(kicad_pcb
	(version 20260206)
	(generator "pcbnew")
	(generator_version "10.0")
	(general
		(thickness 1.6)
		(legacy_teardrops no)
	)
	(paper "A4")
	(layers
		(0 "F.Cu" signal "TOP")
		(4 "In1.Cu" signal "GND")
		(6 "In2.Cu" signal "VCC")
		(8 "In3.Cu" signal "VCC1")
		(10 "In4.Cu" signal "GND1")
		(12 "In5.Cu" signal "IN1")
		(14 "In6.Cu" signal "GND2")
		(16 "In7.Cu" signal "IN2")
		(18 "In8.Cu" signal "GND3")
		(20 "In9.Cu" signal "IN3")
		(22 "In10.Cu" signal "GND4")
		(24 "In11.Cu" signal "IN4")
		(26 "In12.Cu" signal "GND5")
		(28 "In13.Cu" signal "IN5")
		(30 "In14.Cu" signal "GND6")
		(32 "In15.Cu" signal "IN6")
		(34 "In16.Cu" signal "GND7")
		(2 "B.Cu" signal "BOTTOM")
		(9 "F.Adhes" user "F.Adhesive")
		(11 "B.Adhes" user "B.Adhesive")
		(13 "F.Paste" user "Package Geometry/Pastemask Top")
		(15 "B.Paste" user "Package Geometry/Pastemask Bottom")
		(5 "F.SilkS" user "Ref Des/Silkscreen Top")
		(7 "B.SilkS" user "Ref Des/Silkscreen Bottom")
		(1 "F.Mask" user "Board Geometry/Soldermask Top")
		(3 "B.Mask" user "Board Geometry/Soldermask Bottom")
		(17 "Dwgs.User" user "User.Drawings")
		(19 "Cmts.User" user "User.Comments")
		(21 "Eco1.User" user "User.Eco1")
		(23 "Eco2.User" user "User.Eco2")
		(25 "Edge.Cuts" user "Board Geometry/Outline")
		(27 "Margin" user)
		(31 "F.CrtYd" user "Package Geometry/Place Bound Top")
		(29 "B.CrtYd" user "Package Geometry/Place Bound Bottom")
		(35 "F.Fab" user "Ref Des/Assembly Top")
		(33 "B.Fab" user "Ref Des/Assembly Bottom")
	)
	(setup
		(pad_to_mask_clearance 0)
		(allow_soldermask_bridges_in_footprints no)
		(tenting
			(front yes)
			(back yes)
		)
		(covering
			(front no)
			(back no)
		)
		(plugging
			(front no)
			(back no)
		)
		(capping no)
		(filling no)
		(pcbplotparams
			(layerselection 0x00000000_00000000_55555555_5755f5ff)
			(plot_on_all_layers_selection 0x00000000_00000000_00000000_00000000)
			(disableapertmacros no)
			(usegerberextensions no)
			(usegerberattributes yes)
			(usegerberadvancedattributes yes)
			(creategerberjobfile yes)
			(dashed_line_dash_ratio 12)
			(dashed_line_gap_ratio 3)
			(svgprecision 4)
			(plotframeref no)
			(mode 1)
			(useauxorigin no)
			(pdf_front_fp_property_popups yes)
			(pdf_back_fp_property_popups yes)
			(pdf_metadata yes)
			(pdf_single_document no)
			(dxfpolygonmode yes)
			(dxfimperialunits yes)
			(dxfusepcbnewfont yes)
			(psnegative no)
			(psa4output no)
			(plot_black_and_white yes)
			(sketchpadsonfab no)
			(plotpadnumbers no)
			(hidednponfab no)
			(sketchdnponfab yes)
			(crossoutdnponfab yes)
			(subtractmaskfromsilk no)
			(outputformat 1)
			(mirror no)
			(drillshape 1)
			(scaleselection 1)
			(outputdirectory "")
		)
	)
	(gr_poly
		(pts
			(xy 141.148308 -317.619888) (xy 141.158377 -317.619463) (xy 141.176978 -317.611745) (xy 141.184376 -317.604902)
			(xy 142.774162 -316.015116) (xy 142.781563 -316.008278) (xy 142.800162 -316.000563) (xy 142.81023 -316.00013)
			(xy 152.54605 -316.00013) (xy 152.556797 -315.999646) (xy 152.576395 -315.990824) (xy 152.583896 -315.983112)
			(xy 152.641554 -315.918088) (xy 152.648158 -315.89726) (xy 152.646888 -315.886338) (xy 152.645833 -315.877231)
			(xy 152.644687 -315.85893) (xy 152.644602 -315.849762) (xy 152.645124 -315.824507) (xy 152.653437 -315.774685)
			(xy 152.669838 -315.726911) (xy 152.693879 -315.682488) (xy 152.724903 -315.642628) (xy 152.762065 -315.608418)
			(xy 152.804351 -315.580792) (xy 152.850607 -315.560502) (xy 152.899572 -315.548102) (xy 152.94991 -315.543931)
			(xy 153.000248 -315.548102) (xy 153.049213 -315.560502) (xy 153.095469 -315.580792) (xy 153.137755 -315.608418)
			(xy 153.174917 -315.642628) (xy 153.205941 -315.682488) (xy 153.229982 -315.726911) (xy 153.246383 -315.774685)
			(xy 153.254696 -315.824507) (xy 153.255218 -315.849762) (xy 153.255127 -315.85893) (xy 153.253985 -315.87723)
			(xy 153.252932 -315.886338) (xy 153.251662 -315.89726) (xy 153.258266 -315.918088) (xy 153.315924 -315.983112)
			(xy 153.323491 -315.990729) (xy 153.34305 -315.99952) (xy 153.35377 -316.00013) (xy 153.49601 -316.00013)
			(xy 153.50676 -315.999654) (xy 153.526371 -315.990842) (xy 153.533856 -315.983112) (xy 153.591514 -315.918088)
			(xy 153.598118 -315.89726) (xy 153.596848 -315.886338) (xy 153.595793 -315.877231) (xy 153.594647 -315.85893)
			(xy 153.594562 -315.849762) (xy 153.595084 -315.824507) (xy 153.603397 -315.774685) (xy 153.619798 -315.726911)
			(xy 153.643839 -315.682488) (xy 153.674863 -315.642628) (xy 153.712025 -315.608418) (xy 153.754311 -315.580792)
			(xy 153.800567 -315.560502) (xy 153.849532 -315.548102) (xy 153.89987 -315.543931) (xy 153.950208 -315.548102)
			(xy 153.999173 -315.560502) (xy 154.045429 -315.580792) (xy 154.087715 -315.608418) (xy 154.124877 -315.642628)
			(xy 154.155901 -315.682488) (xy 154.179942 -315.726911) (xy 154.196343 -315.774685) (xy 154.204656 -315.824507)
			(xy 154.205178 -315.849762) (xy 154.205087 -315.85893) (xy 154.203945 -315.87723) (xy 154.202892 -315.886338)
			(xy 154.201622 -315.89726) (xy 154.208226 -315.918088) (xy 154.265884 -315.983112) (xy 154.273448 -315.990735)
			(xy 154.293008 -315.999541) (xy 154.30373 -316.00013) (xy 154.446224 -316.00013) (xy 154.456973 -315.999651)
			(xy 154.476579 -315.990836) (xy 154.48407 -315.983112) (xy 154.541728 -315.918088) (xy 154.548332 -315.89726)
			(xy 154.547062 -315.886338) (xy 154.546007 -315.877231) (xy 154.544861 -315.85893) (xy 154.544776 -315.849762)
			(xy 154.545298 -315.824507) (xy 154.553611 -315.774685) (xy 154.570012 -315.726911) (xy 154.594053 -315.682488)
			(xy 154.625077 -315.642628) (xy 154.662239 -315.608418) (xy 154.704525 -315.580792) (xy 154.750781 -315.560502)
			(xy 154.799746 -315.548102) (xy 154.850084 -315.543931) (xy 154.900422 -315.548102) (xy 154.949387 -315.560502)
			(xy 154.995643 -315.580792) (xy 155.037929 -315.608418) (xy 155.075091 -315.642628) (xy 155.106115 -315.682488)
			(xy 155.130156 -315.726911) (xy 155.146557 -315.774685) (xy 155.15487 -315.824507) (xy 155.155392 -315.849762)
			(xy 155.155301 -315.85893) (xy 155.154159 -315.87723) (xy 155.153106 -315.886338) (xy 155.151836 -315.89726)
			(xy 155.15844 -315.918088) (xy 155.216098 -315.983112) (xy 155.223663 -315.990733) (xy 155.243223 -315.999533)
			(xy 155.253944 -316.00013) (xy 155.374086 -316.00013) (xy 155.384899 -315.999689) (xy 155.404638 -315.990868)
			(xy 155.412186 -315.983112) (xy 155.469844 -315.918342) (xy 155.476448 -315.898022) (xy 155.475178 -315.8871)
			(xy 155.474139 -315.8778) (xy 155.472994 -315.859119) (xy 155.472892 -315.849762) (xy 155.473396 -315.824054)
			(xy 155.481439 -315.773272) (xy 155.497327 -315.724373) (xy 155.52067 -315.678561) (xy 155.550891 -315.636965)
			(xy 155.587247 -315.600609) (xy 155.628843 -315.570388) (xy 155.674655 -315.547045) (xy 155.723554 -315.531157)
			(xy 155.774336 -315.523114) (xy 155.825752 -315.523114) (xy 155.876534 -315.531157) (xy 155.925433 -315.547045)
			(xy 155.971245 -315.570388) (xy 156.012841 -315.600609) (xy 156.049197 -315.636965) (xy 156.079418 -315.678561)
			(xy 156.102761 -315.724373) (xy 156.118649 -315.773272) (xy 156.126692 -315.824054) (xy 156.127196 -315.849762)
			(xy 156.127094 -315.859119) (xy 156.12595 -315.8778) (xy 156.12491 -315.8871) (xy 156.12364 -315.898022)
			(xy 156.130244 -315.918342) (xy 156.187902 -315.983112) (xy 156.195468 -315.99084) (xy 156.215197 -315.999656)
			(xy 156.226002 -316.00013) (xy 156.346144 -316.00013) (xy 156.356891 -315.999647) (xy 156.376492 -315.990827)
			(xy 156.38399 -315.983112) (xy 156.441648 -315.918088) (xy 156.448252 -315.89726) (xy 156.446982 -315.886338)
			(xy 156.445927 -315.877231) (xy 156.444781 -315.85893) (xy 156.444696 -315.849762) (xy 156.445218 -315.824507)
			(xy 156.453531 -315.774685) (xy 156.469932 -315.726911) (xy 156.493973 -315.682488) (xy 156.524997 -315.642628)
			(xy 156.562159 -315.608418) (xy 156.604445 -315.580792) (xy 156.650701 -315.560502) (xy 156.699666 -315.548102)
			(xy 156.750004 -315.543931) (xy 156.800342 -315.548102) (xy 156.849307 -315.560502) (xy 156.895563 -315.580792)
			(xy 156.937849 -315.608418) (xy 156.975011 -315.642628) (xy 157.006035 -315.682488) (xy 157.030076 -315.726911)
			(xy 157.046477 -315.774685) (xy 157.05479 -315.824507) (xy 157.055312 -315.849762) (xy 157.055221 -315.85893)
			(xy 157.054079 -315.87723) (xy 157.053026 -315.886338) (xy 157.051756 -315.89726) (xy 157.05836 -315.918088)
			(xy 157.116018 -315.983112) (xy 157.123584 -315.99073) (xy 157.143144 -315.999523) (xy 157.153864 -316.00013)
			(xy 157.164532 -316.00013) (xy 157.1746 -315.999702) (xy 157.193199 -315.991983) (xy 157.2006 -315.985144)
			(xy 157.369002 -315.816742) (xy 157.376114 -315.802772) (xy 157.377638 -315.794898) (xy 157.382333 -315.770112)
			(xy 157.398339 -315.722274) (xy 157.421501 -315.677462) (xy 157.45127 -315.636738) (xy 157.486939 -315.601068)
			(xy 157.527664 -315.571299) (xy 157.572476 -315.548138) (xy 157.620314 -315.532133) (xy 157.6451 -315.527436)
			(xy 157.652974 -315.525912) (xy 157.666944 -315.5188) (xy 158.199836 -314.985908) (xy 158.204883 -314.981116)
			(xy 158.216997 -314.974274) (xy 158.223712 -314.972446) (xy 158.234126 -314.969906) (xy 158.265114 -314.938156)
			(xy 158.268416 -314.931552) (xy 158.281878 -314.906406) (xy 158.282132 -314.906152) (xy 158.282386 -314.905644)
			(xy 158.286315 -314.897649) (xy 158.288882 -314.880032) (xy 158.285237 -314.862606) (xy 158.280862 -314.854844)
			(xy 158.23438 -314.779406) (xy 158.230631 -314.773747) (xy 158.22072 -314.764478) (xy 158.214822 -314.761118)
			(xy 158.214568 -314.761118) (xy 158.209095 -314.758449) (xy 158.197285 -314.755506) (xy 158.1912 -314.755276)
			(xy 158.185612 -314.755276) (xy 158.175198 -314.755784) (xy 158.174182 -314.755784) (xy 158.160719 -314.755595)
			(xy 158.133889 -314.753306) (xy 158.120588 -314.751212) (xy 158.10865 -314.749434) (xy 158.086044 -314.756292)
			(xy 158.00959 -314.82919) (xy 158.001716 -314.851542) (xy 158.00324 -314.86348) (xy 158.004228 -314.872527)
			(xy 158.005243 -314.890701) (xy 158.005272 -314.899802) (xy 158.004786 -314.924619) (xy 157.996756 -314.9736)
			(xy 157.980908 -315.020636) (xy 157.957659 -315.064489) (xy 157.927622 -315.104003) (xy 157.891588 -315.138137)
			(xy 157.850506 -315.165993) (xy 157.80546 -315.186835) (xy 157.757635 -315.200115) (xy 157.708291 -315.205483)
			(xy 157.658729 -315.202797) (xy 157.610255 -315.192129) (xy 157.564145 -315.17376) (xy 157.521614 -315.148172)
			(xy 157.483782 -315.116042) (xy 157.451647 -315.078214) (xy 157.426055 -315.035686) (xy 157.407681 -314.989578)
			(xy 157.397007 -314.941104) (xy 157.394317 -314.891543) (xy 157.399679 -314.842199) (xy 157.412954 -314.794372)
			(xy 157.433791 -314.749323) (xy 157.461641 -314.708239) (xy 157.495771 -314.672201) (xy 157.535282 -314.64216)
			(xy 157.579132 -314.618906) (xy 157.626167 -314.603052) (xy 157.675147 -314.595017) (xy 157.699964 -314.594494)
			(xy 157.709001 -314.59454) (xy 157.727047 -314.595557) (xy 157.736032 -314.596526) (xy 157.74797 -314.59805)
			(xy 157.770322 -314.590176) (xy 157.84322 -314.513722) (xy 157.850078 -314.491116) (xy 157.8483 -314.479178)
			(xy 157.846169 -314.46569) (xy 157.843878 -314.438477) (xy 157.843728 -314.424822) (xy 157.843728 -314.354464)
			(xy 157.843262 -314.343808) (xy 157.834574 -314.324347) (xy 157.826964 -314.316872) (xy 157.762702 -314.25896)
			(xy 157.742382 -314.252356) (xy 157.731714 -314.253626) (xy 157.699964 -314.25515) (xy 157.674707 -314.254625)
			(xy 157.624883 -314.246306) (xy 157.577108 -314.2299) (xy 157.532684 -314.205854) (xy 157.492824 -314.174825)
			(xy 157.458614 -314.137659) (xy 157.430987 -314.095369) (xy 157.410698 -314.04911) (xy 157.398298 -314.000141)
			(xy 157.394127 -313.9498) (xy 157.398298 -313.899459) (xy 157.410698 -313.85049) (xy 157.430987 -313.804231)
			(xy 157.458614 -313.761941) (xy 157.492824 -313.724775) (xy 157.532684 -313.693746) (xy 157.577108 -313.6697)
			(xy 157.624883 -313.653294) (xy 157.674707 -313.644975) (xy 157.699964 -313.644534) (xy 157.731714 -313.646058)
			(xy 157.742382 -313.647328) (xy 157.762702 -313.640724) (xy 157.826964 -313.582812) (xy 157.834475 -313.575268)
			(xy 157.843138 -313.555849) (xy 157.843728 -313.54522) (xy 157.843728 -313.474862) (xy 157.843889 -313.461208)
			(xy 157.846176 -313.433995) (xy 157.8483 -313.420506) (xy 157.850078 -313.408568) (xy 157.84322 -313.385962)
			(xy 157.770322 -313.309508) (xy 157.74797 -313.301634) (xy 157.736032 -313.303158) (xy 157.727048 -313.304141)
			(xy 157.709002 -313.305158) (xy 157.699964 -313.30519) (xy 157.675146 -313.304701) (xy 157.626163 -313.296665)
			(xy 157.579127 -313.280811) (xy 157.535274 -313.257557) (xy 157.495761 -313.227514) (xy 157.461629 -313.191475)
			(xy 157.433777 -313.150389) (xy 157.412938 -313.105338) (xy 157.399662 -313.057509) (xy 157.394299 -313.008163)
			(xy 157.396989 -312.958599) (xy 157.407662 -312.910123) (xy 157.426036 -312.864012) (xy 157.451628 -312.821482)
			(xy 157.483764 -312.783651) (xy 157.521596 -312.751518) (xy 157.564128 -312.725928) (xy 157.61024 -312.707556)
			(xy 157.658717 -312.696886) (xy 157.708281 -312.694199) (xy 157.757627 -312.699566) (xy 157.805455 -312.712844)
			(xy 157.850504 -312.733686) (xy 157.891589 -312.76154) (xy 157.927626 -312.795675) (xy 157.957666 -312.835189)
			(xy 157.980918 -312.879043) (xy 157.99677 -312.926081) (xy 158.004803 -312.975064) (xy 158.005272 -312.999882)
			(xy 158.005233 -313.008983) (xy 158.004218 -313.027156) (xy 158.00324 -313.036204) (xy 158.001716 -313.048142)
			(xy 158.00959 -313.070494) (xy 158.086044 -313.143392) (xy 158.10865 -313.15025) (xy 158.120588 -313.148472)
			(xy 158.133951 -313.146364) (xy 158.160909 -313.144078) (xy 158.174436 -313.1439) (xy 158.174944 -313.1439)
			(xy 158.184619 -313.143979) (xy 158.203935 -313.145125) (xy 158.213552 -313.146186) (xy 158.218632 -313.146948)
			(xy 158.218886 -313.146948) (xy 158.232748 -313.148971) (xy 158.260089 -313.155078) (xy 158.273496 -313.15914)
			(xy 158.284268 -313.161953) (xy 158.306319 -313.159079) (xy 158.325098 -313.147167) (xy 158.337097 -313.128444)
			(xy 158.340074 -313.106406) (xy 158.33725 -313.09564) (xy 158.330519 -313.072273) (xy 158.323246 -313.024194)
			(xy 158.322772 -312.999882) (xy 158.323277 -312.974196) (xy 158.331315 -312.923456) (xy 158.34719 -312.874599)
			(xy 158.370512 -312.828825) (xy 158.400706 -312.787263) (xy 158.437029 -312.750935) (xy 158.478587 -312.720735)
			(xy 158.524357 -312.697407) (xy 158.573213 -312.681525) (xy 158.623951 -312.67348) (xy 158.675324 -312.673471)
			(xy 158.726065 -312.681496) (xy 158.774927 -312.697359) (xy 158.820706 -312.720669) (xy 158.862276 -312.750853)
			(xy 158.898613 -312.787167) (xy 158.928823 -312.828718) (xy 158.952162 -312.874483) (xy 158.968056 -312.923334)
			(xy 158.976113 -312.974071) (xy 158.976136 -313.025443) (xy 158.968123 -313.076186) (xy 158.952272 -313.125052)
			(xy 158.928973 -313.170837) (xy 158.898799 -313.212414) (xy 158.862494 -313.24876) (xy 158.820951 -313.27898)
			(xy 158.775192 -313.302331) (xy 158.726344 -313.318237) (xy 158.67561 -313.326307) (xy 158.649924 -313.32678)
			(xy 158.615126 -313.325002) (xy 158.603696 -313.323732) (xy 158.582106 -313.331606) (xy 158.509716 -313.40425)
			(xy 158.502096 -313.42584) (xy 158.50362 -313.437524) (xy 158.504587 -313.446828) (xy 158.505601 -313.465508)
			(xy 158.505652 -313.474862) (xy 158.505652 -313.523376) (xy 158.506108 -313.534036) (xy 158.514791 -313.553505)
			(xy 158.522416 -313.560968) (xy 158.58617 -313.61888) (xy 158.60649 -313.625484) (xy 158.617412 -313.624468)
			(xy 158.649924 -313.622944) (xy 158.675618 -313.623449) (xy 158.726373 -313.631487) (xy 158.775248 -313.647362)
			(xy 158.821039 -313.670683) (xy 158.862621 -313.700877) (xy 158.898971 -313.737201) (xy 158.929194 -313.778761)
			(xy 158.952548 -313.824536) (xy 158.968458 -313.873399) (xy 158.976533 -313.924148) (xy 158.977076 -313.949842)
			(xy 158.975044 -313.984386) (xy 158.973774 -313.99607) (xy 158.981648 -314.01766) (xy 159.054292 -314.09005)
			(xy 159.075882 -314.097416) (xy 159.087566 -314.096146) (xy 159.119316 -314.094114) (xy 159.13437 -314.094065)
			(xy 159.164388 -314.096353) (xy 159.17926 -314.098686) (xy 159.191198 -314.100718) (xy 159.213804 -314.093606)
			(xy 159.290258 -314.020708) (xy 159.298132 -313.998356) (xy 159.296862 -313.986164) (xy 159.295812 -313.97712)
			(xy 159.294666 -313.958946) (xy 159.294576 -313.949842) (xy 159.295019 -313.925846) (xy 159.30252 -313.878445)
			(xy 159.317345 -313.8328) (xy 159.339128 -313.790037) (xy 159.367333 -313.751209) (xy 159.401264 -313.71727)
			(xy 159.440088 -313.689058) (xy 159.482847 -313.667267) (xy 159.528488 -313.652434) (xy 159.575888 -313.644924)
			(xy 159.599884 -313.644534) (xy 159.631888 -313.646312) (xy 159.64281 -313.647328) (xy 159.66313 -313.640724)
			(xy 159.727392 -313.583066) (xy 159.735043 -313.575545) (xy 159.743707 -313.555941) (xy 159.744156 -313.54522)
			(xy 159.744156 -313.474862) (xy 159.744317 -313.461208) (xy 159.746604 -313.433995) (xy 159.748728 -313.420506)
			(xy 159.75076 -313.408568) (xy 159.743648 -313.385962) (xy 159.67075 -313.309508) (xy 159.648398 -313.301634)
			(xy 159.636206 -313.302904) (xy 159.627162 -313.303952) (xy 159.608988 -313.305095) (xy 159.599884 -313.30519)
			(xy 159.575065 -313.304703) (xy 159.526082 -313.29667) (xy 159.479043 -313.280819) (xy 159.435189 -313.257566)
			(xy 159.395674 -313.227525) (xy 159.361539 -313.191487) (xy 159.333684 -313.150402) (xy 159.312843 -313.105352)
			(xy 159.299565 -313.057523) (xy 159.294199 -313.008176) (xy 159.296887 -312.958612) (xy 159.307558 -312.910135)
			(xy 159.325931 -312.864022) (xy 159.351522 -312.82149) (xy 159.383657 -312.783658) (xy 159.421489 -312.751523)
			(xy 159.464021 -312.725932) (xy 159.510133 -312.707559) (xy 159.55861 -312.696887) (xy 159.608174 -312.694199)
			(xy 159.657521 -312.699565) (xy 159.70535 -312.712843) (xy 159.7504 -312.733683) (xy 159.791486 -312.761538)
			(xy 159.827524 -312.795672) (xy 159.857565 -312.835187) (xy 159.880818 -312.879042) (xy 159.89667 -312.92608)
			(xy 159.904703 -312.975063) (xy 159.905192 -312.999882) (xy 159.905093 -313.008986) (xy 159.903947 -313.027159)
			(xy 159.902906 -313.036204) (xy 159.901636 -313.048396) (xy 159.90951 -313.070748) (xy 159.985964 -313.143646)
			(xy 160.00857 -313.150758) (xy 160.020508 -313.148726) (xy 160.033996 -313.146594) (xy 160.061209 -313.144303)
			(xy 160.074864 -313.144154) (xy 160.084218 -313.144196) (xy 160.102899 -313.14521) (xy 160.112202 -313.146186)
			(xy 160.123886 -313.14771) (xy 160.145476 -313.14009) (xy 160.21812 -313.0677) (xy 160.225994 -313.04611)
			(xy 160.224724 -313.034426) (xy 160.222692 -312.999882) (xy 160.223197 -312.974198) (xy 160.231234 -312.923462)
			(xy 160.247108 -312.874608) (xy 160.270428 -312.828838) (xy 160.300619 -312.787278) (xy 160.336939 -312.750952)
			(xy 160.378494 -312.720754) (xy 160.42426 -312.697428) (xy 160.473112 -312.681546) (xy 160.523847 -312.673501)
			(xy 160.575215 -312.67349) (xy 160.625953 -312.681514) (xy 160.674811 -312.697374) (xy 160.720588 -312.720682)
			(xy 160.762155 -312.750862) (xy 160.798491 -312.787173) (xy 160.8287 -312.828719) (xy 160.852039 -312.87448)
			(xy 160.867933 -312.923327) (xy 160.875992 -312.974059) (xy 160.876017 -313.025428) (xy 160.868007 -313.076168)
			(xy 160.852159 -313.125031) (xy 160.828864 -313.170813) (xy 160.798695 -313.212389) (xy 160.762394 -313.248734)
			(xy 160.720855 -313.278954) (xy 160.675101 -313.302305) (xy 160.626258 -313.318213) (xy 160.575528 -313.326285)
			(xy 160.549844 -313.32678) (xy 160.5153 -313.325002) (xy 160.503616 -313.323732) (xy 160.482026 -313.331606)
			(xy 160.409636 -313.40425) (xy 160.402016 -313.42584) (xy 160.40354 -313.437524) (xy 160.404508 -313.446828)
			(xy 160.405524 -313.465508) (xy 160.405572 -313.474862) (xy 160.405572 -313.523376) (xy 160.406026 -313.534038)
			(xy 160.414699 -313.553516) (xy 160.422336 -313.560968) (xy 160.48609 -313.61888) (xy 160.50641 -313.625484)
			(xy 160.517332 -313.624468) (xy 160.549844 -313.622944) (xy 160.575537 -313.62345) (xy 160.62629 -313.631491)
			(xy 160.675162 -313.647368) (xy 160.72095 -313.67069) (xy 160.762529 -313.700884) (xy 160.798877 -313.737208)
			(xy 160.829098 -313.778767) (xy 160.85245 -313.82454) (xy 160.868359 -313.873402) (xy 160.876433 -313.924149)
			(xy 160.876996 -313.949842) (xy 160.874964 -313.984386) (xy 160.873694 -313.99607) (xy 160.881568 -314.01766)
			(xy 160.954212 -314.09005) (xy 160.976056 -314.097416) (xy 160.987486 -314.096146) (xy 161.01949 -314.094114)
			(xy 161.034543 -314.094069) (xy 161.064561 -314.096362) (xy 161.079434 -314.098686) (xy 161.091372 -314.100718)
			(xy 161.113978 -314.093606) (xy 161.190432 -314.020708) (xy 161.198306 -313.998356) (xy 161.197036 -313.986164)
			(xy 161.195986 -313.97712) (xy 161.19484 -313.958946) (xy 161.19475 -313.949842) (xy 161.195217 -313.925847)
			(xy 161.202718 -313.878448) (xy 161.217541 -313.832806) (xy 161.239322 -313.790044) (xy 161.267524 -313.751216)
			(xy 161.301453 -313.717278) (xy 161.340273 -313.689066) (xy 161.383028 -313.667273) (xy 161.428666 -313.652438)
			(xy 161.476064 -313.644924) (xy 161.500058 -313.644534) (xy 161.531808 -313.646058) (xy 161.542476 -313.647328)
			(xy 161.562796 -313.640724) (xy 161.627058 -313.582812) (xy 161.634569 -313.575268) (xy 161.643234 -313.555849)
			(xy 161.643822 -313.54522) (xy 161.643822 -313.474862) (xy 161.643983 -313.461208) (xy 161.64627 -313.433995)
			(xy 161.648394 -313.420506) (xy 161.650172 -313.408568) (xy 161.643314 -313.385962) (xy 161.570416 -313.309508)
			(xy 161.548064 -313.301634) (xy 161.536126 -313.303158) (xy 161.527142 -313.304141) (xy 161.509096 -313.305157)
			(xy 161.500058 -313.30519) (xy 161.47524 -313.304701) (xy 161.426258 -313.296664) (xy 161.379221 -313.280809)
			(xy 161.33537 -313.257554) (xy 161.295857 -313.227511) (xy 161.261726 -313.191471) (xy 161.233875 -313.150385)
			(xy 161.213037 -313.105334) (xy 161.199761 -313.057505) (xy 161.194399 -313.008159) (xy 161.197089 -312.958595)
			(xy 161.207763 -312.91012) (xy 161.226138 -312.864009) (xy 161.25173 -312.821479) (xy 161.283866 -312.783649)
			(xy 161.321698 -312.751516) (xy 161.364231 -312.725927) (xy 161.410343 -312.707556) (xy 161.458819 -312.696886)
			(xy 161.508383 -312.694199) (xy 161.557729 -312.699566) (xy 161.605556 -312.712845) (xy 161.650605 -312.733686)
			(xy 161.69169 -312.761541) (xy 161.727727 -312.795675) (xy 161.757767 -312.83519) (xy 161.781019 -312.879044)
			(xy 161.79687 -312.926081) (xy 161.804903 -312.975064) (xy 161.805366 -312.999882) (xy 161.805327 -313.008983)
			(xy 161.804312 -313.027156) (xy 161.803334 -313.036204) (xy 161.80181 -313.048142) (xy 161.809684 -313.070494)
			(xy 161.886138 -313.143392) (xy 161.908744 -313.15025) (xy 161.920682 -313.148472) (xy 161.934045 -313.146363)
			(xy 161.961003 -313.144077) (xy 161.97453 -313.1439) (xy 161.989008 -313.144154) (xy 161.992564 -313.144408)
			(xy 161.993072 -313.144408) (xy 162.009582 -313.145678) (xy 162.01009 -313.145678) (xy 162.012122 -313.145932)
			(xy 162.023806 -313.147202) (xy 162.045396 -313.139836) (xy 162.118294 -313.067446) (xy 162.126168 -313.045856)
			(xy 162.124898 -313.034426) (xy 162.12312 -312.999882) (xy 162.123625 -312.974196) (xy 162.131664 -312.923458)
			(xy 162.147541 -312.874601) (xy 162.170865 -312.82883) (xy 162.201062 -312.787271) (xy 162.237389 -312.750947)
			(xy 162.27895 -312.720753) (xy 162.324723 -312.697432) (xy 162.373581 -312.681558) (xy 162.42432 -312.673523)
			(xy 162.475692 -312.673524) (xy 162.526431 -312.681561) (xy 162.575288 -312.697436) (xy 162.62106 -312.720759)
			(xy 162.66262 -312.750955) (xy 162.698945 -312.78728) (xy 162.729141 -312.82884) (xy 162.752464 -312.874612)
			(xy 162.768339 -312.923469) (xy 162.776376 -312.974208) (xy 162.776377 -313.02558) (xy 162.768342 -313.076319)
			(xy 162.752468 -313.125177) (xy 162.729147 -313.17095) (xy 162.698953 -313.212511) (xy 162.662629 -313.248838)
			(xy 162.62107 -313.279035) (xy 162.575299 -313.302359) (xy 162.526442 -313.318236) (xy 162.475704 -313.326275)
			(xy 162.450018 -313.32678) (xy 162.41522 -313.325002) (xy 162.403536 -313.323732) (xy 162.381946 -313.331352)
			(xy 162.30981 -313.40425) (xy 162.30219 -313.42584) (xy 162.30346 -313.437524) (xy 162.305492 -313.465718)
			(xy 162.305492 -313.523376) (xy 162.305946 -313.534037) (xy 162.314622 -313.553513) (xy 162.322256 -313.560968)
			(xy 162.386264 -313.61888) (xy 162.40633 -313.625484) (xy 162.417252 -313.624468) (xy 162.450018 -313.622944)
			(xy 162.475706 -313.623423) (xy 162.526448 -313.631463) (xy 162.575308 -313.647343) (xy 162.621082 -313.67067)
			(xy 162.662643 -313.700871) (xy 162.698968 -313.737203) (xy 162.729161 -313.778769) (xy 162.75248 -313.824548)
			(xy 162.768351 -313.87341) (xy 162.776381 -313.924154) (xy 162.776916 -313.949842) (xy 162.775138 -313.984386)
			(xy 162.773868 -313.99607) (xy 162.781742 -314.01766) (xy 162.854386 -314.09005) (xy 162.875976 -314.097416)
			(xy 162.88766 -314.096146) (xy 162.91941 -314.094114) (xy 162.934464 -314.094065) (xy 162.964482 -314.096352)
			(xy 162.979354 -314.098686) (xy 162.991292 -314.100718) (xy 163.013898 -314.093606) (xy 163.090352 -314.020708)
			(xy 163.098226 -313.998356) (xy 163.096956 -313.986164) (xy 163.095906 -313.97712) (xy 163.09476 -313.958946)
			(xy 163.09467 -313.949842) (xy 163.095113 -313.925846) (xy 163.102614 -313.878444) (xy 163.117439 -313.8328)
			(xy 163.139222 -313.790036) (xy 163.167426 -313.751207) (xy 163.201358 -313.717268) (xy 163.240181 -313.689055)
			(xy 163.28294 -313.667264) (xy 163.328582 -313.652429) (xy 163.375982 -313.644918) (xy 163.399978 -313.644534)
			(xy 163.431728 -313.646058) (xy 163.442396 -313.647328) (xy 163.462716 -313.640724) (xy 163.526978 -313.582812)
			(xy 163.534487 -313.575267) (xy 163.543148 -313.555848) (xy 163.543742 -313.54522) (xy 163.543742 -313.474862)
			(xy 163.543903 -313.461208) (xy 163.54619 -313.433995) (xy 163.548314 -313.420506) (xy 163.550092 -313.408568)
			(xy 163.543234 -313.385962) (xy 163.470336 -313.309508) (xy 163.447984 -313.301634) (xy 163.436046 -313.303158)
			(xy 163.427062 -313.304141) (xy 163.409016 -313.305159) (xy 163.399978 -313.30519) (xy 163.375159 -313.304702)
			(xy 163.326176 -313.296669) (xy 163.279138 -313.280816) (xy 163.235284 -313.257563) (xy 163.19577 -313.227522)
			(xy 163.161636 -313.191484) (xy 163.133782 -313.150398) (xy 163.112942 -313.105348) (xy 163.099664 -313.057519)
			(xy 163.094299 -313.008172) (xy 163.096988 -312.958608) (xy 163.107659 -312.910131) (xy 163.126033 -312.864019)
			(xy 163.151624 -312.821488) (xy 163.183759 -312.783656) (xy 163.221591 -312.751522) (xy 163.264123 -312.725931)
			(xy 163.310235 -312.707558) (xy 163.358712 -312.696887) (xy 163.408276 -312.694199) (xy 163.457623 -312.699565)
			(xy 163.505451 -312.712843) (xy 163.550502 -312.733684) (xy 163.591587 -312.761539) (xy 163.627625 -312.795673)
			(xy 163.657665 -312.835188) (xy 163.680918 -312.879042) (xy 163.69677 -312.92608) (xy 163.704803 -312.975063)
			(xy 163.705286 -312.999882) (xy 163.705247 -313.008983) (xy 163.704232 -313.027156) (xy 163.703254 -313.036204)
			(xy 163.70173 -313.048142) (xy 163.709604 -313.070494) (xy 163.786058 -313.143392) (xy 163.808664 -313.15025)
			(xy 163.820602 -313.148472) (xy 163.833965 -313.14636) (xy 163.860923 -313.144067) (xy 163.87445 -313.1439)
			(xy 163.888928 -313.144154) (xy 163.892484 -313.144408) (xy 163.892992 -313.144408) (xy 163.909502 -313.145678)
			(xy 163.91001 -313.145678) (xy 163.912042 -313.145932) (xy 163.923726 -313.147202) (xy 163.945316 -313.139836)
			(xy 164.018214 -313.067446) (xy 164.026088 -313.045856) (xy 164.024818 -313.034426) (xy 164.02304 -312.999882)
			(xy 164.023545 -312.974198) (xy 164.031583 -312.923463) (xy 164.047459 -312.87461) (xy 164.070781 -312.828842)
			(xy 164.100976 -312.787286) (xy 164.137299 -312.750964) (xy 164.178857 -312.720772) (xy 164.224626 -312.697452)
			(xy 164.27348 -312.681579) (xy 164.324215 -312.673544) (xy 164.375583 -312.673544) (xy 164.426319 -312.681579)
			(xy 164.475172 -312.697452) (xy 164.520942 -312.720771) (xy 164.5625 -312.750963) (xy 164.598824 -312.787285)
			(xy 164.629018 -312.828841) (xy 164.652341 -312.874609) (xy 164.668216 -312.923462) (xy 164.676255 -312.974197)
			(xy 164.676258 -313.025565) (xy 164.668226 -313.0763) (xy 164.652355 -313.125155) (xy 164.629039 -313.170926)
			(xy 164.598849 -313.212486) (xy 164.562529 -313.248811) (xy 164.520975 -313.279009) (xy 164.475208 -313.302334)
			(xy 164.426356 -313.318212) (xy 164.375622 -313.326253) (xy 164.349938 -313.32678) (xy 164.31514 -313.325002)
			(xy 164.303456 -313.323732) (xy 164.281866 -313.331352) (xy 164.20973 -313.40425) (xy 164.20211 -313.42584)
			(xy 164.20338 -313.437524) (xy 164.205412 -313.465718) (xy 164.205412 -313.523376) (xy 164.205867 -313.534037)
			(xy 164.214545 -313.55351) (xy 164.222176 -313.560968) (xy 164.286184 -313.61888) (xy 164.30625 -313.625484)
			(xy 164.317172 -313.624468) (xy 164.349938 -313.622944) (xy 164.375625 -313.623425) (xy 164.426365 -313.631467)
			(xy 164.475222 -313.647348) (xy 164.520993 -313.670677) (xy 164.562551 -313.700878) (xy 164.598874 -313.737209)
			(xy 164.629065 -313.778775) (xy 164.652382 -313.824552) (xy 164.668251 -313.873413) (xy 164.676282 -313.924155)
			(xy 164.676836 -313.949842) (xy 164.675058 -313.984386) (xy 164.673788 -313.99607) (xy 164.681662 -314.01766)
			(xy 164.754306 -314.09005) (xy 164.775896 -314.097416) (xy 164.78758 -314.096146) (xy 164.81933 -314.094114)
			(xy 164.834384 -314.094066) (xy 164.864402 -314.096354) (xy 164.879274 -314.098686) (xy 164.891212 -314.100718)
			(xy 164.913818 -314.093606) (xy 164.990272 -314.020708) (xy 164.998146 -313.998356) (xy 164.996876 -313.986164)
			(xy 164.995826 -313.97712) (xy 164.99468 -313.958946) (xy 164.99459 -313.949842) (xy 164.995033 -313.925847)
			(xy 165.002535 -313.878446) (xy 165.017359 -313.832803) (xy 165.039142 -313.79004) (xy 165.067347 -313.751213)
			(xy 165.101279 -313.717276) (xy 165.140103 -313.689065) (xy 165.182862 -313.667276) (xy 165.228503 -313.652445)
			(xy 165.275903 -313.644937) (xy 165.299898 -313.644534) (xy 165.331648 -313.646312) (xy 165.34257 -313.647328)
			(xy 165.36289 -313.640724) (xy 165.427152 -313.582812) (xy 165.434664 -313.575268) (xy 165.443329 -313.555849)
			(xy 165.443916 -313.54522) (xy 165.443916 -313.474862) (xy 165.444077 -313.461208) (xy 165.446364 -313.433995)
			(xy 165.448488 -313.420506) (xy 165.45052 -313.408568) (xy 165.443408 -313.385962) (xy 165.37051 -313.309508)
			(xy 165.348158 -313.301634) (xy 165.33622 -313.303158) (xy 165.327173 -313.304146) (xy 165.308999 -313.305161)
			(xy 165.299898 -313.30519) (xy 165.275079 -313.304704) (xy 165.226095 -313.296673) (xy 165.179055 -313.280824)
			(xy 165.135199 -313.257573) (xy 165.095683 -313.227533) (xy 165.061546 -313.191496) (xy 165.03369 -313.150412)
			(xy 165.012847 -313.105361) (xy 164.999567 -313.057533) (xy 164.994199 -313.008186) (xy 164.996886 -312.95862)
			(xy 165.007556 -312.910143) (xy 165.025928 -312.86403) (xy 165.051518 -312.821496) (xy 165.083652 -312.783663)
			(xy 165.121483 -312.751527) (xy 165.164015 -312.725935) (xy 165.210127 -312.70756) (xy 165.258605 -312.696888)
			(xy 165.30817 -312.694199) (xy 165.357517 -312.699564) (xy 165.405346 -312.712841) (xy 165.450398 -312.733682)
			(xy 165.491484 -312.761536) (xy 165.527522 -312.795671) (xy 165.557564 -312.835186) (xy 165.580817 -312.87904)
			(xy 165.596669 -312.926079) (xy 165.604703 -312.975063) (xy 165.605206 -312.999882) (xy 165.605167 -313.008983)
			(xy 165.604152 -313.027156) (xy 165.603174 -313.036204) (xy 165.60165 -313.048142) (xy 165.609524 -313.070494)
			(xy 165.685978 -313.143392) (xy 165.708584 -313.150504) (xy 165.720522 -313.148472) (xy 165.73401 -313.14634)
			(xy 165.761223 -313.14405) (xy 165.774878 -313.1439) (xy 165.784232 -313.143943) (xy 165.802912 -313.144959)
			(xy 165.812216 -313.145932) (xy 165.8239 -313.147202) (xy 165.84549 -313.139836) (xy 165.918134 -313.067446)
			(xy 165.926008 -313.045856) (xy 165.924738 -313.034426) (xy 165.92296 -312.999882) (xy 165.923439 -312.974188)
			(xy 165.931481 -312.923434) (xy 165.947363 -312.874563) (xy 165.970695 -312.828779) (xy 166.000902 -312.787207)
			(xy 166.037241 -312.750874) (xy 166.078816 -312.720672) (xy 166.124604 -312.697346) (xy 166.173477 -312.68147)
			(xy 166.224232 -312.673435) (xy 166.27562 -312.67344) (xy 166.326373 -312.681482) (xy 166.375244 -312.697366)
			(xy 166.421028 -312.720699) (xy 166.462599 -312.750908) (xy 166.498931 -312.787247) (xy 166.529132 -312.828823)
			(xy 166.552457 -312.874612) (xy 166.568332 -312.923485) (xy 166.576365 -312.97424) (xy 166.576363 -312.999882)
			(xy 166.894268 -312.999882) (xy 166.898228 -312.950828) (xy 166.910005 -312.903044) (xy 166.929296 -312.857768)
			(xy 166.955599 -312.816172) (xy 166.988234 -312.779335) (xy 167.026355 -312.74821) (xy 167.068976 -312.723603)
			(xy 167.114992 -312.706151) (xy 167.163211 -312.696307) (xy 167.212386 -312.694326) (xy 167.261241 -312.700258)
			(xy 167.308512 -312.71395) (xy 167.352974 -312.735048) (xy 167.393477 -312.763004) (xy 167.42897 -312.797096)
			(xy 167.458535 -312.83644) (xy 167.481406 -312.880017) (xy 167.49699 -312.926698) (xy 167.504885 -312.975275)
			(xy 167.50538 -312.999882) (xy 167.504885 -313.024489) (xy 167.504706 -313.02559) (xy 167.823384 -313.02559)
			(xy 167.823384 -312.974174) (xy 167.831427 -312.923392) (xy 167.847315 -312.874493) (xy 167.870658 -312.828681)
			(xy 167.900879 -312.787085) (xy 167.937235 -312.750729) (xy 167.978831 -312.720508) (xy 168.024643 -312.697165)
			(xy 168.073542 -312.681277) (xy 168.124324 -312.673234) (xy 168.17574 -312.673234) (xy 168.226522 -312.681277)
			(xy 168.275421 -312.697165) (xy 168.321233 -312.720508) (xy 168.362829 -312.750729) (xy 168.399185 -312.787085)
			(xy 168.429406 -312.828681) (xy 168.452749 -312.874493) (xy 168.468637 -312.923392) (xy 168.47668 -312.974174)
			(xy 168.477184 -312.999882) (xy 168.794188 -312.999882) (xy 168.798148 -312.950828) (xy 168.809925 -312.903044)
			(xy 168.829216 -312.857768) (xy 168.855519 -312.816172) (xy 168.888154 -312.779335) (xy 168.926275 -312.74821)
			(xy 168.968896 -312.723603) (xy 169.014912 -312.706151) (xy 169.063131 -312.696307) (xy 169.112306 -312.694326)
			(xy 169.161161 -312.700258) (xy 169.208432 -312.71395) (xy 169.252894 -312.735048) (xy 169.293397 -312.763004)
			(xy 169.32889 -312.797096) (xy 169.358455 -312.83644) (xy 169.381326 -312.880017) (xy 169.39691 -312.926698)
			(xy 169.404805 -312.975275) (xy 169.4053 -312.999882) (xy 169.404805 -313.024489) (xy 169.404626 -313.02559)
			(xy 169.723304 -313.02559) (xy 169.723304 -312.974174) (xy 169.731347 -312.923392) (xy 169.747235 -312.874493)
			(xy 169.770578 -312.828681) (xy 169.800799 -312.787085) (xy 169.837155 -312.750729) (xy 169.878751 -312.720508)
			(xy 169.924563 -312.697165) (xy 169.973462 -312.681277) (xy 170.024244 -312.673234) (xy 170.07566 -312.673234)
			(xy 170.126442 -312.681277) (xy 170.175341 -312.697165) (xy 170.221153 -312.720508) (xy 170.262749 -312.750729)
			(xy 170.299105 -312.787085) (xy 170.329326 -312.828681) (xy 170.352669 -312.874493) (xy 170.368557 -312.923392)
			(xy 170.3766 -312.974174) (xy 170.377104 -312.999882) (xy 170.694108 -312.999882) (xy 170.698068 -312.950828)
			(xy 170.709845 -312.903044) (xy 170.729136 -312.857768) (xy 170.755439 -312.816172) (xy 170.788074 -312.779335)
			(xy 170.826195 -312.74821) (xy 170.868816 -312.723603) (xy 170.914832 -312.706151) (xy 170.963051 -312.696307)
			(xy 171.012226 -312.694326) (xy 171.061081 -312.700258) (xy 171.108352 -312.71395) (xy 171.152814 -312.735048)
			(xy 171.193317 -312.763004) (xy 171.22881 -312.797096) (xy 171.258375 -312.83644) (xy 171.281246 -312.880017)
			(xy 171.29683 -312.926698) (xy 171.304725 -312.975275) (xy 171.30522 -312.999882) (xy 171.304725 -313.024489)
			(xy 171.304546 -313.02559) (xy 171.623224 -313.02559) (xy 171.623224 -312.974174) (xy 171.631267 -312.923392)
			(xy 171.647155 -312.874493) (xy 171.670498 -312.828681) (xy 171.700719 -312.787085) (xy 171.737075 -312.750729)
			(xy 171.778671 -312.720508) (xy 171.824483 -312.697165) (xy 171.873382 -312.681277) (xy 171.924164 -312.673234)
			(xy 171.97558 -312.673234) (xy 172.026362 -312.681277) (xy 172.075261 -312.697165) (xy 172.121073 -312.720508)
			(xy 172.162669 -312.750729) (xy 172.199025 -312.787085) (xy 172.229246 -312.828681) (xy 172.252589 -312.874493)
			(xy 172.268477 -312.923392) (xy 172.27652 -312.974174) (xy 172.277024 -312.999882) (xy 172.27652 -313.02559)
			(xy 172.268477 -313.076372) (xy 172.252589 -313.125271) (xy 172.229246 -313.171083) (xy 172.199025 -313.212679)
			(xy 172.162669 -313.249035) (xy 172.121073 -313.279256) (xy 172.075261 -313.302599) (xy 172.026362 -313.318487)
			(xy 171.97558 -313.32653) (xy 171.924164 -313.32653) (xy 171.873382 -313.318487) (xy 171.824483 -313.302599)
			(xy 171.778671 -313.279256) (xy 171.737075 -313.249035) (xy 171.700719 -313.212679) (xy 171.670498 -313.171083)
			(xy 171.647155 -313.125271) (xy 171.631267 -313.076372) (xy 171.623224 -313.02559) (xy 171.304546 -313.02559)
			(xy 171.29683 -313.073066) (xy 171.281246 -313.119747) (xy 171.258375 -313.163324) (xy 171.22881 -313.202668)
			(xy 171.193317 -313.23676) (xy 171.152814 -313.264716) (xy 171.108352 -313.285814) (xy 171.061081 -313.299506)
			(xy 171.012226 -313.305438) (xy 170.963051 -313.303457) (xy 170.914832 -313.293613) (xy 170.868816 -313.276161)
			(xy 170.826195 -313.251554) (xy 170.788074 -313.220429) (xy 170.755439 -313.183592) (xy 170.729136 -313.141996)
			(xy 170.709845 -313.09672) (xy 170.698068 -313.048936) (xy 170.694108 -312.999882) (xy 170.377104 -312.999882)
			(xy 170.3766 -313.02559) (xy 170.368557 -313.076372) (xy 170.352669 -313.125271) (xy 170.329326 -313.171083)
			(xy 170.299105 -313.212679) (xy 170.262749 -313.249035) (xy 170.221153 -313.279256) (xy 170.175341 -313.302599)
			(xy 170.126442 -313.318487) (xy 170.07566 -313.32653) (xy 170.024244 -313.32653) (xy 169.973462 -313.318487)
			(xy 169.924563 -313.302599) (xy 169.878751 -313.279256) (xy 169.837155 -313.249035) (xy 169.800799 -313.212679)
			(xy 169.770578 -313.171083) (xy 169.747235 -313.125271) (xy 169.731347 -313.076372) (xy 169.723304 -313.02559)
			(xy 169.404626 -313.02559) (xy 169.39691 -313.073066) (xy 169.381326 -313.119747) (xy 169.358455 -313.163324)
			(xy 169.32889 -313.202668) (xy 169.293397 -313.23676) (xy 169.252894 -313.264716) (xy 169.208432 -313.285814)
			(xy 169.161161 -313.299506) (xy 169.112306 -313.305438) (xy 169.063131 -313.303457) (xy 169.014912 -313.293613)
			(xy 168.968896 -313.276161) (xy 168.926275 -313.251554) (xy 168.888154 -313.220429) (xy 168.855519 -313.183592)
			(xy 168.829216 -313.141996) (xy 168.809925 -313.09672) (xy 168.798148 -313.048936) (xy 168.794188 -312.999882)
			(xy 168.477184 -312.999882) (xy 168.47668 -313.02559) (xy 168.468637 -313.076372) (xy 168.452749 -313.125271)
			(xy 168.429406 -313.171083) (xy 168.399185 -313.212679) (xy 168.362829 -313.249035) (xy 168.321233 -313.279256)
			(xy 168.275421 -313.302599) (xy 168.226522 -313.318487) (xy 168.17574 -313.32653) (xy 168.124324 -313.32653)
			(xy 168.073542 -313.318487) (xy 168.024643 -313.302599) (xy 167.978831 -313.279256) (xy 167.937235 -313.249035)
			(xy 167.900879 -313.212679) (xy 167.870658 -313.171083) (xy 167.847315 -313.125271) (xy 167.831427 -313.076372)
			(xy 167.823384 -313.02559) (xy 167.504706 -313.02559) (xy 167.49699 -313.073066) (xy 167.481406 -313.119747)
			(xy 167.458535 -313.163324) (xy 167.42897 -313.202668) (xy 167.393477 -313.23676) (xy 167.352974 -313.264716)
			(xy 167.308512 -313.285814) (xy 167.261241 -313.299506) (xy 167.212386 -313.305438) (xy 167.163211 -313.303457)
			(xy 167.114992 -313.293613) (xy 167.068976 -313.276161) (xy 167.026355 -313.251554) (xy 166.988234 -313.220429)
			(xy 166.955599 -313.183592) (xy 166.929296 -313.141996) (xy 166.910005 -313.09672) (xy 166.898228 -313.048936)
			(xy 166.894268 -312.999882) (xy 166.576363 -312.999882) (xy 166.57636 -313.025628) (xy 166.568316 -313.076381)
			(xy 166.552431 -313.125251) (xy 166.529097 -313.171035) (xy 166.498887 -313.212605) (xy 166.462547 -313.248937)
			(xy 166.42097 -313.279136) (xy 166.375181 -313.30246) (xy 166.326307 -313.318333) (xy 166.275552 -313.326366)
			(xy 166.249858 -313.32678) (xy 166.215314 -313.325002) (xy 166.203884 -313.323732) (xy 166.182294 -313.331606)
			(xy 166.109904 -313.40425) (xy 166.102538 -313.42584) (xy 166.103808 -313.437524) (xy 166.104775 -313.446828)
			(xy 166.105789 -313.465508) (xy 166.10584 -313.474862) (xy 166.10584 -313.523376) (xy 166.106296 -313.534036)
			(xy 166.114977 -313.553506) (xy 166.122604 -313.560968) (xy 166.186358 -313.61888) (xy 166.206678 -313.625484)
			(xy 166.2176 -313.624468) (xy 166.249858 -313.622944) (xy 166.275547 -313.623419) (xy 166.326292 -313.63145)
			(xy 166.375157 -313.647321) (xy 166.420936 -313.670642) (xy 166.462504 -313.700838) (xy 166.498835 -313.737164)
			(xy 166.529036 -313.778728) (xy 166.552363 -313.824505) (xy 166.56824 -313.873367) (xy 166.576278 -313.924111)
			(xy 166.576278 -313.949842) (xy 166.894268 -313.949842) (xy 166.898228 -313.900788) (xy 166.910005 -313.853004)
			(xy 166.929296 -313.807728) (xy 166.955599 -313.766132) (xy 166.988234 -313.729295) (xy 167.026355 -313.69817)
			(xy 167.068976 -313.673563) (xy 167.114992 -313.656111) (xy 167.163211 -313.646267) (xy 167.212386 -313.644286)
			(xy 167.261241 -313.650218) (xy 167.308512 -313.66391) (xy 167.352974 -313.685008) (xy 167.393477 -313.712964)
			(xy 167.42897 -313.747056) (xy 167.458535 -313.7864) (xy 167.481406 -313.829977) (xy 167.49699 -313.876658)
			(xy 167.504885 -313.925235) (xy 167.50538 -313.949842) (xy 167.504885 -313.974449) (xy 167.504706 -313.97555)
			(xy 167.823384 -313.97555) (xy 167.823384 -313.924134) (xy 167.831427 -313.873352) (xy 167.847315 -313.824453)
			(xy 167.870658 -313.778641) (xy 167.900879 -313.737045) (xy 167.937235 -313.700689) (xy 167.978831 -313.670468)
			(xy 168.024643 -313.647125) (xy 168.073542 -313.631237) (xy 168.124324 -313.623194) (xy 168.17574 -313.623194)
			(xy 168.226522 -313.631237) (xy 168.275421 -313.647125) (xy 168.321233 -313.670468) (xy 168.362829 -313.700689)
			(xy 168.399185 -313.737045) (xy 168.429406 -313.778641) (xy 168.452749 -313.824453) (xy 168.468637 -313.873352)
			(xy 168.47668 -313.924134) (xy 168.477184 -313.949842) (xy 168.794188 -313.949842) (xy 168.798148 -313.900788)
			(xy 168.809925 -313.853004) (xy 168.829216 -313.807728) (xy 168.855519 -313.766132) (xy 168.888154 -313.729295)
			(xy 168.926275 -313.69817) (xy 168.968896 -313.673563) (xy 169.014912 -313.656111) (xy 169.063131 -313.646267)
			(xy 169.112306 -313.644286) (xy 169.161161 -313.650218) (xy 169.208432 -313.66391) (xy 169.252894 -313.685008)
			(xy 169.293397 -313.712964) (xy 169.32889 -313.747056) (xy 169.358455 -313.7864) (xy 169.381326 -313.829977)
			(xy 169.39691 -313.876658) (xy 169.404805 -313.925235) (xy 169.4053 -313.949842) (xy 169.404805 -313.974449)
			(xy 169.404626 -313.97555) (xy 169.723304 -313.97555) (xy 169.723304 -313.924134) (xy 169.731347 -313.873352)
			(xy 169.747235 -313.824453) (xy 169.770578 -313.778641) (xy 169.800799 -313.737045) (xy 169.837155 -313.700689)
			(xy 169.878751 -313.670468) (xy 169.924563 -313.647125) (xy 169.973462 -313.631237) (xy 170.024244 -313.623194)
			(xy 170.07566 -313.623194) (xy 170.126442 -313.631237) (xy 170.175341 -313.647125) (xy 170.221153 -313.670468)
			(xy 170.262749 -313.700689) (xy 170.299105 -313.737045) (xy 170.329326 -313.778641) (xy 170.352669 -313.824453)
			(xy 170.368557 -313.873352) (xy 170.3766 -313.924134) (xy 170.377104 -313.949842) (xy 170.694108 -313.949842)
			(xy 170.698068 -313.900788) (xy 170.709845 -313.853004) (xy 170.729136 -313.807728) (xy 170.755439 -313.766132)
			(xy 170.788074 -313.729295) (xy 170.826195 -313.69817) (xy 170.868816 -313.673563) (xy 170.914832 -313.656111)
			(xy 170.963051 -313.646267) (xy 171.012226 -313.644286) (xy 171.061081 -313.650218) (xy 171.108352 -313.66391)
			(xy 171.152814 -313.685008) (xy 171.193317 -313.712964) (xy 171.22881 -313.747056) (xy 171.258375 -313.7864)
			(xy 171.281246 -313.829977) (xy 171.29683 -313.876658) (xy 171.304725 -313.925235) (xy 171.30522 -313.949842)
			(xy 171.304725 -313.974449) (xy 171.304546 -313.97555) (xy 171.623224 -313.97555) (xy 171.623224 -313.924134)
			(xy 171.631267 -313.873352) (xy 171.647155 -313.824453) (xy 171.670498 -313.778641) (xy 171.700719 -313.737045)
			(xy 171.737075 -313.700689) (xy 171.778671 -313.670468) (xy 171.824483 -313.647125) (xy 171.873382 -313.631237)
			(xy 171.924164 -313.623194) (xy 171.97558 -313.623194) (xy 172.026362 -313.631237) (xy 172.075261 -313.647125)
			(xy 172.121073 -313.670468) (xy 172.162669 -313.700689) (xy 172.199025 -313.737045) (xy 172.229246 -313.778641)
			(xy 172.252589 -313.824453) (xy 172.268477 -313.873352) (xy 172.27652 -313.924134) (xy 172.277024 -313.949842)
			(xy 172.27652 -313.97555) (xy 172.268477 -314.026332) (xy 172.252589 -314.075231) (xy 172.229246 -314.121043)
			(xy 172.199025 -314.162639) (xy 172.162669 -314.198995) (xy 172.121073 -314.229216) (xy 172.075261 -314.252559)
			(xy 172.026362 -314.268447) (xy 171.97558 -314.27649) (xy 171.924164 -314.27649) (xy 171.873382 -314.268447)
			(xy 171.824483 -314.252559) (xy 171.778671 -314.229216) (xy 171.737075 -314.198995) (xy 171.700719 -314.162639)
			(xy 171.670498 -314.121043) (xy 171.647155 -314.075231) (xy 171.631267 -314.026332) (xy 171.623224 -313.97555)
			(xy 171.304546 -313.97555) (xy 171.29683 -314.023026) (xy 171.281246 -314.069707) (xy 171.258375 -314.113284)
			(xy 171.22881 -314.152628) (xy 171.193317 -314.18672) (xy 171.152814 -314.214676) (xy 171.108352 -314.235774)
			(xy 171.061081 -314.249466) (xy 171.012226 -314.255398) (xy 170.963051 -314.253417) (xy 170.914832 -314.243573)
			(xy 170.868816 -314.226121) (xy 170.826195 -314.201514) (xy 170.788074 -314.170389) (xy 170.755439 -314.133552)
			(xy 170.729136 -314.091956) (xy 170.709845 -314.04668) (xy 170.698068 -313.998896) (xy 170.694108 -313.949842)
			(xy 170.377104 -313.949842) (xy 170.3766 -313.97555) (xy 170.368557 -314.026332) (xy 170.352669 -314.075231)
			(xy 170.329326 -314.121043) (xy 170.299105 -314.162639) (xy 170.262749 -314.198995) (xy 170.221153 -314.229216)
			(xy 170.175341 -314.252559) (xy 170.126442 -314.268447) (xy 170.07566 -314.27649) (xy 170.024244 -314.27649)
			(xy 169.973462 -314.268447) (xy 169.924563 -314.252559) (xy 169.878751 -314.229216) (xy 169.837155 -314.198995)
			(xy 169.800799 -314.162639) (xy 169.770578 -314.121043) (xy 169.747235 -314.075231) (xy 169.731347 -314.026332)
			(xy 169.723304 -313.97555) (xy 169.404626 -313.97555) (xy 169.39691 -314.023026) (xy 169.381326 -314.069707)
			(xy 169.358455 -314.113284) (xy 169.32889 -314.152628) (xy 169.293397 -314.18672) (xy 169.252894 -314.214676)
			(xy 169.208432 -314.235774) (xy 169.161161 -314.249466) (xy 169.112306 -314.255398) (xy 169.063131 -314.253417)
			(xy 169.014912 -314.243573) (xy 168.968896 -314.226121) (xy 168.926275 -314.201514) (xy 168.888154 -314.170389)
			(xy 168.855519 -314.133552) (xy 168.829216 -314.091956) (xy 168.809925 -314.04668) (xy 168.798148 -313.998896)
			(xy 168.794188 -313.949842) (xy 168.477184 -313.949842) (xy 168.47668 -313.97555) (xy 168.468637 -314.026332)
			(xy 168.452749 -314.075231) (xy 168.429406 -314.121043) (xy 168.399185 -314.162639) (xy 168.362829 -314.198995)
			(xy 168.321233 -314.229216) (xy 168.275421 -314.252559) (xy 168.226522 -314.268447) (xy 168.17574 -314.27649)
			(xy 168.124324 -314.27649) (xy 168.073542 -314.268447) (xy 168.024643 -314.252559) (xy 167.978831 -314.229216)
			(xy 167.937235 -314.198995) (xy 167.900879 -314.162639) (xy 167.870658 -314.121043) (xy 167.847315 -314.075231)
			(xy 167.831427 -314.026332) (xy 167.823384 -313.97555) (xy 167.504706 -313.97555) (xy 167.49699 -314.023026)
			(xy 167.481406 -314.069707) (xy 167.458535 -314.113284) (xy 167.42897 -314.152628) (xy 167.393477 -314.18672)
			(xy 167.352974 -314.214676) (xy 167.308512 -314.235774) (xy 167.261241 -314.249466) (xy 167.212386 -314.255398)
			(xy 167.163211 -314.253417) (xy 167.114992 -314.243573) (xy 167.068976 -314.226121) (xy 167.026355 -314.201514)
			(xy 166.988234 -314.170389) (xy 166.955599 -314.133552) (xy 166.929296 -314.091956) (xy 166.910005 -314.04668)
			(xy 166.898228 -313.998896) (xy 166.894268 -313.949842) (xy 166.576278 -313.949842) (xy 166.576278 -313.975489)
			(xy 166.56824 -314.026233) (xy 166.552363 -314.075095) (xy 166.529036 -314.120872) (xy 166.498835 -314.162436)
			(xy 166.462504 -314.198762) (xy 166.420936 -314.228958) (xy 166.375157 -314.252279) (xy 166.326292 -314.26815)
			(xy 166.275547 -314.276181) (xy 166.249858 -314.27674) (xy 166.2176 -314.275216) (xy 166.206678 -314.2742)
			(xy 166.186358 -314.280804) (xy 166.122604 -314.338716) (xy 166.115102 -314.346263) (xy 166.106454 -314.365683)
			(xy 166.10584 -314.376308) (xy 166.10584 -314.424822) (xy 166.105676 -314.438476) (xy 166.103384 -314.465688)
			(xy 166.101268 -314.479178) (xy 166.099236 -314.491116) (xy 166.106348 -314.513722) (xy 166.179246 -314.590176)
			(xy 166.201598 -314.59805) (xy 166.213536 -314.596526) (xy 166.222583 -314.595536) (xy 166.240757 -314.594519)
			(xy 166.249858 -314.594494) (xy 166.275028 -314.595006) (xy 166.324687 -314.603262) (xy 166.372317 -314.619559)
			(xy 166.416626 -314.643453) (xy 166.456412 -314.674296) (xy 166.490594 -314.711251) (xy 166.518247 -314.753317)
			(xy 166.53862 -314.799351) (xy 166.55116 -314.848105) (xy 166.553896 -314.873132) (xy 166.554912 -314.882784)
			(xy 166.563294 -314.899548) (xy 166.620952 -314.95238) (xy 166.628156 -314.95853) (xy 166.645778 -314.965441)
			(xy 166.655242 -314.965842) (xy 166.794688 -314.965842) (xy 166.804129 -314.965344) (xy 166.821705 -314.958424)
			(xy 166.828978 -314.95238) (xy 166.886636 -314.899548) (xy 166.895018 -314.882784) (xy 166.896034 -314.873132)
			(xy 166.898746 -314.848108) (xy 166.91131 -314.799371) (xy 166.9317 -314.753356) (xy 166.959364 -314.71131)
			(xy 166.993551 -314.674372) (xy 167.033335 -314.643544) (xy 167.077638 -314.619661) (xy 167.125258 -314.603369)
			(xy 167.174907 -314.595112) (xy 167.225237 -314.595112) (xy 167.274886 -314.603369) (xy 167.322506 -314.619661)
			(xy 167.366809 -314.643544) (xy 167.406593 -314.674372) (xy 167.44078 -314.71131) (xy 167.468444 -314.753356)
			(xy 167.488834 -314.799371) (xy 167.501398 -314.848108) (xy 167.50411 -314.873132) (xy 167.505126 -314.882784)
			(xy 167.513508 -314.899548) (xy 167.571166 -314.95238) (xy 167.578366 -314.958543) (xy 167.595987 -314.965484)
			(xy 167.605456 -314.965842) (xy 167.744648 -314.965842) (xy 167.754092 -314.965351) (xy 167.771678 -314.958441)
			(xy 167.778938 -314.95238) (xy 167.836596 -314.899548) (xy 167.844978 -314.882784) (xy 167.845994 -314.873132)
			(xy 167.848706 -314.848108) (xy 167.86127 -314.799371) (xy 167.88166 -314.753356) (xy 167.909324 -314.71131)
			(xy 167.943511 -314.674372) (xy 167.983295 -314.643544) (xy 168.027598 -314.619661) (xy 168.075218 -314.603369)
			(xy 168.124867 -314.595112) (xy 168.175197 -314.595112) (xy 168.224846 -314.603369) (xy 168.272466 -314.619661)
			(xy 168.316769 -314.643544) (xy 168.356553 -314.674372) (xy 168.39074 -314.71131) (xy 168.418404 -314.753356)
			(xy 168.438794 -314.799371) (xy 168.451358 -314.848108) (xy 168.45407 -314.873132) (xy 168.455086 -314.882784)
			(xy 168.463468 -314.899548) (xy 168.521126 -314.95238) (xy 168.528329 -314.958534) (xy 168.54595 -314.965454)
			(xy 168.555416 -314.965842) (xy 168.694608 -314.965842) (xy 168.704055 -314.965358) (xy 168.72165 -314.958458)
			(xy 168.728898 -314.95238) (xy 168.786556 -314.899548) (xy 168.794938 -314.882784) (xy 168.795954 -314.873132)
			(xy 168.798666 -314.848108) (xy 168.81123 -314.799371) (xy 168.83162 -314.753356) (xy 168.859284 -314.71131)
			(xy 168.893471 -314.674372) (xy 168.933255 -314.643544) (xy 168.977558 -314.619661) (xy 169.025178 -314.603369)
			(xy 169.074827 -314.595112) (xy 169.125157 -314.595112) (xy 169.174806 -314.603369) (xy 169.222426 -314.619661)
			(xy 169.266729 -314.643544) (xy 169.306513 -314.674372) (xy 169.3407 -314.71131) (xy 169.368364 -314.753356)
			(xy 169.388754 -314.799371) (xy 169.401318 -314.848108) (xy 169.40403 -314.873132) (xy 169.405046 -314.882784)
			(xy 169.413428 -314.899548) (xy 169.471086 -314.95238) (xy 169.478287 -314.95854) (xy 169.495908 -314.965475)
			(xy 169.505376 -314.965842) (xy 169.644568 -314.965842) (xy 169.654011 -314.965348) (xy 169.671592 -314.958432)
			(xy 169.678858 -314.95238) (xy 169.736516 -314.899548) (xy 169.744898 -314.882784) (xy 169.745914 -314.873132)
			(xy 169.748626 -314.848108) (xy 169.76119 -314.799371) (xy 169.78158 -314.753356) (xy 169.809244 -314.71131)
			(xy 169.843431 -314.674372) (xy 169.883215 -314.643544) (xy 169.927518 -314.619661) (xy 169.975138 -314.603369)
			(xy 170.024787 -314.595112) (xy 170.075117 -314.595112) (xy 170.124766 -314.603369) (xy 170.172386 -314.619661)
			(xy 170.216689 -314.643544) (xy 170.256473 -314.674372) (xy 170.29066 -314.71131) (xy 170.318324 -314.753356)
			(xy 170.338714 -314.799371) (xy 170.351278 -314.848108) (xy 170.35399 -314.873132) (xy 170.355006 -314.882784)
			(xy 170.363388 -314.899548) (xy 170.421046 -314.95238) (xy 170.42825 -314.958531) (xy 170.445871 -314.965444)
			(xy 170.455336 -314.965842) (xy 170.594528 -314.965842) (xy 170.603974 -314.965355) (xy 170.621564 -314.958449)
			(xy 170.628818 -314.95238) (xy 170.686476 -314.899548) (xy 170.694858 -314.882784) (xy 170.695874 -314.873132)
			(xy 170.698586 -314.848108) (xy 170.71115 -314.799371) (xy 170.73154 -314.753356) (xy 170.759204 -314.71131)
			(xy 170.793391 -314.674372) (xy 170.833175 -314.643544) (xy 170.877478 -314.619661) (xy 170.925098 -314.603369)
			(xy 170.974747 -314.595112) (xy 171.025077 -314.595112) (xy 171.074726 -314.603369) (xy 171.122346 -314.619661)
			(xy 171.166649 -314.643544) (xy 171.206433 -314.674372) (xy 171.24062 -314.71131) (xy 171.268284 -314.753356)
			(xy 171.288674 -314.799371) (xy 171.301238 -314.848108) (xy 171.30395 -314.873132) (xy 171.304966 -314.882784)
			(xy 171.313348 -314.899548) (xy 171.371006 -314.95238) (xy 171.378208 -314.958537) (xy 171.395829 -314.965465)
			(xy 171.405296 -314.965842) (xy 171.544488 -314.965842) (xy 171.553929 -314.965344) (xy 171.571505 -314.958424)
			(xy 171.578778 -314.95238) (xy 171.636436 -314.899548) (xy 171.644818 -314.882784) (xy 171.645834 -314.873132)
			(xy 171.648546 -314.848108) (xy 171.66111 -314.799371) (xy 171.6815 -314.753356) (xy 171.709164 -314.71131)
			(xy 171.743351 -314.674372) (xy 171.783135 -314.643544) (xy 171.827438 -314.619661) (xy 171.875058 -314.603369)
			(xy 171.924707 -314.595112) (xy 171.975037 -314.595112) (xy 172.024686 -314.603369) (xy 172.072306 -314.619661)
			(xy 172.116609 -314.643544) (xy 172.156393 -314.674372) (xy 172.19058 -314.71131) (xy 172.218244 -314.753356)
			(xy 172.238634 -314.799371) (xy 172.251198 -314.848108) (xy 172.25391 -314.873132) (xy 172.254926 -314.882784)
			(xy 172.263308 -314.899548) (xy 172.320966 -314.95238) (xy 172.328166 -314.958543) (xy 172.345787 -314.965484)
			(xy 172.355256 -314.965842) (xy 172.494702 -314.965842) (xy 172.50415 -314.965359) (xy 172.521746 -314.95846)
			(xy 172.528992 -314.95238) (xy 172.58665 -314.899548) (xy 172.595032 -314.882784) (xy 172.596048 -314.873132)
			(xy 172.598765 -314.848107) (xy 172.611338 -314.799368) (xy 172.631732 -314.75335) (xy 172.659395 -314.711298)
			(xy 172.693579 -314.674352) (xy 172.733357 -314.64351) (xy 172.777655 -314.619607) (xy 172.825271 -314.603292)
			(xy 172.874919 -314.595004) (xy 172.900086 -314.594494) (xy 172.909187 -314.594533) (xy 172.92736 -314.595549)
			(xy 172.936408 -314.596526) (xy 172.948346 -314.59805) (xy 172.970698 -314.590176) (xy 173.043596 -314.513722)
			(xy 173.050708 -314.491116) (xy 173.048676 -314.479178) (xy 173.046545 -314.46569) (xy 173.044253 -314.438477)
			(xy 173.044104 -314.424822) (xy 173.044104 -314.354464) (xy 173.043638 -314.343808) (xy 173.034947 -314.324351)
			(xy 173.02734 -314.316872) (xy 172.963078 -314.25896) (xy 172.942758 -314.252356) (xy 172.931836 -314.253372)
			(xy 172.900086 -314.25515) (xy 172.874828 -314.254627) (xy 172.825001 -314.24631) (xy 172.777223 -314.229906)
			(xy 172.732796 -314.205862) (xy 172.692932 -314.174833) (xy 172.65872 -314.137666) (xy 172.631091 -314.095376)
			(xy 172.610799 -314.049114) (xy 172.598398 -314.000144) (xy 172.594227 -313.9498) (xy 172.598398 -313.899456)
			(xy 172.610799 -313.850486) (xy 172.631091 -313.804224) (xy 172.65872 -313.761934) (xy 172.692932 -313.724767)
			(xy 172.732796 -313.693738) (xy 172.777223 -313.669694) (xy 172.825001 -313.65329) (xy 172.874828 -313.644973)
			(xy 172.900086 -313.644534) (xy 172.931836 -313.646312) (xy 172.942758 -313.647328) (xy 172.963078 -313.640724)
			(xy 173.02734 -313.582812) (xy 173.034853 -313.575269) (xy 173.043521 -313.55585) (xy 173.044104 -313.54522)
			(xy 173.044104 -313.474862) (xy 173.044265 -313.461208) (xy 173.046552 -313.433995) (xy 173.048676 -313.420506)
			(xy 173.050708 -313.408568) (xy 173.043596 -313.385962) (xy 172.970698 -313.309508) (xy 172.948346 -313.301634)
			(xy 172.936408 -313.303158) (xy 172.927361 -313.304146) (xy 172.909187 -313.30516) (xy 172.900086 -313.30519)
			(xy 172.875267 -313.304703) (xy 172.826284 -313.296671) (xy 172.779245 -313.280819) (xy 172.73539 -313.257567)
			(xy 172.695875 -313.227526) (xy 172.66174 -313.191489) (xy 172.633885 -313.150403) (xy 172.613044 -313.105353)
			(xy 172.599765 -313.057524) (xy 172.594399 -313.008178) (xy 172.597087 -312.958613) (xy 172.607758 -312.910136)
			(xy 172.626131 -312.864024) (xy 172.651722 -312.821491) (xy 172.683856 -312.783659) (xy 172.721688 -312.751524)
			(xy 172.76422 -312.725932) (xy 172.810332 -312.707559) (xy 172.858809 -312.696887) (xy 172.908374 -312.694199)
			(xy 172.957721 -312.699564) (xy 173.005549 -312.712842) (xy 173.0506 -312.733683) (xy 173.091686 -312.761538)
			(xy 173.127724 -312.795672) (xy 173.157765 -312.835187) (xy 173.181018 -312.879041) (xy 173.19687 -312.92608)
			(xy 173.204903 -312.975063) (xy 173.205394 -312.999882) (xy 173.205355 -313.008983) (xy 173.20434 -313.027156)
			(xy 173.203362 -313.036204) (xy 173.201838 -313.048142) (xy 173.209712 -313.070494) (xy 173.286166 -313.143392)
			(xy 173.308772 -313.150504) (xy 173.32071 -313.148472) (xy 173.334198 -313.14634) (xy 173.361411 -313.144049)
			(xy 173.375066 -313.1439) (xy 173.38442 -313.143942) (xy 173.403101 -313.144958) (xy 173.412404 -313.145932)
			(xy 173.424088 -313.147202) (xy 173.445678 -313.139836) (xy 173.518322 -313.067446) (xy 173.526196 -313.045856)
			(xy 173.524926 -313.034426) (xy 173.523148 -312.999882) (xy 173.523653 -312.974199) (xy 173.531691 -312.923465)
			(xy 173.547566 -312.874614) (xy 173.570887 -312.828847) (xy 173.601081 -312.787292) (xy 173.637403 -312.750971)
			(xy 173.67896 -312.72078) (xy 173.724728 -312.69746) (xy 173.77358 -312.681587) (xy 173.824314 -312.673552)
			(xy 173.87568 -312.673551) (xy 173.926414 -312.681586) (xy 173.975266 -312.697458) (xy 174.021035 -312.720776)
			(xy 174.062592 -312.750967) (xy 174.098915 -312.787287) (xy 174.129109 -312.828841) (xy 174.152431 -312.874608)
			(xy 174.168308 -312.923459) (xy 174.176347 -312.974192) (xy 174.176349 -312.999882) (xy 174.494202 -312.999882)
			(xy 174.498162 -312.950828) (xy 174.509939 -312.903044) (xy 174.52923 -312.857768) (xy 174.555533 -312.816172)
			(xy 174.588168 -312.779335) (xy 174.626289 -312.74821) (xy 174.66891 -312.723603) (xy 174.714926 -312.706151)
			(xy 174.763145 -312.696307) (xy 174.81232 -312.694326) (xy 174.861175 -312.700258) (xy 174.908446 -312.71395)
			(xy 174.952908 -312.735048) (xy 174.993411 -312.763004) (xy 175.028904 -312.797096) (xy 175.058469 -312.83644)
			(xy 175.08134 -312.880017) (xy 175.096924 -312.926698) (xy 175.104819 -312.975275) (xy 175.105314 -312.999882)
			(xy 175.104819 -313.024489) (xy 175.096924 -313.073066) (xy 175.08134 -313.119747) (xy 175.058469 -313.163324)
			(xy 175.028904 -313.202668) (xy 174.993411 -313.23676) (xy 174.952908 -313.264716) (xy 174.908446 -313.285814)
			(xy 174.861175 -313.299506) (xy 174.81232 -313.305438) (xy 174.763145 -313.303457) (xy 174.714926 -313.293613)
			(xy 174.66891 -313.276161) (xy 174.626289 -313.251554) (xy 174.588168 -313.220429) (xy 174.555533 -313.183592)
			(xy 174.52923 -313.141996) (xy 174.509939 -313.09672) (xy 174.498162 -313.048936) (xy 174.494202 -312.999882)
			(xy 174.176349 -312.999882) (xy 174.17635 -313.025558) (xy 174.168319 -313.076293) (xy 174.15245 -313.125147)
			(xy 174.129135 -313.170916) (xy 174.098947 -313.212476) (xy 174.062629 -313.248801) (xy 174.021077 -313.278998)
			(xy 173.975312 -313.302323) (xy 173.926462 -313.318203) (xy 173.875729 -313.326245) (xy 173.850046 -313.32678)
			(xy 173.815502 -313.325002) (xy 173.804072 -313.323732) (xy 173.782482 -313.331606) (xy 173.710092 -313.40425)
			(xy 173.702726 -313.42584) (xy 173.703996 -313.437524) (xy 173.704963 -313.446828) (xy 173.705977 -313.465508)
			(xy 173.706028 -313.474862) (xy 173.706028 -313.523376) (xy 173.706483 -313.534036) (xy 173.715163 -313.553508)
			(xy 173.722792 -313.560968) (xy 173.786546 -313.61888) (xy 173.806866 -313.625484) (xy 173.817788 -313.624468)
			(xy 173.850046 -313.622944) (xy 173.87573 -313.623451) (xy 173.926465 -313.631494) (xy 173.975317 -313.647375)
			(xy 174.021084 -313.670702) (xy 174.062638 -313.700901) (xy 174.098956 -313.737229) (xy 174.129144 -313.778791)
			(xy 174.152459 -313.824564) (xy 174.168326 -313.87342) (xy 174.176356 -313.924158) (xy 174.176944 -313.949842)
			(xy 174.175166 -313.984386) (xy 174.173896 -313.99607) (xy 174.18177 -314.01766) (xy 174.254414 -314.09005)
			(xy 174.276004 -314.09767) (xy 174.287688 -314.096146) (xy 174.296929 -314.095183) (xy 174.315482 -314.094164)
			(xy 174.324772 -314.094114) (xy 174.33849 -314.094266) (xy 174.36583 -314.096552) (xy 174.379382 -314.098686)
			(xy 174.39132 -314.100718) (xy 174.413926 -314.093606) (xy 174.49038 -314.020708) (xy 174.498254 -313.998356)
			(xy 174.496984 -313.986418) (xy 174.495929 -313.97731) (xy 174.494785 -313.95901) (xy 174.494698 -313.949842)
			(xy 174.49518 -313.925021) (xy 174.503205 -313.876032) (xy 174.51905 -313.828986) (xy 174.542297 -313.785124)
			(xy 174.572334 -313.745601) (xy 174.60837 -313.711458) (xy 174.649455 -313.683595) (xy 174.694507 -313.662746)
			(xy 174.742338 -313.64946) (xy 174.791688 -313.644088) (xy 174.841258 -313.646771) (xy 174.88974 -313.657438)
			(xy 174.935858 -313.675808) (xy 174.978396 -313.701398) (xy 175.016234 -313.733532) (xy 175.048374 -313.771365)
			(xy 175.073971 -313.813899) (xy 175.092348 -313.860014) (xy 175.103023 -313.908495) (xy 175.105713 -313.958064)
			(xy 175.100349 -314.007415) (xy 175.087071 -314.055248) (xy 175.066229 -314.100303) (xy 175.038372 -314.141392)
			(xy 175.004235 -314.177434) (xy 174.964716 -314.207477) (xy 174.920858 -314.230731) (xy 174.873815 -314.246583)
			(xy 174.824827 -314.254616) (xy 174.800006 -314.25515) (xy 174.790838 -314.255058) (xy 174.772538 -314.253914)
			(xy 174.76343 -314.252864) (xy 174.751238 -314.251594) (xy 174.72914 -314.259468) (xy 174.655988 -314.335922)
			(xy 174.64913 -314.358528) (xy 174.650908 -314.370466) (xy 174.652851 -314.382634) (xy 174.655143 -314.407171)
			(xy 174.65548 -314.419488) (xy 174.655734 -314.434474) (xy 174.682404 -314.474352) (xy 174.688246 -314.479178)
			(xy 174.694088 -314.484258) (xy 174.701454 -314.487306) (xy 174.74091 -314.50459) (xy 174.816869 -314.545229)
			(xy 174.888889 -314.592498) (xy 174.922942 -314.618878) (xy 174.932594 -314.62472) (xy 174.955532 -314.636353)
			(xy 174.997467 -314.666125) (xy 175.033802 -314.702521) (xy 175.063504 -314.744505) (xy 175.075088 -314.767468)
			(xy 175.08093 -314.776866) (xy 175.110243 -314.814859) (xy 175.162033 -314.895652) (xy 175.184308 -314.938156)
			(xy 175.188922 -314.946271) (xy 175.202787 -314.958745) (xy 175.220195 -314.965439) (xy 175.22952 -314.965842)
			(xy 175.344582 -314.965842) (xy 175.354024 -314.965345) (xy 175.371601 -314.958426) (xy 175.378872 -314.95238)
			(xy 175.43653 -314.899548) (xy 175.444912 -314.882784) (xy 175.445928 -314.873132) (xy 175.448645 -314.848106)
			(xy 175.461218 -314.799366) (xy 175.481611 -314.753346) (xy 175.509274 -314.711293) (xy 175.543457 -314.674344)
			(xy 175.583236 -314.6435) (xy 175.627533 -314.619595) (xy 175.67515 -314.603276) (xy 175.724798 -314.594986)
			(xy 175.749966 -314.594494) (xy 175.75907 -314.594592) (xy 175.777243 -314.595737) (xy 175.786288 -314.59678)
			(xy 175.79848 -314.59805) (xy 175.820832 -314.590176) (xy 175.89373 -314.513722) (xy 175.900842 -314.491116)
			(xy 175.89881 -314.479178) (xy 175.896679 -314.46569) (xy 175.894388 -314.438477) (xy 175.894238 -314.424822)
			(xy 175.894238 -314.416186) (xy 175.894492 -314.415932) (xy 175.894492 -314.376308) (xy 175.894034 -314.365649)
			(xy 175.885352 -314.346179) (xy 175.877728 -314.338716) (xy 175.81372 -314.280804) (xy 175.793654 -314.2742)
			(xy 175.782732 -314.275216) (xy 175.749966 -314.27674) (xy 175.724277 -314.276234) (xy 175.673531 -314.268191)
			(xy 175.624668 -314.25231) (xy 175.578891 -314.228982) (xy 175.537327 -314.198779) (xy 175.500999 -314.162447)
			(xy 175.470801 -314.12088) (xy 175.447477 -314.0751) (xy 175.431601 -314.026236) (xy 175.423564 -313.975489)
			(xy 175.423564 -313.924111) (xy 175.431601 -313.873364) (xy 175.447477 -313.8245) (xy 175.470801 -313.77872)
			(xy 175.500999 -313.737153) (xy 175.537327 -313.700821) (xy 175.578891 -313.670618) (xy 175.624668 -313.64729)
			(xy 175.673531 -313.631409) (xy 175.724277 -313.623366) (xy 175.749966 -313.622944) (xy 175.782732 -313.624468)
			(xy 175.793654 -313.625484) (xy 175.81372 -313.61888) (xy 175.877728 -313.560968) (xy 175.885236 -313.553423)
			(xy 175.893889 -313.534003) (xy 175.894492 -313.523376) (xy 175.894492 -313.474862) (xy 175.894536 -313.465508)
			(xy 175.895554 -313.446828) (xy 175.896524 -313.437524) (xy 175.898048 -313.42584) (xy 175.890428 -313.40425)
			(xy 175.818038 -313.331352) (xy 175.796448 -313.323732) (xy 175.784764 -313.325002) (xy 175.749966 -313.32678)
			(xy 175.724281 -313.326274) (xy 175.673543 -313.318232) (xy 175.624688 -313.302353) (xy 175.578918 -313.279027)
			(xy 175.53736 -313.248829) (xy 175.501038 -313.212501) (xy 175.470846 -313.170939) (xy 175.447527 -313.125166)
			(xy 175.431656 -313.076308) (xy 175.423622 -313.025569) (xy 175.423625 -312.974198) (xy 175.431663 -312.92346)
			(xy 175.44754 -312.874604) (xy 175.470864 -312.828832) (xy 175.50106 -312.787273) (xy 175.537386 -312.750949)
			(xy 175.578946 -312.720755) (xy 175.624718 -312.697434) (xy 175.673575 -312.68156) (xy 175.724314 -312.673524)
			(xy 175.775685 -312.673524) (xy 175.826423 -312.681559) (xy 175.87528 -312.697433) (xy 175.921053 -312.720754)
			(xy 175.962613 -312.750949) (xy 175.998939 -312.787272) (xy 176.029136 -312.828831) (xy 176.05246 -312.874602)
			(xy 176.068336 -312.923458) (xy 176.076375 -312.974197) (xy 176.076864 -312.999882) (xy 176.075086 -313.03468)
			(xy 176.073816 -313.04611) (xy 176.08169 -313.0677) (xy 176.154334 -313.14009) (xy 176.176178 -313.14771)
			(xy 176.187608 -313.146186) (xy 176.196975 -313.145211) (xy 176.215782 -313.144194) (xy 176.2252 -313.144154)
			(xy 176.238791 -313.144323) (xy 176.265876 -313.146609) (xy 176.279302 -313.148726) (xy 176.29124 -313.150504)
			(xy 176.313846 -313.143646) (xy 176.3903 -313.070748) (xy 176.398174 -313.048396) (xy 176.396904 -313.036204)
			(xy 176.395856 -313.02716) (xy 176.394713 -313.008986) (xy 176.394618 -312.999882) (xy 176.395105 -312.975064)
			(xy 176.403138 -312.926082) (xy 176.418989 -312.879045) (xy 176.442241 -312.835193) (xy 176.472281 -312.795679)
			(xy 176.508318 -312.761545) (xy 176.549402 -312.733692) (xy 176.594451 -312.712851) (xy 176.642277 -312.699573)
			(xy 176.691623 -312.694207) (xy 176.741186 -312.696895) (xy 176.789661 -312.707565) (xy 176.835772 -312.725937)
			(xy 176.878303 -312.751527) (xy 176.916134 -312.78366) (xy 176.948268 -312.821491) (xy 176.973859 -312.864021)
			(xy 176.992232 -312.910131) (xy 177.002904 -312.958606) (xy 177.005593 -313.008169) (xy 177.000229 -313.057515)
			(xy 176.986952 -313.105342) (xy 176.966112 -313.150391) (xy 176.93826 -313.191476) (xy 176.904127 -313.227514)
			(xy 176.864614 -313.257555) (xy 176.820762 -313.280808) (xy 176.773725 -313.29666) (xy 176.724744 -313.304694)
			(xy 176.699926 -313.30519) (xy 176.690825 -313.305151) (xy 176.672652 -313.304136) (xy 176.663604 -313.303158)
			(xy 176.651666 -313.301634) (xy 176.629314 -313.309508) (xy 176.556416 -313.385962) (xy 176.549304 -313.408568)
			(xy 176.551336 -313.420506) (xy 176.553468 -313.433994) (xy 176.55576 -313.461207) (xy 176.555908 -313.474862)
			(xy 176.555908 -313.54522) (xy 176.556372 -313.555877) (xy 176.56506 -313.575338) (xy 176.572672 -313.582812)
			(xy 176.636934 -313.640724) (xy 176.657254 -313.647328) (xy 176.668176 -313.646312) (xy 176.699926 -313.644534)
			(xy 176.723917 -313.644982) (xy 176.771306 -313.652492) (xy 176.816938 -313.667324) (xy 176.859687 -313.689111)
			(xy 176.898502 -313.717318) (xy 176.932426 -313.75125) (xy 176.960624 -313.790071) (xy 176.982402 -313.832825)
			(xy 176.997224 -313.87846) (xy 177.004723 -313.925851) (xy 177.005234 -313.949842) (xy 177.005136 -313.958946)
			(xy 177.003992 -313.977119) (xy 177.002948 -313.986164) (xy 177.001678 -313.998356) (xy 177.009552 -314.020708)
			(xy 177.086006 -314.093606) (xy 177.108612 -314.100464) (xy 177.12055 -314.098432) (xy 177.132658 -314.096554)
			(xy 177.157068 -314.09439) (xy 177.169318 -314.094114) (xy 177.18007 -314.094009) (xy 177.20155 -314.095023)
			(xy 177.212244 -314.096146) (xy 177.223674 -314.097416) (xy 177.245518 -314.09005) (xy 177.318162 -314.01766)
			(xy 177.326036 -313.99607) (xy 177.324766 -313.984386) (xy 177.322988 -313.949842) (xy 177.323462 -313.92415)
			(xy 177.331494 -313.873397) (xy 177.347368 -313.824525) (xy 177.370691 -313.778738) (xy 177.400891 -313.737165)
			(xy 177.437222 -313.700827) (xy 177.478791 -313.670621) (xy 177.524573 -313.647289) (xy 177.573442 -313.631408)
			(xy 177.624194 -313.623367) (xy 177.649886 -313.622944) (xy 177.682652 -313.624468) (xy 177.693574 -313.625484)
			(xy 177.71364 -313.61888) (xy 177.777648 -313.560968) (xy 177.785154 -313.553422) (xy 177.793803 -313.534002)
			(xy 177.794412 -313.523376) (xy 177.794412 -313.474862) (xy 177.794456 -313.465508) (xy 177.795474 -313.446828)
			(xy 177.796444 -313.437524) (xy 177.797968 -313.42584) (xy 177.790348 -313.40425) (xy 177.717958 -313.331352)
			(xy 177.696368 -313.323732) (xy 177.684684 -313.325002) (xy 177.649886 -313.32678) (xy 177.6242 -313.326275)
			(xy 177.573461 -313.318237) (xy 177.524605 -313.30236) (xy 177.478833 -313.279037) (xy 177.437273 -313.24884)
			(xy 177.400949 -313.212514) (xy 177.370754 -313.170952) (xy 177.347433 -313.125179) (xy 177.331559 -313.076322)
			(xy 177.323523 -313.025583) (xy 177.323524 -312.974211) (xy 177.331561 -312.923472) (xy 177.347435 -312.874614)
			(xy 177.370758 -312.828842) (xy 177.400953 -312.787281) (xy 177.437278 -312.750956) (xy 177.478838 -312.72076)
			(xy 177.524611 -312.697437) (xy 177.573468 -312.681562) (xy 177.624207 -312.673524) (xy 177.675579 -312.673523)
			(xy 177.726318 -312.681558) (xy 177.775176 -312.697431) (xy 177.820949 -312.720752) (xy 177.862511 -312.750946)
			(xy 177.898837 -312.78727) (xy 177.929035 -312.828829) (xy 177.952359 -312.874601) (xy 177.968236 -312.923457)
			(xy 177.976275 -312.974196) (xy 177.976784 -312.999882) (xy 177.975006 -313.03468) (xy 177.973736 -313.04611)
			(xy 177.98161 -313.0677) (xy 178.054254 -313.14009) (xy 178.076098 -313.14771) (xy 178.087528 -313.146186)
			(xy 178.096895 -313.145211) (xy 178.115702 -313.144196) (xy 178.12512 -313.144154) (xy 178.138711 -313.144324)
			(xy 178.165796 -313.146611) (xy 178.179222 -313.148726) (xy 178.19116 -313.150504) (xy 178.213766 -313.143646)
			(xy 178.29022 -313.070748) (xy 178.298094 -313.048396) (xy 178.296824 -313.036204) (xy 178.295776 -313.02716)
			(xy 178.294634 -313.008986) (xy 178.294538 -312.999882) (xy 178.295025 -312.975066) (xy 178.303057 -312.926088)
			(xy 178.318907 -312.879055) (xy 178.342157 -312.835205) (xy 178.372194 -312.795695) (xy 178.408227 -312.761563)
			(xy 178.449308 -312.733711) (xy 178.494353 -312.712872) (xy 178.542176 -312.699594) (xy 178.591517 -312.694227)
			(xy 178.641076 -312.696914) (xy 178.689548 -312.707582) (xy 178.735655 -312.725951) (xy 178.778184 -312.751538)
			(xy 178.816013 -312.783667) (xy 178.848146 -312.821494) (xy 178.873736 -312.86402) (xy 178.89211 -312.910125)
			(xy 178.902783 -312.958596) (xy 178.905474 -313.008155) (xy 178.900112 -313.057497) (xy 178.886838 -313.105321)
			(xy 178.866003 -313.150368) (xy 178.838154 -313.191451) (xy 178.804026 -313.227487) (xy 178.764518 -313.257528)
			(xy 178.720671 -313.280782) (xy 178.673639 -313.296636) (xy 178.624662 -313.304673) (xy 178.599846 -313.30519)
			(xy 178.590745 -313.305152) (xy 178.572572 -313.304138) (xy 178.563524 -313.303158) (xy 178.551586 -313.301634)
			(xy 178.529234 -313.309508) (xy 178.456336 -313.385962) (xy 178.449224 -313.408568) (xy 178.451256 -313.420506)
			(xy 178.453388 -313.433994) (xy 178.455679 -313.461207) (xy 178.455828 -313.474862) (xy 178.455828 -313.54522)
			(xy 178.456292 -313.555876) (xy 178.464983 -313.575335) (xy 178.472592 -313.582812) (xy 178.536854 -313.640724)
			(xy 178.557174 -313.647328) (xy 178.568096 -313.646312) (xy 178.599846 -313.644534) (xy 178.623834 -313.645008)
			(xy 178.671217 -313.65252) (xy 178.716843 -313.667352) (xy 178.759586 -313.689139) (xy 178.798395 -313.717344)
			(xy 178.832313 -313.751272) (xy 178.860507 -313.790089) (xy 178.882282 -313.832839) (xy 178.8971 -313.878468)
			(xy 178.904599 -313.925854) (xy 178.905154 -313.949842) (xy 178.905056 -313.958946) (xy 178.903912 -313.977119)
			(xy 178.902868 -313.986164) (xy 178.901598 -313.998356) (xy 178.909472 -314.020708) (xy 178.985926 -314.093606)
			(xy 179.008532 -314.100718) (xy 179.02047 -314.098686) (xy 179.032638 -314.096743) (xy 179.057175 -314.094452)
			(xy 179.069492 -314.094114) (xy 179.080244 -314.094011) (xy 179.101724 -314.09503) (xy 179.112418 -314.096146)
			(xy 179.123848 -314.097416) (xy 179.145692 -314.09005) (xy 179.218336 -314.01766) (xy 179.22621 -313.99607)
			(xy 179.22494 -313.984386) (xy 179.222908 -313.949842) (xy 179.223384 -313.924138) (xy 179.231424 -313.873361)
			(xy 179.247313 -313.824469) (xy 179.270659 -313.778667) (xy 179.300886 -313.737084) (xy 179.33725 -313.700744)
			(xy 179.378854 -313.670545) (xy 179.424671 -313.647229) (xy 179.473574 -313.631373) (xy 179.524355 -313.623367)
			(xy 179.55006 -313.622944) (xy 179.582572 -313.624468) (xy 179.593494 -313.625484) (xy 179.613814 -313.61888)
			(xy 179.677568 -313.560968) (xy 179.685071 -313.553421) (xy 179.693717 -313.534002) (xy 179.694332 -313.523376)
			(xy 179.694332 -313.474862) (xy 179.694373 -313.465508) (xy 179.695388 -313.446827) (xy 179.696364 -313.437524)
			(xy 179.697634 -313.42584) (xy 179.690268 -313.40425) (xy 179.617878 -313.331606) (xy 179.596288 -313.323732)
			(xy 179.584604 -313.325002) (xy 179.55006 -313.32678) (xy 179.524344 -313.326298) (xy 179.473546 -313.318245)
			(xy 179.424634 -313.302343) (xy 179.378813 -313.278985) (xy 179.33721 -313.248745) (xy 179.300851 -313.212368)
			(xy 179.270631 -313.17075) (xy 179.247295 -313.124917) (xy 179.231417 -313.075997) (xy 179.223389 -313.025196)
			(xy 179.223408 -312.973763) (xy 179.231474 -312.922968) (xy 179.247388 -312.87406) (xy 179.270758 -312.828244)
			(xy 179.301008 -312.786649) (xy 179.337394 -312.750298) (xy 179.379019 -312.720089) (xy 179.424858 -312.696764)
			(xy 179.473782 -312.680899) (xy 179.524585 -312.672883) (xy 179.576017 -312.672914) (xy 179.626811 -312.680993)
			(xy 179.675715 -312.696919) (xy 179.721525 -312.7203) (xy 179.763113 -312.750561) (xy 179.799454 -312.786955)
			(xy 179.829653 -312.828588) (xy 179.852967 -312.874432) (xy 179.86882 -312.92336) (xy 179.876824 -312.974166)
			(xy 179.877212 -312.999882) (xy 179.87518 -313.034426) (xy 179.87391 -313.04611) (xy 179.881784 -313.067446)
			(xy 179.954682 -313.139836) (xy 179.976272 -313.147456) (xy 179.987702 -313.145932) (xy 179.997006 -313.144965)
			(xy 180.015686 -313.143949) (xy 180.02504 -313.1439) (xy 180.038694 -313.144061) (xy 180.065907 -313.146348)
			(xy 180.079396 -313.148472) (xy 180.091334 -313.150504) (xy 180.11394 -313.143392) (xy 180.190394 -313.070494)
			(xy 180.198268 -313.048142) (xy 180.196998 -313.036204) (xy 180.19595 -313.02716) (xy 180.194807 -313.008986)
			(xy 180.194712 -312.999882) (xy 180.195199 -312.975063) (xy 180.203232 -312.926081) (xy 180.219084 -312.879043)
			(xy 180.242336 -312.835189) (xy 180.272377 -312.795674) (xy 180.308415 -312.76154) (xy 180.3495 -312.733686)
			(xy 180.39455 -312.712845) (xy 180.442378 -312.699567) (xy 180.491724 -312.694201) (xy 180.541289 -312.696889)
			(xy 180.589765 -312.70756) (xy 180.635877 -312.725933) (xy 180.678409 -312.751524) (xy 180.71624 -312.783658)
			(xy 180.748375 -312.82149) (xy 180.773966 -312.864021) (xy 180.792339 -312.910133) (xy 180.803011 -312.958609)
			(xy 180.805699 -313.008174) (xy 180.800334 -313.05752) (xy 180.787056 -313.105348) (xy 180.766215 -313.150398)
			(xy 180.738361 -313.191484) (xy 180.704227 -313.227522) (xy 180.664713 -313.257563) (xy 180.620859 -313.280815)
			(xy 180.573821 -313.296667) (xy 180.524839 -313.304701) (xy 180.50002 -313.30519) (xy 180.490983 -313.305143)
			(xy 180.472937 -313.304126) (xy 180.463952 -313.303158) (xy 180.45176 -313.301634) (xy 180.429662 -313.309508)
			(xy 180.356764 -313.385962) (xy 180.349652 -313.408568) (xy 180.351684 -313.42076) (xy 180.353801 -313.434186)
			(xy 180.356087 -313.461271) (xy 180.356256 -313.474862) (xy 180.356256 -313.54522) (xy 180.356721 -313.555876)
			(xy 180.365415 -313.575331) (xy 180.37302 -313.582812) (xy 180.437282 -313.640724) (xy 180.457602 -313.647328)
			(xy 180.46827 -313.646058) (xy 180.50002 -313.644534) (xy 180.524011 -313.644982) (xy 180.571402 -313.652491)
			(xy 180.617034 -313.667322) (xy 180.659784 -313.689109) (xy 180.6986 -313.717316) (xy 180.732525 -313.751248)
			(xy 180.760723 -313.790069) (xy 180.782502 -313.832824) (xy 180.797323 -313.878459) (xy 180.804823 -313.925851)
			(xy 180.805328 -313.949842) (xy 180.80523 -313.958946) (xy 180.804086 -313.977119) (xy 180.803042 -313.986164)
			(xy 180.801772 -313.998356) (xy 180.809646 -314.020708) (xy 180.8861 -314.093606) (xy 180.908706 -314.100464)
			(xy 180.920644 -314.098432) (xy 180.932752 -314.096554) (xy 180.957162 -314.094389) (xy 180.969412 -314.094114)
			(xy 180.980164 -314.094012) (xy 181.001643 -314.095032) (xy 181.012338 -314.096146) (xy 181.023768 -314.097416)
			(xy 181.045612 -314.09005) (xy 181.118256 -314.01766) (xy 181.12613 -313.99607) (xy 181.12486 -313.984386)
			(xy 181.122828 -313.949842) (xy 181.123304 -313.924138) (xy 181.131344 -313.873363) (xy 181.147233 -313.824472)
			(xy 181.17058 -313.778672) (xy 181.200807 -313.73709) (xy 181.237171 -313.700753) (xy 181.278775 -313.670555)
			(xy 181.324593 -313.647242) (xy 181.373495 -313.631389) (xy 181.424276 -313.623385) (xy 181.44998 -313.622944)
			(xy 181.482492 -313.624468) (xy 181.493414 -313.625484) (xy 181.513734 -313.61888) (xy 181.577488 -313.560968)
			(xy 181.584988 -313.55342) (xy 181.593631 -313.534001) (xy 181.594252 -313.523376) (xy 181.594252 -313.474862)
			(xy 181.594293 -313.465508) (xy 181.595308 -313.446827) (xy 181.596284 -313.437524) (xy 181.597554 -313.42584)
			(xy 181.590188 -313.40425) (xy 181.517798 -313.331606) (xy 181.496208 -313.323732) (xy 181.484524 -313.325002)
			(xy 181.44998 -313.32678) (xy 181.424264 -313.3263) (xy 181.373465 -313.31825) (xy 181.324551 -313.30235)
			(xy 181.278728 -313.278994) (xy 181.237123 -313.248756) (xy 181.200762 -313.21238) (xy 181.170539 -313.170763)
			(xy 181.147201 -313.124931) (xy 181.131321 -313.076011) (xy 181.12329 -313.025209) (xy 181.123307 -312.973776)
			(xy 181.131371 -312.92298) (xy 181.147283 -312.874071) (xy 181.170652 -312.828253) (xy 181.200901 -312.786656)
			(xy 181.237286 -312.750305) (xy 181.278911 -312.720094) (xy 181.32475 -312.696767) (xy 181.373674 -312.6809)
			(xy 181.424478 -312.672883) (xy 181.475911 -312.672914) (xy 181.526705 -312.680991) (xy 181.57561 -312.696917)
			(xy 181.621421 -312.720298) (xy 181.66301 -312.750558) (xy 181.699352 -312.786953) (xy 181.729552 -312.828586)
			(xy 181.752866 -312.874431) (xy 181.76872 -312.923359) (xy 181.776723 -312.974165) (xy 181.777132 -312.999882)
			(xy 181.7751 -313.034426) (xy 181.77383 -313.04611) (xy 181.781704 -313.067446) (xy 181.854602 -313.139836)
			(xy 181.876192 -313.147456) (xy 181.887622 -313.145932) (xy 181.896926 -313.144965) (xy 181.915606 -313.143951)
			(xy 181.92496 -313.1439) (xy 181.938614 -313.144062) (xy 181.965827 -313.14635) (xy 181.979316 -313.148472)
			(xy 181.991254 -313.150504) (xy 182.01386 -313.143392) (xy 182.090314 -313.070494) (xy 182.098188 -313.048142)
			(xy 182.096918 -313.036204) (xy 182.09587 -313.02716) (xy 182.094728 -313.008986) (xy 182.094632 -312.999882)
			(xy 182.095119 -312.975065) (xy 182.103151 -312.926086) (xy 182.119002 -312.879052) (xy 182.142252 -312.835201)
			(xy 182.17229 -312.79569) (xy 182.208324 -312.761558) (xy 182.249406 -312.733705) (xy 182.294452 -312.712865)
			(xy 182.342276 -312.699587) (xy 182.391618 -312.694221) (xy 182.441179 -312.696908) (xy 182.489652 -312.707577)
			(xy 182.53576 -312.725947) (xy 182.578289 -312.751535) (xy 182.616119 -312.783665) (xy 182.648252 -312.821493)
			(xy 182.673843 -312.86402) (xy 182.692217 -312.910127) (xy 182.702889 -312.958599) (xy 182.705579 -313.00816)
			(xy 182.703685 -313.02559) (xy 183.023252 -313.02559) (xy 183.023252 -312.974174) (xy 183.031295 -312.923392)
			(xy 183.047183 -312.874493) (xy 183.070526 -312.828681) (xy 183.100747 -312.787085) (xy 183.137103 -312.750729)
			(xy 183.178699 -312.720508) (xy 183.224511 -312.697165) (xy 183.27341 -312.681277) (xy 183.324192 -312.673234)
			(xy 183.375608 -312.673234) (xy 183.42639 -312.681277) (xy 183.475289 -312.697165) (xy 183.521101 -312.720508)
			(xy 183.562697 -312.750729) (xy 183.599053 -312.787085) (xy 183.629274 -312.828681) (xy 183.652617 -312.874493)
			(xy 183.668505 -312.923392) (xy 183.676548 -312.974174) (xy 183.677052 -312.999882) (xy 183.994056 -312.999882)
			(xy 183.998016 -312.950828) (xy 184.009793 -312.903044) (xy 184.029084 -312.857768) (xy 184.055387 -312.816172)
			(xy 184.088022 -312.779335) (xy 184.126143 -312.74821) (xy 184.168764 -312.723603) (xy 184.21478 -312.706151)
			(xy 184.262999 -312.696307) (xy 184.312174 -312.694326) (xy 184.361029 -312.700258) (xy 184.4083 -312.71395)
			(xy 184.452762 -312.735048) (xy 184.493265 -312.763004) (xy 184.528758 -312.797096) (xy 184.558323 -312.83644)
			(xy 184.581194 -312.880017) (xy 184.596778 -312.926698) (xy 184.604673 -312.975275) (xy 184.605168 -312.999882)
			(xy 184.604673 -313.024489) (xy 184.596778 -313.073066) (xy 184.581194 -313.119747) (xy 184.558323 -313.163324)
			(xy 184.528758 -313.202668) (xy 184.493265 -313.23676) (xy 184.452762 -313.264716) (xy 184.4083 -313.285814)
			(xy 184.361029 -313.299506) (xy 184.312174 -313.305438) (xy 184.262999 -313.303457) (xy 184.21478 -313.293613)
			(xy 184.168764 -313.276161) (xy 184.126143 -313.251554) (xy 184.088022 -313.220429) (xy 184.055387 -313.183592)
			(xy 184.029084 -313.141996) (xy 184.009793 -313.09672) (xy 183.998016 -313.048936) (xy 183.994056 -312.999882)
			(xy 183.677052 -312.999882) (xy 183.676548 -313.02559) (xy 183.668505 -313.076372) (xy 183.652617 -313.125271)
			(xy 183.629274 -313.171083) (xy 183.599053 -313.212679) (xy 183.562697 -313.249035) (xy 183.521101 -313.279256)
			(xy 183.475289 -313.302599) (xy 183.42639 -313.318487) (xy 183.375608 -313.32653) (xy 183.324192 -313.32653)
			(xy 183.27341 -313.318487) (xy 183.224511 -313.302599) (xy 183.178699 -313.279256) (xy 183.137103 -313.249035)
			(xy 183.100747 -313.212679) (xy 183.070526 -313.171083) (xy 183.047183 -313.125271) (xy 183.031295 -313.076372)
			(xy 183.023252 -313.02559) (xy 182.703685 -313.02559) (xy 182.700217 -313.057502) (xy 182.686942 -313.105327)
			(xy 182.666106 -313.150375) (xy 182.638256 -313.191458) (xy 182.604127 -313.227495) (xy 182.564617 -313.257536)
			(xy 182.520768 -313.28079) (xy 182.473735 -313.296643) (xy 182.424757 -313.304679) (xy 182.39994 -313.30519)
			(xy 182.390903 -313.305144) (xy 182.372857 -313.304128) (xy 182.363872 -313.303158) (xy 182.35168 -313.301634)
			(xy 182.329582 -313.309508) (xy 182.256684 -313.385962) (xy 182.249572 -313.408568) (xy 182.251604 -313.42076)
			(xy 182.253722 -313.434186) (xy 182.256007 -313.461271) (xy 182.256176 -313.474862) (xy 182.256176 -313.54522)
			(xy 182.256639 -313.555878) (xy 182.265323 -313.575342) (xy 182.27294 -313.582812) (xy 182.337202 -313.640724)
			(xy 182.357522 -313.647328) (xy 182.36819 -313.646058) (xy 182.39994 -313.644534) (xy 182.42519 -313.645059)
			(xy 182.474999 -313.653376) (xy 182.522761 -313.669778) (xy 182.567172 -313.693818) (xy 182.607021 -313.724838)
			(xy 182.641221 -313.761994) (xy 182.668839 -313.804272) (xy 182.689123 -313.850518) (xy 182.701519 -313.899473)
			(xy 182.705689 -313.9498) (xy 182.703555 -313.97555) (xy 183.023252 -313.97555) (xy 183.023252 -313.924134)
			(xy 183.031295 -313.873352) (xy 183.047183 -313.824453) (xy 183.070526 -313.778641) (xy 183.100747 -313.737045)
			(xy 183.137103 -313.700689) (xy 183.178699 -313.670468) (xy 183.224511 -313.647125) (xy 183.27341 -313.631237)
			(xy 183.324192 -313.623194) (xy 183.375608 -313.623194) (xy 183.42639 -313.631237) (xy 183.475289 -313.647125)
			(xy 183.521101 -313.670468) (xy 183.562697 -313.700689) (xy 183.599053 -313.737045) (xy 183.629274 -313.778641)
			(xy 183.652617 -313.824453) (xy 183.668505 -313.873352) (xy 183.676548 -313.924134) (xy 183.677052 -313.949842)
			(xy 183.994056 -313.949842) (xy 183.998016 -313.900788) (xy 184.009793 -313.853004) (xy 184.029084 -313.807728)
			(xy 184.055387 -313.766132) (xy 184.088022 -313.729295) (xy 184.126143 -313.69817) (xy 184.168764 -313.673563)
			(xy 184.21478 -313.656111) (xy 184.262999 -313.646267) (xy 184.312174 -313.644286) (xy 184.361029 -313.650218)
			(xy 184.4083 -313.66391) (xy 184.452762 -313.685008) (xy 184.493265 -313.712964) (xy 184.528758 -313.747056)
			(xy 184.558323 -313.7864) (xy 184.581194 -313.829977) (xy 184.596778 -313.876658) (xy 184.604673 -313.925235)
			(xy 184.605168 -313.949842) (xy 184.604673 -313.974449) (xy 184.596778 -314.023026) (xy 184.581194 -314.069707)
			(xy 184.558323 -314.113284) (xy 184.528758 -314.152628) (xy 184.493265 -314.18672) (xy 184.452762 -314.214676)
			(xy 184.4083 -314.235774) (xy 184.361029 -314.249466) (xy 184.312174 -314.255398) (xy 184.262999 -314.253417)
			(xy 184.21478 -314.243573) (xy 184.168764 -314.226121) (xy 184.126143 -314.201514) (xy 184.088022 -314.170389)
			(xy 184.055387 -314.133552) (xy 184.029084 -314.091956) (xy 184.009793 -314.04668) (xy 183.998016 -313.998896)
			(xy 183.994056 -313.949842) (xy 183.677052 -313.949842) (xy 183.676548 -313.97555) (xy 183.668505 -314.026332)
			(xy 183.652617 -314.075231) (xy 183.629274 -314.121043) (xy 183.599053 -314.162639) (xy 183.562697 -314.198995)
			(xy 183.521101 -314.229216) (xy 183.475289 -314.252559) (xy 183.42639 -314.268447) (xy 183.375608 -314.27649)
			(xy 183.324192 -314.27649) (xy 183.27341 -314.268447) (xy 183.224511 -314.252559) (xy 183.178699 -314.229216)
			(xy 183.137103 -314.198995) (xy 183.100747 -314.162639) (xy 183.070526 -314.121043) (xy 183.047183 -314.075231)
			(xy 183.031295 -314.026332) (xy 183.023252 -313.97555) (xy 182.703555 -313.97555) (xy 182.701519 -314.000127)
			(xy 182.689123 -314.049082) (xy 182.668839 -314.095328) (xy 182.641221 -314.137606) (xy 182.607021 -314.174762)
			(xy 182.567172 -314.205782) (xy 182.522761 -314.229822) (xy 182.474999 -314.246224) (xy 182.42519 -314.254541)
			(xy 182.39994 -314.25515) (xy 182.36819 -314.253626) (xy 182.357522 -314.252356) (xy 182.337202 -314.25896)
			(xy 182.27294 -314.316872) (xy 182.265426 -314.324415) (xy 182.256756 -314.343834) (xy 182.256176 -314.354464)
			(xy 182.256176 -314.424822) (xy 182.256012 -314.438476) (xy 182.25372 -314.465688) (xy 182.251604 -314.479178)
			(xy 182.249572 -314.491116) (xy 182.256684 -314.513722) (xy 182.329582 -314.590176) (xy 182.35168 -314.59805)
			(xy 182.363872 -314.596526) (xy 182.372856 -314.595543) (xy 182.390902 -314.594526) (xy 182.39994 -314.594494)
			(xy 182.423554 -314.594937) (xy 182.470219 -314.602211) (xy 182.515209 -314.616581) (xy 182.557452 -314.637702)
			(xy 182.595941 -314.665073) (xy 182.629759 -314.69804) (xy 182.658101 -314.73582) (xy 182.680291 -314.777511)
			(xy 182.695801 -314.82212) (xy 182.704262 -314.868585) (xy 182.705248 -314.892182) (xy 182.705877 -314.90232)
			(xy 182.714098 -314.920875) (xy 182.72889 -314.934769) (xy 182.738268 -314.938664) (xy 182.794402 -314.961524)
			(xy 182.804308 -314.965842) (xy 182.944516 -314.965842) (xy 182.953963 -314.965357) (xy 182.971556 -314.958454)
			(xy 182.978806 -314.95238) (xy 183.036464 -314.899548) (xy 183.044846 -314.882784) (xy 183.045862 -314.873132)
			(xy 183.048574 -314.848108) (xy 183.061138 -314.799371) (xy 183.081528 -314.753356) (xy 183.109192 -314.71131)
			(xy 183.143379 -314.674372) (xy 183.183163 -314.643544) (xy 183.227466 -314.619661) (xy 183.275086 -314.603369)
			(xy 183.324735 -314.595112) (xy 183.375065 -314.595112) (xy 183.424714 -314.603369) (xy 183.472334 -314.619661)
			(xy 183.516637 -314.643544) (xy 183.556421 -314.674372) (xy 183.590608 -314.71131) (xy 183.618272 -314.753356)
			(xy 183.638662 -314.799371) (xy 183.651226 -314.848108) (xy 183.653938 -314.873132) (xy 183.654954 -314.882784)
			(xy 183.663336 -314.899548) (xy 183.720994 -314.95238) (xy 183.728196 -314.958539) (xy 183.745816 -314.965471)
			(xy 183.755284 -314.965842) (xy 183.895492 -314.965842) (xy 183.905398 -314.961524) (xy 183.961532 -314.938664)
			(xy 183.970868 -314.934694) (xy 183.985635 -314.920808) (xy 183.993913 -314.902304) (xy 183.994552 -314.892182)
			(xy 183.995661 -314.867339) (xy 184.004938 -314.818487) (xy 184.022007 -314.771783) (xy 184.046417 -314.728461)
			(xy 184.077523 -314.689666) (xy 184.114503 -314.656422) (xy 184.15638 -314.629609) (xy 184.202047 -314.609934)
			(xy 184.250299 -314.597917) (xy 184.29986 -314.593875) (xy 184.349421 -314.597917) (xy 184.397673 -314.609934)
			(xy 184.44334 -314.629609) (xy 184.485217 -314.656422) (xy 184.522197 -314.689666) (xy 184.553303 -314.728461)
			(xy 184.577713 -314.771783) (xy 184.594782 -314.818487) (xy 184.604059 -314.867339) (xy 184.605168 -314.892182)
			(xy 184.605798 -314.902319) (xy 184.61402 -314.920871) (xy 184.628814 -314.93476) (xy 184.638188 -314.938664)
			(xy 184.694322 -314.961524) (xy 184.704228 -314.965842) (xy 184.84469 -314.965842) (xy 184.854131 -314.965344)
			(xy 184.871707 -314.958423) (xy 184.87898 -314.95238) (xy 184.936638 -314.899548) (xy 184.94502 -314.882784)
			(xy 184.946036 -314.873132) (xy 184.948753 -314.848106) (xy 184.961326 -314.799366) (xy 184.981719 -314.753347)
			(xy 185.009382 -314.711295) (xy 185.043566 -314.674347) (xy 185.083344 -314.643504) (xy 185.127642 -314.6196)
			(xy 185.175259 -314.603282) (xy 185.224907 -314.594993) (xy 185.250074 -314.594494) (xy 185.259178 -314.594593)
			(xy 185.277351 -314.595738) (xy 185.286396 -314.59678) (xy 185.298334 -314.59805) (xy 185.320686 -314.590176)
			(xy 185.393584 -314.513722) (xy 185.400696 -314.491116) (xy 185.398664 -314.478924) (xy 185.395918 -314.461092)
			(xy 185.393876 -314.425069) (xy 185.3946 -314.407042) (xy 185.3946 -314.376308) (xy 185.394142 -314.365648)
			(xy 185.385462 -314.346178) (xy 185.377836 -314.338716) (xy 185.313828 -314.280804) (xy 185.293762 -314.2742)
			(xy 185.28284 -314.275216) (xy 185.250074 -314.27674) (xy 185.224384 -314.276234) (xy 185.173638 -314.268193)
			(xy 185.124774 -314.252313) (xy 185.078996 -314.228984) (xy 185.03743 -314.198782) (xy 185.001101 -314.16245)
			(xy 184.970902 -314.120882) (xy 184.947577 -314.075102) (xy 184.931701 -314.026237) (xy 184.923664 -313.97549)
			(xy 184.923664 -313.92411) (xy 184.931701 -313.873363) (xy 184.947577 -313.824498) (xy 184.970902 -313.778718)
			(xy 185.001101 -313.73715) (xy 185.03743 -313.700818) (xy 185.078996 -313.670616) (xy 185.124774 -313.647287)
			(xy 185.173638 -313.631407) (xy 185.224384 -313.623366) (xy 185.250074 -313.622944) (xy 185.28284 -313.624468)
			(xy 185.293762 -313.625484) (xy 185.313828 -313.61888) (xy 185.377836 -313.560968) (xy 185.385343 -313.553423)
			(xy 185.393994 -313.534003) (xy 185.3946 -313.523376) (xy 185.3946 -313.49315) (xy 185.393891 -313.474799)
			(xy 185.396057 -313.438138) (xy 185.398918 -313.419998) (xy 185.400933 -313.408927) (xy 185.406273 -313.387064)
			(xy 185.409586 -313.37631) (xy 185.412379 -313.365556) (xy 185.409482 -313.343553) (xy 185.397575 -313.324824)
			(xy 185.378879 -313.312866) (xy 185.356884 -313.309909) (xy 185.346086 -313.312556) (xy 185.322656 -313.319272)
			(xy 185.274444 -313.326421) (xy 185.250074 -313.32678) (xy 185.224389 -313.326274) (xy 185.173652 -313.318235)
			(xy 185.124797 -313.302357) (xy 185.079027 -313.279033) (xy 185.037469 -313.248837) (xy 185.001147 -313.212511)
			(xy 184.970953 -313.170951) (xy 184.947633 -313.125179) (xy 184.931759 -313.076323) (xy 184.923724 -313.025585)
			(xy 184.923724 -312.974215) (xy 184.931759 -312.923477) (xy 184.947633 -312.874621) (xy 184.970953 -312.828849)
			(xy 185.001147 -312.787289) (xy 185.037469 -312.750963) (xy 185.079027 -312.720767) (xy 185.124797 -312.697443)
			(xy 185.173652 -312.681565) (xy 185.224389 -312.673526) (xy 185.250074 -312.672984) (xy 185.284872 -312.674762)
			(xy 185.296556 -312.676032) (xy 185.318146 -312.668412) (xy 185.390536 -312.595514) (xy 185.398156 -312.573924)
			(xy 185.396632 -312.56224) (xy 185.394189 -312.535966) (xy 185.396679 -312.483261) (xy 185.407502 -312.431618)
			(xy 185.416444 -312.406792) (xy 185.417714 -312.403744) (xy 185.420927 -312.394504) (xy 185.420862 -312.37496)
			(xy 185.413496 -312.356856) (xy 185.399897 -312.342818) (xy 185.382037 -312.33488) (xy 185.362504 -312.334193)
			(xy 185.353198 -312.337196) (xy 185.328246 -312.34559) (xy 185.276394 -312.354661) (xy 185.250074 -312.35523)
			(xy 185.224818 -312.354706) (xy 185.174996 -312.346389) (xy 185.127223 -312.329984) (xy 185.0828 -312.305941)
			(xy 185.042941 -312.274914) (xy 185.008732 -312.23775) (xy 184.981106 -312.195463) (xy 184.960817 -312.149205)
			(xy 184.948418 -312.100239) (xy 184.944247 -312.0499) (xy 184.948418 -311.999561) (xy 184.960817 -311.950595)
			(xy 184.981106 -311.904337) (xy 185.008732 -311.86205) (xy 185.042941 -311.824886) (xy 185.0828 -311.793859)
			(xy 185.127223 -311.769816) (xy 185.174996 -311.753411) (xy 185.224818 -311.745094) (xy 185.250074 -311.744614)
			(xy 185.259242 -311.744706) (xy 185.277542 -311.745848) (xy 185.28665 -311.7469) (xy 185.298842 -311.74817)
			(xy 185.321194 -311.740296) (xy 185.394092 -311.663842) (xy 185.401204 -311.641236) (xy 185.399172 -311.629298)
			(xy 185.394947 -311.600344) (xy 185.395589 -311.541841) (xy 185.406554 -311.48437) (xy 185.416444 -311.456832)
			(xy 185.417714 -311.453784) (xy 185.420914 -311.444551) (xy 185.420832 -311.425028) (xy 185.413464 -311.406948)
			(xy 185.399875 -311.39293) (xy 185.382033 -311.385002) (xy 185.362522 -311.384313) (xy 185.353198 -311.387236)
			(xy 185.328247 -311.395632) (xy 185.276394 -311.404704) (xy 185.250074 -311.40527) (xy 185.224823 -311.404747)
			(xy 185.175011 -311.39643) (xy 185.127247 -311.380029) (xy 185.082833 -311.355991) (xy 185.042982 -311.32497)
			(xy 185.00878 -311.287813) (xy 184.981159 -311.245534) (xy 184.960874 -311.199286) (xy 184.948477 -311.150329)
			(xy 184.944307 -311.1) (xy 184.948477 -311.049671) (xy 184.960874 -311.000714) (xy 184.981159 -310.954466)
			(xy 185.00878 -310.912187) (xy 185.042982 -310.87503) (xy 185.082833 -310.844009) (xy 185.127247 -310.819971)
			(xy 185.175011 -310.80357) (xy 185.224823 -310.795253) (xy 185.250074 -310.794654) (xy 185.259242 -310.794746)
			(xy 185.277542 -310.795888) (xy 185.28665 -310.79694) (xy 185.298842 -310.79821) (xy 185.321194 -310.790336)
			(xy 185.394346 -310.713882) (xy 185.401204 -310.691276) (xy 185.399172 -310.679338) (xy 185.394951 -310.650342)
			(xy 185.3956 -310.591757) (xy 185.40656 -310.534202) (xy 185.416444 -310.506618) (xy 185.417714 -310.50357)
			(xy 185.420911 -310.494339) (xy 185.420826 -310.47482) (xy 185.413456 -310.456746) (xy 185.39987 -310.442732)
			(xy 185.382032 -310.434807) (xy 185.362526 -310.434118) (xy 185.353198 -310.437022) (xy 185.328246 -310.445416)
			(xy 185.276393 -310.454486) (xy 185.250074 -310.455056) (xy 185.224816 -310.454533) (xy 185.17499 -310.446214)
			(xy 185.127212 -310.429809) (xy 185.082786 -310.405763) (xy 185.042923 -310.374734) (xy 185.008711 -310.337566)
			(xy 184.981083 -310.295275) (xy 184.960792 -310.249014) (xy 184.948392 -310.200043) (xy 184.94422 -310.1497)
			(xy 184.948392 -310.099357) (xy 184.960792 -310.050386) (xy 184.981083 -310.004125) (xy 185.008711 -309.961834)
			(xy 185.042923 -309.924666) (xy 185.082786 -309.893637) (xy 185.127212 -309.869591) (xy 185.17499 -309.853186)
			(xy 185.224816 -309.844867) (xy 185.250074 -309.84444) (xy 185.259242 -309.844532) (xy 185.277542 -309.845674)
			(xy 185.28665 -309.846726) (xy 185.298842 -309.847996) (xy 185.321194 -309.840122) (xy 185.394092 -309.763668)
			(xy 185.401204 -309.741062) (xy 185.399172 -309.729124) (xy 185.394944 -309.70017) (xy 185.395582 -309.641665)
			(xy 185.406543 -309.584193) (xy 185.416444 -309.556658) (xy 185.42708 -309.530501) (xy 185.45594 -309.48197)
			(xy 185.473848 -309.460138) (xy 185.474356 -309.45963) (xy 185.475626 -309.458106) (xy 185.480747 -309.451184)
			(xy 185.486473 -309.434958) (xy 185.486802 -309.426356) (xy 185.486802 -308.977284) (xy 185.486294 -308.969664)
			(xy 185.484262 -308.957218) (xy 185.478674 -308.944772) (xy 185.473848 -308.939184) (xy 185.457741 -308.919652)
			(xy 185.431089 -308.87661) (xy 185.411326 -308.830002) (xy 185.398915 -308.780921) (xy 185.394148 -308.730521)
			(xy 185.397136 -308.679984) (xy 185.40781 -308.630497) (xy 185.416444 -308.606698) (xy 185.427078 -308.580539)
			(xy 185.455933 -308.532005) (xy 185.473848 -308.510178) (xy 185.474356 -308.50967) (xy 185.475626 -308.508146)
			(xy 185.480738 -308.501222) (xy 185.486445 -308.484996) (xy 185.486802 -308.476396) (xy 185.486802 -308.027324)
			(xy 185.486294 -308.019704) (xy 185.484262 -308.007258) (xy 185.478674 -307.994812) (xy 185.473848 -307.989224)
			(xy 185.457745 -307.969691) (xy 185.431102 -307.92665) (xy 185.411347 -307.880043) (xy 185.398945 -307.830965)
			(xy 185.394186 -307.780568) (xy 185.397182 -307.730036) (xy 185.407863 -307.680555) (xy 185.416444 -307.656738)
			(xy 185.427082 -307.630581) (xy 185.455944 -307.582053) (xy 185.473848 -307.560218) (xy 185.474356 -307.55971)
			(xy 185.475626 -307.558186) (xy 185.480744 -307.551264) (xy 185.486463 -307.535038) (xy 185.486802 -307.526436)
			(xy 185.486802 -307.077364) (xy 185.486294 -307.069744) (xy 185.484262 -307.057298) (xy 185.478674 -307.044852)
			(xy 185.473848 -307.039264) (xy 185.457742 -307.019732) (xy 185.431093 -306.97669) (xy 185.411333 -306.930082)
			(xy 185.398925 -306.881002) (xy 185.39416 -306.830603) (xy 185.397152 -306.780068) (xy 185.407828 -306.730583)
			(xy 185.416444 -306.706778) (xy 185.427079 -306.68062) (xy 185.455937 -306.632088) (xy 185.473848 -306.610258)
			(xy 185.474356 -306.60975) (xy 185.475626 -306.608226) (xy 185.480735 -306.601301) (xy 185.486436 -306.585075)
			(xy 185.486802 -306.576476) (xy 185.486802 -306.127404) (xy 185.486294 -306.119784) (xy 185.484262 -306.107338)
			(xy 185.478674 -306.094892) (xy 185.473848 -306.089304) (xy 185.45774 -306.069772) (xy 185.431085 -306.02673)
			(xy 185.411319 -305.980122) (xy 185.398905 -305.93104) (xy 185.394135 -305.880639) (xy 185.397121 -305.8301)
			(xy 185.407793 -305.780611) (xy 185.416444 -305.756818) (xy 185.427083 -305.730662) (xy 185.455948 -305.682136)
			(xy 185.473848 -305.660298) (xy 185.474356 -305.65979) (xy 185.475626 -305.658266) (xy 185.480741 -305.651343)
			(xy 185.486454 -305.635117) (xy 185.486802 -305.626516) (xy 185.486802 -305.17719) (xy 185.486294 -305.16957)
			(xy 185.484262 -305.157124) (xy 185.478674 -305.144678) (xy 185.473848 -305.13909) (xy 185.457741 -305.119558)
			(xy 185.431088 -305.076516) (xy 185.411324 -305.029908) (xy 185.398912 -304.980827) (xy 185.394144 -304.930426)
			(xy 185.397132 -304.879889) (xy 185.407805 -304.830401) (xy 185.416444 -304.806604) (xy 185.427077 -304.780445)
			(xy 185.455932 -304.73191) (xy 185.473848 -304.710084) (xy 185.474356 -304.709576) (xy 185.475626 -304.708052)
			(xy 185.480739 -304.701128) (xy 185.486448 -304.684902) (xy 185.486802 -304.676302) (xy 185.486802 -304.22723)
			(xy 185.486294 -304.21961) (xy 185.484262 -304.207164) (xy 185.478674 -304.194718) (xy 185.473848 -304.18913)
			(xy 185.457745 -304.169597) (xy 185.431101 -304.126556) (xy 185.411345 -304.079948) (xy 185.398942 -304.03087)
			(xy 185.394182 -303.980473) (xy 185.397178 -303.929941) (xy 185.407858 -303.880459) (xy 185.416444 -303.856644)
			(xy 185.427081 -303.830487) (xy 185.455943 -303.781958) (xy 185.473848 -303.760124) (xy 185.474356 -303.759616)
			(xy 185.475626 -303.758092) (xy 185.480745 -303.75117) (xy 185.486466 -303.734944) (xy 185.486802 -303.726342)
			(xy 185.486802 -303.27727) (xy 185.486294 -303.26965) (xy 185.484262 -303.257204) (xy 185.478674 -303.244758)
			(xy 185.473848 -303.23917) (xy 185.457742 -303.219638) (xy 185.431092 -303.176596) (xy 185.411331 -303.129988)
			(xy 185.398922 -303.080908) (xy 185.394157 -303.030509) (xy 185.397147 -302.979973) (xy 185.407823 -302.930487)
			(xy 185.416444 -302.906684) (xy 185.427079 -302.880525) (xy 185.455936 -302.831993) (xy 185.473848 -302.810164)
			(xy 185.474356 -302.809656) (xy 185.475626 -302.808132) (xy 185.480736 -302.801208) (xy 185.486439 -302.784981)
			(xy 185.486802 -302.776382) (xy 185.486802 -302.32731) (xy 185.486294 -302.31969) (xy 185.484262 -302.307244)
			(xy 185.478674 -302.294798) (xy 185.473848 -302.28921) (xy 185.457739 -302.269678) (xy 185.431084 -302.226636)
			(xy 185.411317 -302.180027) (xy 185.398902 -302.130946) (xy 185.394131 -302.080544) (xy 185.397116 -302.030005)
			(xy 185.407787 -301.980515) (xy 185.416444 -301.956724) (xy 185.427083 -301.930568) (xy 185.455946 -301.882041)
			(xy 185.473848 -301.860204) (xy 185.474356 -301.859696) (xy 185.475626 -301.858172) (xy 185.480742 -301.851249)
			(xy 185.486457 -301.835023) (xy 185.486802 -301.826422) (xy 185.486802 -301.37735) (xy 185.486294 -301.36973)
			(xy 185.484262 -301.357284) (xy 185.478674 -301.344838) (xy 185.473848 -301.33925) (xy 185.457743 -301.319718)
			(xy 185.431096 -301.276676) (xy 185.411338 -301.230068) (xy 185.398932 -301.180989) (xy 185.394169 -301.130591)
			(xy 185.397162 -301.080057) (xy 185.40784 -301.030573) (xy 185.416444 -301.006764) (xy 185.42708 -300.980606)
			(xy 185.455939 -300.932076) (xy 185.473848 -300.910244) (xy 185.474356 -300.909736) (xy 185.475626 -300.908212)
			(xy 185.480733 -300.901287) (xy 185.486429 -300.88506) (xy 185.486802 -300.876462) (xy 185.486802 -300.42739)
			(xy 185.486294 -300.41977) (xy 185.484262 -300.407324) (xy 185.478674 -300.394878) (xy 185.473848 -300.38929)
			(xy 185.457741 -300.369758) (xy 185.431088 -300.326716) (xy 185.411324 -300.280108) (xy 185.398912 -300.231027)
			(xy 185.394144 -300.180626) (xy 185.397132 -300.130089) (xy 185.407805 -300.080601) (xy 185.416444 -300.056804)
			(xy 185.427077 -300.030645) (xy 185.455932 -299.98211) (xy 185.473848 -299.960284) (xy 185.474356 -299.959776)
			(xy 185.475626 -299.958252) (xy 185.480739 -299.951328) (xy 185.486448 -299.935102) (xy 185.486802 -299.926502)
			(xy 185.486802 -299.47743) (xy 185.486294 -299.46981) (xy 185.484262 -299.457364) (xy 185.478674 -299.444918)
			(xy 185.473848 -299.43933) (xy 185.457745 -299.419797) (xy 185.431101 -299.376756) (xy 185.411345 -299.330148)
			(xy 185.398942 -299.28107) (xy 185.394182 -299.230673) (xy 185.397178 -299.180141) (xy 185.407858 -299.130659)
			(xy 185.416444 -299.106844) (xy 185.427081 -299.080687) (xy 185.455943 -299.032158) (xy 185.473848 -299.010324)
			(xy 185.474356 -299.009816) (xy 185.475626 -299.008292) (xy 185.480745 -299.00137) (xy 185.486466 -298.985144)
			(xy 185.486802 -298.976542) (xy 185.486802 -298.527216) (xy 185.486294 -298.519596) (xy 185.484262 -298.50715)
			(xy 185.478674 -298.494704) (xy 185.473848 -298.489116) (xy 185.457746 -298.469583) (xy 185.431103 -298.426541)
			(xy 185.41135 -298.379935) (xy 185.398949 -298.330857) (xy 185.394191 -298.280461) (xy 185.397188 -298.22993)
			(xy 185.407871 -298.180449) (xy 185.416444 -298.15663) (xy 185.427082 -298.130474) (xy 185.455945 -298.081946)
			(xy 185.473848 -298.06011) (xy 185.474356 -298.059602) (xy 185.475626 -298.058078) (xy 185.480743 -298.051155)
			(xy 185.48646 -298.034929) (xy 185.486802 -298.026328) (xy 185.486802 -297.577256) (xy 185.486294 -297.569636)
			(xy 185.484262 -297.55719) (xy 185.478674 -297.544744) (xy 185.473848 -297.539156) (xy 185.457743 -297.519624)
			(xy 185.431095 -297.476582) (xy 185.411336 -297.429974) (xy 185.398929 -297.380895) (xy 185.394165 -297.330496)
			(xy 185.397158 -297.279962) (xy 185.407835 -297.230477) (xy 185.416444 -297.20667) (xy 185.42708 -297.180512)
			(xy 185.455938 -297.131981) (xy 185.473848 -297.11015) (xy 185.474356 -297.109642) (xy 185.483246 -297.098466)
			(xy 185.485024 -297.089322) (xy 185.5216 -297.089322) (xy 185.53684 -297.084242) (xy 185.543444 -297.079416)
			(xy 185.552624 -297.072699) (xy 185.57182 -297.060493) (xy 185.581798 -297.055032) (xy 185.588656 -297.051476)
			(xy 185.753756 -296.886376) (xy 185.760604 -296.878978) (xy 185.768336 -296.86038) (xy 185.768742 -296.850308)
			(xy 185.768742 -296.751502) (xy 185.768287 -296.741622) (xy 185.760853 -296.723315) (xy 185.754264 -296.715942)
			(xy 185.732928 -296.694352) (xy 185.726304 -296.688027) (xy 185.709763 -296.680202) (xy 185.70067 -296.679112)
			(xy 185.675491 -296.676593) (xy 185.626412 -296.664283) (xy 185.580034 -296.64405) (xy 185.537626 -296.616448)
			(xy 185.50035 -296.582231) (xy 185.469226 -296.542337) (xy 185.445105 -296.497856) (xy 185.428648 -296.450008)
			(xy 185.420305 -296.400101) (xy 185.420305 -296.349502) (xy 185.428647 -296.299595) (xy 185.445104 -296.251747)
			(xy 185.469224 -296.207266) (xy 185.500348 -296.167371) (xy 185.537624 -296.133154) (xy 185.580031 -296.105551)
			(xy 185.626409 -296.085318) (xy 185.675488 -296.073008) (xy 185.70067 -296.070528) (xy 185.709738 -296.069356)
			(xy 185.726253 -296.061538) (xy 185.732928 -296.055288) (xy 185.754264 -296.033698) (xy 185.760837 -296.026314)
			(xy 185.768268 -296.008015) (xy 185.768742 -295.998138) (xy 185.768742 -294.851582) (xy 185.768283 -294.841704)
			(xy 185.760844 -294.823402) (xy 185.754264 -294.816022) (xy 185.732928 -294.794432) (xy 185.726303 -294.788109)
			(xy 185.709762 -294.780287) (xy 185.70067 -294.779192) (xy 185.67549 -294.776673) (xy 185.626407 -294.764366)
			(xy 185.580024 -294.744136) (xy 185.537611 -294.716537) (xy 185.500327 -294.682324) (xy 185.469194 -294.642433)
			(xy 185.445062 -294.597955) (xy 185.428591 -294.550108) (xy 185.420234 -294.500201) (xy 185.419746 -294.4749)
			(xy 185.420118 -294.453084) (xy 185.426334 -294.409898) (xy 185.43864 -294.368038) (xy 185.456784 -294.328358)
			(xy 185.46826 -294.3098) (xy 185.47842 -294.294052) (xy 185.47588 -294.27043) (xy 185.481468 -294.251126)
			(xy 185.48477 -294.23995) (xy 185.485721 -294.236471) (xy 185.486744 -294.229332) (xy 185.486802 -294.225726)
			(xy 185.486802 -293.777416) (xy 185.486294 -293.769796) (xy 185.484262 -293.75735) (xy 185.478674 -293.744904)
			(xy 185.473848 -293.739316) (xy 185.457746 -293.719783) (xy 185.431103 -293.676741) (xy 185.41135 -293.630135)
			(xy 185.398949 -293.581057) (xy 185.394191 -293.530661) (xy 185.397188 -293.48013) (xy 185.407871 -293.430649)
			(xy 185.416444 -293.40683) (xy 185.427082 -293.380674) (xy 185.455945 -293.332146) (xy 185.473848 -293.31031)
			(xy 185.474356 -293.309802) (xy 185.475626 -293.308278) (xy 185.480743 -293.301355) (xy 185.48646 -293.285129)
			(xy 185.486802 -293.276528) (xy 185.486802 -292.827202) (xy 185.486294 -292.819582) (xy 185.484262 -292.807136)
			(xy 185.478674 -292.79469) (xy 185.473848 -292.789102) (xy 185.45774 -292.76957) (xy 185.431085 -292.726528)
			(xy 185.411319 -292.67992) (xy 185.398906 -292.630838) (xy 185.394136 -292.580437) (xy 185.397122 -292.529899)
			(xy 185.407794 -292.48041) (xy 185.416444 -292.456616) (xy 185.427083 -292.43046) (xy 185.455948 -292.381934)
			(xy 185.473848 -292.360096) (xy 185.474356 -292.359588) (xy 185.475626 -292.358064) (xy 185.480741 -292.351141)
			(xy 185.486454 -292.334915) (xy 185.486802 -292.326314) (xy 185.486802 -291.877242) (xy 185.486294 -291.869622)
			(xy 185.484262 -291.857176) (xy 185.478674 -291.84473) (xy 185.473848 -291.839142) (xy 185.457744 -291.819609)
			(xy 185.431098 -291.776568) (xy 185.411341 -291.72996) (xy 185.398936 -291.680882) (xy 185.394174 -291.630484)
			(xy 185.397168 -291.57995) (xy 185.407848 -291.530468) (xy 185.416444 -291.506656) (xy 185.427081 -291.480499)
			(xy 185.455941 -291.431969) (xy 185.473848 -291.410136) (xy 185.474356 -291.409628) (xy 185.475626 -291.408104)
			(xy 185.480746 -291.401182) (xy 185.486472 -291.384956) (xy 185.486802 -291.376354) (xy 185.486802 -290.927282)
			(xy 185.486294 -290.919662) (xy 185.484262 -290.907216) (xy 185.478674 -290.89477) (xy 185.473848 -290.889182)
			(xy 185.457741 -290.86965) (xy 185.43109 -290.826608) (xy 185.411326 -290.78) (xy 185.398916 -290.73092)
			(xy 185.394149 -290.680519) (xy 185.397138 -290.629983) (xy 185.407812 -290.580496) (xy 185.416444 -290.556696)
			(xy 185.427078 -290.530537) (xy 185.455934 -290.482003) (xy 185.473848 -290.460176) (xy 185.474356 -290.459668)
			(xy 185.475626 -290.458144) (xy 185.480738 -290.45122) (xy 185.486444 -290.434994) (xy 185.486802 -290.426394)
			(xy 185.486802 -289.977322) (xy 185.486294 -289.969702) (xy 185.484262 -289.957256) (xy 185.478674 -289.94481)
			(xy 185.473848 -289.939222) (xy 185.457745 -289.919689) (xy 185.431102 -289.876648) (xy 185.411348 -289.830041)
			(xy 185.398946 -289.780963) (xy 185.394187 -289.730566) (xy 185.397184 -289.680034) (xy 185.407865 -289.630554)
			(xy 185.416444 -289.606736) (xy 185.427082 -289.580579) (xy 185.455944 -289.532051) (xy 185.473848 -289.510216)
			(xy 185.474356 -289.509708) (xy 185.475626 -289.508184) (xy 185.480744 -289.501262) (xy 185.486463 -289.485035)
			(xy 185.486802 -289.476434) (xy 185.486802 -289.027362) (xy 185.486294 -289.019742) (xy 185.484262 -289.007296)
			(xy 185.478674 -288.99485) (xy 185.473848 -288.989262) (xy 185.457743 -288.96973) (xy 185.431094 -288.926688)
			(xy 185.411334 -288.88008) (xy 185.398926 -288.831001) (xy 185.394162 -288.780602) (xy 185.397153 -288.730067)
			(xy 185.40783 -288.680582) (xy 185.416444 -288.656776) (xy 185.427079 -288.630618) (xy 185.455937 -288.582086)
			(xy 185.473848 -288.560256) (xy 185.474356 -288.559748) (xy 185.475626 -288.558224) (xy 185.480735 -288.551299)
			(xy 185.486435 -288.535073) (xy 185.486802 -288.526474) (xy 185.486802 -287.127442) (xy 185.486294 -287.119822)
			(xy 185.484262 -287.107376) (xy 185.478674 -287.09493) (xy 185.473848 -287.089342) (xy 185.457744 -287.069809)
			(xy 185.431098 -287.026768) (xy 185.411341 -286.98016) (xy 185.398936 -286.931082) (xy 185.394174 -286.880684)
			(xy 185.397168 -286.83015) (xy 185.407848 -286.780668) (xy 185.416444 -286.756856) (xy 185.427081 -286.730699)
			(xy 185.455941 -286.682169) (xy 185.473848 -286.660336) (xy 185.474356 -286.659828) (xy 185.475626 -286.658304)
			(xy 185.480746 -286.651382) (xy 185.486472 -286.635156) (xy 185.486802 -286.626554) (xy 185.486802 -286.370776)
			(xy 185.48631 -286.360771) (xy 185.478646 -286.342288) (xy 185.464494 -286.328142) (xy 185.446007 -286.320486)
			(xy 185.436002 -286.319976) (xy 156.501338 -286.319976) (xy 156.491273 -286.319541) (xy 156.472687 -286.311808)
			(xy 156.46527 -286.30499) (xy 156.431234 -286.270954) (xy 156.404818 -286.263842) (xy 156.39161 -286.267398)
			(xy 156.378656 -286.269176) (xy 148.312124 -286.269176) (xy 148.302582 -286.269632) (xy 148.284844 -286.276687)
			(xy 148.27758 -286.282892) (xy 148.263864 -286.295592) (xy 148.263356 -286.2961) (xy 148.22043 -286.335724)
			(xy 148.212048 -286.352742) (xy 148.211286 -286.362394) (xy 148.209679 -286.380141) (xy 148.203571 -286.41525)
			(xy 148.199094 -286.432498) (xy 148.189696 -286.462216) (xy 148.187918 -286.466534) (xy 148.17816 -286.4912)
			(xy 148.152788 -286.537783) (xy 148.121192 -286.580391) (xy 148.083985 -286.618197) (xy 148.063204 -286.634682)
			(xy 148.061172 -286.636206) (xy 148.0566 -286.640524) (xy 148.049445 -286.647866) (xy 148.04119 -286.666611)
			(xy 148.040598 -286.676846) (xy 148.04009 -286.717994) (xy 148.039328 -286.768032) (xy 148.049234 -286.789114)
			(xy 148.058632 -286.79648) (xy 148.080454 -286.814712) (xy 148.118977 -286.856536) (xy 148.150873 -286.90361)
			(xy 148.175436 -286.954893) (xy 148.192125 -287.009251) (xy 148.200568 -287.065483) (xy 148.201126 -287.093914)
			(xy 148.8346 -287.093914) (xy 148.838671 -287.038292) (xy 148.850797 -286.983855) (xy 148.87072 -286.931764)
			(xy 148.898016 -286.883129) (xy 148.932102 -286.838986) (xy 148.972251 -286.800277) (xy 149.017609 -286.767826)
			(xy 149.067209 -286.742325) (xy 149.119993 -286.724318) (xy 149.174836 -286.714188) (xy 149.23057 -286.712151)
			(xy 149.286007 -286.718251) (xy 149.339964 -286.732357) (xy 149.391293 -286.754169) (xy 149.438899 -286.783223)
			(xy 149.481767 -286.818898) (xy 149.518984 -286.860435) (xy 149.549757 -286.906948) (xy 149.573429 -286.957445)
			(xy 149.589497 -287.010852) (xy 149.597617 -287.066028) (xy 149.598126 -287.093914) (xy 149.72106 -287.093914)
			(xy 149.725131 -287.038292) (xy 149.737257 -286.983855) (xy 149.75718 -286.931764) (xy 149.784476 -286.883129)
			(xy 149.818562 -286.838986) (xy 149.858711 -286.800277) (xy 149.904069 -286.767826) (xy 149.953669 -286.742325)
			(xy 150.006453 -286.724318) (xy 150.061296 -286.714188) (xy 150.11703 -286.712151) (xy 150.172467 -286.718251)
			(xy 150.226424 -286.732357) (xy 150.277753 -286.754169) (xy 150.325359 -286.783223) (xy 150.368227 -286.818898)
			(xy 150.405444 -286.860435) (xy 150.415058 -286.874966) (xy 152.169126 -286.874966) (xy 152.173086 -286.825912)
			(xy 152.184863 -286.778128) (xy 152.204154 -286.732852) (xy 152.230457 -286.691256) (xy 152.263092 -286.654419)
			(xy 152.301213 -286.623294) (xy 152.343834 -286.598687) (xy 152.38985 -286.581235) (xy 152.438069 -286.571391)
			(xy 152.487244 -286.56941) (xy 152.536099 -286.575342) (xy 152.58337 -286.589034) (xy 152.627832 -286.610132)
			(xy 152.668335 -286.638088) (xy 152.703828 -286.67218) (xy 152.733393 -286.711524) (xy 152.756264 -286.755101)
			(xy 152.771848 -286.801782) (xy 152.779743 -286.850359) (xy 152.780238 -286.874966) (xy 153.119086 -286.874966)
			(xy 153.123046 -286.825912) (xy 153.134823 -286.778128) (xy 153.154114 -286.732852) (xy 153.180417 -286.691256)
			(xy 153.213052 -286.654419) (xy 153.251173 -286.623294) (xy 153.293794 -286.598687) (xy 153.33981 -286.581235)
			(xy 153.388029 -286.571391) (xy 153.437204 -286.56941) (xy 153.486059 -286.575342) (xy 153.53333 -286.589034)
			(xy 153.577792 -286.610132) (xy 153.618295 -286.638088) (xy 153.653788 -286.67218) (xy 153.683353 -286.711524)
			(xy 153.706224 -286.755101) (xy 153.721808 -286.801782) (xy 153.729703 -286.850359) (xy 153.730198 -286.874966)
			(xy 154.0693 -286.874966) (xy 154.07326 -286.825912) (xy 154.085037 -286.778128) (xy 154.104328 -286.732852)
			(xy 154.130631 -286.691256) (xy 154.163266 -286.654419) (xy 154.201387 -286.623294) (xy 154.244008 -286.598687)
			(xy 154.290024 -286.581235) (xy 154.338243 -286.571391) (xy 154.387418 -286.56941) (xy 154.436273 -286.575342)
			(xy 154.483544 -286.589034) (xy 154.528006 -286.610132) (xy 154.568509 -286.638088) (xy 154.604002 -286.67218)
			(xy 154.633567 -286.711524) (xy 154.656438 -286.755101) (xy 154.672022 -286.801782) (xy 154.679917 -286.850359)
			(xy 154.680412 -286.874966) (xy 155.01926 -286.874966) (xy 155.02322 -286.825912) (xy 155.034997 -286.778128)
			(xy 155.054288 -286.732852) (xy 155.080591 -286.691256) (xy 155.113226 -286.654419) (xy 155.151347 -286.623294)
			(xy 155.193968 -286.598687) (xy 155.239984 -286.581235) (xy 155.288203 -286.571391) (xy 155.337378 -286.56941)
			(xy 155.386233 -286.575342) (xy 155.433504 -286.589034) (xy 155.477966 -286.610132) (xy 155.518469 -286.638088)
			(xy 155.553962 -286.67218) (xy 155.583527 -286.711524) (xy 155.606398 -286.755101) (xy 155.621982 -286.801782)
			(xy 155.629877 -286.850359) (xy 155.630372 -286.874966) (xy 155.96922 -286.874966) (xy 155.97318 -286.825912)
			(xy 155.984957 -286.778128) (xy 156.004248 -286.732852) (xy 156.030551 -286.691256) (xy 156.063186 -286.654419)
			(xy 156.101307 -286.623294) (xy 156.143928 -286.598687) (xy 156.189944 -286.581235) (xy 156.238163 -286.571391)
			(xy 156.287338 -286.56941) (xy 156.336193 -286.575342) (xy 156.383464 -286.589034) (xy 156.427926 -286.610132)
			(xy 156.468429 -286.638088) (xy 156.503922 -286.67218) (xy 156.533487 -286.711524) (xy 156.556358 -286.755101)
			(xy 156.571942 -286.801782) (xy 156.579837 -286.850359) (xy 156.580332 -286.874966) (xy 156.91918 -286.874966)
			(xy 156.92314 -286.825912) (xy 156.934917 -286.778128) (xy 156.954208 -286.732852) (xy 156.980511 -286.691256)
			(xy 157.013146 -286.654419) (xy 157.051267 -286.623294) (xy 157.093888 -286.598687) (xy 157.139904 -286.581235)
			(xy 157.188123 -286.571391) (xy 157.237298 -286.56941) (xy 157.286153 -286.575342) (xy 157.333424 -286.589034)
			(xy 157.377886 -286.610132) (xy 157.418389 -286.638088) (xy 157.453882 -286.67218) (xy 157.483447 -286.711524)
			(xy 157.506318 -286.755101) (xy 157.521902 -286.801782) (xy 157.529797 -286.850359) (xy 157.530292 -286.874966)
			(xy 157.86914 -286.874966) (xy 157.8731 -286.825912) (xy 157.884877 -286.778128) (xy 157.904168 -286.732852)
			(xy 157.930471 -286.691256) (xy 157.963106 -286.654419) (xy 158.001227 -286.623294) (xy 158.043848 -286.598687)
			(xy 158.089864 -286.581235) (xy 158.138083 -286.571391) (xy 158.187258 -286.56941) (xy 158.236113 -286.575342)
			(xy 158.283384 -286.589034) (xy 158.327846 -286.610132) (xy 158.368349 -286.638088) (xy 158.403842 -286.67218)
			(xy 158.433407 -286.711524) (xy 158.456278 -286.755101) (xy 158.471862 -286.801782) (xy 158.479757 -286.850359)
			(xy 158.480247 -286.874712) (xy 158.8191 -286.874712) (xy 158.82306 -286.825658) (xy 158.834837 -286.777874)
			(xy 158.854128 -286.732598) (xy 158.880431 -286.691002) (xy 158.913066 -286.654165) (xy 158.951187 -286.62304)
			(xy 158.993808 -286.598433) (xy 159.039824 -286.580981) (xy 159.088043 -286.571137) (xy 159.137218 -286.569156)
			(xy 159.186073 -286.575088) (xy 159.233344 -286.58878) (xy 159.277806 -286.609878) (xy 159.318309 -286.637834)
			(xy 159.353802 -286.671926) (xy 159.383367 -286.71127) (xy 159.406238 -286.754847) (xy 159.421822 -286.801528)
			(xy 159.429717 -286.850105) (xy 159.430212 -286.874712) (xy 159.76906 -286.874712) (xy 159.77302 -286.825658)
			(xy 159.784797 -286.777874) (xy 159.804088 -286.732598) (xy 159.830391 -286.691002) (xy 159.863026 -286.654165)
			(xy 159.901147 -286.62304) (xy 159.943768 -286.598433) (xy 159.989784 -286.580981) (xy 160.038003 -286.571137)
			(xy 160.087178 -286.569156) (xy 160.136033 -286.575088) (xy 160.183304 -286.58878) (xy 160.227766 -286.609878)
			(xy 160.268269 -286.637834) (xy 160.303762 -286.671926) (xy 160.333327 -286.71127) (xy 160.356198 -286.754847)
			(xy 160.371782 -286.801528) (xy 160.379677 -286.850105) (xy 160.380172 -286.874712) (xy 160.380167 -286.874966)
			(xy 160.719274 -286.874966) (xy 160.723234 -286.825912) (xy 160.735011 -286.778128) (xy 160.754302 -286.732852)
			(xy 160.780605 -286.691256) (xy 160.81324 -286.654419) (xy 160.851361 -286.623294) (xy 160.893982 -286.598687)
			(xy 160.939998 -286.581235) (xy 160.988217 -286.571391) (xy 161.037392 -286.56941) (xy 161.086247 -286.575342)
			(xy 161.133518 -286.589034) (xy 161.17798 -286.610132) (xy 161.218483 -286.638088) (xy 161.253976 -286.67218)
			(xy 161.283541 -286.711524) (xy 161.306412 -286.755101) (xy 161.321996 -286.801782) (xy 161.329891 -286.850359)
			(xy 161.330386 -286.874966) (xy 161.669234 -286.874966) (xy 161.673194 -286.825912) (xy 161.684971 -286.778128)
			(xy 161.704262 -286.732852) (xy 161.730565 -286.691256) (xy 161.7632 -286.654419) (xy 161.801321 -286.623294)
			(xy 161.843942 -286.598687) (xy 161.889958 -286.581235) (xy 161.938177 -286.571391) (xy 161.987352 -286.56941)
			(xy 162.036207 -286.575342) (xy 162.083478 -286.589034) (xy 162.12794 -286.610132) (xy 162.168443 -286.638088)
			(xy 162.203936 -286.67218) (xy 162.233501 -286.711524) (xy 162.256372 -286.755101) (xy 162.271956 -286.801782)
			(xy 162.279851 -286.850359) (xy 162.280346 -286.874966) (xy 162.619194 -286.874966) (xy 162.623154 -286.825912)
			(xy 162.634931 -286.778128) (xy 162.654222 -286.732852) (xy 162.680525 -286.691256) (xy 162.71316 -286.654419)
			(xy 162.751281 -286.623294) (xy 162.793902 -286.598687) (xy 162.839918 -286.581235) (xy 162.888137 -286.571391)
			(xy 162.937312 -286.56941) (xy 162.986167 -286.575342) (xy 163.033438 -286.589034) (xy 163.0779 -286.610132)
			(xy 163.118403 -286.638088) (xy 163.153896 -286.67218) (xy 163.183461 -286.711524) (xy 163.206332 -286.755101)
			(xy 163.221916 -286.801782) (xy 163.229811 -286.850359) (xy 163.230306 -286.874966) (xy 163.569154 -286.874966)
			(xy 163.573114 -286.825912) (xy 163.584891 -286.778128) (xy 163.604182 -286.732852) (xy 163.630485 -286.691256)
			(xy 163.66312 -286.654419) (xy 163.701241 -286.623294) (xy 163.743862 -286.598687) (xy 163.789878 -286.581235)
			(xy 163.838097 -286.571391) (xy 163.887272 -286.56941) (xy 163.936127 -286.575342) (xy 163.983398 -286.589034)
			(xy 164.02786 -286.610132) (xy 164.068363 -286.638088) (xy 164.103856 -286.67218) (xy 164.133421 -286.711524)
			(xy 164.156292 -286.755101) (xy 164.171876 -286.801782) (xy 164.179771 -286.850359) (xy 164.180266 -286.874966)
			(xy 164.519114 -286.874966) (xy 164.523074 -286.825912) (xy 164.534851 -286.778128) (xy 164.554142 -286.732852)
			(xy 164.580445 -286.691256) (xy 164.61308 -286.654419) (xy 164.651201 -286.623294) (xy 164.693822 -286.598687)
			(xy 164.739838 -286.581235) (xy 164.788057 -286.571391) (xy 164.837232 -286.56941) (xy 164.886087 -286.575342)
			(xy 164.933358 -286.589034) (xy 164.97782 -286.610132) (xy 165.018323 -286.638088) (xy 165.053816 -286.67218)
			(xy 165.083381 -286.711524) (xy 165.106252 -286.755101) (xy 165.121836 -286.801782) (xy 165.129731 -286.850359)
			(xy 165.130226 -286.874966) (xy 165.469074 -286.874966) (xy 165.473034 -286.825912) (xy 165.484811 -286.778128)
			(xy 165.504102 -286.732852) (xy 165.530405 -286.691256) (xy 165.56304 -286.654419) (xy 165.601161 -286.623294)
			(xy 165.643782 -286.598687) (xy 165.689798 -286.581235) (xy 165.738017 -286.571391) (xy 165.787192 -286.56941)
			(xy 165.836047 -286.575342) (xy 165.883318 -286.589034) (xy 165.92778 -286.610132) (xy 165.968283 -286.638088)
			(xy 166.003776 -286.67218) (xy 166.033341 -286.711524) (xy 166.056212 -286.755101) (xy 166.071796 -286.801782)
			(xy 166.079691 -286.850359) (xy 166.080186 -286.874966) (xy 166.419288 -286.874966) (xy 166.423248 -286.825912)
			(xy 166.435025 -286.778128) (xy 166.454316 -286.732852) (xy 166.480619 -286.691256) (xy 166.513254 -286.654419)
			(xy 166.551375 -286.623294) (xy 166.593996 -286.598687) (xy 166.640012 -286.581235) (xy 166.688231 -286.571391)
			(xy 166.737406 -286.56941) (xy 166.786261 -286.575342) (xy 166.833532 -286.589034) (xy 166.877994 -286.610132)
			(xy 166.918497 -286.638088) (xy 166.95399 -286.67218) (xy 166.983555 -286.711524) (xy 167.006426 -286.755101)
			(xy 167.02201 -286.801782) (xy 167.029905 -286.850359) (xy 167.0304 -286.874966) (xy 167.369248 -286.874966)
			(xy 167.373208 -286.825912) (xy 167.384985 -286.778128) (xy 167.404276 -286.732852) (xy 167.430579 -286.691256)
			(xy 167.463214 -286.654419) (xy 167.501335 -286.623294) (xy 167.543956 -286.598687) (xy 167.589972 -286.581235)
			(xy 167.638191 -286.571391) (xy 167.687366 -286.56941) (xy 167.736221 -286.575342) (xy 167.783492 -286.589034)
			(xy 167.827954 -286.610132) (xy 167.868457 -286.638088) (xy 167.90395 -286.67218) (xy 167.933515 -286.711524)
			(xy 167.956386 -286.755101) (xy 167.97197 -286.801782) (xy 167.979865 -286.850359) (xy 167.98036 -286.874966)
			(xy 168.319208 -286.874966) (xy 168.323168 -286.825912) (xy 168.334945 -286.778128) (xy 168.354236 -286.732852)
			(xy 168.380539 -286.691256) (xy 168.413174 -286.654419) (xy 168.451295 -286.623294) (xy 168.493916 -286.598687)
			(xy 168.539932 -286.581235) (xy 168.588151 -286.571391) (xy 168.637326 -286.56941) (xy 168.686181 -286.575342)
			(xy 168.733452 -286.589034) (xy 168.777914 -286.610132) (xy 168.818417 -286.638088) (xy 168.85391 -286.67218)
			(xy 168.883475 -286.711524) (xy 168.906346 -286.755101) (xy 168.92193 -286.801782) (xy 168.929825 -286.850359)
			(xy 168.93032 -286.874966) (xy 169.269168 -286.874966) (xy 169.273128 -286.825912) (xy 169.284905 -286.778128)
			(xy 169.304196 -286.732852) (xy 169.330499 -286.691256) (xy 169.363134 -286.654419) (xy 169.401255 -286.623294)
			(xy 169.443876 -286.598687) (xy 169.489892 -286.581235) (xy 169.538111 -286.571391) (xy 169.587286 -286.56941)
			(xy 169.636141 -286.575342) (xy 169.683412 -286.589034) (xy 169.727874 -286.610132) (xy 169.768377 -286.638088)
			(xy 169.80387 -286.67218) (xy 169.833435 -286.711524) (xy 169.856306 -286.755101) (xy 169.87189 -286.801782)
			(xy 169.879785 -286.850359) (xy 169.88028 -286.874966) (xy 170.219128 -286.874966) (xy 170.223088 -286.825912)
			(xy 170.234865 -286.778128) (xy 170.254156 -286.732852) (xy 170.280459 -286.691256) (xy 170.313094 -286.654419)
			(xy 170.351215 -286.623294) (xy 170.393836 -286.598687) (xy 170.439852 -286.581235) (xy 170.488071 -286.571391)
			(xy 170.537246 -286.56941) (xy 170.586101 -286.575342) (xy 170.633372 -286.589034) (xy 170.677834 -286.610132)
			(xy 170.718337 -286.638088) (xy 170.75383 -286.67218) (xy 170.783395 -286.711524) (xy 170.806266 -286.755101)
			(xy 170.82185 -286.801782) (xy 170.829745 -286.850359) (xy 170.83024 -286.874966) (xy 171.169088 -286.874966)
			(xy 171.173048 -286.825912) (xy 171.184825 -286.778128) (xy 171.204116 -286.732852) (xy 171.230419 -286.691256)
			(xy 171.263054 -286.654419) (xy 171.301175 -286.623294) (xy 171.343796 -286.598687) (xy 171.389812 -286.581235)
			(xy 171.438031 -286.571391) (xy 171.487206 -286.56941) (xy 171.536061 -286.575342) (xy 171.583332 -286.589034)
			(xy 171.627794 -286.610132) (xy 171.668297 -286.638088) (xy 171.70379 -286.67218) (xy 171.733355 -286.711524)
			(xy 171.756226 -286.755101) (xy 171.77181 -286.801782) (xy 171.779705 -286.850359) (xy 171.7802 -286.874966)
			(xy 172.119048 -286.874966) (xy 172.123008 -286.825912) (xy 172.134785 -286.778128) (xy 172.154076 -286.732852)
			(xy 172.180379 -286.691256) (xy 172.213014 -286.654419) (xy 172.251135 -286.623294) (xy 172.293756 -286.598687)
			(xy 172.339772 -286.581235) (xy 172.387991 -286.571391) (xy 172.437166 -286.56941) (xy 172.486021 -286.575342)
			(xy 172.533292 -286.589034) (xy 172.577754 -286.610132) (xy 172.618257 -286.638088) (xy 172.65375 -286.67218)
			(xy 172.683315 -286.711524) (xy 172.706186 -286.755101) (xy 172.72177 -286.801782) (xy 172.729665 -286.850359)
			(xy 172.73016 -286.874966) (xy 173.069262 -286.874966) (xy 173.073222 -286.825912) (xy 173.084999 -286.778128)
			(xy 173.10429 -286.732852) (xy 173.130593 -286.691256) (xy 173.163228 -286.654419) (xy 173.201349 -286.623294)
			(xy 173.24397 -286.598687) (xy 173.289986 -286.581235) (xy 173.338205 -286.571391) (xy 173.38738 -286.56941)
			(xy 173.436235 -286.575342) (xy 173.483506 -286.589034) (xy 173.527968 -286.610132) (xy 173.568471 -286.638088)
			(xy 173.603964 -286.67218) (xy 173.633529 -286.711524) (xy 173.6564 -286.755101) (xy 173.671984 -286.801782)
			(xy 173.679879 -286.850359) (xy 173.680374 -286.874966) (xy 174.019222 -286.874966) (xy 174.023182 -286.825912)
			(xy 174.034959 -286.778128) (xy 174.05425 -286.732852) (xy 174.080553 -286.691256) (xy 174.113188 -286.654419)
			(xy 174.151309 -286.623294) (xy 174.19393 -286.598687) (xy 174.239946 -286.581235) (xy 174.288165 -286.571391)
			(xy 174.33734 -286.56941) (xy 174.386195 -286.575342) (xy 174.433466 -286.589034) (xy 174.477928 -286.610132)
			(xy 174.518431 -286.638088) (xy 174.553924 -286.67218) (xy 174.583489 -286.711524) (xy 174.60636 -286.755101)
			(xy 174.621944 -286.801782) (xy 174.629839 -286.850359) (xy 174.630334 -286.874966) (xy 175.919142 -286.874966)
			(xy 175.923102 -286.825912) (xy 175.934879 -286.778128) (xy 175.95417 -286.732852) (xy 175.980473 -286.691256)
			(xy 176.013108 -286.654419) (xy 176.051229 -286.623294) (xy 176.09385 -286.598687) (xy 176.139866 -286.581235)
			(xy 176.188085 -286.571391) (xy 176.23726 -286.56941) (xy 176.286115 -286.575342) (xy 176.333386 -286.589034)
			(xy 176.377848 -286.610132) (xy 176.418351 -286.638088) (xy 176.453844 -286.67218) (xy 176.483409 -286.711524)
			(xy 176.50628 -286.755101) (xy 176.521864 -286.801782) (xy 176.529759 -286.850359) (xy 176.530254 -286.874966)
			(xy 176.869102 -286.874966) (xy 176.873062 -286.825912) (xy 176.884839 -286.778128) (xy 176.90413 -286.732852)
			(xy 176.930433 -286.691256) (xy 176.963068 -286.654419) (xy 177.001189 -286.623294) (xy 177.04381 -286.598687)
			(xy 177.089826 -286.581235) (xy 177.138045 -286.571391) (xy 177.18722 -286.56941) (xy 177.236075 -286.575342)
			(xy 177.283346 -286.589034) (xy 177.327808 -286.610132) (xy 177.368311 -286.638088) (xy 177.403804 -286.67218)
			(xy 177.433369 -286.711524) (xy 177.45624 -286.755101) (xy 177.471824 -286.801782) (xy 177.479719 -286.850359)
			(xy 177.480214 -286.874966) (xy 177.819062 -286.874966) (xy 177.823022 -286.825912) (xy 177.834799 -286.778128)
			(xy 177.85409 -286.732852) (xy 177.880393 -286.691256) (xy 177.913028 -286.654419) (xy 177.951149 -286.623294)
			(xy 177.99377 -286.598687) (xy 178.039786 -286.581235) (xy 178.088005 -286.571391) (xy 178.13718 -286.56941)
			(xy 178.186035 -286.575342) (xy 178.233306 -286.589034) (xy 178.277768 -286.610132) (xy 178.318271 -286.638088)
			(xy 178.353764 -286.67218) (xy 178.383329 -286.711524) (xy 178.4062 -286.755101) (xy 178.421784 -286.801782)
			(xy 178.429679 -286.850359) (xy 178.430174 -286.874966) (xy 178.769276 -286.874966) (xy 178.773236 -286.825912)
			(xy 178.785013 -286.778128) (xy 178.804304 -286.732852) (xy 178.830607 -286.691256) (xy 178.863242 -286.654419)
			(xy 178.901363 -286.623294) (xy 178.943984 -286.598687) (xy 178.99 -286.581235) (xy 179.038219 -286.571391)
			(xy 179.087394 -286.56941) (xy 179.136249 -286.575342) (xy 179.18352 -286.589034) (xy 179.227982 -286.610132)
			(xy 179.268485 -286.638088) (xy 179.303978 -286.67218) (xy 179.333543 -286.711524) (xy 179.356414 -286.755101)
			(xy 179.371998 -286.801782) (xy 179.379893 -286.850359) (xy 179.380388 -286.874966) (xy 179.719236 -286.874966)
			(xy 179.723196 -286.825912) (xy 179.734973 -286.778128) (xy 179.754264 -286.732852) (xy 179.780567 -286.691256)
			(xy 179.813202 -286.654419) (xy 179.851323 -286.623294) (xy 179.893944 -286.598687) (xy 179.93996 -286.581235)
			(xy 179.988179 -286.571391) (xy 180.037354 -286.56941) (xy 180.086209 -286.575342) (xy 180.13348 -286.589034)
			(xy 180.177942 -286.610132) (xy 180.218445 -286.638088) (xy 180.253938 -286.67218) (xy 180.283503 -286.711524)
			(xy 180.306374 -286.755101) (xy 180.321958 -286.801782) (xy 180.329853 -286.850359) (xy 180.330348 -286.874966)
			(xy 180.669196 -286.874966) (xy 180.673156 -286.825912) (xy 180.684933 -286.778128) (xy 180.704224 -286.732852)
			(xy 180.730527 -286.691256) (xy 180.763162 -286.654419) (xy 180.801283 -286.623294) (xy 180.843904 -286.598687)
			(xy 180.88992 -286.581235) (xy 180.938139 -286.571391) (xy 180.987314 -286.56941) (xy 181.036169 -286.575342)
			(xy 181.08344 -286.589034) (xy 181.127902 -286.610132) (xy 181.168405 -286.638088) (xy 181.203898 -286.67218)
			(xy 181.233463 -286.711524) (xy 181.256334 -286.755101) (xy 181.271918 -286.801782) (xy 181.279813 -286.850359)
			(xy 181.280308 -286.874966) (xy 181.619156 -286.874966) (xy 181.623116 -286.825912) (xy 181.634893 -286.778128)
			(xy 181.654184 -286.732852) (xy 181.680487 -286.691256) (xy 181.713122 -286.654419) (xy 181.751243 -286.623294)
			(xy 181.793864 -286.598687) (xy 181.83988 -286.581235) (xy 181.888099 -286.571391) (xy 181.937274 -286.56941)
			(xy 181.986129 -286.575342) (xy 182.0334 -286.589034) (xy 182.077862 -286.610132) (xy 182.118365 -286.638088)
			(xy 182.153858 -286.67218) (xy 182.183423 -286.711524) (xy 182.206294 -286.755101) (xy 182.221878 -286.801782)
			(xy 182.229773 -286.850359) (xy 182.230268 -286.874966) (xy 182.569116 -286.874966) (xy 182.573076 -286.825912)
			(xy 182.584853 -286.778128) (xy 182.604144 -286.732852) (xy 182.630447 -286.691256) (xy 182.663082 -286.654419)
			(xy 182.701203 -286.623294) (xy 182.743824 -286.598687) (xy 182.78984 -286.581235) (xy 182.838059 -286.571391)
			(xy 182.887234 -286.56941) (xy 182.936089 -286.575342) (xy 182.98336 -286.589034) (xy 183.027822 -286.610132)
			(xy 183.068325 -286.638088) (xy 183.103818 -286.67218) (xy 183.133383 -286.711524) (xy 183.156254 -286.755101)
			(xy 183.171838 -286.801782) (xy 183.179733 -286.850359) (xy 183.180228 -286.874966) (xy 183.519076 -286.874966)
			(xy 183.523036 -286.825912) (xy 183.534813 -286.778128) (xy 183.554104 -286.732852) (xy 183.580407 -286.691256)
			(xy 183.613042 -286.654419) (xy 183.651163 -286.623294) (xy 183.693784 -286.598687) (xy 183.7398 -286.581235)
			(xy 183.788019 -286.571391) (xy 183.837194 -286.56941) (xy 183.886049 -286.575342) (xy 183.93332 -286.589034)
			(xy 183.977782 -286.610132) (xy 184.018285 -286.638088) (xy 184.053778 -286.67218) (xy 184.083343 -286.711524)
			(xy 184.106214 -286.755101) (xy 184.121798 -286.801782) (xy 184.129693 -286.850359) (xy 184.130188 -286.874966)
			(xy 184.469036 -286.874966) (xy 184.472996 -286.825912) (xy 184.484773 -286.778128) (xy 184.504064 -286.732852)
			(xy 184.530367 -286.691256) (xy 184.563002 -286.654419) (xy 184.601123 -286.623294) (xy 184.643744 -286.598687)
			(xy 184.68976 -286.581235) (xy 184.737979 -286.571391) (xy 184.787154 -286.56941) (xy 184.836009 -286.575342)
			(xy 184.88328 -286.589034) (xy 184.927742 -286.610132) (xy 184.968245 -286.638088) (xy 185.003738 -286.67218)
			(xy 185.033303 -286.711524) (xy 185.056174 -286.755101) (xy 185.071758 -286.801782) (xy 185.079653 -286.850359)
			(xy 185.080148 -286.874966) (xy 185.079653 -286.899573) (xy 185.071758 -286.94815) (xy 185.056174 -286.994831)
			(xy 185.033303 -287.038408) (xy 185.003738 -287.077752) (xy 184.968245 -287.111844) (xy 184.927742 -287.1398)
			(xy 184.88328 -287.160898) (xy 184.836009 -287.17459) (xy 184.787154 -287.180522) (xy 184.737979 -287.178541)
			(xy 184.68976 -287.168697) (xy 184.643744 -287.151245) (xy 184.601123 -287.126638) (xy 184.563002 -287.095513)
			(xy 184.530367 -287.058676) (xy 184.504064 -287.01708) (xy 184.484773 -286.971804) (xy 184.472996 -286.92402)
			(xy 184.469036 -286.874966) (xy 184.130188 -286.874966) (xy 184.129693 -286.899573) (xy 184.121798 -286.94815)
			(xy 184.106214 -286.994831) (xy 184.083343 -287.038408) (xy 184.053778 -287.077752) (xy 184.018285 -287.111844)
			(xy 183.977782 -287.1398) (xy 183.93332 -287.160898) (xy 183.886049 -287.17459) (xy 183.837194 -287.180522)
			(xy 183.788019 -287.178541) (xy 183.7398 -287.168697) (xy 183.693784 -287.151245) (xy 183.651163 -287.126638)
			(xy 183.613042 -287.095513) (xy 183.580407 -287.058676) (xy 183.554104 -287.01708) (xy 183.534813 -286.971804)
			(xy 183.523036 -286.92402) (xy 183.519076 -286.874966) (xy 183.180228 -286.874966) (xy 183.179733 -286.899573)
			(xy 183.171838 -286.94815) (xy 183.156254 -286.994831) (xy 183.133383 -287.038408) (xy 183.103818 -287.077752)
			(xy 183.068325 -287.111844) (xy 183.027822 -287.1398) (xy 182.98336 -287.160898) (xy 182.936089 -287.17459)
			(xy 182.887234 -287.180522) (xy 182.838059 -287.178541) (xy 182.78984 -287.168697) (xy 182.743824 -287.151245)
			(xy 182.701203 -287.126638) (xy 182.663082 -287.095513) (xy 182.630447 -287.058676) (xy 182.604144 -287.01708)
			(xy 182.584853 -286.971804) (xy 182.573076 -286.92402) (xy 182.569116 -286.874966) (xy 182.230268 -286.874966)
			(xy 182.229773 -286.899573) (xy 182.221878 -286.94815) (xy 182.206294 -286.994831) (xy 182.183423 -287.038408)
			(xy 182.153858 -287.077752) (xy 182.118365 -287.111844) (xy 182.077862 -287.1398) (xy 182.0334 -287.160898)
			(xy 181.986129 -287.17459) (xy 181.937274 -287.180522) (xy 181.888099 -287.178541) (xy 181.83988 -287.168697)
			(xy 181.793864 -287.151245) (xy 181.751243 -287.126638) (xy 181.713122 -287.095513) (xy 181.680487 -287.058676)
			(xy 181.654184 -287.01708) (xy 181.634893 -286.971804) (xy 181.623116 -286.92402) (xy 181.619156 -286.874966)
			(xy 181.280308 -286.874966) (xy 181.279813 -286.899573) (xy 181.271918 -286.94815) (xy 181.256334 -286.994831)
			(xy 181.233463 -287.038408) (xy 181.203898 -287.077752) (xy 181.168405 -287.111844) (xy 181.127902 -287.1398)
			(xy 181.08344 -287.160898) (xy 181.036169 -287.17459) (xy 180.987314 -287.180522) (xy 180.938139 -287.178541)
			(xy 180.88992 -287.168697) (xy 180.843904 -287.151245) (xy 180.801283 -287.126638) (xy 180.763162 -287.095513)
			(xy 180.730527 -287.058676) (xy 180.704224 -287.01708) (xy 180.684933 -286.971804) (xy 180.673156 -286.92402)
			(xy 180.669196 -286.874966) (xy 180.330348 -286.874966) (xy 180.329853 -286.899573) (xy 180.321958 -286.94815)
			(xy 180.306374 -286.994831) (xy 180.283503 -287.038408) (xy 180.253938 -287.077752) (xy 180.218445 -287.111844)
			(xy 180.177942 -287.1398) (xy 180.13348 -287.160898) (xy 180.086209 -287.17459) (xy 180.037354 -287.180522)
			(xy 179.988179 -287.178541) (xy 179.93996 -287.168697) (xy 179.893944 -287.151245) (xy 179.851323 -287.126638)
			(xy 179.813202 -287.095513) (xy 179.780567 -287.058676) (xy 179.754264 -287.01708) (xy 179.734973 -286.971804)
			(xy 179.723196 -286.92402) (xy 179.719236 -286.874966) (xy 179.380388 -286.874966) (xy 179.379893 -286.899573)
			(xy 179.371998 -286.94815) (xy 179.356414 -286.994831) (xy 179.333543 -287.038408) (xy 179.303978 -287.077752)
			(xy 179.268485 -287.111844) (xy 179.227982 -287.1398) (xy 179.18352 -287.160898) (xy 179.136249 -287.17459)
			(xy 179.087394 -287.180522) (xy 179.038219 -287.178541) (xy 178.99 -287.168697) (xy 178.943984 -287.151245)
			(xy 178.901363 -287.126638) (xy 178.863242 -287.095513) (xy 178.830607 -287.058676) (xy 178.804304 -287.01708)
			(xy 178.785013 -286.971804) (xy 178.773236 -286.92402) (xy 178.769276 -286.874966) (xy 178.430174 -286.874966)
			(xy 178.429679 -286.899573) (xy 178.421784 -286.94815) (xy 178.4062 -286.994831) (xy 178.383329 -287.038408)
			(xy 178.353764 -287.077752) (xy 178.318271 -287.111844) (xy 178.277768 -287.1398) (xy 178.233306 -287.160898)
			(xy 178.186035 -287.17459) (xy 178.13718 -287.180522) (xy 178.088005 -287.178541) (xy 178.039786 -287.168697)
			(xy 177.99377 -287.151245) (xy 177.951149 -287.126638) (xy 177.913028 -287.095513) (xy 177.880393 -287.058676)
			(xy 177.85409 -287.01708) (xy 177.834799 -286.971804) (xy 177.823022 -286.92402) (xy 177.819062 -286.874966)
			(xy 177.480214 -286.874966) (xy 177.479719 -286.899573) (xy 177.471824 -286.94815) (xy 177.45624 -286.994831)
			(xy 177.433369 -287.038408) (xy 177.403804 -287.077752) (xy 177.368311 -287.111844) (xy 177.327808 -287.1398)
			(xy 177.283346 -287.160898) (xy 177.236075 -287.17459) (xy 177.18722 -287.180522) (xy 177.138045 -287.178541)
			(xy 177.089826 -287.168697) (xy 177.04381 -287.151245) (xy 177.001189 -287.126638) (xy 176.963068 -287.095513)
			(xy 176.930433 -287.058676) (xy 176.90413 -287.01708) (xy 176.884839 -286.971804) (xy 176.873062 -286.92402)
			(xy 176.869102 -286.874966) (xy 176.530254 -286.874966) (xy 176.529759 -286.899573) (xy 176.521864 -286.94815)
			(xy 176.50628 -286.994831) (xy 176.483409 -287.038408) (xy 176.453844 -287.077752) (xy 176.418351 -287.111844)
			(xy 176.377848 -287.1398) (xy 176.333386 -287.160898) (xy 176.286115 -287.17459) (xy 176.23726 -287.180522)
			(xy 176.188085 -287.178541) (xy 176.139866 -287.168697) (xy 176.09385 -287.151245) (xy 176.051229 -287.126638)
			(xy 176.013108 -287.095513) (xy 175.980473 -287.058676) (xy 175.95417 -287.01708) (xy 175.934879 -286.971804)
			(xy 175.923102 -286.92402) (xy 175.919142 -286.874966) (xy 174.630334 -286.874966) (xy 174.629839 -286.899573)
			(xy 174.621944 -286.94815) (xy 174.60636 -286.994831) (xy 174.583489 -287.038408) (xy 174.553924 -287.077752)
			(xy 174.518431 -287.111844) (xy 174.477928 -287.1398) (xy 174.433466 -287.160898) (xy 174.386195 -287.17459)
			(xy 174.33734 -287.180522) (xy 174.288165 -287.178541) (xy 174.239946 -287.168697) (xy 174.19393 -287.151245)
			(xy 174.151309 -287.126638) (xy 174.113188 -287.095513) (xy 174.080553 -287.058676) (xy 174.05425 -287.01708)
			(xy 174.034959 -286.971804) (xy 174.023182 -286.92402) (xy 174.019222 -286.874966) (xy 173.680374 -286.874966)
			(xy 173.679879 -286.899573) (xy 173.671984 -286.94815) (xy 173.6564 -286.994831) (xy 173.633529 -287.038408)
			(xy 173.603964 -287.077752) (xy 173.568471 -287.111844) (xy 173.527968 -287.1398) (xy 173.483506 -287.160898)
			(xy 173.436235 -287.17459) (xy 173.38738 -287.180522) (xy 173.338205 -287.178541) (xy 173.289986 -287.168697)
			(xy 173.24397 -287.151245) (xy 173.201349 -287.126638) (xy 173.163228 -287.095513) (xy 173.130593 -287.058676)
			(xy 173.10429 -287.01708) (xy 173.084999 -286.971804) (xy 173.073222 -286.92402) (xy 173.069262 -286.874966)
			(xy 172.73016 -286.874966) (xy 172.729665 -286.899573) (xy 172.72177 -286.94815) (xy 172.706186 -286.994831)
			(xy 172.683315 -287.038408) (xy 172.65375 -287.077752) (xy 172.618257 -287.111844) (xy 172.577754 -287.1398)
			(xy 172.533292 -287.160898) (xy 172.486021 -287.17459) (xy 172.437166 -287.180522) (xy 172.387991 -287.178541)
			(xy 172.339772 -287.168697) (xy 172.293756 -287.151245) (xy 172.251135 -287.126638) (xy 172.213014 -287.095513)
			(xy 172.180379 -287.058676) (xy 172.154076 -287.01708) (xy 172.134785 -286.971804) (xy 172.123008 -286.92402)
			(xy 172.119048 -286.874966) (xy 171.7802 -286.874966) (xy 171.779705 -286.899573) (xy 171.77181 -286.94815)
			(xy 171.756226 -286.994831) (xy 171.733355 -287.038408) (xy 171.70379 -287.077752) (xy 171.668297 -287.111844)
			(xy 171.627794 -287.1398) (xy 171.583332 -287.160898) (xy 171.536061 -287.17459) (xy 171.487206 -287.180522)
			(xy 171.438031 -287.178541) (xy 171.389812 -287.168697) (xy 171.343796 -287.151245) (xy 171.301175 -287.126638)
			(xy 171.263054 -287.095513) (xy 171.230419 -287.058676) (xy 171.204116 -287.01708) (xy 171.184825 -286.971804)
			(xy 171.173048 -286.92402) (xy 171.169088 -286.874966) (xy 170.83024 -286.874966) (xy 170.829745 -286.899573)
			(xy 170.82185 -286.94815) (xy 170.806266 -286.994831) (xy 170.783395 -287.038408) (xy 170.75383 -287.077752)
			(xy 170.718337 -287.111844) (xy 170.677834 -287.1398) (xy 170.633372 -287.160898) (xy 170.586101 -287.17459)
			(xy 170.537246 -287.180522) (xy 170.488071 -287.178541) (xy 170.439852 -287.168697) (xy 170.393836 -287.151245)
			(xy 170.351215 -287.126638) (xy 170.313094 -287.095513) (xy 170.280459 -287.058676) (xy 170.254156 -287.01708)
			(xy 170.234865 -286.971804) (xy 170.223088 -286.92402) (xy 170.219128 -286.874966) (xy 169.88028 -286.874966)
			(xy 169.879785 -286.899573) (xy 169.87189 -286.94815) (xy 169.856306 -286.994831) (xy 169.833435 -287.038408)
			(xy 169.80387 -287.077752) (xy 169.768377 -287.111844) (xy 169.727874 -287.1398) (xy 169.683412 -287.160898)
			(xy 169.636141 -287.17459) (xy 169.587286 -287.180522) (xy 169.538111 -287.178541) (xy 169.489892 -287.168697)
			(xy 169.443876 -287.151245) (xy 169.401255 -287.126638) (xy 169.363134 -287.095513) (xy 169.330499 -287.058676)
			(xy 169.304196 -287.01708) (xy 169.284905 -286.971804) (xy 169.273128 -286.92402) (xy 169.269168 -286.874966)
			(xy 168.93032 -286.874966) (xy 168.929825 -286.899573) (xy 168.92193 -286.94815) (xy 168.906346 -286.994831)
			(xy 168.883475 -287.038408) (xy 168.85391 -287.077752) (xy 168.818417 -287.111844) (xy 168.777914 -287.1398)
			(xy 168.733452 -287.160898) (xy 168.686181 -287.17459) (xy 168.637326 -287.180522) (xy 168.588151 -287.178541)
			(xy 168.539932 -287.168697) (xy 168.493916 -287.151245) (xy 168.451295 -287.126638) (xy 168.413174 -287.095513)
			(xy 168.380539 -287.058676) (xy 168.354236 -287.01708) (xy 168.334945 -286.971804) (xy 168.323168 -286.92402)
			(xy 168.319208 -286.874966) (xy 167.98036 -286.874966) (xy 167.979865 -286.899573) (xy 167.97197 -286.94815)
			(xy 167.956386 -286.994831) (xy 167.933515 -287.038408) (xy 167.90395 -287.077752) (xy 167.868457 -287.111844)
			(xy 167.827954 -287.1398) (xy 167.783492 -287.160898) (xy 167.736221 -287.17459) (xy 167.687366 -287.180522)
			(xy 167.638191 -287.178541) (xy 167.589972 -287.168697) (xy 167.543956 -287.151245) (xy 167.501335 -287.126638)
			(xy 167.463214 -287.095513) (xy 167.430579 -287.058676) (xy 167.404276 -287.01708) (xy 167.384985 -286.971804)
			(xy 167.373208 -286.92402) (xy 167.369248 -286.874966) (xy 167.0304 -286.874966) (xy 167.029905 -286.899573)
			(xy 167.02201 -286.94815) (xy 167.006426 -286.994831) (xy 166.983555 -287.038408) (xy 166.95399 -287.077752)
			(xy 166.918497 -287.111844) (xy 166.877994 -287.1398) (xy 166.833532 -287.160898) (xy 166.786261 -287.17459)
			(xy 166.737406 -287.180522) (xy 166.688231 -287.178541) (xy 166.640012 -287.168697) (xy 166.593996 -287.151245)
			(xy 166.551375 -287.126638) (xy 166.513254 -287.095513) (xy 166.480619 -287.058676) (xy 166.454316 -287.01708)
			(xy 166.435025 -286.971804) (xy 166.423248 -286.92402) (xy 166.419288 -286.874966) (xy 166.080186 -286.874966)
			(xy 166.079691 -286.899573) (xy 166.071796 -286.94815) (xy 166.056212 -286.994831) (xy 166.033341 -287.038408)
			(xy 166.003776 -287.077752) (xy 165.968283 -287.111844) (xy 165.92778 -287.1398) (xy 165.883318 -287.160898)
			(xy 165.836047 -287.17459) (xy 165.787192 -287.180522) (xy 165.738017 -287.178541) (xy 165.689798 -287.168697)
			(xy 165.643782 -287.151245) (xy 165.601161 -287.126638) (xy 165.56304 -287.095513) (xy 165.530405 -287.058676)
			(xy 165.504102 -287.01708) (xy 165.484811 -286.971804) (xy 165.473034 -286.92402) (xy 165.469074 -286.874966)
			(xy 165.130226 -286.874966) (xy 165.129731 -286.899573) (xy 165.121836 -286.94815) (xy 165.106252 -286.994831)
			(xy 165.083381 -287.038408) (xy 165.053816 -287.077752) (xy 165.018323 -287.111844) (xy 164.97782 -287.1398)
			(xy 164.933358 -287.160898) (xy 164.886087 -287.17459) (xy 164.837232 -287.180522) (xy 164.788057 -287.178541)
			(xy 164.739838 -287.168697) (xy 164.693822 -287.151245) (xy 164.651201 -287.126638) (xy 164.61308 -287.095513)
			(xy 164.580445 -287.058676) (xy 164.554142 -287.01708) (xy 164.534851 -286.971804) (xy 164.523074 -286.92402)
			(xy 164.519114 -286.874966) (xy 164.180266 -286.874966) (xy 164.179771 -286.899573) (xy 164.171876 -286.94815)
			(xy 164.156292 -286.994831) (xy 164.133421 -287.038408) (xy 164.103856 -287.077752) (xy 164.068363 -287.111844)
			(xy 164.02786 -287.1398) (xy 163.983398 -287.160898) (xy 163.936127 -287.17459) (xy 163.887272 -287.180522)
			(xy 163.838097 -287.178541) (xy 163.789878 -287.168697) (xy 163.743862 -287.151245) (xy 163.701241 -287.126638)
			(xy 163.66312 -287.095513) (xy 163.630485 -287.058676) (xy 163.604182 -287.01708) (xy 163.584891 -286.971804)
			(xy 163.573114 -286.92402) (xy 163.569154 -286.874966) (xy 163.230306 -286.874966) (xy 163.229811 -286.899573)
			(xy 163.221916 -286.94815) (xy 163.206332 -286.994831) (xy 163.183461 -287.038408) (xy 163.153896 -287.077752)
			(xy 163.118403 -287.111844) (xy 163.0779 -287.1398) (xy 163.033438 -287.160898) (xy 162.986167 -287.17459)
			(xy 162.937312 -287.180522) (xy 162.888137 -287.178541) (xy 162.839918 -287.168697) (xy 162.793902 -287.151245)
			(xy 162.751281 -287.126638) (xy 162.71316 -287.095513) (xy 162.680525 -287.058676) (xy 162.654222 -287.01708)
			(xy 162.634931 -286.971804) (xy 162.623154 -286.92402) (xy 162.619194 -286.874966) (xy 162.280346 -286.874966)
			(xy 162.279851 -286.899573) (xy 162.271956 -286.94815) (xy 162.256372 -286.994831) (xy 162.233501 -287.038408)
			(xy 162.203936 -287.077752) (xy 162.168443 -287.111844) (xy 162.12794 -287.1398) (xy 162.083478 -287.160898)
			(xy 162.036207 -287.17459) (xy 161.987352 -287.180522) (xy 161.938177 -287.178541) (xy 161.889958 -287.168697)
			(xy 161.843942 -287.151245) (xy 161.801321 -287.126638) (xy 161.7632 -287.095513) (xy 161.730565 -287.058676)
			(xy 161.704262 -287.01708) (xy 161.684971 -286.971804) (xy 161.673194 -286.92402) (xy 161.669234 -286.874966)
			(xy 161.330386 -286.874966) (xy 161.329891 -286.899573) (xy 161.321996 -286.94815) (xy 161.306412 -286.994831)
			(xy 161.283541 -287.038408) (xy 161.253976 -287.077752) (xy 161.218483 -287.111844) (xy 161.17798 -287.1398)
			(xy 161.133518 -287.160898) (xy 161.086247 -287.17459) (xy 161.037392 -287.180522) (xy 160.988217 -287.178541)
			(xy 160.939998 -287.168697) (xy 160.893982 -287.151245) (xy 160.851361 -287.126638) (xy 160.81324 -287.095513)
			(xy 160.780605 -287.058676) (xy 160.754302 -287.01708) (xy 160.735011 -286.971804) (xy 160.723234 -286.92402)
			(xy 160.719274 -286.874966) (xy 160.380167 -286.874966) (xy 160.379677 -286.899319) (xy 160.371782 -286.947896)
			(xy 160.356198 -286.994577) (xy 160.333327 -287.038154) (xy 160.303762 -287.077498) (xy 160.268269 -287.11159)
			(xy 160.227766 -287.139546) (xy 160.183304 -287.160644) (xy 160.136033 -287.174336) (xy 160.087178 -287.180268)
			(xy 160.038003 -287.178287) (xy 159.989784 -287.168443) (xy 159.943768 -287.150991) (xy 159.901147 -287.126384)
			(xy 159.863026 -287.095259) (xy 159.830391 -287.058422) (xy 159.804088 -287.016826) (xy 159.784797 -286.97155)
			(xy 159.77302 -286.923766) (xy 159.76906 -286.874712) (xy 159.430212 -286.874712) (xy 159.429717 -286.899319)
			(xy 159.421822 -286.947896) (xy 159.406238 -286.994577) (xy 159.383367 -287.038154) (xy 159.353802 -287.077498)
			(xy 159.318309 -287.11159) (xy 159.277806 -287.139546) (xy 159.233344 -287.160644) (xy 159.186073 -287.174336)
			(xy 159.137218 -287.180268) (xy 159.088043 -287.178287) (xy 159.039824 -287.168443) (xy 158.993808 -287.150991)
			(xy 158.951187 -287.126384) (xy 158.913066 -287.095259) (xy 158.880431 -287.058422) (xy 158.854128 -287.016826)
			(xy 158.834837 -286.97155) (xy 158.82306 -286.923766) (xy 158.8191 -286.874712) (xy 158.480247 -286.874712)
			(xy 158.480252 -286.874966) (xy 158.479757 -286.899573) (xy 158.471862 -286.94815) (xy 158.456278 -286.994831)
			(xy 158.433407 -287.038408) (xy 158.403842 -287.077752) (xy 158.368349 -287.111844) (xy 158.327846 -287.1398)
			(xy 158.283384 -287.160898) (xy 158.236113 -287.17459) (xy 158.187258 -287.180522) (xy 158.138083 -287.178541)
			(xy 158.089864 -287.168697) (xy 158.043848 -287.151245) (xy 158.001227 -287.126638) (xy 157.963106 -287.095513)
			(xy 157.930471 -287.058676) (xy 157.904168 -287.01708) (xy 157.884877 -286.971804) (xy 157.8731 -286.92402)
			(xy 157.86914 -286.874966) (xy 157.530292 -286.874966) (xy 157.529797 -286.899573) (xy 157.521902 -286.94815)
			(xy 157.506318 -286.994831) (xy 157.483447 -287.038408) (xy 157.453882 -287.077752) (xy 157.418389 -287.111844)
			(xy 157.377886 -287.1398) (xy 157.333424 -287.160898) (xy 157.286153 -287.17459) (xy 157.237298 -287.180522)
			(xy 157.188123 -287.178541) (xy 157.139904 -287.168697) (xy 157.093888 -287.151245) (xy 157.051267 -287.126638)
			(xy 157.013146 -287.095513) (xy 156.980511 -287.058676) (xy 156.954208 -287.01708) (xy 156.934917 -286.971804)
			(xy 156.92314 -286.92402) (xy 156.91918 -286.874966) (xy 156.580332 -286.874966) (xy 156.579837 -286.899573)
			(xy 156.571942 -286.94815) (xy 156.556358 -286.994831) (xy 156.533487 -287.038408) (xy 156.503922 -287.077752)
			(xy 156.468429 -287.111844) (xy 156.427926 -287.1398) (xy 156.383464 -287.160898) (xy 156.336193 -287.17459)
			(xy 156.287338 -287.180522) (xy 156.238163 -287.178541) (xy 156.189944 -287.168697) (xy 156.143928 -287.151245)
			(xy 156.101307 -287.126638) (xy 156.063186 -287.095513) (xy 156.030551 -287.058676) (xy 156.004248 -287.01708)
			(xy 155.984957 -286.971804) (xy 155.97318 -286.92402) (xy 155.96922 -286.874966) (xy 155.630372 -286.874966)
			(xy 155.629877 -286.899573) (xy 155.621982 -286.94815) (xy 155.606398 -286.994831) (xy 155.583527 -287.038408)
			(xy 155.553962 -287.077752) (xy 155.518469 -287.111844) (xy 155.477966 -287.1398) (xy 155.433504 -287.160898)
			(xy 155.386233 -287.17459) (xy 155.337378 -287.180522) (xy 155.288203 -287.178541) (xy 155.239984 -287.168697)
			(xy 155.193968 -287.151245) (xy 155.151347 -287.126638) (xy 155.113226 -287.095513) (xy 155.080591 -287.058676)
			(xy 155.054288 -287.01708) (xy 155.034997 -286.971804) (xy 155.02322 -286.92402) (xy 155.01926 -286.874966)
			(xy 154.680412 -286.874966) (xy 154.679917 -286.899573) (xy 154.672022 -286.94815) (xy 154.656438 -286.994831)
			(xy 154.633567 -287.038408) (xy 154.604002 -287.077752) (xy 154.568509 -287.111844) (xy 154.528006 -287.1398)
			(xy 154.483544 -287.160898) (xy 154.436273 -287.17459) (xy 154.387418 -287.180522) (xy 154.338243 -287.178541)
			(xy 154.290024 -287.168697) (xy 154.244008 -287.151245) (xy 154.201387 -287.126638) (xy 154.163266 -287.095513)
			(xy 154.130631 -287.058676) (xy 154.104328 -287.01708) (xy 154.085037 -286.971804) (xy 154.07326 -286.92402)
			(xy 154.0693 -286.874966) (xy 153.730198 -286.874966) (xy 153.729703 -286.899573) (xy 153.721808 -286.94815)
			(xy 153.706224 -286.994831) (xy 153.683353 -287.038408) (xy 153.653788 -287.077752) (xy 153.618295 -287.111844)
			(xy 153.577792 -287.1398) (xy 153.53333 -287.160898) (xy 153.486059 -287.17459) (xy 153.437204 -287.180522)
			(xy 153.388029 -287.178541) (xy 153.33981 -287.168697) (xy 153.293794 -287.151245) (xy 153.251173 -287.126638)
			(xy 153.213052 -287.095513) (xy 153.180417 -287.058676) (xy 153.154114 -287.01708) (xy 153.134823 -286.971804)
			(xy 153.123046 -286.92402) (xy 153.119086 -286.874966) (xy 152.780238 -286.874966) (xy 152.779743 -286.899573)
			(xy 152.771848 -286.94815) (xy 152.756264 -286.994831) (xy 152.733393 -287.038408) (xy 152.703828 -287.077752)
			(xy 152.668335 -287.111844) (xy 152.627832 -287.1398) (xy 152.58337 -287.160898) (xy 152.536099 -287.17459)
			(xy 152.487244 -287.180522) (xy 152.438069 -287.178541) (xy 152.38985 -287.168697) (xy 152.343834 -287.151245)
			(xy 152.301213 -287.126638) (xy 152.263092 -287.095513) (xy 152.230457 -287.058676) (xy 152.204154 -287.01708)
			(xy 152.184863 -286.971804) (xy 152.173086 -286.92402) (xy 152.169126 -286.874966) (xy 150.415058 -286.874966)
			(xy 150.436217 -286.906948) (xy 150.459889 -286.957445) (xy 150.475957 -287.010852) (xy 150.484077 -287.066028)
			(xy 150.484586 -287.093914) (xy 150.484077 -287.1218) (xy 150.475957 -287.176976) (xy 150.459889 -287.230383)
			(xy 150.436217 -287.28088) (xy 150.405444 -287.327393) (xy 150.368227 -287.36893) (xy 150.325359 -287.404605)
			(xy 150.277753 -287.433659) (xy 150.226424 -287.455471) (xy 150.172467 -287.469577) (xy 150.11703 -287.475677)
			(xy 150.061296 -287.47364) (xy 150.006453 -287.46351) (xy 149.953669 -287.445503) (xy 149.904069 -287.420002)
			(xy 149.858711 -287.387551) (xy 149.818562 -287.348842) (xy 149.784476 -287.304699) (xy 149.75718 -287.256064)
			(xy 149.737257 -287.203973) (xy 149.725131 -287.149536) (xy 149.72106 -287.093914) (xy 149.598126 -287.093914)
			(xy 149.597617 -287.1218) (xy 149.589497 -287.176976) (xy 149.573429 -287.230383) (xy 149.549757 -287.28088)
			(xy 149.518984 -287.327393) (xy 149.481767 -287.36893) (xy 149.438899 -287.404605) (xy 149.391293 -287.433659)
			(xy 149.339964 -287.455471) (xy 149.286007 -287.469577) (xy 149.23057 -287.475677) (xy 149.174836 -287.47364)
			(xy 149.119993 -287.46351) (xy 149.067209 -287.445503) (xy 149.017609 -287.420002) (xy 148.972251 -287.387551)
			(xy 148.932102 -287.348842) (xy 148.898016 -287.304699) (xy 148.87072 -287.256064) (xy 148.850797 -287.203973)
			(xy 148.838671 -287.149536) (xy 148.8346 -287.093914) (xy 148.201126 -287.093914) (xy 148.20064 -287.121165)
			(xy 148.192884 -287.175113) (xy 148.177529 -287.227408) (xy 148.154887 -287.276985) (xy 148.125421 -287.322835)
			(xy 148.08973 -287.364026) (xy 148.048539 -287.399717) (xy 148.002689 -287.429183) (xy 147.953112 -287.451825)
			(xy 147.900817 -287.46718) (xy 147.846869 -287.474936) (xy 147.792367 -287.474936) (xy 147.738419 -287.46718)
			(xy 147.686124 -287.451825) (xy 147.636547 -287.429183) (xy 147.590697 -287.399717) (xy 147.549506 -287.364026)
			(xy 147.513815 -287.322835) (xy 147.484349 -287.276985) (xy 147.461707 -287.227408) (xy 147.446352 -287.175113)
			(xy 147.438596 -287.121165) (xy 147.43811 -287.093914) (xy 147.438529 -287.068485) (xy 147.445283 -287.018077)
			(xy 147.458673 -286.969013) (xy 147.478462 -286.922162) (xy 147.504299 -286.878356) (xy 147.535726 -286.838369)
			(xy 147.55368 -286.820356) (xy 147.560538 -286.814006) (xy 147.589494 -286.789622) (xy 147.589748 -286.789368)
			(xy 147.598652 -286.781874) (xy 147.609105 -286.761106) (xy 147.609814 -286.74949) (xy 147.61083 -286.672782)
			(xy 147.610774 -286.668508) (xy 147.609375 -286.660077) (xy 147.608036 -286.656018) (xy 147.604226 -286.644334)
			(xy 147.596098 -286.63265) (xy 147.59051 -286.628078) (xy 147.570806 -286.611539) (xy 147.535591 -286.574038)
			(xy 147.505741 -286.53214) (xy 147.481798 -286.486608) (xy 147.464198 -286.438269) (xy 147.45326 -286.388002)
			(xy 147.45081 -286.362394) (xy 147.450048 -286.352742) (xy 147.441666 -286.335724) (xy 147.384008 -286.282638)
			(xy 147.376896 -286.276034) (xy 147.35937 -286.269176) (xy 145.139156 -286.269176) (xy 145.129612 -286.269627)
			(xy 145.111866 -286.276673) (xy 145.104612 -286.282892) (xy 145.090896 -286.295592) (xy 145.090388 -286.2961)
			(xy 145.047462 -286.335724) (xy 145.03908 -286.352742) (xy 145.038318 -286.362394) (xy 145.03552 -286.39071)
			(xy 145.0226 -286.446122) (xy 145.001595 -286.499001) (xy 144.972969 -286.548174) (xy 144.937359 -286.592551)
			(xy 144.895553 -286.631147) (xy 144.848478 -286.663107) (xy 144.79718 -286.687722) (xy 144.742795 -286.704445)
			(xy 144.686529 -286.712907) (xy 144.65808 -286.713422) (xy 144.630841 -286.712936) (xy 144.576917 -286.705183)
			(xy 144.524644 -286.68984) (xy 144.475085 -286.667216) (xy 144.429249 -286.637773) (xy 144.388066 -286.602109)
			(xy 144.352376 -286.56095) (xy 144.322903 -286.515133) (xy 144.300247 -286.465589) (xy 144.284869 -286.413326)
			(xy 144.277082 -286.359407) (xy 144.276572 -286.332168) (xy 144.276572 -286.331914) (xy 144.276826 -286.3215)
			(xy 144.276826 -286.319976) (xy 144.276334 -286.30997) (xy 144.268671 -286.291482) (xy 144.25452 -286.27733)
			(xy 144.236032 -286.269666) (xy 144.226026 -286.269176) (xy 144.201134 -286.269176) (xy 144.191106 -286.26959)
			(xy 144.172574 -286.277253) (xy 144.158385 -286.291425) (xy 144.150701 -286.309949) (xy 144.150334 -286.319976)
			(xy 144.150334 -286.3215) (xy 144.150588 -286.331914) (xy 144.150588 -286.332168) (xy 144.150083 -286.359406)
			(xy 144.142296 -286.413324) (xy 144.126917 -286.465585) (xy 144.104261 -286.515127) (xy 144.074787 -286.560943)
			(xy 144.039095 -286.602099) (xy 143.997912 -286.63776) (xy 143.952074 -286.667199) (xy 143.902515 -286.689818)
			(xy 143.850242 -286.705157) (xy 143.796319 -286.712904) (xy 143.76908 -286.713422) (xy 143.740627 -286.712902)
			(xy 143.684351 -286.704459) (xy 143.629954 -286.687749) (xy 143.578644 -286.663143) (xy 143.531558 -286.631186)
			(xy 143.489743 -286.592589) (xy 143.454127 -286.548208) (xy 143.425499 -286.499027) (xy 143.404496 -286.44614)
			(xy 143.391583 -286.390718) (xy 143.388842 -286.362394) (xy 143.38808 -286.352742) (xy 143.379698 -286.335724)
			(xy 143.32204 -286.282638) (xy 143.314928 -286.276034) (xy 143.297402 -286.269176) (xy 142.77467 -286.269176)
			(xy 142.765125 -286.269624) (xy 142.747375 -286.276667) (xy 142.740126 -286.282892) (xy 142.72641 -286.295592)
			(xy 142.725902 -286.2961) (xy 142.682976 -286.335724) (xy 142.674594 -286.352742) (xy 142.673832 -286.362394)
			(xy 142.671194 -286.389361) (xy 142.659265 -286.442215) (xy 142.639977 -286.49285) (xy 142.613719 -286.540245)
			(xy 142.581017 -286.583448) (xy 142.542532 -286.621589) (xy 142.499036 -286.6539) (xy 142.451406 -286.679731)
			(xy 142.400601 -286.698563) (xy 142.347641 -286.710015) (xy 142.293594 -286.713859) (xy 142.239547 -286.710015)
			(xy 142.186587 -286.698563) (xy 142.135782 -286.679731) (xy 142.088152 -286.6539) (xy 142.044656 -286.621589)
			(xy 142.006171 -286.583448) (xy 141.973469 -286.540245) (xy 141.947211 -286.49285) (xy 141.927923 -286.442215)
			(xy 141.915994 -286.389361) (xy 141.913356 -286.362394) (xy 141.912594 -286.352742) (xy 141.904212 -286.335724)
			(xy 141.846554 -286.282638) (xy 141.839442 -286.276034) (xy 141.821916 -286.269176) (xy 137.66165 -286.269176)
			(xy 137.651584 -286.268743) (xy 137.632995 -286.261013) (xy 137.625582 -286.25419) (xy 137.42543 -286.053784)
			(xy 137.20318 -285.831534) (xy 136.962134 -285.590742) (xy 136.954734 -285.583901) (xy 136.936135 -285.576184)
			(xy 136.926066 -285.575756) (xy 136.764522 -285.575756) (xy 136.754459 -285.576195) (xy 136.735881 -285.583935)
			(xy 136.728454 -285.590742) (xy 136.365234 -285.953962) (xy 136.358394 -285.961362) (xy 136.350676 -285.979961)
			(xy 136.350248 -285.99003) (xy 136.350248 -286.314896) (xy 136.349994 -286.319976) (xy 136.349994 -287.824926)
			(xy 152.169126 -287.824926) (xy 152.173086 -287.775872) (xy 152.184863 -287.728088) (xy 152.204154 -287.682812)
			(xy 152.230457 -287.641216) (xy 152.263092 -287.604379) (xy 152.301213 -287.573254) (xy 152.343834 -287.548647)
			(xy 152.38985 -287.531195) (xy 152.438069 -287.521351) (xy 152.487244 -287.51937) (xy 152.536099 -287.525302)
			(xy 152.58337 -287.538994) (xy 152.627832 -287.560092) (xy 152.668335 -287.588048) (xy 152.703828 -287.62214)
			(xy 152.733393 -287.661484) (xy 152.756264 -287.705061) (xy 152.771848 -287.751742) (xy 152.779743 -287.800319)
			(xy 152.780238 -287.824926) (xy 153.119086 -287.824926) (xy 153.123046 -287.775872) (xy 153.134823 -287.728088)
			(xy 153.154114 -287.682812) (xy 153.180417 -287.641216) (xy 153.213052 -287.604379) (xy 153.251173 -287.573254)
			(xy 153.293794 -287.548647) (xy 153.33981 -287.531195) (xy 153.388029 -287.521351) (xy 153.437204 -287.51937)
			(xy 153.486059 -287.525302) (xy 153.53333 -287.538994) (xy 153.577792 -287.560092) (xy 153.618295 -287.588048)
			(xy 153.653788 -287.62214) (xy 153.683353 -287.661484) (xy 153.706224 -287.705061) (xy 153.721808 -287.751742)
			(xy 153.729703 -287.800319) (xy 153.730198 -287.824926) (xy 154.0693 -287.824926) (xy 154.07326 -287.775872)
			(xy 154.085037 -287.728088) (xy 154.104328 -287.682812) (xy 154.130631 -287.641216) (xy 154.163266 -287.604379)
			(xy 154.201387 -287.573254) (xy 154.244008 -287.548647) (xy 154.290024 -287.531195) (xy 154.338243 -287.521351)
			(xy 154.387418 -287.51937) (xy 154.436273 -287.525302) (xy 154.483544 -287.538994) (xy 154.528006 -287.560092)
			(xy 154.568509 -287.588048) (xy 154.604002 -287.62214) (xy 154.633567 -287.661484) (xy 154.656438 -287.705061)
			(xy 154.672022 -287.751742) (xy 154.679917 -287.800319) (xy 154.680412 -287.824926) (xy 156.91918 -287.824926)
			(xy 156.92314 -287.775872) (xy 156.934917 -287.728088) (xy 156.954208 -287.682812) (xy 156.980511 -287.641216)
			(xy 157.013146 -287.604379) (xy 157.051267 -287.573254) (xy 157.093888 -287.548647) (xy 157.139904 -287.531195)
			(xy 157.188123 -287.521351) (xy 157.237298 -287.51937) (xy 157.286153 -287.525302) (xy 157.333424 -287.538994)
			(xy 157.377886 -287.560092) (xy 157.418389 -287.588048) (xy 157.453882 -287.62214) (xy 157.483447 -287.661484)
			(xy 157.506318 -287.705061) (xy 157.521902 -287.751742) (xy 157.529797 -287.800319) (xy 157.530292 -287.824926)
			(xy 160.719274 -287.824926) (xy 160.723234 -287.775872) (xy 160.735011 -287.728088) (xy 160.754302 -287.682812)
			(xy 160.780605 -287.641216) (xy 160.81324 -287.604379) (xy 160.851361 -287.573254) (xy 160.893982 -287.548647)
			(xy 160.939998 -287.531195) (xy 160.988217 -287.521351) (xy 161.037392 -287.51937) (xy 161.086247 -287.525302)
			(xy 161.133518 -287.538994) (xy 161.17798 -287.560092) (xy 161.218483 -287.588048) (xy 161.253976 -287.62214)
			(xy 161.283541 -287.661484) (xy 161.306412 -287.705061) (xy 161.321996 -287.751742) (xy 161.329891 -287.800319)
			(xy 161.330386 -287.824926) (xy 161.669234 -287.824926) (xy 161.673194 -287.775872) (xy 161.684971 -287.728088)
			(xy 161.704262 -287.682812) (xy 161.730565 -287.641216) (xy 161.7632 -287.604379) (xy 161.801321 -287.573254)
			(xy 161.843942 -287.548647) (xy 161.889958 -287.531195) (xy 161.938177 -287.521351) (xy 161.987352 -287.51937)
			(xy 162.036207 -287.525302) (xy 162.083478 -287.538994) (xy 162.12794 -287.560092) (xy 162.168443 -287.588048)
			(xy 162.203936 -287.62214) (xy 162.233501 -287.661484) (xy 162.256372 -287.705061) (xy 162.271956 -287.751742)
			(xy 162.279851 -287.800319) (xy 162.280346 -287.824926) (xy 162.619194 -287.824926) (xy 162.623154 -287.775872)
			(xy 162.634931 -287.728088) (xy 162.654222 -287.682812) (xy 162.680525 -287.641216) (xy 162.71316 -287.604379)
			(xy 162.751281 -287.573254) (xy 162.793902 -287.548647) (xy 162.839918 -287.531195) (xy 162.888137 -287.521351)
			(xy 162.937312 -287.51937) (xy 162.986167 -287.525302) (xy 163.033438 -287.538994) (xy 163.0779 -287.560092)
			(xy 163.118403 -287.588048) (xy 163.153896 -287.62214) (xy 163.183461 -287.661484) (xy 163.206332 -287.705061)
			(xy 163.221916 -287.751742) (xy 163.229811 -287.800319) (xy 163.230306 -287.824926) (xy 163.569154 -287.824926)
			(xy 163.573114 -287.775872) (xy 163.584891 -287.728088) (xy 163.604182 -287.682812) (xy 163.630485 -287.641216)
			(xy 163.66312 -287.604379) (xy 163.701241 -287.573254) (xy 163.743862 -287.548647) (xy 163.789878 -287.531195)
			(xy 163.838097 -287.521351) (xy 163.887272 -287.51937) (xy 163.936127 -287.525302) (xy 163.983398 -287.538994)
			(xy 164.02786 -287.560092) (xy 164.068363 -287.588048) (xy 164.103856 -287.62214) (xy 164.133421 -287.661484)
			(xy 164.156292 -287.705061) (xy 164.171876 -287.751742) (xy 164.179771 -287.800319) (xy 164.180266 -287.824926)
			(xy 164.519114 -287.824926) (xy 164.523074 -287.775872) (xy 164.534851 -287.728088) (xy 164.554142 -287.682812)
			(xy 164.580445 -287.641216) (xy 164.61308 -287.604379) (xy 164.651201 -287.573254) (xy 164.693822 -287.548647)
			(xy 164.739838 -287.531195) (xy 164.788057 -287.521351) (xy 164.837232 -287.51937) (xy 164.886087 -287.525302)
			(xy 164.933358 -287.538994) (xy 164.97782 -287.560092) (xy 165.018323 -287.588048) (xy 165.053816 -287.62214)
			(xy 165.083381 -287.661484) (xy 165.106252 -287.705061) (xy 165.121836 -287.751742) (xy 165.129731 -287.800319)
			(xy 165.130226 -287.824926) (xy 165.469074 -287.824926) (xy 165.473034 -287.775872) (xy 165.484811 -287.728088)
			(xy 165.504102 -287.682812) (xy 165.530405 -287.641216) (xy 165.56304 -287.604379) (xy 165.601161 -287.573254)
			(xy 165.643782 -287.548647) (xy 165.689798 -287.531195) (xy 165.738017 -287.521351) (xy 165.787192 -287.51937)
			(xy 165.836047 -287.525302) (xy 165.883318 -287.538994) (xy 165.92778 -287.560092) (xy 165.968283 -287.588048)
			(xy 166.003776 -287.62214) (xy 166.033341 -287.661484) (xy 166.056212 -287.705061) (xy 166.071796 -287.751742)
			(xy 166.079691 -287.800319) (xy 166.080186 -287.824926) (xy 166.419288 -287.824926) (xy 166.423248 -287.775872)
			(xy 166.435025 -287.728088) (xy 166.454316 -287.682812) (xy 166.480619 -287.641216) (xy 166.513254 -287.604379)
			(xy 166.551375 -287.573254) (xy 166.593996 -287.548647) (xy 166.640012 -287.531195) (xy 166.688231 -287.521351)
			(xy 166.737406 -287.51937) (xy 166.786261 -287.525302) (xy 166.833532 -287.538994) (xy 166.877994 -287.560092)
			(xy 166.918497 -287.588048) (xy 166.95399 -287.62214) (xy 166.983555 -287.661484) (xy 167.006426 -287.705061)
			(xy 167.02201 -287.751742) (xy 167.029905 -287.800319) (xy 167.0304 -287.824926) (xy 167.369248 -287.824926)
			(xy 167.373208 -287.775872) (xy 167.384985 -287.728088) (xy 167.404276 -287.682812) (xy 167.430579 -287.641216)
			(xy 167.463214 -287.604379) (xy 167.501335 -287.573254) (xy 167.543956 -287.548647) (xy 167.589972 -287.531195)
			(xy 167.638191 -287.521351) (xy 167.687366 -287.51937) (xy 167.736221 -287.525302) (xy 167.783492 -287.538994)
			(xy 167.827954 -287.560092) (xy 167.868457 -287.588048) (xy 167.90395 -287.62214) (xy 167.933515 -287.661484)
			(xy 167.956386 -287.705061) (xy 167.97197 -287.751742) (xy 167.979865 -287.800319) (xy 167.98036 -287.824926)
			(xy 168.319208 -287.824926) (xy 168.323168 -287.775872) (xy 168.334945 -287.728088) (xy 168.354236 -287.682812)
			(xy 168.380539 -287.641216) (xy 168.413174 -287.604379) (xy 168.451295 -287.573254) (xy 168.493916 -287.548647)
			(xy 168.539932 -287.531195) (xy 168.588151 -287.521351) (xy 168.637326 -287.51937) (xy 168.686181 -287.525302)
			(xy 168.733452 -287.538994) (xy 168.777914 -287.560092) (xy 168.818417 -287.588048) (xy 168.85391 -287.62214)
			(xy 168.883475 -287.661484) (xy 168.906346 -287.705061) (xy 168.92193 -287.751742) (xy 168.929825 -287.800319)
			(xy 168.93032 -287.824926) (xy 169.269168 -287.824926) (xy 169.273128 -287.775872) (xy 169.284905 -287.728088)
			(xy 169.304196 -287.682812) (xy 169.330499 -287.641216) (xy 169.363134 -287.604379) (xy 169.401255 -287.573254)
			(xy 169.443876 -287.548647) (xy 169.489892 -287.531195) (xy 169.538111 -287.521351) (xy 169.587286 -287.51937)
			(xy 169.636141 -287.525302) (xy 169.683412 -287.538994) (xy 169.727874 -287.560092) (xy 169.768377 -287.588048)
			(xy 169.80387 -287.62214) (xy 169.833435 -287.661484) (xy 169.856306 -287.705061) (xy 169.87189 -287.751742)
			(xy 169.879785 -287.800319) (xy 169.88028 -287.824926) (xy 170.219128 -287.824926) (xy 170.223088 -287.775872)
			(xy 170.234865 -287.728088) (xy 170.254156 -287.682812) (xy 170.280459 -287.641216) (xy 170.313094 -287.604379)
			(xy 170.351215 -287.573254) (xy 170.393836 -287.548647) (xy 170.439852 -287.531195) (xy 170.488071 -287.521351)
			(xy 170.537246 -287.51937) (xy 170.586101 -287.525302) (xy 170.633372 -287.538994) (xy 170.677834 -287.560092)
			(xy 170.718337 -287.588048) (xy 170.75383 -287.62214) (xy 170.783395 -287.661484) (xy 170.806266 -287.705061)
			(xy 170.82185 -287.751742) (xy 170.829745 -287.800319) (xy 170.83024 -287.824926) (xy 171.169088 -287.824926)
			(xy 171.173048 -287.775872) (xy 171.184825 -287.728088) (xy 171.204116 -287.682812) (xy 171.230419 -287.641216)
			(xy 171.263054 -287.604379) (xy 171.301175 -287.573254) (xy 171.343796 -287.548647) (xy 171.389812 -287.531195)
			(xy 171.438031 -287.521351) (xy 171.487206 -287.51937) (xy 171.536061 -287.525302) (xy 171.583332 -287.538994)
			(xy 171.627794 -287.560092) (xy 171.668297 -287.588048) (xy 171.70379 -287.62214) (xy 171.733355 -287.661484)
			(xy 171.756226 -287.705061) (xy 171.77181 -287.751742) (xy 171.779705 -287.800319) (xy 171.7802 -287.824926)
			(xy 172.119048 -287.824926) (xy 172.123008 -287.775872) (xy 172.134785 -287.728088) (xy 172.154076 -287.682812)
			(xy 172.180379 -287.641216) (xy 172.213014 -287.604379) (xy 172.251135 -287.573254) (xy 172.293756 -287.548647)
			(xy 172.339772 -287.531195) (xy 172.387991 -287.521351) (xy 172.437166 -287.51937) (xy 172.486021 -287.525302)
			(xy 172.533292 -287.538994) (xy 172.577754 -287.560092) (xy 172.618257 -287.588048) (xy 172.65375 -287.62214)
			(xy 172.683315 -287.661484) (xy 172.706186 -287.705061) (xy 172.72177 -287.751742) (xy 172.729665 -287.800319)
			(xy 172.73016 -287.824926) (xy 173.069262 -287.824926) (xy 173.073222 -287.775872) (xy 173.084999 -287.728088)
			(xy 173.10429 -287.682812) (xy 173.130593 -287.641216) (xy 173.163228 -287.604379) (xy 173.201349 -287.573254)
			(xy 173.24397 -287.548647) (xy 173.289986 -287.531195) (xy 173.338205 -287.521351) (xy 173.38738 -287.51937)
			(xy 173.436235 -287.525302) (xy 173.483506 -287.538994) (xy 173.527968 -287.560092) (xy 173.568471 -287.588048)
			(xy 173.603964 -287.62214) (xy 173.633529 -287.661484) (xy 173.653722 -287.699958) (xy 174.044114 -287.699958)
			(xy 174.048074 -287.650904) (xy 174.059851 -287.60312) (xy 174.079142 -287.557844) (xy 174.105445 -287.516248)
			(xy 174.13808 -287.479411) (xy 174.176201 -287.448286) (xy 174.218822 -287.423679) (xy 174.264838 -287.406227)
			(xy 174.313057 -287.396383) (xy 174.362232 -287.394402) (xy 174.411087 -287.400334) (xy 174.458358 -287.414026)
			(xy 174.50282 -287.435124) (xy 174.543323 -287.46308) (xy 174.578816 -287.497172) (xy 174.608381 -287.536516)
			(xy 174.631252 -287.580093) (xy 174.646836 -287.626774) (xy 174.654731 -287.675351) (xy 174.655226 -287.699958)
			(xy 174.654731 -287.724565) (xy 174.646836 -287.773142) (xy 174.631252 -287.819823) (xy 174.608381 -287.8634)
			(xy 174.580986 -287.899856) (xy 175.919142 -287.899856) (xy 175.923102 -287.850802) (xy 175.934879 -287.803018)
			(xy 175.95417 -287.757742) (xy 175.980473 -287.716146) (xy 176.013108 -287.679309) (xy 176.051229 -287.648184)
			(xy 176.09385 -287.623577) (xy 176.139866 -287.606125) (xy 176.188085 -287.596281) (xy 176.23726 -287.5943)
			(xy 176.286115 -287.600232) (xy 176.333386 -287.613924) (xy 176.377848 -287.635022) (xy 176.418351 -287.662978)
			(xy 176.453844 -287.69707) (xy 176.483409 -287.736414) (xy 176.50628 -287.779991) (xy 176.521281 -287.824926)
			(xy 176.869102 -287.824926) (xy 176.873062 -287.775872) (xy 176.884839 -287.728088) (xy 176.90413 -287.682812)
			(xy 176.930433 -287.641216) (xy 176.963068 -287.604379) (xy 177.001189 -287.573254) (xy 177.04381 -287.548647)
			(xy 177.089826 -287.531195) (xy 177.138045 -287.521351) (xy 177.18722 -287.51937) (xy 177.236075 -287.525302)
			(xy 177.283346 -287.538994) (xy 177.327808 -287.560092) (xy 177.368311 -287.588048) (xy 177.403804 -287.62214)
			(xy 177.433369 -287.661484) (xy 177.45624 -287.705061) (xy 177.471824 -287.751742) (xy 177.479719 -287.800319)
			(xy 177.480214 -287.824926) (xy 177.819062 -287.824926) (xy 177.823022 -287.775872) (xy 177.834799 -287.728088)
			(xy 177.85409 -287.682812) (xy 177.880393 -287.641216) (xy 177.913028 -287.604379) (xy 177.951149 -287.573254)
			(xy 177.99377 -287.548647) (xy 178.039786 -287.531195) (xy 178.088005 -287.521351) (xy 178.13718 -287.51937)
			(xy 178.186035 -287.525302) (xy 178.233306 -287.538994) (xy 178.277768 -287.560092) (xy 178.318271 -287.588048)
			(xy 178.353764 -287.62214) (xy 178.383329 -287.661484) (xy 178.4062 -287.705061) (xy 178.421784 -287.751742)
			(xy 178.429679 -287.800319) (xy 178.430174 -287.824926) (xy 178.769276 -287.824926) (xy 178.773236 -287.775872)
			(xy 178.785013 -287.728088) (xy 178.804304 -287.682812) (xy 178.830607 -287.641216) (xy 178.863242 -287.604379)
			(xy 178.901363 -287.573254) (xy 178.943984 -287.548647) (xy 178.99 -287.531195) (xy 179.038219 -287.521351)
			(xy 179.087394 -287.51937) (xy 179.136249 -287.525302) (xy 179.18352 -287.538994) (xy 179.227982 -287.560092)
			(xy 179.268485 -287.588048) (xy 179.303978 -287.62214) (xy 179.333543 -287.661484) (xy 179.356414 -287.705061)
			(xy 179.371998 -287.751742) (xy 179.379893 -287.800319) (xy 179.380388 -287.824926) (xy 179.719236 -287.824926)
			(xy 179.723196 -287.775872) (xy 179.734973 -287.728088) (xy 179.754264 -287.682812) (xy 179.780567 -287.641216)
			(xy 179.813202 -287.604379) (xy 179.851323 -287.573254) (xy 179.893944 -287.548647) (xy 179.93996 -287.531195)
			(xy 179.988179 -287.521351) (xy 180.037354 -287.51937) (xy 180.086209 -287.525302) (xy 180.13348 -287.538994)
			(xy 180.177942 -287.560092) (xy 180.218445 -287.588048) (xy 180.253938 -287.62214) (xy 180.283503 -287.661484)
			(xy 180.306374 -287.705061) (xy 180.321958 -287.751742) (xy 180.329853 -287.800319) (xy 180.330348 -287.824926)
			(xy 180.669196 -287.824926) (xy 180.673156 -287.775872) (xy 180.684933 -287.728088) (xy 180.704224 -287.682812)
			(xy 180.730527 -287.641216) (xy 180.763162 -287.604379) (xy 180.801283 -287.573254) (xy 180.843904 -287.548647)
			(xy 180.88992 -287.531195) (xy 180.938139 -287.521351) (xy 180.987314 -287.51937) (xy 181.036169 -287.525302)
			(xy 181.08344 -287.538994) (xy 181.127902 -287.560092) (xy 181.168405 -287.588048) (xy 181.203898 -287.62214)
			(xy 181.233463 -287.661484) (xy 181.256334 -287.705061) (xy 181.271918 -287.751742) (xy 181.279813 -287.800319)
			(xy 181.280308 -287.824926) (xy 181.619156 -287.824926) (xy 181.623116 -287.775872) (xy 181.634893 -287.728088)
			(xy 181.654184 -287.682812) (xy 181.680487 -287.641216) (xy 181.713122 -287.604379) (xy 181.751243 -287.573254)
			(xy 181.793864 -287.548647) (xy 181.83988 -287.531195) (xy 181.888099 -287.521351) (xy 181.937274 -287.51937)
			(xy 181.986129 -287.525302) (xy 182.0334 -287.538994) (xy 182.077862 -287.560092) (xy 182.118365 -287.588048)
			(xy 182.153858 -287.62214) (xy 182.183423 -287.661484) (xy 182.206294 -287.705061) (xy 182.221878 -287.751742)
			(xy 182.229773 -287.800319) (xy 182.230268 -287.824926) (xy 182.569116 -287.824926) (xy 182.573076 -287.775872)
			(xy 182.584853 -287.728088) (xy 182.604144 -287.682812) (xy 182.630447 -287.641216) (xy 182.663082 -287.604379)
			(xy 182.701203 -287.573254) (xy 182.743824 -287.548647) (xy 182.78984 -287.531195) (xy 182.838059 -287.521351)
			(xy 182.887234 -287.51937) (xy 182.936089 -287.525302) (xy 182.98336 -287.538994) (xy 183.027822 -287.560092)
			(xy 183.068325 -287.588048) (xy 183.103818 -287.62214) (xy 183.133383 -287.661484) (xy 183.156254 -287.705061)
			(xy 183.171838 -287.751742) (xy 183.179733 -287.800319) (xy 183.180228 -287.824926) (xy 183.519076 -287.824926)
			(xy 183.523036 -287.775872) (xy 183.534813 -287.728088) (xy 183.554104 -287.682812) (xy 183.580407 -287.641216)
			(xy 183.613042 -287.604379) (xy 183.651163 -287.573254) (xy 183.693784 -287.548647) (xy 183.7398 -287.531195)
			(xy 183.788019 -287.521351) (xy 183.837194 -287.51937) (xy 183.886049 -287.525302) (xy 183.93332 -287.538994)
			(xy 183.977782 -287.560092) (xy 184.018285 -287.588048) (xy 184.053778 -287.62214) (xy 184.083343 -287.661484)
			(xy 184.106214 -287.705061) (xy 184.121798 -287.751742) (xy 184.129693 -287.800319) (xy 184.130188 -287.824926)
			(xy 184.469036 -287.824926) (xy 184.472996 -287.775872) (xy 184.484773 -287.728088) (xy 184.504064 -287.682812)
			(xy 184.530367 -287.641216) (xy 184.563002 -287.604379) (xy 184.601123 -287.573254) (xy 184.643744 -287.548647)
			(xy 184.68976 -287.531195) (xy 184.737979 -287.521351) (xy 184.787154 -287.51937) (xy 184.836009 -287.525302)
			(xy 184.88328 -287.538994) (xy 184.927742 -287.560092) (xy 184.968245 -287.588048) (xy 185.003738 -287.62214)
			(xy 185.033303 -287.661484) (xy 185.056174 -287.705061) (xy 185.071758 -287.751742) (xy 185.079653 -287.800319)
			(xy 185.080148 -287.824926) (xy 185.079653 -287.849533) (xy 185.071758 -287.89811) (xy 185.056174 -287.944791)
			(xy 185.033303 -287.988368) (xy 185.003738 -288.027712) (xy 184.968245 -288.061804) (xy 184.927742 -288.08976)
			(xy 184.88328 -288.110858) (xy 184.836009 -288.12455) (xy 184.787154 -288.130482) (xy 184.737979 -288.128501)
			(xy 184.68976 -288.118657) (xy 184.643744 -288.101205) (xy 184.601123 -288.076598) (xy 184.563002 -288.045473)
			(xy 184.530367 -288.008636) (xy 184.504064 -287.96704) (xy 184.484773 -287.921764) (xy 184.472996 -287.87398)
			(xy 184.469036 -287.824926) (xy 184.130188 -287.824926) (xy 184.129693 -287.849533) (xy 184.121798 -287.89811)
			(xy 184.106214 -287.944791) (xy 184.083343 -287.988368) (xy 184.053778 -288.027712) (xy 184.018285 -288.061804)
			(xy 183.977782 -288.08976) (xy 183.93332 -288.110858) (xy 183.886049 -288.12455) (xy 183.837194 -288.130482)
			(xy 183.788019 -288.128501) (xy 183.7398 -288.118657) (xy 183.693784 -288.101205) (xy 183.651163 -288.076598)
			(xy 183.613042 -288.045473) (xy 183.580407 -288.008636) (xy 183.554104 -287.96704) (xy 183.534813 -287.921764)
			(xy 183.523036 -287.87398) (xy 183.519076 -287.824926) (xy 183.180228 -287.824926) (xy 183.179733 -287.849533)
			(xy 183.171838 -287.89811) (xy 183.156254 -287.944791) (xy 183.133383 -287.988368) (xy 183.103818 -288.027712)
			(xy 183.068325 -288.061804) (xy 183.027822 -288.08976) (xy 182.98336 -288.110858) (xy 182.936089 -288.12455)
			(xy 182.887234 -288.130482) (xy 182.838059 -288.128501) (xy 182.78984 -288.118657) (xy 182.743824 -288.101205)
			(xy 182.701203 -288.076598) (xy 182.663082 -288.045473) (xy 182.630447 -288.008636) (xy 182.604144 -287.96704)
			(xy 182.584853 -287.921764) (xy 182.573076 -287.87398) (xy 182.569116 -287.824926) (xy 182.230268 -287.824926)
			(xy 182.229773 -287.849533) (xy 182.221878 -287.89811) (xy 182.206294 -287.944791) (xy 182.183423 -287.988368)
			(xy 182.153858 -288.027712) (xy 182.118365 -288.061804) (xy 182.077862 -288.08976) (xy 182.0334 -288.110858)
			(xy 181.986129 -288.12455) (xy 181.937274 -288.130482) (xy 181.888099 -288.128501) (xy 181.83988 -288.118657)
			(xy 181.793864 -288.101205) (xy 181.751243 -288.076598) (xy 181.713122 -288.045473) (xy 181.680487 -288.008636)
			(xy 181.654184 -287.96704) (xy 181.634893 -287.921764) (xy 181.623116 -287.87398) (xy 181.619156 -287.824926)
			(xy 181.280308 -287.824926) (xy 181.279813 -287.849533) (xy 181.271918 -287.89811) (xy 181.256334 -287.944791)
			(xy 181.233463 -287.988368) (xy 181.203898 -288.027712) (xy 181.168405 -288.061804) (xy 181.127902 -288.08976)
			(xy 181.08344 -288.110858) (xy 181.036169 -288.12455) (xy 180.987314 -288.130482) (xy 180.938139 -288.128501)
			(xy 180.88992 -288.118657) (xy 180.843904 -288.101205) (xy 180.801283 -288.076598) (xy 180.763162 -288.045473)
			(xy 180.730527 -288.008636) (xy 180.704224 -287.96704) (xy 180.684933 -287.921764) (xy 180.673156 -287.87398)
			(xy 180.669196 -287.824926) (xy 180.330348 -287.824926) (xy 180.329853 -287.849533) (xy 180.321958 -287.89811)
			(xy 180.306374 -287.944791) (xy 180.283503 -287.988368) (xy 180.253938 -288.027712) (xy 180.218445 -288.061804)
			(xy 180.177942 -288.08976) (xy 180.13348 -288.110858) (xy 180.086209 -288.12455) (xy 180.037354 -288.130482)
			(xy 179.988179 -288.128501) (xy 179.93996 -288.118657) (xy 179.893944 -288.101205) (xy 179.851323 -288.076598)
			(xy 179.813202 -288.045473) (xy 179.780567 -288.008636) (xy 179.754264 -287.96704) (xy 179.734973 -287.921764)
			(xy 179.723196 -287.87398) (xy 179.719236 -287.824926) (xy 179.380388 -287.824926) (xy 179.379893 -287.849533)
			(xy 179.371998 -287.89811) (xy 179.356414 -287.944791) (xy 179.333543 -287.988368) (xy 179.303978 -288.027712)
			(xy 179.268485 -288.061804) (xy 179.227982 -288.08976) (xy 179.18352 -288.110858) (xy 179.136249 -288.12455)
			(xy 179.087394 -288.130482) (xy 179.038219 -288.128501) (xy 178.99 -288.118657) (xy 178.943984 -288.101205)
			(xy 178.901363 -288.076598) (xy 178.863242 -288.045473) (xy 178.830607 -288.008636) (xy 178.804304 -287.96704)
			(xy 178.785013 -287.921764) (xy 178.773236 -287.87398) (xy 178.769276 -287.824926) (xy 178.430174 -287.824926)
			(xy 178.429679 -287.849533) (xy 178.421784 -287.89811) (xy 178.4062 -287.944791) (xy 178.383329 -287.988368)
			(xy 178.353764 -288.027712) (xy 178.318271 -288.061804) (xy 178.277768 -288.08976) (xy 178.233306 -288.110858)
			(xy 178.186035 -288.12455) (xy 178.13718 -288.130482) (xy 178.088005 -288.128501) (xy 178.039786 -288.118657)
			(xy 177.99377 -288.101205) (xy 177.951149 -288.076598) (xy 177.913028 -288.045473) (xy 177.880393 -288.008636)
			(xy 177.85409 -287.96704) (xy 177.834799 -287.921764) (xy 177.823022 -287.87398) (xy 177.819062 -287.824926)
			(xy 177.480214 -287.824926) (xy 177.479719 -287.849533) (xy 177.471824 -287.89811) (xy 177.45624 -287.944791)
			(xy 177.433369 -287.988368) (xy 177.403804 -288.027712) (xy 177.368311 -288.061804) (xy 177.327808 -288.08976)
			(xy 177.283346 -288.110858) (xy 177.236075 -288.12455) (xy 177.18722 -288.130482) (xy 177.138045 -288.128501)
			(xy 177.089826 -288.118657) (xy 177.04381 -288.101205) (xy 177.001189 -288.076598) (xy 176.963068 -288.045473)
			(xy 176.930433 -288.008636) (xy 176.90413 -287.96704) (xy 176.884839 -287.921764) (xy 176.873062 -287.87398)
			(xy 176.869102 -287.824926) (xy 176.521281 -287.824926) (xy 176.521864 -287.826672) (xy 176.529759 -287.875249)
			(xy 176.530254 -287.899856) (xy 176.529759 -287.924463) (xy 176.521864 -287.97304) (xy 176.50628 -288.019721)
			(xy 176.483409 -288.063298) (xy 176.453844 -288.102642) (xy 176.418351 -288.136734) (xy 176.377848 -288.16469)
			(xy 176.333386 -288.185788) (xy 176.286115 -288.19948) (xy 176.23726 -288.205412) (xy 176.188085 -288.203431)
			(xy 176.139866 -288.193587) (xy 176.09385 -288.176135) (xy 176.051229 -288.151528) (xy 176.013108 -288.120403)
			(xy 175.980473 -288.083566) (xy 175.95417 -288.04197) (xy 175.934879 -287.996694) (xy 175.923102 -287.94891)
			(xy 175.919142 -287.899856) (xy 174.580986 -287.899856) (xy 174.578816 -287.902744) (xy 174.543323 -287.936836)
			(xy 174.50282 -287.964792) (xy 174.458358 -287.98589) (xy 174.411087 -287.999582) (xy 174.362232 -288.005514)
			(xy 174.313057 -288.003533) (xy 174.264838 -287.993689) (xy 174.218822 -287.976237) (xy 174.176201 -287.95163)
			(xy 174.13808 -287.920505) (xy 174.105445 -287.883668) (xy 174.079142 -287.842072) (xy 174.059851 -287.796796)
			(xy 174.048074 -287.749012) (xy 174.044114 -287.699958) (xy 173.653722 -287.699958) (xy 173.6564 -287.705061)
			(xy 173.671984 -287.751742) (xy 173.679879 -287.800319) (xy 173.680374 -287.824926) (xy 173.679879 -287.849533)
			(xy 173.671984 -287.89811) (xy 173.6564 -287.944791) (xy 173.633529 -287.988368) (xy 173.603964 -288.027712)
			(xy 173.568471 -288.061804) (xy 173.527968 -288.08976) (xy 173.483506 -288.110858) (xy 173.436235 -288.12455)
			(xy 173.38738 -288.130482) (xy 173.338205 -288.128501) (xy 173.289986 -288.118657) (xy 173.24397 -288.101205)
			(xy 173.201349 -288.076598) (xy 173.163228 -288.045473) (xy 173.130593 -288.008636) (xy 173.10429 -287.96704)
			(xy 173.084999 -287.921764) (xy 173.073222 -287.87398) (xy 173.069262 -287.824926) (xy 172.73016 -287.824926)
			(xy 172.729665 -287.849533) (xy 172.72177 -287.89811) (xy 172.706186 -287.944791) (xy 172.683315 -287.988368)
			(xy 172.65375 -288.027712) (xy 172.618257 -288.061804) (xy 172.577754 -288.08976) (xy 172.533292 -288.110858)
			(xy 172.486021 -288.12455) (xy 172.437166 -288.130482) (xy 172.387991 -288.128501) (xy 172.339772 -288.118657)
			(xy 172.293756 -288.101205) (xy 172.251135 -288.076598) (xy 172.213014 -288.045473) (xy 172.180379 -288.008636)
			(xy 172.154076 -287.96704) (xy 172.134785 -287.921764) (xy 172.123008 -287.87398) (xy 172.119048 -287.824926)
			(xy 171.7802 -287.824926) (xy 171.779705 -287.849533) (xy 171.77181 -287.89811) (xy 171.756226 -287.944791)
			(xy 171.733355 -287.988368) (xy 171.70379 -288.027712) (xy 171.668297 -288.061804) (xy 171.627794 -288.08976)
			(xy 171.583332 -288.110858) (xy 171.536061 -288.12455) (xy 171.487206 -288.130482) (xy 171.438031 -288.128501)
			(xy 171.389812 -288.118657) (xy 171.343796 -288.101205) (xy 171.301175 -288.076598) (xy 171.263054 -288.045473)
			(xy 171.230419 -288.008636) (xy 171.204116 -287.96704) (xy 171.184825 -287.921764) (xy 171.173048 -287.87398)
			(xy 171.169088 -287.824926) (xy 170.83024 -287.824926) (xy 170.829745 -287.849533) (xy 170.82185 -287.89811)
			(xy 170.806266 -287.944791) (xy 170.783395 -287.988368) (xy 170.75383 -288.027712) (xy 170.718337 -288.061804)
			(xy 170.677834 -288.08976) (xy 170.633372 -288.110858) (xy 170.586101 -288.12455) (xy 170.537246 -288.130482)
			(xy 170.488071 -288.128501) (xy 170.439852 -288.118657) (xy 170.393836 -288.101205) (xy 170.351215 -288.076598)
			(xy 170.313094 -288.045473) (xy 170.280459 -288.008636) (xy 170.254156 -287.96704) (xy 170.234865 -287.921764)
			(xy 170.223088 -287.87398) (xy 170.219128 -287.824926) (xy 169.88028 -287.824926) (xy 169.879785 -287.849533)
			(xy 169.87189 -287.89811) (xy 169.856306 -287.944791) (xy 169.833435 -287.988368) (xy 169.80387 -288.027712)
			(xy 169.768377 -288.061804) (xy 169.727874 -288.08976) (xy 169.683412 -288.110858) (xy 169.636141 -288.12455)
			(xy 169.587286 -288.130482) (xy 169.538111 -288.128501) (xy 169.489892 -288.118657) (xy 169.443876 -288.101205)
			(xy 169.401255 -288.076598) (xy 169.363134 -288.045473) (xy 169.330499 -288.008636) (xy 169.304196 -287.96704)
			(xy 169.284905 -287.921764) (xy 169.273128 -287.87398) (xy 169.269168 -287.824926) (xy 168.93032 -287.824926)
			(xy 168.929825 -287.849533) (xy 168.92193 -287.89811) (xy 168.906346 -287.944791) (xy 168.883475 -287.988368)
			(xy 168.85391 -288.027712) (xy 168.818417 -288.061804) (xy 168.777914 -288.08976) (xy 168.733452 -288.110858)
			(xy 168.686181 -288.12455) (xy 168.637326 -288.130482) (xy 168.588151 -288.128501) (xy 168.539932 -288.118657)
			(xy 168.493916 -288.101205) (xy 168.451295 -288.076598) (xy 168.413174 -288.045473) (xy 168.380539 -288.008636)
			(xy 168.354236 -287.96704) (xy 168.334945 -287.921764) (xy 168.323168 -287.87398) (xy 168.319208 -287.824926)
			(xy 167.98036 -287.824926) (xy 167.979865 -287.849533) (xy 167.97197 -287.89811) (xy 167.956386 -287.944791)
			(xy 167.933515 -287.988368) (xy 167.90395 -288.027712) (xy 167.868457 -288.061804) (xy 167.827954 -288.08976)
			(xy 167.783492 -288.110858) (xy 167.736221 -288.12455) (xy 167.687366 -288.130482) (xy 167.638191 -288.128501)
			(xy 167.589972 -288.118657) (xy 167.543956 -288.101205) (xy 167.501335 -288.076598) (xy 167.463214 -288.045473)
			(xy 167.430579 -288.008636) (xy 167.404276 -287.96704) (xy 167.384985 -287.921764) (xy 167.373208 -287.87398)
			(xy 167.369248 -287.824926) (xy 167.0304 -287.824926) (xy 167.029905 -287.849533) (xy 167.02201 -287.89811)
			(xy 167.006426 -287.944791) (xy 166.983555 -287.988368) (xy 166.95399 -288.027712) (xy 166.918497 -288.061804)
			(xy 166.877994 -288.08976) (xy 166.833532 -288.110858) (xy 166.786261 -288.12455) (xy 166.737406 -288.130482)
			(xy 166.688231 -288.128501) (xy 166.640012 -288.118657) (xy 166.593996 -288.101205) (xy 166.551375 -288.076598)
			(xy 166.513254 -288.045473) (xy 166.480619 -288.008636) (xy 166.454316 -287.96704) (xy 166.435025 -287.921764)
			(xy 166.423248 -287.87398) (xy 166.419288 -287.824926) (xy 166.080186 -287.824926) (xy 166.079691 -287.849533)
			(xy 166.071796 -287.89811) (xy 166.056212 -287.944791) (xy 166.033341 -287.988368) (xy 166.003776 -288.027712)
			(xy 165.968283 -288.061804) (xy 165.92778 -288.08976) (xy 165.883318 -288.110858) (xy 165.836047 -288.12455)
			(xy 165.787192 -288.130482) (xy 165.738017 -288.128501) (xy 165.689798 -288.118657) (xy 165.643782 -288.101205)
			(xy 165.601161 -288.076598) (xy 165.56304 -288.045473) (xy 165.530405 -288.008636) (xy 165.504102 -287.96704)
			(xy 165.484811 -287.921764) (xy 165.473034 -287.87398) (xy 165.469074 -287.824926) (xy 165.130226 -287.824926)
			(xy 165.129731 -287.849533) (xy 165.121836 -287.89811) (xy 165.106252 -287.944791) (xy 165.083381 -287.988368)
			(xy 165.053816 -288.027712) (xy 165.018323 -288.061804) (xy 164.97782 -288.08976) (xy 164.933358 -288.110858)
			(xy 164.886087 -288.12455) (xy 164.837232 -288.130482) (xy 164.788057 -288.128501) (xy 164.739838 -288.118657)
			(xy 164.693822 -288.101205) (xy 164.651201 -288.076598) (xy 164.61308 -288.045473) (xy 164.580445 -288.008636)
			(xy 164.554142 -287.96704) (xy 164.534851 -287.921764) (xy 164.523074 -287.87398) (xy 164.519114 -287.824926)
			(xy 164.180266 -287.824926) (xy 164.179771 -287.849533) (xy 164.171876 -287.89811) (xy 164.156292 -287.944791)
			(xy 164.133421 -287.988368) (xy 164.103856 -288.027712) (xy 164.068363 -288.061804) (xy 164.02786 -288.08976)
			(xy 163.983398 -288.110858) (xy 163.936127 -288.12455) (xy 163.887272 -288.130482) (xy 163.838097 -288.128501)
			(xy 163.789878 -288.118657) (xy 163.743862 -288.101205) (xy 163.701241 -288.076598) (xy 163.66312 -288.045473)
			(xy 163.630485 -288.008636) (xy 163.604182 -287.96704) (xy 163.584891 -287.921764) (xy 163.573114 -287.87398)
			(xy 163.569154 -287.824926) (xy 163.230306 -287.824926) (xy 163.229811 -287.849533) (xy 163.221916 -287.89811)
			(xy 163.206332 -287.944791) (xy 163.183461 -287.988368) (xy 163.153896 -288.027712) (xy 163.118403 -288.061804)
			(xy 163.0779 -288.08976) (xy 163.033438 -288.110858) (xy 162.986167 -288.12455) (xy 162.937312 -288.130482)
			(xy 162.888137 -288.128501) (xy 162.839918 -288.118657) (xy 162.793902 -288.101205) (xy 162.751281 -288.076598)
			(xy 162.71316 -288.045473) (xy 162.680525 -288.008636) (xy 162.654222 -287.96704) (xy 162.634931 -287.921764)
			(xy 162.623154 -287.87398) (xy 162.619194 -287.824926) (xy 162.280346 -287.824926) (xy 162.279851 -287.849533)
			(xy 162.271956 -287.89811) (xy 162.256372 -287.944791) (xy 162.233501 -287.988368) (xy 162.203936 -288.027712)
			(xy 162.168443 -288.061804) (xy 162.12794 -288.08976) (xy 162.083478 -288.110858) (xy 162.036207 -288.12455)
			(xy 161.987352 -288.130482) (xy 161.938177 -288.128501) (xy 161.889958 -288.118657) (xy 161.843942 -288.101205)
			(xy 161.801321 -288.076598) (xy 161.7632 -288.045473) (xy 161.730565 -288.008636) (xy 161.704262 -287.96704)
			(xy 161.684971 -287.921764) (xy 161.673194 -287.87398) (xy 161.669234 -287.824926) (xy 161.330386 -287.824926)
			(xy 161.329891 -287.849533) (xy 161.321996 -287.89811) (xy 161.306412 -287.944791) (xy 161.283541 -287.988368)
			(xy 161.253976 -288.027712) (xy 161.218483 -288.061804) (xy 161.17798 -288.08976) (xy 161.133518 -288.110858)
			(xy 161.086247 -288.12455) (xy 161.037392 -288.130482) (xy 160.988217 -288.128501) (xy 160.939998 -288.118657)
			(xy 160.893982 -288.101205) (xy 160.851361 -288.076598) (xy 160.81324 -288.045473) (xy 160.780605 -288.008636)
			(xy 160.754302 -287.96704) (xy 160.735011 -287.921764) (xy 160.723234 -287.87398) (xy 160.719274 -287.824926)
			(xy 157.530292 -287.824926) (xy 157.529797 -287.849533) (xy 157.521902 -287.89811) (xy 157.506318 -287.944791)
			(xy 157.483447 -287.988368) (xy 157.453882 -288.027712) (xy 157.418389 -288.061804) (xy 157.377886 -288.08976)
			(xy 157.333424 -288.110858) (xy 157.286153 -288.12455) (xy 157.237298 -288.130482) (xy 157.188123 -288.128501)
			(xy 157.139904 -288.118657) (xy 157.093888 -288.101205) (xy 157.051267 -288.076598) (xy 157.013146 -288.045473)
			(xy 156.980511 -288.008636) (xy 156.954208 -287.96704) (xy 156.934917 -287.921764) (xy 156.92314 -287.87398)
			(xy 156.91918 -287.824926) (xy 154.680412 -287.824926) (xy 154.679917 -287.849533) (xy 154.672022 -287.89811)
			(xy 154.656438 -287.944791) (xy 154.633567 -287.988368) (xy 154.604002 -288.027712) (xy 154.568509 -288.061804)
			(xy 154.528006 -288.08976) (xy 154.483544 -288.110858) (xy 154.436273 -288.12455) (xy 154.387418 -288.130482)
			(xy 154.338243 -288.128501) (xy 154.290024 -288.118657) (xy 154.244008 -288.101205) (xy 154.201387 -288.076598)
			(xy 154.163266 -288.045473) (xy 154.130631 -288.008636) (xy 154.104328 -287.96704) (xy 154.085037 -287.921764)
			(xy 154.07326 -287.87398) (xy 154.0693 -287.824926) (xy 153.730198 -287.824926) (xy 153.729703 -287.849533)
			(xy 153.721808 -287.89811) (xy 153.706224 -287.944791) (xy 153.683353 -287.988368) (xy 153.653788 -288.027712)
			(xy 153.618295 -288.061804) (xy 153.577792 -288.08976) (xy 153.53333 -288.110858) (xy 153.486059 -288.12455)
			(xy 153.437204 -288.130482) (xy 153.388029 -288.128501) (xy 153.33981 -288.118657) (xy 153.293794 -288.101205)
			(xy 153.251173 -288.076598) (xy 153.213052 -288.045473) (xy 153.180417 -288.008636) (xy 153.154114 -287.96704)
			(xy 153.134823 -287.921764) (xy 153.123046 -287.87398) (xy 153.119086 -287.824926) (xy 152.780238 -287.824926)
			(xy 152.779743 -287.849533) (xy 152.771848 -287.89811) (xy 152.756264 -287.944791) (xy 152.733393 -287.988368)
			(xy 152.703828 -288.027712) (xy 152.668335 -288.061804) (xy 152.627832 -288.08976) (xy 152.58337 -288.110858)
			(xy 152.536099 -288.12455) (xy 152.487244 -288.130482) (xy 152.438069 -288.128501) (xy 152.38985 -288.118657)
			(xy 152.343834 -288.101205) (xy 152.301213 -288.076598) (xy 152.263092 -288.045473) (xy 152.230457 -288.008636)
			(xy 152.204154 -287.96704) (xy 152.184863 -287.921764) (xy 152.173086 -287.87398) (xy 152.169126 -287.824926)
			(xy 136.349994 -287.824926) (xy 136.349994 -288.230056) (xy 141.911576 -288.230056) (xy 141.915647 -288.174434)
			(xy 141.927773 -288.119997) (xy 141.947696 -288.067906) (xy 141.974992 -288.019271) (xy 142.009078 -287.975128)
			(xy 142.049227 -287.936419) (xy 142.094585 -287.903968) (xy 142.144185 -287.878467) (xy 142.196969 -287.86046)
			(xy 142.251812 -287.85033) (xy 142.307546 -287.848293) (xy 142.362983 -287.854393) (xy 142.41694 -287.868499)
			(xy 142.468269 -287.890311) (xy 142.515875 -287.919365) (xy 142.558743 -287.95504) (xy 142.59596 -287.996577)
			(xy 142.626733 -288.04309) (xy 142.650405 -288.093587) (xy 142.666473 -288.146994) (xy 142.674593 -288.20217)
			(xy 142.675102 -288.230056) (xy 143.396714 -288.230056) (xy 143.400785 -288.174434) (xy 143.412911 -288.119997)
			(xy 143.432834 -288.067906) (xy 143.46013 -288.019271) (xy 143.494216 -287.975128) (xy 143.534365 -287.936419)
			(xy 143.579723 -287.903968) (xy 143.629323 -287.878467) (xy 143.682107 -287.86046) (xy 143.73695 -287.85033)
			(xy 143.792684 -287.848293) (xy 143.848121 -287.854393) (xy 143.902078 -287.868499) (xy 143.953407 -287.890311)
			(xy 144.001013 -287.919365) (xy 144.043881 -287.95504) (xy 144.081098 -287.996577) (xy 144.111871 -288.04309)
			(xy 144.135543 -288.093587) (xy 144.151611 -288.146994) (xy 144.159731 -288.20217) (xy 144.16024 -288.230056)
			(xy 144.159731 -288.257942) (xy 144.151611 -288.313118) (xy 144.135543 -288.366525) (xy 144.111871 -288.417022)
			(xy 144.081098 -288.463535) (xy 144.043881 -288.505072) (xy 144.001013 -288.540747) (xy 143.953407 -288.569801)
			(xy 143.902078 -288.591613) (xy 143.848121 -288.605719) (xy 143.792684 -288.611819) (xy 143.73695 -288.609782)
			(xy 143.682107 -288.599652) (xy 143.629323 -288.581645) (xy 143.579723 -288.556144) (xy 143.534365 -288.523693)
			(xy 143.494216 -288.484984) (xy 143.46013 -288.440841) (xy 143.432834 -288.392206) (xy 143.412911 -288.340115)
			(xy 143.400785 -288.285678) (xy 143.396714 -288.230056) (xy 142.675102 -288.230056) (xy 142.674593 -288.257942)
			(xy 142.666473 -288.313118) (xy 142.650405 -288.366525) (xy 142.626733 -288.417022) (xy 142.59596 -288.463535)
			(xy 142.558743 -288.505072) (xy 142.515875 -288.540747) (xy 142.468269 -288.569801) (xy 142.41694 -288.591613)
			(xy 142.362983 -288.605719) (xy 142.307546 -288.611819) (xy 142.251812 -288.609782) (xy 142.196969 -288.599652)
			(xy 142.144185 -288.581645) (xy 142.094585 -288.556144) (xy 142.049227 -288.523693) (xy 142.009078 -288.484984)
			(xy 141.974992 -288.440841) (xy 141.947696 -288.392206) (xy 141.927773 -288.340115) (xy 141.915647 -288.285678)
			(xy 141.911576 -288.230056) (xy 136.349994 -288.230056) (xy 136.349994 -288.774886) (xy 152.169126 -288.774886)
			(xy 152.173086 -288.725832) (xy 152.184863 -288.678048) (xy 152.204154 -288.632772) (xy 152.230457 -288.591176)
			(xy 152.263092 -288.554339) (xy 152.301213 -288.523214) (xy 152.343834 -288.498607) (xy 152.38985 -288.481155)
			(xy 152.438069 -288.471311) (xy 152.487244 -288.46933) (xy 152.536099 -288.475262) (xy 152.58337 -288.488954)
			(xy 152.627832 -288.510052) (xy 152.668335 -288.538008) (xy 152.703828 -288.5721) (xy 152.733393 -288.611444)
			(xy 152.756264 -288.655021) (xy 152.771848 -288.701702) (xy 152.779743 -288.750279) (xy 152.780238 -288.774886)
			(xy 153.119086 -288.774886) (xy 153.123046 -288.725832) (xy 153.134823 -288.678048) (xy 153.154114 -288.632772)
			(xy 153.180417 -288.591176) (xy 153.213052 -288.554339) (xy 153.251173 -288.523214) (xy 153.293794 -288.498607)
			(xy 153.33981 -288.481155) (xy 153.388029 -288.471311) (xy 153.437204 -288.46933) (xy 153.486059 -288.475262)
			(xy 153.53333 -288.488954) (xy 153.577792 -288.510052) (xy 153.618295 -288.538008) (xy 153.653788 -288.5721)
			(xy 153.683353 -288.611444) (xy 153.706224 -288.655021) (xy 153.721808 -288.701702) (xy 153.729703 -288.750279)
			(xy 153.730198 -288.774886) (xy 154.0693 -288.774886) (xy 154.07326 -288.725832) (xy 154.085037 -288.678048)
			(xy 154.104328 -288.632772) (xy 154.130631 -288.591176) (xy 154.163266 -288.554339) (xy 154.201387 -288.523214)
			(xy 154.244008 -288.498607) (xy 154.290024 -288.481155) (xy 154.338243 -288.471311) (xy 154.387418 -288.46933)
			(xy 154.436273 -288.475262) (xy 154.483544 -288.488954) (xy 154.528006 -288.510052) (xy 154.568509 -288.538008)
			(xy 154.604002 -288.5721) (xy 154.633567 -288.611444) (xy 154.656438 -288.655021) (xy 154.672022 -288.701702)
			(xy 154.679917 -288.750279) (xy 154.680412 -288.774886) (xy 158.8191 -288.774886) (xy 158.82306 -288.725832)
			(xy 158.834837 -288.678048) (xy 158.854128 -288.632772) (xy 158.880431 -288.591176) (xy 158.913066 -288.554339)
			(xy 158.951187 -288.523214) (xy 158.993808 -288.498607) (xy 159.039824 -288.481155) (xy 159.088043 -288.471311)
			(xy 159.137218 -288.46933) (xy 159.186073 -288.475262) (xy 159.233344 -288.488954) (xy 159.277806 -288.510052)
			(xy 159.318309 -288.538008) (xy 159.353802 -288.5721) (xy 159.383367 -288.611444) (xy 159.406238 -288.655021)
			(xy 159.421822 -288.701702) (xy 159.429717 -288.750279) (xy 159.430212 -288.774886) (xy 159.76906 -288.774886)
			(xy 159.77302 -288.725832) (xy 159.784797 -288.678048) (xy 159.804088 -288.632772) (xy 159.830391 -288.591176)
			(xy 159.863026 -288.554339) (xy 159.901147 -288.523214) (xy 159.943768 -288.498607) (xy 159.989784 -288.481155)
			(xy 160.038003 -288.471311) (xy 160.087178 -288.46933) (xy 160.136033 -288.475262) (xy 160.183304 -288.488954)
			(xy 160.227766 -288.510052) (xy 160.268269 -288.538008) (xy 160.303762 -288.5721) (xy 160.333327 -288.611444)
			(xy 160.356198 -288.655021) (xy 160.371782 -288.701702) (xy 160.379677 -288.750279) (xy 160.380172 -288.774886)
			(xy 160.719274 -288.774886) (xy 160.723234 -288.725832) (xy 160.735011 -288.678048) (xy 160.754302 -288.632772)
			(xy 160.780605 -288.591176) (xy 160.81324 -288.554339) (xy 160.851361 -288.523214) (xy 160.893982 -288.498607)
			(xy 160.939998 -288.481155) (xy 160.988217 -288.471311) (xy 161.037392 -288.46933) (xy 161.086247 -288.475262)
			(xy 161.133518 -288.488954) (xy 161.17798 -288.510052) (xy 161.218483 -288.538008) (xy 161.253976 -288.5721)
			(xy 161.283541 -288.611444) (xy 161.306412 -288.655021) (xy 161.321996 -288.701702) (xy 161.329891 -288.750279)
			(xy 161.330386 -288.774886) (xy 161.669234 -288.774886) (xy 161.673194 -288.725832) (xy 161.684971 -288.678048)
			(xy 161.704262 -288.632772) (xy 161.730565 -288.591176) (xy 161.7632 -288.554339) (xy 161.801321 -288.523214)
			(xy 161.843942 -288.498607) (xy 161.889958 -288.481155) (xy 161.938177 -288.471311) (xy 161.987352 -288.46933)
			(xy 162.036207 -288.475262) (xy 162.083478 -288.488954) (xy 162.12794 -288.510052) (xy 162.168443 -288.538008)
			(xy 162.203936 -288.5721) (xy 162.233501 -288.611444) (xy 162.256372 -288.655021) (xy 162.271956 -288.701702)
			(xy 162.279851 -288.750279) (xy 162.280346 -288.774886) (xy 162.619194 -288.774886) (xy 162.623154 -288.725832)
			(xy 162.634931 -288.678048) (xy 162.654222 -288.632772) (xy 162.680525 -288.591176) (xy 162.71316 -288.554339)
			(xy 162.751281 -288.523214) (xy 162.793902 -288.498607) (xy 162.839918 -288.481155) (xy 162.888137 -288.471311)
			(xy 162.937312 -288.46933) (xy 162.986167 -288.475262) (xy 163.033438 -288.488954) (xy 163.0779 -288.510052)
			(xy 163.118403 -288.538008) (xy 163.153896 -288.5721) (xy 163.183461 -288.611444) (xy 163.206332 -288.655021)
			(xy 163.221916 -288.701702) (xy 163.229811 -288.750279) (xy 163.230306 -288.774886) (xy 163.569154 -288.774886)
			(xy 163.573114 -288.725832) (xy 163.584891 -288.678048) (xy 163.604182 -288.632772) (xy 163.630485 -288.591176)
			(xy 163.66312 -288.554339) (xy 163.701241 -288.523214) (xy 163.743862 -288.498607) (xy 163.789878 -288.481155)
			(xy 163.838097 -288.471311) (xy 163.887272 -288.46933) (xy 163.936127 -288.475262) (xy 163.983398 -288.488954)
			(xy 164.02786 -288.510052) (xy 164.068363 -288.538008) (xy 164.103856 -288.5721) (xy 164.133421 -288.611444)
			(xy 164.156292 -288.655021) (xy 164.171876 -288.701702) (xy 164.179771 -288.750279) (xy 164.180266 -288.774886)
			(xy 164.519114 -288.774886) (xy 164.523074 -288.725832) (xy 164.534851 -288.678048) (xy 164.554142 -288.632772)
			(xy 164.580445 -288.591176) (xy 164.61308 -288.554339) (xy 164.651201 -288.523214) (xy 164.693822 -288.498607)
			(xy 164.739838 -288.481155) (xy 164.788057 -288.471311) (xy 164.837232 -288.46933) (xy 164.886087 -288.475262)
			(xy 164.933358 -288.488954) (xy 164.97782 -288.510052) (xy 165.018323 -288.538008) (xy 165.053816 -288.5721)
			(xy 165.083381 -288.611444) (xy 165.106252 -288.655021) (xy 165.121836 -288.701702) (xy 165.129731 -288.750279)
			(xy 165.130226 -288.774886) (xy 165.469074 -288.774886) (xy 165.473034 -288.725832) (xy 165.484811 -288.678048)
			(xy 165.504102 -288.632772) (xy 165.530405 -288.591176) (xy 165.56304 -288.554339) (xy 165.601161 -288.523214)
			(xy 165.643782 -288.498607) (xy 165.689798 -288.481155) (xy 165.738017 -288.471311) (xy 165.787192 -288.46933)
			(xy 165.836047 -288.475262) (xy 165.883318 -288.488954) (xy 165.92778 -288.510052) (xy 165.968283 -288.538008)
			(xy 166.003776 -288.5721) (xy 166.033341 -288.611444) (xy 166.056212 -288.655021) (xy 166.071796 -288.701702)
			(xy 166.079691 -288.750279) (xy 166.080186 -288.774886) (xy 166.419288 -288.774886) (xy 166.423248 -288.725832)
			(xy 166.435025 -288.678048) (xy 166.454316 -288.632772) (xy 166.480619 -288.591176) (xy 166.513254 -288.554339)
			(xy 166.551375 -288.523214) (xy 166.593996 -288.498607) (xy 166.640012 -288.481155) (xy 166.688231 -288.471311)
			(xy 166.737406 -288.46933) (xy 166.786261 -288.475262) (xy 166.833532 -288.488954) (xy 166.877994 -288.510052)
			(xy 166.918497 -288.538008) (xy 166.95399 -288.5721) (xy 166.983555 -288.611444) (xy 167.006426 -288.655021)
			(xy 167.02201 -288.701702) (xy 167.029905 -288.750279) (xy 167.0304 -288.774886) (xy 167.369248 -288.774886)
			(xy 167.373208 -288.725832) (xy 167.384985 -288.678048) (xy 167.404276 -288.632772) (xy 167.430579 -288.591176)
			(xy 167.463214 -288.554339) (xy 167.501335 -288.523214) (xy 167.543956 -288.498607) (xy 167.589972 -288.481155)
			(xy 167.638191 -288.471311) (xy 167.687366 -288.46933) (xy 167.736221 -288.475262) (xy 167.783492 -288.488954)
			(xy 167.827954 -288.510052) (xy 167.868457 -288.538008) (xy 167.90395 -288.5721) (xy 167.933515 -288.611444)
			(xy 167.956386 -288.655021) (xy 167.97197 -288.701702) (xy 167.979865 -288.750279) (xy 167.98036 -288.774886)
			(xy 168.319208 -288.774886) (xy 168.323168 -288.725832) (xy 168.334945 -288.678048) (xy 168.354236 -288.632772)
			(xy 168.380539 -288.591176) (xy 168.413174 -288.554339) (xy 168.451295 -288.523214) (xy 168.493916 -288.498607)
			(xy 168.539932 -288.481155) (xy 168.588151 -288.471311) (xy 168.637326 -288.46933) (xy 168.686181 -288.475262)
			(xy 168.733452 -288.488954) (xy 168.777914 -288.510052) (xy 168.818417 -288.538008) (xy 168.85391 -288.5721)
			(xy 168.883475 -288.611444) (xy 168.906346 -288.655021) (xy 168.92193 -288.701702) (xy 168.929825 -288.750279)
			(xy 168.93032 -288.774886) (xy 169.269168 -288.774886) (xy 169.273128 -288.725832) (xy 169.284905 -288.678048)
			(xy 169.304196 -288.632772) (xy 169.330499 -288.591176) (xy 169.363134 -288.554339) (xy 169.401255 -288.523214)
			(xy 169.443876 -288.498607) (xy 169.489892 -288.481155) (xy 169.538111 -288.471311) (xy 169.587286 -288.46933)
			(xy 169.636141 -288.475262) (xy 169.683412 -288.488954) (xy 169.727874 -288.510052) (xy 169.768377 -288.538008)
			(xy 169.80387 -288.5721) (xy 169.833435 -288.611444) (xy 169.856306 -288.655021) (xy 169.87189 -288.701702)
			(xy 169.879785 -288.750279) (xy 169.88028 -288.774886) (xy 170.219128 -288.774886) (xy 170.223088 -288.725832)
			(xy 170.234865 -288.678048) (xy 170.254156 -288.632772) (xy 170.280459 -288.591176) (xy 170.313094 -288.554339)
			(xy 170.351215 -288.523214) (xy 170.393836 -288.498607) (xy 170.439852 -288.481155) (xy 170.488071 -288.471311)
			(xy 170.537246 -288.46933) (xy 170.586101 -288.475262) (xy 170.633372 -288.488954) (xy 170.677834 -288.510052)
			(xy 170.718337 -288.538008) (xy 170.75383 -288.5721) (xy 170.783395 -288.611444) (xy 170.806266 -288.655021)
			(xy 170.82185 -288.701702) (xy 170.829745 -288.750279) (xy 170.83024 -288.774886) (xy 171.169088 -288.774886)
			(xy 171.173048 -288.725832) (xy 171.184825 -288.678048) (xy 171.204116 -288.632772) (xy 171.230419 -288.591176)
			(xy 171.263054 -288.554339) (xy 171.301175 -288.523214) (xy 171.343796 -288.498607) (xy 171.389812 -288.481155)
			(xy 171.438031 -288.471311) (xy 171.487206 -288.46933) (xy 171.536061 -288.475262) (xy 171.583332 -288.488954)
			(xy 171.627794 -288.510052) (xy 171.668297 -288.538008) (xy 171.70379 -288.5721) (xy 171.733355 -288.611444)
			(xy 171.756226 -288.655021) (xy 171.77181 -288.701702) (xy 171.779705 -288.750279) (xy 171.7802 -288.774886)
			(xy 172.119048 -288.774886) (xy 172.123008 -288.725832) (xy 172.134785 -288.678048) (xy 172.154076 -288.632772)
			(xy 172.180379 -288.591176) (xy 172.213014 -288.554339) (xy 172.251135 -288.523214) (xy 172.293756 -288.498607)
			(xy 172.339772 -288.481155) (xy 172.387991 -288.471311) (xy 172.437166 -288.46933) (xy 172.486021 -288.475262)
			(xy 172.533292 -288.488954) (xy 172.577754 -288.510052) (xy 172.618257 -288.538008) (xy 172.65375 -288.5721)
			(xy 172.683315 -288.611444) (xy 172.706186 -288.655021) (xy 172.72177 -288.701702) (xy 172.729665 -288.750279)
			(xy 172.73016 -288.774886) (xy 173.069262 -288.774886) (xy 173.073222 -288.725832) (xy 173.084999 -288.678048)
			(xy 173.10429 -288.632772) (xy 173.130593 -288.591176) (xy 173.163228 -288.554339) (xy 173.201349 -288.523214)
			(xy 173.24397 -288.498607) (xy 173.289986 -288.481155) (xy 173.338205 -288.471311) (xy 173.38738 -288.46933)
			(xy 173.436235 -288.475262) (xy 173.483506 -288.488954) (xy 173.527968 -288.510052) (xy 173.568471 -288.538008)
			(xy 173.603964 -288.5721) (xy 173.633529 -288.611444) (xy 173.6564 -288.655021) (xy 173.671984 -288.701702)
			(xy 173.679879 -288.750279) (xy 173.680374 -288.774886) (xy 174.019222 -288.774886) (xy 174.023182 -288.725832)
			(xy 174.034959 -288.678048) (xy 174.05425 -288.632772) (xy 174.080553 -288.591176) (xy 174.113188 -288.554339)
			(xy 174.151309 -288.523214) (xy 174.19393 -288.498607) (xy 174.239946 -288.481155) (xy 174.288165 -288.471311)
			(xy 174.33734 -288.46933) (xy 174.386195 -288.475262) (xy 174.433466 -288.488954) (xy 174.477928 -288.510052)
			(xy 174.518431 -288.538008) (xy 174.553924 -288.5721) (xy 174.583489 -288.611444) (xy 174.60636 -288.655021)
			(xy 174.621944 -288.701702) (xy 174.629839 -288.750279) (xy 174.630334 -288.774886) (xy 175.919142 -288.774886)
			(xy 175.923102 -288.725832) (xy 175.934879 -288.678048) (xy 175.95417 -288.632772) (xy 175.980473 -288.591176)
			(xy 176.013108 -288.554339) (xy 176.051229 -288.523214) (xy 176.09385 -288.498607) (xy 176.139866 -288.481155)
			(xy 176.188085 -288.471311) (xy 176.23726 -288.46933) (xy 176.286115 -288.475262) (xy 176.333386 -288.488954)
			(xy 176.377848 -288.510052) (xy 176.418351 -288.538008) (xy 176.453844 -288.5721) (xy 176.483409 -288.611444)
			(xy 176.50628 -288.655021) (xy 176.521864 -288.701702) (xy 176.529759 -288.750279) (xy 176.530254 -288.774886)
			(xy 176.869102 -288.774886) (xy 176.873062 -288.725832) (xy 176.884839 -288.678048) (xy 176.90413 -288.632772)
			(xy 176.930433 -288.591176) (xy 176.963068 -288.554339) (xy 177.001189 -288.523214) (xy 177.04381 -288.498607)
			(xy 177.089826 -288.481155) (xy 177.138045 -288.471311) (xy 177.18722 -288.46933) (xy 177.236075 -288.475262)
			(xy 177.283346 -288.488954) (xy 177.327808 -288.510052) (xy 177.368311 -288.538008) (xy 177.403804 -288.5721)
			(xy 177.433369 -288.611444) (xy 177.45624 -288.655021) (xy 177.471824 -288.701702) (xy 177.479719 -288.750279)
			(xy 177.480214 -288.774886) (xy 177.819062 -288.774886) (xy 177.823022 -288.725832) (xy 177.834799 -288.678048)
			(xy 177.85409 -288.632772) (xy 177.880393 -288.591176) (xy 177.913028 -288.554339) (xy 177.951149 -288.523214)
			(xy 177.99377 -288.498607) (xy 178.039786 -288.481155) (xy 178.088005 -288.471311) (xy 178.13718 -288.46933)
			(xy 178.186035 -288.475262) (xy 178.233306 -288.488954) (xy 178.277768 -288.510052) (xy 178.318271 -288.538008)
			(xy 178.353764 -288.5721) (xy 178.383329 -288.611444) (xy 178.4062 -288.655021) (xy 178.421784 -288.701702)
			(xy 178.429679 -288.750279) (xy 178.430174 -288.774886) (xy 178.769276 -288.774886) (xy 178.773236 -288.725832)
			(xy 178.785013 -288.678048) (xy 178.804304 -288.632772) (xy 178.830607 -288.591176) (xy 178.863242 -288.554339)
			(xy 178.901363 -288.523214) (xy 178.943984 -288.498607) (xy 178.99 -288.481155) (xy 179.038219 -288.471311)
			(xy 179.087394 -288.46933) (xy 179.136249 -288.475262) (xy 179.18352 -288.488954) (xy 179.227982 -288.510052)
			(xy 179.268485 -288.538008) (xy 179.303978 -288.5721) (xy 179.333543 -288.611444) (xy 179.356414 -288.655021)
			(xy 179.371998 -288.701702) (xy 179.379893 -288.750279) (xy 179.380388 -288.774886) (xy 179.719236 -288.774886)
			(xy 179.723196 -288.725832) (xy 179.734973 -288.678048) (xy 179.754264 -288.632772) (xy 179.780567 -288.591176)
			(xy 179.813202 -288.554339) (xy 179.851323 -288.523214) (xy 179.893944 -288.498607) (xy 179.93996 -288.481155)
			(xy 179.988179 -288.471311) (xy 180.037354 -288.46933) (xy 180.086209 -288.475262) (xy 180.13348 -288.488954)
			(xy 180.177942 -288.510052) (xy 180.218445 -288.538008) (xy 180.253938 -288.5721) (xy 180.283503 -288.611444)
			(xy 180.306374 -288.655021) (xy 180.321958 -288.701702) (xy 180.329853 -288.750279) (xy 180.330348 -288.774886)
			(xy 180.669196 -288.774886) (xy 180.673156 -288.725832) (xy 180.684933 -288.678048) (xy 180.704224 -288.632772)
			(xy 180.730527 -288.591176) (xy 180.763162 -288.554339) (xy 180.801283 -288.523214) (xy 180.843904 -288.498607)
			(xy 180.88992 -288.481155) (xy 180.938139 -288.471311) (xy 180.987314 -288.46933) (xy 181.036169 -288.475262)
			(xy 181.08344 -288.488954) (xy 181.127902 -288.510052) (xy 181.168405 -288.538008) (xy 181.203898 -288.5721)
			(xy 181.233463 -288.611444) (xy 181.256334 -288.655021) (xy 181.271918 -288.701702) (xy 181.279813 -288.750279)
			(xy 181.280308 -288.774886) (xy 181.619156 -288.774886) (xy 181.623116 -288.725832) (xy 181.634893 -288.678048)
			(xy 181.654184 -288.632772) (xy 181.680487 -288.591176) (xy 181.713122 -288.554339) (xy 181.751243 -288.523214)
			(xy 181.793864 -288.498607) (xy 181.83988 -288.481155) (xy 181.888099 -288.471311) (xy 181.937274 -288.46933)
			(xy 181.986129 -288.475262) (xy 182.0334 -288.488954) (xy 182.077862 -288.510052) (xy 182.118365 -288.538008)
			(xy 182.153858 -288.5721) (xy 182.183423 -288.611444) (xy 182.206294 -288.655021) (xy 182.221878 -288.701702)
			(xy 182.229773 -288.750279) (xy 182.230268 -288.774886) (xy 182.569116 -288.774886) (xy 182.573076 -288.725832)
			(xy 182.584853 -288.678048) (xy 182.604144 -288.632772) (xy 182.630447 -288.591176) (xy 182.663082 -288.554339)
			(xy 182.701203 -288.523214) (xy 182.743824 -288.498607) (xy 182.78984 -288.481155) (xy 182.838059 -288.471311)
			(xy 182.887234 -288.46933) (xy 182.936089 -288.475262) (xy 182.98336 -288.488954) (xy 183.027822 -288.510052)
			(xy 183.068325 -288.538008) (xy 183.103818 -288.5721) (xy 183.133383 -288.611444) (xy 183.156254 -288.655021)
			(xy 183.171838 -288.701702) (xy 183.179733 -288.750279) (xy 183.180228 -288.774886) (xy 183.519076 -288.774886)
			(xy 183.523036 -288.725832) (xy 183.534813 -288.678048) (xy 183.554104 -288.632772) (xy 183.580407 -288.591176)
			(xy 183.613042 -288.554339) (xy 183.651163 -288.523214) (xy 183.693784 -288.498607) (xy 183.7398 -288.481155)
			(xy 183.788019 -288.471311) (xy 183.837194 -288.46933) (xy 183.886049 -288.475262) (xy 183.93332 -288.488954)
			(xy 183.977782 -288.510052) (xy 184.018285 -288.538008) (xy 184.053778 -288.5721) (xy 184.083343 -288.611444)
			(xy 184.106214 -288.655021) (xy 184.121798 -288.701702) (xy 184.129693 -288.750279) (xy 184.130188 -288.774886)
			(xy 184.469036 -288.774886) (xy 184.472996 -288.725832) (xy 184.484773 -288.678048) (xy 184.504064 -288.632772)
			(xy 184.530367 -288.591176) (xy 184.563002 -288.554339) (xy 184.601123 -288.523214) (xy 184.643744 -288.498607)
			(xy 184.68976 -288.481155) (xy 184.737979 -288.471311) (xy 184.787154 -288.46933) (xy 184.836009 -288.475262)
			(xy 184.88328 -288.488954) (xy 184.927742 -288.510052) (xy 184.968245 -288.538008) (xy 185.003738 -288.5721)
			(xy 185.033303 -288.611444) (xy 185.056174 -288.655021) (xy 185.071758 -288.701702) (xy 185.079653 -288.750279)
			(xy 185.080148 -288.774886) (xy 185.079653 -288.799493) (xy 185.071758 -288.84807) (xy 185.056174 -288.894751)
			(xy 185.033303 -288.938328) (xy 185.003738 -288.977672) (xy 184.968245 -289.011764) (xy 184.927742 -289.03972)
			(xy 184.88328 -289.060818) (xy 184.836009 -289.07451) (xy 184.787154 -289.080442) (xy 184.737979 -289.078461)
			(xy 184.68976 -289.068617) (xy 184.643744 -289.051165) (xy 184.601123 -289.026558) (xy 184.563002 -288.995433)
			(xy 184.530367 -288.958596) (xy 184.504064 -288.917) (xy 184.484773 -288.871724) (xy 184.472996 -288.82394)
			(xy 184.469036 -288.774886) (xy 184.130188 -288.774886) (xy 184.129693 -288.799493) (xy 184.121798 -288.84807)
			(xy 184.106214 -288.894751) (xy 184.083343 -288.938328) (xy 184.053778 -288.977672) (xy 184.018285 -289.011764)
			(xy 183.977782 -289.03972) (xy 183.93332 -289.060818) (xy 183.886049 -289.07451) (xy 183.837194 -289.080442)
			(xy 183.788019 -289.078461) (xy 183.7398 -289.068617) (xy 183.693784 -289.051165) (xy 183.651163 -289.026558)
			(xy 183.613042 -288.995433) (xy 183.580407 -288.958596) (xy 183.554104 -288.917) (xy 183.534813 -288.871724)
			(xy 183.523036 -288.82394) (xy 183.519076 -288.774886) (xy 183.180228 -288.774886) (xy 183.179733 -288.799493)
			(xy 183.171838 -288.84807) (xy 183.156254 -288.894751) (xy 183.133383 -288.938328) (xy 183.103818 -288.977672)
			(xy 183.068325 -289.011764) (xy 183.027822 -289.03972) (xy 182.98336 -289.060818) (xy 182.936089 -289.07451)
			(xy 182.887234 -289.080442) (xy 182.838059 -289.078461) (xy 182.78984 -289.068617) (xy 182.743824 -289.051165)
			(xy 182.701203 -289.026558) (xy 182.663082 -288.995433) (xy 182.630447 -288.958596) (xy 182.604144 -288.917)
			(xy 182.584853 -288.871724) (xy 182.573076 -288.82394) (xy 182.569116 -288.774886) (xy 182.230268 -288.774886)
			(xy 182.229773 -288.799493) (xy 182.221878 -288.84807) (xy 182.206294 -288.894751) (xy 182.183423 -288.938328)
			(xy 182.153858 -288.977672) (xy 182.118365 -289.011764) (xy 182.077862 -289.03972) (xy 182.0334 -289.060818)
			(xy 181.986129 -289.07451) (xy 181.937274 -289.080442) (xy 181.888099 -289.078461) (xy 181.83988 -289.068617)
			(xy 181.793864 -289.051165) (xy 181.751243 -289.026558) (xy 181.713122 -288.995433) (xy 181.680487 -288.958596)
			(xy 181.654184 -288.917) (xy 181.634893 -288.871724) (xy 181.623116 -288.82394) (xy 181.619156 -288.774886)
			(xy 181.280308 -288.774886) (xy 181.279813 -288.799493) (xy 181.271918 -288.84807) (xy 181.256334 -288.894751)
			(xy 181.233463 -288.938328) (xy 181.203898 -288.977672) (xy 181.168405 -289.011764) (xy 181.127902 -289.03972)
			(xy 181.08344 -289.060818) (xy 181.036169 -289.07451) (xy 180.987314 -289.080442) (xy 180.938139 -289.078461)
			(xy 180.88992 -289.068617) (xy 180.843904 -289.051165) (xy 180.801283 -289.026558) (xy 180.763162 -288.995433)
			(xy 180.730527 -288.958596) (xy 180.704224 -288.917) (xy 180.684933 -288.871724) (xy 180.673156 -288.82394)
			(xy 180.669196 -288.774886) (xy 180.330348 -288.774886) (xy 180.329853 -288.799493) (xy 180.321958 -288.84807)
			(xy 180.306374 -288.894751) (xy 180.283503 -288.938328) (xy 180.253938 -288.977672) (xy 180.218445 -289.011764)
			(xy 180.177942 -289.03972) (xy 180.13348 -289.060818) (xy 180.086209 -289.07451) (xy 180.037354 -289.080442)
			(xy 179.988179 -289.078461) (xy 179.93996 -289.068617) (xy 179.893944 -289.051165) (xy 179.851323 -289.026558)
			(xy 179.813202 -288.995433) (xy 179.780567 -288.958596) (xy 179.754264 -288.917) (xy 179.734973 -288.871724)
			(xy 179.723196 -288.82394) (xy 179.719236 -288.774886) (xy 179.380388 -288.774886) (xy 179.379893 -288.799493)
			(xy 179.371998 -288.84807) (xy 179.356414 -288.894751) (xy 179.333543 -288.938328) (xy 179.303978 -288.977672)
			(xy 179.268485 -289.011764) (xy 179.227982 -289.03972) (xy 179.18352 -289.060818) (xy 179.136249 -289.07451)
			(xy 179.087394 -289.080442) (xy 179.038219 -289.078461) (xy 178.99 -289.068617) (xy 178.943984 -289.051165)
			(xy 178.901363 -289.026558) (xy 178.863242 -288.995433) (xy 178.830607 -288.958596) (xy 178.804304 -288.917)
			(xy 178.785013 -288.871724) (xy 178.773236 -288.82394) (xy 178.769276 -288.774886) (xy 178.430174 -288.774886)
			(xy 178.429679 -288.799493) (xy 178.421784 -288.84807) (xy 178.4062 -288.894751) (xy 178.383329 -288.938328)
			(xy 178.353764 -288.977672) (xy 178.318271 -289.011764) (xy 178.277768 -289.03972) (xy 178.233306 -289.060818)
			(xy 178.186035 -289.07451) (xy 178.13718 -289.080442) (xy 178.088005 -289.078461) (xy 178.039786 -289.068617)
			(xy 177.99377 -289.051165) (xy 177.951149 -289.026558) (xy 177.913028 -288.995433) (xy 177.880393 -288.958596)
			(xy 177.85409 -288.917) (xy 177.834799 -288.871724) (xy 177.823022 -288.82394) (xy 177.819062 -288.774886)
			(xy 177.480214 -288.774886) (xy 177.479719 -288.799493) (xy 177.471824 -288.84807) (xy 177.45624 -288.894751)
			(xy 177.433369 -288.938328) (xy 177.403804 -288.977672) (xy 177.368311 -289.011764) (xy 177.327808 -289.03972)
			(xy 177.283346 -289.060818) (xy 177.236075 -289.07451) (xy 177.18722 -289.080442) (xy 177.138045 -289.078461)
			(xy 177.089826 -289.068617) (xy 177.04381 -289.051165) (xy 177.001189 -289.026558) (xy 176.963068 -288.995433)
			(xy 176.930433 -288.958596) (xy 176.90413 -288.917) (xy 176.884839 -288.871724) (xy 176.873062 -288.82394)
			(xy 176.869102 -288.774886) (xy 176.530254 -288.774886) (xy 176.529759 -288.799493) (xy 176.521864 -288.84807)
			(xy 176.50628 -288.894751) (xy 176.483409 -288.938328) (xy 176.453844 -288.977672) (xy 176.418351 -289.011764)
			(xy 176.377848 -289.03972) (xy 176.333386 -289.060818) (xy 176.286115 -289.07451) (xy 176.23726 -289.080442)
			(xy 176.188085 -289.078461) (xy 176.139866 -289.068617) (xy 176.09385 -289.051165) (xy 176.051229 -289.026558)
			(xy 176.013108 -288.995433) (xy 175.980473 -288.958596) (xy 175.95417 -288.917) (xy 175.934879 -288.871724)
			(xy 175.923102 -288.82394) (xy 175.919142 -288.774886) (xy 174.630334 -288.774886) (xy 174.629839 -288.799493)
			(xy 174.621944 -288.84807) (xy 174.60636 -288.894751) (xy 174.583489 -288.938328) (xy 174.553924 -288.977672)
			(xy 174.518431 -289.011764) (xy 174.477928 -289.03972) (xy 174.433466 -289.060818) (xy 174.386195 -289.07451)
			(xy 174.33734 -289.080442) (xy 174.288165 -289.078461) (xy 174.239946 -289.068617) (xy 174.19393 -289.051165)
			(xy 174.151309 -289.026558) (xy 174.113188 -288.995433) (xy 174.080553 -288.958596) (xy 174.05425 -288.917)
			(xy 174.034959 -288.871724) (xy 174.023182 -288.82394) (xy 174.019222 -288.774886) (xy 173.680374 -288.774886)
			(xy 173.679879 -288.799493) (xy 173.671984 -288.84807) (xy 173.6564 -288.894751) (xy 173.633529 -288.938328)
			(xy 173.603964 -288.977672) (xy 173.568471 -289.011764) (xy 173.527968 -289.03972) (xy 173.483506 -289.060818)
			(xy 173.436235 -289.07451) (xy 173.38738 -289.080442) (xy 173.338205 -289.078461) (xy 173.289986 -289.068617)
			(xy 173.24397 -289.051165) (xy 173.201349 -289.026558) (xy 173.163228 -288.995433) (xy 173.130593 -288.958596)
			(xy 173.10429 -288.917) (xy 173.084999 -288.871724) (xy 173.073222 -288.82394) (xy 173.069262 -288.774886)
			(xy 172.73016 -288.774886) (xy 172.729665 -288.799493) (xy 172.72177 -288.84807) (xy 172.706186 -288.894751)
			(xy 172.683315 -288.938328) (xy 172.65375 -288.977672) (xy 172.618257 -289.011764) (xy 172.577754 -289.03972)
			(xy 172.533292 -289.060818) (xy 172.486021 -289.07451) (xy 172.437166 -289.080442) (xy 172.387991 -289.078461)
			(xy 172.339772 -289.068617) (xy 172.293756 -289.051165) (xy 172.251135 -289.026558) (xy 172.213014 -288.995433)
			(xy 172.180379 -288.958596) (xy 172.154076 -288.917) (xy 172.134785 -288.871724) (xy 172.123008 -288.82394)
			(xy 172.119048 -288.774886) (xy 171.7802 -288.774886) (xy 171.779705 -288.799493) (xy 171.77181 -288.84807)
			(xy 171.756226 -288.894751) (xy 171.733355 -288.938328) (xy 171.70379 -288.977672) (xy 171.668297 -289.011764)
			(xy 171.627794 -289.03972) (xy 171.583332 -289.060818) (xy 171.536061 -289.07451) (xy 171.487206 -289.080442)
			(xy 171.438031 -289.078461) (xy 171.389812 -289.068617) (xy 171.343796 -289.051165) (xy 171.301175 -289.026558)
			(xy 171.263054 -288.995433) (xy 171.230419 -288.958596) (xy 171.204116 -288.917) (xy 171.184825 -288.871724)
			(xy 171.173048 -288.82394) (xy 171.169088 -288.774886) (xy 170.83024 -288.774886) (xy 170.829745 -288.799493)
			(xy 170.82185 -288.84807) (xy 170.806266 -288.894751) (xy 170.783395 -288.938328) (xy 170.75383 -288.977672)
			(xy 170.718337 -289.011764) (xy 170.677834 -289.03972) (xy 170.633372 -289.060818) (xy 170.586101 -289.07451)
			(xy 170.537246 -289.080442) (xy 170.488071 -289.078461) (xy 170.439852 -289.068617) (xy 170.393836 -289.051165)
			(xy 170.351215 -289.026558) (xy 170.313094 -288.995433) (xy 170.280459 -288.958596) (xy 170.254156 -288.917)
			(xy 170.234865 -288.871724) (xy 170.223088 -288.82394) (xy 170.219128 -288.774886) (xy 169.88028 -288.774886)
			(xy 169.879785 -288.799493) (xy 169.87189 -288.84807) (xy 169.856306 -288.894751) (xy 169.833435 -288.938328)
			(xy 169.80387 -288.977672) (xy 169.768377 -289.011764) (xy 169.727874 -289.03972) (xy 169.683412 -289.060818)
			(xy 169.636141 -289.07451) (xy 169.587286 -289.080442) (xy 169.538111 -289.078461) (xy 169.489892 -289.068617)
			(xy 169.443876 -289.051165) (xy 169.401255 -289.026558) (xy 169.363134 -288.995433) (xy 169.330499 -288.958596)
			(xy 169.304196 -288.917) (xy 169.284905 -288.871724) (xy 169.273128 -288.82394) (xy 169.269168 -288.774886)
			(xy 168.93032 -288.774886) (xy 168.929825 -288.799493) (xy 168.92193 -288.84807) (xy 168.906346 -288.894751)
			(xy 168.883475 -288.938328) (xy 168.85391 -288.977672) (xy 168.818417 -289.011764) (xy 168.777914 -289.03972)
			(xy 168.733452 -289.060818) (xy 168.686181 -289.07451) (xy 168.637326 -289.080442) (xy 168.588151 -289.078461)
			(xy 168.539932 -289.068617) (xy 168.493916 -289.051165) (xy 168.451295 -289.026558) (xy 168.413174 -288.995433)
			(xy 168.380539 -288.958596) (xy 168.354236 -288.917) (xy 168.334945 -288.871724) (xy 168.323168 -288.82394)
			(xy 168.319208 -288.774886) (xy 167.98036 -288.774886) (xy 167.979865 -288.799493) (xy 167.97197 -288.84807)
			(xy 167.956386 -288.894751) (xy 167.933515 -288.938328) (xy 167.90395 -288.977672) (xy 167.868457 -289.011764)
			(xy 167.827954 -289.03972) (xy 167.783492 -289.060818) (xy 167.736221 -289.07451) (xy 167.687366 -289.080442)
			(xy 167.638191 -289.078461) (xy 167.589972 -289.068617) (xy 167.543956 -289.051165) (xy 167.501335 -289.026558)
			(xy 167.463214 -288.995433) (xy 167.430579 -288.958596) (xy 167.404276 -288.917) (xy 167.384985 -288.871724)
			(xy 167.373208 -288.82394) (xy 167.369248 -288.774886) (xy 167.0304 -288.774886) (xy 167.029905 -288.799493)
			(xy 167.02201 -288.84807) (xy 167.006426 -288.894751) (xy 166.983555 -288.938328) (xy 166.95399 -288.977672)
			(xy 166.918497 -289.011764) (xy 166.877994 -289.03972) (xy 166.833532 -289.060818) (xy 166.786261 -289.07451)
			(xy 166.737406 -289.080442) (xy 166.688231 -289.078461) (xy 166.640012 -289.068617) (xy 166.593996 -289.051165)
			(xy 166.551375 -289.026558) (xy 166.513254 -288.995433) (xy 166.480619 -288.958596) (xy 166.454316 -288.917)
			(xy 166.435025 -288.871724) (xy 166.423248 -288.82394) (xy 166.419288 -288.774886) (xy 166.080186 -288.774886)
			(xy 166.079691 -288.799493) (xy 166.071796 -288.84807) (xy 166.056212 -288.894751) (xy 166.033341 -288.938328)
			(xy 166.003776 -288.977672) (xy 165.968283 -289.011764) (xy 165.92778 -289.03972) (xy 165.883318 -289.060818)
			(xy 165.836047 -289.07451) (xy 165.787192 -289.080442) (xy 165.738017 -289.078461) (xy 165.689798 -289.068617)
			(xy 165.643782 -289.051165) (xy 165.601161 -289.026558) (xy 165.56304 -288.995433) (xy 165.530405 -288.958596)
			(xy 165.504102 -288.917) (xy 165.484811 -288.871724) (xy 165.473034 -288.82394) (xy 165.469074 -288.774886)
			(xy 165.130226 -288.774886) (xy 165.129731 -288.799493) (xy 165.121836 -288.84807) (xy 165.106252 -288.894751)
			(xy 165.083381 -288.938328) (xy 165.053816 -288.977672) (xy 165.018323 -289.011764) (xy 164.97782 -289.03972)
			(xy 164.933358 -289.060818) (xy 164.886087 -289.07451) (xy 164.837232 -289.080442) (xy 164.788057 -289.078461)
			(xy 164.739838 -289.068617) (xy 164.693822 -289.051165) (xy 164.651201 -289.026558) (xy 164.61308 -288.995433)
			(xy 164.580445 -288.958596) (xy 164.554142 -288.917) (xy 164.534851 -288.871724) (xy 164.523074 -288.82394)
			(xy 164.519114 -288.774886) (xy 164.180266 -288.774886) (xy 164.179771 -288.799493) (xy 164.171876 -288.84807)
			(xy 164.156292 -288.894751) (xy 164.133421 -288.938328) (xy 164.103856 -288.977672) (xy 164.068363 -289.011764)
			(xy 164.02786 -289.03972) (xy 163.983398 -289.060818) (xy 163.936127 -289.07451) (xy 163.887272 -289.080442)
			(xy 163.838097 -289.078461) (xy 163.789878 -289.068617) (xy 163.743862 -289.051165) (xy 163.701241 -289.026558)
			(xy 163.66312 -288.995433) (xy 163.630485 -288.958596) (xy 163.604182 -288.917) (xy 163.584891 -288.871724)
			(xy 163.573114 -288.82394) (xy 163.569154 -288.774886) (xy 163.230306 -288.774886) (xy 163.229811 -288.799493)
			(xy 163.221916 -288.84807) (xy 163.206332 -288.894751) (xy 163.183461 -288.938328) (xy 163.153896 -288.977672)
			(xy 163.118403 -289.011764) (xy 163.0779 -289.03972) (xy 163.033438 -289.060818) (xy 162.986167 -289.07451)
			(xy 162.937312 -289.080442) (xy 162.888137 -289.078461) (xy 162.839918 -289.068617) (xy 162.793902 -289.051165)
			(xy 162.751281 -289.026558) (xy 162.71316 -288.995433) (xy 162.680525 -288.958596) (xy 162.654222 -288.917)
			(xy 162.634931 -288.871724) (xy 162.623154 -288.82394) (xy 162.619194 -288.774886) (xy 162.280346 -288.774886)
			(xy 162.279851 -288.799493) (xy 162.271956 -288.84807) (xy 162.256372 -288.894751) (xy 162.233501 -288.938328)
			(xy 162.203936 -288.977672) (xy 162.168443 -289.011764) (xy 162.12794 -289.03972) (xy 162.083478 -289.060818)
			(xy 162.036207 -289.07451) (xy 161.987352 -289.080442) (xy 161.938177 -289.078461) (xy 161.889958 -289.068617)
			(xy 161.843942 -289.051165) (xy 161.801321 -289.026558) (xy 161.7632 -288.995433) (xy 161.730565 -288.958596)
			(xy 161.704262 -288.917) (xy 161.684971 -288.871724) (xy 161.673194 -288.82394) (xy 161.669234 -288.774886)
			(xy 161.330386 -288.774886) (xy 161.329891 -288.799493) (xy 161.321996 -288.84807) (xy 161.306412 -288.894751)
			(xy 161.283541 -288.938328) (xy 161.253976 -288.977672) (xy 161.218483 -289.011764) (xy 161.17798 -289.03972)
			(xy 161.133518 -289.060818) (xy 161.086247 -289.07451) (xy 161.037392 -289.080442) (xy 160.988217 -289.078461)
			(xy 160.939998 -289.068617) (xy 160.893982 -289.051165) (xy 160.851361 -289.026558) (xy 160.81324 -288.995433)
			(xy 160.780605 -288.958596) (xy 160.754302 -288.917) (xy 160.735011 -288.871724) (xy 160.723234 -288.82394)
			(xy 160.719274 -288.774886) (xy 160.380172 -288.774886) (xy 160.379677 -288.799493) (xy 160.371782 -288.84807)
			(xy 160.356198 -288.894751) (xy 160.333327 -288.938328) (xy 160.303762 -288.977672) (xy 160.268269 -289.011764)
			(xy 160.227766 -289.03972) (xy 160.183304 -289.060818) (xy 160.136033 -289.07451) (xy 160.087178 -289.080442)
			(xy 160.038003 -289.078461) (xy 159.989784 -289.068617) (xy 159.943768 -289.051165) (xy 159.901147 -289.026558)
			(xy 159.863026 -288.995433) (xy 159.830391 -288.958596) (xy 159.804088 -288.917) (xy 159.784797 -288.871724)
			(xy 159.77302 -288.82394) (xy 159.76906 -288.774886) (xy 159.430212 -288.774886) (xy 159.429717 -288.799493)
			(xy 159.421822 -288.84807) (xy 159.406238 -288.894751) (xy 159.383367 -288.938328) (xy 159.353802 -288.977672)
			(xy 159.318309 -289.011764) (xy 159.277806 -289.03972) (xy 159.233344 -289.060818) (xy 159.186073 -289.07451)
			(xy 159.137218 -289.080442) (xy 159.088043 -289.078461) (xy 159.039824 -289.068617) (xy 158.993808 -289.051165)
			(xy 158.951187 -289.026558) (xy 158.913066 -288.995433) (xy 158.880431 -288.958596) (xy 158.854128 -288.917)
			(xy 158.834837 -288.871724) (xy 158.82306 -288.82394) (xy 158.8191 -288.774886) (xy 154.680412 -288.774886)
			(xy 154.679917 -288.799493) (xy 154.672022 -288.84807) (xy 154.656438 -288.894751) (xy 154.633567 -288.938328)
			(xy 154.604002 -288.977672) (xy 154.568509 -289.011764) (xy 154.528006 -289.03972) (xy 154.483544 -289.060818)
			(xy 154.436273 -289.07451) (xy 154.387418 -289.080442) (xy 154.338243 -289.078461) (xy 154.290024 -289.068617)
			(xy 154.244008 -289.051165) (xy 154.201387 -289.026558) (xy 154.163266 -288.995433) (xy 154.130631 -288.958596)
			(xy 154.104328 -288.917) (xy 154.085037 -288.871724) (xy 154.07326 -288.82394) (xy 154.0693 -288.774886)
			(xy 153.730198 -288.774886) (xy 153.729703 -288.799493) (xy 153.721808 -288.84807) (xy 153.706224 -288.894751)
			(xy 153.683353 -288.938328) (xy 153.653788 -288.977672) (xy 153.618295 -289.011764) (xy 153.577792 -289.03972)
			(xy 153.53333 -289.060818) (xy 153.486059 -289.07451) (xy 153.437204 -289.080442) (xy 153.388029 -289.078461)
			(xy 153.33981 -289.068617) (xy 153.293794 -289.051165) (xy 153.251173 -289.026558) (xy 153.213052 -288.995433)
			(xy 153.180417 -288.958596) (xy 153.154114 -288.917) (xy 153.134823 -288.871724) (xy 153.123046 -288.82394)
			(xy 153.119086 -288.774886) (xy 152.780238 -288.774886) (xy 152.779743 -288.799493) (xy 152.771848 -288.84807)
			(xy 152.756264 -288.894751) (xy 152.733393 -288.938328) (xy 152.703828 -288.977672) (xy 152.668335 -289.011764)
			(xy 152.627832 -289.03972) (xy 152.58337 -289.060818) (xy 152.536099 -289.07451) (xy 152.487244 -289.080442)
			(xy 152.438069 -289.078461) (xy 152.38985 -289.068617) (xy 152.343834 -289.051165) (xy 152.301213 -289.026558)
			(xy 152.263092 -288.995433) (xy 152.230457 -288.958596) (xy 152.204154 -288.917) (xy 152.184863 -288.871724)
			(xy 152.173086 -288.82394) (xy 152.169126 -288.774886) (xy 136.349994 -288.774886) (xy 136.349994 -289.532314)
			(xy 141.911576 -289.532314) (xy 141.915647 -289.476692) (xy 141.927773 -289.422255) (xy 141.947696 -289.370164)
			(xy 141.974992 -289.321529) (xy 142.009078 -289.277386) (xy 142.049227 -289.238677) (xy 142.094585 -289.206226)
			(xy 142.144185 -289.180725) (xy 142.196969 -289.162718) (xy 142.251812 -289.152588) (xy 142.307546 -289.150551)
			(xy 142.362983 -289.156651) (xy 142.41694 -289.170757) (xy 142.468269 -289.192569) (xy 142.515875 -289.221623)
			(xy 142.558743 -289.257298) (xy 142.59596 -289.298835) (xy 142.626733 -289.345348) (xy 142.650405 -289.395845)
			(xy 142.666473 -289.449252) (xy 142.674593 -289.504428) (xy 142.675102 -289.532314) (xy 143.387062 -289.532314)
			(xy 143.391133 -289.476692) (xy 143.403259 -289.422255) (xy 143.423182 -289.370164) (xy 143.450478 -289.321529)
			(xy 143.484564 -289.277386) (xy 143.524713 -289.238677) (xy 143.570071 -289.206226) (xy 143.619671 -289.180725)
			(xy 143.672455 -289.162718) (xy 143.727298 -289.152588) (xy 143.783032 -289.150551) (xy 143.838469 -289.156651)
			(xy 143.892426 -289.170757) (xy 143.943755 -289.192569) (xy 143.991361 -289.221623) (xy 144.034229 -289.257298)
			(xy 144.071446 -289.298835) (xy 144.102219 -289.345348) (xy 144.125891 -289.395845) (xy 144.141959 -289.449252)
			(xy 144.150079 -289.504428) (xy 144.150588 -289.532314) (xy 144.276062 -289.532314) (xy 144.280133 -289.476692)
			(xy 144.292259 -289.422255) (xy 144.312182 -289.370164) (xy 144.339478 -289.321529) (xy 144.373564 -289.277386)
			(xy 144.413713 -289.238677) (xy 144.459071 -289.206226) (xy 144.508671 -289.180725) (xy 144.561455 -289.162718)
			(xy 144.616298 -289.152588) (xy 144.672032 -289.150551) (xy 144.727469 -289.156651) (xy 144.781426 -289.170757)
			(xy 144.832755 -289.192569) (xy 144.880361 -289.221623) (xy 144.923229 -289.257298) (xy 144.960446 -289.298835)
			(xy 144.991219 -289.345348) (xy 145.014891 -289.395845) (xy 145.030959 -289.449252) (xy 145.039079 -289.504428)
			(xy 145.039588 -289.532314) (xy 145.039079 -289.5602) (xy 145.030959 -289.615376) (xy 145.014891 -289.668783)
			(xy 144.991219 -289.71928) (xy 144.960446 -289.765793) (xy 144.923229 -289.80733) (xy 144.880361 -289.843005)
			(xy 144.832755 -289.872059) (xy 144.781426 -289.893871) (xy 144.727469 -289.907977) (xy 144.672032 -289.914077)
			(xy 144.616298 -289.91204) (xy 144.561455 -289.90191) (xy 144.508671 -289.883903) (xy 144.459071 -289.858402)
			(xy 144.413713 -289.825951) (xy 144.373564 -289.787242) (xy 144.339478 -289.743099) (xy 144.312182 -289.694464)
			(xy 144.292259 -289.642373) (xy 144.280133 -289.587936) (xy 144.276062 -289.532314) (xy 144.150588 -289.532314)
			(xy 144.150079 -289.5602) (xy 144.141959 -289.615376) (xy 144.125891 -289.668783) (xy 144.102219 -289.71928)
			(xy 144.071446 -289.765793) (xy 144.034229 -289.80733) (xy 143.991361 -289.843005) (xy 143.943755 -289.872059)
			(xy 143.892426 -289.893871) (xy 143.838469 -289.907977) (xy 143.783032 -289.914077) (xy 143.727298 -289.91204)
			(xy 143.672455 -289.90191) (xy 143.619671 -289.883903) (xy 143.570071 -289.858402) (xy 143.524713 -289.825951)
			(xy 143.484564 -289.787242) (xy 143.450478 -289.743099) (xy 143.423182 -289.694464) (xy 143.403259 -289.642373)
			(xy 143.391133 -289.587936) (xy 143.387062 -289.532314) (xy 142.675102 -289.532314) (xy 142.674593 -289.5602)
			(xy 142.666473 -289.615376) (xy 142.650405 -289.668783) (xy 142.626733 -289.71928) (xy 142.59596 -289.765793)
			(xy 142.558743 -289.80733) (xy 142.515875 -289.843005) (xy 142.468269 -289.872059) (xy 142.41694 -289.893871)
			(xy 142.362983 -289.907977) (xy 142.307546 -289.914077) (xy 142.251812 -289.91204) (xy 142.196969 -289.90191)
			(xy 142.144185 -289.883903) (xy 142.094585 -289.858402) (xy 142.049227 -289.825951) (xy 142.009078 -289.787242)
			(xy 141.974992 -289.743099) (xy 141.947696 -289.694464) (xy 141.927773 -289.642373) (xy 141.915647 -289.587936)
			(xy 141.911576 -289.532314) (xy 136.349994 -289.532314) (xy 136.349994 -290.294314) (xy 147.43811 -290.294314)
			(xy 147.438654 -290.264932) (xy 147.447683 -290.206865) (xy 147.465514 -290.150871) (xy 147.491725 -290.098275)
			(xy 147.525695 -290.050324) (xy 147.56662 -290.008152) (xy 147.589748 -289.990022) (xy 147.599146 -289.982656)
			(xy 147.60956 -289.962082) (xy 147.611084 -289.858196) (xy 147.601178 -289.837114) (xy 147.592034 -289.829748)
			(xy 147.570186 -289.811542) (xy 147.531644 -289.769724) (xy 147.499736 -289.722649) (xy 147.475169 -289.671359)
			(xy 147.458486 -289.616991) (xy 147.450058 -289.560749) (xy 147.44954 -289.532314) (xy 147.450026 -289.505063)
			(xy 147.457782 -289.451115) (xy 147.473137 -289.39882) (xy 147.495779 -289.349243) (xy 147.525245 -289.303393)
			(xy 147.560936 -289.262202) (xy 147.602127 -289.226511) (xy 147.647977 -289.197045) (xy 147.697554 -289.174403)
			(xy 147.749849 -289.159048) (xy 147.803797 -289.151292) (xy 147.858299 -289.151292) (xy 147.912247 -289.159048)
			(xy 147.964542 -289.174403) (xy 148.014119 -289.197045) (xy 148.059969 -289.226511) (xy 148.10116 -289.262202)
			(xy 148.136851 -289.303393) (xy 148.166317 -289.349243) (xy 148.188959 -289.39882) (xy 148.204314 -289.451115)
			(xy 148.21207 -289.505063) (xy 148.212556 -289.532314) (xy 148.212006 -289.561696) (xy 148.202975 -289.619761)
			(xy 148.185143 -289.675754) (xy 148.160679 -289.724846) (xy 152.169126 -289.724846) (xy 152.173086 -289.675792)
			(xy 152.184863 -289.628008) (xy 152.204154 -289.582732) (xy 152.230457 -289.541136) (xy 152.263092 -289.504299)
			(xy 152.301213 -289.473174) (xy 152.343834 -289.448567) (xy 152.38985 -289.431115) (xy 152.438069 -289.421271)
			(xy 152.487244 -289.41929) (xy 152.536099 -289.425222) (xy 152.58337 -289.438914) (xy 152.627832 -289.460012)
			(xy 152.668335 -289.487968) (xy 152.703828 -289.52206) (xy 152.733393 -289.561404) (xy 152.756264 -289.604981)
			(xy 152.771848 -289.651662) (xy 152.779743 -289.700239) (xy 152.780238 -289.724846) (xy 153.119086 -289.724846)
			(xy 153.123046 -289.675792) (xy 153.134823 -289.628008) (xy 153.154114 -289.582732) (xy 153.180417 -289.541136)
			(xy 153.213052 -289.504299) (xy 153.251173 -289.473174) (xy 153.293794 -289.448567) (xy 153.33981 -289.431115)
			(xy 153.388029 -289.421271) (xy 153.437204 -289.41929) (xy 153.486059 -289.425222) (xy 153.53333 -289.438914)
			(xy 153.577792 -289.460012) (xy 153.618295 -289.487968) (xy 153.653788 -289.52206) (xy 153.683353 -289.561404)
			(xy 153.706224 -289.604981) (xy 153.721808 -289.651662) (xy 153.729703 -289.700239) (xy 153.730198 -289.724846)
			(xy 154.0693 -289.724846) (xy 154.07326 -289.675792) (xy 154.085037 -289.628008) (xy 154.104328 -289.582732)
			(xy 154.130631 -289.541136) (xy 154.163266 -289.504299) (xy 154.201387 -289.473174) (xy 154.244008 -289.448567)
			(xy 154.290024 -289.431115) (xy 154.338243 -289.421271) (xy 154.387418 -289.41929) (xy 154.436273 -289.425222)
			(xy 154.483544 -289.438914) (xy 154.528006 -289.460012) (xy 154.568509 -289.487968) (xy 154.604002 -289.52206)
			(xy 154.633567 -289.561404) (xy 154.656438 -289.604981) (xy 154.672022 -289.651662) (xy 154.679917 -289.700239)
			(xy 154.680412 -289.724846) (xy 155.01926 -289.724846) (xy 155.02322 -289.675792) (xy 155.034997 -289.628008)
			(xy 155.054288 -289.582732) (xy 155.080591 -289.541136) (xy 155.113226 -289.504299) (xy 155.151347 -289.473174)
			(xy 155.193968 -289.448567) (xy 155.239984 -289.431115) (xy 155.288203 -289.421271) (xy 155.337378 -289.41929)
			(xy 155.386233 -289.425222) (xy 155.433504 -289.438914) (xy 155.477966 -289.460012) (xy 155.518469 -289.487968)
			(xy 155.553962 -289.52206) (xy 155.583527 -289.561404) (xy 155.606398 -289.604981) (xy 155.621982 -289.651662)
			(xy 155.629877 -289.700239) (xy 155.630372 -289.724846) (xy 155.96922 -289.724846) (xy 155.97318 -289.675792)
			(xy 155.984957 -289.628008) (xy 156.004248 -289.582732) (xy 156.030551 -289.541136) (xy 156.063186 -289.504299)
			(xy 156.101307 -289.473174) (xy 156.143928 -289.448567) (xy 156.189944 -289.431115) (xy 156.238163 -289.421271)
			(xy 156.287338 -289.41929) (xy 156.336193 -289.425222) (xy 156.383464 -289.438914) (xy 156.427926 -289.460012)
			(xy 156.468429 -289.487968) (xy 156.503922 -289.52206) (xy 156.533487 -289.561404) (xy 156.556358 -289.604981)
			(xy 156.571942 -289.651662) (xy 156.579837 -289.700239) (xy 156.580332 -289.724846) (xy 156.91918 -289.724846)
			(xy 156.92314 -289.675792) (xy 156.934917 -289.628008) (xy 156.954208 -289.582732) (xy 156.980511 -289.541136)
			(xy 157.013146 -289.504299) (xy 157.051267 -289.473174) (xy 157.093888 -289.448567) (xy 157.139904 -289.431115)
			(xy 157.188123 -289.421271) (xy 157.237298 -289.41929) (xy 157.286153 -289.425222) (xy 157.333424 -289.438914)
			(xy 157.377886 -289.460012) (xy 157.418389 -289.487968) (xy 157.453882 -289.52206) (xy 157.483447 -289.561404)
			(xy 157.506318 -289.604981) (xy 157.521902 -289.651662) (xy 157.529797 -289.700239) (xy 157.530292 -289.724846)
			(xy 157.86914 -289.724846) (xy 157.8731 -289.675792) (xy 157.884877 -289.628008) (xy 157.904168 -289.582732)
			(xy 157.930471 -289.541136) (xy 157.963106 -289.504299) (xy 158.001227 -289.473174) (xy 158.043848 -289.448567)
			(xy 158.089864 -289.431115) (xy 158.138083 -289.421271) (xy 158.187258 -289.41929) (xy 158.236113 -289.425222)
			(xy 158.283384 -289.438914) (xy 158.327846 -289.460012) (xy 158.368349 -289.487968) (xy 158.403842 -289.52206)
			(xy 158.433407 -289.561404) (xy 158.456278 -289.604981) (xy 158.471862 -289.651662) (xy 158.479757 -289.700239)
			(xy 158.480252 -289.724846) (xy 158.8191 -289.724846) (xy 158.82306 -289.675792) (xy 158.834837 -289.628008)
			(xy 158.854128 -289.582732) (xy 158.880431 -289.541136) (xy 158.913066 -289.504299) (xy 158.951187 -289.473174)
			(xy 158.993808 -289.448567) (xy 159.039824 -289.431115) (xy 159.088043 -289.421271) (xy 159.137218 -289.41929)
			(xy 159.186073 -289.425222) (xy 159.233344 -289.438914) (xy 159.277806 -289.460012) (xy 159.318309 -289.487968)
			(xy 159.353802 -289.52206) (xy 159.383367 -289.561404) (xy 159.406238 -289.604981) (xy 159.421822 -289.651662)
			(xy 159.429717 -289.700239) (xy 159.430212 -289.724846) (xy 159.76906 -289.724846) (xy 159.77302 -289.675792)
			(xy 159.784797 -289.628008) (xy 159.804088 -289.582732) (xy 159.830391 -289.541136) (xy 159.863026 -289.504299)
			(xy 159.901147 -289.473174) (xy 159.943768 -289.448567) (xy 159.989784 -289.431115) (xy 160.038003 -289.421271)
			(xy 160.087178 -289.41929) (xy 160.136033 -289.425222) (xy 160.183304 -289.438914) (xy 160.227766 -289.460012)
			(xy 160.268269 -289.487968) (xy 160.303762 -289.52206) (xy 160.333327 -289.561404) (xy 160.356198 -289.604981)
			(xy 160.371782 -289.651662) (xy 160.379677 -289.700239) (xy 160.380172 -289.724846) (xy 160.719274 -289.724846)
			(xy 160.723234 -289.675792) (xy 160.735011 -289.628008) (xy 160.754302 -289.582732) (xy 160.780605 -289.541136)
			(xy 160.81324 -289.504299) (xy 160.851361 -289.473174) (xy 160.893982 -289.448567) (xy 160.939998 -289.431115)
			(xy 160.988217 -289.421271) (xy 161.037392 -289.41929) (xy 161.086247 -289.425222) (xy 161.133518 -289.438914)
			(xy 161.17798 -289.460012) (xy 161.218483 -289.487968) (xy 161.253976 -289.52206) (xy 161.283541 -289.561404)
			(xy 161.306412 -289.604981) (xy 161.321996 -289.651662) (xy 161.329891 -289.700239) (xy 161.330386 -289.724846)
			(xy 161.669234 -289.724846) (xy 161.673194 -289.675792) (xy 161.684971 -289.628008) (xy 161.704262 -289.582732)
			(xy 161.730565 -289.541136) (xy 161.7632 -289.504299) (xy 161.801321 -289.473174) (xy 161.843942 -289.448567)
			(xy 161.889958 -289.431115) (xy 161.938177 -289.421271) (xy 161.987352 -289.41929) (xy 162.036207 -289.425222)
			(xy 162.083478 -289.438914) (xy 162.12794 -289.460012) (xy 162.168443 -289.487968) (xy 162.203936 -289.52206)
			(xy 162.233501 -289.561404) (xy 162.256372 -289.604981) (xy 162.271956 -289.651662) (xy 162.279851 -289.700239)
			(xy 162.280346 -289.724846) (xy 162.619194 -289.724846) (xy 162.623154 -289.675792) (xy 162.634931 -289.628008)
			(xy 162.654222 -289.582732) (xy 162.680525 -289.541136) (xy 162.71316 -289.504299) (xy 162.751281 -289.473174)
			(xy 162.793902 -289.448567) (xy 162.839918 -289.431115) (xy 162.888137 -289.421271) (xy 162.937312 -289.41929)
			(xy 162.986167 -289.425222) (xy 163.033438 -289.438914) (xy 163.0779 -289.460012) (xy 163.118403 -289.487968)
			(xy 163.153896 -289.52206) (xy 163.183461 -289.561404) (xy 163.206332 -289.604981) (xy 163.221916 -289.651662)
			(xy 163.229811 -289.700239) (xy 163.230306 -289.724846) (xy 163.569154 -289.724846) (xy 163.573114 -289.675792)
			(xy 163.584891 -289.628008) (xy 163.604182 -289.582732) (xy 163.630485 -289.541136) (xy 163.66312 -289.504299)
			(xy 163.701241 -289.473174) (xy 163.743862 -289.448567) (xy 163.789878 -289.431115) (xy 163.838097 -289.421271)
			(xy 163.887272 -289.41929) (xy 163.936127 -289.425222) (xy 163.983398 -289.438914) (xy 164.02786 -289.460012)
			(xy 164.068363 -289.487968) (xy 164.103856 -289.52206) (xy 164.133421 -289.561404) (xy 164.156292 -289.604981)
			(xy 164.171876 -289.651662) (xy 164.179771 -289.700239) (xy 164.180266 -289.724846) (xy 164.519114 -289.724846)
			(xy 164.523074 -289.675792) (xy 164.534851 -289.628008) (xy 164.554142 -289.582732) (xy 164.580445 -289.541136)
			(xy 164.61308 -289.504299) (xy 164.651201 -289.473174) (xy 164.693822 -289.448567) (xy 164.739838 -289.431115)
			(xy 164.788057 -289.421271) (xy 164.837232 -289.41929) (xy 164.886087 -289.425222) (xy 164.933358 -289.438914)
			(xy 164.97782 -289.460012) (xy 165.018323 -289.487968) (xy 165.053816 -289.52206) (xy 165.083381 -289.561404)
			(xy 165.106252 -289.604981) (xy 165.121836 -289.651662) (xy 165.129731 -289.700239) (xy 165.130226 -289.724846)
			(xy 165.469074 -289.724846) (xy 165.473034 -289.675792) (xy 165.484811 -289.628008) (xy 165.504102 -289.582732)
			(xy 165.530405 -289.541136) (xy 165.56304 -289.504299) (xy 165.601161 -289.473174) (xy 165.643782 -289.448567)
			(xy 165.689798 -289.431115) (xy 165.738017 -289.421271) (xy 165.787192 -289.41929) (xy 165.836047 -289.425222)
			(xy 165.883318 -289.438914) (xy 165.92778 -289.460012) (xy 165.968283 -289.487968) (xy 166.003776 -289.52206)
			(xy 166.033341 -289.561404) (xy 166.056212 -289.604981) (xy 166.071796 -289.651662) (xy 166.079691 -289.700239)
			(xy 166.080186 -289.724846) (xy 166.419288 -289.724846) (xy 166.423248 -289.675792) (xy 166.435025 -289.628008)
			(xy 166.454316 -289.582732) (xy 166.480619 -289.541136) (xy 166.513254 -289.504299) (xy 166.551375 -289.473174)
			(xy 166.593996 -289.448567) (xy 166.640012 -289.431115) (xy 166.688231 -289.421271) (xy 166.737406 -289.41929)
			(xy 166.786261 -289.425222) (xy 166.833532 -289.438914) (xy 166.877994 -289.460012) (xy 166.918497 -289.487968)
			(xy 166.95399 -289.52206) (xy 166.983555 -289.561404) (xy 167.006426 -289.604981) (xy 167.02201 -289.651662)
			(xy 167.029905 -289.700239) (xy 167.0304 -289.724846) (xy 167.369248 -289.724846) (xy 167.373208 -289.675792)
			(xy 167.384985 -289.628008) (xy 167.404276 -289.582732) (xy 167.430579 -289.541136) (xy 167.463214 -289.504299)
			(xy 167.501335 -289.473174) (xy 167.543956 -289.448567) (xy 167.589972 -289.431115) (xy 167.638191 -289.421271)
			(xy 167.687366 -289.41929) (xy 167.736221 -289.425222) (xy 167.783492 -289.438914) (xy 167.827954 -289.460012)
			(xy 167.868457 -289.487968) (xy 167.90395 -289.52206) (xy 167.933515 -289.561404) (xy 167.956386 -289.604981)
			(xy 167.97197 -289.651662) (xy 167.979865 -289.700239) (xy 167.98036 -289.724846) (xy 168.319208 -289.724846)
			(xy 168.323168 -289.675792) (xy 168.334945 -289.628008) (xy 168.354236 -289.582732) (xy 168.380539 -289.541136)
			(xy 168.413174 -289.504299) (xy 168.451295 -289.473174) (xy 168.493916 -289.448567) (xy 168.539932 -289.431115)
			(xy 168.588151 -289.421271) (xy 168.637326 -289.41929) (xy 168.686181 -289.425222) (xy 168.733452 -289.438914)
			(xy 168.777914 -289.460012) (xy 168.818417 -289.487968) (xy 168.85391 -289.52206) (xy 168.883475 -289.561404)
			(xy 168.906346 -289.604981) (xy 168.92193 -289.651662) (xy 168.929825 -289.700239) (xy 168.93032 -289.724846)
			(xy 169.269168 -289.724846) (xy 169.273128 -289.675792) (xy 169.284905 -289.628008) (xy 169.304196 -289.582732)
			(xy 169.330499 -289.541136) (xy 169.363134 -289.504299) (xy 169.401255 -289.473174) (xy 169.443876 -289.448567)
			(xy 169.489892 -289.431115) (xy 169.538111 -289.421271) (xy 169.587286 -289.41929) (xy 169.636141 -289.425222)
			(xy 169.683412 -289.438914) (xy 169.727874 -289.460012) (xy 169.768377 -289.487968) (xy 169.80387 -289.52206)
			(xy 169.833435 -289.561404) (xy 169.856306 -289.604981) (xy 169.87189 -289.651662) (xy 169.879785 -289.700239)
			(xy 169.88028 -289.724846) (xy 170.219128 -289.724846) (xy 170.223088 -289.675792) (xy 170.234865 -289.628008)
			(xy 170.254156 -289.582732) (xy 170.280459 -289.541136) (xy 170.313094 -289.504299) (xy 170.351215 -289.473174)
			(xy 170.393836 -289.448567) (xy 170.439852 -289.431115) (xy 170.488071 -289.421271) (xy 170.537246 -289.41929)
			(xy 170.586101 -289.425222) (xy 170.633372 -289.438914) (xy 170.677834 -289.460012) (xy 170.718337 -289.487968)
			(xy 170.75383 -289.52206) (xy 170.783395 -289.561404) (xy 170.806266 -289.604981) (xy 170.82185 -289.651662)
			(xy 170.829745 -289.700239) (xy 170.83024 -289.724846) (xy 171.169088 -289.724846) (xy 171.173048 -289.675792)
			(xy 171.184825 -289.628008) (xy 171.204116 -289.582732) (xy 171.230419 -289.541136) (xy 171.263054 -289.504299)
			(xy 171.301175 -289.473174) (xy 171.343796 -289.448567) (xy 171.389812 -289.431115) (xy 171.438031 -289.421271)
			(xy 171.487206 -289.41929) (xy 171.536061 -289.425222) (xy 171.583332 -289.438914) (xy 171.627794 -289.460012)
			(xy 171.668297 -289.487968) (xy 171.70379 -289.52206) (xy 171.733355 -289.561404) (xy 171.756226 -289.604981)
			(xy 171.77181 -289.651662) (xy 171.779705 -289.700239) (xy 171.7802 -289.724846) (xy 172.119048 -289.724846)
			(xy 172.123008 -289.675792) (xy 172.134785 -289.628008) (xy 172.154076 -289.582732) (xy 172.180379 -289.541136)
			(xy 172.213014 -289.504299) (xy 172.251135 -289.473174) (xy 172.293756 -289.448567) (xy 172.339772 -289.431115)
			(xy 172.387991 -289.421271) (xy 172.437166 -289.41929) (xy 172.486021 -289.425222) (xy 172.533292 -289.438914)
			(xy 172.577754 -289.460012) (xy 172.618257 -289.487968) (xy 172.65375 -289.52206) (xy 172.683315 -289.561404)
			(xy 172.706186 -289.604981) (xy 172.72177 -289.651662) (xy 172.729665 -289.700239) (xy 172.73016 -289.724846)
			(xy 173.069262 -289.724846) (xy 173.073222 -289.675792) (xy 173.084999 -289.628008) (xy 173.10429 -289.582732)
			(xy 173.130593 -289.541136) (xy 173.163228 -289.504299) (xy 173.201349 -289.473174) (xy 173.24397 -289.448567)
			(xy 173.289986 -289.431115) (xy 173.338205 -289.421271) (xy 173.38738 -289.41929) (xy 173.436235 -289.425222)
			(xy 173.483506 -289.438914) (xy 173.527968 -289.460012) (xy 173.568471 -289.487968) (xy 173.603964 -289.52206)
			(xy 173.633529 -289.561404) (xy 173.6564 -289.604981) (xy 173.671984 -289.651662) (xy 173.679879 -289.700239)
			(xy 173.680374 -289.724846) (xy 174.019222 -289.724846) (xy 174.023182 -289.675792) (xy 174.034959 -289.628008)
			(xy 174.05425 -289.582732) (xy 174.080553 -289.541136) (xy 174.113188 -289.504299) (xy 174.151309 -289.473174)
			(xy 174.19393 -289.448567) (xy 174.239946 -289.431115) (xy 174.288165 -289.421271) (xy 174.33734 -289.41929)
			(xy 174.386195 -289.425222) (xy 174.433466 -289.438914) (xy 174.477928 -289.460012) (xy 174.518431 -289.487968)
			(xy 174.553924 -289.52206) (xy 174.583489 -289.561404) (xy 174.60636 -289.604981) (xy 174.621944 -289.651662)
			(xy 174.629839 -289.700239) (xy 174.630334 -289.724846) (xy 175.919142 -289.724846) (xy 175.923102 -289.675792)
			(xy 175.934879 -289.628008) (xy 175.95417 -289.582732) (xy 175.980473 -289.541136) (xy 176.013108 -289.504299)
			(xy 176.051229 -289.473174) (xy 176.09385 -289.448567) (xy 176.139866 -289.431115) (xy 176.188085 -289.421271)
			(xy 176.23726 -289.41929) (xy 176.286115 -289.425222) (xy 176.333386 -289.438914) (xy 176.377848 -289.460012)
			(xy 176.418351 -289.487968) (xy 176.453844 -289.52206) (xy 176.483409 -289.561404) (xy 176.50628 -289.604981)
			(xy 176.521864 -289.651662) (xy 176.529759 -289.700239) (xy 176.530254 -289.724846) (xy 176.869102 -289.724846)
			(xy 176.873062 -289.675792) (xy 176.884839 -289.628008) (xy 176.90413 -289.582732) (xy 176.930433 -289.541136)
			(xy 176.963068 -289.504299) (xy 177.001189 -289.473174) (xy 177.04381 -289.448567) (xy 177.089826 -289.431115)
			(xy 177.138045 -289.421271) (xy 177.18722 -289.41929) (xy 177.236075 -289.425222) (xy 177.283346 -289.438914)
			(xy 177.327808 -289.460012) (xy 177.368311 -289.487968) (xy 177.403804 -289.52206) (xy 177.433369 -289.561404)
			(xy 177.45624 -289.604981) (xy 177.471824 -289.651662) (xy 177.479719 -289.700239) (xy 177.480214 -289.724846)
			(xy 177.819062 -289.724846) (xy 177.823022 -289.675792) (xy 177.834799 -289.628008) (xy 177.85409 -289.582732)
			(xy 177.880393 -289.541136) (xy 177.913028 -289.504299) (xy 177.951149 -289.473174) (xy 177.99377 -289.448567)
			(xy 178.039786 -289.431115) (xy 178.088005 -289.421271) (xy 178.13718 -289.41929) (xy 178.186035 -289.425222)
			(xy 178.233306 -289.438914) (xy 178.277768 -289.460012) (xy 178.318271 -289.487968) (xy 178.353764 -289.52206)
			(xy 178.383329 -289.561404) (xy 178.4062 -289.604981) (xy 178.421784 -289.651662) (xy 178.429679 -289.700239)
			(xy 178.430174 -289.724846) (xy 178.769276 -289.724846) (xy 178.773236 -289.675792) (xy 178.785013 -289.628008)
			(xy 178.804304 -289.582732) (xy 178.830607 -289.541136) (xy 178.863242 -289.504299) (xy 178.901363 -289.473174)
			(xy 178.943984 -289.448567) (xy 178.99 -289.431115) (xy 179.038219 -289.421271) (xy 179.087394 -289.41929)
			(xy 179.136249 -289.425222) (xy 179.18352 -289.438914) (xy 179.227982 -289.460012) (xy 179.268485 -289.487968)
			(xy 179.303978 -289.52206) (xy 179.333543 -289.561404) (xy 179.356414 -289.604981) (xy 179.371998 -289.651662)
			(xy 179.379893 -289.700239) (xy 179.380388 -289.724846) (xy 179.719236 -289.724846) (xy 179.723196 -289.675792)
			(xy 179.734973 -289.628008) (xy 179.754264 -289.582732) (xy 179.780567 -289.541136) (xy 179.813202 -289.504299)
			(xy 179.851323 -289.473174) (xy 179.893944 -289.448567) (xy 179.93996 -289.431115) (xy 179.988179 -289.421271)
			(xy 180.037354 -289.41929) (xy 180.086209 -289.425222) (xy 180.13348 -289.438914) (xy 180.177942 -289.460012)
			(xy 180.218445 -289.487968) (xy 180.253938 -289.52206) (xy 180.283503 -289.561404) (xy 180.306374 -289.604981)
			(xy 180.321958 -289.651662) (xy 180.329853 -289.700239) (xy 180.330348 -289.724846) (xy 180.669196 -289.724846)
			(xy 180.673156 -289.675792) (xy 180.684933 -289.628008) (xy 180.704224 -289.582732) (xy 180.730527 -289.541136)
			(xy 180.763162 -289.504299) (xy 180.801283 -289.473174) (xy 180.843904 -289.448567) (xy 180.88992 -289.431115)
			(xy 180.938139 -289.421271) (xy 180.987314 -289.41929) (xy 181.036169 -289.425222) (xy 181.08344 -289.438914)
			(xy 181.127902 -289.460012) (xy 181.168405 -289.487968) (xy 181.203898 -289.52206) (xy 181.233463 -289.561404)
			(xy 181.256334 -289.604981) (xy 181.271918 -289.651662) (xy 181.279813 -289.700239) (xy 181.280308 -289.724846)
			(xy 181.619156 -289.724846) (xy 181.623116 -289.675792) (xy 181.634893 -289.628008) (xy 181.654184 -289.582732)
			(xy 181.680487 -289.541136) (xy 181.713122 -289.504299) (xy 181.751243 -289.473174) (xy 181.793864 -289.448567)
			(xy 181.83988 -289.431115) (xy 181.888099 -289.421271) (xy 181.937274 -289.41929) (xy 181.986129 -289.425222)
			(xy 182.0334 -289.438914) (xy 182.077862 -289.460012) (xy 182.118365 -289.487968) (xy 182.153858 -289.52206)
			(xy 182.183423 -289.561404) (xy 182.206294 -289.604981) (xy 182.221878 -289.651662) (xy 182.229773 -289.700239)
			(xy 182.230268 -289.724846) (xy 182.569116 -289.724846) (xy 182.573076 -289.675792) (xy 182.584853 -289.628008)
			(xy 182.604144 -289.582732) (xy 182.630447 -289.541136) (xy 182.663082 -289.504299) (xy 182.701203 -289.473174)
			(xy 182.743824 -289.448567) (xy 182.78984 -289.431115) (xy 182.838059 -289.421271) (xy 182.887234 -289.41929)
			(xy 182.936089 -289.425222) (xy 182.98336 -289.438914) (xy 183.027822 -289.460012) (xy 183.068325 -289.487968)
			(xy 183.103818 -289.52206) (xy 183.133383 -289.561404) (xy 183.156254 -289.604981) (xy 183.171838 -289.651662)
			(xy 183.179733 -289.700239) (xy 183.180228 -289.724846) (xy 183.519076 -289.724846) (xy 183.523036 -289.675792)
			(xy 183.534813 -289.628008) (xy 183.554104 -289.582732) (xy 183.580407 -289.541136) (xy 183.613042 -289.504299)
			(xy 183.651163 -289.473174) (xy 183.693784 -289.448567) (xy 183.7398 -289.431115) (xy 183.788019 -289.421271)
			(xy 183.837194 -289.41929) (xy 183.886049 -289.425222) (xy 183.93332 -289.438914) (xy 183.977782 -289.460012)
			(xy 184.018285 -289.487968) (xy 184.053778 -289.52206) (xy 184.083343 -289.561404) (xy 184.106214 -289.604981)
			(xy 184.121798 -289.651662) (xy 184.129693 -289.700239) (xy 184.130188 -289.724846) (xy 184.469036 -289.724846)
			(xy 184.472996 -289.675792) (xy 184.484773 -289.628008) (xy 184.504064 -289.582732) (xy 184.530367 -289.541136)
			(xy 184.563002 -289.504299) (xy 184.601123 -289.473174) (xy 184.643744 -289.448567) (xy 184.68976 -289.431115)
			(xy 184.737979 -289.421271) (xy 184.787154 -289.41929) (xy 184.836009 -289.425222) (xy 184.88328 -289.438914)
			(xy 184.927742 -289.460012) (xy 184.968245 -289.487968) (xy 185.003738 -289.52206) (xy 185.033303 -289.561404)
			(xy 185.056174 -289.604981) (xy 185.071758 -289.651662) (xy 185.079653 -289.700239) (xy 185.080148 -289.724846)
			(xy 185.079653 -289.749453) (xy 185.071758 -289.79803) (xy 185.056174 -289.844711) (xy 185.033303 -289.888288)
			(xy 185.003738 -289.927632) (xy 184.968245 -289.961724) (xy 184.927742 -289.98968) (xy 184.88328 -290.010778)
			(xy 184.836009 -290.02447) (xy 184.787154 -290.030402) (xy 184.737979 -290.028421) (xy 184.68976 -290.018577)
			(xy 184.643744 -290.001125) (xy 184.601123 -289.976518) (xy 184.563002 -289.945393) (xy 184.530367 -289.908556)
			(xy 184.504064 -289.86696) (xy 184.484773 -289.821684) (xy 184.472996 -289.7739) (xy 184.469036 -289.724846)
			(xy 184.130188 -289.724846) (xy 184.129693 -289.749453) (xy 184.121798 -289.79803) (xy 184.106214 -289.844711)
			(xy 184.083343 -289.888288) (xy 184.053778 -289.927632) (xy 184.018285 -289.961724) (xy 183.977782 -289.98968)
			(xy 183.93332 -290.010778) (xy 183.886049 -290.02447) (xy 183.837194 -290.030402) (xy 183.788019 -290.028421)
			(xy 183.7398 -290.018577) (xy 183.693784 -290.001125) (xy 183.651163 -289.976518) (xy 183.613042 -289.945393)
			(xy 183.580407 -289.908556) (xy 183.554104 -289.86696) (xy 183.534813 -289.821684) (xy 183.523036 -289.7739)
			(xy 183.519076 -289.724846) (xy 183.180228 -289.724846) (xy 183.179733 -289.749453) (xy 183.171838 -289.79803)
			(xy 183.156254 -289.844711) (xy 183.133383 -289.888288) (xy 183.103818 -289.927632) (xy 183.068325 -289.961724)
			(xy 183.027822 -289.98968) (xy 182.98336 -290.010778) (xy 182.936089 -290.02447) (xy 182.887234 -290.030402)
			(xy 182.838059 -290.028421) (xy 182.78984 -290.018577) (xy 182.743824 -290.001125) (xy 182.701203 -289.976518)
			(xy 182.663082 -289.945393) (xy 182.630447 -289.908556) (xy 182.604144 -289.86696) (xy 182.584853 -289.821684)
			(xy 182.573076 -289.7739) (xy 182.569116 -289.724846) (xy 182.230268 -289.724846) (xy 182.229773 -289.749453)
			(xy 182.221878 -289.79803) (xy 182.206294 -289.844711) (xy 182.183423 -289.888288) (xy 182.153858 -289.927632)
			(xy 182.118365 -289.961724) (xy 182.077862 -289.98968) (xy 182.0334 -290.010778) (xy 181.986129 -290.02447)
			(xy 181.937274 -290.030402) (xy 181.888099 -290.028421) (xy 181.83988 -290.018577) (xy 181.793864 -290.001125)
			(xy 181.751243 -289.976518) (xy 181.713122 -289.945393) (xy 181.680487 -289.908556) (xy 181.654184 -289.86696)
			(xy 181.634893 -289.821684) (xy 181.623116 -289.7739) (xy 181.619156 -289.724846) (xy 181.280308 -289.724846)
			(xy 181.279813 -289.749453) (xy 181.271918 -289.79803) (xy 181.256334 -289.844711) (xy 181.233463 -289.888288)
			(xy 181.203898 -289.927632) (xy 181.168405 -289.961724) (xy 181.127902 -289.98968) (xy 181.08344 -290.010778)
			(xy 181.036169 -290.02447) (xy 180.987314 -290.030402) (xy 180.938139 -290.028421) (xy 180.88992 -290.018577)
			(xy 180.843904 -290.001125) (xy 180.801283 -289.976518) (xy 180.763162 -289.945393) (xy 180.730527 -289.908556)
			(xy 180.704224 -289.86696) (xy 180.684933 -289.821684) (xy 180.673156 -289.7739) (xy 180.669196 -289.724846)
			(xy 180.330348 -289.724846) (xy 180.329853 -289.749453) (xy 180.321958 -289.79803) (xy 180.306374 -289.844711)
			(xy 180.283503 -289.888288) (xy 180.253938 -289.927632) (xy 180.218445 -289.961724) (xy 180.177942 -289.98968)
			(xy 180.13348 -290.010778) (xy 180.086209 -290.02447) (xy 180.037354 -290.030402) (xy 179.988179 -290.028421)
			(xy 179.93996 -290.018577) (xy 179.893944 -290.001125) (xy 179.851323 -289.976518) (xy 179.813202 -289.945393)
			(xy 179.780567 -289.908556) (xy 179.754264 -289.86696) (xy 179.734973 -289.821684) (xy 179.723196 -289.7739)
			(xy 179.719236 -289.724846) (xy 179.380388 -289.724846) (xy 179.379893 -289.749453) (xy 179.371998 -289.79803)
			(xy 179.356414 -289.844711) (xy 179.333543 -289.888288) (xy 179.303978 -289.927632) (xy 179.268485 -289.961724)
			(xy 179.227982 -289.98968) (xy 179.18352 -290.010778) (xy 179.136249 -290.02447) (xy 179.087394 -290.030402)
			(xy 179.038219 -290.028421) (xy 178.99 -290.018577) (xy 178.943984 -290.001125) (xy 178.901363 -289.976518)
			(xy 178.863242 -289.945393) (xy 178.830607 -289.908556) (xy 178.804304 -289.86696) (xy 178.785013 -289.821684)
			(xy 178.773236 -289.7739) (xy 178.769276 -289.724846) (xy 178.430174 -289.724846) (xy 178.429679 -289.749453)
			(xy 178.421784 -289.79803) (xy 178.4062 -289.844711) (xy 178.383329 -289.888288) (xy 178.353764 -289.927632)
			(xy 178.318271 -289.961724) (xy 178.277768 -289.98968) (xy 178.233306 -290.010778) (xy 178.186035 -290.02447)
			(xy 178.13718 -290.030402) (xy 178.088005 -290.028421) (xy 178.039786 -290.018577) (xy 177.99377 -290.001125)
			(xy 177.951149 -289.976518) (xy 177.913028 -289.945393) (xy 177.880393 -289.908556) (xy 177.85409 -289.86696)
			(xy 177.834799 -289.821684) (xy 177.823022 -289.7739) (xy 177.819062 -289.724846) (xy 177.480214 -289.724846)
			(xy 177.479719 -289.749453) (xy 177.471824 -289.79803) (xy 177.45624 -289.844711) (xy 177.433369 -289.888288)
			(xy 177.403804 -289.927632) (xy 177.368311 -289.961724) (xy 177.327808 -289.98968) (xy 177.283346 -290.010778)
			(xy 177.236075 -290.02447) (xy 177.18722 -290.030402) (xy 177.138045 -290.028421) (xy 177.089826 -290.018577)
			(xy 177.04381 -290.001125) (xy 177.001189 -289.976518) (xy 176.963068 -289.945393) (xy 176.930433 -289.908556)
			(xy 176.90413 -289.86696) (xy 176.884839 -289.821684) (xy 176.873062 -289.7739) (xy 176.869102 -289.724846)
			(xy 176.530254 -289.724846) (xy 176.529759 -289.749453) (xy 176.521864 -289.79803) (xy 176.50628 -289.844711)
			(xy 176.483409 -289.888288) (xy 176.453844 -289.927632) (xy 176.418351 -289.961724) (xy 176.377848 -289.98968)
			(xy 176.333386 -290.010778) (xy 176.286115 -290.02447) (xy 176.23726 -290.030402) (xy 176.188085 -290.028421)
			(xy 176.139866 -290.018577) (xy 176.09385 -290.001125) (xy 176.051229 -289.976518) (xy 176.013108 -289.945393)
			(xy 175.980473 -289.908556) (xy 175.95417 -289.86696) (xy 175.934879 -289.821684) (xy 175.923102 -289.7739)
			(xy 175.919142 -289.724846) (xy 174.630334 -289.724846) (xy 174.629839 -289.749453) (xy 174.621944 -289.79803)
			(xy 174.60636 -289.844711) (xy 174.583489 -289.888288) (xy 174.553924 -289.927632) (xy 174.518431 -289.961724)
			(xy 174.477928 -289.98968) (xy 174.433466 -290.010778) (xy 174.386195 -290.02447) (xy 174.33734 -290.030402)
			(xy 174.288165 -290.028421) (xy 174.239946 -290.018577) (xy 174.19393 -290.001125) (xy 174.151309 -289.976518)
			(xy 174.113188 -289.945393) (xy 174.080553 -289.908556) (xy 174.05425 -289.86696) (xy 174.034959 -289.821684)
			(xy 174.023182 -289.7739) (xy 174.019222 -289.724846) (xy 173.680374 -289.724846) (xy 173.679879 -289.749453)
			(xy 173.671984 -289.79803) (xy 173.6564 -289.844711) (xy 173.633529 -289.888288) (xy 173.603964 -289.927632)
			(xy 173.568471 -289.961724) (xy 173.527968 -289.98968) (xy 173.483506 -290.010778) (xy 173.436235 -290.02447)
			(xy 173.38738 -290.030402) (xy 173.338205 -290.028421) (xy 173.289986 -290.018577) (xy 173.24397 -290.001125)
			(xy 173.201349 -289.976518) (xy 173.163228 -289.945393) (xy 173.130593 -289.908556) (xy 173.10429 -289.86696)
			(xy 173.084999 -289.821684) (xy 173.073222 -289.7739) (xy 173.069262 -289.724846) (xy 172.73016 -289.724846)
			(xy 172.729665 -289.749453) (xy 172.72177 -289.79803) (xy 172.706186 -289.844711) (xy 172.683315 -289.888288)
			(xy 172.65375 -289.927632) (xy 172.618257 -289.961724) (xy 172.577754 -289.98968) (xy 172.533292 -290.010778)
			(xy 172.486021 -290.02447) (xy 172.437166 -290.030402) (xy 172.387991 -290.028421) (xy 172.339772 -290.018577)
			(xy 172.293756 -290.001125) (xy 172.251135 -289.976518) (xy 172.213014 -289.945393) (xy 172.180379 -289.908556)
			(xy 172.154076 -289.86696) (xy 172.134785 -289.821684) (xy 172.123008 -289.7739) (xy 172.119048 -289.724846)
			(xy 171.7802 -289.724846) (xy 171.779705 -289.749453) (xy 171.77181 -289.79803) (xy 171.756226 -289.844711)
			(xy 171.733355 -289.888288) (xy 171.70379 -289.927632) (xy 171.668297 -289.961724) (xy 171.627794 -289.98968)
			(xy 171.583332 -290.010778) (xy 171.536061 -290.02447) (xy 171.487206 -290.030402) (xy 171.438031 -290.028421)
			(xy 171.389812 -290.018577) (xy 171.343796 -290.001125) (xy 171.301175 -289.976518) (xy 171.263054 -289.945393)
			(xy 171.230419 -289.908556) (xy 171.204116 -289.86696) (xy 171.184825 -289.821684) (xy 171.173048 -289.7739)
			(xy 171.169088 -289.724846) (xy 170.83024 -289.724846) (xy 170.829745 -289.749453) (xy 170.82185 -289.79803)
			(xy 170.806266 -289.844711) (xy 170.783395 -289.888288) (xy 170.75383 -289.927632) (xy 170.718337 -289.961724)
			(xy 170.677834 -289.98968) (xy 170.633372 -290.010778) (xy 170.586101 -290.02447) (xy 170.537246 -290.030402)
			(xy 170.488071 -290.028421) (xy 170.439852 -290.018577) (xy 170.393836 -290.001125) (xy 170.351215 -289.976518)
			(xy 170.313094 -289.945393) (xy 170.280459 -289.908556) (xy 170.254156 -289.86696) (xy 170.234865 -289.821684)
			(xy 170.223088 -289.7739) (xy 170.219128 -289.724846) (xy 169.88028 -289.724846) (xy 169.879785 -289.749453)
			(xy 169.87189 -289.79803) (xy 169.856306 -289.844711) (xy 169.833435 -289.888288) (xy 169.80387 -289.927632)
			(xy 169.768377 -289.961724) (xy 169.727874 -289.98968) (xy 169.683412 -290.010778) (xy 169.636141 -290.02447)
			(xy 169.587286 -290.030402) (xy 169.538111 -290.028421) (xy 169.489892 -290.018577) (xy 169.443876 -290.001125)
			(xy 169.401255 -289.976518) (xy 169.363134 -289.945393) (xy 169.330499 -289.908556) (xy 169.304196 -289.86696)
			(xy 169.284905 -289.821684) (xy 169.273128 -289.7739) (xy 169.269168 -289.724846) (xy 168.93032 -289.724846)
			(xy 168.929825 -289.749453) (xy 168.92193 -289.79803) (xy 168.906346 -289.844711) (xy 168.883475 -289.888288)
			(xy 168.85391 -289.927632) (xy 168.818417 -289.961724) (xy 168.777914 -289.98968) (xy 168.733452 -290.010778)
			(xy 168.686181 -290.02447) (xy 168.637326 -290.030402) (xy 168.588151 -290.028421) (xy 168.539932 -290.018577)
			(xy 168.493916 -290.001125) (xy 168.451295 -289.976518) (xy 168.413174 -289.945393) (xy 168.380539 -289.908556)
			(xy 168.354236 -289.86696) (xy 168.334945 -289.821684) (xy 168.323168 -289.7739) (xy 168.319208 -289.724846)
			(xy 167.98036 -289.724846) (xy 167.979865 -289.749453) (xy 167.97197 -289.79803) (xy 167.956386 -289.844711)
			(xy 167.933515 -289.888288) (xy 167.90395 -289.927632) (xy 167.868457 -289.961724) (xy 167.827954 -289.98968)
			(xy 167.783492 -290.010778) (xy 167.736221 -290.02447) (xy 167.687366 -290.030402) (xy 167.638191 -290.028421)
			(xy 167.589972 -290.018577) (xy 167.543956 -290.001125) (xy 167.501335 -289.976518) (xy 167.463214 -289.945393)
			(xy 167.430579 -289.908556) (xy 167.404276 -289.86696) (xy 167.384985 -289.821684) (xy 167.373208 -289.7739)
			(xy 167.369248 -289.724846) (xy 167.0304 -289.724846) (xy 167.029905 -289.749453) (xy 167.02201 -289.79803)
			(xy 167.006426 -289.844711) (xy 166.983555 -289.888288) (xy 166.95399 -289.927632) (xy 166.918497 -289.961724)
			(xy 166.877994 -289.98968) (xy 166.833532 -290.010778) (xy 166.786261 -290.02447) (xy 166.737406 -290.030402)
			(xy 166.688231 -290.028421) (xy 166.640012 -290.018577) (xy 166.593996 -290.001125) (xy 166.551375 -289.976518)
			(xy 166.513254 -289.945393) (xy 166.480619 -289.908556) (xy 166.454316 -289.86696) (xy 166.435025 -289.821684)
			(xy 166.423248 -289.7739) (xy 166.419288 -289.724846) (xy 166.080186 -289.724846) (xy 166.079691 -289.749453)
			(xy 166.071796 -289.79803) (xy 166.056212 -289.844711) (xy 166.033341 -289.888288) (xy 166.003776 -289.927632)
			(xy 165.968283 -289.961724) (xy 165.92778 -289.98968) (xy 165.883318 -290.010778) (xy 165.836047 -290.02447)
			(xy 165.787192 -290.030402) (xy 165.738017 -290.028421) (xy 165.689798 -290.018577) (xy 165.643782 -290.001125)
			(xy 165.601161 -289.976518) (xy 165.56304 -289.945393) (xy 165.530405 -289.908556) (xy 165.504102 -289.86696)
			(xy 165.484811 -289.821684) (xy 165.473034 -289.7739) (xy 165.469074 -289.724846) (xy 165.130226 -289.724846)
			(xy 165.129731 -289.749453) (xy 165.121836 -289.79803) (xy 165.106252 -289.844711) (xy 165.083381 -289.888288)
			(xy 165.053816 -289.927632) (xy 165.018323 -289.961724) (xy 164.97782 -289.98968) (xy 164.933358 -290.010778)
			(xy 164.886087 -290.02447) (xy 164.837232 -290.030402) (xy 164.788057 -290.028421) (xy 164.739838 -290.018577)
			(xy 164.693822 -290.001125) (xy 164.651201 -289.976518) (xy 164.61308 -289.945393) (xy 164.580445 -289.908556)
			(xy 164.554142 -289.86696) (xy 164.534851 -289.821684) (xy 164.523074 -289.7739) (xy 164.519114 -289.724846)
			(xy 164.180266 -289.724846) (xy 164.179771 -289.749453) (xy 164.171876 -289.79803) (xy 164.156292 -289.844711)
			(xy 164.133421 -289.888288) (xy 164.103856 -289.927632) (xy 164.068363 -289.961724) (xy 164.02786 -289.98968)
			(xy 163.983398 -290.010778) (xy 163.936127 -290.02447) (xy 163.887272 -290.030402) (xy 163.838097 -290.028421)
			(xy 163.789878 -290.018577) (xy 163.743862 -290.001125) (xy 163.701241 -289.976518) (xy 163.66312 -289.945393)
			(xy 163.630485 -289.908556) (xy 163.604182 -289.86696) (xy 163.584891 -289.821684) (xy 163.573114 -289.7739)
			(xy 163.569154 -289.724846) (xy 163.230306 -289.724846) (xy 163.229811 -289.749453) (xy 163.221916 -289.79803)
			(xy 163.206332 -289.844711) (xy 163.183461 -289.888288) (xy 163.153896 -289.927632) (xy 163.118403 -289.961724)
			(xy 163.0779 -289.98968) (xy 163.033438 -290.010778) (xy 162.986167 -290.02447) (xy 162.937312 -290.030402)
			(xy 162.888137 -290.028421) (xy 162.839918 -290.018577) (xy 162.793902 -290.001125) (xy 162.751281 -289.976518)
			(xy 162.71316 -289.945393) (xy 162.680525 -289.908556) (xy 162.654222 -289.86696) (xy 162.634931 -289.821684)
			(xy 162.623154 -289.7739) (xy 162.619194 -289.724846) (xy 162.280346 -289.724846) (xy 162.279851 -289.749453)
			(xy 162.271956 -289.79803) (xy 162.256372 -289.844711) (xy 162.233501 -289.888288) (xy 162.203936 -289.927632)
			(xy 162.168443 -289.961724) (xy 162.12794 -289.98968) (xy 162.083478 -290.010778) (xy 162.036207 -290.02447)
			(xy 161.987352 -290.030402) (xy 161.938177 -290.028421) (xy 161.889958 -290.018577) (xy 161.843942 -290.001125)
			(xy 161.801321 -289.976518) (xy 161.7632 -289.945393) (xy 161.730565 -289.908556) (xy 161.704262 -289.86696)
			(xy 161.684971 -289.821684) (xy 161.673194 -289.7739) (xy 161.669234 -289.724846) (xy 161.330386 -289.724846)
			(xy 161.329891 -289.749453) (xy 161.321996 -289.79803) (xy 161.306412 -289.844711) (xy 161.283541 -289.888288)
			(xy 161.253976 -289.927632) (xy 161.218483 -289.961724) (xy 161.17798 -289.98968) (xy 161.133518 -290.010778)
			(xy 161.086247 -290.02447) (xy 161.037392 -290.030402) (xy 160.988217 -290.028421) (xy 160.939998 -290.018577)
			(xy 160.893982 -290.001125) (xy 160.851361 -289.976518) (xy 160.81324 -289.945393) (xy 160.780605 -289.908556)
			(xy 160.754302 -289.86696) (xy 160.735011 -289.821684) (xy 160.723234 -289.7739) (xy 160.719274 -289.724846)
			(xy 160.380172 -289.724846) (xy 160.379677 -289.749453) (xy 160.371782 -289.79803) (xy 160.356198 -289.844711)
			(xy 160.333327 -289.888288) (xy 160.303762 -289.927632) (xy 160.268269 -289.961724) (xy 160.227766 -289.98968)
			(xy 160.183304 -290.010778) (xy 160.136033 -290.02447) (xy 160.087178 -290.030402) (xy 160.038003 -290.028421)
			(xy 159.989784 -290.018577) (xy 159.943768 -290.001125) (xy 159.901147 -289.976518) (xy 159.863026 -289.945393)
			(xy 159.830391 -289.908556) (xy 159.804088 -289.86696) (xy 159.784797 -289.821684) (xy 159.77302 -289.7739)
			(xy 159.76906 -289.724846) (xy 159.430212 -289.724846) (xy 159.429717 -289.749453) (xy 159.421822 -289.79803)
			(xy 159.406238 -289.844711) (xy 159.383367 -289.888288) (xy 159.353802 -289.927632) (xy 159.318309 -289.961724)
			(xy 159.277806 -289.98968) (xy 159.233344 -290.010778) (xy 159.186073 -290.02447) (xy 159.137218 -290.030402)
			(xy 159.088043 -290.028421) (xy 159.039824 -290.018577) (xy 158.993808 -290.001125) (xy 158.951187 -289.976518)
			(xy 158.913066 -289.945393) (xy 158.880431 -289.908556) (xy 158.854128 -289.86696) (xy 158.834837 -289.821684)
			(xy 158.82306 -289.7739) (xy 158.8191 -289.724846) (xy 158.480252 -289.724846) (xy 158.479757 -289.749453)
			(xy 158.471862 -289.79803) (xy 158.456278 -289.844711) (xy 158.433407 -289.888288) (xy 158.403842 -289.927632)
			(xy 158.368349 -289.961724) (xy 158.327846 -289.98968) (xy 158.283384 -290.010778) (xy 158.236113 -290.02447)
			(xy 158.187258 -290.030402) (xy 158.138083 -290.028421) (xy 158.089864 -290.018577) (xy 158.043848 -290.001125)
			(xy 158.001227 -289.976518) (xy 157.963106 -289.945393) (xy 157.930471 -289.908556) (xy 157.904168 -289.86696)
			(xy 157.884877 -289.821684) (xy 157.8731 -289.7739) (xy 157.86914 -289.724846) (xy 157.530292 -289.724846)
			(xy 157.529797 -289.749453) (xy 157.521902 -289.79803) (xy 157.506318 -289.844711) (xy 157.483447 -289.888288)
			(xy 157.453882 -289.927632) (xy 157.418389 -289.961724) (xy 157.377886 -289.98968) (xy 157.333424 -290.010778)
			(xy 157.286153 -290.02447) (xy 157.237298 -290.030402) (xy 157.188123 -290.028421) (xy 157.139904 -290.018577)
			(xy 157.093888 -290.001125) (xy 157.051267 -289.976518) (xy 157.013146 -289.945393) (xy 156.980511 -289.908556)
			(xy 156.954208 -289.86696) (xy 156.934917 -289.821684) (xy 156.92314 -289.7739) (xy 156.91918 -289.724846)
			(xy 156.580332 -289.724846) (xy 156.579837 -289.749453) (xy 156.571942 -289.79803) (xy 156.556358 -289.844711)
			(xy 156.533487 -289.888288) (xy 156.503922 -289.927632) (xy 156.468429 -289.961724) (xy 156.427926 -289.98968)
			(xy 156.383464 -290.010778) (xy 156.336193 -290.02447) (xy 156.287338 -290.030402) (xy 156.238163 -290.028421)
			(xy 156.189944 -290.018577) (xy 156.143928 -290.001125) (xy 156.101307 -289.976518) (xy 156.063186 -289.945393)
			(xy 156.030551 -289.908556) (xy 156.004248 -289.86696) (xy 155.984957 -289.821684) (xy 155.97318 -289.7739)
			(xy 155.96922 -289.724846) (xy 155.630372 -289.724846) (xy 155.629877 -289.749453) (xy 155.621982 -289.79803)
			(xy 155.606398 -289.844711) (xy 155.583527 -289.888288) (xy 155.553962 -289.927632) (xy 155.518469 -289.961724)
			(xy 155.477966 -289.98968) (xy 155.433504 -290.010778) (xy 155.386233 -290.02447) (xy 155.337378 -290.030402)
			(xy 155.288203 -290.028421) (xy 155.239984 -290.018577) (xy 155.193968 -290.001125) (xy 155.151347 -289.976518)
			(xy 155.113226 -289.945393) (xy 155.080591 -289.908556) (xy 155.054288 -289.86696) (xy 155.034997 -289.821684)
			(xy 155.02322 -289.7739) (xy 155.01926 -289.724846) (xy 154.680412 -289.724846) (xy 154.679917 -289.749453)
			(xy 154.672022 -289.79803) (xy 154.656438 -289.844711) (xy 154.633567 -289.888288) (xy 154.604002 -289.927632)
			(xy 154.568509 -289.961724) (xy 154.528006 -289.98968) (xy 154.483544 -290.010778) (xy 154.436273 -290.02447)
			(xy 154.387418 -290.030402) (xy 154.338243 -290.028421) (xy 154.290024 -290.018577) (xy 154.244008 -290.001125)
			(xy 154.201387 -289.976518) (xy 154.163266 -289.945393) (xy 154.130631 -289.908556) (xy 154.104328 -289.86696)
			(xy 154.085037 -289.821684) (xy 154.07326 -289.7739) (xy 154.0693 -289.724846) (xy 153.730198 -289.724846)
			(xy 153.729703 -289.749453) (xy 153.721808 -289.79803) (xy 153.706224 -289.844711) (xy 153.683353 -289.888288)
			(xy 153.653788 -289.927632) (xy 153.618295 -289.961724) (xy 153.577792 -289.98968) (xy 153.53333 -290.010778)
			(xy 153.486059 -290.02447) (xy 153.437204 -290.030402) (xy 153.388029 -290.028421) (xy 153.33981 -290.018577)
			(xy 153.293794 -290.001125) (xy 153.251173 -289.976518) (xy 153.213052 -289.945393) (xy 153.180417 -289.908556)
			(xy 153.154114 -289.86696) (xy 153.134823 -289.821684) (xy 153.123046 -289.7739) (xy 153.119086 -289.724846)
			(xy 152.780238 -289.724846) (xy 152.779743 -289.749453) (xy 152.771848 -289.79803) (xy 152.756264 -289.844711)
			(xy 152.733393 -289.888288) (xy 152.703828 -289.927632) (xy 152.668335 -289.961724) (xy 152.627832 -289.98968)
			(xy 152.58337 -290.010778) (xy 152.536099 -290.02447) (xy 152.487244 -290.030402) (xy 152.438069 -290.028421)
			(xy 152.38985 -290.018577) (xy 152.343834 -290.001125) (xy 152.301213 -289.976518) (xy 152.263092 -289.945393)
			(xy 152.230457 -289.908556) (xy 152.204154 -289.86696) (xy 152.184863 -289.821684) (xy 152.173086 -289.7739)
			(xy 152.169126 -289.724846) (xy 148.160679 -289.724846) (xy 148.158933 -289.728349) (xy 148.124966 -289.776301)
			(xy 148.084044 -289.818474) (xy 148.060918 -289.836606) (xy 148.05152 -289.843972) (xy 148.041106 -289.864546)
			(xy 148.039582 -289.968432) (xy 148.049488 -289.989514) (xy 148.058632 -289.99688) (xy 148.080459 -290.015109)
			(xy 148.118999 -290.056924) (xy 148.150908 -290.103995) (xy 148.175478 -290.15528) (xy 148.192166 -290.209643)
			(xy 148.200603 -290.265881) (xy 148.201126 -290.294314) (xy 148.8346 -290.294314) (xy 148.838671 -290.238692)
			(xy 148.850797 -290.184255) (xy 148.87072 -290.132164) (xy 148.898016 -290.083529) (xy 148.932102 -290.039386)
			(xy 148.972251 -290.000677) (xy 149.017609 -289.968226) (xy 149.067209 -289.942725) (xy 149.119993 -289.924718)
			(xy 149.174836 -289.914588) (xy 149.23057 -289.912551) (xy 149.286007 -289.918651) (xy 149.339964 -289.932757)
			(xy 149.391293 -289.954569) (xy 149.438899 -289.983623) (xy 149.481767 -290.019298) (xy 149.518984 -290.060835)
			(xy 149.549757 -290.107348) (xy 149.573429 -290.157845) (xy 149.589497 -290.211252) (xy 149.597617 -290.266428)
			(xy 149.598126 -290.294314) (xy 149.72106 -290.294314) (xy 149.725131 -290.238692) (xy 149.737257 -290.184255)
			(xy 149.75718 -290.132164) (xy 149.784476 -290.083529) (xy 149.818562 -290.039386) (xy 149.858711 -290.000677)
			(xy 149.904069 -289.968226) (xy 149.953669 -289.942725) (xy 150.006453 -289.924718) (xy 150.061296 -289.914588)
			(xy 150.11703 -289.912551) (xy 150.172467 -289.918651) (xy 150.226424 -289.932757) (xy 150.277753 -289.954569)
			(xy 150.325359 -289.983623) (xy 150.368227 -290.019298) (xy 150.405444 -290.060835) (xy 150.436217 -290.107348)
			(xy 150.459889 -290.157845) (xy 150.475957 -290.211252) (xy 150.484077 -290.266428) (xy 150.484586 -290.294314)
			(xy 150.484077 -290.3222) (xy 150.475957 -290.377376) (xy 150.459889 -290.430783) (xy 150.436217 -290.48128)
			(xy 150.405444 -290.527793) (xy 150.368227 -290.56933) (xy 150.325359 -290.605005) (xy 150.277753 -290.634059)
			(xy 150.226424 -290.655871) (xy 150.172467 -290.669977) (xy 150.128581 -290.674806) (xy 152.169126 -290.674806)
			(xy 152.173086 -290.625752) (xy 152.184863 -290.577968) (xy 152.204154 -290.532692) (xy 152.230457 -290.491096)
			(xy 152.263092 -290.454259) (xy 152.301213 -290.423134) (xy 152.343834 -290.398527) (xy 152.38985 -290.381075)
			(xy 152.438069 -290.371231) (xy 152.487244 -290.36925) (xy 152.536099 -290.375182) (xy 152.58337 -290.388874)
			(xy 152.627832 -290.409972) (xy 152.668335 -290.437928) (xy 152.703828 -290.47202) (xy 152.733393 -290.511364)
			(xy 152.756264 -290.554941) (xy 152.771848 -290.601622) (xy 152.779743 -290.650199) (xy 152.780238 -290.674806)
			(xy 153.119086 -290.674806) (xy 153.123046 -290.625752) (xy 153.134823 -290.577968) (xy 153.154114 -290.532692)
			(xy 153.180417 -290.491096) (xy 153.213052 -290.454259) (xy 153.251173 -290.423134) (xy 153.293794 -290.398527)
			(xy 153.33981 -290.381075) (xy 153.388029 -290.371231) (xy 153.437204 -290.36925) (xy 153.486059 -290.375182)
			(xy 153.53333 -290.388874) (xy 153.577792 -290.409972) (xy 153.618295 -290.437928) (xy 153.653788 -290.47202)
			(xy 153.683353 -290.511364) (xy 153.706224 -290.554941) (xy 153.721808 -290.601622) (xy 153.729703 -290.650199)
			(xy 153.730198 -290.674806) (xy 154.0693 -290.674806) (xy 154.07326 -290.625752) (xy 154.085037 -290.577968)
			(xy 154.104328 -290.532692) (xy 154.130631 -290.491096) (xy 154.163266 -290.454259) (xy 154.201387 -290.423134)
			(xy 154.244008 -290.398527) (xy 154.290024 -290.381075) (xy 154.338243 -290.371231) (xy 154.387418 -290.36925)
			(xy 154.436273 -290.375182) (xy 154.483544 -290.388874) (xy 154.528006 -290.409972) (xy 154.568509 -290.437928)
			(xy 154.604002 -290.47202) (xy 154.633567 -290.511364) (xy 154.656438 -290.554941) (xy 154.672022 -290.601622)
			(xy 154.679917 -290.650199) (xy 154.680412 -290.674806) (xy 156.91918 -290.674806) (xy 156.92314 -290.625752)
			(xy 156.934917 -290.577968) (xy 156.954208 -290.532692) (xy 156.980511 -290.491096) (xy 157.013146 -290.454259)
			(xy 157.051267 -290.423134) (xy 157.093888 -290.398527) (xy 157.139904 -290.381075) (xy 157.188123 -290.371231)
			(xy 157.237298 -290.36925) (xy 157.286153 -290.375182) (xy 157.333424 -290.388874) (xy 157.377886 -290.409972)
			(xy 157.418389 -290.437928) (xy 157.453882 -290.47202) (xy 157.483447 -290.511364) (xy 157.506318 -290.554941)
			(xy 157.521902 -290.601622) (xy 157.529797 -290.650199) (xy 157.530292 -290.674806) (xy 157.86914 -290.674806)
			(xy 157.8731 -290.625752) (xy 157.884877 -290.577968) (xy 157.904168 -290.532692) (xy 157.930471 -290.491096)
			(xy 157.963106 -290.454259) (xy 158.001227 -290.423134) (xy 158.043848 -290.398527) (xy 158.089864 -290.381075)
			(xy 158.138083 -290.371231) (xy 158.187258 -290.36925) (xy 158.236113 -290.375182) (xy 158.283384 -290.388874)
			(xy 158.327846 -290.409972) (xy 158.368349 -290.437928) (xy 158.403842 -290.47202) (xy 158.433407 -290.511364)
			(xy 158.456278 -290.554941) (xy 158.471862 -290.601622) (xy 158.479757 -290.650199) (xy 158.480252 -290.674806)
			(xy 158.8191 -290.674806) (xy 158.82306 -290.625752) (xy 158.834837 -290.577968) (xy 158.854128 -290.532692)
			(xy 158.880431 -290.491096) (xy 158.913066 -290.454259) (xy 158.951187 -290.423134) (xy 158.993808 -290.398527)
			(xy 159.039824 -290.381075) (xy 159.088043 -290.371231) (xy 159.137218 -290.36925) (xy 159.186073 -290.375182)
			(xy 159.233344 -290.388874) (xy 159.277806 -290.409972) (xy 159.318309 -290.437928) (xy 159.353802 -290.47202)
			(xy 159.383367 -290.511364) (xy 159.406238 -290.554941) (xy 159.421822 -290.601622) (xy 159.429717 -290.650199)
			(xy 159.430212 -290.674806) (xy 159.76906 -290.674806) (xy 159.77302 -290.625752) (xy 159.784797 -290.577968)
			(xy 159.804088 -290.532692) (xy 159.830391 -290.491096) (xy 159.863026 -290.454259) (xy 159.901147 -290.423134)
			(xy 159.943768 -290.398527) (xy 159.989784 -290.381075) (xy 160.038003 -290.371231) (xy 160.087178 -290.36925)
			(xy 160.136033 -290.375182) (xy 160.183304 -290.388874) (xy 160.227766 -290.409972) (xy 160.268269 -290.437928)
			(xy 160.303762 -290.47202) (xy 160.333327 -290.511364) (xy 160.356198 -290.554941) (xy 160.371782 -290.601622)
			(xy 160.379677 -290.650199) (xy 160.380172 -290.674806) (xy 160.719274 -290.674806) (xy 160.723234 -290.625752)
			(xy 160.735011 -290.577968) (xy 160.754302 -290.532692) (xy 160.780605 -290.491096) (xy 160.81324 -290.454259)
			(xy 160.851361 -290.423134) (xy 160.893982 -290.398527) (xy 160.939998 -290.381075) (xy 160.988217 -290.371231)
			(xy 161.037392 -290.36925) (xy 161.086247 -290.375182) (xy 161.133518 -290.388874) (xy 161.17798 -290.409972)
			(xy 161.218483 -290.437928) (xy 161.253976 -290.47202) (xy 161.283541 -290.511364) (xy 161.306412 -290.554941)
			(xy 161.321996 -290.601622) (xy 161.329891 -290.650199) (xy 161.330386 -290.674806) (xy 161.669234 -290.674806)
			(xy 161.673194 -290.625752) (xy 161.684971 -290.577968) (xy 161.704262 -290.532692) (xy 161.730565 -290.491096)
			(xy 161.7632 -290.454259) (xy 161.801321 -290.423134) (xy 161.843942 -290.398527) (xy 161.889958 -290.381075)
			(xy 161.938177 -290.371231) (xy 161.987352 -290.36925) (xy 162.036207 -290.375182) (xy 162.083478 -290.388874)
			(xy 162.12794 -290.409972) (xy 162.168443 -290.437928) (xy 162.203936 -290.47202) (xy 162.233501 -290.511364)
			(xy 162.256372 -290.554941) (xy 162.271956 -290.601622) (xy 162.279851 -290.650199) (xy 162.280346 -290.674806)
			(xy 162.619194 -290.674806) (xy 162.623154 -290.625752) (xy 162.634931 -290.577968) (xy 162.654222 -290.532692)
			(xy 162.680525 -290.491096) (xy 162.71316 -290.454259) (xy 162.751281 -290.423134) (xy 162.793902 -290.398527)
			(xy 162.839918 -290.381075) (xy 162.888137 -290.371231) (xy 162.937312 -290.36925) (xy 162.986167 -290.375182)
			(xy 163.033438 -290.388874) (xy 163.0779 -290.409972) (xy 163.118403 -290.437928) (xy 163.153896 -290.47202)
			(xy 163.183461 -290.511364) (xy 163.206332 -290.554941) (xy 163.221916 -290.601622) (xy 163.229811 -290.650199)
			(xy 163.230306 -290.674806) (xy 163.569154 -290.674806) (xy 163.573114 -290.625752) (xy 163.584891 -290.577968)
			(xy 163.604182 -290.532692) (xy 163.630485 -290.491096) (xy 163.66312 -290.454259) (xy 163.701241 -290.423134)
			(xy 163.743862 -290.398527) (xy 163.789878 -290.381075) (xy 163.838097 -290.371231) (xy 163.887272 -290.36925)
			(xy 163.936127 -290.375182) (xy 163.983398 -290.388874) (xy 164.02786 -290.409972) (xy 164.068363 -290.437928)
			(xy 164.103856 -290.47202) (xy 164.133421 -290.511364) (xy 164.156292 -290.554941) (xy 164.171876 -290.601622)
			(xy 164.179771 -290.650199) (xy 164.180266 -290.674806) (xy 165.469074 -290.674806) (xy 165.473034 -290.625752)
			(xy 165.484811 -290.577968) (xy 165.504102 -290.532692) (xy 165.530405 -290.491096) (xy 165.56304 -290.454259)
			(xy 165.601161 -290.423134) (xy 165.643782 -290.398527) (xy 165.689798 -290.381075) (xy 165.738017 -290.371231)
			(xy 165.787192 -290.36925) (xy 165.836047 -290.375182) (xy 165.883318 -290.388874) (xy 165.92778 -290.409972)
			(xy 165.968283 -290.437928) (xy 166.003776 -290.47202) (xy 166.033341 -290.511364) (xy 166.056212 -290.554941)
			(xy 166.071796 -290.601622) (xy 166.079691 -290.650199) (xy 166.080186 -290.674806) (xy 166.419288 -290.674806)
			(xy 166.423248 -290.625752) (xy 166.435025 -290.577968) (xy 166.454316 -290.532692) (xy 166.480619 -290.491096)
			(xy 166.513254 -290.454259) (xy 166.551375 -290.423134) (xy 166.593996 -290.398527) (xy 166.640012 -290.381075)
			(xy 166.688231 -290.371231) (xy 166.737406 -290.36925) (xy 166.786261 -290.375182) (xy 166.833532 -290.388874)
			(xy 166.877994 -290.409972) (xy 166.918497 -290.437928) (xy 166.95399 -290.47202) (xy 166.983555 -290.511364)
			(xy 167.006426 -290.554941) (xy 167.02201 -290.601622) (xy 167.029905 -290.650199) (xy 167.0304 -290.674806)
			(xy 167.369248 -290.674806) (xy 167.373208 -290.625752) (xy 167.384985 -290.577968) (xy 167.404276 -290.532692)
			(xy 167.430579 -290.491096) (xy 167.463214 -290.454259) (xy 167.501335 -290.423134) (xy 167.543956 -290.398527)
			(xy 167.589972 -290.381075) (xy 167.638191 -290.371231) (xy 167.687366 -290.36925) (xy 167.736221 -290.375182)
			(xy 167.783492 -290.388874) (xy 167.827954 -290.409972) (xy 167.868457 -290.437928) (xy 167.90395 -290.47202)
			(xy 167.933515 -290.511364) (xy 167.956386 -290.554941) (xy 167.97197 -290.601622) (xy 167.979865 -290.650199)
			(xy 167.98036 -290.674806) (xy 168.319208 -290.674806) (xy 168.323168 -290.625752) (xy 168.334945 -290.577968)
			(xy 168.354236 -290.532692) (xy 168.380539 -290.491096) (xy 168.413174 -290.454259) (xy 168.451295 -290.423134)
			(xy 168.493916 -290.398527) (xy 168.539932 -290.381075) (xy 168.588151 -290.371231) (xy 168.637326 -290.36925)
			(xy 168.686181 -290.375182) (xy 168.733452 -290.388874) (xy 168.777914 -290.409972) (xy 168.818417 -290.437928)
			(xy 168.85391 -290.47202) (xy 168.883475 -290.511364) (xy 168.906346 -290.554941) (xy 168.92193 -290.601622)
			(xy 168.929825 -290.650199) (xy 168.93032 -290.674806) (xy 169.269168 -290.674806) (xy 169.273128 -290.625752)
			(xy 169.284905 -290.577968) (xy 169.304196 -290.532692) (xy 169.330499 -290.491096) (xy 169.363134 -290.454259)
			(xy 169.401255 -290.423134) (xy 169.443876 -290.398527) (xy 169.489892 -290.381075) (xy 169.538111 -290.371231)
			(xy 169.587286 -290.36925) (xy 169.636141 -290.375182) (xy 169.683412 -290.388874) (xy 169.727874 -290.409972)
			(xy 169.768377 -290.437928) (xy 169.80387 -290.47202) (xy 169.833435 -290.511364) (xy 169.856306 -290.554941)
			(xy 169.87189 -290.601622) (xy 169.879785 -290.650199) (xy 169.88028 -290.674806) (xy 170.219128 -290.674806)
			(xy 170.223088 -290.625752) (xy 170.234865 -290.577968) (xy 170.254156 -290.532692) (xy 170.280459 -290.491096)
			(xy 170.313094 -290.454259) (xy 170.351215 -290.423134) (xy 170.393836 -290.398527) (xy 170.439852 -290.381075)
			(xy 170.488071 -290.371231) (xy 170.537246 -290.36925) (xy 170.586101 -290.375182) (xy 170.633372 -290.388874)
			(xy 170.677834 -290.409972) (xy 170.718337 -290.437928) (xy 170.75383 -290.47202) (xy 170.783395 -290.511364)
			(xy 170.806266 -290.554941) (xy 170.82185 -290.601622) (xy 170.829745 -290.650199) (xy 170.83024 -290.674806)
			(xy 171.169088 -290.674806) (xy 171.173048 -290.625752) (xy 171.184825 -290.577968) (xy 171.204116 -290.532692)
			(xy 171.230419 -290.491096) (xy 171.263054 -290.454259) (xy 171.301175 -290.423134) (xy 171.343796 -290.398527)
			(xy 171.389812 -290.381075) (xy 171.438031 -290.371231) (xy 171.487206 -290.36925) (xy 171.536061 -290.375182)
			(xy 171.583332 -290.388874) (xy 171.627794 -290.409972) (xy 171.668297 -290.437928) (xy 171.70379 -290.47202)
			(xy 171.733355 -290.511364) (xy 171.756226 -290.554941) (xy 171.77181 -290.601622) (xy 171.779705 -290.650199)
			(xy 171.7802 -290.674806) (xy 172.119048 -290.674806) (xy 172.123008 -290.625752) (xy 172.134785 -290.577968)
			(xy 172.154076 -290.532692) (xy 172.180379 -290.491096) (xy 172.213014 -290.454259) (xy 172.251135 -290.423134)
			(xy 172.293756 -290.398527) (xy 172.339772 -290.381075) (xy 172.387991 -290.371231) (xy 172.437166 -290.36925)
			(xy 172.486021 -290.375182) (xy 172.533292 -290.388874) (xy 172.577754 -290.409972) (xy 172.618257 -290.437928)
			(xy 172.65375 -290.47202) (xy 172.683315 -290.511364) (xy 172.706186 -290.554941) (xy 172.72177 -290.601622)
			(xy 172.729665 -290.650199) (xy 172.73016 -290.674806) (xy 173.069262 -290.674806) (xy 173.073222 -290.625752)
			(xy 173.084999 -290.577968) (xy 173.10429 -290.532692) (xy 173.130593 -290.491096) (xy 173.163228 -290.454259)
			(xy 173.201349 -290.423134) (xy 173.24397 -290.398527) (xy 173.289986 -290.381075) (xy 173.338205 -290.371231)
			(xy 173.38738 -290.36925) (xy 173.436235 -290.375182) (xy 173.483506 -290.388874) (xy 173.527968 -290.409972)
			(xy 173.568471 -290.437928) (xy 173.603964 -290.47202) (xy 173.633529 -290.511364) (xy 173.6564 -290.554941)
			(xy 173.671984 -290.601622) (xy 173.679879 -290.650199) (xy 173.680374 -290.674806) (xy 174.019222 -290.674806)
			(xy 174.023182 -290.625752) (xy 174.034959 -290.577968) (xy 174.05425 -290.532692) (xy 174.080553 -290.491096)
			(xy 174.113188 -290.454259) (xy 174.151309 -290.423134) (xy 174.19393 -290.398527) (xy 174.239946 -290.381075)
			(xy 174.288165 -290.371231) (xy 174.33734 -290.36925) (xy 174.386195 -290.375182) (xy 174.433466 -290.388874)
			(xy 174.477928 -290.409972) (xy 174.518431 -290.437928) (xy 174.553924 -290.47202) (xy 174.583489 -290.511364)
			(xy 174.60636 -290.554941) (xy 174.621944 -290.601622) (xy 174.629839 -290.650199) (xy 174.630334 -290.674806)
			(xy 175.919142 -290.674806) (xy 175.923102 -290.625752) (xy 175.934879 -290.577968) (xy 175.95417 -290.532692)
			(xy 175.980473 -290.491096) (xy 176.013108 -290.454259) (xy 176.051229 -290.423134) (xy 176.09385 -290.398527)
			(xy 176.139866 -290.381075) (xy 176.188085 -290.371231) (xy 176.23726 -290.36925) (xy 176.286115 -290.375182)
			(xy 176.333386 -290.388874) (xy 176.377848 -290.409972) (xy 176.418351 -290.437928) (xy 176.453844 -290.47202)
			(xy 176.483409 -290.511364) (xy 176.50628 -290.554941) (xy 176.521864 -290.601622) (xy 176.529759 -290.650199)
			(xy 176.530254 -290.674806) (xy 176.869102 -290.674806) (xy 176.873062 -290.625752) (xy 176.884839 -290.577968)
			(xy 176.90413 -290.532692) (xy 176.930433 -290.491096) (xy 176.963068 -290.454259) (xy 177.001189 -290.423134)
			(xy 177.04381 -290.398527) (xy 177.089826 -290.381075) (xy 177.138045 -290.371231) (xy 177.18722 -290.36925)
			(xy 177.236075 -290.375182) (xy 177.283346 -290.388874) (xy 177.327808 -290.409972) (xy 177.368311 -290.437928)
			(xy 177.403804 -290.47202) (xy 177.433369 -290.511364) (xy 177.45624 -290.554941) (xy 177.471824 -290.601622)
			(xy 177.479719 -290.650199) (xy 177.480214 -290.674806) (xy 177.819062 -290.674806) (xy 177.823022 -290.625752)
			(xy 177.834799 -290.577968) (xy 177.85409 -290.532692) (xy 177.880393 -290.491096) (xy 177.913028 -290.454259)
			(xy 177.951149 -290.423134) (xy 177.99377 -290.398527) (xy 178.039786 -290.381075) (xy 178.088005 -290.371231)
			(xy 178.13718 -290.36925) (xy 178.186035 -290.375182) (xy 178.233306 -290.388874) (xy 178.277768 -290.409972)
			(xy 178.318271 -290.437928) (xy 178.353764 -290.47202) (xy 178.383329 -290.511364) (xy 178.4062 -290.554941)
			(xy 178.421784 -290.601622) (xy 178.429679 -290.650199) (xy 178.430174 -290.674806) (xy 178.769276 -290.674806)
			(xy 178.773236 -290.625752) (xy 178.785013 -290.577968) (xy 178.804304 -290.532692) (xy 178.830607 -290.491096)
			(xy 178.863242 -290.454259) (xy 178.901363 -290.423134) (xy 178.943984 -290.398527) (xy 178.99 -290.381075)
			(xy 179.038219 -290.371231) (xy 179.087394 -290.36925) (xy 179.136249 -290.375182) (xy 179.18352 -290.388874)
			(xy 179.227982 -290.409972) (xy 179.268485 -290.437928) (xy 179.303978 -290.47202) (xy 179.333543 -290.511364)
			(xy 179.356414 -290.554941) (xy 179.371998 -290.601622) (xy 179.379893 -290.650199) (xy 179.380388 -290.674806)
			(xy 179.719236 -290.674806) (xy 179.723196 -290.625752) (xy 179.734973 -290.577968) (xy 179.754264 -290.532692)
			(xy 179.780567 -290.491096) (xy 179.813202 -290.454259) (xy 179.851323 -290.423134) (xy 179.893944 -290.398527)
			(xy 179.93996 -290.381075) (xy 179.988179 -290.371231) (xy 180.037354 -290.36925) (xy 180.086209 -290.375182)
			(xy 180.13348 -290.388874) (xy 180.177942 -290.409972) (xy 180.218445 -290.437928) (xy 180.253938 -290.47202)
			(xy 180.283503 -290.511364) (xy 180.306374 -290.554941) (xy 180.321958 -290.601622) (xy 180.329853 -290.650199)
			(xy 180.330348 -290.674806) (xy 180.669196 -290.674806) (xy 180.673156 -290.625752) (xy 180.684933 -290.577968)
			(xy 180.704224 -290.532692) (xy 180.730527 -290.491096) (xy 180.763162 -290.454259) (xy 180.801283 -290.423134)
			(xy 180.843904 -290.398527) (xy 180.88992 -290.381075) (xy 180.938139 -290.371231) (xy 180.987314 -290.36925)
			(xy 181.036169 -290.375182) (xy 181.08344 -290.388874) (xy 181.127902 -290.409972) (xy 181.168405 -290.437928)
			(xy 181.203898 -290.47202) (xy 181.233463 -290.511364) (xy 181.256334 -290.554941) (xy 181.271918 -290.601622)
			(xy 181.279813 -290.650199) (xy 181.280308 -290.674806) (xy 181.619156 -290.674806) (xy 181.623116 -290.625752)
			(xy 181.634893 -290.577968) (xy 181.654184 -290.532692) (xy 181.680487 -290.491096) (xy 181.713122 -290.454259)
			(xy 181.751243 -290.423134) (xy 181.793864 -290.398527) (xy 181.83988 -290.381075) (xy 181.888099 -290.371231)
			(xy 181.937274 -290.36925) (xy 181.986129 -290.375182) (xy 182.0334 -290.388874) (xy 182.077862 -290.409972)
			(xy 182.118365 -290.437928) (xy 182.153858 -290.47202) (xy 182.183423 -290.511364) (xy 182.206294 -290.554941)
			(xy 182.221878 -290.601622) (xy 182.229773 -290.650199) (xy 182.230268 -290.674806) (xy 182.569116 -290.674806)
			(xy 182.573076 -290.625752) (xy 182.584853 -290.577968) (xy 182.604144 -290.532692) (xy 182.630447 -290.491096)
			(xy 182.663082 -290.454259) (xy 182.701203 -290.423134) (xy 182.743824 -290.398527) (xy 182.78984 -290.381075)
			(xy 182.838059 -290.371231) (xy 182.887234 -290.36925) (xy 182.936089 -290.375182) (xy 182.98336 -290.388874)
			(xy 183.027822 -290.409972) (xy 183.068325 -290.437928) (xy 183.103818 -290.47202) (xy 183.133383 -290.511364)
			(xy 183.156254 -290.554941) (xy 183.171838 -290.601622) (xy 183.179733 -290.650199) (xy 183.180228 -290.674806)
			(xy 183.519076 -290.674806) (xy 183.523036 -290.625752) (xy 183.534813 -290.577968) (xy 183.554104 -290.532692)
			(xy 183.580407 -290.491096) (xy 183.613042 -290.454259) (xy 183.651163 -290.423134) (xy 183.693784 -290.398527)
			(xy 183.7398 -290.381075) (xy 183.788019 -290.371231) (xy 183.837194 -290.36925) (xy 183.886049 -290.375182)
			(xy 183.93332 -290.388874) (xy 183.977782 -290.409972) (xy 184.018285 -290.437928) (xy 184.053778 -290.47202)
			(xy 184.083343 -290.511364) (xy 184.106214 -290.554941) (xy 184.121798 -290.601622) (xy 184.129693 -290.650199)
			(xy 184.130188 -290.674806) (xy 184.469036 -290.674806) (xy 184.472996 -290.625752) (xy 184.484773 -290.577968)
			(xy 184.504064 -290.532692) (xy 184.530367 -290.491096) (xy 184.563002 -290.454259) (xy 184.601123 -290.423134)
			(xy 184.643744 -290.398527) (xy 184.68976 -290.381075) (xy 184.737979 -290.371231) (xy 184.787154 -290.36925)
			(xy 184.836009 -290.375182) (xy 184.88328 -290.388874) (xy 184.927742 -290.409972) (xy 184.968245 -290.437928)
			(xy 185.003738 -290.47202) (xy 185.033303 -290.511364) (xy 185.056174 -290.554941) (xy 185.071758 -290.601622)
			(xy 185.079653 -290.650199) (xy 185.080148 -290.674806) (xy 185.079653 -290.699413) (xy 185.071758 -290.74799)
			(xy 185.056174 -290.794671) (xy 185.033303 -290.838248) (xy 185.003738 -290.877592) (xy 184.968245 -290.911684)
			(xy 184.927742 -290.93964) (xy 184.88328 -290.960738) (xy 184.836009 -290.97443) (xy 184.787154 -290.980362)
			(xy 184.737979 -290.978381) (xy 184.68976 -290.968537) (xy 184.643744 -290.951085) (xy 184.601123 -290.926478)
			(xy 184.563002 -290.895353) (xy 184.530367 -290.858516) (xy 184.504064 -290.81692) (xy 184.484773 -290.771644)
			(xy 184.472996 -290.72386) (xy 184.469036 -290.674806) (xy 184.130188 -290.674806) (xy 184.129693 -290.699413)
			(xy 184.121798 -290.74799) (xy 184.106214 -290.794671) (xy 184.083343 -290.838248) (xy 184.053778 -290.877592)
			(xy 184.018285 -290.911684) (xy 183.977782 -290.93964) (xy 183.93332 -290.960738) (xy 183.886049 -290.97443)
			(xy 183.837194 -290.980362) (xy 183.788019 -290.978381) (xy 183.7398 -290.968537) (xy 183.693784 -290.951085)
			(xy 183.651163 -290.926478) (xy 183.613042 -290.895353) (xy 183.580407 -290.858516) (xy 183.554104 -290.81692)
			(xy 183.534813 -290.771644) (xy 183.523036 -290.72386) (xy 183.519076 -290.674806) (xy 183.180228 -290.674806)
			(xy 183.179733 -290.699413) (xy 183.171838 -290.74799) (xy 183.156254 -290.794671) (xy 183.133383 -290.838248)
			(xy 183.103818 -290.877592) (xy 183.068325 -290.911684) (xy 183.027822 -290.93964) (xy 182.98336 -290.960738)
			(xy 182.936089 -290.97443) (xy 182.887234 -290.980362) (xy 182.838059 -290.978381) (xy 182.78984 -290.968537)
			(xy 182.743824 -290.951085) (xy 182.701203 -290.926478) (xy 182.663082 -290.895353) (xy 182.630447 -290.858516)
			(xy 182.604144 -290.81692) (xy 182.584853 -290.771644) (xy 182.573076 -290.72386) (xy 182.569116 -290.674806)
			(xy 182.230268 -290.674806) (xy 182.229773 -290.699413) (xy 182.221878 -290.74799) (xy 182.206294 -290.794671)
			(xy 182.183423 -290.838248) (xy 182.153858 -290.877592) (xy 182.118365 -290.911684) (xy 182.077862 -290.93964)
			(xy 182.0334 -290.960738) (xy 181.986129 -290.97443) (xy 181.937274 -290.980362) (xy 181.888099 -290.978381)
			(xy 181.83988 -290.968537) (xy 181.793864 -290.951085) (xy 181.751243 -290.926478) (xy 181.713122 -290.895353)
			(xy 181.680487 -290.858516) (xy 181.654184 -290.81692) (xy 181.634893 -290.771644) (xy 181.623116 -290.72386)
			(xy 181.619156 -290.674806) (xy 181.280308 -290.674806) (xy 181.279813 -290.699413) (xy 181.271918 -290.74799)
			(xy 181.256334 -290.794671) (xy 181.233463 -290.838248) (xy 181.203898 -290.877592) (xy 181.168405 -290.911684)
			(xy 181.127902 -290.93964) (xy 181.08344 -290.960738) (xy 181.036169 -290.97443) (xy 180.987314 -290.980362)
			(xy 180.938139 -290.978381) (xy 180.88992 -290.968537) (xy 180.843904 -290.951085) (xy 180.801283 -290.926478)
			(xy 180.763162 -290.895353) (xy 180.730527 -290.858516) (xy 180.704224 -290.81692) (xy 180.684933 -290.771644)
			(xy 180.673156 -290.72386) (xy 180.669196 -290.674806) (xy 180.330348 -290.674806) (xy 180.329853 -290.699413)
			(xy 180.321958 -290.74799) (xy 180.306374 -290.794671) (xy 180.283503 -290.838248) (xy 180.253938 -290.877592)
			(xy 180.218445 -290.911684) (xy 180.177942 -290.93964) (xy 180.13348 -290.960738) (xy 180.086209 -290.97443)
			(xy 180.037354 -290.980362) (xy 179.988179 -290.978381) (xy 179.93996 -290.968537) (xy 179.893944 -290.951085)
			(xy 179.851323 -290.926478) (xy 179.813202 -290.895353) (xy 179.780567 -290.858516) (xy 179.754264 -290.81692)
			(xy 179.734973 -290.771644) (xy 179.723196 -290.72386) (xy 179.719236 -290.674806) (xy 179.380388 -290.674806)
			(xy 179.379893 -290.699413) (xy 179.371998 -290.74799) (xy 179.356414 -290.794671) (xy 179.333543 -290.838248)
			(xy 179.303978 -290.877592) (xy 179.268485 -290.911684) (xy 179.227982 -290.93964) (xy 179.18352 -290.960738)
			(xy 179.136249 -290.97443) (xy 179.087394 -290.980362) (xy 179.038219 -290.978381) (xy 178.99 -290.968537)
			(xy 178.943984 -290.951085) (xy 178.901363 -290.926478) (xy 178.863242 -290.895353) (xy 178.830607 -290.858516)
			(xy 178.804304 -290.81692) (xy 178.785013 -290.771644) (xy 178.773236 -290.72386) (xy 178.769276 -290.674806)
			(xy 178.430174 -290.674806) (xy 178.429679 -290.699413) (xy 178.421784 -290.74799) (xy 178.4062 -290.794671)
			(xy 178.383329 -290.838248) (xy 178.353764 -290.877592) (xy 178.318271 -290.911684) (xy 178.277768 -290.93964)
			(xy 178.233306 -290.960738) (xy 178.186035 -290.97443) (xy 178.13718 -290.980362) (xy 178.088005 -290.978381)
			(xy 178.039786 -290.968537) (xy 177.99377 -290.951085) (xy 177.951149 -290.926478) (xy 177.913028 -290.895353)
			(xy 177.880393 -290.858516) (xy 177.85409 -290.81692) (xy 177.834799 -290.771644) (xy 177.823022 -290.72386)
			(xy 177.819062 -290.674806) (xy 177.480214 -290.674806) (xy 177.479719 -290.699413) (xy 177.471824 -290.74799)
			(xy 177.45624 -290.794671) (xy 177.433369 -290.838248) (xy 177.403804 -290.877592) (xy 177.368311 -290.911684)
			(xy 177.327808 -290.93964) (xy 177.283346 -290.960738) (xy 177.236075 -290.97443) (xy 177.18722 -290.980362)
			(xy 177.138045 -290.978381) (xy 177.089826 -290.968537) (xy 177.04381 -290.951085) (xy 177.001189 -290.926478)
			(xy 176.963068 -290.895353) (xy 176.930433 -290.858516) (xy 176.90413 -290.81692) (xy 176.884839 -290.771644)
			(xy 176.873062 -290.72386) (xy 176.869102 -290.674806) (xy 176.530254 -290.674806) (xy 176.529759 -290.699413)
			(xy 176.521864 -290.74799) (xy 176.50628 -290.794671) (xy 176.483409 -290.838248) (xy 176.453844 -290.877592)
			(xy 176.418351 -290.911684) (xy 176.377848 -290.93964) (xy 176.333386 -290.960738) (xy 176.286115 -290.97443)
			(xy 176.23726 -290.980362) (xy 176.188085 -290.978381) (xy 176.139866 -290.968537) (xy 176.09385 -290.951085)
			(xy 176.051229 -290.926478) (xy 176.013108 -290.895353) (xy 175.980473 -290.858516) (xy 175.95417 -290.81692)
			(xy 175.934879 -290.771644) (xy 175.923102 -290.72386) (xy 175.919142 -290.674806) (xy 174.630334 -290.674806)
			(xy 174.629839 -290.699413) (xy 174.621944 -290.74799) (xy 174.60636 -290.794671) (xy 174.583489 -290.838248)
			(xy 174.553924 -290.877592) (xy 174.518431 -290.911684) (xy 174.477928 -290.93964) (xy 174.433466 -290.960738)
			(xy 174.386195 -290.97443) (xy 174.33734 -290.980362) (xy 174.288165 -290.978381) (xy 174.239946 -290.968537)
			(xy 174.19393 -290.951085) (xy 174.151309 -290.926478) (xy 174.113188 -290.895353) (xy 174.080553 -290.858516)
			(xy 174.05425 -290.81692) (xy 174.034959 -290.771644) (xy 174.023182 -290.72386) (xy 174.019222 -290.674806)
			(xy 173.680374 -290.674806) (xy 173.679879 -290.699413) (xy 173.671984 -290.74799) (xy 173.6564 -290.794671)
			(xy 173.633529 -290.838248) (xy 173.603964 -290.877592) (xy 173.568471 -290.911684) (xy 173.527968 -290.93964)
			(xy 173.483506 -290.960738) (xy 173.436235 -290.97443) (xy 173.38738 -290.980362) (xy 173.338205 -290.978381)
			(xy 173.289986 -290.968537) (xy 173.24397 -290.951085) (xy 173.201349 -290.926478) (xy 173.163228 -290.895353)
			(xy 173.130593 -290.858516) (xy 173.10429 -290.81692) (xy 173.084999 -290.771644) (xy 173.073222 -290.72386)
			(xy 173.069262 -290.674806) (xy 172.73016 -290.674806) (xy 172.729665 -290.699413) (xy 172.72177 -290.74799)
			(xy 172.706186 -290.794671) (xy 172.683315 -290.838248) (xy 172.65375 -290.877592) (xy 172.618257 -290.911684)
			(xy 172.577754 -290.93964) (xy 172.533292 -290.960738) (xy 172.486021 -290.97443) (xy 172.437166 -290.980362)
			(xy 172.387991 -290.978381) (xy 172.339772 -290.968537) (xy 172.293756 -290.951085) (xy 172.251135 -290.926478)
			(xy 172.213014 -290.895353) (xy 172.180379 -290.858516) (xy 172.154076 -290.81692) (xy 172.134785 -290.771644)
			(xy 172.123008 -290.72386) (xy 172.119048 -290.674806) (xy 171.7802 -290.674806) (xy 171.779705 -290.699413)
			(xy 171.77181 -290.74799) (xy 171.756226 -290.794671) (xy 171.733355 -290.838248) (xy 171.70379 -290.877592)
			(xy 171.668297 -290.911684) (xy 171.627794 -290.93964) (xy 171.583332 -290.960738) (xy 171.536061 -290.97443)
			(xy 171.487206 -290.980362) (xy 171.438031 -290.978381) (xy 171.389812 -290.968537) (xy 171.343796 -290.951085)
			(xy 171.301175 -290.926478) (xy 171.263054 -290.895353) (xy 171.230419 -290.858516) (xy 171.204116 -290.81692)
			(xy 171.184825 -290.771644) (xy 171.173048 -290.72386) (xy 171.169088 -290.674806) (xy 170.83024 -290.674806)
			(xy 170.829745 -290.699413) (xy 170.82185 -290.74799) (xy 170.806266 -290.794671) (xy 170.783395 -290.838248)
			(xy 170.75383 -290.877592) (xy 170.718337 -290.911684) (xy 170.677834 -290.93964) (xy 170.633372 -290.960738)
			(xy 170.586101 -290.97443) (xy 170.537246 -290.980362) (xy 170.488071 -290.978381) (xy 170.439852 -290.968537)
			(xy 170.393836 -290.951085) (xy 170.351215 -290.926478) (xy 170.313094 -290.895353) (xy 170.280459 -290.858516)
			(xy 170.254156 -290.81692) (xy 170.234865 -290.771644) (xy 170.223088 -290.72386) (xy 170.219128 -290.674806)
			(xy 169.88028 -290.674806) (xy 169.879785 -290.699413) (xy 169.87189 -290.74799) (xy 169.856306 -290.794671)
			(xy 169.833435 -290.838248) (xy 169.80387 -290.877592) (xy 169.768377 -290.911684) (xy 169.727874 -290.93964)
			(xy 169.683412 -290.960738) (xy 169.636141 -290.97443) (xy 169.587286 -290.980362) (xy 169.538111 -290.978381)
			(xy 169.489892 -290.968537) (xy 169.443876 -290.951085) (xy 169.401255 -290.926478) (xy 169.363134 -290.895353)
			(xy 169.330499 -290.858516) (xy 169.304196 -290.81692) (xy 169.284905 -290.771644) (xy 169.273128 -290.72386)
			(xy 169.269168 -290.674806) (xy 168.93032 -290.674806) (xy 168.929825 -290.699413) (xy 168.92193 -290.74799)
			(xy 168.906346 -290.794671) (xy 168.883475 -290.838248) (xy 168.85391 -290.877592) (xy 168.818417 -290.911684)
			(xy 168.777914 -290.93964) (xy 168.733452 -290.960738) (xy 168.686181 -290.97443) (xy 168.637326 -290.980362)
			(xy 168.588151 -290.978381) (xy 168.539932 -290.968537) (xy 168.493916 -290.951085) (xy 168.451295 -290.926478)
			(xy 168.413174 -290.895353) (xy 168.380539 -290.858516) (xy 168.354236 -290.81692) (xy 168.334945 -290.771644)
			(xy 168.323168 -290.72386) (xy 168.319208 -290.674806) (xy 167.98036 -290.674806) (xy 167.979865 -290.699413)
			(xy 167.97197 -290.74799) (xy 167.956386 -290.794671) (xy 167.933515 -290.838248) (xy 167.90395 -290.877592)
			(xy 167.868457 -290.911684) (xy 167.827954 -290.93964) (xy 167.783492 -290.960738) (xy 167.736221 -290.97443)
			(xy 167.687366 -290.980362) (xy 167.638191 -290.978381) (xy 167.589972 -290.968537) (xy 167.543956 -290.951085)
			(xy 167.501335 -290.926478) (xy 167.463214 -290.895353) (xy 167.430579 -290.858516) (xy 167.404276 -290.81692)
			(xy 167.384985 -290.771644) (xy 167.373208 -290.72386) (xy 167.369248 -290.674806) (xy 167.0304 -290.674806)
			(xy 167.029905 -290.699413) (xy 167.02201 -290.74799) (xy 167.006426 -290.794671) (xy 166.983555 -290.838248)
			(xy 166.95399 -290.877592) (xy 166.918497 -290.911684) (xy 166.877994 -290.93964) (xy 166.833532 -290.960738)
			(xy 166.786261 -290.97443) (xy 166.737406 -290.980362) (xy 166.688231 -290.978381) (xy 166.640012 -290.968537)
			(xy 166.593996 -290.951085) (xy 166.551375 -290.926478) (xy 166.513254 -290.895353) (xy 166.480619 -290.858516)
			(xy 166.454316 -290.81692) (xy 166.435025 -290.771644) (xy 166.423248 -290.72386) (xy 166.419288 -290.674806)
			(xy 166.080186 -290.674806) (xy 166.079691 -290.699413) (xy 166.071796 -290.74799) (xy 166.056212 -290.794671)
			(xy 166.033341 -290.838248) (xy 166.003776 -290.877592) (xy 165.968283 -290.911684) (xy 165.92778 -290.93964)
			(xy 165.883318 -290.960738) (xy 165.836047 -290.97443) (xy 165.787192 -290.980362) (xy 165.738017 -290.978381)
			(xy 165.689798 -290.968537) (xy 165.643782 -290.951085) (xy 165.601161 -290.926478) (xy 165.56304 -290.895353)
			(xy 165.530405 -290.858516) (xy 165.504102 -290.81692) (xy 165.484811 -290.771644) (xy 165.473034 -290.72386)
			(xy 165.469074 -290.674806) (xy 164.180266 -290.674806) (xy 164.179771 -290.699413) (xy 164.171876 -290.74799)
			(xy 164.156292 -290.794671) (xy 164.133421 -290.838248) (xy 164.103856 -290.877592) (xy 164.068363 -290.911684)
			(xy 164.02786 -290.93964) (xy 163.983398 -290.960738) (xy 163.936127 -290.97443) (xy 163.887272 -290.980362)
			(xy 163.838097 -290.978381) (xy 163.789878 -290.968537) (xy 163.743862 -290.951085) (xy 163.701241 -290.926478)
			(xy 163.66312 -290.895353) (xy 163.630485 -290.858516) (xy 163.604182 -290.81692) (xy 163.584891 -290.771644)
			(xy 163.573114 -290.72386) (xy 163.569154 -290.674806) (xy 163.230306 -290.674806) (xy 163.229811 -290.699413)
			(xy 163.221916 -290.74799) (xy 163.206332 -290.794671) (xy 163.183461 -290.838248) (xy 163.153896 -290.877592)
			(xy 163.118403 -290.911684) (xy 163.0779 -290.93964) (xy 163.033438 -290.960738) (xy 162.986167 -290.97443)
			(xy 162.937312 -290.980362) (xy 162.888137 -290.978381) (xy 162.839918 -290.968537) (xy 162.793902 -290.951085)
			(xy 162.751281 -290.926478) (xy 162.71316 -290.895353) (xy 162.680525 -290.858516) (xy 162.654222 -290.81692)
			(xy 162.634931 -290.771644) (xy 162.623154 -290.72386) (xy 162.619194 -290.674806) (xy 162.280346 -290.674806)
			(xy 162.279851 -290.699413) (xy 162.271956 -290.74799) (xy 162.256372 -290.794671) (xy 162.233501 -290.838248)
			(xy 162.203936 -290.877592) (xy 162.168443 -290.911684) (xy 162.12794 -290.93964) (xy 162.083478 -290.960738)
			(xy 162.036207 -290.97443) (xy 161.987352 -290.980362) (xy 161.938177 -290.978381) (xy 161.889958 -290.968537)
			(xy 161.843942 -290.951085) (xy 161.801321 -290.926478) (xy 161.7632 -290.895353) (xy 161.730565 -290.858516)
			(xy 161.704262 -290.81692) (xy 161.684971 -290.771644) (xy 161.673194 -290.72386) (xy 161.669234 -290.674806)
			(xy 161.330386 -290.674806) (xy 161.329891 -290.699413) (xy 161.321996 -290.74799) (xy 161.306412 -290.794671)
			(xy 161.283541 -290.838248) (xy 161.253976 -290.877592) (xy 161.218483 -290.911684) (xy 161.17798 -290.93964)
			(xy 161.133518 -290.960738) (xy 161.086247 -290.97443) (xy 161.037392 -290.980362) (xy 160.988217 -290.978381)
			(xy 160.939998 -290.968537) (xy 160.893982 -290.951085) (xy 160.851361 -290.926478) (xy 160.81324 -290.895353)
			(xy 160.780605 -290.858516) (xy 160.754302 -290.81692) (xy 160.735011 -290.771644) (xy 160.723234 -290.72386)
			(xy 160.719274 -290.674806) (xy 160.380172 -290.674806) (xy 160.379677 -290.699413) (xy 160.371782 -290.74799)
			(xy 160.356198 -290.794671) (xy 160.333327 -290.838248) (xy 160.303762 -290.877592) (xy 160.268269 -290.911684)
			(xy 160.227766 -290.93964) (xy 160.183304 -290.960738) (xy 160.136033 -290.97443) (xy 160.087178 -290.980362)
			(xy 160.038003 -290.978381) (xy 159.989784 -290.968537) (xy 159.943768 -290.951085) (xy 159.901147 -290.926478)
			(xy 159.863026 -290.895353) (xy 159.830391 -290.858516) (xy 159.804088 -290.81692) (xy 159.784797 -290.771644)
			(xy 159.77302 -290.72386) (xy 159.76906 -290.674806) (xy 159.430212 -290.674806) (xy 159.429717 -290.699413)
			(xy 159.421822 -290.74799) (xy 159.406238 -290.794671) (xy 159.383367 -290.838248) (xy 159.353802 -290.877592)
			(xy 159.318309 -290.911684) (xy 159.277806 -290.93964) (xy 159.233344 -290.960738) (xy 159.186073 -290.97443)
			(xy 159.137218 -290.980362) (xy 159.088043 -290.978381) (xy 159.039824 -290.968537) (xy 158.993808 -290.951085)
			(xy 158.951187 -290.926478) (xy 158.913066 -290.895353) (xy 158.880431 -290.858516) (xy 158.854128 -290.81692)
			(xy 158.834837 -290.771644) (xy 158.82306 -290.72386) (xy 158.8191 -290.674806) (xy 158.480252 -290.674806)
			(xy 158.479757 -290.699413) (xy 158.471862 -290.74799) (xy 158.456278 -290.794671) (xy 158.433407 -290.838248)
			(xy 158.403842 -290.877592) (xy 158.368349 -290.911684) (xy 158.327846 -290.93964) (xy 158.283384 -290.960738)
			(xy 158.236113 -290.97443) (xy 158.187258 -290.980362) (xy 158.138083 -290.978381) (xy 158.089864 -290.968537)
			(xy 158.043848 -290.951085) (xy 158.001227 -290.926478) (xy 157.963106 -290.895353) (xy 157.930471 -290.858516)
			(xy 157.904168 -290.81692) (xy 157.884877 -290.771644) (xy 157.8731 -290.72386) (xy 157.86914 -290.674806)
			(xy 157.530292 -290.674806) (xy 157.529797 -290.699413) (xy 157.521902 -290.74799) (xy 157.506318 -290.794671)
			(xy 157.483447 -290.838248) (xy 157.453882 -290.877592) (xy 157.418389 -290.911684) (xy 157.377886 -290.93964)
			(xy 157.333424 -290.960738) (xy 157.286153 -290.97443) (xy 157.237298 -290.980362) (xy 157.188123 -290.978381)
			(xy 157.139904 -290.968537) (xy 157.093888 -290.951085) (xy 157.051267 -290.926478) (xy 157.013146 -290.895353)
			(xy 156.980511 -290.858516) (xy 156.954208 -290.81692) (xy 156.934917 -290.771644) (xy 156.92314 -290.72386)
			(xy 156.91918 -290.674806) (xy 154.680412 -290.674806) (xy 154.679917 -290.699413) (xy 154.672022 -290.74799)
			(xy 154.656438 -290.794671) (xy 154.633567 -290.838248) (xy 154.604002 -290.877592) (xy 154.568509 -290.911684)
			(xy 154.528006 -290.93964) (xy 154.483544 -290.960738) (xy 154.436273 -290.97443) (xy 154.387418 -290.980362)
			(xy 154.338243 -290.978381) (xy 154.290024 -290.968537) (xy 154.244008 -290.951085) (xy 154.201387 -290.926478)
			(xy 154.163266 -290.895353) (xy 154.130631 -290.858516) (xy 154.104328 -290.81692) (xy 154.085037 -290.771644)
			(xy 154.07326 -290.72386) (xy 154.0693 -290.674806) (xy 153.730198 -290.674806) (xy 153.729703 -290.699413)
			(xy 153.721808 -290.74799) (xy 153.706224 -290.794671) (xy 153.683353 -290.838248) (xy 153.653788 -290.877592)
			(xy 153.618295 -290.911684) (xy 153.577792 -290.93964) (xy 153.53333 -290.960738) (xy 153.486059 -290.97443)
			(xy 153.437204 -290.980362) (xy 153.388029 -290.978381) (xy 153.33981 -290.968537) (xy 153.293794 -290.951085)
			(xy 153.251173 -290.926478) (xy 153.213052 -290.895353) (xy 153.180417 -290.858516) (xy 153.154114 -290.81692)
			(xy 153.134823 -290.771644) (xy 153.123046 -290.72386) (xy 153.119086 -290.674806) (xy 152.780238 -290.674806)
			(xy 152.779743 -290.699413) (xy 152.771848 -290.74799) (xy 152.756264 -290.794671) (xy 152.733393 -290.838248)
			(xy 152.703828 -290.877592) (xy 152.668335 -290.911684) (xy 152.627832 -290.93964) (xy 152.58337 -290.960738)
			(xy 152.536099 -290.97443) (xy 152.487244 -290.980362) (xy 152.438069 -290.978381) (xy 152.38985 -290.968537)
			(xy 152.343834 -290.951085) (xy 152.301213 -290.926478) (xy 152.263092 -290.895353) (xy 152.230457 -290.858516)
			(xy 152.204154 -290.81692) (xy 152.184863 -290.771644) (xy 152.173086 -290.72386) (xy 152.169126 -290.674806)
			(xy 150.128581 -290.674806) (xy 150.11703 -290.676077) (xy 150.061296 -290.67404) (xy 150.006453 -290.66391)
			(xy 149.953669 -290.645903) (xy 149.904069 -290.620402) (xy 149.858711 -290.587951) (xy 149.818562 -290.549242)
			(xy 149.784476 -290.505099) (xy 149.75718 -290.456464) (xy 149.737257 -290.404373) (xy 149.725131 -290.349936)
			(xy 149.72106 -290.294314) (xy 149.598126 -290.294314) (xy 149.597617 -290.3222) (xy 149.589497 -290.377376)
			(xy 149.573429 -290.430783) (xy 149.549757 -290.48128) (xy 149.518984 -290.527793) (xy 149.481767 -290.56933)
			(xy 149.438899 -290.605005) (xy 149.391293 -290.634059) (xy 149.339964 -290.655871) (xy 149.286007 -290.669977)
			(xy 149.23057 -290.676077) (xy 149.174836 -290.67404) (xy 149.119993 -290.66391) (xy 149.067209 -290.645903)
			(xy 149.017609 -290.620402) (xy 148.972251 -290.587951) (xy 148.932102 -290.549242) (xy 148.898016 -290.505099)
			(xy 148.87072 -290.456464) (xy 148.850797 -290.404373) (xy 148.838671 -290.349936) (xy 148.8346 -290.294314)
			(xy 148.201126 -290.294314) (xy 148.20064 -290.321565) (xy 148.192884 -290.375513) (xy 148.177529 -290.427808)
			(xy 148.154887 -290.477385) (xy 148.125421 -290.523235) (xy 148.08973 -290.564426) (xy 148.048539 -290.600117)
			(xy 148.002689 -290.629583) (xy 147.953112 -290.652225) (xy 147.900817 -290.66758) (xy 147.846869 -290.675336)
			(xy 147.792367 -290.675336) (xy 147.738419 -290.66758) (xy 147.686124 -290.652225) (xy 147.636547 -290.629583)
			(xy 147.590697 -290.600117) (xy 147.549506 -290.564426) (xy 147.513815 -290.523235) (xy 147.484349 -290.477385)
			(xy 147.461707 -290.427808) (xy 147.446352 -290.375513) (xy 147.438596 -290.321565) (xy 147.43811 -290.294314)
			(xy 136.349994 -290.294314) (xy 136.349994 -291.430456) (xy 141.911576 -291.430456) (xy 141.915647 -291.374834)
			(xy 141.927773 -291.320397) (xy 141.947696 -291.268306) (xy 141.974992 -291.219671) (xy 142.009078 -291.175528)
			(xy 142.049227 -291.136819) (xy 142.094585 -291.104368) (xy 142.144185 -291.078867) (xy 142.196969 -291.06086)
			(xy 142.251812 -291.05073) (xy 142.307546 -291.048693) (xy 142.362983 -291.054793) (xy 142.41694 -291.068899)
			(xy 142.468269 -291.090711) (xy 142.515875 -291.119765) (xy 142.558743 -291.15544) (xy 142.59596 -291.196977)
			(xy 142.626733 -291.24349) (xy 142.650405 -291.293987) (xy 142.666473 -291.347394) (xy 142.674593 -291.40257)
			(xy 142.675102 -291.430456) (xy 143.396714 -291.430456) (xy 143.400785 -291.374834) (xy 143.412911 -291.320397)
			(xy 143.432834 -291.268306) (xy 143.46013 -291.219671) (xy 143.494216 -291.175528) (xy 143.534365 -291.136819)
			(xy 143.579723 -291.104368) (xy 143.629323 -291.078867) (xy 143.682107 -291.06086) (xy 143.73695 -291.05073)
			(xy 143.792684 -291.048693) (xy 143.848121 -291.054793) (xy 143.902078 -291.068899) (xy 143.953407 -291.090711)
			(xy 144.001013 -291.119765) (xy 144.043881 -291.15544) (xy 144.081098 -291.196977) (xy 144.111871 -291.24349)
			(xy 144.135543 -291.293987) (xy 144.151611 -291.347394) (xy 144.159731 -291.40257) (xy 144.16024 -291.430456)
			(xy 144.159731 -291.458342) (xy 144.151611 -291.513518) (xy 144.135543 -291.566925) (xy 144.111871 -291.617422)
			(xy 144.107012 -291.624766) (xy 152.169126 -291.624766) (xy 152.173086 -291.575712) (xy 152.184863 -291.527928)
			(xy 152.204154 -291.482652) (xy 152.230457 -291.441056) (xy 152.263092 -291.404219) (xy 152.301213 -291.373094)
			(xy 152.343834 -291.348487) (xy 152.38985 -291.331035) (xy 152.438069 -291.321191) (xy 152.487244 -291.31921)
			(xy 152.536099 -291.325142) (xy 152.58337 -291.338834) (xy 152.627832 -291.359932) (xy 152.668335 -291.387888)
			(xy 152.703828 -291.42198) (xy 152.733393 -291.461324) (xy 152.756264 -291.504901) (xy 152.771848 -291.551582)
			(xy 152.779743 -291.600159) (xy 152.780238 -291.624766) (xy 153.119086 -291.624766) (xy 153.123046 -291.575712)
			(xy 153.134823 -291.527928) (xy 153.154114 -291.482652) (xy 153.180417 -291.441056) (xy 153.213052 -291.404219)
			(xy 153.251173 -291.373094) (xy 153.293794 -291.348487) (xy 153.33981 -291.331035) (xy 153.388029 -291.321191)
			(xy 153.437204 -291.31921) (xy 153.486059 -291.325142) (xy 153.53333 -291.338834) (xy 153.577792 -291.359932)
			(xy 153.618295 -291.387888) (xy 153.653788 -291.42198) (xy 153.683353 -291.461324) (xy 153.706224 -291.504901)
			(xy 153.721808 -291.551582) (xy 153.729703 -291.600159) (xy 153.730198 -291.624766) (xy 154.0693 -291.624766)
			(xy 154.07326 -291.575712) (xy 154.085037 -291.527928) (xy 154.104328 -291.482652) (xy 154.130631 -291.441056)
			(xy 154.163266 -291.404219) (xy 154.201387 -291.373094) (xy 154.244008 -291.348487) (xy 154.290024 -291.331035)
			(xy 154.338243 -291.321191) (xy 154.387418 -291.31921) (xy 154.436273 -291.325142) (xy 154.483544 -291.338834)
			(xy 154.528006 -291.359932) (xy 154.568509 -291.387888) (xy 154.604002 -291.42198) (xy 154.633567 -291.461324)
			(xy 154.656438 -291.504901) (xy 154.672022 -291.551582) (xy 154.679917 -291.600159) (xy 154.680412 -291.624766)
			(xy 156.91918 -291.624766) (xy 156.92314 -291.575712) (xy 156.934917 -291.527928) (xy 156.954208 -291.482652)
			(xy 156.980511 -291.441056) (xy 157.013146 -291.404219) (xy 157.051267 -291.373094) (xy 157.093888 -291.348487)
			(xy 157.139904 -291.331035) (xy 157.188123 -291.321191) (xy 157.237298 -291.31921) (xy 157.286153 -291.325142)
			(xy 157.333424 -291.338834) (xy 157.377886 -291.359932) (xy 157.418389 -291.387888) (xy 157.453882 -291.42198)
			(xy 157.483447 -291.461324) (xy 157.506318 -291.504901) (xy 157.521902 -291.551582) (xy 157.529797 -291.600159)
			(xy 157.530292 -291.624766) (xy 157.86914 -291.624766) (xy 157.8731 -291.575712) (xy 157.884877 -291.527928)
			(xy 157.904168 -291.482652) (xy 157.930471 -291.441056) (xy 157.963106 -291.404219) (xy 158.001227 -291.373094)
			(xy 158.043848 -291.348487) (xy 158.089864 -291.331035) (xy 158.138083 -291.321191) (xy 158.187258 -291.31921)
			(xy 158.236113 -291.325142) (xy 158.283384 -291.338834) (xy 158.327846 -291.359932) (xy 158.368349 -291.387888)
			(xy 158.403842 -291.42198) (xy 158.433407 -291.461324) (xy 158.456278 -291.504901) (xy 158.471862 -291.551582)
			(xy 158.479757 -291.600159) (xy 158.480252 -291.624766) (xy 158.8191 -291.624766) (xy 158.82306 -291.575712)
			(xy 158.834837 -291.527928) (xy 158.854128 -291.482652) (xy 158.880431 -291.441056) (xy 158.913066 -291.404219)
			(xy 158.951187 -291.373094) (xy 158.993808 -291.348487) (xy 159.039824 -291.331035) (xy 159.088043 -291.321191)
			(xy 159.137218 -291.31921) (xy 159.186073 -291.325142) (xy 159.233344 -291.338834) (xy 159.277806 -291.359932)
			(xy 159.318309 -291.387888) (xy 159.353802 -291.42198) (xy 159.383367 -291.461324) (xy 159.406238 -291.504901)
			(xy 159.421822 -291.551582) (xy 159.429717 -291.600159) (xy 159.430212 -291.624766) (xy 159.76906 -291.624766)
			(xy 159.77302 -291.575712) (xy 159.784797 -291.527928) (xy 159.804088 -291.482652) (xy 159.830391 -291.441056)
			(xy 159.863026 -291.404219) (xy 159.901147 -291.373094) (xy 159.943768 -291.348487) (xy 159.989784 -291.331035)
			(xy 160.038003 -291.321191) (xy 160.087178 -291.31921) (xy 160.136033 -291.325142) (xy 160.183304 -291.338834)
			(xy 160.227766 -291.359932) (xy 160.268269 -291.387888) (xy 160.303762 -291.42198) (xy 160.333327 -291.461324)
			(xy 160.356198 -291.504901) (xy 160.371782 -291.551582) (xy 160.379677 -291.600159) (xy 160.380172 -291.624766)
			(xy 160.719274 -291.624766) (xy 160.723234 -291.575712) (xy 160.735011 -291.527928) (xy 160.754302 -291.482652)
			(xy 160.780605 -291.441056) (xy 160.81324 -291.404219) (xy 160.851361 -291.373094) (xy 160.893982 -291.348487)
			(xy 160.939998 -291.331035) (xy 160.988217 -291.321191) (xy 161.037392 -291.31921) (xy 161.086247 -291.325142)
			(xy 161.133518 -291.338834) (xy 161.17798 -291.359932) (xy 161.218483 -291.387888) (xy 161.253976 -291.42198)
			(xy 161.283541 -291.461324) (xy 161.306412 -291.504901) (xy 161.321996 -291.551582) (xy 161.329891 -291.600159)
			(xy 161.330386 -291.624766) (xy 161.669234 -291.624766) (xy 161.673194 -291.575712) (xy 161.684971 -291.527928)
			(xy 161.704262 -291.482652) (xy 161.730565 -291.441056) (xy 161.7632 -291.404219) (xy 161.801321 -291.373094)
			(xy 161.843942 -291.348487) (xy 161.889958 -291.331035) (xy 161.938177 -291.321191) (xy 161.987352 -291.31921)
			(xy 162.036207 -291.325142) (xy 162.083478 -291.338834) (xy 162.12794 -291.359932) (xy 162.168443 -291.387888)
			(xy 162.203936 -291.42198) (xy 162.233501 -291.461324) (xy 162.256372 -291.504901) (xy 162.271956 -291.551582)
			(xy 162.279851 -291.600159) (xy 162.280346 -291.624766) (xy 163.569154 -291.624766) (xy 163.573114 -291.575712)
			(xy 163.584891 -291.527928) (xy 163.604182 -291.482652) (xy 163.630485 -291.441056) (xy 163.66312 -291.404219)
			(xy 163.701241 -291.373094) (xy 163.743862 -291.348487) (xy 163.789878 -291.331035) (xy 163.838097 -291.321191)
			(xy 163.887272 -291.31921) (xy 163.936127 -291.325142) (xy 163.983398 -291.338834) (xy 164.02786 -291.359932)
			(xy 164.068363 -291.387888) (xy 164.103856 -291.42198) (xy 164.133421 -291.461324) (xy 164.156292 -291.504901)
			(xy 164.171876 -291.551582) (xy 164.179771 -291.600159) (xy 164.180266 -291.624766) (xy 164.519114 -291.624766)
			(xy 164.523074 -291.575712) (xy 164.534851 -291.527928) (xy 164.554142 -291.482652) (xy 164.580445 -291.441056)
			(xy 164.61308 -291.404219) (xy 164.651201 -291.373094) (xy 164.693822 -291.348487) (xy 164.739838 -291.331035)
			(xy 164.788057 -291.321191) (xy 164.837232 -291.31921) (xy 164.886087 -291.325142) (xy 164.933358 -291.338834)
			(xy 164.97782 -291.359932) (xy 165.018323 -291.387888) (xy 165.053816 -291.42198) (xy 165.083381 -291.461324)
			(xy 165.106252 -291.504901) (xy 165.121836 -291.551582) (xy 165.129731 -291.600159) (xy 165.130226 -291.624766)
			(xy 166.419288 -291.624766) (xy 166.423248 -291.575712) (xy 166.435025 -291.527928) (xy 166.454316 -291.482652)
			(xy 166.480619 -291.441056) (xy 166.513254 -291.404219) (xy 166.551375 -291.373094) (xy 166.593996 -291.348487)
			(xy 166.640012 -291.331035) (xy 166.688231 -291.321191) (xy 166.737406 -291.31921) (xy 166.786261 -291.325142)
			(xy 166.833532 -291.338834) (xy 166.877994 -291.359932) (xy 166.918497 -291.387888) (xy 166.95399 -291.42198)
			(xy 166.983555 -291.461324) (xy 167.006426 -291.504901) (xy 167.02201 -291.551582) (xy 167.029905 -291.600159)
			(xy 167.0304 -291.624766) (xy 167.369248 -291.624766) (xy 167.373208 -291.575712) (xy 167.384985 -291.527928)
			(xy 167.404276 -291.482652) (xy 167.430579 -291.441056) (xy 167.463214 -291.404219) (xy 167.501335 -291.373094)
			(xy 167.543956 -291.348487) (xy 167.589972 -291.331035) (xy 167.638191 -291.321191) (xy 167.687366 -291.31921)
			(xy 167.736221 -291.325142) (xy 167.783492 -291.338834) (xy 167.827954 -291.359932) (xy 167.868457 -291.387888)
			(xy 167.90395 -291.42198) (xy 167.933515 -291.461324) (xy 167.956386 -291.504901) (xy 167.97197 -291.551582)
			(xy 167.979865 -291.600159) (xy 167.98036 -291.624766) (xy 168.319208 -291.624766) (xy 168.323168 -291.575712)
			(xy 168.334945 -291.527928) (xy 168.354236 -291.482652) (xy 168.380539 -291.441056) (xy 168.413174 -291.404219)
			(xy 168.451295 -291.373094) (xy 168.493916 -291.348487) (xy 168.539932 -291.331035) (xy 168.588151 -291.321191)
			(xy 168.637326 -291.31921) (xy 168.686181 -291.325142) (xy 168.733452 -291.338834) (xy 168.777914 -291.359932)
			(xy 168.818417 -291.387888) (xy 168.85391 -291.42198) (xy 168.883475 -291.461324) (xy 168.906346 -291.504901)
			(xy 168.92193 -291.551582) (xy 168.929825 -291.600159) (xy 168.93032 -291.624766) (xy 169.269168 -291.624766)
			(xy 169.273128 -291.575712) (xy 169.284905 -291.527928) (xy 169.304196 -291.482652) (xy 169.330499 -291.441056)
			(xy 169.363134 -291.404219) (xy 169.401255 -291.373094) (xy 169.443876 -291.348487) (xy 169.489892 -291.331035)
			(xy 169.538111 -291.321191) (xy 169.587286 -291.31921) (xy 169.636141 -291.325142) (xy 169.683412 -291.338834)
			(xy 169.727874 -291.359932) (xy 169.768377 -291.387888) (xy 169.80387 -291.42198) (xy 169.833435 -291.461324)
			(xy 169.856306 -291.504901) (xy 169.87189 -291.551582) (xy 169.879785 -291.600159) (xy 169.88028 -291.624766)
			(xy 170.219128 -291.624766) (xy 170.223088 -291.575712) (xy 170.234865 -291.527928) (xy 170.254156 -291.482652)
			(xy 170.280459 -291.441056) (xy 170.313094 -291.404219) (xy 170.351215 -291.373094) (xy 170.393836 -291.348487)
			(xy 170.439852 -291.331035) (xy 170.488071 -291.321191) (xy 170.537246 -291.31921) (xy 170.586101 -291.325142)
			(xy 170.633372 -291.338834) (xy 170.677834 -291.359932) (xy 170.718337 -291.387888) (xy 170.75383 -291.42198)
			(xy 170.783395 -291.461324) (xy 170.806266 -291.504901) (xy 170.82185 -291.551582) (xy 170.829745 -291.600159)
			(xy 170.83024 -291.624766) (xy 171.169088 -291.624766) (xy 171.173048 -291.575712) (xy 171.184825 -291.527928)
			(xy 171.204116 -291.482652) (xy 171.230419 -291.441056) (xy 171.263054 -291.404219) (xy 171.301175 -291.373094)
			(xy 171.343796 -291.348487) (xy 171.389812 -291.331035) (xy 171.438031 -291.321191) (xy 171.487206 -291.31921)
			(xy 171.536061 -291.325142) (xy 171.583332 -291.338834) (xy 171.627794 -291.359932) (xy 171.668297 -291.387888)
			(xy 171.70379 -291.42198) (xy 171.733355 -291.461324) (xy 171.756226 -291.504901) (xy 171.77181 -291.551582)
			(xy 171.779705 -291.600159) (xy 171.7802 -291.624766) (xy 172.119048 -291.624766) (xy 172.123008 -291.575712)
			(xy 172.134785 -291.527928) (xy 172.154076 -291.482652) (xy 172.180379 -291.441056) (xy 172.213014 -291.404219)
			(xy 172.251135 -291.373094) (xy 172.293756 -291.348487) (xy 172.339772 -291.331035) (xy 172.387991 -291.321191)
			(xy 172.437166 -291.31921) (xy 172.486021 -291.325142) (xy 172.533292 -291.338834) (xy 172.577754 -291.359932)
			(xy 172.618257 -291.387888) (xy 172.65375 -291.42198) (xy 172.683315 -291.461324) (xy 172.706186 -291.504901)
			(xy 172.72177 -291.551582) (xy 172.729665 -291.600159) (xy 172.73016 -291.624766) (xy 173.069262 -291.624766)
			(xy 173.073222 -291.575712) (xy 173.084999 -291.527928) (xy 173.10429 -291.482652) (xy 173.130593 -291.441056)
			(xy 173.163228 -291.404219) (xy 173.201349 -291.373094) (xy 173.24397 -291.348487) (xy 173.289986 -291.331035)
			(xy 173.338205 -291.321191) (xy 173.38738 -291.31921) (xy 173.436235 -291.325142) (xy 173.483506 -291.338834)
			(xy 173.527968 -291.359932) (xy 173.568471 -291.387888) (xy 173.603964 -291.42198) (xy 173.633529 -291.461324)
			(xy 173.6564 -291.504901) (xy 173.671984 -291.551582) (xy 173.679879 -291.600159) (xy 173.680374 -291.624766)
			(xy 174.019222 -291.624766) (xy 174.023182 -291.575712) (xy 174.034959 -291.527928) (xy 174.05425 -291.482652)
			(xy 174.080553 -291.441056) (xy 174.113188 -291.404219) (xy 174.151309 -291.373094) (xy 174.19393 -291.348487)
			(xy 174.239946 -291.331035) (xy 174.288165 -291.321191) (xy 174.33734 -291.31921) (xy 174.386195 -291.325142)
			(xy 174.433466 -291.338834) (xy 174.477928 -291.359932) (xy 174.518431 -291.387888) (xy 174.553924 -291.42198)
			(xy 174.583489 -291.461324) (xy 174.60636 -291.504901) (xy 174.621944 -291.551582) (xy 174.629839 -291.600159)
			(xy 174.630334 -291.624766) (xy 175.919142 -291.624766) (xy 175.923102 -291.575712) (xy 175.934879 -291.527928)
			(xy 175.95417 -291.482652) (xy 175.980473 -291.441056) (xy 176.013108 -291.404219) (xy 176.051229 -291.373094)
			(xy 176.09385 -291.348487) (xy 176.139866 -291.331035) (xy 176.188085 -291.321191) (xy 176.23726 -291.31921)
			(xy 176.286115 -291.325142) (xy 176.333386 -291.338834) (xy 176.377848 -291.359932) (xy 176.418351 -291.387888)
			(xy 176.453844 -291.42198) (xy 176.483409 -291.461324) (xy 176.50628 -291.504901) (xy 176.521864 -291.551582)
			(xy 176.529759 -291.600159) (xy 176.530254 -291.624766) (xy 176.869102 -291.624766) (xy 176.873062 -291.575712)
			(xy 176.884839 -291.527928) (xy 176.90413 -291.482652) (xy 176.930433 -291.441056) (xy 176.963068 -291.404219)
			(xy 177.001189 -291.373094) (xy 177.04381 -291.348487) (xy 177.089826 -291.331035) (xy 177.138045 -291.321191)
			(xy 177.18722 -291.31921) (xy 177.236075 -291.325142) (xy 177.283346 -291.338834) (xy 177.327808 -291.359932)
			(xy 177.368311 -291.387888) (xy 177.403804 -291.42198) (xy 177.433369 -291.461324) (xy 177.45624 -291.504901)
			(xy 177.471824 -291.551582) (xy 177.479719 -291.600159) (xy 177.480214 -291.624766) (xy 177.819062 -291.624766)
			(xy 177.823022 -291.575712) (xy 177.834799 -291.527928) (xy 177.85409 -291.482652) (xy 177.880393 -291.441056)
			(xy 177.913028 -291.404219) (xy 177.951149 -291.373094) (xy 177.99377 -291.348487) (xy 178.039786 -291.331035)
			(xy 178.088005 -291.321191) (xy 178.13718 -291.31921) (xy 178.186035 -291.325142) (xy 178.233306 -291.338834)
			(xy 178.277768 -291.359932) (xy 178.318271 -291.387888) (xy 178.353764 -291.42198) (xy 178.383329 -291.461324)
			(xy 178.4062 -291.504901) (xy 178.421784 -291.551582) (xy 178.429679 -291.600159) (xy 178.430174 -291.624766)
			(xy 178.769276 -291.624766) (xy 178.773236 -291.575712) (xy 178.785013 -291.527928) (xy 178.804304 -291.482652)
			(xy 178.830607 -291.441056) (xy 178.863242 -291.404219) (xy 178.901363 -291.373094) (xy 178.943984 -291.348487)
			(xy 178.99 -291.331035) (xy 179.038219 -291.321191) (xy 179.087394 -291.31921) (xy 179.136249 -291.325142)
			(xy 179.18352 -291.338834) (xy 179.227982 -291.359932) (xy 179.268485 -291.387888) (xy 179.303978 -291.42198)
			(xy 179.333543 -291.461324) (xy 179.356414 -291.504901) (xy 179.371998 -291.551582) (xy 179.379893 -291.600159)
			(xy 179.380388 -291.624766) (xy 179.719236 -291.624766) (xy 179.723196 -291.575712) (xy 179.734973 -291.527928)
			(xy 179.754264 -291.482652) (xy 179.780567 -291.441056) (xy 179.813202 -291.404219) (xy 179.851323 -291.373094)
			(xy 179.893944 -291.348487) (xy 179.93996 -291.331035) (xy 179.988179 -291.321191) (xy 180.037354 -291.31921)
			(xy 180.086209 -291.325142) (xy 180.13348 -291.338834) (xy 180.177942 -291.359932) (xy 180.218445 -291.387888)
			(xy 180.253938 -291.42198) (xy 180.283503 -291.461324) (xy 180.306374 -291.504901) (xy 180.321958 -291.551582)
			(xy 180.329853 -291.600159) (xy 180.330348 -291.624766) (xy 180.669196 -291.624766) (xy 180.673156 -291.575712)
			(xy 180.684933 -291.527928) (xy 180.704224 -291.482652) (xy 180.730527 -291.441056) (xy 180.763162 -291.404219)
			(xy 180.801283 -291.373094) (xy 180.843904 -291.348487) (xy 180.88992 -291.331035) (xy 180.938139 -291.321191)
			(xy 180.987314 -291.31921) (xy 181.036169 -291.325142) (xy 181.08344 -291.338834) (xy 181.127902 -291.359932)
			(xy 181.168405 -291.387888) (xy 181.203898 -291.42198) (xy 181.233463 -291.461324) (xy 181.256334 -291.504901)
			(xy 181.271918 -291.551582) (xy 181.279813 -291.600159) (xy 181.280308 -291.624766) (xy 181.619156 -291.624766)
			(xy 181.623116 -291.575712) (xy 181.634893 -291.527928) (xy 181.654184 -291.482652) (xy 181.680487 -291.441056)
			(xy 181.713122 -291.404219) (xy 181.751243 -291.373094) (xy 181.793864 -291.348487) (xy 181.83988 -291.331035)
			(xy 181.888099 -291.321191) (xy 181.937274 -291.31921) (xy 181.986129 -291.325142) (xy 182.0334 -291.338834)
			(xy 182.077862 -291.359932) (xy 182.118365 -291.387888) (xy 182.153858 -291.42198) (xy 182.183423 -291.461324)
			(xy 182.206294 -291.504901) (xy 182.221878 -291.551582) (xy 182.229773 -291.600159) (xy 182.230268 -291.624766)
			(xy 182.569116 -291.624766) (xy 182.573076 -291.575712) (xy 182.584853 -291.527928) (xy 182.604144 -291.482652)
			(xy 182.630447 -291.441056) (xy 182.663082 -291.404219) (xy 182.701203 -291.373094) (xy 182.743824 -291.348487)
			(xy 182.78984 -291.331035) (xy 182.838059 -291.321191) (xy 182.887234 -291.31921) (xy 182.936089 -291.325142)
			(xy 182.98336 -291.338834) (xy 183.027822 -291.359932) (xy 183.068325 -291.387888) (xy 183.103818 -291.42198)
			(xy 183.133383 -291.461324) (xy 183.156254 -291.504901) (xy 183.171838 -291.551582) (xy 183.179733 -291.600159)
			(xy 183.180228 -291.624766) (xy 183.519076 -291.624766) (xy 183.523036 -291.575712) (xy 183.534813 -291.527928)
			(xy 183.554104 -291.482652) (xy 183.580407 -291.441056) (xy 183.613042 -291.404219) (xy 183.651163 -291.373094)
			(xy 183.693784 -291.348487) (xy 183.7398 -291.331035) (xy 183.788019 -291.321191) (xy 183.837194 -291.31921)
			(xy 183.886049 -291.325142) (xy 183.93332 -291.338834) (xy 183.977782 -291.359932) (xy 184.018285 -291.387888)
			(xy 184.053778 -291.42198) (xy 184.083343 -291.461324) (xy 184.106214 -291.504901) (xy 184.121798 -291.551582)
			(xy 184.129693 -291.600159) (xy 184.130188 -291.624766) (xy 184.469036 -291.624766) (xy 184.472996 -291.575712)
			(xy 184.484773 -291.527928) (xy 184.504064 -291.482652) (xy 184.530367 -291.441056) (xy 184.563002 -291.404219)
			(xy 184.601123 -291.373094) (xy 184.643744 -291.348487) (xy 184.68976 -291.331035) (xy 184.737979 -291.321191)
			(xy 184.787154 -291.31921) (xy 184.836009 -291.325142) (xy 184.88328 -291.338834) (xy 184.927742 -291.359932)
			(xy 184.968245 -291.387888) (xy 185.003738 -291.42198) (xy 185.033303 -291.461324) (xy 185.056174 -291.504901)
			(xy 185.071758 -291.551582) (xy 185.079653 -291.600159) (xy 185.080148 -291.624766) (xy 185.079653 -291.649373)
			(xy 185.071758 -291.69795) (xy 185.056174 -291.744631) (xy 185.033303 -291.788208) (xy 185.003738 -291.827552)
			(xy 184.968245 -291.861644) (xy 184.927742 -291.8896) (xy 184.88328 -291.910698) (xy 184.836009 -291.92439)
			(xy 184.787154 -291.930322) (xy 184.737979 -291.928341) (xy 184.68976 -291.918497) (xy 184.643744 -291.901045)
			(xy 184.601123 -291.876438) (xy 184.563002 -291.845313) (xy 184.530367 -291.808476) (xy 184.504064 -291.76688)
			(xy 184.484773 -291.721604) (xy 184.472996 -291.67382) (xy 184.469036 -291.624766) (xy 184.130188 -291.624766)
			(xy 184.129693 -291.649373) (xy 184.121798 -291.69795) (xy 184.106214 -291.744631) (xy 184.083343 -291.788208)
			(xy 184.053778 -291.827552) (xy 184.018285 -291.861644) (xy 183.977782 -291.8896) (xy 183.93332 -291.910698)
			(xy 183.886049 -291.92439) (xy 183.837194 -291.930322) (xy 183.788019 -291.928341) (xy 183.7398 -291.918497)
			(xy 183.693784 -291.901045) (xy 183.651163 -291.876438) (xy 183.613042 -291.845313) (xy 183.580407 -291.808476)
			(xy 183.554104 -291.76688) (xy 183.534813 -291.721604) (xy 183.523036 -291.67382) (xy 183.519076 -291.624766)
			(xy 183.180228 -291.624766) (xy 183.179733 -291.649373) (xy 183.171838 -291.69795) (xy 183.156254 -291.744631)
			(xy 183.133383 -291.788208) (xy 183.103818 -291.827552) (xy 183.068325 -291.861644) (xy 183.027822 -291.8896)
			(xy 182.98336 -291.910698) (xy 182.936089 -291.92439) (xy 182.887234 -291.930322) (xy 182.838059 -291.928341)
			(xy 182.78984 -291.918497) (xy 182.743824 -291.901045) (xy 182.701203 -291.876438) (xy 182.663082 -291.845313)
			(xy 182.630447 -291.808476) (xy 182.604144 -291.76688) (xy 182.584853 -291.721604) (xy 182.573076 -291.67382)
			(xy 182.569116 -291.624766) (xy 182.230268 -291.624766) (xy 182.229773 -291.649373) (xy 182.221878 -291.69795)
			(xy 182.206294 -291.744631) (xy 182.183423 -291.788208) (xy 182.153858 -291.827552) (xy 182.118365 -291.861644)
			(xy 182.077862 -291.8896) (xy 182.0334 -291.910698) (xy 181.986129 -291.92439) (xy 181.937274 -291.930322)
			(xy 181.888099 -291.928341) (xy 181.83988 -291.918497) (xy 181.793864 -291.901045) (xy 181.751243 -291.876438)
			(xy 181.713122 -291.845313) (xy 181.680487 -291.808476) (xy 181.654184 -291.76688) (xy 181.634893 -291.721604)
			(xy 181.623116 -291.67382) (xy 181.619156 -291.624766) (xy 181.280308 -291.624766) (xy 181.279813 -291.649373)
			(xy 181.271918 -291.69795) (xy 181.256334 -291.744631) (xy 181.233463 -291.788208) (xy 181.203898 -291.827552)
			(xy 181.168405 -291.861644) (xy 181.127902 -291.8896) (xy 181.08344 -291.910698) (xy 181.036169 -291.92439)
			(xy 180.987314 -291.930322) (xy 180.938139 -291.928341) (xy 180.88992 -291.918497) (xy 180.843904 -291.901045)
			(xy 180.801283 -291.876438) (xy 180.763162 -291.845313) (xy 180.730527 -291.808476) (xy 180.704224 -291.76688)
			(xy 180.684933 -291.721604) (xy 180.673156 -291.67382) (xy 180.669196 -291.624766) (xy 180.330348 -291.624766)
			(xy 180.329853 -291.649373) (xy 180.321958 -291.69795) (xy 180.306374 -291.744631) (xy 180.283503 -291.788208)
			(xy 180.253938 -291.827552) (xy 180.218445 -291.861644) (xy 180.177942 -291.8896) (xy 180.13348 -291.910698)
			(xy 180.086209 -291.92439) (xy 180.037354 -291.930322) (xy 179.988179 -291.928341) (xy 179.93996 -291.918497)
			(xy 179.893944 -291.901045) (xy 179.851323 -291.876438) (xy 179.813202 -291.845313) (xy 179.780567 -291.808476)
			(xy 179.754264 -291.76688) (xy 179.734973 -291.721604) (xy 179.723196 -291.67382) (xy 179.719236 -291.624766)
			(xy 179.380388 -291.624766) (xy 179.379893 -291.649373) (xy 179.371998 -291.69795) (xy 179.356414 -291.744631)
			(xy 179.333543 -291.788208) (xy 179.303978 -291.827552) (xy 179.268485 -291.861644) (xy 179.227982 -291.8896)
			(xy 179.18352 -291.910698) (xy 179.136249 -291.92439) (xy 179.087394 -291.930322) (xy 179.038219 -291.928341)
			(xy 178.99 -291.918497) (xy 178.943984 -291.901045) (xy 178.901363 -291.876438) (xy 178.863242 -291.845313)
			(xy 178.830607 -291.808476) (xy 178.804304 -291.76688) (xy 178.785013 -291.721604) (xy 178.773236 -291.67382)
			(xy 178.769276 -291.624766) (xy 178.430174 -291.624766) (xy 178.429679 -291.649373) (xy 178.421784 -291.69795)
			(xy 178.4062 -291.744631) (xy 178.383329 -291.788208) (xy 178.353764 -291.827552) (xy 178.318271 -291.861644)
			(xy 178.277768 -291.8896) (xy 178.233306 -291.910698) (xy 178.186035 -291.92439) (xy 178.13718 -291.930322)
			(xy 178.088005 -291.928341) (xy 178.039786 -291.918497) (xy 177.99377 -291.901045) (xy 177.951149 -291.876438)
			(xy 177.913028 -291.845313) (xy 177.880393 -291.808476) (xy 177.85409 -291.76688) (xy 177.834799 -291.721604)
			(xy 177.823022 -291.67382) (xy 177.819062 -291.624766) (xy 177.480214 -291.624766) (xy 177.479719 -291.649373)
			(xy 177.471824 -291.69795) (xy 177.45624 -291.744631) (xy 177.433369 -291.788208) (xy 177.403804 -291.827552)
			(xy 177.368311 -291.861644) (xy 177.327808 -291.8896) (xy 177.283346 -291.910698) (xy 177.236075 -291.92439)
			(xy 177.18722 -291.930322) (xy 177.138045 -291.928341) (xy 177.089826 -291.918497) (xy 177.04381 -291.901045)
			(xy 177.001189 -291.876438) (xy 176.963068 -291.845313) (xy 176.930433 -291.808476) (xy 176.90413 -291.76688)
			(xy 176.884839 -291.721604) (xy 176.873062 -291.67382) (xy 176.869102 -291.624766) (xy 176.530254 -291.624766)
			(xy 176.529759 -291.649373) (xy 176.521864 -291.69795) (xy 176.50628 -291.744631) (xy 176.483409 -291.788208)
			(xy 176.453844 -291.827552) (xy 176.418351 -291.861644) (xy 176.377848 -291.8896) (xy 176.333386 -291.910698)
			(xy 176.286115 -291.92439) (xy 176.23726 -291.930322) (xy 176.188085 -291.928341) (xy 176.139866 -291.918497)
			(xy 176.09385 -291.901045) (xy 176.051229 -291.876438) (xy 176.013108 -291.845313) (xy 175.980473 -291.808476)
			(xy 175.95417 -291.76688) (xy 175.934879 -291.721604) (xy 175.923102 -291.67382) (xy 175.919142 -291.624766)
			(xy 174.630334 -291.624766) (xy 174.629839 -291.649373) (xy 174.621944 -291.69795) (xy 174.60636 -291.744631)
			(xy 174.583489 -291.788208) (xy 174.553924 -291.827552) (xy 174.518431 -291.861644) (xy 174.477928 -291.8896)
			(xy 174.433466 -291.910698) (xy 174.386195 -291.92439) (xy 174.33734 -291.930322) (xy 174.288165 -291.928341)
			(xy 174.239946 -291.918497) (xy 174.19393 -291.901045) (xy 174.151309 -291.876438) (xy 174.113188 -291.845313)
			(xy 174.080553 -291.808476) (xy 174.05425 -291.76688) (xy 174.034959 -291.721604) (xy 174.023182 -291.67382)
			(xy 174.019222 -291.624766) (xy 173.680374 -291.624766) (xy 173.679879 -291.649373) (xy 173.671984 -291.69795)
			(xy 173.6564 -291.744631) (xy 173.633529 -291.788208) (xy 173.603964 -291.827552) (xy 173.568471 -291.861644)
			(xy 173.527968 -291.8896) (xy 173.483506 -291.910698) (xy 173.436235 -291.92439) (xy 173.38738 -291.930322)
			(xy 173.338205 -291.928341) (xy 173.289986 -291.918497) (xy 173.24397 -291.901045) (xy 173.201349 -291.876438)
			(xy 173.163228 -291.845313) (xy 173.130593 -291.808476) (xy 173.10429 -291.76688) (xy 173.084999 -291.721604)
			(xy 173.073222 -291.67382) (xy 173.069262 -291.624766) (xy 172.73016 -291.624766) (xy 172.729665 -291.649373)
			(xy 172.72177 -291.69795) (xy 172.706186 -291.744631) (xy 172.683315 -291.788208) (xy 172.65375 -291.827552)
			(xy 172.618257 -291.861644) (xy 172.577754 -291.8896) (xy 172.533292 -291.910698) (xy 172.486021 -291.92439)
			(xy 172.437166 -291.930322) (xy 172.387991 -291.928341) (xy 172.339772 -291.918497) (xy 172.293756 -291.901045)
			(xy 172.251135 -291.876438) (xy 172.213014 -291.845313) (xy 172.180379 -291.808476) (xy 172.154076 -291.76688)
			(xy 172.134785 -291.721604) (xy 172.123008 -291.67382) (xy 172.119048 -291.624766) (xy 171.7802 -291.624766)
			(xy 171.779705 -291.649373) (xy 171.77181 -291.69795) (xy 171.756226 -291.744631) (xy 171.733355 -291.788208)
			(xy 171.70379 -291.827552) (xy 171.668297 -291.861644) (xy 171.627794 -291.8896) (xy 171.583332 -291.910698)
			(xy 171.536061 -291.92439) (xy 171.487206 -291.930322) (xy 171.438031 -291.928341) (xy 171.389812 -291.918497)
			(xy 171.343796 -291.901045) (xy 171.301175 -291.876438) (xy 171.263054 -291.845313) (xy 171.230419 -291.808476)
			(xy 171.204116 -291.76688) (xy 171.184825 -291.721604) (xy 171.173048 -291.67382) (xy 171.169088 -291.624766)
			(xy 170.83024 -291.624766) (xy 170.829745 -291.649373) (xy 170.82185 -291.69795) (xy 170.806266 -291.744631)
			(xy 170.783395 -291.788208) (xy 170.75383 -291.827552) (xy 170.718337 -291.861644) (xy 170.677834 -291.8896)
			(xy 170.633372 -291.910698) (xy 170.586101 -291.92439) (xy 170.537246 -291.930322) (xy 170.488071 -291.928341)
			(xy 170.439852 -291.918497) (xy 170.393836 -291.901045) (xy 170.351215 -291.876438) (xy 170.313094 -291.845313)
			(xy 170.280459 -291.808476) (xy 170.254156 -291.76688) (xy 170.234865 -291.721604) (xy 170.223088 -291.67382)
			(xy 170.219128 -291.624766) (xy 169.88028 -291.624766) (xy 169.879785 -291.649373) (xy 169.87189 -291.69795)
			(xy 169.856306 -291.744631) (xy 169.833435 -291.788208) (xy 169.80387 -291.827552) (xy 169.768377 -291.861644)
			(xy 169.727874 -291.8896) (xy 169.683412 -291.910698) (xy 169.636141 -291.92439) (xy 169.587286 -291.930322)
			(xy 169.538111 -291.928341) (xy 169.489892 -291.918497) (xy 169.443876 -291.901045) (xy 169.401255 -291.876438)
			(xy 169.363134 -291.845313) (xy 169.330499 -291.808476) (xy 169.304196 -291.76688) (xy 169.284905 -291.721604)
			(xy 169.273128 -291.67382) (xy 169.269168 -291.624766) (xy 168.93032 -291.624766) (xy 168.929825 -291.649373)
			(xy 168.92193 -291.69795) (xy 168.906346 -291.744631) (xy 168.883475 -291.788208) (xy 168.85391 -291.827552)
			(xy 168.818417 -291.861644) (xy 168.777914 -291.8896) (xy 168.733452 -291.910698) (xy 168.686181 -291.92439)
			(xy 168.637326 -291.930322) (xy 168.588151 -291.928341) (xy 168.539932 -291.918497) (xy 168.493916 -291.901045)
			(xy 168.451295 -291.876438) (xy 168.413174 -291.845313) (xy 168.380539 -291.808476) (xy 168.354236 -291.76688)
			(xy 168.334945 -291.721604) (xy 168.323168 -291.67382) (xy 168.319208 -291.624766) (xy 167.98036 -291.624766)
			(xy 167.979865 -291.649373) (xy 167.97197 -291.69795) (xy 167.956386 -291.744631) (xy 167.933515 -291.788208)
			(xy 167.90395 -291.827552) (xy 167.868457 -291.861644) (xy 167.827954 -291.8896) (xy 167.783492 -291.910698)
			(xy 167.736221 -291.92439) (xy 167.687366 -291.930322) (xy 167.638191 -291.928341) (xy 167.589972 -291.918497)
			(xy 167.543956 -291.901045) (xy 167.501335 -291.876438) (xy 167.463214 -291.845313) (xy 167.430579 -291.808476)
			(xy 167.404276 -291.76688) (xy 167.384985 -291.721604) (xy 167.373208 -291.67382) (xy 167.369248 -291.624766)
			(xy 167.0304 -291.624766) (xy 167.029905 -291.649373) (xy 167.02201 -291.69795) (xy 167.006426 -291.744631)
			(xy 166.983555 -291.788208) (xy 166.95399 -291.827552) (xy 166.918497 -291.861644) (xy 166.877994 -291.8896)
			(xy 166.833532 -291.910698) (xy 166.786261 -291.92439) (xy 166.737406 -291.930322) (xy 166.688231 -291.928341)
			(xy 166.640012 -291.918497) (xy 166.593996 -291.901045) (xy 166.551375 -291.876438) (xy 166.513254 -291.845313)
			(xy 166.480619 -291.808476) (xy 166.454316 -291.76688) (xy 166.435025 -291.721604) (xy 166.423248 -291.67382)
			(xy 166.419288 -291.624766) (xy 165.130226 -291.624766) (xy 165.129731 -291.649373) (xy 165.121836 -291.69795)
			(xy 165.106252 -291.744631) (xy 165.083381 -291.788208) (xy 165.053816 -291.827552) (xy 165.018323 -291.861644)
			(xy 164.97782 -291.8896) (xy 164.933358 -291.910698) (xy 164.886087 -291.92439) (xy 164.837232 -291.930322)
			(xy 164.788057 -291.928341) (xy 164.739838 -291.918497) (xy 164.693822 -291.901045) (xy 164.651201 -291.876438)
			(xy 164.61308 -291.845313) (xy 164.580445 -291.808476) (xy 164.554142 -291.76688) (xy 164.534851 -291.721604)
			(xy 164.523074 -291.67382) (xy 164.519114 -291.624766) (xy 164.180266 -291.624766) (xy 164.179771 -291.649373)
			(xy 164.171876 -291.69795) (xy 164.156292 -291.744631) (xy 164.133421 -291.788208) (xy 164.103856 -291.827552)
			(xy 164.068363 -291.861644) (xy 164.02786 -291.8896) (xy 163.983398 -291.910698) (xy 163.936127 -291.92439)
			(xy 163.887272 -291.930322) (xy 163.838097 -291.928341) (xy 163.789878 -291.918497) (xy 163.743862 -291.901045)
			(xy 163.701241 -291.876438) (xy 163.66312 -291.845313) (xy 163.630485 -291.808476) (xy 163.604182 -291.76688)
			(xy 163.584891 -291.721604) (xy 163.573114 -291.67382) (xy 163.569154 -291.624766) (xy 162.280346 -291.624766)
			(xy 162.279851 -291.649373) (xy 162.271956 -291.69795) (xy 162.256372 -291.744631) (xy 162.233501 -291.788208)
			(xy 162.203936 -291.827552) (xy 162.168443 -291.861644) (xy 162.12794 -291.8896) (xy 162.083478 -291.910698)
			(xy 162.036207 -291.92439) (xy 161.987352 -291.930322) (xy 161.938177 -291.928341) (xy 161.889958 -291.918497)
			(xy 161.843942 -291.901045) (xy 161.801321 -291.876438) (xy 161.7632 -291.845313) (xy 161.730565 -291.808476)
			(xy 161.704262 -291.76688) (xy 161.684971 -291.721604) (xy 161.673194 -291.67382) (xy 161.669234 -291.624766)
			(xy 161.330386 -291.624766) (xy 161.329891 -291.649373) (xy 161.321996 -291.69795) (xy 161.306412 -291.744631)
			(xy 161.283541 -291.788208) (xy 161.253976 -291.827552) (xy 161.218483 -291.861644) (xy 161.17798 -291.8896)
			(xy 161.133518 -291.910698) (xy 161.086247 -291.92439) (xy 161.037392 -291.930322) (xy 160.988217 -291.928341)
			(xy 160.939998 -291.918497) (xy 160.893982 -291.901045) (xy 160.851361 -291.876438) (xy 160.81324 -291.845313)
			(xy 160.780605 -291.808476) (xy 160.754302 -291.76688) (xy 160.735011 -291.721604) (xy 160.723234 -291.67382)
			(xy 160.719274 -291.624766) (xy 160.380172 -291.624766) (xy 160.379677 -291.649373) (xy 160.371782 -291.69795)
			(xy 160.356198 -291.744631) (xy 160.333327 -291.788208) (xy 160.303762 -291.827552) (xy 160.268269 -291.861644)
			(xy 160.227766 -291.8896) (xy 160.183304 -291.910698) (xy 160.136033 -291.92439) (xy 160.087178 -291.930322)
			(xy 160.038003 -291.928341) (xy 159.989784 -291.918497) (xy 159.943768 -291.901045) (xy 159.901147 -291.876438)
			(xy 159.863026 -291.845313) (xy 159.830391 -291.808476) (xy 159.804088 -291.76688) (xy 159.784797 -291.721604)
			(xy 159.77302 -291.67382) (xy 159.76906 -291.624766) (xy 159.430212 -291.624766) (xy 159.429717 -291.649373)
			(xy 159.421822 -291.69795) (xy 159.406238 -291.744631) (xy 159.383367 -291.788208) (xy 159.353802 -291.827552)
			(xy 159.318309 -291.861644) (xy 159.277806 -291.8896) (xy 159.233344 -291.910698) (xy 159.186073 -291.92439)
			(xy 159.137218 -291.930322) (xy 159.088043 -291.928341) (xy 159.039824 -291.918497) (xy 158.993808 -291.901045)
			(xy 158.951187 -291.876438) (xy 158.913066 -291.845313) (xy 158.880431 -291.808476) (xy 158.854128 -291.76688)
			(xy 158.834837 -291.721604) (xy 158.82306 -291.67382) (xy 158.8191 -291.624766) (xy 158.480252 -291.624766)
			(xy 158.479757 -291.649373) (xy 158.471862 -291.69795) (xy 158.456278 -291.744631) (xy 158.433407 -291.788208)
			(xy 158.403842 -291.827552) (xy 158.368349 -291.861644) (xy 158.327846 -291.8896) (xy 158.283384 -291.910698)
			(xy 158.236113 -291.92439) (xy 158.187258 -291.930322) (xy 158.138083 -291.928341) (xy 158.089864 -291.918497)
			(xy 158.043848 -291.901045) (xy 158.001227 -291.876438) (xy 157.963106 -291.845313) (xy 157.930471 -291.808476)
			(xy 157.904168 -291.76688) (xy 157.884877 -291.721604) (xy 157.8731 -291.67382) (xy 157.86914 -291.624766)
			(xy 157.530292 -291.624766) (xy 157.529797 -291.649373) (xy 157.521902 -291.69795) (xy 157.506318 -291.744631)
			(xy 157.483447 -291.788208) (xy 157.453882 -291.827552) (xy 157.418389 -291.861644) (xy 157.377886 -291.8896)
			(xy 157.333424 -291.910698) (xy 157.286153 -291.92439) (xy 157.237298 -291.930322) (xy 157.188123 -291.928341)
			(xy 157.139904 -291.918497) (xy 157.093888 -291.901045) (xy 157.051267 -291.876438) (xy 157.013146 -291.845313)
			(xy 156.980511 -291.808476) (xy 156.954208 -291.76688) (xy 156.934917 -291.721604) (xy 156.92314 -291.67382)
			(xy 156.91918 -291.624766) (xy 154.680412 -291.624766) (xy 154.679917 -291.649373) (xy 154.672022 -291.69795)
			(xy 154.656438 -291.744631) (xy 154.633567 -291.788208) (xy 154.604002 -291.827552) (xy 154.568509 -291.861644)
			(xy 154.528006 -291.8896) (xy 154.483544 -291.910698) (xy 154.436273 -291.92439) (xy 154.387418 -291.930322)
			(xy 154.338243 -291.928341) (xy 154.290024 -291.918497) (xy 154.244008 -291.901045) (xy 154.201387 -291.876438)
			(xy 154.163266 -291.845313) (xy 154.130631 -291.808476) (xy 154.104328 -291.76688) (xy 154.085037 -291.721604)
			(xy 154.07326 -291.67382) (xy 154.0693 -291.624766) (xy 153.730198 -291.624766) (xy 153.729703 -291.649373)
			(xy 153.721808 -291.69795) (xy 153.706224 -291.744631) (xy 153.683353 -291.788208) (xy 153.653788 -291.827552)
			(xy 153.618295 -291.861644) (xy 153.577792 -291.8896) (xy 153.53333 -291.910698) (xy 153.486059 -291.92439)
			(xy 153.437204 -291.930322) (xy 153.388029 -291.928341) (xy 153.33981 -291.918497) (xy 153.293794 -291.901045)
			(xy 153.251173 -291.876438) (xy 153.213052 -291.845313) (xy 153.180417 -291.808476) (xy 153.154114 -291.76688)
			(xy 153.134823 -291.721604) (xy 153.123046 -291.67382) (xy 153.119086 -291.624766) (xy 152.780238 -291.624766)
			(xy 152.779743 -291.649373) (xy 152.771848 -291.69795) (xy 152.756264 -291.744631) (xy 152.733393 -291.788208)
			(xy 152.703828 -291.827552) (xy 152.668335 -291.861644) (xy 152.627832 -291.8896) (xy 152.58337 -291.910698)
			(xy 152.536099 -291.92439) (xy 152.487244 -291.930322) (xy 152.438069 -291.928341) (xy 152.38985 -291.918497)
			(xy 152.343834 -291.901045) (xy 152.301213 -291.876438) (xy 152.263092 -291.845313) (xy 152.230457 -291.808476)
			(xy 152.204154 -291.76688) (xy 152.184863 -291.721604) (xy 152.173086 -291.67382) (xy 152.169126 -291.624766)
			(xy 144.107012 -291.624766) (xy 144.081098 -291.663935) (xy 144.043881 -291.705472) (xy 144.001013 -291.741147)
			(xy 143.953407 -291.770201) (xy 143.902078 -291.792013) (xy 143.848121 -291.806119) (xy 143.792684 -291.812219)
			(xy 143.73695 -291.810182) (xy 143.682107 -291.800052) (xy 143.629323 -291.782045) (xy 143.579723 -291.756544)
			(xy 143.534365 -291.724093) (xy 143.494216 -291.685384) (xy 143.46013 -291.641241) (xy 143.432834 -291.592606)
			(xy 143.412911 -291.540515) (xy 143.400785 -291.486078) (xy 143.396714 -291.430456) (xy 142.675102 -291.430456)
			(xy 142.674593 -291.458342) (xy 142.666473 -291.513518) (xy 142.650405 -291.566925) (xy 142.626733 -291.617422)
			(xy 142.59596 -291.663935) (xy 142.558743 -291.705472) (xy 142.515875 -291.741147) (xy 142.468269 -291.770201)
			(xy 142.41694 -291.792013) (xy 142.362983 -291.806119) (xy 142.307546 -291.812219) (xy 142.251812 -291.810182)
			(xy 142.196969 -291.800052) (xy 142.144185 -291.782045) (xy 142.094585 -291.756544) (xy 142.049227 -291.724093)
			(xy 142.009078 -291.685384) (xy 141.974992 -291.641241) (xy 141.947696 -291.592606) (xy 141.927773 -291.540515)
			(xy 141.915647 -291.486078) (xy 141.911576 -291.430456) (xy 136.349994 -291.430456) (xy 136.349994 -292.016434)
			(xy 136.349564 -292.026501) (xy 136.341841 -292.045096) (xy 136.335008 -292.052502) (xy 135.654796 -292.732714)
			(xy 141.911576 -292.732714) (xy 141.915647 -292.677092) (xy 141.927773 -292.622655) (xy 141.947696 -292.570564)
			(xy 141.974992 -292.521929) (xy 142.009078 -292.477786) (xy 142.049227 -292.439077) (xy 142.094585 -292.406626)
			(xy 142.144185 -292.381125) (xy 142.196969 -292.363118) (xy 142.251812 -292.352988) (xy 142.307546 -292.350951)
			(xy 142.362983 -292.357051) (xy 142.41694 -292.371157) (xy 142.468269 -292.392969) (xy 142.515875 -292.422023)
			(xy 142.558743 -292.457698) (xy 142.59596 -292.499235) (xy 142.626733 -292.545748) (xy 142.650405 -292.596245)
			(xy 142.666473 -292.649652) (xy 142.674593 -292.704828) (xy 142.675102 -292.732714) (xy 143.387062 -292.732714)
			(xy 143.391133 -292.677092) (xy 143.403259 -292.622655) (xy 143.423182 -292.570564) (xy 143.450478 -292.521929)
			(xy 143.484564 -292.477786) (xy 143.524713 -292.439077) (xy 143.570071 -292.406626) (xy 143.619671 -292.381125)
			(xy 143.672455 -292.363118) (xy 143.727298 -292.352988) (xy 143.783032 -292.350951) (xy 143.838469 -292.357051)
			(xy 143.892426 -292.371157) (xy 143.943755 -292.392969) (xy 143.991361 -292.422023) (xy 144.034229 -292.457698)
			(xy 144.071446 -292.499235) (xy 144.102219 -292.545748) (xy 144.125891 -292.596245) (xy 144.141959 -292.649652)
			(xy 144.150079 -292.704828) (xy 144.150588 -292.732714) (xy 144.276062 -292.732714) (xy 144.280133 -292.677092)
			(xy 144.292259 -292.622655) (xy 144.312182 -292.570564) (xy 144.339478 -292.521929) (xy 144.373564 -292.477786)
			(xy 144.413713 -292.439077) (xy 144.459071 -292.406626) (xy 144.508671 -292.381125) (xy 144.561455 -292.363118)
			(xy 144.616298 -292.352988) (xy 144.672032 -292.350951) (xy 144.727469 -292.357051) (xy 144.781426 -292.371157)
			(xy 144.832755 -292.392969) (xy 144.880361 -292.422023) (xy 144.923229 -292.457698) (xy 144.960446 -292.499235)
			(xy 144.991219 -292.545748) (xy 145.014891 -292.596245) (xy 145.030959 -292.649652) (xy 145.039079 -292.704828)
			(xy 145.039588 -292.732714) (xy 145.039079 -292.7606) (xy 145.030959 -292.815776) (xy 145.014891 -292.869183)
			(xy 144.991219 -292.91968) (xy 144.960446 -292.966193) (xy 144.923229 -293.00773) (xy 144.880361 -293.043405)
			(xy 144.832755 -293.072459) (xy 144.781426 -293.094271) (xy 144.727469 -293.108377) (xy 144.672032 -293.114477)
			(xy 144.616298 -293.11244) (xy 144.561455 -293.10231) (xy 144.508671 -293.084303) (xy 144.459071 -293.058802)
			(xy 144.413713 -293.026351) (xy 144.373564 -292.987642) (xy 144.339478 -292.943499) (xy 144.312182 -292.894864)
			(xy 144.292259 -292.842773) (xy 144.280133 -292.788336) (xy 144.276062 -292.732714) (xy 144.150588 -292.732714)
			(xy 144.150079 -292.7606) (xy 144.141959 -292.815776) (xy 144.125891 -292.869183) (xy 144.102219 -292.91968)
			(xy 144.071446 -292.966193) (xy 144.034229 -293.00773) (xy 143.991361 -293.043405) (xy 143.943755 -293.072459)
			(xy 143.892426 -293.094271) (xy 143.838469 -293.108377) (xy 143.783032 -293.114477) (xy 143.727298 -293.11244)
			(xy 143.672455 -293.10231) (xy 143.619671 -293.084303) (xy 143.570071 -293.058802) (xy 143.524713 -293.026351)
			(xy 143.484564 -292.987642) (xy 143.450478 -292.943499) (xy 143.423182 -292.894864) (xy 143.403259 -292.842773)
			(xy 143.391133 -292.788336) (xy 143.387062 -292.732714) (xy 142.675102 -292.732714) (xy 142.674593 -292.7606)
			(xy 142.666473 -292.815776) (xy 142.650405 -292.869183) (xy 142.626733 -292.91968) (xy 142.59596 -292.966193)
			(xy 142.558743 -293.00773) (xy 142.515875 -293.043405) (xy 142.468269 -293.072459) (xy 142.41694 -293.094271)
			(xy 142.362983 -293.108377) (xy 142.307546 -293.114477) (xy 142.251812 -293.11244) (xy 142.196969 -293.10231)
			(xy 142.144185 -293.084303) (xy 142.094585 -293.058802) (xy 142.049227 -293.026351) (xy 142.009078 -292.987642)
			(xy 141.974992 -292.943499) (xy 141.947696 -292.894864) (xy 141.927773 -292.842773) (xy 141.915647 -292.788336)
			(xy 141.911576 -292.732714) (xy 135.654796 -292.732714) (xy 134.892796 -293.494714) (xy 147.43811 -293.494714)
			(xy 147.438654 -293.465332) (xy 147.447683 -293.407265) (xy 147.465514 -293.351271) (xy 147.491725 -293.298675)
			(xy 147.525695 -293.250724) (xy 147.56662 -293.208552) (xy 147.589748 -293.190422) (xy 147.599146 -293.183056)
			(xy 147.60956 -293.162482) (xy 147.611084 -293.058596) (xy 147.601178 -293.037514) (xy 147.592034 -293.030148)
			(xy 147.570186 -293.011942) (xy 147.531644 -292.970124) (xy 147.499736 -292.923049) (xy 147.475169 -292.871759)
			(xy 147.458486 -292.817391) (xy 147.450058 -292.761149) (xy 147.44954 -292.732714) (xy 147.450026 -292.705463)
			(xy 147.457782 -292.651515) (xy 147.473137 -292.59922) (xy 147.495779 -292.549643) (xy 147.525245 -292.503793)
			(xy 147.560936 -292.462602) (xy 147.602127 -292.426911) (xy 147.647977 -292.397445) (xy 147.697554 -292.374803)
			(xy 147.749849 -292.359448) (xy 147.803797 -292.351692) (xy 147.858299 -292.351692) (xy 147.912247 -292.359448)
			(xy 147.964542 -292.374803) (xy 148.014119 -292.397445) (xy 148.059969 -292.426911) (xy 148.10116 -292.462602)
			(xy 148.136851 -292.503793) (xy 148.166317 -292.549643) (xy 148.177889 -292.57498) (xy 152.169126 -292.57498)
			(xy 152.173086 -292.525926) (xy 152.184863 -292.478142) (xy 152.204154 -292.432866) (xy 152.230457 -292.39127)
			(xy 152.263092 -292.354433) (xy 152.301213 -292.323308) (xy 152.343834 -292.298701) (xy 152.38985 -292.281249)
			(xy 152.438069 -292.271405) (xy 152.487244 -292.269424) (xy 152.536099 -292.275356) (xy 152.58337 -292.289048)
			(xy 152.627832 -292.310146) (xy 152.668335 -292.338102) (xy 152.703828 -292.372194) (xy 152.733393 -292.411538)
			(xy 152.756264 -292.455115) (xy 152.771848 -292.501796) (xy 152.779743 -292.550373) (xy 152.780238 -292.57498)
			(xy 153.119086 -292.57498) (xy 153.123046 -292.525926) (xy 153.134823 -292.478142) (xy 153.154114 -292.432866)
			(xy 153.180417 -292.39127) (xy 153.213052 -292.354433) (xy 153.251173 -292.323308) (xy 153.293794 -292.298701)
			(xy 153.33981 -292.281249) (xy 153.388029 -292.271405) (xy 153.437204 -292.269424) (xy 153.486059 -292.275356)
			(xy 153.53333 -292.289048) (xy 153.577792 -292.310146) (xy 153.618295 -292.338102) (xy 153.653788 -292.372194)
			(xy 153.683353 -292.411538) (xy 153.706224 -292.455115) (xy 153.721808 -292.501796) (xy 153.729703 -292.550373)
			(xy 153.730198 -292.57498) (xy 154.0693 -292.57498) (xy 154.07326 -292.525926) (xy 154.085037 -292.478142)
			(xy 154.104328 -292.432866) (xy 154.130631 -292.39127) (xy 154.163266 -292.354433) (xy 154.201387 -292.323308)
			(xy 154.244008 -292.298701) (xy 154.290024 -292.281249) (xy 154.338243 -292.271405) (xy 154.387418 -292.269424)
			(xy 154.436273 -292.275356) (xy 154.483544 -292.289048) (xy 154.528006 -292.310146) (xy 154.568509 -292.338102)
			(xy 154.604002 -292.372194) (xy 154.633567 -292.411538) (xy 154.656438 -292.455115) (xy 154.672022 -292.501796)
			(xy 154.679917 -292.550373) (xy 154.680407 -292.574726) (xy 155.01926 -292.574726) (xy 155.02322 -292.525672)
			(xy 155.034997 -292.477888) (xy 155.054288 -292.432612) (xy 155.080591 -292.391016) (xy 155.113226 -292.354179)
			(xy 155.151347 -292.323054) (xy 155.193968 -292.298447) (xy 155.239984 -292.280995) (xy 155.288203 -292.271151)
			(xy 155.337378 -292.26917) (xy 155.386233 -292.275102) (xy 155.433504 -292.288794) (xy 155.477966 -292.309892)
			(xy 155.518469 -292.337848) (xy 155.553962 -292.37194) (xy 155.583527 -292.411284) (xy 155.606398 -292.454861)
			(xy 155.621982 -292.501542) (xy 155.629877 -292.550119) (xy 155.630372 -292.574726) (xy 155.96922 -292.574726)
			(xy 155.97318 -292.525672) (xy 155.984957 -292.477888) (xy 156.004248 -292.432612) (xy 156.030551 -292.391016)
			(xy 156.063186 -292.354179) (xy 156.101307 -292.323054) (xy 156.143928 -292.298447) (xy 156.189944 -292.280995)
			(xy 156.238163 -292.271151) (xy 156.287338 -292.26917) (xy 156.336193 -292.275102) (xy 156.383464 -292.288794)
			(xy 156.427926 -292.309892) (xy 156.468429 -292.337848) (xy 156.503922 -292.37194) (xy 156.533487 -292.411284)
			(xy 156.556358 -292.454861) (xy 156.571942 -292.501542) (xy 156.579837 -292.550119) (xy 156.580332 -292.574726)
			(xy 156.580327 -292.57498) (xy 156.91918 -292.57498) (xy 156.92314 -292.525926) (xy 156.934917 -292.478142)
			(xy 156.954208 -292.432866) (xy 156.980511 -292.39127) (xy 157.013146 -292.354433) (xy 157.051267 -292.323308)
			(xy 157.093888 -292.298701) (xy 157.139904 -292.281249) (xy 157.188123 -292.271405) (xy 157.237298 -292.269424)
			(xy 157.286153 -292.275356) (xy 157.333424 -292.289048) (xy 157.377886 -292.310146) (xy 157.418389 -292.338102)
			(xy 157.453882 -292.372194) (xy 157.483447 -292.411538) (xy 157.506318 -292.455115) (xy 157.521902 -292.501796)
			(xy 157.529797 -292.550373) (xy 157.530292 -292.57498) (xy 157.529797 -292.599587) (xy 157.529465 -292.601629)
			(xy 157.819334 -292.601629) (xy 157.819334 -292.548331) (xy 157.827277 -292.495627) (xy 157.842987 -292.444697)
			(xy 157.866113 -292.396676) (xy 157.896137 -292.352639) (xy 157.932389 -292.313568) (xy 157.97406 -292.280337)
			(xy 158.020218 -292.253688) (xy 158.069832 -292.234216) (xy 158.121794 -292.222356) (xy 158.174944 -292.218373)
			(xy 158.228094 -292.222356) (xy 158.280056 -292.234216) (xy 158.32967 -292.253688) (xy 158.375828 -292.280337)
			(xy 158.417499 -292.313568) (xy 158.453751 -292.352639) (xy 158.483775 -292.396676) (xy 158.506901 -292.444697)
			(xy 158.522611 -292.495627) (xy 158.530554 -292.548331) (xy 158.531052 -292.57498) (xy 158.8191 -292.57498)
			(xy 158.82306 -292.525926) (xy 158.834837 -292.478142) (xy 158.854128 -292.432866) (xy 158.880431 -292.39127)
			(xy 158.913066 -292.354433) (xy 158.951187 -292.323308) (xy 158.993808 -292.298701) (xy 159.039824 -292.281249)
			(xy 159.088043 -292.271405) (xy 159.137218 -292.269424) (xy 159.186073 -292.275356) (xy 159.233344 -292.289048)
			(xy 159.277806 -292.310146) (xy 159.318309 -292.338102) (xy 159.353802 -292.372194) (xy 159.383367 -292.411538)
			(xy 159.406238 -292.455115) (xy 159.421822 -292.501796) (xy 159.429717 -292.550373) (xy 159.430212 -292.57498)
			(xy 159.76906 -292.57498) (xy 159.77302 -292.525926) (xy 159.784797 -292.478142) (xy 159.804088 -292.432866)
			(xy 159.830391 -292.39127) (xy 159.863026 -292.354433) (xy 159.901147 -292.323308) (xy 159.943768 -292.298701)
			(xy 159.989784 -292.281249) (xy 160.038003 -292.271405) (xy 160.087178 -292.269424) (xy 160.136033 -292.275356)
			(xy 160.183304 -292.289048) (xy 160.227766 -292.310146) (xy 160.268269 -292.338102) (xy 160.303762 -292.372194)
			(xy 160.333327 -292.411538) (xy 160.356198 -292.455115) (xy 160.371782 -292.501796) (xy 160.379677 -292.550373)
			(xy 160.380172 -292.57498) (xy 160.719274 -292.57498) (xy 160.723234 -292.525926) (xy 160.735011 -292.478142)
			(xy 160.754302 -292.432866) (xy 160.780605 -292.39127) (xy 160.81324 -292.354433) (xy 160.851361 -292.323308)
			(xy 160.893982 -292.298701) (xy 160.939998 -292.281249) (xy 160.988217 -292.271405) (xy 161.037392 -292.269424)
			(xy 161.086247 -292.275356) (xy 161.133518 -292.289048) (xy 161.17798 -292.310146) (xy 161.218483 -292.338102)
			(xy 161.253976 -292.372194) (xy 161.283541 -292.411538) (xy 161.306412 -292.455115) (xy 161.321996 -292.501796)
			(xy 161.329891 -292.550373) (xy 161.330386 -292.57498) (xy 161.669234 -292.57498) (xy 161.673194 -292.525926)
			(xy 161.684971 -292.478142) (xy 161.704262 -292.432866) (xy 161.730565 -292.39127) (xy 161.7632 -292.354433)
			(xy 161.801321 -292.323308) (xy 161.843942 -292.298701) (xy 161.889958 -292.281249) (xy 161.938177 -292.271405)
			(xy 161.987352 -292.269424) (xy 162.036207 -292.275356) (xy 162.083478 -292.289048) (xy 162.12794 -292.310146)
			(xy 162.168443 -292.338102) (xy 162.203936 -292.372194) (xy 162.233501 -292.411538) (xy 162.256372 -292.455115)
			(xy 162.271956 -292.501796) (xy 162.279851 -292.550373) (xy 162.280346 -292.57498) (xy 162.619194 -292.57498)
			(xy 162.623154 -292.525926) (xy 162.634931 -292.478142) (xy 162.654222 -292.432866) (xy 162.680525 -292.39127)
			(xy 162.71316 -292.354433) (xy 162.751281 -292.323308) (xy 162.793902 -292.298701) (xy 162.839918 -292.281249)
			(xy 162.888137 -292.271405) (xy 162.937312 -292.269424) (xy 162.986167 -292.275356) (xy 163.033438 -292.289048)
			(xy 163.0779 -292.310146) (xy 163.118403 -292.338102) (xy 163.153896 -292.372194) (xy 163.183461 -292.411538)
			(xy 163.206332 -292.455115) (xy 163.221916 -292.501796) (xy 163.229811 -292.550373) (xy 163.230306 -292.57498)
			(xy 163.569154 -292.57498) (xy 163.573114 -292.525926) (xy 163.584891 -292.478142) (xy 163.604182 -292.432866)
			(xy 163.630485 -292.39127) (xy 163.66312 -292.354433) (xy 163.701241 -292.323308) (xy 163.743862 -292.298701)
			(xy 163.789878 -292.281249) (xy 163.838097 -292.271405) (xy 163.887272 -292.269424) (xy 163.936127 -292.275356)
			(xy 163.983398 -292.289048) (xy 164.02786 -292.310146) (xy 164.068363 -292.338102) (xy 164.103856 -292.372194)
			(xy 164.133421 -292.411538) (xy 164.156292 -292.455115) (xy 164.171876 -292.501796) (xy 164.179771 -292.550373)
			(xy 164.180261 -292.574726) (xy 165.469074 -292.574726) (xy 165.473034 -292.525672) (xy 165.484811 -292.477888)
			(xy 165.504102 -292.432612) (xy 165.530405 -292.391016) (xy 165.56304 -292.354179) (xy 165.601161 -292.323054)
			(xy 165.643782 -292.298447) (xy 165.689798 -292.280995) (xy 165.738017 -292.271151) (xy 165.787192 -292.26917)
			(xy 165.836047 -292.275102) (xy 165.883318 -292.288794) (xy 165.92778 -292.309892) (xy 165.968283 -292.337848)
			(xy 166.003776 -292.37194) (xy 166.033341 -292.411284) (xy 166.056212 -292.454861) (xy 166.071796 -292.501542)
			(xy 166.079691 -292.550119) (xy 166.080186 -292.574726) (xy 166.080181 -292.57498) (xy 166.419288 -292.57498)
			(xy 166.423248 -292.525926) (xy 166.435025 -292.478142) (xy 166.454316 -292.432866) (xy 166.480619 -292.39127)
			(xy 166.513254 -292.354433) (xy 166.551375 -292.323308) (xy 166.593996 -292.298701) (xy 166.640012 -292.281249)
			(xy 166.688231 -292.271405) (xy 166.737406 -292.269424) (xy 166.786261 -292.275356) (xy 166.833532 -292.289048)
			(xy 166.877994 -292.310146) (xy 166.918497 -292.338102) (xy 166.95399 -292.372194) (xy 166.983555 -292.411538)
			(xy 167.006426 -292.455115) (xy 167.02201 -292.501796) (xy 167.029905 -292.550373) (xy 167.0304 -292.57498)
			(xy 167.369248 -292.57498) (xy 167.373208 -292.525926) (xy 167.384985 -292.478142) (xy 167.404276 -292.432866)
			(xy 167.430579 -292.39127) (xy 167.463214 -292.354433) (xy 167.501335 -292.323308) (xy 167.543956 -292.298701)
			(xy 167.589972 -292.281249) (xy 167.638191 -292.271405) (xy 167.687366 -292.269424) (xy 167.736221 -292.275356)
			(xy 167.783492 -292.289048) (xy 167.827954 -292.310146) (xy 167.868457 -292.338102) (xy 167.90395 -292.372194)
			(xy 167.933515 -292.411538) (xy 167.956386 -292.455115) (xy 167.97197 -292.501796) (xy 167.979865 -292.550373)
			(xy 167.98036 -292.57498) (xy 168.319208 -292.57498) (xy 168.323168 -292.525926) (xy 168.334945 -292.478142)
			(xy 168.354236 -292.432866) (xy 168.380539 -292.39127) (xy 168.413174 -292.354433) (xy 168.451295 -292.323308)
			(xy 168.493916 -292.298701) (xy 168.539932 -292.281249) (xy 168.588151 -292.271405) (xy 168.637326 -292.269424)
			(xy 168.686181 -292.275356) (xy 168.733452 -292.289048) (xy 168.777914 -292.310146) (xy 168.818417 -292.338102)
			(xy 168.85391 -292.372194) (xy 168.883475 -292.411538) (xy 168.906346 -292.455115) (xy 168.92193 -292.501796)
			(xy 168.929825 -292.550373) (xy 168.93032 -292.57498) (xy 169.269168 -292.57498) (xy 169.273128 -292.525926)
			(xy 169.284905 -292.478142) (xy 169.304196 -292.432866) (xy 169.330499 -292.39127) (xy 169.363134 -292.354433)
			(xy 169.401255 -292.323308) (xy 169.443876 -292.298701) (xy 169.489892 -292.281249) (xy 169.538111 -292.271405)
			(xy 169.587286 -292.269424) (xy 169.636141 -292.275356) (xy 169.683412 -292.289048) (xy 169.727874 -292.310146)
			(xy 169.768377 -292.338102) (xy 169.80387 -292.372194) (xy 169.833435 -292.411538) (xy 169.856306 -292.455115)
			(xy 169.87189 -292.501796) (xy 169.879785 -292.550373) (xy 169.88028 -292.57498) (xy 170.219128 -292.57498)
			(xy 170.223088 -292.525926) (xy 170.234865 -292.478142) (xy 170.254156 -292.432866) (xy 170.280459 -292.39127)
			(xy 170.313094 -292.354433) (xy 170.351215 -292.323308) (xy 170.393836 -292.298701) (xy 170.439852 -292.281249)
			(xy 170.488071 -292.271405) (xy 170.537246 -292.269424) (xy 170.586101 -292.275356) (xy 170.633372 -292.289048)
			(xy 170.677834 -292.310146) (xy 170.718337 -292.338102) (xy 170.75383 -292.372194) (xy 170.783395 -292.411538)
			(xy 170.806266 -292.455115) (xy 170.82185 -292.501796) (xy 170.829745 -292.550373) (xy 170.83024 -292.57498)
			(xy 171.169088 -292.57498) (xy 171.173048 -292.525926) (xy 171.184825 -292.478142) (xy 171.204116 -292.432866)
			(xy 171.230419 -292.39127) (xy 171.263054 -292.354433) (xy 171.301175 -292.323308) (xy 171.343796 -292.298701)
			(xy 171.389812 -292.281249) (xy 171.438031 -292.271405) (xy 171.487206 -292.269424) (xy 171.536061 -292.275356)
			(xy 171.583332 -292.289048) (xy 171.627794 -292.310146) (xy 171.668297 -292.338102) (xy 171.70379 -292.372194)
			(xy 171.733355 -292.411538) (xy 171.756226 -292.455115) (xy 171.77181 -292.501796) (xy 171.779705 -292.550373)
			(xy 171.7802 -292.57498) (xy 172.119302 -292.57498) (xy 172.123262 -292.525926) (xy 172.135039 -292.478142)
			(xy 172.15433 -292.432866) (xy 172.180633 -292.39127) (xy 172.213268 -292.354433) (xy 172.251389 -292.323308)
			(xy 172.29401 -292.298701) (xy 172.340026 -292.281249) (xy 172.388245 -292.271405) (xy 172.43742 -292.269424)
			(xy 172.486275 -292.275356) (xy 172.533546 -292.289048) (xy 172.578008 -292.310146) (xy 172.618511 -292.338102)
			(xy 172.654004 -292.372194) (xy 172.683569 -292.411538) (xy 172.70644 -292.455115) (xy 172.722024 -292.501796)
			(xy 172.729919 -292.550373) (xy 172.730414 -292.57498) (xy 173.069262 -292.57498) (xy 173.073222 -292.525926)
			(xy 173.084999 -292.478142) (xy 173.10429 -292.432866) (xy 173.130593 -292.39127) (xy 173.163228 -292.354433)
			(xy 173.201349 -292.323308) (xy 173.24397 -292.298701) (xy 173.289986 -292.281249) (xy 173.338205 -292.271405)
			(xy 173.38738 -292.269424) (xy 173.436235 -292.275356) (xy 173.483506 -292.289048) (xy 173.527968 -292.310146)
			(xy 173.568471 -292.338102) (xy 173.603964 -292.372194) (xy 173.633529 -292.411538) (xy 173.6564 -292.455115)
			(xy 173.671984 -292.501796) (xy 173.679879 -292.550373) (xy 173.680374 -292.57498) (xy 174.019222 -292.57498)
			(xy 174.023182 -292.525926) (xy 174.034959 -292.478142) (xy 174.05425 -292.432866) (xy 174.080553 -292.39127)
			(xy 174.113188 -292.354433) (xy 174.151309 -292.323308) (xy 174.19393 -292.298701) (xy 174.239946 -292.281249)
			(xy 174.288165 -292.271405) (xy 174.33734 -292.269424) (xy 174.386195 -292.275356) (xy 174.433466 -292.289048)
			(xy 174.477928 -292.310146) (xy 174.518431 -292.338102) (xy 174.553924 -292.372194) (xy 174.583489 -292.411538)
			(xy 174.60636 -292.455115) (xy 174.621944 -292.501796) (xy 174.629839 -292.550373) (xy 174.630329 -292.574726)
			(xy 175.919142 -292.574726) (xy 175.923102 -292.525672) (xy 175.934879 -292.477888) (xy 175.95417 -292.432612)
			(xy 175.980473 -292.391016) (xy 176.013108 -292.354179) (xy 176.051229 -292.323054) (xy 176.09385 -292.298447)
			(xy 176.139866 -292.280995) (xy 176.188085 -292.271151) (xy 176.23726 -292.26917) (xy 176.286115 -292.275102)
			(xy 176.333386 -292.288794) (xy 176.377848 -292.309892) (xy 176.418351 -292.337848) (xy 176.453844 -292.37194)
			(xy 176.483409 -292.411284) (xy 176.50628 -292.454861) (xy 176.521864 -292.501542) (xy 176.529759 -292.550119)
			(xy 176.530254 -292.574726) (xy 176.869102 -292.574726) (xy 176.873062 -292.525672) (xy 176.884839 -292.477888)
			(xy 176.90413 -292.432612) (xy 176.930433 -292.391016) (xy 176.963068 -292.354179) (xy 177.001189 -292.323054)
			(xy 177.04381 -292.298447) (xy 177.089826 -292.280995) (xy 177.138045 -292.271151) (xy 177.18722 -292.26917)
			(xy 177.236075 -292.275102) (xy 177.283346 -292.288794) (xy 177.327808 -292.309892) (xy 177.368311 -292.337848)
			(xy 177.403804 -292.37194) (xy 177.433369 -292.411284) (xy 177.45624 -292.454861) (xy 177.471824 -292.501542)
			(xy 177.479719 -292.550119) (xy 177.480214 -292.574726) (xy 177.819062 -292.574726) (xy 177.823022 -292.525672)
			(xy 177.834799 -292.477888) (xy 177.85409 -292.432612) (xy 177.880393 -292.391016) (xy 177.913028 -292.354179)
			(xy 177.951149 -292.323054) (xy 177.99377 -292.298447) (xy 178.039786 -292.280995) (xy 178.088005 -292.271151)
			(xy 178.13718 -292.26917) (xy 178.186035 -292.275102) (xy 178.233306 -292.288794) (xy 178.277768 -292.309892)
			(xy 178.318271 -292.337848) (xy 178.353764 -292.37194) (xy 178.383329 -292.411284) (xy 178.4062 -292.454861)
			(xy 178.421784 -292.501542) (xy 178.429679 -292.550119) (xy 178.430174 -292.574726) (xy 178.769276 -292.574726)
			(xy 178.773236 -292.525672) (xy 178.785013 -292.477888) (xy 178.804304 -292.432612) (xy 178.830607 -292.391016)
			(xy 178.863242 -292.354179) (xy 178.901363 -292.323054) (xy 178.943984 -292.298447) (xy 178.99 -292.280995)
			(xy 179.038219 -292.271151) (xy 179.087394 -292.26917) (xy 179.136249 -292.275102) (xy 179.18352 -292.288794)
			(xy 179.227982 -292.309892) (xy 179.268485 -292.337848) (xy 179.303978 -292.37194) (xy 179.333543 -292.411284)
			(xy 179.356414 -292.454861) (xy 179.371998 -292.501542) (xy 179.379893 -292.550119) (xy 179.380388 -292.574726)
			(xy 179.719236 -292.574726) (xy 179.723196 -292.525672) (xy 179.734973 -292.477888) (xy 179.754264 -292.432612)
			(xy 179.780567 -292.391016) (xy 179.813202 -292.354179) (xy 179.851323 -292.323054) (xy 179.893944 -292.298447)
			(xy 179.93996 -292.280995) (xy 179.988179 -292.271151) (xy 180.037354 -292.26917) (xy 180.086209 -292.275102)
			(xy 180.13348 -292.288794) (xy 180.177942 -292.309892) (xy 180.218445 -292.337848) (xy 180.253938 -292.37194)
			(xy 180.283503 -292.411284) (xy 180.306374 -292.454861) (xy 180.321958 -292.501542) (xy 180.329853 -292.550119)
			(xy 180.330348 -292.574726) (xy 180.669196 -292.574726) (xy 180.673156 -292.525672) (xy 180.684933 -292.477888)
			(xy 180.704224 -292.432612) (xy 180.730527 -292.391016) (xy 180.763162 -292.354179) (xy 180.801283 -292.323054)
			(xy 180.843904 -292.298447) (xy 180.88992 -292.280995) (xy 180.938139 -292.271151) (xy 180.987314 -292.26917)
			(xy 181.036169 -292.275102) (xy 181.08344 -292.288794) (xy 181.127902 -292.309892) (xy 181.168405 -292.337848)
			(xy 181.203898 -292.37194) (xy 181.233463 -292.411284) (xy 181.256334 -292.454861) (xy 181.271918 -292.501542)
			(xy 181.279813 -292.550119) (xy 181.280308 -292.574726) (xy 181.619156 -292.574726) (xy 181.623116 -292.525672)
			(xy 181.634893 -292.477888) (xy 181.654184 -292.432612) (xy 181.680487 -292.391016) (xy 181.713122 -292.354179)
			(xy 181.751243 -292.323054) (xy 181.793864 -292.298447) (xy 181.83988 -292.280995) (xy 181.888099 -292.271151)
			(xy 181.937274 -292.26917) (xy 181.986129 -292.275102) (xy 182.0334 -292.288794) (xy 182.077862 -292.309892)
			(xy 182.118365 -292.337848) (xy 182.153858 -292.37194) (xy 182.183423 -292.411284) (xy 182.206294 -292.454861)
			(xy 182.221878 -292.501542) (xy 182.229773 -292.550119) (xy 182.230268 -292.574726) (xy 182.569116 -292.574726)
			(xy 182.573076 -292.525672) (xy 182.584853 -292.477888) (xy 182.604144 -292.432612) (xy 182.630447 -292.391016)
			(xy 182.663082 -292.354179) (xy 182.701203 -292.323054) (xy 182.743824 -292.298447) (xy 182.78984 -292.280995)
			(xy 182.838059 -292.271151) (xy 182.887234 -292.26917) (xy 182.936089 -292.275102) (xy 182.98336 -292.288794)
			(xy 183.027822 -292.309892) (xy 183.068325 -292.337848) (xy 183.103818 -292.37194) (xy 183.133383 -292.411284)
			(xy 183.156254 -292.454861) (xy 183.171838 -292.501542) (xy 183.179733 -292.550119) (xy 183.180228 -292.574726)
			(xy 183.519076 -292.574726) (xy 183.523036 -292.525672) (xy 183.534813 -292.477888) (xy 183.554104 -292.432612)
			(xy 183.580407 -292.391016) (xy 183.613042 -292.354179) (xy 183.651163 -292.323054) (xy 183.693784 -292.298447)
			(xy 183.7398 -292.280995) (xy 183.788019 -292.271151) (xy 183.837194 -292.26917) (xy 183.886049 -292.275102)
			(xy 183.93332 -292.288794) (xy 183.977782 -292.309892) (xy 184.018285 -292.337848) (xy 184.053778 -292.37194)
			(xy 184.083343 -292.411284) (xy 184.106214 -292.454861) (xy 184.121798 -292.501542) (xy 184.129693 -292.550119)
			(xy 184.130188 -292.574726) (xy 184.469036 -292.574726) (xy 184.472996 -292.525672) (xy 184.484773 -292.477888)
			(xy 184.504064 -292.432612) (xy 184.530367 -292.391016) (xy 184.563002 -292.354179) (xy 184.601123 -292.323054)
			(xy 184.643744 -292.298447) (xy 184.68976 -292.280995) (xy 184.737979 -292.271151) (xy 184.787154 -292.26917)
			(xy 184.836009 -292.275102) (xy 184.88328 -292.288794) (xy 184.927742 -292.309892) (xy 184.968245 -292.337848)
			(xy 185.003738 -292.37194) (xy 185.033303 -292.411284) (xy 185.056174 -292.454861) (xy 185.071758 -292.501542)
			(xy 185.079653 -292.550119) (xy 185.080148 -292.574726) (xy 185.079653 -292.599333) (xy 185.071758 -292.64791)
			(xy 185.056174 -292.694591) (xy 185.033303 -292.738168) (xy 185.003738 -292.777512) (xy 184.968245 -292.811604)
			(xy 184.927742 -292.83956) (xy 184.88328 -292.860658) (xy 184.836009 -292.87435) (xy 184.787154 -292.880282)
			(xy 184.737979 -292.878301) (xy 184.68976 -292.868457) (xy 184.643744 -292.851005) (xy 184.601123 -292.826398)
			(xy 184.563002 -292.795273) (xy 184.530367 -292.758436) (xy 184.504064 -292.71684) (xy 184.484773 -292.671564)
			(xy 184.472996 -292.62378) (xy 184.469036 -292.574726) (xy 184.130188 -292.574726) (xy 184.129693 -292.599333)
			(xy 184.121798 -292.64791) (xy 184.106214 -292.694591) (xy 184.083343 -292.738168) (xy 184.053778 -292.777512)
			(xy 184.018285 -292.811604) (xy 183.977782 -292.83956) (xy 183.93332 -292.860658) (xy 183.886049 -292.87435)
			(xy 183.837194 -292.880282) (xy 183.788019 -292.878301) (xy 183.7398 -292.868457) (xy 183.693784 -292.851005)
			(xy 183.651163 -292.826398) (xy 183.613042 -292.795273) (xy 183.580407 -292.758436) (xy 183.554104 -292.71684)
			(xy 183.534813 -292.671564) (xy 183.523036 -292.62378) (xy 183.519076 -292.574726) (xy 183.180228 -292.574726)
			(xy 183.179733 -292.599333) (xy 183.171838 -292.64791) (xy 183.156254 -292.694591) (xy 183.133383 -292.738168)
			(xy 183.103818 -292.777512) (xy 183.068325 -292.811604) (xy 183.027822 -292.83956) (xy 182.98336 -292.860658)
			(xy 182.936089 -292.87435) (xy 182.887234 -292.880282) (xy 182.838059 -292.878301) (xy 182.78984 -292.868457)
			(xy 182.743824 -292.851005) (xy 182.701203 -292.826398) (xy 182.663082 -292.795273) (xy 182.630447 -292.758436)
			(xy 182.604144 -292.71684) (xy 182.584853 -292.671564) (xy 182.573076 -292.62378) (xy 182.569116 -292.574726)
			(xy 182.230268 -292.574726) (xy 182.229773 -292.599333) (xy 182.221878 -292.64791) (xy 182.206294 -292.694591)
			(xy 182.183423 -292.738168) (xy 182.153858 -292.777512) (xy 182.118365 -292.811604) (xy 182.077862 -292.83956)
			(xy 182.0334 -292.860658) (xy 181.986129 -292.87435) (xy 181.937274 -292.880282) (xy 181.888099 -292.878301)
			(xy 181.83988 -292.868457) (xy 181.793864 -292.851005) (xy 181.751243 -292.826398) (xy 181.713122 -292.795273)
			(xy 181.680487 -292.758436) (xy 181.654184 -292.71684) (xy 181.634893 -292.671564) (xy 181.623116 -292.62378)
			(xy 181.619156 -292.574726) (xy 181.280308 -292.574726) (xy 181.279813 -292.599333) (xy 181.271918 -292.64791)
			(xy 181.256334 -292.694591) (xy 181.233463 -292.738168) (xy 181.203898 -292.777512) (xy 181.168405 -292.811604)
			(xy 181.127902 -292.83956) (xy 181.08344 -292.860658) (xy 181.036169 -292.87435) (xy 180.987314 -292.880282)
			(xy 180.938139 -292.878301) (xy 180.88992 -292.868457) (xy 180.843904 -292.851005) (xy 180.801283 -292.826398)
			(xy 180.763162 -292.795273) (xy 180.730527 -292.758436) (xy 180.704224 -292.71684) (xy 180.684933 -292.671564)
			(xy 180.673156 -292.62378) (xy 180.669196 -292.574726) (xy 180.330348 -292.574726) (xy 180.329853 -292.599333)
			(xy 180.321958 -292.64791) (xy 180.306374 -292.694591) (xy 180.283503 -292.738168) (xy 180.253938 -292.777512)
			(xy 180.218445 -292.811604) (xy 180.177942 -292.83956) (xy 180.13348 -292.860658) (xy 180.086209 -292.87435)
			(xy 180.037354 -292.880282) (xy 179.988179 -292.878301) (xy 179.93996 -292.868457) (xy 179.893944 -292.851005)
			(xy 179.851323 -292.826398) (xy 179.813202 -292.795273) (xy 179.780567 -292.758436) (xy 179.754264 -292.71684)
			(xy 179.734973 -292.671564) (xy 179.723196 -292.62378) (xy 179.719236 -292.574726) (xy 179.380388 -292.574726)
			(xy 179.379893 -292.599333) (xy 179.371998 -292.64791) (xy 179.356414 -292.694591) (xy 179.333543 -292.738168)
			(xy 179.303978 -292.777512) (xy 179.268485 -292.811604) (xy 179.227982 -292.83956) (xy 179.18352 -292.860658)
			(xy 179.136249 -292.87435) (xy 179.087394 -292.880282) (xy 179.038219 -292.878301) (xy 178.99 -292.868457)
			(xy 178.943984 -292.851005) (xy 178.901363 -292.826398) (xy 178.863242 -292.795273) (xy 178.830607 -292.758436)
			(xy 178.804304 -292.71684) (xy 178.785013 -292.671564) (xy 178.773236 -292.62378) (xy 178.769276 -292.574726)
			(xy 178.430174 -292.574726) (xy 178.429679 -292.599333) (xy 178.421784 -292.64791) (xy 178.4062 -292.694591)
			(xy 178.383329 -292.738168) (xy 178.353764 -292.777512) (xy 178.318271 -292.811604) (xy 178.277768 -292.83956)
			(xy 178.233306 -292.860658) (xy 178.186035 -292.87435) (xy 178.13718 -292.880282) (xy 178.088005 -292.878301)
			(xy 178.039786 -292.868457) (xy 177.99377 -292.851005) (xy 177.951149 -292.826398) (xy 177.913028 -292.795273)
			(xy 177.880393 -292.758436) (xy 177.85409 -292.71684) (xy 177.834799 -292.671564) (xy 177.823022 -292.62378)
			(xy 177.819062 -292.574726) (xy 177.480214 -292.574726) (xy 177.479719 -292.599333) (xy 177.471824 -292.64791)
			(xy 177.45624 -292.694591) (xy 177.433369 -292.738168) (xy 177.403804 -292.777512) (xy 177.368311 -292.811604)
			(xy 177.327808 -292.83956) (xy 177.283346 -292.860658) (xy 177.236075 -292.87435) (xy 177.18722 -292.880282)
			(xy 177.138045 -292.878301) (xy 177.089826 -292.868457) (xy 177.04381 -292.851005) (xy 177.001189 -292.826398)
			(xy 176.963068 -292.795273) (xy 176.930433 -292.758436) (xy 176.90413 -292.71684) (xy 176.884839 -292.671564)
			(xy 176.873062 -292.62378) (xy 176.869102 -292.574726) (xy 176.530254 -292.574726) (xy 176.529759 -292.599333)
			(xy 176.521864 -292.64791) (xy 176.50628 -292.694591) (xy 176.483409 -292.738168) (xy 176.453844 -292.777512)
			(xy 176.418351 -292.811604) (xy 176.377848 -292.83956) (xy 176.333386 -292.860658) (xy 176.286115 -292.87435)
			(xy 176.23726 -292.880282) (xy 176.188085 -292.878301) (xy 176.139866 -292.868457) (xy 176.09385 -292.851005)
			(xy 176.051229 -292.826398) (xy 176.013108 -292.795273) (xy 175.980473 -292.758436) (xy 175.95417 -292.71684)
			(xy 175.934879 -292.671564) (xy 175.923102 -292.62378) (xy 175.919142 -292.574726) (xy 174.630329 -292.574726)
			(xy 174.630334 -292.57498) (xy 174.629839 -292.599587) (xy 174.621944 -292.648164) (xy 174.60636 -292.694845)
			(xy 174.583489 -292.738422) (xy 174.553924 -292.777766) (xy 174.518431 -292.811858) (xy 174.477928 -292.839814)
			(xy 174.433466 -292.860912) (xy 174.386195 -292.874604) (xy 174.33734 -292.880536) (xy 174.288165 -292.878555)
			(xy 174.239946 -292.868711) (xy 174.19393 -292.851259) (xy 174.151309 -292.826652) (xy 174.113188 -292.795527)
			(xy 174.080553 -292.75869) (xy 174.05425 -292.717094) (xy 174.034959 -292.671818) (xy 174.023182 -292.624034)
			(xy 174.019222 -292.57498) (xy 173.680374 -292.57498) (xy 173.679879 -292.599587) (xy 173.671984 -292.648164)
			(xy 173.6564 -292.694845) (xy 173.633529 -292.738422) (xy 173.603964 -292.777766) (xy 173.568471 -292.811858)
			(xy 173.527968 -292.839814) (xy 173.483506 -292.860912) (xy 173.436235 -292.874604) (xy 173.38738 -292.880536)
			(xy 173.338205 -292.878555) (xy 173.289986 -292.868711) (xy 173.24397 -292.851259) (xy 173.201349 -292.826652)
			(xy 173.163228 -292.795527) (xy 173.130593 -292.75869) (xy 173.10429 -292.717094) (xy 173.084999 -292.671818)
			(xy 173.073222 -292.624034) (xy 173.069262 -292.57498) (xy 172.730414 -292.57498) (xy 172.729919 -292.599587)
			(xy 172.722024 -292.648164) (xy 172.70644 -292.694845) (xy 172.683569 -292.738422) (xy 172.654004 -292.777766)
			(xy 172.618511 -292.811858) (xy 172.578008 -292.839814) (xy 172.533546 -292.860912) (xy 172.486275 -292.874604)
			(xy 172.43742 -292.880536) (xy 172.388245 -292.878555) (xy 172.340026 -292.868711) (xy 172.29401 -292.851259)
			(xy 172.251389 -292.826652) (xy 172.213268 -292.795527) (xy 172.180633 -292.75869) (xy 172.15433 -292.717094)
			(xy 172.135039 -292.671818) (xy 172.123262 -292.624034) (xy 172.119302 -292.57498) (xy 171.7802 -292.57498)
			(xy 171.779705 -292.599587) (xy 171.77181 -292.648164) (xy 171.756226 -292.694845) (xy 171.733355 -292.738422)
			(xy 171.70379 -292.777766) (xy 171.668297 -292.811858) (xy 171.627794 -292.839814) (xy 171.583332 -292.860912)
			(xy 171.536061 -292.874604) (xy 171.487206 -292.880536) (xy 171.438031 -292.878555) (xy 171.389812 -292.868711)
			(xy 171.343796 -292.851259) (xy 171.301175 -292.826652) (xy 171.263054 -292.795527) (xy 171.230419 -292.75869)
			(xy 171.204116 -292.717094) (xy 171.184825 -292.671818) (xy 171.173048 -292.624034) (xy 171.169088 -292.57498)
			(xy 170.83024 -292.57498) (xy 170.829745 -292.599587) (xy 170.82185 -292.648164) (xy 170.806266 -292.694845)
			(xy 170.783395 -292.738422) (xy 170.75383 -292.777766) (xy 170.718337 -292.811858) (xy 170.677834 -292.839814)
			(xy 170.633372 -292.860912) (xy 170.586101 -292.874604) (xy 170.537246 -292.880536) (xy 170.488071 -292.878555)
			(xy 170.439852 -292.868711) (xy 170.393836 -292.851259) (xy 170.351215 -292.826652) (xy 170.313094 -292.795527)
			(xy 170.280459 -292.75869) (xy 170.254156 -292.717094) (xy 170.234865 -292.671818) (xy 170.223088 -292.624034)
			(xy 170.219128 -292.57498) (xy 169.88028 -292.57498) (xy 169.879785 -292.599587) (xy 169.87189 -292.648164)
			(xy 169.856306 -292.694845) (xy 169.833435 -292.738422) (xy 169.80387 -292.777766) (xy 169.768377 -292.811858)
			(xy 169.727874 -292.839814) (xy 169.683412 -292.860912) (xy 169.636141 -292.874604) (xy 169.587286 -292.880536)
			(xy 169.538111 -292.878555) (xy 169.489892 -292.868711) (xy 169.443876 -292.851259) (xy 169.401255 -292.826652)
			(xy 169.363134 -292.795527) (xy 169.330499 -292.75869) (xy 169.304196 -292.717094) (xy 169.284905 -292.671818)
			(xy 169.273128 -292.624034) (xy 169.269168 -292.57498) (xy 168.93032 -292.57498) (xy 168.929825 -292.599587)
			(xy 168.92193 -292.648164) (xy 168.906346 -292.694845) (xy 168.883475 -292.738422) (xy 168.85391 -292.777766)
			(xy 168.818417 -292.811858) (xy 168.777914 -292.839814) (xy 168.733452 -292.860912) (xy 168.686181 -292.874604)
			(xy 168.637326 -292.880536) (xy 168.588151 -292.878555) (xy 168.539932 -292.868711) (xy 168.493916 -292.851259)
			(xy 168.451295 -292.826652) (xy 168.413174 -292.795527) (xy 168.380539 -292.75869) (xy 168.354236 -292.717094)
			(xy 168.334945 -292.671818) (xy 168.323168 -292.624034) (xy 168.319208 -292.57498) (xy 167.98036 -292.57498)
			(xy 167.979865 -292.599587) (xy 167.97197 -292.648164) (xy 167.956386 -292.694845) (xy 167.933515 -292.738422)
			(xy 167.90395 -292.777766) (xy 167.868457 -292.811858) (xy 167.827954 -292.839814) (xy 167.783492 -292.860912)
			(xy 167.736221 -292.874604) (xy 167.687366 -292.880536) (xy 167.638191 -292.878555) (xy 167.589972 -292.868711)
			(xy 167.543956 -292.851259) (xy 167.501335 -292.826652) (xy 167.463214 -292.795527) (xy 167.430579 -292.75869)
			(xy 167.404276 -292.717094) (xy 167.384985 -292.671818) (xy 167.373208 -292.624034) (xy 167.369248 -292.57498)
			(xy 167.0304 -292.57498) (xy 167.029905 -292.599587) (xy 167.02201 -292.648164) (xy 167.006426 -292.694845)
			(xy 166.983555 -292.738422) (xy 166.95399 -292.777766) (xy 166.918497 -292.811858) (xy 166.877994 -292.839814)
			(xy 166.833532 -292.860912) (xy 166.786261 -292.874604) (xy 166.737406 -292.880536) (xy 166.688231 -292.878555)
			(xy 166.640012 -292.868711) (xy 166.593996 -292.851259) (xy 166.551375 -292.826652) (xy 166.513254 -292.795527)
			(xy 166.480619 -292.75869) (xy 166.454316 -292.717094) (xy 166.435025 -292.671818) (xy 166.423248 -292.624034)
			(xy 166.419288 -292.57498) (xy 166.080181 -292.57498) (xy 166.079691 -292.599333) (xy 166.071796 -292.64791)
			(xy 166.056212 -292.694591) (xy 166.033341 -292.738168) (xy 166.003776 -292.777512) (xy 165.968283 -292.811604)
			(xy 165.92778 -292.83956) (xy 165.883318 -292.860658) (xy 165.836047 -292.87435) (xy 165.787192 -292.880282)
			(xy 165.738017 -292.878301) (xy 165.689798 -292.868457) (xy 165.643782 -292.851005) (xy 165.601161 -292.826398)
			(xy 165.56304 -292.795273) (xy 165.530405 -292.758436) (xy 165.504102 -292.71684) (xy 165.484811 -292.671564)
			(xy 165.473034 -292.62378) (xy 165.469074 -292.574726) (xy 164.180261 -292.574726) (xy 164.180266 -292.57498)
			(xy 164.179771 -292.599587) (xy 164.171876 -292.648164) (xy 164.156292 -292.694845) (xy 164.133421 -292.738422)
			(xy 164.103856 -292.777766) (xy 164.068363 -292.811858) (xy 164.02786 -292.839814) (xy 163.983398 -292.860912)
			(xy 163.936127 -292.874604) (xy 163.887272 -292.880536) (xy 163.838097 -292.878555) (xy 163.789878 -292.868711)
			(xy 163.743862 -292.851259) (xy 163.701241 -292.826652) (xy 163.66312 -292.795527) (xy 163.630485 -292.75869)
			(xy 163.604182 -292.717094) (xy 163.584891 -292.671818) (xy 163.573114 -292.624034) (xy 163.569154 -292.57498)
			(xy 163.230306 -292.57498) (xy 163.229811 -292.599587) (xy 163.221916 -292.648164) (xy 163.206332 -292.694845)
			(xy 163.183461 -292.738422) (xy 163.153896 -292.777766) (xy 163.118403 -292.811858) (xy 163.0779 -292.839814)
			(xy 163.033438 -292.860912) (xy 162.986167 -292.874604) (xy 162.937312 -292.880536) (xy 162.888137 -292.878555)
			(xy 162.839918 -292.868711) (xy 162.793902 -292.851259) (xy 162.751281 -292.826652) (xy 162.71316 -292.795527)
			(xy 162.680525 -292.75869) (xy 162.654222 -292.717094) (xy 162.634931 -292.671818) (xy 162.623154 -292.624034)
			(xy 162.619194 -292.57498) (xy 162.280346 -292.57498) (xy 162.279851 -292.599587) (xy 162.271956 -292.648164)
			(xy 162.256372 -292.694845) (xy 162.233501 -292.738422) (xy 162.203936 -292.777766) (xy 162.168443 -292.811858)
			(xy 162.12794 -292.839814) (xy 162.083478 -292.860912) (xy 162.036207 -292.874604) (xy 161.987352 -292.880536)
			(xy 161.938177 -292.878555) (xy 161.889958 -292.868711) (xy 161.843942 -292.851259) (xy 161.801321 -292.826652)
			(xy 161.7632 -292.795527) (xy 161.730565 -292.75869) (xy 161.704262 -292.717094) (xy 161.684971 -292.671818)
			(xy 161.673194 -292.624034) (xy 161.669234 -292.57498) (xy 161.330386 -292.57498) (xy 161.329891 -292.599587)
			(xy 161.321996 -292.648164) (xy 161.306412 -292.694845) (xy 161.283541 -292.738422) (xy 161.253976 -292.777766)
			(xy 161.218483 -292.811858) (xy 161.17798 -292.839814) (xy 161.133518 -292.860912) (xy 161.086247 -292.874604)
			(xy 161.037392 -292.880536) (xy 160.988217 -292.878555) (xy 160.939998 -292.868711) (xy 160.893982 -292.851259)
			(xy 160.851361 -292.826652) (xy 160.81324 -292.795527) (xy 160.780605 -292.75869) (xy 160.754302 -292.717094)
			(xy 160.735011 -292.671818) (xy 160.723234 -292.624034) (xy 160.719274 -292.57498) (xy 160.380172 -292.57498)
			(xy 160.379677 -292.599587) (xy 160.371782 -292.648164) (xy 160.356198 -292.694845) (xy 160.333327 -292.738422)
			(xy 160.303762 -292.777766) (xy 160.268269 -292.811858) (xy 160.227766 -292.839814) (xy 160.183304 -292.860912)
			(xy 160.136033 -292.874604) (xy 160.087178 -292.880536) (xy 160.038003 -292.878555) (xy 159.989784 -292.868711)
			(xy 159.943768 -292.851259) (xy 159.901147 -292.826652) (xy 159.863026 -292.795527) (xy 159.830391 -292.75869)
			(xy 159.804088 -292.717094) (xy 159.784797 -292.671818) (xy 159.77302 -292.624034) (xy 159.76906 -292.57498)
			(xy 159.430212 -292.57498) (xy 159.429717 -292.599587) (xy 159.421822 -292.648164) (xy 159.406238 -292.694845)
			(xy 159.383367 -292.738422) (xy 159.353802 -292.777766) (xy 159.318309 -292.811858) (xy 159.277806 -292.839814)
			(xy 159.233344 -292.860912) (xy 159.186073 -292.874604) (xy 159.137218 -292.880536) (xy 159.088043 -292.878555)
			(xy 159.039824 -292.868711) (xy 158.993808 -292.851259) (xy 158.951187 -292.826652) (xy 158.913066 -292.795527)
			(xy 158.880431 -292.75869) (xy 158.854128 -292.717094) (xy 158.834837 -292.671818) (xy 158.82306 -292.624034)
			(xy 158.8191 -292.57498) (xy 158.531052 -292.57498) (xy 158.530554 -292.601629) (xy 158.522611 -292.654333)
			(xy 158.506901 -292.705263) (xy 158.483775 -292.753284) (xy 158.453751 -292.797321) (xy 158.417499 -292.836392)
			(xy 158.375828 -292.869623) (xy 158.32967 -292.896272) (xy 158.280056 -292.915744) (xy 158.228094 -292.927604)
			(xy 158.174944 -292.931588) (xy 158.121794 -292.927604) (xy 158.069832 -292.915744) (xy 158.020218 -292.896272)
			(xy 157.97406 -292.869623) (xy 157.932389 -292.836392) (xy 157.896137 -292.797321) (xy 157.866113 -292.753284)
			(xy 157.842987 -292.705263) (xy 157.827277 -292.654333) (xy 157.819334 -292.601629) (xy 157.529465 -292.601629)
			(xy 157.521902 -292.648164) (xy 157.506318 -292.694845) (xy 157.483447 -292.738422) (xy 157.453882 -292.777766)
			(xy 157.418389 -292.811858) (xy 157.377886 -292.839814) (xy 157.333424 -292.860912) (xy 157.286153 -292.874604)
			(xy 157.237298 -292.880536) (xy 157.188123 -292.878555) (xy 157.139904 -292.868711) (xy 157.093888 -292.851259)
			(xy 157.051267 -292.826652) (xy 157.013146 -292.795527) (xy 156.980511 -292.75869) (xy 156.954208 -292.717094)
			(xy 156.934917 -292.671818) (xy 156.92314 -292.624034) (xy 156.91918 -292.57498) (xy 156.580327 -292.57498)
			(xy 156.579837 -292.599333) (xy 156.571942 -292.64791) (xy 156.556358 -292.694591) (xy 156.533487 -292.738168)
			(xy 156.503922 -292.777512) (xy 156.468429 -292.811604) (xy 156.427926 -292.83956) (xy 156.383464 -292.860658)
			(xy 156.336193 -292.87435) (xy 156.287338 -292.880282) (xy 156.238163 -292.878301) (xy 156.189944 -292.868457)
			(xy 156.143928 -292.851005) (xy 156.101307 -292.826398) (xy 156.063186 -292.795273) (xy 156.030551 -292.758436)
			(xy 156.004248 -292.71684) (xy 155.984957 -292.671564) (xy 155.97318 -292.62378) (xy 155.96922 -292.574726)
			(xy 155.630372 -292.574726) (xy 155.629877 -292.599333) (xy 155.621982 -292.64791) (xy 155.606398 -292.694591)
			(xy 155.583527 -292.738168) (xy 155.553962 -292.777512) (xy 155.518469 -292.811604) (xy 155.477966 -292.83956)
			(xy 155.433504 -292.860658) (xy 155.386233 -292.87435) (xy 155.337378 -292.880282) (xy 155.288203 -292.878301)
			(xy 155.239984 -292.868457) (xy 155.193968 -292.851005) (xy 155.151347 -292.826398) (xy 155.113226 -292.795273)
			(xy 155.080591 -292.758436) (xy 155.054288 -292.71684) (xy 155.034997 -292.671564) (xy 155.02322 -292.62378)
			(xy 155.01926 -292.574726) (xy 154.680407 -292.574726) (xy 154.680412 -292.57498) (xy 154.679917 -292.599587)
			(xy 154.672022 -292.648164) (xy 154.656438 -292.694845) (xy 154.633567 -292.738422) (xy 154.604002 -292.777766)
			(xy 154.568509 -292.811858) (xy 154.528006 -292.839814) (xy 154.483544 -292.860912) (xy 154.436273 -292.874604)
			(xy 154.387418 -292.880536) (xy 154.338243 -292.878555) (xy 154.290024 -292.868711) (xy 154.244008 -292.851259)
			(xy 154.201387 -292.826652) (xy 154.163266 -292.795527) (xy 154.130631 -292.75869) (xy 154.104328 -292.717094)
			(xy 154.085037 -292.671818) (xy 154.07326 -292.624034) (xy 154.0693 -292.57498) (xy 153.730198 -292.57498)
			(xy 153.729703 -292.599587) (xy 153.721808 -292.648164) (xy 153.706224 -292.694845) (xy 153.683353 -292.738422)
			(xy 153.653788 -292.777766) (xy 153.618295 -292.811858) (xy 153.577792 -292.839814) (xy 153.53333 -292.860912)
			(xy 153.486059 -292.874604) (xy 153.437204 -292.880536) (xy 153.388029 -292.878555) (xy 153.33981 -292.868711)
			(xy 153.293794 -292.851259) (xy 153.251173 -292.826652) (xy 153.213052 -292.795527) (xy 153.180417 -292.75869)
			(xy 153.154114 -292.717094) (xy 153.134823 -292.671818) (xy 153.123046 -292.624034) (xy 153.119086 -292.57498)
			(xy 152.780238 -292.57498) (xy 152.779743 -292.599587) (xy 152.771848 -292.648164) (xy 152.756264 -292.694845)
			(xy 152.733393 -292.738422) (xy 152.703828 -292.777766) (xy 152.668335 -292.811858) (xy 152.627832 -292.839814)
			(xy 152.58337 -292.860912) (xy 152.536099 -292.874604) (xy 152.487244 -292.880536) (xy 152.438069 -292.878555)
			(xy 152.38985 -292.868711) (xy 152.343834 -292.851259) (xy 152.301213 -292.826652) (xy 152.263092 -292.795527)
			(xy 152.230457 -292.75869) (xy 152.204154 -292.717094) (xy 152.184863 -292.671818) (xy 152.173086 -292.624034)
			(xy 152.169126 -292.57498) (xy 148.177889 -292.57498) (xy 148.188959 -292.59922) (xy 148.204314 -292.651515)
			(xy 148.21207 -292.705463) (xy 148.212556 -292.732714) (xy 148.212006 -292.762096) (xy 148.202975 -292.820161)
			(xy 148.185143 -292.876154) (xy 148.158933 -292.928749) (xy 148.124966 -292.976701) (xy 148.084044 -293.018874)
			(xy 148.060918 -293.037006) (xy 148.05152 -293.044372) (xy 148.041106 -293.064946) (xy 148.039582 -293.168832)
			(xy 148.049488 -293.189914) (xy 148.058632 -293.19728) (xy 148.080459 -293.215509) (xy 148.118999 -293.257324)
			(xy 148.150908 -293.304395) (xy 148.175478 -293.35568) (xy 148.192166 -293.410043) (xy 148.200603 -293.466281)
			(xy 148.201126 -293.494714) (xy 148.8346 -293.494714) (xy 148.838671 -293.439092) (xy 148.850797 -293.384655)
			(xy 148.87072 -293.332564) (xy 148.898016 -293.283929) (xy 148.932102 -293.239786) (xy 148.972251 -293.201077)
			(xy 149.017609 -293.168626) (xy 149.067209 -293.143125) (xy 149.119993 -293.125118) (xy 149.174836 -293.114988)
			(xy 149.23057 -293.112951) (xy 149.286007 -293.119051) (xy 149.339964 -293.133157) (xy 149.391293 -293.154969)
			(xy 149.438899 -293.184023) (xy 149.481767 -293.219698) (xy 149.518984 -293.261235) (xy 149.549757 -293.307748)
			(xy 149.573429 -293.358245) (xy 149.589497 -293.411652) (xy 149.597617 -293.466828) (xy 149.598126 -293.494714)
			(xy 149.72106 -293.494714) (xy 149.725131 -293.439092) (xy 149.737257 -293.384655) (xy 149.75718 -293.332564)
			(xy 149.784476 -293.283929) (xy 149.818562 -293.239786) (xy 149.858711 -293.201077) (xy 149.904069 -293.168626)
			(xy 149.953669 -293.143125) (xy 150.006453 -293.125118) (xy 150.061296 -293.114988) (xy 150.11703 -293.112951)
			(xy 150.172467 -293.119051) (xy 150.226424 -293.133157) (xy 150.277753 -293.154969) (xy 150.325359 -293.184023)
			(xy 150.368227 -293.219698) (xy 150.405444 -293.261235) (xy 150.436217 -293.307748) (xy 150.459889 -293.358245)
			(xy 150.475957 -293.411652) (xy 150.484077 -293.466828) (xy 150.484586 -293.494714) (xy 150.484077 -293.5226)
			(xy 150.483733 -293.52494) (xy 154.0693 -293.52494) (xy 154.07326 -293.475886) (xy 154.085037 -293.428102)
			(xy 154.104328 -293.382826) (xy 154.130631 -293.34123) (xy 154.163266 -293.304393) (xy 154.201387 -293.273268)
			(xy 154.244008 -293.248661) (xy 154.290024 -293.231209) (xy 154.338243 -293.221365) (xy 154.387418 -293.219384)
			(xy 154.436273 -293.225316) (xy 154.483544 -293.239008) (xy 154.528006 -293.260106) (xy 154.568509 -293.288062)
			(xy 154.604002 -293.322154) (xy 154.633567 -293.361498) (xy 154.656438 -293.405075) (xy 154.672022 -293.451756)
			(xy 154.679917 -293.500333) (xy 154.680412 -293.52494) (xy 155.01926 -293.52494) (xy 155.02322 -293.475886)
			(xy 155.034997 -293.428102) (xy 155.054288 -293.382826) (xy 155.080591 -293.34123) (xy 155.113226 -293.304393)
			(xy 155.151347 -293.273268) (xy 155.193968 -293.248661) (xy 155.239984 -293.231209) (xy 155.288203 -293.221365)
			(xy 155.337378 -293.219384) (xy 155.386233 -293.225316) (xy 155.433504 -293.239008) (xy 155.477966 -293.260106)
			(xy 155.518469 -293.288062) (xy 155.553962 -293.322154) (xy 155.583527 -293.361498) (xy 155.606398 -293.405075)
			(xy 155.621982 -293.451756) (xy 155.629877 -293.500333) (xy 155.630372 -293.52494) (xy 155.96922 -293.52494)
			(xy 155.97318 -293.475886) (xy 155.984957 -293.428102) (xy 156.004248 -293.382826) (xy 156.030551 -293.34123)
			(xy 156.063186 -293.304393) (xy 156.101307 -293.273268) (xy 156.143928 -293.248661) (xy 156.189944 -293.231209)
			(xy 156.238163 -293.221365) (xy 156.287338 -293.219384) (xy 156.336193 -293.225316) (xy 156.383464 -293.239008)
			(xy 156.427926 -293.260106) (xy 156.468429 -293.288062) (xy 156.503922 -293.322154) (xy 156.533487 -293.361498)
			(xy 156.556358 -293.405075) (xy 156.571942 -293.451756) (xy 156.579837 -293.500333) (xy 156.580332 -293.52494)
			(xy 156.91918 -293.52494) (xy 156.92314 -293.475886) (xy 156.934917 -293.428102) (xy 156.954208 -293.382826)
			(xy 156.980511 -293.34123) (xy 157.013146 -293.304393) (xy 157.051267 -293.273268) (xy 157.093888 -293.248661)
			(xy 157.139904 -293.231209) (xy 157.188123 -293.221365) (xy 157.237298 -293.219384) (xy 157.286153 -293.225316)
			(xy 157.333424 -293.239008) (xy 157.377886 -293.260106) (xy 157.418389 -293.288062) (xy 157.453882 -293.322154)
			(xy 157.483447 -293.361498) (xy 157.506318 -293.405075) (xy 157.521902 -293.451756) (xy 157.529797 -293.500333)
			(xy 157.530292 -293.52494) (xy 157.86914 -293.52494) (xy 157.8731 -293.475886) (xy 157.884877 -293.428102)
			(xy 157.904168 -293.382826) (xy 157.930471 -293.34123) (xy 157.963106 -293.304393) (xy 158.001227 -293.273268)
			(xy 158.043848 -293.248661) (xy 158.089864 -293.231209) (xy 158.138083 -293.221365) (xy 158.187258 -293.219384)
			(xy 158.236113 -293.225316) (xy 158.283384 -293.239008) (xy 158.327846 -293.260106) (xy 158.368349 -293.288062)
			(xy 158.403842 -293.322154) (xy 158.433407 -293.361498) (xy 158.456278 -293.405075) (xy 158.471862 -293.451756)
			(xy 158.479757 -293.500333) (xy 158.480252 -293.52494) (xy 158.479757 -293.549547) (xy 158.479425 -293.551589)
			(xy 158.769294 -293.551589) (xy 158.769294 -293.498291) (xy 158.777237 -293.445587) (xy 158.792947 -293.394657)
			(xy 158.816073 -293.346636) (xy 158.846097 -293.302599) (xy 158.882349 -293.263528) (xy 158.92402 -293.230297)
			(xy 158.970178 -293.203648) (xy 159.019792 -293.184176) (xy 159.071754 -293.172316) (xy 159.124904 -293.168333)
			(xy 159.178054 -293.172316) (xy 159.230016 -293.184176) (xy 159.27963 -293.203648) (xy 159.325788 -293.230297)
			(xy 159.367459 -293.263528) (xy 159.403711 -293.302599) (xy 159.433735 -293.346636) (xy 159.456861 -293.394657)
			(xy 159.472571 -293.445587) (xy 159.480514 -293.498291) (xy 159.481012 -293.52494) (xy 159.76906 -293.52494)
			(xy 159.77302 -293.475886) (xy 159.784797 -293.428102) (xy 159.804088 -293.382826) (xy 159.830391 -293.34123)
			(xy 159.863026 -293.304393) (xy 159.901147 -293.273268) (xy 159.943768 -293.248661) (xy 159.989784 -293.231209)
			(xy 160.038003 -293.221365) (xy 160.087178 -293.219384) (xy 160.136033 -293.225316) (xy 160.183304 -293.239008)
			(xy 160.227766 -293.260106) (xy 160.268269 -293.288062) (xy 160.303762 -293.322154) (xy 160.333327 -293.361498)
			(xy 160.356198 -293.405075) (xy 160.371782 -293.451756) (xy 160.379677 -293.500333) (xy 160.380172 -293.52494)
			(xy 161.669234 -293.52494) (xy 161.673194 -293.475886) (xy 161.684971 -293.428102) (xy 161.704262 -293.382826)
			(xy 161.730565 -293.34123) (xy 161.7632 -293.304393) (xy 161.801321 -293.273268) (xy 161.843942 -293.248661)
			(xy 161.889958 -293.231209) (xy 161.938177 -293.221365) (xy 161.987352 -293.219384) (xy 162.036207 -293.225316)
			(xy 162.083478 -293.239008) (xy 162.12794 -293.260106) (xy 162.168443 -293.288062) (xy 162.203936 -293.322154)
			(xy 162.233501 -293.361498) (xy 162.256372 -293.405075) (xy 162.271956 -293.451756) (xy 162.279851 -293.500333)
			(xy 162.280346 -293.52494) (xy 163.569154 -293.52494) (xy 163.573114 -293.475886) (xy 163.584891 -293.428102)
			(xy 163.604182 -293.382826) (xy 163.630485 -293.34123) (xy 163.66312 -293.304393) (xy 163.701241 -293.273268)
			(xy 163.743862 -293.248661) (xy 163.789878 -293.231209) (xy 163.838097 -293.221365) (xy 163.887272 -293.219384)
			(xy 163.936127 -293.225316) (xy 163.983398 -293.239008) (xy 164.02786 -293.260106) (xy 164.068363 -293.288062)
			(xy 164.103856 -293.322154) (xy 164.133421 -293.361498) (xy 164.156292 -293.405075) (xy 164.171876 -293.451756)
			(xy 164.179771 -293.500333) (xy 164.180266 -293.52494) (xy 164.519114 -293.52494) (xy 164.523074 -293.475886)
			(xy 164.534851 -293.428102) (xy 164.554142 -293.382826) (xy 164.580445 -293.34123) (xy 164.61308 -293.304393)
			(xy 164.651201 -293.273268) (xy 164.693822 -293.248661) (xy 164.739838 -293.231209) (xy 164.788057 -293.221365)
			(xy 164.837232 -293.219384) (xy 164.886087 -293.225316) (xy 164.933358 -293.239008) (xy 164.97782 -293.260106)
			(xy 165.018323 -293.288062) (xy 165.053816 -293.322154) (xy 165.083381 -293.361498) (xy 165.106252 -293.405075)
			(xy 165.121836 -293.451756) (xy 165.129731 -293.500333) (xy 165.130226 -293.52494) (xy 166.419288 -293.52494)
			(xy 166.423248 -293.475886) (xy 166.435025 -293.428102) (xy 166.454316 -293.382826) (xy 166.480619 -293.34123)
			(xy 166.513254 -293.304393) (xy 166.551375 -293.273268) (xy 166.593996 -293.248661) (xy 166.640012 -293.231209)
			(xy 166.688231 -293.221365) (xy 166.737406 -293.219384) (xy 166.786261 -293.225316) (xy 166.833532 -293.239008)
			(xy 166.877994 -293.260106) (xy 166.918497 -293.288062) (xy 166.95399 -293.322154) (xy 166.983555 -293.361498)
			(xy 167.006426 -293.405075) (xy 167.02201 -293.451756) (xy 167.029905 -293.500333) (xy 167.0304 -293.52494)
			(xy 168.319208 -293.52494) (xy 168.323168 -293.475886) (xy 168.334945 -293.428102) (xy 168.354236 -293.382826)
			(xy 168.380539 -293.34123) (xy 168.413174 -293.304393) (xy 168.451295 -293.273268) (xy 168.493916 -293.248661)
			(xy 168.539932 -293.231209) (xy 168.588151 -293.221365) (xy 168.637326 -293.219384) (xy 168.686181 -293.225316)
			(xy 168.733452 -293.239008) (xy 168.777914 -293.260106) (xy 168.818417 -293.288062) (xy 168.85391 -293.322154)
			(xy 168.883475 -293.361498) (xy 168.906346 -293.405075) (xy 168.92193 -293.451756) (xy 168.929825 -293.500333)
			(xy 168.93032 -293.52494) (xy 170.219128 -293.52494) (xy 170.223088 -293.475886) (xy 170.234865 -293.428102)
			(xy 170.254156 -293.382826) (xy 170.280459 -293.34123) (xy 170.313094 -293.304393) (xy 170.351215 -293.273268)
			(xy 170.393836 -293.248661) (xy 170.439852 -293.231209) (xy 170.488071 -293.221365) (xy 170.537246 -293.219384)
			(xy 170.586101 -293.225316) (xy 170.633372 -293.239008) (xy 170.677834 -293.260106) (xy 170.718337 -293.288062)
			(xy 170.75383 -293.322154) (xy 170.783395 -293.361498) (xy 170.806266 -293.405075) (xy 170.82185 -293.451756)
			(xy 170.829745 -293.500333) (xy 170.83024 -293.52494) (xy 172.119048 -293.52494) (xy 172.123008 -293.475886)
			(xy 172.134785 -293.428102) (xy 172.154076 -293.382826) (xy 172.180379 -293.34123) (xy 172.213014 -293.304393)
			(xy 172.251135 -293.273268) (xy 172.293756 -293.248661) (xy 172.339772 -293.231209) (xy 172.387991 -293.221365)
			(xy 172.437166 -293.219384) (xy 172.486021 -293.225316) (xy 172.533292 -293.239008) (xy 172.577754 -293.260106)
			(xy 172.618257 -293.288062) (xy 172.65375 -293.322154) (xy 172.683315 -293.361498) (xy 172.706186 -293.405075)
			(xy 172.72177 -293.451756) (xy 172.729665 -293.500333) (xy 172.73016 -293.52494) (xy 174.019222 -293.52494)
			(xy 174.023182 -293.475886) (xy 174.034959 -293.428102) (xy 174.05425 -293.382826) (xy 174.080553 -293.34123)
			(xy 174.113188 -293.304393) (xy 174.151309 -293.273268) (xy 174.19393 -293.248661) (xy 174.239946 -293.231209)
			(xy 174.288165 -293.221365) (xy 174.33734 -293.219384) (xy 174.386195 -293.225316) (xy 174.433466 -293.239008)
			(xy 174.477928 -293.260106) (xy 174.518431 -293.288062) (xy 174.553924 -293.322154) (xy 174.583489 -293.361498)
			(xy 174.60636 -293.405075) (xy 174.621944 -293.451756) (xy 174.629839 -293.500333) (xy 174.630334 -293.52494)
			(xy 176.869102 -293.52494) (xy 176.873062 -293.475886) (xy 176.884839 -293.428102) (xy 176.90413 -293.382826)
			(xy 176.930433 -293.34123) (xy 176.963068 -293.304393) (xy 177.001189 -293.273268) (xy 177.04381 -293.248661)
			(xy 177.089826 -293.231209) (xy 177.138045 -293.221365) (xy 177.18722 -293.219384) (xy 177.236075 -293.225316)
			(xy 177.283346 -293.239008) (xy 177.327808 -293.260106) (xy 177.368311 -293.288062) (xy 177.403804 -293.322154)
			(xy 177.433369 -293.361498) (xy 177.45624 -293.405075) (xy 177.471824 -293.451756) (xy 177.479719 -293.500333)
			(xy 177.480214 -293.52494) (xy 178.769276 -293.52494) (xy 178.773236 -293.475886) (xy 178.785013 -293.428102)
			(xy 178.804304 -293.382826) (xy 178.830607 -293.34123) (xy 178.863242 -293.304393) (xy 178.901363 -293.273268)
			(xy 178.943984 -293.248661) (xy 178.99 -293.231209) (xy 179.038219 -293.221365) (xy 179.087394 -293.219384)
			(xy 179.136249 -293.225316) (xy 179.18352 -293.239008) (xy 179.227982 -293.260106) (xy 179.268485 -293.288062)
			(xy 179.303978 -293.322154) (xy 179.333543 -293.361498) (xy 179.356414 -293.405075) (xy 179.371998 -293.451756)
			(xy 179.379893 -293.500333) (xy 179.380388 -293.52494) (xy 180.669196 -293.52494) (xy 180.673156 -293.475886)
			(xy 180.684933 -293.428102) (xy 180.704224 -293.382826) (xy 180.730527 -293.34123) (xy 180.763162 -293.304393)
			(xy 180.801283 -293.273268) (xy 180.843904 -293.248661) (xy 180.88992 -293.231209) (xy 180.938139 -293.221365)
			(xy 180.987314 -293.219384) (xy 181.036169 -293.225316) (xy 181.08344 -293.239008) (xy 181.127902 -293.260106)
			(xy 181.168405 -293.288062) (xy 181.203898 -293.322154) (xy 181.233463 -293.361498) (xy 181.256334 -293.405075)
			(xy 181.271918 -293.451756) (xy 181.279813 -293.500333) (xy 181.280308 -293.52494) (xy 182.569116 -293.52494)
			(xy 182.573076 -293.475886) (xy 182.584853 -293.428102) (xy 182.604144 -293.382826) (xy 182.630447 -293.34123)
			(xy 182.663082 -293.304393) (xy 182.701203 -293.273268) (xy 182.743824 -293.248661) (xy 182.78984 -293.231209)
			(xy 182.838059 -293.221365) (xy 182.887234 -293.219384) (xy 182.936089 -293.225316) (xy 182.98336 -293.239008)
			(xy 183.027822 -293.260106) (xy 183.068325 -293.288062) (xy 183.103818 -293.322154) (xy 183.133383 -293.361498)
			(xy 183.156254 -293.405075) (xy 183.171838 -293.451756) (xy 183.179733 -293.500333) (xy 183.180228 -293.52494)
			(xy 184.469036 -293.52494) (xy 184.472996 -293.475886) (xy 184.484773 -293.428102) (xy 184.504064 -293.382826)
			(xy 184.530367 -293.34123) (xy 184.563002 -293.304393) (xy 184.601123 -293.273268) (xy 184.643744 -293.248661)
			(xy 184.68976 -293.231209) (xy 184.737979 -293.221365) (xy 184.787154 -293.219384) (xy 184.836009 -293.225316)
			(xy 184.88328 -293.239008) (xy 184.927742 -293.260106) (xy 184.968245 -293.288062) (xy 185.003738 -293.322154)
			(xy 185.033303 -293.361498) (xy 185.056174 -293.405075) (xy 185.071758 -293.451756) (xy 185.079653 -293.500333)
			(xy 185.080148 -293.52494) (xy 185.079653 -293.549547) (xy 185.071758 -293.598124) (xy 185.056174 -293.644805)
			(xy 185.033303 -293.688382) (xy 185.003738 -293.727726) (xy 184.968245 -293.761818) (xy 184.927742 -293.789774)
			(xy 184.88328 -293.810872) (xy 184.836009 -293.824564) (xy 184.787154 -293.830496) (xy 184.737979 -293.828515)
			(xy 184.68976 -293.818671) (xy 184.643744 -293.801219) (xy 184.601123 -293.776612) (xy 184.563002 -293.745487)
			(xy 184.530367 -293.70865) (xy 184.504064 -293.667054) (xy 184.484773 -293.621778) (xy 184.472996 -293.573994)
			(xy 184.469036 -293.52494) (xy 183.180228 -293.52494) (xy 183.179733 -293.549547) (xy 183.171838 -293.598124)
			(xy 183.156254 -293.644805) (xy 183.133383 -293.688382) (xy 183.103818 -293.727726) (xy 183.068325 -293.761818)
			(xy 183.027822 -293.789774) (xy 182.98336 -293.810872) (xy 182.936089 -293.824564) (xy 182.887234 -293.830496)
			(xy 182.838059 -293.828515) (xy 182.78984 -293.818671) (xy 182.743824 -293.801219) (xy 182.701203 -293.776612)
			(xy 182.663082 -293.745487) (xy 182.630447 -293.70865) (xy 182.604144 -293.667054) (xy 182.584853 -293.621778)
			(xy 182.573076 -293.573994) (xy 182.569116 -293.52494) (xy 181.280308 -293.52494) (xy 181.279813 -293.549547)
			(xy 181.271918 -293.598124) (xy 181.256334 -293.644805) (xy 181.233463 -293.688382) (xy 181.203898 -293.727726)
			(xy 181.168405 -293.761818) (xy 181.127902 -293.789774) (xy 181.08344 -293.810872) (xy 181.036169 -293.824564)
			(xy 180.987314 -293.830496) (xy 180.938139 -293.828515) (xy 180.88992 -293.818671) (xy 180.843904 -293.801219)
			(xy 180.801283 -293.776612) (xy 180.763162 -293.745487) (xy 180.730527 -293.70865) (xy 180.704224 -293.667054)
			(xy 180.684933 -293.621778) (xy 180.673156 -293.573994) (xy 180.669196 -293.52494) (xy 179.380388 -293.52494)
			(xy 179.379893 -293.549547) (xy 179.371998 -293.598124) (xy 179.356414 -293.644805) (xy 179.333543 -293.688382)
			(xy 179.303978 -293.727726) (xy 179.268485 -293.761818) (xy 179.227982 -293.789774) (xy 179.18352 -293.810872)
			(xy 179.136249 -293.824564) (xy 179.087394 -293.830496) (xy 179.038219 -293.828515) (xy 178.99 -293.818671)
			(xy 178.943984 -293.801219) (xy 178.901363 -293.776612) (xy 178.863242 -293.745487) (xy 178.830607 -293.70865)
			(xy 178.804304 -293.667054) (xy 178.785013 -293.621778) (xy 178.773236 -293.573994) (xy 178.769276 -293.52494)
			(xy 177.480214 -293.52494) (xy 177.479719 -293.549547) (xy 177.471824 -293.598124) (xy 177.45624 -293.644805)
			(xy 177.433369 -293.688382) (xy 177.403804 -293.727726) (xy 177.368311 -293.761818) (xy 177.327808 -293.789774)
			(xy 177.283346 -293.810872) (xy 177.236075 -293.824564) (xy 177.18722 -293.830496) (xy 177.138045 -293.828515)
			(xy 177.089826 -293.818671) (xy 177.04381 -293.801219) (xy 177.001189 -293.776612) (xy 176.963068 -293.745487)
			(xy 176.930433 -293.70865) (xy 176.90413 -293.667054) (xy 176.884839 -293.621778) (xy 176.873062 -293.573994)
			(xy 176.869102 -293.52494) (xy 174.630334 -293.52494) (xy 174.629839 -293.549547) (xy 174.621944 -293.598124)
			(xy 174.60636 -293.644805) (xy 174.583489 -293.688382) (xy 174.553924 -293.727726) (xy 174.518431 -293.761818)
			(xy 174.477928 -293.789774) (xy 174.433466 -293.810872) (xy 174.386195 -293.824564) (xy 174.33734 -293.830496)
			(xy 174.288165 -293.828515) (xy 174.239946 -293.818671) (xy 174.19393 -293.801219) (xy 174.151309 -293.776612)
			(xy 174.113188 -293.745487) (xy 174.080553 -293.70865) (xy 174.05425 -293.667054) (xy 174.034959 -293.621778)
			(xy 174.023182 -293.573994) (xy 174.019222 -293.52494) (xy 172.73016 -293.52494) (xy 172.729665 -293.549547)
			(xy 172.72177 -293.598124) (xy 172.706186 -293.644805) (xy 172.683315 -293.688382) (xy 172.65375 -293.727726)
			(xy 172.618257 -293.761818) (xy 172.577754 -293.789774) (xy 172.533292 -293.810872) (xy 172.486021 -293.824564)
			(xy 172.437166 -293.830496) (xy 172.387991 -293.828515) (xy 172.339772 -293.818671) (xy 172.293756 -293.801219)
			(xy 172.251135 -293.776612) (xy 172.213014 -293.745487) (xy 172.180379 -293.70865) (xy 172.154076 -293.667054)
			(xy 172.134785 -293.621778) (xy 172.123008 -293.573994) (xy 172.119048 -293.52494) (xy 170.83024 -293.52494)
			(xy 170.829745 -293.549547) (xy 170.82185 -293.598124) (xy 170.806266 -293.644805) (xy 170.783395 -293.688382)
			(xy 170.75383 -293.727726) (xy 170.718337 -293.761818) (xy 170.677834 -293.789774) (xy 170.633372 -293.810872)
			(xy 170.586101 -293.824564) (xy 170.537246 -293.830496) (xy 170.488071 -293.828515) (xy 170.439852 -293.818671)
			(xy 170.393836 -293.801219) (xy 170.351215 -293.776612) (xy 170.313094 -293.745487) (xy 170.280459 -293.70865)
			(xy 170.254156 -293.667054) (xy 170.234865 -293.621778) (xy 170.223088 -293.573994) (xy 170.219128 -293.52494)
			(xy 168.93032 -293.52494) (xy 168.929825 -293.549547) (xy 168.92193 -293.598124) (xy 168.906346 -293.644805)
			(xy 168.883475 -293.688382) (xy 168.85391 -293.727726) (xy 168.818417 -293.761818) (xy 168.777914 -293.789774)
			(xy 168.733452 -293.810872) (xy 168.686181 -293.824564) (xy 168.637326 -293.830496) (xy 168.588151 -293.828515)
			(xy 168.539932 -293.818671) (xy 168.493916 -293.801219) (xy 168.451295 -293.776612) (xy 168.413174 -293.745487)
			(xy 168.380539 -293.70865) (xy 168.354236 -293.667054) (xy 168.334945 -293.621778) (xy 168.323168 -293.573994)
			(xy 168.319208 -293.52494) (xy 167.0304 -293.52494) (xy 167.029905 -293.549547) (xy 167.02201 -293.598124)
			(xy 167.006426 -293.644805) (xy 166.983555 -293.688382) (xy 166.95399 -293.727726) (xy 166.918497 -293.761818)
			(xy 166.877994 -293.789774) (xy 166.833532 -293.810872) (xy 166.786261 -293.824564) (xy 166.737406 -293.830496)
			(xy 166.688231 -293.828515) (xy 166.640012 -293.818671) (xy 166.593996 -293.801219) (xy 166.551375 -293.776612)
			(xy 166.513254 -293.745487) (xy 166.480619 -293.70865) (xy 166.454316 -293.667054) (xy 166.435025 -293.621778)
			(xy 166.423248 -293.573994) (xy 166.419288 -293.52494) (xy 165.130226 -293.52494) (xy 165.129731 -293.549547)
			(xy 165.121836 -293.598124) (xy 165.106252 -293.644805) (xy 165.083381 -293.688382) (xy 165.053816 -293.727726)
			(xy 165.018323 -293.761818) (xy 164.97782 -293.789774) (xy 164.933358 -293.810872) (xy 164.886087 -293.824564)
			(xy 164.837232 -293.830496) (xy 164.788057 -293.828515) (xy 164.739838 -293.818671) (xy 164.693822 -293.801219)
			(xy 164.651201 -293.776612) (xy 164.61308 -293.745487) (xy 164.580445 -293.70865) (xy 164.554142 -293.667054)
			(xy 164.534851 -293.621778) (xy 164.523074 -293.573994) (xy 164.519114 -293.52494) (xy 164.180266 -293.52494)
			(xy 164.179771 -293.549547) (xy 164.171876 -293.598124) (xy 164.156292 -293.644805) (xy 164.133421 -293.688382)
			(xy 164.103856 -293.727726) (xy 164.068363 -293.761818) (xy 164.02786 -293.789774) (xy 163.983398 -293.810872)
			(xy 163.936127 -293.824564) (xy 163.887272 -293.830496) (xy 163.838097 -293.828515) (xy 163.789878 -293.818671)
			(xy 163.743862 -293.801219) (xy 163.701241 -293.776612) (xy 163.66312 -293.745487) (xy 163.630485 -293.70865)
			(xy 163.604182 -293.667054) (xy 163.584891 -293.621778) (xy 163.573114 -293.573994) (xy 163.569154 -293.52494)
			(xy 162.280346 -293.52494) (xy 162.279851 -293.549547) (xy 162.271956 -293.598124) (xy 162.256372 -293.644805)
			(xy 162.233501 -293.688382) (xy 162.203936 -293.727726) (xy 162.168443 -293.761818) (xy 162.12794 -293.789774)
			(xy 162.083478 -293.810872) (xy 162.036207 -293.824564) (xy 161.987352 -293.830496) (xy 161.938177 -293.828515)
			(xy 161.889958 -293.818671) (xy 161.843942 -293.801219) (xy 161.801321 -293.776612) (xy 161.7632 -293.745487)
			(xy 161.730565 -293.70865) (xy 161.704262 -293.667054) (xy 161.684971 -293.621778) (xy 161.673194 -293.573994)
			(xy 161.669234 -293.52494) (xy 160.380172 -293.52494) (xy 160.379677 -293.549547) (xy 160.371782 -293.598124)
			(xy 160.356198 -293.644805) (xy 160.333327 -293.688382) (xy 160.303762 -293.727726) (xy 160.268269 -293.761818)
			(xy 160.227766 -293.789774) (xy 160.183304 -293.810872) (xy 160.136033 -293.824564) (xy 160.087178 -293.830496)
			(xy 160.038003 -293.828515) (xy 159.989784 -293.818671) (xy 159.943768 -293.801219) (xy 159.901147 -293.776612)
			(xy 159.863026 -293.745487) (xy 159.830391 -293.70865) (xy 159.804088 -293.667054) (xy 159.784797 -293.621778)
			(xy 159.77302 -293.573994) (xy 159.76906 -293.52494) (xy 159.481012 -293.52494) (xy 159.480514 -293.551589)
			(xy 159.472571 -293.604293) (xy 159.456861 -293.655223) (xy 159.433735 -293.703244) (xy 159.403711 -293.747281)
			(xy 159.367459 -293.786352) (xy 159.325788 -293.819583) (xy 159.27963 -293.846232) (xy 159.230016 -293.865704)
			(xy 159.178054 -293.877564) (xy 159.124904 -293.881548) (xy 159.071754 -293.877564) (xy 159.019792 -293.865704)
			(xy 158.970178 -293.846232) (xy 158.92402 -293.819583) (xy 158.882349 -293.786352) (xy 158.846097 -293.747281)
			(xy 158.816073 -293.703244) (xy 158.792947 -293.655223) (xy 158.777237 -293.604293) (xy 158.769294 -293.551589)
			(xy 158.479425 -293.551589) (xy 158.471862 -293.598124) (xy 158.456278 -293.644805) (xy 158.433407 -293.688382)
			(xy 158.403842 -293.727726) (xy 158.368349 -293.761818) (xy 158.327846 -293.789774) (xy 158.283384 -293.810872)
			(xy 158.236113 -293.824564) (xy 158.187258 -293.830496) (xy 158.138083 -293.828515) (xy 158.089864 -293.818671)
			(xy 158.043848 -293.801219) (xy 158.001227 -293.776612) (xy 157.963106 -293.745487) (xy 157.930471 -293.70865)
			(xy 157.904168 -293.667054) (xy 157.884877 -293.621778) (xy 157.8731 -293.573994) (xy 157.86914 -293.52494)
			(xy 157.530292 -293.52494) (xy 157.529797 -293.549547) (xy 157.521902 -293.598124) (xy 157.506318 -293.644805)
			(xy 157.483447 -293.688382) (xy 157.453882 -293.727726) (xy 157.418389 -293.761818) (xy 157.377886 -293.789774)
			(xy 157.333424 -293.810872) (xy 157.286153 -293.824564) (xy 157.237298 -293.830496) (xy 157.188123 -293.828515)
			(xy 157.139904 -293.818671) (xy 157.093888 -293.801219) (xy 157.051267 -293.776612) (xy 157.013146 -293.745487)
			(xy 156.980511 -293.70865) (xy 156.954208 -293.667054) (xy 156.934917 -293.621778) (xy 156.92314 -293.573994)
			(xy 156.91918 -293.52494) (xy 156.580332 -293.52494) (xy 156.579837 -293.549547) (xy 156.571942 -293.598124)
			(xy 156.556358 -293.644805) (xy 156.533487 -293.688382) (xy 156.503922 -293.727726) (xy 156.468429 -293.761818)
			(xy 156.427926 -293.789774) (xy 156.383464 -293.810872) (xy 156.336193 -293.824564) (xy 156.287338 -293.830496)
			(xy 156.238163 -293.828515) (xy 156.189944 -293.818671) (xy 156.143928 -293.801219) (xy 156.101307 -293.776612)
			(xy 156.063186 -293.745487) (xy 156.030551 -293.70865) (xy 156.004248 -293.667054) (xy 155.984957 -293.621778)
			(xy 155.97318 -293.573994) (xy 155.96922 -293.52494) (xy 155.630372 -293.52494) (xy 155.629877 -293.549547)
			(xy 155.621982 -293.598124) (xy 155.606398 -293.644805) (xy 155.583527 -293.688382) (xy 155.553962 -293.727726)
			(xy 155.518469 -293.761818) (xy 155.477966 -293.789774) (xy 155.433504 -293.810872) (xy 155.386233 -293.824564)
			(xy 155.337378 -293.830496) (xy 155.288203 -293.828515) (xy 155.239984 -293.818671) (xy 155.193968 -293.801219)
			(xy 155.151347 -293.776612) (xy 155.113226 -293.745487) (xy 155.080591 -293.70865) (xy 155.054288 -293.667054)
			(xy 155.034997 -293.621778) (xy 155.02322 -293.573994) (xy 155.01926 -293.52494) (xy 154.680412 -293.52494)
			(xy 154.679917 -293.549547) (xy 154.672022 -293.598124) (xy 154.656438 -293.644805) (xy 154.633567 -293.688382)
			(xy 154.604002 -293.727726) (xy 154.568509 -293.761818) (xy 154.528006 -293.789774) (xy 154.483544 -293.810872)
			(xy 154.436273 -293.824564) (xy 154.387418 -293.830496) (xy 154.338243 -293.828515) (xy 154.290024 -293.818671)
			(xy 154.244008 -293.801219) (xy 154.201387 -293.776612) (xy 154.163266 -293.745487) (xy 154.130631 -293.70865)
			(xy 154.104328 -293.667054) (xy 154.085037 -293.621778) (xy 154.07326 -293.573994) (xy 154.0693 -293.52494)
			(xy 150.483733 -293.52494) (xy 150.475957 -293.577776) (xy 150.459889 -293.631183) (xy 150.436217 -293.68168)
			(xy 150.405444 -293.728193) (xy 150.368227 -293.76973) (xy 150.325359 -293.805405) (xy 150.277753 -293.834459)
			(xy 150.226424 -293.856271) (xy 150.172467 -293.870377) (xy 150.11703 -293.876477) (xy 150.061296 -293.87444)
			(xy 150.006453 -293.86431) (xy 149.953669 -293.846303) (xy 149.904069 -293.820802) (xy 149.858711 -293.788351)
			(xy 149.818562 -293.749642) (xy 149.784476 -293.705499) (xy 149.75718 -293.656864) (xy 149.737257 -293.604773)
			(xy 149.725131 -293.550336) (xy 149.72106 -293.494714) (xy 149.598126 -293.494714) (xy 149.597617 -293.5226)
			(xy 149.589497 -293.577776) (xy 149.573429 -293.631183) (xy 149.549757 -293.68168) (xy 149.518984 -293.728193)
			(xy 149.481767 -293.76973) (xy 149.438899 -293.805405) (xy 149.391293 -293.834459) (xy 149.339964 -293.856271)
			(xy 149.286007 -293.870377) (xy 149.23057 -293.876477) (xy 149.174836 -293.87444) (xy 149.119993 -293.86431)
			(xy 149.067209 -293.846303) (xy 149.017609 -293.820802) (xy 148.972251 -293.788351) (xy 148.932102 -293.749642)
			(xy 148.898016 -293.705499) (xy 148.87072 -293.656864) (xy 148.850797 -293.604773) (xy 148.838671 -293.550336)
			(xy 148.8346 -293.494714) (xy 148.201126 -293.494714) (xy 148.20064 -293.521965) (xy 148.192884 -293.575913)
			(xy 148.177529 -293.628208) (xy 148.154887 -293.677785) (xy 148.125421 -293.723635) (xy 148.08973 -293.764826)
			(xy 148.048539 -293.800517) (xy 148.002689 -293.829983) (xy 147.953112 -293.852625) (xy 147.900817 -293.86798)
			(xy 147.846869 -293.875736) (xy 147.792367 -293.875736) (xy 147.738419 -293.86798) (xy 147.686124 -293.852625)
			(xy 147.636547 -293.829983) (xy 147.590697 -293.800517) (xy 147.549506 -293.764826) (xy 147.513815 -293.723635)
			(xy 147.484349 -293.677785) (xy 147.461707 -293.628208) (xy 147.446352 -293.575913) (xy 147.438596 -293.521965)
			(xy 147.43811 -293.494714) (xy 134.892796 -293.494714) (xy 134.463282 -293.924228) (xy 134.455886 -293.931079)
			(xy 134.437287 -293.938819) (xy 134.427214 -293.939214) (xy 119.198136 -293.939214) (xy 119.188071 -293.939649)
			(xy 119.169485 -293.947381) (xy 119.162068 -293.9542) (xy 118.898924 -294.217344) (xy 118.892082 -294.224744)
			(xy 118.884359 -294.243342) (xy 118.883938 -294.253412) (xy 118.883938 -294.630856) (xy 141.911576 -294.630856)
			(xy 141.915647 -294.575234) (xy 141.927773 -294.520797) (xy 141.947696 -294.468706) (xy 141.974992 -294.420071)
			(xy 142.009078 -294.375928) (xy 142.049227 -294.337219) (xy 142.094585 -294.304768) (xy 142.144185 -294.279267)
			(xy 142.196969 -294.26126) (xy 142.251812 -294.25113) (xy 142.307546 -294.249093) (xy 142.362983 -294.255193)
			(xy 142.41694 -294.269299) (xy 142.468269 -294.291111) (xy 142.515875 -294.320165) (xy 142.558743 -294.35584)
			(xy 142.59596 -294.397377) (xy 142.626733 -294.44389) (xy 142.650405 -294.494387) (xy 142.666473 -294.547794)
			(xy 142.674593 -294.60297) (xy 142.675102 -294.630856) (xy 143.396714 -294.630856) (xy 143.400785 -294.575234)
			(xy 143.412911 -294.520797) (xy 143.432834 -294.468706) (xy 143.46013 -294.420071) (xy 143.494216 -294.375928)
			(xy 143.534365 -294.337219) (xy 143.579723 -294.304768) (xy 143.629323 -294.279267) (xy 143.682107 -294.26126)
			(xy 143.73695 -294.25113) (xy 143.792684 -294.249093) (xy 143.848121 -294.255193) (xy 143.902078 -294.269299)
			(xy 143.953407 -294.291111) (xy 144.001013 -294.320165) (xy 144.043881 -294.35584) (xy 144.081098 -294.397377)
			(xy 144.111871 -294.44389) (xy 144.126408 -294.4749) (xy 152.169126 -294.4749) (xy 152.173086 -294.425846)
			(xy 152.184863 -294.378062) (xy 152.204154 -294.332786) (xy 152.230457 -294.29119) (xy 152.263092 -294.254353)
			(xy 152.301213 -294.223228) (xy 152.343834 -294.198621) (xy 152.38985 -294.181169) (xy 152.438069 -294.171325)
			(xy 152.487244 -294.169344) (xy 152.536099 -294.175276) (xy 152.58337 -294.188968) (xy 152.627832 -294.210066)
			(xy 152.668335 -294.238022) (xy 152.703828 -294.272114) (xy 152.733393 -294.311458) (xy 152.756264 -294.355035)
			(xy 152.771848 -294.401716) (xy 152.779743 -294.450293) (xy 152.780238 -294.4749) (xy 153.119086 -294.4749)
			(xy 153.123046 -294.425846) (xy 153.134823 -294.378062) (xy 153.154114 -294.332786) (xy 153.180417 -294.29119)
			(xy 153.213052 -294.254353) (xy 153.251173 -294.223228) (xy 153.293794 -294.198621) (xy 153.33981 -294.181169)
			(xy 153.388029 -294.171325) (xy 153.437204 -294.169344) (xy 153.486059 -294.175276) (xy 153.53333 -294.188968)
			(xy 153.577792 -294.210066) (xy 153.618295 -294.238022) (xy 153.653788 -294.272114) (xy 153.683353 -294.311458)
			(xy 153.706224 -294.355035) (xy 153.721808 -294.401716) (xy 153.729703 -294.450293) (xy 153.730198 -294.4749)
			(xy 154.0693 -294.4749) (xy 154.07326 -294.425846) (xy 154.085037 -294.378062) (xy 154.104328 -294.332786)
			(xy 154.130631 -294.29119) (xy 154.163266 -294.254353) (xy 154.201387 -294.223228) (xy 154.244008 -294.198621)
			(xy 154.290024 -294.181169) (xy 154.338243 -294.171325) (xy 154.387418 -294.169344) (xy 154.436273 -294.175276)
			(xy 154.483544 -294.188968) (xy 154.528006 -294.210066) (xy 154.568509 -294.238022) (xy 154.604002 -294.272114)
			(xy 154.633567 -294.311458) (xy 154.656438 -294.355035) (xy 154.672022 -294.401716) (xy 154.679917 -294.450293)
			(xy 154.680412 -294.4749) (xy 156.91918 -294.4749) (xy 156.92314 -294.425846) (xy 156.934917 -294.378062)
			(xy 156.954208 -294.332786) (xy 156.980511 -294.29119) (xy 157.013146 -294.254353) (xy 157.051267 -294.223228)
			(xy 157.093888 -294.198621) (xy 157.139904 -294.181169) (xy 157.188123 -294.171325) (xy 157.237298 -294.169344)
			(xy 157.286153 -294.175276) (xy 157.333424 -294.188968) (xy 157.377886 -294.210066) (xy 157.418389 -294.238022)
			(xy 157.453882 -294.272114) (xy 157.483447 -294.311458) (xy 157.506318 -294.355035) (xy 157.521902 -294.401716)
			(xy 157.529797 -294.450293) (xy 157.530292 -294.4749) (xy 157.529797 -294.499507) (xy 157.529465 -294.501549)
			(xy 157.819334 -294.501549) (xy 157.819334 -294.448251) (xy 157.827277 -294.395547) (xy 157.842987 -294.344617)
			(xy 157.866113 -294.296596) (xy 157.896137 -294.252559) (xy 157.932389 -294.213488) (xy 157.97406 -294.180257)
			(xy 158.020218 -294.153608) (xy 158.069832 -294.134136) (xy 158.121794 -294.122276) (xy 158.174944 -294.118293)
			(xy 158.228094 -294.122276) (xy 158.280056 -294.134136) (xy 158.32967 -294.153608) (xy 158.375828 -294.180257)
			(xy 158.417499 -294.213488) (xy 158.453751 -294.252559) (xy 158.483775 -294.296596) (xy 158.506901 -294.344617)
			(xy 158.522611 -294.395547) (xy 158.530554 -294.448251) (xy 158.531052 -294.4749) (xy 158.8191 -294.4749)
			(xy 158.82306 -294.425846) (xy 158.834837 -294.378062) (xy 158.854128 -294.332786) (xy 158.880431 -294.29119)
			(xy 158.913066 -294.254353) (xy 158.951187 -294.223228) (xy 158.993808 -294.198621) (xy 159.039824 -294.181169)
			(xy 159.088043 -294.171325) (xy 159.137218 -294.169344) (xy 159.186073 -294.175276) (xy 159.233344 -294.188968)
			(xy 159.277806 -294.210066) (xy 159.318309 -294.238022) (xy 159.353802 -294.272114) (xy 159.383367 -294.311458)
			(xy 159.406238 -294.355035) (xy 159.421822 -294.401716) (xy 159.429717 -294.450293) (xy 159.430212 -294.4749)
			(xy 159.76906 -294.4749) (xy 159.77302 -294.425846) (xy 159.784797 -294.378062) (xy 159.804088 -294.332786)
			(xy 159.830391 -294.29119) (xy 159.863026 -294.254353) (xy 159.901147 -294.223228) (xy 159.943768 -294.198621)
			(xy 159.989784 -294.181169) (xy 160.038003 -294.171325) (xy 160.087178 -294.169344) (xy 160.136033 -294.175276)
			(xy 160.183304 -294.188968) (xy 160.227766 -294.210066) (xy 160.268269 -294.238022) (xy 160.303762 -294.272114)
			(xy 160.333327 -294.311458) (xy 160.356198 -294.355035) (xy 160.371782 -294.401716) (xy 160.379677 -294.450293)
			(xy 160.380172 -294.4749) (xy 160.719274 -294.4749) (xy 160.723234 -294.425846) (xy 160.735011 -294.378062)
			(xy 160.754302 -294.332786) (xy 160.780605 -294.29119) (xy 160.81324 -294.254353) (xy 160.851361 -294.223228)
			(xy 160.893982 -294.198621) (xy 160.939998 -294.181169) (xy 160.988217 -294.171325) (xy 161.037392 -294.169344)
			(xy 161.086247 -294.175276) (xy 161.133518 -294.188968) (xy 161.17798 -294.210066) (xy 161.218483 -294.238022)
			(xy 161.253976 -294.272114) (xy 161.283541 -294.311458) (xy 161.306412 -294.355035) (xy 161.321996 -294.401716)
			(xy 161.329891 -294.450293) (xy 161.330386 -294.4749) (xy 161.669234 -294.4749) (xy 161.673194 -294.425846)
			(xy 161.684971 -294.378062) (xy 161.704262 -294.332786) (xy 161.730565 -294.29119) (xy 161.7632 -294.254353)
			(xy 161.801321 -294.223228) (xy 161.843942 -294.198621) (xy 161.889958 -294.181169) (xy 161.938177 -294.171325)
			(xy 161.987352 -294.169344) (xy 162.036207 -294.175276) (xy 162.083478 -294.188968) (xy 162.12794 -294.210066)
			(xy 162.168443 -294.238022) (xy 162.203936 -294.272114) (xy 162.233501 -294.311458) (xy 162.256372 -294.355035)
			(xy 162.271956 -294.401716) (xy 162.279851 -294.450293) (xy 162.280346 -294.4749) (xy 162.619194 -294.4749)
			(xy 162.623154 -294.425846) (xy 162.634931 -294.378062) (xy 162.654222 -294.332786) (xy 162.680525 -294.29119)
			(xy 162.71316 -294.254353) (xy 162.751281 -294.223228) (xy 162.793902 -294.198621) (xy 162.839918 -294.181169)
			(xy 162.888137 -294.171325) (xy 162.937312 -294.169344) (xy 162.986167 -294.175276) (xy 163.033438 -294.188968)
			(xy 163.0779 -294.210066) (xy 163.118403 -294.238022) (xy 163.153896 -294.272114) (xy 163.183461 -294.311458)
			(xy 163.206332 -294.355035) (xy 163.221916 -294.401716) (xy 163.229811 -294.450293) (xy 163.230306 -294.4749)
			(xy 163.569154 -294.4749) (xy 163.573114 -294.425846) (xy 163.584891 -294.378062) (xy 163.604182 -294.332786)
			(xy 163.630485 -294.29119) (xy 163.66312 -294.254353) (xy 163.701241 -294.223228) (xy 163.743862 -294.198621)
			(xy 163.789878 -294.181169) (xy 163.838097 -294.171325) (xy 163.887272 -294.169344) (xy 163.936127 -294.175276)
			(xy 163.983398 -294.188968) (xy 164.02786 -294.210066) (xy 164.068363 -294.238022) (xy 164.103856 -294.272114)
			(xy 164.133421 -294.311458) (xy 164.156292 -294.355035) (xy 164.171876 -294.401716) (xy 164.179771 -294.450293)
			(xy 164.180266 -294.4749) (xy 165.469074 -294.4749) (xy 165.473034 -294.425846) (xy 165.484811 -294.378062)
			(xy 165.504102 -294.332786) (xy 165.530405 -294.29119) (xy 165.56304 -294.254353) (xy 165.601161 -294.223228)
			(xy 165.643782 -294.198621) (xy 165.689798 -294.181169) (xy 165.738017 -294.171325) (xy 165.787192 -294.169344)
			(xy 165.836047 -294.175276) (xy 165.883318 -294.188968) (xy 165.92778 -294.210066) (xy 165.968283 -294.238022)
			(xy 166.003776 -294.272114) (xy 166.033341 -294.311458) (xy 166.056212 -294.355035) (xy 166.071796 -294.401716)
			(xy 166.079691 -294.450293) (xy 166.080186 -294.4749) (xy 167.369248 -294.4749) (xy 167.373208 -294.425846)
			(xy 167.384985 -294.378062) (xy 167.404276 -294.332786) (xy 167.430579 -294.29119) (xy 167.463214 -294.254353)
			(xy 167.501335 -294.223228) (xy 167.543956 -294.198621) (xy 167.589972 -294.181169) (xy 167.638191 -294.171325)
			(xy 167.687366 -294.169344) (xy 167.736221 -294.175276) (xy 167.783492 -294.188968) (xy 167.827954 -294.210066)
			(xy 167.868457 -294.238022) (xy 167.90395 -294.272114) (xy 167.933515 -294.311458) (xy 167.956386 -294.355035)
			(xy 167.97197 -294.401716) (xy 167.979865 -294.450293) (xy 167.98036 -294.4749) (xy 169.269168 -294.4749)
			(xy 169.273128 -294.425846) (xy 169.284905 -294.378062) (xy 169.304196 -294.332786) (xy 169.330499 -294.29119)
			(xy 169.363134 -294.254353) (xy 169.401255 -294.223228) (xy 169.443876 -294.198621) (xy 169.489892 -294.181169)
			(xy 169.538111 -294.171325) (xy 169.587286 -294.169344) (xy 169.636141 -294.175276) (xy 169.683412 -294.188968)
			(xy 169.727874 -294.210066) (xy 169.768377 -294.238022) (xy 169.80387 -294.272114) (xy 169.833435 -294.311458)
			(xy 169.856306 -294.355035) (xy 169.87189 -294.401716) (xy 169.879785 -294.450293) (xy 169.88028 -294.4749)
			(xy 171.169088 -294.4749) (xy 171.173048 -294.425846) (xy 171.184825 -294.378062) (xy 171.204116 -294.332786)
			(xy 171.230419 -294.29119) (xy 171.263054 -294.254353) (xy 171.301175 -294.223228) (xy 171.343796 -294.198621)
			(xy 171.389812 -294.181169) (xy 171.438031 -294.171325) (xy 171.487206 -294.169344) (xy 171.536061 -294.175276)
			(xy 171.583332 -294.188968) (xy 171.627794 -294.210066) (xy 171.668297 -294.238022) (xy 171.70379 -294.272114)
			(xy 171.733355 -294.311458) (xy 171.756226 -294.355035) (xy 171.77181 -294.401716) (xy 171.779705 -294.450293)
			(xy 171.7802 -294.4749) (xy 173.069262 -294.4749) (xy 173.073222 -294.425846) (xy 173.084999 -294.378062)
			(xy 173.10429 -294.332786) (xy 173.130593 -294.29119) (xy 173.163228 -294.254353) (xy 173.201349 -294.223228)
			(xy 173.24397 -294.198621) (xy 173.289986 -294.181169) (xy 173.338205 -294.171325) (xy 173.38738 -294.169344)
			(xy 173.436235 -294.175276) (xy 173.483506 -294.188968) (xy 173.527968 -294.210066) (xy 173.568471 -294.238022)
			(xy 173.603964 -294.272114) (xy 173.633529 -294.311458) (xy 173.6564 -294.355035) (xy 173.671984 -294.401716)
			(xy 173.679879 -294.450293) (xy 173.680374 -294.4749) (xy 175.919142 -294.4749) (xy 175.923102 -294.425846)
			(xy 175.934879 -294.378062) (xy 175.95417 -294.332786) (xy 175.980473 -294.29119) (xy 176.013108 -294.254353)
			(xy 176.051229 -294.223228) (xy 176.09385 -294.198621) (xy 176.139866 -294.181169) (xy 176.188085 -294.171325)
			(xy 176.23726 -294.169344) (xy 176.286115 -294.175276) (xy 176.333386 -294.188968) (xy 176.377848 -294.210066)
			(xy 176.418351 -294.238022) (xy 176.453844 -294.272114) (xy 176.483409 -294.311458) (xy 176.50628 -294.355035)
			(xy 176.521864 -294.401716) (xy 176.529759 -294.450293) (xy 176.530254 -294.4749) (xy 177.819062 -294.4749)
			(xy 177.823022 -294.425846) (xy 177.834799 -294.378062) (xy 177.85409 -294.332786) (xy 177.880393 -294.29119)
			(xy 177.913028 -294.254353) (xy 177.951149 -294.223228) (xy 177.99377 -294.198621) (xy 178.039786 -294.181169)
			(xy 178.088005 -294.171325) (xy 178.13718 -294.169344) (xy 178.186035 -294.175276) (xy 178.233306 -294.188968)
			(xy 178.277768 -294.210066) (xy 178.318271 -294.238022) (xy 178.353764 -294.272114) (xy 178.383329 -294.311458)
			(xy 178.4062 -294.355035) (xy 178.421784 -294.401716) (xy 178.429679 -294.450293) (xy 178.430174 -294.4749)
			(xy 179.719236 -294.4749) (xy 179.723196 -294.425846) (xy 179.734973 -294.378062) (xy 179.754264 -294.332786)
			(xy 179.780567 -294.29119) (xy 179.813202 -294.254353) (xy 179.851323 -294.223228) (xy 179.893944 -294.198621)
			(xy 179.93996 -294.181169) (xy 179.988179 -294.171325) (xy 180.037354 -294.169344) (xy 180.086209 -294.175276)
			(xy 180.13348 -294.188968) (xy 180.177942 -294.210066) (xy 180.218445 -294.238022) (xy 180.253938 -294.272114)
			(xy 180.283503 -294.311458) (xy 180.306374 -294.355035) (xy 180.321958 -294.401716) (xy 180.329853 -294.450293)
			(xy 180.330348 -294.4749) (xy 181.619156 -294.4749) (xy 181.623116 -294.425846) (xy 181.634893 -294.378062)
			(xy 181.654184 -294.332786) (xy 181.680487 -294.29119) (xy 181.713122 -294.254353) (xy 181.751243 -294.223228)
			(xy 181.793864 -294.198621) (xy 181.83988 -294.181169) (xy 181.888099 -294.171325) (xy 181.937274 -294.169344)
			(xy 181.986129 -294.175276) (xy 182.0334 -294.188968) (xy 182.077862 -294.210066) (xy 182.118365 -294.238022)
			(xy 182.153858 -294.272114) (xy 182.183423 -294.311458) (xy 182.206294 -294.355035) (xy 182.221878 -294.401716)
			(xy 182.229773 -294.450293) (xy 182.230268 -294.4749) (xy 182.569116 -294.4749) (xy 182.573076 -294.425846)
			(xy 182.584853 -294.378062) (xy 182.604144 -294.332786) (xy 182.630447 -294.29119) (xy 182.663082 -294.254353)
			(xy 182.701203 -294.223228) (xy 182.743824 -294.198621) (xy 182.78984 -294.181169) (xy 182.838059 -294.171325)
			(xy 182.887234 -294.169344) (xy 182.936089 -294.175276) (xy 182.98336 -294.188968) (xy 183.027822 -294.210066)
			(xy 183.068325 -294.238022) (xy 183.103818 -294.272114) (xy 183.133383 -294.311458) (xy 183.156254 -294.355035)
			(xy 183.171838 -294.401716) (xy 183.179733 -294.450293) (xy 183.180228 -294.4749) (xy 183.519076 -294.4749)
			(xy 183.523036 -294.425846) (xy 183.534813 -294.378062) (xy 183.554104 -294.332786) (xy 183.580407 -294.29119)
			(xy 183.613042 -294.254353) (xy 183.651163 -294.223228) (xy 183.693784 -294.198621) (xy 183.7398 -294.181169)
			(xy 183.788019 -294.171325) (xy 183.837194 -294.169344) (xy 183.886049 -294.175276) (xy 183.93332 -294.188968)
			(xy 183.977782 -294.210066) (xy 184.018285 -294.238022) (xy 184.053778 -294.272114) (xy 184.083343 -294.311458)
			(xy 184.106214 -294.355035) (xy 184.121798 -294.401716) (xy 184.129693 -294.450293) (xy 184.130188 -294.4749)
			(xy 184.469036 -294.4749) (xy 184.472996 -294.425846) (xy 184.484773 -294.378062) (xy 184.504064 -294.332786)
			(xy 184.530367 -294.29119) (xy 184.563002 -294.254353) (xy 184.601123 -294.223228) (xy 184.643744 -294.198621)
			(xy 184.68976 -294.181169) (xy 184.737979 -294.171325) (xy 184.787154 -294.169344) (xy 184.836009 -294.175276)
			(xy 184.88328 -294.188968) (xy 184.927742 -294.210066) (xy 184.968245 -294.238022) (xy 185.003738 -294.272114)
			(xy 185.033303 -294.311458) (xy 185.056174 -294.355035) (xy 185.071758 -294.401716) (xy 185.079653 -294.450293)
			(xy 185.080148 -294.4749) (xy 185.079653 -294.499507) (xy 185.071758 -294.548084) (xy 185.056174 -294.594765)
			(xy 185.033303 -294.638342) (xy 185.003738 -294.677686) (xy 184.968245 -294.711778) (xy 184.927742 -294.739734)
			(xy 184.88328 -294.760832) (xy 184.836009 -294.774524) (xy 184.787154 -294.780456) (xy 184.737979 -294.778475)
			(xy 184.68976 -294.768631) (xy 184.643744 -294.751179) (xy 184.601123 -294.726572) (xy 184.563002 -294.695447)
			(xy 184.530367 -294.65861) (xy 184.504064 -294.617014) (xy 184.484773 -294.571738) (xy 184.472996 -294.523954)
			(xy 184.469036 -294.4749) (xy 184.130188 -294.4749) (xy 184.129693 -294.499507) (xy 184.121798 -294.548084)
			(xy 184.106214 -294.594765) (xy 184.083343 -294.638342) (xy 184.053778 -294.677686) (xy 184.018285 -294.711778)
			(xy 183.977782 -294.739734) (xy 183.93332 -294.760832) (xy 183.886049 -294.774524) (xy 183.837194 -294.780456)
			(xy 183.788019 -294.778475) (xy 183.7398 -294.768631) (xy 183.693784 -294.751179) (xy 183.651163 -294.726572)
			(xy 183.613042 -294.695447) (xy 183.580407 -294.65861) (xy 183.554104 -294.617014) (xy 183.534813 -294.571738)
			(xy 183.523036 -294.523954) (xy 183.519076 -294.4749) (xy 183.180228 -294.4749) (xy 183.179733 -294.499507)
			(xy 183.171838 -294.548084) (xy 183.156254 -294.594765) (xy 183.133383 -294.638342) (xy 183.103818 -294.677686)
			(xy 183.068325 -294.711778) (xy 183.027822 -294.739734) (xy 182.98336 -294.760832) (xy 182.936089 -294.774524)
			(xy 182.887234 -294.780456) (xy 182.838059 -294.778475) (xy 182.78984 -294.768631) (xy 182.743824 -294.751179)
			(xy 182.701203 -294.726572) (xy 182.663082 -294.695447) (xy 182.630447 -294.65861) (xy 182.604144 -294.617014)
			(xy 182.584853 -294.571738) (xy 182.573076 -294.523954) (xy 182.569116 -294.4749) (xy 182.230268 -294.4749)
			(xy 182.229773 -294.499507) (xy 182.221878 -294.548084) (xy 182.206294 -294.594765) (xy 182.183423 -294.638342)
			(xy 182.153858 -294.677686) (xy 182.118365 -294.711778) (xy 182.077862 -294.739734) (xy 182.0334 -294.760832)
			(xy 181.986129 -294.774524) (xy 181.937274 -294.780456) (xy 181.888099 -294.778475) (xy 181.83988 -294.768631)
			(xy 181.793864 -294.751179) (xy 181.751243 -294.726572) (xy 181.713122 -294.695447) (xy 181.680487 -294.65861)
			(xy 181.654184 -294.617014) (xy 181.634893 -294.571738) (xy 181.623116 -294.523954) (xy 181.619156 -294.4749)
			(xy 180.330348 -294.4749) (xy 180.329853 -294.499507) (xy 180.321958 -294.548084) (xy 180.306374 -294.594765)
			(xy 180.283503 -294.638342) (xy 180.253938 -294.677686) (xy 180.218445 -294.711778) (xy 180.177942 -294.739734)
			(xy 180.13348 -294.760832) (xy 180.086209 -294.774524) (xy 180.037354 -294.780456) (xy 179.988179 -294.778475)
			(xy 179.93996 -294.768631) (xy 179.893944 -294.751179) (xy 179.851323 -294.726572) (xy 179.813202 -294.695447)
			(xy 179.780567 -294.65861) (xy 179.754264 -294.617014) (xy 179.734973 -294.571738) (xy 179.723196 -294.523954)
			(xy 179.719236 -294.4749) (xy 178.430174 -294.4749) (xy 178.429679 -294.499507) (xy 178.421784 -294.548084)
			(xy 178.4062 -294.594765) (xy 178.383329 -294.638342) (xy 178.353764 -294.677686) (xy 178.318271 -294.711778)
			(xy 178.277768 -294.739734) (xy 178.233306 -294.760832) (xy 178.186035 -294.774524) (xy 178.13718 -294.780456)
			(xy 178.088005 -294.778475) (xy 178.039786 -294.768631) (xy 177.99377 -294.751179) (xy 177.951149 -294.726572)
			(xy 177.913028 -294.695447) (xy 177.880393 -294.65861) (xy 177.85409 -294.617014) (xy 177.834799 -294.571738)
			(xy 177.823022 -294.523954) (xy 177.819062 -294.4749) (xy 176.530254 -294.4749) (xy 176.529759 -294.499507)
			(xy 176.521864 -294.548084) (xy 176.50628 -294.594765) (xy 176.483409 -294.638342) (xy 176.453844 -294.677686)
			(xy 176.418351 -294.711778) (xy 176.377848 -294.739734) (xy 176.333386 -294.760832) (xy 176.286115 -294.774524)
			(xy 176.23726 -294.780456) (xy 176.188085 -294.778475) (xy 176.139866 -294.768631) (xy 176.09385 -294.751179)
			(xy 176.051229 -294.726572) (xy 176.013108 -294.695447) (xy 175.980473 -294.65861) (xy 175.95417 -294.617014)
			(xy 175.934879 -294.571738) (xy 175.923102 -294.523954) (xy 175.919142 -294.4749) (xy 173.680374 -294.4749)
			(xy 173.679879 -294.499507) (xy 173.671984 -294.548084) (xy 173.6564 -294.594765) (xy 173.633529 -294.638342)
			(xy 173.603964 -294.677686) (xy 173.568471 -294.711778) (xy 173.527968 -294.739734) (xy 173.483506 -294.760832)
			(xy 173.436235 -294.774524) (xy 173.38738 -294.780456) (xy 173.338205 -294.778475) (xy 173.289986 -294.768631)
			(xy 173.24397 -294.751179) (xy 173.201349 -294.726572) (xy 173.163228 -294.695447) (xy 173.130593 -294.65861)
			(xy 173.10429 -294.617014) (xy 173.084999 -294.571738) (xy 173.073222 -294.523954) (xy 173.069262 -294.4749)
			(xy 171.7802 -294.4749) (xy 171.779705 -294.499507) (xy 171.77181 -294.548084) (xy 171.756226 -294.594765)
			(xy 171.733355 -294.638342) (xy 171.70379 -294.677686) (xy 171.668297 -294.711778) (xy 171.627794 -294.739734)
			(xy 171.583332 -294.760832) (xy 171.536061 -294.774524) (xy 171.487206 -294.780456) (xy 171.438031 -294.778475)
			(xy 171.389812 -294.768631) (xy 171.343796 -294.751179) (xy 171.301175 -294.726572) (xy 171.263054 -294.695447)
			(xy 171.230419 -294.65861) (xy 171.204116 -294.617014) (xy 171.184825 -294.571738) (xy 171.173048 -294.523954)
			(xy 171.169088 -294.4749) (xy 169.88028 -294.4749) (xy 169.879785 -294.499507) (xy 169.87189 -294.548084)
			(xy 169.856306 -294.594765) (xy 169.833435 -294.638342) (xy 169.80387 -294.677686) (xy 169.768377 -294.711778)
			(xy 169.727874 -294.739734) (xy 169.683412 -294.760832) (xy 169.636141 -294.774524) (xy 169.587286 -294.780456)
			(xy 169.538111 -294.778475) (xy 169.489892 -294.768631) (xy 169.443876 -294.751179) (xy 169.401255 -294.726572)
			(xy 169.363134 -294.695447) (xy 169.330499 -294.65861) (xy 169.304196 -294.617014) (xy 169.284905 -294.571738)
			(xy 169.273128 -294.523954) (xy 169.269168 -294.4749) (xy 167.98036 -294.4749) (xy 167.979865 -294.499507)
			(xy 167.97197 -294.548084) (xy 167.956386 -294.594765) (xy 167.933515 -294.638342) (xy 167.90395 -294.677686)
			(xy 167.868457 -294.711778) (xy 167.827954 -294.739734) (xy 167.783492 -294.760832) (xy 167.736221 -294.774524)
			(xy 167.687366 -294.780456) (xy 167.638191 -294.778475) (xy 167.589972 -294.768631) (xy 167.543956 -294.751179)
			(xy 167.501335 -294.726572) (xy 167.463214 -294.695447) (xy 167.430579 -294.65861) (xy 167.404276 -294.617014)
			(xy 167.384985 -294.571738) (xy 167.373208 -294.523954) (xy 167.369248 -294.4749) (xy 166.080186 -294.4749)
			(xy 166.079691 -294.499507) (xy 166.071796 -294.548084) (xy 166.056212 -294.594765) (xy 166.033341 -294.638342)
			(xy 166.003776 -294.677686) (xy 165.968283 -294.711778) (xy 165.92778 -294.739734) (xy 165.883318 -294.760832)
			(xy 165.836047 -294.774524) (xy 165.787192 -294.780456) (xy 165.738017 -294.778475) (xy 165.689798 -294.768631)
			(xy 165.643782 -294.751179) (xy 165.601161 -294.726572) (xy 165.56304 -294.695447) (xy 165.530405 -294.65861)
			(xy 165.504102 -294.617014) (xy 165.484811 -294.571738) (xy 165.473034 -294.523954) (xy 165.469074 -294.4749)
			(xy 164.180266 -294.4749) (xy 164.179771 -294.499507) (xy 164.171876 -294.548084) (xy 164.156292 -294.594765)
			(xy 164.133421 -294.638342) (xy 164.103856 -294.677686) (xy 164.068363 -294.711778) (xy 164.02786 -294.739734)
			(xy 163.983398 -294.760832) (xy 163.936127 -294.774524) (xy 163.887272 -294.780456) (xy 163.838097 -294.778475)
			(xy 163.789878 -294.768631) (xy 163.743862 -294.751179) (xy 163.701241 -294.726572) (xy 163.66312 -294.695447)
			(xy 163.630485 -294.65861) (xy 163.604182 -294.617014) (xy 163.584891 -294.571738) (xy 163.573114 -294.523954)
			(xy 163.569154 -294.4749) (xy 163.230306 -294.4749) (xy 163.229811 -294.499507) (xy 163.221916 -294.548084)
			(xy 163.206332 -294.594765) (xy 163.183461 -294.638342) (xy 163.153896 -294.677686) (xy 163.118403 -294.711778)
			(xy 163.0779 -294.739734) (xy 163.033438 -294.760832) (xy 162.986167 -294.774524) (xy 162.937312 -294.780456)
			(xy 162.888137 -294.778475) (xy 162.839918 -294.768631) (xy 162.793902 -294.751179) (xy 162.751281 -294.726572)
			(xy 162.71316 -294.695447) (xy 162.680525 -294.65861) (xy 162.654222 -294.617014) (xy 162.634931 -294.571738)
			(xy 162.623154 -294.523954) (xy 162.619194 -294.4749) (xy 162.280346 -294.4749) (xy 162.279851 -294.499507)
			(xy 162.271956 -294.548084) (xy 162.256372 -294.594765) (xy 162.233501 -294.638342) (xy 162.203936 -294.677686)
			(xy 162.168443 -294.711778) (xy 162.12794 -294.739734) (xy 162.083478 -294.760832) (xy 162.036207 -294.774524)
			(xy 161.987352 -294.780456) (xy 161.938177 -294.778475) (xy 161.889958 -294.768631) (xy 161.843942 -294.751179)
			(xy 161.801321 -294.726572) (xy 161.7632 -294.695447) (xy 161.730565 -294.65861) (xy 161.704262 -294.617014)
			(xy 161.684971 -294.571738) (xy 161.673194 -294.523954) (xy 161.669234 -294.4749) (xy 161.330386 -294.4749)
			(xy 161.329891 -294.499507) (xy 161.321996 -294.548084) (xy 161.306412 -294.594765) (xy 161.283541 -294.638342)
			(xy 161.253976 -294.677686) (xy 161.218483 -294.711778) (xy 161.17798 -294.739734) (xy 161.133518 -294.760832)
			(xy 161.086247 -294.774524) (xy 161.037392 -294.780456) (xy 160.988217 -294.778475) (xy 160.939998 -294.768631)
			(xy 160.893982 -294.751179) (xy 160.851361 -294.726572) (xy 160.81324 -294.695447) (xy 160.780605 -294.65861)
			(xy 160.754302 -294.617014) (xy 160.735011 -294.571738) (xy 160.723234 -294.523954) (xy 160.719274 -294.4749)
			(xy 160.380172 -294.4749) (xy 160.379677 -294.499507) (xy 160.371782 -294.548084) (xy 160.356198 -294.594765)
			(xy 160.333327 -294.638342) (xy 160.303762 -294.677686) (xy 160.268269 -294.711778) (xy 160.227766 -294.739734)
			(xy 160.183304 -294.760832) (xy 160.136033 -294.774524) (xy 160.087178 -294.780456) (xy 160.038003 -294.778475)
			(xy 159.989784 -294.768631) (xy 159.943768 -294.751179) (xy 159.901147 -294.726572) (xy 159.863026 -294.695447)
			(xy 159.830391 -294.65861) (xy 159.804088 -294.617014) (xy 159.784797 -294.571738) (xy 159.77302 -294.523954)
			(xy 159.76906 -294.4749) (xy 159.430212 -294.4749) (xy 159.429717 -294.499507) (xy 159.421822 -294.548084)
			(xy 159.406238 -294.594765) (xy 159.383367 -294.638342) (xy 159.353802 -294.677686) (xy 159.318309 -294.711778)
			(xy 159.277806 -294.739734) (xy 159.233344 -294.760832) (xy 159.186073 -294.774524) (xy 159.137218 -294.780456)
			(xy 159.088043 -294.778475) (xy 159.039824 -294.768631) (xy 158.993808 -294.751179) (xy 158.951187 -294.726572)
			(xy 158.913066 -294.695447) (xy 158.880431 -294.65861) (xy 158.854128 -294.617014) (xy 158.834837 -294.571738)
			(xy 158.82306 -294.523954) (xy 158.8191 -294.4749) (xy 158.531052 -294.4749) (xy 158.530554 -294.501549)
			(xy 158.522611 -294.554253) (xy 158.506901 -294.605183) (xy 158.483775 -294.653204) (xy 158.453751 -294.697241)
			(xy 158.417499 -294.736312) (xy 158.375828 -294.769543) (xy 158.32967 -294.796192) (xy 158.280056 -294.815664)
			(xy 158.228094 -294.827524) (xy 158.174944 -294.831508) (xy 158.121794 -294.827524) (xy 158.069832 -294.815664)
			(xy 158.020218 -294.796192) (xy 157.97406 -294.769543) (xy 157.932389 -294.736312) (xy 157.896137 -294.697241)
			(xy 157.866113 -294.653204) (xy 157.842987 -294.605183) (xy 157.827277 -294.554253) (xy 157.819334 -294.501549)
			(xy 157.529465 -294.501549) (xy 157.521902 -294.548084) (xy 157.506318 -294.594765) (xy 157.483447 -294.638342)
			(xy 157.453882 -294.677686) (xy 157.418389 -294.711778) (xy 157.377886 -294.739734) (xy 157.333424 -294.760832)
			(xy 157.286153 -294.774524) (xy 157.237298 -294.780456) (xy 157.188123 -294.778475) (xy 157.139904 -294.768631)
			(xy 157.093888 -294.751179) (xy 157.051267 -294.726572) (xy 157.013146 -294.695447) (xy 156.980511 -294.65861)
			(xy 156.954208 -294.617014) (xy 156.934917 -294.571738) (xy 156.92314 -294.523954) (xy 156.91918 -294.4749)
			(xy 154.680412 -294.4749) (xy 154.679917 -294.499507) (xy 154.672022 -294.548084) (xy 154.656438 -294.594765)
			(xy 154.633567 -294.638342) (xy 154.604002 -294.677686) (xy 154.568509 -294.711778) (xy 154.528006 -294.739734)
			(xy 154.483544 -294.760832) (xy 154.436273 -294.774524) (xy 154.387418 -294.780456) (xy 154.338243 -294.778475)
			(xy 154.290024 -294.768631) (xy 154.244008 -294.751179) (xy 154.201387 -294.726572) (xy 154.163266 -294.695447)
			(xy 154.130631 -294.65861) (xy 154.104328 -294.617014) (xy 154.085037 -294.571738) (xy 154.07326 -294.523954)
			(xy 154.0693 -294.4749) (xy 153.730198 -294.4749) (xy 153.729703 -294.499507) (xy 153.721808 -294.548084)
			(xy 153.706224 -294.594765) (xy 153.683353 -294.638342) (xy 153.653788 -294.677686) (xy 153.618295 -294.711778)
			(xy 153.577792 -294.739734) (xy 153.53333 -294.760832) (xy 153.486059 -294.774524) (xy 153.437204 -294.780456)
			(xy 153.388029 -294.778475) (xy 153.33981 -294.768631) (xy 153.293794 -294.751179) (xy 153.251173 -294.726572)
			(xy 153.213052 -294.695447) (xy 153.180417 -294.65861) (xy 153.154114 -294.617014) (xy 153.134823 -294.571738)
			(xy 153.123046 -294.523954) (xy 153.119086 -294.4749) (xy 152.780238 -294.4749) (xy 152.779743 -294.499507)
			(xy 152.771848 -294.548084) (xy 152.756264 -294.594765) (xy 152.733393 -294.638342) (xy 152.703828 -294.677686)
			(xy 152.668335 -294.711778) (xy 152.627832 -294.739734) (xy 152.58337 -294.760832) (xy 152.536099 -294.774524)
			(xy 152.487244 -294.780456) (xy 152.438069 -294.778475) (xy 152.38985 -294.768631) (xy 152.343834 -294.751179)
			(xy 152.301213 -294.726572) (xy 152.263092 -294.695447) (xy 152.230457 -294.65861) (xy 152.204154 -294.617014)
			(xy 152.184863 -294.571738) (xy 152.173086 -294.523954) (xy 152.169126 -294.4749) (xy 144.126408 -294.4749)
			(xy 144.135543 -294.494387) (xy 144.151611 -294.547794) (xy 144.159731 -294.60297) (xy 144.16024 -294.630856)
			(xy 144.159731 -294.658742) (xy 144.151611 -294.713918) (xy 144.135543 -294.767325) (xy 144.111871 -294.817822)
			(xy 144.081098 -294.864335) (xy 144.043881 -294.905872) (xy 144.001013 -294.941547) (xy 143.953407 -294.970601)
			(xy 143.902078 -294.992413) (xy 143.848121 -295.006519) (xy 143.792684 -295.012619) (xy 143.73695 -295.010582)
			(xy 143.682107 -295.000452) (xy 143.629323 -294.982445) (xy 143.579723 -294.956944) (xy 143.534365 -294.924493)
			(xy 143.494216 -294.885784) (xy 143.46013 -294.841641) (xy 143.432834 -294.793006) (xy 143.412911 -294.740915)
			(xy 143.400785 -294.686478) (xy 143.396714 -294.630856) (xy 142.675102 -294.630856) (xy 142.674593 -294.658742)
			(xy 142.666473 -294.713918) (xy 142.650405 -294.767325) (xy 142.626733 -294.817822) (xy 142.59596 -294.864335)
			(xy 142.558743 -294.905872) (xy 142.515875 -294.941547) (xy 142.468269 -294.970601) (xy 142.41694 -294.992413)
			(xy 142.362983 -295.006519) (xy 142.307546 -295.012619) (xy 142.251812 -295.010582) (xy 142.196969 -295.000452)
			(xy 142.144185 -294.982445) (xy 142.094585 -294.956944) (xy 142.049227 -294.924493) (xy 142.009078 -294.885784)
			(xy 141.974992 -294.841641) (xy 141.947696 -294.793006) (xy 141.927773 -294.740915) (xy 141.915647 -294.686478)
			(xy 141.911576 -294.630856) (xy 118.883938 -294.630856) (xy 118.883938 -294.6781) (xy 118.85422 -294.707818)
			(xy 118.848124 -294.707818) (xy 118.835424 -294.745664) (xy 118.83424 -294.749559) (xy 118.832957 -294.757596)
			(xy 118.832884 -294.761666) (xy 118.832884 -295.933114) (xy 141.911576 -295.933114) (xy 141.915647 -295.877492)
			(xy 141.927773 -295.823055) (xy 141.947696 -295.770964) (xy 141.974992 -295.722329) (xy 142.009078 -295.678186)
			(xy 142.049227 -295.639477) (xy 142.094585 -295.607026) (xy 142.144185 -295.581525) (xy 142.196969 -295.563518)
			(xy 142.251812 -295.553388) (xy 142.307546 -295.551351) (xy 142.362983 -295.557451) (xy 142.41694 -295.571557)
			(xy 142.468269 -295.593369) (xy 142.515875 -295.622423) (xy 142.558743 -295.658098) (xy 142.59596 -295.699635)
			(xy 142.626733 -295.746148) (xy 142.650405 -295.796645) (xy 142.666473 -295.850052) (xy 142.674593 -295.905228)
			(xy 142.675102 -295.933114) (xy 143.387062 -295.933114) (xy 143.391133 -295.877492) (xy 143.403259 -295.823055)
			(xy 143.423182 -295.770964) (xy 143.450478 -295.722329) (xy 143.484564 -295.678186) (xy 143.524713 -295.639477)
			(xy 143.570071 -295.607026) (xy 143.619671 -295.581525) (xy 143.672455 -295.563518) (xy 143.727298 -295.553388)
			(xy 143.783032 -295.551351) (xy 143.838469 -295.557451) (xy 143.892426 -295.571557) (xy 143.943755 -295.593369)
			(xy 143.991361 -295.622423) (xy 144.034229 -295.658098) (xy 144.071446 -295.699635) (xy 144.102219 -295.746148)
			(xy 144.125891 -295.796645) (xy 144.141959 -295.850052) (xy 144.150079 -295.905228) (xy 144.150588 -295.933114)
			(xy 144.276062 -295.933114) (xy 144.280133 -295.877492) (xy 144.292259 -295.823055) (xy 144.312182 -295.770964)
			(xy 144.339478 -295.722329) (xy 144.373564 -295.678186) (xy 144.413713 -295.639477) (xy 144.459071 -295.607026)
			(xy 144.508671 -295.581525) (xy 144.561455 -295.563518) (xy 144.616298 -295.553388) (xy 144.672032 -295.551351)
			(xy 144.727469 -295.557451) (xy 144.781426 -295.571557) (xy 144.832755 -295.593369) (xy 144.880361 -295.622423)
			(xy 144.923229 -295.658098) (xy 144.960446 -295.699635) (xy 144.991219 -295.746148) (xy 145.014891 -295.796645)
			(xy 145.030959 -295.850052) (xy 145.039079 -295.905228) (xy 145.039588 -295.933114) (xy 145.039079 -295.961)
			(xy 145.030959 -296.016176) (xy 145.014891 -296.069583) (xy 144.991219 -296.12008) (xy 144.960446 -296.166593)
			(xy 144.923229 -296.20813) (xy 144.880361 -296.243805) (xy 144.832755 -296.272859) (xy 144.781426 -296.294671)
			(xy 144.727469 -296.308777) (xy 144.672032 -296.314877) (xy 144.616298 -296.31284) (xy 144.561455 -296.30271)
			(xy 144.508671 -296.284703) (xy 144.459071 -296.259202) (xy 144.413713 -296.226751) (xy 144.373564 -296.188042)
			(xy 144.339478 -296.143899) (xy 144.312182 -296.095264) (xy 144.292259 -296.043173) (xy 144.280133 -295.988736)
			(xy 144.276062 -295.933114) (xy 144.150588 -295.933114) (xy 144.150079 -295.961) (xy 144.141959 -296.016176)
			(xy 144.125891 -296.069583) (xy 144.102219 -296.12008) (xy 144.071446 -296.166593) (xy 144.034229 -296.20813)
			(xy 143.991361 -296.243805) (xy 143.943755 -296.272859) (xy 143.892426 -296.294671) (xy 143.838469 -296.308777)
			(xy 143.783032 -296.314877) (xy 143.727298 -296.31284) (xy 143.672455 -296.30271) (xy 143.619671 -296.284703)
			(xy 143.570071 -296.259202) (xy 143.524713 -296.226751) (xy 143.484564 -296.188042) (xy 143.450478 -296.143899)
			(xy 143.423182 -296.095264) (xy 143.403259 -296.043173) (xy 143.391133 -295.988736) (xy 143.387062 -295.933114)
			(xy 142.675102 -295.933114) (xy 142.674593 -295.961) (xy 142.666473 -296.016176) (xy 142.650405 -296.069583)
			(xy 142.626733 -296.12008) (xy 142.59596 -296.166593) (xy 142.558743 -296.20813) (xy 142.515875 -296.243805)
			(xy 142.468269 -296.272859) (xy 142.41694 -296.294671) (xy 142.362983 -296.308777) (xy 142.307546 -296.314877)
			(xy 142.251812 -296.31284) (xy 142.196969 -296.30271) (xy 142.144185 -296.284703) (xy 142.094585 -296.259202)
			(xy 142.049227 -296.226751) (xy 142.009078 -296.188042) (xy 141.974992 -296.143899) (xy 141.947696 -296.095264)
			(xy 141.927773 -296.043173) (xy 141.915647 -295.988736) (xy 141.911576 -295.933114) (xy 118.832884 -295.933114)
			(xy 118.832884 -296.695114) (xy 147.43811 -296.695114) (xy 147.438654 -296.665732) (xy 147.447683 -296.607665)
			(xy 147.465514 -296.551671) (xy 147.491725 -296.499075) (xy 147.525695 -296.451124) (xy 147.56662 -296.408952)
			(xy 147.589748 -296.390822) (xy 147.599146 -296.383456) (xy 147.60956 -296.362882) (xy 147.611084 -296.258996)
			(xy 147.601178 -296.237914) (xy 147.592034 -296.230548) (xy 147.570186 -296.212342) (xy 147.531644 -296.170524)
			(xy 147.499736 -296.123449) (xy 147.475169 -296.072159) (xy 147.458486 -296.017791) (xy 147.450058 -295.961549)
			(xy 147.44954 -295.933114) (xy 147.450026 -295.905863) (xy 147.457782 -295.851915) (xy 147.473137 -295.79962)
			(xy 147.495779 -295.750043) (xy 147.525245 -295.704193) (xy 147.560936 -295.663002) (xy 147.602127 -295.627311)
			(xy 147.647977 -295.597845) (xy 147.697554 -295.575203) (xy 147.749849 -295.559848) (xy 147.803797 -295.552092)
			(xy 147.858299 -295.552092) (xy 147.912247 -295.559848) (xy 147.964542 -295.575203) (xy 148.014119 -295.597845)
			(xy 148.059969 -295.627311) (xy 148.10116 -295.663002) (xy 148.136851 -295.704193) (xy 148.166317 -295.750043)
			(xy 148.188959 -295.79962) (xy 148.204314 -295.851915) (xy 148.21207 -295.905863) (xy 148.212556 -295.933114)
			(xy 148.212006 -295.962496) (xy 148.202975 -296.020561) (xy 148.185143 -296.076554) (xy 148.158933 -296.129149)
			(xy 148.124966 -296.177101) (xy 148.084044 -296.219274) (xy 148.060918 -296.237406) (xy 148.05152 -296.244772)
			(xy 148.041106 -296.265346) (xy 148.039582 -296.369232) (xy 148.049488 -296.390314) (xy 148.058632 -296.39768)
			(xy 148.080459 -296.415909) (xy 148.118999 -296.457724) (xy 148.150908 -296.504795) (xy 148.175478 -296.55608)
			(xy 148.192166 -296.610443) (xy 148.200603 -296.666681) (xy 148.201126 -296.695114) (xy 148.8346 -296.695114)
			(xy 148.838671 -296.639492) (xy 148.850797 -296.585055) (xy 148.87072 -296.532964) (xy 148.898016 -296.484329)
			(xy 148.932102 -296.440186) (xy 148.972251 -296.401477) (xy 149.017609 -296.369026) (xy 149.067209 -296.343525)
			(xy 149.119993 -296.325518) (xy 149.174836 -296.315388) (xy 149.23057 -296.313351) (xy 149.286007 -296.319451)
			(xy 149.339964 -296.333557) (xy 149.391293 -296.355369) (xy 149.438899 -296.384423) (xy 149.481767 -296.420098)
			(xy 149.518984 -296.461635) (xy 149.549757 -296.508148) (xy 149.573429 -296.558645) (xy 149.589497 -296.612052)
			(xy 149.597617 -296.667228) (xy 149.598126 -296.695114) (xy 149.72106 -296.695114) (xy 149.725131 -296.639492)
			(xy 149.737257 -296.585055) (xy 149.75718 -296.532964) (xy 149.784476 -296.484329) (xy 149.818562 -296.440186)
			(xy 149.858711 -296.401477) (xy 149.904069 -296.369026) (xy 149.953669 -296.343525) (xy 150.006453 -296.325518)
			(xy 150.061296 -296.315388) (xy 150.11703 -296.313351) (xy 150.172467 -296.319451) (xy 150.226424 -296.333557)
			(xy 150.277753 -296.355369) (xy 150.309624 -296.37482) (xy 153.11934 -296.37482) (xy 153.1233 -296.325766)
			(xy 153.135077 -296.277982) (xy 153.154368 -296.232706) (xy 153.180671 -296.19111) (xy 153.213306 -296.154273)
			(xy 153.251427 -296.123148) (xy 153.294048 -296.098541) (xy 153.340064 -296.081089) (xy 153.388283 -296.071245)
			(xy 153.437458 -296.069264) (xy 153.486313 -296.075196) (xy 153.533584 -296.088888) (xy 153.578046 -296.109986)
			(xy 153.618549 -296.137942) (xy 153.654042 -296.172034) (xy 153.683607 -296.211378) (xy 153.706478 -296.254955)
			(xy 153.722062 -296.301636) (xy 153.729957 -296.350213) (xy 153.730452 -296.37482) (xy 154.069046 -296.37482)
			(xy 154.073006 -296.325766) (xy 154.084783 -296.277982) (xy 154.104074 -296.232706) (xy 154.130377 -296.19111)
			(xy 154.163012 -296.154273) (xy 154.201133 -296.123148) (xy 154.243754 -296.098541) (xy 154.28977 -296.081089)
			(xy 154.337989 -296.071245) (xy 154.387164 -296.069264) (xy 154.436019 -296.075196) (xy 154.48329 -296.088888)
			(xy 154.527752 -296.109986) (xy 154.568255 -296.137942) (xy 154.603748 -296.172034) (xy 154.633313 -296.211378)
			(xy 154.656184 -296.254955) (xy 154.671768 -296.301636) (xy 154.679663 -296.350213) (xy 154.680158 -296.37482)
			(xy 155.01926 -296.37482) (xy 155.02322 -296.325766) (xy 155.034997 -296.277982) (xy 155.054288 -296.232706)
			(xy 155.080591 -296.19111) (xy 155.113226 -296.154273) (xy 155.151347 -296.123148) (xy 155.193968 -296.098541)
			(xy 155.239984 -296.081089) (xy 155.288203 -296.071245) (xy 155.337378 -296.069264) (xy 155.386233 -296.075196)
			(xy 155.433504 -296.088888) (xy 155.477966 -296.109986) (xy 155.518469 -296.137942) (xy 155.553962 -296.172034)
			(xy 155.583527 -296.211378) (xy 155.606398 -296.254955) (xy 155.621982 -296.301636) (xy 155.629877 -296.350213)
			(xy 155.630372 -296.37482) (xy 155.96922 -296.37482) (xy 155.97318 -296.325766) (xy 155.984957 -296.277982)
			(xy 156.004248 -296.232706) (xy 156.030551 -296.19111) (xy 156.063186 -296.154273) (xy 156.101307 -296.123148)
			(xy 156.143928 -296.098541) (xy 156.189944 -296.081089) (xy 156.238163 -296.071245) (xy 156.287338 -296.069264)
			(xy 156.336193 -296.075196) (xy 156.383464 -296.088888) (xy 156.427926 -296.109986) (xy 156.468429 -296.137942)
			(xy 156.503922 -296.172034) (xy 156.533487 -296.211378) (xy 156.556358 -296.254955) (xy 156.571942 -296.301636)
			(xy 156.579837 -296.350213) (xy 156.580332 -296.37482) (xy 157.86914 -296.37482) (xy 157.8731 -296.325766)
			(xy 157.884877 -296.277982) (xy 157.904168 -296.232706) (xy 157.930471 -296.19111) (xy 157.963106 -296.154273)
			(xy 158.001227 -296.123148) (xy 158.043848 -296.098541) (xy 158.089864 -296.081089) (xy 158.138083 -296.071245)
			(xy 158.187258 -296.069264) (xy 158.236113 -296.075196) (xy 158.283384 -296.088888) (xy 158.327846 -296.109986)
			(xy 158.368349 -296.137942) (xy 158.403842 -296.172034) (xy 158.433407 -296.211378) (xy 158.456278 -296.254955)
			(xy 158.471862 -296.301636) (xy 158.479757 -296.350213) (xy 158.480252 -296.37482) (xy 159.76906 -296.37482)
			(xy 159.77302 -296.325766) (xy 159.784797 -296.277982) (xy 159.804088 -296.232706) (xy 159.830391 -296.19111)
			(xy 159.863026 -296.154273) (xy 159.901147 -296.123148) (xy 159.943768 -296.098541) (xy 159.989784 -296.081089)
			(xy 160.038003 -296.071245) (xy 160.087178 -296.069264) (xy 160.136033 -296.075196) (xy 160.183304 -296.088888)
			(xy 160.227766 -296.109986) (xy 160.268269 -296.137942) (xy 160.303762 -296.172034) (xy 160.333327 -296.211378)
			(xy 160.356198 -296.254955) (xy 160.371782 -296.301636) (xy 160.379677 -296.350213) (xy 160.380172 -296.37482)
			(xy 160.719274 -296.37482) (xy 160.723234 -296.325766) (xy 160.735011 -296.277982) (xy 160.754302 -296.232706)
			(xy 160.780605 -296.19111) (xy 160.81324 -296.154273) (xy 160.851361 -296.123148) (xy 160.893982 -296.098541)
			(xy 160.939998 -296.081089) (xy 160.988217 -296.071245) (xy 161.037392 -296.069264) (xy 161.086247 -296.075196)
			(xy 161.133518 -296.088888) (xy 161.17798 -296.109986) (xy 161.218483 -296.137942) (xy 161.253976 -296.172034)
			(xy 161.283541 -296.211378) (xy 161.306412 -296.254955) (xy 161.321996 -296.301636) (xy 161.329891 -296.350213)
			(xy 161.330386 -296.37482) (xy 161.669234 -296.37482) (xy 161.673194 -296.325766) (xy 161.684971 -296.277982)
			(xy 161.704262 -296.232706) (xy 161.730565 -296.19111) (xy 161.7632 -296.154273) (xy 161.801321 -296.123148)
			(xy 161.843942 -296.098541) (xy 161.889958 -296.081089) (xy 161.938177 -296.071245) (xy 161.987352 -296.069264)
			(xy 162.036207 -296.075196) (xy 162.083478 -296.088888) (xy 162.12794 -296.109986) (xy 162.168443 -296.137942)
			(xy 162.203936 -296.172034) (xy 162.233501 -296.211378) (xy 162.256372 -296.254955) (xy 162.271956 -296.301636)
			(xy 162.279851 -296.350213) (xy 162.280346 -296.37482) (xy 163.569154 -296.37482) (xy 163.573114 -296.325766)
			(xy 163.584891 -296.277982) (xy 163.604182 -296.232706) (xy 163.630485 -296.19111) (xy 163.66312 -296.154273)
			(xy 163.701241 -296.123148) (xy 163.743862 -296.098541) (xy 163.789878 -296.081089) (xy 163.838097 -296.071245)
			(xy 163.887272 -296.069264) (xy 163.936127 -296.075196) (xy 163.983398 -296.088888) (xy 164.02786 -296.109986)
			(xy 164.068363 -296.137942) (xy 164.103856 -296.172034) (xy 164.133421 -296.211378) (xy 164.156292 -296.254955)
			(xy 164.171876 -296.301636) (xy 164.179771 -296.350213) (xy 164.180266 -296.37482) (xy 164.519114 -296.37482)
			(xy 164.523074 -296.325766) (xy 164.534851 -296.277982) (xy 164.554142 -296.232706) (xy 164.580445 -296.19111)
			(xy 164.61308 -296.154273) (xy 164.651201 -296.123148) (xy 164.693822 -296.098541) (xy 164.739838 -296.081089)
			(xy 164.788057 -296.071245) (xy 164.837232 -296.069264) (xy 164.886087 -296.075196) (xy 164.933358 -296.088888)
			(xy 164.97782 -296.109986) (xy 165.018323 -296.137942) (xy 165.053816 -296.172034) (xy 165.083381 -296.211378)
			(xy 165.106252 -296.254955) (xy 165.121836 -296.301636) (xy 165.129731 -296.350213) (xy 165.130226 -296.37482)
			(xy 166.419288 -296.37482) (xy 166.423248 -296.325766) (xy 166.435025 -296.277982) (xy 166.454316 -296.232706)
			(xy 166.480619 -296.19111) (xy 166.513254 -296.154273) (xy 166.551375 -296.123148) (xy 166.593996 -296.098541)
			(xy 166.640012 -296.081089) (xy 166.688231 -296.071245) (xy 166.737406 -296.069264) (xy 166.786261 -296.075196)
			(xy 166.833532 -296.088888) (xy 166.877994 -296.109986) (xy 166.918497 -296.137942) (xy 166.95399 -296.172034)
			(xy 166.983555 -296.211378) (xy 167.006426 -296.254955) (xy 167.02201 -296.301636) (xy 167.029905 -296.350213)
			(xy 167.0304 -296.37482) (xy 168.319208 -296.37482) (xy 168.323168 -296.325766) (xy 168.334945 -296.277982)
			(xy 168.354236 -296.232706) (xy 168.380539 -296.19111) (xy 168.413174 -296.154273) (xy 168.451295 -296.123148)
			(xy 168.493916 -296.098541) (xy 168.539932 -296.081089) (xy 168.588151 -296.071245) (xy 168.637326 -296.069264)
			(xy 168.686181 -296.075196) (xy 168.733452 -296.088888) (xy 168.777914 -296.109986) (xy 168.818417 -296.137942)
			(xy 168.85391 -296.172034) (xy 168.883475 -296.211378) (xy 168.906346 -296.254955) (xy 168.92193 -296.301636)
			(xy 168.929825 -296.350213) (xy 168.93032 -296.37482) (xy 170.219128 -296.37482) (xy 170.223088 -296.325766)
			(xy 170.234865 -296.277982) (xy 170.254156 -296.232706) (xy 170.280459 -296.19111) (xy 170.313094 -296.154273)
			(xy 170.351215 -296.123148) (xy 170.393836 -296.098541) (xy 170.439852 -296.081089) (xy 170.488071 -296.071245)
			(xy 170.537246 -296.069264) (xy 170.586101 -296.075196) (xy 170.633372 -296.088888) (xy 170.677834 -296.109986)
			(xy 170.718337 -296.137942) (xy 170.75383 -296.172034) (xy 170.783395 -296.211378) (xy 170.806266 -296.254955)
			(xy 170.82185 -296.301636) (xy 170.829745 -296.350213) (xy 170.83024 -296.37482) (xy 172.119302 -296.37482)
			(xy 172.123262 -296.325766) (xy 172.135039 -296.277982) (xy 172.15433 -296.232706) (xy 172.180633 -296.19111)
			(xy 172.213268 -296.154273) (xy 172.251389 -296.123148) (xy 172.29401 -296.098541) (xy 172.340026 -296.081089)
			(xy 172.388245 -296.071245) (xy 172.43742 -296.069264) (xy 172.486275 -296.075196) (xy 172.533546 -296.088888)
			(xy 172.578008 -296.109986) (xy 172.618511 -296.137942) (xy 172.654004 -296.172034) (xy 172.683569 -296.211378)
			(xy 172.70644 -296.254955) (xy 172.722024 -296.301636) (xy 172.729919 -296.350213) (xy 172.730414 -296.37482)
			(xy 174.019222 -296.37482) (xy 174.023182 -296.325766) (xy 174.034959 -296.277982) (xy 174.05425 -296.232706)
			(xy 174.080553 -296.19111) (xy 174.113188 -296.154273) (xy 174.151309 -296.123148) (xy 174.19393 -296.098541)
			(xy 174.239946 -296.081089) (xy 174.288165 -296.071245) (xy 174.33734 -296.069264) (xy 174.386195 -296.075196)
			(xy 174.433466 -296.088888) (xy 174.477928 -296.109986) (xy 174.518431 -296.137942) (xy 174.553924 -296.172034)
			(xy 174.583489 -296.211378) (xy 174.60636 -296.254955) (xy 174.621944 -296.301636) (xy 174.629839 -296.350213)
			(xy 174.630334 -296.37482) (xy 176.869102 -296.37482) (xy 176.873062 -296.325766) (xy 176.884839 -296.277982)
			(xy 176.90413 -296.232706) (xy 176.930433 -296.19111) (xy 176.963068 -296.154273) (xy 177.001189 -296.123148)
			(xy 177.04381 -296.098541) (xy 177.089826 -296.081089) (xy 177.138045 -296.071245) (xy 177.18722 -296.069264)
			(xy 177.236075 -296.075196) (xy 177.283346 -296.088888) (xy 177.327808 -296.109986) (xy 177.368311 -296.137942)
			(xy 177.403804 -296.172034) (xy 177.433369 -296.211378) (xy 177.45624 -296.254955) (xy 177.471824 -296.301636)
			(xy 177.479719 -296.350213) (xy 177.480214 -296.37482) (xy 178.769276 -296.37482) (xy 178.773236 -296.325766)
			(xy 178.785013 -296.277982) (xy 178.804304 -296.232706) (xy 178.830607 -296.19111) (xy 178.863242 -296.154273)
			(xy 178.901363 -296.123148) (xy 178.943984 -296.098541) (xy 178.99 -296.081089) (xy 179.038219 -296.071245)
			(xy 179.087394 -296.069264) (xy 179.136249 -296.075196) (xy 179.18352 -296.088888) (xy 179.227982 -296.109986)
			(xy 179.268485 -296.137942) (xy 179.303978 -296.172034) (xy 179.333543 -296.211378) (xy 179.356414 -296.254955)
			(xy 179.371998 -296.301636) (xy 179.379893 -296.350213) (xy 179.380388 -296.37482) (xy 180.669196 -296.37482)
			(xy 180.673156 -296.325766) (xy 180.684933 -296.277982) (xy 180.704224 -296.232706) (xy 180.730527 -296.19111)
			(xy 180.763162 -296.154273) (xy 180.801283 -296.123148) (xy 180.843904 -296.098541) (xy 180.88992 -296.081089)
			(xy 180.938139 -296.071245) (xy 180.987314 -296.069264) (xy 181.036169 -296.075196) (xy 181.08344 -296.088888)
			(xy 181.127902 -296.109986) (xy 181.168405 -296.137942) (xy 181.203898 -296.172034) (xy 181.233463 -296.211378)
			(xy 181.256334 -296.254955) (xy 181.271918 -296.301636) (xy 181.279813 -296.350213) (xy 181.280308 -296.37482)
			(xy 182.569116 -296.37482) (xy 182.573076 -296.325766) (xy 182.584853 -296.277982) (xy 182.604144 -296.232706)
			(xy 182.630447 -296.19111) (xy 182.663082 -296.154273) (xy 182.701203 -296.123148) (xy 182.743824 -296.098541)
			(xy 182.78984 -296.081089) (xy 182.838059 -296.071245) (xy 182.887234 -296.069264) (xy 182.936089 -296.075196)
			(xy 182.98336 -296.088888) (xy 183.027822 -296.109986) (xy 183.068325 -296.137942) (xy 183.103818 -296.172034)
			(xy 183.133383 -296.211378) (xy 183.156254 -296.254955) (xy 183.171838 -296.301636) (xy 183.179733 -296.350213)
			(xy 183.180228 -296.37482) (xy 183.519076 -296.37482) (xy 183.523036 -296.325766) (xy 183.534813 -296.277982)
			(xy 183.554104 -296.232706) (xy 183.580407 -296.19111) (xy 183.613042 -296.154273) (xy 183.651163 -296.123148)
			(xy 183.693784 -296.098541) (xy 183.7398 -296.081089) (xy 183.788019 -296.071245) (xy 183.837194 -296.069264)
			(xy 183.886049 -296.075196) (xy 183.93332 -296.088888) (xy 183.977782 -296.109986) (xy 184.018285 -296.137942)
			(xy 184.053778 -296.172034) (xy 184.083343 -296.211378) (xy 184.106214 -296.254955) (xy 184.121798 -296.301636)
			(xy 184.129693 -296.350213) (xy 184.130188 -296.37482) (xy 184.469036 -296.37482) (xy 184.472996 -296.325766)
			(xy 184.484773 -296.277982) (xy 184.504064 -296.232706) (xy 184.530367 -296.19111) (xy 184.563002 -296.154273)
			(xy 184.601123 -296.123148) (xy 184.643744 -296.098541) (xy 184.68976 -296.081089) (xy 184.737979 -296.071245)
			(xy 184.787154 -296.069264) (xy 184.836009 -296.075196) (xy 184.88328 -296.088888) (xy 184.927742 -296.109986)
			(xy 184.968245 -296.137942) (xy 185.003738 -296.172034) (xy 185.033303 -296.211378) (xy 185.056174 -296.254955)
			(xy 185.071758 -296.301636) (xy 185.079653 -296.350213) (xy 185.080148 -296.37482) (xy 185.079653 -296.399427)
			(xy 185.071758 -296.448004) (xy 185.056174 -296.494685) (xy 185.033303 -296.538262) (xy 185.003738 -296.577606)
			(xy 184.968245 -296.611698) (xy 184.927742 -296.639654) (xy 184.88328 -296.660752) (xy 184.836009 -296.674444)
			(xy 184.787154 -296.680376) (xy 184.737979 -296.678395) (xy 184.68976 -296.668551) (xy 184.643744 -296.651099)
			(xy 184.601123 -296.626492) (xy 184.563002 -296.595367) (xy 184.530367 -296.55853) (xy 184.504064 -296.516934)
			(xy 184.484773 -296.471658) (xy 184.472996 -296.423874) (xy 184.469036 -296.37482) (xy 184.130188 -296.37482)
			(xy 184.129693 -296.399427) (xy 184.121798 -296.448004) (xy 184.106214 -296.494685) (xy 184.083343 -296.538262)
			(xy 184.053778 -296.577606) (xy 184.018285 -296.611698) (xy 183.977782 -296.639654) (xy 183.93332 -296.660752)
			(xy 183.886049 -296.674444) (xy 183.837194 -296.680376) (xy 183.788019 -296.678395) (xy 183.7398 -296.668551)
			(xy 183.693784 -296.651099) (xy 183.651163 -296.626492) (xy 183.613042 -296.595367) (xy 183.580407 -296.55853)
			(xy 183.554104 -296.516934) (xy 183.534813 -296.471658) (xy 183.523036 -296.423874) (xy 183.519076 -296.37482)
			(xy 183.180228 -296.37482) (xy 183.179733 -296.399427) (xy 183.171838 -296.448004) (xy 183.156254 -296.494685)
			(xy 183.133383 -296.538262) (xy 183.103818 -296.577606) (xy 183.068325 -296.611698) (xy 183.027822 -296.639654)
			(xy 182.98336 -296.660752) (xy 182.936089 -296.674444) (xy 182.887234 -296.680376) (xy 182.838059 -296.678395)
			(xy 182.78984 -296.668551) (xy 182.743824 -296.651099) (xy 182.701203 -296.626492) (xy 182.663082 -296.595367)
			(xy 182.630447 -296.55853) (xy 182.604144 -296.516934) (xy 182.584853 -296.471658) (xy 182.573076 -296.423874)
			(xy 182.569116 -296.37482) (xy 181.280308 -296.37482) (xy 181.279813 -296.399427) (xy 181.271918 -296.448004)
			(xy 181.256334 -296.494685) (xy 181.233463 -296.538262) (xy 181.203898 -296.577606) (xy 181.168405 -296.611698)
			(xy 181.127902 -296.639654) (xy 181.08344 -296.660752) (xy 181.036169 -296.674444) (xy 180.987314 -296.680376)
			(xy 180.938139 -296.678395) (xy 180.88992 -296.668551) (xy 180.843904 -296.651099) (xy 180.801283 -296.626492)
			(xy 180.763162 -296.595367) (xy 180.730527 -296.55853) (xy 180.704224 -296.516934) (xy 180.684933 -296.471658)
			(xy 180.673156 -296.423874) (xy 180.669196 -296.37482) (xy 179.380388 -296.37482) (xy 179.379893 -296.399427)
			(xy 179.371998 -296.448004) (xy 179.356414 -296.494685) (xy 179.333543 -296.538262) (xy 179.303978 -296.577606)
			(xy 179.268485 -296.611698) (xy 179.227982 -296.639654) (xy 179.18352 -296.660752) (xy 179.136249 -296.674444)
			(xy 179.087394 -296.680376) (xy 179.038219 -296.678395) (xy 178.99 -296.668551) (xy 178.943984 -296.651099)
			(xy 178.901363 -296.626492) (xy 178.863242 -296.595367) (xy 178.830607 -296.55853) (xy 178.804304 -296.516934)
			(xy 178.785013 -296.471658) (xy 178.773236 -296.423874) (xy 178.769276 -296.37482) (xy 177.480214 -296.37482)
			(xy 177.479719 -296.399427) (xy 177.471824 -296.448004) (xy 177.45624 -296.494685) (xy 177.433369 -296.538262)
			(xy 177.403804 -296.577606) (xy 177.368311 -296.611698) (xy 177.327808 -296.639654) (xy 177.283346 -296.660752)
			(xy 177.236075 -296.674444) (xy 177.18722 -296.680376) (xy 177.138045 -296.678395) (xy 177.089826 -296.668551)
			(xy 177.04381 -296.651099) (xy 177.001189 -296.626492) (xy 176.963068 -296.595367) (xy 176.930433 -296.55853)
			(xy 176.90413 -296.516934) (xy 176.884839 -296.471658) (xy 176.873062 -296.423874) (xy 176.869102 -296.37482)
			(xy 174.630334 -296.37482) (xy 174.629839 -296.399427) (xy 174.621944 -296.448004) (xy 174.60636 -296.494685)
			(xy 174.583489 -296.538262) (xy 174.553924 -296.577606) (xy 174.518431 -296.611698) (xy 174.477928 -296.639654)
			(xy 174.433466 -296.660752) (xy 174.386195 -296.674444) (xy 174.33734 -296.680376) (xy 174.288165 -296.678395)
			(xy 174.239946 -296.668551) (xy 174.19393 -296.651099) (xy 174.151309 -296.626492) (xy 174.113188 -296.595367)
			(xy 174.080553 -296.55853) (xy 174.05425 -296.516934) (xy 174.034959 -296.471658) (xy 174.023182 -296.423874)
			(xy 174.019222 -296.37482) (xy 172.730414 -296.37482) (xy 172.729919 -296.399427) (xy 172.722024 -296.448004)
			(xy 172.70644 -296.494685) (xy 172.683569 -296.538262) (xy 172.654004 -296.577606) (xy 172.618511 -296.611698)
			(xy 172.578008 -296.639654) (xy 172.533546 -296.660752) (xy 172.486275 -296.674444) (xy 172.43742 -296.680376)
			(xy 172.388245 -296.678395) (xy 172.340026 -296.668551) (xy 172.29401 -296.651099) (xy 172.251389 -296.626492)
			(xy 172.213268 -296.595367) (xy 172.180633 -296.55853) (xy 172.15433 -296.516934) (xy 172.135039 -296.471658)
			(xy 172.123262 -296.423874) (xy 172.119302 -296.37482) (xy 170.83024 -296.37482) (xy 170.829745 -296.399427)
			(xy 170.82185 -296.448004) (xy 170.806266 -296.494685) (xy 170.783395 -296.538262) (xy 170.75383 -296.577606)
			(xy 170.718337 -296.611698) (xy 170.677834 -296.639654) (xy 170.633372 -296.660752) (xy 170.586101 -296.674444)
			(xy 170.537246 -296.680376) (xy 170.488071 -296.678395) (xy 170.439852 -296.668551) (xy 170.393836 -296.651099)
			(xy 170.351215 -296.626492) (xy 170.313094 -296.595367) (xy 170.280459 -296.55853) (xy 170.254156 -296.516934)
			(xy 170.234865 -296.471658) (xy 170.223088 -296.423874) (xy 170.219128 -296.37482) (xy 168.93032 -296.37482)
			(xy 168.929825 -296.399427) (xy 168.92193 -296.448004) (xy 168.906346 -296.494685) (xy 168.883475 -296.538262)
			(xy 168.85391 -296.577606) (xy 168.818417 -296.611698) (xy 168.777914 -296.639654) (xy 168.733452 -296.660752)
			(xy 168.686181 -296.674444) (xy 168.637326 -296.680376) (xy 168.588151 -296.678395) (xy 168.539932 -296.668551)
			(xy 168.493916 -296.651099) (xy 168.451295 -296.626492) (xy 168.413174 -296.595367) (xy 168.380539 -296.55853)
			(xy 168.354236 -296.516934) (xy 168.334945 -296.471658) (xy 168.323168 -296.423874) (xy 168.319208 -296.37482)
			(xy 167.0304 -296.37482) (xy 167.029905 -296.399427) (xy 167.02201 -296.448004) (xy 167.006426 -296.494685)
			(xy 166.983555 -296.538262) (xy 166.95399 -296.577606) (xy 166.918497 -296.611698) (xy 166.877994 -296.639654)
			(xy 166.833532 -296.660752) (xy 166.786261 -296.674444) (xy 166.737406 -296.680376) (xy 166.688231 -296.678395)
			(xy 166.640012 -296.668551) (xy 166.593996 -296.651099) (xy 166.551375 -296.626492) (xy 166.513254 -296.595367)
			(xy 166.480619 -296.55853) (xy 166.454316 -296.516934) (xy 166.435025 -296.471658) (xy 166.423248 -296.423874)
			(xy 166.419288 -296.37482) (xy 165.130226 -296.37482) (xy 165.129731 -296.399427) (xy 165.121836 -296.448004)
			(xy 165.106252 -296.494685) (xy 165.083381 -296.538262) (xy 165.053816 -296.577606) (xy 165.018323 -296.611698)
			(xy 164.97782 -296.639654) (xy 164.933358 -296.660752) (xy 164.886087 -296.674444) (xy 164.837232 -296.680376)
			(xy 164.788057 -296.678395) (xy 164.739838 -296.668551) (xy 164.693822 -296.651099) (xy 164.651201 -296.626492)
			(xy 164.61308 -296.595367) (xy 164.580445 -296.55853) (xy 164.554142 -296.516934) (xy 164.534851 -296.471658)
			(xy 164.523074 -296.423874) (xy 164.519114 -296.37482) (xy 164.180266 -296.37482) (xy 164.179771 -296.399427)
			(xy 164.171876 -296.448004) (xy 164.156292 -296.494685) (xy 164.133421 -296.538262) (xy 164.103856 -296.577606)
			(xy 164.068363 -296.611698) (xy 164.02786 -296.639654) (xy 163.983398 -296.660752) (xy 163.936127 -296.674444)
			(xy 163.887272 -296.680376) (xy 163.838097 -296.678395) (xy 163.789878 -296.668551) (xy 163.743862 -296.651099)
			(xy 163.701241 -296.626492) (xy 163.66312 -296.595367) (xy 163.630485 -296.55853) (xy 163.604182 -296.516934)
			(xy 163.584891 -296.471658) (xy 163.573114 -296.423874) (xy 163.569154 -296.37482) (xy 162.280346 -296.37482)
			(xy 162.279851 -296.399427) (xy 162.271956 -296.448004) (xy 162.256372 -296.494685) (xy 162.233501 -296.538262)
			(xy 162.203936 -296.577606) (xy 162.168443 -296.611698) (xy 162.12794 -296.639654) (xy 162.083478 -296.660752)
			(xy 162.036207 -296.674444) (xy 161.987352 -296.680376) (xy 161.938177 -296.678395) (xy 161.889958 -296.668551)
			(xy 161.843942 -296.651099) (xy 161.801321 -296.626492) (xy 161.7632 -296.595367) (xy 161.730565 -296.55853)
			(xy 161.704262 -296.516934) (xy 161.684971 -296.471658) (xy 161.673194 -296.423874) (xy 161.669234 -296.37482)
			(xy 161.330386 -296.37482) (xy 161.329891 -296.399427) (xy 161.321996 -296.448004) (xy 161.306412 -296.494685)
			(xy 161.283541 -296.538262) (xy 161.253976 -296.577606) (xy 161.218483 -296.611698) (xy 161.17798 -296.639654)
			(xy 161.133518 -296.660752) (xy 161.086247 -296.674444) (xy 161.037392 -296.680376) (xy 160.988217 -296.678395)
			(xy 160.939998 -296.668551) (xy 160.893982 -296.651099) (xy 160.851361 -296.626492) (xy 160.81324 -296.595367)
			(xy 160.780605 -296.55853) (xy 160.754302 -296.516934) (xy 160.735011 -296.471658) (xy 160.723234 -296.423874)
			(xy 160.719274 -296.37482) (xy 160.380172 -296.37482) (xy 160.379677 -296.399427) (xy 160.371782 -296.448004)
			(xy 160.356198 -296.494685) (xy 160.333327 -296.538262) (xy 160.303762 -296.577606) (xy 160.268269 -296.611698)
			(xy 160.227766 -296.639654) (xy 160.183304 -296.660752) (xy 160.136033 -296.674444) (xy 160.087178 -296.680376)
			(xy 160.038003 -296.678395) (xy 159.989784 -296.668551) (xy 159.943768 -296.651099) (xy 159.901147 -296.626492)
			(xy 159.863026 -296.595367) (xy 159.830391 -296.55853) (xy 159.804088 -296.516934) (xy 159.784797 -296.471658)
			(xy 159.77302 -296.423874) (xy 159.76906 -296.37482) (xy 158.480252 -296.37482) (xy 158.479757 -296.399427)
			(xy 158.471862 -296.448004) (xy 158.456278 -296.494685) (xy 158.433407 -296.538262) (xy 158.403842 -296.577606)
			(xy 158.368349 -296.611698) (xy 158.327846 -296.639654) (xy 158.283384 -296.660752) (xy 158.236113 -296.674444)
			(xy 158.187258 -296.680376) (xy 158.138083 -296.678395) (xy 158.089864 -296.668551) (xy 158.043848 -296.651099)
			(xy 158.001227 -296.626492) (xy 157.963106 -296.595367) (xy 157.930471 -296.55853) (xy 157.904168 -296.516934)
			(xy 157.884877 -296.471658) (xy 157.8731 -296.423874) (xy 157.86914 -296.37482) (xy 156.580332 -296.37482)
			(xy 156.579837 -296.399427) (xy 156.571942 -296.448004) (xy 156.556358 -296.494685) (xy 156.533487 -296.538262)
			(xy 156.503922 -296.577606) (xy 156.468429 -296.611698) (xy 156.427926 -296.639654) (xy 156.383464 -296.660752)
			(xy 156.336193 -296.674444) (xy 156.287338 -296.680376) (xy 156.238163 -296.678395) (xy 156.189944 -296.668551)
			(xy 156.143928 -296.651099) (xy 156.101307 -296.626492) (xy 156.063186 -296.595367) (xy 156.030551 -296.55853)
			(xy 156.004248 -296.516934) (xy 155.984957 -296.471658) (xy 155.97318 -296.423874) (xy 155.96922 -296.37482)
			(xy 155.630372 -296.37482) (xy 155.629877 -296.399427) (xy 155.621982 -296.448004) (xy 155.606398 -296.494685)
			(xy 155.583527 -296.538262) (xy 155.553962 -296.577606) (xy 155.518469 -296.611698) (xy 155.477966 -296.639654)
			(xy 155.433504 -296.660752) (xy 155.386233 -296.674444) (xy 155.337378 -296.680376) (xy 155.288203 -296.678395)
			(xy 155.239984 -296.668551) (xy 155.193968 -296.651099) (xy 155.151347 -296.626492) (xy 155.113226 -296.595367)
			(xy 155.080591 -296.55853) (xy 155.054288 -296.516934) (xy 155.034997 -296.471658) (xy 155.02322 -296.423874)
			(xy 155.01926 -296.37482) (xy 154.680158 -296.37482) (xy 154.679663 -296.399427) (xy 154.671768 -296.448004)
			(xy 154.656184 -296.494685) (xy 154.633313 -296.538262) (xy 154.603748 -296.577606) (xy 154.568255 -296.611698)
			(xy 154.527752 -296.639654) (xy 154.48329 -296.660752) (xy 154.436019 -296.674444) (xy 154.387164 -296.680376)
			(xy 154.337989 -296.678395) (xy 154.28977 -296.668551) (xy 154.243754 -296.651099) (xy 154.201133 -296.626492)
			(xy 154.163012 -296.595367) (xy 154.130377 -296.55853) (xy 154.104074 -296.516934) (xy 154.084783 -296.471658)
			(xy 154.073006 -296.423874) (xy 154.069046 -296.37482) (xy 153.730452 -296.37482) (xy 153.729957 -296.399427)
			(xy 153.722062 -296.448004) (xy 153.706478 -296.494685) (xy 153.683607 -296.538262) (xy 153.654042 -296.577606)
			(xy 153.618549 -296.611698) (xy 153.578046 -296.639654) (xy 153.533584 -296.660752) (xy 153.486313 -296.674444)
			(xy 153.437458 -296.680376) (xy 153.388283 -296.678395) (xy 153.340064 -296.668551) (xy 153.294048 -296.651099)
			(xy 153.251427 -296.626492) (xy 153.213306 -296.595367) (xy 153.180671 -296.55853) (xy 153.154368 -296.516934)
			(xy 153.135077 -296.471658) (xy 153.1233 -296.423874) (xy 153.11934 -296.37482) (xy 150.309624 -296.37482)
			(xy 150.325359 -296.384423) (xy 150.368227 -296.420098) (xy 150.405444 -296.461635) (xy 150.436217 -296.508148)
			(xy 150.459889 -296.558645) (xy 150.475957 -296.612052) (xy 150.484077 -296.667228) (xy 150.484586 -296.695114)
			(xy 150.484077 -296.723) (xy 150.475957 -296.778176) (xy 150.459889 -296.831583) (xy 150.436217 -296.88208)
			(xy 150.405444 -296.928593) (xy 150.368227 -296.97013) (xy 150.325359 -297.005805) (xy 150.277753 -297.034859)
			(xy 150.226424 -297.056671) (xy 150.172467 -297.070777) (xy 150.11703 -297.076877) (xy 150.061296 -297.07484)
			(xy 150.006453 -297.06471) (xy 149.953669 -297.046703) (xy 149.904069 -297.021202) (xy 149.858711 -296.988751)
			(xy 149.818562 -296.950042) (xy 149.784476 -296.905899) (xy 149.75718 -296.857264) (xy 149.737257 -296.805173)
			(xy 149.725131 -296.750736) (xy 149.72106 -296.695114) (xy 149.598126 -296.695114) (xy 149.597617 -296.723)
			(xy 149.589497 -296.778176) (xy 149.573429 -296.831583) (xy 149.549757 -296.88208) (xy 149.518984 -296.928593)
			(xy 149.481767 -296.97013) (xy 149.438899 -297.005805) (xy 149.391293 -297.034859) (xy 149.339964 -297.056671)
			(xy 149.286007 -297.070777) (xy 149.23057 -297.076877) (xy 149.174836 -297.07484) (xy 149.119993 -297.06471)
			(xy 149.067209 -297.046703) (xy 149.017609 -297.021202) (xy 148.972251 -296.988751) (xy 148.932102 -296.950042)
			(xy 148.898016 -296.905899) (xy 148.87072 -296.857264) (xy 148.850797 -296.805173) (xy 148.838671 -296.750736)
			(xy 148.8346 -296.695114) (xy 148.201126 -296.695114) (xy 148.20064 -296.722365) (xy 148.192884 -296.776313)
			(xy 148.177529 -296.828608) (xy 148.154887 -296.878185) (xy 148.125421 -296.924035) (xy 148.08973 -296.965226)
			(xy 148.048539 -297.000917) (xy 148.002689 -297.030383) (xy 147.953112 -297.053025) (xy 147.900817 -297.06838)
			(xy 147.846869 -297.076136) (xy 147.792367 -297.076136) (xy 147.738419 -297.06838) (xy 147.686124 -297.053025)
			(xy 147.636547 -297.030383) (xy 147.590697 -297.000917) (xy 147.549506 -296.965226) (xy 147.513815 -296.924035)
			(xy 147.484349 -296.878185) (xy 147.461707 -296.828608) (xy 147.446352 -296.776313) (xy 147.438596 -296.722365)
			(xy 147.43811 -296.695114) (xy 118.832884 -296.695114) (xy 118.832884 -297.3248) (xy 151.53402 -297.3248)
			(xy 151.538192 -297.274451) (xy 151.550595 -297.225475) (xy 151.570891 -297.179209) (xy 151.598525 -297.136915)
			(xy 151.632745 -297.099746) (xy 151.672615 -297.068717) (xy 151.71705 -297.044674) (xy 151.764835 -297.028274)
			(xy 151.814669 -297.019962) (xy 151.83993 -297.019472) (xy 151.865324 -297.020012) (xy 151.915412 -297.028419)
			(xy 151.963419 -297.044996) (xy 152.008022 -297.069287) (xy 152.047992 -297.100622) (xy 152.065482 -297.11904)
			(xy 152.073102 -297.127168) (xy 152.092914 -297.135804) (xy 152.192228 -297.13301) (xy 152.211786 -297.123612)
			(xy 152.218898 -297.114976) (xy 152.234711 -297.096425) (xy 152.270839 -297.063704) (xy 152.311375 -297.036635)
			(xy 152.355443 -297.015803) (xy 152.402088 -297.001658) (xy 152.450304 -296.994507) (xy 152.474676 -296.994072)
			(xy 153.424636 -296.994072) (xy 153.45062 -296.994624) (xy 153.501947 -297.002759) (xy 153.55137 -297.018822)
			(xy 153.597671 -297.042418) (xy 153.639712 -297.072967) (xy 153.676457 -297.109715) (xy 153.707001 -297.151759)
			(xy 153.730592 -297.198064) (xy 153.74665 -297.247488) (xy 153.754779 -297.298816) (xy 153.754779 -297.32478)
			(xy 154.069046 -297.32478) (xy 154.073006 -297.275726) (xy 154.084783 -297.227942) (xy 154.104074 -297.182666)
			(xy 154.130377 -297.14107) (xy 154.163012 -297.104233) (xy 154.201133 -297.073108) (xy 154.243754 -297.048501)
			(xy 154.28977 -297.031049) (xy 154.337989 -297.021205) (xy 154.387164 -297.019224) (xy 154.436019 -297.025156)
			(xy 154.48329 -297.038848) (xy 154.527752 -297.059946) (xy 154.568255 -297.087902) (xy 154.603748 -297.121994)
			(xy 154.633313 -297.161338) (xy 154.656184 -297.204915) (xy 154.671768 -297.251596) (xy 154.679663 -297.300173)
			(xy 154.680158 -297.32478) (xy 155.01926 -297.32478) (xy 155.02322 -297.275726) (xy 155.034997 -297.227942)
			(xy 155.054288 -297.182666) (xy 155.080591 -297.14107) (xy 155.113226 -297.104233) (xy 155.151347 -297.073108)
			(xy 155.193968 -297.048501) (xy 155.239984 -297.031049) (xy 155.288203 -297.021205) (xy 155.337378 -297.019224)
			(xy 155.386233 -297.025156) (xy 155.433504 -297.038848) (xy 155.477966 -297.059946) (xy 155.518469 -297.087902)
			(xy 155.553962 -297.121994) (xy 155.583527 -297.161338) (xy 155.606398 -297.204915) (xy 155.621982 -297.251596)
			(xy 155.629877 -297.300173) (xy 155.630372 -297.32478) (xy 157.86914 -297.32478) (xy 157.8731 -297.275726)
			(xy 157.884877 -297.227942) (xy 157.904168 -297.182666) (xy 157.930471 -297.14107) (xy 157.963106 -297.104233)
			(xy 158.001227 -297.073108) (xy 158.043848 -297.048501) (xy 158.089864 -297.031049) (xy 158.138083 -297.021205)
			(xy 158.187258 -297.019224) (xy 158.236113 -297.025156) (xy 158.283384 -297.038848) (xy 158.327846 -297.059946)
			(xy 158.368349 -297.087902) (xy 158.403842 -297.121994) (xy 158.433407 -297.161338) (xy 158.456278 -297.204915)
			(xy 158.471862 -297.251596) (xy 158.479757 -297.300173) (xy 158.480252 -297.32478) (xy 159.76906 -297.32478)
			(xy 159.77302 -297.275726) (xy 159.784797 -297.227942) (xy 159.804088 -297.182666) (xy 159.830391 -297.14107)
			(xy 159.863026 -297.104233) (xy 159.901147 -297.073108) (xy 159.943768 -297.048501) (xy 159.989784 -297.031049)
			(xy 160.038003 -297.021205) (xy 160.087178 -297.019224) (xy 160.136033 -297.025156) (xy 160.183304 -297.038848)
			(xy 160.227766 -297.059946) (xy 160.268269 -297.087902) (xy 160.303762 -297.121994) (xy 160.333327 -297.161338)
			(xy 160.356198 -297.204915) (xy 160.371782 -297.251596) (xy 160.379677 -297.300173) (xy 160.380172 -297.32478)
			(xy 160.719274 -297.32478) (xy 160.723234 -297.275726) (xy 160.735011 -297.227942) (xy 160.754302 -297.182666)
			(xy 160.780605 -297.14107) (xy 160.81324 -297.104233) (xy 160.851361 -297.073108) (xy 160.893982 -297.048501)
			(xy 160.939998 -297.031049) (xy 160.988217 -297.021205) (xy 161.037392 -297.019224) (xy 161.086247 -297.025156)
			(xy 161.133518 -297.038848) (xy 161.17798 -297.059946) (xy 161.218483 -297.087902) (xy 161.253976 -297.121994)
			(xy 161.283541 -297.161338) (xy 161.306412 -297.204915) (xy 161.321996 -297.251596) (xy 161.329891 -297.300173)
			(xy 161.330386 -297.32478) (xy 161.669234 -297.32478) (xy 161.673194 -297.275726) (xy 161.684971 -297.227942)
			(xy 161.704262 -297.182666) (xy 161.730565 -297.14107) (xy 161.7632 -297.104233) (xy 161.801321 -297.073108)
			(xy 161.843942 -297.048501) (xy 161.889958 -297.031049) (xy 161.938177 -297.021205) (xy 161.987352 -297.019224)
			(xy 162.036207 -297.025156) (xy 162.083478 -297.038848) (xy 162.12794 -297.059946) (xy 162.168443 -297.087902)
			(xy 162.203936 -297.121994) (xy 162.233501 -297.161338) (xy 162.256372 -297.204915) (xy 162.271956 -297.251596)
			(xy 162.279851 -297.300173) (xy 162.280346 -297.32478) (xy 162.619194 -297.32478) (xy 162.623154 -297.275726)
			(xy 162.634931 -297.227942) (xy 162.654222 -297.182666) (xy 162.680525 -297.14107) (xy 162.71316 -297.104233)
			(xy 162.751281 -297.073108) (xy 162.793902 -297.048501) (xy 162.839918 -297.031049) (xy 162.888137 -297.021205)
			(xy 162.937312 -297.019224) (xy 162.986167 -297.025156) (xy 163.033438 -297.038848) (xy 163.0779 -297.059946)
			(xy 163.118403 -297.087902) (xy 163.153896 -297.121994) (xy 163.183461 -297.161338) (xy 163.206332 -297.204915)
			(xy 163.221916 -297.251596) (xy 163.229811 -297.300173) (xy 163.230306 -297.32478) (xy 163.569154 -297.32478)
			(xy 163.573114 -297.275726) (xy 163.584891 -297.227942) (xy 163.604182 -297.182666) (xy 163.630485 -297.14107)
			(xy 163.66312 -297.104233) (xy 163.701241 -297.073108) (xy 163.743862 -297.048501) (xy 163.789878 -297.031049)
			(xy 163.838097 -297.021205) (xy 163.887272 -297.019224) (xy 163.936127 -297.025156) (xy 163.983398 -297.038848)
			(xy 164.02786 -297.059946) (xy 164.068363 -297.087902) (xy 164.103856 -297.121994) (xy 164.133421 -297.161338)
			(xy 164.156292 -297.204915) (xy 164.171876 -297.251596) (xy 164.179771 -297.300173) (xy 164.180266 -297.32478)
			(xy 165.469074 -297.32478) (xy 165.473034 -297.275726) (xy 165.484811 -297.227942) (xy 165.504102 -297.182666)
			(xy 165.530405 -297.14107) (xy 165.56304 -297.104233) (xy 165.601161 -297.073108) (xy 165.643782 -297.048501)
			(xy 165.689798 -297.031049) (xy 165.738017 -297.021205) (xy 165.787192 -297.019224) (xy 165.836047 -297.025156)
			(xy 165.883318 -297.038848) (xy 165.92778 -297.059946) (xy 165.968283 -297.087902) (xy 166.003776 -297.121994)
			(xy 166.033341 -297.161338) (xy 166.056212 -297.204915) (xy 166.071796 -297.251596) (xy 166.079691 -297.300173)
			(xy 166.080186 -297.32478) (xy 167.369248 -297.32478) (xy 167.373208 -297.275726) (xy 167.384985 -297.227942)
			(xy 167.404276 -297.182666) (xy 167.430579 -297.14107) (xy 167.463214 -297.104233) (xy 167.501335 -297.073108)
			(xy 167.543956 -297.048501) (xy 167.589972 -297.031049) (xy 167.638191 -297.021205) (xy 167.687366 -297.019224)
			(xy 167.736221 -297.025156) (xy 167.783492 -297.038848) (xy 167.827954 -297.059946) (xy 167.868457 -297.087902)
			(xy 167.90395 -297.121994) (xy 167.933515 -297.161338) (xy 167.956386 -297.204915) (xy 167.97197 -297.251596)
			(xy 167.979865 -297.300173) (xy 167.98036 -297.32478) (xy 169.269168 -297.32478) (xy 169.273128 -297.275726)
			(xy 169.284905 -297.227942) (xy 169.304196 -297.182666) (xy 169.330499 -297.14107) (xy 169.363134 -297.104233)
			(xy 169.401255 -297.073108) (xy 169.443876 -297.048501) (xy 169.489892 -297.031049) (xy 169.538111 -297.021205)
			(xy 169.587286 -297.019224) (xy 169.636141 -297.025156) (xy 169.683412 -297.038848) (xy 169.727874 -297.059946)
			(xy 169.768377 -297.087902) (xy 169.80387 -297.121994) (xy 169.833435 -297.161338) (xy 169.856306 -297.204915)
			(xy 169.87189 -297.251596) (xy 169.879785 -297.300173) (xy 169.88028 -297.32478) (xy 171.169088 -297.32478)
			(xy 171.173048 -297.275726) (xy 171.184825 -297.227942) (xy 171.204116 -297.182666) (xy 171.230419 -297.14107)
			(xy 171.263054 -297.104233) (xy 171.301175 -297.073108) (xy 171.343796 -297.048501) (xy 171.389812 -297.031049)
			(xy 171.438031 -297.021205) (xy 171.487206 -297.019224) (xy 171.536061 -297.025156) (xy 171.583332 -297.038848)
			(xy 171.627794 -297.059946) (xy 171.668297 -297.087902) (xy 171.70379 -297.121994) (xy 171.733355 -297.161338)
			(xy 171.756226 -297.204915) (xy 171.77181 -297.251596) (xy 171.779705 -297.300173) (xy 171.7802 -297.32478)
			(xy 173.069262 -297.32478) (xy 173.073222 -297.275726) (xy 173.084999 -297.227942) (xy 173.10429 -297.182666)
			(xy 173.130593 -297.14107) (xy 173.163228 -297.104233) (xy 173.201349 -297.073108) (xy 173.24397 -297.048501)
			(xy 173.289986 -297.031049) (xy 173.338205 -297.021205) (xy 173.38738 -297.019224) (xy 173.436235 -297.025156)
			(xy 173.483506 -297.038848) (xy 173.527968 -297.059946) (xy 173.568471 -297.087902) (xy 173.603964 -297.121994)
			(xy 173.633529 -297.161338) (xy 173.6564 -297.204915) (xy 173.671984 -297.251596) (xy 173.679879 -297.300173)
			(xy 173.680374 -297.32478) (xy 175.919142 -297.32478) (xy 175.923102 -297.275726) (xy 175.934879 -297.227942)
			(xy 175.95417 -297.182666) (xy 175.980473 -297.14107) (xy 176.013108 -297.104233) (xy 176.051229 -297.073108)
			(xy 176.09385 -297.048501) (xy 176.139866 -297.031049) (xy 176.188085 -297.021205) (xy 176.23726 -297.019224)
			(xy 176.286115 -297.025156) (xy 176.333386 -297.038848) (xy 176.377848 -297.059946) (xy 176.418351 -297.087902)
			(xy 176.453844 -297.121994) (xy 176.483409 -297.161338) (xy 176.50628 -297.204915) (xy 176.521864 -297.251596)
			(xy 176.529759 -297.300173) (xy 176.530254 -297.32478) (xy 177.819062 -297.32478) (xy 177.823022 -297.275726)
			(xy 177.834799 -297.227942) (xy 177.85409 -297.182666) (xy 177.880393 -297.14107) (xy 177.913028 -297.104233)
			(xy 177.951149 -297.073108) (xy 177.99377 -297.048501) (xy 178.039786 -297.031049) (xy 178.088005 -297.021205)
			(xy 178.13718 -297.019224) (xy 178.186035 -297.025156) (xy 178.233306 -297.038848) (xy 178.277768 -297.059946)
			(xy 178.318271 -297.087902) (xy 178.353764 -297.121994) (xy 178.383329 -297.161338) (xy 178.4062 -297.204915)
			(xy 178.421784 -297.251596) (xy 178.429679 -297.300173) (xy 178.430174 -297.32478) (xy 179.719236 -297.32478)
			(xy 179.723196 -297.275726) (xy 179.734973 -297.227942) (xy 179.754264 -297.182666) (xy 179.780567 -297.14107)
			(xy 179.813202 -297.104233) (xy 179.851323 -297.073108) (xy 179.893944 -297.048501) (xy 179.93996 -297.031049)
			(xy 179.988179 -297.021205) (xy 180.037354 -297.019224) (xy 180.086209 -297.025156) (xy 180.13348 -297.038848)
			(xy 180.177942 -297.059946) (xy 180.218445 -297.087902) (xy 180.253938 -297.121994) (xy 180.283503 -297.161338)
			(xy 180.306374 -297.204915) (xy 180.321958 -297.251596) (xy 180.329853 -297.300173) (xy 180.330348 -297.32478)
			(xy 181.619156 -297.32478) (xy 181.623116 -297.275726) (xy 181.634893 -297.227942) (xy 181.654184 -297.182666)
			(xy 181.680487 -297.14107) (xy 181.713122 -297.104233) (xy 181.751243 -297.073108) (xy 181.793864 -297.048501)
			(xy 181.83988 -297.031049) (xy 181.888099 -297.021205) (xy 181.937274 -297.019224) (xy 181.986129 -297.025156)
			(xy 182.0334 -297.038848) (xy 182.077862 -297.059946) (xy 182.118365 -297.087902) (xy 182.153858 -297.121994)
			(xy 182.183423 -297.161338) (xy 182.206294 -297.204915) (xy 182.221878 -297.251596) (xy 182.229773 -297.300173)
			(xy 182.230268 -297.32478) (xy 182.569116 -297.32478) (xy 182.573076 -297.275726) (xy 182.584853 -297.227942)
			(xy 182.604144 -297.182666) (xy 182.630447 -297.14107) (xy 182.663082 -297.104233) (xy 182.701203 -297.073108)
			(xy 182.743824 -297.048501) (xy 182.78984 -297.031049) (xy 182.838059 -297.021205) (xy 182.887234 -297.019224)
			(xy 182.936089 -297.025156) (xy 182.98336 -297.038848) (xy 183.027822 -297.059946) (xy 183.068325 -297.087902)
			(xy 183.103818 -297.121994) (xy 183.133383 -297.161338) (xy 183.156254 -297.204915) (xy 183.171838 -297.251596)
			(xy 183.179733 -297.300173) (xy 183.180228 -297.32478) (xy 183.519076 -297.32478) (xy 183.523036 -297.275726)
			(xy 183.534813 -297.227942) (xy 183.554104 -297.182666) (xy 183.580407 -297.14107) (xy 183.613042 -297.104233)
			(xy 183.651163 -297.073108) (xy 183.693784 -297.048501) (xy 183.7398 -297.031049) (xy 183.788019 -297.021205)
			(xy 183.837194 -297.019224) (xy 183.886049 -297.025156) (xy 183.93332 -297.038848) (xy 183.977782 -297.059946)
			(xy 184.018285 -297.087902) (xy 184.053778 -297.121994) (xy 184.083343 -297.161338) (xy 184.106214 -297.204915)
			(xy 184.121798 -297.251596) (xy 184.129693 -297.300173) (xy 184.130188 -297.32478) (xy 184.469036 -297.32478)
			(xy 184.472996 -297.275726) (xy 184.484773 -297.227942) (xy 184.504064 -297.182666) (xy 184.530367 -297.14107)
			(xy 184.563002 -297.104233) (xy 184.601123 -297.073108) (xy 184.643744 -297.048501) (xy 184.68976 -297.031049)
			(xy 184.737979 -297.021205) (xy 184.787154 -297.019224) (xy 184.836009 -297.025156) (xy 184.88328 -297.038848)
			(xy 184.927742 -297.059946) (xy 184.968245 -297.087902) (xy 185.003738 -297.121994) (xy 185.033303 -297.161338)
			(xy 185.056174 -297.204915) (xy 185.071758 -297.251596) (xy 185.079653 -297.300173) (xy 185.080148 -297.32478)
			(xy 185.079653 -297.349387) (xy 185.071758 -297.397964) (xy 185.056174 -297.444645) (xy 185.033303 -297.488222)
			(xy 185.003738 -297.527566) (xy 184.968245 -297.561658) (xy 184.927742 -297.589614) (xy 184.88328 -297.610712)
			(xy 184.836009 -297.624404) (xy 184.787154 -297.630336) (xy 184.737979 -297.628355) (xy 184.68976 -297.618511)
			(xy 184.643744 -297.601059) (xy 184.601123 -297.576452) (xy 184.563002 -297.545327) (xy 184.530367 -297.50849)
			(xy 184.504064 -297.466894) (xy 184.484773 -297.421618) (xy 184.472996 -297.373834) (xy 184.469036 -297.32478)
			(xy 184.130188 -297.32478) (xy 184.129693 -297.349387) (xy 184.121798 -297.397964) (xy 184.106214 -297.444645)
			(xy 184.083343 -297.488222) (xy 184.053778 -297.527566) (xy 184.018285 -297.561658) (xy 183.977782 -297.589614)
			(xy 183.93332 -297.610712) (xy 183.886049 -297.624404) (xy 183.837194 -297.630336) (xy 183.788019 -297.628355)
			(xy 183.7398 -297.618511) (xy 183.693784 -297.601059) (xy 183.651163 -297.576452) (xy 183.613042 -297.545327)
			(xy 183.580407 -297.50849) (xy 183.554104 -297.466894) (xy 183.534813 -297.421618) (xy 183.523036 -297.373834)
			(xy 183.519076 -297.32478) (xy 183.180228 -297.32478) (xy 183.179733 -297.349387) (xy 183.171838 -297.397964)
			(xy 183.156254 -297.444645) (xy 183.133383 -297.488222) (xy 183.103818 -297.527566) (xy 183.068325 -297.561658)
			(xy 183.027822 -297.589614) (xy 182.98336 -297.610712) (xy 182.936089 -297.624404) (xy 182.887234 -297.630336)
			(xy 182.838059 -297.628355) (xy 182.78984 -297.618511) (xy 182.743824 -297.601059) (xy 182.701203 -297.576452)
			(xy 182.663082 -297.545327) (xy 182.630447 -297.50849) (xy 182.604144 -297.466894) (xy 182.584853 -297.421618)
			(xy 182.573076 -297.373834) (xy 182.569116 -297.32478) (xy 182.230268 -297.32478) (xy 182.229773 -297.349387)
			(xy 182.221878 -297.397964) (xy 182.206294 -297.444645) (xy 182.183423 -297.488222) (xy 182.153858 -297.527566)
			(xy 182.118365 -297.561658) (xy 182.077862 -297.589614) (xy 182.0334 -297.610712) (xy 181.986129 -297.624404)
			(xy 181.937274 -297.630336) (xy 181.888099 -297.628355) (xy 181.83988 -297.618511) (xy 181.793864 -297.601059)
			(xy 181.751243 -297.576452) (xy 181.713122 -297.545327) (xy 181.680487 -297.50849) (xy 181.654184 -297.466894)
			(xy 181.634893 -297.421618) (xy 181.623116 -297.373834) (xy 181.619156 -297.32478) (xy 180.330348 -297.32478)
			(xy 180.329853 -297.349387) (xy 180.321958 -297.397964) (xy 180.306374 -297.444645) (xy 180.283503 -297.488222)
			(xy 180.253938 -297.527566) (xy 180.218445 -297.561658) (xy 180.177942 -297.589614) (xy 180.13348 -297.610712)
			(xy 180.086209 -297.624404) (xy 180.037354 -297.630336) (xy 179.988179 -297.628355) (xy 179.93996 -297.618511)
			(xy 179.893944 -297.601059) (xy 179.851323 -297.576452) (xy 179.813202 -297.545327) (xy 179.780567 -297.50849)
			(xy 179.754264 -297.466894) (xy 179.734973 -297.421618) (xy 179.723196 -297.373834) (xy 179.719236 -297.32478)
			(xy 178.430174 -297.32478) (xy 178.429679 -297.349387) (xy 178.421784 -297.397964) (xy 178.4062 -297.444645)
			(xy 178.383329 -297.488222) (xy 178.353764 -297.527566) (xy 178.318271 -297.561658) (xy 178.277768 -297.589614)
			(xy 178.233306 -297.610712) (xy 178.186035 -297.624404) (xy 178.13718 -297.630336) (xy 178.088005 -297.628355)
			(xy 178.039786 -297.618511) (xy 177.99377 -297.601059) (xy 177.951149 -297.576452) (xy 177.913028 -297.545327)
			(xy 177.880393 -297.50849) (xy 177.85409 -297.466894) (xy 177.834799 -297.421618) (xy 177.823022 -297.373834)
			(xy 177.819062 -297.32478) (xy 176.530254 -297.32478) (xy 176.529759 -297.349387) (xy 176.521864 -297.397964)
			(xy 176.50628 -297.444645) (xy 176.483409 -297.488222) (xy 176.453844 -297.527566) (xy 176.418351 -297.561658)
			(xy 176.377848 -297.589614) (xy 176.333386 -297.610712) (xy 176.286115 -297.624404) (xy 176.23726 -297.630336)
			(xy 176.188085 -297.628355) (xy 176.139866 -297.618511) (xy 176.09385 -297.601059) (xy 176.051229 -297.576452)
			(xy 176.013108 -297.545327) (xy 175.980473 -297.50849) (xy 175.95417 -297.466894) (xy 175.934879 -297.421618)
			(xy 175.923102 -297.373834) (xy 175.919142 -297.32478) (xy 173.680374 -297.32478) (xy 173.679879 -297.349387)
			(xy 173.671984 -297.397964) (xy 173.6564 -297.444645) (xy 173.633529 -297.488222) (xy 173.603964 -297.527566)
			(xy 173.568471 -297.561658) (xy 173.527968 -297.589614) (xy 173.483506 -297.610712) (xy 173.436235 -297.624404)
			(xy 173.38738 -297.630336) (xy 173.338205 -297.628355) (xy 173.289986 -297.618511) (xy 173.24397 -297.601059)
			(xy 173.201349 -297.576452) (xy 173.163228 -297.545327) (xy 173.130593 -297.50849) (xy 173.10429 -297.466894)
			(xy 173.084999 -297.421618) (xy 173.073222 -297.373834) (xy 173.069262 -297.32478) (xy 171.7802 -297.32478)
			(xy 171.779705 -297.349387) (xy 171.77181 -297.397964) (xy 171.756226 -297.444645) (xy 171.733355 -297.488222)
			(xy 171.70379 -297.527566) (xy 171.668297 -297.561658) (xy 171.627794 -297.589614) (xy 171.583332 -297.610712)
			(xy 171.536061 -297.624404) (xy 171.487206 -297.630336) (xy 171.438031 -297.628355) (xy 171.389812 -297.618511)
			(xy 171.343796 -297.601059) (xy 171.301175 -297.576452) (xy 171.263054 -297.545327) (xy 171.230419 -297.50849)
			(xy 171.204116 -297.466894) (xy 171.184825 -297.421618) (xy 171.173048 -297.373834) (xy 171.169088 -297.32478)
			(xy 169.88028 -297.32478) (xy 169.879785 -297.349387) (xy 169.87189 -297.397964) (xy 169.856306 -297.444645)
			(xy 169.833435 -297.488222) (xy 169.80387 -297.527566) (xy 169.768377 -297.561658) (xy 169.727874 -297.589614)
			(xy 169.683412 -297.610712) (xy 169.636141 -297.624404) (xy 169.587286 -297.630336) (xy 169.538111 -297.628355)
			(xy 169.489892 -297.618511) (xy 169.443876 -297.601059) (xy 169.401255 -297.576452) (xy 169.363134 -297.545327)
			(xy 169.330499 -297.50849) (xy 169.304196 -297.466894) (xy 169.284905 -297.421618) (xy 169.273128 -297.373834)
			(xy 169.269168 -297.32478) (xy 167.98036 -297.32478) (xy 167.979865 -297.349387) (xy 167.97197 -297.397964)
			(xy 167.956386 -297.444645) (xy 167.933515 -297.488222) (xy 167.90395 -297.527566) (xy 167.868457 -297.561658)
			(xy 167.827954 -297.589614) (xy 167.783492 -297.610712) (xy 167.736221 -297.624404) (xy 167.687366 -297.630336)
			(xy 167.638191 -297.628355) (xy 167.589972 -297.618511) (xy 167.543956 -297.601059) (xy 167.501335 -297.576452)
			(xy 167.463214 -297.545327) (xy 167.430579 -297.50849) (xy 167.404276 -297.466894) (xy 167.384985 -297.421618)
			(xy 167.373208 -297.373834) (xy 167.369248 -297.32478) (xy 166.080186 -297.32478) (xy 166.079691 -297.349387)
			(xy 166.071796 -297.397964) (xy 166.056212 -297.444645) (xy 166.033341 -297.488222) (xy 166.003776 -297.527566)
			(xy 165.968283 -297.561658) (xy 165.92778 -297.589614) (xy 165.883318 -297.610712) (xy 165.836047 -297.624404)
			(xy 165.787192 -297.630336) (xy 165.738017 -297.628355) (xy 165.689798 -297.618511) (xy 165.643782 -297.601059)
			(xy 165.601161 -297.576452) (xy 165.56304 -297.545327) (xy 165.530405 -297.50849) (xy 165.504102 -297.466894)
			(xy 165.484811 -297.421618) (xy 165.473034 -297.373834) (xy 165.469074 -297.32478) (xy 164.180266 -297.32478)
			(xy 164.179771 -297.349387) (xy 164.171876 -297.397964) (xy 164.156292 -297.444645) (xy 164.133421 -297.488222)
			(xy 164.103856 -297.527566) (xy 164.068363 -297.561658) (xy 164.02786 -297.589614) (xy 163.983398 -297.610712)
			(xy 163.936127 -297.624404) (xy 163.887272 -297.630336) (xy 163.838097 -297.628355) (xy 163.789878 -297.618511)
			(xy 163.743862 -297.601059) (xy 163.701241 -297.576452) (xy 163.66312 -297.545327) (xy 163.630485 -297.50849)
			(xy 163.604182 -297.466894) (xy 163.584891 -297.421618) (xy 163.573114 -297.373834) (xy 163.569154 -297.32478)
			(xy 163.230306 -297.32478) (xy 163.229811 -297.349387) (xy 163.221916 -297.397964) (xy 163.206332 -297.444645)
			(xy 163.183461 -297.488222) (xy 163.153896 -297.527566) (xy 163.118403 -297.561658) (xy 163.0779 -297.589614)
			(xy 163.033438 -297.610712) (xy 162.986167 -297.624404) (xy 162.937312 -297.630336) (xy 162.888137 -297.628355)
			(xy 162.839918 -297.618511) (xy 162.793902 -297.601059) (xy 162.751281 -297.576452) (xy 162.71316 -297.545327)
			(xy 162.680525 -297.50849) (xy 162.654222 -297.466894) (xy 162.634931 -297.421618) (xy 162.623154 -297.373834)
			(xy 162.619194 -297.32478) (xy 162.280346 -297.32478) (xy 162.279851 -297.349387) (xy 162.271956 -297.397964)
			(xy 162.256372 -297.444645) (xy 162.233501 -297.488222) (xy 162.203936 -297.527566) (xy 162.168443 -297.561658)
			(xy 162.12794 -297.589614) (xy 162.083478 -297.610712) (xy 162.036207 -297.624404) (xy 161.987352 -297.630336)
			(xy 161.938177 -297.628355) (xy 161.889958 -297.618511) (xy 161.843942 -297.601059) (xy 161.801321 -297.576452)
			(xy 161.7632 -297.545327) (xy 161.730565 -297.50849) (xy 161.704262 -297.466894) (xy 161.684971 -297.421618)
			(xy 161.673194 -297.373834) (xy 161.669234 -297.32478) (xy 161.330386 -297.32478) (xy 161.329891 -297.349387)
			(xy 161.321996 -297.397964) (xy 161.306412 -297.444645) (xy 161.283541 -297.488222) (xy 161.253976 -297.527566)
			(xy 161.218483 -297.561658) (xy 161.17798 -297.589614) (xy 161.133518 -297.610712) (xy 161.086247 -297.624404)
			(xy 161.037392 -297.630336) (xy 160.988217 -297.628355) (xy 160.939998 -297.618511) (xy 160.893982 -297.601059)
			(xy 160.851361 -297.576452) (xy 160.81324 -297.545327) (xy 160.780605 -297.50849) (xy 160.754302 -297.466894)
			(xy 160.735011 -297.421618) (xy 160.723234 -297.373834) (xy 160.719274 -297.32478) (xy 160.380172 -297.32478)
			(xy 160.379677 -297.349387) (xy 160.371782 -297.397964) (xy 160.356198 -297.444645) (xy 160.333327 -297.488222)
			(xy 160.303762 -297.527566) (xy 160.268269 -297.561658) (xy 160.227766 -297.589614) (xy 160.183304 -297.610712)
			(xy 160.136033 -297.624404) (xy 160.087178 -297.630336) (xy 160.038003 -297.628355) (xy 159.989784 -297.618511)
			(xy 159.943768 -297.601059) (xy 159.901147 -297.576452) (xy 159.863026 -297.545327) (xy 159.830391 -297.50849)
			(xy 159.804088 -297.466894) (xy 159.784797 -297.421618) (xy 159.77302 -297.373834) (xy 159.76906 -297.32478)
			(xy 158.480252 -297.32478) (xy 158.479757 -297.349387) (xy 158.471862 -297.397964) (xy 158.456278 -297.444645)
			(xy 158.433407 -297.488222) (xy 158.403842 -297.527566) (xy 158.368349 -297.561658) (xy 158.327846 -297.589614)
			(xy 158.283384 -297.610712) (xy 158.236113 -297.624404) (xy 158.187258 -297.630336) (xy 158.138083 -297.628355)
			(xy 158.089864 -297.618511) (xy 158.043848 -297.601059) (xy 158.001227 -297.576452) (xy 157.963106 -297.545327)
			(xy 157.930471 -297.50849) (xy 157.904168 -297.466894) (xy 157.884877 -297.421618) (xy 157.8731 -297.373834)
			(xy 157.86914 -297.32478) (xy 155.630372 -297.32478) (xy 155.629877 -297.349387) (xy 155.621982 -297.397964)
			(xy 155.606398 -297.444645) (xy 155.583527 -297.488222) (xy 155.553962 -297.527566) (xy 155.518469 -297.561658)
			(xy 155.477966 -297.589614) (xy 155.433504 -297.610712) (xy 155.386233 -297.624404) (xy 155.337378 -297.630336)
			(xy 155.288203 -297.628355) (xy 155.239984 -297.618511) (xy 155.193968 -297.601059) (xy 155.151347 -297.576452)
			(xy 155.113226 -297.545327) (xy 155.080591 -297.50849) (xy 155.054288 -297.466894) (xy 155.034997 -297.421618)
			(xy 155.02322 -297.373834) (xy 155.01926 -297.32478) (xy 154.680158 -297.32478) (xy 154.679663 -297.349387)
			(xy 154.671768 -297.397964) (xy 154.656184 -297.444645) (xy 154.633313 -297.488222) (xy 154.603748 -297.527566)
			(xy 154.568255 -297.561658) (xy 154.527752 -297.589614) (xy 154.48329 -297.610712) (xy 154.436019 -297.624404)
			(xy 154.387164 -297.630336) (xy 154.337989 -297.628355) (xy 154.28977 -297.618511) (xy 154.243754 -297.601059)
			(xy 154.201133 -297.576452) (xy 154.163012 -297.545327) (xy 154.130377 -297.50849) (xy 154.104074 -297.466894)
			(xy 154.084783 -297.421618) (xy 154.073006 -297.373834) (xy 154.069046 -297.32478) (xy 153.754779 -297.32478)
			(xy 153.754779 -297.350784) (xy 153.74665 -297.402112) (xy 153.730592 -297.451536) (xy 153.707001 -297.497841)
			(xy 153.676457 -297.539885) (xy 153.639712 -297.576633) (xy 153.597671 -297.607182) (xy 153.55137 -297.630778)
			(xy 153.501947 -297.646841) (xy 153.45062 -297.654976) (xy 153.424636 -297.655488) (xy 152.474676 -297.655488)
			(xy 152.450304 -297.655045) (xy 152.402085 -297.647904) (xy 152.355436 -297.633766) (xy 152.311365 -297.612937)
			(xy 152.270828 -297.585868) (xy 152.234701 -297.553144) (xy 152.218898 -297.534584) (xy 152.211786 -297.525948)
			(xy 152.192228 -297.51655) (xy 152.092914 -297.513756) (xy 152.073102 -297.522392) (xy 152.065482 -297.53052)
			(xy 152.048017 -297.548966) (xy 152.008048 -297.580314) (xy 151.96344 -297.604613) (xy 151.915425 -297.62119)
			(xy 151.865328 -297.629589) (xy 151.83993 -297.630088) (xy 151.814669 -297.629638) (xy 151.764835 -297.621326)
			(xy 151.71705 -297.604926) (xy 151.672615 -297.580883) (xy 151.632745 -297.549854) (xy 151.598525 -297.512685)
			(xy 151.570891 -297.470391) (xy 151.550595 -297.424125) (xy 151.538192 -297.375149) (xy 151.53402 -297.3248)
			(xy 118.832884 -297.3248) (xy 118.832884 -297.831256) (xy 141.911576 -297.831256) (xy 141.915647 -297.775634)
			(xy 141.927773 -297.721197) (xy 141.947696 -297.669106) (xy 141.974992 -297.620471) (xy 142.009078 -297.576328)
			(xy 142.049227 -297.537619) (xy 142.094585 -297.505168) (xy 142.144185 -297.479667) (xy 142.196969 -297.46166)
			(xy 142.251812 -297.45153) (xy 142.307546 -297.449493) (xy 142.362983 -297.455593) (xy 142.41694 -297.469699)
			(xy 142.468269 -297.491511) (xy 142.515875 -297.520565) (xy 142.558743 -297.55624) (xy 142.59596 -297.597777)
			(xy 142.626733 -297.64429) (xy 142.650405 -297.694787) (xy 142.666473 -297.748194) (xy 142.674593 -297.80337)
			(xy 142.675102 -297.831256) (xy 143.396714 -297.831256) (xy 143.400785 -297.775634) (xy 143.412911 -297.721197)
			(xy 143.432834 -297.669106) (xy 143.46013 -297.620471) (xy 143.494216 -297.576328) (xy 143.534365 -297.537619)
			(xy 143.579723 -297.505168) (xy 143.629323 -297.479667) (xy 143.682107 -297.46166) (xy 143.73695 -297.45153)
			(xy 143.792684 -297.449493) (xy 143.848121 -297.455593) (xy 143.902078 -297.469699) (xy 143.953407 -297.491511)
			(xy 144.001013 -297.520565) (xy 144.043881 -297.55624) (xy 144.081098 -297.597777) (xy 144.111871 -297.64429)
			(xy 144.135543 -297.694787) (xy 144.151611 -297.748194) (xy 144.159731 -297.80337) (xy 144.16024 -297.831256)
			(xy 144.159731 -297.859142) (xy 144.151611 -297.914318) (xy 144.135543 -297.967725) (xy 144.111871 -298.018222)
			(xy 144.081098 -298.064735) (xy 144.043881 -298.106272) (xy 144.001013 -298.141947) (xy 143.953407 -298.171001)
			(xy 143.902078 -298.192813) (xy 143.848121 -298.206919) (xy 143.792684 -298.213019) (xy 143.73695 -298.210982)
			(xy 143.682107 -298.200852) (xy 143.629323 -298.182845) (xy 143.579723 -298.157344) (xy 143.534365 -298.124893)
			(xy 143.494216 -298.086184) (xy 143.46013 -298.042041) (xy 143.432834 -297.993406) (xy 143.412911 -297.941315)
			(xy 143.400785 -297.886878) (xy 143.396714 -297.831256) (xy 142.675102 -297.831256) (xy 142.674593 -297.859142)
			(xy 142.666473 -297.914318) (xy 142.650405 -297.967725) (xy 142.626733 -298.018222) (xy 142.59596 -298.064735)
			(xy 142.558743 -298.106272) (xy 142.515875 -298.141947) (xy 142.468269 -298.171001) (xy 142.41694 -298.192813)
			(xy 142.362983 -298.206919) (xy 142.307546 -298.213019) (xy 142.251812 -298.210982) (xy 142.196969 -298.200852)
			(xy 142.144185 -298.182845) (xy 142.094585 -298.157344) (xy 142.049227 -298.124893) (xy 142.009078 -298.086184)
			(xy 141.974992 -298.042041) (xy 141.947696 -297.993406) (xy 141.927773 -297.941315) (xy 141.915647 -297.886878)
			(xy 141.911576 -297.831256) (xy 118.832884 -297.831256) (xy 118.832884 -298.27474) (xy 153.118832 -298.27474)
			(xy 153.122792 -298.225686) (xy 153.134569 -298.177902) (xy 153.15386 -298.132626) (xy 153.180163 -298.09103)
			(xy 153.212798 -298.054193) (xy 153.250919 -298.023068) (xy 153.29354 -297.998461) (xy 153.339556 -297.981009)
			(xy 153.387775 -297.971165) (xy 153.43695 -297.969184) (xy 153.485805 -297.975116) (xy 153.533076 -297.988808)
			(xy 153.577538 -298.009906) (xy 153.618041 -298.037862) (xy 153.653534 -298.071954) (xy 153.683099 -298.111298)
			(xy 153.70597 -298.154875) (xy 153.721554 -298.201556) (xy 153.729449 -298.250133) (xy 153.729944 -298.27474)
			(xy 154.069046 -298.27474) (xy 154.073006 -298.225686) (xy 154.084783 -298.177902) (xy 154.104074 -298.132626)
			(xy 154.130377 -298.09103) (xy 154.163012 -298.054193) (xy 154.201133 -298.023068) (xy 154.243754 -297.998461)
			(xy 154.28977 -297.981009) (xy 154.337989 -297.971165) (xy 154.387164 -297.969184) (xy 154.436019 -297.975116)
			(xy 154.48329 -297.988808) (xy 154.527752 -298.009906) (xy 154.568255 -298.037862) (xy 154.603748 -298.071954)
			(xy 154.633313 -298.111298) (xy 154.656184 -298.154875) (xy 154.671768 -298.201556) (xy 154.679663 -298.250133)
			(xy 154.680158 -298.27474) (xy 155.01926 -298.27474) (xy 155.02322 -298.225686) (xy 155.034997 -298.177902)
			(xy 155.054288 -298.132626) (xy 155.080591 -298.09103) (xy 155.113226 -298.054193) (xy 155.151347 -298.023068)
			(xy 155.193968 -297.998461) (xy 155.239984 -297.981009) (xy 155.288203 -297.971165) (xy 155.337378 -297.969184)
			(xy 155.386233 -297.975116) (xy 155.433504 -297.988808) (xy 155.477966 -298.009906) (xy 155.518469 -298.037862)
			(xy 155.553962 -298.071954) (xy 155.583527 -298.111298) (xy 155.606398 -298.154875) (xy 155.621982 -298.201556)
			(xy 155.629877 -298.250133) (xy 155.630372 -298.27474) (xy 155.96922 -298.27474) (xy 155.97318 -298.225686)
			(xy 155.984957 -298.177902) (xy 156.004248 -298.132626) (xy 156.030551 -298.09103) (xy 156.063186 -298.054193)
			(xy 156.101307 -298.023068) (xy 156.143928 -297.998461) (xy 156.189944 -297.981009) (xy 156.238163 -297.971165)
			(xy 156.287338 -297.969184) (xy 156.336193 -297.975116) (xy 156.383464 -297.988808) (xy 156.427926 -298.009906)
			(xy 156.468429 -298.037862) (xy 156.503922 -298.071954) (xy 156.533487 -298.111298) (xy 156.556358 -298.154875)
			(xy 156.571942 -298.201556) (xy 156.579837 -298.250133) (xy 156.580332 -298.27474) (xy 156.91918 -298.27474)
			(xy 156.92314 -298.225686) (xy 156.934917 -298.177902) (xy 156.954208 -298.132626) (xy 156.980511 -298.09103)
			(xy 157.013146 -298.054193) (xy 157.051267 -298.023068) (xy 157.093888 -297.998461) (xy 157.139904 -297.981009)
			(xy 157.188123 -297.971165) (xy 157.237298 -297.969184) (xy 157.286153 -297.975116) (xy 157.333424 -297.988808)
			(xy 157.377886 -298.009906) (xy 157.418389 -298.037862) (xy 157.453882 -298.071954) (xy 157.483447 -298.111298)
			(xy 157.506318 -298.154875) (xy 157.521902 -298.201556) (xy 157.529797 -298.250133) (xy 157.530292 -298.27474)
			(xy 157.86914 -298.27474) (xy 157.8731 -298.225686) (xy 157.884877 -298.177902) (xy 157.904168 -298.132626)
			(xy 157.930471 -298.09103) (xy 157.963106 -298.054193) (xy 158.001227 -298.023068) (xy 158.043848 -297.998461)
			(xy 158.089864 -297.981009) (xy 158.138083 -297.971165) (xy 158.187258 -297.969184) (xy 158.236113 -297.975116)
			(xy 158.283384 -297.988808) (xy 158.327846 -298.009906) (xy 158.368349 -298.037862) (xy 158.403842 -298.071954)
			(xy 158.433407 -298.111298) (xy 158.456278 -298.154875) (xy 158.471862 -298.201556) (xy 158.479757 -298.250133)
			(xy 158.480252 -298.27474) (xy 159.76906 -298.27474) (xy 159.77302 -298.225686) (xy 159.784797 -298.177902)
			(xy 159.804088 -298.132626) (xy 159.830391 -298.09103) (xy 159.863026 -298.054193) (xy 159.901147 -298.023068)
			(xy 159.943768 -297.998461) (xy 159.989784 -297.981009) (xy 160.038003 -297.971165) (xy 160.087178 -297.969184)
			(xy 160.136033 -297.975116) (xy 160.183304 -297.988808) (xy 160.227766 -298.009906) (xy 160.268269 -298.037862)
			(xy 160.303762 -298.071954) (xy 160.333327 -298.111298) (xy 160.356198 -298.154875) (xy 160.371782 -298.201556)
			(xy 160.379677 -298.250133) (xy 160.380172 -298.27474) (xy 160.719274 -298.27474) (xy 160.723234 -298.225686)
			(xy 160.735011 -298.177902) (xy 160.754302 -298.132626) (xy 160.780605 -298.09103) (xy 160.81324 -298.054193)
			(xy 160.851361 -298.023068) (xy 160.893982 -297.998461) (xy 160.939998 -297.981009) (xy 160.988217 -297.971165)
			(xy 161.037392 -297.969184) (xy 161.086247 -297.975116) (xy 161.133518 -297.988808) (xy 161.17798 -298.009906)
			(xy 161.218483 -298.037862) (xy 161.253976 -298.071954) (xy 161.283541 -298.111298) (xy 161.306412 -298.154875)
			(xy 161.321996 -298.201556) (xy 161.329891 -298.250133) (xy 161.330386 -298.27474) (xy 161.669234 -298.27474)
			(xy 161.673194 -298.225686) (xy 161.684971 -298.177902) (xy 161.704262 -298.132626) (xy 161.730565 -298.09103)
			(xy 161.7632 -298.054193) (xy 161.801321 -298.023068) (xy 161.843942 -297.998461) (xy 161.889958 -297.981009)
			(xy 161.938177 -297.971165) (xy 161.987352 -297.969184) (xy 162.036207 -297.975116) (xy 162.083478 -297.988808)
			(xy 162.12794 -298.009906) (xy 162.168443 -298.037862) (xy 162.203936 -298.071954) (xy 162.233501 -298.111298)
			(xy 162.256372 -298.154875) (xy 162.271956 -298.201556) (xy 162.279851 -298.250133) (xy 162.280346 -298.27474)
			(xy 163.569154 -298.27474) (xy 163.573114 -298.225686) (xy 163.584891 -298.177902) (xy 163.604182 -298.132626)
			(xy 163.630485 -298.09103) (xy 163.66312 -298.054193) (xy 163.701241 -298.023068) (xy 163.743862 -297.998461)
			(xy 163.789878 -297.981009) (xy 163.838097 -297.971165) (xy 163.887272 -297.969184) (xy 163.936127 -297.975116)
			(xy 163.983398 -297.988808) (xy 164.02786 -298.009906) (xy 164.068363 -298.037862) (xy 164.103856 -298.071954)
			(xy 164.133421 -298.111298) (xy 164.156292 -298.154875) (xy 164.171876 -298.201556) (xy 164.179771 -298.250133)
			(xy 164.180266 -298.27474) (xy 164.519114 -298.27474) (xy 164.523074 -298.225686) (xy 164.534851 -298.177902)
			(xy 164.554142 -298.132626) (xy 164.580445 -298.09103) (xy 164.61308 -298.054193) (xy 164.651201 -298.023068)
			(xy 164.693822 -297.998461) (xy 164.739838 -297.981009) (xy 164.788057 -297.971165) (xy 164.837232 -297.969184)
			(xy 164.886087 -297.975116) (xy 164.933358 -297.988808) (xy 164.97782 -298.009906) (xy 165.018323 -298.037862)
			(xy 165.053816 -298.071954) (xy 165.083381 -298.111298) (xy 165.106252 -298.154875) (xy 165.121836 -298.201556)
			(xy 165.129731 -298.250133) (xy 165.130226 -298.27474) (xy 166.419288 -298.27474) (xy 166.423248 -298.225686)
			(xy 166.435025 -298.177902) (xy 166.454316 -298.132626) (xy 166.480619 -298.09103) (xy 166.513254 -298.054193)
			(xy 166.551375 -298.023068) (xy 166.593996 -297.998461) (xy 166.640012 -297.981009) (xy 166.688231 -297.971165)
			(xy 166.737406 -297.969184) (xy 166.786261 -297.975116) (xy 166.833532 -297.988808) (xy 166.877994 -298.009906)
			(xy 166.918497 -298.037862) (xy 166.95399 -298.071954) (xy 166.983555 -298.111298) (xy 167.006426 -298.154875)
			(xy 167.02201 -298.201556) (xy 167.029905 -298.250133) (xy 167.0304 -298.27474) (xy 168.319208 -298.27474)
			(xy 168.323168 -298.225686) (xy 168.334945 -298.177902) (xy 168.354236 -298.132626) (xy 168.380539 -298.09103)
			(xy 168.413174 -298.054193) (xy 168.451295 -298.023068) (xy 168.493916 -297.998461) (xy 168.539932 -297.981009)
			(xy 168.588151 -297.971165) (xy 168.637326 -297.969184) (xy 168.686181 -297.975116) (xy 168.733452 -297.988808)
			(xy 168.777914 -298.009906) (xy 168.818417 -298.037862) (xy 168.85391 -298.071954) (xy 168.883475 -298.111298)
			(xy 168.906346 -298.154875) (xy 168.92193 -298.201556) (xy 168.929825 -298.250133) (xy 168.93032 -298.27474)
			(xy 170.219128 -298.27474) (xy 170.223088 -298.225686) (xy 170.234865 -298.177902) (xy 170.254156 -298.132626)
			(xy 170.280459 -298.09103) (xy 170.313094 -298.054193) (xy 170.351215 -298.023068) (xy 170.393836 -297.998461)
			(xy 170.439852 -297.981009) (xy 170.488071 -297.971165) (xy 170.537246 -297.969184) (xy 170.586101 -297.975116)
			(xy 170.633372 -297.988808) (xy 170.677834 -298.009906) (xy 170.718337 -298.037862) (xy 170.75383 -298.071954)
			(xy 170.783395 -298.111298) (xy 170.806266 -298.154875) (xy 170.82185 -298.201556) (xy 170.829745 -298.250133)
			(xy 170.83024 -298.27474) (xy 172.119048 -298.27474) (xy 172.123008 -298.225686) (xy 172.134785 -298.177902)
			(xy 172.154076 -298.132626) (xy 172.180379 -298.09103) (xy 172.213014 -298.054193) (xy 172.251135 -298.023068)
			(xy 172.293756 -297.998461) (xy 172.339772 -297.981009) (xy 172.387991 -297.971165) (xy 172.437166 -297.969184)
			(xy 172.486021 -297.975116) (xy 172.533292 -297.988808) (xy 172.577754 -298.009906) (xy 172.618257 -298.037862)
			(xy 172.65375 -298.071954) (xy 172.683315 -298.111298) (xy 172.706186 -298.154875) (xy 172.72177 -298.201556)
			(xy 172.729665 -298.250133) (xy 172.73016 -298.27474) (xy 174.019222 -298.27474) (xy 174.023182 -298.225686)
			(xy 174.034959 -298.177902) (xy 174.05425 -298.132626) (xy 174.080553 -298.09103) (xy 174.113188 -298.054193)
			(xy 174.151309 -298.023068) (xy 174.19393 -297.998461) (xy 174.239946 -297.981009) (xy 174.288165 -297.971165)
			(xy 174.33734 -297.969184) (xy 174.386195 -297.975116) (xy 174.433466 -297.988808) (xy 174.477928 -298.009906)
			(xy 174.518431 -298.037862) (xy 174.553924 -298.071954) (xy 174.583489 -298.111298) (xy 174.60636 -298.154875)
			(xy 174.621944 -298.201556) (xy 174.629839 -298.250133) (xy 174.630334 -298.27474) (xy 176.869102 -298.27474)
			(xy 176.873062 -298.225686) (xy 176.884839 -298.177902) (xy 176.90413 -298.132626) (xy 176.930433 -298.09103)
			(xy 176.963068 -298.054193) (xy 177.001189 -298.023068) (xy 177.04381 -297.998461) (xy 177.089826 -297.981009)
			(xy 177.138045 -297.971165) (xy 177.18722 -297.969184) (xy 177.236075 -297.975116) (xy 177.283346 -297.988808)
			(xy 177.327808 -298.009906) (xy 177.368311 -298.037862) (xy 177.403804 -298.071954) (xy 177.433369 -298.111298)
			(xy 177.45624 -298.154875) (xy 177.471824 -298.201556) (xy 177.479719 -298.250133) (xy 177.480214 -298.27474)
			(xy 178.769276 -298.27474) (xy 178.773236 -298.225686) (xy 178.785013 -298.177902) (xy 178.804304 -298.132626)
			(xy 178.830607 -298.09103) (xy 178.863242 -298.054193) (xy 178.901363 -298.023068) (xy 178.943984 -297.998461)
			(xy 178.99 -297.981009) (xy 179.038219 -297.971165) (xy 179.087394 -297.969184) (xy 179.136249 -297.975116)
			(xy 179.18352 -297.988808) (xy 179.227982 -298.009906) (xy 179.268485 -298.037862) (xy 179.303978 -298.071954)
			(xy 179.333543 -298.111298) (xy 179.356414 -298.154875) (xy 179.371998 -298.201556) (xy 179.379893 -298.250133)
			(xy 179.380388 -298.27474) (xy 180.669196 -298.27474) (xy 180.673156 -298.225686) (xy 180.684933 -298.177902)
			(xy 180.704224 -298.132626) (xy 180.730527 -298.09103) (xy 180.763162 -298.054193) (xy 180.801283 -298.023068)
			(xy 180.843904 -297.998461) (xy 180.88992 -297.981009) (xy 180.938139 -297.971165) (xy 180.987314 -297.969184)
			(xy 181.036169 -297.975116) (xy 181.08344 -297.988808) (xy 181.127902 -298.009906) (xy 181.168405 -298.037862)
			(xy 181.203898 -298.071954) (xy 181.233463 -298.111298) (xy 181.256334 -298.154875) (xy 181.271918 -298.201556)
			(xy 181.279813 -298.250133) (xy 181.280308 -298.27474) (xy 182.569116 -298.27474) (xy 182.573076 -298.225686)
			(xy 182.584853 -298.177902) (xy 182.604144 -298.132626) (xy 182.630447 -298.09103) (xy 182.663082 -298.054193)
			(xy 182.701203 -298.023068) (xy 182.743824 -297.998461) (xy 182.78984 -297.981009) (xy 182.838059 -297.971165)
			(xy 182.887234 -297.969184) (xy 182.936089 -297.975116) (xy 182.98336 -297.988808) (xy 183.027822 -298.009906)
			(xy 183.068325 -298.037862) (xy 183.103818 -298.071954) (xy 183.133383 -298.111298) (xy 183.156254 -298.154875)
			(xy 183.171838 -298.201556) (xy 183.179733 -298.250133) (xy 183.180228 -298.27474) (xy 184.469036 -298.27474)
			(xy 184.472996 -298.225686) (xy 184.484773 -298.177902) (xy 184.504064 -298.132626) (xy 184.530367 -298.09103)
			(xy 184.563002 -298.054193) (xy 184.601123 -298.023068) (xy 184.643744 -297.998461) (xy 184.68976 -297.981009)
			(xy 184.737979 -297.971165) (xy 184.787154 -297.969184) (xy 184.836009 -297.975116) (xy 184.88328 -297.988808)
			(xy 184.927742 -298.009906) (xy 184.968245 -298.037862) (xy 185.003738 -298.071954) (xy 185.033303 -298.111298)
			(xy 185.056174 -298.154875) (xy 185.071758 -298.201556) (xy 185.079653 -298.250133) (xy 185.080148 -298.27474)
			(xy 185.079653 -298.299347) (xy 185.071758 -298.347924) (xy 185.056174 -298.394605) (xy 185.033303 -298.438182)
			(xy 185.003738 -298.477526) (xy 184.968245 -298.511618) (xy 184.927742 -298.539574) (xy 184.88328 -298.560672)
			(xy 184.836009 -298.574364) (xy 184.787154 -298.580296) (xy 184.737979 -298.578315) (xy 184.68976 -298.568471)
			(xy 184.643744 -298.551019) (xy 184.601123 -298.526412) (xy 184.563002 -298.495287) (xy 184.530367 -298.45845)
			(xy 184.504064 -298.416854) (xy 184.484773 -298.371578) (xy 184.472996 -298.323794) (xy 184.469036 -298.27474)
			(xy 183.180228 -298.27474) (xy 183.179733 -298.299347) (xy 183.171838 -298.347924) (xy 183.156254 -298.394605)
			(xy 183.133383 -298.438182) (xy 183.103818 -298.477526) (xy 183.068325 -298.511618) (xy 183.027822 -298.539574)
			(xy 182.98336 -298.560672) (xy 182.936089 -298.574364) (xy 182.887234 -298.580296) (xy 182.838059 -298.578315)
			(xy 182.78984 -298.568471) (xy 182.743824 -298.551019) (xy 182.701203 -298.526412) (xy 182.663082 -298.495287)
			(xy 182.630447 -298.45845) (xy 182.604144 -298.416854) (xy 182.584853 -298.371578) (xy 182.573076 -298.323794)
			(xy 182.569116 -298.27474) (xy 181.280308 -298.27474) (xy 181.279813 -298.299347) (xy 181.271918 -298.347924)
			(xy 181.256334 -298.394605) (xy 181.233463 -298.438182) (xy 181.203898 -298.477526) (xy 181.168405 -298.511618)
			(xy 181.127902 -298.539574) (xy 181.08344 -298.560672) (xy 181.036169 -298.574364) (xy 180.987314 -298.580296)
			(xy 180.938139 -298.578315) (xy 180.88992 -298.568471) (xy 180.843904 -298.551019) (xy 180.801283 -298.526412)
			(xy 180.763162 -298.495287) (xy 180.730527 -298.45845) (xy 180.704224 -298.416854) (xy 180.684933 -298.371578)
			(xy 180.673156 -298.323794) (xy 180.669196 -298.27474) (xy 179.380388 -298.27474) (xy 179.379893 -298.299347)
			(xy 179.371998 -298.347924) (xy 179.356414 -298.394605) (xy 179.333543 -298.438182) (xy 179.303978 -298.477526)
			(xy 179.268485 -298.511618) (xy 179.227982 -298.539574) (xy 179.18352 -298.560672) (xy 179.136249 -298.574364)
			(xy 179.087394 -298.580296) (xy 179.038219 -298.578315) (xy 178.99 -298.568471) (xy 178.943984 -298.551019)
			(xy 178.901363 -298.526412) (xy 178.863242 -298.495287) (xy 178.830607 -298.45845) (xy 178.804304 -298.416854)
			(xy 178.785013 -298.371578) (xy 178.773236 -298.323794) (xy 178.769276 -298.27474) (xy 177.480214 -298.27474)
			(xy 177.479719 -298.299347) (xy 177.471824 -298.347924) (xy 177.45624 -298.394605) (xy 177.433369 -298.438182)
			(xy 177.403804 -298.477526) (xy 177.368311 -298.511618) (xy 177.327808 -298.539574) (xy 177.283346 -298.560672)
			(xy 177.236075 -298.574364) (xy 177.18722 -298.580296) (xy 177.138045 -298.578315) (xy 177.089826 -298.568471)
			(xy 177.04381 -298.551019) (xy 177.001189 -298.526412) (xy 176.963068 -298.495287) (xy 176.930433 -298.45845)
			(xy 176.90413 -298.416854) (xy 176.884839 -298.371578) (xy 176.873062 -298.323794) (xy 176.869102 -298.27474)
			(xy 174.630334 -298.27474) (xy 174.629839 -298.299347) (xy 174.621944 -298.347924) (xy 174.60636 -298.394605)
			(xy 174.583489 -298.438182) (xy 174.553924 -298.477526) (xy 174.518431 -298.511618) (xy 174.477928 -298.539574)
			(xy 174.433466 -298.560672) (xy 174.386195 -298.574364) (xy 174.33734 -298.580296) (xy 174.288165 -298.578315)
			(xy 174.239946 -298.568471) (xy 174.19393 -298.551019) (xy 174.151309 -298.526412) (xy 174.113188 -298.495287)
			(xy 174.080553 -298.45845) (xy 174.05425 -298.416854) (xy 174.034959 -298.371578) (xy 174.023182 -298.323794)
			(xy 174.019222 -298.27474) (xy 172.73016 -298.27474) (xy 172.729665 -298.299347) (xy 172.72177 -298.347924)
			(xy 172.706186 -298.394605) (xy 172.683315 -298.438182) (xy 172.65375 -298.477526) (xy 172.618257 -298.511618)
			(xy 172.577754 -298.539574) (xy 172.533292 -298.560672) (xy 172.486021 -298.574364) (xy 172.437166 -298.580296)
			(xy 172.387991 -298.578315) (xy 172.339772 -298.568471) (xy 172.293756 -298.551019) (xy 172.251135 -298.526412)
			(xy 172.213014 -298.495287) (xy 172.180379 -298.45845) (xy 172.154076 -298.416854) (xy 172.134785 -298.371578)
			(xy 172.123008 -298.323794) (xy 172.119048 -298.27474) (xy 170.83024 -298.27474) (xy 170.829745 -298.299347)
			(xy 170.82185 -298.347924) (xy 170.806266 -298.394605) (xy 170.783395 -298.438182) (xy 170.75383 -298.477526)
			(xy 170.718337 -298.511618) (xy 170.677834 -298.539574) (xy 170.633372 -298.560672) (xy 170.586101 -298.574364)
			(xy 170.537246 -298.580296) (xy 170.488071 -298.578315) (xy 170.439852 -298.568471) (xy 170.393836 -298.551019)
			(xy 170.351215 -298.526412) (xy 170.313094 -298.495287) (xy 170.280459 -298.45845) (xy 170.254156 -298.416854)
			(xy 170.234865 -298.371578) (xy 170.223088 -298.323794) (xy 170.219128 -298.27474) (xy 168.93032 -298.27474)
			(xy 168.929825 -298.299347) (xy 168.92193 -298.347924) (xy 168.906346 -298.394605) (xy 168.883475 -298.438182)
			(xy 168.85391 -298.477526) (xy 168.818417 -298.511618) (xy 168.777914 -298.539574) (xy 168.733452 -298.560672)
			(xy 168.686181 -298.574364) (xy 168.637326 -298.580296) (xy 168.588151 -298.578315) (xy 168.539932 -298.568471)
			(xy 168.493916 -298.551019) (xy 168.451295 -298.526412) (xy 168.413174 -298.495287) (xy 168.380539 -298.45845)
			(xy 168.354236 -298.416854) (xy 168.334945 -298.371578) (xy 168.323168 -298.323794) (xy 168.319208 -298.27474)
			(xy 167.0304 -298.27474) (xy 167.029905 -298.299347) (xy 167.02201 -298.347924) (xy 167.006426 -298.394605)
			(xy 166.983555 -298.438182) (xy 166.95399 -298.477526) (xy 166.918497 -298.511618) (xy 166.877994 -298.539574)
			(xy 166.833532 -298.560672) (xy 166.786261 -298.574364) (xy 166.737406 -298.580296) (xy 166.688231 -298.578315)
			(xy 166.640012 -298.568471) (xy 166.593996 -298.551019) (xy 166.551375 -298.526412) (xy 166.513254 -298.495287)
			(xy 166.480619 -298.45845) (xy 166.454316 -298.416854) (xy 166.435025 -298.371578) (xy 166.423248 -298.323794)
			(xy 166.419288 -298.27474) (xy 165.130226 -298.27474) (xy 165.129731 -298.299347) (xy 165.121836 -298.347924)
			(xy 165.106252 -298.394605) (xy 165.083381 -298.438182) (xy 165.053816 -298.477526) (xy 165.018323 -298.511618)
			(xy 164.97782 -298.539574) (xy 164.933358 -298.560672) (xy 164.886087 -298.574364) (xy 164.837232 -298.580296)
			(xy 164.788057 -298.578315) (xy 164.739838 -298.568471) (xy 164.693822 -298.551019) (xy 164.651201 -298.526412)
			(xy 164.61308 -298.495287) (xy 164.580445 -298.45845) (xy 164.554142 -298.416854) (xy 164.534851 -298.371578)
			(xy 164.523074 -298.323794) (xy 164.519114 -298.27474) (xy 164.180266 -298.27474) (xy 164.179771 -298.299347)
			(xy 164.171876 -298.347924) (xy 164.156292 -298.394605) (xy 164.133421 -298.438182) (xy 164.103856 -298.477526)
			(xy 164.068363 -298.511618) (xy 164.02786 -298.539574) (xy 163.983398 -298.560672) (xy 163.936127 -298.574364)
			(xy 163.887272 -298.580296) (xy 163.838097 -298.578315) (xy 163.789878 -298.568471) (xy 163.743862 -298.551019)
			(xy 163.701241 -298.526412) (xy 163.66312 -298.495287) (xy 163.630485 -298.45845) (xy 163.604182 -298.416854)
			(xy 163.584891 -298.371578) (xy 163.573114 -298.323794) (xy 163.569154 -298.27474) (xy 162.280346 -298.27474)
			(xy 162.279851 -298.299347) (xy 162.271956 -298.347924) (xy 162.256372 -298.394605) (xy 162.233501 -298.438182)
			(xy 162.203936 -298.477526) (xy 162.168443 -298.511618) (xy 162.12794 -298.539574) (xy 162.083478 -298.560672)
			(xy 162.036207 -298.574364) (xy 161.987352 -298.580296) (xy 161.938177 -298.578315) (xy 161.889958 -298.568471)
			(xy 161.843942 -298.551019) (xy 161.801321 -298.526412) (xy 161.7632 -298.495287) (xy 161.730565 -298.45845)
			(xy 161.704262 -298.416854) (xy 161.684971 -298.371578) (xy 161.673194 -298.323794) (xy 161.669234 -298.27474)
			(xy 161.330386 -298.27474) (xy 161.329891 -298.299347) (xy 161.321996 -298.347924) (xy 161.306412 -298.394605)
			(xy 161.283541 -298.438182) (xy 161.253976 -298.477526) (xy 161.218483 -298.511618) (xy 161.17798 -298.539574)
			(xy 161.133518 -298.560672) (xy 161.086247 -298.574364) (xy 161.037392 -298.580296) (xy 160.988217 -298.578315)
			(xy 160.939998 -298.568471) (xy 160.893982 -298.551019) (xy 160.851361 -298.526412) (xy 160.81324 -298.495287)
			(xy 160.780605 -298.45845) (xy 160.754302 -298.416854) (xy 160.735011 -298.371578) (xy 160.723234 -298.323794)
			(xy 160.719274 -298.27474) (xy 160.380172 -298.27474) (xy 160.379677 -298.299347) (xy 160.371782 -298.347924)
			(xy 160.356198 -298.394605) (xy 160.333327 -298.438182) (xy 160.303762 -298.477526) (xy 160.268269 -298.511618)
			(xy 160.227766 -298.539574) (xy 160.183304 -298.560672) (xy 160.136033 -298.574364) (xy 160.087178 -298.580296)
			(xy 160.038003 -298.578315) (xy 159.989784 -298.568471) (xy 159.943768 -298.551019) (xy 159.901147 -298.526412)
			(xy 159.863026 -298.495287) (xy 159.830391 -298.45845) (xy 159.804088 -298.416854) (xy 159.784797 -298.371578)
			(xy 159.77302 -298.323794) (xy 159.76906 -298.27474) (xy 158.480252 -298.27474) (xy 158.479757 -298.299347)
			(xy 158.471862 -298.347924) (xy 158.456278 -298.394605) (xy 158.433407 -298.438182) (xy 158.403842 -298.477526)
			(xy 158.368349 -298.511618) (xy 158.327846 -298.539574) (xy 158.283384 -298.560672) (xy 158.236113 -298.574364)
			(xy 158.187258 -298.580296) (xy 158.138083 -298.578315) (xy 158.089864 -298.568471) (xy 158.043848 -298.551019)
			(xy 158.001227 -298.526412) (xy 157.963106 -298.495287) (xy 157.930471 -298.45845) (xy 157.904168 -298.416854)
			(xy 157.884877 -298.371578) (xy 157.8731 -298.323794) (xy 157.86914 -298.27474) (xy 157.530292 -298.27474)
			(xy 157.529797 -298.299347) (xy 157.521902 -298.347924) (xy 157.506318 -298.394605) (xy 157.483447 -298.438182)
			(xy 157.453882 -298.477526) (xy 157.418389 -298.511618) (xy 157.377886 -298.539574) (xy 157.333424 -298.560672)
			(xy 157.286153 -298.574364) (xy 157.237298 -298.580296) (xy 157.188123 -298.578315) (xy 157.139904 -298.568471)
			(xy 157.093888 -298.551019) (xy 157.051267 -298.526412) (xy 157.013146 -298.495287) (xy 156.980511 -298.45845)
			(xy 156.954208 -298.416854) (xy 156.934917 -298.371578) (xy 156.92314 -298.323794) (xy 156.91918 -298.27474)
			(xy 156.580332 -298.27474) (xy 156.579837 -298.299347) (xy 156.571942 -298.347924) (xy 156.556358 -298.394605)
			(xy 156.533487 -298.438182) (xy 156.503922 -298.477526) (xy 156.468429 -298.511618) (xy 156.427926 -298.539574)
			(xy 156.383464 -298.560672) (xy 156.336193 -298.574364) (xy 156.287338 -298.580296) (xy 156.238163 -298.578315)
			(xy 156.189944 -298.568471) (xy 156.143928 -298.551019) (xy 156.101307 -298.526412) (xy 156.063186 -298.495287)
			(xy 156.030551 -298.45845) (xy 156.004248 -298.416854) (xy 155.984957 -298.371578) (xy 155.97318 -298.323794)
			(xy 155.96922 -298.27474) (xy 155.630372 -298.27474) (xy 155.629877 -298.299347) (xy 155.621982 -298.347924)
			(xy 155.606398 -298.394605) (xy 155.583527 -298.438182) (xy 155.553962 -298.477526) (xy 155.518469 -298.511618)
			(xy 155.477966 -298.539574) (xy 155.433504 -298.560672) (xy 155.386233 -298.574364) (xy 155.337378 -298.580296)
			(xy 155.288203 -298.578315) (xy 155.239984 -298.568471) (xy 155.193968 -298.551019) (xy 155.151347 -298.526412)
			(xy 155.113226 -298.495287) (xy 155.080591 -298.45845) (xy 155.054288 -298.416854) (xy 155.034997 -298.371578)
			(xy 155.02322 -298.323794) (xy 155.01926 -298.27474) (xy 154.680158 -298.27474) (xy 154.679663 -298.299347)
			(xy 154.671768 -298.347924) (xy 154.656184 -298.394605) (xy 154.633313 -298.438182) (xy 154.603748 -298.477526)
			(xy 154.568255 -298.511618) (xy 154.527752 -298.539574) (xy 154.48329 -298.560672) (xy 154.436019 -298.574364)
			(xy 154.387164 -298.580296) (xy 154.337989 -298.578315) (xy 154.28977 -298.568471) (xy 154.243754 -298.551019)
			(xy 154.201133 -298.526412) (xy 154.163012 -298.495287) (xy 154.130377 -298.45845) (xy 154.104074 -298.416854)
			(xy 154.084783 -298.371578) (xy 154.073006 -298.323794) (xy 154.069046 -298.27474) (xy 153.729944 -298.27474)
			(xy 153.729449 -298.299347) (xy 153.721554 -298.347924) (xy 153.70597 -298.394605) (xy 153.683099 -298.438182)
			(xy 153.653534 -298.477526) (xy 153.618041 -298.511618) (xy 153.577538 -298.539574) (xy 153.533076 -298.560672)
			(xy 153.485805 -298.574364) (xy 153.43695 -298.580296) (xy 153.387775 -298.578315) (xy 153.339556 -298.568471)
			(xy 153.29354 -298.551019) (xy 153.250919 -298.526412) (xy 153.212798 -298.495287) (xy 153.180163 -298.45845)
			(xy 153.15386 -298.416854) (xy 153.134569 -298.371578) (xy 153.122792 -298.323794) (xy 153.118832 -298.27474)
			(xy 118.832884 -298.27474) (xy 118.832884 -299.133514) (xy 141.911576 -299.133514) (xy 141.915647 -299.077892)
			(xy 141.927773 -299.023455) (xy 141.947696 -298.971364) (xy 141.974992 -298.922729) (xy 142.009078 -298.878586)
			(xy 142.049227 -298.839877) (xy 142.094585 -298.807426) (xy 142.144185 -298.781925) (xy 142.196969 -298.763918)
			(xy 142.251812 -298.753788) (xy 142.307546 -298.751751) (xy 142.362983 -298.757851) (xy 142.41694 -298.771957)
			(xy 142.468269 -298.793769) (xy 142.515875 -298.822823) (xy 142.558743 -298.858498) (xy 142.59596 -298.900035)
			(xy 142.626733 -298.946548) (xy 142.650405 -298.997045) (xy 142.666473 -299.050452) (xy 142.674593 -299.105628)
			(xy 142.675102 -299.133514) (xy 143.387062 -299.133514) (xy 143.391133 -299.077892) (xy 143.403259 -299.023455)
			(xy 143.423182 -298.971364) (xy 143.450478 -298.922729) (xy 143.484564 -298.878586) (xy 143.524713 -298.839877)
			(xy 143.570071 -298.807426) (xy 143.619671 -298.781925) (xy 143.672455 -298.763918) (xy 143.727298 -298.753788)
			(xy 143.783032 -298.751751) (xy 143.838469 -298.757851) (xy 143.892426 -298.771957) (xy 143.943755 -298.793769)
			(xy 143.991361 -298.822823) (xy 144.034229 -298.858498) (xy 144.071446 -298.900035) (xy 144.102219 -298.946548)
			(xy 144.125891 -298.997045) (xy 144.141959 -299.050452) (xy 144.150079 -299.105628) (xy 144.150588 -299.133514)
			(xy 144.276062 -299.133514) (xy 144.280133 -299.077892) (xy 144.292259 -299.023455) (xy 144.312182 -298.971364)
			(xy 144.339478 -298.922729) (xy 144.373564 -298.878586) (xy 144.413713 -298.839877) (xy 144.459071 -298.807426)
			(xy 144.508671 -298.781925) (xy 144.561455 -298.763918) (xy 144.616298 -298.753788) (xy 144.672032 -298.751751)
			(xy 144.727469 -298.757851) (xy 144.781426 -298.771957) (xy 144.832755 -298.793769) (xy 144.880361 -298.822823)
			(xy 144.923229 -298.858498) (xy 144.960446 -298.900035) (xy 144.991219 -298.946548) (xy 145.014891 -298.997045)
			(xy 145.030959 -299.050452) (xy 145.039079 -299.105628) (xy 145.039588 -299.133514) (xy 145.039079 -299.1614)
			(xy 145.030959 -299.216576) (xy 145.014891 -299.269983) (xy 144.991219 -299.32048) (xy 144.960446 -299.366993)
			(xy 144.923229 -299.40853) (xy 144.880361 -299.444205) (xy 144.832755 -299.473259) (xy 144.781426 -299.495071)
			(xy 144.727469 -299.509177) (xy 144.672032 -299.515277) (xy 144.616298 -299.51324) (xy 144.561455 -299.50311)
			(xy 144.508671 -299.485103) (xy 144.459071 -299.459602) (xy 144.413713 -299.427151) (xy 144.373564 -299.388442)
			(xy 144.339478 -299.344299) (xy 144.312182 -299.295664) (xy 144.292259 -299.243573) (xy 144.280133 -299.189136)
			(xy 144.276062 -299.133514) (xy 144.150588 -299.133514) (xy 144.150079 -299.1614) (xy 144.141959 -299.216576)
			(xy 144.125891 -299.269983) (xy 144.102219 -299.32048) (xy 144.071446 -299.366993) (xy 144.034229 -299.40853)
			(xy 143.991361 -299.444205) (xy 143.943755 -299.473259) (xy 143.892426 -299.495071) (xy 143.838469 -299.509177)
			(xy 143.783032 -299.515277) (xy 143.727298 -299.51324) (xy 143.672455 -299.50311) (xy 143.619671 -299.485103)
			(xy 143.570071 -299.459602) (xy 143.524713 -299.427151) (xy 143.484564 -299.388442) (xy 143.450478 -299.344299)
			(xy 143.423182 -299.295664) (xy 143.403259 -299.243573) (xy 143.391133 -299.189136) (xy 143.387062 -299.133514)
			(xy 142.675102 -299.133514) (xy 142.674593 -299.1614) (xy 142.666473 -299.216576) (xy 142.650405 -299.269983)
			(xy 142.626733 -299.32048) (xy 142.59596 -299.366993) (xy 142.558743 -299.40853) (xy 142.515875 -299.444205)
			(xy 142.468269 -299.473259) (xy 142.41694 -299.495071) (xy 142.362983 -299.509177) (xy 142.307546 -299.515277)
			(xy 142.251812 -299.51324) (xy 142.196969 -299.50311) (xy 142.144185 -299.485103) (xy 142.094585 -299.459602)
			(xy 142.049227 -299.427151) (xy 142.009078 -299.388442) (xy 141.974992 -299.344299) (xy 141.947696 -299.295664)
			(xy 141.927773 -299.243573) (xy 141.915647 -299.189136) (xy 141.911576 -299.133514) (xy 118.832884 -299.133514)
			(xy 118.832884 -299.895514) (xy 147.43811 -299.895514) (xy 147.438654 -299.866132) (xy 147.447683 -299.808065)
			(xy 147.465514 -299.752071) (xy 147.491725 -299.699475) (xy 147.525695 -299.651524) (xy 147.56662 -299.609352)
			(xy 147.589748 -299.591222) (xy 147.599146 -299.583856) (xy 147.60956 -299.563282) (xy 147.611084 -299.459396)
			(xy 147.601178 -299.438314) (xy 147.592034 -299.430948) (xy 147.570186 -299.412742) (xy 147.531644 -299.370924)
			(xy 147.499736 -299.323849) (xy 147.475169 -299.272559) (xy 147.458486 -299.218191) (xy 147.450058 -299.161949)
			(xy 147.44954 -299.133514) (xy 147.450026 -299.106263) (xy 147.457782 -299.052315) (xy 147.473137 -299.00002)
			(xy 147.495779 -298.950443) (xy 147.525245 -298.904593) (xy 147.560936 -298.863402) (xy 147.602127 -298.827711)
			(xy 147.647977 -298.798245) (xy 147.697554 -298.775603) (xy 147.749849 -298.760248) (xy 147.803797 -298.752492)
			(xy 147.858299 -298.752492) (xy 147.912247 -298.760248) (xy 147.964542 -298.775603) (xy 148.014119 -298.798245)
			(xy 148.059969 -298.827711) (xy 148.10116 -298.863402) (xy 148.136851 -298.904593) (xy 148.166317 -298.950443)
			(xy 148.188959 -299.00002) (xy 148.204314 -299.052315) (xy 148.21207 -299.106263) (xy 148.212556 -299.133514)
			(xy 148.212006 -299.162896) (xy 148.202975 -299.220961) (xy 148.201784 -299.2247) (xy 151.53404 -299.2247)
			(xy 151.538212 -299.174354) (xy 151.550614 -299.125381) (xy 151.570909 -299.079118) (xy 151.598541 -299.036827)
			(xy 151.632758 -298.999661) (xy 151.672626 -298.968634) (xy 151.717058 -298.944593) (xy 151.76484 -298.928193)
			(xy 151.814671 -298.919882) (xy 151.83993 -298.919392) (xy 151.865325 -298.919926) (xy 151.915413 -298.928333)
			(xy 151.96342 -298.944912) (xy 152.008023 -298.969204) (xy 152.047993 -299.000541) (xy 152.065482 -299.01896)
			(xy 152.073102 -299.027342) (xy 152.093168 -299.035724) (xy 152.192482 -299.033184) (xy 152.211786 -299.023786)
			(xy 152.219152 -299.014896) (xy 152.234926 -298.996339) (xy 152.271023 -298.963642) (xy 152.311522 -298.936588)
			(xy 152.355548 -298.915761) (xy 152.402151 -298.90161) (xy 152.450324 -298.89444) (xy 152.474676 -298.893992)
			(xy 153.424636 -298.893992) (xy 153.450638 -298.894597) (xy 153.502 -298.902737) (xy 153.551457 -298.918811)
			(xy 153.59779 -298.942424) (xy 153.63986 -298.972993) (xy 153.67663 -299.009767) (xy 153.707195 -299.05184)
			(xy 153.730803 -299.098177) (xy 153.746871 -299.147635) (xy 153.755006 -299.198998) (xy 153.755006 -299.224954)
			(xy 154.069046 -299.224954) (xy 154.073006 -299.1759) (xy 154.084783 -299.128116) (xy 154.104074 -299.08284)
			(xy 154.130377 -299.041244) (xy 154.163012 -299.004407) (xy 154.201133 -298.973282) (xy 154.243754 -298.948675)
			(xy 154.28977 -298.931223) (xy 154.337989 -298.921379) (xy 154.387164 -298.919398) (xy 154.436019 -298.92533)
			(xy 154.48329 -298.939022) (xy 154.527752 -298.96012) (xy 154.568255 -298.988076) (xy 154.603748 -299.022168)
			(xy 154.633313 -299.061512) (xy 154.656184 -299.105089) (xy 154.671768 -299.15177) (xy 154.679663 -299.200347)
			(xy 154.680158 -299.224954) (xy 154.679663 -299.249561) (xy 154.679428 -299.251009) (xy 154.994602 -299.251009)
			(xy 154.994602 -299.198991) (xy 155.002739 -299.147613) (xy 155.018812 -299.098141) (xy 155.042426 -299.051792)
			(xy 155.073 -299.009707) (xy 155.10978 -298.972923) (xy 155.151861 -298.942345) (xy 155.198208 -298.918726)
			(xy 155.247678 -298.902647) (xy 155.299055 -298.894505) (xy 155.325064 -298.893992) (xy 156.275024 -298.893992)
			(xy 156.301026 -298.894596) (xy 156.35239 -298.902735) (xy 156.401848 -298.918808) (xy 156.448184 -298.94242)
			(xy 156.490255 -298.972989) (xy 156.527026 -299.009763) (xy 156.557593 -299.051837) (xy 156.581201 -299.098174)
			(xy 156.597271 -299.147633) (xy 156.605406 -299.198998) (xy 156.605406 -299.224954) (xy 156.91918 -299.224954)
			(xy 156.92314 -299.1759) (xy 156.934917 -299.128116) (xy 156.954208 -299.08284) (xy 156.980511 -299.041244)
			(xy 157.013146 -299.004407) (xy 157.051267 -298.973282) (xy 157.093888 -298.948675) (xy 157.139904 -298.931223)
			(xy 157.188123 -298.921379) (xy 157.237298 -298.919398) (xy 157.286153 -298.92533) (xy 157.333424 -298.939022)
			(xy 157.377886 -298.96012) (xy 157.418389 -298.988076) (xy 157.453882 -299.022168) (xy 157.483447 -299.061512)
			(xy 157.506318 -299.105089) (xy 157.521902 -299.15177) (xy 157.529797 -299.200347) (xy 157.530287 -299.2247)
			(xy 157.86914 -299.2247) (xy 157.8731 -299.175646) (xy 157.884877 -299.127862) (xy 157.904168 -299.082586)
			(xy 157.930471 -299.04099) (xy 157.963106 -299.004153) (xy 158.001227 -298.973028) (xy 158.043848 -298.948421)
			(xy 158.089864 -298.930969) (xy 158.138083 -298.921125) (xy 158.187258 -298.919144) (xy 158.236113 -298.925076)
			(xy 158.283384 -298.938768) (xy 158.327846 -298.959866) (xy 158.368349 -298.987822) (xy 158.403842 -299.021914)
			(xy 158.433407 -299.061258) (xy 158.456278 -299.104835) (xy 158.471862 -299.151516) (xy 158.479757 -299.200093)
			(xy 158.480252 -299.2247) (xy 158.480247 -299.224954) (xy 159.76906 -299.224954) (xy 159.77302 -299.1759)
			(xy 159.784797 -299.128116) (xy 159.804088 -299.08284) (xy 159.830391 -299.041244) (xy 159.863026 -299.004407)
			(xy 159.901147 -298.973282) (xy 159.943768 -298.948675) (xy 159.989784 -298.931223) (xy 160.038003 -298.921379)
			(xy 160.087178 -298.919398) (xy 160.136033 -298.92533) (xy 160.183304 -298.939022) (xy 160.227766 -298.96012)
			(xy 160.268269 -298.988076) (xy 160.303762 -299.022168) (xy 160.333327 -299.061512) (xy 160.356198 -299.105089)
			(xy 160.371782 -299.15177) (xy 160.379677 -299.200347) (xy 160.380172 -299.224954) (xy 160.719274 -299.224954)
			(xy 160.723234 -299.1759) (xy 160.735011 -299.128116) (xy 160.754302 -299.08284) (xy 160.780605 -299.041244)
			(xy 160.81324 -299.004407) (xy 160.851361 -298.973282) (xy 160.893982 -298.948675) (xy 160.939998 -298.931223)
			(xy 160.988217 -298.921379) (xy 161.037392 -298.919398) (xy 161.086247 -298.92533) (xy 161.133518 -298.939022)
			(xy 161.17798 -298.96012) (xy 161.218483 -298.988076) (xy 161.253976 -299.022168) (xy 161.283541 -299.061512)
			(xy 161.306412 -299.105089) (xy 161.321996 -299.15177) (xy 161.329891 -299.200347) (xy 161.330386 -299.224954)
			(xy 161.669234 -299.224954) (xy 161.673194 -299.1759) (xy 161.684971 -299.128116) (xy 161.704262 -299.08284)
			(xy 161.730565 -299.041244) (xy 161.7632 -299.004407) (xy 161.801321 -298.973282) (xy 161.843942 -298.948675)
			(xy 161.889958 -298.931223) (xy 161.938177 -298.921379) (xy 161.987352 -298.919398) (xy 162.036207 -298.92533)
			(xy 162.083478 -298.939022) (xy 162.12794 -298.96012) (xy 162.168443 -298.988076) (xy 162.203936 -299.022168)
			(xy 162.233501 -299.061512) (xy 162.256372 -299.105089) (xy 162.271956 -299.15177) (xy 162.279851 -299.200347)
			(xy 162.280346 -299.224954) (xy 162.619194 -299.224954) (xy 162.623154 -299.1759) (xy 162.634931 -299.128116)
			(xy 162.654222 -299.08284) (xy 162.680525 -299.041244) (xy 162.71316 -299.004407) (xy 162.751281 -298.973282)
			(xy 162.793902 -298.948675) (xy 162.839918 -298.931223) (xy 162.888137 -298.921379) (xy 162.937312 -298.919398)
			(xy 162.986167 -298.92533) (xy 163.033438 -298.939022) (xy 163.0779 -298.96012) (xy 163.118403 -298.988076)
			(xy 163.153896 -299.022168) (xy 163.183461 -299.061512) (xy 163.206332 -299.105089) (xy 163.221916 -299.15177)
			(xy 163.229811 -299.200347) (xy 163.230306 -299.224954) (xy 163.569154 -299.224954) (xy 163.573114 -299.1759)
			(xy 163.584891 -299.128116) (xy 163.604182 -299.08284) (xy 163.630485 -299.041244) (xy 163.66312 -299.004407)
			(xy 163.701241 -298.973282) (xy 163.743862 -298.948675) (xy 163.789878 -298.931223) (xy 163.838097 -298.921379)
			(xy 163.887272 -298.919398) (xy 163.936127 -298.92533) (xy 163.983398 -298.939022) (xy 164.02786 -298.96012)
			(xy 164.068363 -298.988076) (xy 164.103856 -299.022168) (xy 164.133421 -299.061512) (xy 164.156292 -299.105089)
			(xy 164.171876 -299.15177) (xy 164.179771 -299.200347) (xy 164.180266 -299.224954) (xy 165.469074 -299.224954)
			(xy 165.473034 -299.1759) (xy 165.484811 -299.128116) (xy 165.504102 -299.08284) (xy 165.530405 -299.041244)
			(xy 165.56304 -299.004407) (xy 165.601161 -298.973282) (xy 165.643782 -298.948675) (xy 165.689798 -298.931223)
			(xy 165.738017 -298.921379) (xy 165.787192 -298.919398) (xy 165.836047 -298.92533) (xy 165.883318 -298.939022)
			(xy 165.92778 -298.96012) (xy 165.968283 -298.988076) (xy 166.003776 -299.022168) (xy 166.033341 -299.061512)
			(xy 166.056212 -299.105089) (xy 166.071796 -299.15177) (xy 166.079691 -299.200347) (xy 166.080186 -299.224954)
			(xy 166.419288 -299.224954) (xy 166.423248 -299.1759) (xy 166.435025 -299.128116) (xy 166.454316 -299.08284)
			(xy 166.480619 -299.041244) (xy 166.513254 -299.004407) (xy 166.551375 -298.973282) (xy 166.593996 -298.948675)
			(xy 166.640012 -298.931223) (xy 166.688231 -298.921379) (xy 166.737406 -298.919398) (xy 166.786261 -298.92533)
			(xy 166.833532 -298.939022) (xy 166.877994 -298.96012) (xy 166.918497 -298.988076) (xy 166.95399 -299.022168)
			(xy 166.983555 -299.061512) (xy 167.006426 -299.105089) (xy 167.02201 -299.15177) (xy 167.029905 -299.200347)
			(xy 167.0304 -299.224954) (xy 167.369248 -299.224954) (xy 167.373208 -299.1759) (xy 167.384985 -299.128116)
			(xy 167.404276 -299.08284) (xy 167.430579 -299.041244) (xy 167.463214 -299.004407) (xy 167.501335 -298.973282)
			(xy 167.543956 -298.948675) (xy 167.589972 -298.931223) (xy 167.638191 -298.921379) (xy 167.687366 -298.919398)
			(xy 167.736221 -298.92533) (xy 167.783492 -298.939022) (xy 167.827954 -298.96012) (xy 167.868457 -298.988076)
			(xy 167.90395 -299.022168) (xy 167.933515 -299.061512) (xy 167.956386 -299.105089) (xy 167.97197 -299.15177)
			(xy 167.979865 -299.200347) (xy 167.98036 -299.224954) (xy 168.319208 -299.224954) (xy 168.323168 -299.1759)
			(xy 168.334945 -299.128116) (xy 168.354236 -299.08284) (xy 168.380539 -299.041244) (xy 168.413174 -299.004407)
			(xy 168.451295 -298.973282) (xy 168.493916 -298.948675) (xy 168.539932 -298.931223) (xy 168.588151 -298.921379)
			(xy 168.637326 -298.919398) (xy 168.686181 -298.92533) (xy 168.733452 -298.939022) (xy 168.777914 -298.96012)
			(xy 168.818417 -298.988076) (xy 168.85391 -299.022168) (xy 168.883475 -299.061512) (xy 168.906346 -299.105089)
			(xy 168.92193 -299.15177) (xy 168.929825 -299.200347) (xy 168.93032 -299.224954) (xy 169.269168 -299.224954)
			(xy 169.273128 -299.1759) (xy 169.284905 -299.128116) (xy 169.304196 -299.08284) (xy 169.330499 -299.041244)
			(xy 169.363134 -299.004407) (xy 169.401255 -298.973282) (xy 169.443876 -298.948675) (xy 169.489892 -298.931223)
			(xy 169.538111 -298.921379) (xy 169.587286 -298.919398) (xy 169.636141 -298.92533) (xy 169.683412 -298.939022)
			(xy 169.727874 -298.96012) (xy 169.768377 -298.988076) (xy 169.80387 -299.022168) (xy 169.833435 -299.061512)
			(xy 169.856306 -299.105089) (xy 169.87189 -299.15177) (xy 169.879785 -299.200347) (xy 169.88028 -299.224954)
			(xy 170.219128 -299.224954) (xy 170.223088 -299.1759) (xy 170.234865 -299.128116) (xy 170.254156 -299.08284)
			(xy 170.280459 -299.041244) (xy 170.313094 -299.004407) (xy 170.351215 -298.973282) (xy 170.393836 -298.948675)
			(xy 170.439852 -298.931223) (xy 170.488071 -298.921379) (xy 170.537246 -298.919398) (xy 170.586101 -298.92533)
			(xy 170.633372 -298.939022) (xy 170.677834 -298.96012) (xy 170.718337 -298.988076) (xy 170.75383 -299.022168)
			(xy 170.783395 -299.061512) (xy 170.806266 -299.105089) (xy 170.82185 -299.15177) (xy 170.829745 -299.200347)
			(xy 170.83024 -299.224954) (xy 171.169088 -299.224954) (xy 171.173048 -299.1759) (xy 171.184825 -299.128116)
			(xy 171.204116 -299.08284) (xy 171.230419 -299.041244) (xy 171.263054 -299.004407) (xy 171.301175 -298.973282)
			(xy 171.343796 -298.948675) (xy 171.389812 -298.931223) (xy 171.438031 -298.921379) (xy 171.487206 -298.919398)
			(xy 171.536061 -298.92533) (xy 171.583332 -298.939022) (xy 171.627794 -298.96012) (xy 171.668297 -298.988076)
			(xy 171.70379 -299.022168) (xy 171.733355 -299.061512) (xy 171.756226 -299.105089) (xy 171.77181 -299.15177)
			(xy 171.779705 -299.200347) (xy 171.7802 -299.224954) (xy 172.119048 -299.224954) (xy 172.123008 -299.1759)
			(xy 172.134785 -299.128116) (xy 172.154076 -299.08284) (xy 172.180379 -299.041244) (xy 172.213014 -299.004407)
			(xy 172.251135 -298.973282) (xy 172.293756 -298.948675) (xy 172.339772 -298.931223) (xy 172.387991 -298.921379)
			(xy 172.437166 -298.919398) (xy 172.486021 -298.92533) (xy 172.533292 -298.939022) (xy 172.577754 -298.96012)
			(xy 172.618257 -298.988076) (xy 172.65375 -299.022168) (xy 172.683315 -299.061512) (xy 172.706186 -299.105089)
			(xy 172.72177 -299.15177) (xy 172.729665 -299.200347) (xy 172.73016 -299.224954) (xy 173.069262 -299.224954)
			(xy 173.073222 -299.1759) (xy 173.084999 -299.128116) (xy 173.10429 -299.08284) (xy 173.130593 -299.041244)
			(xy 173.163228 -299.004407) (xy 173.201349 -298.973282) (xy 173.24397 -298.948675) (xy 173.289986 -298.931223)
			(xy 173.338205 -298.921379) (xy 173.38738 -298.919398) (xy 173.436235 -298.92533) (xy 173.483506 -298.939022)
			(xy 173.527968 -298.96012) (xy 173.568471 -298.988076) (xy 173.603964 -299.022168) (xy 173.633529 -299.061512)
			(xy 173.6564 -299.105089) (xy 173.671984 -299.15177) (xy 173.679879 -299.200347) (xy 173.680374 -299.224954)
			(xy 174.019222 -299.224954) (xy 174.023182 -299.1759) (xy 174.034959 -299.128116) (xy 174.05425 -299.08284)
			(xy 174.080553 -299.041244) (xy 174.113188 -299.004407) (xy 174.151309 -298.973282) (xy 174.19393 -298.948675)
			(xy 174.239946 -298.931223) (xy 174.288165 -298.921379) (xy 174.33734 -298.919398) (xy 174.386195 -298.92533)
			(xy 174.433466 -298.939022) (xy 174.477928 -298.96012) (xy 174.518431 -298.988076) (xy 174.553924 -299.022168)
			(xy 174.583489 -299.061512) (xy 174.60636 -299.105089) (xy 174.621944 -299.15177) (xy 174.629839 -299.200347)
			(xy 174.630334 -299.224954) (xy 175.919142 -299.224954) (xy 175.923102 -299.1759) (xy 175.934879 -299.128116)
			(xy 175.95417 -299.08284) (xy 175.980473 -299.041244) (xy 176.013108 -299.004407) (xy 176.051229 -298.973282)
			(xy 176.09385 -298.948675) (xy 176.139866 -298.931223) (xy 176.188085 -298.921379) (xy 176.23726 -298.919398)
			(xy 176.286115 -298.92533) (xy 176.333386 -298.939022) (xy 176.377848 -298.96012) (xy 176.418351 -298.988076)
			(xy 176.453844 -299.022168) (xy 176.483409 -299.061512) (xy 176.50628 -299.105089) (xy 176.521864 -299.15177)
			(xy 176.529759 -299.200347) (xy 176.530254 -299.224954) (xy 176.869102 -299.224954) (xy 176.873062 -299.1759)
			(xy 176.884839 -299.128116) (xy 176.90413 -299.08284) (xy 176.930433 -299.041244) (xy 176.963068 -299.004407)
			(xy 177.001189 -298.973282) (xy 177.04381 -298.948675) (xy 177.089826 -298.931223) (xy 177.138045 -298.921379)
			(xy 177.18722 -298.919398) (xy 177.236075 -298.92533) (xy 177.283346 -298.939022) (xy 177.327808 -298.96012)
			(xy 177.368311 -298.988076) (xy 177.403804 -299.022168) (xy 177.433369 -299.061512) (xy 177.45624 -299.105089)
			(xy 177.471824 -299.15177) (xy 177.479719 -299.200347) (xy 177.480214 -299.224954) (xy 177.819062 -299.224954)
			(xy 177.823022 -299.1759) (xy 177.834799 -299.128116) (xy 177.85409 -299.08284) (xy 177.880393 -299.041244)
			(xy 177.913028 -299.004407) (xy 177.951149 -298.973282) (xy 177.99377 -298.948675) (xy 178.039786 -298.931223)
			(xy 178.088005 -298.921379) (xy 178.13718 -298.919398) (xy 178.186035 -298.92533) (xy 178.233306 -298.939022)
			(xy 178.277768 -298.96012) (xy 178.318271 -298.988076) (xy 178.353764 -299.022168) (xy 178.383329 -299.061512)
			(xy 178.4062 -299.105089) (xy 178.421784 -299.15177) (xy 178.429679 -299.200347) (xy 178.430174 -299.224954)
			(xy 178.769276 -299.224954) (xy 178.773236 -299.1759) (xy 178.785013 -299.128116) (xy 178.804304 -299.08284)
			(xy 178.830607 -299.041244) (xy 178.863242 -299.004407) (xy 178.901363 -298.973282) (xy 178.943984 -298.948675)
			(xy 178.99 -298.931223) (xy 179.038219 -298.921379) (xy 179.087394 -298.919398) (xy 179.136249 -298.92533)
			(xy 179.18352 -298.939022) (xy 179.227982 -298.96012) (xy 179.268485 -298.988076) (xy 179.303978 -299.022168)
			(xy 179.333543 -299.061512) (xy 179.356414 -299.105089) (xy 179.371998 -299.15177) (xy 179.379893 -299.200347)
			(xy 179.380388 -299.224954) (xy 179.719236 -299.224954) (xy 179.723196 -299.1759) (xy 179.734973 -299.128116)
			(xy 179.754264 -299.08284) (xy 179.780567 -299.041244) (xy 179.813202 -299.004407) (xy 179.851323 -298.973282)
			(xy 179.893944 -298.948675) (xy 179.93996 -298.931223) (xy 179.988179 -298.921379) (xy 180.037354 -298.919398)
			(xy 180.086209 -298.92533) (xy 180.13348 -298.939022) (xy 180.177942 -298.96012) (xy 180.218445 -298.988076)
			(xy 180.253938 -299.022168) (xy 180.283503 -299.061512) (xy 180.306374 -299.105089) (xy 180.321958 -299.15177)
			(xy 180.329853 -299.200347) (xy 180.330348 -299.224954) (xy 180.669196 -299.224954) (xy 180.673156 -299.1759)
			(xy 180.684933 -299.128116) (xy 180.704224 -299.08284) (xy 180.730527 -299.041244) (xy 180.763162 -299.004407)
			(xy 180.801283 -298.973282) (xy 180.843904 -298.948675) (xy 180.88992 -298.931223) (xy 180.938139 -298.921379)
			(xy 180.987314 -298.919398) (xy 181.036169 -298.92533) (xy 181.08344 -298.939022) (xy 181.127902 -298.96012)
			(xy 181.168405 -298.988076) (xy 181.203898 -299.022168) (xy 181.233463 -299.061512) (xy 181.256334 -299.105089)
			(xy 181.271918 -299.15177) (xy 181.279813 -299.200347) (xy 181.280308 -299.224954) (xy 181.619156 -299.224954)
			(xy 181.623116 -299.1759) (xy 181.634893 -299.128116) (xy 181.654184 -299.08284) (xy 181.680487 -299.041244)
			(xy 181.713122 -299.004407) (xy 181.751243 -298.973282) (xy 181.793864 -298.948675) (xy 181.83988 -298.931223)
			(xy 181.888099 -298.921379) (xy 181.937274 -298.919398) (xy 181.986129 -298.92533) (xy 182.0334 -298.939022)
			(xy 182.077862 -298.96012) (xy 182.118365 -298.988076) (xy 182.153858 -299.022168) (xy 182.183423 -299.061512)
			(xy 182.206294 -299.105089) (xy 182.221878 -299.15177) (xy 182.229773 -299.200347) (xy 182.230268 -299.224954)
			(xy 182.569116 -299.224954) (xy 182.573076 -299.1759) (xy 182.584853 -299.128116) (xy 182.604144 -299.08284)
			(xy 182.630447 -299.041244) (xy 182.663082 -299.004407) (xy 182.701203 -298.973282) (xy 182.743824 -298.948675)
			(xy 182.78984 -298.931223) (xy 182.838059 -298.921379) (xy 182.887234 -298.919398) (xy 182.936089 -298.92533)
			(xy 182.98336 -298.939022) (xy 183.027822 -298.96012) (xy 183.068325 -298.988076) (xy 183.103818 -299.022168)
			(xy 183.133383 -299.061512) (xy 183.156254 -299.105089) (xy 183.171838 -299.15177) (xy 183.179733 -299.200347)
			(xy 183.180228 -299.224954) (xy 183.519076 -299.224954) (xy 183.523036 -299.1759) (xy 183.534813 -299.128116)
			(xy 183.554104 -299.08284) (xy 183.580407 -299.041244) (xy 183.613042 -299.004407) (xy 183.651163 -298.973282)
			(xy 183.693784 -298.948675) (xy 183.7398 -298.931223) (xy 183.788019 -298.921379) (xy 183.837194 -298.919398)
			(xy 183.886049 -298.92533) (xy 183.93332 -298.939022) (xy 183.977782 -298.96012) (xy 184.018285 -298.988076)
			(xy 184.053778 -299.022168) (xy 184.083343 -299.061512) (xy 184.106214 -299.105089) (xy 184.121798 -299.15177)
			(xy 184.129693 -299.200347) (xy 184.130188 -299.224954) (xy 184.469036 -299.224954) (xy 184.472996 -299.1759)
			(xy 184.484773 -299.128116) (xy 184.504064 -299.08284) (xy 184.530367 -299.041244) (xy 184.563002 -299.004407)
			(xy 184.601123 -298.973282) (xy 184.643744 -298.948675) (xy 184.68976 -298.931223) (xy 184.737979 -298.921379)
			(xy 184.787154 -298.919398) (xy 184.836009 -298.92533) (xy 184.88328 -298.939022) (xy 184.927742 -298.96012)
			(xy 184.968245 -298.988076) (xy 185.003738 -299.022168) (xy 185.033303 -299.061512) (xy 185.056174 -299.105089)
			(xy 185.071758 -299.15177) (xy 185.079653 -299.200347) (xy 185.080148 -299.224954) (xy 185.079653 -299.249561)
			(xy 185.071758 -299.298138) (xy 185.056174 -299.344819) (xy 185.033303 -299.388396) (xy 185.003738 -299.42774)
			(xy 184.968245 -299.461832) (xy 184.927742 -299.489788) (xy 184.88328 -299.510886) (xy 184.836009 -299.524578)
			(xy 184.787154 -299.53051) (xy 184.737979 -299.528529) (xy 184.68976 -299.518685) (xy 184.643744 -299.501233)
			(xy 184.601123 -299.476626) (xy 184.563002 -299.445501) (xy 184.530367 -299.408664) (xy 184.504064 -299.367068)
			(xy 184.484773 -299.321792) (xy 184.472996 -299.274008) (xy 184.469036 -299.224954) (xy 184.130188 -299.224954)
			(xy 184.129693 -299.249561) (xy 184.121798 -299.298138) (xy 184.106214 -299.344819) (xy 184.083343 -299.388396)
			(xy 184.053778 -299.42774) (xy 184.018285 -299.461832) (xy 183.977782 -299.489788) (xy 183.93332 -299.510886)
			(xy 183.886049 -299.524578) (xy 183.837194 -299.53051) (xy 183.788019 -299.528529) (xy 183.7398 -299.518685)
			(xy 183.693784 -299.501233) (xy 183.651163 -299.476626) (xy 183.613042 -299.445501) (xy 183.580407 -299.408664)
			(xy 183.554104 -299.367068) (xy 183.534813 -299.321792) (xy 183.523036 -299.274008) (xy 183.519076 -299.224954)
			(xy 183.180228 -299.224954) (xy 183.179733 -299.249561) (xy 183.171838 -299.298138) (xy 183.156254 -299.344819)
			(xy 183.133383 -299.388396) (xy 183.103818 -299.42774) (xy 183.068325 -299.461832) (xy 183.027822 -299.489788)
			(xy 182.98336 -299.510886) (xy 182.936089 -299.524578) (xy 182.887234 -299.53051) (xy 182.838059 -299.528529)
			(xy 182.78984 -299.518685) (xy 182.743824 -299.501233) (xy 182.701203 -299.476626) (xy 182.663082 -299.445501)
			(xy 182.630447 -299.408664) (xy 182.604144 -299.367068) (xy 182.584853 -299.321792) (xy 182.573076 -299.274008)
			(xy 182.569116 -299.224954) (xy 182.230268 -299.224954) (xy 182.229773 -299.249561) (xy 182.221878 -299.298138)
			(xy 182.206294 -299.344819) (xy 182.183423 -299.388396) (xy 182.153858 -299.42774) (xy 182.118365 -299.461832)
			(xy 182.077862 -299.489788) (xy 182.0334 -299.510886) (xy 181.986129 -299.524578) (xy 181.937274 -299.53051)
			(xy 181.888099 -299.528529) (xy 181.83988 -299.518685) (xy 181.793864 -299.501233) (xy 181.751243 -299.476626)
			(xy 181.713122 -299.445501) (xy 181.680487 -299.408664) (xy 181.654184 -299.367068) (xy 181.634893 -299.321792)
			(xy 181.623116 -299.274008) (xy 181.619156 -299.224954) (xy 181.280308 -299.224954) (xy 181.279813 -299.249561)
			(xy 181.271918 -299.298138) (xy 181.256334 -299.344819) (xy 181.233463 -299.388396) (xy 181.203898 -299.42774)
			(xy 181.168405 -299.461832) (xy 181.127902 -299.489788) (xy 181.08344 -299.510886) (xy 181.036169 -299.524578)
			(xy 180.987314 -299.53051) (xy 180.938139 -299.528529) (xy 180.88992 -299.518685) (xy 180.843904 -299.501233)
			(xy 180.801283 -299.476626) (xy 180.763162 -299.445501) (xy 180.730527 -299.408664) (xy 180.704224 -299.367068)
			(xy 180.684933 -299.321792) (xy 180.673156 -299.274008) (xy 180.669196 -299.224954) (xy 180.330348 -299.224954)
			(xy 180.329853 -299.249561) (xy 180.321958 -299.298138) (xy 180.306374 -299.344819) (xy 180.283503 -299.388396)
			(xy 180.253938 -299.42774) (xy 180.218445 -299.461832) (xy 180.177942 -299.489788) (xy 180.13348 -299.510886)
			(xy 180.086209 -299.524578) (xy 180.037354 -299.53051) (xy 179.988179 -299.528529) (xy 179.93996 -299.518685)
			(xy 179.893944 -299.501233) (xy 179.851323 -299.476626) (xy 179.813202 -299.445501) (xy 179.780567 -299.408664)
			(xy 179.754264 -299.367068) (xy 179.734973 -299.321792) (xy 179.723196 -299.274008) (xy 179.719236 -299.224954)
			(xy 179.380388 -299.224954) (xy 179.379893 -299.249561) (xy 179.371998 -299.298138) (xy 179.356414 -299.344819)
			(xy 179.333543 -299.388396) (xy 179.303978 -299.42774) (xy 179.268485 -299.461832) (xy 179.227982 -299.489788)
			(xy 179.18352 -299.510886) (xy 179.136249 -299.524578) (xy 179.087394 -299.53051) (xy 179.038219 -299.528529)
			(xy 178.99 -299.518685) (xy 178.943984 -299.501233) (xy 178.901363 -299.476626) (xy 178.863242 -299.445501)
			(xy 178.830607 -299.408664) (xy 178.804304 -299.367068) (xy 178.785013 -299.321792) (xy 178.773236 -299.274008)
			(xy 178.769276 -299.224954) (xy 178.430174 -299.224954) (xy 178.429679 -299.249561) (xy 178.421784 -299.298138)
			(xy 178.4062 -299.344819) (xy 178.383329 -299.388396) (xy 178.353764 -299.42774) (xy 178.318271 -299.461832)
			(xy 178.277768 -299.489788) (xy 178.233306 -299.510886) (xy 178.186035 -299.524578) (xy 178.13718 -299.53051)
			(xy 178.088005 -299.528529) (xy 178.039786 -299.518685) (xy 177.99377 -299.501233) (xy 177.951149 -299.476626)
			(xy 177.913028 -299.445501) (xy 177.880393 -299.408664) (xy 177.85409 -299.367068) (xy 177.834799 -299.321792)
			(xy 177.823022 -299.274008) (xy 177.819062 -299.224954) (xy 177.480214 -299.224954) (xy 177.479719 -299.249561)
			(xy 177.471824 -299.298138) (xy 177.45624 -299.344819) (xy 177.433369 -299.388396) (xy 177.403804 -299.42774)
			(xy 177.368311 -299.461832) (xy 177.327808 -299.489788) (xy 177.283346 -299.510886) (xy 177.236075 -299.524578)
			(xy 177.18722 -299.53051) (xy 177.138045 -299.528529) (xy 177.089826 -299.518685) (xy 177.04381 -299.501233)
			(xy 177.001189 -299.476626) (xy 176.963068 -299.445501) (xy 176.930433 -299.408664) (xy 176.90413 -299.367068)
			(xy 176.884839 -299.321792) (xy 176.873062 -299.274008) (xy 176.869102 -299.224954) (xy 176.530254 -299.224954)
			(xy 176.529759 -299.249561) (xy 176.521864 -299.298138) (xy 176.50628 -299.344819) (xy 176.483409 -299.388396)
			(xy 176.453844 -299.42774) (xy 176.418351 -299.461832) (xy 176.377848 -299.489788) (xy 176.333386 -299.510886)
			(xy 176.286115 -299.524578) (xy 176.23726 -299.53051) (xy 176.188085 -299.528529) (xy 176.139866 -299.518685)
			(xy 176.09385 -299.501233) (xy 176.051229 -299.476626) (xy 176.013108 -299.445501) (xy 175.980473 -299.408664)
			(xy 175.95417 -299.367068) (xy 175.934879 -299.321792) (xy 175.923102 -299.274008) (xy 175.919142 -299.224954)
			(xy 174.630334 -299.224954) (xy 174.629839 -299.249561) (xy 174.621944 -299.298138) (xy 174.60636 -299.344819)
			(xy 174.583489 -299.388396) (xy 174.553924 -299.42774) (xy 174.518431 -299.461832) (xy 174.477928 -299.489788)
			(xy 174.433466 -299.510886) (xy 174.386195 -299.524578) (xy 174.33734 -299.53051) (xy 174.288165 -299.528529)
			(xy 174.239946 -299.518685) (xy 174.19393 -299.501233) (xy 174.151309 -299.476626) (xy 174.113188 -299.445501)
			(xy 174.080553 -299.408664) (xy 174.05425 -299.367068) (xy 174.034959 -299.321792) (xy 174.023182 -299.274008)
			(xy 174.019222 -299.224954) (xy 173.680374 -299.224954) (xy 173.679879 -299.249561) (xy 173.671984 -299.298138)
			(xy 173.6564 -299.344819) (xy 173.633529 -299.388396) (xy 173.603964 -299.42774) (xy 173.568471 -299.461832)
			(xy 173.527968 -299.489788) (xy 173.483506 -299.510886) (xy 173.436235 -299.524578) (xy 173.38738 -299.53051)
			(xy 173.338205 -299.528529) (xy 173.289986 -299.518685) (xy 173.24397 -299.501233) (xy 173.201349 -299.476626)
			(xy 173.163228 -299.445501) (xy 173.130593 -299.408664) (xy 173.10429 -299.367068) (xy 173.084999 -299.321792)
			(xy 173.073222 -299.274008) (xy 173.069262 -299.224954) (xy 172.73016 -299.224954) (xy 172.729665 -299.249561)
			(xy 172.72177 -299.298138) (xy 172.706186 -299.344819) (xy 172.683315 -299.388396) (xy 172.65375 -299.42774)
			(xy 172.618257 -299.461832) (xy 172.577754 -299.489788) (xy 172.533292 -299.510886) (xy 172.486021 -299.524578)
			(xy 172.437166 -299.53051) (xy 172.387991 -299.528529) (xy 172.339772 -299.518685) (xy 172.293756 -299.501233)
			(xy 172.251135 -299.476626) (xy 172.213014 -299.445501) (xy 172.180379 -299.408664) (xy 172.154076 -299.367068)
			(xy 172.134785 -299.321792) (xy 172.123008 -299.274008) (xy 172.119048 -299.224954) (xy 171.7802 -299.224954)
			(xy 171.779705 -299.249561) (xy 171.77181 -299.298138) (xy 171.756226 -299.344819) (xy 171.733355 -299.388396)
			(xy 171.70379 -299.42774) (xy 171.668297 -299.461832) (xy 171.627794 -299.489788) (xy 171.583332 -299.510886)
			(xy 171.536061 -299.524578) (xy 171.487206 -299.53051) (xy 171.438031 -299.528529) (xy 171.389812 -299.518685)
			(xy 171.343796 -299.501233) (xy 171.301175 -299.476626) (xy 171.263054 -299.445501) (xy 171.230419 -299.408664)
			(xy 171.204116 -299.367068) (xy 171.184825 -299.321792) (xy 171.173048 -299.274008) (xy 171.169088 -299.224954)
			(xy 170.83024 -299.224954) (xy 170.829745 -299.249561) (xy 170.82185 -299.298138) (xy 170.806266 -299.344819)
			(xy 170.783395 -299.388396) (xy 170.75383 -299.42774) (xy 170.718337 -299.461832) (xy 170.677834 -299.489788)
			(xy 170.633372 -299.510886) (xy 170.586101 -299.524578) (xy 170.537246 -299.53051) (xy 170.488071 -299.528529)
			(xy 170.439852 -299.518685) (xy 170.393836 -299.501233) (xy 170.351215 -299.476626) (xy 170.313094 -299.445501)
			(xy 170.280459 -299.408664) (xy 170.254156 -299.367068) (xy 170.234865 -299.321792) (xy 170.223088 -299.274008)
			(xy 170.219128 -299.224954) (xy 169.88028 -299.224954) (xy 169.879785 -299.249561) (xy 169.87189 -299.298138)
			(xy 169.856306 -299.344819) (xy 169.833435 -299.388396) (xy 169.80387 -299.42774) (xy 169.768377 -299.461832)
			(xy 169.727874 -299.489788) (xy 169.683412 -299.510886) (xy 169.636141 -299.524578) (xy 169.587286 -299.53051)
			(xy 169.538111 -299.528529) (xy 169.489892 -299.518685) (xy 169.443876 -299.501233) (xy 169.401255 -299.476626)
			(xy 169.363134 -299.445501) (xy 169.330499 -299.408664) (xy 169.304196 -299.367068) (xy 169.284905 -299.321792)
			(xy 169.273128 -299.274008) (xy 169.269168 -299.224954) (xy 168.93032 -299.224954) (xy 168.929825 -299.249561)
			(xy 168.92193 -299.298138) (xy 168.906346 -299.344819) (xy 168.883475 -299.388396) (xy 168.85391 -299.42774)
			(xy 168.818417 -299.461832) (xy 168.777914 -299.489788) (xy 168.733452 -299.510886) (xy 168.686181 -299.524578)
			(xy 168.637326 -299.53051) (xy 168.588151 -299.528529) (xy 168.539932 -299.518685) (xy 168.493916 -299.501233)
			(xy 168.451295 -299.476626) (xy 168.413174 -299.445501) (xy 168.380539 -299.408664) (xy 168.354236 -299.367068)
			(xy 168.334945 -299.321792) (xy 168.323168 -299.274008) (xy 168.319208 -299.224954) (xy 167.98036 -299.224954)
			(xy 167.979865 -299.249561) (xy 167.97197 -299.298138) (xy 167.956386 -299.344819) (xy 167.933515 -299.388396)
			(xy 167.90395 -299.42774) (xy 167.868457 -299.461832) (xy 167.827954 -299.489788) (xy 167.783492 -299.510886)
			(xy 167.736221 -299.524578) (xy 167.687366 -299.53051) (xy 167.638191 -299.528529) (xy 167.589972 -299.518685)
			(xy 167.543956 -299.501233) (xy 167.501335 -299.476626) (xy 167.463214 -299.445501) (xy 167.430579 -299.408664)
			(xy 167.404276 -299.367068) (xy 167.384985 -299.321792) (xy 167.373208 -299.274008) (xy 167.369248 -299.224954)
			(xy 167.0304 -299.224954) (xy 167.029905 -299.249561) (xy 167.02201 -299.298138) (xy 167.006426 -299.344819)
			(xy 166.983555 -299.388396) (xy 166.95399 -299.42774) (xy 166.918497 -299.461832) (xy 166.877994 -299.489788)
			(xy 166.833532 -299.510886) (xy 166.786261 -299.524578) (xy 166.737406 -299.53051) (xy 166.688231 -299.528529)
			(xy 166.640012 -299.518685) (xy 166.593996 -299.501233) (xy 166.551375 -299.476626) (xy 166.513254 -299.445501)
			(xy 166.480619 -299.408664) (xy 166.454316 -299.367068) (xy 166.435025 -299.321792) (xy 166.423248 -299.274008)
			(xy 166.419288 -299.224954) (xy 166.080186 -299.224954) (xy 166.079691 -299.249561) (xy 166.071796 -299.298138)
			(xy 166.056212 -299.344819) (xy 166.033341 -299.388396) (xy 166.003776 -299.42774) (xy 165.968283 -299.461832)
			(xy 165.92778 -299.489788) (xy 165.883318 -299.510886) (xy 165.836047 -299.524578) (xy 165.787192 -299.53051)
			(xy 165.738017 -299.528529) (xy 165.689798 -299.518685) (xy 165.643782 -299.501233) (xy 165.601161 -299.476626)
			(xy 165.56304 -299.445501) (xy 165.530405 -299.408664) (xy 165.504102 -299.367068) (xy 165.484811 -299.321792)
			(xy 165.473034 -299.274008) (xy 165.469074 -299.224954) (xy 164.180266 -299.224954) (xy 164.179771 -299.249561)
			(xy 164.171876 -299.298138) (xy 164.156292 -299.344819) (xy 164.133421 -299.388396) (xy 164.103856 -299.42774)
			(xy 164.068363 -299.461832) (xy 164.02786 -299.489788) (xy 163.983398 -299.510886) (xy 163.936127 -299.524578)
			(xy 163.887272 -299.53051) (xy 163.838097 -299.528529) (xy 163.789878 -299.518685) (xy 163.743862 -299.501233)
			(xy 163.701241 -299.476626) (xy 163.66312 -299.445501) (xy 163.630485 -299.408664) (xy 163.604182 -299.367068)
			(xy 163.584891 -299.321792) (xy 163.573114 -299.274008) (xy 163.569154 -299.224954) (xy 163.230306 -299.224954)
			(xy 163.229811 -299.249561) (xy 163.221916 -299.298138) (xy 163.206332 -299.344819) (xy 163.183461 -299.388396)
			(xy 163.153896 -299.42774) (xy 163.118403 -299.461832) (xy 163.0779 -299.489788) (xy 163.033438 -299.510886)
			(xy 162.986167 -299.524578) (xy 162.937312 -299.53051) (xy 162.888137 -299.528529) (xy 162.839918 -299.518685)
			(xy 162.793902 -299.501233) (xy 162.751281 -299.476626) (xy 162.71316 -299.445501) (xy 162.680525 -299.408664)
			(xy 162.654222 -299.367068) (xy 162.634931 -299.321792) (xy 162.623154 -299.274008) (xy 162.619194 -299.224954)
			(xy 162.280346 -299.224954) (xy 162.279851 -299.249561) (xy 162.271956 -299.298138) (xy 162.256372 -299.344819)
			(xy 162.233501 -299.388396) (xy 162.203936 -299.42774) (xy 162.168443 -299.461832) (xy 162.12794 -299.489788)
			(xy 162.083478 -299.510886) (xy 162.036207 -299.524578) (xy 161.987352 -299.53051) (xy 161.938177 -299.528529)
			(xy 161.889958 -299.518685) (xy 161.843942 -299.501233) (xy 161.801321 -299.476626) (xy 161.7632 -299.445501)
			(xy 161.730565 -299.408664) (xy 161.704262 -299.367068) (xy 161.684971 -299.321792) (xy 161.673194 -299.274008)
			(xy 161.669234 -299.224954) (xy 161.330386 -299.224954) (xy 161.329891 -299.249561) (xy 161.321996 -299.298138)
			(xy 161.306412 -299.344819) (xy 161.283541 -299.388396) (xy 161.253976 -299.42774) (xy 161.218483 -299.461832)
			(xy 161.17798 -299.489788) (xy 161.133518 -299.510886) (xy 161.086247 -299.524578) (xy 161.037392 -299.53051)
			(xy 160.988217 -299.528529) (xy 160.939998 -299.518685) (xy 160.893982 -299.501233) (xy 160.851361 -299.476626)
			(xy 160.81324 -299.445501) (xy 160.780605 -299.408664) (xy 160.754302 -299.367068) (xy 160.735011 -299.321792)
			(xy 160.723234 -299.274008) (xy 160.719274 -299.224954) (xy 160.380172 -299.224954) (xy 160.379677 -299.249561)
			(xy 160.371782 -299.298138) (xy 160.356198 -299.344819) (xy 160.333327 -299.388396) (xy 160.303762 -299.42774)
			(xy 160.268269 -299.461832) (xy 160.227766 -299.489788) (xy 160.183304 -299.510886) (xy 160.136033 -299.524578)
			(xy 160.087178 -299.53051) (xy 160.038003 -299.528529) (xy 159.989784 -299.518685) (xy 159.943768 -299.501233)
			(xy 159.901147 -299.476626) (xy 159.863026 -299.445501) (xy 159.830391 -299.408664) (xy 159.804088 -299.367068)
			(xy 159.784797 -299.321792) (xy 159.77302 -299.274008) (xy 159.76906 -299.224954) (xy 158.480247 -299.224954)
			(xy 158.479757 -299.249307) (xy 158.471862 -299.297884) (xy 158.456278 -299.344565) (xy 158.433407 -299.388142)
			(xy 158.403842 -299.427486) (xy 158.368349 -299.461578) (xy 158.327846 -299.489534) (xy 158.283384 -299.510632)
			(xy 158.236113 -299.524324) (xy 158.187258 -299.530256) (xy 158.138083 -299.528275) (xy 158.089864 -299.518431)
			(xy 158.043848 -299.500979) (xy 158.001227 -299.476372) (xy 157.963106 -299.445247) (xy 157.930471 -299.40841)
			(xy 157.904168 -299.366814) (xy 157.884877 -299.321538) (xy 157.8731 -299.273754) (xy 157.86914 -299.2247)
			(xy 157.530287 -299.2247) (xy 157.530292 -299.224954) (xy 157.529797 -299.249561) (xy 157.521902 -299.298138)
			(xy 157.506318 -299.344819) (xy 157.483447 -299.388396) (xy 157.453882 -299.42774) (xy 157.418389 -299.461832)
			(xy 157.377886 -299.489788) (xy 157.333424 -299.510886) (xy 157.286153 -299.524578) (xy 157.237298 -299.53051)
			(xy 157.188123 -299.528529) (xy 157.139904 -299.518685) (xy 157.093888 -299.501233) (xy 157.051267 -299.476626)
			(xy 157.013146 -299.445501) (xy 156.980511 -299.408664) (xy 156.954208 -299.367068) (xy 156.934917 -299.321792)
			(xy 156.92314 -299.274008) (xy 156.91918 -299.224954) (xy 156.605406 -299.224954) (xy 156.605406 -299.251002)
			(xy 156.597271 -299.302367) (xy 156.581201 -299.351826) (xy 156.557593 -299.398163) (xy 156.527026 -299.440237)
			(xy 156.490255 -299.477011) (xy 156.448184 -299.50758) (xy 156.401848 -299.531192) (xy 156.35239 -299.547265)
			(xy 156.301026 -299.555404) (xy 156.275024 -299.555916) (xy 156.204666 -299.555916) (xy 156.194039 -299.556515)
			(xy 156.17462 -299.565174) (xy 156.167074 -299.57268) (xy 156.109162 -299.636942) (xy 156.102558 -299.657008)
			(xy 156.103574 -299.66793) (xy 156.105352 -299.699934) (xy 156.10483 -299.725189) (xy 156.096517 -299.775011)
			(xy 156.080116 -299.822785) (xy 156.056075 -299.867208) (xy 156.025051 -299.907068) (xy 155.987889 -299.941278)
			(xy 155.945603 -299.968904) (xy 155.899347 -299.989194) (xy 155.850382 -300.001594) (xy 155.800044 -300.005765)
			(xy 155.749706 -300.001594) (xy 155.700741 -299.989194) (xy 155.654485 -299.968904) (xy 155.612199 -299.941278)
			(xy 155.575037 -299.907068) (xy 155.544013 -299.867208) (xy 155.519972 -299.822785) (xy 155.503571 -299.775011)
			(xy 155.495258 -299.725189) (xy 155.494736 -299.699934) (xy 155.496514 -299.66793) (xy 155.49753 -299.657008)
			(xy 155.490926 -299.636942) (xy 155.433014 -299.57268) (xy 155.425538 -299.56507) (xy 155.406079 -299.55638)
			(xy 155.395422 -299.555916) (xy 155.325064 -299.555916) (xy 155.299055 -299.555495) (xy 155.247678 -299.547353)
			(xy 155.198208 -299.531274) (xy 155.151861 -299.507655) (xy 155.10978 -299.477077) (xy 155.073 -299.440293)
			(xy 155.042426 -299.398208) (xy 155.018812 -299.351859) (xy 155.002739 -299.302387) (xy 154.994602 -299.251009)
			(xy 154.679428 -299.251009) (xy 154.671768 -299.298138) (xy 154.656184 -299.344819) (xy 154.633313 -299.388396)
			(xy 154.603748 -299.42774) (xy 154.568255 -299.461832) (xy 154.527752 -299.489788) (xy 154.48329 -299.510886)
			(xy 154.436019 -299.524578) (xy 154.387164 -299.53051) (xy 154.337989 -299.528529) (xy 154.28977 -299.518685)
			(xy 154.243754 -299.501233) (xy 154.201133 -299.476626) (xy 154.163012 -299.445501) (xy 154.130377 -299.408664)
			(xy 154.104074 -299.367068) (xy 154.084783 -299.321792) (xy 154.073006 -299.274008) (xy 154.069046 -299.224954)
			(xy 153.755006 -299.224954) (xy 153.755006 -299.251002) (xy 153.746871 -299.302365) (xy 153.730803 -299.351823)
			(xy 153.707195 -299.39816) (xy 153.67663 -299.440233) (xy 153.63986 -299.477007) (xy 153.59779 -299.507576)
			(xy 153.551457 -299.531189) (xy 153.502 -299.547263) (xy 153.450638 -299.555403) (xy 153.424636 -299.555916)
			(xy 152.474676 -299.555916) (xy 152.450291 -299.555513) (xy 152.402052 -299.548333) (xy 152.355391 -299.534148)
			(xy 152.311318 -299.513264) (xy 152.27079 -299.486135) (xy 152.234684 -299.453349) (xy 152.218898 -299.434758)
			(xy 152.211786 -299.426122) (xy 152.192228 -299.41647) (xy 152.092914 -299.41393) (xy 152.072848 -299.422312)
			(xy 152.065228 -299.430694) (xy 152.047764 -299.449091) (xy 152.007828 -299.480363) (xy 151.96327 -299.5046)
			(xy 151.915318 -299.521135) (xy 151.865292 -299.529511) (xy 151.83993 -299.530008) (xy 151.814671 -299.529518)
			(xy 151.76484 -299.521207) (xy 151.717058 -299.504807) (xy 151.672626 -299.480766) (xy 151.632758 -299.449739)
			(xy 151.598541 -299.412573) (xy 151.570909 -299.370282) (xy 151.550614 -299.324019) (xy 151.538212 -299.275046)
			(xy 151.53404 -299.2247) (xy 148.201784 -299.2247) (xy 148.185143 -299.276954) (xy 148.158933 -299.329549)
			(xy 148.124966 -299.377501) (xy 148.084044 -299.419674) (xy 148.060918 -299.437806) (xy 148.05152 -299.445172)
			(xy 148.041106 -299.465746) (xy 148.039582 -299.569632) (xy 148.049488 -299.590714) (xy 148.058632 -299.59808)
			(xy 148.080459 -299.616309) (xy 148.118999 -299.658124) (xy 148.150908 -299.705195) (xy 148.175478 -299.75648)
			(xy 148.192166 -299.810843) (xy 148.200603 -299.867081) (xy 148.201126 -299.895514) (xy 148.8346 -299.895514)
			(xy 148.838671 -299.839892) (xy 148.850797 -299.785455) (xy 148.87072 -299.733364) (xy 148.898016 -299.684729)
			(xy 148.932102 -299.640586) (xy 148.972251 -299.601877) (xy 149.017609 -299.569426) (xy 149.067209 -299.543925)
			(xy 149.119993 -299.525918) (xy 149.174836 -299.515788) (xy 149.23057 -299.513751) (xy 149.286007 -299.519851)
			(xy 149.339964 -299.533957) (xy 149.391293 -299.555769) (xy 149.438899 -299.584823) (xy 149.481767 -299.620498)
			(xy 149.518984 -299.662035) (xy 149.549757 -299.708548) (xy 149.573429 -299.759045) (xy 149.589497 -299.812452)
			(xy 149.597617 -299.867628) (xy 149.598126 -299.895514) (xy 149.72106 -299.895514) (xy 149.725131 -299.839892)
			(xy 149.737257 -299.785455) (xy 149.75718 -299.733364) (xy 149.784476 -299.684729) (xy 149.818562 -299.640586)
			(xy 149.858711 -299.601877) (xy 149.904069 -299.569426) (xy 149.953669 -299.543925) (xy 150.006453 -299.525918)
			(xy 150.061296 -299.515788) (xy 150.11703 -299.513751) (xy 150.172467 -299.519851) (xy 150.226424 -299.533957)
			(xy 150.277753 -299.555769) (xy 150.325359 -299.584823) (xy 150.368227 -299.620498) (xy 150.405444 -299.662035)
			(xy 150.436217 -299.708548) (xy 150.459889 -299.759045) (xy 150.475957 -299.812452) (xy 150.484077 -299.867628)
			(xy 150.484586 -299.895514) (xy 150.484077 -299.9234) (xy 150.475957 -299.978576) (xy 150.459889 -300.031983)
			(xy 150.436217 -300.08248) (xy 150.405444 -300.128993) (xy 150.368227 -300.17053) (xy 150.325359 -300.206205)
			(xy 150.277753 -300.235259) (xy 150.226424 -300.257071) (xy 150.172467 -300.271177) (xy 150.11703 -300.277277)
			(xy 150.061296 -300.27524) (xy 150.006453 -300.26511) (xy 149.953669 -300.247103) (xy 149.904069 -300.221602)
			(xy 149.858711 -300.189151) (xy 149.818562 -300.150442) (xy 149.784476 -300.106299) (xy 149.75718 -300.057664)
			(xy 149.737257 -300.005573) (xy 149.725131 -299.951136) (xy 149.72106 -299.895514) (xy 149.598126 -299.895514)
			(xy 149.597617 -299.9234) (xy 149.589497 -299.978576) (xy 149.573429 -300.031983) (xy 149.549757 -300.08248)
			(xy 149.518984 -300.128993) (xy 149.481767 -300.17053) (xy 149.438899 -300.206205) (xy 149.391293 -300.235259)
			(xy 149.339964 -300.257071) (xy 149.286007 -300.271177) (xy 149.23057 -300.277277) (xy 149.174836 -300.27524)
			(xy 149.119993 -300.26511) (xy 149.067209 -300.247103) (xy 149.017609 -300.221602) (xy 148.972251 -300.189151)
			(xy 148.932102 -300.150442) (xy 148.898016 -300.106299) (xy 148.87072 -300.057664) (xy 148.850797 -300.005573)
			(xy 148.838671 -299.951136) (xy 148.8346 -299.895514) (xy 148.201126 -299.895514) (xy 148.20064 -299.922765)
			(xy 148.192884 -299.976713) (xy 148.177529 -300.029008) (xy 148.154887 -300.078585) (xy 148.125421 -300.124435)
			(xy 148.08973 -300.165626) (xy 148.048539 -300.201317) (xy 148.002689 -300.230783) (xy 147.953112 -300.253425)
			(xy 147.900817 -300.26878) (xy 147.846869 -300.276536) (xy 147.792367 -300.276536) (xy 147.738419 -300.26878)
			(xy 147.686124 -300.253425) (xy 147.636547 -300.230783) (xy 147.590697 -300.201317) (xy 147.549506 -300.165626)
			(xy 147.513815 -300.124435) (xy 147.484349 -300.078585) (xy 147.461707 -300.029008) (xy 147.446352 -299.976713)
			(xy 147.438596 -299.922765) (xy 147.43811 -299.895514) (xy 118.832884 -299.895514) (xy 118.832884 -301.031656)
			(xy 141.911576 -301.031656) (xy 141.915647 -300.976034) (xy 141.927773 -300.921597) (xy 141.947696 -300.869506)
			(xy 141.974992 -300.820871) (xy 142.009078 -300.776728) (xy 142.049227 -300.738019) (xy 142.094585 -300.705568)
			(xy 142.144185 -300.680067) (xy 142.196969 -300.66206) (xy 142.251812 -300.65193) (xy 142.307546 -300.649893)
			(xy 142.362983 -300.655993) (xy 142.41694 -300.670099) (xy 142.468269 -300.691911) (xy 142.515875 -300.720965)
			(xy 142.558743 -300.75664) (xy 142.59596 -300.798177) (xy 142.626733 -300.84469) (xy 142.650405 -300.895187)
			(xy 142.666473 -300.948594) (xy 142.674593 -301.00377) (xy 142.675102 -301.031656) (xy 143.396714 -301.031656)
			(xy 143.400785 -300.976034) (xy 143.412911 -300.921597) (xy 143.432834 -300.869506) (xy 143.46013 -300.820871)
			(xy 143.494216 -300.776728) (xy 143.534365 -300.738019) (xy 143.579723 -300.705568) (xy 143.629323 -300.680067)
			(xy 143.682107 -300.66206) (xy 143.73695 -300.65193) (xy 143.792684 -300.649893) (xy 143.792693 -300.649894)
			(xy 152.644106 -300.649894) (xy 152.648066 -300.60084) (xy 152.659843 -300.553056) (xy 152.679134 -300.50778)
			(xy 152.705437 -300.466184) (xy 152.738072 -300.429347) (xy 152.776193 -300.398222) (xy 152.818814 -300.373615)
			(xy 152.86483 -300.356163) (xy 152.913049 -300.346319) (xy 152.962224 -300.344338) (xy 153.011079 -300.35027)
			(xy 153.05835 -300.363962) (xy 153.102812 -300.38506) (xy 153.143315 -300.413016) (xy 153.178808 -300.447108)
			(xy 153.208373 -300.486452) (xy 153.231244 -300.530029) (xy 153.246828 -300.57671) (xy 153.254723 -300.625287)
			(xy 153.255218 -300.649894) (xy 153.594066 -300.649894) (xy 153.598026 -300.60084) (xy 153.609803 -300.553056)
			(xy 153.629094 -300.50778) (xy 153.655397 -300.466184) (xy 153.688032 -300.429347) (xy 153.726153 -300.398222)
			(xy 153.768774 -300.373615) (xy 153.81479 -300.356163) (xy 153.863009 -300.346319) (xy 153.912184 -300.344338)
			(xy 153.961039 -300.35027) (xy 154.00831 -300.363962) (xy 154.052772 -300.38506) (xy 154.093275 -300.413016)
			(xy 154.128768 -300.447108) (xy 154.158333 -300.486452) (xy 154.181204 -300.530029) (xy 154.196788 -300.57671)
			(xy 154.204683 -300.625287) (xy 154.205178 -300.649894) (xy 154.54428 -300.649894) (xy 154.54824 -300.60084)
			(xy 154.560017 -300.553056) (xy 154.579308 -300.50778) (xy 154.605611 -300.466184) (xy 154.638246 -300.429347)
			(xy 154.676367 -300.398222) (xy 154.718988 -300.373615) (xy 154.765004 -300.356163) (xy 154.813223 -300.346319)
			(xy 154.862398 -300.344338) (xy 154.911253 -300.35027) (xy 154.958524 -300.363962) (xy 155.002986 -300.38506)
			(xy 155.043489 -300.413016) (xy 155.078982 -300.447108) (xy 155.108547 -300.486452) (xy 155.131418 -300.530029)
			(xy 155.147002 -300.57671) (xy 155.154897 -300.625287) (xy 155.155392 -300.649894) (xy 155.49424 -300.649894)
			(xy 155.4982 -300.60084) (xy 155.509977 -300.553056) (xy 155.529268 -300.50778) (xy 155.555571 -300.466184)
			(xy 155.588206 -300.429347) (xy 155.626327 -300.398222) (xy 155.668948 -300.373615) (xy 155.714964 -300.356163)
			(xy 155.763183 -300.346319) (xy 155.812358 -300.344338) (xy 155.861213 -300.35027) (xy 155.908484 -300.363962)
			(xy 155.952946 -300.38506) (xy 155.993449 -300.413016) (xy 156.028942 -300.447108) (xy 156.058507 -300.486452)
			(xy 156.081378 -300.530029) (xy 156.096962 -300.57671) (xy 156.104857 -300.625287) (xy 156.105352 -300.649894)
			(xy 156.4442 -300.649894) (xy 156.44816 -300.60084) (xy 156.459937 -300.553056) (xy 156.479228 -300.50778)
			(xy 156.505531 -300.466184) (xy 156.538166 -300.429347) (xy 156.576287 -300.398222) (xy 156.618908 -300.373615)
			(xy 156.664924 -300.356163) (xy 156.713143 -300.346319) (xy 156.762318 -300.344338) (xy 156.811173 -300.35027)
			(xy 156.858444 -300.363962) (xy 156.902906 -300.38506) (xy 156.943409 -300.413016) (xy 156.978902 -300.447108)
			(xy 157.008467 -300.486452) (xy 157.031338 -300.530029) (xy 157.046922 -300.57671) (xy 157.054817 -300.625287)
			(xy 157.055312 -300.649894) (xy 157.39416 -300.649894) (xy 157.39812 -300.60084) (xy 157.409897 -300.553056)
			(xy 157.429188 -300.50778) (xy 157.455491 -300.466184) (xy 157.488126 -300.429347) (xy 157.526247 -300.398222)
			(xy 157.568868 -300.373615) (xy 157.614884 -300.356163) (xy 157.663103 -300.346319) (xy 157.712278 -300.344338)
			(xy 157.761133 -300.35027) (xy 157.808404 -300.363962) (xy 157.852866 -300.38506) (xy 157.893369 -300.413016)
			(xy 157.928862 -300.447108) (xy 157.958427 -300.486452) (xy 157.981298 -300.530029) (xy 157.996882 -300.57671)
			(xy 158.004777 -300.625287) (xy 158.005272 -300.649894) (xy 158.34412 -300.649894) (xy 158.34808 -300.60084)
			(xy 158.359857 -300.553056) (xy 158.379148 -300.50778) (xy 158.405451 -300.466184) (xy 158.438086 -300.429347)
			(xy 158.476207 -300.398222) (xy 158.518828 -300.373615) (xy 158.564844 -300.356163) (xy 158.613063 -300.346319)
			(xy 158.662238 -300.344338) (xy 158.711093 -300.35027) (xy 158.758364 -300.363962) (xy 158.802826 -300.38506)
			(xy 158.843329 -300.413016) (xy 158.878822 -300.447108) (xy 158.908387 -300.486452) (xy 158.931258 -300.530029)
			(xy 158.946842 -300.57671) (xy 158.954737 -300.625287) (xy 158.955066 -300.641631) (xy 159.294175 -300.641631)
			(xy 159.29954 -300.592279) (xy 159.312819 -300.544446) (xy 159.333661 -300.499391) (xy 159.361518 -300.458301)
			(xy 159.395655 -300.422259) (xy 159.435174 -300.392215) (xy 159.479032 -300.36896) (xy 159.526075 -300.353107)
			(xy 159.575063 -300.345073) (xy 159.599884 -300.344586) (xy 159.614067 -300.344765) (xy 159.642307 -300.347436)
			(xy 159.656272 -300.34992) (xy 159.670242 -300.352051) (xy 159.698371 -300.349479) (xy 159.724717 -300.339295)
			(xy 159.747264 -300.322281) (xy 159.764284 -300.299738) (xy 159.774473 -300.273394) (xy 159.777053 -300.245266)
			(xy 159.77489 -300.231302) (xy 159.772418 -300.217335) (xy 159.769743 -300.189096) (xy 159.769556 -300.174914)
			(xy 159.770063 -300.150091) (xy 159.778093 -300.101099) (xy 159.793943 -300.054052) (xy 159.817196 -300.010188)
			(xy 159.84724 -299.970665) (xy 159.883282 -299.936523) (xy 159.924372 -299.908662) (xy 159.969429 -299.887816)
			(xy 160.017266 -299.874534) (xy 160.06662 -299.869167) (xy 160.116193 -299.871855) (xy 160.164678 -299.882529)
			(xy 160.210797 -299.900905) (xy 160.253336 -299.926502) (xy 160.291173 -299.958643) (xy 160.323311 -299.996482)
			(xy 160.348904 -300.039022) (xy 160.367278 -300.085143) (xy 160.377948 -300.133629) (xy 160.380183 -300.174914)
			(xy 160.719274 -300.174914) (xy 160.723234 -300.12586) (xy 160.735011 -300.078076) (xy 160.754302 -300.0328)
			(xy 160.780605 -299.991204) (xy 160.81324 -299.954367) (xy 160.851361 -299.923242) (xy 160.893982 -299.898635)
			(xy 160.939998 -299.881183) (xy 160.988217 -299.871339) (xy 161.037392 -299.869358) (xy 161.086247 -299.87529)
			(xy 161.133518 -299.888982) (xy 161.17798 -299.91008) (xy 161.218483 -299.938036) (xy 161.253976 -299.972128)
			(xy 161.283541 -300.011472) (xy 161.306412 -300.055049) (xy 161.321996 -300.10173) (xy 161.329891 -300.150307)
			(xy 161.330386 -300.174914) (xy 161.669234 -300.174914) (xy 161.673194 -300.12586) (xy 161.684971 -300.078076)
			(xy 161.704262 -300.0328) (xy 161.730565 -299.991204) (xy 161.7632 -299.954367) (xy 161.801321 -299.923242)
			(xy 161.843942 -299.898635) (xy 161.889958 -299.881183) (xy 161.938177 -299.871339) (xy 161.987352 -299.869358)
			(xy 162.036207 -299.87529) (xy 162.083478 -299.888982) (xy 162.12794 -299.91008) (xy 162.168443 -299.938036)
			(xy 162.203936 -299.972128) (xy 162.233501 -300.011472) (xy 162.256372 -300.055049) (xy 162.271956 -300.10173)
			(xy 162.279851 -300.150307) (xy 162.280346 -300.174914) (xy 163.569154 -300.174914) (xy 163.573114 -300.12586)
			(xy 163.584891 -300.078076) (xy 163.604182 -300.0328) (xy 163.630485 -299.991204) (xy 163.66312 -299.954367)
			(xy 163.701241 -299.923242) (xy 163.743862 -299.898635) (xy 163.789878 -299.881183) (xy 163.838097 -299.871339)
			(xy 163.887272 -299.869358) (xy 163.936127 -299.87529) (xy 163.983398 -299.888982) (xy 164.02786 -299.91008)
			(xy 164.068363 -299.938036) (xy 164.103856 -299.972128) (xy 164.133421 -300.011472) (xy 164.156292 -300.055049)
			(xy 164.171876 -300.10173) (xy 164.179771 -300.150307) (xy 164.180266 -300.174914) (xy 164.519114 -300.174914)
			(xy 164.523074 -300.12586) (xy 164.534851 -300.078076) (xy 164.554142 -300.0328) (xy 164.580445 -299.991204)
			(xy 164.61308 -299.954367) (xy 164.651201 -299.923242) (xy 164.693822 -299.898635) (xy 164.739838 -299.881183)
			(xy 164.788057 -299.871339) (xy 164.837232 -299.869358) (xy 164.886087 -299.87529) (xy 164.933358 -299.888982)
			(xy 164.97782 -299.91008) (xy 165.018323 -299.938036) (xy 165.053816 -299.972128) (xy 165.083381 -300.011472)
			(xy 165.106252 -300.055049) (xy 165.121836 -300.10173) (xy 165.129731 -300.150307) (xy 165.130226 -300.174914)
			(xy 166.419288 -300.174914) (xy 166.423248 -300.12586) (xy 166.435025 -300.078076) (xy 166.454316 -300.0328)
			(xy 166.480619 -299.991204) (xy 166.513254 -299.954367) (xy 166.551375 -299.923242) (xy 166.593996 -299.898635)
			(xy 166.640012 -299.881183) (xy 166.688231 -299.871339) (xy 166.737406 -299.869358) (xy 166.786261 -299.87529)
			(xy 166.833532 -299.888982) (xy 166.877994 -299.91008) (xy 166.918497 -299.938036) (xy 166.95399 -299.972128)
			(xy 166.983555 -300.011472) (xy 167.006426 -300.055049) (xy 167.02201 -300.10173) (xy 167.029905 -300.150307)
			(xy 167.0304 -300.174914) (xy 167.369248 -300.174914) (xy 167.373208 -300.12586) (xy 167.384985 -300.078076)
			(xy 167.404276 -300.0328) (xy 167.430579 -299.991204) (xy 167.463214 -299.954367) (xy 167.501335 -299.923242)
			(xy 167.543956 -299.898635) (xy 167.589972 -299.881183) (xy 167.638191 -299.871339) (xy 167.687366 -299.869358)
			(xy 167.736221 -299.87529) (xy 167.783492 -299.888982) (xy 167.827954 -299.91008) (xy 167.868457 -299.938036)
			(xy 167.90395 -299.972128) (xy 167.933515 -300.011472) (xy 167.956386 -300.055049) (xy 167.97197 -300.10173)
			(xy 167.979865 -300.150307) (xy 167.98036 -300.174914) (xy 168.319208 -300.174914) (xy 168.323168 -300.12586)
			(xy 168.334945 -300.078076) (xy 168.354236 -300.0328) (xy 168.380539 -299.991204) (xy 168.413174 -299.954367)
			(xy 168.451295 -299.923242) (xy 168.493916 -299.898635) (xy 168.539932 -299.881183) (xy 168.588151 -299.871339)
			(xy 168.637326 -299.869358) (xy 168.686181 -299.87529) (xy 168.733452 -299.888982) (xy 168.777914 -299.91008)
			(xy 168.818417 -299.938036) (xy 168.85391 -299.972128) (xy 168.883475 -300.011472) (xy 168.906346 -300.055049)
			(xy 168.92193 -300.10173) (xy 168.929825 -300.150307) (xy 168.93032 -300.174914) (xy 169.269168 -300.174914)
			(xy 169.273128 -300.12586) (xy 169.284905 -300.078076) (xy 169.304196 -300.0328) (xy 169.330499 -299.991204)
			(xy 169.363134 -299.954367) (xy 169.401255 -299.923242) (xy 169.443876 -299.898635) (xy 169.489892 -299.881183)
			(xy 169.538111 -299.871339) (xy 169.587286 -299.869358) (xy 169.636141 -299.87529) (xy 169.683412 -299.888982)
			(xy 169.727874 -299.91008) (xy 169.768377 -299.938036) (xy 169.80387 -299.972128) (xy 169.833435 -300.011472)
			(xy 169.856306 -300.055049) (xy 169.87189 -300.10173) (xy 169.879785 -300.150307) (xy 169.88028 -300.174914)
			(xy 170.219128 -300.174914) (xy 170.223088 -300.12586) (xy 170.234865 -300.078076) (xy 170.254156 -300.0328)
			(xy 170.280459 -299.991204) (xy 170.313094 -299.954367) (xy 170.351215 -299.923242) (xy 170.393836 -299.898635)
			(xy 170.439852 -299.881183) (xy 170.488071 -299.871339) (xy 170.537246 -299.869358) (xy 170.586101 -299.87529)
			(xy 170.633372 -299.888982) (xy 170.677834 -299.91008) (xy 170.718337 -299.938036) (xy 170.75383 -299.972128)
			(xy 170.783395 -300.011472) (xy 170.806266 -300.055049) (xy 170.82185 -300.10173) (xy 170.829745 -300.150307)
			(xy 170.83024 -300.174914) (xy 171.169088 -300.174914) (xy 171.173048 -300.12586) (xy 171.184825 -300.078076)
			(xy 171.204116 -300.0328) (xy 171.230419 -299.991204) (xy 171.263054 -299.954367) (xy 171.301175 -299.923242)
			(xy 171.343796 -299.898635) (xy 171.389812 -299.881183) (xy 171.438031 -299.871339) (xy 171.487206 -299.869358)
			(xy 171.536061 -299.87529) (xy 171.583332 -299.888982) (xy 171.627794 -299.91008) (xy 171.668297 -299.938036)
			(xy 171.70379 -299.972128) (xy 171.733355 -300.011472) (xy 171.756226 -300.055049) (xy 171.77181 -300.10173)
			(xy 171.779705 -300.150307) (xy 171.7802 -300.174914) (xy 172.119048 -300.174914) (xy 172.123008 -300.12586)
			(xy 172.134785 -300.078076) (xy 172.154076 -300.0328) (xy 172.180379 -299.991204) (xy 172.213014 -299.954367)
			(xy 172.251135 -299.923242) (xy 172.293756 -299.898635) (xy 172.339772 -299.881183) (xy 172.387991 -299.871339)
			(xy 172.437166 -299.869358) (xy 172.486021 -299.87529) (xy 172.533292 -299.888982) (xy 172.577754 -299.91008)
			(xy 172.618257 -299.938036) (xy 172.65375 -299.972128) (xy 172.683315 -300.011472) (xy 172.706186 -300.055049)
			(xy 172.72177 -300.10173) (xy 172.729665 -300.150307) (xy 172.73016 -300.174914) (xy 173.069262 -300.174914)
			(xy 173.073222 -300.12586) (xy 173.084999 -300.078076) (xy 173.10429 -300.0328) (xy 173.130593 -299.991204)
			(xy 173.163228 -299.954367) (xy 173.201349 -299.923242) (xy 173.24397 -299.898635) (xy 173.289986 -299.881183)
			(xy 173.338205 -299.871339) (xy 173.38738 -299.869358) (xy 173.436235 -299.87529) (xy 173.483506 -299.888982)
			(xy 173.527968 -299.91008) (xy 173.568471 -299.938036) (xy 173.603964 -299.972128) (xy 173.633529 -300.011472)
			(xy 173.6564 -300.055049) (xy 173.671984 -300.10173) (xy 173.679879 -300.150307) (xy 173.680374 -300.174914)
			(xy 174.019222 -300.174914) (xy 174.023182 -300.12586) (xy 174.034959 -300.078076) (xy 174.05425 -300.0328)
			(xy 174.080553 -299.991204) (xy 174.113188 -299.954367) (xy 174.151309 -299.923242) (xy 174.19393 -299.898635)
			(xy 174.239946 -299.881183) (xy 174.288165 -299.871339) (xy 174.33734 -299.869358) (xy 174.386195 -299.87529)
			(xy 174.433466 -299.888982) (xy 174.477928 -299.91008) (xy 174.518431 -299.938036) (xy 174.553924 -299.972128)
			(xy 174.583489 -300.011472) (xy 174.60636 -300.055049) (xy 174.621944 -300.10173) (xy 174.629839 -300.150307)
			(xy 174.630334 -300.174914) (xy 175.919142 -300.174914) (xy 175.923102 -300.12586) (xy 175.934879 -300.078076)
			(xy 175.95417 -300.0328) (xy 175.980473 -299.991204) (xy 176.013108 -299.954367) (xy 176.051229 -299.923242)
			(xy 176.09385 -299.898635) (xy 176.139866 -299.881183) (xy 176.188085 -299.871339) (xy 176.23726 -299.869358)
			(xy 176.286115 -299.87529) (xy 176.333386 -299.888982) (xy 176.377848 -299.91008) (xy 176.418351 -299.938036)
			(xy 176.453844 -299.972128) (xy 176.483409 -300.011472) (xy 176.50628 -300.055049) (xy 176.521864 -300.10173)
			(xy 176.529759 -300.150307) (xy 176.530254 -300.174914) (xy 176.869102 -300.174914) (xy 176.873062 -300.12586)
			(xy 176.884839 -300.078076) (xy 176.90413 -300.0328) (xy 176.930433 -299.991204) (xy 176.963068 -299.954367)
			(xy 177.001189 -299.923242) (xy 177.04381 -299.898635) (xy 177.089826 -299.881183) (xy 177.138045 -299.871339)
			(xy 177.18722 -299.869358) (xy 177.236075 -299.87529) (xy 177.283346 -299.888982) (xy 177.327808 -299.91008)
			(xy 177.368311 -299.938036) (xy 177.403804 -299.972128) (xy 177.433369 -300.011472) (xy 177.45624 -300.055049)
			(xy 177.471824 -300.10173) (xy 177.479719 -300.150307) (xy 177.480214 -300.174914) (xy 177.819062 -300.174914)
			(xy 177.823022 -300.12586) (xy 177.834799 -300.078076) (xy 177.85409 -300.0328) (xy 177.880393 -299.991204)
			(xy 177.913028 -299.954367) (xy 177.951149 -299.923242) (xy 177.99377 -299.898635) (xy 178.039786 -299.881183)
			(xy 178.088005 -299.871339) (xy 178.13718 -299.869358) (xy 178.186035 -299.87529) (xy 178.233306 -299.888982)
			(xy 178.277768 -299.91008) (xy 178.318271 -299.938036) (xy 178.353764 -299.972128) (xy 178.383329 -300.011472)
			(xy 178.4062 -300.055049) (xy 178.421784 -300.10173) (xy 178.429679 -300.150307) (xy 178.430174 -300.174914)
			(xy 178.769276 -300.174914) (xy 178.773236 -300.12586) (xy 178.785013 -300.078076) (xy 178.804304 -300.0328)
			(xy 178.830607 -299.991204) (xy 178.863242 -299.954367) (xy 178.901363 -299.923242) (xy 178.943984 -299.898635)
			(xy 178.99 -299.881183) (xy 179.038219 -299.871339) (xy 179.087394 -299.869358) (xy 179.136249 -299.87529)
			(xy 179.18352 -299.888982) (xy 179.227982 -299.91008) (xy 179.268485 -299.938036) (xy 179.303978 -299.972128)
			(xy 179.333543 -300.011472) (xy 179.356414 -300.055049) (xy 179.371998 -300.10173) (xy 179.379893 -300.150307)
			(xy 179.380388 -300.174914) (xy 179.719236 -300.174914) (xy 179.723196 -300.12586) (xy 179.734973 -300.078076)
			(xy 179.754264 -300.0328) (xy 179.780567 -299.991204) (xy 179.813202 -299.954367) (xy 179.851323 -299.923242)
			(xy 179.893944 -299.898635) (xy 179.93996 -299.881183) (xy 179.988179 -299.871339) (xy 180.037354 -299.869358)
			(xy 180.086209 -299.87529) (xy 180.13348 -299.888982) (xy 180.177942 -299.91008) (xy 180.218445 -299.938036)
			(xy 180.253938 -299.972128) (xy 180.283503 -300.011472) (xy 180.306374 -300.055049) (xy 180.321958 -300.10173)
			(xy 180.329853 -300.150307) (xy 180.330348 -300.174914) (xy 180.669196 -300.174914) (xy 180.673156 -300.12586)
			(xy 180.684933 -300.078076) (xy 180.704224 -300.0328) (xy 180.730527 -299.991204) (xy 180.763162 -299.954367)
			(xy 180.801283 -299.923242) (xy 180.843904 -299.898635) (xy 180.88992 -299.881183) (xy 180.938139 -299.871339)
			(xy 180.987314 -299.869358) (xy 181.036169 -299.87529) (xy 181.08344 -299.888982) (xy 181.127902 -299.91008)
			(xy 181.168405 -299.938036) (xy 181.203898 -299.972128) (xy 181.233463 -300.011472) (xy 181.256334 -300.055049)
			(xy 181.271918 -300.10173) (xy 181.279813 -300.150307) (xy 181.280308 -300.174914) (xy 181.619156 -300.174914)
			(xy 181.623116 -300.12586) (xy 181.634893 -300.078076) (xy 181.654184 -300.0328) (xy 181.680487 -299.991204)
			(xy 181.713122 -299.954367) (xy 181.751243 -299.923242) (xy 181.793864 -299.898635) (xy 181.83988 -299.881183)
			(xy 181.888099 -299.871339) (xy 181.937274 -299.869358) (xy 181.986129 -299.87529) (xy 182.0334 -299.888982)
			(xy 182.077862 -299.91008) (xy 182.118365 -299.938036) (xy 182.153858 -299.972128) (xy 182.183423 -300.011472)
			(xy 182.206294 -300.055049) (xy 182.221878 -300.10173) (xy 182.229773 -300.150307) (xy 182.230268 -300.174914)
			(xy 182.569116 -300.174914) (xy 182.573076 -300.12586) (xy 182.584853 -300.078076) (xy 182.604144 -300.0328)
			(xy 182.630447 -299.991204) (xy 182.663082 -299.954367) (xy 182.701203 -299.923242) (xy 182.743824 -299.898635)
			(xy 182.78984 -299.881183) (xy 182.838059 -299.871339) (xy 182.887234 -299.869358) (xy 182.936089 -299.87529)
			(xy 182.98336 -299.888982) (xy 183.027822 -299.91008) (xy 183.068325 -299.938036) (xy 183.103818 -299.972128)
			(xy 183.133383 -300.011472) (xy 183.156254 -300.055049) (xy 183.171838 -300.10173) (xy 183.179733 -300.150307)
			(xy 183.180228 -300.174914) (xy 183.519076 -300.174914) (xy 183.523036 -300.12586) (xy 183.534813 -300.078076)
			(xy 183.554104 -300.0328) (xy 183.580407 -299.991204) (xy 183.613042 -299.954367) (xy 183.651163 -299.923242)
			(xy 183.693784 -299.898635) (xy 183.7398 -299.881183) (xy 183.788019 -299.871339) (xy 183.837194 -299.869358)
			(xy 183.886049 -299.87529) (xy 183.93332 -299.888982) (xy 183.977782 -299.91008) (xy 184.018285 -299.938036)
			(xy 184.053778 -299.972128) (xy 184.083343 -300.011472) (xy 184.106214 -300.055049) (xy 184.121798 -300.10173)
			(xy 184.129693 -300.150307) (xy 184.130188 -300.174914) (xy 184.469036 -300.174914) (xy 184.472996 -300.12586)
			(xy 184.484773 -300.078076) (xy 184.504064 -300.0328) (xy 184.530367 -299.991204) (xy 184.563002 -299.954367)
			(xy 184.601123 -299.923242) (xy 184.643744 -299.898635) (xy 184.68976 -299.881183) (xy 184.737979 -299.871339)
			(xy 184.787154 -299.869358) (xy 184.836009 -299.87529) (xy 184.88328 -299.888982) (xy 184.927742 -299.91008)
			(xy 184.968245 -299.938036) (xy 185.003738 -299.972128) (xy 185.033303 -300.011472) (xy 185.056174 -300.055049)
			(xy 185.071758 -300.10173) (xy 185.079653 -300.150307) (xy 185.080148 -300.174914) (xy 185.079653 -300.199521)
			(xy 185.071758 -300.248098) (xy 185.056174 -300.294779) (xy 185.033303 -300.338356) (xy 185.003738 -300.3777)
			(xy 184.968245 -300.411792) (xy 184.927742 -300.439748) (xy 184.88328 -300.460846) (xy 184.836009 -300.474538)
			(xy 184.787154 -300.48047) (xy 184.737979 -300.478489) (xy 184.68976 -300.468645) (xy 184.643744 -300.451193)
			(xy 184.601123 -300.426586) (xy 184.563002 -300.395461) (xy 184.530367 -300.358624) (xy 184.504064 -300.317028)
			(xy 184.484773 -300.271752) (xy 184.472996 -300.223968) (xy 184.469036 -300.174914) (xy 184.130188 -300.174914)
			(xy 184.129693 -300.199521) (xy 184.121798 -300.248098) (xy 184.106214 -300.294779) (xy 184.083343 -300.338356)
			(xy 184.053778 -300.3777) (xy 184.018285 -300.411792) (xy 183.977782 -300.439748) (xy 183.93332 -300.460846)
			(xy 183.886049 -300.474538) (xy 183.837194 -300.48047) (xy 183.788019 -300.478489) (xy 183.7398 -300.468645)
			(xy 183.693784 -300.451193) (xy 183.651163 -300.426586) (xy 183.613042 -300.395461) (xy 183.580407 -300.358624)
			(xy 183.554104 -300.317028) (xy 183.534813 -300.271752) (xy 183.523036 -300.223968) (xy 183.519076 -300.174914)
			(xy 183.180228 -300.174914) (xy 183.179733 -300.199521) (xy 183.171838 -300.248098) (xy 183.156254 -300.294779)
			(xy 183.133383 -300.338356) (xy 183.103818 -300.3777) (xy 183.068325 -300.411792) (xy 183.027822 -300.439748)
			(xy 182.98336 -300.460846) (xy 182.936089 -300.474538) (xy 182.887234 -300.48047) (xy 182.838059 -300.478489)
			(xy 182.78984 -300.468645) (xy 182.743824 -300.451193) (xy 182.701203 -300.426586) (xy 182.663082 -300.395461)
			(xy 182.630447 -300.358624) (xy 182.604144 -300.317028) (xy 182.584853 -300.271752) (xy 182.573076 -300.223968)
			(xy 182.569116 -300.174914) (xy 182.230268 -300.174914) (xy 182.229773 -300.199521) (xy 182.221878 -300.248098)
			(xy 182.206294 -300.294779) (xy 182.183423 -300.338356) (xy 182.153858 -300.3777) (xy 182.118365 -300.411792)
			(xy 182.077862 -300.439748) (xy 182.0334 -300.460846) (xy 181.986129 -300.474538) (xy 181.937274 -300.48047)
			(xy 181.888099 -300.478489) (xy 181.83988 -300.468645) (xy 181.793864 -300.451193) (xy 181.751243 -300.426586)
			(xy 181.713122 -300.395461) (xy 181.680487 -300.358624) (xy 181.654184 -300.317028) (xy 181.634893 -300.271752)
			(xy 181.623116 -300.223968) (xy 181.619156 -300.174914) (xy 181.280308 -300.174914) (xy 181.279813 -300.199521)
			(xy 181.271918 -300.248098) (xy 181.256334 -300.294779) (xy 181.233463 -300.338356) (xy 181.203898 -300.3777)
			(xy 181.168405 -300.411792) (xy 181.127902 -300.439748) (xy 181.08344 -300.460846) (xy 181.036169 -300.474538)
			(xy 180.987314 -300.48047) (xy 180.938139 -300.478489) (xy 180.88992 -300.468645) (xy 180.843904 -300.451193)
			(xy 180.801283 -300.426586) (xy 180.763162 -300.395461) (xy 180.730527 -300.358624) (xy 180.704224 -300.317028)
			(xy 180.684933 -300.271752) (xy 180.673156 -300.223968) (xy 180.669196 -300.174914) (xy 180.330348 -300.174914)
			(xy 180.329853 -300.199521) (xy 180.321958 -300.248098) (xy 180.306374 -300.294779) (xy 180.283503 -300.338356)
			(xy 180.253938 -300.3777) (xy 180.218445 -300.411792) (xy 180.177942 -300.439748) (xy 180.13348 -300.460846)
			(xy 180.086209 -300.474538) (xy 180.037354 -300.48047) (xy 179.988179 -300.478489) (xy 179.93996 -300.468645)
			(xy 179.893944 -300.451193) (xy 179.851323 -300.426586) (xy 179.813202 -300.395461) (xy 179.780567 -300.358624)
			(xy 179.754264 -300.317028) (xy 179.734973 -300.271752) (xy 179.723196 -300.223968) (xy 179.719236 -300.174914)
			(xy 179.380388 -300.174914) (xy 179.379893 -300.199521) (xy 179.371998 -300.248098) (xy 179.356414 -300.294779)
			(xy 179.333543 -300.338356) (xy 179.303978 -300.3777) (xy 179.268485 -300.411792) (xy 179.227982 -300.439748)
			(xy 179.18352 -300.460846) (xy 179.136249 -300.474538) (xy 179.087394 -300.48047) (xy 179.038219 -300.478489)
			(xy 178.99 -300.468645) (xy 178.943984 -300.451193) (xy 178.901363 -300.426586) (xy 178.863242 -300.395461)
			(xy 178.830607 -300.358624) (xy 178.804304 -300.317028) (xy 178.785013 -300.271752) (xy 178.773236 -300.223968)
			(xy 178.769276 -300.174914) (xy 178.430174 -300.174914) (xy 178.429679 -300.199521) (xy 178.421784 -300.248098)
			(xy 178.4062 -300.294779) (xy 178.383329 -300.338356) (xy 178.353764 -300.3777) (xy 178.318271 -300.411792)
			(xy 178.277768 -300.439748) (xy 178.233306 -300.460846) (xy 178.186035 -300.474538) (xy 178.13718 -300.48047)
			(xy 178.088005 -300.478489) (xy 178.039786 -300.468645) (xy 177.99377 -300.451193) (xy 177.951149 -300.426586)
			(xy 177.913028 -300.395461) (xy 177.880393 -300.358624) (xy 177.85409 -300.317028) (xy 177.834799 -300.271752)
			(xy 177.823022 -300.223968) (xy 177.819062 -300.174914) (xy 177.480214 -300.174914) (xy 177.479719 -300.199521)
			(xy 177.471824 -300.248098) (xy 177.45624 -300.294779) (xy 177.433369 -300.338356) (xy 177.403804 -300.3777)
			(xy 177.368311 -300.411792) (xy 177.327808 -300.439748) (xy 177.283346 -300.460846) (xy 177.236075 -300.474538)
			(xy 177.18722 -300.48047) (xy 177.138045 -300.478489) (xy 177.089826 -300.468645) (xy 177.04381 -300.451193)
			(xy 177.001189 -300.426586) (xy 176.963068 -300.395461) (xy 176.930433 -300.358624) (xy 176.90413 -300.317028)
			(xy 176.884839 -300.271752) (xy 176.873062 -300.223968) (xy 176.869102 -300.174914) (xy 176.530254 -300.174914)
			(xy 176.529759 -300.199521) (xy 176.521864 -300.248098) (xy 176.50628 -300.294779) (xy 176.483409 -300.338356)
			(xy 176.453844 -300.3777) (xy 176.418351 -300.411792) (xy 176.377848 -300.439748) (xy 176.333386 -300.460846)
			(xy 176.286115 -300.474538) (xy 176.23726 -300.48047) (xy 176.188085 -300.478489) (xy 176.139866 -300.468645)
			(xy 176.09385 -300.451193) (xy 176.051229 -300.426586) (xy 176.013108 -300.395461) (xy 175.980473 -300.358624)
			(xy 175.95417 -300.317028) (xy 175.934879 -300.271752) (xy 175.923102 -300.223968) (xy 175.919142 -300.174914)
			(xy 174.630334 -300.174914) (xy 174.629839 -300.199521) (xy 174.621944 -300.248098) (xy 174.60636 -300.294779)
			(xy 174.583489 -300.338356) (xy 174.553924 -300.3777) (xy 174.518431 -300.411792) (xy 174.477928 -300.439748)
			(xy 174.433466 -300.460846) (xy 174.386195 -300.474538) (xy 174.33734 -300.48047) (xy 174.288165 -300.478489)
			(xy 174.239946 -300.468645) (xy 174.19393 -300.451193) (xy 174.151309 -300.426586) (xy 174.113188 -300.395461)
			(xy 174.080553 -300.358624) (xy 174.05425 -300.317028) (xy 174.034959 -300.271752) (xy 174.023182 -300.223968)
			(xy 174.019222 -300.174914) (xy 173.680374 -300.174914) (xy 173.679879 -300.199521) (xy 173.671984 -300.248098)
			(xy 173.6564 -300.294779) (xy 173.633529 -300.338356) (xy 173.603964 -300.3777) (xy 173.568471 -300.411792)
			(xy 173.527968 -300.439748) (xy 173.483506 -300.460846) (xy 173.436235 -300.474538) (xy 173.38738 -300.48047)
			(xy 173.338205 -300.478489) (xy 173.289986 -300.468645) (xy 173.24397 -300.451193) (xy 173.201349 -300.426586)
			(xy 173.163228 -300.395461) (xy 173.130593 -300.358624) (xy 173.10429 -300.317028) (xy 173.084999 -300.271752)
			(xy 173.073222 -300.223968) (xy 173.069262 -300.174914) (xy 172.73016 -300.174914) (xy 172.729665 -300.199521)
			(xy 172.72177 -300.248098) (xy 172.706186 -300.294779) (xy 172.683315 -300.338356) (xy 172.65375 -300.3777)
			(xy 172.618257 -300.411792) (xy 172.577754 -300.439748) (xy 172.533292 -300.460846) (xy 172.486021 -300.474538)
			(xy 172.437166 -300.48047) (xy 172.387991 -300.478489) (xy 172.339772 -300.468645) (xy 172.293756 -300.451193)
			(xy 172.251135 -300.426586) (xy 172.213014 -300.395461) (xy 172.180379 -300.358624) (xy 172.154076 -300.317028)
			(xy 172.134785 -300.271752) (xy 172.123008 -300.223968) (xy 172.119048 -300.174914) (xy 171.7802 -300.174914)
			(xy 171.779705 -300.199521) (xy 171.77181 -300.248098) (xy 171.756226 -300.294779) (xy 171.733355 -300.338356)
			(xy 171.70379 -300.3777) (xy 171.668297 -300.411792) (xy 171.627794 -300.439748) (xy 171.583332 -300.460846)
			(xy 171.536061 -300.474538) (xy 171.487206 -300.48047) (xy 171.438031 -300.478489) (xy 171.389812 -300.468645)
			(xy 171.343796 -300.451193) (xy 171.301175 -300.426586) (xy 171.263054 -300.395461) (xy 171.230419 -300.358624)
			(xy 171.204116 -300.317028) (xy 171.184825 -300.271752) (xy 171.173048 -300.223968) (xy 171.169088 -300.174914)
			(xy 170.83024 -300.174914) (xy 170.829745 -300.199521) (xy 170.82185 -300.248098) (xy 170.806266 -300.294779)
			(xy 170.783395 -300.338356) (xy 170.75383 -300.3777) (xy 170.718337 -300.411792) (xy 170.677834 -300.439748)
			(xy 170.633372 -300.460846) (xy 170.586101 -300.474538) (xy 170.537246 -300.48047) (xy 170.488071 -300.478489)
			(xy 170.439852 -300.468645) (xy 170.393836 -300.451193) (xy 170.351215 -300.426586) (xy 170.313094 -300.395461)
			(xy 170.280459 -300.358624) (xy 170.254156 -300.317028) (xy 170.234865 -300.271752) (xy 170.223088 -300.223968)
			(xy 170.219128 -300.174914) (xy 169.88028 -300.174914) (xy 169.879785 -300.199521) (xy 169.87189 -300.248098)
			(xy 169.856306 -300.294779) (xy 169.833435 -300.338356) (xy 169.80387 -300.3777) (xy 169.768377 -300.411792)
			(xy 169.727874 -300.439748) (xy 169.683412 -300.460846) (xy 169.636141 -300.474538) (xy 169.587286 -300.48047)
			(xy 169.538111 -300.478489) (xy 169.489892 -300.468645) (xy 169.443876 -300.451193) (xy 169.401255 -300.426586)
			(xy 169.363134 -300.395461) (xy 169.330499 -300.358624) (xy 169.304196 -300.317028) (xy 169.284905 -300.271752)
			(xy 169.273128 -300.223968) (xy 169.269168 -300.174914) (xy 168.93032 -300.174914) (xy 168.929825 -300.199521)
			(xy 168.92193 -300.248098) (xy 168.906346 -300.294779) (xy 168.883475 -300.338356) (xy 168.85391 -300.3777)
			(xy 168.818417 -300.411792) (xy 168.777914 -300.439748) (xy 168.733452 -300.460846) (xy 168.686181 -300.474538)
			(xy 168.637326 -300.48047) (xy 168.588151 -300.478489) (xy 168.539932 -300.468645) (xy 168.493916 -300.451193)
			(xy 168.451295 -300.426586) (xy 168.413174 -300.395461) (xy 168.380539 -300.358624) (xy 168.354236 -300.317028)
			(xy 168.334945 -300.271752) (xy 168.323168 -300.223968) (xy 168.319208 -300.174914) (xy 167.98036 -300.174914)
			(xy 167.979865 -300.199521) (xy 167.97197 -300.248098) (xy 167.956386 -300.294779) (xy 167.933515 -300.338356)
			(xy 167.90395 -300.3777) (xy 167.868457 -300.411792) (xy 167.827954 -300.439748) (xy 167.783492 -300.460846)
			(xy 167.736221 -300.474538) (xy 167.687366 -300.48047) (xy 167.638191 -300.478489) (xy 167.589972 -300.468645)
			(xy 167.543956 -300.451193) (xy 167.501335 -300.426586) (xy 167.463214 -300.395461) (xy 167.430579 -300.358624)
			(xy 167.404276 -300.317028) (xy 167.384985 -300.271752) (xy 167.373208 -300.223968) (xy 167.369248 -300.174914)
			(xy 167.0304 -300.174914) (xy 167.029905 -300.199521) (xy 167.02201 -300.248098) (xy 167.006426 -300.294779)
			(xy 166.983555 -300.338356) (xy 166.95399 -300.3777) (xy 166.918497 -300.411792) (xy 166.877994 -300.439748)
			(xy 166.833532 -300.460846) (xy 166.786261 -300.474538) (xy 166.737406 -300.48047) (xy 166.688231 -300.478489)
			(xy 166.640012 -300.468645) (xy 166.593996 -300.451193) (xy 166.551375 -300.426586) (xy 166.513254 -300.395461)
			(xy 166.480619 -300.358624) (xy 166.454316 -300.317028) (xy 166.435025 -300.271752) (xy 166.423248 -300.223968)
			(xy 166.419288 -300.174914) (xy 165.130226 -300.174914) (xy 165.129731 -300.199521) (xy 165.121836 -300.248098)
			(xy 165.106252 -300.294779) (xy 165.083381 -300.338356) (xy 165.053816 -300.3777) (xy 165.018323 -300.411792)
			(xy 164.97782 -300.439748) (xy 164.933358 -300.460846) (xy 164.886087 -300.474538) (xy 164.837232 -300.48047)
			(xy 164.788057 -300.478489) (xy 164.739838 -300.468645) (xy 164.693822 -300.451193) (xy 164.651201 -300.426586)
			(xy 164.61308 -300.395461) (xy 164.580445 -300.358624) (xy 164.554142 -300.317028) (xy 164.534851 -300.271752)
			(xy 164.523074 -300.223968) (xy 164.519114 -300.174914) (xy 164.180266 -300.174914) (xy 164.179771 -300.199521)
			(xy 164.171876 -300.248098) (xy 164.156292 -300.294779) (xy 164.133421 -300.338356) (xy 164.103856 -300.3777)
			(xy 164.068363 -300.411792) (xy 164.02786 -300.439748) (xy 163.983398 -300.460846) (xy 163.936127 -300.474538)
			(xy 163.887272 -300.48047) (xy 163.838097 -300.478489) (xy 163.789878 -300.468645) (xy 163.743862 -300.451193)
			(xy 163.701241 -300.426586) (xy 163.66312 -300.395461) (xy 163.630485 -300.358624) (xy 163.604182 -300.317028)
			(xy 163.584891 -300.271752) (xy 163.573114 -300.223968) (xy 163.569154 -300.174914) (xy 162.280346 -300.174914)
			(xy 162.279851 -300.199521) (xy 162.271956 -300.248098) (xy 162.256372 -300.294779) (xy 162.233501 -300.338356)
			(xy 162.203936 -300.3777) (xy 162.168443 -300.411792) (xy 162.12794 -300.439748) (xy 162.083478 -300.460846)
			(xy 162.036207 -300.474538) (xy 161.987352 -300.48047) (xy 161.938177 -300.478489) (xy 161.889958 -300.468645)
			(xy 161.843942 -300.451193) (xy 161.801321 -300.426586) (xy 161.7632 -300.395461) (xy 161.730565 -300.358624)
			(xy 161.704262 -300.317028) (xy 161.684971 -300.271752) (xy 161.673194 -300.223968) (xy 161.669234 -300.174914)
			(xy 161.330386 -300.174914) (xy 161.329891 -300.199521) (xy 161.321996 -300.248098) (xy 161.306412 -300.294779)
			(xy 161.283541 -300.338356) (xy 161.253976 -300.3777) (xy 161.218483 -300.411792) (xy 161.17798 -300.439748)
			(xy 161.133518 -300.460846) (xy 161.086247 -300.474538) (xy 161.037392 -300.48047) (xy 160.988217 -300.478489)
			(xy 160.939998 -300.468645) (xy 160.893982 -300.451193) (xy 160.851361 -300.426586) (xy 160.81324 -300.395461)
			(xy 160.780605 -300.358624) (xy 160.754302 -300.317028) (xy 160.735011 -300.271752) (xy 160.723234 -300.223968)
			(xy 160.719274 -300.174914) (xy 160.380183 -300.174914) (xy 160.380632 -300.183202) (xy 160.375261 -300.232556)
			(xy 160.361976 -300.280391) (xy 160.341127 -300.325447) (xy 160.313263 -300.366536) (xy 160.279118 -300.402575)
			(xy 160.239593 -300.432616) (xy 160.195728 -300.455866) (xy 160.14868 -300.471713) (xy 160.099687 -300.479739)
			(xy 160.074864 -300.480222) (xy 160.060681 -300.48005) (xy 160.032441 -300.477375) (xy 160.018476 -300.474888)
			(xy 160.004514 -300.472693) (xy 159.976379 -300.475278) (xy 159.950029 -300.485473) (xy 159.927482 -300.502499)
			(xy 159.910462 -300.52505) (xy 159.900273 -300.551403) (xy 159.897694 -300.579538) (xy 159.899858 -300.593506)
			(xy 159.902331 -300.607472) (xy 159.905005 -300.635712) (xy 159.905192 -300.649894) (xy 159.904729 -300.674715)
			(xy 159.896698 -300.723704) (xy 159.880849 -300.770748) (xy 159.857597 -300.814608) (xy 159.827555 -300.854129)
			(xy 159.791516 -300.888268) (xy 159.750428 -300.916128) (xy 159.705375 -300.936974) (xy 159.657542 -300.950256)
			(xy 159.608191 -300.955625) (xy 159.558622 -300.952939) (xy 159.510139 -300.942268) (xy 159.464022 -300.923895)
			(xy 159.421485 -300.898304) (xy 159.383648 -300.866167) (xy 159.351509 -300.828333) (xy 159.325914 -300.785797)
			(xy 159.307538 -300.739682) (xy 159.296864 -300.6912) (xy 159.294175 -300.641631) (xy 158.955066 -300.641631)
			(xy 158.955232 -300.649894) (xy 158.954737 -300.674501) (xy 158.946842 -300.723078) (xy 158.931258 -300.769759)
			(xy 158.908387 -300.813336) (xy 158.878822 -300.85268) (xy 158.843329 -300.886772) (xy 158.802826 -300.914728)
			(xy 158.758364 -300.935826) (xy 158.711093 -300.949518) (xy 158.662238 -300.95545) (xy 158.613063 -300.953469)
			(xy 158.564844 -300.943625) (xy 158.518828 -300.926173) (xy 158.476207 -300.901566) (xy 158.438086 -300.870441)
			(xy 158.405451 -300.833604) (xy 158.379148 -300.792008) (xy 158.359857 -300.746732) (xy 158.34808 -300.698948)
			(xy 158.34412 -300.649894) (xy 158.005272 -300.649894) (xy 158.004777 -300.674501) (xy 157.996882 -300.723078)
			(xy 157.981298 -300.769759) (xy 157.958427 -300.813336) (xy 157.928862 -300.85268) (xy 157.893369 -300.886772)
			(xy 157.852866 -300.914728) (xy 157.808404 -300.935826) (xy 157.761133 -300.949518) (xy 157.712278 -300.95545)
			(xy 157.663103 -300.953469) (xy 157.614884 -300.943625) (xy 157.568868 -300.926173) (xy 157.526247 -300.901566)
			(xy 157.488126 -300.870441) (xy 157.455491 -300.833604) (xy 157.429188 -300.792008) (xy 157.409897 -300.746732)
			(xy 157.39812 -300.698948) (xy 157.39416 -300.649894) (xy 157.055312 -300.649894) (xy 157.054817 -300.674501)
			(xy 157.046922 -300.723078) (xy 157.031338 -300.769759) (xy 157.008467 -300.813336) (xy 156.978902 -300.85268)
			(xy 156.943409 -300.886772) (xy 156.902906 -300.914728) (xy 156.858444 -300.935826) (xy 156.811173 -300.949518)
			(xy 156.762318 -300.95545) (xy 156.713143 -300.953469) (xy 156.664924 -300.943625) (xy 156.618908 -300.926173)
			(xy 156.576287 -300.901566) (xy 156.538166 -300.870441) (xy 156.505531 -300.833604) (xy 156.479228 -300.792008)
			(xy 156.459937 -300.746732) (xy 156.44816 -300.698948) (xy 156.4442 -300.649894) (xy 156.105352 -300.649894)
			(xy 156.104857 -300.674501) (xy 156.096962 -300.723078) (xy 156.081378 -300.769759) (xy 156.058507 -300.813336)
			(xy 156.028942 -300.85268) (xy 155.993449 -300.886772) (xy 155.952946 -300.914728) (xy 155.908484 -300.935826)
			(xy 155.861213 -300.949518) (xy 155.812358 -300.95545) (xy 155.763183 -300.953469) (xy 155.714964 -300.943625)
			(xy 155.668948 -300.926173) (xy 155.626327 -300.901566) (xy 155.588206 -300.870441) (xy 155.555571 -300.833604)
			(xy 155.529268 -300.792008) (xy 155.509977 -300.746732) (xy 155.4982 -300.698948) (xy 155.49424 -300.649894)
			(xy 155.155392 -300.649894) (xy 155.154897 -300.674501) (xy 155.147002 -300.723078) (xy 155.131418 -300.769759)
			(xy 155.108547 -300.813336) (xy 155.078982 -300.85268) (xy 155.043489 -300.886772) (xy 155.002986 -300.914728)
			(xy 154.958524 -300.935826) (xy 154.911253 -300.949518) (xy 154.862398 -300.95545) (xy 154.813223 -300.953469)
			(xy 154.765004 -300.943625) (xy 154.718988 -300.926173) (xy 154.676367 -300.901566) (xy 154.638246 -300.870441)
			(xy 154.605611 -300.833604) (xy 154.579308 -300.792008) (xy 154.560017 -300.746732) (xy 154.54824 -300.698948)
			(xy 154.54428 -300.649894) (xy 154.205178 -300.649894) (xy 154.204683 -300.674501) (xy 154.196788 -300.723078)
			(xy 154.181204 -300.769759) (xy 154.158333 -300.813336) (xy 154.128768 -300.85268) (xy 154.093275 -300.886772)
			(xy 154.052772 -300.914728) (xy 154.00831 -300.935826) (xy 153.961039 -300.949518) (xy 153.912184 -300.95545)
			(xy 153.863009 -300.953469) (xy 153.81479 -300.943625) (xy 153.768774 -300.926173) (xy 153.726153 -300.901566)
			(xy 153.688032 -300.870441) (xy 153.655397 -300.833604) (xy 153.629094 -300.792008) (xy 153.609803 -300.746732)
			(xy 153.598026 -300.698948) (xy 153.594066 -300.649894) (xy 153.255218 -300.649894) (xy 153.254723 -300.674501)
			(xy 153.246828 -300.723078) (xy 153.231244 -300.769759) (xy 153.208373 -300.813336) (xy 153.178808 -300.85268)
			(xy 153.143315 -300.886772) (xy 153.102812 -300.914728) (xy 153.05835 -300.935826) (xy 153.011079 -300.949518)
			(xy 152.962224 -300.95545) (xy 152.913049 -300.953469) (xy 152.86483 -300.943625) (xy 152.818814 -300.926173)
			(xy 152.776193 -300.901566) (xy 152.738072 -300.870441) (xy 152.705437 -300.833604) (xy 152.679134 -300.792008)
			(xy 152.659843 -300.746732) (xy 152.648066 -300.698948) (xy 152.644106 -300.649894) (xy 143.792693 -300.649894)
			(xy 143.848121 -300.655993) (xy 143.902078 -300.670099) (xy 143.953407 -300.691911) (xy 144.001013 -300.720965)
			(xy 144.043881 -300.75664) (xy 144.081098 -300.798177) (xy 144.111871 -300.84469) (xy 144.135543 -300.895187)
			(xy 144.151611 -300.948594) (xy 144.159731 -301.00377) (xy 144.16024 -301.031656) (xy 144.159731 -301.059542)
			(xy 144.151611 -301.114718) (xy 144.135543 -301.168125) (xy 144.111871 -301.218622) (xy 144.081098 -301.265135)
			(xy 144.043881 -301.306672) (xy 144.001013 -301.342347) (xy 143.953407 -301.371401) (xy 143.902078 -301.393213)
			(xy 143.848121 -301.407319) (xy 143.792684 -301.413419) (xy 143.73695 -301.411382) (xy 143.682107 -301.401252)
			(xy 143.629323 -301.383245) (xy 143.579723 -301.357744) (xy 143.534365 -301.325293) (xy 143.494216 -301.286584)
			(xy 143.46013 -301.242441) (xy 143.432834 -301.193806) (xy 143.412911 -301.141715) (xy 143.400785 -301.087278)
			(xy 143.396714 -301.031656) (xy 142.675102 -301.031656) (xy 142.674593 -301.059542) (xy 142.666473 -301.114718)
			(xy 142.650405 -301.168125) (xy 142.626733 -301.218622) (xy 142.59596 -301.265135) (xy 142.558743 -301.306672)
			(xy 142.515875 -301.342347) (xy 142.468269 -301.371401) (xy 142.41694 -301.393213) (xy 142.362983 -301.407319)
			(xy 142.307546 -301.413419) (xy 142.251812 -301.411382) (xy 142.196969 -301.401252) (xy 142.144185 -301.383245)
			(xy 142.094585 -301.357744) (xy 142.049227 -301.325293) (xy 142.009078 -301.286584) (xy 141.974992 -301.242441)
			(xy 141.947696 -301.193806) (xy 141.927773 -301.141715) (xy 141.915647 -301.087278) (xy 141.911576 -301.031656)
			(xy 118.832884 -301.031656) (xy 118.832884 -301.599854) (xy 152.644106 -301.599854) (xy 152.648066 -301.5508)
			(xy 152.659843 -301.503016) (xy 152.679134 -301.45774) (xy 152.705437 -301.416144) (xy 152.738072 -301.379307)
			(xy 152.776193 -301.348182) (xy 152.818814 -301.323575) (xy 152.86483 -301.306123) (xy 152.913049 -301.296279)
			(xy 152.962224 -301.294298) (xy 153.011079 -301.30023) (xy 153.05835 -301.313922) (xy 153.102812 -301.33502)
			(xy 153.143315 -301.362976) (xy 153.178808 -301.397068) (xy 153.208373 -301.436412) (xy 153.231244 -301.479989)
			(xy 153.246828 -301.52667) (xy 153.254723 -301.575247) (xy 153.255218 -301.599854) (xy 153.594066 -301.599854)
			(xy 153.598026 -301.5508) (xy 153.609803 -301.503016) (xy 153.629094 -301.45774) (xy 153.655397 -301.416144)
			(xy 153.688032 -301.379307) (xy 153.726153 -301.348182) (xy 153.768774 -301.323575) (xy 153.81479 -301.306123)
			(xy 153.863009 -301.296279) (xy 153.912184 -301.294298) (xy 153.961039 -301.30023) (xy 154.00831 -301.313922)
			(xy 154.052772 -301.33502) (xy 154.093275 -301.362976) (xy 154.128768 -301.397068) (xy 154.158333 -301.436412)
			(xy 154.181204 -301.479989) (xy 154.196788 -301.52667) (xy 154.204683 -301.575247) (xy 154.205178 -301.599854)
			(xy 154.204683 -301.624461) (xy 154.204504 -301.625562) (xy 154.523436 -301.625562) (xy 154.523436 -301.574146)
			(xy 154.531479 -301.523364) (xy 154.547367 -301.474465) (xy 154.57071 -301.428653) (xy 154.600931 -301.387057)
			(xy 154.637287 -301.350701) (xy 154.678883 -301.32048) (xy 154.724695 -301.297137) (xy 154.773594 -301.281249)
			(xy 154.824376 -301.273206) (xy 154.875792 -301.273206) (xy 154.926574 -301.281249) (xy 154.975473 -301.297137)
			(xy 155.021285 -301.32048) (xy 155.062881 -301.350701) (xy 155.099237 -301.387057) (xy 155.129458 -301.428653)
			(xy 155.152801 -301.474465) (xy 155.168689 -301.523364) (xy 155.176732 -301.574146) (xy 155.177236 -301.599854)
			(xy 155.176732 -301.625562) (xy 155.473396 -301.625562) (xy 155.473396 -301.574146) (xy 155.481439 -301.523364)
			(xy 155.497327 -301.474465) (xy 155.52067 -301.428653) (xy 155.550891 -301.387057) (xy 155.587247 -301.350701)
			(xy 155.628843 -301.32048) (xy 155.674655 -301.297137) (xy 155.723554 -301.281249) (xy 155.774336 -301.273206)
			(xy 155.825752 -301.273206) (xy 155.876534 -301.281249) (xy 155.925433 -301.297137) (xy 155.971245 -301.32048)
			(xy 156.012841 -301.350701) (xy 156.049197 -301.387057) (xy 156.079418 -301.428653) (xy 156.102761 -301.474465)
			(xy 156.118649 -301.523364) (xy 156.126692 -301.574146) (xy 156.127196 -301.599854) (xy 156.4442 -301.599854)
			(xy 156.44816 -301.5508) (xy 156.459937 -301.503016) (xy 156.479228 -301.45774) (xy 156.505531 -301.416144)
			(xy 156.538166 -301.379307) (xy 156.576287 -301.348182) (xy 156.618908 -301.323575) (xy 156.664924 -301.306123)
			(xy 156.713143 -301.296279) (xy 156.762318 -301.294298) (xy 156.811173 -301.30023) (xy 156.858444 -301.313922)
			(xy 156.902906 -301.33502) (xy 156.943409 -301.362976) (xy 156.978902 -301.397068) (xy 157.008467 -301.436412)
			(xy 157.031338 -301.479989) (xy 157.046922 -301.52667) (xy 157.054817 -301.575247) (xy 157.055312 -301.599854)
			(xy 157.054817 -301.624461) (xy 157.054638 -301.625562) (xy 157.373316 -301.625562) (xy 157.373316 -301.574146)
			(xy 157.381359 -301.523364) (xy 157.397247 -301.474465) (xy 157.42059 -301.428653) (xy 157.450811 -301.387057)
			(xy 157.487167 -301.350701) (xy 157.528763 -301.32048) (xy 157.574575 -301.297137) (xy 157.623474 -301.281249)
			(xy 157.674256 -301.273206) (xy 157.725672 -301.273206) (xy 157.776454 -301.281249) (xy 157.825353 -301.297137)
			(xy 157.871165 -301.32048) (xy 157.912761 -301.350701) (xy 157.949117 -301.387057) (xy 157.979338 -301.428653)
			(xy 158.002681 -301.474465) (xy 158.018569 -301.523364) (xy 158.026612 -301.574146) (xy 158.027116 -301.599854)
			(xy 158.026612 -301.625562) (xy 158.323276 -301.625562) (xy 158.323276 -301.574146) (xy 158.331319 -301.523364)
			(xy 158.347207 -301.474465) (xy 158.37055 -301.428653) (xy 158.400771 -301.387057) (xy 158.437127 -301.350701)
			(xy 158.478723 -301.32048) (xy 158.524535 -301.297137) (xy 158.573434 -301.281249) (xy 158.624216 -301.273206)
			(xy 158.675632 -301.273206) (xy 158.726414 -301.281249) (xy 158.775313 -301.297137) (xy 158.821125 -301.32048)
			(xy 158.862721 -301.350701) (xy 158.899077 -301.387057) (xy 158.929298 -301.428653) (xy 158.952641 -301.474465)
			(xy 158.968529 -301.523364) (xy 158.976572 -301.574146) (xy 158.977076 -301.599854) (xy 159.29408 -301.599854)
			(xy 159.29804 -301.5508) (xy 159.309817 -301.503016) (xy 159.329108 -301.45774) (xy 159.355411 -301.416144)
			(xy 159.388046 -301.379307) (xy 159.426167 -301.348182) (xy 159.468788 -301.323575) (xy 159.514804 -301.306123)
			(xy 159.563023 -301.296279) (xy 159.612198 -301.294298) (xy 159.661053 -301.30023) (xy 159.708324 -301.313922)
			(xy 159.752786 -301.33502) (xy 159.793289 -301.362976) (xy 159.828782 -301.397068) (xy 159.858347 -301.436412)
			(xy 159.881218 -301.479989) (xy 159.896802 -301.52667) (xy 159.904697 -301.575247) (xy 159.905026 -301.591602)
			(xy 160.244035 -301.591602) (xy 160.249406 -301.542241) (xy 160.262692 -301.4944) (xy 160.283544 -301.449338)
			(xy 160.311412 -301.408244) (xy 160.345561 -301.372199) (xy 160.385092 -301.342155) (xy 160.428963 -301.318903)
			(xy 160.476018 -301.303054) (xy 160.525018 -301.295028) (xy 160.549844 -301.294546) (xy 160.564091 -301.294708)
			(xy 160.592459 -301.297381) (xy 160.606486 -301.29988) (xy 160.618678 -301.302166) (xy 160.642808 -301.2948)
			(xy 160.720024 -301.217584) (xy 160.72739 -301.193708) (xy 160.725104 -301.181262) (xy 160.722626 -301.167296)
			(xy 160.719955 -301.139057) (xy 160.71977 -301.124874) (xy 160.720292 -301.099619) (xy 160.728605 -301.049797)
			(xy 160.745006 -301.002023) (xy 160.769047 -300.9576) (xy 160.800071 -300.91774) (xy 160.837233 -300.88353)
			(xy 160.879519 -300.855904) (xy 160.925775 -300.835614) (xy 160.97474 -300.823214) (xy 161.025078 -300.819043)
			(xy 161.075416 -300.823214) (xy 161.124381 -300.835614) (xy 161.170637 -300.855904) (xy 161.212923 -300.88353)
			(xy 161.250085 -300.91774) (xy 161.281109 -300.9576) (xy 161.30515 -301.002023) (xy 161.321551 -301.049797)
			(xy 161.329864 -301.099619) (xy 161.330386 -301.124874) (xy 161.330206 -301.139057) (xy 161.327536 -301.167297)
			(xy 161.325052 -301.181262) (xy 161.322766 -301.193708) (xy 161.330132 -301.21733) (xy 161.407602 -301.2948)
			(xy 161.431224 -301.302166) (xy 161.44367 -301.29988) (xy 161.457635 -301.297398) (xy 161.485875 -301.29473)
			(xy 161.500058 -301.294546) (xy 161.514241 -301.294729) (xy 161.542481 -301.297397) (xy 161.556446 -301.29988)
			(xy 161.568892 -301.302166) (xy 161.592514 -301.2948) (xy 161.669984 -301.21733) (xy 161.67735 -301.193708)
			(xy 161.675064 -301.181262) (xy 161.672587 -301.167296) (xy 161.669915 -301.139057) (xy 161.66973 -301.124874)
			(xy 161.670206 -301.100056) (xy 161.67824 -301.051076) (xy 161.694092 -301.00404) (xy 161.717344 -300.960188)
			(xy 161.747384 -300.920675) (xy 161.783421 -300.886543) (xy 161.824505 -300.85869) (xy 161.869553 -300.83785)
			(xy 161.91738 -300.824573) (xy 161.966724 -300.819207) (xy 162.016286 -300.821895) (xy 162.064761 -300.832565)
			(xy 162.110871 -300.850937) (xy 162.153402 -300.876526) (xy 162.191233 -300.908659) (xy 162.223367 -300.946488)
			(xy 162.248958 -300.989018) (xy 162.267331 -301.035127) (xy 162.278004 -301.083602) (xy 162.280243 -301.124874)
			(xy 162.619194 -301.124874) (xy 162.623154 -301.07582) (xy 162.634931 -301.028036) (xy 162.654222 -300.98276)
			(xy 162.680525 -300.941164) (xy 162.71316 -300.904327) (xy 162.751281 -300.873202) (xy 162.793902 -300.848595)
			(xy 162.839918 -300.831143) (xy 162.888137 -300.821299) (xy 162.937312 -300.819318) (xy 162.986167 -300.82525)
			(xy 163.033438 -300.838942) (xy 163.0779 -300.86004) (xy 163.118403 -300.887996) (xy 163.153896 -300.922088)
			(xy 163.183461 -300.961432) (xy 163.206332 -301.005009) (xy 163.221916 -301.05169) (xy 163.229811 -301.100267)
			(xy 163.230306 -301.124874) (xy 163.569154 -301.124874) (xy 163.573114 -301.07582) (xy 163.584891 -301.028036)
			(xy 163.604182 -300.98276) (xy 163.630485 -300.941164) (xy 163.66312 -300.904327) (xy 163.701241 -300.873202)
			(xy 163.743862 -300.848595) (xy 163.789878 -300.831143) (xy 163.838097 -300.821299) (xy 163.887272 -300.819318)
			(xy 163.936127 -300.82525) (xy 163.983398 -300.838942) (xy 164.02786 -300.86004) (xy 164.068363 -300.887996)
			(xy 164.103856 -300.922088) (xy 164.133421 -300.961432) (xy 164.156292 -301.005009) (xy 164.171876 -301.05169)
			(xy 164.179771 -301.100267) (xy 164.180266 -301.124874) (xy 165.469074 -301.124874) (xy 165.473034 -301.07582)
			(xy 165.484811 -301.028036) (xy 165.504102 -300.98276) (xy 165.530405 -300.941164) (xy 165.56304 -300.904327)
			(xy 165.601161 -300.873202) (xy 165.643782 -300.848595) (xy 165.689798 -300.831143) (xy 165.738017 -300.821299)
			(xy 165.787192 -300.819318) (xy 165.836047 -300.82525) (xy 165.883318 -300.838942) (xy 165.92778 -300.86004)
			(xy 165.968283 -300.887996) (xy 166.003776 -300.922088) (xy 166.033341 -300.961432) (xy 166.056212 -301.005009)
			(xy 166.071796 -301.05169) (xy 166.079691 -301.100267) (xy 166.080186 -301.124874) (xy 166.419288 -301.124874)
			(xy 166.423248 -301.07582) (xy 166.435025 -301.028036) (xy 166.454316 -300.98276) (xy 166.480619 -300.941164)
			(xy 166.513254 -300.904327) (xy 166.551375 -300.873202) (xy 166.593996 -300.848595) (xy 166.640012 -300.831143)
			(xy 166.688231 -300.821299) (xy 166.737406 -300.819318) (xy 166.786261 -300.82525) (xy 166.833532 -300.838942)
			(xy 166.877994 -300.86004) (xy 166.918497 -300.887996) (xy 166.95399 -300.922088) (xy 166.983555 -300.961432)
			(xy 167.006426 -301.005009) (xy 167.02201 -301.05169) (xy 167.029905 -301.100267) (xy 167.0304 -301.124874)
			(xy 167.369248 -301.124874) (xy 167.373208 -301.07582) (xy 167.384985 -301.028036) (xy 167.404276 -300.98276)
			(xy 167.430579 -300.941164) (xy 167.463214 -300.904327) (xy 167.501335 -300.873202) (xy 167.543956 -300.848595)
			(xy 167.589972 -300.831143) (xy 167.638191 -300.821299) (xy 167.687366 -300.819318) (xy 167.736221 -300.82525)
			(xy 167.783492 -300.838942) (xy 167.827954 -300.86004) (xy 167.868457 -300.887996) (xy 167.90395 -300.922088)
			(xy 167.933515 -300.961432) (xy 167.956386 -301.005009) (xy 167.97197 -301.05169) (xy 167.979865 -301.100267)
			(xy 167.98036 -301.124874) (xy 168.319208 -301.124874) (xy 168.323168 -301.07582) (xy 168.334945 -301.028036)
			(xy 168.354236 -300.98276) (xy 168.380539 -300.941164) (xy 168.413174 -300.904327) (xy 168.451295 -300.873202)
			(xy 168.493916 -300.848595) (xy 168.539932 -300.831143) (xy 168.588151 -300.821299) (xy 168.637326 -300.819318)
			(xy 168.686181 -300.82525) (xy 168.733452 -300.838942) (xy 168.777914 -300.86004) (xy 168.818417 -300.887996)
			(xy 168.85391 -300.922088) (xy 168.883475 -300.961432) (xy 168.906346 -301.005009) (xy 168.92193 -301.05169)
			(xy 168.929825 -301.100267) (xy 168.93032 -301.124874) (xy 169.269168 -301.124874) (xy 169.273128 -301.07582)
			(xy 169.284905 -301.028036) (xy 169.304196 -300.98276) (xy 169.330499 -300.941164) (xy 169.363134 -300.904327)
			(xy 169.401255 -300.873202) (xy 169.443876 -300.848595) (xy 169.489892 -300.831143) (xy 169.538111 -300.821299)
			(xy 169.587286 -300.819318) (xy 169.636141 -300.82525) (xy 169.683412 -300.838942) (xy 169.727874 -300.86004)
			(xy 169.768377 -300.887996) (xy 169.80387 -300.922088) (xy 169.833435 -300.961432) (xy 169.856306 -301.005009)
			(xy 169.87189 -301.05169) (xy 169.879785 -301.100267) (xy 169.88028 -301.124874) (xy 170.219128 -301.124874)
			(xy 170.223088 -301.07582) (xy 170.234865 -301.028036) (xy 170.254156 -300.98276) (xy 170.280459 -300.941164)
			(xy 170.313094 -300.904327) (xy 170.351215 -300.873202) (xy 170.393836 -300.848595) (xy 170.439852 -300.831143)
			(xy 170.488071 -300.821299) (xy 170.537246 -300.819318) (xy 170.586101 -300.82525) (xy 170.633372 -300.838942)
			(xy 170.677834 -300.86004) (xy 170.718337 -300.887996) (xy 170.75383 -300.922088) (xy 170.783395 -300.961432)
			(xy 170.806266 -301.005009) (xy 170.82185 -301.05169) (xy 170.829745 -301.100267) (xy 170.83024 -301.124874)
			(xy 171.169088 -301.124874) (xy 171.173048 -301.07582) (xy 171.184825 -301.028036) (xy 171.204116 -300.98276)
			(xy 171.230419 -300.941164) (xy 171.263054 -300.904327) (xy 171.301175 -300.873202) (xy 171.343796 -300.848595)
			(xy 171.389812 -300.831143) (xy 171.438031 -300.821299) (xy 171.487206 -300.819318) (xy 171.536061 -300.82525)
			(xy 171.583332 -300.838942) (xy 171.627794 -300.86004) (xy 171.668297 -300.887996) (xy 171.70379 -300.922088)
			(xy 171.733355 -300.961432) (xy 171.756226 -301.005009) (xy 171.77181 -301.05169) (xy 171.779705 -301.100267)
			(xy 171.7802 -301.124874) (xy 172.119048 -301.124874) (xy 172.123008 -301.07582) (xy 172.134785 -301.028036)
			(xy 172.154076 -300.98276) (xy 172.180379 -300.941164) (xy 172.213014 -300.904327) (xy 172.251135 -300.873202)
			(xy 172.293756 -300.848595) (xy 172.339772 -300.831143) (xy 172.387991 -300.821299) (xy 172.437166 -300.819318)
			(xy 172.486021 -300.82525) (xy 172.533292 -300.838942) (xy 172.577754 -300.86004) (xy 172.618257 -300.887996)
			(xy 172.65375 -300.922088) (xy 172.683315 -300.961432) (xy 172.706186 -301.005009) (xy 172.72177 -301.05169)
			(xy 172.729665 -301.100267) (xy 172.73016 -301.124874) (xy 173.069262 -301.124874) (xy 173.073222 -301.07582)
			(xy 173.084999 -301.028036) (xy 173.10429 -300.98276) (xy 173.130593 -300.941164) (xy 173.163228 -300.904327)
			(xy 173.201349 -300.873202) (xy 173.24397 -300.848595) (xy 173.289986 -300.831143) (xy 173.338205 -300.821299)
			(xy 173.38738 -300.819318) (xy 173.436235 -300.82525) (xy 173.483506 -300.838942) (xy 173.527968 -300.86004)
			(xy 173.568471 -300.887996) (xy 173.603964 -300.922088) (xy 173.633529 -300.961432) (xy 173.6564 -301.005009)
			(xy 173.671984 -301.05169) (xy 173.679879 -301.100267) (xy 173.680374 -301.124874) (xy 174.019222 -301.124874)
			(xy 174.023182 -301.07582) (xy 174.034959 -301.028036) (xy 174.05425 -300.98276) (xy 174.080553 -300.941164)
			(xy 174.113188 -300.904327) (xy 174.151309 -300.873202) (xy 174.19393 -300.848595) (xy 174.239946 -300.831143)
			(xy 174.288165 -300.821299) (xy 174.33734 -300.819318) (xy 174.386195 -300.82525) (xy 174.433466 -300.838942)
			(xy 174.477928 -300.86004) (xy 174.518431 -300.887996) (xy 174.553924 -300.922088) (xy 174.583489 -300.961432)
			(xy 174.60636 -301.005009) (xy 174.621944 -301.05169) (xy 174.629839 -301.100267) (xy 174.630334 -301.124874)
			(xy 175.919142 -301.124874) (xy 175.923102 -301.07582) (xy 175.934879 -301.028036) (xy 175.95417 -300.98276)
			(xy 175.980473 -300.941164) (xy 176.013108 -300.904327) (xy 176.051229 -300.873202) (xy 176.09385 -300.848595)
			(xy 176.139866 -300.831143) (xy 176.188085 -300.821299) (xy 176.23726 -300.819318) (xy 176.286115 -300.82525)
			(xy 176.333386 -300.838942) (xy 176.377848 -300.86004) (xy 176.418351 -300.887996) (xy 176.453844 -300.922088)
			(xy 176.483409 -300.961432) (xy 176.50628 -301.005009) (xy 176.521864 -301.05169) (xy 176.529759 -301.100267)
			(xy 176.530254 -301.124874) (xy 176.869102 -301.124874) (xy 176.873062 -301.07582) (xy 176.884839 -301.028036)
			(xy 176.90413 -300.98276) (xy 176.930433 -300.941164) (xy 176.963068 -300.904327) (xy 177.001189 -300.873202)
			(xy 177.04381 -300.848595) (xy 177.089826 -300.831143) (xy 177.138045 -300.821299) (xy 177.18722 -300.819318)
			(xy 177.236075 -300.82525) (xy 177.283346 -300.838942) (xy 177.327808 -300.86004) (xy 177.368311 -300.887996)
			(xy 177.403804 -300.922088) (xy 177.433369 -300.961432) (xy 177.45624 -301.005009) (xy 177.471824 -301.05169)
			(xy 177.479719 -301.100267) (xy 177.480214 -301.124874) (xy 177.819062 -301.124874) (xy 177.823022 -301.07582)
			(xy 177.834799 -301.028036) (xy 177.85409 -300.98276) (xy 177.880393 -300.941164) (xy 177.913028 -300.904327)
			(xy 177.951149 -300.873202) (xy 177.99377 -300.848595) (xy 178.039786 -300.831143) (xy 178.088005 -300.821299)
			(xy 178.13718 -300.819318) (xy 178.186035 -300.82525) (xy 178.233306 -300.838942) (xy 178.277768 -300.86004)
			(xy 178.318271 -300.887996) (xy 178.353764 -300.922088) (xy 178.383329 -300.961432) (xy 178.4062 -301.005009)
			(xy 178.421784 -301.05169) (xy 178.429679 -301.100267) (xy 178.430174 -301.124874) (xy 178.769276 -301.124874)
			(xy 178.773236 -301.07582) (xy 178.785013 -301.028036) (xy 178.804304 -300.98276) (xy 178.830607 -300.941164)
			(xy 178.863242 -300.904327) (xy 178.901363 -300.873202) (xy 178.943984 -300.848595) (xy 178.99 -300.831143)
			(xy 179.038219 -300.821299) (xy 179.087394 -300.819318) (xy 179.136249 -300.82525) (xy 179.18352 -300.838942)
			(xy 179.227982 -300.86004) (xy 179.268485 -300.887996) (xy 179.303978 -300.922088) (xy 179.333543 -300.961432)
			(xy 179.356414 -301.005009) (xy 179.371998 -301.05169) (xy 179.379893 -301.100267) (xy 179.380388 -301.124874)
			(xy 179.719236 -301.124874) (xy 179.723196 -301.07582) (xy 179.734973 -301.028036) (xy 179.754264 -300.98276)
			(xy 179.780567 -300.941164) (xy 179.813202 -300.904327) (xy 179.851323 -300.873202) (xy 179.893944 -300.848595)
			(xy 179.93996 -300.831143) (xy 179.988179 -300.821299) (xy 180.037354 -300.819318) (xy 180.086209 -300.82525)
			(xy 180.13348 -300.838942) (xy 180.177942 -300.86004) (xy 180.218445 -300.887996) (xy 180.253938 -300.922088)
			(xy 180.283503 -300.961432) (xy 180.306374 -301.005009) (xy 180.321958 -301.05169) (xy 180.329853 -301.100267)
			(xy 180.330348 -301.124874) (xy 180.669196 -301.124874) (xy 180.673156 -301.07582) (xy 180.684933 -301.028036)
			(xy 180.704224 -300.98276) (xy 180.730527 -300.941164) (xy 180.763162 -300.904327) (xy 180.801283 -300.873202)
			(xy 180.843904 -300.848595) (xy 180.88992 -300.831143) (xy 180.938139 -300.821299) (xy 180.987314 -300.819318)
			(xy 181.036169 -300.82525) (xy 181.08344 -300.838942) (xy 181.127902 -300.86004) (xy 181.168405 -300.887996)
			(xy 181.203898 -300.922088) (xy 181.233463 -300.961432) (xy 181.256334 -301.005009) (xy 181.271918 -301.05169)
			(xy 181.279813 -301.100267) (xy 181.280308 -301.124874) (xy 181.619156 -301.124874) (xy 181.623116 -301.07582)
			(xy 181.634893 -301.028036) (xy 181.654184 -300.98276) (xy 181.680487 -300.941164) (xy 181.713122 -300.904327)
			(xy 181.751243 -300.873202) (xy 181.793864 -300.848595) (xy 181.83988 -300.831143) (xy 181.888099 -300.821299)
			(xy 181.937274 -300.819318) (xy 181.986129 -300.82525) (xy 182.0334 -300.838942) (xy 182.077862 -300.86004)
			(xy 182.118365 -300.887996) (xy 182.153858 -300.922088) (xy 182.183423 -300.961432) (xy 182.206294 -301.005009)
			(xy 182.221878 -301.05169) (xy 182.229773 -301.100267) (xy 182.230268 -301.124874) (xy 182.569116 -301.124874)
			(xy 182.573076 -301.07582) (xy 182.584853 -301.028036) (xy 182.604144 -300.98276) (xy 182.630447 -300.941164)
			(xy 182.663082 -300.904327) (xy 182.701203 -300.873202) (xy 182.743824 -300.848595) (xy 182.78984 -300.831143)
			(xy 182.838059 -300.821299) (xy 182.887234 -300.819318) (xy 182.936089 -300.82525) (xy 182.98336 -300.838942)
			(xy 183.027822 -300.86004) (xy 183.068325 -300.887996) (xy 183.103818 -300.922088) (xy 183.133383 -300.961432)
			(xy 183.156254 -301.005009) (xy 183.171838 -301.05169) (xy 183.179733 -301.100267) (xy 183.180228 -301.124874)
			(xy 183.519076 -301.124874) (xy 183.523036 -301.07582) (xy 183.534813 -301.028036) (xy 183.554104 -300.98276)
			(xy 183.580407 -300.941164) (xy 183.613042 -300.904327) (xy 183.651163 -300.873202) (xy 183.693784 -300.848595)
			(xy 183.7398 -300.831143) (xy 183.788019 -300.821299) (xy 183.837194 -300.819318) (xy 183.886049 -300.82525)
			(xy 183.93332 -300.838942) (xy 183.977782 -300.86004) (xy 184.018285 -300.887996) (xy 184.053778 -300.922088)
			(xy 184.083343 -300.961432) (xy 184.106214 -301.005009) (xy 184.121798 -301.05169) (xy 184.129693 -301.100267)
			(xy 184.130188 -301.124874) (xy 184.469036 -301.124874) (xy 184.472996 -301.07582) (xy 184.484773 -301.028036)
			(xy 184.504064 -300.98276) (xy 184.530367 -300.941164) (xy 184.563002 -300.904327) (xy 184.601123 -300.873202)
			(xy 184.643744 -300.848595) (xy 184.68976 -300.831143) (xy 184.737979 -300.821299) (xy 184.787154 -300.819318)
			(xy 184.836009 -300.82525) (xy 184.88328 -300.838942) (xy 184.927742 -300.86004) (xy 184.968245 -300.887996)
			(xy 185.003738 -300.922088) (xy 185.033303 -300.961432) (xy 185.056174 -301.005009) (xy 185.071758 -301.05169)
			(xy 185.079653 -301.100267) (xy 185.080148 -301.124874) (xy 185.079653 -301.149481) (xy 185.071758 -301.198058)
			(xy 185.056174 -301.244739) (xy 185.033303 -301.288316) (xy 185.003738 -301.32766) (xy 184.968245 -301.361752)
			(xy 184.927742 -301.389708) (xy 184.88328 -301.410806) (xy 184.836009 -301.424498) (xy 184.787154 -301.43043)
			(xy 184.737979 -301.428449) (xy 184.68976 -301.418605) (xy 184.643744 -301.401153) (xy 184.601123 -301.376546)
			(xy 184.563002 -301.345421) (xy 184.530367 -301.308584) (xy 184.504064 -301.266988) (xy 184.484773 -301.221712)
			(xy 184.472996 -301.173928) (xy 184.469036 -301.124874) (xy 184.130188 -301.124874) (xy 184.129693 -301.149481)
			(xy 184.121798 -301.198058) (xy 184.106214 -301.244739) (xy 184.083343 -301.288316) (xy 184.053778 -301.32766)
			(xy 184.018285 -301.361752) (xy 183.977782 -301.389708) (xy 183.93332 -301.410806) (xy 183.886049 -301.424498)
			(xy 183.837194 -301.43043) (xy 183.788019 -301.428449) (xy 183.7398 -301.418605) (xy 183.693784 -301.401153)
			(xy 183.651163 -301.376546) (xy 183.613042 -301.345421) (xy 183.580407 -301.308584) (xy 183.554104 -301.266988)
			(xy 183.534813 -301.221712) (xy 183.523036 -301.173928) (xy 183.519076 -301.124874) (xy 183.180228 -301.124874)
			(xy 183.179733 -301.149481) (xy 183.171838 -301.198058) (xy 183.156254 -301.244739) (xy 183.133383 -301.288316)
			(xy 183.103818 -301.32766) (xy 183.068325 -301.361752) (xy 183.027822 -301.389708) (xy 182.98336 -301.410806)
			(xy 182.936089 -301.424498) (xy 182.887234 -301.43043) (xy 182.838059 -301.428449) (xy 182.78984 -301.418605)
			(xy 182.743824 -301.401153) (xy 182.701203 -301.376546) (xy 182.663082 -301.345421) (xy 182.630447 -301.308584)
			(xy 182.604144 -301.266988) (xy 182.584853 -301.221712) (xy 182.573076 -301.173928) (xy 182.569116 -301.124874)
			(xy 182.230268 -301.124874) (xy 182.229773 -301.149481) (xy 182.221878 -301.198058) (xy 182.206294 -301.244739)
			(xy 182.183423 -301.288316) (xy 182.153858 -301.32766) (xy 182.118365 -301.361752) (xy 182.077862 -301.389708)
			(xy 182.0334 -301.410806) (xy 181.986129 -301.424498) (xy 181.937274 -301.43043) (xy 181.888099 -301.428449)
			(xy 181.83988 -301.418605) (xy 181.793864 -301.401153) (xy 181.751243 -301.376546) (xy 181.713122 -301.345421)
			(xy 181.680487 -301.308584) (xy 181.654184 -301.266988) (xy 181.634893 -301.221712) (xy 181.623116 -301.173928)
			(xy 181.619156 -301.124874) (xy 181.280308 -301.124874) (xy 181.279813 -301.149481) (xy 181.271918 -301.198058)
			(xy 181.256334 -301.244739) (xy 181.233463 -301.288316) (xy 181.203898 -301.32766) (xy 181.168405 -301.361752)
			(xy 181.127902 -301.389708) (xy 181.08344 -301.410806) (xy 181.036169 -301.424498) (xy 180.987314 -301.43043)
			(xy 180.938139 -301.428449) (xy 180.88992 -301.418605) (xy 180.843904 -301.401153) (xy 180.801283 -301.376546)
			(xy 180.763162 -301.345421) (xy 180.730527 -301.308584) (xy 180.704224 -301.266988) (xy 180.684933 -301.221712)
			(xy 180.673156 -301.173928) (xy 180.669196 -301.124874) (xy 180.330348 -301.124874) (xy 180.329853 -301.149481)
			(xy 180.321958 -301.198058) (xy 180.306374 -301.244739) (xy 180.283503 -301.288316) (xy 180.253938 -301.32766)
			(xy 180.218445 -301.361752) (xy 180.177942 -301.389708) (xy 180.13348 -301.410806) (xy 180.086209 -301.424498)
			(xy 180.037354 -301.43043) (xy 179.988179 -301.428449) (xy 179.93996 -301.418605) (xy 179.893944 -301.401153)
			(xy 179.851323 -301.376546) (xy 179.813202 -301.345421) (xy 179.780567 -301.308584) (xy 179.754264 -301.266988)
			(xy 179.734973 -301.221712) (xy 179.723196 -301.173928) (xy 179.719236 -301.124874) (xy 179.380388 -301.124874)
			(xy 179.379893 -301.149481) (xy 179.371998 -301.198058) (xy 179.356414 -301.244739) (xy 179.333543 -301.288316)
			(xy 179.303978 -301.32766) (xy 179.268485 -301.361752) (xy 179.227982 -301.389708) (xy 179.18352 -301.410806)
			(xy 179.136249 -301.424498) (xy 179.087394 -301.43043) (xy 179.038219 -301.428449) (xy 178.99 -301.418605)
			(xy 178.943984 -301.401153) (xy 178.901363 -301.376546) (xy 178.863242 -301.345421) (xy 178.830607 -301.308584)
			(xy 178.804304 -301.266988) (xy 178.785013 -301.221712) (xy 178.773236 -301.173928) (xy 178.769276 -301.124874)
			(xy 178.430174 -301.124874) (xy 178.429679 -301.149481) (xy 178.421784 -301.198058) (xy 178.4062 -301.244739)
			(xy 178.383329 -301.288316) (xy 178.353764 -301.32766) (xy 178.318271 -301.361752) (xy 178.277768 -301.389708)
			(xy 178.233306 -301.410806) (xy 178.186035 -301.424498) (xy 178.13718 -301.43043) (xy 178.088005 -301.428449)
			(xy 178.039786 -301.418605) (xy 177.99377 -301.401153) (xy 177.951149 -301.376546) (xy 177.913028 -301.345421)
			(xy 177.880393 -301.308584) (xy 177.85409 -301.266988) (xy 177.834799 -301.221712) (xy 177.823022 -301.173928)
			(xy 177.819062 -301.124874) (xy 177.480214 -301.124874) (xy 177.479719 -301.149481) (xy 177.471824 -301.198058)
			(xy 177.45624 -301.244739) (xy 177.433369 -301.288316) (xy 177.403804 -301.32766) (xy 177.368311 -301.361752)
			(xy 177.327808 -301.389708) (xy 177.283346 -301.410806) (xy 177.236075 -301.424498) (xy 177.18722 -301.43043)
			(xy 177.138045 -301.428449) (xy 177.089826 -301.418605) (xy 177.04381 -301.401153) (xy 177.001189 -301.376546)
			(xy 176.963068 -301.345421) (xy 176.930433 -301.308584) (xy 176.90413 -301.266988) (xy 176.884839 -301.221712)
			(xy 176.873062 -301.173928) (xy 176.869102 -301.124874) (xy 176.530254 -301.124874) (xy 176.529759 -301.149481)
			(xy 176.521864 -301.198058) (xy 176.50628 -301.244739) (xy 176.483409 -301.288316) (xy 176.453844 -301.32766)
			(xy 176.418351 -301.361752) (xy 176.377848 -301.389708) (xy 176.333386 -301.410806) (xy 176.286115 -301.424498)
			(xy 176.23726 -301.43043) (xy 176.188085 -301.428449) (xy 176.139866 -301.418605) (xy 176.09385 -301.401153)
			(xy 176.051229 -301.376546) (xy 176.013108 -301.345421) (xy 175.980473 -301.308584) (xy 175.95417 -301.266988)
			(xy 175.934879 -301.221712) (xy 175.923102 -301.173928) (xy 175.919142 -301.124874) (xy 174.630334 -301.124874)
			(xy 174.629839 -301.149481) (xy 174.621944 -301.198058) (xy 174.60636 -301.244739) (xy 174.583489 -301.288316)
			(xy 174.553924 -301.32766) (xy 174.518431 -301.361752) (xy 174.477928 -301.389708) (xy 174.433466 -301.410806)
			(xy 174.386195 -301.424498) (xy 174.33734 -301.43043) (xy 174.288165 -301.428449) (xy 174.239946 -301.418605)
			(xy 174.19393 -301.401153) (xy 174.151309 -301.376546) (xy 174.113188 -301.345421) (xy 174.080553 -301.308584)
			(xy 174.05425 -301.266988) (xy 174.034959 -301.221712) (xy 174.023182 -301.173928) (xy 174.019222 -301.124874)
			(xy 173.680374 -301.124874) (xy 173.679879 -301.149481) (xy 173.671984 -301.198058) (xy 173.6564 -301.244739)
			(xy 173.633529 -301.288316) (xy 173.603964 -301.32766) (xy 173.568471 -301.361752) (xy 173.527968 -301.389708)
			(xy 173.483506 -301.410806) (xy 173.436235 -301.424498) (xy 173.38738 -301.43043) (xy 173.338205 -301.428449)
			(xy 173.289986 -301.418605) (xy 173.24397 -301.401153) (xy 173.201349 -301.376546) (xy 173.163228 -301.345421)
			(xy 173.130593 -301.308584) (xy 173.10429 -301.266988) (xy 173.084999 -301.221712) (xy 173.073222 -301.173928)
			(xy 173.069262 -301.124874) (xy 172.73016 -301.124874) (xy 172.729665 -301.149481) (xy 172.72177 -301.198058)
			(xy 172.706186 -301.244739) (xy 172.683315 -301.288316) (xy 172.65375 -301.32766) (xy 172.618257 -301.361752)
			(xy 172.577754 -301.389708) (xy 172.533292 -301.410806) (xy 172.486021 -301.424498) (xy 172.437166 -301.43043)
			(xy 172.387991 -301.428449) (xy 172.339772 -301.418605) (xy 172.293756 -301.401153) (xy 172.251135 -301.376546)
			(xy 172.213014 -301.345421) (xy 172.180379 -301.308584) (xy 172.154076 -301.266988) (xy 172.134785 -301.221712)
			(xy 172.123008 -301.173928) (xy 172.119048 -301.124874) (xy 171.7802 -301.124874) (xy 171.779705 -301.149481)
			(xy 171.77181 -301.198058) (xy 171.756226 -301.244739) (xy 171.733355 -301.288316) (xy 171.70379 -301.32766)
			(xy 171.668297 -301.361752) (xy 171.627794 -301.389708) (xy 171.583332 -301.410806) (xy 171.536061 -301.424498)
			(xy 171.487206 -301.43043) (xy 171.438031 -301.428449) (xy 171.389812 -301.418605) (xy 171.343796 -301.401153)
			(xy 171.301175 -301.376546) (xy 171.263054 -301.345421) (xy 171.230419 -301.308584) (xy 171.204116 -301.266988)
			(xy 171.184825 -301.221712) (xy 171.173048 -301.173928) (xy 171.169088 -301.124874) (xy 170.83024 -301.124874)
			(xy 170.829745 -301.149481) (xy 170.82185 -301.198058) (xy 170.806266 -301.244739) (xy 170.783395 -301.288316)
			(xy 170.75383 -301.32766) (xy 170.718337 -301.361752) (xy 170.677834 -301.389708) (xy 170.633372 -301.410806)
			(xy 170.586101 -301.424498) (xy 170.537246 -301.43043) (xy 170.488071 -301.428449) (xy 170.439852 -301.418605)
			(xy 170.393836 -301.401153) (xy 170.351215 -301.376546) (xy 170.313094 -301.345421) (xy 170.280459 -301.308584)
			(xy 170.254156 -301.266988) (xy 170.234865 -301.221712) (xy 170.223088 -301.173928) (xy 170.219128 -301.124874)
			(xy 169.88028 -301.124874) (xy 169.879785 -301.149481) (xy 169.87189 -301.198058) (xy 169.856306 -301.244739)
			(xy 169.833435 -301.288316) (xy 169.80387 -301.32766) (xy 169.768377 -301.361752) (xy 169.727874 -301.389708)
			(xy 169.683412 -301.410806) (xy 169.636141 -301.424498) (xy 169.587286 -301.43043) (xy 169.538111 -301.428449)
			(xy 169.489892 -301.418605) (xy 169.443876 -301.401153) (xy 169.401255 -301.376546) (xy 169.363134 -301.345421)
			(xy 169.330499 -301.308584) (xy 169.304196 -301.266988) (xy 169.284905 -301.221712) (xy 169.273128 -301.173928)
			(xy 169.269168 -301.124874) (xy 168.93032 -301.124874) (xy 168.929825 -301.149481) (xy 168.92193 -301.198058)
			(xy 168.906346 -301.244739) (xy 168.883475 -301.288316) (xy 168.85391 -301.32766) (xy 168.818417 -301.361752)
			(xy 168.777914 -301.389708) (xy 168.733452 -301.410806) (xy 168.686181 -301.424498) (xy 168.637326 -301.43043)
			(xy 168.588151 -301.428449) (xy 168.539932 -301.418605) (xy 168.493916 -301.401153) (xy 168.451295 -301.376546)
			(xy 168.413174 -301.345421) (xy 168.380539 -301.308584) (xy 168.354236 -301.266988) (xy 168.334945 -301.221712)
			(xy 168.323168 -301.173928) (xy 168.319208 -301.124874) (xy 167.98036 -301.124874) (xy 167.979865 -301.149481)
			(xy 167.97197 -301.198058) (xy 167.956386 -301.244739) (xy 167.933515 -301.288316) (xy 167.90395 -301.32766)
			(xy 167.868457 -301.361752) (xy 167.827954 -301.389708) (xy 167.783492 -301.410806) (xy 167.736221 -301.424498)
			(xy 167.687366 -301.43043) (xy 167.638191 -301.428449) (xy 167.589972 -301.418605) (xy 167.543956 -301.401153)
			(xy 167.501335 -301.376546) (xy 167.463214 -301.345421) (xy 167.430579 -301.308584) (xy 167.404276 -301.266988)
			(xy 167.384985 -301.221712) (xy 167.373208 -301.173928) (xy 167.369248 -301.124874) (xy 167.0304 -301.124874)
			(xy 167.029905 -301.149481) (xy 167.02201 -301.198058) (xy 167.006426 -301.244739) (xy 166.983555 -301.288316)
			(xy 166.95399 -301.32766) (xy 166.918497 -301.361752) (xy 166.877994 -301.389708) (xy 166.833532 -301.410806)
			(xy 166.786261 -301.424498) (xy 166.737406 -301.43043) (xy 166.688231 -301.428449) (xy 166.640012 -301.418605)
			(xy 166.593996 -301.401153) (xy 166.551375 -301.376546) (xy 166.513254 -301.345421) (xy 166.480619 -301.308584)
			(xy 166.454316 -301.266988) (xy 166.435025 -301.221712) (xy 166.423248 -301.173928) (xy 166.419288 -301.124874)
			(xy 166.080186 -301.124874) (xy 166.079691 -301.149481) (xy 166.071796 -301.198058) (xy 166.056212 -301.244739)
			(xy 166.033341 -301.288316) (xy 166.003776 -301.32766) (xy 165.968283 -301.361752) (xy 165.92778 -301.389708)
			(xy 165.883318 -301.410806) (xy 165.836047 -301.424498) (xy 165.787192 -301.43043) (xy 165.738017 -301.428449)
			(xy 165.689798 -301.418605) (xy 165.643782 -301.401153) (xy 165.601161 -301.376546) (xy 165.56304 -301.345421)
			(xy 165.530405 -301.308584) (xy 165.504102 -301.266988) (xy 165.484811 -301.221712) (xy 165.473034 -301.173928)
			(xy 165.469074 -301.124874) (xy 164.180266 -301.124874) (xy 164.179771 -301.149481) (xy 164.171876 -301.198058)
			(xy 164.156292 -301.244739) (xy 164.133421 -301.288316) (xy 164.103856 -301.32766) (xy 164.068363 -301.361752)
			(xy 164.02786 -301.389708) (xy 163.983398 -301.410806) (xy 163.936127 -301.424498) (xy 163.887272 -301.43043)
			(xy 163.838097 -301.428449) (xy 163.789878 -301.418605) (xy 163.743862 -301.401153) (xy 163.701241 -301.376546)
			(xy 163.66312 -301.345421) (xy 163.630485 -301.308584) (xy 163.604182 -301.266988) (xy 163.584891 -301.221712)
			(xy 163.573114 -301.173928) (xy 163.569154 -301.124874) (xy 163.230306 -301.124874) (xy 163.229811 -301.149481)
			(xy 163.221916 -301.198058) (xy 163.206332 -301.244739) (xy 163.183461 -301.288316) (xy 163.153896 -301.32766)
			(xy 163.118403 -301.361752) (xy 163.0779 -301.389708) (xy 163.033438 -301.410806) (xy 162.986167 -301.424498)
			(xy 162.937312 -301.43043) (xy 162.888137 -301.428449) (xy 162.839918 -301.418605) (xy 162.793902 -301.401153)
			(xy 162.751281 -301.376546) (xy 162.71316 -301.345421) (xy 162.680525 -301.308584) (xy 162.654222 -301.266988)
			(xy 162.634931 -301.221712) (xy 162.623154 -301.173928) (xy 162.619194 -301.124874) (xy 162.280243 -301.124874)
			(xy 162.280693 -301.133164) (xy 162.27533 -301.182509) (xy 162.262054 -301.230336) (xy 162.241216 -301.275385)
			(xy 162.213365 -301.31647) (xy 162.179234 -301.352508) (xy 162.139722 -301.382549) (xy 162.095871 -301.405804)
			(xy 162.048836 -301.421657) (xy 161.999856 -301.429693) (xy 161.975038 -301.430182) (xy 161.960855 -301.430001)
			(xy 161.932615 -301.427332) (xy 161.91865 -301.424848) (xy 161.906204 -301.422562) (xy 161.882582 -301.429928)
			(xy 161.805112 -301.507398) (xy 161.797746 -301.53102) (xy 161.800032 -301.543466) (xy 161.802514 -301.557431)
			(xy 161.805182 -301.585671) (xy 161.805366 -301.599854) (xy 161.805184 -301.614037) (xy 161.802515 -301.642277)
			(xy 161.800032 -301.656242) (xy 161.797746 -301.668688) (xy 161.805112 -301.69231) (xy 161.882582 -301.76978)
			(xy 161.906204 -301.777146) (xy 161.91865 -301.77486) (xy 161.932616 -301.772381) (xy 161.960855 -301.769711)
			(xy 161.975038 -301.769526) (xy 162.000294 -301.769983) (xy 162.050117 -301.778302) (xy 162.09789 -301.794708)
			(xy 162.142312 -301.818753) (xy 162.182171 -301.849781) (xy 162.21638 -301.886946) (xy 162.244006 -301.929235)
			(xy 162.264295 -301.975493) (xy 162.276694 -302.02446) (xy 162.280865 -302.0748) (xy 162.280862 -302.074834)
			(xy 165.469074 -302.074834) (xy 165.473034 -302.02578) (xy 165.484811 -301.977996) (xy 165.504102 -301.93272)
			(xy 165.530405 -301.891124) (xy 165.56304 -301.854287) (xy 165.601161 -301.823162) (xy 165.643782 -301.798555)
			(xy 165.689798 -301.781103) (xy 165.738017 -301.771259) (xy 165.787192 -301.769278) (xy 165.836047 -301.77521)
			(xy 165.883318 -301.788902) (xy 165.92778 -301.81) (xy 165.968283 -301.837956) (xy 166.003776 -301.872048)
			(xy 166.033341 -301.911392) (xy 166.056212 -301.954969) (xy 166.071796 -302.00165) (xy 166.079691 -302.050227)
			(xy 166.080186 -302.074834) (xy 166.419288 -302.074834) (xy 166.423248 -302.02578) (xy 166.435025 -301.977996)
			(xy 166.454316 -301.93272) (xy 166.480619 -301.891124) (xy 166.513254 -301.854287) (xy 166.551375 -301.823162)
			(xy 166.593996 -301.798555) (xy 166.640012 -301.781103) (xy 166.688231 -301.771259) (xy 166.737406 -301.769278)
			(xy 166.786261 -301.77521) (xy 166.833532 -301.788902) (xy 166.877994 -301.81) (xy 166.918497 -301.837956)
			(xy 166.95399 -301.872048) (xy 166.983555 -301.911392) (xy 167.006426 -301.954969) (xy 167.02201 -302.00165)
			(xy 167.029905 -302.050227) (xy 167.0304 -302.074834) (xy 167.369248 -302.074834) (xy 167.373208 -302.02578)
			(xy 167.384985 -301.977996) (xy 167.404276 -301.93272) (xy 167.430579 -301.891124) (xy 167.463214 -301.854287)
			(xy 167.501335 -301.823162) (xy 167.543956 -301.798555) (xy 167.589972 -301.781103) (xy 167.638191 -301.771259)
			(xy 167.687366 -301.769278) (xy 167.736221 -301.77521) (xy 167.783492 -301.788902) (xy 167.827954 -301.81)
			(xy 167.868457 -301.837956) (xy 167.90395 -301.872048) (xy 167.933515 -301.911392) (xy 167.956386 -301.954969)
			(xy 167.97197 -302.00165) (xy 167.979865 -302.050227) (xy 167.98036 -302.074834) (xy 168.319208 -302.074834)
			(xy 168.323168 -302.02578) (xy 168.334945 -301.977996) (xy 168.354236 -301.93272) (xy 168.380539 -301.891124)
			(xy 168.413174 -301.854287) (xy 168.451295 -301.823162) (xy 168.493916 -301.798555) (xy 168.539932 -301.781103)
			(xy 168.588151 -301.771259) (xy 168.637326 -301.769278) (xy 168.686181 -301.77521) (xy 168.733452 -301.788902)
			(xy 168.777914 -301.81) (xy 168.818417 -301.837956) (xy 168.85391 -301.872048) (xy 168.883475 -301.911392)
			(xy 168.906346 -301.954969) (xy 168.92193 -302.00165) (xy 168.929825 -302.050227) (xy 168.93032 -302.074834)
			(xy 169.269168 -302.074834) (xy 169.273128 -302.02578) (xy 169.284905 -301.977996) (xy 169.304196 -301.93272)
			(xy 169.330499 -301.891124) (xy 169.363134 -301.854287) (xy 169.401255 -301.823162) (xy 169.443876 -301.798555)
			(xy 169.489892 -301.781103) (xy 169.538111 -301.771259) (xy 169.587286 -301.769278) (xy 169.636141 -301.77521)
			(xy 169.683412 -301.788902) (xy 169.727874 -301.81) (xy 169.768377 -301.837956) (xy 169.80387 -301.872048)
			(xy 169.833435 -301.911392) (xy 169.856306 -301.954969) (xy 169.87189 -302.00165) (xy 169.879785 -302.050227)
			(xy 169.88028 -302.074834) (xy 170.219128 -302.074834) (xy 170.223088 -302.02578) (xy 170.234865 -301.977996)
			(xy 170.254156 -301.93272) (xy 170.280459 -301.891124) (xy 170.313094 -301.854287) (xy 170.351215 -301.823162)
			(xy 170.393836 -301.798555) (xy 170.439852 -301.781103) (xy 170.488071 -301.771259) (xy 170.537246 -301.769278)
			(xy 170.586101 -301.77521) (xy 170.633372 -301.788902) (xy 170.677834 -301.81) (xy 170.718337 -301.837956)
			(xy 170.75383 -301.872048) (xy 170.783395 -301.911392) (xy 170.806266 -301.954969) (xy 170.82185 -302.00165)
			(xy 170.829745 -302.050227) (xy 170.83024 -302.074834) (xy 171.169088 -302.074834) (xy 171.173048 -302.02578)
			(xy 171.184825 -301.977996) (xy 171.204116 -301.93272) (xy 171.230419 -301.891124) (xy 171.263054 -301.854287)
			(xy 171.301175 -301.823162) (xy 171.343796 -301.798555) (xy 171.389812 -301.781103) (xy 171.438031 -301.771259)
			(xy 171.487206 -301.769278) (xy 171.536061 -301.77521) (xy 171.583332 -301.788902) (xy 171.627794 -301.81)
			(xy 171.668297 -301.837956) (xy 171.70379 -301.872048) (xy 171.733355 -301.911392) (xy 171.756226 -301.954969)
			(xy 171.77181 -302.00165) (xy 171.779705 -302.050227) (xy 171.7802 -302.074834) (xy 172.119048 -302.074834)
			(xy 172.123008 -302.02578) (xy 172.134785 -301.977996) (xy 172.154076 -301.93272) (xy 172.180379 -301.891124)
			(xy 172.213014 -301.854287) (xy 172.251135 -301.823162) (xy 172.293756 -301.798555) (xy 172.339772 -301.781103)
			(xy 172.387991 -301.771259) (xy 172.437166 -301.769278) (xy 172.486021 -301.77521) (xy 172.533292 -301.788902)
			(xy 172.577754 -301.81) (xy 172.618257 -301.837956) (xy 172.65375 -301.872048) (xy 172.683315 -301.911392)
			(xy 172.706186 -301.954969) (xy 172.72177 -302.00165) (xy 172.729665 -302.050227) (xy 172.73016 -302.074834)
			(xy 173.069262 -302.074834) (xy 173.073222 -302.02578) (xy 173.084999 -301.977996) (xy 173.10429 -301.93272)
			(xy 173.130593 -301.891124) (xy 173.163228 -301.854287) (xy 173.201349 -301.823162) (xy 173.24397 -301.798555)
			(xy 173.289986 -301.781103) (xy 173.338205 -301.771259) (xy 173.38738 -301.769278) (xy 173.436235 -301.77521)
			(xy 173.483506 -301.788902) (xy 173.527968 -301.81) (xy 173.568471 -301.837956) (xy 173.603964 -301.872048)
			(xy 173.633529 -301.911392) (xy 173.6564 -301.954969) (xy 173.671984 -302.00165) (xy 173.679879 -302.050227)
			(xy 173.680374 -302.074834) (xy 174.019222 -302.074834) (xy 174.023182 -302.02578) (xy 174.034959 -301.977996)
			(xy 174.05425 -301.93272) (xy 174.080553 -301.891124) (xy 174.113188 -301.854287) (xy 174.151309 -301.823162)
			(xy 174.19393 -301.798555) (xy 174.239946 -301.781103) (xy 174.288165 -301.771259) (xy 174.33734 -301.769278)
			(xy 174.386195 -301.77521) (xy 174.433466 -301.788902) (xy 174.477928 -301.81) (xy 174.518431 -301.837956)
			(xy 174.553924 -301.872048) (xy 174.583489 -301.911392) (xy 174.60636 -301.954969) (xy 174.621944 -302.00165)
			(xy 174.629839 -302.050227) (xy 174.630334 -302.074834) (xy 175.919142 -302.074834) (xy 175.923102 -302.02578)
			(xy 175.934879 -301.977996) (xy 175.95417 -301.93272) (xy 175.980473 -301.891124) (xy 176.013108 -301.854287)
			(xy 176.051229 -301.823162) (xy 176.09385 -301.798555) (xy 176.139866 -301.781103) (xy 176.188085 -301.771259)
			(xy 176.23726 -301.769278) (xy 176.286115 -301.77521) (xy 176.333386 -301.788902) (xy 176.377848 -301.81)
			(xy 176.418351 -301.837956) (xy 176.453844 -301.872048) (xy 176.483409 -301.911392) (xy 176.50628 -301.954969)
			(xy 176.521864 -302.00165) (xy 176.529759 -302.050227) (xy 176.530254 -302.074834) (xy 176.869102 -302.074834)
			(xy 176.873062 -302.02578) (xy 176.884839 -301.977996) (xy 176.90413 -301.93272) (xy 176.930433 -301.891124)
			(xy 176.963068 -301.854287) (xy 177.001189 -301.823162) (xy 177.04381 -301.798555) (xy 177.089826 -301.781103)
			(xy 177.138045 -301.771259) (xy 177.18722 -301.769278) (xy 177.236075 -301.77521) (xy 177.283346 -301.788902)
			(xy 177.327808 -301.81) (xy 177.368311 -301.837956) (xy 177.403804 -301.872048) (xy 177.433369 -301.911392)
			(xy 177.45624 -301.954969) (xy 177.471824 -302.00165) (xy 177.479719 -302.050227) (xy 177.480214 -302.074834)
			(xy 177.819062 -302.074834) (xy 177.823022 -302.02578) (xy 177.834799 -301.977996) (xy 177.85409 -301.93272)
			(xy 177.880393 -301.891124) (xy 177.913028 -301.854287) (xy 177.951149 -301.823162) (xy 177.99377 -301.798555)
			(xy 178.039786 -301.781103) (xy 178.088005 -301.771259) (xy 178.13718 -301.769278) (xy 178.186035 -301.77521)
			(xy 178.233306 -301.788902) (xy 178.277768 -301.81) (xy 178.318271 -301.837956) (xy 178.353764 -301.872048)
			(xy 178.383329 -301.911392) (xy 178.4062 -301.954969) (xy 178.421784 -302.00165) (xy 178.429679 -302.050227)
			(xy 178.430174 -302.074834) (xy 178.769276 -302.074834) (xy 178.773236 -302.02578) (xy 178.785013 -301.977996)
			(xy 178.804304 -301.93272) (xy 178.830607 -301.891124) (xy 178.863242 -301.854287) (xy 178.901363 -301.823162)
			(xy 178.943984 -301.798555) (xy 178.99 -301.781103) (xy 179.038219 -301.771259) (xy 179.087394 -301.769278)
			(xy 179.136249 -301.77521) (xy 179.18352 -301.788902) (xy 179.227982 -301.81) (xy 179.268485 -301.837956)
			(xy 179.303978 -301.872048) (xy 179.333543 -301.911392) (xy 179.356414 -301.954969) (xy 179.371998 -302.00165)
			(xy 179.379893 -302.050227) (xy 179.380388 -302.074834) (xy 179.719236 -302.074834) (xy 179.723196 -302.02578)
			(xy 179.734973 -301.977996) (xy 179.754264 -301.93272) (xy 179.780567 -301.891124) (xy 179.813202 -301.854287)
			(xy 179.851323 -301.823162) (xy 179.893944 -301.798555) (xy 179.93996 -301.781103) (xy 179.988179 -301.771259)
			(xy 180.037354 -301.769278) (xy 180.086209 -301.77521) (xy 180.13348 -301.788902) (xy 180.177942 -301.81)
			(xy 180.218445 -301.837956) (xy 180.253938 -301.872048) (xy 180.283503 -301.911392) (xy 180.306374 -301.954969)
			(xy 180.321958 -302.00165) (xy 180.329853 -302.050227) (xy 180.330348 -302.074834) (xy 180.669196 -302.074834)
			(xy 180.673156 -302.02578) (xy 180.684933 -301.977996) (xy 180.704224 -301.93272) (xy 180.730527 -301.891124)
			(xy 180.763162 -301.854287) (xy 180.801283 -301.823162) (xy 180.843904 -301.798555) (xy 180.88992 -301.781103)
			(xy 180.938139 -301.771259) (xy 180.987314 -301.769278) (xy 181.036169 -301.77521) (xy 181.08344 -301.788902)
			(xy 181.127902 -301.81) (xy 181.168405 -301.837956) (xy 181.203898 -301.872048) (xy 181.233463 -301.911392)
			(xy 181.256334 -301.954969) (xy 181.271918 -302.00165) (xy 181.279813 -302.050227) (xy 181.280308 -302.074834)
			(xy 181.619156 -302.074834) (xy 181.623116 -302.02578) (xy 181.634893 -301.977996) (xy 181.654184 -301.93272)
			(xy 181.680487 -301.891124) (xy 181.713122 -301.854287) (xy 181.751243 -301.823162) (xy 181.793864 -301.798555)
			(xy 181.83988 -301.781103) (xy 181.888099 -301.771259) (xy 181.937274 -301.769278) (xy 181.986129 -301.77521)
			(xy 182.0334 -301.788902) (xy 182.077862 -301.81) (xy 182.118365 -301.837956) (xy 182.153858 -301.872048)
			(xy 182.183423 -301.911392) (xy 182.206294 -301.954969) (xy 182.221878 -302.00165) (xy 182.229773 -302.050227)
			(xy 182.230268 -302.074834) (xy 182.569116 -302.074834) (xy 182.573076 -302.02578) (xy 182.584853 -301.977996)
			(xy 182.604144 -301.93272) (xy 182.630447 -301.891124) (xy 182.663082 -301.854287) (xy 182.701203 -301.823162)
			(xy 182.743824 -301.798555) (xy 182.78984 -301.781103) (xy 182.838059 -301.771259) (xy 182.887234 -301.769278)
			(xy 182.936089 -301.77521) (xy 182.98336 -301.788902) (xy 183.027822 -301.81) (xy 183.068325 -301.837956)
			(xy 183.103818 -301.872048) (xy 183.133383 -301.911392) (xy 183.156254 -301.954969) (xy 183.171838 -302.00165)
			(xy 183.179733 -302.050227) (xy 183.180228 -302.074834) (xy 183.519076 -302.074834) (xy 183.523036 -302.02578)
			(xy 183.534813 -301.977996) (xy 183.554104 -301.93272) (xy 183.580407 -301.891124) (xy 183.613042 -301.854287)
			(xy 183.651163 -301.823162) (xy 183.693784 -301.798555) (xy 183.7398 -301.781103) (xy 183.788019 -301.771259)
			(xy 183.837194 -301.769278) (xy 183.886049 -301.77521) (xy 183.93332 -301.788902) (xy 183.977782 -301.81)
			(xy 184.018285 -301.837956) (xy 184.053778 -301.872048) (xy 184.083343 -301.911392) (xy 184.106214 -301.954969)
			(xy 184.121798 -302.00165) (xy 184.129693 -302.050227) (xy 184.130188 -302.074834) (xy 184.469036 -302.074834)
			(xy 184.472996 -302.02578) (xy 184.484773 -301.977996) (xy 184.504064 -301.93272) (xy 184.530367 -301.891124)
			(xy 184.563002 -301.854287) (xy 184.601123 -301.823162) (xy 184.643744 -301.798555) (xy 184.68976 -301.781103)
			(xy 184.737979 -301.771259) (xy 184.787154 -301.769278) (xy 184.836009 -301.77521) (xy 184.88328 -301.788902)
			(xy 184.927742 -301.81) (xy 184.968245 -301.837956) (xy 185.003738 -301.872048) (xy 185.033303 -301.911392)
			(xy 185.056174 -301.954969) (xy 185.071758 -302.00165) (xy 185.079653 -302.050227) (xy 185.080148 -302.074834)
			(xy 185.079653 -302.099441) (xy 185.071758 -302.148018) (xy 185.056174 -302.194699) (xy 185.033303 -302.238276)
			(xy 185.003738 -302.27762) (xy 184.968245 -302.311712) (xy 184.927742 -302.339668) (xy 184.88328 -302.360766)
			(xy 184.836009 -302.374458) (xy 184.787154 -302.38039) (xy 184.737979 -302.378409) (xy 184.68976 -302.368565)
			(xy 184.643744 -302.351113) (xy 184.601123 -302.326506) (xy 184.563002 -302.295381) (xy 184.530367 -302.258544)
			(xy 184.504064 -302.216948) (xy 184.484773 -302.171672) (xy 184.472996 -302.123888) (xy 184.469036 -302.074834)
			(xy 184.130188 -302.074834) (xy 184.129693 -302.099441) (xy 184.121798 -302.148018) (xy 184.106214 -302.194699)
			(xy 184.083343 -302.238276) (xy 184.053778 -302.27762) (xy 184.018285 -302.311712) (xy 183.977782 -302.339668)
			(xy 183.93332 -302.360766) (xy 183.886049 -302.374458) (xy 183.837194 -302.38039) (xy 183.788019 -302.378409)
			(xy 183.7398 -302.368565) (xy 183.693784 -302.351113) (xy 183.651163 -302.326506) (xy 183.613042 -302.295381)
			(xy 183.580407 -302.258544) (xy 183.554104 -302.216948) (xy 183.534813 -302.171672) (xy 183.523036 -302.123888)
			(xy 183.519076 -302.074834) (xy 183.180228 -302.074834) (xy 183.179733 -302.099441) (xy 183.171838 -302.148018)
			(xy 183.156254 -302.194699) (xy 183.133383 -302.238276) (xy 183.103818 -302.27762) (xy 183.068325 -302.311712)
			(xy 183.027822 -302.339668) (xy 182.98336 -302.360766) (xy 182.936089 -302.374458) (xy 182.887234 -302.38039)
			(xy 182.838059 -302.378409) (xy 182.78984 -302.368565) (xy 182.743824 -302.351113) (xy 182.701203 -302.326506)
			(xy 182.663082 -302.295381) (xy 182.630447 -302.258544) (xy 182.604144 -302.216948) (xy 182.584853 -302.171672)
			(xy 182.573076 -302.123888) (xy 182.569116 -302.074834) (xy 182.230268 -302.074834) (xy 182.229773 -302.099441)
			(xy 182.221878 -302.148018) (xy 182.206294 -302.194699) (xy 182.183423 -302.238276) (xy 182.153858 -302.27762)
			(xy 182.118365 -302.311712) (xy 182.077862 -302.339668) (xy 182.0334 -302.360766) (xy 181.986129 -302.374458)
			(xy 181.937274 -302.38039) (xy 181.888099 -302.378409) (xy 181.83988 -302.368565) (xy 181.793864 -302.351113)
			(xy 181.751243 -302.326506) (xy 181.713122 -302.295381) (xy 181.680487 -302.258544) (xy 181.654184 -302.216948)
			(xy 181.634893 -302.171672) (xy 181.623116 -302.123888) (xy 181.619156 -302.074834) (xy 181.280308 -302.074834)
			(xy 181.279813 -302.099441) (xy 181.271918 -302.148018) (xy 181.256334 -302.194699) (xy 181.233463 -302.238276)
			(xy 181.203898 -302.27762) (xy 181.168405 -302.311712) (xy 181.127902 -302.339668) (xy 181.08344 -302.360766)
			(xy 181.036169 -302.374458) (xy 180.987314 -302.38039) (xy 180.938139 -302.378409) (xy 180.88992 -302.368565)
			(xy 180.843904 -302.351113) (xy 180.801283 -302.326506) (xy 180.763162 -302.295381) (xy 180.730527 -302.258544)
			(xy 180.704224 -302.216948) (xy 180.684933 -302.171672) (xy 180.673156 -302.123888) (xy 180.669196 -302.074834)
			(xy 180.330348 -302.074834) (xy 180.329853 -302.099441) (xy 180.321958 -302.148018) (xy 180.306374 -302.194699)
			(xy 180.283503 -302.238276) (xy 180.253938 -302.27762) (xy 180.218445 -302.311712) (xy 180.177942 -302.339668)
			(xy 180.13348 -302.360766) (xy 180.086209 -302.374458) (xy 180.037354 -302.38039) (xy 179.988179 -302.378409)
			(xy 179.93996 -302.368565) (xy 179.893944 -302.351113) (xy 179.851323 -302.326506) (xy 179.813202 -302.295381)
			(xy 179.780567 -302.258544) (xy 179.754264 -302.216948) (xy 179.734973 -302.171672) (xy 179.723196 -302.123888)
			(xy 179.719236 -302.074834) (xy 179.380388 -302.074834) (xy 179.379893 -302.099441) (xy 179.371998 -302.148018)
			(xy 179.356414 -302.194699) (xy 179.333543 -302.238276) (xy 179.303978 -302.27762) (xy 179.268485 -302.311712)
			(xy 179.227982 -302.339668) (xy 179.18352 -302.360766) (xy 179.136249 -302.374458) (xy 179.087394 -302.38039)
			(xy 179.038219 -302.378409) (xy 178.99 -302.368565) (xy 178.943984 -302.351113) (xy 178.901363 -302.326506)
			(xy 178.863242 -302.295381) (xy 178.830607 -302.258544) (xy 178.804304 -302.216948) (xy 178.785013 -302.171672)
			(xy 178.773236 -302.123888) (xy 178.769276 -302.074834) (xy 178.430174 -302.074834) (xy 178.429679 -302.099441)
			(xy 178.421784 -302.148018) (xy 178.4062 -302.194699) (xy 178.383329 -302.238276) (xy 178.353764 -302.27762)
			(xy 178.318271 -302.311712) (xy 178.277768 -302.339668) (xy 178.233306 -302.360766) (xy 178.186035 -302.374458)
			(xy 178.13718 -302.38039) (xy 178.088005 -302.378409) (xy 178.039786 -302.368565) (xy 177.99377 -302.351113)
			(xy 177.951149 -302.326506) (xy 177.913028 -302.295381) (xy 177.880393 -302.258544) (xy 177.85409 -302.216948)
			(xy 177.834799 -302.171672) (xy 177.823022 -302.123888) (xy 177.819062 -302.074834) (xy 177.480214 -302.074834)
			(xy 177.479719 -302.099441) (xy 177.471824 -302.148018) (xy 177.45624 -302.194699) (xy 177.433369 -302.238276)
			(xy 177.403804 -302.27762) (xy 177.368311 -302.311712) (xy 177.327808 -302.339668) (xy 177.283346 -302.360766)
			(xy 177.236075 -302.374458) (xy 177.18722 -302.38039) (xy 177.138045 -302.378409) (xy 177.089826 -302.368565)
			(xy 177.04381 -302.351113) (xy 177.001189 -302.326506) (xy 176.963068 -302.295381) (xy 176.930433 -302.258544)
			(xy 176.90413 -302.216948) (xy 176.884839 -302.171672) (xy 176.873062 -302.123888) (xy 176.869102 -302.074834)
			(xy 176.530254 -302.074834) (xy 176.529759 -302.099441) (xy 176.521864 -302.148018) (xy 176.50628 -302.194699)
			(xy 176.483409 -302.238276) (xy 176.453844 -302.27762) (xy 176.418351 -302.311712) (xy 176.377848 -302.339668)
			(xy 176.333386 -302.360766) (xy 176.286115 -302.374458) (xy 176.23726 -302.38039) (xy 176.188085 -302.378409)
			(xy 176.139866 -302.368565) (xy 176.09385 -302.351113) (xy 176.051229 -302.326506) (xy 176.013108 -302.295381)
			(xy 175.980473 -302.258544) (xy 175.95417 -302.216948) (xy 175.934879 -302.171672) (xy 175.923102 -302.123888)
			(xy 175.919142 -302.074834) (xy 174.630334 -302.074834) (xy 174.629839 -302.099441) (xy 174.621944 -302.148018)
			(xy 174.60636 -302.194699) (xy 174.583489 -302.238276) (xy 174.553924 -302.27762) (xy 174.518431 -302.311712)
			(xy 174.477928 -302.339668) (xy 174.433466 -302.360766) (xy 174.386195 -302.374458) (xy 174.33734 -302.38039)
			(xy 174.288165 -302.378409) (xy 174.239946 -302.368565) (xy 174.19393 -302.351113) (xy 174.151309 -302.326506)
			(xy 174.113188 -302.295381) (xy 174.080553 -302.258544) (xy 174.05425 -302.216948) (xy 174.034959 -302.171672)
			(xy 174.023182 -302.123888) (xy 174.019222 -302.074834) (xy 173.680374 -302.074834) (xy 173.679879 -302.099441)
			(xy 173.671984 -302.148018) (xy 173.6564 -302.194699) (xy 173.633529 -302.238276) (xy 173.603964 -302.27762)
			(xy 173.568471 -302.311712) (xy 173.527968 -302.339668) (xy 173.483506 -302.360766) (xy 173.436235 -302.374458)
			(xy 173.38738 -302.38039) (xy 173.338205 -302.378409) (xy 173.289986 -302.368565) (xy 173.24397 -302.351113)
			(xy 173.201349 -302.326506) (xy 173.163228 -302.295381) (xy 173.130593 -302.258544) (xy 173.10429 -302.216948)
			(xy 173.084999 -302.171672) (xy 173.073222 -302.123888) (xy 173.069262 -302.074834) (xy 172.73016 -302.074834)
			(xy 172.729665 -302.099441) (xy 172.72177 -302.148018) (xy 172.706186 -302.194699) (xy 172.683315 -302.238276)
			(xy 172.65375 -302.27762) (xy 172.618257 -302.311712) (xy 172.577754 -302.339668) (xy 172.533292 -302.360766)
			(xy 172.486021 -302.374458) (xy 172.437166 -302.38039) (xy 172.387991 -302.378409) (xy 172.339772 -302.368565)
			(xy 172.293756 -302.351113) (xy 172.251135 -302.326506) (xy 172.213014 -302.295381) (xy 172.180379 -302.258544)
			(xy 172.154076 -302.216948) (xy 172.134785 -302.171672) (xy 172.123008 -302.123888) (xy 172.119048 -302.074834)
			(xy 171.7802 -302.074834) (xy 171.779705 -302.099441) (xy 171.77181 -302.148018) (xy 171.756226 -302.194699)
			(xy 171.733355 -302.238276) (xy 171.70379 -302.27762) (xy 171.668297 -302.311712) (xy 171.627794 -302.339668)
			(xy 171.583332 -302.360766) (xy 171.536061 -302.374458) (xy 171.487206 -302.38039) (xy 171.438031 -302.378409)
			(xy 171.389812 -302.368565) (xy 171.343796 -302.351113) (xy 171.301175 -302.326506) (xy 171.263054 -302.295381)
			(xy 171.230419 -302.258544) (xy 171.204116 -302.216948) (xy 171.184825 -302.171672) (xy 171.173048 -302.123888)
			(xy 171.169088 -302.074834) (xy 170.83024 -302.074834) (xy 170.829745 -302.099441) (xy 170.82185 -302.148018)
			(xy 170.806266 -302.194699) (xy 170.783395 -302.238276) (xy 170.75383 -302.27762) (xy 170.718337 -302.311712)
			(xy 170.677834 -302.339668) (xy 170.633372 -302.360766) (xy 170.586101 -302.374458) (xy 170.537246 -302.38039)
			(xy 170.488071 -302.378409) (xy 170.439852 -302.368565) (xy 170.393836 -302.351113) (xy 170.351215 -302.326506)
			(xy 170.313094 -302.295381) (xy 170.280459 -302.258544) (xy 170.254156 -302.216948) (xy 170.234865 -302.171672)
			(xy 170.223088 -302.123888) (xy 170.219128 -302.074834) (xy 169.88028 -302.074834) (xy 169.879785 -302.099441)
			(xy 169.87189 -302.148018) (xy 169.856306 -302.194699) (xy 169.833435 -302.238276) (xy 169.80387 -302.27762)
			(xy 169.768377 -302.311712) (xy 169.727874 -302.339668) (xy 169.683412 -302.360766) (xy 169.636141 -302.374458)
			(xy 169.587286 -302.38039) (xy 169.538111 -302.378409) (xy 169.489892 -302.368565) (xy 169.443876 -302.351113)
			(xy 169.401255 -302.326506) (xy 169.363134 -302.295381) (xy 169.330499 -302.258544) (xy 169.304196 -302.216948)
			(xy 169.284905 -302.171672) (xy 169.273128 -302.123888) (xy 169.269168 -302.074834) (xy 168.93032 -302.074834)
			(xy 168.929825 -302.099441) (xy 168.92193 -302.148018) (xy 168.906346 -302.194699) (xy 168.883475 -302.238276)
			(xy 168.85391 -302.27762) (xy 168.818417 -302.311712) (xy 168.777914 -302.339668) (xy 168.733452 -302.360766)
			(xy 168.686181 -302.374458) (xy 168.637326 -302.38039) (xy 168.588151 -302.378409) (xy 168.539932 -302.368565)
			(xy 168.493916 -302.351113) (xy 168.451295 -302.326506) (xy 168.413174 -302.295381) (xy 168.380539 -302.258544)
			(xy 168.354236 -302.216948) (xy 168.334945 -302.171672) (xy 168.323168 -302.123888) (xy 168.319208 -302.074834)
			(xy 167.98036 -302.074834) (xy 167.979865 -302.099441) (xy 167.97197 -302.148018) (xy 167.956386 -302.194699)
			(xy 167.933515 -302.238276) (xy 167.90395 -302.27762) (xy 167.868457 -302.311712) (xy 167.827954 -302.339668)
			(xy 167.783492 -302.360766) (xy 167.736221 -302.374458) (xy 167.687366 -302.38039) (xy 167.638191 -302.378409)
			(xy 167.589972 -302.368565) (xy 167.543956 -302.351113) (xy 167.501335 -302.326506) (xy 167.463214 -302.295381)
			(xy 167.430579 -302.258544) (xy 167.404276 -302.216948) (xy 167.384985 -302.171672) (xy 167.373208 -302.123888)
			(xy 167.369248 -302.074834) (xy 167.0304 -302.074834) (xy 167.029905 -302.099441) (xy 167.02201 -302.148018)
			(xy 167.006426 -302.194699) (xy 166.983555 -302.238276) (xy 166.95399 -302.27762) (xy 166.918497 -302.311712)
			(xy 166.877994 -302.339668) (xy 166.833532 -302.360766) (xy 166.786261 -302.374458) (xy 166.737406 -302.38039)
			(xy 166.688231 -302.378409) (xy 166.640012 -302.368565) (xy 166.593996 -302.351113) (xy 166.551375 -302.326506)
			(xy 166.513254 -302.295381) (xy 166.480619 -302.258544) (xy 166.454316 -302.216948) (xy 166.435025 -302.171672)
			(xy 166.423248 -302.123888) (xy 166.419288 -302.074834) (xy 166.080186 -302.074834) (xy 166.079691 -302.099441)
			(xy 166.071796 -302.148018) (xy 166.056212 -302.194699) (xy 166.033341 -302.238276) (xy 166.003776 -302.27762)
			(xy 165.968283 -302.311712) (xy 165.92778 -302.339668) (xy 165.883318 -302.360766) (xy 165.836047 -302.374458)
			(xy 165.787192 -302.38039) (xy 165.738017 -302.378409) (xy 165.689798 -302.368565) (xy 165.643782 -302.351113)
			(xy 165.601161 -302.326506) (xy 165.56304 -302.295381) (xy 165.530405 -302.258544) (xy 165.504102 -302.216948)
			(xy 165.484811 -302.171672) (xy 165.473034 -302.123888) (xy 165.469074 -302.074834) (xy 162.280862 -302.074834)
			(xy 162.276694 -302.12514) (xy 162.264295 -302.174107) (xy 162.244006 -302.220365) (xy 162.21638 -302.262654)
			(xy 162.182171 -302.299819) (xy 162.142312 -302.330847) (xy 162.09789 -302.354892) (xy 162.050116 -302.371298)
			(xy 162.000294 -302.379617) (xy 161.975038 -302.380142) (xy 161.960855 -302.37996) (xy 161.932615 -302.377291)
			(xy 161.91865 -302.374808) (xy 161.906204 -302.372522) (xy 161.882582 -302.379888) (xy 161.805112 -302.457358)
			(xy 161.797746 -302.48098) (xy 161.800032 -302.493426) (xy 161.802508 -302.507392) (xy 161.80518 -302.535631)
			(xy 161.805366 -302.549814) (xy 161.805192 -302.563997) (xy 161.802518 -302.592237) (xy 161.800032 -302.606202)
			(xy 161.797746 -302.618648) (xy 161.805112 -302.64227) (xy 161.882582 -302.71974) (xy 161.906204 -302.727106)
			(xy 161.91865 -302.72482) (xy 161.932615 -302.722341) (xy 161.960855 -302.719671) (xy 161.975038 -302.719486)
			(xy 162.000291 -302.720023) (xy 162.050107 -302.728341) (xy 162.097874 -302.744745) (xy 162.142291 -302.768787)
			(xy 162.182144 -302.799811) (xy 162.216349 -302.836971) (xy 162.243971 -302.879254) (xy 162.264257 -302.925506)
			(xy 162.276655 -302.974467) (xy 162.280825 -303.024794) (xy 162.619194 -303.024794) (xy 162.623154 -302.97574)
			(xy 162.634931 -302.927956) (xy 162.654222 -302.88268) (xy 162.680525 -302.841084) (xy 162.71316 -302.804247)
			(xy 162.751281 -302.773122) (xy 162.793902 -302.748515) (xy 162.839918 -302.731063) (xy 162.888137 -302.721219)
			(xy 162.937312 -302.719238) (xy 162.986167 -302.72517) (xy 163.033438 -302.738862) (xy 163.0779 -302.75996)
			(xy 163.118403 -302.787916) (xy 163.153896 -302.822008) (xy 163.183461 -302.861352) (xy 163.206332 -302.904929)
			(xy 163.221916 -302.95161) (xy 163.229811 -303.000187) (xy 163.230306 -303.024794) (xy 163.569154 -303.024794)
			(xy 163.573114 -302.97574) (xy 163.584891 -302.927956) (xy 163.604182 -302.88268) (xy 163.630485 -302.841084)
			(xy 163.66312 -302.804247) (xy 163.701241 -302.773122) (xy 163.743862 -302.748515) (xy 163.789878 -302.731063)
			(xy 163.838097 -302.721219) (xy 163.887272 -302.719238) (xy 163.936127 -302.72517) (xy 163.983398 -302.738862)
			(xy 164.02786 -302.75996) (xy 164.068363 -302.787916) (xy 164.103856 -302.822008) (xy 164.133421 -302.861352)
			(xy 164.156292 -302.904929) (xy 164.171876 -302.95161) (xy 164.179771 -303.000187) (xy 164.180266 -303.024794)
			(xy 164.519114 -303.024794) (xy 164.523074 -302.97574) (xy 164.534851 -302.927956) (xy 164.554142 -302.88268)
			(xy 164.580445 -302.841084) (xy 164.61308 -302.804247) (xy 164.651201 -302.773122) (xy 164.693822 -302.748515)
			(xy 164.739838 -302.731063) (xy 164.788057 -302.721219) (xy 164.837232 -302.719238) (xy 164.886087 -302.72517)
			(xy 164.933358 -302.738862) (xy 164.97782 -302.75996) (xy 165.018323 -302.787916) (xy 165.053816 -302.822008)
			(xy 165.083381 -302.861352) (xy 165.106252 -302.904929) (xy 165.121836 -302.95161) (xy 165.129731 -303.000187)
			(xy 165.130226 -303.024794) (xy 165.469074 -303.024794) (xy 165.473034 -302.97574) (xy 165.484811 -302.927956)
			(xy 165.504102 -302.88268) (xy 165.530405 -302.841084) (xy 165.56304 -302.804247) (xy 165.601161 -302.773122)
			(xy 165.643782 -302.748515) (xy 165.689798 -302.731063) (xy 165.738017 -302.721219) (xy 165.787192 -302.719238)
			(xy 165.836047 -302.72517) (xy 165.883318 -302.738862) (xy 165.92778 -302.75996) (xy 165.968283 -302.787916)
			(xy 166.003776 -302.822008) (xy 166.033341 -302.861352) (xy 166.056212 -302.904929) (xy 166.071796 -302.95161)
			(xy 166.079691 -303.000187) (xy 166.080186 -303.024794) (xy 166.419288 -303.024794) (xy 166.423248 -302.97574)
			(xy 166.435025 -302.927956) (xy 166.454316 -302.88268) (xy 166.480619 -302.841084) (xy 166.513254 -302.804247)
			(xy 166.551375 -302.773122) (xy 166.593996 -302.748515) (xy 166.640012 -302.731063) (xy 166.688231 -302.721219)
			(xy 166.737406 -302.719238) (xy 166.786261 -302.72517) (xy 166.833532 -302.738862) (xy 166.877994 -302.75996)
			(xy 166.918497 -302.787916) (xy 166.95399 -302.822008) (xy 166.983555 -302.861352) (xy 167.006426 -302.904929)
			(xy 167.02201 -302.95161) (xy 167.029905 -303.000187) (xy 167.0304 -303.024794) (xy 167.369248 -303.024794)
			(xy 167.373208 -302.97574) (xy 167.384985 -302.927956) (xy 167.404276 -302.88268) (xy 167.430579 -302.841084)
			(xy 167.463214 -302.804247) (xy 167.501335 -302.773122) (xy 167.543956 -302.748515) (xy 167.589972 -302.731063)
			(xy 167.638191 -302.721219) (xy 167.687366 -302.719238) (xy 167.736221 -302.72517) (xy 167.783492 -302.738862)
			(xy 167.827954 -302.75996) (xy 167.868457 -302.787916) (xy 167.90395 -302.822008) (xy 167.933515 -302.861352)
			(xy 167.956386 -302.904929) (xy 167.97197 -302.95161) (xy 167.979865 -303.000187) (xy 167.98036 -303.024794)
			(xy 168.319208 -303.024794) (xy 168.323168 -302.97574) (xy 168.334945 -302.927956) (xy 168.354236 -302.88268)
			(xy 168.380539 -302.841084) (xy 168.413174 -302.804247) (xy 168.451295 -302.773122) (xy 168.493916 -302.748515)
			(xy 168.539932 -302.731063) (xy 168.588151 -302.721219) (xy 168.637326 -302.719238) (xy 168.686181 -302.72517)
			(xy 168.733452 -302.738862) (xy 168.777914 -302.75996) (xy 168.818417 -302.787916) (xy 168.85391 -302.822008)
			(xy 168.883475 -302.861352) (xy 168.906346 -302.904929) (xy 168.92193 -302.95161) (xy 168.929825 -303.000187)
			(xy 168.93032 -303.024794) (xy 169.269168 -303.024794) (xy 169.273128 -302.97574) (xy 169.284905 -302.927956)
			(xy 169.304196 -302.88268) (xy 169.330499 -302.841084) (xy 169.363134 -302.804247) (xy 169.401255 -302.773122)
			(xy 169.443876 -302.748515) (xy 169.489892 -302.731063) (xy 169.538111 -302.721219) (xy 169.587286 -302.719238)
			(xy 169.636141 -302.72517) (xy 169.683412 -302.738862) (xy 169.727874 -302.75996) (xy 169.768377 -302.787916)
			(xy 169.80387 -302.822008) (xy 169.833435 -302.861352) (xy 169.856306 -302.904929) (xy 169.87189 -302.95161)
			(xy 169.879785 -303.000187) (xy 169.88028 -303.024794) (xy 170.219128 -303.024794) (xy 170.223088 -302.97574)
			(xy 170.234865 -302.927956) (xy 170.254156 -302.88268) (xy 170.280459 -302.841084) (xy 170.313094 -302.804247)
			(xy 170.351215 -302.773122) (xy 170.393836 -302.748515) (xy 170.439852 -302.731063) (xy 170.488071 -302.721219)
			(xy 170.537246 -302.719238) (xy 170.586101 -302.72517) (xy 170.633372 -302.738862) (xy 170.677834 -302.75996)
			(xy 170.718337 -302.787916) (xy 170.75383 -302.822008) (xy 170.783395 -302.861352) (xy 170.806266 -302.904929)
			(xy 170.82185 -302.95161) (xy 170.829745 -303.000187) (xy 170.83024 -303.024794) (xy 171.169088 -303.024794)
			(xy 171.173048 -302.97574) (xy 171.184825 -302.927956) (xy 171.204116 -302.88268) (xy 171.230419 -302.841084)
			(xy 171.263054 -302.804247) (xy 171.301175 -302.773122) (xy 171.343796 -302.748515) (xy 171.389812 -302.731063)
			(xy 171.438031 -302.721219) (xy 171.487206 -302.719238) (xy 171.536061 -302.72517) (xy 171.583332 -302.738862)
			(xy 171.627794 -302.75996) (xy 171.668297 -302.787916) (xy 171.70379 -302.822008) (xy 171.733355 -302.861352)
			(xy 171.756226 -302.904929) (xy 171.77181 -302.95161) (xy 171.779705 -303.000187) (xy 171.7802 -303.024794)
			(xy 172.119048 -303.024794) (xy 172.123008 -302.97574) (xy 172.134785 -302.927956) (xy 172.154076 -302.88268)
			(xy 172.180379 -302.841084) (xy 172.213014 -302.804247) (xy 172.251135 -302.773122) (xy 172.293756 -302.748515)
			(xy 172.339772 -302.731063) (xy 172.387991 -302.721219) (xy 172.437166 -302.719238) (xy 172.486021 -302.72517)
			(xy 172.533292 -302.738862) (xy 172.577754 -302.75996) (xy 172.618257 -302.787916) (xy 172.65375 -302.822008)
			(xy 172.683315 -302.861352) (xy 172.706186 -302.904929) (xy 172.72177 -302.95161) (xy 172.729665 -303.000187)
			(xy 172.73016 -303.024794) (xy 173.069262 -303.024794) (xy 173.073222 -302.97574) (xy 173.084999 -302.927956)
			(xy 173.10429 -302.88268) (xy 173.130593 -302.841084) (xy 173.163228 -302.804247) (xy 173.201349 -302.773122)
			(xy 173.24397 -302.748515) (xy 173.289986 -302.731063) (xy 173.338205 -302.721219) (xy 173.38738 -302.719238)
			(xy 173.436235 -302.72517) (xy 173.483506 -302.738862) (xy 173.527968 -302.75996) (xy 173.568471 -302.787916)
			(xy 173.603964 -302.822008) (xy 173.633529 -302.861352) (xy 173.6564 -302.904929) (xy 173.671984 -302.95161)
			(xy 173.679879 -303.000187) (xy 173.680374 -303.024794) (xy 174.019222 -303.024794) (xy 174.023182 -302.97574)
			(xy 174.034959 -302.927956) (xy 174.05425 -302.88268) (xy 174.080553 -302.841084) (xy 174.113188 -302.804247)
			(xy 174.151309 -302.773122) (xy 174.19393 -302.748515) (xy 174.239946 -302.731063) (xy 174.288165 -302.721219)
			(xy 174.33734 -302.719238) (xy 174.386195 -302.72517) (xy 174.433466 -302.738862) (xy 174.477928 -302.75996)
			(xy 174.518431 -302.787916) (xy 174.553924 -302.822008) (xy 174.583489 -302.861352) (xy 174.60636 -302.904929)
			(xy 174.621944 -302.95161) (xy 174.629839 -303.000187) (xy 174.630334 -303.024794) (xy 175.919142 -303.024794)
			(xy 175.923102 -302.97574) (xy 175.934879 -302.927956) (xy 175.95417 -302.88268) (xy 175.980473 -302.841084)
			(xy 176.013108 -302.804247) (xy 176.051229 -302.773122) (xy 176.09385 -302.748515) (xy 176.139866 -302.731063)
			(xy 176.188085 -302.721219) (xy 176.23726 -302.719238) (xy 176.286115 -302.72517) (xy 176.333386 -302.738862)
			(xy 176.377848 -302.75996) (xy 176.418351 -302.787916) (xy 176.453844 -302.822008) (xy 176.483409 -302.861352)
			(xy 176.50628 -302.904929) (xy 176.521864 -302.95161) (xy 176.529759 -303.000187) (xy 176.530254 -303.024794)
			(xy 176.869102 -303.024794) (xy 176.873062 -302.97574) (xy 176.884839 -302.927956) (xy 176.90413 -302.88268)
			(xy 176.930433 -302.841084) (xy 176.963068 -302.804247) (xy 177.001189 -302.773122) (xy 177.04381 -302.748515)
			(xy 177.089826 -302.731063) (xy 177.138045 -302.721219) (xy 177.18722 -302.719238) (xy 177.236075 -302.72517)
			(xy 177.283346 -302.738862) (xy 177.327808 -302.75996) (xy 177.368311 -302.787916) (xy 177.403804 -302.822008)
			(xy 177.433369 -302.861352) (xy 177.45624 -302.904929) (xy 177.471824 -302.95161) (xy 177.479719 -303.000187)
			(xy 177.480214 -303.024794) (xy 177.819062 -303.024794) (xy 177.823022 -302.97574) (xy 177.834799 -302.927956)
			(xy 177.85409 -302.88268) (xy 177.880393 -302.841084) (xy 177.913028 -302.804247) (xy 177.951149 -302.773122)
			(xy 177.99377 -302.748515) (xy 178.039786 -302.731063) (xy 178.088005 -302.721219) (xy 178.13718 -302.719238)
			(xy 178.186035 -302.72517) (xy 178.233306 -302.738862) (xy 178.277768 -302.75996) (xy 178.318271 -302.787916)
			(xy 178.353764 -302.822008) (xy 178.383329 -302.861352) (xy 178.4062 -302.904929) (xy 178.421784 -302.95161)
			(xy 178.429679 -303.000187) (xy 178.430174 -303.024794) (xy 178.769276 -303.024794) (xy 178.773236 -302.97574)
			(xy 178.785013 -302.927956) (xy 178.804304 -302.88268) (xy 178.830607 -302.841084) (xy 178.863242 -302.804247)
			(xy 178.901363 -302.773122) (xy 178.943984 -302.748515) (xy 178.99 -302.731063) (xy 179.038219 -302.721219)
			(xy 179.087394 -302.719238) (xy 179.136249 -302.72517) (xy 179.18352 -302.738862) (xy 179.227982 -302.75996)
			(xy 179.268485 -302.787916) (xy 179.303978 -302.822008) (xy 179.333543 -302.861352) (xy 179.356414 -302.904929)
			(xy 179.371998 -302.95161) (xy 179.379893 -303.000187) (xy 179.380388 -303.024794) (xy 179.719236 -303.024794)
			(xy 179.723196 -302.97574) (xy 179.734973 -302.927956) (xy 179.754264 -302.88268) (xy 179.780567 -302.841084)
			(xy 179.813202 -302.804247) (xy 179.851323 -302.773122) (xy 179.893944 -302.748515) (xy 179.93996 -302.731063)
			(xy 179.988179 -302.721219) (xy 180.037354 -302.719238) (xy 180.086209 -302.72517) (xy 180.13348 -302.738862)
			(xy 180.177942 -302.75996) (xy 180.218445 -302.787916) (xy 180.253938 -302.822008) (xy 180.283503 -302.861352)
			(xy 180.306374 -302.904929) (xy 180.321958 -302.95161) (xy 180.329853 -303.000187) (xy 180.330348 -303.024794)
			(xy 180.669196 -303.024794) (xy 180.673156 -302.97574) (xy 180.684933 -302.927956) (xy 180.704224 -302.88268)
			(xy 180.730527 -302.841084) (xy 180.763162 -302.804247) (xy 180.801283 -302.773122) (xy 180.843904 -302.748515)
			(xy 180.88992 -302.731063) (xy 180.938139 -302.721219) (xy 180.987314 -302.719238) (xy 181.036169 -302.72517)
			(xy 181.08344 -302.738862) (xy 181.127902 -302.75996) (xy 181.168405 -302.787916) (xy 181.203898 -302.822008)
			(xy 181.233463 -302.861352) (xy 181.256334 -302.904929) (xy 181.271918 -302.95161) (xy 181.279813 -303.000187)
			(xy 181.280308 -303.024794) (xy 181.619156 -303.024794) (xy 181.623116 -302.97574) (xy 181.634893 -302.927956)
			(xy 181.654184 -302.88268) (xy 181.680487 -302.841084) (xy 181.713122 -302.804247) (xy 181.751243 -302.773122)
			(xy 181.793864 -302.748515) (xy 181.83988 -302.731063) (xy 181.888099 -302.721219) (xy 181.937274 -302.719238)
			(xy 181.986129 -302.72517) (xy 182.0334 -302.738862) (xy 182.077862 -302.75996) (xy 182.118365 -302.787916)
			(xy 182.153858 -302.822008) (xy 182.183423 -302.861352) (xy 182.206294 -302.904929) (xy 182.221878 -302.95161)
			(xy 182.229773 -303.000187) (xy 182.230268 -303.024794) (xy 182.569116 -303.024794) (xy 182.573076 -302.97574)
			(xy 182.584853 -302.927956) (xy 182.604144 -302.88268) (xy 182.630447 -302.841084) (xy 182.663082 -302.804247)
			(xy 182.701203 -302.773122) (xy 182.743824 -302.748515) (xy 182.78984 -302.731063) (xy 182.838059 -302.721219)
			(xy 182.887234 -302.719238) (xy 182.936089 -302.72517) (xy 182.98336 -302.738862) (xy 183.027822 -302.75996)
			(xy 183.068325 -302.787916) (xy 183.103818 -302.822008) (xy 183.133383 -302.861352) (xy 183.156254 -302.904929)
			(xy 183.171838 -302.95161) (xy 183.179733 -303.000187) (xy 183.180228 -303.024794) (xy 183.519076 -303.024794)
			(xy 183.523036 -302.97574) (xy 183.534813 -302.927956) (xy 183.554104 -302.88268) (xy 183.580407 -302.841084)
			(xy 183.613042 -302.804247) (xy 183.651163 -302.773122) (xy 183.693784 -302.748515) (xy 183.7398 -302.731063)
			(xy 183.788019 -302.721219) (xy 183.837194 -302.719238) (xy 183.886049 -302.72517) (xy 183.93332 -302.738862)
			(xy 183.977782 -302.75996) (xy 184.018285 -302.787916) (xy 184.053778 -302.822008) (xy 184.083343 -302.861352)
			(xy 184.106214 -302.904929) (xy 184.121798 -302.95161) (xy 184.129693 -303.000187) (xy 184.130188 -303.024794)
			(xy 184.469036 -303.024794) (xy 184.472996 -302.97574) (xy 184.484773 -302.927956) (xy 184.504064 -302.88268)
			(xy 184.530367 -302.841084) (xy 184.563002 -302.804247) (xy 184.601123 -302.773122) (xy 184.643744 -302.748515)
			(xy 184.68976 -302.731063) (xy 184.737979 -302.721219) (xy 184.787154 -302.719238) (xy 184.836009 -302.72517)
			(xy 184.88328 -302.738862) (xy 184.927742 -302.75996) (xy 184.968245 -302.787916) (xy 185.003738 -302.822008)
			(xy 185.033303 -302.861352) (xy 185.056174 -302.904929) (xy 185.071758 -302.95161) (xy 185.079653 -303.000187)
			(xy 185.080148 -303.024794) (xy 185.079653 -303.049401) (xy 185.071758 -303.097978) (xy 185.056174 -303.144659)
			(xy 185.033303 -303.188236) (xy 185.003738 -303.22758) (xy 184.968245 -303.261672) (xy 184.927742 -303.289628)
			(xy 184.88328 -303.310726) (xy 184.836009 -303.324418) (xy 184.787154 -303.33035) (xy 184.737979 -303.328369)
			(xy 184.68976 -303.318525) (xy 184.643744 -303.301073) (xy 184.601123 -303.276466) (xy 184.563002 -303.245341)
			(xy 184.530367 -303.208504) (xy 184.504064 -303.166908) (xy 184.484773 -303.121632) (xy 184.472996 -303.073848)
			(xy 184.469036 -303.024794) (xy 184.130188 -303.024794) (xy 184.129693 -303.049401) (xy 184.121798 -303.097978)
			(xy 184.106214 -303.144659) (xy 184.083343 -303.188236) (xy 184.053778 -303.22758) (xy 184.018285 -303.261672)
			(xy 183.977782 -303.289628) (xy 183.93332 -303.310726) (xy 183.886049 -303.324418) (xy 183.837194 -303.33035)
			(xy 183.788019 -303.328369) (xy 183.7398 -303.318525) (xy 183.693784 -303.301073) (xy 183.651163 -303.276466)
			(xy 183.613042 -303.245341) (xy 183.580407 -303.208504) (xy 183.554104 -303.166908) (xy 183.534813 -303.121632)
			(xy 183.523036 -303.073848) (xy 183.519076 -303.024794) (xy 183.180228 -303.024794) (xy 183.179733 -303.049401)
			(xy 183.171838 -303.097978) (xy 183.156254 -303.144659) (xy 183.133383 -303.188236) (xy 183.103818 -303.22758)
			(xy 183.068325 -303.261672) (xy 183.027822 -303.289628) (xy 182.98336 -303.310726) (xy 182.936089 -303.324418)
			(xy 182.887234 -303.33035) (xy 182.838059 -303.328369) (xy 182.78984 -303.318525) (xy 182.743824 -303.301073)
			(xy 182.701203 -303.276466) (xy 182.663082 -303.245341) (xy 182.630447 -303.208504) (xy 182.604144 -303.166908)
			(xy 182.584853 -303.121632) (xy 182.573076 -303.073848) (xy 182.569116 -303.024794) (xy 182.230268 -303.024794)
			(xy 182.229773 -303.049401) (xy 182.221878 -303.097978) (xy 182.206294 -303.144659) (xy 182.183423 -303.188236)
			(xy 182.153858 -303.22758) (xy 182.118365 -303.261672) (xy 182.077862 -303.289628) (xy 182.0334 -303.310726)
			(xy 181.986129 -303.324418) (xy 181.937274 -303.33035) (xy 181.888099 -303.328369) (xy 181.83988 -303.318525)
			(xy 181.793864 -303.301073) (xy 181.751243 -303.276466) (xy 181.713122 -303.245341) (xy 181.680487 -303.208504)
			(xy 181.654184 -303.166908) (xy 181.634893 -303.121632) (xy 181.623116 -303.073848) (xy 181.619156 -303.024794)
			(xy 181.280308 -303.024794) (xy 181.279813 -303.049401) (xy 181.271918 -303.097978) (xy 181.256334 -303.144659)
			(xy 181.233463 -303.188236) (xy 181.203898 -303.22758) (xy 181.168405 -303.261672) (xy 181.127902 -303.289628)
			(xy 181.08344 -303.310726) (xy 181.036169 -303.324418) (xy 180.987314 -303.33035) (xy 180.938139 -303.328369)
			(xy 180.88992 -303.318525) (xy 180.843904 -303.301073) (xy 180.801283 -303.276466) (xy 180.763162 -303.245341)
			(xy 180.730527 -303.208504) (xy 180.704224 -303.166908) (xy 180.684933 -303.121632) (xy 180.673156 -303.073848)
			(xy 180.669196 -303.024794) (xy 180.330348 -303.024794) (xy 180.329853 -303.049401) (xy 180.321958 -303.097978)
			(xy 180.306374 -303.144659) (xy 180.283503 -303.188236) (xy 180.253938 -303.22758) (xy 180.218445 -303.261672)
			(xy 180.177942 -303.289628) (xy 180.13348 -303.310726) (xy 180.086209 -303.324418) (xy 180.037354 -303.33035)
			(xy 179.988179 -303.328369) (xy 179.93996 -303.318525) (xy 179.893944 -303.301073) (xy 179.851323 -303.276466)
			(xy 179.813202 -303.245341) (xy 179.780567 -303.208504) (xy 179.754264 -303.166908) (xy 179.734973 -303.121632)
			(xy 179.723196 -303.073848) (xy 179.719236 -303.024794) (xy 179.380388 -303.024794) (xy 179.379893 -303.049401)
			(xy 179.371998 -303.097978) (xy 179.356414 -303.144659) (xy 179.333543 -303.188236) (xy 179.303978 -303.22758)
			(xy 179.268485 -303.261672) (xy 179.227982 -303.289628) (xy 179.18352 -303.310726) (xy 179.136249 -303.324418)
			(xy 179.087394 -303.33035) (xy 179.038219 -303.328369) (xy 178.99 -303.318525) (xy 178.943984 -303.301073)
			(xy 178.901363 -303.276466) (xy 178.863242 -303.245341) (xy 178.830607 -303.208504) (xy 178.804304 -303.166908)
			(xy 178.785013 -303.121632) (xy 178.773236 -303.073848) (xy 178.769276 -303.024794) (xy 178.430174 -303.024794)
			(xy 178.429679 -303.049401) (xy 178.421784 -303.097978) (xy 178.4062 -303.144659) (xy 178.383329 -303.188236)
			(xy 178.353764 -303.22758) (xy 178.318271 -303.261672) (xy 178.277768 -303.289628) (xy 178.233306 -303.310726)
			(xy 178.186035 -303.324418) (xy 178.13718 -303.33035) (xy 178.088005 -303.328369) (xy 178.039786 -303.318525)
			(xy 177.99377 -303.301073) (xy 177.951149 -303.276466) (xy 177.913028 -303.245341) (xy 177.880393 -303.208504)
			(xy 177.85409 -303.166908) (xy 177.834799 -303.121632) (xy 177.823022 -303.073848) (xy 177.819062 -303.024794)
			(xy 177.480214 -303.024794) (xy 177.479719 -303.049401) (xy 177.471824 -303.097978) (xy 177.45624 -303.144659)
			(xy 177.433369 -303.188236) (xy 177.403804 -303.22758) (xy 177.368311 -303.261672) (xy 177.327808 -303.289628)
			(xy 177.283346 -303.310726) (xy 177.236075 -303.324418) (xy 177.18722 -303.33035) (xy 177.138045 -303.328369)
			(xy 177.089826 -303.318525) (xy 177.04381 -303.301073) (xy 177.001189 -303.276466) (xy 176.963068 -303.245341)
			(xy 176.930433 -303.208504) (xy 176.90413 -303.166908) (xy 176.884839 -303.121632) (xy 176.873062 -303.073848)
			(xy 176.869102 -303.024794) (xy 176.530254 -303.024794) (xy 176.529759 -303.049401) (xy 176.521864 -303.097978)
			(xy 176.50628 -303.144659) (xy 176.483409 -303.188236) (xy 176.453844 -303.22758) (xy 176.418351 -303.261672)
			(xy 176.377848 -303.289628) (xy 176.333386 -303.310726) (xy 176.286115 -303.324418) (xy 176.23726 -303.33035)
			(xy 176.188085 -303.328369) (xy 176.139866 -303.318525) (xy 176.09385 -303.301073) (xy 176.051229 -303.276466)
			(xy 176.013108 -303.245341) (xy 175.980473 -303.208504) (xy 175.95417 -303.166908) (xy 175.934879 -303.121632)
			(xy 175.923102 -303.073848) (xy 175.919142 -303.024794) (xy 174.630334 -303.024794) (xy 174.629839 -303.049401)
			(xy 174.621944 -303.097978) (xy 174.60636 -303.144659) (xy 174.583489 -303.188236) (xy 174.553924 -303.22758)
			(xy 174.518431 -303.261672) (xy 174.477928 -303.289628) (xy 174.433466 -303.310726) (xy 174.386195 -303.324418)
			(xy 174.33734 -303.33035) (xy 174.288165 -303.328369) (xy 174.239946 -303.318525) (xy 174.19393 -303.301073)
			(xy 174.151309 -303.276466) (xy 174.113188 -303.245341) (xy 174.080553 -303.208504) (xy 174.05425 -303.166908)
			(xy 174.034959 -303.121632) (xy 174.023182 -303.073848) (xy 174.019222 -303.024794) (xy 173.680374 -303.024794)
			(xy 173.679879 -303.049401) (xy 173.671984 -303.097978) (xy 173.6564 -303.144659) (xy 173.633529 -303.188236)
			(xy 173.603964 -303.22758) (xy 173.568471 -303.261672) (xy 173.527968 -303.289628) (xy 173.483506 -303.310726)
			(xy 173.436235 -303.324418) (xy 173.38738 -303.33035) (xy 173.338205 -303.328369) (xy 173.289986 -303.318525)
			(xy 173.24397 -303.301073) (xy 173.201349 -303.276466) (xy 173.163228 -303.245341) (xy 173.130593 -303.208504)
			(xy 173.10429 -303.166908) (xy 173.084999 -303.121632) (xy 173.073222 -303.073848) (xy 173.069262 -303.024794)
			(xy 172.73016 -303.024794) (xy 172.729665 -303.049401) (xy 172.72177 -303.097978) (xy 172.706186 -303.144659)
			(xy 172.683315 -303.188236) (xy 172.65375 -303.22758) (xy 172.618257 -303.261672) (xy 172.577754 -303.289628)
			(xy 172.533292 -303.310726) (xy 172.486021 -303.324418) (xy 172.437166 -303.33035) (xy 172.387991 -303.328369)
			(xy 172.339772 -303.318525) (xy 172.293756 -303.301073) (xy 172.251135 -303.276466) (xy 172.213014 -303.245341)
			(xy 172.180379 -303.208504) (xy 172.154076 -303.166908) (xy 172.134785 -303.121632) (xy 172.123008 -303.073848)
			(xy 172.119048 -303.024794) (xy 171.7802 -303.024794) (xy 171.779705 -303.049401) (xy 171.77181 -303.097978)
			(xy 171.756226 -303.144659) (xy 171.733355 -303.188236) (xy 171.70379 -303.22758) (xy 171.668297 -303.261672)
			(xy 171.627794 -303.289628) (xy 171.583332 -303.310726) (xy 171.536061 -303.324418) (xy 171.487206 -303.33035)
			(xy 171.438031 -303.328369) (xy 171.389812 -303.318525) (xy 171.343796 -303.301073) (xy 171.301175 -303.276466)
			(xy 171.263054 -303.245341) (xy 171.230419 -303.208504) (xy 171.204116 -303.166908) (xy 171.184825 -303.121632)
			(xy 171.173048 -303.073848) (xy 171.169088 -303.024794) (xy 170.83024 -303.024794) (xy 170.829745 -303.049401)
			(xy 170.82185 -303.097978) (xy 170.806266 -303.144659) (xy 170.783395 -303.188236) (xy 170.75383 -303.22758)
			(xy 170.718337 -303.261672) (xy 170.677834 -303.289628) (xy 170.633372 -303.310726) (xy 170.586101 -303.324418)
			(xy 170.537246 -303.33035) (xy 170.488071 -303.328369) (xy 170.439852 -303.318525) (xy 170.393836 -303.301073)
			(xy 170.351215 -303.276466) (xy 170.313094 -303.245341) (xy 170.280459 -303.208504) (xy 170.254156 -303.166908)
			(xy 170.234865 -303.121632) (xy 170.223088 -303.073848) (xy 170.219128 -303.024794) (xy 169.88028 -303.024794)
			(xy 169.879785 -303.049401) (xy 169.87189 -303.097978) (xy 169.856306 -303.144659) (xy 169.833435 -303.188236)
			(xy 169.80387 -303.22758) (xy 169.768377 -303.261672) (xy 169.727874 -303.289628) (xy 169.683412 -303.310726)
			(xy 169.636141 -303.324418) (xy 169.587286 -303.33035) (xy 169.538111 -303.328369) (xy 169.489892 -303.318525)
			(xy 169.443876 -303.301073) (xy 169.401255 -303.276466) (xy 169.363134 -303.245341) (xy 169.330499 -303.208504)
			(xy 169.304196 -303.166908) (xy 169.284905 -303.121632) (xy 169.273128 -303.073848) (xy 169.269168 -303.024794)
			(xy 168.93032 -303.024794) (xy 168.929825 -303.049401) (xy 168.92193 -303.097978) (xy 168.906346 -303.144659)
			(xy 168.883475 -303.188236) (xy 168.85391 -303.22758) (xy 168.818417 -303.261672) (xy 168.777914 -303.289628)
			(xy 168.733452 -303.310726) (xy 168.686181 -303.324418) (xy 168.637326 -303.33035) (xy 168.588151 -303.328369)
			(xy 168.539932 -303.318525) (xy 168.493916 -303.301073) (xy 168.451295 -303.276466) (xy 168.413174 -303.245341)
			(xy 168.380539 -303.208504) (xy 168.354236 -303.166908) (xy 168.334945 -303.121632) (xy 168.323168 -303.073848)
			(xy 168.319208 -303.024794) (xy 167.98036 -303.024794) (xy 167.979865 -303.049401) (xy 167.97197 -303.097978)
			(xy 167.956386 -303.144659) (xy 167.933515 -303.188236) (xy 167.90395 -303.22758) (xy 167.868457 -303.261672)
			(xy 167.827954 -303.289628) (xy 167.783492 -303.310726) (xy 167.736221 -303.324418) (xy 167.687366 -303.33035)
			(xy 167.638191 -303.328369) (xy 167.589972 -303.318525) (xy 167.543956 -303.301073) (xy 167.501335 -303.276466)
			(xy 167.463214 -303.245341) (xy 167.430579 -303.208504) (xy 167.404276 -303.166908) (xy 167.384985 -303.121632)
			(xy 167.373208 -303.073848) (xy 167.369248 -303.024794) (xy 167.0304 -303.024794) (xy 167.029905 -303.049401)
			(xy 167.02201 -303.097978) (xy 167.006426 -303.144659) (xy 166.983555 -303.188236) (xy 166.95399 -303.22758)
			(xy 166.918497 -303.261672) (xy 166.877994 -303.289628) (xy 166.833532 -303.310726) (xy 166.786261 -303.324418)
			(xy 166.737406 -303.33035) (xy 166.688231 -303.328369) (xy 166.640012 -303.318525) (xy 166.593996 -303.301073)
			(xy 166.551375 -303.276466) (xy 166.513254 -303.245341) (xy 166.480619 -303.208504) (xy 166.454316 -303.166908)
			(xy 166.435025 -303.121632) (xy 166.423248 -303.073848) (xy 166.419288 -303.024794) (xy 166.080186 -303.024794)
			(xy 166.079691 -303.049401) (xy 166.071796 -303.097978) (xy 166.056212 -303.144659) (xy 166.033341 -303.188236)
			(xy 166.003776 -303.22758) (xy 165.968283 -303.261672) (xy 165.92778 -303.289628) (xy 165.883318 -303.310726)
			(xy 165.836047 -303.324418) (xy 165.787192 -303.33035) (xy 165.738017 -303.328369) (xy 165.689798 -303.318525)
			(xy 165.643782 -303.301073) (xy 165.601161 -303.276466) (xy 165.56304 -303.245341) (xy 165.530405 -303.208504)
			(xy 165.504102 -303.166908) (xy 165.484811 -303.121632) (xy 165.473034 -303.073848) (xy 165.469074 -303.024794)
			(xy 165.130226 -303.024794) (xy 165.129731 -303.049401) (xy 165.121836 -303.097978) (xy 165.106252 -303.144659)
			(xy 165.083381 -303.188236) (xy 165.053816 -303.22758) (xy 165.018323 -303.261672) (xy 164.97782 -303.289628)
			(xy 164.933358 -303.310726) (xy 164.886087 -303.324418) (xy 164.837232 -303.33035) (xy 164.788057 -303.328369)
			(xy 164.739838 -303.318525) (xy 164.693822 -303.301073) (xy 164.651201 -303.276466) (xy 164.61308 -303.245341)
			(xy 164.580445 -303.208504) (xy 164.554142 -303.166908) (xy 164.534851 -303.121632) (xy 164.523074 -303.073848)
			(xy 164.519114 -303.024794) (xy 164.180266 -303.024794) (xy 164.179771 -303.049401) (xy 164.171876 -303.097978)
			(xy 164.156292 -303.144659) (xy 164.133421 -303.188236) (xy 164.103856 -303.22758) (xy 164.068363 -303.261672)
			(xy 164.02786 -303.289628) (xy 163.983398 -303.310726) (xy 163.936127 -303.324418) (xy 163.887272 -303.33035)
			(xy 163.838097 -303.328369) (xy 163.789878 -303.318525) (xy 163.743862 -303.301073) (xy 163.701241 -303.276466)
			(xy 163.66312 -303.245341) (xy 163.630485 -303.208504) (xy 163.604182 -303.166908) (xy 163.584891 -303.121632)
			(xy 163.573114 -303.073848) (xy 163.569154 -303.024794) (xy 163.230306 -303.024794) (xy 163.229811 -303.049401)
			(xy 163.221916 -303.097978) (xy 163.206332 -303.144659) (xy 163.183461 -303.188236) (xy 163.153896 -303.22758)
			(xy 163.118403 -303.261672) (xy 163.0779 -303.289628) (xy 163.033438 -303.310726) (xy 162.986167 -303.324418)
			(xy 162.937312 -303.33035) (xy 162.888137 -303.328369) (xy 162.839918 -303.318525) (xy 162.793902 -303.301073)
			(xy 162.751281 -303.276466) (xy 162.71316 -303.245341) (xy 162.680525 -303.208504) (xy 162.654222 -303.166908)
			(xy 162.634931 -303.121632) (xy 162.623154 -303.073848) (xy 162.619194 -303.024794) (xy 162.280825 -303.024794)
			(xy 162.280825 -303.0248) (xy 162.276655 -303.075133) (xy 162.264257 -303.124094) (xy 162.243971 -303.170346)
			(xy 162.216349 -303.212629) (xy 162.182144 -303.249789) (xy 162.142291 -303.280813) (xy 162.097874 -303.304855)
			(xy 162.050107 -303.321259) (xy 162.000291 -303.329577) (xy 161.975038 -303.330102) (xy 161.960855 -303.32992)
			(xy 161.932615 -303.327252) (xy 161.91865 -303.324768) (xy 161.906204 -303.322482) (xy 161.882582 -303.329848)
			(xy 161.805112 -303.407318) (xy 161.797746 -303.43094) (xy 161.800032 -303.443386) (xy 161.802503 -303.457353)
			(xy 161.805178 -303.485592) (xy 161.805366 -303.499774) (xy 161.80495 -303.524597) (xy 161.796923 -303.573589)
			(xy 161.781075 -303.620637) (xy 161.757825 -303.664501) (xy 161.727784 -303.704026) (xy 161.691745 -303.738171)
			(xy 161.650657 -303.766035) (xy 161.605602 -303.786885) (xy 161.557768 -303.800171) (xy 161.508414 -303.805544)
			(xy 161.458841 -303.802861) (xy 161.410355 -303.792194) (xy 161.364234 -303.773823) (xy 161.321692 -303.748233)
			(xy 161.283851 -303.716098) (xy 161.251707 -303.678263) (xy 161.226107 -303.635727) (xy 161.207726 -303.58961)
			(xy 161.197048 -303.541127) (xy 161.194354 -303.491554) (xy 161.199716 -303.442199) (xy 161.212991 -303.394362)
			(xy 161.233831 -303.349302) (xy 161.261687 -303.308208) (xy 161.295823 -303.272161) (xy 161.335341 -303.242112)
			(xy 161.379201 -303.218852) (xy 161.426245 -303.202994) (xy 161.475235 -303.194955) (xy 161.500058 -303.194466)
			(xy 161.514241 -303.194649) (xy 161.542481 -303.197317) (xy 161.556446 -303.1998) (xy 161.568892 -303.202086)
			(xy 161.592514 -303.19472) (xy 161.669984 -303.11725) (xy 161.67735 -303.093628) (xy 161.675064 -303.081182)
			(xy 161.67259 -303.067216) (xy 161.669916 -303.038976) (xy 161.66973 -303.024794) (xy 161.669905 -303.010611)
			(xy 161.672578 -302.982371) (xy 161.675064 -302.968406) (xy 161.67735 -302.95596) (xy 161.669984 -302.932338)
			(xy 161.592514 -302.854868) (xy 161.568892 -302.847502) (xy 161.556446 -302.849788) (xy 161.542481 -302.852268)
			(xy 161.514241 -302.854937) (xy 161.500058 -302.855122) (xy 161.474806 -302.854569) (xy 161.424992 -302.84625)
			(xy 161.377226 -302.829847) (xy 161.332812 -302.805805) (xy 161.292959 -302.774782) (xy 161.258757 -302.737623)
			(xy 161.231136 -302.695341) (xy 161.21085 -302.64909) (xy 161.198453 -302.600131) (xy 161.194283 -302.5498)
			(xy 161.198453 -302.499469) (xy 161.21085 -302.45051) (xy 161.231136 -302.404259) (xy 161.258757 -302.361977)
			(xy 161.292959 -302.324818) (xy 161.332812 -302.293795) (xy 161.377226 -302.269753) (xy 161.424992 -302.25335)
			(xy 161.474806 -302.245031) (xy 161.500058 -302.244506) (xy 161.514241 -302.244688) (xy 161.542481 -302.247357)
			(xy 161.556446 -302.24984) (xy 161.568892 -302.252126) (xy 161.592514 -302.24476) (xy 161.669984 -302.16729)
			(xy 161.67735 -302.143668) (xy 161.675064 -302.131222) (xy 161.672581 -302.117257) (xy 161.669914 -302.089017)
			(xy 161.66973 -302.074834) (xy 161.669911 -302.060651) (xy 161.67258 -302.032411) (xy 161.675064 -302.018446)
			(xy 161.67735 -302.006) (xy 161.669984 -301.982378) (xy 161.592514 -301.904908) (xy 161.568892 -301.897542)
			(xy 161.556446 -301.899828) (xy 161.542481 -301.902308) (xy 161.514241 -301.904977) (xy 161.500058 -301.905162)
			(xy 161.476061 -301.9048) (xy 161.42866 -301.897286) (xy 161.383018 -301.882449) (xy 161.340259 -301.860654)
			(xy 161.301435 -301.832439) (xy 161.267504 -301.798498) (xy 161.2393 -301.759666) (xy 161.217517 -301.716901)
			(xy 161.202693 -301.671254) (xy 161.195193 -301.623851) (xy 161.19475 -301.599854) (xy 161.194935 -301.585671)
			(xy 161.197602 -301.557431) (xy 161.200084 -301.543466) (xy 161.20237 -301.53102) (xy 161.195004 -301.507398)
			(xy 161.117534 -301.429928) (xy 161.093912 -301.422562) (xy 161.081466 -301.424848) (xy 161.0675 -301.427325)
			(xy 161.039261 -301.429996) (xy 161.025078 -301.430182) (xy 161.010831 -301.430011) (xy 160.982464 -301.427341)
			(xy 160.968436 -301.424848) (xy 160.956244 -301.422562) (xy 160.932114 -301.429928) (xy 160.854898 -301.507144)
			(xy 160.847532 -301.53102) (xy 160.849818 -301.543466) (xy 160.8523 -301.557431) (xy 160.854968 -301.585671)
			(xy 160.855152 -301.599854) (xy 160.854672 -301.62468) (xy 160.846646 -301.67368) (xy 160.830798 -301.720735)
			(xy 160.807546 -301.764606) (xy 160.777502 -301.804137) (xy 160.741458 -301.838287) (xy 160.700364 -301.866155)
			(xy 160.655302 -301.887007) (xy 160.60746 -301.900294) (xy 160.5581 -301.905665) (xy 160.50852 -301.902979)
			(xy 160.460028 -301.892307) (xy 160.413902 -301.87393) (xy 160.371356 -301.848333) (xy 160.333513 -301.816189)
			(xy 160.301368 -301.778346) (xy 160.275771 -301.7358) (xy 160.257393 -301.689674) (xy 160.246721 -301.641182)
			(xy 160.244035 -301.591602) (xy 159.905026 -301.591602) (xy 159.905192 -301.599854) (xy 159.904697 -301.624461)
			(xy 159.896802 -301.673038) (xy 159.881218 -301.719719) (xy 159.858347 -301.763296) (xy 159.828782 -301.80264)
			(xy 159.793289 -301.836732) (xy 159.752786 -301.864688) (xy 159.708324 -301.885786) (xy 159.661053 -301.899478)
			(xy 159.612198 -301.90541) (xy 159.563023 -301.903429) (xy 159.514804 -301.893585) (xy 159.468788 -301.876133)
			(xy 159.426167 -301.851526) (xy 159.388046 -301.820401) (xy 159.355411 -301.783564) (xy 159.329108 -301.741968)
			(xy 159.309817 -301.696692) (xy 159.29804 -301.648908) (xy 159.29408 -301.599854) (xy 158.977076 -301.599854)
			(xy 158.976572 -301.625562) (xy 158.968529 -301.676344) (xy 158.952641 -301.725243) (xy 158.929298 -301.771055)
			(xy 158.899077 -301.812651) (xy 158.862721 -301.849007) (xy 158.821125 -301.879228) (xy 158.775313 -301.902571)
			(xy 158.726414 -301.918459) (xy 158.675632 -301.926502) (xy 158.624216 -301.926502) (xy 158.573434 -301.918459)
			(xy 158.524535 -301.902571) (xy 158.478723 -301.879228) (xy 158.437127 -301.849007) (xy 158.400771 -301.812651)
			(xy 158.37055 -301.771055) (xy 158.347207 -301.725243) (xy 158.331319 -301.676344) (xy 158.323276 -301.625562)
			(xy 158.026612 -301.625562) (xy 158.018569 -301.676344) (xy 158.002681 -301.725243) (xy 157.979338 -301.771055)
			(xy 157.949117 -301.812651) (xy 157.912761 -301.849007) (xy 157.871165 -301.879228) (xy 157.825353 -301.902571)
			(xy 157.776454 -301.918459) (xy 157.725672 -301.926502) (xy 157.674256 -301.926502) (xy 157.623474 -301.918459)
			(xy 157.574575 -301.902571) (xy 157.528763 -301.879228) (xy 157.487167 -301.849007) (xy 157.450811 -301.812651)
			(xy 157.42059 -301.771055) (xy 157.397247 -301.725243) (xy 157.381359 -301.676344) (xy 157.373316 -301.625562)
			(xy 157.054638 -301.625562) (xy 157.046922 -301.673038) (xy 157.031338 -301.719719) (xy 157.008467 -301.763296)
			(xy 156.978902 -301.80264) (xy 156.943409 -301.836732) (xy 156.902906 -301.864688) (xy 156.858444 -301.885786)
			(xy 156.811173 -301.899478) (xy 156.762318 -301.90541) (xy 156.713143 -301.903429) (xy 156.664924 -301.893585)
			(xy 156.618908 -301.876133) (xy 156.576287 -301.851526) (xy 156.538166 -301.820401) (xy 156.505531 -301.783564)
			(xy 156.479228 -301.741968) (xy 156.459937 -301.696692) (xy 156.44816 -301.648908) (xy 156.4442 -301.599854)
			(xy 156.127196 -301.599854) (xy 156.126692 -301.625562) (xy 156.118649 -301.676344) (xy 156.102761 -301.725243)
			(xy 156.079418 -301.771055) (xy 156.049197 -301.812651) (xy 156.012841 -301.849007) (xy 155.971245 -301.879228)
			(xy 155.925433 -301.902571) (xy 155.876534 -301.918459) (xy 155.825752 -301.926502) (xy 155.774336 -301.926502)
			(xy 155.723554 -301.918459) (xy 155.674655 -301.902571) (xy 155.628843 -301.879228) (xy 155.587247 -301.849007)
			(xy 155.550891 -301.812651) (xy 155.52067 -301.771055) (xy 155.497327 -301.725243) (xy 155.481439 -301.676344)
			(xy 155.473396 -301.625562) (xy 155.176732 -301.625562) (xy 155.168689 -301.676344) (xy 155.152801 -301.725243)
			(xy 155.129458 -301.771055) (xy 155.099237 -301.812651) (xy 155.062881 -301.849007) (xy 155.021285 -301.879228)
			(xy 154.975473 -301.902571) (xy 154.926574 -301.918459) (xy 154.875792 -301.926502) (xy 154.824376 -301.926502)
			(xy 154.773594 -301.918459) (xy 154.724695 -301.902571) (xy 154.678883 -301.879228) (xy 154.637287 -301.849007)
			(xy 154.600931 -301.812651) (xy 154.57071 -301.771055) (xy 154.547367 -301.725243) (xy 154.531479 -301.676344)
			(xy 154.523436 -301.625562) (xy 154.204504 -301.625562) (xy 154.196788 -301.673038) (xy 154.181204 -301.719719)
			(xy 154.158333 -301.763296) (xy 154.128768 -301.80264) (xy 154.093275 -301.836732) (xy 154.052772 -301.864688)
			(xy 154.00831 -301.885786) (xy 153.961039 -301.899478) (xy 153.912184 -301.90541) (xy 153.863009 -301.903429)
			(xy 153.81479 -301.893585) (xy 153.768774 -301.876133) (xy 153.726153 -301.851526) (xy 153.688032 -301.820401)
			(xy 153.655397 -301.783564) (xy 153.629094 -301.741968) (xy 153.609803 -301.696692) (xy 153.598026 -301.648908)
			(xy 153.594066 -301.599854) (xy 153.255218 -301.599854) (xy 153.254723 -301.624461) (xy 153.246828 -301.673038)
			(xy 153.231244 -301.719719) (xy 153.208373 -301.763296) (xy 153.178808 -301.80264) (xy 153.143315 -301.836732)
			(xy 153.102812 -301.864688) (xy 153.05835 -301.885786) (xy 153.011079 -301.899478) (xy 152.962224 -301.90541)
			(xy 152.913049 -301.903429) (xy 152.86483 -301.893585) (xy 152.818814 -301.876133) (xy 152.776193 -301.851526)
			(xy 152.738072 -301.820401) (xy 152.705437 -301.783564) (xy 152.679134 -301.741968) (xy 152.659843 -301.696692)
			(xy 152.648066 -301.648908) (xy 152.644106 -301.599854) (xy 118.832884 -301.599854) (xy 118.832884 -302.550068)
			(xy 151.693892 -302.550068) (xy 151.697852 -302.501014) (xy 151.709629 -302.45323) (xy 151.72892 -302.407954)
			(xy 151.755223 -302.366358) (xy 151.787858 -302.329521) (xy 151.825979 -302.298396) (xy 151.8686 -302.273789)
			(xy 151.914616 -302.256337) (xy 151.962835 -302.246493) (xy 152.01201 -302.244512) (xy 152.060865 -302.250444)
			(xy 152.108136 -302.264136) (xy 152.152598 -302.285234) (xy 152.193101 -302.31319) (xy 152.228594 -302.347282)
			(xy 152.258159 -302.386626) (xy 152.28103 -302.430203) (xy 152.296614 -302.476884) (xy 152.304509 -302.525461)
			(xy 152.305004 -302.550068) (xy 152.304509 -302.574675) (xy 152.304371 -302.575522) (xy 152.623262 -302.575522)
			(xy 152.623262 -302.524106) (xy 152.631305 -302.473324) (xy 152.647193 -302.424425) (xy 152.670536 -302.378613)
			(xy 152.700757 -302.337017) (xy 152.737113 -302.300661) (xy 152.778709 -302.27044) (xy 152.824521 -302.247097)
			(xy 152.87342 -302.231209) (xy 152.924202 -302.223166) (xy 152.975618 -302.223166) (xy 153.0264 -302.231209)
			(xy 153.075299 -302.247097) (xy 153.121111 -302.27044) (xy 153.162707 -302.300661) (xy 153.199063 -302.337017)
			(xy 153.229284 -302.378613) (xy 153.252627 -302.424425) (xy 153.268515 -302.473324) (xy 153.276558 -302.524106)
			(xy 153.277062 -302.549814) (xy 153.276558 -302.575522) (xy 153.573222 -302.575522) (xy 153.573222 -302.524106)
			(xy 153.581265 -302.473324) (xy 153.597153 -302.424425) (xy 153.620496 -302.378613) (xy 153.650717 -302.337017)
			(xy 153.687073 -302.300661) (xy 153.728669 -302.27044) (xy 153.774481 -302.247097) (xy 153.82338 -302.231209)
			(xy 153.874162 -302.223166) (xy 153.925578 -302.223166) (xy 153.97636 -302.231209) (xy 154.025259 -302.247097)
			(xy 154.071071 -302.27044) (xy 154.112667 -302.300661) (xy 154.149023 -302.337017) (xy 154.179244 -302.378613)
			(xy 154.202587 -302.424425) (xy 154.218475 -302.473324) (xy 154.226518 -302.524106) (xy 154.227022 -302.549814)
			(xy 154.54428 -302.549814) (xy 154.54824 -302.50076) (xy 154.560017 -302.452976) (xy 154.579308 -302.4077)
			(xy 154.605611 -302.366104) (xy 154.638246 -302.329267) (xy 154.676367 -302.298142) (xy 154.718988 -302.273535)
			(xy 154.765004 -302.256083) (xy 154.813223 -302.246239) (xy 154.862398 -302.244258) (xy 154.911253 -302.25019)
			(xy 154.958524 -302.263882) (xy 155.002986 -302.28498) (xy 155.043489 -302.312936) (xy 155.078982 -302.347028)
			(xy 155.108547 -302.386372) (xy 155.131418 -302.429949) (xy 155.147002 -302.47663) (xy 155.154897 -302.525207)
			(xy 155.155392 -302.549814) (xy 155.49424 -302.549814) (xy 155.4982 -302.50076) (xy 155.509977 -302.452976)
			(xy 155.529268 -302.4077) (xy 155.555571 -302.366104) (xy 155.588206 -302.329267) (xy 155.626327 -302.298142)
			(xy 155.668948 -302.273535) (xy 155.714964 -302.256083) (xy 155.763183 -302.246239) (xy 155.812358 -302.244258)
			(xy 155.861213 -302.25019) (xy 155.908484 -302.263882) (xy 155.952946 -302.28498) (xy 155.993449 -302.312936)
			(xy 156.028942 -302.347028) (xy 156.058507 -302.386372) (xy 156.081378 -302.429949) (xy 156.096962 -302.47663)
			(xy 156.104857 -302.525207) (xy 156.105352 -302.549814) (xy 156.4442 -302.549814) (xy 156.44816 -302.50076)
			(xy 156.459937 -302.452976) (xy 156.479228 -302.4077) (xy 156.505531 -302.366104) (xy 156.538166 -302.329267)
			(xy 156.576287 -302.298142) (xy 156.618908 -302.273535) (xy 156.664924 -302.256083) (xy 156.713143 -302.246239)
			(xy 156.762318 -302.244258) (xy 156.811173 -302.25019) (xy 156.858444 -302.263882) (xy 156.902906 -302.28498)
			(xy 156.943409 -302.312936) (xy 156.978902 -302.347028) (xy 157.008467 -302.386372) (xy 157.031338 -302.429949)
			(xy 157.046922 -302.47663) (xy 157.054817 -302.525207) (xy 157.055312 -302.549814) (xy 157.39416 -302.549814)
			(xy 157.39812 -302.50076) (xy 157.409897 -302.452976) (xy 157.429188 -302.4077) (xy 157.455491 -302.366104)
			(xy 157.488126 -302.329267) (xy 157.526247 -302.298142) (xy 157.568868 -302.273535) (xy 157.614884 -302.256083)
			(xy 157.663103 -302.246239) (xy 157.712278 -302.244258) (xy 157.761133 -302.25019) (xy 157.808404 -302.263882)
			(xy 157.852866 -302.28498) (xy 157.893369 -302.312936) (xy 157.928862 -302.347028) (xy 157.958427 -302.386372)
			(xy 157.981298 -302.429949) (xy 157.996882 -302.47663) (xy 158.004777 -302.525207) (xy 158.005272 -302.549814)
			(xy 158.34412 -302.549814) (xy 158.34808 -302.50076) (xy 158.359857 -302.452976) (xy 158.379148 -302.4077)
			(xy 158.405451 -302.366104) (xy 158.438086 -302.329267) (xy 158.476207 -302.298142) (xy 158.518828 -302.273535)
			(xy 158.564844 -302.256083) (xy 158.613063 -302.246239) (xy 158.662238 -302.244258) (xy 158.711093 -302.25019)
			(xy 158.758364 -302.263882) (xy 158.802826 -302.28498) (xy 158.843329 -302.312936) (xy 158.878822 -302.347028)
			(xy 158.908387 -302.386372) (xy 158.931258 -302.429949) (xy 158.946842 -302.47663) (xy 158.954737 -302.525207)
			(xy 158.955232 -302.549814) (xy 158.954737 -302.574421) (xy 158.954558 -302.575522) (xy 159.273236 -302.575522)
			(xy 159.273236 -302.524106) (xy 159.281279 -302.473324) (xy 159.297167 -302.424425) (xy 159.32051 -302.378613)
			(xy 159.350731 -302.337017) (xy 159.387087 -302.300661) (xy 159.428683 -302.27044) (xy 159.474495 -302.247097)
			(xy 159.523394 -302.231209) (xy 159.574176 -302.223166) (xy 159.625592 -302.223166) (xy 159.676374 -302.231209)
			(xy 159.725273 -302.247097) (xy 159.771085 -302.27044) (xy 159.812681 -302.300661) (xy 159.849037 -302.337017)
			(xy 159.879258 -302.378613) (xy 159.902601 -302.424425) (xy 159.918489 -302.473324) (xy 159.926532 -302.524106)
			(xy 159.927036 -302.549814) (xy 159.926532 -302.575522) (xy 160.223196 -302.575522) (xy 160.223196 -302.524106)
			(xy 160.231239 -302.473324) (xy 160.247127 -302.424425) (xy 160.27047 -302.378613) (xy 160.300691 -302.337017)
			(xy 160.337047 -302.300661) (xy 160.378643 -302.27044) (xy 160.424455 -302.247097) (xy 160.473354 -302.231209)
			(xy 160.524136 -302.223166) (xy 160.575552 -302.223166) (xy 160.626334 -302.231209) (xy 160.675233 -302.247097)
			(xy 160.721045 -302.27044) (xy 160.762641 -302.300661) (xy 160.798997 -302.337017) (xy 160.829218 -302.378613)
			(xy 160.852561 -302.424425) (xy 160.868449 -302.473324) (xy 160.876492 -302.524106) (xy 160.876996 -302.549814)
			(xy 160.876492 -302.575522) (xy 160.868449 -302.626304) (xy 160.852561 -302.675203) (xy 160.829218 -302.721015)
			(xy 160.798997 -302.762611) (xy 160.762641 -302.798967) (xy 160.721045 -302.829188) (xy 160.675233 -302.852531)
			(xy 160.626334 -302.868419) (xy 160.575552 -302.876462) (xy 160.524136 -302.876462) (xy 160.473354 -302.868419)
			(xy 160.424455 -302.852531) (xy 160.378643 -302.829188) (xy 160.337047 -302.798967) (xy 160.300691 -302.762611)
			(xy 160.27047 -302.721015) (xy 160.247127 -302.675203) (xy 160.231239 -302.626304) (xy 160.223196 -302.575522)
			(xy 159.926532 -302.575522) (xy 159.918489 -302.626304) (xy 159.902601 -302.675203) (xy 159.879258 -302.721015)
			(xy 159.849037 -302.762611) (xy 159.812681 -302.798967) (xy 159.771085 -302.829188) (xy 159.725273 -302.852531)
			(xy 159.676374 -302.868419) (xy 159.625592 -302.876462) (xy 159.574176 -302.876462) (xy 159.523394 -302.868419)
			(xy 159.474495 -302.852531) (xy 159.428683 -302.829188) (xy 159.387087 -302.798967) (xy 159.350731 -302.762611)
			(xy 159.32051 -302.721015) (xy 159.297167 -302.675203) (xy 159.281279 -302.626304) (xy 159.273236 -302.575522)
			(xy 158.954558 -302.575522) (xy 158.946842 -302.622998) (xy 158.931258 -302.669679) (xy 158.908387 -302.713256)
			(xy 158.878822 -302.7526) (xy 158.843329 -302.786692) (xy 158.802826 -302.814648) (xy 158.758364 -302.835746)
			(xy 158.711093 -302.849438) (xy 158.662238 -302.85537) (xy 158.613063 -302.853389) (xy 158.564844 -302.843545)
			(xy 158.518828 -302.826093) (xy 158.476207 -302.801486) (xy 158.438086 -302.770361) (xy 158.405451 -302.733524)
			(xy 158.379148 -302.691928) (xy 158.359857 -302.646652) (xy 158.34808 -302.598868) (xy 158.34412 -302.549814)
			(xy 158.005272 -302.549814) (xy 158.004777 -302.574421) (xy 157.996882 -302.622998) (xy 157.981298 -302.669679)
			(xy 157.958427 -302.713256) (xy 157.928862 -302.7526) (xy 157.893369 -302.786692) (xy 157.852866 -302.814648)
			(xy 157.808404 -302.835746) (xy 157.761133 -302.849438) (xy 157.712278 -302.85537) (xy 157.663103 -302.853389)
			(xy 157.614884 -302.843545) (xy 157.568868 -302.826093) (xy 157.526247 -302.801486) (xy 157.488126 -302.770361)
			(xy 157.455491 -302.733524) (xy 157.429188 -302.691928) (xy 157.409897 -302.646652) (xy 157.39812 -302.598868)
			(xy 157.39416 -302.549814) (xy 157.055312 -302.549814) (xy 157.054817 -302.574421) (xy 157.046922 -302.622998)
			(xy 157.031338 -302.669679) (xy 157.008467 -302.713256) (xy 156.978902 -302.7526) (xy 156.943409 -302.786692)
			(xy 156.902906 -302.814648) (xy 156.858444 -302.835746) (xy 156.811173 -302.849438) (xy 156.762318 -302.85537)
			(xy 156.713143 -302.853389) (xy 156.664924 -302.843545) (xy 156.618908 -302.826093) (xy 156.576287 -302.801486)
			(xy 156.538166 -302.770361) (xy 156.505531 -302.733524) (xy 156.479228 -302.691928) (xy 156.459937 -302.646652)
			(xy 156.44816 -302.598868) (xy 156.4442 -302.549814) (xy 156.105352 -302.549814) (xy 156.104857 -302.574421)
			(xy 156.096962 -302.622998) (xy 156.081378 -302.669679) (xy 156.058507 -302.713256) (xy 156.028942 -302.7526)
			(xy 155.993449 -302.786692) (xy 155.952946 -302.814648) (xy 155.908484 -302.835746) (xy 155.861213 -302.849438)
			(xy 155.812358 -302.85537) (xy 155.763183 -302.853389) (xy 155.714964 -302.843545) (xy 155.668948 -302.826093)
			(xy 155.626327 -302.801486) (xy 155.588206 -302.770361) (xy 155.555571 -302.733524) (xy 155.529268 -302.691928)
			(xy 155.509977 -302.646652) (xy 155.4982 -302.598868) (xy 155.49424 -302.549814) (xy 155.155392 -302.549814)
			(xy 155.154897 -302.574421) (xy 155.147002 -302.622998) (xy 155.131418 -302.669679) (xy 155.108547 -302.713256)
			(xy 155.078982 -302.7526) (xy 155.043489 -302.786692) (xy 155.002986 -302.814648) (xy 154.958524 -302.835746)
			(xy 154.911253 -302.849438) (xy 154.862398 -302.85537) (xy 154.813223 -302.853389) (xy 154.765004 -302.843545)
			(xy 154.718988 -302.826093) (xy 154.676367 -302.801486) (xy 154.638246 -302.770361) (xy 154.605611 -302.733524)
			(xy 154.579308 -302.691928) (xy 154.560017 -302.646652) (xy 154.54824 -302.598868) (xy 154.54428 -302.549814)
			(xy 154.227022 -302.549814) (xy 154.226518 -302.575522) (xy 154.218475 -302.626304) (xy 154.202587 -302.675203)
			(xy 154.179244 -302.721015) (xy 154.149023 -302.762611) (xy 154.112667 -302.798967) (xy 154.071071 -302.829188)
			(xy 154.025259 -302.852531) (xy 153.97636 -302.868419) (xy 153.925578 -302.876462) (xy 153.874162 -302.876462)
			(xy 153.82338 -302.868419) (xy 153.774481 -302.852531) (xy 153.728669 -302.829188) (xy 153.687073 -302.798967)
			(xy 153.650717 -302.762611) (xy 153.620496 -302.721015) (xy 153.597153 -302.675203) (xy 153.581265 -302.626304)
			(xy 153.573222 -302.575522) (xy 153.276558 -302.575522) (xy 153.268515 -302.626304) (xy 153.252627 -302.675203)
			(xy 153.229284 -302.721015) (xy 153.199063 -302.762611) (xy 153.162707 -302.798967) (xy 153.121111 -302.829188)
			(xy 153.075299 -302.852531) (xy 153.0264 -302.868419) (xy 152.975618 -302.876462) (xy 152.924202 -302.876462)
			(xy 152.87342 -302.868419) (xy 152.824521 -302.852531) (xy 152.778709 -302.829188) (xy 152.737113 -302.798967)
			(xy 152.700757 -302.762611) (xy 152.670536 -302.721015) (xy 152.647193 -302.675203) (xy 152.631305 -302.626304)
			(xy 152.623262 -302.575522) (xy 152.304371 -302.575522) (xy 152.296614 -302.623252) (xy 152.28103 -302.669933)
			(xy 152.258159 -302.71351) (xy 152.228594 -302.752854) (xy 152.193101 -302.786946) (xy 152.152598 -302.814902)
			(xy 152.108136 -302.836) (xy 152.060865 -302.849692) (xy 152.01201 -302.855624) (xy 151.962835 -302.853643)
			(xy 151.914616 -302.843799) (xy 151.8686 -302.826347) (xy 151.825979 -302.80174) (xy 151.787858 -302.770615)
			(xy 151.755223 -302.733778) (xy 151.72892 -302.692182) (xy 151.709629 -302.646906) (xy 151.697852 -302.599122)
			(xy 151.693892 -302.550068) (xy 118.832884 -302.550068) (xy 118.832884 -303.499774) (xy 152.644106 -303.499774)
			(xy 152.648066 -303.45072) (xy 152.659843 -303.402936) (xy 152.679134 -303.35766) (xy 152.705437 -303.316064)
			(xy 152.738072 -303.279227) (xy 152.776193 -303.248102) (xy 152.818814 -303.223495) (xy 152.86483 -303.206043)
			(xy 152.913049 -303.196199) (xy 152.962224 -303.194218) (xy 153.011079 -303.20015) (xy 153.05835 -303.213842)
			(xy 153.102812 -303.23494) (xy 153.143315 -303.262896) (xy 153.178808 -303.296988) (xy 153.208373 -303.336332)
			(xy 153.231244 -303.379909) (xy 153.246828 -303.42659) (xy 153.254723 -303.475167) (xy 153.255218 -303.499774)
			(xy 153.594066 -303.499774) (xy 153.598026 -303.45072) (xy 153.609803 -303.402936) (xy 153.629094 -303.35766)
			(xy 153.655397 -303.316064) (xy 153.688032 -303.279227) (xy 153.726153 -303.248102) (xy 153.768774 -303.223495)
			(xy 153.81479 -303.206043) (xy 153.863009 -303.196199) (xy 153.912184 -303.194218) (xy 153.961039 -303.20015)
			(xy 154.00831 -303.213842) (xy 154.052772 -303.23494) (xy 154.093275 -303.262896) (xy 154.128768 -303.296988)
			(xy 154.158333 -303.336332) (xy 154.181204 -303.379909) (xy 154.196788 -303.42659) (xy 154.204683 -303.475167)
			(xy 154.205178 -303.499774) (xy 154.204683 -303.524381) (xy 154.204504 -303.525482) (xy 154.523436 -303.525482)
			(xy 154.523436 -303.474066) (xy 154.531479 -303.423284) (xy 154.547367 -303.374385) (xy 154.57071 -303.328573)
			(xy 154.600931 -303.286977) (xy 154.637287 -303.250621) (xy 154.678883 -303.2204) (xy 154.724695 -303.197057)
			(xy 154.773594 -303.181169) (xy 154.824376 -303.173126) (xy 154.875792 -303.173126) (xy 154.926574 -303.181169)
			(xy 154.975473 -303.197057) (xy 155.021285 -303.2204) (xy 155.062881 -303.250621) (xy 155.099237 -303.286977)
			(xy 155.129458 -303.328573) (xy 155.152801 -303.374385) (xy 155.168689 -303.423284) (xy 155.176732 -303.474066)
			(xy 155.177236 -303.499774) (xy 155.176732 -303.525482) (xy 155.473396 -303.525482) (xy 155.473396 -303.474066)
			(xy 155.481439 -303.423284) (xy 155.497327 -303.374385) (xy 155.52067 -303.328573) (xy 155.550891 -303.286977)
			(xy 155.587247 -303.250621) (xy 155.628843 -303.2204) (xy 155.674655 -303.197057) (xy 155.723554 -303.181169)
			(xy 155.774336 -303.173126) (xy 155.825752 -303.173126) (xy 155.876534 -303.181169) (xy 155.925433 -303.197057)
			(xy 155.971245 -303.2204) (xy 156.012841 -303.250621) (xy 156.049197 -303.286977) (xy 156.079418 -303.328573)
			(xy 156.102761 -303.374385) (xy 156.118649 -303.423284) (xy 156.126692 -303.474066) (xy 156.127196 -303.499774)
			(xy 156.4442 -303.499774) (xy 156.44816 -303.45072) (xy 156.459937 -303.402936) (xy 156.479228 -303.35766)
			(xy 156.505531 -303.316064) (xy 156.538166 -303.279227) (xy 156.576287 -303.248102) (xy 156.618908 -303.223495)
			(xy 156.664924 -303.206043) (xy 156.713143 -303.196199) (xy 156.762318 -303.194218) (xy 156.811173 -303.20015)
			(xy 156.858444 -303.213842) (xy 156.902906 -303.23494) (xy 156.943409 -303.262896) (xy 156.978902 -303.296988)
			(xy 157.008467 -303.336332) (xy 157.031338 -303.379909) (xy 157.046922 -303.42659) (xy 157.054817 -303.475167)
			(xy 157.055312 -303.499774) (xy 157.054817 -303.524381) (xy 157.054638 -303.525482) (xy 157.373316 -303.525482)
			(xy 157.373316 -303.474066) (xy 157.381359 -303.423284) (xy 157.397247 -303.374385) (xy 157.42059 -303.328573)
			(xy 157.450811 -303.286977) (xy 157.487167 -303.250621) (xy 157.528763 -303.2204) (xy 157.574575 -303.197057)
			(xy 157.623474 -303.181169) (xy 157.674256 -303.173126) (xy 157.725672 -303.173126) (xy 157.776454 -303.181169)
			(xy 157.825353 -303.197057) (xy 157.871165 -303.2204) (xy 157.912761 -303.250621) (xy 157.949117 -303.286977)
			(xy 157.979338 -303.328573) (xy 158.002681 -303.374385) (xy 158.018569 -303.423284) (xy 158.026612 -303.474066)
			(xy 158.027116 -303.499774) (xy 158.026612 -303.525482) (xy 158.323276 -303.525482) (xy 158.323276 -303.474066)
			(xy 158.331319 -303.423284) (xy 158.347207 -303.374385) (xy 158.37055 -303.328573) (xy 158.400771 -303.286977)
			(xy 158.437127 -303.250621) (xy 158.478723 -303.2204) (xy 158.524535 -303.197057) (xy 158.573434 -303.181169)
			(xy 158.624216 -303.173126) (xy 158.675632 -303.173126) (xy 158.726414 -303.181169) (xy 158.775313 -303.197057)
			(xy 158.821125 -303.2204) (xy 158.862721 -303.250621) (xy 158.899077 -303.286977) (xy 158.929298 -303.328573)
			(xy 158.952641 -303.374385) (xy 158.968529 -303.423284) (xy 158.976572 -303.474066) (xy 158.977076 -303.499774)
			(xy 159.29408 -303.499774) (xy 159.29804 -303.45072) (xy 159.309817 -303.402936) (xy 159.329108 -303.35766)
			(xy 159.355411 -303.316064) (xy 159.388046 -303.279227) (xy 159.426167 -303.248102) (xy 159.468788 -303.223495)
			(xy 159.514804 -303.206043) (xy 159.563023 -303.196199) (xy 159.612198 -303.194218) (xy 159.661053 -303.20015)
			(xy 159.708324 -303.213842) (xy 159.752786 -303.23494) (xy 159.793289 -303.262896) (xy 159.828782 -303.296988)
			(xy 159.858347 -303.336332) (xy 159.881218 -303.379909) (xy 159.896802 -303.42659) (xy 159.904697 -303.475167)
			(xy 159.905192 -303.499774) (xy 160.24404 -303.499774) (xy 160.248 -303.45072) (xy 160.259777 -303.402936)
			(xy 160.279068 -303.35766) (xy 160.305371 -303.316064) (xy 160.338006 -303.279227) (xy 160.376127 -303.248102)
			(xy 160.418748 -303.223495) (xy 160.464764 -303.206043) (xy 160.512983 -303.196199) (xy 160.562158 -303.194218)
			(xy 160.611013 -303.20015) (xy 160.658284 -303.213842) (xy 160.702746 -303.23494) (xy 160.743249 -303.262896)
			(xy 160.778742 -303.296988) (xy 160.808307 -303.336332) (xy 160.831178 -303.379909) (xy 160.846762 -303.42659)
			(xy 160.854657 -303.475167) (xy 160.855152 -303.499774) (xy 160.854657 -303.524381) (xy 160.846762 -303.572958)
			(xy 160.831178 -303.619639) (xy 160.808307 -303.663216) (xy 160.778742 -303.70256) (xy 160.743249 -303.736652)
			(xy 160.702746 -303.764608) (xy 160.658284 -303.785706) (xy 160.611013 -303.799398) (xy 160.562158 -303.80533)
			(xy 160.512983 -303.803349) (xy 160.464764 -303.793505) (xy 160.418748 -303.776053) (xy 160.376127 -303.751446)
			(xy 160.338006 -303.720321) (xy 160.305371 -303.683484) (xy 160.279068 -303.641888) (xy 160.259777 -303.596612)
			(xy 160.248 -303.548828) (xy 160.24404 -303.499774) (xy 159.905192 -303.499774) (xy 159.904697 -303.524381)
			(xy 159.896802 -303.572958) (xy 159.881218 -303.619639) (xy 159.858347 -303.663216) (xy 159.828782 -303.70256)
			(xy 159.793289 -303.736652) (xy 159.752786 -303.764608) (xy 159.708324 -303.785706) (xy 159.661053 -303.799398)
			(xy 159.612198 -303.80533) (xy 159.563023 -303.803349) (xy 159.514804 -303.793505) (xy 159.468788 -303.776053)
			(xy 159.426167 -303.751446) (xy 159.388046 -303.720321) (xy 159.355411 -303.683484) (xy 159.329108 -303.641888)
			(xy 159.309817 -303.596612) (xy 159.29804 -303.548828) (xy 159.29408 -303.499774) (xy 158.977076 -303.499774)
			(xy 158.976572 -303.525482) (xy 158.968529 -303.576264) (xy 158.952641 -303.625163) (xy 158.929298 -303.670975)
			(xy 158.899077 -303.712571) (xy 158.862721 -303.748927) (xy 158.821125 -303.779148) (xy 158.775313 -303.802491)
			(xy 158.726414 -303.818379) (xy 158.675632 -303.826422) (xy 158.624216 -303.826422) (xy 158.573434 -303.818379)
			(xy 158.524535 -303.802491) (xy 158.478723 -303.779148) (xy 158.437127 -303.748927) (xy 158.400771 -303.712571)
			(xy 158.37055 -303.670975) (xy 158.347207 -303.625163) (xy 158.331319 -303.576264) (xy 158.323276 -303.525482)
			(xy 158.026612 -303.525482) (xy 158.018569 -303.576264) (xy 158.002681 -303.625163) (xy 157.979338 -303.670975)
			(xy 157.949117 -303.712571) (xy 157.912761 -303.748927) (xy 157.871165 -303.779148) (xy 157.825353 -303.802491)
			(xy 157.776454 -303.818379) (xy 157.725672 -303.826422) (xy 157.674256 -303.826422) (xy 157.623474 -303.818379)
			(xy 157.574575 -303.802491) (xy 157.528763 -303.779148) (xy 157.487167 -303.748927) (xy 157.450811 -303.712571)
			(xy 157.42059 -303.670975) (xy 157.397247 -303.625163) (xy 157.381359 -303.576264) (xy 157.373316 -303.525482)
			(xy 157.054638 -303.525482) (xy 157.046922 -303.572958) (xy 157.031338 -303.619639) (xy 157.008467 -303.663216)
			(xy 156.978902 -303.70256) (xy 156.943409 -303.736652) (xy 156.902906 -303.764608) (xy 156.858444 -303.785706)
			(xy 156.811173 -303.799398) (xy 156.762318 -303.80533) (xy 156.713143 -303.803349) (xy 156.664924 -303.793505)
			(xy 156.618908 -303.776053) (xy 156.576287 -303.751446) (xy 156.538166 -303.720321) (xy 156.505531 -303.683484)
			(xy 156.479228 -303.641888) (xy 156.459937 -303.596612) (xy 156.44816 -303.548828) (xy 156.4442 -303.499774)
			(xy 156.127196 -303.499774) (xy 156.126692 -303.525482) (xy 156.118649 -303.576264) (xy 156.102761 -303.625163)
			(xy 156.079418 -303.670975) (xy 156.049197 -303.712571) (xy 156.012841 -303.748927) (xy 155.971245 -303.779148)
			(xy 155.925433 -303.802491) (xy 155.876534 -303.818379) (xy 155.825752 -303.826422) (xy 155.774336 -303.826422)
			(xy 155.723554 -303.818379) (xy 155.674655 -303.802491) (xy 155.628843 -303.779148) (xy 155.587247 -303.748927)
			(xy 155.550891 -303.712571) (xy 155.52067 -303.670975) (xy 155.497327 -303.625163) (xy 155.481439 -303.576264)
			(xy 155.473396 -303.525482) (xy 155.176732 -303.525482) (xy 155.168689 -303.576264) (xy 155.152801 -303.625163)
			(xy 155.129458 -303.670975) (xy 155.099237 -303.712571) (xy 155.062881 -303.748927) (xy 155.021285 -303.779148)
			(xy 154.975473 -303.802491) (xy 154.926574 -303.818379) (xy 154.875792 -303.826422) (xy 154.824376 -303.826422)
			(xy 154.773594 -303.818379) (xy 154.724695 -303.802491) (xy 154.678883 -303.779148) (xy 154.637287 -303.748927)
			(xy 154.600931 -303.712571) (xy 154.57071 -303.670975) (xy 154.547367 -303.625163) (xy 154.531479 -303.576264)
			(xy 154.523436 -303.525482) (xy 154.204504 -303.525482) (xy 154.196788 -303.572958) (xy 154.181204 -303.619639)
			(xy 154.158333 -303.663216) (xy 154.128768 -303.70256) (xy 154.093275 -303.736652) (xy 154.052772 -303.764608)
			(xy 154.00831 -303.785706) (xy 153.961039 -303.799398) (xy 153.912184 -303.80533) (xy 153.863009 -303.803349)
			(xy 153.81479 -303.793505) (xy 153.768774 -303.776053) (xy 153.726153 -303.751446) (xy 153.688032 -303.720321)
			(xy 153.655397 -303.683484) (xy 153.629094 -303.641888) (xy 153.609803 -303.596612) (xy 153.598026 -303.548828)
			(xy 153.594066 -303.499774) (xy 153.255218 -303.499774) (xy 153.254723 -303.524381) (xy 153.246828 -303.572958)
			(xy 153.231244 -303.619639) (xy 153.208373 -303.663216) (xy 153.178808 -303.70256) (xy 153.143315 -303.736652)
			(xy 153.102812 -303.764608) (xy 153.05835 -303.785706) (xy 153.011079 -303.799398) (xy 152.962224 -303.80533)
			(xy 152.913049 -303.803349) (xy 152.86483 -303.793505) (xy 152.818814 -303.776053) (xy 152.776193 -303.751446)
			(xy 152.738072 -303.720321) (xy 152.705437 -303.683484) (xy 152.679134 -303.641888) (xy 152.659843 -303.596612)
			(xy 152.648066 -303.548828) (xy 152.644106 -303.499774) (xy 118.832884 -303.499774) (xy 118.832884 -303.974754)
			(xy 162.619194 -303.974754) (xy 162.623154 -303.9257) (xy 162.634931 -303.877916) (xy 162.654222 -303.83264)
			(xy 162.680525 -303.791044) (xy 162.71316 -303.754207) (xy 162.751281 -303.723082) (xy 162.793902 -303.698475)
			(xy 162.839918 -303.681023) (xy 162.888137 -303.671179) (xy 162.937312 -303.669198) (xy 162.986167 -303.67513)
			(xy 163.033438 -303.688822) (xy 163.0779 -303.70992) (xy 163.118403 -303.737876) (xy 163.153896 -303.771968)
			(xy 163.183461 -303.811312) (xy 163.206332 -303.854889) (xy 163.221916 -303.90157) (xy 163.229811 -303.950147)
			(xy 163.230306 -303.974754) (xy 163.569154 -303.974754) (xy 163.573114 -303.9257) (xy 163.584891 -303.877916)
			(xy 163.604182 -303.83264) (xy 163.630485 -303.791044) (xy 163.66312 -303.754207) (xy 163.701241 -303.723082)
			(xy 163.743862 -303.698475) (xy 163.789878 -303.681023) (xy 163.838097 -303.671179) (xy 163.887272 -303.669198)
			(xy 163.936127 -303.67513) (xy 163.983398 -303.688822) (xy 164.02786 -303.70992) (xy 164.068363 -303.737876)
			(xy 164.103856 -303.771968) (xy 164.133421 -303.811312) (xy 164.156292 -303.854889) (xy 164.171876 -303.90157)
			(xy 164.179771 -303.950147) (xy 164.180266 -303.974754) (xy 164.519114 -303.974754) (xy 164.523074 -303.9257)
			(xy 164.534851 -303.877916) (xy 164.554142 -303.83264) (xy 164.580445 -303.791044) (xy 164.61308 -303.754207)
			(xy 164.651201 -303.723082) (xy 164.693822 -303.698475) (xy 164.739838 -303.681023) (xy 164.788057 -303.671179)
			(xy 164.837232 -303.669198) (xy 164.886087 -303.67513) (xy 164.933358 -303.688822) (xy 164.97782 -303.70992)
			(xy 165.018323 -303.737876) (xy 165.053816 -303.771968) (xy 165.083381 -303.811312) (xy 165.106252 -303.854889)
			(xy 165.121836 -303.90157) (xy 165.129731 -303.950147) (xy 165.130226 -303.974754) (xy 165.469074 -303.974754)
			(xy 165.473034 -303.9257) (xy 165.484811 -303.877916) (xy 165.504102 -303.83264) (xy 165.530405 -303.791044)
			(xy 165.56304 -303.754207) (xy 165.601161 -303.723082) (xy 165.643782 -303.698475) (xy 165.689798 -303.681023)
			(xy 165.738017 -303.671179) (xy 165.787192 -303.669198) (xy 165.836047 -303.67513) (xy 165.883318 -303.688822)
			(xy 165.92778 -303.70992) (xy 165.968283 -303.737876) (xy 166.003776 -303.771968) (xy 166.033341 -303.811312)
			(xy 166.056212 -303.854889) (xy 166.071796 -303.90157) (xy 166.079691 -303.950147) (xy 166.080186 -303.974754)
			(xy 166.419288 -303.974754) (xy 166.423248 -303.9257) (xy 166.435025 -303.877916) (xy 166.454316 -303.83264)
			(xy 166.480619 -303.791044) (xy 166.513254 -303.754207) (xy 166.551375 -303.723082) (xy 166.593996 -303.698475)
			(xy 166.640012 -303.681023) (xy 166.688231 -303.671179) (xy 166.737406 -303.669198) (xy 166.786261 -303.67513)
			(xy 166.833532 -303.688822) (xy 166.877994 -303.70992) (xy 166.918497 -303.737876) (xy 166.95399 -303.771968)
			(xy 166.983555 -303.811312) (xy 167.006426 -303.854889) (xy 167.02201 -303.90157) (xy 167.029905 -303.950147)
			(xy 167.0304 -303.974754) (xy 167.369248 -303.974754) (xy 167.373208 -303.9257) (xy 167.384985 -303.877916)
			(xy 167.404276 -303.83264) (xy 167.430579 -303.791044) (xy 167.463214 -303.754207) (xy 167.501335 -303.723082)
			(xy 167.543956 -303.698475) (xy 167.589972 -303.681023) (xy 167.638191 -303.671179) (xy 167.687366 -303.669198)
			(xy 167.736221 -303.67513) (xy 167.783492 -303.688822) (xy 167.827954 -303.70992) (xy 167.868457 -303.737876)
			(xy 167.90395 -303.771968) (xy 167.933515 -303.811312) (xy 167.956386 -303.854889) (xy 167.97197 -303.90157)
			(xy 167.979865 -303.950147) (xy 167.98036 -303.974754) (xy 168.319208 -303.974754) (xy 168.323168 -303.9257)
			(xy 168.334945 -303.877916) (xy 168.354236 -303.83264) (xy 168.380539 -303.791044) (xy 168.413174 -303.754207)
			(xy 168.451295 -303.723082) (xy 168.493916 -303.698475) (xy 168.539932 -303.681023) (xy 168.588151 -303.671179)
			(xy 168.637326 -303.669198) (xy 168.686181 -303.67513) (xy 168.733452 -303.688822) (xy 168.777914 -303.70992)
			(xy 168.818417 -303.737876) (xy 168.85391 -303.771968) (xy 168.883475 -303.811312) (xy 168.906346 -303.854889)
			(xy 168.92193 -303.90157) (xy 168.929825 -303.950147) (xy 168.93032 -303.974754) (xy 169.269168 -303.974754)
			(xy 169.273128 -303.9257) (xy 169.284905 -303.877916) (xy 169.304196 -303.83264) (xy 169.330499 -303.791044)
			(xy 169.363134 -303.754207) (xy 169.401255 -303.723082) (xy 169.443876 -303.698475) (xy 169.489892 -303.681023)
			(xy 169.538111 -303.671179) (xy 169.587286 -303.669198) (xy 169.636141 -303.67513) (xy 169.683412 -303.688822)
			(xy 169.727874 -303.70992) (xy 169.768377 -303.737876) (xy 169.80387 -303.771968) (xy 169.833435 -303.811312)
			(xy 169.856306 -303.854889) (xy 169.87189 -303.90157) (xy 169.879785 -303.950147) (xy 169.88028 -303.974754)
			(xy 170.219128 -303.974754) (xy 170.223088 -303.9257) (xy 170.234865 -303.877916) (xy 170.254156 -303.83264)
			(xy 170.280459 -303.791044) (xy 170.313094 -303.754207) (xy 170.351215 -303.723082) (xy 170.393836 -303.698475)
			(xy 170.439852 -303.681023) (xy 170.488071 -303.671179) (xy 170.537246 -303.669198) (xy 170.586101 -303.67513)
			(xy 170.633372 -303.688822) (xy 170.677834 -303.70992) (xy 170.718337 -303.737876) (xy 170.75383 -303.771968)
			(xy 170.783395 -303.811312) (xy 170.806266 -303.854889) (xy 170.82185 -303.90157) (xy 170.829745 -303.950147)
			(xy 170.83024 -303.974754) (xy 171.169088 -303.974754) (xy 171.173048 -303.9257) (xy 171.184825 -303.877916)
			(xy 171.204116 -303.83264) (xy 171.230419 -303.791044) (xy 171.263054 -303.754207) (xy 171.301175 -303.723082)
			(xy 171.343796 -303.698475) (xy 171.389812 -303.681023) (xy 171.438031 -303.671179) (xy 171.487206 -303.669198)
			(xy 171.536061 -303.67513) (xy 171.583332 -303.688822) (xy 171.627794 -303.70992) (xy 171.668297 -303.737876)
			(xy 171.70379 -303.771968) (xy 171.733355 -303.811312) (xy 171.756226 -303.854889) (xy 171.77181 -303.90157)
			(xy 171.779705 -303.950147) (xy 171.7802 -303.974754) (xy 172.119048 -303.974754) (xy 172.123008 -303.9257)
			(xy 172.134785 -303.877916) (xy 172.154076 -303.83264) (xy 172.180379 -303.791044) (xy 172.213014 -303.754207)
			(xy 172.251135 -303.723082) (xy 172.293756 -303.698475) (xy 172.339772 -303.681023) (xy 172.387991 -303.671179)
			(xy 172.437166 -303.669198) (xy 172.486021 -303.67513) (xy 172.533292 -303.688822) (xy 172.577754 -303.70992)
			(xy 172.618257 -303.737876) (xy 172.65375 -303.771968) (xy 172.683315 -303.811312) (xy 172.706186 -303.854889)
			(xy 172.72177 -303.90157) (xy 172.729665 -303.950147) (xy 172.73016 -303.974754) (xy 173.069262 -303.974754)
			(xy 173.073222 -303.9257) (xy 173.084999 -303.877916) (xy 173.10429 -303.83264) (xy 173.130593 -303.791044)
			(xy 173.163228 -303.754207) (xy 173.201349 -303.723082) (xy 173.24397 -303.698475) (xy 173.289986 -303.681023)
			(xy 173.338205 -303.671179) (xy 173.38738 -303.669198) (xy 173.436235 -303.67513) (xy 173.483506 -303.688822)
			(xy 173.527968 -303.70992) (xy 173.568471 -303.737876) (xy 173.603964 -303.771968) (xy 173.633529 -303.811312)
			(xy 173.6564 -303.854889) (xy 173.671984 -303.90157) (xy 173.679879 -303.950147) (xy 173.680374 -303.974754)
			(xy 174.019222 -303.974754) (xy 174.023182 -303.9257) (xy 174.034959 -303.877916) (xy 174.05425 -303.83264)
			(xy 174.080553 -303.791044) (xy 174.113188 -303.754207) (xy 174.151309 -303.723082) (xy 174.19393 -303.698475)
			(xy 174.239946 -303.681023) (xy 174.288165 -303.671179) (xy 174.33734 -303.669198) (xy 174.386195 -303.67513)
			(xy 174.433466 -303.688822) (xy 174.477928 -303.70992) (xy 174.518431 -303.737876) (xy 174.553924 -303.771968)
			(xy 174.583489 -303.811312) (xy 174.60636 -303.854889) (xy 174.621944 -303.90157) (xy 174.629839 -303.950147)
			(xy 174.630334 -303.974754) (xy 175.919142 -303.974754) (xy 175.923102 -303.9257) (xy 175.934879 -303.877916)
			(xy 175.95417 -303.83264) (xy 175.980473 -303.791044) (xy 176.013108 -303.754207) (xy 176.051229 -303.723082)
			(xy 176.09385 -303.698475) (xy 176.139866 -303.681023) (xy 176.188085 -303.671179) (xy 176.23726 -303.669198)
			(xy 176.286115 -303.67513) (xy 176.333386 -303.688822) (xy 176.377848 -303.70992) (xy 176.418351 -303.737876)
			(xy 176.453844 -303.771968) (xy 176.483409 -303.811312) (xy 176.50628 -303.854889) (xy 176.521864 -303.90157)
			(xy 176.529759 -303.950147) (xy 176.530254 -303.974754) (xy 176.869102 -303.974754) (xy 176.873062 -303.9257)
			(xy 176.884839 -303.877916) (xy 176.90413 -303.83264) (xy 176.930433 -303.791044) (xy 176.963068 -303.754207)
			(xy 177.001189 -303.723082) (xy 177.04381 -303.698475) (xy 177.089826 -303.681023) (xy 177.138045 -303.671179)
			(xy 177.18722 -303.669198) (xy 177.236075 -303.67513) (xy 177.283346 -303.688822) (xy 177.327808 -303.70992)
			(xy 177.368311 -303.737876) (xy 177.403804 -303.771968) (xy 177.433369 -303.811312) (xy 177.45624 -303.854889)
			(xy 177.471824 -303.90157) (xy 177.479719 -303.950147) (xy 177.480214 -303.974754) (xy 177.819062 -303.974754)
			(xy 177.823022 -303.9257) (xy 177.834799 -303.877916) (xy 177.85409 -303.83264) (xy 177.880393 -303.791044)
			(xy 177.913028 -303.754207) (xy 177.951149 -303.723082) (xy 177.99377 -303.698475) (xy 178.039786 -303.681023)
			(xy 178.088005 -303.671179) (xy 178.13718 -303.669198) (xy 178.186035 -303.67513) (xy 178.233306 -303.688822)
			(xy 178.277768 -303.70992) (xy 178.318271 -303.737876) (xy 178.353764 -303.771968) (xy 178.383329 -303.811312)
			(xy 178.4062 -303.854889) (xy 178.421784 -303.90157) (xy 178.429679 -303.950147) (xy 178.430174 -303.974754)
			(xy 178.769276 -303.974754) (xy 178.773236 -303.9257) (xy 178.785013 -303.877916) (xy 178.804304 -303.83264)
			(xy 178.830607 -303.791044) (xy 178.863242 -303.754207) (xy 178.901363 -303.723082) (xy 178.943984 -303.698475)
			(xy 178.99 -303.681023) (xy 179.038219 -303.671179) (xy 179.087394 -303.669198) (xy 179.136249 -303.67513)
			(xy 179.18352 -303.688822) (xy 179.227982 -303.70992) (xy 179.268485 -303.737876) (xy 179.303978 -303.771968)
			(xy 179.333543 -303.811312) (xy 179.356414 -303.854889) (xy 179.371998 -303.90157) (xy 179.379893 -303.950147)
			(xy 179.380388 -303.974754) (xy 179.719236 -303.974754) (xy 179.723196 -303.9257) (xy 179.734973 -303.877916)
			(xy 179.754264 -303.83264) (xy 179.780567 -303.791044) (xy 179.813202 -303.754207) (xy 179.851323 -303.723082)
			(xy 179.893944 -303.698475) (xy 179.93996 -303.681023) (xy 179.988179 -303.671179) (xy 180.037354 -303.669198)
			(xy 180.086209 -303.67513) (xy 180.13348 -303.688822) (xy 180.177942 -303.70992) (xy 180.218445 -303.737876)
			(xy 180.253938 -303.771968) (xy 180.283503 -303.811312) (xy 180.306374 -303.854889) (xy 180.321958 -303.90157)
			(xy 180.329853 -303.950147) (xy 180.330348 -303.974754) (xy 180.669196 -303.974754) (xy 180.673156 -303.9257)
			(xy 180.684933 -303.877916) (xy 180.704224 -303.83264) (xy 180.730527 -303.791044) (xy 180.763162 -303.754207)
			(xy 180.801283 -303.723082) (xy 180.843904 -303.698475) (xy 180.88992 -303.681023) (xy 180.938139 -303.671179)
			(xy 180.987314 -303.669198) (xy 181.036169 -303.67513) (xy 181.08344 -303.688822) (xy 181.127902 -303.70992)
			(xy 181.168405 -303.737876) (xy 181.203898 -303.771968) (xy 181.233463 -303.811312) (xy 181.256334 -303.854889)
			(xy 181.271918 -303.90157) (xy 181.279813 -303.950147) (xy 181.280308 -303.974754) (xy 181.619156 -303.974754)
			(xy 181.623116 -303.9257) (xy 181.634893 -303.877916) (xy 181.654184 -303.83264) (xy 181.680487 -303.791044)
			(xy 181.713122 -303.754207) (xy 181.751243 -303.723082) (xy 181.793864 -303.698475) (xy 181.83988 -303.681023)
			(xy 181.888099 -303.671179) (xy 181.937274 -303.669198) (xy 181.986129 -303.67513) (xy 182.0334 -303.688822)
			(xy 182.077862 -303.70992) (xy 182.118365 -303.737876) (xy 182.153858 -303.771968) (xy 182.183423 -303.811312)
			(xy 182.206294 -303.854889) (xy 182.221878 -303.90157) (xy 182.229773 -303.950147) (xy 182.230268 -303.974754)
			(xy 182.569116 -303.974754) (xy 182.573076 -303.9257) (xy 182.584853 -303.877916) (xy 182.604144 -303.83264)
			(xy 182.630447 -303.791044) (xy 182.663082 -303.754207) (xy 182.701203 -303.723082) (xy 182.743824 -303.698475)
			(xy 182.78984 -303.681023) (xy 182.838059 -303.671179) (xy 182.887234 -303.669198) (xy 182.936089 -303.67513)
			(xy 182.98336 -303.688822) (xy 183.027822 -303.70992) (xy 183.068325 -303.737876) (xy 183.103818 -303.771968)
			(xy 183.133383 -303.811312) (xy 183.156254 -303.854889) (xy 183.171838 -303.90157) (xy 183.179733 -303.950147)
			(xy 183.180228 -303.974754) (xy 183.519076 -303.974754) (xy 183.523036 -303.9257) (xy 183.534813 -303.877916)
			(xy 183.554104 -303.83264) (xy 183.580407 -303.791044) (xy 183.613042 -303.754207) (xy 183.651163 -303.723082)
			(xy 183.693784 -303.698475) (xy 183.7398 -303.681023) (xy 183.788019 -303.671179) (xy 183.837194 -303.669198)
			(xy 183.886049 -303.67513) (xy 183.93332 -303.688822) (xy 183.977782 -303.70992) (xy 184.018285 -303.737876)
			(xy 184.053778 -303.771968) (xy 184.083343 -303.811312) (xy 184.106214 -303.854889) (xy 184.121798 -303.90157)
			(xy 184.129693 -303.950147) (xy 184.130091 -303.969928) (xy 184.474116 -303.969928) (xy 184.478076 -303.920874)
			(xy 184.489853 -303.87309) (xy 184.509144 -303.827814) (xy 184.535447 -303.786218) (xy 184.568082 -303.749381)
			(xy 184.606203 -303.718256) (xy 184.648824 -303.693649) (xy 184.69484 -303.676197) (xy 184.743059 -303.666353)
			(xy 184.792234 -303.664372) (xy 184.841089 -303.670304) (xy 184.88836 -303.683996) (xy 184.932822 -303.705094)
			(xy 184.973325 -303.73305) (xy 185.008818 -303.767142) (xy 185.038383 -303.806486) (xy 185.061254 -303.850063)
			(xy 185.076838 -303.896744) (xy 185.084733 -303.945321) (xy 185.085228 -303.969928) (xy 185.084733 -303.994535)
			(xy 185.076838 -304.043112) (xy 185.061254 -304.089793) (xy 185.038383 -304.13337) (xy 185.008818 -304.172714)
			(xy 184.973325 -304.206806) (xy 184.932822 -304.234762) (xy 184.88836 -304.25586) (xy 184.841089 -304.269552)
			(xy 184.792234 -304.275484) (xy 184.743059 -304.273503) (xy 184.69484 -304.263659) (xy 184.648824 -304.246207)
			(xy 184.606203 -304.2216) (xy 184.568082 -304.190475) (xy 184.535447 -304.153638) (xy 184.509144 -304.112042)
			(xy 184.489853 -304.066766) (xy 184.478076 -304.018982) (xy 184.474116 -303.969928) (xy 184.130091 -303.969928)
			(xy 184.130188 -303.974754) (xy 184.129693 -303.999361) (xy 184.121798 -304.047938) (xy 184.106214 -304.094619)
			(xy 184.083343 -304.138196) (xy 184.053778 -304.17754) (xy 184.018285 -304.211632) (xy 183.977782 -304.239588)
			(xy 183.93332 -304.260686) (xy 183.886049 -304.274378) (xy 183.837194 -304.28031) (xy 183.788019 -304.278329)
			(xy 183.7398 -304.268485) (xy 183.693784 -304.251033) (xy 183.651163 -304.226426) (xy 183.613042 -304.195301)
			(xy 183.580407 -304.158464) (xy 183.554104 -304.116868) (xy 183.534813 -304.071592) (xy 183.523036 -304.023808)
			(xy 183.519076 -303.974754) (xy 183.180228 -303.974754) (xy 183.179733 -303.999361) (xy 183.171838 -304.047938)
			(xy 183.156254 -304.094619) (xy 183.133383 -304.138196) (xy 183.103818 -304.17754) (xy 183.068325 -304.211632)
			(xy 183.027822 -304.239588) (xy 182.98336 -304.260686) (xy 182.936089 -304.274378) (xy 182.887234 -304.28031)
			(xy 182.838059 -304.278329) (xy 182.78984 -304.268485) (xy 182.743824 -304.251033) (xy 182.701203 -304.226426)
			(xy 182.663082 -304.195301) (xy 182.630447 -304.158464) (xy 182.604144 -304.116868) (xy 182.584853 -304.071592)
			(xy 182.573076 -304.023808) (xy 182.569116 -303.974754) (xy 182.230268 -303.974754) (xy 182.229773 -303.999361)
			(xy 182.221878 -304.047938) (xy 182.206294 -304.094619) (xy 182.183423 -304.138196) (xy 182.153858 -304.17754)
			(xy 182.118365 -304.211632) (xy 182.077862 -304.239588) (xy 182.0334 -304.260686) (xy 181.986129 -304.274378)
			(xy 181.937274 -304.28031) (xy 181.888099 -304.278329) (xy 181.83988 -304.268485) (xy 181.793864 -304.251033)
			(xy 181.751243 -304.226426) (xy 181.713122 -304.195301) (xy 181.680487 -304.158464) (xy 181.654184 -304.116868)
			(xy 181.634893 -304.071592) (xy 181.623116 -304.023808) (xy 181.619156 -303.974754) (xy 181.280308 -303.974754)
			(xy 181.279813 -303.999361) (xy 181.271918 -304.047938) (xy 181.256334 -304.094619) (xy 181.233463 -304.138196)
			(xy 181.203898 -304.17754) (xy 181.168405 -304.211632) (xy 181.127902 -304.239588) (xy 181.08344 -304.260686)
			(xy 181.036169 -304.274378) (xy 180.987314 -304.28031) (xy 180.938139 -304.278329) (xy 180.88992 -304.268485)
			(xy 180.843904 -304.251033) (xy 180.801283 -304.226426) (xy 180.763162 -304.195301) (xy 180.730527 -304.158464)
			(xy 180.704224 -304.116868) (xy 180.684933 -304.071592) (xy 180.673156 -304.023808) (xy 180.669196 -303.974754)
			(xy 180.330348 -303.974754) (xy 180.329853 -303.999361) (xy 180.321958 -304.047938) (xy 180.306374 -304.094619)
			(xy 180.283503 -304.138196) (xy 180.253938 -304.17754) (xy 180.218445 -304.211632) (xy 180.177942 -304.239588)
			(xy 180.13348 -304.260686) (xy 180.086209 -304.274378) (xy 180.037354 -304.28031) (xy 179.988179 -304.278329)
			(xy 179.93996 -304.268485) (xy 179.893944 -304.251033) (xy 179.851323 -304.226426) (xy 179.813202 -304.195301)
			(xy 179.780567 -304.158464) (xy 179.754264 -304.116868) (xy 179.734973 -304.071592) (xy 179.723196 -304.023808)
			(xy 179.719236 -303.974754) (xy 179.380388 -303.974754) (xy 179.379893 -303.999361) (xy 179.371998 -304.047938)
			(xy 179.356414 -304.094619) (xy 179.333543 -304.138196) (xy 179.303978 -304.17754) (xy 179.268485 -304.211632)
			(xy 179.227982 -304.239588) (xy 179.18352 -304.260686) (xy 179.136249 -304.274378) (xy 179.087394 -304.28031)
			(xy 179.038219 -304.278329) (xy 178.99 -304.268485) (xy 178.943984 -304.251033) (xy 178.901363 -304.226426)
			(xy 178.863242 -304.195301) (xy 178.830607 -304.158464) (xy 178.804304 -304.116868) (xy 178.785013 -304.071592)
			(xy 178.773236 -304.023808) (xy 178.769276 -303.974754) (xy 178.430174 -303.974754) (xy 178.429679 -303.999361)
			(xy 178.421784 -304.047938) (xy 178.4062 -304.094619) (xy 178.383329 -304.138196) (xy 178.353764 -304.17754)
			(xy 178.318271 -304.211632) (xy 178.277768 -304.239588) (xy 178.233306 -304.260686) (xy 178.186035 -304.274378)
			(xy 178.13718 -304.28031) (xy 178.088005 -304.278329) (xy 178.039786 -304.268485) (xy 177.99377 -304.251033)
			(xy 177.951149 -304.226426) (xy 177.913028 -304.195301) (xy 177.880393 -304.158464) (xy 177.85409 -304.116868)
			(xy 177.834799 -304.071592) (xy 177.823022 -304.023808) (xy 177.819062 -303.974754) (xy 177.480214 -303.974754)
			(xy 177.479719 -303.999361) (xy 177.471824 -304.047938) (xy 177.45624 -304.094619) (xy 177.433369 -304.138196)
			(xy 177.403804 -304.17754) (xy 177.368311 -304.211632) (xy 177.327808 -304.239588) (xy 177.283346 -304.260686)
			(xy 177.236075 -304.274378) (xy 177.18722 -304.28031) (xy 177.138045 -304.278329) (xy 177.089826 -304.268485)
			(xy 177.04381 -304.251033) (xy 177.001189 -304.226426) (xy 176.963068 -304.195301) (xy 176.930433 -304.158464)
			(xy 176.90413 -304.116868) (xy 176.884839 -304.071592) (xy 176.873062 -304.023808) (xy 176.869102 -303.974754)
			(xy 176.530254 -303.974754) (xy 176.529759 -303.999361) (xy 176.521864 -304.047938) (xy 176.50628 -304.094619)
			(xy 176.483409 -304.138196) (xy 176.453844 -304.17754) (xy 176.418351 -304.211632) (xy 176.377848 -304.239588)
			(xy 176.333386 -304.260686) (xy 176.286115 -304.274378) (xy 176.23726 -304.28031) (xy 176.188085 -304.278329)
			(xy 176.139866 -304.268485) (xy 176.09385 -304.251033) (xy 176.051229 -304.226426) (xy 176.013108 -304.195301)
			(xy 175.980473 -304.158464) (xy 175.95417 -304.116868) (xy 175.934879 -304.071592) (xy 175.923102 -304.023808)
			(xy 175.919142 -303.974754) (xy 174.630334 -303.974754) (xy 174.629839 -303.999361) (xy 174.621944 -304.047938)
			(xy 174.60636 -304.094619) (xy 174.583489 -304.138196) (xy 174.553924 -304.17754) (xy 174.518431 -304.211632)
			(xy 174.477928 -304.239588) (xy 174.433466 -304.260686) (xy 174.386195 -304.274378) (xy 174.33734 -304.28031)
			(xy 174.288165 -304.278329) (xy 174.239946 -304.268485) (xy 174.19393 -304.251033) (xy 174.151309 -304.226426)
			(xy 174.113188 -304.195301) (xy 174.080553 -304.158464) (xy 174.05425 -304.116868) (xy 174.034959 -304.071592)
			(xy 174.023182 -304.023808) (xy 174.019222 -303.974754) (xy 173.680374 -303.974754) (xy 173.679879 -303.999361)
			(xy 173.671984 -304.047938) (xy 173.6564 -304.094619) (xy 173.633529 -304.138196) (xy 173.603964 -304.17754)
			(xy 173.568471 -304.211632) (xy 173.527968 -304.239588) (xy 173.483506 -304.260686) (xy 173.436235 -304.274378)
			(xy 173.38738 -304.28031) (xy 173.338205 -304.278329) (xy 173.289986 -304.268485) (xy 173.24397 -304.251033)
			(xy 173.201349 -304.226426) (xy 173.163228 -304.195301) (xy 173.130593 -304.158464) (xy 173.10429 -304.116868)
			(xy 173.084999 -304.071592) (xy 173.073222 -304.023808) (xy 173.069262 -303.974754) (xy 172.73016 -303.974754)
			(xy 172.729665 -303.999361) (xy 172.72177 -304.047938) (xy 172.706186 -304.094619) (xy 172.683315 -304.138196)
			(xy 172.65375 -304.17754) (xy 172.618257 -304.211632) (xy 172.577754 -304.239588) (xy 172.533292 -304.260686)
			(xy 172.486021 -304.274378) (xy 172.437166 -304.28031) (xy 172.387991 -304.278329) (xy 172.339772 -304.268485)
			(xy 172.293756 -304.251033) (xy 172.251135 -304.226426) (xy 172.213014 -304.195301) (xy 172.180379 -304.158464)
			(xy 172.154076 -304.116868) (xy 172.134785 -304.071592) (xy 172.123008 -304.023808) (xy 172.119048 -303.974754)
			(xy 171.7802 -303.974754) (xy 171.779705 -303.999361) (xy 171.77181 -304.047938) (xy 171.756226 -304.094619)
			(xy 171.733355 -304.138196) (xy 171.70379 -304.17754) (xy 171.668297 -304.211632) (xy 171.627794 -304.239588)
			(xy 171.583332 -304.260686) (xy 171.536061 -304.274378) (xy 171.487206 -304.28031) (xy 171.438031 -304.278329)
			(xy 171.389812 -304.268485) (xy 171.343796 -304.251033) (xy 171.301175 -304.226426) (xy 171.263054 -304.195301)
			(xy 171.230419 -304.158464) (xy 171.204116 -304.116868) (xy 171.184825 -304.071592) (xy 171.173048 -304.023808)
			(xy 171.169088 -303.974754) (xy 170.83024 -303.974754) (xy 170.829745 -303.999361) (xy 170.82185 -304.047938)
			(xy 170.806266 -304.094619) (xy 170.783395 -304.138196) (xy 170.75383 -304.17754) (xy 170.718337 -304.211632)
			(xy 170.677834 -304.239588) (xy 170.633372 -304.260686) (xy 170.586101 -304.274378) (xy 170.537246 -304.28031)
			(xy 170.488071 -304.278329) (xy 170.439852 -304.268485) (xy 170.393836 -304.251033) (xy 170.351215 -304.226426)
			(xy 170.313094 -304.195301) (xy 170.280459 -304.158464) (xy 170.254156 -304.116868) (xy 170.234865 -304.071592)
			(xy 170.223088 -304.023808) (xy 170.219128 -303.974754) (xy 169.88028 -303.974754) (xy 169.879785 -303.999361)
			(xy 169.87189 -304.047938) (xy 169.856306 -304.094619) (xy 169.833435 -304.138196) (xy 169.80387 -304.17754)
			(xy 169.768377 -304.211632) (xy 169.727874 -304.239588) (xy 169.683412 -304.260686) (xy 169.636141 -304.274378)
			(xy 169.587286 -304.28031) (xy 169.538111 -304.278329) (xy 169.489892 -304.268485) (xy 169.443876 -304.251033)
			(xy 169.401255 -304.226426) (xy 169.363134 -304.195301) (xy 169.330499 -304.158464) (xy 169.304196 -304.116868)
			(xy 169.284905 -304.071592) (xy 169.273128 -304.023808) (xy 169.269168 -303.974754) (xy 168.93032 -303.974754)
			(xy 168.929825 -303.999361) (xy 168.92193 -304.047938) (xy 168.906346 -304.094619) (xy 168.883475 -304.138196)
			(xy 168.85391 -304.17754) (xy 168.818417 -304.211632) (xy 168.777914 -304.239588) (xy 168.733452 -304.260686)
			(xy 168.686181 -304.274378) (xy 168.637326 -304.28031) (xy 168.588151 -304.278329) (xy 168.539932 -304.268485)
			(xy 168.493916 -304.251033) (xy 168.451295 -304.226426) (xy 168.413174 -304.195301) (xy 168.380539 -304.158464)
			(xy 168.354236 -304.116868) (xy 168.334945 -304.071592) (xy 168.323168 -304.023808) (xy 168.319208 -303.974754)
			(xy 167.98036 -303.974754) (xy 167.979865 -303.999361) (xy 167.97197 -304.047938) (xy 167.956386 -304.094619)
			(xy 167.933515 -304.138196) (xy 167.90395 -304.17754) (xy 167.868457 -304.211632) (xy 167.827954 -304.239588)
			(xy 167.783492 -304.260686) (xy 167.736221 -304.274378) (xy 167.687366 -304.28031) (xy 167.638191 -304.278329)
			(xy 167.589972 -304.268485) (xy 167.543956 -304.251033) (xy 167.501335 -304.226426) (xy 167.463214 -304.195301)
			(xy 167.430579 -304.158464) (xy 167.404276 -304.116868) (xy 167.384985 -304.071592) (xy 167.373208 -304.023808)
			(xy 167.369248 -303.974754) (xy 167.0304 -303.974754) (xy 167.029905 -303.999361) (xy 167.02201 -304.047938)
			(xy 167.006426 -304.094619) (xy 166.983555 -304.138196) (xy 166.95399 -304.17754) (xy 166.918497 -304.211632)
			(xy 166.877994 -304.239588) (xy 166.833532 -304.260686) (xy 166.786261 -304.274378) (xy 166.737406 -304.28031)
			(xy 166.688231 -304.278329) (xy 166.640012 -304.268485) (xy 166.593996 -304.251033) (xy 166.551375 -304.226426)
			(xy 166.513254 -304.195301) (xy 166.480619 -304.158464) (xy 166.454316 -304.116868) (xy 166.435025 -304.071592)
			(xy 166.423248 -304.023808) (xy 166.419288 -303.974754) (xy 166.080186 -303.974754) (xy 166.079691 -303.999361)
			(xy 166.071796 -304.047938) (xy 166.056212 -304.094619) (xy 166.033341 -304.138196) (xy 166.003776 -304.17754)
			(xy 165.968283 -304.211632) (xy 165.92778 -304.239588) (xy 165.883318 -304.260686) (xy 165.836047 -304.274378)
			(xy 165.787192 -304.28031) (xy 165.738017 -304.278329) (xy 165.689798 -304.268485) (xy 165.643782 -304.251033)
			(xy 165.601161 -304.226426) (xy 165.56304 -304.195301) (xy 165.530405 -304.158464) (xy 165.504102 -304.116868)
			(xy 165.484811 -304.071592) (xy 165.473034 -304.023808) (xy 165.469074 -303.974754) (xy 165.130226 -303.974754)
			(xy 165.129731 -303.999361) (xy 165.121836 -304.047938) (xy 165.106252 -304.094619) (xy 165.083381 -304.138196)
			(xy 165.053816 -304.17754) (xy 165.018323 -304.211632) (xy 164.97782 -304.239588) (xy 164.933358 -304.260686)
			(xy 164.886087 -304.274378) (xy 164.837232 -304.28031) (xy 164.788057 -304.278329) (xy 164.739838 -304.268485)
			(xy 164.693822 -304.251033) (xy 164.651201 -304.226426) (xy 164.61308 -304.195301) (xy 164.580445 -304.158464)
			(xy 164.554142 -304.116868) (xy 164.534851 -304.071592) (xy 164.523074 -304.023808) (xy 164.519114 -303.974754)
			(xy 164.180266 -303.974754) (xy 164.179771 -303.999361) (xy 164.171876 -304.047938) (xy 164.156292 -304.094619)
			(xy 164.133421 -304.138196) (xy 164.103856 -304.17754) (xy 164.068363 -304.211632) (xy 164.02786 -304.239588)
			(xy 163.983398 -304.260686) (xy 163.936127 -304.274378) (xy 163.887272 -304.28031) (xy 163.838097 -304.278329)
			(xy 163.789878 -304.268485) (xy 163.743862 -304.251033) (xy 163.701241 -304.226426) (xy 163.66312 -304.195301)
			(xy 163.630485 -304.158464) (xy 163.604182 -304.116868) (xy 163.584891 -304.071592) (xy 163.573114 -304.023808)
			(xy 163.569154 -303.974754) (xy 163.230306 -303.974754) (xy 163.229811 -303.999361) (xy 163.221916 -304.047938)
			(xy 163.206332 -304.094619) (xy 163.183461 -304.138196) (xy 163.153896 -304.17754) (xy 163.118403 -304.211632)
			(xy 163.0779 -304.239588) (xy 163.033438 -304.260686) (xy 162.986167 -304.274378) (xy 162.937312 -304.28031)
			(xy 162.888137 -304.278329) (xy 162.839918 -304.268485) (xy 162.793902 -304.251033) (xy 162.751281 -304.226426)
			(xy 162.71316 -304.195301) (xy 162.680525 -304.158464) (xy 162.654222 -304.116868) (xy 162.634931 -304.071592)
			(xy 162.623154 -304.023808) (xy 162.619194 -303.974754) (xy 118.832884 -303.974754) (xy 118.832884 -305.008534)
			(xy 120.828816 -305.008534) (xy 120.829298 -304.981164) (xy 120.837111 -304.926986) (xy 120.852597 -304.874483)
			(xy 120.875435 -304.824736) (xy 120.905156 -304.778768) (xy 120.922796 -304.757836) (xy 120.928892 -304.750724)
			(xy 120.935242 -304.733706) (xy 120.935242 -304.648362) (xy 120.928892 -304.631344) (xy 120.922796 -304.624232)
			(xy 120.905158 -304.603299) (xy 120.875446 -304.557327) (xy 120.85261 -304.507579) (xy 120.837119 -304.455079)
			(xy 120.82929 -304.400903) (xy 120.828816 -304.373534) (xy 120.829302 -304.346283) (xy 120.837058 -304.292335)
			(xy 120.852413 -304.24004) (xy 120.875055 -304.190463) (xy 120.904521 -304.144613) (xy 120.940212 -304.103422)
			(xy 120.981403 -304.067731) (xy 121.027253 -304.038265) (xy 121.07683 -304.015623) (xy 121.129125 -304.000268)
			(xy 121.183073 -303.992512) (xy 121.237575 -303.992512) (xy 121.291523 -304.000268) (xy 121.343818 -304.015623)
			(xy 121.393395 -304.038265) (xy 121.439245 -304.067731) (xy 121.480436 -304.103422) (xy 121.516127 -304.144613)
			(xy 121.545593 -304.190463) (xy 121.568235 -304.24004) (xy 121.58359 -304.292335) (xy 121.591346 -304.346283)
			(xy 121.591832 -304.373534) (xy 121.591402 -304.400906) (xy 121.583578 -304.455087) (xy 121.568082 -304.507591)
			(xy 121.545231 -304.557338) (xy 121.515498 -304.603302) (xy 121.497852 -304.624232) (xy 121.491756 -304.631344)
			(xy 121.485406 -304.648362) (xy 121.485406 -304.733706) (xy 121.491756 -304.750724) (xy 121.497852 -304.757836)
			(xy 121.515467 -304.778788) (xy 121.545184 -304.824754) (xy 121.568026 -304.874497) (xy 121.583522 -304.926993)
			(xy 121.591355 -304.981166) (xy 121.591832 -305.008534) (xy 124.248926 -305.008534) (xy 124.249406 -304.981164)
			(xy 124.257219 -304.926985) (xy 124.272705 -304.874482) (xy 124.295544 -304.824735) (xy 124.325266 -304.778768)
			(xy 124.342906 -304.757836) (xy 124.349002 -304.750724) (xy 124.355352 -304.733706) (xy 124.355352 -304.648362)
			(xy 124.349002 -304.631344) (xy 124.342906 -304.624232) (xy 124.325269 -304.603298) (xy 124.295557 -304.557326)
			(xy 124.27272 -304.507579) (xy 124.257229 -304.455079) (xy 124.2494 -304.400903) (xy 124.248926 -304.373534)
			(xy 124.249412 -304.346283) (xy 124.257168 -304.292335) (xy 124.272523 -304.24004) (xy 124.295165 -304.190463)
			(xy 124.324631 -304.144613) (xy 124.360322 -304.103422) (xy 124.401513 -304.067731) (xy 124.447363 -304.038265)
			(xy 124.49694 -304.015623) (xy 124.549235 -304.000268) (xy 124.603183 -303.992512) (xy 124.657685 -303.992512)
			(xy 124.711633 -304.000268) (xy 124.763928 -304.015623) (xy 124.813505 -304.038265) (xy 124.859355 -304.067731)
			(xy 124.900546 -304.103422) (xy 124.936237 -304.144613) (xy 124.965703 -304.190463) (xy 124.988345 -304.24004)
			(xy 125.0037 -304.292335) (xy 125.011456 -304.346283) (xy 125.011942 -304.373534) (xy 125.01151 -304.400906)
			(xy 125.003686 -304.455087) (xy 124.98819 -304.507591) (xy 124.96534 -304.557337) (xy 124.935607 -304.603302)
			(xy 124.917962 -304.624232) (xy 124.911866 -304.631344) (xy 124.905516 -304.648362) (xy 124.905516 -304.733706)
			(xy 124.911866 -304.750724) (xy 124.917962 -304.757836) (xy 124.935579 -304.778786) (xy 124.965295 -304.824753)
			(xy 124.988136 -304.874496) (xy 125.003632 -304.926993) (xy 125.011465 -304.981166) (xy 125.011942 -305.008534)
			(xy 125.637036 -305.008534) (xy 125.637513 -304.981164) (xy 125.645327 -304.926985) (xy 125.660813 -304.874482)
			(xy 125.683652 -304.824735) (xy 125.713375 -304.778768) (xy 125.731016 -304.757836) (xy 125.737112 -304.750724)
			(xy 125.743462 -304.733706) (xy 125.743462 -304.648362) (xy 125.737112 -304.631344) (xy 125.731016 -304.624232)
			(xy 125.713381 -304.603297) (xy 125.683668 -304.557325) (xy 125.660831 -304.507578) (xy 125.645339 -304.455078)
			(xy 125.63751 -304.400903) (xy 125.637036 -304.373534) (xy 125.637522 -304.346283) (xy 125.645278 -304.292335)
			(xy 125.660633 -304.24004) (xy 125.683275 -304.190463) (xy 125.712741 -304.144613) (xy 125.748432 -304.103422)
			(xy 125.789623 -304.067731) (xy 125.835473 -304.038265) (xy 125.88505 -304.015623) (xy 125.937345 -304.000268)
			(xy 125.991293 -303.992512) (xy 126.045795 -303.992512) (xy 126.099743 -304.000268) (xy 126.152038 -304.015623)
			(xy 126.201615 -304.038265) (xy 126.247465 -304.067731) (xy 126.288656 -304.103422) (xy 126.324347 -304.144613)
			(xy 126.353813 -304.190463) (xy 126.376455 -304.24004) (xy 126.39181 -304.292335) (xy 126.399566 -304.346283)
			(xy 126.400052 -304.373534) (xy 126.399618 -304.400906) (xy 126.391794 -304.455086) (xy 126.376298 -304.50759)
			(xy 126.353449 -304.557337) (xy 126.323717 -304.603302) (xy 126.306072 -304.624232) (xy 126.299976 -304.631344)
			(xy 126.293626 -304.648362) (xy 126.293626 -304.733706) (xy 126.299976 -304.750724) (xy 126.306072 -304.757836)
			(xy 126.32369 -304.778785) (xy 126.353406 -304.824753) (xy 126.376247 -304.874496) (xy 126.391742 -304.926993)
			(xy 126.399576 -304.981166) (xy 126.400052 -305.008534) (xy 127.669036 -305.008534) (xy 127.669513 -304.981164)
			(xy 127.677327 -304.926985) (xy 127.692813 -304.874482) (xy 127.715652 -304.824735) (xy 127.745375 -304.778768)
			(xy 127.763016 -304.757836) (xy 127.769112 -304.750724) (xy 127.775462 -304.733706) (xy 127.775462 -304.648362)
			(xy 127.769112 -304.631344) (xy 127.763016 -304.624232) (xy 127.745381 -304.603297) (xy 127.715668 -304.557325)
			(xy 127.692831 -304.507578) (xy 127.677339 -304.455078) (xy 127.66951 -304.400903) (xy 127.669036 -304.373534)
			(xy 127.669522 -304.346283) (xy 127.677278 -304.292335) (xy 127.692633 -304.24004) (xy 127.715275 -304.190463)
			(xy 127.744741 -304.144613) (xy 127.780432 -304.103422) (xy 127.821623 -304.067731) (xy 127.867473 -304.038265)
			(xy 127.91705 -304.015623) (xy 127.969345 -304.000268) (xy 128.023293 -303.992512) (xy 128.077795 -303.992512)
			(xy 128.131743 -304.000268) (xy 128.184038 -304.015623) (xy 128.233615 -304.038265) (xy 128.279465 -304.067731)
			(xy 128.320656 -304.103422) (xy 128.356347 -304.144613) (xy 128.385813 -304.190463) (xy 128.408455 -304.24004)
			(xy 128.42381 -304.292335) (xy 128.431566 -304.346283) (xy 128.432052 -304.373534) (xy 128.431618 -304.400906)
			(xy 128.423794 -304.455086) (xy 128.408298 -304.50759) (xy 128.385449 -304.557337) (xy 128.355717 -304.603302)
			(xy 128.338072 -304.624232) (xy 128.331976 -304.631344) (xy 128.325626 -304.648362) (xy 128.325626 -304.733706)
			(xy 128.331976 -304.750724) (xy 128.338072 -304.757836) (xy 128.35569 -304.778785) (xy 128.385406 -304.824753)
			(xy 128.408247 -304.874496) (xy 128.423742 -304.926993) (xy 128.431576 -304.981166) (xy 128.432052 -305.008534)
			(xy 132.477256 -305.008534) (xy 132.477728 -304.981164) (xy 132.485543 -304.926984) (xy 132.501029 -304.874481)
			(xy 132.52387 -304.824734) (xy 132.553595 -304.778767) (xy 132.571236 -304.757836) (xy 132.577332 -304.750724)
			(xy 132.583682 -304.733706) (xy 132.583682 -304.648362) (xy 132.577332 -304.631344) (xy 132.571236 -304.624232)
			(xy 132.553604 -304.603294) (xy 132.52389 -304.557323) (xy 132.501052 -304.507577) (xy 132.485559 -304.455078)
			(xy 132.47773 -304.400903) (xy 132.477256 -304.373534) (xy 132.477742 -304.346283) (xy 132.485498 -304.292335)
			(xy 132.500853 -304.24004) (xy 132.523495 -304.190463) (xy 132.552961 -304.144613) (xy 132.588652 -304.103422)
			(xy 132.629843 -304.067731) (xy 132.675693 -304.038265) (xy 132.72527 -304.015623) (xy 132.777565 -304.000268)
			(xy 132.831513 -303.992512) (xy 132.886015 -303.992512) (xy 132.939963 -304.000268) (xy 132.992258 -304.015623)
			(xy 133.041835 -304.038265) (xy 133.087685 -304.067731) (xy 133.128876 -304.103422) (xy 133.164567 -304.144613)
			(xy 133.194033 -304.190463) (xy 133.216675 -304.24004) (xy 133.23203 -304.292335) (xy 133.239786 -304.346283)
			(xy 133.240272 -304.373534) (xy 133.239833 -304.400905) (xy 133.232009 -304.455086) (xy 133.216514 -304.507589)
			(xy 133.193667 -304.557336) (xy 133.163936 -304.603301) (xy 133.146292 -304.624232) (xy 133.140196 -304.631344)
			(xy 133.133846 -304.648362) (xy 133.133846 -304.733706) (xy 133.140196 -304.750724) (xy 133.146292 -304.757836)
			(xy 133.163913 -304.778782) (xy 133.193628 -304.824751) (xy 133.216468 -304.874495) (xy 133.231963 -304.926993)
			(xy 133.239796 -304.981166) (xy 133.240272 -305.008534) (xy 133.239786 -305.035785) (xy 133.23203 -305.089733)
			(xy 133.216675 -305.142028) (xy 133.194033 -305.191605) (xy 133.164567 -305.237455) (xy 133.128876 -305.278646)
			(xy 133.096209 -305.306951) (xy 143.510416 -305.306951) (xy 143.518174 -305.252993) (xy 143.533531 -305.200689)
			(xy 143.556176 -305.151102) (xy 143.585647 -305.105243) (xy 143.621345 -305.064045) (xy 143.662543 -305.028347)
			(xy 143.708403 -304.998876) (xy 143.757989 -304.976231) (xy 143.810294 -304.960873) (xy 143.864252 -304.953116)
			(xy 143.891508 -304.952654) (xy 143.919448 -304.95367) (xy 143.930624 -304.954432) (xy 143.951706 -304.946558)
			(xy 144.02181 -304.873914) (xy 144.029176 -304.852578) (xy 144.027906 -304.841402) (xy 144.026845 -304.831148)
			(xy 144.025701 -304.810562) (xy 144.02562 -304.800254) (xy 144.026127 -304.773007) (xy 144.033889 -304.719069)
			(xy 144.049247 -304.666785) (xy 144.07189 -304.617218) (xy 144.101356 -304.571378) (xy 144.137045 -304.530197)
			(xy 144.178232 -304.494515) (xy 144.224077 -304.465057) (xy 144.273648 -304.442424) (xy 144.325935 -304.427074)
			(xy 144.379874 -304.419323) (xy 144.434368 -304.419326) (xy 144.488307 -304.427084) (xy 144.540592 -304.442438)
			(xy 144.557122 -304.449988) (xy 151.693892 -304.449988) (xy 151.697852 -304.400934) (xy 151.709629 -304.35315)
			(xy 151.72892 -304.307874) (xy 151.755223 -304.266278) (xy 151.787858 -304.229441) (xy 151.825979 -304.198316)
			(xy 151.8686 -304.173709) (xy 151.914616 -304.156257) (xy 151.962835 -304.146413) (xy 152.01201 -304.144432)
			(xy 152.060865 -304.150364) (xy 152.108136 -304.164056) (xy 152.152598 -304.185154) (xy 152.193101 -304.21311)
			(xy 152.228594 -304.247202) (xy 152.258159 -304.286546) (xy 152.28103 -304.330123) (xy 152.296614 -304.376804)
			(xy 152.304509 -304.425381) (xy 152.305004 -304.449988) (xy 152.304509 -304.474595) (xy 152.304371 -304.475442)
			(xy 152.623262 -304.475442) (xy 152.623262 -304.424026) (xy 152.631305 -304.373244) (xy 152.647193 -304.324345)
			(xy 152.670536 -304.278533) (xy 152.700757 -304.236937) (xy 152.737113 -304.200581) (xy 152.778709 -304.17036)
			(xy 152.824521 -304.147017) (xy 152.87342 -304.131129) (xy 152.924202 -304.123086) (xy 152.975618 -304.123086)
			(xy 153.0264 -304.131129) (xy 153.075299 -304.147017) (xy 153.121111 -304.17036) (xy 153.162707 -304.200581)
			(xy 153.199063 -304.236937) (xy 153.229284 -304.278533) (xy 153.252627 -304.324345) (xy 153.268515 -304.373244)
			(xy 153.276558 -304.424026) (xy 153.277062 -304.449734) (xy 153.276558 -304.475442) (xy 153.573222 -304.475442)
			(xy 153.573222 -304.424026) (xy 153.581265 -304.373244) (xy 153.597153 -304.324345) (xy 153.620496 -304.278533)
			(xy 153.650717 -304.236937) (xy 153.687073 -304.200581) (xy 153.728669 -304.17036) (xy 153.774481 -304.147017)
			(xy 153.82338 -304.131129) (xy 153.874162 -304.123086) (xy 153.925578 -304.123086) (xy 153.97636 -304.131129)
			(xy 154.025259 -304.147017) (xy 154.071071 -304.17036) (xy 154.112667 -304.200581) (xy 154.149023 -304.236937)
			(xy 154.179244 -304.278533) (xy 154.202587 -304.324345) (xy 154.218475 -304.373244) (xy 154.226518 -304.424026)
			(xy 154.227022 -304.449734) (xy 154.54428 -304.449734) (xy 154.54824 -304.40068) (xy 154.560017 -304.352896)
			(xy 154.579308 -304.30762) (xy 154.605611 -304.266024) (xy 154.638246 -304.229187) (xy 154.676367 -304.198062)
			(xy 154.718988 -304.173455) (xy 154.765004 -304.156003) (xy 154.813223 -304.146159) (xy 154.862398 -304.144178)
			(xy 154.911253 -304.15011) (xy 154.958524 -304.163802) (xy 155.002986 -304.1849) (xy 155.043489 -304.212856)
			(xy 155.078982 -304.246948) (xy 155.108547 -304.286292) (xy 155.131418 -304.329869) (xy 155.147002 -304.37655)
			(xy 155.154897 -304.425127) (xy 155.155392 -304.449734) (xy 155.49424 -304.449734) (xy 155.4982 -304.40068)
			(xy 155.509977 -304.352896) (xy 155.529268 -304.30762) (xy 155.555571 -304.266024) (xy 155.588206 -304.229187)
			(xy 155.626327 -304.198062) (xy 155.668948 -304.173455) (xy 155.714964 -304.156003) (xy 155.763183 -304.146159)
			(xy 155.812358 -304.144178) (xy 155.861213 -304.15011) (xy 155.908484 -304.163802) (xy 155.952946 -304.1849)
			(xy 155.993449 -304.212856) (xy 156.028942 -304.246948) (xy 156.058507 -304.286292) (xy 156.081378 -304.329869)
			(xy 156.096962 -304.37655) (xy 156.104857 -304.425127) (xy 156.105352 -304.449734) (xy 156.4442 -304.449734)
			(xy 156.44816 -304.40068) (xy 156.459937 -304.352896) (xy 156.479228 -304.30762) (xy 156.505531 -304.266024)
			(xy 156.538166 -304.229187) (xy 156.576287 -304.198062) (xy 156.618908 -304.173455) (xy 156.664924 -304.156003)
			(xy 156.713143 -304.146159) (xy 156.762318 -304.144178) (xy 156.811173 -304.15011) (xy 156.858444 -304.163802)
			(xy 156.902906 -304.1849) (xy 156.943409 -304.212856) (xy 156.978902 -304.246948) (xy 157.008467 -304.286292)
			(xy 157.031338 -304.329869) (xy 157.046922 -304.37655) (xy 157.054817 -304.425127) (xy 157.055312 -304.449734)
			(xy 157.39416 -304.449734) (xy 157.39812 -304.40068) (xy 157.409897 -304.352896) (xy 157.429188 -304.30762)
			(xy 157.455491 -304.266024) (xy 157.488126 -304.229187) (xy 157.526247 -304.198062) (xy 157.568868 -304.173455)
			(xy 157.614884 -304.156003) (xy 157.663103 -304.146159) (xy 157.712278 -304.144178) (xy 157.761133 -304.15011)
			(xy 157.808404 -304.163802) (xy 157.852866 -304.1849) (xy 157.893369 -304.212856) (xy 157.928862 -304.246948)
			(xy 157.958427 -304.286292) (xy 157.981298 -304.329869) (xy 157.996882 -304.37655) (xy 158.004777 -304.425127)
			(xy 158.005272 -304.449734) (xy 158.34412 -304.449734) (xy 158.34808 -304.40068) (xy 158.359857 -304.352896)
			(xy 158.379148 -304.30762) (xy 158.405451 -304.266024) (xy 158.438086 -304.229187) (xy 158.476207 -304.198062)
			(xy 158.518828 -304.173455) (xy 158.564844 -304.156003) (xy 158.613063 -304.146159) (xy 158.662238 -304.144178)
			(xy 158.711093 -304.15011) (xy 158.758364 -304.163802) (xy 158.802826 -304.1849) (xy 158.843329 -304.212856)
			(xy 158.878822 -304.246948) (xy 158.908387 -304.286292) (xy 158.931258 -304.329869) (xy 158.946842 -304.37655)
			(xy 158.954737 -304.425127) (xy 158.955232 -304.449734) (xy 158.954737 -304.474341) (xy 158.954558 -304.475442)
			(xy 159.273236 -304.475442) (xy 159.273236 -304.424026) (xy 159.281279 -304.373244) (xy 159.297167 -304.324345)
			(xy 159.32051 -304.278533) (xy 159.350731 -304.236937) (xy 159.387087 -304.200581) (xy 159.428683 -304.17036)
			(xy 159.474495 -304.147017) (xy 159.523394 -304.131129) (xy 159.574176 -304.123086) (xy 159.625592 -304.123086)
			(xy 159.676374 -304.131129) (xy 159.725273 -304.147017) (xy 159.771085 -304.17036) (xy 159.812681 -304.200581)
			(xy 159.849037 -304.236937) (xy 159.879258 -304.278533) (xy 159.902601 -304.324345) (xy 159.918489 -304.373244)
			(xy 159.926532 -304.424026) (xy 159.927036 -304.449734) (xy 159.926532 -304.475442) (xy 160.223196 -304.475442)
			(xy 160.223196 -304.424026) (xy 160.231239 -304.373244) (xy 160.247127 -304.324345) (xy 160.27047 -304.278533)
			(xy 160.300691 -304.236937) (xy 160.337047 -304.200581) (xy 160.378643 -304.17036) (xy 160.424455 -304.147017)
			(xy 160.473354 -304.131129) (xy 160.524136 -304.123086) (xy 160.575552 -304.123086) (xy 160.626334 -304.131129)
			(xy 160.675233 -304.147017) (xy 160.721045 -304.17036) (xy 160.762641 -304.200581) (xy 160.798997 -304.236937)
			(xy 160.829218 -304.278533) (xy 160.852561 -304.324345) (xy 160.868449 -304.373244) (xy 160.876492 -304.424026)
			(xy 160.876996 -304.449734) (xy 161.194254 -304.449734) (xy 161.198214 -304.40068) (xy 161.209991 -304.352896)
			(xy 161.229282 -304.30762) (xy 161.255585 -304.266024) (xy 161.28822 -304.229187) (xy 161.326341 -304.198062)
			(xy 161.368962 -304.173455) (xy 161.414978 -304.156003) (xy 161.463197 -304.146159) (xy 161.512372 -304.144178)
			(xy 161.561227 -304.15011) (xy 161.608498 -304.163802) (xy 161.65296 -304.1849) (xy 161.693463 -304.212856)
			(xy 161.728956 -304.246948) (xy 161.758521 -304.286292) (xy 161.781392 -304.329869) (xy 161.796976 -304.37655)
			(xy 161.804871 -304.425127) (xy 161.805366 -304.449734) (xy 161.804871 -304.474341) (xy 161.796976 -304.522918)
			(xy 161.781392 -304.569599) (xy 161.758521 -304.613176) (xy 161.728956 -304.65252) (xy 161.693463 -304.686612)
			(xy 161.65296 -304.714568) (xy 161.608498 -304.735666) (xy 161.561227 -304.749358) (xy 161.512372 -304.75529)
			(xy 161.463197 -304.753309) (xy 161.414978 -304.743465) (xy 161.368962 -304.726013) (xy 161.326341 -304.701406)
			(xy 161.28822 -304.670281) (xy 161.255585 -304.633444) (xy 161.229282 -304.591848) (xy 161.209991 -304.546572)
			(xy 161.198214 -304.498788) (xy 161.194254 -304.449734) (xy 160.876996 -304.449734) (xy 160.876492 -304.475442)
			(xy 160.868449 -304.526224) (xy 160.852561 -304.575123) (xy 160.829218 -304.620935) (xy 160.798997 -304.662531)
			(xy 160.762641 -304.698887) (xy 160.721045 -304.729108) (xy 160.675233 -304.752451) (xy 160.626334 -304.768339)
			(xy 160.575552 -304.776382) (xy 160.524136 -304.776382) (xy 160.473354 -304.768339) (xy 160.424455 -304.752451)
			(xy 160.378643 -304.729108) (xy 160.337047 -304.698887) (xy 160.300691 -304.662531) (xy 160.27047 -304.620935)
			(xy 160.247127 -304.575123) (xy 160.231239 -304.526224) (xy 160.223196 -304.475442) (xy 159.926532 -304.475442)
			(xy 159.918489 -304.526224) (xy 159.902601 -304.575123) (xy 159.879258 -304.620935) (xy 159.849037 -304.662531)
			(xy 159.812681 -304.698887) (xy 159.771085 -304.729108) (xy 159.725273 -304.752451) (xy 159.676374 -304.768339)
			(xy 159.625592 -304.776382) (xy 159.574176 -304.776382) (xy 159.523394 -304.768339) (xy 159.474495 -304.752451)
			(xy 159.428683 -304.729108) (xy 159.387087 -304.698887) (xy 159.350731 -304.662531) (xy 159.32051 -304.620935)
			(xy 159.297167 -304.575123) (xy 159.281279 -304.526224) (xy 159.273236 -304.475442) (xy 158.954558 -304.475442)
			(xy 158.946842 -304.522918) (xy 158.931258 -304.569599) (xy 158.908387 -304.613176) (xy 158.878822 -304.65252)
			(xy 158.843329 -304.686612) (xy 158.802826 -304.714568) (xy 158.758364 -304.735666) (xy 158.711093 -304.749358)
			(xy 158.662238 -304.75529) (xy 158.613063 -304.753309) (xy 158.564844 -304.743465) (xy 158.518828 -304.726013)
			(xy 158.476207 -304.701406) (xy 158.438086 -304.670281) (xy 158.405451 -304.633444) (xy 158.379148 -304.591848)
			(xy 158.359857 -304.546572) (xy 158.34808 -304.498788) (xy 158.34412 -304.449734) (xy 158.005272 -304.449734)
			(xy 158.004777 -304.474341) (xy 157.996882 -304.522918) (xy 157.981298 -304.569599) (xy 157.958427 -304.613176)
			(xy 157.928862 -304.65252) (xy 157.893369 -304.686612) (xy 157.852866 -304.714568) (xy 157.808404 -304.735666)
			(xy 157.761133 -304.749358) (xy 157.712278 -304.75529) (xy 157.663103 -304.753309) (xy 157.614884 -304.743465)
			(xy 157.568868 -304.726013) (xy 157.526247 -304.701406) (xy 157.488126 -304.670281) (xy 157.455491 -304.633444)
			(xy 157.429188 -304.591848) (xy 157.409897 -304.546572) (xy 157.39812 -304.498788) (xy 157.39416 -304.449734)
			(xy 157.055312 -304.449734) (xy 157.054817 -304.474341) (xy 157.046922 -304.522918) (xy 157.031338 -304.569599)
			(xy 157.008467 -304.613176) (xy 156.978902 -304.65252) (xy 156.943409 -304.686612) (xy 156.902906 -304.714568)
			(xy 156.858444 -304.735666) (xy 156.811173 -304.749358) (xy 156.762318 -304.75529) (xy 156.713143 -304.753309)
			(xy 156.664924 -304.743465) (xy 156.618908 -304.726013) (xy 156.576287 -304.701406) (xy 156.538166 -304.670281)
			(xy 156.505531 -304.633444) (xy 156.479228 -304.591848) (xy 156.459937 -304.546572) (xy 156.44816 -304.498788)
			(xy 156.4442 -304.449734) (xy 156.105352 -304.449734) (xy 156.104857 -304.474341) (xy 156.096962 -304.522918)
			(xy 156.081378 -304.569599) (xy 156.058507 -304.613176) (xy 156.028942 -304.65252) (xy 155.993449 -304.686612)
			(xy 155.952946 -304.714568) (xy 155.908484 -304.735666) (xy 155.861213 -304.749358) (xy 155.812358 -304.75529)
			(xy 155.763183 -304.753309) (xy 155.714964 -304.743465) (xy 155.668948 -304.726013) (xy 155.626327 -304.701406)
			(xy 155.588206 -304.670281) (xy 155.555571 -304.633444) (xy 155.529268 -304.591848) (xy 155.509977 -304.546572)
			(xy 155.4982 -304.498788) (xy 155.49424 -304.449734) (xy 155.155392 -304.449734) (xy 155.154897 -304.474341)
			(xy 155.147002 -304.522918) (xy 155.131418 -304.569599) (xy 155.108547 -304.613176) (xy 155.078982 -304.65252)
			(xy 155.043489 -304.686612) (xy 155.002986 -304.714568) (xy 154.958524 -304.735666) (xy 154.911253 -304.749358)
			(xy 154.862398 -304.75529) (xy 154.813223 -304.753309) (xy 154.765004 -304.743465) (xy 154.718988 -304.726013)
			(xy 154.676367 -304.701406) (xy 154.638246 -304.670281) (xy 154.605611 -304.633444) (xy 154.579308 -304.591848)
			(xy 154.560017 -304.546572) (xy 154.54824 -304.498788) (xy 154.54428 -304.449734) (xy 154.227022 -304.449734)
			(xy 154.226518 -304.475442) (xy 154.218475 -304.526224) (xy 154.202587 -304.575123) (xy 154.179244 -304.620935)
			(xy 154.149023 -304.662531) (xy 154.112667 -304.698887) (xy 154.071071 -304.729108) (xy 154.025259 -304.752451)
			(xy 153.97636 -304.768339) (xy 153.925578 -304.776382) (xy 153.874162 -304.776382) (xy 153.82338 -304.768339)
			(xy 153.774481 -304.752451) (xy 153.728669 -304.729108) (xy 153.687073 -304.698887) (xy 153.650717 -304.662531)
			(xy 153.620496 -304.620935) (xy 153.597153 -304.575123) (xy 153.581265 -304.526224) (xy 153.573222 -304.475442)
			(xy 153.276558 -304.475442) (xy 153.268515 -304.526224) (xy 153.252627 -304.575123) (xy 153.229284 -304.620935)
			(xy 153.199063 -304.662531) (xy 153.162707 -304.698887) (xy 153.121111 -304.729108) (xy 153.075299 -304.752451)
			(xy 153.0264 -304.768339) (xy 152.975618 -304.776382) (xy 152.924202 -304.776382) (xy 152.87342 -304.768339)
			(xy 152.824521 -304.752451) (xy 152.778709 -304.729108) (xy 152.737113 -304.698887) (xy 152.700757 -304.662531)
			(xy 152.670536 -304.620935) (xy 152.647193 -304.575123) (xy 152.631305 -304.526224) (xy 152.623262 -304.475442)
			(xy 152.304371 -304.475442) (xy 152.296614 -304.523172) (xy 152.28103 -304.569853) (xy 152.258159 -304.61343)
			(xy 152.228594 -304.652774) (xy 152.193101 -304.686866) (xy 152.152598 -304.714822) (xy 152.108136 -304.73592)
			(xy 152.060865 -304.749612) (xy 152.01201 -304.755544) (xy 151.962835 -304.753563) (xy 151.914616 -304.743719)
			(xy 151.8686 -304.726267) (xy 151.825979 -304.70166) (xy 151.787858 -304.670535) (xy 151.755223 -304.633698)
			(xy 151.72892 -304.592102) (xy 151.709629 -304.546826) (xy 151.697852 -304.499042) (xy 151.693892 -304.449988)
			(xy 144.557122 -304.449988) (xy 144.590161 -304.465078) (xy 144.636003 -304.494541) (xy 144.677185 -304.530228)
			(xy 144.71287 -304.571412) (xy 144.742331 -304.617255) (xy 144.764968 -304.666825) (xy 144.78032 -304.719111)
			(xy 144.788076 -304.77305) (xy 144.788076 -304.827543) (xy 144.780322 -304.881483) (xy 144.767629 -304.924714)
			(xy 162.619194 -304.924714) (xy 162.623154 -304.87566) (xy 162.634931 -304.827876) (xy 162.654222 -304.7826)
			(xy 162.680525 -304.741004) (xy 162.71316 -304.704167) (xy 162.751281 -304.673042) (xy 162.793902 -304.648435)
			(xy 162.839918 -304.630983) (xy 162.888137 -304.621139) (xy 162.937312 -304.619158) (xy 162.986167 -304.62509)
			(xy 163.033438 -304.638782) (xy 163.0779 -304.65988) (xy 163.118403 -304.687836) (xy 163.153896 -304.721928)
			(xy 163.183461 -304.761272) (xy 163.206332 -304.804849) (xy 163.221916 -304.85153) (xy 163.229811 -304.900107)
			(xy 163.230306 -304.924714) (xy 163.569154 -304.924714) (xy 163.573114 -304.87566) (xy 163.584891 -304.827876)
			(xy 163.604182 -304.7826) (xy 163.630485 -304.741004) (xy 163.66312 -304.704167) (xy 163.701241 -304.673042)
			(xy 163.743862 -304.648435) (xy 163.789878 -304.630983) (xy 163.838097 -304.621139) (xy 163.887272 -304.619158)
			(xy 163.936127 -304.62509) (xy 163.983398 -304.638782) (xy 164.02786 -304.65988) (xy 164.068363 -304.687836)
			(xy 164.103856 -304.721928) (xy 164.133421 -304.761272) (xy 164.156292 -304.804849) (xy 164.171876 -304.85153)
			(xy 164.179771 -304.900107) (xy 164.180266 -304.924714) (xy 164.519114 -304.924714) (xy 164.523074 -304.87566)
			(xy 164.534851 -304.827876) (xy 164.554142 -304.7826) (xy 164.580445 -304.741004) (xy 164.61308 -304.704167)
			(xy 164.651201 -304.673042) (xy 164.693822 -304.648435) (xy 164.739838 -304.630983) (xy 164.788057 -304.621139)
			(xy 164.837232 -304.619158) (xy 164.886087 -304.62509) (xy 164.933358 -304.638782) (xy 164.97782 -304.65988)
			(xy 165.018323 -304.687836) (xy 165.053816 -304.721928) (xy 165.083381 -304.761272) (xy 165.106252 -304.804849)
			(xy 165.121836 -304.85153) (xy 165.129731 -304.900107) (xy 165.130226 -304.924714) (xy 165.469074 -304.924714)
			(xy 165.473034 -304.87566) (xy 165.484811 -304.827876) (xy 165.504102 -304.7826) (xy 165.530405 -304.741004)
			(xy 165.56304 -304.704167) (xy 165.601161 -304.673042) (xy 165.643782 -304.648435) (xy 165.689798 -304.630983)
			(xy 165.738017 -304.621139) (xy 165.787192 -304.619158) (xy 165.836047 -304.62509) (xy 165.883318 -304.638782)
			(xy 165.92778 -304.65988) (xy 165.968283 -304.687836) (xy 166.003776 -304.721928) (xy 166.033341 -304.761272)
			(xy 166.056212 -304.804849) (xy 166.071796 -304.85153) (xy 166.079691 -304.900107) (xy 166.080186 -304.924714)
			(xy 166.419288 -304.924714) (xy 166.423248 -304.87566) (xy 166.435025 -304.827876) (xy 166.454316 -304.7826)
			(xy 166.480619 -304.741004) (xy 166.513254 -304.704167) (xy 166.551375 -304.673042) (xy 166.593996 -304.648435)
			(xy 166.640012 -304.630983) (xy 166.688231 -304.621139) (xy 166.737406 -304.619158) (xy 166.786261 -304.62509)
			(xy 166.833532 -304.638782) (xy 166.877994 -304.65988) (xy 166.918497 -304.687836) (xy 166.95399 -304.721928)
			(xy 166.983555 -304.761272) (xy 167.006426 -304.804849) (xy 167.02201 -304.85153) (xy 167.029905 -304.900107)
			(xy 167.0304 -304.924714) (xy 167.369248 -304.924714) (xy 167.373208 -304.87566) (xy 167.384985 -304.827876)
			(xy 167.404276 -304.7826) (xy 167.430579 -304.741004) (xy 167.463214 -304.704167) (xy 167.501335 -304.673042)
			(xy 167.543956 -304.648435) (xy 167.589972 -304.630983) (xy 167.638191 -304.621139) (xy 167.687366 -304.619158)
			(xy 167.736221 -304.62509) (xy 167.783492 -304.638782) (xy 167.827954 -304.65988) (xy 167.868457 -304.687836)
			(xy 167.90395 -304.721928) (xy 167.933515 -304.761272) (xy 167.956386 -304.804849) (xy 167.97197 -304.85153)
			(xy 167.979865 -304.900107) (xy 167.98036 -304.924714) (xy 168.319208 -304.924714) (xy 168.323168 -304.87566)
			(xy 168.334945 -304.827876) (xy 168.354236 -304.7826) (xy 168.380539 -304.741004) (xy 168.413174 -304.704167)
			(xy 168.451295 -304.673042) (xy 168.493916 -304.648435) (xy 168.539932 -304.630983) (xy 168.588151 -304.621139)
			(xy 168.637326 -304.619158) (xy 168.686181 -304.62509) (xy 168.733452 -304.638782) (xy 168.777914 -304.65988)
			(xy 168.818417 -304.687836) (xy 168.85391 -304.721928) (xy 168.883475 -304.761272) (xy 168.906346 -304.804849)
			(xy 168.92193 -304.85153) (xy 168.929825 -304.900107) (xy 168.93032 -304.924714) (xy 169.269168 -304.924714)
			(xy 169.273128 -304.87566) (xy 169.284905 -304.827876) (xy 169.304196 -304.7826) (xy 169.330499 -304.741004)
			(xy 169.363134 -304.704167) (xy 169.401255 -304.673042) (xy 169.443876 -304.648435) (xy 169.489892 -304.630983)
			(xy 169.538111 -304.621139) (xy 169.587286 -304.619158) (xy 169.636141 -304.62509) (xy 169.683412 -304.638782)
			(xy 169.727874 -304.65988) (xy 169.768377 -304.687836) (xy 169.80387 -304.721928) (xy 169.833435 -304.761272)
			(xy 169.856306 -304.804849) (xy 169.87189 -304.85153) (xy 169.879785 -304.900107) (xy 169.88028 -304.924714)
			(xy 170.219128 -304.924714) (xy 170.223088 -304.87566) (xy 170.234865 -304.827876) (xy 170.254156 -304.7826)
			(xy 170.280459 -304.741004) (xy 170.313094 -304.704167) (xy 170.351215 -304.673042) (xy 170.393836 -304.648435)
			(xy 170.439852 -304.630983) (xy 170.488071 -304.621139) (xy 170.537246 -304.619158) (xy 170.586101 -304.62509)
			(xy 170.633372 -304.638782) (xy 170.677834 -304.65988) (xy 170.718337 -304.687836) (xy 170.75383 -304.721928)
			(xy 170.783395 -304.761272) (xy 170.806266 -304.804849) (xy 170.82185 -304.85153) (xy 170.829745 -304.900107)
			(xy 170.83024 -304.924714) (xy 171.169088 -304.924714) (xy 171.173048 -304.87566) (xy 171.184825 -304.827876)
			(xy 171.204116 -304.7826) (xy 171.230419 -304.741004) (xy 171.263054 -304.704167) (xy 171.301175 -304.673042)
			(xy 171.343796 -304.648435) (xy 171.389812 -304.630983) (xy 171.438031 -304.621139) (xy 171.487206 -304.619158)
			(xy 171.536061 -304.62509) (xy 171.583332 -304.638782) (xy 171.627794 -304.65988) (xy 171.668297 -304.687836)
			(xy 171.70379 -304.721928) (xy 171.733355 -304.761272) (xy 171.756226 -304.804849) (xy 171.77181 -304.85153)
			(xy 171.779705 -304.900107) (xy 171.7802 -304.924714) (xy 172.119048 -304.924714) (xy 172.123008 -304.87566)
			(xy 172.134785 -304.827876) (xy 172.154076 -304.7826) (xy 172.180379 -304.741004) (xy 172.213014 -304.704167)
			(xy 172.251135 -304.673042) (xy 172.293756 -304.648435) (xy 172.339772 -304.630983) (xy 172.387991 -304.621139)
			(xy 172.437166 -304.619158) (xy 172.486021 -304.62509) (xy 172.533292 -304.638782) (xy 172.577754 -304.65988)
			(xy 172.618257 -304.687836) (xy 172.65375 -304.721928) (xy 172.683315 -304.761272) (xy 172.706186 -304.804849)
			(xy 172.72177 -304.85153) (xy 172.729665 -304.900107) (xy 172.73016 -304.924714) (xy 173.069262 -304.924714)
			(xy 173.073222 -304.87566) (xy 173.084999 -304.827876) (xy 173.10429 -304.7826) (xy 173.130593 -304.741004)
			(xy 173.163228 -304.704167) (xy 173.201349 -304.673042) (xy 173.24397 -304.648435) (xy 173.289986 -304.630983)
			(xy 173.338205 -304.621139) (xy 173.38738 -304.619158) (xy 173.436235 -304.62509) (xy 173.483506 -304.638782)
			(xy 173.527968 -304.65988) (xy 173.568471 -304.687836) (xy 173.603964 -304.721928) (xy 173.633529 -304.761272)
			(xy 173.6564 -304.804849) (xy 173.671984 -304.85153) (xy 173.679879 -304.900107) (xy 173.680374 -304.924714)
			(xy 174.019222 -304.924714) (xy 174.023182 -304.87566) (xy 174.034959 -304.827876) (xy 174.05425 -304.7826)
			(xy 174.080553 -304.741004) (xy 174.113188 -304.704167) (xy 174.151309 -304.673042) (xy 174.19393 -304.648435)
			(xy 174.239946 -304.630983) (xy 174.288165 -304.621139) (xy 174.33734 -304.619158) (xy 174.386195 -304.62509)
			(xy 174.433466 -304.638782) (xy 174.477928 -304.65988) (xy 174.518431 -304.687836) (xy 174.553924 -304.721928)
			(xy 174.583489 -304.761272) (xy 174.60636 -304.804849) (xy 174.621944 -304.85153) (xy 174.629839 -304.900107)
			(xy 174.630334 -304.924714) (xy 175.919142 -304.924714) (xy 175.923102 -304.87566) (xy 175.934879 -304.827876)
			(xy 175.95417 -304.7826) (xy 175.980473 -304.741004) (xy 176.013108 -304.704167) (xy 176.051229 -304.673042)
			(xy 176.09385 -304.648435) (xy 176.139866 -304.630983) (xy 176.188085 -304.621139) (xy 176.23726 -304.619158)
			(xy 176.286115 -304.62509) (xy 176.333386 -304.638782) (xy 176.377848 -304.65988) (xy 176.418351 -304.687836)
			(xy 176.453844 -304.721928) (xy 176.483409 -304.761272) (xy 176.50628 -304.804849) (xy 176.521864 -304.85153)
			(xy 176.529759 -304.900107) (xy 176.530254 -304.924714) (xy 176.869102 -304.924714) (xy 176.873062 -304.87566)
			(xy 176.884839 -304.827876) (xy 176.90413 -304.7826) (xy 176.930433 -304.741004) (xy 176.963068 -304.704167)
			(xy 177.001189 -304.673042) (xy 177.04381 -304.648435) (xy 177.089826 -304.630983) (xy 177.138045 -304.621139)
			(xy 177.18722 -304.619158) (xy 177.236075 -304.62509) (xy 177.283346 -304.638782) (xy 177.327808 -304.65988)
			(xy 177.368311 -304.687836) (xy 177.403804 -304.721928) (xy 177.433369 -304.761272) (xy 177.45624 -304.804849)
			(xy 177.471824 -304.85153) (xy 177.479719 -304.900107) (xy 177.480214 -304.924714) (xy 177.819062 -304.924714)
			(xy 177.823022 -304.87566) (xy 177.834799 -304.827876) (xy 177.85409 -304.7826) (xy 177.880393 -304.741004)
			(xy 177.913028 -304.704167) (xy 177.951149 -304.673042) (xy 177.99377 -304.648435) (xy 178.039786 -304.630983)
			(xy 178.088005 -304.621139) (xy 178.13718 -304.619158) (xy 178.186035 -304.62509) (xy 178.233306 -304.638782)
			(xy 178.277768 -304.65988) (xy 178.318271 -304.687836) (xy 178.353764 -304.721928) (xy 178.383329 -304.761272)
			(xy 178.4062 -304.804849) (xy 178.421784 -304.85153) (xy 178.429679 -304.900107) (xy 178.430174 -304.924714)
			(xy 178.769276 -304.924714) (xy 178.773236 -304.87566) (xy 178.785013 -304.827876) (xy 178.804304 -304.7826)
			(xy 178.830607 -304.741004) (xy 178.863242 -304.704167) (xy 178.901363 -304.673042) (xy 178.943984 -304.648435)
			(xy 178.99 -304.630983) (xy 179.038219 -304.621139) (xy 179.087394 -304.619158) (xy 179.136249 -304.62509)
			(xy 179.18352 -304.638782) (xy 179.227982 -304.65988) (xy 179.268485 -304.687836) (xy 179.303978 -304.721928)
			(xy 179.333543 -304.761272) (xy 179.356414 -304.804849) (xy 179.371998 -304.85153) (xy 179.379893 -304.900107)
			(xy 179.380388 -304.924714) (xy 179.719236 -304.924714) (xy 179.723196 -304.87566) (xy 179.734973 -304.827876)
			(xy 179.754264 -304.7826) (xy 179.780567 -304.741004) (xy 179.813202 -304.704167) (xy 179.851323 -304.673042)
			(xy 179.893944 -304.648435) (xy 179.93996 -304.630983) (xy 179.988179 -304.621139) (xy 180.037354 -304.619158)
			(xy 180.086209 -304.62509) (xy 180.13348 -304.638782) (xy 180.177942 -304.65988) (xy 180.218445 -304.687836)
			(xy 180.253938 -304.721928) (xy 180.283503 -304.761272) (xy 180.306374 -304.804849) (xy 180.321958 -304.85153)
			(xy 180.329853 -304.900107) (xy 180.330348 -304.924714) (xy 180.669196 -304.924714) (xy 180.673156 -304.87566)
			(xy 180.684933 -304.827876) (xy 180.704224 -304.7826) (xy 180.730527 -304.741004) (xy 180.763162 -304.704167)
			(xy 180.801283 -304.673042) (xy 180.843904 -304.648435) (xy 180.88992 -304.630983) (xy 180.938139 -304.621139)
			(xy 180.987314 -304.619158) (xy 181.036169 -304.62509) (xy 181.08344 -304.638782) (xy 181.127902 -304.65988)
			(xy 181.168405 -304.687836) (xy 181.203898 -304.721928) (xy 181.233463 -304.761272) (xy 181.256334 -304.804849)
			(xy 181.271918 -304.85153) (xy 181.279813 -304.900107) (xy 181.280308 -304.924714) (xy 181.619156 -304.924714)
			(xy 181.623116 -304.87566) (xy 181.634893 -304.827876) (xy 181.654184 -304.7826) (xy 181.680487 -304.741004)
			(xy 181.713122 -304.704167) (xy 181.751243 -304.673042) (xy 181.793864 -304.648435) (xy 181.83988 -304.630983)
			(xy 181.888099 -304.621139) (xy 181.937274 -304.619158) (xy 181.986129 -304.62509) (xy 182.0334 -304.638782)
			(xy 182.077862 -304.65988) (xy 182.118365 -304.687836) (xy 182.153858 -304.721928) (xy 182.183423 -304.761272)
			(xy 182.206294 -304.804849) (xy 182.221878 -304.85153) (xy 182.229773 -304.900107) (xy 182.230268 -304.924714)
			(xy 182.569116 -304.924714) (xy 182.573076 -304.87566) (xy 182.584853 -304.827876) (xy 182.604144 -304.7826)
			(xy 182.630447 -304.741004) (xy 182.663082 -304.704167) (xy 182.701203 -304.673042) (xy 182.743824 -304.648435)
			(xy 182.78984 -304.630983) (xy 182.838059 -304.621139) (xy 182.887234 -304.619158) (xy 182.936089 -304.62509)
			(xy 182.98336 -304.638782) (xy 183.027822 -304.65988) (xy 183.068325 -304.687836) (xy 183.103818 -304.721928)
			(xy 183.133383 -304.761272) (xy 183.156254 -304.804849) (xy 183.171838 -304.85153) (xy 183.179733 -304.900107)
			(xy 183.180228 -304.924714) (xy 183.519076 -304.924714) (xy 183.523036 -304.87566) (xy 183.534813 -304.827876)
			(xy 183.554104 -304.7826) (xy 183.580407 -304.741004) (xy 183.613042 -304.704167) (xy 183.651163 -304.673042)
			(xy 183.693784 -304.648435) (xy 183.7398 -304.630983) (xy 183.788019 -304.621139) (xy 183.837194 -304.619158)
			(xy 183.886049 -304.62509) (xy 183.93332 -304.638782) (xy 183.977782 -304.65988) (xy 184.018285 -304.687836)
			(xy 184.053778 -304.721928) (xy 184.083343 -304.761272) (xy 184.106214 -304.804849) (xy 184.121798 -304.85153)
			(xy 184.129693 -304.900107) (xy 184.130188 -304.924714) (xy 184.469036 -304.924714) (xy 184.472996 -304.87566)
			(xy 184.484773 -304.827876) (xy 184.504064 -304.7826) (xy 184.530367 -304.741004) (xy 184.563002 -304.704167)
			(xy 184.601123 -304.673042) (xy 184.643744 -304.648435) (xy 184.68976 -304.630983) (xy 184.737979 -304.621139)
			(xy 184.787154 -304.619158) (xy 184.836009 -304.62509) (xy 184.88328 -304.638782) (xy 184.927742 -304.65988)
			(xy 184.968245 -304.687836) (xy 185.003738 -304.721928) (xy 185.033303 -304.761272) (xy 185.056174 -304.804849)
			(xy 185.071758 -304.85153) (xy 185.079653 -304.900107) (xy 185.080148 -304.924714) (xy 185.079653 -304.949321)
			(xy 185.071758 -304.997898) (xy 185.056174 -305.044579) (xy 185.033303 -305.088156) (xy 185.003738 -305.1275)
			(xy 184.968245 -305.161592) (xy 184.927742 -305.189548) (xy 184.88328 -305.210646) (xy 184.836009 -305.224338)
			(xy 184.787154 -305.23027) (xy 184.737979 -305.228289) (xy 184.68976 -305.218445) (xy 184.643744 -305.200993)
			(xy 184.601123 -305.176386) (xy 184.563002 -305.145261) (xy 184.530367 -305.108424) (xy 184.504064 -305.066828)
			(xy 184.484773 -305.021552) (xy 184.472996 -304.973768) (xy 184.469036 -304.924714) (xy 184.130188 -304.924714)
			(xy 184.129693 -304.949321) (xy 184.121798 -304.997898) (xy 184.106214 -305.044579) (xy 184.083343 -305.088156)
			(xy 184.053778 -305.1275) (xy 184.018285 -305.161592) (xy 183.977782 -305.189548) (xy 183.93332 -305.210646)
			(xy 183.886049 -305.224338) (xy 183.837194 -305.23027) (xy 183.788019 -305.228289) (xy 183.7398 -305.218445)
			(xy 183.693784 -305.200993) (xy 183.651163 -305.176386) (xy 183.613042 -305.145261) (xy 183.580407 -305.108424)
			(xy 183.554104 -305.066828) (xy 183.534813 -305.021552) (xy 183.523036 -304.973768) (xy 183.519076 -304.924714)
			(xy 183.180228 -304.924714) (xy 183.179733 -304.949321) (xy 183.171838 -304.997898) (xy 183.156254 -305.044579)
			(xy 183.133383 -305.088156) (xy 183.103818 -305.1275) (xy 183.068325 -305.161592) (xy 183.027822 -305.189548)
			(xy 182.98336 -305.210646) (xy 182.936089 -305.224338) (xy 182.887234 -305.23027) (xy 182.838059 -305.228289)
			(xy 182.78984 -305.218445) (xy 182.743824 -305.200993) (xy 182.701203 -305.176386) (xy 182.663082 -305.145261)
			(xy 182.630447 -305.108424) (xy 182.604144 -305.066828) (xy 182.584853 -305.021552) (xy 182.573076 -304.973768)
			(xy 182.569116 -304.924714) (xy 182.230268 -304.924714) (xy 182.229773 -304.949321) (xy 182.221878 -304.997898)
			(xy 182.206294 -305.044579) (xy 182.183423 -305.088156) (xy 182.153858 -305.1275) (xy 182.118365 -305.161592)
			(xy 182.077862 -305.189548) (xy 182.0334 -305.210646) (xy 181.986129 -305.224338) (xy 181.937274 -305.23027)
			(xy 181.888099 -305.228289) (xy 181.83988 -305.218445) (xy 181.793864 -305.200993) (xy 181.751243 -305.176386)
			(xy 181.713122 -305.145261) (xy 181.680487 -305.108424) (xy 181.654184 -305.066828) (xy 181.634893 -305.021552)
			(xy 181.623116 -304.973768) (xy 181.619156 -304.924714) (xy 181.280308 -304.924714) (xy 181.279813 -304.949321)
			(xy 181.271918 -304.997898) (xy 181.256334 -305.044579) (xy 181.233463 -305.088156) (xy 181.203898 -305.1275)
			(xy 181.168405 -305.161592) (xy 181.127902 -305.189548) (xy 181.08344 -305.210646) (xy 181.036169 -305.224338)
			(xy 180.987314 -305.23027) (xy 180.938139 -305.228289) (xy 180.88992 -305.218445) (xy 180.843904 -305.200993)
			(xy 180.801283 -305.176386) (xy 180.763162 -305.145261) (xy 180.730527 -305.108424) (xy 180.704224 -305.066828)
			(xy 180.684933 -305.021552) (xy 180.673156 -304.973768) (xy 180.669196 -304.924714) (xy 180.330348 -304.924714)
			(xy 180.329853 -304.949321) (xy 180.321958 -304.997898) (xy 180.306374 -305.044579) (xy 180.283503 -305.088156)
			(xy 180.253938 -305.1275) (xy 180.218445 -305.161592) (xy 180.177942 -305.189548) (xy 180.13348 -305.210646)
			(xy 180.086209 -305.224338) (xy 180.037354 -305.23027) (xy 179.988179 -305.228289) (xy 179.93996 -305.218445)
			(xy 179.893944 -305.200993) (xy 179.851323 -305.176386) (xy 179.813202 -305.145261) (xy 179.780567 -305.108424)
			(xy 179.754264 -305.066828) (xy 179.734973 -305.021552) (xy 179.723196 -304.973768) (xy 179.719236 -304.924714)
			(xy 179.380388 -304.924714) (xy 179.379893 -304.949321) (xy 179.371998 -304.997898) (xy 179.356414 -305.044579)
			(xy 179.333543 -305.088156) (xy 179.303978 -305.1275) (xy 179.268485 -305.161592) (xy 179.227982 -305.189548)
			(xy 179.18352 -305.210646) (xy 179.136249 -305.224338) (xy 179.087394 -305.23027) (xy 179.038219 -305.228289)
			(xy 178.99 -305.218445) (xy 178.943984 -305.200993) (xy 178.901363 -305.176386) (xy 178.863242 -305.145261)
			(xy 178.830607 -305.108424) (xy 178.804304 -305.066828) (xy 178.785013 -305.021552) (xy 178.773236 -304.973768)
			(xy 178.769276 -304.924714) (xy 178.430174 -304.924714) (xy 178.429679 -304.949321) (xy 178.421784 -304.997898)
			(xy 178.4062 -305.044579) (xy 178.383329 -305.088156) (xy 178.353764 -305.1275) (xy 178.318271 -305.161592)
			(xy 178.277768 -305.189548) (xy 178.233306 -305.210646) (xy 178.186035 -305.224338) (xy 178.13718 -305.23027)
			(xy 178.088005 -305.228289) (xy 178.039786 -305.218445) (xy 177.99377 -305.200993) (xy 177.951149 -305.176386)
			(xy 177.913028 -305.145261) (xy 177.880393 -305.108424) (xy 177.85409 -305.066828) (xy 177.834799 -305.021552)
			(xy 177.823022 -304.973768) (xy 177.819062 -304.924714) (xy 177.480214 -304.924714) (xy 177.479719 -304.949321)
			(xy 177.471824 -304.997898) (xy 177.45624 -305.044579) (xy 177.433369 -305.088156) (xy 177.403804 -305.1275)
			(xy 177.368311 -305.161592) (xy 177.327808 -305.189548) (xy 177.283346 -305.210646) (xy 177.236075 -305.224338)
			(xy 177.18722 -305.23027) (xy 177.138045 -305.228289) (xy 177.089826 -305.218445) (xy 177.04381 -305.200993)
			(xy 177.001189 -305.176386) (xy 176.963068 -305.145261) (xy 176.930433 -305.108424) (xy 176.90413 -305.066828)
			(xy 176.884839 -305.021552) (xy 176.873062 -304.973768) (xy 176.869102 -304.924714) (xy 176.530254 -304.924714)
			(xy 176.529759 -304.949321) (xy 176.521864 -304.997898) (xy 176.50628 -305.044579) (xy 176.483409 -305.088156)
			(xy 176.453844 -305.1275) (xy 176.418351 -305.161592) (xy 176.377848 -305.189548) (xy 176.333386 -305.210646)
			(xy 176.286115 -305.224338) (xy 176.23726 -305.23027) (xy 176.188085 -305.228289) (xy 176.139866 -305.218445)
			(xy 176.09385 -305.200993) (xy 176.051229 -305.176386) (xy 176.013108 -305.145261) (xy 175.980473 -305.108424)
			(xy 175.95417 -305.066828) (xy 175.934879 -305.021552) (xy 175.923102 -304.973768) (xy 175.919142 -304.924714)
			(xy 174.630334 -304.924714) (xy 174.629839 -304.949321) (xy 174.621944 -304.997898) (xy 174.60636 -305.044579)
			(xy 174.583489 -305.088156) (xy 174.553924 -305.1275) (xy 174.518431 -305.161592) (xy 174.477928 -305.189548)
			(xy 174.433466 -305.210646) (xy 174.386195 -305.224338) (xy 174.33734 -305.23027) (xy 174.288165 -305.228289)
			(xy 174.239946 -305.218445) (xy 174.19393 -305.200993) (xy 174.151309 -305.176386) (xy 174.113188 -305.145261)
			(xy 174.080553 -305.108424) (xy 174.05425 -305.066828) (xy 174.034959 -305.021552) (xy 174.023182 -304.973768)
			(xy 174.019222 -304.924714) (xy 173.680374 -304.924714) (xy 173.679879 -304.949321) (xy 173.671984 -304.997898)
			(xy 173.6564 -305.044579) (xy 173.633529 -305.088156) (xy 173.603964 -305.1275) (xy 173.568471 -305.161592)
			(xy 173.527968 -305.189548) (xy 173.483506 -305.210646) (xy 173.436235 -305.224338) (xy 173.38738 -305.23027)
			(xy 173.338205 -305.228289) (xy 173.289986 -305.218445) (xy 173.24397 -305.200993) (xy 173.201349 -305.176386)
			(xy 173.163228 -305.145261) (xy 173.130593 -305.108424) (xy 173.10429 -305.066828) (xy 173.084999 -305.021552)
			(xy 173.073222 -304.973768) (xy 173.069262 -304.924714) (xy 172.73016 -304.924714) (xy 172.729665 -304.949321)
			(xy 172.72177 -304.997898) (xy 172.706186 -305.044579) (xy 172.683315 -305.088156) (xy 172.65375 -305.1275)
			(xy 172.618257 -305.161592) (xy 172.577754 -305.189548) (xy 172.533292 -305.210646) (xy 172.486021 -305.224338)
			(xy 172.437166 -305.23027) (xy 172.387991 -305.228289) (xy 172.339772 -305.218445) (xy 172.293756 -305.200993)
			(xy 172.251135 -305.176386) (xy 172.213014 -305.145261) (xy 172.180379 -305.108424) (xy 172.154076 -305.066828)
			(xy 172.134785 -305.021552) (xy 172.123008 -304.973768) (xy 172.119048 -304.924714) (xy 171.7802 -304.924714)
			(xy 171.779705 -304.949321) (xy 171.77181 -304.997898) (xy 171.756226 -305.044579) (xy 171.733355 -305.088156)
			(xy 171.70379 -305.1275) (xy 171.668297 -305.161592) (xy 171.627794 -305.189548) (xy 171.583332 -305.210646)
			(xy 171.536061 -305.224338) (xy 171.487206 -305.23027) (xy 171.438031 -305.228289) (xy 171.389812 -305.218445)
			(xy 171.343796 -305.200993) (xy 171.301175 -305.176386) (xy 171.263054 -305.145261) (xy 171.230419 -305.108424)
			(xy 171.204116 -305.066828) (xy 171.184825 -305.021552) (xy 171.173048 -304.973768) (xy 171.169088 -304.924714)
			(xy 170.83024 -304.924714) (xy 170.829745 -304.949321) (xy 170.82185 -304.997898) (xy 170.806266 -305.044579)
			(xy 170.783395 -305.088156) (xy 170.75383 -305.1275) (xy 170.718337 -305.161592) (xy 170.677834 -305.189548)
			(xy 170.633372 -305.210646) (xy 170.586101 -305.224338) (xy 170.537246 -305.23027) (xy 170.488071 -305.228289)
			(xy 170.439852 -305.218445) (xy 170.393836 -305.200993) (xy 170.351215 -305.176386) (xy 170.313094 -305.145261)
			(xy 170.280459 -305.108424) (xy 170.254156 -305.066828) (xy 170.234865 -305.021552) (xy 170.223088 -304.973768)
			(xy 170.219128 -304.924714) (xy 169.88028 -304.924714) (xy 169.879785 -304.949321) (xy 169.87189 -304.997898)
			(xy 169.856306 -305.044579) (xy 169.833435 -305.088156) (xy 169.80387 -305.1275) (xy 169.768377 -305.161592)
			(xy 169.727874 -305.189548) (xy 169.683412 -305.210646) (xy 169.636141 -305.224338) (xy 169.587286 -305.23027)
			(xy 169.538111 -305.228289) (xy 169.489892 -305.218445) (xy 169.443876 -305.200993) (xy 169.401255 -305.176386)
			(xy 169.363134 -305.145261) (xy 169.330499 -305.108424) (xy 169.304196 -305.066828) (xy 169.284905 -305.021552)
			(xy 169.273128 -304.973768) (xy 169.269168 -304.924714) (xy 168.93032 -304.924714) (xy 168.929825 -304.949321)
			(xy 168.92193 -304.997898) (xy 168.906346 -305.044579) (xy 168.883475 -305.088156) (xy 168.85391 -305.1275)
			(xy 168.818417 -305.161592) (xy 168.777914 -305.189548) (xy 168.733452 -305.210646) (xy 168.686181 -305.224338)
			(xy 168.637326 -305.23027) (xy 168.588151 -305.228289) (xy 168.539932 -305.218445) (xy 168.493916 -305.200993)
			(xy 168.451295 -305.176386) (xy 168.413174 -305.145261) (xy 168.380539 -305.108424) (xy 168.354236 -305.066828)
			(xy 168.334945 -305.021552) (xy 168.323168 -304.973768) (xy 168.319208 -304.924714) (xy 167.98036 -304.924714)
			(xy 167.979865 -304.949321) (xy 167.97197 -304.997898) (xy 167.956386 -305.044579) (xy 167.933515 -305.088156)
			(xy 167.90395 -305.1275) (xy 167.868457 -305.161592) (xy 167.827954 -305.189548) (xy 167.783492 -305.210646)
			(xy 167.736221 -305.224338) (xy 167.687366 -305.23027) (xy 167.638191 -305.228289) (xy 167.589972 -305.218445)
			(xy 167.543956 -305.200993) (xy 167.501335 -305.176386) (xy 167.463214 -305.145261) (xy 167.430579 -305.108424)
			(xy 167.404276 -305.066828) (xy 167.384985 -305.021552) (xy 167.373208 -304.973768) (xy 167.369248 -304.924714)
			(xy 167.0304 -304.924714) (xy 167.029905 -304.949321) (xy 167.02201 -304.997898) (xy 167.006426 -305.044579)
			(xy 166.983555 -305.088156) (xy 166.95399 -305.1275) (xy 166.918497 -305.161592) (xy 166.877994 -305.189548)
			(xy 166.833532 -305.210646) (xy 166.786261 -305.224338) (xy 166.737406 -305.23027) (xy 166.688231 -305.228289)
			(xy 166.640012 -305.218445) (xy 166.593996 -305.200993) (xy 166.551375 -305.176386) (xy 166.513254 -305.145261)
			(xy 166.480619 -305.108424) (xy 166.454316 -305.066828) (xy 166.435025 -305.021552) (xy 166.423248 -304.973768)
			(xy 166.419288 -304.924714) (xy 166.080186 -304.924714) (xy 166.079691 -304.949321) (xy 166.071796 -304.997898)
			(xy 166.056212 -305.044579) (xy 166.033341 -305.088156) (xy 166.003776 -305.1275) (xy 165.968283 -305.161592)
			(xy 165.92778 -305.189548) (xy 165.883318 -305.210646) (xy 165.836047 -305.224338) (xy 165.787192 -305.23027)
			(xy 165.738017 -305.228289) (xy 165.689798 -305.218445) (xy 165.643782 -305.200993) (xy 165.601161 -305.176386)
			(xy 165.56304 -305.145261) (xy 165.530405 -305.108424) (xy 165.504102 -305.066828) (xy 165.484811 -305.021552)
			(xy 165.473034 -304.973768) (xy 165.469074 -304.924714) (xy 165.130226 -304.924714) (xy 165.129731 -304.949321)
			(xy 165.121836 -304.997898) (xy 165.106252 -305.044579) (xy 165.083381 -305.088156) (xy 165.053816 -305.1275)
			(xy 165.018323 -305.161592) (xy 164.97782 -305.189548) (xy 164.933358 -305.210646) (xy 164.886087 -305.224338)
			(xy 164.837232 -305.23027) (xy 164.788057 -305.228289) (xy 164.739838 -305.218445) (xy 164.693822 -305.200993)
			(xy 164.651201 -305.176386) (xy 164.61308 -305.145261) (xy 164.580445 -305.108424) (xy 164.554142 -305.066828)
			(xy 164.534851 -305.021552) (xy 164.523074 -304.973768) (xy 164.519114 -304.924714) (xy 164.180266 -304.924714)
			(xy 164.179771 -304.949321) (xy 164.171876 -304.997898) (xy 164.156292 -305.044579) (xy 164.133421 -305.088156)
			(xy 164.103856 -305.1275) (xy 164.068363 -305.161592) (xy 164.02786 -305.189548) (xy 163.983398 -305.210646)
			(xy 163.936127 -305.224338) (xy 163.887272 -305.23027) (xy 163.838097 -305.228289) (xy 163.789878 -305.218445)
			(xy 163.743862 -305.200993) (xy 163.701241 -305.176386) (xy 163.66312 -305.145261) (xy 163.630485 -305.108424)
			(xy 163.604182 -305.066828) (xy 163.584891 -305.021552) (xy 163.573114 -304.973768) (xy 163.569154 -304.924714)
			(xy 163.230306 -304.924714) (xy 163.229811 -304.949321) (xy 163.221916 -304.997898) (xy 163.206332 -305.044579)
			(xy 163.183461 -305.088156) (xy 163.153896 -305.1275) (xy 163.118403 -305.161592) (xy 163.0779 -305.189548)
			(xy 163.033438 -305.210646) (xy 162.986167 -305.224338) (xy 162.937312 -305.23027) (xy 162.888137 -305.228289)
			(xy 162.839918 -305.218445) (xy 162.793902 -305.200993) (xy 162.751281 -305.176386) (xy 162.71316 -305.145261)
			(xy 162.680525 -305.108424) (xy 162.654222 -305.066828) (xy 162.634931 -305.021552) (xy 162.623154 -304.973768)
			(xy 162.619194 -304.924714) (xy 144.767629 -304.924714) (xy 144.76497 -304.933769) (xy 144.742334 -304.983339)
			(xy 144.712874 -305.029183) (xy 144.67719 -305.070368) (xy 144.636008 -305.106055) (xy 144.590166 -305.135519)
			(xy 144.540599 -305.158159) (xy 144.488313 -305.173515) (xy 144.434375 -305.181274) (xy 144.407128 -305.181762)
			(xy 144.379188 -305.180746) (xy 144.368012 -305.179984) (xy 144.34693 -305.187858) (xy 144.276826 -305.260502)
			(xy 144.26946 -305.281838) (xy 144.27073 -305.293014) (xy 144.271792 -305.303268) (xy 144.272935 -305.323853)
			(xy 144.273016 -305.334162) (xy 144.272586 -305.361418) (xy 144.26705 -305.399948) (xy 152.644106 -305.399948)
			(xy 152.648066 -305.350894) (xy 152.659843 -305.30311) (xy 152.679134 -305.257834) (xy 152.705437 -305.216238)
			(xy 152.738072 -305.179401) (xy 152.776193 -305.148276) (xy 152.818814 -305.123669) (xy 152.86483 -305.106217)
			(xy 152.913049 -305.096373) (xy 152.962224 -305.094392) (xy 153.011079 -305.100324) (xy 153.05835 -305.114016)
			(xy 153.102812 -305.135114) (xy 153.143315 -305.16307) (xy 153.178808 -305.197162) (xy 153.208373 -305.236506)
			(xy 153.231244 -305.280083) (xy 153.246828 -305.326764) (xy 153.254723 -305.375341) (xy 153.255218 -305.399948)
			(xy 153.594066 -305.399948) (xy 153.598026 -305.350894) (xy 153.609803 -305.30311) (xy 153.629094 -305.257834)
			(xy 153.655397 -305.216238) (xy 153.688032 -305.179401) (xy 153.726153 -305.148276) (xy 153.768774 -305.123669)
			(xy 153.81479 -305.106217) (xy 153.863009 -305.096373) (xy 153.912184 -305.094392) (xy 153.961039 -305.100324)
			(xy 154.00831 -305.114016) (xy 154.052772 -305.135114) (xy 154.093275 -305.16307) (xy 154.128768 -305.197162)
			(xy 154.158333 -305.236506) (xy 154.181204 -305.280083) (xy 154.196788 -305.326764) (xy 154.204683 -305.375341)
			(xy 154.205178 -305.399948) (xy 154.204683 -305.424555) (xy 154.204504 -305.425656) (xy 154.523436 -305.425656)
			(xy 154.523436 -305.37424) (xy 154.531479 -305.323458) (xy 154.547367 -305.274559) (xy 154.57071 -305.228747)
			(xy 154.600931 -305.187151) (xy 154.637287 -305.150795) (xy 154.678883 -305.120574) (xy 154.724695 -305.097231)
			(xy 154.773594 -305.081343) (xy 154.824376 -305.0733) (xy 154.875792 -305.0733) (xy 154.926574 -305.081343)
			(xy 154.975473 -305.097231) (xy 155.021285 -305.120574) (xy 155.062881 -305.150795) (xy 155.099237 -305.187151)
			(xy 155.129458 -305.228747) (xy 155.152801 -305.274559) (xy 155.168689 -305.323458) (xy 155.176732 -305.37424)
			(xy 155.177236 -305.399948) (xy 155.176732 -305.425656) (xy 155.473396 -305.425656) (xy 155.473396 -305.37424)
			(xy 155.481439 -305.323458) (xy 155.497327 -305.274559) (xy 155.52067 -305.228747) (xy 155.550891 -305.187151)
			(xy 155.587247 -305.150795) (xy 155.628843 -305.120574) (xy 155.674655 -305.097231) (xy 155.723554 -305.081343)
			(xy 155.774336 -305.0733) (xy 155.825752 -305.0733) (xy 155.876534 -305.081343) (xy 155.925433 -305.097231)
			(xy 155.971245 -305.120574) (xy 156.012841 -305.150795) (xy 156.049197 -305.187151) (xy 156.079418 -305.228747)
			(xy 156.102761 -305.274559) (xy 156.118649 -305.323458) (xy 156.126692 -305.37424) (xy 156.127196 -305.399948)
			(xy 156.4442 -305.399948) (xy 156.44816 -305.350894) (xy 156.459937 -305.30311) (xy 156.479228 -305.257834)
			(xy 156.505531 -305.216238) (xy 156.538166 -305.179401) (xy 156.576287 -305.148276) (xy 156.618908 -305.123669)
			(xy 156.664924 -305.106217) (xy 156.713143 -305.096373) (xy 156.762318 -305.094392) (xy 156.811173 -305.100324)
			(xy 156.858444 -305.114016) (xy 156.902906 -305.135114) (xy 156.943409 -305.16307) (xy 156.978902 -305.197162)
			(xy 157.008467 -305.236506) (xy 157.031338 -305.280083) (xy 157.046922 -305.326764) (xy 157.054817 -305.375341)
			(xy 157.055312 -305.399948) (xy 157.054817 -305.424555) (xy 157.054638 -305.425656) (xy 157.373316 -305.425656)
			(xy 157.373316 -305.37424) (xy 157.381359 -305.323458) (xy 157.397247 -305.274559) (xy 157.42059 -305.228747)
			(xy 157.450811 -305.187151) (xy 157.487167 -305.150795) (xy 157.528763 -305.120574) (xy 157.574575 -305.097231)
			(xy 157.623474 -305.081343) (xy 157.674256 -305.0733) (xy 157.725672 -305.0733) (xy 157.776454 -305.081343)
			(xy 157.825353 -305.097231) (xy 157.871165 -305.120574) (xy 157.912761 -305.150795) (xy 157.949117 -305.187151)
			(xy 157.979338 -305.228747) (xy 158.002681 -305.274559) (xy 158.018569 -305.323458) (xy 158.026612 -305.37424)
			(xy 158.027116 -305.399948) (xy 158.026612 -305.425656) (xy 158.323276 -305.425656) (xy 158.323276 -305.37424)
			(xy 158.331319 -305.323458) (xy 158.347207 -305.274559) (xy 158.37055 -305.228747) (xy 158.400771 -305.187151)
			(xy 158.437127 -305.150795) (xy 158.478723 -305.120574) (xy 158.524535 -305.097231) (xy 158.573434 -305.081343)
			(xy 158.624216 -305.0733) (xy 158.675632 -305.0733) (xy 158.726414 -305.081343) (xy 158.775313 -305.097231)
			(xy 158.821125 -305.120574) (xy 158.862721 -305.150795) (xy 158.899077 -305.187151) (xy 158.929298 -305.228747)
			(xy 158.952641 -305.274559) (xy 158.968529 -305.323458) (xy 158.976572 -305.37424) (xy 158.977076 -305.399948)
			(xy 159.29408 -305.399948) (xy 159.29804 -305.350894) (xy 159.309817 -305.30311) (xy 159.329108 -305.257834)
			(xy 159.355411 -305.216238) (xy 159.388046 -305.179401) (xy 159.426167 -305.148276) (xy 159.468788 -305.123669)
			(xy 159.514804 -305.106217) (xy 159.563023 -305.096373) (xy 159.612198 -305.094392) (xy 159.661053 -305.100324)
			(xy 159.708324 -305.114016) (xy 159.752786 -305.135114) (xy 159.793289 -305.16307) (xy 159.828782 -305.197162)
			(xy 159.858347 -305.236506) (xy 159.881218 -305.280083) (xy 159.896802 -305.326764) (xy 159.904697 -305.375341)
			(xy 159.905192 -305.399948) (xy 160.24404 -305.399948) (xy 160.248 -305.350894) (xy 160.259777 -305.30311)
			(xy 160.279068 -305.257834) (xy 160.305371 -305.216238) (xy 160.338006 -305.179401) (xy 160.376127 -305.148276)
			(xy 160.418748 -305.123669) (xy 160.464764 -305.106217) (xy 160.512983 -305.096373) (xy 160.562158 -305.094392)
			(xy 160.611013 -305.100324) (xy 160.658284 -305.114016) (xy 160.702746 -305.135114) (xy 160.743249 -305.16307)
			(xy 160.778742 -305.197162) (xy 160.808307 -305.236506) (xy 160.831178 -305.280083) (xy 160.846762 -305.326764)
			(xy 160.854657 -305.375341) (xy 160.855152 -305.399948) (xy 161.194254 -305.399948) (xy 161.198214 -305.350894)
			(xy 161.209991 -305.30311) (xy 161.229282 -305.257834) (xy 161.255585 -305.216238) (xy 161.28822 -305.179401)
			(xy 161.326341 -305.148276) (xy 161.368962 -305.123669) (xy 161.414978 -305.106217) (xy 161.463197 -305.096373)
			(xy 161.512372 -305.094392) (xy 161.561227 -305.100324) (xy 161.608498 -305.114016) (xy 161.65296 -305.135114)
			(xy 161.693463 -305.16307) (xy 161.728956 -305.197162) (xy 161.758521 -305.236506) (xy 161.781392 -305.280083)
			(xy 161.796976 -305.326764) (xy 161.804871 -305.375341) (xy 161.805366 -305.399948) (xy 161.804871 -305.424555)
			(xy 161.796976 -305.473132) (xy 161.781392 -305.519813) (xy 161.758521 -305.56339) (xy 161.728956 -305.602734)
			(xy 161.693463 -305.636826) (xy 161.65296 -305.664782) (xy 161.608498 -305.68588) (xy 161.561227 -305.699572)
			(xy 161.512372 -305.705504) (xy 161.463197 -305.703523) (xy 161.414978 -305.693679) (xy 161.368962 -305.676227)
			(xy 161.326341 -305.65162) (xy 161.28822 -305.620495) (xy 161.255585 -305.583658) (xy 161.229282 -305.542062)
			(xy 161.209991 -305.496786) (xy 161.198214 -305.449002) (xy 161.194254 -305.399948) (xy 160.855152 -305.399948)
			(xy 160.854657 -305.424555) (xy 160.846762 -305.473132) (xy 160.831178 -305.519813) (xy 160.808307 -305.56339)
			(xy 160.778742 -305.602734) (xy 160.743249 -305.636826) (xy 160.702746 -305.664782) (xy 160.658284 -305.68588)
			(xy 160.611013 -305.699572) (xy 160.562158 -305.705504) (xy 160.512983 -305.703523) (xy 160.464764 -305.693679)
			(xy 160.418748 -305.676227) (xy 160.376127 -305.65162) (xy 160.338006 -305.620495) (xy 160.305371 -305.583658)
			(xy 160.279068 -305.542062) (xy 160.259777 -305.496786) (xy 160.248 -305.449002) (xy 160.24404 -305.399948)
			(xy 159.905192 -305.399948) (xy 159.904697 -305.424555) (xy 159.896802 -305.473132) (xy 159.881218 -305.519813)
			(xy 159.858347 -305.56339) (xy 159.828782 -305.602734) (xy 159.793289 -305.636826) (xy 159.752786 -305.664782)
			(xy 159.708324 -305.68588) (xy 159.661053 -305.699572) (xy 159.612198 -305.705504) (xy 159.563023 -305.703523)
			(xy 159.514804 -305.693679) (xy 159.468788 -305.676227) (xy 159.426167 -305.65162) (xy 159.388046 -305.620495)
			(xy 159.355411 -305.583658) (xy 159.329108 -305.542062) (xy 159.309817 -305.496786) (xy 159.29804 -305.449002)
			(xy 159.29408 -305.399948) (xy 158.977076 -305.399948) (xy 158.976572 -305.425656) (xy 158.968529 -305.476438)
			(xy 158.952641 -305.525337) (xy 158.929298 -305.571149) (xy 158.899077 -305.612745) (xy 158.862721 -305.649101)
			(xy 158.821125 -305.679322) (xy 158.775313 -305.702665) (xy 158.726414 -305.718553) (xy 158.675632 -305.726596)
			(xy 158.624216 -305.726596) (xy 158.573434 -305.718553) (xy 158.524535 -305.702665) (xy 158.478723 -305.679322)
			(xy 158.437127 -305.649101) (xy 158.400771 -305.612745) (xy 158.37055 -305.571149) (xy 158.347207 -305.525337)
			(xy 158.331319 -305.476438) (xy 158.323276 -305.425656) (xy 158.026612 -305.425656) (xy 158.018569 -305.476438)
			(xy 158.002681 -305.525337) (xy 157.979338 -305.571149) (xy 157.949117 -305.612745) (xy 157.912761 -305.649101)
			(xy 157.871165 -305.679322) (xy 157.825353 -305.702665) (xy 157.776454 -305.718553) (xy 157.725672 -305.726596)
			(xy 157.674256 -305.726596) (xy 157.623474 -305.718553) (xy 157.574575 -305.702665) (xy 157.528763 -305.679322)
			(xy 157.487167 -305.649101) (xy 157.450811 -305.612745) (xy 157.42059 -305.571149) (xy 157.397247 -305.525337)
			(xy 157.381359 -305.476438) (xy 157.373316 -305.425656) (xy 157.054638 -305.425656) (xy 157.046922 -305.473132)
			(xy 157.031338 -305.519813) (xy 157.008467 -305.56339) (xy 156.978902 -305.602734) (xy 156.943409 -305.636826)
			(xy 156.902906 -305.664782) (xy 156.858444 -305.68588) (xy 156.811173 -305.699572) (xy 156.762318 -305.705504)
			(xy 156.713143 -305.703523) (xy 156.664924 -305.693679) (xy 156.618908 -305.676227) (xy 156.576287 -305.65162)
			(xy 156.538166 -305.620495) (xy 156.505531 -305.583658) (xy 156.479228 -305.542062) (xy 156.459937 -305.496786)
			(xy 156.44816 -305.449002) (xy 156.4442 -305.399948) (xy 156.127196 -305.399948) (xy 156.126692 -305.425656)
			(xy 156.118649 -305.476438) (xy 156.102761 -305.525337) (xy 156.079418 -305.571149) (xy 156.049197 -305.612745)
			(xy 156.012841 -305.649101) (xy 155.971245 -305.679322) (xy 155.925433 -305.702665) (xy 155.876534 -305.718553)
			(xy 155.825752 -305.726596) (xy 155.774336 -305.726596) (xy 155.723554 -305.718553) (xy 155.674655 -305.702665)
			(xy 155.628843 -305.679322) (xy 155.587247 -305.649101) (xy 155.550891 -305.612745) (xy 155.52067 -305.571149)
			(xy 155.497327 -305.525337) (xy 155.481439 -305.476438) (xy 155.473396 -305.425656) (xy 155.176732 -305.425656)
			(xy 155.168689 -305.476438) (xy 155.152801 -305.525337) (xy 155.129458 -305.571149) (xy 155.099237 -305.612745)
			(xy 155.062881 -305.649101) (xy 155.021285 -305.679322) (xy 154.975473 -305.702665) (xy 154.926574 -305.718553)
			(xy 154.875792 -305.726596) (xy 154.824376 -305.726596) (xy 154.773594 -305.718553) (xy 154.724695 -305.702665)
			(xy 154.678883 -305.679322) (xy 154.637287 -305.649101) (xy 154.600931 -305.612745) (xy 154.57071 -305.571149)
			(xy 154.547367 -305.525337) (xy 154.531479 -305.476438) (xy 154.523436 -305.425656) (xy 154.204504 -305.425656)
			(xy 154.196788 -305.473132) (xy 154.181204 -305.519813) (xy 154.158333 -305.56339) (xy 154.128768 -305.602734)
			(xy 154.093275 -305.636826) (xy 154.052772 -305.664782) (xy 154.00831 -305.68588) (xy 153.961039 -305.699572)
			(xy 153.912184 -305.705504) (xy 153.863009 -305.703523) (xy 153.81479 -305.693679) (xy 153.768774 -305.676227)
			(xy 153.726153 -305.65162) (xy 153.688032 -305.620495) (xy 153.655397 -305.583658) (xy 153.629094 -305.542062)
			(xy 153.609803 -305.496786) (xy 153.598026 -305.449002) (xy 153.594066 -305.399948) (xy 153.255218 -305.399948)
			(xy 153.254723 -305.424555) (xy 153.246828 -305.473132) (xy 153.231244 -305.519813) (xy 153.208373 -305.56339)
			(xy 153.178808 -305.602734) (xy 153.143315 -305.636826) (xy 153.102812 -305.664782) (xy 153.05835 -305.68588)
			(xy 153.011079 -305.699572) (xy 152.962224 -305.705504) (xy 152.913049 -305.703523) (xy 152.86483 -305.693679)
			(xy 152.818814 -305.676227) (xy 152.776193 -305.65162) (xy 152.738072 -305.620495) (xy 152.705437 -305.583658)
			(xy 152.679134 -305.542062) (xy 152.659843 -305.496786) (xy 152.648066 -305.449002) (xy 152.644106 -305.399948)
			(xy 144.26705 -305.399948) (xy 144.264833 -305.415377) (xy 144.24948 -305.467683) (xy 144.226839 -305.517271)
			(xy 144.197371 -305.563132) (xy 144.161676 -305.604333) (xy 144.120481 -305.640035) (xy 144.074624 -305.66951)
			(xy 144.02504 -305.692159) (xy 143.972736 -305.70752) (xy 143.918779 -305.715281) (xy 143.864266 -305.715285)
			(xy 143.810308 -305.70753) (xy 143.758003 -305.692174) (xy 143.708415 -305.669531) (xy 143.662555 -305.640062)
			(xy 143.621356 -305.604365) (xy 143.585656 -305.563169) (xy 143.556183 -305.517311) (xy 143.533536 -305.467725)
			(xy 143.518177 -305.415421) (xy 143.510418 -305.361464) (xy 143.510416 -305.306951) (xy 133.096209 -305.306951)
			(xy 133.087685 -305.314337) (xy 133.041835 -305.343803) (xy 132.992258 -305.366445) (xy 132.939963 -305.3818)
			(xy 132.886015 -305.389556) (xy 132.831513 -305.389556) (xy 132.777565 -305.3818) (xy 132.72527 -305.366445)
			(xy 132.675693 -305.343803) (xy 132.629843 -305.314337) (xy 132.588652 -305.278646) (xy 132.552961 -305.237455)
			(xy 132.523495 -305.191605) (xy 132.500853 -305.142028) (xy 132.485498 -305.089733) (xy 132.477742 -305.035785)
			(xy 132.477256 -305.008534) (xy 128.432052 -305.008534) (xy 128.431566 -305.035785) (xy 128.42381 -305.089733)
			(xy 128.408455 -305.142028) (xy 128.385813 -305.191605) (xy 128.356347 -305.237455) (xy 128.320656 -305.278646)
			(xy 128.279465 -305.314337) (xy 128.233615 -305.343803) (xy 128.184038 -305.366445) (xy 128.131743 -305.3818)
			(xy 128.077795 -305.389556) (xy 128.023293 -305.389556) (xy 127.969345 -305.3818) (xy 127.91705 -305.366445)
			(xy 127.867473 -305.343803) (xy 127.821623 -305.314337) (xy 127.780432 -305.278646) (xy 127.744741 -305.237455)
			(xy 127.715275 -305.191605) (xy 127.692633 -305.142028) (xy 127.677278 -305.089733) (xy 127.669522 -305.035785)
			(xy 127.669036 -305.008534) (xy 126.400052 -305.008534) (xy 126.399566 -305.035785) (xy 126.39181 -305.089733)
			(xy 126.376455 -305.142028) (xy 126.353813 -305.191605) (xy 126.324347 -305.237455) (xy 126.288656 -305.278646)
			(xy 126.247465 -305.314337) (xy 126.201615 -305.343803) (xy 126.152038 -305.366445) (xy 126.099743 -305.3818)
			(xy 126.045795 -305.389556) (xy 125.991293 -305.389556) (xy 125.937345 -305.3818) (xy 125.88505 -305.366445)
			(xy 125.835473 -305.343803) (xy 125.789623 -305.314337) (xy 125.748432 -305.278646) (xy 125.712741 -305.237455)
			(xy 125.683275 -305.191605) (xy 125.660633 -305.142028) (xy 125.645278 -305.089733) (xy 125.637522 -305.035785)
			(xy 125.637036 -305.008534) (xy 125.011942 -305.008534) (xy 125.011456 -305.035785) (xy 125.0037 -305.089733)
			(xy 124.988345 -305.142028) (xy 124.965703 -305.191605) (xy 124.936237 -305.237455) (xy 124.900546 -305.278646)
			(xy 124.859355 -305.314337) (xy 124.813505 -305.343803) (xy 124.763928 -305.366445) (xy 124.711633 -305.3818)
			(xy 124.657685 -305.389556) (xy 124.603183 -305.389556) (xy 124.549235 -305.3818) (xy 124.49694 -305.366445)
			(xy 124.447363 -305.343803) (xy 124.401513 -305.314337) (xy 124.360322 -305.278646) (xy 124.324631 -305.237455)
			(xy 124.295165 -305.191605) (xy 124.272523 -305.142028) (xy 124.257168 -305.089733) (xy 124.249412 -305.035785)
			(xy 124.248926 -305.008534) (xy 121.591832 -305.008534) (xy 121.591346 -305.035785) (xy 121.58359 -305.089733)
			(xy 121.568235 -305.142028) (xy 121.545593 -305.191605) (xy 121.516127 -305.237455) (xy 121.480436 -305.278646)
			(xy 121.439245 -305.314337) (xy 121.393395 -305.343803) (xy 121.343818 -305.366445) (xy 121.291523 -305.3818)
			(xy 121.237575 -305.389556) (xy 121.183073 -305.389556) (xy 121.129125 -305.3818) (xy 121.07683 -305.366445)
			(xy 121.027253 -305.343803) (xy 120.981403 -305.314337) (xy 120.940212 -305.278646) (xy 120.904521 -305.237455)
			(xy 120.875055 -305.191605) (xy 120.852413 -305.142028) (xy 120.837058 -305.089733) (xy 120.829302 -305.035785)
			(xy 120.828816 -305.008534) (xy 118.832884 -305.008534) (xy 118.832884 -307.82387) (xy 121.416826 -307.82387)
			(xy 121.417268 -307.796499) (xy 121.425091 -307.742318) (xy 121.440585 -307.689815) (xy 121.463432 -307.640068)
			(xy 121.493162 -307.594103) (xy 121.510806 -307.573172) (xy 121.516902 -307.56606) (xy 121.523252 -307.549042)
			(xy 121.523252 -307.463698) (xy 121.516902 -307.44668) (xy 121.510806 -307.439568) (xy 121.493137 -307.418659)
			(xy 121.463415 -307.372686) (xy 121.440572 -307.322936) (xy 121.425079 -307.270431) (xy 121.417254 -307.216249)
			(xy 121.417257 -307.161506) (xy 121.425089 -307.107325) (xy 121.440588 -307.054822) (xy 121.463437 -307.005074)
			(xy 121.493164 -306.959105) (xy 121.510806 -306.938172) (xy 121.516902 -306.93106) (xy 121.523252 -306.914042)
			(xy 121.523252 -306.828698) (xy 121.516902 -306.81168) (xy 121.510806 -306.804568) (xy 121.493137 -306.783659)
			(xy 121.463415 -306.737686) (xy 121.440572 -306.687936) (xy 121.425079 -306.635431) (xy 121.417254 -306.581249)
			(xy 121.417257 -306.526506) (xy 121.425089 -306.472325) (xy 121.440588 -306.419822) (xy 121.463437 -306.370074)
			(xy 121.493164 -306.324105) (xy 121.510806 -306.303172) (xy 121.516902 -306.29606) (xy 121.523252 -306.279042)
			(xy 121.523252 -306.193698) (xy 121.516902 -306.17668) (xy 121.510806 -306.169568) (xy 121.493186 -306.14862)
			(xy 121.463471 -306.102652) (xy 121.440632 -306.052908) (xy 121.425136 -306.000411) (xy 121.417303 -305.946238)
			(xy 121.416826 -305.91887) (xy 121.417312 -305.891619) (xy 121.425068 -305.837671) (xy 121.440423 -305.785376)
			(xy 121.463065 -305.735799) (xy 121.492531 -305.689949) (xy 121.528222 -305.648758) (xy 121.569413 -305.613067)
			(xy 121.615263 -305.583601) (xy 121.66484 -305.560959) (xy 121.717135 -305.545604) (xy 121.771083 -305.537848)
			(xy 121.825585 -305.537848) (xy 121.879533 -305.545604) (xy 121.931828 -305.560959) (xy 121.981405 -305.583601)
			(xy 122.027255 -305.613067) (xy 122.068446 -305.648758) (xy 122.104137 -305.689949) (xy 122.133603 -305.735799)
			(xy 122.156245 -305.785376) (xy 122.1716 -305.837671) (xy 122.179356 -305.891619) (xy 122.179842 -305.91887)
			(xy 122.179372 -305.94624) (xy 122.171558 -306.00042) (xy 122.15607 -306.052923) (xy 122.133229 -306.10267)
			(xy 122.103504 -306.148637) (xy 122.085862 -306.169568) (xy 122.079766 -306.17668) (xy 122.073416 -306.193698)
			(xy 122.073416 -306.279042) (xy 122.079766 -306.29606) (xy 122.085862 -306.303172) (xy 122.103474 -306.324128)
			(xy 122.133201 -306.370092) (xy 122.156048 -306.419834) (xy 122.171547 -306.472333) (xy 122.179379 -306.526508)
			(xy 122.179382 -306.581247) (xy 122.171557 -306.635423) (xy 122.156064 -306.687924) (xy 122.133222 -306.737669)
			(xy 122.103501 -306.783636) (xy 122.085862 -306.804568) (xy 122.079766 -306.81168) (xy 122.073416 -306.828698)
			(xy 122.073416 -306.914042) (xy 122.079766 -306.93106) (xy 122.085862 -306.938172) (xy 122.103474 -306.959128)
			(xy 122.133201 -307.005092) (xy 122.156048 -307.054834) (xy 122.171547 -307.107333) (xy 122.179379 -307.161508)
			(xy 122.179382 -307.216247) (xy 122.171557 -307.270423) (xy 122.156064 -307.322924) (xy 122.133222 -307.372669)
			(xy 122.103501 -307.418636) (xy 122.085862 -307.439568) (xy 122.079766 -307.44668) (xy 122.073416 -307.463698)
			(xy 122.073416 -307.549042) (xy 122.079766 -307.56606) (xy 122.085862 -307.573172) (xy 122.103496 -307.594109)
			(xy 122.133209 -307.64008) (xy 122.156047 -307.689826) (xy 122.171539 -307.742326) (xy 122.179368 -307.796501)
			(xy 122.179842 -307.82387) (xy 122.179356 -307.851121) (xy 122.175532 -307.877718) (xy 125.049026 -307.877718)
			(xy 125.049496 -307.850348) (xy 125.057312 -307.796169) (xy 125.0728 -307.743665) (xy 125.095641 -307.693918)
			(xy 125.125365 -307.647952) (xy 125.143006 -307.62702) (xy 125.149102 -307.619908) (xy 125.155452 -307.60289)
			(xy 125.155452 -307.517546) (xy 125.149102 -307.500528) (xy 125.143006 -307.493416) (xy 125.125384 -307.472469)
			(xy 125.09566 -307.426503) (xy 125.072815 -307.376759) (xy 125.057318 -307.324259) (xy 125.049488 -307.270083)
			(xy 125.049486 -307.215344) (xy 125.057312 -307.161167) (xy 125.072805 -307.108667) (xy 125.095647 -307.058921)
			(xy 125.125367 -307.012953) (xy 125.143006 -306.99202) (xy 125.149102 -306.984908) (xy 125.155452 -306.96789)
			(xy 125.155452 -306.882546) (xy 125.149102 -306.865528) (xy 125.143006 -306.858416) (xy 125.125384 -306.837469)
			(xy 125.09566 -306.791503) (xy 125.072815 -306.741759) (xy 125.057318 -306.689259) (xy 125.049488 -306.635083)
			(xy 125.049486 -306.580344) (xy 125.057312 -306.526167) (xy 125.072805 -306.473667) (xy 125.095647 -306.423921)
			(xy 125.125367 -306.377953) (xy 125.143006 -306.35702) (xy 125.149102 -306.349908) (xy 125.155452 -306.33289)
			(xy 125.155452 -306.247546) (xy 125.149102 -306.230528) (xy 125.143006 -306.223416) (xy 125.125362 -306.202488)
			(xy 125.095651 -306.156514) (xy 125.072816 -306.106766) (xy 125.057326 -306.054264) (xy 125.049499 -306.000087)
			(xy 125.049026 -305.972718) (xy 125.049512 -305.945467) (xy 125.057268 -305.891519) (xy 125.072623 -305.839224)
			(xy 125.095265 -305.789647) (xy 125.124731 -305.743797) (xy 125.160422 -305.702606) (xy 125.201613 -305.666915)
			(xy 125.247463 -305.637449) (xy 125.29704 -305.614807) (xy 125.349335 -305.599452) (xy 125.403283 -305.591696)
			(xy 125.457785 -305.591696) (xy 125.511733 -305.599452) (xy 125.564028 -305.614807) (xy 125.613605 -305.637449)
			(xy 125.659455 -305.666915) (xy 125.700646 -305.702606) (xy 125.736337 -305.743797) (xy 125.765803 -305.789647)
			(xy 125.788445 -305.839224) (xy 125.8038 -305.891519) (xy 125.811556 -305.945467) (xy 125.812042 -305.972718)
			(xy 125.811601 -306.000089) (xy 125.803779 -306.05427) (xy 125.788285 -306.106774) (xy 125.765437 -306.15652)
			(xy 125.735706 -306.202486) (xy 125.718062 -306.223416) (xy 125.711966 -306.230528) (xy 125.705616 -306.247546)
			(xy 125.705616 -306.33289) (xy 125.711966 -306.349908) (xy 125.718062 -306.35702) (xy 125.735721 -306.377938)
			(xy 125.765446 -306.423908) (xy 125.788291 -306.473657) (xy 125.803786 -306.526161) (xy 125.811613 -306.580342)
			(xy 125.811611 -306.635085) (xy 125.80378 -306.689265) (xy 125.788281 -306.741769) (xy 125.765433 -306.791516)
			(xy 125.735704 -306.837483) (xy 125.718062 -306.858416) (xy 125.711966 -306.865528) (xy 125.705616 -306.882546)
			(xy 125.705616 -306.96789) (xy 125.711966 -306.984908) (xy 125.718062 -306.99202) (xy 125.735721 -307.012938)
			(xy 125.765446 -307.058908) (xy 125.788291 -307.108657) (xy 125.803786 -307.161161) (xy 125.811613 -307.215342)
			(xy 125.811611 -307.270085) (xy 125.80378 -307.324265) (xy 125.788281 -307.376769) (xy 125.765433 -307.426516)
			(xy 125.735704 -307.472483) (xy 125.718062 -307.493416) (xy 125.711966 -307.500528) (xy 125.705616 -307.517546)
			(xy 125.705616 -307.60289) (xy 125.711966 -307.619908) (xy 125.718062 -307.62702) (xy 125.735671 -307.647976)
			(xy 125.765389 -307.693942) (xy 125.788231 -307.743683) (xy 125.803729 -307.796179) (xy 125.807734 -307.82387)
			(xy 128.257046 -307.82387) (xy 128.257483 -307.796499) (xy 128.265306 -307.742318) (xy 128.280802 -307.689814)
			(xy 128.30365 -307.640068) (xy 128.333381 -307.594102) (xy 128.351026 -307.573172) (xy 128.357122 -307.56606)
			(xy 128.363472 -307.549042) (xy 128.363472 -307.463698) (xy 128.357122 -307.44668) (xy 128.351026 -307.439568)
			(xy 128.333356 -307.418659) (xy 128.303632 -307.372687) (xy 128.280789 -307.322937) (xy 128.265295 -307.270431)
			(xy 128.257469 -307.216249) (xy 128.257472 -307.161505) (xy 128.265305 -307.107325) (xy 128.280805 -307.054821)
			(xy 128.303654 -307.005073) (xy 128.333383 -306.959105) (xy 128.351026 -306.938172) (xy 128.357122 -306.93106)
			(xy 128.363472 -306.914042) (xy 128.363472 -306.828698) (xy 128.357122 -306.81168) (xy 128.351026 -306.804568)
			(xy 128.333356 -306.783659) (xy 128.303632 -306.737687) (xy 128.280789 -306.687937) (xy 128.265295 -306.635431)
			(xy 128.257469 -306.581249) (xy 128.257472 -306.526505) (xy 128.265305 -306.472325) (xy 128.280805 -306.419821)
			(xy 128.303654 -306.370073) (xy 128.333383 -306.324105) (xy 128.351026 -306.303172) (xy 128.357122 -306.29606)
			(xy 128.363472 -306.279042) (xy 128.363472 -306.193698) (xy 128.357122 -306.17668) (xy 128.351026 -306.169568)
			(xy 128.333409 -306.148618) (xy 128.303693 -306.10265) (xy 128.280853 -306.052908) (xy 128.265356 -306.000411)
			(xy 128.257523 -305.946238) (xy 128.257046 -305.91887) (xy 128.257532 -305.891619) (xy 128.265288 -305.837671)
			(xy 128.280643 -305.785376) (xy 128.303285 -305.735799) (xy 128.332751 -305.689949) (xy 128.368442 -305.648758)
			(xy 128.409633 -305.613067) (xy 128.455483 -305.583601) (xy 128.50506 -305.560959) (xy 128.557355 -305.545604)
			(xy 128.611303 -305.537848) (xy 128.665805 -305.537848) (xy 128.719753 -305.545604) (xy 128.772048 -305.560959)
			(xy 128.821625 -305.583601) (xy 128.867475 -305.613067) (xy 128.908666 -305.648758) (xy 128.944357 -305.689949)
			(xy 128.973823 -305.735799) (xy 128.996465 -305.785376) (xy 129.01182 -305.837671) (xy 129.019576 -305.891619)
			(xy 129.020062 -305.91887) (xy 129.019588 -305.94624) (xy 129.011773 -306.000419) (xy 128.996287 -306.052923)
			(xy 128.973446 -306.10267) (xy 128.943723 -306.148636) (xy 128.926082 -306.169568) (xy 128.919986 -306.17668)
			(xy 128.913636 -306.193698) (xy 128.913636 -306.279042) (xy 128.919986 -306.29606) (xy 128.926082 -306.303172)
			(xy 128.943693 -306.324129) (xy 128.973418 -306.370093) (xy 128.996265 -306.419835) (xy 129.011763 -306.472333)
			(xy 129.019594 -306.526508) (xy 129.019597 -306.581247) (xy 129.011773 -306.635423) (xy 128.996281 -306.687923)
			(xy 128.97344 -306.737668) (xy 128.94372 -306.783635) (xy 128.926082 -306.804568) (xy 128.919986 -306.81168)
			(xy 128.913636 -306.828698) (xy 128.913636 -306.914042) (xy 128.919986 -306.93106) (xy 128.926082 -306.938172)
			(xy 128.943693 -306.959129) (xy 128.973418 -307.005093) (xy 128.996265 -307.054835) (xy 129.011763 -307.107333)
			(xy 129.019594 -307.161508) (xy 129.019597 -307.216247) (xy 129.011773 -307.270423) (xy 128.996281 -307.322923)
			(xy 128.97344 -307.372668) (xy 128.94372 -307.418635) (xy 128.926082 -307.439568) (xy 128.919986 -307.44668)
			(xy 128.913636 -307.463698) (xy 128.913636 -307.549042) (xy 128.919986 -307.56606) (xy 128.926082 -307.573172)
			(xy 128.943719 -307.594106) (xy 128.973431 -307.640078) (xy 128.996268 -307.689825) (xy 129.01176 -307.742325)
			(xy 129.019588 -307.796501) (xy 129.020062 -307.82387) (xy 129.019576 -307.851121) (xy 129.015752 -307.877718)
			(xy 131.889246 -307.877718) (xy 131.889711 -307.850348) (xy 131.897528 -307.796168) (xy 131.913016 -307.743665)
			(xy 131.935858 -307.693918) (xy 131.965584 -307.647951) (xy 131.983226 -307.62702) (xy 131.989322 -307.619908)
			(xy 131.995672 -307.60289) (xy 131.995672 -307.517546) (xy 131.989322 -307.500528) (xy 131.983226 -307.493416)
			(xy 131.965603 -307.472469) (xy 131.935878 -307.426504) (xy 131.913031 -307.37676) (xy 131.897534 -307.32426)
			(xy 131.889703 -307.270083) (xy 131.889701 -307.215344) (xy 131.897528 -307.161167) (xy 131.913022 -307.108666)
			(xy 131.935864 -307.05892) (xy 131.965587 -307.012953) (xy 131.983226 -306.99202) (xy 131.989322 -306.984908)
			(xy 131.995672 -306.96789) (xy 131.995672 -306.882546) (xy 131.989322 -306.865528) (xy 131.983226 -306.858416)
			(xy 131.965603 -306.837469) (xy 131.935878 -306.791504) (xy 131.913031 -306.74176) (xy 131.897534 -306.68926)
			(xy 131.889703 -306.635083) (xy 131.889701 -306.580344) (xy 131.897528 -306.526167) (xy 131.913022 -306.473666)
			(xy 131.935864 -306.42392) (xy 131.965587 -306.377953) (xy 131.983226 -306.35702) (xy 131.989322 -306.349908)
			(xy 131.995672 -306.33289) (xy 131.995672 -306.247546) (xy 131.989322 -306.230528) (xy 131.983226 -306.223416)
			(xy 131.965585 -306.202485) (xy 131.935873 -306.156513) (xy 131.913037 -306.106765) (xy 131.897546 -306.054264)
			(xy 131.889719 -306.000087) (xy 131.889246 -305.972718) (xy 131.889732 -305.945467) (xy 131.897488 -305.891519)
			(xy 131.912843 -305.839224) (xy 131.935485 -305.789647) (xy 131.964951 -305.743797) (xy 132.000642 -305.702606)
			(xy 132.041833 -305.666915) (xy 132.087683 -305.637449) (xy 132.13726 -305.614807) (xy 132.189555 -305.599452)
			(xy 132.243503 -305.591696) (xy 132.298005 -305.591696) (xy 132.351953 -305.599452) (xy 132.404248 -305.614807)
			(xy 132.453825 -305.637449) (xy 132.499675 -305.666915) (xy 132.540866 -305.702606) (xy 132.576557 -305.743797)
			(xy 132.606023 -305.789647) (xy 132.628665 -305.839224) (xy 132.64402 -305.891519) (xy 132.651776 -305.945467)
			(xy 132.652262 -305.972718) (xy 132.651816 -306.000089) (xy 132.644217 -306.052728) (xy 142.790924 -306.052728)
			(xy 142.794995 -305.997106) (xy 142.807121 -305.942669) (xy 142.827044 -305.890578) (xy 142.85434 -305.841943)
			(xy 142.888426 -305.7978) (xy 142.928575 -305.759091) (xy 142.973933 -305.72664) (xy 143.023533 -305.701139)
			(xy 143.076317 -305.683132) (xy 143.13116 -305.673002) (xy 143.186894 -305.670965) (xy 143.242331 -305.677065)
			(xy 143.296288 -305.691171) (xy 143.347617 -305.712983) (xy 143.395223 -305.742037) (xy 143.438091 -305.777712)
			(xy 143.475308 -305.819249) (xy 143.506081 -305.865762) (xy 143.510378 -305.874928) (xy 162.619194 -305.874928)
			(xy 162.623154 -305.825874) (xy 162.634931 -305.77809) (xy 162.654222 -305.732814) (xy 162.680525 -305.691218)
			(xy 162.71316 -305.654381) (xy 162.751281 -305.623256) (xy 162.793902 -305.598649) (xy 162.839918 -305.581197)
			(xy 162.888137 -305.571353) (xy 162.937312 -305.569372) (xy 162.986167 -305.575304) (xy 163.033438 -305.588996)
			(xy 163.0779 -305.610094) (xy 163.118403 -305.63805) (xy 163.153896 -305.672142) (xy 163.183461 -305.711486)
			(xy 163.206332 -305.755063) (xy 163.221916 -305.801744) (xy 163.229811 -305.850321) (xy 163.230306 -305.874928)
			(xy 163.569154 -305.874928) (xy 163.573114 -305.825874) (xy 163.584891 -305.77809) (xy 163.604182 -305.732814)
			(xy 163.630485 -305.691218) (xy 163.66312 -305.654381) (xy 163.701241 -305.623256) (xy 163.743862 -305.598649)
			(xy 163.789878 -305.581197) (xy 163.838097 -305.571353) (xy 163.887272 -305.569372) (xy 163.936127 -305.575304)
			(xy 163.983398 -305.588996) (xy 164.02786 -305.610094) (xy 164.068363 -305.63805) (xy 164.103856 -305.672142)
			(xy 164.133421 -305.711486) (xy 164.156292 -305.755063) (xy 164.171876 -305.801744) (xy 164.179771 -305.850321)
			(xy 164.180266 -305.874928) (xy 164.519114 -305.874928) (xy 164.523074 -305.825874) (xy 164.534851 -305.77809)
			(xy 164.554142 -305.732814) (xy 164.580445 -305.691218) (xy 164.61308 -305.654381) (xy 164.651201 -305.623256)
			(xy 164.693822 -305.598649) (xy 164.739838 -305.581197) (xy 164.788057 -305.571353) (xy 164.837232 -305.569372)
			(xy 164.886087 -305.575304) (xy 164.933358 -305.588996) (xy 164.97782 -305.610094) (xy 165.018323 -305.63805)
			(xy 165.053816 -305.672142) (xy 165.083381 -305.711486) (xy 165.106252 -305.755063) (xy 165.121836 -305.801744)
			(xy 165.129731 -305.850321) (xy 165.130226 -305.874928) (xy 165.469074 -305.874928) (xy 165.473034 -305.825874)
			(xy 165.484811 -305.77809) (xy 165.504102 -305.732814) (xy 165.530405 -305.691218) (xy 165.56304 -305.654381)
			(xy 165.601161 -305.623256) (xy 165.643782 -305.598649) (xy 165.689798 -305.581197) (xy 165.738017 -305.571353)
			(xy 165.787192 -305.569372) (xy 165.836047 -305.575304) (xy 165.883318 -305.588996) (xy 165.92778 -305.610094)
			(xy 165.968283 -305.63805) (xy 166.003776 -305.672142) (xy 166.033341 -305.711486) (xy 166.056212 -305.755063)
			(xy 166.071796 -305.801744) (xy 166.079691 -305.850321) (xy 166.080186 -305.874928) (xy 166.419288 -305.874928)
			(xy 166.423248 -305.825874) (xy 166.435025 -305.77809) (xy 166.454316 -305.732814) (xy 166.480619 -305.691218)
			(xy 166.513254 -305.654381) (xy 166.551375 -305.623256) (xy 166.593996 -305.598649) (xy 166.640012 -305.581197)
			(xy 166.688231 -305.571353) (xy 166.737406 -305.569372) (xy 166.786261 -305.575304) (xy 166.833532 -305.588996)
			(xy 166.877994 -305.610094) (xy 166.918497 -305.63805) (xy 166.95399 -305.672142) (xy 166.983555 -305.711486)
			(xy 167.006426 -305.755063) (xy 167.02201 -305.801744) (xy 167.029905 -305.850321) (xy 167.0304 -305.874928)
			(xy 167.369248 -305.874928) (xy 167.373208 -305.825874) (xy 167.384985 -305.77809) (xy 167.404276 -305.732814)
			(xy 167.430579 -305.691218) (xy 167.463214 -305.654381) (xy 167.501335 -305.623256) (xy 167.543956 -305.598649)
			(xy 167.589972 -305.581197) (xy 167.638191 -305.571353) (xy 167.687366 -305.569372) (xy 167.736221 -305.575304)
			(xy 167.783492 -305.588996) (xy 167.827954 -305.610094) (xy 167.868457 -305.63805) (xy 167.90395 -305.672142)
			(xy 167.933515 -305.711486) (xy 167.956386 -305.755063) (xy 167.97197 -305.801744) (xy 167.979865 -305.850321)
			(xy 167.98036 -305.874928) (xy 168.319208 -305.874928) (xy 168.323168 -305.825874) (xy 168.334945 -305.77809)
			(xy 168.354236 -305.732814) (xy 168.380539 -305.691218) (xy 168.413174 -305.654381) (xy 168.451295 -305.623256)
			(xy 168.493916 -305.598649) (xy 168.539932 -305.581197) (xy 168.588151 -305.571353) (xy 168.637326 -305.569372)
			(xy 168.686181 -305.575304) (xy 168.733452 -305.588996) (xy 168.777914 -305.610094) (xy 168.818417 -305.63805)
			(xy 168.85391 -305.672142) (xy 168.883475 -305.711486) (xy 168.906346 -305.755063) (xy 168.92193 -305.801744)
			(xy 168.929825 -305.850321) (xy 168.93032 -305.874928) (xy 169.269168 -305.874928) (xy 169.273128 -305.825874)
			(xy 169.284905 -305.77809) (xy 169.304196 -305.732814) (xy 169.330499 -305.691218) (xy 169.363134 -305.654381)
			(xy 169.401255 -305.623256) (xy 169.443876 -305.598649) (xy 169.489892 -305.581197) (xy 169.538111 -305.571353)
			(xy 169.587286 -305.569372) (xy 169.636141 -305.575304) (xy 169.683412 -305.588996) (xy 169.727874 -305.610094)
			(xy 169.768377 -305.63805) (xy 169.80387 -305.672142) (xy 169.833435 -305.711486) (xy 169.856306 -305.755063)
			(xy 169.87189 -305.801744) (xy 169.879785 -305.850321) (xy 169.88028 -305.874928) (xy 170.219128 -305.874928)
			(xy 170.223088 -305.825874) (xy 170.234865 -305.77809) (xy 170.254156 -305.732814) (xy 170.280459 -305.691218)
			(xy 170.313094 -305.654381) (xy 170.351215 -305.623256) (xy 170.393836 -305.598649) (xy 170.439852 -305.581197)
			(xy 170.488071 -305.571353) (xy 170.537246 -305.569372) (xy 170.586101 -305.575304) (xy 170.633372 -305.588996)
			(xy 170.677834 -305.610094) (xy 170.718337 -305.63805) (xy 170.75383 -305.672142) (xy 170.783395 -305.711486)
			(xy 170.806266 -305.755063) (xy 170.82185 -305.801744) (xy 170.829745 -305.850321) (xy 170.83024 -305.874928)
			(xy 171.169088 -305.874928) (xy 171.173048 -305.825874) (xy 171.184825 -305.77809) (xy 171.204116 -305.732814)
			(xy 171.230419 -305.691218) (xy 171.263054 -305.654381) (xy 171.301175 -305.623256) (xy 171.343796 -305.598649)
			(xy 171.389812 -305.581197) (xy 171.438031 -305.571353) (xy 171.487206 -305.569372) (xy 171.536061 -305.575304)
			(xy 171.583332 -305.588996) (xy 171.627794 -305.610094) (xy 171.668297 -305.63805) (xy 171.70379 -305.672142)
			(xy 171.733355 -305.711486) (xy 171.756226 -305.755063) (xy 171.77181 -305.801744) (xy 171.779705 -305.850321)
			(xy 171.7802 -305.874928) (xy 172.119048 -305.874928) (xy 172.123008 -305.825874) (xy 172.134785 -305.77809)
			(xy 172.154076 -305.732814) (xy 172.180379 -305.691218) (xy 172.213014 -305.654381) (xy 172.251135 -305.623256)
			(xy 172.293756 -305.598649) (xy 172.339772 -305.581197) (xy 172.387991 -305.571353) (xy 172.437166 -305.569372)
			(xy 172.486021 -305.575304) (xy 172.533292 -305.588996) (xy 172.577754 -305.610094) (xy 172.618257 -305.63805)
			(xy 172.65375 -305.672142) (xy 172.683315 -305.711486) (xy 172.706186 -305.755063) (xy 172.72177 -305.801744)
			(xy 172.729665 -305.850321) (xy 172.73016 -305.874928) (xy 173.069262 -305.874928) (xy 173.073222 -305.825874)
			(xy 173.084999 -305.77809) (xy 173.10429 -305.732814) (xy 173.130593 -305.691218) (xy 173.163228 -305.654381)
			(xy 173.201349 -305.623256) (xy 173.24397 -305.598649) (xy 173.289986 -305.581197) (xy 173.338205 -305.571353)
			(xy 173.38738 -305.569372) (xy 173.436235 -305.575304) (xy 173.483506 -305.588996) (xy 173.527968 -305.610094)
			(xy 173.568471 -305.63805) (xy 173.603964 -305.672142) (xy 173.633529 -305.711486) (xy 173.6564 -305.755063)
			(xy 173.671984 -305.801744) (xy 173.679879 -305.850321) (xy 173.680374 -305.874928) (xy 174.019222 -305.874928)
			(xy 174.023182 -305.825874) (xy 174.034959 -305.77809) (xy 174.05425 -305.732814) (xy 174.080553 -305.691218)
			(xy 174.113188 -305.654381) (xy 174.151309 -305.623256) (xy 174.19393 -305.598649) (xy 174.239946 -305.581197)
			(xy 174.288165 -305.571353) (xy 174.33734 -305.569372) (xy 174.386195 -305.575304) (xy 174.433466 -305.588996)
			(xy 174.477928 -305.610094) (xy 174.518431 -305.63805) (xy 174.553924 -305.672142) (xy 174.583489 -305.711486)
			(xy 174.60636 -305.755063) (xy 174.621944 -305.801744) (xy 174.629839 -305.850321) (xy 174.630334 -305.874928)
			(xy 175.919142 -305.874928) (xy 175.923102 -305.825874) (xy 175.934879 -305.77809) (xy 175.95417 -305.732814)
			(xy 175.980473 -305.691218) (xy 176.013108 -305.654381) (xy 176.051229 -305.623256) (xy 176.09385 -305.598649)
			(xy 176.139866 -305.581197) (xy 176.188085 -305.571353) (xy 176.23726 -305.569372) (xy 176.286115 -305.575304)
			(xy 176.333386 -305.588996) (xy 176.377848 -305.610094) (xy 176.418351 -305.63805) (xy 176.453844 -305.672142)
			(xy 176.483409 -305.711486) (xy 176.50628 -305.755063) (xy 176.521864 -305.801744) (xy 176.529759 -305.850321)
			(xy 176.530254 -305.874928) (xy 176.869102 -305.874928) (xy 176.873062 -305.825874) (xy 176.884839 -305.77809)
			(xy 176.90413 -305.732814) (xy 176.930433 -305.691218) (xy 176.963068 -305.654381) (xy 177.001189 -305.623256)
			(xy 177.04381 -305.598649) (xy 177.089826 -305.581197) (xy 177.138045 -305.571353) (xy 177.18722 -305.569372)
			(xy 177.236075 -305.575304) (xy 177.283346 -305.588996) (xy 177.327808 -305.610094) (xy 177.368311 -305.63805)
			(xy 177.403804 -305.672142) (xy 177.433369 -305.711486) (xy 177.45624 -305.755063) (xy 177.471824 -305.801744)
			(xy 177.479719 -305.850321) (xy 177.480214 -305.874928) (xy 177.819062 -305.874928) (xy 177.823022 -305.825874)
			(xy 177.834799 -305.77809) (xy 177.85409 -305.732814) (xy 177.880393 -305.691218) (xy 177.913028 -305.654381)
			(xy 177.951149 -305.623256) (xy 177.99377 -305.598649) (xy 178.039786 -305.581197) (xy 178.088005 -305.571353)
			(xy 178.13718 -305.569372) (xy 178.186035 -305.575304) (xy 178.233306 -305.588996) (xy 178.277768 -305.610094)
			(xy 178.318271 -305.63805) (xy 178.353764 -305.672142) (xy 178.383329 -305.711486) (xy 178.4062 -305.755063)
			(xy 178.421784 -305.801744) (xy 178.429679 -305.850321) (xy 178.430174 -305.874928) (xy 178.769276 -305.874928)
			(xy 178.773236 -305.825874) (xy 178.785013 -305.77809) (xy 178.804304 -305.732814) (xy 178.830607 -305.691218)
			(xy 178.863242 -305.654381) (xy 178.901363 -305.623256) (xy 178.943984 -305.598649) (xy 178.99 -305.581197)
			(xy 179.038219 -305.571353) (xy 179.087394 -305.569372) (xy 179.136249 -305.575304) (xy 179.18352 -305.588996)
			(xy 179.227982 -305.610094) (xy 179.268485 -305.63805) (xy 179.303978 -305.672142) (xy 179.333543 -305.711486)
			(xy 179.356414 -305.755063) (xy 179.371998 -305.801744) (xy 179.379893 -305.850321) (xy 179.380388 -305.874928)
			(xy 179.719236 -305.874928) (xy 179.723196 -305.825874) (xy 179.734973 -305.77809) (xy 179.754264 -305.732814)
			(xy 179.780567 -305.691218) (xy 179.813202 -305.654381) (xy 179.851323 -305.623256) (xy 179.893944 -305.598649)
			(xy 179.93996 -305.581197) (xy 179.988179 -305.571353) (xy 180.037354 -305.569372) (xy 180.086209 -305.575304)
			(xy 180.13348 -305.588996) (xy 180.177942 -305.610094) (xy 180.218445 -305.63805) (xy 180.253938 -305.672142)
			(xy 180.283503 -305.711486) (xy 180.306374 -305.755063) (xy 180.321958 -305.801744) (xy 180.329853 -305.850321)
			(xy 180.330348 -305.874928) (xy 180.669196 -305.874928) (xy 180.673156 -305.825874) (xy 180.684933 -305.77809)
			(xy 180.704224 -305.732814) (xy 180.730527 -305.691218) (xy 180.763162 -305.654381) (xy 180.801283 -305.623256)
			(xy 180.843904 -305.598649) (xy 180.88992 -305.581197) (xy 180.938139 -305.571353) (xy 180.987314 -305.569372)
			(xy 181.036169 -305.575304) (xy 181.08344 -305.588996) (xy 181.127902 -305.610094) (xy 181.168405 -305.63805)
			(xy 181.203898 -305.672142) (xy 181.233463 -305.711486) (xy 181.256334 -305.755063) (xy 181.271918 -305.801744)
			(xy 181.279813 -305.850321) (xy 181.280308 -305.874928) (xy 181.619156 -305.874928) (xy 181.623116 -305.825874)
			(xy 181.634893 -305.77809) (xy 181.654184 -305.732814) (xy 181.680487 -305.691218) (xy 181.713122 -305.654381)
			(xy 181.751243 -305.623256) (xy 181.793864 -305.598649) (xy 181.83988 -305.581197) (xy 181.888099 -305.571353)
			(xy 181.937274 -305.569372) (xy 181.986129 -305.575304) (xy 182.0334 -305.588996) (xy 182.077862 -305.610094)
			(xy 182.118365 -305.63805) (xy 182.153858 -305.672142) (xy 182.183423 -305.711486) (xy 182.206294 -305.755063)
			(xy 182.221878 -305.801744) (xy 182.229773 -305.850321) (xy 182.230268 -305.874928) (xy 182.569116 -305.874928)
			(xy 182.573076 -305.825874) (xy 182.584853 -305.77809) (xy 182.604144 -305.732814) (xy 182.630447 -305.691218)
			(xy 182.663082 -305.654381) (xy 182.701203 -305.623256) (xy 182.743824 -305.598649) (xy 182.78984 -305.581197)
			(xy 182.838059 -305.571353) (xy 182.887234 -305.569372) (xy 182.936089 -305.575304) (xy 182.98336 -305.588996)
			(xy 183.027822 -305.610094) (xy 183.068325 -305.63805) (xy 183.103818 -305.672142) (xy 183.133383 -305.711486)
			(xy 183.156254 -305.755063) (xy 183.171838 -305.801744) (xy 183.179733 -305.850321) (xy 183.180228 -305.874928)
			(xy 183.519076 -305.874928) (xy 183.523036 -305.825874) (xy 183.534813 -305.77809) (xy 183.554104 -305.732814)
			(xy 183.580407 -305.691218) (xy 183.613042 -305.654381) (xy 183.651163 -305.623256) (xy 183.693784 -305.598649)
			(xy 183.7398 -305.581197) (xy 183.788019 -305.571353) (xy 183.837194 -305.569372) (xy 183.886049 -305.575304)
			(xy 183.93332 -305.588996) (xy 183.977782 -305.610094) (xy 184.018285 -305.63805) (xy 184.053778 -305.672142)
			(xy 184.083343 -305.711486) (xy 184.106214 -305.755063) (xy 184.121798 -305.801744) (xy 184.129693 -305.850321)
			(xy 184.130188 -305.874928) (xy 184.469036 -305.874928) (xy 184.472996 -305.825874) (xy 184.484773 -305.77809)
			(xy 184.504064 -305.732814) (xy 184.530367 -305.691218) (xy 184.563002 -305.654381) (xy 184.601123 -305.623256)
			(xy 184.643744 -305.598649) (xy 184.68976 -305.581197) (xy 184.737979 -305.571353) (xy 184.787154 -305.569372)
			(xy 184.836009 -305.575304) (xy 184.88328 -305.588996) (xy 184.927742 -305.610094) (xy 184.968245 -305.63805)
			(xy 185.003738 -305.672142) (xy 185.033303 -305.711486) (xy 185.056174 -305.755063) (xy 185.071758 -305.801744)
			(xy 185.079653 -305.850321) (xy 185.080148 -305.874928) (xy 185.079653 -305.899535) (xy 185.071758 -305.948112)
			(xy 185.056174 -305.994793) (xy 185.033303 -306.03837) (xy 185.003738 -306.077714) (xy 184.968245 -306.111806)
			(xy 184.927742 -306.139762) (xy 184.88328 -306.16086) (xy 184.836009 -306.174552) (xy 184.787154 -306.180484)
			(xy 184.737979 -306.178503) (xy 184.68976 -306.168659) (xy 184.643744 -306.151207) (xy 184.601123 -306.1266)
			(xy 184.563002 -306.095475) (xy 184.530367 -306.058638) (xy 184.504064 -306.017042) (xy 184.484773 -305.971766)
			(xy 184.472996 -305.923982) (xy 184.469036 -305.874928) (xy 184.130188 -305.874928) (xy 184.129693 -305.899535)
			(xy 184.121798 -305.948112) (xy 184.106214 -305.994793) (xy 184.083343 -306.03837) (xy 184.053778 -306.077714)
			(xy 184.018285 -306.111806) (xy 183.977782 -306.139762) (xy 183.93332 -306.16086) (xy 183.886049 -306.174552)
			(xy 183.837194 -306.180484) (xy 183.788019 -306.178503) (xy 183.7398 -306.168659) (xy 183.693784 -306.151207)
			(xy 183.651163 -306.1266) (xy 183.613042 -306.095475) (xy 183.580407 -306.058638) (xy 183.554104 -306.017042)
			(xy 183.534813 -305.971766) (xy 183.523036 -305.923982) (xy 183.519076 -305.874928) (xy 183.180228 -305.874928)
			(xy 183.179733 -305.899535) (xy 183.171838 -305.948112) (xy 183.156254 -305.994793) (xy 183.133383 -306.03837)
			(xy 183.103818 -306.077714) (xy 183.068325 -306.111806) (xy 183.027822 -306.139762) (xy 182.98336 -306.16086)
			(xy 182.936089 -306.174552) (xy 182.887234 -306.180484) (xy 182.838059 -306.178503) (xy 182.78984 -306.168659)
			(xy 182.743824 -306.151207) (xy 182.701203 -306.1266) (xy 182.663082 -306.095475) (xy 182.630447 -306.058638)
			(xy 182.604144 -306.017042) (xy 182.584853 -305.971766) (xy 182.573076 -305.923982) (xy 182.569116 -305.874928)
			(xy 182.230268 -305.874928) (xy 182.229773 -305.899535) (xy 182.221878 -305.948112) (xy 182.206294 -305.994793)
			(xy 182.183423 -306.03837) (xy 182.153858 -306.077714) (xy 182.118365 -306.111806) (xy 182.077862 -306.139762)
			(xy 182.0334 -306.16086) (xy 181.986129 -306.174552) (xy 181.937274 -306.180484) (xy 181.888099 -306.178503)
			(xy 181.83988 -306.168659) (xy 181.793864 -306.151207) (xy 181.751243 -306.1266) (xy 181.713122 -306.095475)
			(xy 181.680487 -306.058638) (xy 181.654184 -306.017042) (xy 181.634893 -305.971766) (xy 181.623116 -305.923982)
			(xy 181.619156 -305.874928) (xy 181.280308 -305.874928) (xy 181.279813 -305.899535) (xy 181.271918 -305.948112)
			(xy 181.256334 -305.994793) (xy 181.233463 -306.03837) (xy 181.203898 -306.077714) (xy 181.168405 -306.111806)
			(xy 181.127902 -306.139762) (xy 181.08344 -306.16086) (xy 181.036169 -306.174552) (xy 180.987314 -306.180484)
			(xy 180.938139 -306.178503) (xy 180.88992 -306.168659) (xy 180.843904 -306.151207) (xy 180.801283 -306.1266)
			(xy 180.763162 -306.095475) (xy 180.730527 -306.058638) (xy 180.704224 -306.017042) (xy 180.684933 -305.971766)
			(xy 180.673156 -305.923982) (xy 180.669196 -305.874928) (xy 180.330348 -305.874928) (xy 180.329853 -305.899535)
			(xy 180.321958 -305.948112) (xy 180.306374 -305.994793) (xy 180.283503 -306.03837) (xy 180.253938 -306.077714)
			(xy 180.218445 -306.111806) (xy 180.177942 -306.139762) (xy 180.13348 -306.16086) (xy 180.086209 -306.174552)
			(xy 180.037354 -306.180484) (xy 179.988179 -306.178503) (xy 179.93996 -306.168659) (xy 179.893944 -306.151207)
			(xy 179.851323 -306.1266) (xy 179.813202 -306.095475) (xy 179.780567 -306.058638) (xy 179.754264 -306.017042)
			(xy 179.734973 -305.971766) (xy 179.723196 -305.923982) (xy 179.719236 -305.874928) (xy 179.380388 -305.874928)
			(xy 179.379893 -305.899535) (xy 179.371998 -305.948112) (xy 179.356414 -305.994793) (xy 179.333543 -306.03837)
			(xy 179.303978 -306.077714) (xy 179.268485 -306.111806) (xy 179.227982 -306.139762) (xy 179.18352 -306.16086)
			(xy 179.136249 -306.174552) (xy 179.087394 -306.180484) (xy 179.038219 -306.178503) (xy 178.99 -306.168659)
			(xy 178.943984 -306.151207) (xy 178.901363 -306.1266) (xy 178.863242 -306.095475) (xy 178.830607 -306.058638)
			(xy 178.804304 -306.017042) (xy 178.785013 -305.971766) (xy 178.773236 -305.923982) (xy 178.769276 -305.874928)
			(xy 178.430174 -305.874928) (xy 178.429679 -305.899535) (xy 178.421784 -305.948112) (xy 178.4062 -305.994793)
			(xy 178.383329 -306.03837) (xy 178.353764 -306.077714) (xy 178.318271 -306.111806) (xy 178.277768 -306.139762)
			(xy 178.233306 -306.16086) (xy 178.186035 -306.174552) (xy 178.13718 -306.180484) (xy 178.088005 -306.178503)
			(xy 178.039786 -306.168659) (xy 177.99377 -306.151207) (xy 177.951149 -306.1266) (xy 177.913028 -306.095475)
			(xy 177.880393 -306.058638) (xy 177.85409 -306.017042) (xy 177.834799 -305.971766) (xy 177.823022 -305.923982)
			(xy 177.819062 -305.874928) (xy 177.480214 -305.874928) (xy 177.479719 -305.899535) (xy 177.471824 -305.948112)
			(xy 177.45624 -305.994793) (xy 177.433369 -306.03837) (xy 177.403804 -306.077714) (xy 177.368311 -306.111806)
			(xy 177.327808 -306.139762) (xy 177.283346 -306.16086) (xy 177.236075 -306.174552) (xy 177.18722 -306.180484)
			(xy 177.138045 -306.178503) (xy 177.089826 -306.168659) (xy 177.04381 -306.151207) (xy 177.001189 -306.1266)
			(xy 176.963068 -306.095475) (xy 176.930433 -306.058638) (xy 176.90413 -306.017042) (xy 176.884839 -305.971766)
			(xy 176.873062 -305.923982) (xy 176.869102 -305.874928) (xy 176.530254 -305.874928) (xy 176.529759 -305.899535)
			(xy 176.521864 -305.948112) (xy 176.50628 -305.994793) (xy 176.483409 -306.03837) (xy 176.453844 -306.077714)
			(xy 176.418351 -306.111806) (xy 176.377848 -306.139762) (xy 176.333386 -306.16086) (xy 176.286115 -306.174552)
			(xy 176.23726 -306.180484) (xy 176.188085 -306.178503) (xy 176.139866 -306.168659) (xy 176.09385 -306.151207)
			(xy 176.051229 -306.1266) (xy 176.013108 -306.095475) (xy 175.980473 -306.058638) (xy 175.95417 -306.017042)
			(xy 175.934879 -305.971766) (xy 175.923102 -305.923982) (xy 175.919142 -305.874928) (xy 174.630334 -305.874928)
			(xy 174.629839 -305.899535) (xy 174.621944 -305.948112) (xy 174.60636 -305.994793) (xy 174.583489 -306.03837)
			(xy 174.553924 -306.077714) (xy 174.518431 -306.111806) (xy 174.477928 -306.139762) (xy 174.433466 -306.16086)
			(xy 174.386195 -306.174552) (xy 174.33734 -306.180484) (xy 174.288165 -306.178503) (xy 174.239946 -306.168659)
			(xy 174.19393 -306.151207) (xy 174.151309 -306.1266) (xy 174.113188 -306.095475) (xy 174.080553 -306.058638)
			(xy 174.05425 -306.017042) (xy 174.034959 -305.971766) (xy 174.023182 -305.923982) (xy 174.019222 -305.874928)
			(xy 173.680374 -305.874928) (xy 173.679879 -305.899535) (xy 173.671984 -305.948112) (xy 173.6564 -305.994793)
			(xy 173.633529 -306.03837) (xy 173.603964 -306.077714) (xy 173.568471 -306.111806) (xy 173.527968 -306.139762)
			(xy 173.483506 -306.16086) (xy 173.436235 -306.174552) (xy 173.38738 -306.180484) (xy 173.338205 -306.178503)
			(xy 173.289986 -306.168659) (xy 173.24397 -306.151207) (xy 173.201349 -306.1266) (xy 173.163228 -306.095475)
			(xy 173.130593 -306.058638) (xy 173.10429 -306.017042) (xy 173.084999 -305.971766) (xy 173.073222 -305.923982)
			(xy 173.069262 -305.874928) (xy 172.73016 -305.874928) (xy 172.729665 -305.899535) (xy 172.72177 -305.948112)
			(xy 172.706186 -305.994793) (xy 172.683315 -306.03837) (xy 172.65375 -306.077714) (xy 172.618257 -306.111806)
			(xy 172.577754 -306.139762) (xy 172.533292 -306.16086) (xy 172.486021 -306.174552) (xy 172.437166 -306.180484)
			(xy 172.387991 -306.178503) (xy 172.339772 -306.168659) (xy 172.293756 -306.151207) (xy 172.251135 -306.1266)
			(xy 172.213014 -306.095475) (xy 172.180379 -306.058638) (xy 172.154076 -306.017042) (xy 172.134785 -305.971766)
			(xy 172.123008 -305.923982) (xy 172.119048 -305.874928) (xy 171.7802 -305.874928) (xy 171.779705 -305.899535)
			(xy 171.77181 -305.948112) (xy 171.756226 -305.994793) (xy 171.733355 -306.03837) (xy 171.70379 -306.077714)
			(xy 171.668297 -306.111806) (xy 171.627794 -306.139762) (xy 171.583332 -306.16086) (xy 171.536061 -306.174552)
			(xy 171.487206 -306.180484) (xy 171.438031 -306.178503) (xy 171.389812 -306.168659) (xy 171.343796 -306.151207)
			(xy 171.301175 -306.1266) (xy 171.263054 -306.095475) (xy 171.230419 -306.058638) (xy 171.204116 -306.017042)
			(xy 171.184825 -305.971766) (xy 171.173048 -305.923982) (xy 171.169088 -305.874928) (xy 170.83024 -305.874928)
			(xy 170.829745 -305.899535) (xy 170.82185 -305.948112) (xy 170.806266 -305.994793) (xy 170.783395 -306.03837)
			(xy 170.75383 -306.077714) (xy 170.718337 -306.111806) (xy 170.677834 -306.139762) (xy 170.633372 -306.16086)
			(xy 170.586101 -306.174552) (xy 170.537246 -306.180484) (xy 170.488071 -306.178503) (xy 170.439852 -306.168659)
			(xy 170.393836 -306.151207) (xy 170.351215 -306.1266) (xy 170.313094 -306.095475) (xy 170.280459 -306.058638)
			(xy 170.254156 -306.017042) (xy 170.234865 -305.971766) (xy 170.223088 -305.923982) (xy 170.219128 -305.874928)
			(xy 169.88028 -305.874928) (xy 169.879785 -305.899535) (xy 169.87189 -305.948112) (xy 169.856306 -305.994793)
			(xy 169.833435 -306.03837) (xy 169.80387 -306.077714) (xy 169.768377 -306.111806) (xy 169.727874 -306.139762)
			(xy 169.683412 -306.16086) (xy 169.636141 -306.174552) (xy 169.587286 -306.180484) (xy 169.538111 -306.178503)
			(xy 169.489892 -306.168659) (xy 169.443876 -306.151207) (xy 169.401255 -306.1266) (xy 169.363134 -306.095475)
			(xy 169.330499 -306.058638) (xy 169.304196 -306.017042) (xy 169.284905 -305.971766) (xy 169.273128 -305.923982)
			(xy 169.269168 -305.874928) (xy 168.93032 -305.874928) (xy 168.929825 -305.899535) (xy 168.92193 -305.948112)
			(xy 168.906346 -305.994793) (xy 168.883475 -306.03837) (xy 168.85391 -306.077714) (xy 168.818417 -306.111806)
			(xy 168.777914 -306.139762) (xy 168.733452 -306.16086) (xy 168.686181 -306.174552) (xy 168.637326 -306.180484)
			(xy 168.588151 -306.178503) (xy 168.539932 -306.168659) (xy 168.493916 -306.151207) (xy 168.451295 -306.1266)
			(xy 168.413174 -306.095475) (xy 168.380539 -306.058638) (xy 168.354236 -306.017042) (xy 168.334945 -305.971766)
			(xy 168.323168 -305.923982) (xy 168.319208 -305.874928) (xy 167.98036 -305.874928) (xy 167.979865 -305.899535)
			(xy 167.97197 -305.948112) (xy 167.956386 -305.994793) (xy 167.933515 -306.03837) (xy 167.90395 -306.077714)
			(xy 167.868457 -306.111806) (xy 167.827954 -306.139762) (xy 167.783492 -306.16086) (xy 167.736221 -306.174552)
			(xy 167.687366 -306.180484) (xy 167.638191 -306.178503) (xy 167.589972 -306.168659) (xy 167.543956 -306.151207)
			(xy 167.501335 -306.1266) (xy 167.463214 -306.095475) (xy 167.430579 -306.058638) (xy 167.404276 -306.017042)
			(xy 167.384985 -305.971766) (xy 167.373208 -305.923982) (xy 167.369248 -305.874928) (xy 167.0304 -305.874928)
			(xy 167.029905 -305.899535) (xy 167.02201 -305.948112) (xy 167.006426 -305.994793) (xy 166.983555 -306.03837)
			(xy 166.95399 -306.077714) (xy 166.918497 -306.111806) (xy 166.877994 -306.139762) (xy 166.833532 -306.16086)
			(xy 166.786261 -306.174552) (xy 166.737406 -306.180484) (xy 166.688231 -306.178503) (xy 166.640012 -306.168659)
			(xy 166.593996 -306.151207) (xy 166.551375 -306.1266) (xy 166.513254 -306.095475) (xy 166.480619 -306.058638)
			(xy 166.454316 -306.017042) (xy 166.435025 -305.971766) (xy 166.423248 -305.923982) (xy 166.419288 -305.874928)
			(xy 166.080186 -305.874928) (xy 166.079691 -305.899535) (xy 166.071796 -305.948112) (xy 166.056212 -305.994793)
			(xy 166.033341 -306.03837) (xy 166.003776 -306.077714) (xy 165.968283 -306.111806) (xy 165.92778 -306.139762)
			(xy 165.883318 -306.16086) (xy 165.836047 -306.174552) (xy 165.787192 -306.180484) (xy 165.738017 -306.178503)
			(xy 165.689798 -306.168659) (xy 165.643782 -306.151207) (xy 165.601161 -306.1266) (xy 165.56304 -306.095475)
			(xy 165.530405 -306.058638) (xy 165.504102 -306.017042) (xy 165.484811 -305.971766) (xy 165.473034 -305.923982)
			(xy 165.469074 -305.874928) (xy 165.130226 -305.874928) (xy 165.129731 -305.899535) (xy 165.121836 -305.948112)
			(xy 165.106252 -305.994793) (xy 165.083381 -306.03837) (xy 165.053816 -306.077714) (xy 165.018323 -306.111806)
			(xy 164.97782 -306.139762) (xy 164.933358 -306.16086) (xy 164.886087 -306.174552) (xy 164.837232 -306.180484)
			(xy 164.788057 -306.178503) (xy 164.739838 -306.168659) (xy 164.693822 -306.151207) (xy 164.651201 -306.1266)
			(xy 164.61308 -306.095475) (xy 164.580445 -306.058638) (xy 164.554142 -306.017042) (xy 164.534851 -305.971766)
			(xy 164.523074 -305.923982) (xy 164.519114 -305.874928) (xy 164.180266 -305.874928) (xy 164.179771 -305.899535)
			(xy 164.171876 -305.948112) (xy 164.156292 -305.994793) (xy 164.133421 -306.03837) (xy 164.103856 -306.077714)
			(xy 164.068363 -306.111806) (xy 164.02786 -306.139762) (xy 163.983398 -306.16086) (xy 163.936127 -306.174552)
			(xy 163.887272 -306.180484) (xy 163.838097 -306.178503) (xy 163.789878 -306.168659) (xy 163.743862 -306.151207)
			(xy 163.701241 -306.1266) (xy 163.66312 -306.095475) (xy 163.630485 -306.058638) (xy 163.604182 -306.017042)
			(xy 163.584891 -305.971766) (xy 163.573114 -305.923982) (xy 163.569154 -305.874928) (xy 163.230306 -305.874928)
			(xy 163.229811 -305.899535) (xy 163.221916 -305.948112) (xy 163.206332 -305.994793) (xy 163.183461 -306.03837)
			(xy 163.153896 -306.077714) (xy 163.118403 -306.111806) (xy 163.0779 -306.139762) (xy 163.033438 -306.16086)
			(xy 162.986167 -306.174552) (xy 162.937312 -306.180484) (xy 162.888137 -306.178503) (xy 162.839918 -306.168659)
			(xy 162.793902 -306.151207) (xy 162.751281 -306.1266) (xy 162.71316 -306.095475) (xy 162.680525 -306.058638)
			(xy 162.654222 -306.017042) (xy 162.634931 -305.971766) (xy 162.623154 -305.923982) (xy 162.619194 -305.874928)
			(xy 143.510378 -305.874928) (xy 143.529753 -305.916259) (xy 143.545821 -305.969666) (xy 143.553941 -306.024842)
			(xy 143.55445 -306.052728) (xy 143.553941 -306.080614) (xy 143.545821 -306.13579) (xy 143.529753 -306.189197)
			(xy 143.506081 -306.239694) (xy 143.475308 -306.286207) (xy 143.438091 -306.327744) (xy 143.411153 -306.350162)
			(xy 151.693892 -306.350162) (xy 151.697852 -306.301108) (xy 151.709629 -306.253324) (xy 151.72892 -306.208048)
			(xy 151.755223 -306.166452) (xy 151.787858 -306.129615) (xy 151.825979 -306.09849) (xy 151.8686 -306.073883)
			(xy 151.914616 -306.056431) (xy 151.962835 -306.046587) (xy 152.01201 -306.044606) (xy 152.060865 -306.050538)
			(xy 152.108136 -306.06423) (xy 152.152598 -306.085328) (xy 152.193101 -306.113284) (xy 152.228594 -306.147376)
			(xy 152.258159 -306.18672) (xy 152.28103 -306.230297) (xy 152.296614 -306.276978) (xy 152.304509 -306.325555)
			(xy 152.305004 -306.350162) (xy 152.304509 -306.374769) (xy 152.304371 -306.375616) (xy 152.623262 -306.375616)
			(xy 152.623262 -306.3242) (xy 152.631305 -306.273418) (xy 152.647193 -306.224519) (xy 152.670536 -306.178707)
			(xy 152.700757 -306.137111) (xy 152.737113 -306.100755) (xy 152.778709 -306.070534) (xy 152.824521 -306.047191)
			(xy 152.87342 -306.031303) (xy 152.924202 -306.02326) (xy 152.975618 -306.02326) (xy 153.0264 -306.031303)
			(xy 153.075299 -306.047191) (xy 153.121111 -306.070534) (xy 153.162707 -306.100755) (xy 153.199063 -306.137111)
			(xy 153.229284 -306.178707) (xy 153.252627 -306.224519) (xy 153.268515 -306.273418) (xy 153.276558 -306.3242)
			(xy 153.277062 -306.349908) (xy 153.276558 -306.375616) (xy 153.573222 -306.375616) (xy 153.573222 -306.3242)
			(xy 153.581265 -306.273418) (xy 153.597153 -306.224519) (xy 153.620496 -306.178707) (xy 153.650717 -306.137111)
			(xy 153.687073 -306.100755) (xy 153.728669 -306.070534) (xy 153.774481 -306.047191) (xy 153.82338 -306.031303)
			(xy 153.874162 -306.02326) (xy 153.925578 -306.02326) (xy 153.97636 -306.031303) (xy 154.025259 -306.047191)
			(xy 154.071071 -306.070534) (xy 154.112667 -306.100755) (xy 154.149023 -306.137111) (xy 154.179244 -306.178707)
			(xy 154.202587 -306.224519) (xy 154.218475 -306.273418) (xy 154.226518 -306.3242) (xy 154.227022 -306.349908)
			(xy 154.54428 -306.349908) (xy 154.54824 -306.300854) (xy 154.560017 -306.25307) (xy 154.579308 -306.207794)
			(xy 154.605611 -306.166198) (xy 154.638246 -306.129361) (xy 154.676367 -306.098236) (xy 154.718988 -306.073629)
			(xy 154.765004 -306.056177) (xy 154.813223 -306.046333) (xy 154.862398 -306.044352) (xy 154.911253 -306.050284)
			(xy 154.958524 -306.063976) (xy 155.002986 -306.085074) (xy 155.043489 -306.11303) (xy 155.078982 -306.147122)
			(xy 155.108547 -306.186466) (xy 155.131418 -306.230043) (xy 155.147002 -306.276724) (xy 155.154897 -306.325301)
			(xy 155.155392 -306.349908) (xy 155.49424 -306.349908) (xy 155.4982 -306.300854) (xy 155.509977 -306.25307)
			(xy 155.529268 -306.207794) (xy 155.555571 -306.166198) (xy 155.588206 -306.129361) (xy 155.626327 -306.098236)
			(xy 155.668948 -306.073629) (xy 155.714964 -306.056177) (xy 155.763183 -306.046333) (xy 155.812358 -306.044352)
			(xy 155.861213 -306.050284) (xy 155.908484 -306.063976) (xy 155.952946 -306.085074) (xy 155.993449 -306.11303)
			(xy 156.028942 -306.147122) (xy 156.058507 -306.186466) (xy 156.081378 -306.230043) (xy 156.096962 -306.276724)
			(xy 156.104857 -306.325301) (xy 156.105352 -306.349908) (xy 156.4442 -306.349908) (xy 156.44816 -306.300854)
			(xy 156.459937 -306.25307) (xy 156.479228 -306.207794) (xy 156.505531 -306.166198) (xy 156.538166 -306.129361)
			(xy 156.576287 -306.098236) (xy 156.618908 -306.073629) (xy 156.664924 -306.056177) (xy 156.713143 -306.046333)
			(xy 156.762318 -306.044352) (xy 156.811173 -306.050284) (xy 156.858444 -306.063976) (xy 156.902906 -306.085074)
			(xy 156.943409 -306.11303) (xy 156.978902 -306.147122) (xy 157.008467 -306.186466) (xy 157.031338 -306.230043)
			(xy 157.046922 -306.276724) (xy 157.054817 -306.325301) (xy 157.055312 -306.349908) (xy 157.39416 -306.349908)
			(xy 157.39812 -306.300854) (xy 157.409897 -306.25307) (xy 157.429188 -306.207794) (xy 157.455491 -306.166198)
			(xy 157.488126 -306.129361) (xy 157.526247 -306.098236) (xy 157.568868 -306.073629) (xy 157.614884 -306.056177)
			(xy 157.663103 -306.046333) (xy 157.712278 -306.044352) (xy 157.761133 -306.050284) (xy 157.808404 -306.063976)
			(xy 157.852866 -306.085074) (xy 157.893369 -306.11303) (xy 157.928862 -306.147122) (xy 157.958427 -306.186466)
			(xy 157.981298 -306.230043) (xy 157.996882 -306.276724) (xy 158.004777 -306.325301) (xy 158.005272 -306.349908)
			(xy 158.34412 -306.349908) (xy 158.34808 -306.300854) (xy 158.359857 -306.25307) (xy 158.379148 -306.207794)
			(xy 158.405451 -306.166198) (xy 158.438086 -306.129361) (xy 158.476207 -306.098236) (xy 158.518828 -306.073629)
			(xy 158.564844 -306.056177) (xy 158.613063 -306.046333) (xy 158.662238 -306.044352) (xy 158.711093 -306.050284)
			(xy 158.758364 -306.063976) (xy 158.802826 -306.085074) (xy 158.843329 -306.11303) (xy 158.878822 -306.147122)
			(xy 158.908387 -306.186466) (xy 158.931258 -306.230043) (xy 158.946842 -306.276724) (xy 158.954737 -306.325301)
			(xy 158.955232 -306.349908) (xy 158.954737 -306.374515) (xy 158.954558 -306.375616) (xy 159.273236 -306.375616)
			(xy 159.273236 -306.3242) (xy 159.281279 -306.273418) (xy 159.297167 -306.224519) (xy 159.32051 -306.178707)
			(xy 159.350731 -306.137111) (xy 159.387087 -306.100755) (xy 159.428683 -306.070534) (xy 159.474495 -306.047191)
			(xy 159.523394 -306.031303) (xy 159.574176 -306.02326) (xy 159.625592 -306.02326) (xy 159.676374 -306.031303)
			(xy 159.725273 -306.047191) (xy 159.771085 -306.070534) (xy 159.812681 -306.100755) (xy 159.849037 -306.137111)
			(xy 159.879258 -306.178707) (xy 159.902601 -306.224519) (xy 159.918489 -306.273418) (xy 159.926532 -306.3242)
			(xy 159.927036 -306.349908) (xy 159.926532 -306.375616) (xy 160.223196 -306.375616) (xy 160.223196 -306.3242)
			(xy 160.231239 -306.273418) (xy 160.247127 -306.224519) (xy 160.27047 -306.178707) (xy 160.300691 -306.137111)
			(xy 160.337047 -306.100755) (xy 160.378643 -306.070534) (xy 160.424455 -306.047191) (xy 160.473354 -306.031303)
			(xy 160.524136 -306.02326) (xy 160.575552 -306.02326) (xy 160.626334 -306.031303) (xy 160.675233 -306.047191)
			(xy 160.721045 -306.070534) (xy 160.762641 -306.100755) (xy 160.798997 -306.137111) (xy 160.829218 -306.178707)
			(xy 160.852561 -306.224519) (xy 160.868449 -306.273418) (xy 160.876492 -306.3242) (xy 160.876996 -306.349908)
			(xy 161.194254 -306.349908) (xy 161.198214 -306.300854) (xy 161.209991 -306.25307) (xy 161.229282 -306.207794)
			(xy 161.255585 -306.166198) (xy 161.28822 -306.129361) (xy 161.326341 -306.098236) (xy 161.368962 -306.073629)
			(xy 161.414978 -306.056177) (xy 161.463197 -306.046333) (xy 161.512372 -306.044352) (xy 161.561227 -306.050284)
			(xy 161.608498 -306.063976) (xy 161.65296 -306.085074) (xy 161.693463 -306.11303) (xy 161.728956 -306.147122)
			(xy 161.758521 -306.186466) (xy 161.781392 -306.230043) (xy 161.796976 -306.276724) (xy 161.804871 -306.325301)
			(xy 161.805366 -306.349908) (xy 161.804871 -306.374515) (xy 161.796976 -306.423092) (xy 161.781392 -306.469773)
			(xy 161.758521 -306.51335) (xy 161.728956 -306.552694) (xy 161.693463 -306.586786) (xy 161.65296 -306.614742)
			(xy 161.608498 -306.63584) (xy 161.561227 -306.649532) (xy 161.512372 -306.655464) (xy 161.463197 -306.653483)
			(xy 161.414978 -306.643639) (xy 161.368962 -306.626187) (xy 161.326341 -306.60158) (xy 161.28822 -306.570455)
			(xy 161.255585 -306.533618) (xy 161.229282 -306.492022) (xy 161.209991 -306.446746) (xy 161.198214 -306.398962)
			(xy 161.194254 -306.349908) (xy 160.876996 -306.349908) (xy 160.876492 -306.375616) (xy 160.868449 -306.426398)
			(xy 160.852561 -306.475297) (xy 160.829218 -306.521109) (xy 160.798997 -306.562705) (xy 160.762641 -306.599061)
			(xy 160.721045 -306.629282) (xy 160.675233 -306.652625) (xy 160.626334 -306.668513) (xy 160.575552 -306.676556)
			(xy 160.524136 -306.676556) (xy 160.473354 -306.668513) (xy 160.424455 -306.652625) (xy 160.378643 -306.629282)
			(xy 160.337047 -306.599061) (xy 160.300691 -306.562705) (xy 160.27047 -306.521109) (xy 160.247127 -306.475297)
			(xy 160.231239 -306.426398) (xy 160.223196 -306.375616) (xy 159.926532 -306.375616) (xy 159.918489 -306.426398)
			(xy 159.902601 -306.475297) (xy 159.879258 -306.521109) (xy 159.849037 -306.562705) (xy 159.812681 -306.599061)
			(xy 159.771085 -306.629282) (xy 159.725273 -306.652625) (xy 159.676374 -306.668513) (xy 159.625592 -306.676556)
			(xy 159.574176 -306.676556) (xy 159.523394 -306.668513) (xy 159.474495 -306.652625) (xy 159.428683 -306.629282)
			(xy 159.387087 -306.599061) (xy 159.350731 -306.562705) (xy 159.32051 -306.521109) (xy 159.297167 -306.475297)
			(xy 159.281279 -306.426398) (xy 159.273236 -306.375616) (xy 158.954558 -306.375616) (xy 158.946842 -306.423092)
			(xy 158.931258 -306.469773) (xy 158.908387 -306.51335) (xy 158.878822 -306.552694) (xy 158.843329 -306.586786)
			(xy 158.802826 -306.614742) (xy 158.758364 -306.63584) (xy 158.711093 -306.649532) (xy 158.662238 -306.655464)
			(xy 158.613063 -306.653483) (xy 158.564844 -306.643639) (xy 158.518828 -306.626187) (xy 158.476207 -306.60158)
			(xy 158.438086 -306.570455) (xy 158.405451 -306.533618) (xy 158.379148 -306.492022) (xy 158.359857 -306.446746)
			(xy 158.34808 -306.398962) (xy 158.34412 -306.349908) (xy 158.005272 -306.349908) (xy 158.004777 -306.374515)
			(xy 157.996882 -306.423092) (xy 157.981298 -306.469773) (xy 157.958427 -306.51335) (xy 157.928862 -306.552694)
			(xy 157.893369 -306.586786) (xy 157.852866 -306.614742) (xy 157.808404 -306.63584) (xy 157.761133 -306.649532)
			(xy 157.712278 -306.655464) (xy 157.663103 -306.653483) (xy 157.614884 -306.643639) (xy 157.568868 -306.626187)
			(xy 157.526247 -306.60158) (xy 157.488126 -306.570455) (xy 157.455491 -306.533618) (xy 157.429188 -306.492022)
			(xy 157.409897 -306.446746) (xy 157.39812 -306.398962) (xy 157.39416 -306.349908) (xy 157.055312 -306.349908)
			(xy 157.054817 -306.374515) (xy 157.046922 -306.423092) (xy 157.031338 -306.469773) (xy 157.008467 -306.51335)
			(xy 156.978902 -306.552694) (xy 156.943409 -306.586786) (xy 156.902906 -306.614742) (xy 156.858444 -306.63584)
			(xy 156.811173 -306.649532) (xy 156.762318 -306.655464) (xy 156.713143 -306.653483) (xy 156.664924 -306.643639)
			(xy 156.618908 -306.626187) (xy 156.576287 -306.60158) (xy 156.538166 -306.570455) (xy 156.505531 -306.533618)
			(xy 156.479228 -306.492022) (xy 156.459937 -306.446746) (xy 156.44816 -306.398962) (xy 156.4442 -306.349908)
			(xy 156.105352 -306.349908) (xy 156.104857 -306.374515) (xy 156.096962 -306.423092) (xy 156.081378 -306.469773)
			(xy 156.058507 -306.51335) (xy 156.028942 -306.552694) (xy 155.993449 -306.586786) (xy 155.952946 -306.614742)
			(xy 155.908484 -306.63584) (xy 155.861213 -306.649532) (xy 155.812358 -306.655464) (xy 155.763183 -306.653483)
			(xy 155.714964 -306.643639) (xy 155.668948 -306.626187) (xy 155.626327 -306.60158) (xy 155.588206 -306.570455)
			(xy 155.555571 -306.533618) (xy 155.529268 -306.492022) (xy 155.509977 -306.446746) (xy 155.4982 -306.398962)
			(xy 155.49424 -306.349908) (xy 155.155392 -306.349908) (xy 155.154897 -306.374515) (xy 155.147002 -306.423092)
			(xy 155.131418 -306.469773) (xy 155.108547 -306.51335) (xy 155.078982 -306.552694) (xy 155.043489 -306.586786)
			(xy 155.002986 -306.614742) (xy 154.958524 -306.63584) (xy 154.911253 -306.649532) (xy 154.862398 -306.655464)
			(xy 154.813223 -306.653483) (xy 154.765004 -306.643639) (xy 154.718988 -306.626187) (xy 154.676367 -306.60158)
			(xy 154.638246 -306.570455) (xy 154.605611 -306.533618) (xy 154.579308 -306.492022) (xy 154.560017 -306.446746)
			(xy 154.54824 -306.398962) (xy 154.54428 -306.349908) (xy 154.227022 -306.349908) (xy 154.226518 -306.375616)
			(xy 154.218475 -306.426398) (xy 154.202587 -306.475297) (xy 154.179244 -306.521109) (xy 154.149023 -306.562705)
			(xy 154.112667 -306.599061) (xy 154.071071 -306.629282) (xy 154.025259 -306.652625) (xy 153.97636 -306.668513)
			(xy 153.925578 -306.676556) (xy 153.874162 -306.676556) (xy 153.82338 -306.668513) (xy 153.774481 -306.652625)
			(xy 153.728669 -306.629282) (xy 153.687073 -306.599061) (xy 153.650717 -306.562705) (xy 153.620496 -306.521109)
			(xy 153.597153 -306.475297) (xy 153.581265 -306.426398) (xy 153.573222 -306.375616) (xy 153.276558 -306.375616)
			(xy 153.268515 -306.426398) (xy 153.252627 -306.475297) (xy 153.229284 -306.521109) (xy 153.199063 -306.562705)
			(xy 153.162707 -306.599061) (xy 153.121111 -306.629282) (xy 153.075299 -306.652625) (xy 153.0264 -306.668513)
			(xy 152.975618 -306.676556) (xy 152.924202 -306.676556) (xy 152.87342 -306.668513) (xy 152.824521 -306.652625)
			(xy 152.778709 -306.629282) (xy 152.737113 -306.599061) (xy 152.700757 -306.562705) (xy 152.670536 -306.521109)
			(xy 152.647193 -306.475297) (xy 152.631305 -306.426398) (xy 152.623262 -306.375616) (xy 152.304371 -306.375616)
			(xy 152.296614 -306.423346) (xy 152.28103 -306.470027) (xy 152.258159 -306.513604) (xy 152.228594 -306.552948)
			(xy 152.193101 -306.58704) (xy 152.152598 -306.614996) (xy 152.108136 -306.636094) (xy 152.060865 -306.649786)
			(xy 152.01201 -306.655718) (xy 151.962835 -306.653737) (xy 151.914616 -306.643893) (xy 151.8686 -306.626441)
			(xy 151.825979 -306.601834) (xy 151.787858 -306.570709) (xy 151.755223 -306.533872) (xy 151.72892 -306.492276)
			(xy 151.709629 -306.447) (xy 151.697852 -306.399216) (xy 151.693892 -306.350162) (xy 143.411153 -306.350162)
			(xy 143.395223 -306.363419) (xy 143.347617 -306.392473) (xy 143.296288 -306.414285) (xy 143.242331 -306.428391)
			(xy 143.186894 -306.434491) (xy 143.13116 -306.432454) (xy 143.076317 -306.422324) (xy 143.023533 -306.404317)
			(xy 142.973933 -306.378816) (xy 142.928575 -306.346365) (xy 142.888426 -306.307656) (xy 142.85434 -306.263513)
			(xy 142.827044 -306.214878) (xy 142.807121 -306.162787) (xy 142.794995 -306.10835) (xy 142.790924 -306.052728)
			(xy 132.644217 -306.052728) (xy 132.643995 -306.054269) (xy 132.628501 -306.106773) (xy 132.605655 -306.15652)
			(xy 132.575926 -306.202485) (xy 132.558282 -306.223416) (xy 132.552186 -306.230528) (xy 132.545836 -306.247546)
			(xy 132.545836 -306.33289) (xy 132.552186 -306.349908) (xy 132.558282 -306.35702) (xy 132.57594 -306.377939)
			(xy 132.605663 -306.423909) (xy 132.628507 -306.473658) (xy 132.644002 -306.526162) (xy 132.651828 -306.580342)
			(xy 132.651826 -306.635085) (xy 132.643996 -306.689265) (xy 132.628498 -306.741768) (xy 132.617737 -306.765198)
			(xy 145.825462 -306.765198) (xy 145.829533 -306.709576) (xy 145.841659 -306.655139) (xy 145.861582 -306.603048)
			(xy 145.888878 -306.554413) (xy 145.922964 -306.51027) (xy 145.963113 -306.471561) (xy 146.008471 -306.43911)
			(xy 146.058071 -306.413609) (xy 146.110855 -306.395602) (xy 146.165698 -306.385472) (xy 146.221432 -306.383435)
			(xy 146.276869 -306.389535) (xy 146.330826 -306.403641) (xy 146.382155 -306.425453) (xy 146.429761 -306.454507)
			(xy 146.472629 -306.490182) (xy 146.509846 -306.531719) (xy 146.540619 -306.578232) (xy 146.564291 -306.628729)
			(xy 146.580359 -306.682136) (xy 146.588479 -306.737312) (xy 146.588988 -306.765198) (xy 146.588479 -306.793084)
			(xy 146.583799 -306.824888) (xy 162.619194 -306.824888) (xy 162.623154 -306.775834) (xy 162.634931 -306.72805)
			(xy 162.654222 -306.682774) (xy 162.680525 -306.641178) (xy 162.71316 -306.604341) (xy 162.751281 -306.573216)
			(xy 162.793902 -306.548609) (xy 162.839918 -306.531157) (xy 162.888137 -306.521313) (xy 162.937312 -306.519332)
			(xy 162.986167 -306.525264) (xy 163.033438 -306.538956) (xy 163.0779 -306.560054) (xy 163.118403 -306.58801)
			(xy 163.153896 -306.622102) (xy 163.183461 -306.661446) (xy 163.206332 -306.705023) (xy 163.221916 -306.751704)
			(xy 163.229811 -306.800281) (xy 163.230306 -306.824888) (xy 163.569154 -306.824888) (xy 163.573114 -306.775834)
			(xy 163.584891 -306.72805) (xy 163.604182 -306.682774) (xy 163.630485 -306.641178) (xy 163.66312 -306.604341)
			(xy 163.701241 -306.573216) (xy 163.743862 -306.548609) (xy 163.789878 -306.531157) (xy 163.838097 -306.521313)
			(xy 163.887272 -306.519332) (xy 163.936127 -306.525264) (xy 163.983398 -306.538956) (xy 164.02786 -306.560054)
			(xy 164.068363 -306.58801) (xy 164.103856 -306.622102) (xy 164.133421 -306.661446) (xy 164.156292 -306.705023)
			(xy 164.171876 -306.751704) (xy 164.179771 -306.800281) (xy 164.180266 -306.824888) (xy 164.519114 -306.824888)
			(xy 164.523074 -306.775834) (xy 164.534851 -306.72805) (xy 164.554142 -306.682774) (xy 164.580445 -306.641178)
			(xy 164.61308 -306.604341) (xy 164.651201 -306.573216) (xy 164.693822 -306.548609) (xy 164.739838 -306.531157)
			(xy 164.788057 -306.521313) (xy 164.837232 -306.519332) (xy 164.886087 -306.525264) (xy 164.933358 -306.538956)
			(xy 164.97782 -306.560054) (xy 165.018323 -306.58801) (xy 165.053816 -306.622102) (xy 165.083381 -306.661446)
			(xy 165.106252 -306.705023) (xy 165.121836 -306.751704) (xy 165.129731 -306.800281) (xy 165.130226 -306.824888)
			(xy 165.469074 -306.824888) (xy 165.473034 -306.775834) (xy 165.484811 -306.72805) (xy 165.504102 -306.682774)
			(xy 165.530405 -306.641178) (xy 165.56304 -306.604341) (xy 165.601161 -306.573216) (xy 165.643782 -306.548609)
			(xy 165.689798 -306.531157) (xy 165.738017 -306.521313) (xy 165.787192 -306.519332) (xy 165.836047 -306.525264)
			(xy 165.883318 -306.538956) (xy 165.92778 -306.560054) (xy 165.968283 -306.58801) (xy 166.003776 -306.622102)
			(xy 166.033341 -306.661446) (xy 166.056212 -306.705023) (xy 166.071796 -306.751704) (xy 166.079691 -306.800281)
			(xy 166.080186 -306.824888) (xy 166.419288 -306.824888) (xy 166.423248 -306.775834) (xy 166.435025 -306.72805)
			(xy 166.454316 -306.682774) (xy 166.480619 -306.641178) (xy 166.513254 -306.604341) (xy 166.551375 -306.573216)
			(xy 166.593996 -306.548609) (xy 166.640012 -306.531157) (xy 166.688231 -306.521313) (xy 166.737406 -306.519332)
			(xy 166.786261 -306.525264) (xy 166.833532 -306.538956) (xy 166.877994 -306.560054) (xy 166.918497 -306.58801)
			(xy 166.95399 -306.622102) (xy 166.983555 -306.661446) (xy 167.006426 -306.705023) (xy 167.02201 -306.751704)
			(xy 167.029905 -306.800281) (xy 167.0304 -306.824888) (xy 167.369248 -306.824888) (xy 167.373208 -306.775834)
			(xy 167.384985 -306.72805) (xy 167.404276 -306.682774) (xy 167.430579 -306.641178) (xy 167.463214 -306.604341)
			(xy 167.501335 -306.573216) (xy 167.543956 -306.548609) (xy 167.589972 -306.531157) (xy 167.638191 -306.521313)
			(xy 167.687366 -306.519332) (xy 167.736221 -306.525264) (xy 167.783492 -306.538956) (xy 167.827954 -306.560054)
			(xy 167.868457 -306.58801) (xy 167.90395 -306.622102) (xy 167.933515 -306.661446) (xy 167.956386 -306.705023)
			(xy 167.97197 -306.751704) (xy 167.979865 -306.800281) (xy 167.98036 -306.824888) (xy 168.319208 -306.824888)
			(xy 168.323168 -306.775834) (xy 168.334945 -306.72805) (xy 168.354236 -306.682774) (xy 168.380539 -306.641178)
			(xy 168.413174 -306.604341) (xy 168.451295 -306.573216) (xy 168.493916 -306.548609) (xy 168.539932 -306.531157)
			(xy 168.588151 -306.521313) (xy 168.637326 -306.519332) (xy 168.686181 -306.525264) (xy 168.733452 -306.538956)
			(xy 168.777914 -306.560054) (xy 168.818417 -306.58801) (xy 168.85391 -306.622102) (xy 168.883475 -306.661446)
			(xy 168.906346 -306.705023) (xy 168.92193 -306.751704) (xy 168.929825 -306.800281) (xy 168.93032 -306.824888)
			(xy 169.269168 -306.824888) (xy 169.273128 -306.775834) (xy 169.284905 -306.72805) (xy 169.304196 -306.682774)
			(xy 169.330499 -306.641178) (xy 169.363134 -306.604341) (xy 169.401255 -306.573216) (xy 169.443876 -306.548609)
			(xy 169.489892 -306.531157) (xy 169.538111 -306.521313) (xy 169.587286 -306.519332) (xy 169.636141 -306.525264)
			(xy 169.683412 -306.538956) (xy 169.727874 -306.560054) (xy 169.768377 -306.58801) (xy 169.80387 -306.622102)
			(xy 169.833435 -306.661446) (xy 169.856306 -306.705023) (xy 169.87189 -306.751704) (xy 169.879785 -306.800281)
			(xy 169.88028 -306.824888) (xy 170.219128 -306.824888) (xy 170.223088 -306.775834) (xy 170.234865 -306.72805)
			(xy 170.254156 -306.682774) (xy 170.280459 -306.641178) (xy 170.313094 -306.604341) (xy 170.351215 -306.573216)
			(xy 170.393836 -306.548609) (xy 170.439852 -306.531157) (xy 170.488071 -306.521313) (xy 170.537246 -306.519332)
			(xy 170.586101 -306.525264) (xy 170.633372 -306.538956) (xy 170.677834 -306.560054) (xy 170.718337 -306.58801)
			(xy 170.75383 -306.622102) (xy 170.783395 -306.661446) (xy 170.806266 -306.705023) (xy 170.82185 -306.751704)
			(xy 170.829745 -306.800281) (xy 170.83024 -306.824888) (xy 171.169088 -306.824888) (xy 171.173048 -306.775834)
			(xy 171.184825 -306.72805) (xy 171.204116 -306.682774) (xy 171.230419 -306.641178) (xy 171.263054 -306.604341)
			(xy 171.301175 -306.573216) (xy 171.343796 -306.548609) (xy 171.389812 -306.531157) (xy 171.438031 -306.521313)
			(xy 171.487206 -306.519332) (xy 171.536061 -306.525264) (xy 171.583332 -306.538956) (xy 171.627794 -306.560054)
			(xy 171.668297 -306.58801) (xy 171.70379 -306.622102) (xy 171.733355 -306.661446) (xy 171.756226 -306.705023)
			(xy 171.77181 -306.751704) (xy 171.779705 -306.800281) (xy 171.7802 -306.824888) (xy 172.119048 -306.824888)
			(xy 172.123008 -306.775834) (xy 172.134785 -306.72805) (xy 172.154076 -306.682774) (xy 172.180379 -306.641178)
			(xy 172.213014 -306.604341) (xy 172.251135 -306.573216) (xy 172.293756 -306.548609) (xy 172.339772 -306.531157)
			(xy 172.387991 -306.521313) (xy 172.437166 -306.519332) (xy 172.486021 -306.525264) (xy 172.533292 -306.538956)
			(xy 172.577754 -306.560054) (xy 172.618257 -306.58801) (xy 172.65375 -306.622102) (xy 172.683315 -306.661446)
			(xy 172.706186 -306.705023) (xy 172.72177 -306.751704) (xy 172.729665 -306.800281) (xy 172.73016 -306.824888)
			(xy 173.069262 -306.824888) (xy 173.073222 -306.775834) (xy 173.084999 -306.72805) (xy 173.10429 -306.682774)
			(xy 173.130593 -306.641178) (xy 173.163228 -306.604341) (xy 173.201349 -306.573216) (xy 173.24397 -306.548609)
			(xy 173.289986 -306.531157) (xy 173.338205 -306.521313) (xy 173.38738 -306.519332) (xy 173.436235 -306.525264)
			(xy 173.483506 -306.538956) (xy 173.527968 -306.560054) (xy 173.568471 -306.58801) (xy 173.603964 -306.622102)
			(xy 173.633529 -306.661446) (xy 173.6564 -306.705023) (xy 173.671984 -306.751704) (xy 173.679879 -306.800281)
			(xy 173.680374 -306.824888) (xy 174.019222 -306.824888) (xy 174.023182 -306.775834) (xy 174.034959 -306.72805)
			(xy 174.05425 -306.682774) (xy 174.080553 -306.641178) (xy 174.113188 -306.604341) (xy 174.151309 -306.573216)
			(xy 174.19393 -306.548609) (xy 174.239946 -306.531157) (xy 174.288165 -306.521313) (xy 174.33734 -306.519332)
			(xy 174.386195 -306.525264) (xy 174.433466 -306.538956) (xy 174.477928 -306.560054) (xy 174.518431 -306.58801)
			(xy 174.553924 -306.622102) (xy 174.583489 -306.661446) (xy 174.60636 -306.705023) (xy 174.621944 -306.751704)
			(xy 174.629839 -306.800281) (xy 174.630334 -306.824888) (xy 175.919142 -306.824888) (xy 175.923102 -306.775834)
			(xy 175.934879 -306.72805) (xy 175.95417 -306.682774) (xy 175.980473 -306.641178) (xy 176.013108 -306.604341)
			(xy 176.051229 -306.573216) (xy 176.09385 -306.548609) (xy 176.139866 -306.531157) (xy 176.188085 -306.521313)
			(xy 176.23726 -306.519332) (xy 176.286115 -306.525264) (xy 176.333386 -306.538956) (xy 176.377848 -306.560054)
			(xy 176.418351 -306.58801) (xy 176.453844 -306.622102) (xy 176.483409 -306.661446) (xy 176.50628 -306.705023)
			(xy 176.521864 -306.751704) (xy 176.529759 -306.800281) (xy 176.530254 -306.824888) (xy 176.869102 -306.824888)
			(xy 176.873062 -306.775834) (xy 176.884839 -306.72805) (xy 176.90413 -306.682774) (xy 176.930433 -306.641178)
			(xy 176.963068 -306.604341) (xy 177.001189 -306.573216) (xy 177.04381 -306.548609) (xy 177.089826 -306.531157)
			(xy 177.138045 -306.521313) (xy 177.18722 -306.519332) (xy 177.236075 -306.525264) (xy 177.283346 -306.538956)
			(xy 177.327808 -306.560054) (xy 177.368311 -306.58801) (xy 177.403804 -306.622102) (xy 177.433369 -306.661446)
			(xy 177.45624 -306.705023) (xy 177.471824 -306.751704) (xy 177.479719 -306.800281) (xy 177.480214 -306.824888)
			(xy 177.819062 -306.824888) (xy 177.823022 -306.775834) (xy 177.834799 -306.72805) (xy 177.85409 -306.682774)
			(xy 177.880393 -306.641178) (xy 177.913028 -306.604341) (xy 177.951149 -306.573216) (xy 177.99377 -306.548609)
			(xy 178.039786 -306.531157) (xy 178.088005 -306.521313) (xy 178.13718 -306.519332) (xy 178.186035 -306.525264)
			(xy 178.233306 -306.538956) (xy 178.277768 -306.560054) (xy 178.318271 -306.58801) (xy 178.353764 -306.622102)
			(xy 178.383329 -306.661446) (xy 178.4062 -306.705023) (xy 178.421784 -306.751704) (xy 178.429679 -306.800281)
			(xy 178.430174 -306.824888) (xy 178.769276 -306.824888) (xy 178.773236 -306.775834) (xy 178.785013 -306.72805)
			(xy 178.804304 -306.682774) (xy 178.830607 -306.641178) (xy 178.863242 -306.604341) (xy 178.901363 -306.573216)
			(xy 178.943984 -306.548609) (xy 178.99 -306.531157) (xy 179.038219 -306.521313) (xy 179.087394 -306.519332)
			(xy 179.136249 -306.525264) (xy 179.18352 -306.538956) (xy 179.227982 -306.560054) (xy 179.268485 -306.58801)
			(xy 179.303978 -306.622102) (xy 179.333543 -306.661446) (xy 179.356414 -306.705023) (xy 179.371998 -306.751704)
			(xy 179.379893 -306.800281) (xy 179.380388 -306.824888) (xy 179.719236 -306.824888) (xy 179.723196 -306.775834)
			(xy 179.734973 -306.72805) (xy 179.754264 -306.682774) (xy 179.780567 -306.641178) (xy 179.813202 -306.604341)
			(xy 179.851323 -306.573216) (xy 179.893944 -306.548609) (xy 179.93996 -306.531157) (xy 179.988179 -306.521313)
			(xy 180.037354 -306.519332) (xy 180.086209 -306.525264) (xy 180.13348 -306.538956) (xy 180.177942 -306.560054)
			(xy 180.218445 -306.58801) (xy 180.253938 -306.622102) (xy 180.283503 -306.661446) (xy 180.306374 -306.705023)
			(xy 180.321958 -306.751704) (xy 180.329853 -306.800281) (xy 180.330348 -306.824888) (xy 180.669196 -306.824888)
			(xy 180.673156 -306.775834) (xy 180.684933 -306.72805) (xy 180.704224 -306.682774) (xy 180.730527 -306.641178)
			(xy 180.763162 -306.604341) (xy 180.801283 -306.573216) (xy 180.843904 -306.548609) (xy 180.88992 -306.531157)
			(xy 180.938139 -306.521313) (xy 180.987314 -306.519332) (xy 181.036169 -306.525264) (xy 181.08344 -306.538956)
			(xy 181.127902 -306.560054) (xy 181.168405 -306.58801) (xy 181.203898 -306.622102) (xy 181.233463 -306.661446)
			(xy 181.256334 -306.705023) (xy 181.271918 -306.751704) (xy 181.279813 -306.800281) (xy 181.280308 -306.824888)
			(xy 181.619156 -306.824888) (xy 181.623116 -306.775834) (xy 181.634893 -306.72805) (xy 181.654184 -306.682774)
			(xy 181.680487 -306.641178) (xy 181.713122 -306.604341) (xy 181.751243 -306.573216) (xy 181.793864 -306.548609)
			(xy 181.83988 -306.531157) (xy 181.888099 -306.521313) (xy 181.937274 -306.519332) (xy 181.986129 -306.525264)
			(xy 182.0334 -306.538956) (xy 182.077862 -306.560054) (xy 182.118365 -306.58801) (xy 182.153858 -306.622102)
			(xy 182.183423 -306.661446) (xy 182.206294 -306.705023) (xy 182.221878 -306.751704) (xy 182.229773 -306.800281)
			(xy 182.230268 -306.824888) (xy 182.569116 -306.824888) (xy 182.573076 -306.775834) (xy 182.584853 -306.72805)
			(xy 182.604144 -306.682774) (xy 182.630447 -306.641178) (xy 182.663082 -306.604341) (xy 182.701203 -306.573216)
			(xy 182.743824 -306.548609) (xy 182.78984 -306.531157) (xy 182.838059 -306.521313) (xy 182.887234 -306.519332)
			(xy 182.936089 -306.525264) (xy 182.98336 -306.538956) (xy 183.027822 -306.560054) (xy 183.068325 -306.58801)
			(xy 183.103818 -306.622102) (xy 183.133383 -306.661446) (xy 183.156254 -306.705023) (xy 183.171838 -306.751704)
			(xy 183.179733 -306.800281) (xy 183.180228 -306.824888) (xy 183.519076 -306.824888) (xy 183.523036 -306.775834)
			(xy 183.534813 -306.72805) (xy 183.554104 -306.682774) (xy 183.580407 -306.641178) (xy 183.613042 -306.604341)
			(xy 183.651163 -306.573216) (xy 183.693784 -306.548609) (xy 183.7398 -306.531157) (xy 183.788019 -306.521313)
			(xy 183.837194 -306.519332) (xy 183.886049 -306.525264) (xy 183.93332 -306.538956) (xy 183.977782 -306.560054)
			(xy 184.018285 -306.58801) (xy 184.053778 -306.622102) (xy 184.083343 -306.661446) (xy 184.106214 -306.705023)
			(xy 184.121798 -306.751704) (xy 184.129693 -306.800281) (xy 184.130188 -306.824888) (xy 184.469036 -306.824888)
			(xy 184.472996 -306.775834) (xy 184.484773 -306.72805) (xy 184.504064 -306.682774) (xy 184.530367 -306.641178)
			(xy 184.563002 -306.604341) (xy 184.601123 -306.573216) (xy 184.643744 -306.548609) (xy 184.68976 -306.531157)
			(xy 184.737979 -306.521313) (xy 184.787154 -306.519332) (xy 184.836009 -306.525264) (xy 184.88328 -306.538956)
			(xy 184.927742 -306.560054) (xy 184.968245 -306.58801) (xy 185.003738 -306.622102) (xy 185.033303 -306.661446)
			(xy 185.056174 -306.705023) (xy 185.071758 -306.751704) (xy 185.079653 -306.800281) (xy 185.080148 -306.824888)
			(xy 185.079653 -306.849495) (xy 185.071758 -306.898072) (xy 185.056174 -306.944753) (xy 185.033303 -306.98833)
			(xy 185.003738 -307.027674) (xy 184.968245 -307.061766) (xy 184.927742 -307.089722) (xy 184.88328 -307.11082)
			(xy 184.836009 -307.124512) (xy 184.787154 -307.130444) (xy 184.737979 -307.128463) (xy 184.68976 -307.118619)
			(xy 184.643744 -307.101167) (xy 184.601123 -307.07656) (xy 184.563002 -307.045435) (xy 184.530367 -307.008598)
			(xy 184.504064 -306.967002) (xy 184.484773 -306.921726) (xy 184.472996 -306.873942) (xy 184.469036 -306.824888)
			(xy 184.130188 -306.824888) (xy 184.129693 -306.849495) (xy 184.121798 -306.898072) (xy 184.106214 -306.944753)
			(xy 184.083343 -306.98833) (xy 184.053778 -307.027674) (xy 184.018285 -307.061766) (xy 183.977782 -307.089722)
			(xy 183.93332 -307.11082) (xy 183.886049 -307.124512) (xy 183.837194 -307.130444) (xy 183.788019 -307.128463)
			(xy 183.7398 -307.118619) (xy 183.693784 -307.101167) (xy 183.651163 -307.07656) (xy 183.613042 -307.045435)
			(xy 183.580407 -307.008598) (xy 183.554104 -306.967002) (xy 183.534813 -306.921726) (xy 183.523036 -306.873942)
			(xy 183.519076 -306.824888) (xy 183.180228 -306.824888) (xy 183.179733 -306.849495) (xy 183.171838 -306.898072)
			(xy 183.156254 -306.944753) (xy 183.133383 -306.98833) (xy 183.103818 -307.027674) (xy 183.068325 -307.061766)
			(xy 183.027822 -307.089722) (xy 182.98336 -307.11082) (xy 182.936089 -307.124512) (xy 182.887234 -307.130444)
			(xy 182.838059 -307.128463) (xy 182.78984 -307.118619) (xy 182.743824 -307.101167) (xy 182.701203 -307.07656)
			(xy 182.663082 -307.045435) (xy 182.630447 -307.008598) (xy 182.604144 -306.967002) (xy 182.584853 -306.921726)
			(xy 182.573076 -306.873942) (xy 182.569116 -306.824888) (xy 182.230268 -306.824888) (xy 182.229773 -306.849495)
			(xy 182.221878 -306.898072) (xy 182.206294 -306.944753) (xy 182.183423 -306.98833) (xy 182.153858 -307.027674)
			(xy 182.118365 -307.061766) (xy 182.077862 -307.089722) (xy 182.0334 -307.11082) (xy 181.986129 -307.124512)
			(xy 181.937274 -307.130444) (xy 181.888099 -307.128463) (xy 181.83988 -307.118619) (xy 181.793864 -307.101167)
			(xy 181.751243 -307.07656) (xy 181.713122 -307.045435) (xy 181.680487 -307.008598) (xy 181.654184 -306.967002)
			(xy 181.634893 -306.921726) (xy 181.623116 -306.873942) (xy 181.619156 -306.824888) (xy 181.280308 -306.824888)
			(xy 181.279813 -306.849495) (xy 181.271918 -306.898072) (xy 181.256334 -306.944753) (xy 181.233463 -306.98833)
			(xy 181.203898 -307.027674) (xy 181.168405 -307.061766) (xy 181.127902 -307.089722) (xy 181.08344 -307.11082)
			(xy 181.036169 -307.124512) (xy 180.987314 -307.130444) (xy 180.938139 -307.128463) (xy 180.88992 -307.118619)
			(xy 180.843904 -307.101167) (xy 180.801283 -307.07656) (xy 180.763162 -307.045435) (xy 180.730527 -307.008598)
			(xy 180.704224 -306.967002) (xy 180.684933 -306.921726) (xy 180.673156 -306.873942) (xy 180.669196 -306.824888)
			(xy 180.330348 -306.824888) (xy 180.329853 -306.849495) (xy 180.321958 -306.898072) (xy 180.306374 -306.944753)
			(xy 180.283503 -306.98833) (xy 180.253938 -307.027674) (xy 180.218445 -307.061766) (xy 180.177942 -307.089722)
			(xy 180.13348 -307.11082) (xy 180.086209 -307.124512) (xy 180.037354 -307.130444) (xy 179.988179 -307.128463)
			(xy 179.93996 -307.118619) (xy 179.893944 -307.101167) (xy 179.851323 -307.07656) (xy 179.813202 -307.045435)
			(xy 179.780567 -307.008598) (xy 179.754264 -306.967002) (xy 179.734973 -306.921726) (xy 179.723196 -306.873942)
			(xy 179.719236 -306.824888) (xy 179.380388 -306.824888) (xy 179.379893 -306.849495) (xy 179.371998 -306.898072)
			(xy 179.356414 -306.944753) (xy 179.333543 -306.98833) (xy 179.303978 -307.027674) (xy 179.268485 -307.061766)
			(xy 179.227982 -307.089722) (xy 179.18352 -307.11082) (xy 179.136249 -307.124512) (xy 179.087394 -307.130444)
			(xy 179.038219 -307.128463) (xy 178.99 -307.118619) (xy 178.943984 -307.101167) (xy 178.901363 -307.07656)
			(xy 178.863242 -307.045435) (xy 178.830607 -307.008598) (xy 178.804304 -306.967002) (xy 178.785013 -306.921726)
			(xy 178.773236 -306.873942) (xy 178.769276 -306.824888) (xy 178.430174 -306.824888) (xy 178.429679 -306.849495)
			(xy 178.421784 -306.898072) (xy 178.4062 -306.944753) (xy 178.383329 -306.98833) (xy 178.353764 -307.027674)
			(xy 178.318271 -307.061766) (xy 178.277768 -307.089722) (xy 178.233306 -307.11082) (xy 178.186035 -307.124512)
			(xy 178.13718 -307.130444) (xy 178.088005 -307.128463) (xy 178.039786 -307.118619) (xy 177.99377 -307.101167)
			(xy 177.951149 -307.07656) (xy 177.913028 -307.045435) (xy 177.880393 -307.008598) (xy 177.85409 -306.967002)
			(xy 177.834799 -306.921726) (xy 177.823022 -306.873942) (xy 177.819062 -306.824888) (xy 177.480214 -306.824888)
			(xy 177.479719 -306.849495) (xy 177.471824 -306.898072) (xy 177.45624 -306.944753) (xy 177.433369 -306.98833)
			(xy 177.403804 -307.027674) (xy 177.368311 -307.061766) (xy 177.327808 -307.089722) (xy 177.283346 -307.11082)
			(xy 177.236075 -307.124512) (xy 177.18722 -307.130444) (xy 177.138045 -307.128463) (xy 177.089826 -307.118619)
			(xy 177.04381 -307.101167) (xy 177.001189 -307.07656) (xy 176.963068 -307.045435) (xy 176.930433 -307.008598)
			(xy 176.90413 -306.967002) (xy 176.884839 -306.921726) (xy 176.873062 -306.873942) (xy 176.869102 -306.824888)
			(xy 176.530254 -306.824888) (xy 176.529759 -306.849495) (xy 176.521864 -306.898072) (xy 176.50628 -306.944753)
			(xy 176.483409 -306.98833) (xy 176.453844 -307.027674) (xy 176.418351 -307.061766) (xy 176.377848 -307.089722)
			(xy 176.333386 -307.11082) (xy 176.286115 -307.124512) (xy 176.23726 -307.130444) (xy 176.188085 -307.128463)
			(xy 176.139866 -307.118619) (xy 176.09385 -307.101167) (xy 176.051229 -307.07656) (xy 176.013108 -307.045435)
			(xy 175.980473 -307.008598) (xy 175.95417 -306.967002) (xy 175.934879 -306.921726) (xy 175.923102 -306.873942)
			(xy 175.919142 -306.824888) (xy 174.630334 -306.824888) (xy 174.629839 -306.849495) (xy 174.621944 -306.898072)
			(xy 174.60636 -306.944753) (xy 174.583489 -306.98833) (xy 174.553924 -307.027674) (xy 174.518431 -307.061766)
			(xy 174.477928 -307.089722) (xy 174.433466 -307.11082) (xy 174.386195 -307.124512) (xy 174.33734 -307.130444)
			(xy 174.288165 -307.128463) (xy 174.239946 -307.118619) (xy 174.19393 -307.101167) (xy 174.151309 -307.07656)
			(xy 174.113188 -307.045435) (xy 174.080553 -307.008598) (xy 174.05425 -306.967002) (xy 174.034959 -306.921726)
			(xy 174.023182 -306.873942) (xy 174.019222 -306.824888) (xy 173.680374 -306.824888) (xy 173.679879 -306.849495)
			(xy 173.671984 -306.898072) (xy 173.6564 -306.944753) (xy 173.633529 -306.98833) (xy 173.603964 -307.027674)
			(xy 173.568471 -307.061766) (xy 173.527968 -307.089722) (xy 173.483506 -307.11082) (xy 173.436235 -307.124512)
			(xy 173.38738 -307.130444) (xy 173.338205 -307.128463) (xy 173.289986 -307.118619) (xy 173.24397 -307.101167)
			(xy 173.201349 -307.07656) (xy 173.163228 -307.045435) (xy 173.130593 -307.008598) (xy 173.10429 -306.967002)
			(xy 173.084999 -306.921726) (xy 173.073222 -306.873942) (xy 173.069262 -306.824888) (xy 172.73016 -306.824888)
			(xy 172.729665 -306.849495) (xy 172.72177 -306.898072) (xy 172.706186 -306.944753) (xy 172.683315 -306.98833)
			(xy 172.65375 -307.027674) (xy 172.618257 -307.061766) (xy 172.577754 -307.089722) (xy 172.533292 -307.11082)
			(xy 172.486021 -307.124512) (xy 172.437166 -307.130444) (xy 172.387991 -307.128463) (xy 172.339772 -307.118619)
			(xy 172.293756 -307.101167) (xy 172.251135 -307.07656) (xy 172.213014 -307.045435) (xy 172.180379 -307.008598)
			(xy 172.154076 -306.967002) (xy 172.134785 -306.921726) (xy 172.123008 -306.873942) (xy 172.119048 -306.824888)
			(xy 171.7802 -306.824888) (xy 171.779705 -306.849495) (xy 171.77181 -306.898072) (xy 171.756226 -306.944753)
			(xy 171.733355 -306.98833) (xy 171.70379 -307.027674) (xy 171.668297 -307.061766) (xy 171.627794 -307.089722)
			(xy 171.583332 -307.11082) (xy 171.536061 -307.124512) (xy 171.487206 -307.130444) (xy 171.438031 -307.128463)
			(xy 171.389812 -307.118619) (xy 171.343796 -307.101167) (xy 171.301175 -307.07656) (xy 171.263054 -307.045435)
			(xy 171.230419 -307.008598) (xy 171.204116 -306.967002) (xy 171.184825 -306.921726) (xy 171.173048 -306.873942)
			(xy 171.169088 -306.824888) (xy 170.83024 -306.824888) (xy 170.829745 -306.849495) (xy 170.82185 -306.898072)
			(xy 170.806266 -306.944753) (xy 170.783395 -306.98833) (xy 170.75383 -307.027674) (xy 170.718337 -307.061766)
			(xy 170.677834 -307.089722) (xy 170.633372 -307.11082) (xy 170.586101 -307.124512) (xy 170.537246 -307.130444)
			(xy 170.488071 -307.128463) (xy 170.439852 -307.118619) (xy 170.393836 -307.101167) (xy 170.351215 -307.07656)
			(xy 170.313094 -307.045435) (xy 170.280459 -307.008598) (xy 170.254156 -306.967002) (xy 170.234865 -306.921726)
			(xy 170.223088 -306.873942) (xy 170.219128 -306.824888) (xy 169.88028 -306.824888) (xy 169.879785 -306.849495)
			(xy 169.87189 -306.898072) (xy 169.856306 -306.944753) (xy 169.833435 -306.98833) (xy 169.80387 -307.027674)
			(xy 169.768377 -307.061766) (xy 169.727874 -307.089722) (xy 169.683412 -307.11082) (xy 169.636141 -307.124512)
			(xy 169.587286 -307.130444) (xy 169.538111 -307.128463) (xy 169.489892 -307.118619) (xy 169.443876 -307.101167)
			(xy 169.401255 -307.07656) (xy 169.363134 -307.045435) (xy 169.330499 -307.008598) (xy 169.304196 -306.967002)
			(xy 169.284905 -306.921726) (xy 169.273128 -306.873942) (xy 169.269168 -306.824888) (xy 168.93032 -306.824888)
			(xy 168.929825 -306.849495) (xy 168.92193 -306.898072) (xy 168.906346 -306.944753) (xy 168.883475 -306.98833)
			(xy 168.85391 -307.027674) (xy 168.818417 -307.061766) (xy 168.777914 -307.089722) (xy 168.733452 -307.11082)
			(xy 168.686181 -307.124512) (xy 168.637326 -307.130444) (xy 168.588151 -307.128463) (xy 168.539932 -307.118619)
			(xy 168.493916 -307.101167) (xy 168.451295 -307.07656) (xy 168.413174 -307.045435) (xy 168.380539 -307.008598)
			(xy 168.354236 -306.967002) (xy 168.334945 -306.921726) (xy 168.323168 -306.873942) (xy 168.319208 -306.824888)
			(xy 167.98036 -306.824888) (xy 167.979865 -306.849495) (xy 167.97197 -306.898072) (xy 167.956386 -306.944753)
			(xy 167.933515 -306.98833) (xy 167.90395 -307.027674) (xy 167.868457 -307.061766) (xy 167.827954 -307.089722)
			(xy 167.783492 -307.11082) (xy 167.736221 -307.124512) (xy 167.687366 -307.130444) (xy 167.638191 -307.128463)
			(xy 167.589972 -307.118619) (xy 167.543956 -307.101167) (xy 167.501335 -307.07656) (xy 167.463214 -307.045435)
			(xy 167.430579 -307.008598) (xy 167.404276 -306.967002) (xy 167.384985 -306.921726) (xy 167.373208 -306.873942)
			(xy 167.369248 -306.824888) (xy 167.0304 -306.824888) (xy 167.029905 -306.849495) (xy 167.02201 -306.898072)
			(xy 167.006426 -306.944753) (xy 166.983555 -306.98833) (xy 166.95399 -307.027674) (xy 166.918497 -307.061766)
			(xy 166.877994 -307.089722) (xy 166.833532 -307.11082) (xy 166.786261 -307.124512) (xy 166.737406 -307.130444)
			(xy 166.688231 -307.128463) (xy 166.640012 -307.118619) (xy 166.593996 -307.101167) (xy 166.551375 -307.07656)
			(xy 166.513254 -307.045435) (xy 166.480619 -307.008598) (xy 166.454316 -306.967002) (xy 166.435025 -306.921726)
			(xy 166.423248 -306.873942) (xy 166.419288 -306.824888) (xy 166.080186 -306.824888) (xy 166.079691 -306.849495)
			(xy 166.071796 -306.898072) (xy 166.056212 -306.944753) (xy 166.033341 -306.98833) (xy 166.003776 -307.027674)
			(xy 165.968283 -307.061766) (xy 165.92778 -307.089722) (xy 165.883318 -307.11082) (xy 165.836047 -307.124512)
			(xy 165.787192 -307.130444) (xy 165.738017 -307.128463) (xy 165.689798 -307.118619) (xy 165.643782 -307.101167)
			(xy 165.601161 -307.07656) (xy 165.56304 -307.045435) (xy 165.530405 -307.008598) (xy 165.504102 -306.967002)
			(xy 165.484811 -306.921726) (xy 165.473034 -306.873942) (xy 165.469074 -306.824888) (xy 165.130226 -306.824888)
			(xy 165.129731 -306.849495) (xy 165.121836 -306.898072) (xy 165.106252 -306.944753) (xy 165.083381 -306.98833)
			(xy 165.053816 -307.027674) (xy 165.018323 -307.061766) (xy 164.97782 -307.089722) (xy 164.933358 -307.11082)
			(xy 164.886087 -307.124512) (xy 164.837232 -307.130444) (xy 164.788057 -307.128463) (xy 164.739838 -307.118619)
			(xy 164.693822 -307.101167) (xy 164.651201 -307.07656) (xy 164.61308 -307.045435) (xy 164.580445 -307.008598)
			(xy 164.554142 -306.967002) (xy 164.534851 -306.921726) (xy 164.523074 -306.873942) (xy 164.519114 -306.824888)
			(xy 164.180266 -306.824888) (xy 164.179771 -306.849495) (xy 164.171876 -306.898072) (xy 164.156292 -306.944753)
			(xy 164.133421 -306.98833) (xy 164.103856 -307.027674) (xy 164.068363 -307.061766) (xy 164.02786 -307.089722)
			(xy 163.983398 -307.11082) (xy 163.936127 -307.124512) (xy 163.887272 -307.130444) (xy 163.838097 -307.128463)
			(xy 163.789878 -307.118619) (xy 163.743862 -307.101167) (xy 163.701241 -307.07656) (xy 163.66312 -307.045435)
			(xy 163.630485 -307.008598) (xy 163.604182 -306.967002) (xy 163.584891 -306.921726) (xy 163.573114 -306.873942)
			(xy 163.569154 -306.824888) (xy 163.230306 -306.824888) (xy 163.229811 -306.849495) (xy 163.221916 -306.898072)
			(xy 163.206332 -306.944753) (xy 163.183461 -306.98833) (xy 163.153896 -307.027674) (xy 163.118403 -307.061766)
			(xy 163.0779 -307.089722) (xy 163.033438 -307.11082) (xy 162.986167 -307.124512) (xy 162.937312 -307.130444)
			(xy 162.888137 -307.128463) (xy 162.839918 -307.118619) (xy 162.793902 -307.101167) (xy 162.751281 -307.07656)
			(xy 162.71316 -307.045435) (xy 162.680525 -307.008598) (xy 162.654222 -306.967002) (xy 162.634931 -306.921726)
			(xy 162.623154 -306.873942) (xy 162.619194 -306.824888) (xy 146.583799 -306.824888) (xy 146.580359 -306.84826)
			(xy 146.564291 -306.901667) (xy 146.540619 -306.952164) (xy 146.509846 -306.998677) (xy 146.472629 -307.040214)
			(xy 146.429761 -307.075889) (xy 146.382155 -307.104943) (xy 146.330826 -307.126755) (xy 146.276869 -307.140861)
			(xy 146.221432 -307.146961) (xy 146.165698 -307.144924) (xy 146.110855 -307.134794) (xy 146.058071 -307.116787)
			(xy 146.008471 -307.091286) (xy 145.963113 -307.058835) (xy 145.922964 -307.020126) (xy 145.888878 -306.975983)
			(xy 145.861582 -306.927348) (xy 145.841659 -306.875257) (xy 145.829533 -306.82082) (xy 145.825462 -306.765198)
			(xy 132.617737 -306.765198) (xy 132.60565 -306.791515) (xy 132.575924 -306.837483) (xy 132.558282 -306.858416)
			(xy 132.552186 -306.865528) (xy 132.545836 -306.882546) (xy 132.545836 -306.96789) (xy 132.552186 -306.984908)
			(xy 132.558282 -306.99202) (xy 132.57594 -307.012939) (xy 132.605663 -307.058909) (xy 132.628507 -307.108658)
			(xy 132.644002 -307.161162) (xy 132.651828 -307.215342) (xy 132.651827 -307.240178) (xy 147.960078 -307.240178)
			(xy 147.964149 -307.184556) (xy 147.976275 -307.130119) (xy 147.996198 -307.078028) (xy 148.023494 -307.029393)
			(xy 148.05758 -306.98525) (xy 148.097729 -306.946541) (xy 148.143087 -306.91409) (xy 148.192687 -306.888589)
			(xy 148.245471 -306.870582) (xy 148.300314 -306.860452) (xy 148.356048 -306.858415) (xy 148.411485 -306.864515)
			(xy 148.465442 -306.878621) (xy 148.516771 -306.900433) (xy 148.564377 -306.929487) (xy 148.607245 -306.965162)
			(xy 148.644462 -307.006699) (xy 148.675235 -307.053212) (xy 148.698907 -307.103709) (xy 148.714975 -307.157116)
			(xy 148.723095 -307.212292) (xy 148.723604 -307.240178) (xy 148.723095 -307.268064) (xy 148.718415 -307.299868)
			(xy 152.644106 -307.299868) (xy 152.648066 -307.250814) (xy 152.659843 -307.20303) (xy 152.679134 -307.157754)
			(xy 152.705437 -307.116158) (xy 152.738072 -307.079321) (xy 152.776193 -307.048196) (xy 152.818814 -307.023589)
			(xy 152.86483 -307.006137) (xy 152.913049 -306.996293) (xy 152.962224 -306.994312) (xy 153.011079 -307.000244)
			(xy 153.05835 -307.013936) (xy 153.102812 -307.035034) (xy 153.143315 -307.06299) (xy 153.178808 -307.097082)
			(xy 153.208373 -307.136426) (xy 153.231244 -307.180003) (xy 153.246828 -307.226684) (xy 153.254723 -307.275261)
			(xy 153.255218 -307.299868) (xy 153.594066 -307.299868) (xy 153.598026 -307.250814) (xy 153.609803 -307.20303)
			(xy 153.629094 -307.157754) (xy 153.655397 -307.116158) (xy 153.688032 -307.079321) (xy 153.726153 -307.048196)
			(xy 153.768774 -307.023589) (xy 153.81479 -307.006137) (xy 153.863009 -306.996293) (xy 153.912184 -306.994312)
			(xy 153.961039 -307.000244) (xy 154.00831 -307.013936) (xy 154.052772 -307.035034) (xy 154.093275 -307.06299)
			(xy 154.128768 -307.097082) (xy 154.158333 -307.136426) (xy 154.181204 -307.180003) (xy 154.196788 -307.226684)
			(xy 154.204683 -307.275261) (xy 154.205178 -307.299868) (xy 154.204683 -307.324475) (xy 154.204504 -307.325576)
			(xy 154.523436 -307.325576) (xy 154.523436 -307.27416) (xy 154.531479 -307.223378) (xy 154.547367 -307.174479)
			(xy 154.57071 -307.128667) (xy 154.600931 -307.087071) (xy 154.637287 -307.050715) (xy 154.678883 -307.020494)
			(xy 154.724695 -306.997151) (xy 154.773594 -306.981263) (xy 154.824376 -306.97322) (xy 154.875792 -306.97322)
			(xy 154.926574 -306.981263) (xy 154.975473 -306.997151) (xy 155.021285 -307.020494) (xy 155.062881 -307.050715)
			(xy 155.099237 -307.087071) (xy 155.129458 -307.128667) (xy 155.152801 -307.174479) (xy 155.168689 -307.223378)
			(xy 155.176732 -307.27416) (xy 155.177236 -307.299868) (xy 155.176732 -307.325576) (xy 155.473396 -307.325576)
			(xy 155.473396 -307.27416) (xy 155.481439 -307.223378) (xy 155.497327 -307.174479) (xy 155.52067 -307.128667)
			(xy 155.550891 -307.087071) (xy 155.587247 -307.050715) (xy 155.628843 -307.020494) (xy 155.674655 -306.997151)
			(xy 155.723554 -306.981263) (xy 155.774336 -306.97322) (xy 155.825752 -306.97322) (xy 155.876534 -306.981263)
			(xy 155.925433 -306.997151) (xy 155.971245 -307.020494) (xy 156.012841 -307.050715) (xy 156.049197 -307.087071)
			(xy 156.079418 -307.128667) (xy 156.102761 -307.174479) (xy 156.118649 -307.223378) (xy 156.126692 -307.27416)
			(xy 156.127196 -307.299868) (xy 156.4442 -307.299868) (xy 156.44816 -307.250814) (xy 156.459937 -307.20303)
			(xy 156.479228 -307.157754) (xy 156.505531 -307.116158) (xy 156.538166 -307.079321) (xy 156.576287 -307.048196)
			(xy 156.618908 -307.023589) (xy 156.664924 -307.006137) (xy 156.713143 -306.996293) (xy 156.762318 -306.994312)
			(xy 156.811173 -307.000244) (xy 156.858444 -307.013936) (xy 156.902906 -307.035034) (xy 156.943409 -307.06299)
			(xy 156.978902 -307.097082) (xy 157.008467 -307.136426) (xy 157.031338 -307.180003) (xy 157.046922 -307.226684)
			(xy 157.054817 -307.275261) (xy 157.055312 -307.299868) (xy 157.054817 -307.324475) (xy 157.054638 -307.325576)
			(xy 157.373316 -307.325576) (xy 157.373316 -307.27416) (xy 157.381359 -307.223378) (xy 157.397247 -307.174479)
			(xy 157.42059 -307.128667) (xy 157.450811 -307.087071) (xy 157.487167 -307.050715) (xy 157.528763 -307.020494)
			(xy 157.574575 -306.997151) (xy 157.623474 -306.981263) (xy 157.674256 -306.97322) (xy 157.725672 -306.97322)
			(xy 157.776454 -306.981263) (xy 157.825353 -306.997151) (xy 157.871165 -307.020494) (xy 157.912761 -307.050715)
			(xy 157.949117 -307.087071) (xy 157.979338 -307.128667) (xy 158.002681 -307.174479) (xy 158.018569 -307.223378)
			(xy 158.026612 -307.27416) (xy 158.027116 -307.299868) (xy 158.026612 -307.325576) (xy 158.323276 -307.325576)
			(xy 158.323276 -307.27416) (xy 158.331319 -307.223378) (xy 158.347207 -307.174479) (xy 158.37055 -307.128667)
			(xy 158.400771 -307.087071) (xy 158.437127 -307.050715) (xy 158.478723 -307.020494) (xy 158.524535 -306.997151)
			(xy 158.573434 -306.981263) (xy 158.624216 -306.97322) (xy 158.675632 -306.97322) (xy 158.726414 -306.981263)
			(xy 158.775313 -306.997151) (xy 158.821125 -307.020494) (xy 158.862721 -307.050715) (xy 158.899077 -307.087071)
			(xy 158.929298 -307.128667) (xy 158.952641 -307.174479) (xy 158.968529 -307.223378) (xy 158.976572 -307.27416)
			(xy 158.977076 -307.299868) (xy 159.29408 -307.299868) (xy 159.29804 -307.250814) (xy 159.309817 -307.20303)
			(xy 159.329108 -307.157754) (xy 159.355411 -307.116158) (xy 159.388046 -307.079321) (xy 159.426167 -307.048196)
			(xy 159.468788 -307.023589) (xy 159.514804 -307.006137) (xy 159.563023 -306.996293) (xy 159.612198 -306.994312)
			(xy 159.661053 -307.000244) (xy 159.708324 -307.013936) (xy 159.752786 -307.035034) (xy 159.793289 -307.06299)
			(xy 159.828782 -307.097082) (xy 159.858347 -307.136426) (xy 159.881218 -307.180003) (xy 159.896802 -307.226684)
			(xy 159.904697 -307.275261) (xy 159.905192 -307.299868) (xy 160.24404 -307.299868) (xy 160.248 -307.250814)
			(xy 160.259777 -307.20303) (xy 160.279068 -307.157754) (xy 160.305371 -307.116158) (xy 160.338006 -307.079321)
			(xy 160.376127 -307.048196) (xy 160.418748 -307.023589) (xy 160.464764 -307.006137) (xy 160.512983 -306.996293)
			(xy 160.562158 -306.994312) (xy 160.611013 -307.000244) (xy 160.658284 -307.013936) (xy 160.702746 -307.035034)
			(xy 160.743249 -307.06299) (xy 160.778742 -307.097082) (xy 160.808307 -307.136426) (xy 160.831178 -307.180003)
			(xy 160.846762 -307.226684) (xy 160.854657 -307.275261) (xy 160.855152 -307.299868) (xy 161.194254 -307.299868)
			(xy 161.198214 -307.250814) (xy 161.209991 -307.20303) (xy 161.229282 -307.157754) (xy 161.255585 -307.116158)
			(xy 161.28822 -307.079321) (xy 161.326341 -307.048196) (xy 161.368962 -307.023589) (xy 161.414978 -307.006137)
			(xy 161.463197 -306.996293) (xy 161.512372 -306.994312) (xy 161.561227 -307.000244) (xy 161.608498 -307.013936)
			(xy 161.65296 -307.035034) (xy 161.693463 -307.06299) (xy 161.728956 -307.097082) (xy 161.758521 -307.136426)
			(xy 161.781392 -307.180003) (xy 161.796976 -307.226684) (xy 161.804871 -307.275261) (xy 161.805366 -307.299868)
			(xy 161.804871 -307.324475) (xy 161.796976 -307.373052) (xy 161.781392 -307.419733) (xy 161.758521 -307.46331)
			(xy 161.728956 -307.502654) (xy 161.693463 -307.536746) (xy 161.65296 -307.564702) (xy 161.608498 -307.5858)
			(xy 161.561227 -307.599492) (xy 161.512372 -307.605424) (xy 161.463197 -307.603443) (xy 161.414978 -307.593599)
			(xy 161.368962 -307.576147) (xy 161.326341 -307.55154) (xy 161.28822 -307.520415) (xy 161.255585 -307.483578)
			(xy 161.229282 -307.441982) (xy 161.209991 -307.396706) (xy 161.198214 -307.348922) (xy 161.194254 -307.299868)
			(xy 160.855152 -307.299868) (xy 160.854657 -307.324475) (xy 160.846762 -307.373052) (xy 160.831178 -307.419733)
			(xy 160.808307 -307.46331) (xy 160.778742 -307.502654) (xy 160.743249 -307.536746) (xy 160.702746 -307.564702)
			(xy 160.658284 -307.5858) (xy 160.611013 -307.599492) (xy 160.562158 -307.605424) (xy 160.512983 -307.603443)
			(xy 160.464764 -307.593599) (xy 160.418748 -307.576147) (xy 160.376127 -307.55154) (xy 160.338006 -307.520415)
			(xy 160.305371 -307.483578) (xy 160.279068 -307.441982) (xy 160.259777 -307.396706) (xy 160.248 -307.348922)
			(xy 160.24404 -307.299868) (xy 159.905192 -307.299868) (xy 159.904697 -307.324475) (xy 159.896802 -307.373052)
			(xy 159.881218 -307.419733) (xy 159.858347 -307.46331) (xy 159.828782 -307.502654) (xy 159.793289 -307.536746)
			(xy 159.752786 -307.564702) (xy 159.708324 -307.5858) (xy 159.661053 -307.599492) (xy 159.612198 -307.605424)
			(xy 159.563023 -307.603443) (xy 159.514804 -307.593599) (xy 159.468788 -307.576147) (xy 159.426167 -307.55154)
			(xy 159.388046 -307.520415) (xy 159.355411 -307.483578) (xy 159.329108 -307.441982) (xy 159.309817 -307.396706)
			(xy 159.29804 -307.348922) (xy 159.29408 -307.299868) (xy 158.977076 -307.299868) (xy 158.976572 -307.325576)
			(xy 158.968529 -307.376358) (xy 158.952641 -307.425257) (xy 158.929298 -307.471069) (xy 158.899077 -307.512665)
			(xy 158.862721 -307.549021) (xy 158.821125 -307.579242) (xy 158.775313 -307.602585) (xy 158.726414 -307.618473)
			(xy 158.675632 -307.626516) (xy 158.624216 -307.626516) (xy 158.573434 -307.618473) (xy 158.524535 -307.602585)
			(xy 158.478723 -307.579242) (xy 158.437127 -307.549021) (xy 158.400771 -307.512665) (xy 158.37055 -307.471069)
			(xy 158.347207 -307.425257) (xy 158.331319 -307.376358) (xy 158.323276 -307.325576) (xy 158.026612 -307.325576)
			(xy 158.018569 -307.376358) (xy 158.002681 -307.425257) (xy 157.979338 -307.471069) (xy 157.949117 -307.512665)
			(xy 157.912761 -307.549021) (xy 157.871165 -307.579242) (xy 157.825353 -307.602585) (xy 157.776454 -307.618473)
			(xy 157.725672 -307.626516) (xy 157.674256 -307.626516) (xy 157.623474 -307.618473) (xy 157.574575 -307.602585)
			(xy 157.528763 -307.579242) (xy 157.487167 -307.549021) (xy 157.450811 -307.512665) (xy 157.42059 -307.471069)
			(xy 157.397247 -307.425257) (xy 157.381359 -307.376358) (xy 157.373316 -307.325576) (xy 157.054638 -307.325576)
			(xy 157.046922 -307.373052) (xy 157.031338 -307.419733) (xy 157.008467 -307.46331) (xy 156.978902 -307.502654)
			(xy 156.943409 -307.536746) (xy 156.902906 -307.564702) (xy 156.858444 -307.5858) (xy 156.811173 -307.599492)
			(xy 156.762318 -307.605424) (xy 156.713143 -307.603443) (xy 156.664924 -307.593599) (xy 156.618908 -307.576147)
			(xy 156.576287 -307.55154) (xy 156.538166 -307.520415) (xy 156.505531 -307.483578) (xy 156.479228 -307.441982)
			(xy 156.459937 -307.396706) (xy 156.44816 -307.348922) (xy 156.4442 -307.299868) (xy 156.127196 -307.299868)
			(xy 156.126692 -307.325576) (xy 156.118649 -307.376358) (xy 156.102761 -307.425257) (xy 156.079418 -307.471069)
			(xy 156.049197 -307.512665) (xy 156.012841 -307.549021) (xy 155.971245 -307.579242) (xy 155.925433 -307.602585)
			(xy 155.876534 -307.618473) (xy 155.825752 -307.626516) (xy 155.774336 -307.626516) (xy 155.723554 -307.618473)
			(xy 155.674655 -307.602585) (xy 155.628843 -307.579242) (xy 155.587247 -307.549021) (xy 155.550891 -307.512665)
			(xy 155.52067 -307.471069) (xy 155.497327 -307.425257) (xy 155.481439 -307.376358) (xy 155.473396 -307.325576)
			(xy 155.176732 -307.325576) (xy 155.168689 -307.376358) (xy 155.152801 -307.425257) (xy 155.129458 -307.471069)
			(xy 155.099237 -307.512665) (xy 155.062881 -307.549021) (xy 155.021285 -307.579242) (xy 154.975473 -307.602585)
			(xy 154.926574 -307.618473) (xy 154.875792 -307.626516) (xy 154.824376 -307.626516) (xy 154.773594 -307.618473)
			(xy 154.724695 -307.602585) (xy 154.678883 -307.579242) (xy 154.637287 -307.549021) (xy 154.600931 -307.512665)
			(xy 154.57071 -307.471069) (xy 154.547367 -307.425257) (xy 154.531479 -307.376358) (xy 154.523436 -307.325576)
			(xy 154.204504 -307.325576) (xy 154.196788 -307.373052) (xy 154.181204 -307.419733) (xy 154.158333 -307.46331)
			(xy 154.128768 -307.502654) (xy 154.093275 -307.536746) (xy 154.052772 -307.564702) (xy 154.00831 -307.5858)
			(xy 153.961039 -307.599492) (xy 153.912184 -307.605424) (xy 153.863009 -307.603443) (xy 153.81479 -307.593599)
			(xy 153.768774 -307.576147) (xy 153.726153 -307.55154) (xy 153.688032 -307.520415) (xy 153.655397 -307.483578)
			(xy 153.629094 -307.441982) (xy 153.609803 -307.396706) (xy 153.598026 -307.348922) (xy 153.594066 -307.299868)
			(xy 153.255218 -307.299868) (xy 153.254723 -307.324475) (xy 153.246828 -307.373052) (xy 153.231244 -307.419733)
			(xy 153.208373 -307.46331) (xy 153.178808 -307.502654) (xy 153.143315 -307.536746) (xy 153.102812 -307.564702)
			(xy 153.05835 -307.5858) (xy 153.011079 -307.599492) (xy 152.962224 -307.605424) (xy 152.913049 -307.603443)
			(xy 152.86483 -307.593599) (xy 152.818814 -307.576147) (xy 152.776193 -307.55154) (xy 152.738072 -307.520415)
			(xy 152.705437 -307.483578) (xy 152.679134 -307.441982) (xy 152.659843 -307.396706) (xy 152.648066 -307.348922)
			(xy 152.644106 -307.299868) (xy 148.718415 -307.299868) (xy 148.714975 -307.32324) (xy 148.698907 -307.376647)
			(xy 148.675235 -307.427144) (xy 148.644462 -307.473657) (xy 148.607245 -307.515194) (xy 148.564377 -307.550869)
			(xy 148.516771 -307.579923) (xy 148.465442 -307.601735) (xy 148.411485 -307.615841) (xy 148.356048 -307.621941)
			(xy 148.300314 -307.619904) (xy 148.245471 -307.609774) (xy 148.192687 -307.591767) (xy 148.143087 -307.566266)
			(xy 148.097729 -307.533815) (xy 148.05758 -307.495106) (xy 148.023494 -307.450963) (xy 147.996198 -307.402328)
			(xy 147.976275 -307.350237) (xy 147.964149 -307.2958) (xy 147.960078 -307.240178) (xy 132.651827 -307.240178)
			(xy 132.651826 -307.270085) (xy 132.643996 -307.324265) (xy 132.628498 -307.376768) (xy 132.60565 -307.426515)
			(xy 132.575924 -307.472483) (xy 132.558282 -307.493416) (xy 132.552186 -307.500528) (xy 132.545836 -307.517546)
			(xy 132.545836 -307.60289) (xy 132.552186 -307.619908) (xy 132.558282 -307.62702) (xy 132.575894 -307.647974)
			(xy 132.605611 -307.69394) (xy 132.628452 -307.743682) (xy 132.637652 -307.774848) (xy 162.619194 -307.774848)
			(xy 162.623154 -307.725794) (xy 162.634931 -307.67801) (xy 162.654222 -307.632734) (xy 162.680525 -307.591138)
			(xy 162.71316 -307.554301) (xy 162.751281 -307.523176) (xy 162.793902 -307.498569) (xy 162.839918 -307.481117)
			(xy 162.888137 -307.471273) (xy 162.937312 -307.469292) (xy 162.986167 -307.475224) (xy 163.033438 -307.488916)
			(xy 163.0779 -307.510014) (xy 163.118403 -307.53797) (xy 163.153896 -307.572062) (xy 163.183461 -307.611406)
			(xy 163.206332 -307.654983) (xy 163.221916 -307.701664) (xy 163.229811 -307.750241) (xy 163.230306 -307.774848)
			(xy 163.569154 -307.774848) (xy 163.573114 -307.725794) (xy 163.584891 -307.67801) (xy 163.604182 -307.632734)
			(xy 163.630485 -307.591138) (xy 163.66312 -307.554301) (xy 163.701241 -307.523176) (xy 163.743862 -307.498569)
			(xy 163.789878 -307.481117) (xy 163.838097 -307.471273) (xy 163.887272 -307.469292) (xy 163.936127 -307.475224)
			(xy 163.983398 -307.488916) (xy 164.02786 -307.510014) (xy 164.068363 -307.53797) (xy 164.103856 -307.572062)
			(xy 164.133421 -307.611406) (xy 164.156292 -307.654983) (xy 164.171876 -307.701664) (xy 164.179771 -307.750241)
			(xy 164.180266 -307.774848) (xy 164.519114 -307.774848) (xy 164.523074 -307.725794) (xy 164.534851 -307.67801)
			(xy 164.554142 -307.632734) (xy 164.580445 -307.591138) (xy 164.61308 -307.554301) (xy 164.651201 -307.523176)
			(xy 164.693822 -307.498569) (xy 164.739838 -307.481117) (xy 164.788057 -307.471273) (xy 164.837232 -307.469292)
			(xy 164.886087 -307.475224) (xy 164.933358 -307.488916) (xy 164.97782 -307.510014) (xy 165.018323 -307.53797)
			(xy 165.053816 -307.572062) (xy 165.083381 -307.611406) (xy 165.106252 -307.654983) (xy 165.121836 -307.701664)
			(xy 165.129731 -307.750241) (xy 165.130226 -307.774848) (xy 165.469074 -307.774848) (xy 165.473034 -307.725794)
			(xy 165.484811 -307.67801) (xy 165.504102 -307.632734) (xy 165.530405 -307.591138) (xy 165.56304 -307.554301)
			(xy 165.601161 -307.523176) (xy 165.643782 -307.498569) (xy 165.689798 -307.481117) (xy 165.738017 -307.471273)
			(xy 165.787192 -307.469292) (xy 165.836047 -307.475224) (xy 165.883318 -307.488916) (xy 165.92778 -307.510014)
			(xy 165.968283 -307.53797) (xy 166.003776 -307.572062) (xy 166.033341 -307.611406) (xy 166.056212 -307.654983)
			(xy 166.071796 -307.701664) (xy 166.079691 -307.750241) (xy 166.080186 -307.774848) (xy 166.419288 -307.774848)
			(xy 166.423248 -307.725794) (xy 166.435025 -307.67801) (xy 166.454316 -307.632734) (xy 166.480619 -307.591138)
			(xy 166.513254 -307.554301) (xy 166.551375 -307.523176) (xy 166.593996 -307.498569) (xy 166.640012 -307.481117)
			(xy 166.688231 -307.471273) (xy 166.737406 -307.469292) (xy 166.786261 -307.475224) (xy 166.833532 -307.488916)
			(xy 166.877994 -307.510014) (xy 166.918497 -307.53797) (xy 166.95399 -307.572062) (xy 166.983555 -307.611406)
			(xy 167.006426 -307.654983) (xy 167.02201 -307.701664) (xy 167.029905 -307.750241) (xy 167.0304 -307.774848)
			(xy 167.369248 -307.774848) (xy 167.373208 -307.725794) (xy 167.384985 -307.67801) (xy 167.404276 -307.632734)
			(xy 167.430579 -307.591138) (xy 167.463214 -307.554301) (xy 167.501335 -307.523176) (xy 167.543956 -307.498569)
			(xy 167.589972 -307.481117) (xy 167.638191 -307.471273) (xy 167.687366 -307.469292) (xy 167.736221 -307.475224)
			(xy 167.783492 -307.488916) (xy 167.827954 -307.510014) (xy 167.868457 -307.53797) (xy 167.90395 -307.572062)
			(xy 167.933515 -307.611406) (xy 167.956386 -307.654983) (xy 167.97197 -307.701664) (xy 167.979865 -307.750241)
			(xy 167.98036 -307.774848) (xy 168.319208 -307.774848) (xy 168.323168 -307.725794) (xy 168.334945 -307.67801)
			(xy 168.354236 -307.632734) (xy 168.380539 -307.591138) (xy 168.413174 -307.554301) (xy 168.451295 -307.523176)
			(xy 168.493916 -307.498569) (xy 168.539932 -307.481117) (xy 168.588151 -307.471273) (xy 168.637326 -307.469292)
			(xy 168.686181 -307.475224) (xy 168.733452 -307.488916) (xy 168.777914 -307.510014) (xy 168.818417 -307.53797)
			(xy 168.85391 -307.572062) (xy 168.883475 -307.611406) (xy 168.906346 -307.654983) (xy 168.92193 -307.701664)
			(xy 168.929825 -307.750241) (xy 168.93032 -307.774848) (xy 169.269168 -307.774848) (xy 169.273128 -307.725794)
			(xy 169.284905 -307.67801) (xy 169.304196 -307.632734) (xy 169.330499 -307.591138) (xy 169.363134 -307.554301)
			(xy 169.401255 -307.523176) (xy 169.443876 -307.498569) (xy 169.489892 -307.481117) (xy 169.538111 -307.471273)
			(xy 169.587286 -307.469292) (xy 169.636141 -307.475224) (xy 169.683412 -307.488916) (xy 169.727874 -307.510014)
			(xy 169.768377 -307.53797) (xy 169.80387 -307.572062) (xy 169.833435 -307.611406) (xy 169.856306 -307.654983)
			(xy 169.87189 -307.701664) (xy 169.879785 -307.750241) (xy 169.88028 -307.774848) (xy 170.219128 -307.774848)
			(xy 170.223088 -307.725794) (xy 170.234865 -307.67801) (xy 170.254156 -307.632734) (xy 170.280459 -307.591138)
			(xy 170.313094 -307.554301) (xy 170.351215 -307.523176) (xy 170.393836 -307.498569) (xy 170.439852 -307.481117)
			(xy 170.488071 -307.471273) (xy 170.537246 -307.469292) (xy 170.586101 -307.475224) (xy 170.633372 -307.488916)
			(xy 170.677834 -307.510014) (xy 170.718337 -307.53797) (xy 170.75383 -307.572062) (xy 170.783395 -307.611406)
			(xy 170.806266 -307.654983) (xy 170.82185 -307.701664) (xy 170.829745 -307.750241) (xy 170.83024 -307.774848)
			(xy 171.169088 -307.774848) (xy 171.173048 -307.725794) (xy 171.184825 -307.67801) (xy 171.204116 -307.632734)
			(xy 171.230419 -307.591138) (xy 171.263054 -307.554301) (xy 171.301175 -307.523176) (xy 171.343796 -307.498569)
			(xy 171.389812 -307.481117) (xy 171.438031 -307.471273) (xy 171.487206 -307.469292) (xy 171.536061 -307.475224)
			(xy 171.583332 -307.488916) (xy 171.627794 -307.510014) (xy 171.668297 -307.53797) (xy 171.70379 -307.572062)
			(xy 171.733355 -307.611406) (xy 171.756226 -307.654983) (xy 171.77181 -307.701664) (xy 171.779705 -307.750241)
			(xy 171.7802 -307.774848) (xy 172.119302 -307.774848) (xy 172.123262 -307.725794) (xy 172.135039 -307.67801)
			(xy 172.15433 -307.632734) (xy 172.180633 -307.591138) (xy 172.213268 -307.554301) (xy 172.251389 -307.523176)
			(xy 172.29401 -307.498569) (xy 172.340026 -307.481117) (xy 172.388245 -307.471273) (xy 172.43742 -307.469292)
			(xy 172.486275 -307.475224) (xy 172.533546 -307.488916) (xy 172.578008 -307.510014) (xy 172.618511 -307.53797)
			(xy 172.654004 -307.572062) (xy 172.683569 -307.611406) (xy 172.70644 -307.654983) (xy 172.722024 -307.701664)
			(xy 172.729919 -307.750241) (xy 172.730414 -307.774848) (xy 173.069262 -307.774848) (xy 173.073222 -307.725794)
			(xy 173.084999 -307.67801) (xy 173.10429 -307.632734) (xy 173.130593 -307.591138) (xy 173.163228 -307.554301)
			(xy 173.201349 -307.523176) (xy 173.24397 -307.498569) (xy 173.289986 -307.481117) (xy 173.338205 -307.471273)
			(xy 173.38738 -307.469292) (xy 173.436235 -307.475224) (xy 173.483506 -307.488916) (xy 173.527968 -307.510014)
			(xy 173.568471 -307.53797) (xy 173.603964 -307.572062) (xy 173.633529 -307.611406) (xy 173.6564 -307.654983)
			(xy 173.671984 -307.701664) (xy 173.679879 -307.750241) (xy 173.680374 -307.774848) (xy 174.019222 -307.774848)
			(xy 174.023182 -307.725794) (xy 174.034959 -307.67801) (xy 174.05425 -307.632734) (xy 174.080553 -307.591138)
			(xy 174.113188 -307.554301) (xy 174.151309 -307.523176) (xy 174.19393 -307.498569) (xy 174.239946 -307.481117)
			(xy 174.288165 -307.471273) (xy 174.33734 -307.469292) (xy 174.386195 -307.475224) (xy 174.433466 -307.488916)
			(xy 174.477928 -307.510014) (xy 174.518431 -307.53797) (xy 174.553924 -307.572062) (xy 174.583489 -307.611406)
			(xy 174.60636 -307.654983) (xy 174.621944 -307.701664) (xy 174.629839 -307.750241) (xy 174.630334 -307.774848)
			(xy 175.919142 -307.774848) (xy 175.923102 -307.725794) (xy 175.934879 -307.67801) (xy 175.95417 -307.632734)
			(xy 175.980473 -307.591138) (xy 176.013108 -307.554301) (xy 176.051229 -307.523176) (xy 176.09385 -307.498569)
			(xy 176.139866 -307.481117) (xy 176.188085 -307.471273) (xy 176.23726 -307.469292) (xy 176.286115 -307.475224)
			(xy 176.333386 -307.488916) (xy 176.377848 -307.510014) (xy 176.418351 -307.53797) (xy 176.453844 -307.572062)
			(xy 176.483409 -307.611406) (xy 176.50628 -307.654983) (xy 176.521864 -307.701664) (xy 176.529759 -307.750241)
			(xy 176.530254 -307.774848) (xy 176.869102 -307.774848) (xy 176.873062 -307.725794) (xy 176.884839 -307.67801)
			(xy 176.90413 -307.632734) (xy 176.930433 -307.591138) (xy 176.963068 -307.554301) (xy 177.001189 -307.523176)
			(xy 177.04381 -307.498569) (xy 177.089826 -307.481117) (xy 177.138045 -307.471273) (xy 177.18722 -307.469292)
			(xy 177.236075 -307.475224) (xy 177.283346 -307.488916) (xy 177.327808 -307.510014) (xy 177.368311 -307.53797)
			(xy 177.403804 -307.572062) (xy 177.433369 -307.611406) (xy 177.45624 -307.654983) (xy 177.471824 -307.701664)
			(xy 177.479719 -307.750241) (xy 177.480214 -307.774848) (xy 177.819062 -307.774848) (xy 177.823022 -307.725794)
			(xy 177.834799 -307.67801) (xy 177.85409 -307.632734) (xy 177.880393 -307.591138) (xy 177.913028 -307.554301)
			(xy 177.951149 -307.523176) (xy 177.99377 -307.498569) (xy 178.039786 -307.481117) (xy 178.088005 -307.471273)
			(xy 178.13718 -307.469292) (xy 178.186035 -307.475224) (xy 178.233306 -307.488916) (xy 178.277768 -307.510014)
			(xy 178.318271 -307.53797) (xy 178.353764 -307.572062) (xy 178.383329 -307.611406) (xy 178.4062 -307.654983)
			(xy 178.421784 -307.701664) (xy 178.429679 -307.750241) (xy 178.430169 -307.774594) (xy 178.769022 -307.774594)
			(xy 178.772982 -307.72554) (xy 178.784759 -307.677756) (xy 178.80405 -307.63248) (xy 178.830353 -307.590884)
			(xy 178.862988 -307.554047) (xy 178.901109 -307.522922) (xy 178.94373 -307.498315) (xy 178.989746 -307.480863)
			(xy 179.037965 -307.471019) (xy 179.08714 -307.469038) (xy 179.135995 -307.47497) (xy 179.183266 -307.488662)
			(xy 179.227728 -307.50976) (xy 179.268231 -307.537716) (xy 179.303724 -307.571808) (xy 179.333289 -307.611152)
			(xy 179.35616 -307.654729) (xy 179.371744 -307.70141) (xy 179.379639 -307.749987) (xy 179.380134 -307.774594)
			(xy 179.719236 -307.774594) (xy 179.723196 -307.72554) (xy 179.734973 -307.677756) (xy 179.754264 -307.63248)
			(xy 179.780567 -307.590884) (xy 179.813202 -307.554047) (xy 179.851323 -307.522922) (xy 179.893944 -307.498315)
			(xy 179.93996 -307.480863) (xy 179.988179 -307.471019) (xy 180.037354 -307.469038) (xy 180.086209 -307.47497)
			(xy 180.13348 -307.488662) (xy 180.177942 -307.50976) (xy 180.218445 -307.537716) (xy 180.253938 -307.571808)
			(xy 180.283503 -307.611152) (xy 180.306374 -307.654729) (xy 180.321958 -307.70141) (xy 180.329853 -307.749987)
			(xy 180.330348 -307.774594) (xy 180.330343 -307.774848) (xy 180.669196 -307.774848) (xy 180.673156 -307.725794)
			(xy 180.684933 -307.67801) (xy 180.704224 -307.632734) (xy 180.730527 -307.591138) (xy 180.763162 -307.554301)
			(xy 180.801283 -307.523176) (xy 180.843904 -307.498569) (xy 180.88992 -307.481117) (xy 180.938139 -307.471273)
			(xy 180.987314 -307.469292) (xy 181.036169 -307.475224) (xy 181.08344 -307.488916) (xy 181.127902 -307.510014)
			(xy 181.168405 -307.53797) (xy 181.203898 -307.572062) (xy 181.233463 -307.611406) (xy 181.256334 -307.654983)
			(xy 181.271918 -307.701664) (xy 181.279813 -307.750241) (xy 181.280308 -307.774848) (xy 181.619156 -307.774848)
			(xy 181.623116 -307.725794) (xy 181.634893 -307.67801) (xy 181.654184 -307.632734) (xy 181.680487 -307.591138)
			(xy 181.713122 -307.554301) (xy 181.751243 -307.523176) (xy 181.793864 -307.498569) (xy 181.83988 -307.481117)
			(xy 181.888099 -307.471273) (xy 181.937274 -307.469292) (xy 181.986129 -307.475224) (xy 182.0334 -307.488916)
			(xy 182.077862 -307.510014) (xy 182.118365 -307.53797) (xy 182.153858 -307.572062) (xy 182.183423 -307.611406)
			(xy 182.206294 -307.654983) (xy 182.221878 -307.701664) (xy 182.229773 -307.750241) (xy 182.230268 -307.774848)
			(xy 182.569116 -307.774848) (xy 182.573076 -307.725794) (xy 182.584853 -307.67801) (xy 182.604144 -307.632734)
			(xy 182.630447 -307.591138) (xy 182.663082 -307.554301) (xy 182.701203 -307.523176) (xy 182.743824 -307.498569)
			(xy 182.78984 -307.481117) (xy 182.838059 -307.471273) (xy 182.887234 -307.469292) (xy 182.936089 -307.475224)
			(xy 182.98336 -307.488916) (xy 183.027822 -307.510014) (xy 183.068325 -307.53797) (xy 183.103818 -307.572062)
			(xy 183.133383 -307.611406) (xy 183.156254 -307.654983) (xy 183.171838 -307.701664) (xy 183.179733 -307.750241)
			(xy 183.180228 -307.774848) (xy 183.519076 -307.774848) (xy 183.523036 -307.725794) (xy 183.534813 -307.67801)
			(xy 183.554104 -307.632734) (xy 183.580407 -307.591138) (xy 183.613042 -307.554301) (xy 183.651163 -307.523176)
			(xy 183.693784 -307.498569) (xy 183.7398 -307.481117) (xy 183.788019 -307.471273) (xy 183.837194 -307.469292)
			(xy 183.886049 -307.475224) (xy 183.93332 -307.488916) (xy 183.977782 -307.510014) (xy 184.018285 -307.53797)
			(xy 184.053778 -307.572062) (xy 184.083343 -307.611406) (xy 184.106214 -307.654983) (xy 184.121798 -307.701664)
			(xy 184.129693 -307.750241) (xy 184.130188 -307.774848) (xy 184.469036 -307.774848) (xy 184.472996 -307.725794)
			(xy 184.484773 -307.67801) (xy 184.504064 -307.632734) (xy 184.530367 -307.591138) (xy 184.563002 -307.554301)
			(xy 184.601123 -307.523176) (xy 184.643744 -307.498569) (xy 184.68976 -307.481117) (xy 184.737979 -307.471273)
			(xy 184.787154 -307.469292) (xy 184.836009 -307.475224) (xy 184.88328 -307.488916) (xy 184.927742 -307.510014)
			(xy 184.968245 -307.53797) (xy 185.003738 -307.572062) (xy 185.033303 -307.611406) (xy 185.056174 -307.654983)
			(xy 185.071758 -307.701664) (xy 185.079653 -307.750241) (xy 185.080148 -307.774848) (xy 185.079653 -307.799455)
			(xy 185.071758 -307.848032) (xy 185.056174 -307.894713) (xy 185.033303 -307.93829) (xy 185.003738 -307.977634)
			(xy 184.968245 -308.011726) (xy 184.927742 -308.039682) (xy 184.88328 -308.06078) (xy 184.836009 -308.074472)
			(xy 184.787154 -308.080404) (xy 184.737979 -308.078423) (xy 184.68976 -308.068579) (xy 184.643744 -308.051127)
			(xy 184.601123 -308.02652) (xy 184.563002 -307.995395) (xy 184.530367 -307.958558) (xy 184.504064 -307.916962)
			(xy 184.484773 -307.871686) (xy 184.472996 -307.823902) (xy 184.469036 -307.774848) (xy 184.130188 -307.774848)
			(xy 184.129693 -307.799455) (xy 184.121798 -307.848032) (xy 184.106214 -307.894713) (xy 184.083343 -307.93829)
			(xy 184.053778 -307.977634) (xy 184.018285 -308.011726) (xy 183.977782 -308.039682) (xy 183.93332 -308.06078)
			(xy 183.886049 -308.074472) (xy 183.837194 -308.080404) (xy 183.788019 -308.078423) (xy 183.7398 -308.068579)
			(xy 183.693784 -308.051127) (xy 183.651163 -308.02652) (xy 183.613042 -307.995395) (xy 183.580407 -307.958558)
			(xy 183.554104 -307.916962) (xy 183.534813 -307.871686) (xy 183.523036 -307.823902) (xy 183.519076 -307.774848)
			(xy 183.180228 -307.774848) (xy 183.179733 -307.799455) (xy 183.171838 -307.848032) (xy 183.156254 -307.894713)
			(xy 183.133383 -307.93829) (xy 183.103818 -307.977634) (xy 183.068325 -308.011726) (xy 183.027822 -308.039682)
			(xy 182.98336 -308.06078) (xy 182.936089 -308.074472) (xy 182.887234 -308.080404) (xy 182.838059 -308.078423)
			(xy 182.78984 -308.068579) (xy 182.743824 -308.051127) (xy 182.701203 -308.02652) (xy 182.663082 -307.995395)
			(xy 182.630447 -307.958558) (xy 182.604144 -307.916962) (xy 182.584853 -307.871686) (xy 182.573076 -307.823902)
			(xy 182.569116 -307.774848) (xy 182.230268 -307.774848) (xy 182.229773 -307.799455) (xy 182.221878 -307.848032)
			(xy 182.206294 -307.894713) (xy 182.183423 -307.93829) (xy 182.153858 -307.977634) (xy 182.118365 -308.011726)
			(xy 182.077862 -308.039682) (xy 182.0334 -308.06078) (xy 181.986129 -308.074472) (xy 181.937274 -308.080404)
			(xy 181.888099 -308.078423) (xy 181.83988 -308.068579) (xy 181.793864 -308.051127) (xy 181.751243 -308.02652)
			(xy 181.713122 -307.995395) (xy 181.680487 -307.958558) (xy 181.654184 -307.916962) (xy 181.634893 -307.871686)
			(xy 181.623116 -307.823902) (xy 181.619156 -307.774848) (xy 181.280308 -307.774848) (xy 181.279813 -307.799455)
			(xy 181.271918 -307.848032) (xy 181.256334 -307.894713) (xy 181.233463 -307.93829) (xy 181.203898 -307.977634)
			(xy 181.168405 -308.011726) (xy 181.127902 -308.039682) (xy 181.08344 -308.06078) (xy 181.036169 -308.074472)
			(xy 180.987314 -308.080404) (xy 180.938139 -308.078423) (xy 180.88992 -308.068579) (xy 180.843904 -308.051127)
			(xy 180.801283 -308.02652) (xy 180.763162 -307.995395) (xy 180.730527 -307.958558) (xy 180.704224 -307.916962)
			(xy 180.684933 -307.871686) (xy 180.673156 -307.823902) (xy 180.669196 -307.774848) (xy 180.330343 -307.774848)
			(xy 180.329853 -307.799201) (xy 180.321958 -307.847778) (xy 180.306374 -307.894459) (xy 180.283503 -307.938036)
			(xy 180.253938 -307.97738) (xy 180.218445 -308.011472) (xy 180.177942 -308.039428) (xy 180.13348 -308.060526)
			(xy 180.086209 -308.074218) (xy 180.037354 -308.08015) (xy 179.988179 -308.078169) (xy 179.93996 -308.068325)
			(xy 179.893944 -308.050873) (xy 179.851323 -308.026266) (xy 179.813202 -307.995141) (xy 179.780567 -307.958304)
			(xy 179.754264 -307.916708) (xy 179.734973 -307.871432) (xy 179.723196 -307.823648) (xy 179.719236 -307.774594)
			(xy 179.380134 -307.774594) (xy 179.379639 -307.799201) (xy 179.371744 -307.847778) (xy 179.35616 -307.894459)
			(xy 179.333289 -307.938036) (xy 179.303724 -307.97738) (xy 179.268231 -308.011472) (xy 179.227728 -308.039428)
			(xy 179.183266 -308.060526) (xy 179.135995 -308.074218) (xy 179.08714 -308.08015) (xy 179.037965 -308.078169)
			(xy 178.989746 -308.068325) (xy 178.94373 -308.050873) (xy 178.901109 -308.026266) (xy 178.862988 -307.995141)
			(xy 178.830353 -307.958304) (xy 178.80405 -307.916708) (xy 178.784759 -307.871432) (xy 178.772982 -307.823648)
			(xy 178.769022 -307.774594) (xy 178.430169 -307.774594) (xy 178.430174 -307.774848) (xy 178.429679 -307.799455)
			(xy 178.421784 -307.848032) (xy 178.4062 -307.894713) (xy 178.383329 -307.93829) (xy 178.353764 -307.977634)
			(xy 178.318271 -308.011726) (xy 178.277768 -308.039682) (xy 178.233306 -308.06078) (xy 178.186035 -308.074472)
			(xy 178.13718 -308.080404) (xy 178.088005 -308.078423) (xy 178.039786 -308.068579) (xy 177.99377 -308.051127)
			(xy 177.951149 -308.02652) (xy 177.913028 -307.995395) (xy 177.880393 -307.958558) (xy 177.85409 -307.916962)
			(xy 177.834799 -307.871686) (xy 177.823022 -307.823902) (xy 177.819062 -307.774848) (xy 177.480214 -307.774848)
			(xy 177.479719 -307.799455) (xy 177.471824 -307.848032) (xy 177.45624 -307.894713) (xy 177.433369 -307.93829)
			(xy 177.403804 -307.977634) (xy 177.368311 -308.011726) (xy 177.327808 -308.039682) (xy 177.283346 -308.06078)
			(xy 177.236075 -308.074472) (xy 177.18722 -308.080404) (xy 177.138045 -308.078423) (xy 177.089826 -308.068579)
			(xy 177.04381 -308.051127) (xy 177.001189 -308.02652) (xy 176.963068 -307.995395) (xy 176.930433 -307.958558)
			(xy 176.90413 -307.916962) (xy 176.884839 -307.871686) (xy 176.873062 -307.823902) (xy 176.869102 -307.774848)
			(xy 176.530254 -307.774848) (xy 176.529759 -307.799455) (xy 176.521864 -307.848032) (xy 176.50628 -307.894713)
			(xy 176.483409 -307.93829) (xy 176.453844 -307.977634) (xy 176.418351 -308.011726) (xy 176.377848 -308.039682)
			(xy 176.333386 -308.06078) (xy 176.286115 -308.074472) (xy 176.23726 -308.080404) (xy 176.188085 -308.078423)
			(xy 176.139866 -308.068579) (xy 176.09385 -308.051127) (xy 176.051229 -308.02652) (xy 176.013108 -307.995395)
			(xy 175.980473 -307.958558) (xy 175.95417 -307.916962) (xy 175.934879 -307.871686) (xy 175.923102 -307.823902)
			(xy 175.919142 -307.774848) (xy 174.630334 -307.774848) (xy 174.629839 -307.799455) (xy 174.621944 -307.848032)
			(xy 174.60636 -307.894713) (xy 174.583489 -307.93829) (xy 174.553924 -307.977634) (xy 174.518431 -308.011726)
			(xy 174.477928 -308.039682) (xy 174.433466 -308.06078) (xy 174.386195 -308.074472) (xy 174.33734 -308.080404)
			(xy 174.288165 -308.078423) (xy 174.239946 -308.068579) (xy 174.19393 -308.051127) (xy 174.151309 -308.02652)
			(xy 174.113188 -307.995395) (xy 174.080553 -307.958558) (xy 174.05425 -307.916962) (xy 174.034959 -307.871686)
			(xy 174.023182 -307.823902) (xy 174.019222 -307.774848) (xy 173.680374 -307.774848) (xy 173.679879 -307.799455)
			(xy 173.671984 -307.848032) (xy 173.6564 -307.894713) (xy 173.633529 -307.93829) (xy 173.603964 -307.977634)
			(xy 173.568471 -308.011726) (xy 173.527968 -308.039682) (xy 173.483506 -308.06078) (xy 173.436235 -308.074472)
			(xy 173.38738 -308.080404) (xy 173.338205 -308.078423) (xy 173.289986 -308.068579) (xy 173.24397 -308.051127)
			(xy 173.201349 -308.02652) (xy 173.163228 -307.995395) (xy 173.130593 -307.958558) (xy 173.10429 -307.916962)
			(xy 173.084999 -307.871686) (xy 173.073222 -307.823902) (xy 173.069262 -307.774848) (xy 172.730414 -307.774848)
			(xy 172.729919 -307.799455) (xy 172.722024 -307.848032) (xy 172.70644 -307.894713) (xy 172.683569 -307.93829)
			(xy 172.654004 -307.977634) (xy 172.618511 -308.011726) (xy 172.578008 -308.039682) (xy 172.533546 -308.06078)
			(xy 172.486275 -308.074472) (xy 172.43742 -308.080404) (xy 172.388245 -308.078423) (xy 172.340026 -308.068579)
			(xy 172.29401 -308.051127) (xy 172.251389 -308.02652) (xy 172.213268 -307.995395) (xy 172.180633 -307.958558)
			(xy 172.15433 -307.916962) (xy 172.135039 -307.871686) (xy 172.123262 -307.823902) (xy 172.119302 -307.774848)
			(xy 171.7802 -307.774848) (xy 171.779705 -307.799455) (xy 171.77181 -307.848032) (xy 171.756226 -307.894713)
			(xy 171.733355 -307.93829) (xy 171.70379 -307.977634) (xy 171.668297 -308.011726) (xy 171.627794 -308.039682)
			(xy 171.583332 -308.06078) (xy 171.536061 -308.074472) (xy 171.487206 -308.080404) (xy 171.438031 -308.078423)
			(xy 171.389812 -308.068579) (xy 171.343796 -308.051127) (xy 171.301175 -308.02652) (xy 171.263054 -307.995395)
			(xy 171.230419 -307.958558) (xy 171.204116 -307.916962) (xy 171.184825 -307.871686) (xy 171.173048 -307.823902)
			(xy 171.169088 -307.774848) (xy 170.83024 -307.774848) (xy 170.829745 -307.799455) (xy 170.82185 -307.848032)
			(xy 170.806266 -307.894713) (xy 170.783395 -307.93829) (xy 170.75383 -307.977634) (xy 170.718337 -308.011726)
			(xy 170.677834 -308.039682) (xy 170.633372 -308.06078) (xy 170.586101 -308.074472) (xy 170.537246 -308.080404)
			(xy 170.488071 -308.078423) (xy 170.439852 -308.068579) (xy 170.393836 -308.051127) (xy 170.351215 -308.02652)
			(xy 170.313094 -307.995395) (xy 170.280459 -307.958558) (xy 170.254156 -307.916962) (xy 170.234865 -307.871686)
			(xy 170.223088 -307.823902) (xy 170.219128 -307.774848) (xy 169.88028 -307.774848) (xy 169.879785 -307.799455)
			(xy 169.87189 -307.848032) (xy 169.856306 -307.894713) (xy 169.833435 -307.93829) (xy 169.80387 -307.977634)
			(xy 169.768377 -308.011726) (xy 169.727874 -308.039682) (xy 169.683412 -308.06078) (xy 169.636141 -308.074472)
			(xy 169.587286 -308.080404) (xy 169.538111 -308.078423) (xy 169.489892 -308.068579) (xy 169.443876 -308.051127)
			(xy 169.401255 -308.02652) (xy 169.363134 -307.995395) (xy 169.330499 -307.958558) (xy 169.304196 -307.916962)
			(xy 169.284905 -307.871686) (xy 169.273128 -307.823902) (xy 169.269168 -307.774848) (xy 168.93032 -307.774848)
			(xy 168.929825 -307.799455) (xy 168.92193 -307.848032) (xy 168.906346 -307.894713) (xy 168.883475 -307.93829)
			(xy 168.85391 -307.977634) (xy 168.818417 -308.011726) (xy 168.777914 -308.039682) (xy 168.733452 -308.06078)
			(xy 168.686181 -308.074472) (xy 168.637326 -308.080404) (xy 168.588151 -308.078423) (xy 168.539932 -308.068579)
			(xy 168.493916 -308.051127) (xy 168.451295 -308.02652) (xy 168.413174 -307.995395) (xy 168.380539 -307.958558)
			(xy 168.354236 -307.916962) (xy 168.334945 -307.871686) (xy 168.323168 -307.823902) (xy 168.319208 -307.774848)
			(xy 167.98036 -307.774848) (xy 167.979865 -307.799455) (xy 167.97197 -307.848032) (xy 167.956386 -307.894713)
			(xy 167.933515 -307.93829) (xy 167.90395 -307.977634) (xy 167.868457 -308.011726) (xy 167.827954 -308.039682)
			(xy 167.783492 -308.06078) (xy 167.736221 -308.074472) (xy 167.687366 -308.080404) (xy 167.638191 -308.078423)
			(xy 167.589972 -308.068579) (xy 167.543956 -308.051127) (xy 167.501335 -308.02652) (xy 167.463214 -307.995395)
			(xy 167.430579 -307.958558) (xy 167.404276 -307.916962) (xy 167.384985 -307.871686) (xy 167.373208 -307.823902)
			(xy 167.369248 -307.774848) (xy 167.0304 -307.774848) (xy 167.029905 -307.799455) (xy 167.02201 -307.848032)
			(xy 167.006426 -307.894713) (xy 166.983555 -307.93829) (xy 166.95399 -307.977634) (xy 166.918497 -308.011726)
			(xy 166.877994 -308.039682) (xy 166.833532 -308.06078) (xy 166.786261 -308.074472) (xy 166.737406 -308.080404)
			(xy 166.688231 -308.078423) (xy 166.640012 -308.068579) (xy 166.593996 -308.051127) (xy 166.551375 -308.02652)
			(xy 166.513254 -307.995395) (xy 166.480619 -307.958558) (xy 166.454316 -307.916962) (xy 166.435025 -307.871686)
			(xy 166.423248 -307.823902) (xy 166.419288 -307.774848) (xy 166.080186 -307.774848) (xy 166.079691 -307.799455)
			(xy 166.071796 -307.848032) (xy 166.056212 -307.894713) (xy 166.033341 -307.93829) (xy 166.003776 -307.977634)
			(xy 165.968283 -308.011726) (xy 165.92778 -308.039682) (xy 165.883318 -308.06078) (xy 165.836047 -308.074472)
			(xy 165.787192 -308.080404) (xy 165.738017 -308.078423) (xy 165.689798 -308.068579) (xy 165.643782 -308.051127)
			(xy 165.601161 -308.02652) (xy 165.56304 -307.995395) (xy 165.530405 -307.958558) (xy 165.504102 -307.916962)
			(xy 165.484811 -307.871686) (xy 165.473034 -307.823902) (xy 165.469074 -307.774848) (xy 165.130226 -307.774848)
			(xy 165.129731 -307.799455) (xy 165.121836 -307.848032) (xy 165.106252 -307.894713) (xy 165.083381 -307.93829)
			(xy 165.053816 -307.977634) (xy 165.018323 -308.011726) (xy 164.97782 -308.039682) (xy 164.933358 -308.06078)
			(xy 164.886087 -308.074472) (xy 164.837232 -308.080404) (xy 164.788057 -308.078423) (xy 164.739838 -308.068579)
			(xy 164.693822 -308.051127) (xy 164.651201 -308.02652) (xy 164.61308 -307.995395) (xy 164.580445 -307.958558)
			(xy 164.554142 -307.916962) (xy 164.534851 -307.871686) (xy 164.523074 -307.823902) (xy 164.519114 -307.774848)
			(xy 164.180266 -307.774848) (xy 164.179771 -307.799455) (xy 164.171876 -307.848032) (xy 164.156292 -307.894713)
			(xy 164.133421 -307.93829) (xy 164.103856 -307.977634) (xy 164.068363 -308.011726) (xy 164.02786 -308.039682)
			(xy 163.983398 -308.06078) (xy 163.936127 -308.074472) (xy 163.887272 -308.080404) (xy 163.838097 -308.078423)
			(xy 163.789878 -308.068579) (xy 163.743862 -308.051127) (xy 163.701241 -308.02652) (xy 163.66312 -307.995395)
			(xy 163.630485 -307.958558) (xy 163.604182 -307.916962) (xy 163.584891 -307.871686) (xy 163.573114 -307.823902)
			(xy 163.569154 -307.774848) (xy 163.230306 -307.774848) (xy 163.229811 -307.799455) (xy 163.221916 -307.848032)
			(xy 163.206332 -307.894713) (xy 163.183461 -307.93829) (xy 163.153896 -307.977634) (xy 163.118403 -308.011726)
			(xy 163.0779 -308.039682) (xy 163.033438 -308.06078) (xy 162.986167 -308.074472) (xy 162.937312 -308.080404)
			(xy 162.888137 -308.078423) (xy 162.839918 -308.068579) (xy 162.793902 -308.051127) (xy 162.751281 -308.02652)
			(xy 162.71316 -307.995395) (xy 162.680525 -307.958558) (xy 162.654222 -307.916962) (xy 162.634931 -307.871686)
			(xy 162.623154 -307.823902) (xy 162.619194 -307.774848) (xy 132.637652 -307.774848) (xy 132.643949 -307.796178)
			(xy 132.651784 -307.85035) (xy 132.652262 -307.877718) (xy 132.651776 -307.904969) (xy 132.64402 -307.958917)
			(xy 132.628665 -308.011212) (xy 132.606023 -308.060789) (xy 132.576557 -308.106639) (xy 132.540866 -308.14783)
			(xy 132.499675 -308.183521) (xy 132.453825 -308.212987) (xy 132.404248 -308.235629) (xy 132.351953 -308.250984)
			(xy 132.298005 -308.25874) (xy 132.243503 -308.25874) (xy 132.189555 -308.250984) (xy 132.13726 -308.235629)
			(xy 132.087683 -308.212987) (xy 132.041833 -308.183521) (xy 132.000642 -308.14783) (xy 131.964951 -308.106639)
			(xy 131.935485 -308.060789) (xy 131.912843 -308.011212) (xy 131.897488 -307.958917) (xy 131.889732 -307.904969)
			(xy 131.889246 -307.877718) (xy 129.015752 -307.877718) (xy 129.01182 -307.905069) (xy 128.996465 -307.957364)
			(xy 128.973823 -308.006941) (xy 128.944357 -308.052791) (xy 128.908666 -308.093982) (xy 128.867475 -308.129673)
			(xy 128.821625 -308.159139) (xy 128.772048 -308.181781) (xy 128.719753 -308.197136) (xy 128.665805 -308.204892)
			(xy 128.611303 -308.204892) (xy 128.557355 -308.197136) (xy 128.50506 -308.181781) (xy 128.455483 -308.159139)
			(xy 128.409633 -308.129673) (xy 128.368442 -308.093982) (xy 128.332751 -308.052791) (xy 128.303285 -308.006941)
			(xy 128.280643 -307.957364) (xy 128.265288 -307.905069) (xy 128.257532 -307.851121) (xy 128.257046 -307.82387)
			(xy 125.807734 -307.82387) (xy 125.811564 -307.85035) (xy 125.812042 -307.877718) (xy 125.811556 -307.904969)
			(xy 125.8038 -307.958917) (xy 125.788445 -308.011212) (xy 125.765803 -308.060789) (xy 125.736337 -308.106639)
			(xy 125.700646 -308.14783) (xy 125.659455 -308.183521) (xy 125.613605 -308.212987) (xy 125.564028 -308.235629)
			(xy 125.511733 -308.250984) (xy 125.457785 -308.25874) (xy 125.403283 -308.25874) (xy 125.349335 -308.250984)
			(xy 125.29704 -308.235629) (xy 125.247463 -308.212987) (xy 125.201613 -308.183521) (xy 125.160422 -308.14783)
			(xy 125.124731 -308.106639) (xy 125.095265 -308.060789) (xy 125.072623 -308.011212) (xy 125.057268 -307.958917)
			(xy 125.049512 -307.904969) (xy 125.049026 -307.877718) (xy 122.175532 -307.877718) (xy 122.1716 -307.905069)
			(xy 122.156245 -307.957364) (xy 122.133603 -308.006941) (xy 122.104137 -308.052791) (xy 122.068446 -308.093982)
			(xy 122.027255 -308.129673) (xy 121.981405 -308.159139) (xy 121.931828 -308.181781) (xy 121.879533 -308.197136)
			(xy 121.825585 -308.204892) (xy 121.771083 -308.204892) (xy 121.717135 -308.197136) (xy 121.66484 -308.181781)
			(xy 121.615263 -308.159139) (xy 121.569413 -308.129673) (xy 121.528222 -308.093982) (xy 121.492531 -308.052791)
			(xy 121.463065 -308.006941) (xy 121.440423 -307.957364) (xy 121.425068 -307.905069) (xy 121.417312 -307.851121)
			(xy 121.416826 -307.82387) (xy 118.832884 -307.82387) (xy 118.832884 -308.450488) (xy 144.178272 -308.450488)
			(xy 144.182343 -308.394866) (xy 144.194469 -308.340429) (xy 144.214392 -308.288338) (xy 144.241688 -308.239703)
			(xy 144.275774 -308.19556) (xy 144.315923 -308.156851) (xy 144.361281 -308.1244) (xy 144.410881 -308.098899)
			(xy 144.463665 -308.080892) (xy 144.518508 -308.070762) (xy 144.574242 -308.068725) (xy 144.629679 -308.074825)
			(xy 144.683636 -308.088931) (xy 144.734965 -308.110743) (xy 144.782571 -308.139797) (xy 144.825439 -308.175472)
			(xy 144.862656 -308.217009) (xy 144.884537 -308.250082) (xy 151.693892 -308.250082) (xy 151.697852 -308.201028)
			(xy 151.709629 -308.153244) (xy 151.72892 -308.107968) (xy 151.755223 -308.066372) (xy 151.787858 -308.029535)
			(xy 151.825979 -307.99841) (xy 151.8686 -307.973803) (xy 151.914616 -307.956351) (xy 151.962835 -307.946507)
			(xy 152.01201 -307.944526) (xy 152.060865 -307.950458) (xy 152.108136 -307.96415) (xy 152.152598 -307.985248)
			(xy 152.193101 -308.013204) (xy 152.228594 -308.047296) (xy 152.258159 -308.08664) (xy 152.28103 -308.130217)
			(xy 152.296614 -308.176898) (xy 152.304509 -308.225475) (xy 152.305004 -308.250082) (xy 152.304509 -308.274689)
			(xy 152.304371 -308.275536) (xy 152.623262 -308.275536) (xy 152.623262 -308.22412) (xy 152.631305 -308.173338)
			(xy 152.647193 -308.124439) (xy 152.670536 -308.078627) (xy 152.700757 -308.037031) (xy 152.737113 -308.000675)
			(xy 152.778709 -307.970454) (xy 152.824521 -307.947111) (xy 152.87342 -307.931223) (xy 152.924202 -307.92318)
			(xy 152.975618 -307.92318) (xy 153.0264 -307.931223) (xy 153.075299 -307.947111) (xy 153.121111 -307.970454)
			(xy 153.162707 -308.000675) (xy 153.199063 -308.037031) (xy 153.229284 -308.078627) (xy 153.252627 -308.124439)
			(xy 153.268515 -308.173338) (xy 153.276558 -308.22412) (xy 153.277062 -308.249828) (xy 153.276558 -308.275536)
			(xy 153.573222 -308.275536) (xy 153.573222 -308.22412) (xy 153.581265 -308.173338) (xy 153.597153 -308.124439)
			(xy 153.620496 -308.078627) (xy 153.650717 -308.037031) (xy 153.687073 -308.000675) (xy 153.728669 -307.970454)
			(xy 153.774481 -307.947111) (xy 153.82338 -307.931223) (xy 153.874162 -307.92318) (xy 153.925578 -307.92318)
			(xy 153.97636 -307.931223) (xy 154.025259 -307.947111) (xy 154.071071 -307.970454) (xy 154.112667 -308.000675)
			(xy 154.149023 -308.037031) (xy 154.179244 -308.078627) (xy 154.202587 -308.124439) (xy 154.218475 -308.173338)
			(xy 154.226518 -308.22412) (xy 154.227022 -308.249828) (xy 154.54428 -308.249828) (xy 154.54824 -308.200774)
			(xy 154.560017 -308.15299) (xy 154.579308 -308.107714) (xy 154.605611 -308.066118) (xy 154.638246 -308.029281)
			(xy 154.676367 -307.998156) (xy 154.718988 -307.973549) (xy 154.765004 -307.956097) (xy 154.813223 -307.946253)
			(xy 154.862398 -307.944272) (xy 154.911253 -307.950204) (xy 154.958524 -307.963896) (xy 155.002986 -307.984994)
			(xy 155.043489 -308.01295) (xy 155.078982 -308.047042) (xy 155.108547 -308.086386) (xy 155.131418 -308.129963)
			(xy 155.147002 -308.176644) (xy 155.154897 -308.225221) (xy 155.155392 -308.249828) (xy 155.49424 -308.249828)
			(xy 155.4982 -308.200774) (xy 155.509977 -308.15299) (xy 155.529268 -308.107714) (xy 155.555571 -308.066118)
			(xy 155.588206 -308.029281) (xy 155.626327 -307.998156) (xy 155.668948 -307.973549) (xy 155.714964 -307.956097)
			(xy 155.763183 -307.946253) (xy 155.812358 -307.944272) (xy 155.861213 -307.950204) (xy 155.908484 -307.963896)
			(xy 155.952946 -307.984994) (xy 155.993449 -308.01295) (xy 156.028942 -308.047042) (xy 156.058507 -308.086386)
			(xy 156.081378 -308.129963) (xy 156.096962 -308.176644) (xy 156.104857 -308.225221) (xy 156.105352 -308.249828)
			(xy 156.4442 -308.249828) (xy 156.44816 -308.200774) (xy 156.459937 -308.15299) (xy 156.479228 -308.107714)
			(xy 156.505531 -308.066118) (xy 156.538166 -308.029281) (xy 156.576287 -307.998156) (xy 156.618908 -307.973549)
			(xy 156.664924 -307.956097) (xy 156.713143 -307.946253) (xy 156.762318 -307.944272) (xy 156.811173 -307.950204)
			(xy 156.858444 -307.963896) (xy 156.902906 -307.984994) (xy 156.943409 -308.01295) (xy 156.978902 -308.047042)
			(xy 157.008467 -308.086386) (xy 157.031338 -308.129963) (xy 157.046922 -308.176644) (xy 157.054817 -308.225221)
			(xy 157.055312 -308.249828) (xy 157.39416 -308.249828) (xy 157.39812 -308.200774) (xy 157.409897 -308.15299)
			(xy 157.429188 -308.107714) (xy 157.455491 -308.066118) (xy 157.488126 -308.029281) (xy 157.526247 -307.998156)
			(xy 157.568868 -307.973549) (xy 157.614884 -307.956097) (xy 157.663103 -307.946253) (xy 157.712278 -307.944272)
			(xy 157.761133 -307.950204) (xy 157.808404 -307.963896) (xy 157.852866 -307.984994) (xy 157.893369 -308.01295)
			(xy 157.928862 -308.047042) (xy 157.958427 -308.086386) (xy 157.981298 -308.129963) (xy 157.996882 -308.176644)
			(xy 158.004777 -308.225221) (xy 158.005272 -308.249828) (xy 158.34412 -308.249828) (xy 158.34808 -308.200774)
			(xy 158.359857 -308.15299) (xy 158.379148 -308.107714) (xy 158.405451 -308.066118) (xy 158.438086 -308.029281)
			(xy 158.476207 -307.998156) (xy 158.518828 -307.973549) (xy 158.564844 -307.956097) (xy 158.613063 -307.946253)
			(xy 158.662238 -307.944272) (xy 158.711093 -307.950204) (xy 158.758364 -307.963896) (xy 158.802826 -307.984994)
			(xy 158.843329 -308.01295) (xy 158.878822 -308.047042) (xy 158.908387 -308.086386) (xy 158.931258 -308.129963)
			(xy 158.946842 -308.176644) (xy 158.954737 -308.225221) (xy 158.955232 -308.249828) (xy 158.954737 -308.274435)
			(xy 158.954558 -308.275536) (xy 159.273236 -308.275536) (xy 159.273236 -308.22412) (xy 159.281279 -308.173338)
			(xy 159.297167 -308.124439) (xy 159.32051 -308.078627) (xy 159.350731 -308.037031) (xy 159.387087 -308.000675)
			(xy 159.428683 -307.970454) (xy 159.474495 -307.947111) (xy 159.523394 -307.931223) (xy 159.574176 -307.92318)
			(xy 159.625592 -307.92318) (xy 159.676374 -307.931223) (xy 159.725273 -307.947111) (xy 159.771085 -307.970454)
			(xy 159.812681 -308.000675) (xy 159.849037 -308.037031) (xy 159.879258 -308.078627) (xy 159.902601 -308.124439)
			(xy 159.918489 -308.173338) (xy 159.926532 -308.22412) (xy 159.927036 -308.249828) (xy 159.926532 -308.275536)
			(xy 160.223196 -308.275536) (xy 160.223196 -308.22412) (xy 160.231239 -308.173338) (xy 160.247127 -308.124439)
			(xy 160.27047 -308.078627) (xy 160.300691 -308.037031) (xy 160.337047 -308.000675) (xy 160.378643 -307.970454)
			(xy 160.424455 -307.947111) (xy 160.473354 -307.931223) (xy 160.524136 -307.92318) (xy 160.575552 -307.92318)
			(xy 160.626334 -307.931223) (xy 160.675233 -307.947111) (xy 160.721045 -307.970454) (xy 160.762641 -308.000675)
			(xy 160.798997 -308.037031) (xy 160.829218 -308.078627) (xy 160.852561 -308.124439) (xy 160.868449 -308.173338)
			(xy 160.876492 -308.22412) (xy 160.876996 -308.249828) (xy 161.194254 -308.249828) (xy 161.198214 -308.200774)
			(xy 161.209991 -308.15299) (xy 161.229282 -308.107714) (xy 161.255585 -308.066118) (xy 161.28822 -308.029281)
			(xy 161.326341 -307.998156) (xy 161.368962 -307.973549) (xy 161.414978 -307.956097) (xy 161.463197 -307.946253)
			(xy 161.512372 -307.944272) (xy 161.561227 -307.950204) (xy 161.608498 -307.963896) (xy 161.65296 -307.984994)
			(xy 161.693463 -308.01295) (xy 161.728956 -308.047042) (xy 161.758521 -308.086386) (xy 161.781392 -308.129963)
			(xy 161.796976 -308.176644) (xy 161.804871 -308.225221) (xy 161.805366 -308.249828) (xy 161.804871 -308.274435)
			(xy 161.796976 -308.323012) (xy 161.781392 -308.369693) (xy 161.758521 -308.41327) (xy 161.728956 -308.452614)
			(xy 161.693463 -308.486706) (xy 161.65296 -308.514662) (xy 161.608498 -308.53576) (xy 161.561227 -308.549452)
			(xy 161.512372 -308.555384) (xy 161.463197 -308.553403) (xy 161.414978 -308.543559) (xy 161.368962 -308.526107)
			(xy 161.326341 -308.5015) (xy 161.28822 -308.470375) (xy 161.255585 -308.433538) (xy 161.229282 -308.391942)
			(xy 161.209991 -308.346666) (xy 161.198214 -308.298882) (xy 161.194254 -308.249828) (xy 160.876996 -308.249828)
			(xy 160.876492 -308.275536) (xy 160.868449 -308.326318) (xy 160.852561 -308.375217) (xy 160.829218 -308.421029)
			(xy 160.798997 -308.462625) (xy 160.762641 -308.498981) (xy 160.721045 -308.529202) (xy 160.675233 -308.552545)
			(xy 160.626334 -308.568433) (xy 160.575552 -308.576476) (xy 160.524136 -308.576476) (xy 160.473354 -308.568433)
			(xy 160.424455 -308.552545) (xy 160.378643 -308.529202) (xy 160.337047 -308.498981) (xy 160.300691 -308.462625)
			(xy 160.27047 -308.421029) (xy 160.247127 -308.375217) (xy 160.231239 -308.326318) (xy 160.223196 -308.275536)
			(xy 159.926532 -308.275536) (xy 159.918489 -308.326318) (xy 159.902601 -308.375217) (xy 159.879258 -308.421029)
			(xy 159.849037 -308.462625) (xy 159.812681 -308.498981) (xy 159.771085 -308.529202) (xy 159.725273 -308.552545)
			(xy 159.676374 -308.568433) (xy 159.625592 -308.576476) (xy 159.574176 -308.576476) (xy 159.523394 -308.568433)
			(xy 159.474495 -308.552545) (xy 159.428683 -308.529202) (xy 159.387087 -308.498981) (xy 159.350731 -308.462625)
			(xy 159.32051 -308.421029) (xy 159.297167 -308.375217) (xy 159.281279 -308.326318) (xy 159.273236 -308.275536)
			(xy 158.954558 -308.275536) (xy 158.946842 -308.323012) (xy 158.931258 -308.369693) (xy 158.908387 -308.41327)
			(xy 158.878822 -308.452614) (xy 158.843329 -308.486706) (xy 158.802826 -308.514662) (xy 158.758364 -308.53576)
			(xy 158.711093 -308.549452) (xy 158.662238 -308.555384) (xy 158.613063 -308.553403) (xy 158.564844 -308.543559)
			(xy 158.518828 -308.526107) (xy 158.476207 -308.5015) (xy 158.438086 -308.470375) (xy 158.405451 -308.433538)
			(xy 158.379148 -308.391942) (xy 158.359857 -308.346666) (xy 158.34808 -308.298882) (xy 158.34412 -308.249828)
			(xy 158.005272 -308.249828) (xy 158.004777 -308.274435) (xy 157.996882 -308.323012) (xy 157.981298 -308.369693)
			(xy 157.958427 -308.41327) (xy 157.928862 -308.452614) (xy 157.893369 -308.486706) (xy 157.852866 -308.514662)
			(xy 157.808404 -308.53576) (xy 157.761133 -308.549452) (xy 157.712278 -308.555384) (xy 157.663103 -308.553403)
			(xy 157.614884 -308.543559) (xy 157.568868 -308.526107) (xy 157.526247 -308.5015) (xy 157.488126 -308.470375)
			(xy 157.455491 -308.433538) (xy 157.429188 -308.391942) (xy 157.409897 -308.346666) (xy 157.39812 -308.298882)
			(xy 157.39416 -308.249828) (xy 157.055312 -308.249828) (xy 157.054817 -308.274435) (xy 157.046922 -308.323012)
			(xy 157.031338 -308.369693) (xy 157.008467 -308.41327) (xy 156.978902 -308.452614) (xy 156.943409 -308.486706)
			(xy 156.902906 -308.514662) (xy 156.858444 -308.53576) (xy 156.811173 -308.549452) (xy 156.762318 -308.555384)
			(xy 156.713143 -308.553403) (xy 156.664924 -308.543559) (xy 156.618908 -308.526107) (xy 156.576287 -308.5015)
			(xy 156.538166 -308.470375) (xy 156.505531 -308.433538) (xy 156.479228 -308.391942) (xy 156.459937 -308.346666)
			(xy 156.44816 -308.298882) (xy 156.4442 -308.249828) (xy 156.105352 -308.249828) (xy 156.104857 -308.274435)
			(xy 156.096962 -308.323012) (xy 156.081378 -308.369693) (xy 156.058507 -308.41327) (xy 156.028942 -308.452614)
			(xy 155.993449 -308.486706) (xy 155.952946 -308.514662) (xy 155.908484 -308.53576) (xy 155.861213 -308.549452)
			(xy 155.812358 -308.555384) (xy 155.763183 -308.553403) (xy 155.714964 -308.543559) (xy 155.668948 -308.526107)
			(xy 155.626327 -308.5015) (xy 155.588206 -308.470375) (xy 155.555571 -308.433538) (xy 155.529268 -308.391942)
			(xy 155.509977 -308.346666) (xy 155.4982 -308.298882) (xy 155.49424 -308.249828) (xy 155.155392 -308.249828)
			(xy 155.154897 -308.274435) (xy 155.147002 -308.323012) (xy 155.131418 -308.369693) (xy 155.108547 -308.41327)
			(xy 155.078982 -308.452614) (xy 155.043489 -308.486706) (xy 155.002986 -308.514662) (xy 154.958524 -308.53576)
			(xy 154.911253 -308.549452) (xy 154.862398 -308.555384) (xy 154.813223 -308.553403) (xy 154.765004 -308.543559)
			(xy 154.718988 -308.526107) (xy 154.676367 -308.5015) (xy 154.638246 -308.470375) (xy 154.605611 -308.433538)
			(xy 154.579308 -308.391942) (xy 154.560017 -308.346666) (xy 154.54824 -308.298882) (xy 154.54428 -308.249828)
			(xy 154.227022 -308.249828) (xy 154.226518 -308.275536) (xy 154.218475 -308.326318) (xy 154.202587 -308.375217)
			(xy 154.179244 -308.421029) (xy 154.149023 -308.462625) (xy 154.112667 -308.498981) (xy 154.071071 -308.529202)
			(xy 154.025259 -308.552545) (xy 153.97636 -308.568433) (xy 153.925578 -308.576476) (xy 153.874162 -308.576476)
			(xy 153.82338 -308.568433) (xy 153.774481 -308.552545) (xy 153.728669 -308.529202) (xy 153.687073 -308.498981)
			(xy 153.650717 -308.462625) (xy 153.620496 -308.421029) (xy 153.597153 -308.375217) (xy 153.581265 -308.326318)
			(xy 153.573222 -308.275536) (xy 153.276558 -308.275536) (xy 153.268515 -308.326318) (xy 153.252627 -308.375217)
			(xy 153.229284 -308.421029) (xy 153.199063 -308.462625) (xy 153.162707 -308.498981) (xy 153.121111 -308.529202)
			(xy 153.075299 -308.552545) (xy 153.0264 -308.568433) (xy 152.975618 -308.576476) (xy 152.924202 -308.576476)
			(xy 152.87342 -308.568433) (xy 152.824521 -308.552545) (xy 152.778709 -308.529202) (xy 152.737113 -308.498981)
			(xy 152.700757 -308.462625) (xy 152.670536 -308.421029) (xy 152.647193 -308.375217) (xy 152.631305 -308.326318)
			(xy 152.623262 -308.275536) (xy 152.304371 -308.275536) (xy 152.296614 -308.323266) (xy 152.28103 -308.369947)
			(xy 152.258159 -308.413524) (xy 152.228594 -308.452868) (xy 152.193101 -308.48696) (xy 152.152598 -308.514916)
			(xy 152.108136 -308.536014) (xy 152.060865 -308.549706) (xy 152.01201 -308.555638) (xy 151.962835 -308.553657)
			(xy 151.914616 -308.543813) (xy 151.8686 -308.526361) (xy 151.825979 -308.501754) (xy 151.787858 -308.470629)
			(xy 151.755223 -308.433792) (xy 151.72892 -308.392196) (xy 151.709629 -308.34692) (xy 151.697852 -308.299136)
			(xy 151.693892 -308.250082) (xy 144.884537 -308.250082) (xy 144.893429 -308.263522) (xy 144.917101 -308.314019)
			(xy 144.933169 -308.367426) (xy 144.941289 -308.422602) (xy 144.941798 -308.450488) (xy 144.941289 -308.478374)
			(xy 144.933169 -308.53355) (xy 144.917101 -308.586957) (xy 144.893429 -308.637454) (xy 144.878824 -308.65953)
			(xy 146.505674 -308.65953) (xy 146.509745 -308.603908) (xy 146.521871 -308.549471) (xy 146.541794 -308.49738)
			(xy 146.56909 -308.448745) (xy 146.603176 -308.404602) (xy 146.643325 -308.365893) (xy 146.688683 -308.333442)
			(xy 146.738283 -308.307941) (xy 146.791067 -308.289934) (xy 146.84591 -308.279804) (xy 146.901644 -308.277767)
			(xy 146.957081 -308.283867) (xy 147.011038 -308.297973) (xy 147.062367 -308.319785) (xy 147.109973 -308.348839)
			(xy 147.152841 -308.384514) (xy 147.190058 -308.426051) (xy 147.220831 -308.472564) (xy 147.244503 -308.523061)
			(xy 147.260571 -308.576468) (xy 147.268691 -308.631644) (xy 147.2692 -308.65953) (xy 147.268691 -308.687416)
			(xy 147.263188 -308.724808) (xy 162.619194 -308.724808) (xy 162.623154 -308.675754) (xy 162.634931 -308.62797)
			(xy 162.654222 -308.582694) (xy 162.680525 -308.541098) (xy 162.71316 -308.504261) (xy 162.751281 -308.473136)
			(xy 162.793902 -308.448529) (xy 162.839918 -308.431077) (xy 162.888137 -308.421233) (xy 162.937312 -308.419252)
			(xy 162.986167 -308.425184) (xy 163.033438 -308.438876) (xy 163.0779 -308.459974) (xy 163.118403 -308.48793)
			(xy 163.153896 -308.522022) (xy 163.183461 -308.561366) (xy 163.206332 -308.604943) (xy 163.221916 -308.651624)
			(xy 163.229811 -308.700201) (xy 163.230306 -308.724808) (xy 163.569154 -308.724808) (xy 163.573114 -308.675754)
			(xy 163.584891 -308.62797) (xy 163.604182 -308.582694) (xy 163.630485 -308.541098) (xy 163.66312 -308.504261)
			(xy 163.701241 -308.473136) (xy 163.743862 -308.448529) (xy 163.789878 -308.431077) (xy 163.838097 -308.421233)
			(xy 163.887272 -308.419252) (xy 163.936127 -308.425184) (xy 163.983398 -308.438876) (xy 164.02786 -308.459974)
			(xy 164.068363 -308.48793) (xy 164.103856 -308.522022) (xy 164.133421 -308.561366) (xy 164.156292 -308.604943)
			(xy 164.171876 -308.651624) (xy 164.179771 -308.700201) (xy 164.180266 -308.724808) (xy 164.519114 -308.724808)
			(xy 164.523074 -308.675754) (xy 164.534851 -308.62797) (xy 164.554142 -308.582694) (xy 164.580445 -308.541098)
			(xy 164.61308 -308.504261) (xy 164.651201 -308.473136) (xy 164.693822 -308.448529) (xy 164.739838 -308.431077)
			(xy 164.788057 -308.421233) (xy 164.837232 -308.419252) (xy 164.886087 -308.425184) (xy 164.933358 -308.438876)
			(xy 164.97782 -308.459974) (xy 165.018323 -308.48793) (xy 165.053816 -308.522022) (xy 165.083381 -308.561366)
			(xy 165.106252 -308.604943) (xy 165.121836 -308.651624) (xy 165.129731 -308.700201) (xy 165.130226 -308.724808)
			(xy 165.469074 -308.724808) (xy 165.473034 -308.675754) (xy 165.484811 -308.62797) (xy 165.504102 -308.582694)
			(xy 165.530405 -308.541098) (xy 165.56304 -308.504261) (xy 165.601161 -308.473136) (xy 165.643782 -308.448529)
			(xy 165.689798 -308.431077) (xy 165.738017 -308.421233) (xy 165.787192 -308.419252) (xy 165.836047 -308.425184)
			(xy 165.883318 -308.438876) (xy 165.92778 -308.459974) (xy 165.968283 -308.48793) (xy 166.003776 -308.522022)
			(xy 166.033341 -308.561366) (xy 166.056212 -308.604943) (xy 166.071796 -308.651624) (xy 166.079691 -308.700201)
			(xy 166.080186 -308.724808) (xy 166.419288 -308.724808) (xy 166.423248 -308.675754) (xy 166.435025 -308.62797)
			(xy 166.454316 -308.582694) (xy 166.480619 -308.541098) (xy 166.513254 -308.504261) (xy 166.551375 -308.473136)
			(xy 166.593996 -308.448529) (xy 166.640012 -308.431077) (xy 166.688231 -308.421233) (xy 166.737406 -308.419252)
			(xy 166.786261 -308.425184) (xy 166.833532 -308.438876) (xy 166.877994 -308.459974) (xy 166.918497 -308.48793)
			(xy 166.95399 -308.522022) (xy 166.983555 -308.561366) (xy 167.006426 -308.604943) (xy 167.02201 -308.651624)
			(xy 167.029905 -308.700201) (xy 167.0304 -308.724808) (xy 167.369248 -308.724808) (xy 167.373208 -308.675754)
			(xy 167.384985 -308.62797) (xy 167.404276 -308.582694) (xy 167.430579 -308.541098) (xy 167.463214 -308.504261)
			(xy 167.501335 -308.473136) (xy 167.543956 -308.448529) (xy 167.589972 -308.431077) (xy 167.638191 -308.421233)
			(xy 167.687366 -308.419252) (xy 167.736221 -308.425184) (xy 167.783492 -308.438876) (xy 167.827954 -308.459974)
			(xy 167.868457 -308.48793) (xy 167.90395 -308.522022) (xy 167.933515 -308.561366) (xy 167.956386 -308.604943)
			(xy 167.97197 -308.651624) (xy 167.979865 -308.700201) (xy 167.98036 -308.724808) (xy 168.319208 -308.724808)
			(xy 168.323168 -308.675754) (xy 168.334945 -308.62797) (xy 168.354236 -308.582694) (xy 168.380539 -308.541098)
			(xy 168.413174 -308.504261) (xy 168.451295 -308.473136) (xy 168.493916 -308.448529) (xy 168.539932 -308.431077)
			(xy 168.588151 -308.421233) (xy 168.637326 -308.419252) (xy 168.686181 -308.425184) (xy 168.733452 -308.438876)
			(xy 168.777914 -308.459974) (xy 168.818417 -308.48793) (xy 168.85391 -308.522022) (xy 168.883475 -308.561366)
			(xy 168.906346 -308.604943) (xy 168.92193 -308.651624) (xy 168.929825 -308.700201) (xy 168.93032 -308.724808)
			(xy 169.269168 -308.724808) (xy 169.273128 -308.675754) (xy 169.284905 -308.62797) (xy 169.304196 -308.582694)
			(xy 169.330499 -308.541098) (xy 169.363134 -308.504261) (xy 169.401255 -308.473136) (xy 169.443876 -308.448529)
			(xy 169.489892 -308.431077) (xy 169.538111 -308.421233) (xy 169.587286 -308.419252) (xy 169.636141 -308.425184)
			(xy 169.683412 -308.438876) (xy 169.727874 -308.459974) (xy 169.768377 -308.48793) (xy 169.80387 -308.522022)
			(xy 169.833435 -308.561366) (xy 169.856306 -308.604943) (xy 169.87189 -308.651624) (xy 169.879785 -308.700201)
			(xy 169.88028 -308.724808) (xy 170.219128 -308.724808) (xy 170.223088 -308.675754) (xy 170.234865 -308.62797)
			(xy 170.254156 -308.582694) (xy 170.280459 -308.541098) (xy 170.313094 -308.504261) (xy 170.351215 -308.473136)
			(xy 170.393836 -308.448529) (xy 170.439852 -308.431077) (xy 170.488071 -308.421233) (xy 170.537246 -308.419252)
			(xy 170.586101 -308.425184) (xy 170.633372 -308.438876) (xy 170.677834 -308.459974) (xy 170.718337 -308.48793)
			(xy 170.75383 -308.522022) (xy 170.783395 -308.561366) (xy 170.806266 -308.604943) (xy 170.82185 -308.651624)
			(xy 170.829745 -308.700201) (xy 170.83024 -308.724808) (xy 171.169088 -308.724808) (xy 171.173048 -308.675754)
			(xy 171.184825 -308.62797) (xy 171.204116 -308.582694) (xy 171.230419 -308.541098) (xy 171.263054 -308.504261)
			(xy 171.301175 -308.473136) (xy 171.343796 -308.448529) (xy 171.389812 -308.431077) (xy 171.438031 -308.421233)
			(xy 171.487206 -308.419252) (xy 171.536061 -308.425184) (xy 171.583332 -308.438876) (xy 171.627794 -308.459974)
			(xy 171.668297 -308.48793) (xy 171.70379 -308.522022) (xy 171.733355 -308.561366) (xy 171.756226 -308.604943)
			(xy 171.77181 -308.651624) (xy 171.779705 -308.700201) (xy 171.7802 -308.724808) (xy 172.119302 -308.724808)
			(xy 172.123262 -308.675754) (xy 172.135039 -308.62797) (xy 172.15433 -308.582694) (xy 172.180633 -308.541098)
			(xy 172.213268 -308.504261) (xy 172.251389 -308.473136) (xy 172.29401 -308.448529) (xy 172.340026 -308.431077)
			(xy 172.388245 -308.421233) (xy 172.43742 -308.419252) (xy 172.486275 -308.425184) (xy 172.533546 -308.438876)
			(xy 172.578008 -308.459974) (xy 172.618511 -308.48793) (xy 172.654004 -308.522022) (xy 172.683569 -308.561366)
			(xy 172.70644 -308.604943) (xy 172.722024 -308.651624) (xy 172.729919 -308.700201) (xy 172.730414 -308.724808)
			(xy 174.019222 -308.724808) (xy 174.023182 -308.675754) (xy 174.034959 -308.62797) (xy 174.05425 -308.582694)
			(xy 174.080553 -308.541098) (xy 174.113188 -308.504261) (xy 174.151309 -308.473136) (xy 174.19393 -308.448529)
			(xy 174.239946 -308.431077) (xy 174.288165 -308.421233) (xy 174.33734 -308.419252) (xy 174.386195 -308.425184)
			(xy 174.433466 -308.438876) (xy 174.477928 -308.459974) (xy 174.518431 -308.48793) (xy 174.553924 -308.522022)
			(xy 174.583489 -308.561366) (xy 174.60636 -308.604943) (xy 174.621944 -308.651624) (xy 174.629839 -308.700201)
			(xy 174.630334 -308.724808) (xy 174.630167 -308.733111) (xy 175.919135 -308.733111) (xy 175.921819 -308.683533)
			(xy 175.932489 -308.635042) (xy 175.950863 -308.588915) (xy 175.976458 -308.54637) (xy 176.008598 -308.508525)
			(xy 176.046439 -308.47638) (xy 176.088981 -308.45078) (xy 176.135105 -308.4324) (xy 176.183595 -308.421724)
			(xy 176.233173 -308.419034) (xy 176.282533 -308.424401) (xy 176.330375 -308.437683) (xy 176.375438 -308.45853)
			(xy 176.416534 -308.486394) (xy 176.45258 -308.520538) (xy 176.482628 -308.560065) (xy 176.505884 -308.603933)
			(xy 176.521737 -308.650985) (xy 176.529769 -308.699982) (xy 176.530254 -308.724808) (xy 176.530078 -308.738991)
			(xy 176.527405 -308.767231) (xy 176.52492 -308.781196) (xy 176.522634 -308.793642) (xy 176.53 -308.817264)
			(xy 176.60747 -308.894734) (xy 176.631092 -308.9021) (xy 176.643538 -308.899814) (xy 176.657504 -308.897336)
			(xy 176.685743 -308.894665) (xy 176.699926 -308.89448) (xy 176.714109 -308.894653) (xy 176.742349 -308.897328)
			(xy 176.756314 -308.899814) (xy 176.76876 -308.9021) (xy 176.792382 -308.894734) (xy 176.869852 -308.817264)
			(xy 176.877218 -308.793642) (xy 176.874932 -308.781196) (xy 176.872459 -308.76723) (xy 176.869785 -308.73899)
			(xy 176.869598 -308.724808) (xy 176.87012 -308.699553) (xy 176.878433 -308.649731) (xy 176.894834 -308.601957)
			(xy 176.918875 -308.557534) (xy 176.949899 -308.517674) (xy 176.987061 -308.483464) (xy 177.029347 -308.455838)
			(xy 177.075603 -308.435548) (xy 177.124568 -308.423148) (xy 177.174906 -308.418977) (xy 177.225244 -308.423148)
			(xy 177.274209 -308.435548) (xy 177.320465 -308.455838) (xy 177.362751 -308.483464) (xy 177.399913 -308.517674)
			(xy 177.430937 -308.557534) (xy 177.454978 -308.601957) (xy 177.471379 -308.649731) (xy 177.479692 -308.699553)
			(xy 177.480214 -308.724808) (xy 177.480038 -308.738991) (xy 177.477366 -308.767231) (xy 177.47488 -308.781196)
			(xy 177.472594 -308.793642) (xy 177.47996 -308.817264) (xy 177.55743 -308.894734) (xy 177.581052 -308.9021)
			(xy 177.593498 -308.899814) (xy 177.607465 -308.897342) (xy 177.635704 -308.894667) (xy 177.649886 -308.89448)
			(xy 177.664069 -308.894659) (xy 177.692309 -308.897329) (xy 177.706274 -308.899814) (xy 177.71872 -308.9021)
			(xy 177.742342 -308.894734) (xy 177.819812 -308.817264) (xy 177.827178 -308.793642) (xy 177.824892 -308.781196)
			(xy 177.822419 -308.76723) (xy 177.819745 -308.73899) (xy 177.819558 -308.724808) (xy 177.820069 -308.699986)
			(xy 177.8281 -308.650995) (xy 177.843951 -308.603949) (xy 177.867204 -308.560087) (xy 177.897247 -308.520566)
			(xy 177.933289 -308.486425) (xy 177.974379 -308.458565) (xy 178.019435 -308.43772) (xy 178.06727 -308.42444)
			(xy 178.116624 -308.419073) (xy 178.166195 -308.421762) (xy 178.214679 -308.432435) (xy 178.260797 -308.450812)
			(xy 178.303334 -308.476408) (xy 178.34117 -308.508548) (xy 178.373307 -308.546387) (xy 178.3989 -308.588926)
			(xy 178.417273 -308.635046) (xy 178.427942 -308.68353) (xy 178.430163 -308.724554) (xy 178.769022 -308.724554)
			(xy 178.772982 -308.6755) (xy 178.784759 -308.627716) (xy 178.80405 -308.58244) (xy 178.830353 -308.540844)
			(xy 178.862988 -308.504007) (xy 178.901109 -308.472882) (xy 178.94373 -308.448275) (xy 178.989746 -308.430823)
			(xy 179.037965 -308.420979) (xy 179.08714 -308.418998) (xy 179.135995 -308.42493) (xy 179.183266 -308.438622)
			(xy 179.227728 -308.45972) (xy 179.268231 -308.487676) (xy 179.303724 -308.521768) (xy 179.333289 -308.561112)
			(xy 179.35616 -308.604689) (xy 179.371744 -308.65137) (xy 179.379639 -308.699947) (xy 179.380134 -308.724554)
			(xy 179.380129 -308.724808) (xy 179.719236 -308.724808) (xy 179.723196 -308.675754) (xy 179.734973 -308.62797)
			(xy 179.754264 -308.582694) (xy 179.780567 -308.541098) (xy 179.813202 -308.504261) (xy 179.851323 -308.473136)
			(xy 179.893944 -308.448529) (xy 179.93996 -308.431077) (xy 179.988179 -308.421233) (xy 180.037354 -308.419252)
			(xy 180.086209 -308.425184) (xy 180.13348 -308.438876) (xy 180.177942 -308.459974) (xy 180.218445 -308.48793)
			(xy 180.253938 -308.522022) (xy 180.283503 -308.561366) (xy 180.306374 -308.604943) (xy 180.321958 -308.651624)
			(xy 180.329853 -308.700201) (xy 180.330348 -308.724808) (xy 180.669196 -308.724808) (xy 180.673156 -308.675754)
			(xy 180.684933 -308.62797) (xy 180.704224 -308.582694) (xy 180.730527 -308.541098) (xy 180.763162 -308.504261)
			(xy 180.801283 -308.473136) (xy 180.843904 -308.448529) (xy 180.88992 -308.431077) (xy 180.938139 -308.421233)
			(xy 180.987314 -308.419252) (xy 181.036169 -308.425184) (xy 181.08344 -308.438876) (xy 181.127902 -308.459974)
			(xy 181.168405 -308.48793) (xy 181.203898 -308.522022) (xy 181.233463 -308.561366) (xy 181.256334 -308.604943)
			(xy 181.271918 -308.651624) (xy 181.279813 -308.700201) (xy 181.280308 -308.724808) (xy 181.619156 -308.724808)
			(xy 181.623116 -308.675754) (xy 181.634893 -308.62797) (xy 181.654184 -308.582694) (xy 181.680487 -308.541098)
			(xy 181.713122 -308.504261) (xy 181.751243 -308.473136) (xy 181.793864 -308.448529) (xy 181.83988 -308.431077)
			(xy 181.888099 -308.421233) (xy 181.937274 -308.419252) (xy 181.986129 -308.425184) (xy 182.0334 -308.438876)
			(xy 182.077862 -308.459974) (xy 182.118365 -308.48793) (xy 182.153858 -308.522022) (xy 182.183423 -308.561366)
			(xy 182.206294 -308.604943) (xy 182.221878 -308.651624) (xy 182.229773 -308.700201) (xy 182.230268 -308.724808)
			(xy 182.569116 -308.724808) (xy 182.573076 -308.675754) (xy 182.584853 -308.62797) (xy 182.604144 -308.582694)
			(xy 182.630447 -308.541098) (xy 182.663082 -308.504261) (xy 182.701203 -308.473136) (xy 182.743824 -308.448529)
			(xy 182.78984 -308.431077) (xy 182.838059 -308.421233) (xy 182.887234 -308.419252) (xy 182.936089 -308.425184)
			(xy 182.98336 -308.438876) (xy 183.027822 -308.459974) (xy 183.068325 -308.48793) (xy 183.103818 -308.522022)
			(xy 183.133383 -308.561366) (xy 183.156254 -308.604943) (xy 183.171838 -308.651624) (xy 183.179733 -308.700201)
			(xy 183.180228 -308.724808) (xy 183.519076 -308.724808) (xy 183.523036 -308.675754) (xy 183.534813 -308.62797)
			(xy 183.554104 -308.582694) (xy 183.580407 -308.541098) (xy 183.613042 -308.504261) (xy 183.651163 -308.473136)
			(xy 183.693784 -308.448529) (xy 183.7398 -308.431077) (xy 183.788019 -308.421233) (xy 183.837194 -308.419252)
			(xy 183.886049 -308.425184) (xy 183.93332 -308.438876) (xy 183.977782 -308.459974) (xy 184.018285 -308.48793)
			(xy 184.053778 -308.522022) (xy 184.083343 -308.561366) (xy 184.106214 -308.604943) (xy 184.121798 -308.651624)
			(xy 184.129693 -308.700201) (xy 184.130188 -308.724808) (xy 184.46929 -308.724808) (xy 184.47325 -308.675754)
			(xy 184.485027 -308.62797) (xy 184.504318 -308.582694) (xy 184.530621 -308.541098) (xy 184.563256 -308.504261)
			(xy 184.601377 -308.473136) (xy 184.643998 -308.448529) (xy 184.690014 -308.431077) (xy 184.738233 -308.421233)
			(xy 184.787408 -308.419252) (xy 184.836263 -308.425184) (xy 184.883534 -308.438876) (xy 184.927996 -308.459974)
			(xy 184.968499 -308.48793) (xy 185.003992 -308.522022) (xy 185.033557 -308.561366) (xy 185.056428 -308.604943)
			(xy 185.072012 -308.651624) (xy 185.079907 -308.700201) (xy 185.080402 -308.724808) (xy 185.079907 -308.749415)
			(xy 185.072012 -308.797992) (xy 185.056428 -308.844673) (xy 185.033557 -308.88825) (xy 185.003992 -308.927594)
			(xy 184.968499 -308.961686) (xy 184.927996 -308.989642) (xy 184.883534 -309.01074) (xy 184.836263 -309.024432)
			(xy 184.787408 -309.030364) (xy 184.738233 -309.028383) (xy 184.690014 -309.018539) (xy 184.643998 -309.001087)
			(xy 184.601377 -308.97648) (xy 184.563256 -308.945355) (xy 184.530621 -308.908518) (xy 184.504318 -308.866922)
			(xy 184.485027 -308.821646) (xy 184.47325 -308.773862) (xy 184.46929 -308.724808) (xy 184.130188 -308.724808)
			(xy 184.129693 -308.749415) (xy 184.121798 -308.797992) (xy 184.106214 -308.844673) (xy 184.083343 -308.88825)
			(xy 184.053778 -308.927594) (xy 184.018285 -308.961686) (xy 183.977782 -308.989642) (xy 183.93332 -309.01074)
			(xy 183.886049 -309.024432) (xy 183.837194 -309.030364) (xy 183.788019 -309.028383) (xy 183.7398 -309.018539)
			(xy 183.693784 -309.001087) (xy 183.651163 -308.97648) (xy 183.613042 -308.945355) (xy 183.580407 -308.908518)
			(xy 183.554104 -308.866922) (xy 183.534813 -308.821646) (xy 183.523036 -308.773862) (xy 183.519076 -308.724808)
			(xy 183.180228 -308.724808) (xy 183.179733 -308.749415) (xy 183.171838 -308.797992) (xy 183.156254 -308.844673)
			(xy 183.133383 -308.88825) (xy 183.103818 -308.927594) (xy 183.068325 -308.961686) (xy 183.027822 -308.989642)
			(xy 182.98336 -309.01074) (xy 182.936089 -309.024432) (xy 182.887234 -309.030364) (xy 182.838059 -309.028383)
			(xy 182.78984 -309.018539) (xy 182.743824 -309.001087) (xy 182.701203 -308.97648) (xy 182.663082 -308.945355)
			(xy 182.630447 -308.908518) (xy 182.604144 -308.866922) (xy 182.584853 -308.821646) (xy 182.573076 -308.773862)
			(xy 182.569116 -308.724808) (xy 182.230268 -308.724808) (xy 182.229773 -308.749415) (xy 182.221878 -308.797992)
			(xy 182.206294 -308.844673) (xy 182.183423 -308.88825) (xy 182.153858 -308.927594) (xy 182.118365 -308.961686)
			(xy 182.077862 -308.989642) (xy 182.0334 -309.01074) (xy 181.986129 -309.024432) (xy 181.937274 -309.030364)
			(xy 181.888099 -309.028383) (xy 181.83988 -309.018539) (xy 181.793864 -309.001087) (xy 181.751243 -308.97648)
			(xy 181.713122 -308.945355) (xy 181.680487 -308.908518) (xy 181.654184 -308.866922) (xy 181.634893 -308.821646)
			(xy 181.623116 -308.773862) (xy 181.619156 -308.724808) (xy 181.280308 -308.724808) (xy 181.279813 -308.749415)
			(xy 181.271918 -308.797992) (xy 181.256334 -308.844673) (xy 181.233463 -308.88825) (xy 181.203898 -308.927594)
			(xy 181.168405 -308.961686) (xy 181.127902 -308.989642) (xy 181.08344 -309.01074) (xy 181.036169 -309.024432)
			(xy 180.987314 -309.030364) (xy 180.938139 -309.028383) (xy 180.88992 -309.018539) (xy 180.843904 -309.001087)
			(xy 180.801283 -308.97648) (xy 180.763162 -308.945355) (xy 180.730527 -308.908518) (xy 180.704224 -308.866922)
			(xy 180.684933 -308.821646) (xy 180.673156 -308.773862) (xy 180.669196 -308.724808) (xy 180.330348 -308.724808)
			(xy 180.329853 -308.749415) (xy 180.321958 -308.797992) (xy 180.306374 -308.844673) (xy 180.283503 -308.88825)
			(xy 180.253938 -308.927594) (xy 180.218445 -308.961686) (xy 180.177942 -308.989642) (xy 180.13348 -309.01074)
			(xy 180.086209 -309.024432) (xy 180.037354 -309.030364) (xy 179.988179 -309.028383) (xy 179.93996 -309.018539)
			(xy 179.893944 -309.001087) (xy 179.851323 -308.97648) (xy 179.813202 -308.945355) (xy 179.780567 -308.908518)
			(xy 179.754264 -308.866922) (xy 179.734973 -308.821646) (xy 179.723196 -308.773862) (xy 179.719236 -308.724808)
			(xy 179.380129 -308.724808) (xy 179.379639 -308.749161) (xy 179.371744 -308.797738) (xy 179.35616 -308.844419)
			(xy 179.333289 -308.887996) (xy 179.303724 -308.92734) (xy 179.268231 -308.961432) (xy 179.227728 -308.989388)
			(xy 179.183266 -309.010486) (xy 179.135995 -309.024178) (xy 179.08714 -309.03011) (xy 179.037965 -309.028129)
			(xy 178.989746 -309.018285) (xy 178.94373 -309.000833) (xy 178.901109 -308.976226) (xy 178.862988 -308.945101)
			(xy 178.830353 -308.908264) (xy 178.80405 -308.866668) (xy 178.784759 -308.821392) (xy 178.772982 -308.773608)
			(xy 178.769022 -308.724554) (xy 178.430163 -308.724554) (xy 178.430626 -308.733102) (xy 178.425255 -308.782455)
			(xy 178.411971 -308.830289) (xy 178.391122 -308.875344) (xy 178.363259 -308.916432) (xy 178.329115 -308.95247)
			(xy 178.289591 -308.98251) (xy 178.245727 -309.00576) (xy 178.19868 -309.021606) (xy 178.149688 -309.029633)
			(xy 178.124866 -309.030116) (xy 178.110683 -309.029944) (xy 178.082443 -309.027269) (xy 178.068478 -309.024782)
			(xy 178.056032 -309.022496) (xy 178.03241 -309.029862) (xy 177.95494 -309.107332) (xy 177.947574 -309.130954)
			(xy 177.94986 -309.1434) (xy 177.952332 -309.157367) (xy 177.955007 -309.185606) (xy 177.955194 -309.199788)
			(xy 177.954672 -309.225043) (xy 177.946359 -309.274865) (xy 177.929958 -309.322639) (xy 177.905917 -309.367062)
			(xy 177.874893 -309.406922) (xy 177.837731 -309.441132) (xy 177.795445 -309.468758) (xy 177.749189 -309.489048)
			(xy 177.700224 -309.501448) (xy 177.649886 -309.505619) (xy 177.599548 -309.501448) (xy 177.550583 -309.489048)
			(xy 177.504327 -309.468758) (xy 177.462041 -309.441132) (xy 177.424879 -309.406922) (xy 177.393855 -309.367062)
			(xy 177.369814 -309.322639) (xy 177.353413 -309.274865) (xy 177.3451 -309.225043) (xy 177.344578 -309.199788)
			(xy 177.344753 -309.185605) (xy 177.347426 -309.157365) (xy 177.349912 -309.1434) (xy 177.352198 -309.130954)
			(xy 177.344832 -309.107332) (xy 177.267362 -309.029862) (xy 177.24374 -309.022496) (xy 177.231294 -309.024782)
			(xy 177.217328 -309.027255) (xy 177.189088 -309.029929) (xy 177.174906 -309.030116) (xy 177.160723 -309.029938)
			(xy 177.132483 -309.027267) (xy 177.118518 -309.024782) (xy 177.106072 -309.022496) (xy 177.08245 -309.029862)
			(xy 177.00498 -309.107332) (xy 176.997614 -309.130954) (xy 176.9999 -309.1434) (xy 177.002373 -309.157367)
			(xy 177.005047 -309.185606) (xy 177.005234 -309.199788) (xy 177.004712 -309.225043) (xy 176.996399 -309.274865)
			(xy 176.979998 -309.322639) (xy 176.955957 -309.367062) (xy 176.924933 -309.406922) (xy 176.887771 -309.441132)
			(xy 176.845485 -309.468758) (xy 176.799229 -309.489048) (xy 176.750264 -309.501448) (xy 176.699926 -309.505619)
			(xy 176.649588 -309.501448) (xy 176.600623 -309.489048) (xy 176.554367 -309.468758) (xy 176.512081 -309.441132)
			(xy 176.474919 -309.406922) (xy 176.443895 -309.367062) (xy 176.419854 -309.322639) (xy 176.403453 -309.274865)
			(xy 176.39514 -309.225043) (xy 176.394618 -309.199788) (xy 176.394793 -309.185605) (xy 176.397466 -309.157365)
			(xy 176.399952 -309.1434) (xy 176.402238 -309.130954) (xy 176.394872 -309.107332) (xy 176.317402 -309.029862)
			(xy 176.29378 -309.022496) (xy 176.281334 -309.024782) (xy 176.267369 -309.027263) (xy 176.239129 -309.029932)
			(xy 176.224946 -309.030116) (xy 176.20012 -309.029672) (xy 176.151122 -309.021647) (xy 176.104068 -309.005799)
			(xy 176.060198 -308.982548) (xy 176.020667 -308.952506) (xy 175.986517 -308.916463) (xy 175.958649 -308.875371)
			(xy 175.937796 -308.830311) (xy 175.924508 -308.782471) (xy 175.919135 -308.733111) (xy 174.630167 -308.733111)
			(xy 174.629839 -308.749415) (xy 174.621944 -308.797992) (xy 174.60636 -308.844673) (xy 174.583489 -308.88825)
			(xy 174.553924 -308.927594) (xy 174.518431 -308.961686) (xy 174.477928 -308.989642) (xy 174.433466 -309.01074)
			(xy 174.386195 -309.024432) (xy 174.33734 -309.030364) (xy 174.288165 -309.028383) (xy 174.239946 -309.018539)
			(xy 174.19393 -309.001087) (xy 174.151309 -308.97648) (xy 174.113188 -308.945355) (xy 174.080553 -308.908518)
			(xy 174.05425 -308.866922) (xy 174.034959 -308.821646) (xy 174.023182 -308.773862) (xy 174.019222 -308.724808)
			(xy 172.730414 -308.724808) (xy 172.729919 -308.749415) (xy 172.722024 -308.797992) (xy 172.70644 -308.844673)
			(xy 172.683569 -308.88825) (xy 172.654004 -308.927594) (xy 172.618511 -308.961686) (xy 172.578008 -308.989642)
			(xy 172.533546 -309.01074) (xy 172.486275 -309.024432) (xy 172.43742 -309.030364) (xy 172.388245 -309.028383)
			(xy 172.340026 -309.018539) (xy 172.29401 -309.001087) (xy 172.251389 -308.97648) (xy 172.213268 -308.945355)
			(xy 172.180633 -308.908518) (xy 172.15433 -308.866922) (xy 172.135039 -308.821646) (xy 172.123262 -308.773862)
			(xy 172.119302 -308.724808) (xy 171.7802 -308.724808) (xy 171.779705 -308.749415) (xy 171.77181 -308.797992)
			(xy 171.756226 -308.844673) (xy 171.733355 -308.88825) (xy 171.70379 -308.927594) (xy 171.668297 -308.961686)
			(xy 171.627794 -308.989642) (xy 171.583332 -309.01074) (xy 171.536061 -309.024432) (xy 171.487206 -309.030364)
			(xy 171.438031 -309.028383) (xy 171.389812 -309.018539) (xy 171.343796 -309.001087) (xy 171.301175 -308.97648)
			(xy 171.263054 -308.945355) (xy 171.230419 -308.908518) (xy 171.204116 -308.866922) (xy 171.184825 -308.821646)
			(xy 171.173048 -308.773862) (xy 171.169088 -308.724808) (xy 170.83024 -308.724808) (xy 170.829745 -308.749415)
			(xy 170.82185 -308.797992) (xy 170.806266 -308.844673) (xy 170.783395 -308.88825) (xy 170.75383 -308.927594)
			(xy 170.718337 -308.961686) (xy 170.677834 -308.989642) (xy 170.633372 -309.01074) (xy 170.586101 -309.024432)
			(xy 170.537246 -309.030364) (xy 170.488071 -309.028383) (xy 170.439852 -309.018539) (xy 170.393836 -309.001087)
			(xy 170.351215 -308.97648) (xy 170.313094 -308.945355) (xy 170.280459 -308.908518) (xy 170.254156 -308.866922)
			(xy 170.234865 -308.821646) (xy 170.223088 -308.773862) (xy 170.219128 -308.724808) (xy 169.88028 -308.724808)
			(xy 169.879785 -308.749415) (xy 169.87189 -308.797992) (xy 169.856306 -308.844673) (xy 169.833435 -308.88825)
			(xy 169.80387 -308.927594) (xy 169.768377 -308.961686) (xy 169.727874 -308.989642) (xy 169.683412 -309.01074)
			(xy 169.636141 -309.024432) (xy 169.587286 -309.030364) (xy 169.538111 -309.028383) (xy 169.489892 -309.018539)
			(xy 169.443876 -309.001087) (xy 169.401255 -308.97648) (xy 169.363134 -308.945355) (xy 169.330499 -308.908518)
			(xy 169.304196 -308.866922) (xy 169.284905 -308.821646) (xy 169.273128 -308.773862) (xy 169.269168 -308.724808)
			(xy 168.93032 -308.724808) (xy 168.929825 -308.749415) (xy 168.92193 -308.797992) (xy 168.906346 -308.844673)
			(xy 168.883475 -308.88825) (xy 168.85391 -308.927594) (xy 168.818417 -308.961686) (xy 168.777914 -308.989642)
			(xy 168.733452 -309.01074) (xy 168.686181 -309.024432) (xy 168.637326 -309.030364) (xy 168.588151 -309.028383)
			(xy 168.539932 -309.018539) (xy 168.493916 -309.001087) (xy 168.451295 -308.97648) (xy 168.413174 -308.945355)
			(xy 168.380539 -308.908518) (xy 168.354236 -308.866922) (xy 168.334945 -308.821646) (xy 168.323168 -308.773862)
			(xy 168.319208 -308.724808) (xy 167.98036 -308.724808) (xy 167.979865 -308.749415) (xy 167.97197 -308.797992)
			(xy 167.956386 -308.844673) (xy 167.933515 -308.88825) (xy 167.90395 -308.927594) (xy 167.868457 -308.961686)
			(xy 167.827954 -308.989642) (xy 167.783492 -309.01074) (xy 167.736221 -309.024432) (xy 167.687366 -309.030364)
			(xy 167.638191 -309.028383) (xy 167.589972 -309.018539) (xy 167.543956 -309.001087) (xy 167.501335 -308.97648)
			(xy 167.463214 -308.945355) (xy 167.430579 -308.908518) (xy 167.404276 -308.866922) (xy 167.384985 -308.821646)
			(xy 167.373208 -308.773862) (xy 167.369248 -308.724808) (xy 167.0304 -308.724808) (xy 167.029905 -308.749415)
			(xy 167.02201 -308.797992) (xy 167.006426 -308.844673) (xy 166.983555 -308.88825) (xy 166.95399 -308.927594)
			(xy 166.918497 -308.961686) (xy 166.877994 -308.989642) (xy 166.833532 -309.01074) (xy 166.786261 -309.024432)
			(xy 166.737406 -309.030364) (xy 166.688231 -309.028383) (xy 166.640012 -309.018539) (xy 166.593996 -309.001087)
			(xy 166.551375 -308.97648) (xy 166.513254 -308.945355) (xy 166.480619 -308.908518) (xy 166.454316 -308.866922)
			(xy 166.435025 -308.821646) (xy 166.423248 -308.773862) (xy 166.419288 -308.724808) (xy 166.080186 -308.724808)
			(xy 166.079691 -308.749415) (xy 166.071796 -308.797992) (xy 166.056212 -308.844673) (xy 166.033341 -308.88825)
			(xy 166.003776 -308.927594) (xy 165.968283 -308.961686) (xy 165.92778 -308.989642) (xy 165.883318 -309.01074)
			(xy 165.836047 -309.024432) (xy 165.787192 -309.030364) (xy 165.738017 -309.028383) (xy 165.689798 -309.018539)
			(xy 165.643782 -309.001087) (xy 165.601161 -308.97648) (xy 165.56304 -308.945355) (xy 165.530405 -308.908518)
			(xy 165.504102 -308.866922) (xy 165.484811 -308.821646) (xy 165.473034 -308.773862) (xy 165.469074 -308.724808)
			(xy 165.130226 -308.724808) (xy 165.129731 -308.749415) (xy 165.121836 -308.797992) (xy 165.106252 -308.844673)
			(xy 165.083381 -308.88825) (xy 165.053816 -308.927594) (xy 165.018323 -308.961686) (xy 164.97782 -308.989642)
			(xy 164.933358 -309.01074) (xy 164.886087 -309.024432) (xy 164.837232 -309.030364) (xy 164.788057 -309.028383)
			(xy 164.739838 -309.018539) (xy 164.693822 -309.001087) (xy 164.651201 -308.97648) (xy 164.61308 -308.945355)
			(xy 164.580445 -308.908518) (xy 164.554142 -308.866922) (xy 164.534851 -308.821646) (xy 164.523074 -308.773862)
			(xy 164.519114 -308.724808) (xy 164.180266 -308.724808) (xy 164.179771 -308.749415) (xy 164.171876 -308.797992)
			(xy 164.156292 -308.844673) (xy 164.133421 -308.88825) (xy 164.103856 -308.927594) (xy 164.068363 -308.961686)
			(xy 164.02786 -308.989642) (xy 163.983398 -309.01074) (xy 163.936127 -309.024432) (xy 163.887272 -309.030364)
			(xy 163.838097 -309.028383) (xy 163.789878 -309.018539) (xy 163.743862 -309.001087) (xy 163.701241 -308.97648)
			(xy 163.66312 -308.945355) (xy 163.630485 -308.908518) (xy 163.604182 -308.866922) (xy 163.584891 -308.821646)
			(xy 163.573114 -308.773862) (xy 163.569154 -308.724808) (xy 163.230306 -308.724808) (xy 163.229811 -308.749415)
			(xy 163.221916 -308.797992) (xy 163.206332 -308.844673) (xy 163.183461 -308.88825) (xy 163.153896 -308.927594)
			(xy 163.118403 -308.961686) (xy 163.0779 -308.989642) (xy 163.033438 -309.01074) (xy 162.986167 -309.024432)
			(xy 162.937312 -309.030364) (xy 162.888137 -309.028383) (xy 162.839918 -309.018539) (xy 162.793902 -309.001087)
			(xy 162.751281 -308.97648) (xy 162.71316 -308.945355) (xy 162.680525 -308.908518) (xy 162.654222 -308.866922)
			(xy 162.634931 -308.821646) (xy 162.623154 -308.773862) (xy 162.619194 -308.724808) (xy 147.263188 -308.724808)
			(xy 147.260571 -308.742592) (xy 147.244503 -308.795999) (xy 147.220831 -308.846496) (xy 147.190058 -308.893009)
			(xy 147.152841 -308.934546) (xy 147.109973 -308.970221) (xy 147.062367 -308.999275) (xy 147.011038 -309.021087)
			(xy 146.957081 -309.035193) (xy 146.901644 -309.041293) (xy 146.84591 -309.039256) (xy 146.791067 -309.029126)
			(xy 146.738283 -309.011119) (xy 146.688683 -308.985618) (xy 146.643325 -308.953167) (xy 146.603176 -308.914458)
			(xy 146.56909 -308.870315) (xy 146.541794 -308.82168) (xy 146.521871 -308.769589) (xy 146.509745 -308.715152)
			(xy 146.505674 -308.65953) (xy 144.878824 -308.65953) (xy 144.862656 -308.683967) (xy 144.825439 -308.725504)
			(xy 144.782571 -308.761179) (xy 144.734965 -308.790233) (xy 144.683636 -308.812045) (xy 144.629679 -308.826151)
			(xy 144.574242 -308.832251) (xy 144.518508 -308.830214) (xy 144.463665 -308.820084) (xy 144.410881 -308.802077)
			(xy 144.361281 -308.776576) (xy 144.315923 -308.744125) (xy 144.275774 -308.705416) (xy 144.241688 -308.661273)
			(xy 144.214392 -308.612638) (xy 144.194469 -308.560547) (xy 144.182343 -308.50611) (xy 144.178272 -308.450488)
			(xy 118.832884 -308.450488) (xy 118.832884 -309.414926) (xy 143.100042 -309.414926) (xy 143.104113 -309.359304)
			(xy 143.116239 -309.304867) (xy 143.136162 -309.252776) (xy 143.163458 -309.204141) (xy 143.197544 -309.159998)
			(xy 143.237693 -309.121289) (xy 143.283051 -309.088838) (xy 143.332651 -309.063337) (xy 143.385435 -309.04533)
			(xy 143.440278 -309.0352) (xy 143.496012 -309.033163) (xy 143.551449 -309.039263) (xy 143.605406 -309.053369)
			(xy 143.656735 -309.075181) (xy 143.704341 -309.104235) (xy 143.747209 -309.13991) (xy 143.784426 -309.181447)
			(xy 143.79656 -309.199788) (xy 152.644106 -309.199788) (xy 152.648066 -309.150734) (xy 152.659843 -309.10295)
			(xy 152.679134 -309.057674) (xy 152.705437 -309.016078) (xy 152.738072 -308.979241) (xy 152.776193 -308.948116)
			(xy 152.818814 -308.923509) (xy 152.86483 -308.906057) (xy 152.913049 -308.896213) (xy 152.962224 -308.894232)
			(xy 153.011079 -308.900164) (xy 153.05835 -308.913856) (xy 153.102812 -308.934954) (xy 153.143315 -308.96291)
			(xy 153.178808 -308.997002) (xy 153.208373 -309.036346) (xy 153.231244 -309.079923) (xy 153.246828 -309.126604)
			(xy 153.254723 -309.175181) (xy 153.255218 -309.199788) (xy 153.594066 -309.199788) (xy 153.598026 -309.150734)
			(xy 153.609803 -309.10295) (xy 153.629094 -309.057674) (xy 153.655397 -309.016078) (xy 153.688032 -308.979241)
			(xy 153.726153 -308.948116) (xy 153.768774 -308.923509) (xy 153.81479 -308.906057) (xy 153.863009 -308.896213)
			(xy 153.912184 -308.894232) (xy 153.961039 -308.900164) (xy 154.00831 -308.913856) (xy 154.052772 -308.934954)
			(xy 154.093275 -308.96291) (xy 154.128768 -308.997002) (xy 154.158333 -309.036346) (xy 154.181204 -309.079923)
			(xy 154.196788 -309.126604) (xy 154.204683 -309.175181) (xy 154.205178 -309.199788) (xy 154.204683 -309.224395)
			(xy 154.204504 -309.225496) (xy 154.523436 -309.225496) (xy 154.523436 -309.17408) (xy 154.531479 -309.123298)
			(xy 154.547367 -309.074399) (xy 154.57071 -309.028587) (xy 154.600931 -308.986991) (xy 154.637287 -308.950635)
			(xy 154.678883 -308.920414) (xy 154.724695 -308.897071) (xy 154.773594 -308.881183) (xy 154.824376 -308.87314)
			(xy 154.875792 -308.87314) (xy 154.926574 -308.881183) (xy 154.975473 -308.897071) (xy 155.021285 -308.920414)
			(xy 155.062881 -308.950635) (xy 155.099237 -308.986991) (xy 155.129458 -309.028587) (xy 155.152801 -309.074399)
			(xy 155.168689 -309.123298) (xy 155.176732 -309.17408) (xy 155.177236 -309.199788) (xy 155.176732 -309.225496)
			(xy 155.473396 -309.225496) (xy 155.473396 -309.17408) (xy 155.481439 -309.123298) (xy 155.497327 -309.074399)
			(xy 155.52067 -309.028587) (xy 155.550891 -308.986991) (xy 155.587247 -308.950635) (xy 155.628843 -308.920414)
			(xy 155.674655 -308.897071) (xy 155.723554 -308.881183) (xy 155.774336 -308.87314) (xy 155.825752 -308.87314)
			(xy 155.876534 -308.881183) (xy 155.925433 -308.897071) (xy 155.971245 -308.920414) (xy 156.012841 -308.950635)
			(xy 156.049197 -308.986991) (xy 156.079418 -309.028587) (xy 156.102761 -309.074399) (xy 156.118649 -309.123298)
			(xy 156.126692 -309.17408) (xy 156.127196 -309.199788) (xy 156.4442 -309.199788) (xy 156.44816 -309.150734)
			(xy 156.459937 -309.10295) (xy 156.479228 -309.057674) (xy 156.505531 -309.016078) (xy 156.538166 -308.979241)
			(xy 156.576287 -308.948116) (xy 156.618908 -308.923509) (xy 156.664924 -308.906057) (xy 156.713143 -308.896213)
			(xy 156.762318 -308.894232) (xy 156.811173 -308.900164) (xy 156.858444 -308.913856) (xy 156.902906 -308.934954)
			(xy 156.943409 -308.96291) (xy 156.978902 -308.997002) (xy 157.008467 -309.036346) (xy 157.031338 -309.079923)
			(xy 157.046922 -309.126604) (xy 157.054817 -309.175181) (xy 157.055312 -309.199788) (xy 157.054817 -309.224395)
			(xy 157.054638 -309.225496) (xy 157.373316 -309.225496) (xy 157.373316 -309.17408) (xy 157.381359 -309.123298)
			(xy 157.397247 -309.074399) (xy 157.42059 -309.028587) (xy 157.450811 -308.986991) (xy 157.487167 -308.950635)
			(xy 157.528763 -308.920414) (xy 157.574575 -308.897071) (xy 157.623474 -308.881183) (xy 157.674256 -308.87314)
			(xy 157.725672 -308.87314) (xy 157.776454 -308.881183) (xy 157.825353 -308.897071) (xy 157.871165 -308.920414)
			(xy 157.912761 -308.950635) (xy 157.949117 -308.986991) (xy 157.979338 -309.028587) (xy 158.002681 -309.074399)
			(xy 158.018569 -309.123298) (xy 158.026612 -309.17408) (xy 158.027116 -309.199788) (xy 158.026612 -309.225496)
			(xy 158.323276 -309.225496) (xy 158.323276 -309.17408) (xy 158.331319 -309.123298) (xy 158.347207 -309.074399)
			(xy 158.37055 -309.028587) (xy 158.400771 -308.986991) (xy 158.437127 -308.950635) (xy 158.478723 -308.920414)
			(xy 158.524535 -308.897071) (xy 158.573434 -308.881183) (xy 158.624216 -308.87314) (xy 158.675632 -308.87314)
			(xy 158.726414 -308.881183) (xy 158.775313 -308.897071) (xy 158.821125 -308.920414) (xy 158.862721 -308.950635)
			(xy 158.899077 -308.986991) (xy 158.929298 -309.028587) (xy 158.952641 -309.074399) (xy 158.968529 -309.123298)
			(xy 158.976572 -309.17408) (xy 158.977076 -309.199788) (xy 159.29408 -309.199788) (xy 159.29804 -309.150734)
			(xy 159.309817 -309.10295) (xy 159.329108 -309.057674) (xy 159.355411 -309.016078) (xy 159.388046 -308.979241)
			(xy 159.426167 -308.948116) (xy 159.468788 -308.923509) (xy 159.514804 -308.906057) (xy 159.563023 -308.896213)
			(xy 159.612198 -308.894232) (xy 159.661053 -308.900164) (xy 159.708324 -308.913856) (xy 159.752786 -308.934954)
			(xy 159.793289 -308.96291) (xy 159.828782 -308.997002) (xy 159.858347 -309.036346) (xy 159.881218 -309.079923)
			(xy 159.896802 -309.126604) (xy 159.904697 -309.175181) (xy 159.905192 -309.199788) (xy 160.24404 -309.199788)
			(xy 160.248 -309.150734) (xy 160.259777 -309.10295) (xy 160.279068 -309.057674) (xy 160.305371 -309.016078)
			(xy 160.338006 -308.979241) (xy 160.376127 -308.948116) (xy 160.418748 -308.923509) (xy 160.464764 -308.906057)
			(xy 160.512983 -308.896213) (xy 160.562158 -308.894232) (xy 160.611013 -308.900164) (xy 160.658284 -308.913856)
			(xy 160.702746 -308.934954) (xy 160.743249 -308.96291) (xy 160.778742 -308.997002) (xy 160.808307 -309.036346)
			(xy 160.831178 -309.079923) (xy 160.846762 -309.126604) (xy 160.854657 -309.175181) (xy 160.855152 -309.199788)
			(xy 161.194254 -309.199788) (xy 161.198214 -309.150734) (xy 161.209991 -309.10295) (xy 161.229282 -309.057674)
			(xy 161.255585 -309.016078) (xy 161.28822 -308.979241) (xy 161.326341 -308.948116) (xy 161.368962 -308.923509)
			(xy 161.414978 -308.906057) (xy 161.463197 -308.896213) (xy 161.512372 -308.894232) (xy 161.561227 -308.900164)
			(xy 161.608498 -308.913856) (xy 161.65296 -308.934954) (xy 161.693463 -308.96291) (xy 161.728956 -308.997002)
			(xy 161.758521 -309.036346) (xy 161.781392 -309.079923) (xy 161.796976 -309.126604) (xy 161.804871 -309.175181)
			(xy 161.805366 -309.199788) (xy 161.804871 -309.224395) (xy 161.796976 -309.272972) (xy 161.781392 -309.319653)
			(xy 161.758521 -309.36323) (xy 161.728956 -309.402574) (xy 161.693463 -309.436666) (xy 161.65296 -309.464622)
			(xy 161.608498 -309.48572) (xy 161.561227 -309.499412) (xy 161.512372 -309.505344) (xy 161.463197 -309.503363)
			(xy 161.414978 -309.493519) (xy 161.368962 -309.476067) (xy 161.326341 -309.45146) (xy 161.28822 -309.420335)
			(xy 161.255585 -309.383498) (xy 161.229282 -309.341902) (xy 161.209991 -309.296626) (xy 161.198214 -309.248842)
			(xy 161.194254 -309.199788) (xy 160.855152 -309.199788) (xy 160.854657 -309.224395) (xy 160.846762 -309.272972)
			(xy 160.831178 -309.319653) (xy 160.808307 -309.36323) (xy 160.778742 -309.402574) (xy 160.743249 -309.436666)
			(xy 160.702746 -309.464622) (xy 160.658284 -309.48572) (xy 160.611013 -309.499412) (xy 160.562158 -309.505344)
			(xy 160.512983 -309.503363) (xy 160.464764 -309.493519) (xy 160.418748 -309.476067) (xy 160.376127 -309.45146)
			(xy 160.338006 -309.420335) (xy 160.305371 -309.383498) (xy 160.279068 -309.341902) (xy 160.259777 -309.296626)
			(xy 160.248 -309.248842) (xy 160.24404 -309.199788) (xy 159.905192 -309.199788) (xy 159.904697 -309.224395)
			(xy 159.896802 -309.272972) (xy 159.881218 -309.319653) (xy 159.858347 -309.36323) (xy 159.828782 -309.402574)
			(xy 159.793289 -309.436666) (xy 159.752786 -309.464622) (xy 159.708324 -309.48572) (xy 159.661053 -309.499412)
			(xy 159.612198 -309.505344) (xy 159.563023 -309.503363) (xy 159.514804 -309.493519) (xy 159.468788 -309.476067)
			(xy 159.426167 -309.45146) (xy 159.388046 -309.420335) (xy 159.355411 -309.383498) (xy 159.329108 -309.341902)
			(xy 159.309817 -309.296626) (xy 159.29804 -309.248842) (xy 159.29408 -309.199788) (xy 158.977076 -309.199788)
			(xy 158.976572 -309.225496) (xy 158.968529 -309.276278) (xy 158.952641 -309.325177) (xy 158.929298 -309.370989)
			(xy 158.899077 -309.412585) (xy 158.862721 -309.448941) (xy 158.821125 -309.479162) (xy 158.775313 -309.502505)
			(xy 158.726414 -309.518393) (xy 158.675632 -309.526436) (xy 158.624216 -309.526436) (xy 158.573434 -309.518393)
			(xy 158.524535 -309.502505) (xy 158.478723 -309.479162) (xy 158.437127 -309.448941) (xy 158.400771 -309.412585)
			(xy 158.37055 -309.370989) (xy 158.347207 -309.325177) (xy 158.331319 -309.276278) (xy 158.323276 -309.225496)
			(xy 158.026612 -309.225496) (xy 158.018569 -309.276278) (xy 158.002681 -309.325177) (xy 157.979338 -309.370989)
			(xy 157.949117 -309.412585) (xy 157.912761 -309.448941) (xy 157.871165 -309.479162) (xy 157.825353 -309.502505)
			(xy 157.776454 -309.518393) (xy 157.725672 -309.526436) (xy 157.674256 -309.526436) (xy 157.623474 -309.518393)
			(xy 157.574575 -309.502505) (xy 157.528763 -309.479162) (xy 157.487167 -309.448941) (xy 157.450811 -309.412585)
			(xy 157.42059 -309.370989) (xy 157.397247 -309.325177) (xy 157.381359 -309.276278) (xy 157.373316 -309.225496)
			(xy 157.054638 -309.225496) (xy 157.046922 -309.272972) (xy 157.031338 -309.319653) (xy 157.008467 -309.36323)
			(xy 156.978902 -309.402574) (xy 156.943409 -309.436666) (xy 156.902906 -309.464622) (xy 156.858444 -309.48572)
			(xy 156.811173 -309.499412) (xy 156.762318 -309.505344) (xy 156.713143 -309.503363) (xy 156.664924 -309.493519)
			(xy 156.618908 -309.476067) (xy 156.576287 -309.45146) (xy 156.538166 -309.420335) (xy 156.505531 -309.383498)
			(xy 156.479228 -309.341902) (xy 156.459937 -309.296626) (xy 156.44816 -309.248842) (xy 156.4442 -309.199788)
			(xy 156.127196 -309.199788) (xy 156.126692 -309.225496) (xy 156.118649 -309.276278) (xy 156.102761 -309.325177)
			(xy 156.079418 -309.370989) (xy 156.049197 -309.412585) (xy 156.012841 -309.448941) (xy 155.971245 -309.479162)
			(xy 155.925433 -309.502505) (xy 155.876534 -309.518393) (xy 155.825752 -309.526436) (xy 155.774336 -309.526436)
			(xy 155.723554 -309.518393) (xy 155.674655 -309.502505) (xy 155.628843 -309.479162) (xy 155.587247 -309.448941)
			(xy 155.550891 -309.412585) (xy 155.52067 -309.370989) (xy 155.497327 -309.325177) (xy 155.481439 -309.276278)
			(xy 155.473396 -309.225496) (xy 155.176732 -309.225496) (xy 155.168689 -309.276278) (xy 155.152801 -309.325177)
			(xy 155.129458 -309.370989) (xy 155.099237 -309.412585) (xy 155.062881 -309.448941) (xy 155.021285 -309.479162)
			(xy 154.975473 -309.502505) (xy 154.926574 -309.518393) (xy 154.875792 -309.526436) (xy 154.824376 -309.526436)
			(xy 154.773594 -309.518393) (xy 154.724695 -309.502505) (xy 154.678883 -309.479162) (xy 154.637287 -309.448941)
			(xy 154.600931 -309.412585) (xy 154.57071 -309.370989) (xy 154.547367 -309.325177) (xy 154.531479 -309.276278)
			(xy 154.523436 -309.225496) (xy 154.204504 -309.225496) (xy 154.196788 -309.272972) (xy 154.181204 -309.319653)
			(xy 154.158333 -309.36323) (xy 154.128768 -309.402574) (xy 154.093275 -309.436666) (xy 154.052772 -309.464622)
			(xy 154.00831 -309.48572) (xy 153.961039 -309.499412) (xy 153.912184 -309.505344) (xy 153.863009 -309.503363)
			(xy 153.81479 -309.493519) (xy 153.768774 -309.476067) (xy 153.726153 -309.45146) (xy 153.688032 -309.420335)
			(xy 153.655397 -309.383498) (xy 153.629094 -309.341902) (xy 153.609803 -309.296626) (xy 153.598026 -309.248842)
			(xy 153.594066 -309.199788) (xy 153.255218 -309.199788) (xy 153.254723 -309.224395) (xy 153.246828 -309.272972)
			(xy 153.231244 -309.319653) (xy 153.208373 -309.36323) (xy 153.178808 -309.402574) (xy 153.143315 -309.436666)
			(xy 153.102812 -309.464622) (xy 153.05835 -309.48572) (xy 153.011079 -309.499412) (xy 152.962224 -309.505344)
			(xy 152.913049 -309.503363) (xy 152.86483 -309.493519) (xy 152.818814 -309.476067) (xy 152.776193 -309.45146)
			(xy 152.738072 -309.420335) (xy 152.705437 -309.383498) (xy 152.679134 -309.341902) (xy 152.659843 -309.296626)
			(xy 152.648066 -309.248842) (xy 152.644106 -309.199788) (xy 143.79656 -309.199788) (xy 143.815199 -309.22796)
			(xy 143.838871 -309.278457) (xy 143.854939 -309.331864) (xy 143.863059 -309.38704) (xy 143.863568 -309.414926)
			(xy 143.863059 -309.442812) (xy 143.854939 -309.497988) (xy 143.838871 -309.551395) (xy 143.815199 -309.601892)
			(xy 143.784426 -309.648405) (xy 143.747209 -309.689942) (xy 143.704341 -309.725617) (xy 143.656735 -309.754671)
			(xy 143.605406 -309.776483) (xy 143.551449 -309.790589) (xy 143.496012 -309.796689) (xy 143.440278 -309.794652)
			(xy 143.385435 -309.784522) (xy 143.332651 -309.766515) (xy 143.283051 -309.741014) (xy 143.237693 -309.708563)
			(xy 143.197544 -309.669854) (xy 143.163458 -309.625711) (xy 143.136162 -309.577076) (xy 143.116239 -309.524985)
			(xy 143.104113 -309.470548) (xy 143.100042 -309.414926) (xy 118.832884 -309.414926) (xy 118.832884 -309.897272)
			(xy 150.540464 -309.897272) (xy 150.544535 -309.84165) (xy 150.556661 -309.787213) (xy 150.576584 -309.735122)
			(xy 150.60388 -309.686487) (xy 150.637966 -309.642344) (xy 150.678115 -309.603635) (xy 150.723473 -309.571184)
			(xy 150.773073 -309.545683) (xy 150.825857 -309.527676) (xy 150.8807 -309.517546) (xy 150.936434 -309.515509)
			(xy 150.991871 -309.521609) (xy 151.045828 -309.535715) (xy 151.097157 -309.557527) (xy 151.144763 -309.586581)
			(xy 151.187631 -309.622256) (xy 151.224848 -309.663793) (xy 151.255621 -309.710306) (xy 151.279293 -309.760803)
			(xy 151.295361 -309.81421) (xy 151.303481 -309.869386) (xy 151.30399 -309.897272) (xy 151.303481 -309.925158)
			(xy 151.295361 -309.980334) (xy 151.279293 -310.033741) (xy 151.255621 -310.084238) (xy 151.224848 -310.130751)
			(xy 151.207599 -310.150002) (xy 151.693892 -310.150002) (xy 151.697852 -310.100948) (xy 151.709629 -310.053164)
			(xy 151.72892 -310.007888) (xy 151.755223 -309.966292) (xy 151.787858 -309.929455) (xy 151.825979 -309.89833)
			(xy 151.8686 -309.873723) (xy 151.914616 -309.856271) (xy 151.962835 -309.846427) (xy 152.01201 -309.844446)
			(xy 152.060865 -309.850378) (xy 152.108136 -309.86407) (xy 152.152598 -309.885168) (xy 152.193101 -309.913124)
			(xy 152.228594 -309.947216) (xy 152.258159 -309.98656) (xy 152.28103 -310.030137) (xy 152.296614 -310.076818)
			(xy 152.304509 -310.125395) (xy 152.305004 -310.150002) (xy 152.304509 -310.174609) (xy 152.304371 -310.175456)
			(xy 152.623262 -310.175456) (xy 152.623262 -310.12404) (xy 152.631305 -310.073258) (xy 152.647193 -310.024359)
			(xy 152.670536 -309.978547) (xy 152.700757 -309.936951) (xy 152.737113 -309.900595) (xy 152.778709 -309.870374)
			(xy 152.824521 -309.847031) (xy 152.87342 -309.831143) (xy 152.924202 -309.8231) (xy 152.975618 -309.8231)
			(xy 153.0264 -309.831143) (xy 153.075299 -309.847031) (xy 153.121111 -309.870374) (xy 153.162707 -309.900595)
			(xy 153.199063 -309.936951) (xy 153.229284 -309.978547) (xy 153.252627 -310.024359) (xy 153.268515 -310.073258)
			(xy 153.276558 -310.12404) (xy 153.277062 -310.149748) (xy 153.276558 -310.175456) (xy 153.573222 -310.175456)
			(xy 153.573222 -310.12404) (xy 153.581265 -310.073258) (xy 153.597153 -310.024359) (xy 153.620496 -309.978547)
			(xy 153.650717 -309.936951) (xy 153.687073 -309.900595) (xy 153.728669 -309.870374) (xy 153.774481 -309.847031)
			(xy 153.82338 -309.831143) (xy 153.874162 -309.8231) (xy 153.925578 -309.8231) (xy 153.97636 -309.831143)
			(xy 154.025259 -309.847031) (xy 154.071071 -309.870374) (xy 154.112667 -309.900595) (xy 154.149023 -309.936951)
			(xy 154.179244 -309.978547) (xy 154.202587 -310.024359) (xy 154.218475 -310.073258) (xy 154.226518 -310.12404)
			(xy 154.227022 -310.149748) (xy 154.54428 -310.149748) (xy 154.54824 -310.100694) (xy 154.560017 -310.05291)
			(xy 154.579308 -310.007634) (xy 154.605611 -309.966038) (xy 154.638246 -309.929201) (xy 154.676367 -309.898076)
			(xy 154.718988 -309.873469) (xy 154.765004 -309.856017) (xy 154.813223 -309.846173) (xy 154.862398 -309.844192)
			(xy 154.911253 -309.850124) (xy 154.958524 -309.863816) (xy 155.002986 -309.884914) (xy 155.043489 -309.91287)
			(xy 155.078982 -309.946962) (xy 155.108547 -309.986306) (xy 155.131418 -310.029883) (xy 155.147002 -310.076564)
			(xy 155.154897 -310.125141) (xy 155.155392 -310.149748) (xy 155.49424 -310.149748) (xy 155.4982 -310.100694)
			(xy 155.509977 -310.05291) (xy 155.529268 -310.007634) (xy 155.555571 -309.966038) (xy 155.588206 -309.929201)
			(xy 155.626327 -309.898076) (xy 155.668948 -309.873469) (xy 155.714964 -309.856017) (xy 155.763183 -309.846173)
			(xy 155.812358 -309.844192) (xy 155.861213 -309.850124) (xy 155.908484 -309.863816) (xy 155.952946 -309.884914)
			(xy 155.993449 -309.91287) (xy 156.028942 -309.946962) (xy 156.058507 -309.986306) (xy 156.081378 -310.029883)
			(xy 156.096962 -310.076564) (xy 156.104857 -310.125141) (xy 156.105352 -310.149748) (xy 156.4442 -310.149748)
			(xy 156.44816 -310.100694) (xy 156.459937 -310.05291) (xy 156.479228 -310.007634) (xy 156.505531 -309.966038)
			(xy 156.538166 -309.929201) (xy 156.576287 -309.898076) (xy 156.618908 -309.873469) (xy 156.664924 -309.856017)
			(xy 156.713143 -309.846173) (xy 156.762318 -309.844192) (xy 156.811173 -309.850124) (xy 156.858444 -309.863816)
			(xy 156.902906 -309.884914) (xy 156.943409 -309.91287) (xy 156.978902 -309.946962) (xy 157.008467 -309.986306)
			(xy 157.031338 -310.029883) (xy 157.046922 -310.076564) (xy 157.054817 -310.125141) (xy 157.055312 -310.149748)
			(xy 157.39416 -310.149748) (xy 157.39812 -310.100694) (xy 157.409897 -310.05291) (xy 157.429188 -310.007634)
			(xy 157.455491 -309.966038) (xy 157.488126 -309.929201) (xy 157.526247 -309.898076) (xy 157.568868 -309.873469)
			(xy 157.614884 -309.856017) (xy 157.663103 -309.846173) (xy 157.712278 -309.844192) (xy 157.761133 -309.850124)
			(xy 157.808404 -309.863816) (xy 157.852866 -309.884914) (xy 157.893369 -309.91287) (xy 157.928862 -309.946962)
			(xy 157.958427 -309.986306) (xy 157.981298 -310.029883) (xy 157.996882 -310.076564) (xy 158.004777 -310.125141)
			(xy 158.005272 -310.149748) (xy 158.34412 -310.149748) (xy 158.34808 -310.100694) (xy 158.359857 -310.05291)
			(xy 158.379148 -310.007634) (xy 158.405451 -309.966038) (xy 158.438086 -309.929201) (xy 158.476207 -309.898076)
			(xy 158.518828 -309.873469) (xy 158.564844 -309.856017) (xy 158.613063 -309.846173) (xy 158.662238 -309.844192)
			(xy 158.711093 -309.850124) (xy 158.758364 -309.863816) (xy 158.802826 -309.884914) (xy 158.843329 -309.91287)
			(xy 158.878822 -309.946962) (xy 158.908387 -309.986306) (xy 158.931258 -310.029883) (xy 158.946842 -310.076564)
			(xy 158.954737 -310.125141) (xy 158.955232 -310.149748) (xy 159.29408 -310.149748) (xy 159.29804 -310.100694)
			(xy 159.309817 -310.05291) (xy 159.329108 -310.007634) (xy 159.355411 -309.966038) (xy 159.388046 -309.929201)
			(xy 159.426167 -309.898076) (xy 159.468788 -309.873469) (xy 159.514804 -309.856017) (xy 159.563023 -309.846173)
			(xy 159.612198 -309.844192) (xy 159.661053 -309.850124) (xy 159.708324 -309.863816) (xy 159.752786 -309.884914)
			(xy 159.793289 -309.91287) (xy 159.828782 -309.946962) (xy 159.858347 -309.986306) (xy 159.881218 -310.029883)
			(xy 159.896802 -310.076564) (xy 159.904697 -310.125141) (xy 159.905192 -310.149748) (xy 160.24404 -310.149748)
			(xy 160.248 -310.100694) (xy 160.259777 -310.05291) (xy 160.279068 -310.007634) (xy 160.305371 -309.966038)
			(xy 160.338006 -309.929201) (xy 160.376127 -309.898076) (xy 160.418748 -309.873469) (xy 160.464764 -309.856017)
			(xy 160.512983 -309.846173) (xy 160.562158 -309.844192) (xy 160.611013 -309.850124) (xy 160.658284 -309.863816)
			(xy 160.702746 -309.884914) (xy 160.743249 -309.91287) (xy 160.778742 -309.946962) (xy 160.808307 -309.986306)
			(xy 160.831178 -310.029883) (xy 160.846762 -310.076564) (xy 160.854657 -310.125141) (xy 160.855152 -310.149748)
			(xy 161.194254 -310.149748) (xy 161.198214 -310.100694) (xy 161.209991 -310.05291) (xy 161.229282 -310.007634)
			(xy 161.255585 -309.966038) (xy 161.28822 -309.929201) (xy 161.326341 -309.898076) (xy 161.368962 -309.873469)
			(xy 161.414978 -309.856017) (xy 161.463197 -309.846173) (xy 161.512372 -309.844192) (xy 161.561227 -309.850124)
			(xy 161.608498 -309.863816) (xy 161.65296 -309.884914) (xy 161.693463 -309.91287) (xy 161.728956 -309.946962)
			(xy 161.758521 -309.986306) (xy 161.781392 -310.029883) (xy 161.796976 -310.076564) (xy 161.804871 -310.125141)
			(xy 161.805198 -310.141392) (xy 162.14433 -310.141392) (xy 162.149701 -310.09205) (xy 162.162983 -310.044228)
			(xy 162.183827 -309.999184) (xy 162.211684 -309.958105) (xy 162.245819 -309.922075) (xy 162.285333 -309.892041)
			(xy 162.329186 -309.868796) (xy 162.376222 -309.852951) (xy 162.425202 -309.844924) (xy 162.450018 -309.84444)
			(xy 162.464201 -309.844613) (xy 162.492441 -309.847288) (xy 162.506406 -309.849774) (xy 162.518852 -309.85206)
			(xy 162.542474 -309.844694) (xy 162.619944 -309.767224) (xy 162.62731 -309.743602) (xy 162.625024 -309.731156)
			(xy 162.622546 -309.71719) (xy 162.619875 -309.688951) (xy 162.61969 -309.674768) (xy 162.620212 -309.649513)
			(xy 162.628525 -309.599691) (xy 162.644926 -309.551917) (xy 162.668967 -309.507494) (xy 162.699991 -309.467634)
			(xy 162.737153 -309.433424) (xy 162.779439 -309.405798) (xy 162.825695 -309.385508) (xy 162.87466 -309.373108)
			(xy 162.924998 -309.368937) (xy 162.975336 -309.373108) (xy 163.024301 -309.385508) (xy 163.070557 -309.405798)
			(xy 163.112843 -309.433424) (xy 163.150005 -309.467634) (xy 163.181029 -309.507494) (xy 163.20507 -309.551917)
			(xy 163.221471 -309.599691) (xy 163.229784 -309.649513) (xy 163.230306 -309.674768) (xy 163.230125 -309.688951)
			(xy 163.227456 -309.717191) (xy 163.224972 -309.731156) (xy 163.222686 -309.743602) (xy 163.230052 -309.767224)
			(xy 163.307522 -309.844694) (xy 163.331144 -309.85206) (xy 163.34359 -309.849774) (xy 163.357557 -309.847303)
			(xy 163.385796 -309.844627) (xy 163.399978 -309.84444) (xy 163.4248 -309.844854) (xy 163.473791 -309.852882)
			(xy 163.520838 -309.86873) (xy 163.564701 -309.89198) (xy 163.604225 -309.92202) (xy 163.638369 -309.958059)
			(xy 163.666232 -309.999147) (xy 163.687082 -310.044201) (xy 163.700368 -310.092034) (xy 163.705739 -310.141378)
			(xy 164.04423 -310.141378) (xy 164.049603 -310.092036) (xy 164.062888 -310.044214) (xy 164.083735 -309.99917)
			(xy 164.111594 -309.958093) (xy 164.145731 -309.922063) (xy 164.185248 -309.892032) (xy 164.229103 -309.868788)
			(xy 164.27614 -309.852946) (xy 164.325121 -309.844923) (xy 164.349938 -309.84444) (xy 164.364121 -309.844611)
			(xy 164.392361 -309.847287) (xy 164.406326 -309.849774) (xy 164.418772 -309.85206) (xy 164.442394 -309.844694)
			(xy 164.519864 -309.767224) (xy 164.52723 -309.743602) (xy 164.524944 -309.731156) (xy 164.522466 -309.71719)
			(xy 164.519795 -309.688951) (xy 164.51961 -309.674768) (xy 164.520132 -309.649513) (xy 164.528445 -309.599691)
			(xy 164.544846 -309.551917) (xy 164.568887 -309.507494) (xy 164.599911 -309.467634) (xy 164.637073 -309.433424)
			(xy 164.679359 -309.405798) (xy 164.725615 -309.385508) (xy 164.77458 -309.373108) (xy 164.824918 -309.368937)
			(xy 164.875256 -309.373108) (xy 164.924221 -309.385508) (xy 164.970477 -309.405798) (xy 165.012763 -309.433424)
			(xy 165.049925 -309.467634) (xy 165.080949 -309.507494) (xy 165.10499 -309.551917) (xy 165.121391 -309.599691)
			(xy 165.129704 -309.649513) (xy 165.130226 -309.674768) (xy 165.130045 -309.688951) (xy 165.127376 -309.717191)
			(xy 165.124892 -309.731156) (xy 165.122606 -309.743602) (xy 165.129972 -309.767224) (xy 165.207442 -309.844694)
			(xy 165.231064 -309.85206) (xy 165.24351 -309.849774) (xy 165.257476 -309.8473) (xy 165.285716 -309.844627)
			(xy 165.299898 -309.84444) (xy 165.314081 -309.844616) (xy 165.342321 -309.847288) (xy 165.356286 -309.849774)
			(xy 165.368732 -309.85206) (xy 165.392354 -309.844694) (xy 165.469824 -309.767224) (xy 165.47719 -309.743602)
			(xy 165.474904 -309.731156) (xy 165.472425 -309.71719) (xy 165.469755 -309.688951) (xy 165.46957 -309.674768)
			(xy 165.470092 -309.649513) (xy 165.478405 -309.599691) (xy 165.494806 -309.551917) (xy 165.518847 -309.507494)
			(xy 165.549871 -309.467634) (xy 165.587033 -309.433424) (xy 165.629319 -309.405798) (xy 165.675575 -309.385508)
			(xy 165.72454 -309.373108) (xy 165.774878 -309.368937) (xy 165.825216 -309.373108) (xy 165.874181 -309.385508)
			(xy 165.920437 -309.405798) (xy 165.962723 -309.433424) (xy 165.999885 -309.467634) (xy 166.030909 -309.507494)
			(xy 166.05495 -309.551917) (xy 166.071351 -309.599691) (xy 166.079664 -309.649513) (xy 166.080186 -309.674768)
			(xy 166.080005 -309.688951) (xy 166.077336 -309.717191) (xy 166.074852 -309.731156) (xy 166.072566 -309.743602)
			(xy 166.079932 -309.767224) (xy 166.157402 -309.844694) (xy 166.181024 -309.85206) (xy 166.19347 -309.849774)
			(xy 166.207435 -309.847292) (xy 166.235675 -309.844624) (xy 166.249858 -309.84444) (xy 166.274682 -309.844833)
			(xy 166.323678 -309.852858) (xy 166.370729 -309.868704) (xy 166.414597 -309.891954) (xy 166.454126 -309.921994)
			(xy 166.488274 -309.958034) (xy 166.516142 -309.999123) (xy 166.536995 -310.04418) (xy 166.550285 -310.092017)
			(xy 166.55566 -310.141373) (xy 166.555207 -310.149748) (xy 166.894268 -310.149748) (xy 166.898228 -310.100694)
			(xy 166.910005 -310.05291) (xy 166.929296 -310.007634) (xy 166.955599 -309.966038) (xy 166.988234 -309.929201)
			(xy 167.026355 -309.898076) (xy 167.068976 -309.873469) (xy 167.114992 -309.856017) (xy 167.163211 -309.846173)
			(xy 167.212386 -309.844192) (xy 167.261241 -309.850124) (xy 167.308512 -309.863816) (xy 167.352974 -309.884914)
			(xy 167.393477 -309.91287) (xy 167.42897 -309.946962) (xy 167.458535 -309.986306) (xy 167.481406 -310.029883)
			(xy 167.49699 -310.076564) (xy 167.504885 -310.125141) (xy 167.50538 -310.149748) (xy 167.844228 -310.149748)
			(xy 167.848188 -310.100694) (xy 167.859965 -310.05291) (xy 167.879256 -310.007634) (xy 167.905559 -309.966038)
			(xy 167.938194 -309.929201) (xy 167.976315 -309.898076) (xy 168.018936 -309.873469) (xy 168.064952 -309.856017)
			(xy 168.113171 -309.846173) (xy 168.162346 -309.844192) (xy 168.211201 -309.850124) (xy 168.258472 -309.863816)
			(xy 168.302934 -309.884914) (xy 168.343437 -309.91287) (xy 168.37893 -309.946962) (xy 168.408495 -309.986306)
			(xy 168.431366 -310.029883) (xy 168.44695 -310.076564) (xy 168.454845 -310.125141) (xy 168.45534 -310.149748)
			(xy 168.794188 -310.149748) (xy 168.798148 -310.100694) (xy 168.809925 -310.05291) (xy 168.829216 -310.007634)
			(xy 168.855519 -309.966038) (xy 168.888154 -309.929201) (xy 168.926275 -309.898076) (xy 168.968896 -309.873469)
			(xy 169.014912 -309.856017) (xy 169.063131 -309.846173) (xy 169.112306 -309.844192) (xy 169.161161 -309.850124)
			(xy 169.208432 -309.863816) (xy 169.252894 -309.884914) (xy 169.293397 -309.91287) (xy 169.32889 -309.946962)
			(xy 169.358455 -309.986306) (xy 169.381326 -310.029883) (xy 169.39691 -310.076564) (xy 169.404805 -310.125141)
			(xy 169.4053 -310.149748) (xy 169.744148 -310.149748) (xy 169.748108 -310.100694) (xy 169.759885 -310.05291)
			(xy 169.779176 -310.007634) (xy 169.805479 -309.966038) (xy 169.838114 -309.929201) (xy 169.876235 -309.898076)
			(xy 169.918856 -309.873469) (xy 169.964872 -309.856017) (xy 170.013091 -309.846173) (xy 170.062266 -309.844192)
			(xy 170.111121 -309.850124) (xy 170.158392 -309.863816) (xy 170.202854 -309.884914) (xy 170.243357 -309.91287)
			(xy 170.27885 -309.946962) (xy 170.308415 -309.986306) (xy 170.331286 -310.029883) (xy 170.34687 -310.076564)
			(xy 170.354765 -310.125141) (xy 170.35526 -310.149748) (xy 170.694108 -310.149748) (xy 170.698068 -310.100694)
			(xy 170.709845 -310.05291) (xy 170.729136 -310.007634) (xy 170.755439 -309.966038) (xy 170.788074 -309.929201)
			(xy 170.826195 -309.898076) (xy 170.868816 -309.873469) (xy 170.914832 -309.856017) (xy 170.963051 -309.846173)
			(xy 171.012226 -309.844192) (xy 171.061081 -309.850124) (xy 171.108352 -309.863816) (xy 171.152814 -309.884914)
			(xy 171.193317 -309.91287) (xy 171.22881 -309.946962) (xy 171.258375 -309.986306) (xy 171.281246 -310.029883)
			(xy 171.29683 -310.076564) (xy 171.304725 -310.125141) (xy 171.305053 -310.141423) (xy 171.644229 -310.141423)
			(xy 171.649594 -310.092082) (xy 171.662871 -310.04426) (xy 171.683709 -309.999215) (xy 171.71156 -309.958134)
			(xy 171.74569 -309.922101) (xy 171.785199 -309.892063) (xy 171.829047 -309.868812) (xy 171.87608 -309.852961)
			(xy 171.925056 -309.844928) (xy 171.949872 -309.84444) (xy 171.964055 -309.84462) (xy 171.992295 -309.84729)
			(xy 172.00626 -309.849774) (xy 172.018706 -309.85206) (xy 172.042328 -309.844694) (xy 172.119798 -309.767224)
			(xy 172.127164 -309.743602) (xy 172.124878 -309.731156) (xy 172.122399 -309.71719) (xy 172.119729 -309.688951)
			(xy 172.119544 -309.674768) (xy 172.120066 -309.649513) (xy 172.128379 -309.599691) (xy 172.14478 -309.551917)
			(xy 172.168821 -309.507494) (xy 172.199845 -309.467634) (xy 172.237007 -309.433424) (xy 172.279293 -309.405798)
			(xy 172.325549 -309.385508) (xy 172.374514 -309.373108) (xy 172.424852 -309.368937) (xy 172.47519 -309.373108)
			(xy 172.524155 -309.385508) (xy 172.570411 -309.405798) (xy 172.612697 -309.433424) (xy 172.649859 -309.467634)
			(xy 172.680883 -309.507494) (xy 172.704924 -309.551917) (xy 172.721325 -309.599691) (xy 172.729638 -309.649513)
			(xy 172.73016 -309.674768) (xy 172.72998 -309.688951) (xy 172.72731 -309.717191) (xy 172.724826 -309.731156)
			(xy 172.72254 -309.743602) (xy 172.729906 -309.767478) (xy 172.807122 -309.844694) (xy 172.831252 -309.85206)
			(xy 172.843444 -309.849774) (xy 172.857472 -309.847286) (xy 172.88584 -309.844616) (xy 172.900086 -309.84444)
			(xy 172.924907 -309.844863) (xy 172.973897 -309.852892) (xy 173.020942 -309.86874) (xy 173.064803 -309.891991)
			(xy 173.104325 -309.922031) (xy 173.138467 -309.958069) (xy 173.166329 -309.999156) (xy 173.187176 -310.044209)
			(xy 173.200461 -310.092041) (xy 173.205832 -310.141393) (xy 173.20538 -310.149748) (xy 173.544242 -310.149748)
			(xy 173.548202 -310.100694) (xy 173.559979 -310.05291) (xy 173.57927 -310.007634) (xy 173.605573 -309.966038)
			(xy 173.638208 -309.929201) (xy 173.676329 -309.898076) (xy 173.71895 -309.873469) (xy 173.764966 -309.856017)
			(xy 173.813185 -309.846173) (xy 173.86236 -309.844192) (xy 173.911215 -309.850124) (xy 173.958486 -309.863816)
			(xy 174.002948 -309.884914) (xy 174.043451 -309.91287) (xy 174.078944 -309.946962) (xy 174.108509 -309.986306)
			(xy 174.13138 -310.029883) (xy 174.146964 -310.076564) (xy 174.154859 -310.125141) (xy 174.155354 -310.149748)
			(xy 174.494202 -310.149748) (xy 174.498162 -310.100694) (xy 174.509939 -310.05291) (xy 174.52923 -310.007634)
			(xy 174.555533 -309.966038) (xy 174.588168 -309.929201) (xy 174.626289 -309.898076) (xy 174.66891 -309.873469)
			(xy 174.714926 -309.856017) (xy 174.763145 -309.846173) (xy 174.81232 -309.844192) (xy 174.861175 -309.850124)
			(xy 174.908446 -309.863816) (xy 174.952908 -309.884914) (xy 174.993411 -309.91287) (xy 175.028904 -309.946962)
			(xy 175.058469 -309.986306) (xy 175.08134 -310.029883) (xy 175.096924 -310.076564) (xy 175.104819 -310.125141)
			(xy 175.105314 -310.149748) (xy 175.444162 -310.149748) (xy 175.448122 -310.100694) (xy 175.459899 -310.05291)
			(xy 175.47919 -310.007634) (xy 175.505493 -309.966038) (xy 175.538128 -309.929201) (xy 175.576249 -309.898076)
			(xy 175.61887 -309.873469) (xy 175.664886 -309.856017) (xy 175.713105 -309.846173) (xy 175.76228 -309.844192)
			(xy 175.811135 -309.850124) (xy 175.858406 -309.863816) (xy 175.902868 -309.884914) (xy 175.943371 -309.91287)
			(xy 175.978864 -309.946962) (xy 176.008429 -309.986306) (xy 176.0313 -310.029883) (xy 176.046884 -310.076564)
			(xy 176.054779 -310.125141) (xy 176.055274 -310.149748) (xy 176.394122 -310.149748) (xy 176.398082 -310.100694)
			(xy 176.409859 -310.05291) (xy 176.42915 -310.007634) (xy 176.455453 -309.966038) (xy 176.488088 -309.929201)
			(xy 176.526209 -309.898076) (xy 176.56883 -309.873469) (xy 176.614846 -309.856017) (xy 176.663065 -309.846173)
			(xy 176.71224 -309.844192) (xy 176.761095 -309.850124) (xy 176.808366 -309.863816) (xy 176.852828 -309.884914)
			(xy 176.893331 -309.91287) (xy 176.928824 -309.946962) (xy 176.958389 -309.986306) (xy 176.98126 -310.029883)
			(xy 176.996844 -310.076564) (xy 177.004739 -310.125141) (xy 177.005234 -310.149748) (xy 177.344082 -310.149748)
			(xy 177.348042 -310.100694) (xy 177.359819 -310.05291) (xy 177.37911 -310.007634) (xy 177.405413 -309.966038)
			(xy 177.438048 -309.929201) (xy 177.476169 -309.898076) (xy 177.51879 -309.873469) (xy 177.564806 -309.856017)
			(xy 177.613025 -309.846173) (xy 177.6622 -309.844192) (xy 177.711055 -309.850124) (xy 177.758326 -309.863816)
			(xy 177.802788 -309.884914) (xy 177.843291 -309.91287) (xy 177.878784 -309.946962) (xy 177.908349 -309.986306)
			(xy 177.93122 -310.029883) (xy 177.946804 -310.076564) (xy 177.954699 -310.125141) (xy 177.955194 -310.149748)
			(xy 178.294042 -310.149748) (xy 178.298002 -310.100694) (xy 178.309779 -310.05291) (xy 178.32907 -310.007634)
			(xy 178.355373 -309.966038) (xy 178.388008 -309.929201) (xy 178.426129 -309.898076) (xy 178.46875 -309.873469)
			(xy 178.514766 -309.856017) (xy 178.562985 -309.846173) (xy 178.61216 -309.844192) (xy 178.661015 -309.850124)
			(xy 178.708286 -309.863816) (xy 178.752748 -309.884914) (xy 178.793251 -309.91287) (xy 178.828744 -309.946962)
			(xy 178.858309 -309.986306) (xy 178.88118 -310.029883) (xy 178.896764 -310.076564) (xy 178.904659 -310.125141)
			(xy 178.905154 -310.149748) (xy 179.244256 -310.149748) (xy 179.248216 -310.100694) (xy 179.259993 -310.05291)
			(xy 179.279284 -310.007634) (xy 179.305587 -309.966038) (xy 179.338222 -309.929201) (xy 179.376343 -309.898076)
			(xy 179.418964 -309.873469) (xy 179.46498 -309.856017) (xy 179.513199 -309.846173) (xy 179.562374 -309.844192)
			(xy 179.611229 -309.850124) (xy 179.6585 -309.863816) (xy 179.702962 -309.884914) (xy 179.743465 -309.91287)
			(xy 179.778958 -309.946962) (xy 179.808523 -309.986306) (xy 179.831394 -310.029883) (xy 179.846978 -310.076564)
			(xy 179.854873 -310.125141) (xy 179.855368 -310.149748) (xy 180.194216 -310.149748) (xy 180.198176 -310.100694)
			(xy 180.209953 -310.05291) (xy 180.229244 -310.007634) (xy 180.255547 -309.966038) (xy 180.288182 -309.929201)
			(xy 180.326303 -309.898076) (xy 180.368924 -309.873469) (xy 180.41494 -309.856017) (xy 180.463159 -309.846173)
			(xy 180.512334 -309.844192) (xy 180.561189 -309.850124) (xy 180.60846 -309.863816) (xy 180.652922 -309.884914)
			(xy 180.693425 -309.91287) (xy 180.728918 -309.946962) (xy 180.758483 -309.986306) (xy 180.781354 -310.029883)
			(xy 180.796938 -310.076564) (xy 180.804833 -310.125141) (xy 180.805328 -310.149748) (xy 181.144176 -310.149748)
			(xy 181.148136 -310.100694) (xy 181.159913 -310.05291) (xy 181.179204 -310.007634) (xy 181.205507 -309.966038)
			(xy 181.238142 -309.929201) (xy 181.276263 -309.898076) (xy 181.318884 -309.873469) (xy 181.3649 -309.856017)
			(xy 181.413119 -309.846173) (xy 181.462294 -309.844192) (xy 181.511149 -309.850124) (xy 181.55842 -309.863816)
			(xy 181.602882 -309.884914) (xy 181.643385 -309.91287) (xy 181.678878 -309.946962) (xy 181.708443 -309.986306)
			(xy 181.731314 -310.029883) (xy 181.746898 -310.076564) (xy 181.754793 -310.125141) (xy 181.755288 -310.149748)
			(xy 182.094136 -310.149748) (xy 182.098096 -310.100694) (xy 182.109873 -310.05291) (xy 182.129164 -310.007634)
			(xy 182.155467 -309.966038) (xy 182.188102 -309.929201) (xy 182.226223 -309.898076) (xy 182.268844 -309.873469)
			(xy 182.31486 -309.856017) (xy 182.363079 -309.846173) (xy 182.412254 -309.844192) (xy 182.461109 -309.850124)
			(xy 182.50838 -309.863816) (xy 182.552842 -309.884914) (xy 182.593345 -309.91287) (xy 182.628838 -309.946962)
			(xy 182.658403 -309.986306) (xy 182.681274 -310.029883) (xy 182.696858 -310.076564) (xy 182.704753 -310.125141)
			(xy 182.705248 -310.149748) (xy 183.044096 -310.149748) (xy 183.048056 -310.100694) (xy 183.059833 -310.05291)
			(xy 183.079124 -310.007634) (xy 183.105427 -309.966038) (xy 183.138062 -309.929201) (xy 183.176183 -309.898076)
			(xy 183.218804 -309.873469) (xy 183.26482 -309.856017) (xy 183.313039 -309.846173) (xy 183.362214 -309.844192)
			(xy 183.411069 -309.850124) (xy 183.45834 -309.863816) (xy 183.502802 -309.884914) (xy 183.543305 -309.91287)
			(xy 183.578798 -309.946962) (xy 183.608363 -309.986306) (xy 183.631234 -310.029883) (xy 183.646818 -310.076564)
			(xy 183.654713 -310.125141) (xy 183.655208 -310.149748) (xy 183.994056 -310.149748) (xy 183.998016 -310.100694)
			(xy 184.009793 -310.05291) (xy 184.029084 -310.007634) (xy 184.055387 -309.966038) (xy 184.088022 -309.929201)
			(xy 184.126143 -309.898076) (xy 184.168764 -309.873469) (xy 184.21478 -309.856017) (xy 184.262999 -309.846173)
			(xy 184.312174 -309.844192) (xy 184.361029 -309.850124) (xy 184.4083 -309.863816) (xy 184.452762 -309.884914)
			(xy 184.493265 -309.91287) (xy 184.528758 -309.946962) (xy 184.558323 -309.986306) (xy 184.581194 -310.029883)
			(xy 184.596778 -310.076564) (xy 184.604673 -310.125141) (xy 184.605168 -310.149748) (xy 184.604673 -310.174355)
			(xy 184.596778 -310.222932) (xy 184.581194 -310.269613) (xy 184.558323 -310.31319) (xy 184.528758 -310.352534)
			(xy 184.493265 -310.386626) (xy 184.452762 -310.414582) (xy 184.4083 -310.43568) (xy 184.361029 -310.449372)
			(xy 184.312174 -310.455304) (xy 184.262999 -310.453323) (xy 184.21478 -310.443479) (xy 184.168764 -310.426027)
			(xy 184.126143 -310.40142) (xy 184.088022 -310.370295) (xy 184.055387 -310.333458) (xy 184.029084 -310.291862)
			(xy 184.009793 -310.246586) (xy 183.998016 -310.198802) (xy 183.994056 -310.149748) (xy 183.655208 -310.149748)
			(xy 183.654713 -310.174355) (xy 183.646818 -310.222932) (xy 183.631234 -310.269613) (xy 183.608363 -310.31319)
			(xy 183.578798 -310.352534) (xy 183.543305 -310.386626) (xy 183.502802 -310.414582) (xy 183.45834 -310.43568)
			(xy 183.411069 -310.449372) (xy 183.362214 -310.455304) (xy 183.313039 -310.453323) (xy 183.26482 -310.443479)
			(xy 183.218804 -310.426027) (xy 183.176183 -310.40142) (xy 183.138062 -310.370295) (xy 183.105427 -310.333458)
			(xy 183.079124 -310.291862) (xy 183.059833 -310.246586) (xy 183.048056 -310.198802) (xy 183.044096 -310.149748)
			(xy 182.705248 -310.149748) (xy 182.704753 -310.174355) (xy 182.696858 -310.222932) (xy 182.681274 -310.269613)
			(xy 182.658403 -310.31319) (xy 182.628838 -310.352534) (xy 182.593345 -310.386626) (xy 182.552842 -310.414582)
			(xy 182.50838 -310.43568) (xy 182.461109 -310.449372) (xy 182.412254 -310.455304) (xy 182.363079 -310.453323)
			(xy 182.31486 -310.443479) (xy 182.268844 -310.426027) (xy 182.226223 -310.40142) (xy 182.188102 -310.370295)
			(xy 182.155467 -310.333458) (xy 182.129164 -310.291862) (xy 182.109873 -310.246586) (xy 182.098096 -310.198802)
			(xy 182.094136 -310.149748) (xy 181.755288 -310.149748) (xy 181.754793 -310.174355) (xy 181.746898 -310.222932)
			(xy 181.731314 -310.269613) (xy 181.708443 -310.31319) (xy 181.678878 -310.352534) (xy 181.643385 -310.386626)
			(xy 181.602882 -310.414582) (xy 181.55842 -310.43568) (xy 181.511149 -310.449372) (xy 181.462294 -310.455304)
			(xy 181.413119 -310.453323) (xy 181.3649 -310.443479) (xy 181.318884 -310.426027) (xy 181.276263 -310.40142)
			(xy 181.238142 -310.370295) (xy 181.205507 -310.333458) (xy 181.179204 -310.291862) (xy 181.159913 -310.246586)
			(xy 181.148136 -310.198802) (xy 181.144176 -310.149748) (xy 180.805328 -310.149748) (xy 180.804833 -310.174355)
			(xy 180.796938 -310.222932) (xy 180.781354 -310.269613) (xy 180.758483 -310.31319) (xy 180.728918 -310.352534)
			(xy 180.693425 -310.386626) (xy 180.652922 -310.414582) (xy 180.60846 -310.43568) (xy 180.561189 -310.449372)
			(xy 180.512334 -310.455304) (xy 180.463159 -310.453323) (xy 180.41494 -310.443479) (xy 180.368924 -310.426027)
			(xy 180.326303 -310.40142) (xy 180.288182 -310.370295) (xy 180.255547 -310.333458) (xy 180.229244 -310.291862)
			(xy 180.209953 -310.246586) (xy 180.198176 -310.198802) (xy 180.194216 -310.149748) (xy 179.855368 -310.149748)
			(xy 179.854873 -310.174355) (xy 179.846978 -310.222932) (xy 179.831394 -310.269613) (xy 179.808523 -310.31319)
			(xy 179.778958 -310.352534) (xy 179.743465 -310.386626) (xy 179.702962 -310.414582) (xy 179.6585 -310.43568)
			(xy 179.611229 -310.449372) (xy 179.562374 -310.455304) (xy 179.513199 -310.453323) (xy 179.46498 -310.443479)
			(xy 179.418964 -310.426027) (xy 179.376343 -310.40142) (xy 179.338222 -310.370295) (xy 179.305587 -310.333458)
			(xy 179.279284 -310.291862) (xy 179.259993 -310.246586) (xy 179.248216 -310.198802) (xy 179.244256 -310.149748)
			(xy 178.905154 -310.149748) (xy 178.904659 -310.174355) (xy 178.896764 -310.222932) (xy 178.88118 -310.269613)
			(xy 178.858309 -310.31319) (xy 178.828744 -310.352534) (xy 178.793251 -310.386626) (xy 178.752748 -310.414582)
			(xy 178.708286 -310.43568) (xy 178.661015 -310.449372) (xy 178.61216 -310.455304) (xy 178.562985 -310.453323)
			(xy 178.514766 -310.443479) (xy 178.46875 -310.426027) (xy 178.426129 -310.40142) (xy 178.388008 -310.370295)
			(xy 178.355373 -310.333458) (xy 178.32907 -310.291862) (xy 178.309779 -310.246586) (xy 178.298002 -310.198802)
			(xy 178.294042 -310.149748) (xy 177.955194 -310.149748) (xy 177.954699 -310.174355) (xy 177.946804 -310.222932)
			(xy 177.93122 -310.269613) (xy 177.908349 -310.31319) (xy 177.878784 -310.352534) (xy 177.843291 -310.386626)
			(xy 177.802788 -310.414582) (xy 177.758326 -310.43568) (xy 177.711055 -310.449372) (xy 177.6622 -310.455304)
			(xy 177.613025 -310.453323) (xy 177.564806 -310.443479) (xy 177.51879 -310.426027) (xy 177.476169 -310.40142)
			(xy 177.438048 -310.370295) (xy 177.405413 -310.333458) (xy 177.37911 -310.291862) (xy 177.359819 -310.246586)
			(xy 177.348042 -310.198802) (xy 177.344082 -310.149748) (xy 177.005234 -310.149748) (xy 177.004739 -310.174355)
			(xy 176.996844 -310.222932) (xy 176.98126 -310.269613) (xy 176.958389 -310.31319) (xy 176.928824 -310.352534)
			(xy 176.893331 -310.386626) (xy 176.852828 -310.414582) (xy 176.808366 -310.43568) (xy 176.761095 -310.449372)
			(xy 176.71224 -310.455304) (xy 176.663065 -310.453323) (xy 176.614846 -310.443479) (xy 176.56883 -310.426027)
			(xy 176.526209 -310.40142) (xy 176.488088 -310.370295) (xy 176.455453 -310.333458) (xy 176.42915 -310.291862)
			(xy 176.409859 -310.246586) (xy 176.398082 -310.198802) (xy 176.394122 -310.149748) (xy 176.055274 -310.149748)
			(xy 176.054779 -310.174355) (xy 176.046884 -310.222932) (xy 176.0313 -310.269613) (xy 176.008429 -310.31319)
			(xy 175.978864 -310.352534) (xy 175.943371 -310.386626) (xy 175.902868 -310.414582) (xy 175.858406 -310.43568)
			(xy 175.811135 -310.449372) (xy 175.76228 -310.455304) (xy 175.713105 -310.453323) (xy 175.664886 -310.443479)
			(xy 175.61887 -310.426027) (xy 175.576249 -310.40142) (xy 175.538128 -310.370295) (xy 175.505493 -310.333458)
			(xy 175.47919 -310.291862) (xy 175.459899 -310.246586) (xy 175.448122 -310.198802) (xy 175.444162 -310.149748)
			(xy 175.105314 -310.149748) (xy 175.104819 -310.174355) (xy 175.096924 -310.222932) (xy 175.08134 -310.269613)
			(xy 175.058469 -310.31319) (xy 175.028904 -310.352534) (xy 174.993411 -310.386626) (xy 174.952908 -310.414582)
			(xy 174.908446 -310.43568) (xy 174.861175 -310.449372) (xy 174.81232 -310.455304) (xy 174.763145 -310.453323)
			(xy 174.714926 -310.443479) (xy 174.66891 -310.426027) (xy 174.626289 -310.40142) (xy 174.588168 -310.370295)
			(xy 174.555533 -310.333458) (xy 174.52923 -310.291862) (xy 174.509939 -310.246586) (xy 174.498162 -310.198802)
			(xy 174.494202 -310.149748) (xy 174.155354 -310.149748) (xy 174.154859 -310.174355) (xy 174.146964 -310.222932)
			(xy 174.13138 -310.269613) (xy 174.108509 -310.31319) (xy 174.078944 -310.352534) (xy 174.043451 -310.386626)
			(xy 174.002948 -310.414582) (xy 173.958486 -310.43568) (xy 173.911215 -310.449372) (xy 173.86236 -310.455304)
			(xy 173.813185 -310.453323) (xy 173.764966 -310.443479) (xy 173.71895 -310.426027) (xy 173.676329 -310.40142)
			(xy 173.638208 -310.370295) (xy 173.605573 -310.333458) (xy 173.57927 -310.291862) (xy 173.559979 -310.246586)
			(xy 173.548202 -310.198802) (xy 173.544242 -310.149748) (xy 173.20538 -310.149748) (xy 173.203149 -310.190963)
			(xy 173.192481 -310.239446) (xy 173.174111 -310.285565) (xy 173.148521 -310.328104) (xy 173.116387 -310.365943)
			(xy 173.078554 -310.398085) (xy 173.03602 -310.423683) (xy 172.989905 -310.442063) (xy 172.941425 -310.45274)
			(xy 172.891855 -310.455434) (xy 172.842502 -310.450073) (xy 172.794667 -310.436798) (xy 172.74961 -310.415959)
			(xy 172.708517 -310.388106) (xy 172.672472 -310.353971) (xy 172.642424 -310.314455) (xy 172.619165 -310.270599)
			(xy 172.603307 -310.223557) (xy 172.595268 -310.174569) (xy 172.594778 -310.149748) (xy 172.594962 -310.135565)
			(xy 172.597629 -310.107325) (xy 172.600112 -310.09336) (xy 172.602398 -310.080914) (xy 172.595032 -310.057038)
			(xy 172.517816 -309.979822) (xy 172.493686 -309.972456) (xy 172.481494 -309.974742) (xy 172.467465 -309.977225)
			(xy 172.439098 -309.979898) (xy 172.424852 -309.980076) (xy 172.410669 -309.979893) (xy 172.382429 -309.977225)
			(xy 172.368464 -309.974742) (xy 172.356018 -309.972456) (xy 172.332396 -309.979822) (xy 172.254926 -310.057292)
			(xy 172.24756 -310.080914) (xy 172.249846 -310.09336) (xy 172.252326 -310.107325) (xy 172.254996 -310.135565)
			(xy 172.25518 -310.149748) (xy 172.25467 -310.174564) (xy 172.246634 -310.22354) (xy 172.23078 -310.270571)
			(xy 172.207526 -310.314418) (xy 172.177486 -310.353925) (xy 172.14145 -310.388052) (xy 172.100368 -310.415901)
			(xy 172.055321 -310.436736) (xy 172.007498 -310.450009) (xy 171.958157 -310.455371) (xy 171.908599 -310.452681)
			(xy 171.860129 -310.442009) (xy 171.814023 -310.423636) (xy 171.771498 -310.398046) (xy 171.733672 -310.365914)
			(xy 171.701542 -310.328086) (xy 171.675955 -310.285559) (xy 171.657585 -310.239452) (xy 171.646916 -310.190981)
			(xy 171.644229 -310.141423) (xy 171.305053 -310.141423) (xy 171.30522 -310.149748) (xy 171.304725 -310.174355)
			(xy 171.29683 -310.222932) (xy 171.281246 -310.269613) (xy 171.258375 -310.31319) (xy 171.22881 -310.352534)
			(xy 171.193317 -310.386626) (xy 171.152814 -310.414582) (xy 171.108352 -310.43568) (xy 171.061081 -310.449372)
			(xy 171.012226 -310.455304) (xy 170.963051 -310.453323) (xy 170.914832 -310.443479) (xy 170.868816 -310.426027)
			(xy 170.826195 -310.40142) (xy 170.788074 -310.370295) (xy 170.755439 -310.333458) (xy 170.729136 -310.291862)
			(xy 170.709845 -310.246586) (xy 170.698068 -310.198802) (xy 170.694108 -310.149748) (xy 170.35526 -310.149748)
			(xy 170.354765 -310.174355) (xy 170.34687 -310.222932) (xy 170.331286 -310.269613) (xy 170.308415 -310.31319)
			(xy 170.27885 -310.352534) (xy 170.243357 -310.386626) (xy 170.202854 -310.414582) (xy 170.158392 -310.43568)
			(xy 170.111121 -310.449372) (xy 170.062266 -310.455304) (xy 170.013091 -310.453323) (xy 169.964872 -310.443479)
			(xy 169.918856 -310.426027) (xy 169.876235 -310.40142) (xy 169.838114 -310.370295) (xy 169.805479 -310.333458)
			(xy 169.779176 -310.291862) (xy 169.759885 -310.246586) (xy 169.748108 -310.198802) (xy 169.744148 -310.149748)
			(xy 169.4053 -310.149748) (xy 169.404805 -310.174355) (xy 169.39691 -310.222932) (xy 169.381326 -310.269613)
			(xy 169.358455 -310.31319) (xy 169.32889 -310.352534) (xy 169.293397 -310.386626) (xy 169.252894 -310.414582)
			(xy 169.208432 -310.43568) (xy 169.161161 -310.449372) (xy 169.112306 -310.455304) (xy 169.063131 -310.453323)
			(xy 169.014912 -310.443479) (xy 168.968896 -310.426027) (xy 168.926275 -310.40142) (xy 168.888154 -310.370295)
			(xy 168.855519 -310.333458) (xy 168.829216 -310.291862) (xy 168.809925 -310.246586) (xy 168.798148 -310.198802)
			(xy 168.794188 -310.149748) (xy 168.45534 -310.149748) (xy 168.454845 -310.174355) (xy 168.44695 -310.222932)
			(xy 168.431366 -310.269613) (xy 168.408495 -310.31319) (xy 168.37893 -310.352534) (xy 168.343437 -310.386626)
			(xy 168.302934 -310.414582) (xy 168.258472 -310.43568) (xy 168.211201 -310.449372) (xy 168.162346 -310.455304)
			(xy 168.113171 -310.453323) (xy 168.064952 -310.443479) (xy 168.018936 -310.426027) (xy 167.976315 -310.40142)
			(xy 167.938194 -310.370295) (xy 167.905559 -310.333458) (xy 167.879256 -310.291862) (xy 167.859965 -310.246586)
			(xy 167.848188 -310.198802) (xy 167.844228 -310.149748) (xy 167.50538 -310.149748) (xy 167.504885 -310.174355)
			(xy 167.49699 -310.222932) (xy 167.481406 -310.269613) (xy 167.458535 -310.31319) (xy 167.42897 -310.352534)
			(xy 167.393477 -310.386626) (xy 167.352974 -310.414582) (xy 167.308512 -310.43568) (xy 167.261241 -310.449372)
			(xy 167.212386 -310.455304) (xy 167.163211 -310.453323) (xy 167.114992 -310.443479) (xy 167.068976 -310.426027)
			(xy 167.026355 -310.40142) (xy 166.988234 -310.370295) (xy 166.955599 -310.333458) (xy 166.929296 -310.291862)
			(xy 166.910005 -310.246586) (xy 166.898228 -310.198802) (xy 166.894268 -310.149748) (xy 166.555207 -310.149748)
			(xy 166.552979 -310.190949) (xy 166.542313 -310.239438) (xy 166.523943 -310.285563) (xy 166.498353 -310.328108)
			(xy 166.466217 -310.365953) (xy 166.428381 -310.3981) (xy 166.385844 -310.423703) (xy 166.339724 -310.442087)
			(xy 166.291238 -310.452767) (xy 166.241663 -310.455462) (xy 166.192305 -310.450102) (xy 166.144465 -310.436827)
			(xy 166.099402 -310.415987) (xy 166.058304 -310.388131) (xy 166.022254 -310.353993) (xy 165.992202 -310.314473)
			(xy 165.96894 -310.270612) (xy 165.95308 -310.223565) (xy 165.94504 -310.174572) (xy 165.94455 -310.149748)
			(xy 165.944734 -310.135565) (xy 165.947401 -310.107325) (xy 165.949884 -310.09336) (xy 165.95217 -310.080914)
			(xy 165.944804 -310.057292) (xy 165.867334 -309.979822) (xy 165.843712 -309.972456) (xy 165.831266 -309.974742)
			(xy 165.8173 -309.977219) (xy 165.789061 -309.97989) (xy 165.774878 -309.980076) (xy 165.760695 -309.979903)
			(xy 165.732455 -309.977229) (xy 165.71849 -309.974742) (xy 165.706044 -309.972456) (xy 165.682422 -309.979822)
			(xy 165.604952 -310.057292) (xy 165.597586 -310.080914) (xy 165.599872 -310.09336) (xy 165.602353 -310.107325)
			(xy 165.605022 -310.135565) (xy 165.605206 -310.149748) (xy 165.604684 -310.175003) (xy 165.596371 -310.224825)
			(xy 165.57997 -310.272599) (xy 165.555929 -310.317022) (xy 165.524905 -310.356882) (xy 165.487743 -310.391092)
			(xy 165.445457 -310.418718) (xy 165.399201 -310.439008) (xy 165.350236 -310.451408) (xy 165.299898 -310.455579)
			(xy 165.24956 -310.451408) (xy 165.200595 -310.439008) (xy 165.154339 -310.418718) (xy 165.112053 -310.391092)
			(xy 165.074891 -310.356882) (xy 165.043867 -310.317022) (xy 165.019826 -310.272599) (xy 165.003425 -310.224825)
			(xy 164.995112 -310.175003) (xy 164.99459 -310.149748) (xy 164.994773 -310.135565) (xy 164.997441 -310.107325)
			(xy 164.999924 -310.09336) (xy 165.00221 -310.080914) (xy 164.994844 -310.057292) (xy 164.917374 -309.979822)
			(xy 164.893752 -309.972456) (xy 164.881306 -309.974742) (xy 164.867339 -309.977213) (xy 164.8391 -309.979889)
			(xy 164.824918 -309.980076) (xy 164.810735 -309.979897) (xy 164.782495 -309.977227) (xy 164.76853 -309.974742)
			(xy 164.756084 -309.972456) (xy 164.732462 -309.979822) (xy 164.654992 -310.057292) (xy 164.647626 -310.080914)
			(xy 164.649912 -310.09336) (xy 164.652393 -310.107325) (xy 164.655062 -310.135565) (xy 164.655246 -310.149748)
			(xy 164.65467 -310.174565) (xy 164.646633 -310.223543) (xy 164.630778 -310.270576) (xy 164.607522 -310.314424)
			(xy 164.577479 -310.353933) (xy 164.54144 -310.38806) (xy 164.500355 -310.415908) (xy 164.455305 -310.436742)
			(xy 164.407479 -310.450013) (xy 164.358136 -310.455372) (xy 164.308575 -310.452678) (xy 164.260104 -310.442001)
			(xy 164.213998 -310.423623) (xy 164.171473 -310.398028) (xy 164.133648 -310.365891) (xy 164.101522 -310.328057)
			(xy 164.075939 -310.285525) (xy 164.057574 -310.239414) (xy 164.046911 -310.190939) (xy 164.04423 -310.141378)
			(xy 163.705739 -310.141378) (xy 163.70574 -310.141387) (xy 163.703057 -310.190959) (xy 163.69239 -310.239444)
			(xy 163.67402 -310.285564) (xy 163.64843 -310.328105) (xy 163.616296 -310.365946) (xy 163.578462 -310.398089)
			(xy 163.535927 -310.423689) (xy 163.489811 -310.44207) (xy 163.441328 -310.452748) (xy 163.391757 -310.455442)
			(xy 163.342403 -310.450081) (xy 163.294567 -310.436806) (xy 163.249508 -310.415967) (xy 163.208414 -310.388113)
			(xy 163.172367 -310.353978) (xy 163.142318 -310.31446) (xy 163.119058 -310.270603) (xy 163.103199 -310.223559)
			(xy 163.09516 -310.17457) (xy 163.09467 -310.149748) (xy 163.094854 -310.135565) (xy 163.097521 -310.107325)
			(xy 163.100004 -310.09336) (xy 163.10229 -310.080914) (xy 163.094924 -310.057292) (xy 163.017454 -309.979822)
			(xy 162.993832 -309.972456) (xy 162.981386 -309.974742) (xy 162.96742 -309.977216) (xy 162.93918 -309.97989)
			(xy 162.924998 -309.980076) (xy 162.910815 -309.9799) (xy 162.882575 -309.977228) (xy 162.86861 -309.974742)
			(xy 162.856164 -309.972456) (xy 162.832542 -309.979822) (xy 162.755072 -310.057292) (xy 162.747706 -310.080914)
			(xy 162.749992 -310.09336) (xy 162.752473 -310.107325) (xy 162.755142 -310.135565) (xy 162.755326 -310.149748)
			(xy 162.75477 -310.174564) (xy 162.746733 -310.223542) (xy 162.730878 -310.270575) (xy 162.707623 -310.314422)
			(xy 162.677581 -310.35393) (xy 162.641543 -310.388058) (xy 162.600459 -310.415906) (xy 162.55541 -310.43674)
			(xy 162.507585 -310.450012) (xy 162.458242 -310.455372) (xy 162.408682 -310.452679) (xy 162.360211 -310.442003)
			(xy 162.314106 -310.423627) (xy 162.27158 -310.398034) (xy 162.233755 -310.365898) (xy 162.201628 -310.328066)
			(xy 162.176044 -310.285535) (xy 162.157677 -310.239426) (xy 162.147012 -310.190952) (xy 162.14433 -310.141392)
			(xy 161.805198 -310.141392) (xy 161.805366 -310.149748) (xy 161.804871 -310.174355) (xy 161.796976 -310.222932)
			(xy 161.781392 -310.269613) (xy 161.758521 -310.31319) (xy 161.728956 -310.352534) (xy 161.693463 -310.386626)
			(xy 161.65296 -310.414582) (xy 161.608498 -310.43568) (xy 161.561227 -310.449372) (xy 161.512372 -310.455304)
			(xy 161.463197 -310.453323) (xy 161.414978 -310.443479) (xy 161.368962 -310.426027) (xy 161.326341 -310.40142)
			(xy 161.28822 -310.370295) (xy 161.255585 -310.333458) (xy 161.229282 -310.291862) (xy 161.209991 -310.246586)
			(xy 161.198214 -310.198802) (xy 161.194254 -310.149748) (xy 160.855152 -310.149748) (xy 160.854657 -310.174355)
			(xy 160.846762 -310.222932) (xy 160.831178 -310.269613) (xy 160.808307 -310.31319) (xy 160.778742 -310.352534)
			(xy 160.743249 -310.386626) (xy 160.702746 -310.414582) (xy 160.658284 -310.43568) (xy 160.611013 -310.449372)
			(xy 160.562158 -310.455304) (xy 160.512983 -310.453323) (xy 160.464764 -310.443479) (xy 160.418748 -310.426027)
			(xy 160.376127 -310.40142) (xy 160.338006 -310.370295) (xy 160.305371 -310.333458) (xy 160.279068 -310.291862)
			(xy 160.259777 -310.246586) (xy 160.248 -310.198802) (xy 160.24404 -310.149748) (xy 159.905192 -310.149748)
			(xy 159.904697 -310.174355) (xy 159.896802 -310.222932) (xy 159.881218 -310.269613) (xy 159.858347 -310.31319)
			(xy 159.828782 -310.352534) (xy 159.793289 -310.386626) (xy 159.752786 -310.414582) (xy 159.708324 -310.43568)
			(xy 159.661053 -310.449372) (xy 159.612198 -310.455304) (xy 159.563023 -310.453323) (xy 159.514804 -310.443479)
			(xy 159.468788 -310.426027) (xy 159.426167 -310.40142) (xy 159.388046 -310.370295) (xy 159.355411 -310.333458)
			(xy 159.329108 -310.291862) (xy 159.309817 -310.246586) (xy 159.29804 -310.198802) (xy 159.29408 -310.149748)
			(xy 158.955232 -310.149748) (xy 158.954737 -310.174355) (xy 158.946842 -310.222932) (xy 158.931258 -310.269613)
			(xy 158.908387 -310.31319) (xy 158.878822 -310.352534) (xy 158.843329 -310.386626) (xy 158.802826 -310.414582)
			(xy 158.758364 -310.43568) (xy 158.711093 -310.449372) (xy 158.662238 -310.455304) (xy 158.613063 -310.453323)
			(xy 158.564844 -310.443479) (xy 158.518828 -310.426027) (xy 158.476207 -310.40142) (xy 158.438086 -310.370295)
			(xy 158.405451 -310.333458) (xy 158.379148 -310.291862) (xy 158.359857 -310.246586) (xy 158.34808 -310.198802)
			(xy 158.34412 -310.149748) (xy 158.005272 -310.149748) (xy 158.004777 -310.174355) (xy 157.996882 -310.222932)
			(xy 157.981298 -310.269613) (xy 157.958427 -310.31319) (xy 157.928862 -310.352534) (xy 157.893369 -310.386626)
			(xy 157.852866 -310.414582) (xy 157.808404 -310.43568) (xy 157.761133 -310.449372) (xy 157.712278 -310.455304)
			(xy 157.663103 -310.453323) (xy 157.614884 -310.443479) (xy 157.568868 -310.426027) (xy 157.526247 -310.40142)
			(xy 157.488126 -310.370295) (xy 157.455491 -310.333458) (xy 157.429188 -310.291862) (xy 157.409897 -310.246586)
			(xy 157.39812 -310.198802) (xy 157.39416 -310.149748) (xy 157.055312 -310.149748) (xy 157.054817 -310.174355)
			(xy 157.046922 -310.222932) (xy 157.031338 -310.269613) (xy 157.008467 -310.31319) (xy 156.978902 -310.352534)
			(xy 156.943409 -310.386626) (xy 156.902906 -310.414582) (xy 156.858444 -310.43568) (xy 156.811173 -310.449372)
			(xy 156.762318 -310.455304) (xy 156.713143 -310.453323) (xy 156.664924 -310.443479) (xy 156.618908 -310.426027)
			(xy 156.576287 -310.40142) (xy 156.538166 -310.370295) (xy 156.505531 -310.333458) (xy 156.479228 -310.291862)
			(xy 156.459937 -310.246586) (xy 156.44816 -310.198802) (xy 156.4442 -310.149748) (xy 156.105352 -310.149748)
			(xy 156.104857 -310.174355) (xy 156.096962 -310.222932) (xy 156.081378 -310.269613) (xy 156.058507 -310.31319)
			(xy 156.028942 -310.352534) (xy 155.993449 -310.386626) (xy 155.952946 -310.414582) (xy 155.908484 -310.43568)
			(xy 155.861213 -310.449372) (xy 155.812358 -310.455304) (xy 155.763183 -310.453323) (xy 155.714964 -310.443479)
			(xy 155.668948 -310.426027) (xy 155.626327 -310.40142) (xy 155.588206 -310.370295) (xy 155.555571 -310.333458)
			(xy 155.529268 -310.291862) (xy 155.509977 -310.246586) (xy 155.4982 -310.198802) (xy 155.49424 -310.149748)
			(xy 155.155392 -310.149748) (xy 155.154897 -310.174355) (xy 155.147002 -310.222932) (xy 155.131418 -310.269613)
			(xy 155.108547 -310.31319) (xy 155.078982 -310.352534) (xy 155.043489 -310.386626) (xy 155.002986 -310.414582)
			(xy 154.958524 -310.43568) (xy 154.911253 -310.449372) (xy 154.862398 -310.455304) (xy 154.813223 -310.453323)
			(xy 154.765004 -310.443479) (xy 154.718988 -310.426027) (xy 154.676367 -310.40142) (xy 154.638246 -310.370295)
			(xy 154.605611 -310.333458) (xy 154.579308 -310.291862) (xy 154.560017 -310.246586) (xy 154.54824 -310.198802)
			(xy 154.54428 -310.149748) (xy 154.227022 -310.149748) (xy 154.226518 -310.175456) (xy 154.218475 -310.226238)
			(xy 154.202587 -310.275137) (xy 154.179244 -310.320949) (xy 154.149023 -310.362545) (xy 154.112667 -310.398901)
			(xy 154.071071 -310.429122) (xy 154.025259 -310.452465) (xy 153.97636 -310.468353) (xy 153.925578 -310.476396)
			(xy 153.874162 -310.476396) (xy 153.82338 -310.468353) (xy 153.774481 -310.452465) (xy 153.728669 -310.429122)
			(xy 153.687073 -310.398901) (xy 153.650717 -310.362545) (xy 153.620496 -310.320949) (xy 153.597153 -310.275137)
			(xy 153.581265 -310.226238) (xy 153.573222 -310.175456) (xy 153.276558 -310.175456) (xy 153.268515 -310.226238)
			(xy 153.252627 -310.275137) (xy 153.229284 -310.320949) (xy 153.199063 -310.362545) (xy 153.162707 -310.398901)
			(xy 153.121111 -310.429122) (xy 153.075299 -310.452465) (xy 153.0264 -310.468353) (xy 152.975618 -310.476396)
			(xy 152.924202 -310.476396) (xy 152.87342 -310.468353) (xy 152.824521 -310.452465) (xy 152.778709 -310.429122)
			(xy 152.737113 -310.398901) (xy 152.700757 -310.362545) (xy 152.670536 -310.320949) (xy 152.647193 -310.275137)
			(xy 152.631305 -310.226238) (xy 152.623262 -310.175456) (xy 152.304371 -310.175456) (xy 152.296614 -310.223186)
			(xy 152.28103 -310.269867) (xy 152.258159 -310.313444) (xy 152.228594 -310.352788) (xy 152.193101 -310.38688)
			(xy 152.152598 -310.414836) (xy 152.108136 -310.435934) (xy 152.060865 -310.449626) (xy 152.01201 -310.455558)
			(xy 151.962835 -310.453577) (xy 151.914616 -310.443733) (xy 151.8686 -310.426281) (xy 151.825979 -310.401674)
			(xy 151.787858 -310.370549) (xy 151.755223 -310.333712) (xy 151.72892 -310.292116) (xy 151.709629 -310.24684)
			(xy 151.697852 -310.199056) (xy 151.693892 -310.150002) (xy 151.207599 -310.150002) (xy 151.187631 -310.172288)
			(xy 151.144763 -310.207963) (xy 151.097157 -310.237017) (xy 151.045828 -310.258829) (xy 150.991871 -310.272935)
			(xy 150.936434 -310.279035) (xy 150.8807 -310.276998) (xy 150.825857 -310.266868) (xy 150.773073 -310.248861)
			(xy 150.723473 -310.22336) (xy 150.678115 -310.190909) (xy 150.637966 -310.1522) (xy 150.60388 -310.108057)
			(xy 150.576584 -310.059422) (xy 150.556661 -310.007331) (xy 150.544535 -309.952894) (xy 150.540464 -309.897272)
			(xy 118.832884 -309.897272) (xy 118.832884 -310.832246) (xy 144.36801 -310.832246) (xy 144.372081 -310.776624)
			(xy 144.384207 -310.722187) (xy 144.40413 -310.670096) (xy 144.431426 -310.621461) (xy 144.465512 -310.577318)
			(xy 144.505661 -310.538609) (xy 144.551019 -310.506158) (xy 144.600619 -310.480657) (xy 144.653403 -310.46265)
			(xy 144.708246 -310.45252) (xy 144.76398 -310.450483) (xy 144.819417 -310.456583) (xy 144.873374 -310.470689)
			(xy 144.924703 -310.492501) (xy 144.972309 -310.521555) (xy 145.015177 -310.55723) (xy 145.052394 -310.598767)
			(xy 145.083167 -310.64528) (xy 145.106839 -310.695777) (xy 145.122907 -310.749184) (xy 145.131027 -310.80436)
			(xy 145.131536 -310.832246) (xy 145.131027 -310.860132) (xy 145.122907 -310.915308) (xy 145.106839 -310.968715)
			(xy 145.084725 -311.015888) (xy 150.371808 -311.015888) (xy 150.375879 -310.960266) (xy 150.388005 -310.905829)
			(xy 150.407928 -310.853738) (xy 150.435224 -310.805103) (xy 150.46931 -310.76096) (xy 150.509459 -310.722251)
			(xy 150.554817 -310.6898) (xy 150.604417 -310.664299) (xy 150.657201 -310.646292) (xy 150.712044 -310.636162)
			(xy 150.767778 -310.634125) (xy 150.823215 -310.640225) (xy 150.877172 -310.654331) (xy 150.928501 -310.676143)
			(xy 150.976107 -310.705197) (xy 151.018975 -310.740872) (xy 151.056192 -310.782409) (xy 151.086965 -310.828922)
			(xy 151.110637 -310.879419) (xy 151.126705 -310.932826) (xy 151.134825 -310.988002) (xy 151.135334 -311.015888)
			(xy 151.134825 -311.043774) (xy 151.126705 -311.09895) (xy 151.126401 -311.099962) (xy 152.644106 -311.099962)
			(xy 152.648066 -311.050908) (xy 152.659843 -311.003124) (xy 152.679134 -310.957848) (xy 152.705437 -310.916252)
			(xy 152.738072 -310.879415) (xy 152.776193 -310.84829) (xy 152.818814 -310.823683) (xy 152.86483 -310.806231)
			(xy 152.913049 -310.796387) (xy 152.962224 -310.794406) (xy 153.011079 -310.800338) (xy 153.05835 -310.81403)
			(xy 153.102812 -310.835128) (xy 153.143315 -310.863084) (xy 153.178808 -310.897176) (xy 153.208373 -310.93652)
			(xy 153.231244 -310.980097) (xy 153.246828 -311.026778) (xy 153.254723 -311.075355) (xy 153.255218 -311.099962)
			(xy 153.594066 -311.099962) (xy 153.598026 -311.050908) (xy 153.609803 -311.003124) (xy 153.629094 -310.957848)
			(xy 153.655397 -310.916252) (xy 153.688032 -310.879415) (xy 153.726153 -310.84829) (xy 153.768774 -310.823683)
			(xy 153.81479 -310.806231) (xy 153.863009 -310.796387) (xy 153.912184 -310.794406) (xy 153.961039 -310.800338)
			(xy 154.00831 -310.81403) (xy 154.052772 -310.835128) (xy 154.093275 -310.863084) (xy 154.128768 -310.897176)
			(xy 154.158333 -310.93652) (xy 154.181204 -310.980097) (xy 154.196788 -311.026778) (xy 154.204683 -311.075355)
			(xy 154.205178 -311.099962) (xy 154.54428 -311.099962) (xy 154.54824 -311.050908) (xy 154.560017 -311.003124)
			(xy 154.579308 -310.957848) (xy 154.605611 -310.916252) (xy 154.638246 -310.879415) (xy 154.676367 -310.84829)
			(xy 154.718988 -310.823683) (xy 154.765004 -310.806231) (xy 154.813223 -310.796387) (xy 154.862398 -310.794406)
			(xy 154.911253 -310.800338) (xy 154.958524 -310.81403) (xy 155.002986 -310.835128) (xy 155.043489 -310.863084)
			(xy 155.078982 -310.897176) (xy 155.108547 -310.93652) (xy 155.131418 -310.980097) (xy 155.147002 -311.026778)
			(xy 155.154897 -311.075355) (xy 155.155392 -311.099962) (xy 155.154897 -311.124569) (xy 155.154718 -311.12567)
			(xy 155.473396 -311.12567) (xy 155.473396 -311.074254) (xy 155.481439 -311.023472) (xy 155.497327 -310.974573)
			(xy 155.52067 -310.928761) (xy 155.550891 -310.887165) (xy 155.587247 -310.850809) (xy 155.628843 -310.820588)
			(xy 155.674655 -310.797245) (xy 155.723554 -310.781357) (xy 155.774336 -310.773314) (xy 155.825752 -310.773314)
			(xy 155.876534 -310.781357) (xy 155.925433 -310.797245) (xy 155.971245 -310.820588) (xy 156.012841 -310.850809)
			(xy 156.049197 -310.887165) (xy 156.079418 -310.928761) (xy 156.102761 -310.974573) (xy 156.118649 -311.023472)
			(xy 156.126692 -311.074254) (xy 156.127196 -311.099962) (xy 156.4442 -311.099962) (xy 156.44816 -311.050908)
			(xy 156.459937 -311.003124) (xy 156.479228 -310.957848) (xy 156.505531 -310.916252) (xy 156.538166 -310.879415)
			(xy 156.576287 -310.84829) (xy 156.618908 -310.823683) (xy 156.664924 -310.806231) (xy 156.713143 -310.796387)
			(xy 156.762318 -310.794406) (xy 156.811173 -310.800338) (xy 156.858444 -310.81403) (xy 156.902906 -310.835128)
			(xy 156.943409 -310.863084) (xy 156.978902 -310.897176) (xy 157.008467 -310.93652) (xy 157.031338 -310.980097)
			(xy 157.046922 -311.026778) (xy 157.054817 -311.075355) (xy 157.055312 -311.099962) (xy 157.054817 -311.124569)
			(xy 157.054638 -311.12567) (xy 157.373316 -311.12567) (xy 157.373316 -311.074254) (xy 157.381359 -311.023472)
			(xy 157.397247 -310.974573) (xy 157.42059 -310.928761) (xy 157.450811 -310.887165) (xy 157.487167 -310.850809)
			(xy 157.528763 -310.820588) (xy 157.574575 -310.797245) (xy 157.623474 -310.781357) (xy 157.674256 -310.773314)
			(xy 157.725672 -310.773314) (xy 157.776454 -310.781357) (xy 157.825353 -310.797245) (xy 157.871165 -310.820588)
			(xy 157.912761 -310.850809) (xy 157.949117 -310.887165) (xy 157.979338 -310.928761) (xy 158.002681 -310.974573)
			(xy 158.018569 -311.023472) (xy 158.026612 -311.074254) (xy 158.027116 -311.099962) (xy 158.34412 -311.099962)
			(xy 158.34808 -311.050908) (xy 158.359857 -311.003124) (xy 158.379148 -310.957848) (xy 158.405451 -310.916252)
			(xy 158.438086 -310.879415) (xy 158.476207 -310.84829) (xy 158.518828 -310.823683) (xy 158.564844 -310.806231)
			(xy 158.613063 -310.796387) (xy 158.662238 -310.794406) (xy 158.711093 -310.800338) (xy 158.758364 -310.81403)
			(xy 158.802826 -310.835128) (xy 158.843329 -310.863084) (xy 158.878822 -310.897176) (xy 158.908387 -310.93652)
			(xy 158.931258 -310.980097) (xy 158.946842 -311.026778) (xy 158.954737 -311.075355) (xy 158.955232 -311.099962)
			(xy 158.954737 -311.124569) (xy 158.954558 -311.12567) (xy 159.273236 -311.12567) (xy 159.273236 -311.074254)
			(xy 159.281279 -311.023472) (xy 159.297167 -310.974573) (xy 159.32051 -310.928761) (xy 159.350731 -310.887165)
			(xy 159.387087 -310.850809) (xy 159.428683 -310.820588) (xy 159.474495 -310.797245) (xy 159.523394 -310.781357)
			(xy 159.574176 -310.773314) (xy 159.625592 -310.773314) (xy 159.676374 -310.781357) (xy 159.725273 -310.797245)
			(xy 159.771085 -310.820588) (xy 159.812681 -310.850809) (xy 159.849037 -310.887165) (xy 159.879258 -310.928761)
			(xy 159.902601 -310.974573) (xy 159.918489 -311.023472) (xy 159.926532 -311.074254) (xy 159.927036 -311.099962)
			(xy 160.24404 -311.099962) (xy 160.248 -311.050908) (xy 160.259777 -311.003124) (xy 160.279068 -310.957848)
			(xy 160.305371 -310.916252) (xy 160.338006 -310.879415) (xy 160.376127 -310.84829) (xy 160.418748 -310.823683)
			(xy 160.464764 -310.806231) (xy 160.512983 -310.796387) (xy 160.562158 -310.794406) (xy 160.611013 -310.800338)
			(xy 160.658284 -310.81403) (xy 160.702746 -310.835128) (xy 160.743249 -310.863084) (xy 160.778742 -310.897176)
			(xy 160.808307 -310.93652) (xy 160.831178 -310.980097) (xy 160.846762 -311.026778) (xy 160.854657 -311.075355)
			(xy 160.855152 -311.099962) (xy 160.854657 -311.124569) (xy 160.854478 -311.12567) (xy 161.17341 -311.12567)
			(xy 161.17341 -311.074254) (xy 161.181453 -311.023472) (xy 161.197341 -310.974573) (xy 161.220684 -310.928761)
			(xy 161.250905 -310.887165) (xy 161.287261 -310.850809) (xy 161.328857 -310.820588) (xy 161.374669 -310.797245)
			(xy 161.423568 -310.781357) (xy 161.47435 -310.773314) (xy 161.525766 -310.773314) (xy 161.576548 -310.781357)
			(xy 161.625447 -310.797245) (xy 161.671259 -310.820588) (xy 161.712855 -310.850809) (xy 161.749211 -310.887165)
			(xy 161.779432 -310.928761) (xy 161.802775 -310.974573) (xy 161.818663 -311.023472) (xy 161.826706 -311.074254)
			(xy 161.82721 -311.099962) (xy 162.144214 -311.099962) (xy 162.148174 -311.050908) (xy 162.159951 -311.003124)
			(xy 162.179242 -310.957848) (xy 162.205545 -310.916252) (xy 162.23818 -310.879415) (xy 162.276301 -310.84829)
			(xy 162.318922 -310.823683) (xy 162.364938 -310.806231) (xy 162.413157 -310.796387) (xy 162.462332 -310.794406)
			(xy 162.511187 -310.800338) (xy 162.558458 -310.81403) (xy 162.60292 -310.835128) (xy 162.643423 -310.863084)
			(xy 162.678916 -310.897176) (xy 162.708481 -310.93652) (xy 162.731352 -310.980097) (xy 162.746936 -311.026778)
			(xy 162.754831 -311.075355) (xy 162.755326 -311.099962) (xy 162.754831 -311.124569) (xy 162.754652 -311.12567)
			(xy 163.07333 -311.12567) (xy 163.07333 -311.074254) (xy 163.081373 -311.023472) (xy 163.097261 -310.974573)
			(xy 163.120604 -310.928761) (xy 163.150825 -310.887165) (xy 163.187181 -310.850809) (xy 163.228777 -310.820588)
			(xy 163.274589 -310.797245) (xy 163.323488 -310.781357) (xy 163.37427 -310.773314) (xy 163.425686 -310.773314)
			(xy 163.476468 -310.781357) (xy 163.525367 -310.797245) (xy 163.571179 -310.820588) (xy 163.612775 -310.850809)
			(xy 163.649131 -310.887165) (xy 163.679352 -310.928761) (xy 163.702695 -310.974573) (xy 163.718583 -311.023472)
			(xy 163.726626 -311.074254) (xy 163.72713 -311.099962) (xy 164.044134 -311.099962) (xy 164.048094 -311.050908)
			(xy 164.059871 -311.003124) (xy 164.079162 -310.957848) (xy 164.105465 -310.916252) (xy 164.1381 -310.879415)
			(xy 164.176221 -310.84829) (xy 164.218842 -310.823683) (xy 164.264858 -310.806231) (xy 164.313077 -310.796387)
			(xy 164.362252 -310.794406) (xy 164.411107 -310.800338) (xy 164.458378 -310.81403) (xy 164.50284 -310.835128)
			(xy 164.543343 -310.863084) (xy 164.578836 -310.897176) (xy 164.608401 -310.93652) (xy 164.631272 -310.980097)
			(xy 164.646856 -311.026778) (xy 164.654751 -311.075355) (xy 164.655246 -311.099962) (xy 164.654751 -311.124569)
			(xy 164.654572 -311.12567) (xy 164.97325 -311.12567) (xy 164.97325 -311.074254) (xy 164.981293 -311.023472)
			(xy 164.997181 -310.974573) (xy 165.020524 -310.928761) (xy 165.050745 -310.887165) (xy 165.087101 -310.850809)
			(xy 165.128697 -310.820588) (xy 165.174509 -310.797245) (xy 165.223408 -310.781357) (xy 165.27419 -310.773314)
			(xy 165.325606 -310.773314) (xy 165.376388 -310.781357) (xy 165.425287 -310.797245) (xy 165.471099 -310.820588)
			(xy 165.512695 -310.850809) (xy 165.549051 -310.887165) (xy 165.579272 -310.928761) (xy 165.602615 -310.974573)
			(xy 165.618503 -311.023472) (xy 165.626546 -311.074254) (xy 165.62705 -311.099962) (xy 165.944054 -311.099962)
			(xy 165.948014 -311.050908) (xy 165.959791 -311.003124) (xy 165.979082 -310.957848) (xy 166.005385 -310.916252)
			(xy 166.03802 -310.879415) (xy 166.076141 -310.84829) (xy 166.118762 -310.823683) (xy 166.164778 -310.806231)
			(xy 166.212997 -310.796387) (xy 166.262172 -310.794406) (xy 166.311027 -310.800338) (xy 166.358298 -310.81403)
			(xy 166.40276 -310.835128) (xy 166.443263 -310.863084) (xy 166.478756 -310.897176) (xy 166.508321 -310.93652)
			(xy 166.531192 -310.980097) (xy 166.546776 -311.026778) (xy 166.554671 -311.075355) (xy 166.555166 -311.099962)
			(xy 166.554671 -311.124569) (xy 166.554492 -311.12567) (xy 166.873424 -311.12567) (xy 166.873424 -311.074254)
			(xy 166.881467 -311.023472) (xy 166.897355 -310.974573) (xy 166.920698 -310.928761) (xy 166.950919 -310.887165)
			(xy 166.987275 -310.850809) (xy 167.028871 -310.820588) (xy 167.074683 -310.797245) (xy 167.123582 -310.781357)
			(xy 167.174364 -310.773314) (xy 167.22578 -310.773314) (xy 167.276562 -310.781357) (xy 167.325461 -310.797245)
			(xy 167.371273 -310.820588) (xy 167.412869 -310.850809) (xy 167.449225 -310.887165) (xy 167.479446 -310.928761)
			(xy 167.502789 -310.974573) (xy 167.518677 -311.023472) (xy 167.52672 -311.074254) (xy 167.527224 -311.099962)
			(xy 167.844228 -311.099962) (xy 167.848188 -311.050908) (xy 167.859965 -311.003124) (xy 167.879256 -310.957848)
			(xy 167.905559 -310.916252) (xy 167.938194 -310.879415) (xy 167.976315 -310.84829) (xy 168.018936 -310.823683)
			(xy 168.064952 -310.806231) (xy 168.113171 -310.796387) (xy 168.162346 -310.794406) (xy 168.211201 -310.800338)
			(xy 168.258472 -310.81403) (xy 168.302934 -310.835128) (xy 168.343437 -310.863084) (xy 168.37893 -310.897176)
			(xy 168.408495 -310.93652) (xy 168.431366 -310.980097) (xy 168.44695 -311.026778) (xy 168.454845 -311.075355)
			(xy 168.45534 -311.099962) (xy 168.454845 -311.124569) (xy 168.454666 -311.12567) (xy 168.773344 -311.12567)
			(xy 168.773344 -311.074254) (xy 168.781387 -311.023472) (xy 168.797275 -310.974573) (xy 168.820618 -310.928761)
			(xy 168.850839 -310.887165) (xy 168.887195 -310.850809) (xy 168.928791 -310.820588) (xy 168.974603 -310.797245)
			(xy 169.023502 -310.781357) (xy 169.074284 -310.773314) (xy 169.1257 -310.773314) (xy 169.176482 -310.781357)
			(xy 169.225381 -310.797245) (xy 169.271193 -310.820588) (xy 169.312789 -310.850809) (xy 169.349145 -310.887165)
			(xy 169.379366 -310.928761) (xy 169.402709 -310.974573) (xy 169.418597 -311.023472) (xy 169.42664 -311.074254)
			(xy 169.427144 -311.099962) (xy 169.744148 -311.099962) (xy 169.748108 -311.050908) (xy 169.759885 -311.003124)
			(xy 169.779176 -310.957848) (xy 169.805479 -310.916252) (xy 169.838114 -310.879415) (xy 169.876235 -310.84829)
			(xy 169.918856 -310.823683) (xy 169.964872 -310.806231) (xy 170.013091 -310.796387) (xy 170.062266 -310.794406)
			(xy 170.111121 -310.800338) (xy 170.158392 -310.81403) (xy 170.202854 -310.835128) (xy 170.243357 -310.863084)
			(xy 170.27885 -310.897176) (xy 170.308415 -310.93652) (xy 170.331286 -310.980097) (xy 170.34687 -311.026778)
			(xy 170.354765 -311.075355) (xy 170.35526 -311.099962) (xy 170.354765 -311.124569) (xy 170.354586 -311.12567)
			(xy 170.673264 -311.12567) (xy 170.673264 -311.074254) (xy 170.681307 -311.023472) (xy 170.697195 -310.974573)
			(xy 170.720538 -310.928761) (xy 170.750759 -310.887165) (xy 170.787115 -310.850809) (xy 170.828711 -310.820588)
			(xy 170.874523 -310.797245) (xy 170.923422 -310.781357) (xy 170.974204 -310.773314) (xy 171.02562 -310.773314)
			(xy 171.076402 -310.781357) (xy 171.125301 -310.797245) (xy 171.171113 -310.820588) (xy 171.212709 -310.850809)
			(xy 171.249065 -310.887165) (xy 171.279286 -310.928761) (xy 171.302629 -310.974573) (xy 171.318517 -311.023472)
			(xy 171.32656 -311.074254) (xy 171.327064 -311.099962) (xy 171.644068 -311.099962) (xy 171.648028 -311.050908)
			(xy 171.659805 -311.003124) (xy 171.679096 -310.957848) (xy 171.705399 -310.916252) (xy 171.738034 -310.879415)
			(xy 171.776155 -310.84829) (xy 171.818776 -310.823683) (xy 171.864792 -310.806231) (xy 171.913011 -310.796387)
			(xy 171.962186 -310.794406) (xy 172.011041 -310.800338) (xy 172.058312 -310.81403) (xy 172.102774 -310.835128)
			(xy 172.143277 -310.863084) (xy 172.17877 -310.897176) (xy 172.208335 -310.93652) (xy 172.231206 -310.980097)
			(xy 172.24679 -311.026778) (xy 172.254685 -311.075355) (xy 172.25518 -311.099962) (xy 172.254685 -311.124569)
			(xy 172.254506 -311.12567) (xy 172.573438 -311.12567) (xy 172.573438 -311.074254) (xy 172.581481 -311.023472)
			(xy 172.597369 -310.974573) (xy 172.620712 -310.928761) (xy 172.650933 -310.887165) (xy 172.687289 -310.850809)
			(xy 172.728885 -310.820588) (xy 172.774697 -310.797245) (xy 172.823596 -310.781357) (xy 172.874378 -310.773314)
			(xy 172.925794 -310.773314) (xy 172.976576 -310.781357) (xy 173.025475 -310.797245) (xy 173.071287 -310.820588)
			(xy 173.112883 -310.850809) (xy 173.149239 -310.887165) (xy 173.17946 -310.928761) (xy 173.202803 -310.974573)
			(xy 173.218691 -311.023472) (xy 173.226734 -311.074254) (xy 173.227238 -311.099962) (xy 173.544242 -311.099962)
			(xy 173.548202 -311.050908) (xy 173.559979 -311.003124) (xy 173.57927 -310.957848) (xy 173.605573 -310.916252)
			(xy 173.638208 -310.879415) (xy 173.676329 -310.84829) (xy 173.71895 -310.823683) (xy 173.764966 -310.806231)
			(xy 173.813185 -310.796387) (xy 173.86236 -310.794406) (xy 173.911215 -310.800338) (xy 173.958486 -310.81403)
			(xy 174.002948 -310.835128) (xy 174.043451 -310.863084) (xy 174.078944 -310.897176) (xy 174.108509 -310.93652)
			(xy 174.13138 -310.980097) (xy 174.146964 -311.026778) (xy 174.154859 -311.075355) (xy 174.155354 -311.099962)
			(xy 174.154859 -311.124569) (xy 174.15468 -311.12567) (xy 174.473358 -311.12567) (xy 174.473358 -311.074254)
			(xy 174.481401 -311.023472) (xy 174.497289 -310.974573) (xy 174.520632 -310.928761) (xy 174.550853 -310.887165)
			(xy 174.587209 -310.850809) (xy 174.628805 -310.820588) (xy 174.674617 -310.797245) (xy 174.723516 -310.781357)
			(xy 174.774298 -310.773314) (xy 174.825714 -310.773314) (xy 174.876496 -310.781357) (xy 174.925395 -310.797245)
			(xy 174.971207 -310.820588) (xy 175.012803 -310.850809) (xy 175.049159 -310.887165) (xy 175.07938 -310.928761)
			(xy 175.102723 -310.974573) (xy 175.118611 -311.023472) (xy 175.126654 -311.074254) (xy 175.127158 -311.099962)
			(xy 175.444162 -311.099962) (xy 175.448122 -311.050908) (xy 175.459899 -311.003124) (xy 175.47919 -310.957848)
			(xy 175.505493 -310.916252) (xy 175.538128 -310.879415) (xy 175.576249 -310.84829) (xy 175.61887 -310.823683)
			(xy 175.664886 -310.806231) (xy 175.713105 -310.796387) (xy 175.76228 -310.794406) (xy 175.811135 -310.800338)
			(xy 175.858406 -310.81403) (xy 175.902868 -310.835128) (xy 175.943371 -310.863084) (xy 175.978864 -310.897176)
			(xy 176.008429 -310.93652) (xy 176.0313 -310.980097) (xy 176.046884 -311.026778) (xy 176.054779 -311.075355)
			(xy 176.055274 -311.099962) (xy 176.054779 -311.124569) (xy 176.0546 -311.12567) (xy 176.373278 -311.12567)
			(xy 176.373278 -311.074254) (xy 176.381321 -311.023472) (xy 176.397209 -310.974573) (xy 176.420552 -310.928761)
			(xy 176.450773 -310.887165) (xy 176.487129 -310.850809) (xy 176.528725 -310.820588) (xy 176.574537 -310.797245)
			(xy 176.623436 -310.781357) (xy 176.674218 -310.773314) (xy 176.725634 -310.773314) (xy 176.776416 -310.781357)
			(xy 176.825315 -310.797245) (xy 176.871127 -310.820588) (xy 176.912723 -310.850809) (xy 176.949079 -310.887165)
			(xy 176.9793 -310.928761) (xy 177.002643 -310.974573) (xy 177.018531 -311.023472) (xy 177.026574 -311.074254)
			(xy 177.027078 -311.099962) (xy 177.344082 -311.099962) (xy 177.348042 -311.050908) (xy 177.359819 -311.003124)
			(xy 177.37911 -310.957848) (xy 177.405413 -310.916252) (xy 177.438048 -310.879415) (xy 177.476169 -310.84829)
			(xy 177.51879 -310.823683) (xy 177.564806 -310.806231) (xy 177.613025 -310.796387) (xy 177.6622 -310.794406)
			(xy 177.711055 -310.800338) (xy 177.758326 -310.81403) (xy 177.802788 -310.835128) (xy 177.843291 -310.863084)
			(xy 177.878784 -310.897176) (xy 177.908349 -310.93652) (xy 177.93122 -310.980097) (xy 177.946804 -311.026778)
			(xy 177.954699 -311.075355) (xy 177.955194 -311.099962) (xy 177.954699 -311.124569) (xy 177.95452 -311.12567)
			(xy 178.273198 -311.12567) (xy 178.273198 -311.074254) (xy 178.281241 -311.023472) (xy 178.297129 -310.974573)
			(xy 178.320472 -310.928761) (xy 178.350693 -310.887165) (xy 178.387049 -310.850809) (xy 178.428645 -310.820588)
			(xy 178.474457 -310.797245) (xy 178.523356 -310.781357) (xy 178.574138 -310.773314) (xy 178.625554 -310.773314)
			(xy 178.676336 -310.781357) (xy 178.725235 -310.797245) (xy 178.771047 -310.820588) (xy 178.812643 -310.850809)
			(xy 178.848999 -310.887165) (xy 178.87922 -310.928761) (xy 178.902563 -310.974573) (xy 178.918451 -311.023472)
			(xy 178.926494 -311.074254) (xy 178.926998 -311.099962) (xy 179.244256 -311.099962) (xy 179.248216 -311.050908)
			(xy 179.259993 -311.003124) (xy 179.279284 -310.957848) (xy 179.305587 -310.916252) (xy 179.338222 -310.879415)
			(xy 179.376343 -310.84829) (xy 179.418964 -310.823683) (xy 179.46498 -310.806231) (xy 179.513199 -310.796387)
			(xy 179.562374 -310.794406) (xy 179.611229 -310.800338) (xy 179.6585 -310.81403) (xy 179.702962 -310.835128)
			(xy 179.743465 -310.863084) (xy 179.778958 -310.897176) (xy 179.808523 -310.93652) (xy 179.831394 -310.980097)
			(xy 179.846978 -311.026778) (xy 179.854873 -311.075355) (xy 179.855368 -311.099962) (xy 179.854873 -311.124569)
			(xy 179.854694 -311.12567) (xy 180.173372 -311.12567) (xy 180.173372 -311.074254) (xy 180.181415 -311.023472)
			(xy 180.197303 -310.974573) (xy 180.220646 -310.928761) (xy 180.250867 -310.887165) (xy 180.287223 -310.850809)
			(xy 180.328819 -310.820588) (xy 180.374631 -310.797245) (xy 180.42353 -310.781357) (xy 180.474312 -310.773314)
			(xy 180.525728 -310.773314) (xy 180.57651 -310.781357) (xy 180.625409 -310.797245) (xy 180.671221 -310.820588)
			(xy 180.712817 -310.850809) (xy 180.749173 -310.887165) (xy 180.779394 -310.928761) (xy 180.802737 -310.974573)
			(xy 180.818625 -311.023472) (xy 180.826668 -311.074254) (xy 180.827172 -311.099962) (xy 181.144176 -311.099962)
			(xy 181.148136 -311.050908) (xy 181.159913 -311.003124) (xy 181.179204 -310.957848) (xy 181.205507 -310.916252)
			(xy 181.238142 -310.879415) (xy 181.276263 -310.84829) (xy 181.318884 -310.823683) (xy 181.3649 -310.806231)
			(xy 181.413119 -310.796387) (xy 181.462294 -310.794406) (xy 181.511149 -310.800338) (xy 181.55842 -310.81403)
			(xy 181.602882 -310.835128) (xy 181.643385 -310.863084) (xy 181.678878 -310.897176) (xy 181.708443 -310.93652)
			(xy 181.731314 -310.980097) (xy 181.746898 -311.026778) (xy 181.754793 -311.075355) (xy 181.755288 -311.099962)
			(xy 181.754793 -311.124569) (xy 181.754614 -311.12567) (xy 182.073292 -311.12567) (xy 182.073292 -311.074254)
			(xy 182.081335 -311.023472) (xy 182.097223 -310.974573) (xy 182.120566 -310.928761) (xy 182.150787 -310.887165)
			(xy 182.187143 -310.850809) (xy 182.228739 -310.820588) (xy 182.274551 -310.797245) (xy 182.32345 -310.781357)
			(xy 182.374232 -310.773314) (xy 182.425648 -310.773314) (xy 182.47643 -310.781357) (xy 182.525329 -310.797245)
			(xy 182.571141 -310.820588) (xy 182.612737 -310.850809) (xy 182.649093 -310.887165) (xy 182.679314 -310.928761)
			(xy 182.702657 -310.974573) (xy 182.718545 -311.023472) (xy 182.726588 -311.074254) (xy 182.727092 -311.099962)
			(xy 183.044096 -311.099962) (xy 183.048056 -311.050908) (xy 183.059833 -311.003124) (xy 183.079124 -310.957848)
			(xy 183.105427 -310.916252) (xy 183.138062 -310.879415) (xy 183.176183 -310.84829) (xy 183.218804 -310.823683)
			(xy 183.26482 -310.806231) (xy 183.313039 -310.796387) (xy 183.362214 -310.794406) (xy 183.411069 -310.800338)
			(xy 183.45834 -310.81403) (xy 183.502802 -310.835128) (xy 183.543305 -310.863084) (xy 183.578798 -310.897176)
			(xy 183.608363 -310.93652) (xy 183.631234 -310.980097) (xy 183.646818 -311.026778) (xy 183.654713 -311.075355)
			(xy 183.655208 -311.099962) (xy 183.654713 -311.124569) (xy 183.654534 -311.12567) (xy 183.973212 -311.12567)
			(xy 183.973212 -311.074254) (xy 183.981255 -311.023472) (xy 183.997143 -310.974573) (xy 184.020486 -310.928761)
			(xy 184.050707 -310.887165) (xy 184.087063 -310.850809) (xy 184.128659 -310.820588) (xy 184.174471 -310.797245)
			(xy 184.22337 -310.781357) (xy 184.274152 -310.773314) (xy 184.325568 -310.773314) (xy 184.37635 -310.781357)
			(xy 184.425249 -310.797245) (xy 184.471061 -310.820588) (xy 184.512657 -310.850809) (xy 184.549013 -310.887165)
			(xy 184.579234 -310.928761) (xy 184.602577 -310.974573) (xy 184.618465 -311.023472) (xy 184.626508 -311.074254)
			(xy 184.627012 -311.099962) (xy 184.626508 -311.12567) (xy 184.618465 -311.176452) (xy 184.602577 -311.225351)
			(xy 184.579234 -311.271163) (xy 184.549013 -311.312759) (xy 184.512657 -311.349115) (xy 184.471061 -311.379336)
			(xy 184.425249 -311.402679) (xy 184.37635 -311.418567) (xy 184.325568 -311.42661) (xy 184.274152 -311.42661)
			(xy 184.22337 -311.418567) (xy 184.174471 -311.402679) (xy 184.128659 -311.379336) (xy 184.087063 -311.349115)
			(xy 184.050707 -311.312759) (xy 184.020486 -311.271163) (xy 183.997143 -311.225351) (xy 183.981255 -311.176452)
			(xy 183.973212 -311.12567) (xy 183.654534 -311.12567) (xy 183.646818 -311.173146) (xy 183.631234 -311.219827)
			(xy 183.608363 -311.263404) (xy 183.578798 -311.302748) (xy 183.543305 -311.33684) (xy 183.502802 -311.364796)
			(xy 183.45834 -311.385894) (xy 183.411069 -311.399586) (xy 183.362214 -311.405518) (xy 183.313039 -311.403537)
			(xy 183.26482 -311.393693) (xy 183.218804 -311.376241) (xy 183.176183 -311.351634) (xy 183.138062 -311.320509)
			(xy 183.105427 -311.283672) (xy 183.079124 -311.242076) (xy 183.059833 -311.1968) (xy 183.048056 -311.149016)
			(xy 183.044096 -311.099962) (xy 182.727092 -311.099962) (xy 182.726588 -311.12567) (xy 182.718545 -311.176452)
			(xy 182.702657 -311.225351) (xy 182.679314 -311.271163) (xy 182.649093 -311.312759) (xy 182.612737 -311.349115)
			(xy 182.571141 -311.379336) (xy 182.525329 -311.402679) (xy 182.47643 -311.418567) (xy 182.425648 -311.42661)
			(xy 182.374232 -311.42661) (xy 182.32345 -311.418567) (xy 182.274551 -311.402679) (xy 182.228739 -311.379336)
			(xy 182.187143 -311.349115) (xy 182.150787 -311.312759) (xy 182.120566 -311.271163) (xy 182.097223 -311.225351)
			(xy 182.081335 -311.176452) (xy 182.073292 -311.12567) (xy 181.754614 -311.12567) (xy 181.746898 -311.173146)
			(xy 181.731314 -311.219827) (xy 181.708443 -311.263404) (xy 181.678878 -311.302748) (xy 181.643385 -311.33684)
			(xy 181.602882 -311.364796) (xy 181.55842 -311.385894) (xy 181.511149 -311.399586) (xy 181.462294 -311.405518)
			(xy 181.413119 -311.403537) (xy 181.3649 -311.393693) (xy 181.318884 -311.376241) (xy 181.276263 -311.351634)
			(xy 181.238142 -311.320509) (xy 181.205507 -311.283672) (xy 181.179204 -311.242076) (xy 181.159913 -311.1968)
			(xy 181.148136 -311.149016) (xy 181.144176 -311.099962) (xy 180.827172 -311.099962) (xy 180.826668 -311.12567)
			(xy 180.818625 -311.176452) (xy 180.802737 -311.225351) (xy 180.779394 -311.271163) (xy 180.749173 -311.312759)
			(xy 180.712817 -311.349115) (xy 180.671221 -311.379336) (xy 180.625409 -311.402679) (xy 180.57651 -311.418567)
			(xy 180.525728 -311.42661) (xy 180.474312 -311.42661) (xy 180.42353 -311.418567) (xy 180.374631 -311.402679)
			(xy 180.328819 -311.379336) (xy 180.287223 -311.349115) (xy 180.250867 -311.312759) (xy 180.220646 -311.271163)
			(xy 180.197303 -311.225351) (xy 180.181415 -311.176452) (xy 180.173372 -311.12567) (xy 179.854694 -311.12567)
			(xy 179.846978 -311.173146) (xy 179.831394 -311.219827) (xy 179.808523 -311.263404) (xy 179.778958 -311.302748)
			(xy 179.743465 -311.33684) (xy 179.702962 -311.364796) (xy 179.6585 -311.385894) (xy 179.611229 -311.399586)
			(xy 179.562374 -311.405518) (xy 179.513199 -311.403537) (xy 179.46498 -311.393693) (xy 179.418964 -311.376241)
			(xy 179.376343 -311.351634) (xy 179.338222 -311.320509) (xy 179.305587 -311.283672) (xy 179.279284 -311.242076)
			(xy 179.259993 -311.1968) (xy 179.248216 -311.149016) (xy 179.244256 -311.099962) (xy 178.926998 -311.099962)
			(xy 178.926494 -311.12567) (xy 178.918451 -311.176452) (xy 178.902563 -311.225351) (xy 178.87922 -311.271163)
			(xy 178.848999 -311.312759) (xy 178.812643 -311.349115) (xy 178.771047 -311.379336) (xy 178.725235 -311.402679)
			(xy 178.676336 -311.418567) (xy 178.625554 -311.42661) (xy 178.574138 -311.42661) (xy 178.523356 -311.418567)
			(xy 178.474457 -311.402679) (xy 178.428645 -311.379336) (xy 178.387049 -311.349115) (xy 178.350693 -311.312759)
			(xy 178.320472 -311.271163) (xy 178.297129 -311.225351) (xy 178.281241 -311.176452) (xy 178.273198 -311.12567)
			(xy 177.95452 -311.12567) (xy 177.946804 -311.173146) (xy 177.93122 -311.219827) (xy 177.908349 -311.263404)
			(xy 177.878784 -311.302748) (xy 177.843291 -311.33684) (xy 177.802788 -311.364796) (xy 177.758326 -311.385894)
			(xy 177.711055 -311.399586) (xy 177.6622 -311.405518) (xy 177.613025 -311.403537) (xy 177.564806 -311.393693)
			(xy 177.51879 -311.376241) (xy 177.476169 -311.351634) (xy 177.438048 -311.320509) (xy 177.405413 -311.283672)
			(xy 177.37911 -311.242076) (xy 177.359819 -311.1968) (xy 177.348042 -311.149016) (xy 177.344082 -311.099962)
			(xy 177.027078 -311.099962) (xy 177.026574 -311.12567) (xy 177.018531 -311.176452) (xy 177.002643 -311.225351)
			(xy 176.9793 -311.271163) (xy 176.949079 -311.312759) (xy 176.912723 -311.349115) (xy 176.871127 -311.379336)
			(xy 176.825315 -311.402679) (xy 176.776416 -311.418567) (xy 176.725634 -311.42661) (xy 176.674218 -311.42661)
			(xy 176.623436 -311.418567) (xy 176.574537 -311.402679) (xy 176.528725 -311.379336) (xy 176.487129 -311.349115)
			(xy 176.450773 -311.312759) (xy 176.420552 -311.271163) (xy 176.397209 -311.225351) (xy 176.381321 -311.176452)
			(xy 176.373278 -311.12567) (xy 176.0546 -311.12567) (xy 176.046884 -311.173146) (xy 176.0313 -311.219827)
			(xy 176.008429 -311.263404) (xy 175.978864 -311.302748) (xy 175.943371 -311.33684) (xy 175.902868 -311.364796)
			(xy 175.858406 -311.385894) (xy 175.811135 -311.399586) (xy 175.76228 -311.405518) (xy 175.713105 -311.403537)
			(xy 175.664886 -311.393693) (xy 175.61887 -311.376241) (xy 175.576249 -311.351634) (xy 175.538128 -311.320509)
			(xy 175.505493 -311.283672) (xy 175.47919 -311.242076) (xy 175.459899 -311.1968) (xy 175.448122 -311.149016)
			(xy 175.444162 -311.099962) (xy 175.127158 -311.099962) (xy 175.126654 -311.12567) (xy 175.118611 -311.176452)
			(xy 175.102723 -311.225351) (xy 175.07938 -311.271163) (xy 175.049159 -311.312759) (xy 175.012803 -311.349115)
			(xy 174.971207 -311.379336) (xy 174.925395 -311.402679) (xy 174.876496 -311.418567) (xy 174.825714 -311.42661)
			(xy 174.774298 -311.42661) (xy 174.723516 -311.418567) (xy 174.674617 -311.402679) (xy 174.628805 -311.379336)
			(xy 174.587209 -311.349115) (xy 174.550853 -311.312759) (xy 174.520632 -311.271163) (xy 174.497289 -311.225351)
			(xy 174.481401 -311.176452) (xy 174.473358 -311.12567) (xy 174.15468 -311.12567) (xy 174.146964 -311.173146)
			(xy 174.13138 -311.219827) (xy 174.108509 -311.263404) (xy 174.078944 -311.302748) (xy 174.043451 -311.33684)
			(xy 174.002948 -311.364796) (xy 173.958486 -311.385894) (xy 173.911215 -311.399586) (xy 173.86236 -311.405518)
			(xy 173.813185 -311.403537) (xy 173.764966 -311.393693) (xy 173.71895 -311.376241) (xy 173.676329 -311.351634)
			(xy 173.638208 -311.320509) (xy 173.605573 -311.283672) (xy 173.57927 -311.242076) (xy 173.559979 -311.1968)
			(xy 173.548202 -311.149016) (xy 173.544242 -311.099962) (xy 173.227238 -311.099962) (xy 173.226734 -311.12567)
			(xy 173.218691 -311.176452) (xy 173.202803 -311.225351) (xy 173.17946 -311.271163) (xy 173.149239 -311.312759)
			(xy 173.112883 -311.349115) (xy 173.071287 -311.379336) (xy 173.025475 -311.402679) (xy 172.976576 -311.418567)
			(xy 172.925794 -311.42661) (xy 172.874378 -311.42661) (xy 172.823596 -311.418567) (xy 172.774697 -311.402679)
			(xy 172.728885 -311.379336) (xy 172.687289 -311.349115) (xy 172.650933 -311.312759) (xy 172.620712 -311.271163)
			(xy 172.597369 -311.225351) (xy 172.581481 -311.176452) (xy 172.573438 -311.12567) (xy 172.254506 -311.12567)
			(xy 172.24679 -311.173146) (xy 172.231206 -311.219827) (xy 172.208335 -311.263404) (xy 172.17877 -311.302748)
			(xy 172.143277 -311.33684) (xy 172.102774 -311.364796) (xy 172.058312 -311.385894) (xy 172.011041 -311.399586)
			(xy 171.962186 -311.405518) (xy 171.913011 -311.403537) (xy 171.864792 -311.393693) (xy 171.818776 -311.376241)
			(xy 171.776155 -311.351634) (xy 171.738034 -311.320509) (xy 171.705399 -311.283672) (xy 171.679096 -311.242076)
			(xy 171.659805 -311.1968) (xy 171.648028 -311.149016) (xy 171.644068 -311.099962) (xy 171.327064 -311.099962)
			(xy 171.32656 -311.12567) (xy 171.318517 -311.176452) (xy 171.302629 -311.225351) (xy 171.279286 -311.271163)
			(xy 171.249065 -311.312759) (xy 171.212709 -311.349115) (xy 171.171113 -311.379336) (xy 171.125301 -311.402679)
			(xy 171.076402 -311.418567) (xy 171.02562 -311.42661) (xy 170.974204 -311.42661) (xy 170.923422 -311.418567)
			(xy 170.874523 -311.402679) (xy 170.828711 -311.379336) (xy 170.787115 -311.349115) (xy 170.750759 -311.312759)
			(xy 170.720538 -311.271163) (xy 170.697195 -311.225351) (xy 170.681307 -311.176452) (xy 170.673264 -311.12567)
			(xy 170.354586 -311.12567) (xy 170.34687 -311.173146) (xy 170.331286 -311.219827) (xy 170.308415 -311.263404)
			(xy 170.27885 -311.302748) (xy 170.243357 -311.33684) (xy 170.202854 -311.364796) (xy 170.158392 -311.385894)
			(xy 170.111121 -311.399586) (xy 170.062266 -311.405518) (xy 170.013091 -311.403537) (xy 169.964872 -311.393693)
			(xy 169.918856 -311.376241) (xy 169.876235 -311.351634) (xy 169.838114 -311.320509) (xy 169.805479 -311.283672)
			(xy 169.779176 -311.242076) (xy 169.759885 -311.1968) (xy 169.748108 -311.149016) (xy 169.744148 -311.099962)
			(xy 169.427144 -311.099962) (xy 169.42664 -311.12567) (xy 169.418597 -311.176452) (xy 169.402709 -311.225351)
			(xy 169.379366 -311.271163) (xy 169.349145 -311.312759) (xy 169.312789 -311.349115) (xy 169.271193 -311.379336)
			(xy 169.225381 -311.402679) (xy 169.176482 -311.418567) (xy 169.1257 -311.42661) (xy 169.074284 -311.42661)
			(xy 169.023502 -311.418567) (xy 168.974603 -311.402679) (xy 168.928791 -311.379336) (xy 168.887195 -311.349115)
			(xy 168.850839 -311.312759) (xy 168.820618 -311.271163) (xy 168.797275 -311.225351) (xy 168.781387 -311.176452)
			(xy 168.773344 -311.12567) (xy 168.454666 -311.12567) (xy 168.44695 -311.173146) (xy 168.431366 -311.219827)
			(xy 168.408495 -311.263404) (xy 168.37893 -311.302748) (xy 168.343437 -311.33684) (xy 168.302934 -311.364796)
			(xy 168.258472 -311.385894) (xy 168.211201 -311.399586) (xy 168.162346 -311.405518) (xy 168.113171 -311.403537)
			(xy 168.064952 -311.393693) (xy 168.018936 -311.376241) (xy 167.976315 -311.351634) (xy 167.938194 -311.320509)
			(xy 167.905559 -311.283672) (xy 167.879256 -311.242076) (xy 167.859965 -311.1968) (xy 167.848188 -311.149016)
			(xy 167.844228 -311.099962) (xy 167.527224 -311.099962) (xy 167.52672 -311.12567) (xy 167.518677 -311.176452)
			(xy 167.502789 -311.225351) (xy 167.479446 -311.271163) (xy 167.449225 -311.312759) (xy 167.412869 -311.349115)
			(xy 167.371273 -311.379336) (xy 167.325461 -311.402679) (xy 167.276562 -311.418567) (xy 167.22578 -311.42661)
			(xy 167.174364 -311.42661) (xy 167.123582 -311.418567) (xy 167.074683 -311.402679) (xy 167.028871 -311.379336)
			(xy 166.987275 -311.349115) (xy 166.950919 -311.312759) (xy 166.920698 -311.271163) (xy 166.897355 -311.225351)
			(xy 166.881467 -311.176452) (xy 166.873424 -311.12567) (xy 166.554492 -311.12567) (xy 166.546776 -311.173146)
			(xy 166.531192 -311.219827) (xy 166.508321 -311.263404) (xy 166.478756 -311.302748) (xy 166.443263 -311.33684)
			(xy 166.40276 -311.364796) (xy 166.358298 -311.385894) (xy 166.311027 -311.399586) (xy 166.262172 -311.405518)
			(xy 166.212997 -311.403537) (xy 166.164778 -311.393693) (xy 166.118762 -311.376241) (xy 166.076141 -311.351634)
			(xy 166.03802 -311.320509) (xy 166.005385 -311.283672) (xy 165.979082 -311.242076) (xy 165.959791 -311.1968)
			(xy 165.948014 -311.149016) (xy 165.944054 -311.099962) (xy 165.62705 -311.099962) (xy 165.626546 -311.12567)
			(xy 165.618503 -311.176452) (xy 165.602615 -311.225351) (xy 165.579272 -311.271163) (xy 165.549051 -311.312759)
			(xy 165.512695 -311.349115) (xy 165.471099 -311.379336) (xy 165.425287 -311.402679) (xy 165.376388 -311.418567)
			(xy 165.325606 -311.42661) (xy 165.27419 -311.42661) (xy 165.223408 -311.418567) (xy 165.174509 -311.402679)
			(xy 165.128697 -311.379336) (xy 165.087101 -311.349115) (xy 165.050745 -311.312759) (xy 165.020524 -311.271163)
			(xy 164.997181 -311.225351) (xy 164.981293 -311.176452) (xy 164.97325 -311.12567) (xy 164.654572 -311.12567)
			(xy 164.646856 -311.173146) (xy 164.631272 -311.219827) (xy 164.608401 -311.263404) (xy 164.578836 -311.302748)
			(xy 164.543343 -311.33684) (xy 164.50284 -311.364796) (xy 164.458378 -311.385894) (xy 164.411107 -311.399586)
			(xy 164.362252 -311.405518) (xy 164.313077 -311.403537) (xy 164.264858 -311.393693) (xy 164.218842 -311.376241)
			(xy 164.176221 -311.351634) (xy 164.1381 -311.320509) (xy 164.105465 -311.283672) (xy 164.079162 -311.242076)
			(xy 164.059871 -311.1968) (xy 164.048094 -311.149016) (xy 164.044134 -311.099962) (xy 163.72713 -311.099962)
			(xy 163.726626 -311.12567) (xy 163.718583 -311.176452) (xy 163.702695 -311.225351) (xy 163.679352 -311.271163)
			(xy 163.649131 -311.312759) (xy 163.612775 -311.349115) (xy 163.571179 -311.379336) (xy 163.525367 -311.402679)
			(xy 163.476468 -311.418567) (xy 163.425686 -311.42661) (xy 163.37427 -311.42661) (xy 163.323488 -311.418567)
			(xy 163.274589 -311.402679) (xy 163.228777 -311.379336) (xy 163.187181 -311.349115) (xy 163.150825 -311.312759)
			(xy 163.120604 -311.271163) (xy 163.097261 -311.225351) (xy 163.081373 -311.176452) (xy 163.07333 -311.12567)
			(xy 162.754652 -311.12567) (xy 162.746936 -311.173146) (xy 162.731352 -311.219827) (xy 162.708481 -311.263404)
			(xy 162.678916 -311.302748) (xy 162.643423 -311.33684) (xy 162.60292 -311.364796) (xy 162.558458 -311.385894)
			(xy 162.511187 -311.399586) (xy 162.462332 -311.405518) (xy 162.413157 -311.403537) (xy 162.364938 -311.393693)
			(xy 162.318922 -311.376241) (xy 162.276301 -311.351634) (xy 162.23818 -311.320509) (xy 162.205545 -311.283672)
			(xy 162.179242 -311.242076) (xy 162.159951 -311.1968) (xy 162.148174 -311.149016) (xy 162.144214 -311.099962)
			(xy 161.82721 -311.099962) (xy 161.826706 -311.12567) (xy 161.818663 -311.176452) (xy 161.802775 -311.225351)
			(xy 161.779432 -311.271163) (xy 161.749211 -311.312759) (xy 161.712855 -311.349115) (xy 161.671259 -311.379336)
			(xy 161.625447 -311.402679) (xy 161.576548 -311.418567) (xy 161.525766 -311.42661) (xy 161.47435 -311.42661)
			(xy 161.423568 -311.418567) (xy 161.374669 -311.402679) (xy 161.328857 -311.379336) (xy 161.287261 -311.349115)
			(xy 161.250905 -311.312759) (xy 161.220684 -311.271163) (xy 161.197341 -311.225351) (xy 161.181453 -311.176452)
			(xy 161.17341 -311.12567) (xy 160.854478 -311.12567) (xy 160.846762 -311.173146) (xy 160.831178 -311.219827)
			(xy 160.808307 -311.263404) (xy 160.778742 -311.302748) (xy 160.743249 -311.33684) (xy 160.702746 -311.364796)
			(xy 160.658284 -311.385894) (xy 160.611013 -311.399586) (xy 160.562158 -311.405518) (xy 160.512983 -311.403537)
			(xy 160.464764 -311.393693) (xy 160.418748 -311.376241) (xy 160.376127 -311.351634) (xy 160.338006 -311.320509)
			(xy 160.305371 -311.283672) (xy 160.279068 -311.242076) (xy 160.259777 -311.1968) (xy 160.248 -311.149016)
			(xy 160.24404 -311.099962) (xy 159.927036 -311.099962) (xy 159.926532 -311.12567) (xy 159.918489 -311.176452)
			(xy 159.902601 -311.225351) (xy 159.879258 -311.271163) (xy 159.849037 -311.312759) (xy 159.812681 -311.349115)
			(xy 159.771085 -311.379336) (xy 159.725273 -311.402679) (xy 159.676374 -311.418567) (xy 159.625592 -311.42661)
			(xy 159.574176 -311.42661) (xy 159.523394 -311.418567) (xy 159.474495 -311.402679) (xy 159.428683 -311.379336)
			(xy 159.387087 -311.349115) (xy 159.350731 -311.312759) (xy 159.32051 -311.271163) (xy 159.297167 -311.225351)
			(xy 159.281279 -311.176452) (xy 159.273236 -311.12567) (xy 158.954558 -311.12567) (xy 158.946842 -311.173146)
			(xy 158.931258 -311.219827) (xy 158.908387 -311.263404) (xy 158.878822 -311.302748) (xy 158.843329 -311.33684)
			(xy 158.802826 -311.364796) (xy 158.758364 -311.385894) (xy 158.711093 -311.399586) (xy 158.662238 -311.405518)
			(xy 158.613063 -311.403537) (xy 158.564844 -311.393693) (xy 158.518828 -311.376241) (xy 158.476207 -311.351634)
			(xy 158.438086 -311.320509) (xy 158.405451 -311.283672) (xy 158.379148 -311.242076) (xy 158.359857 -311.1968)
			(xy 158.34808 -311.149016) (xy 158.34412 -311.099962) (xy 158.027116 -311.099962) (xy 158.026612 -311.12567)
			(xy 158.018569 -311.176452) (xy 158.002681 -311.225351) (xy 157.979338 -311.271163) (xy 157.949117 -311.312759)
			(xy 157.912761 -311.349115) (xy 157.871165 -311.379336) (xy 157.825353 -311.402679) (xy 157.776454 -311.418567)
			(xy 157.725672 -311.42661) (xy 157.674256 -311.42661) (xy 157.623474 -311.418567) (xy 157.574575 -311.402679)
			(xy 157.528763 -311.379336) (xy 157.487167 -311.349115) (xy 157.450811 -311.312759) (xy 157.42059 -311.271163)
			(xy 157.397247 -311.225351) (xy 157.381359 -311.176452) (xy 157.373316 -311.12567) (xy 157.054638 -311.12567)
			(xy 157.046922 -311.173146) (xy 157.031338 -311.219827) (xy 157.008467 -311.263404) (xy 156.978902 -311.302748)
			(xy 156.943409 -311.33684) (xy 156.902906 -311.364796) (xy 156.858444 -311.385894) (xy 156.811173 -311.399586)
			(xy 156.762318 -311.405518) (xy 156.713143 -311.403537) (xy 156.664924 -311.393693) (xy 156.618908 -311.376241)
			(xy 156.576287 -311.351634) (xy 156.538166 -311.320509) (xy 156.505531 -311.283672) (xy 156.479228 -311.242076)
			(xy 156.459937 -311.1968) (xy 156.44816 -311.149016) (xy 156.4442 -311.099962) (xy 156.127196 -311.099962)
			(xy 156.126692 -311.12567) (xy 156.118649 -311.176452) (xy 156.102761 -311.225351) (xy 156.079418 -311.271163)
			(xy 156.049197 -311.312759) (xy 156.012841 -311.349115) (xy 155.971245 -311.379336) (xy 155.925433 -311.402679)
			(xy 155.876534 -311.418567) (xy 155.825752 -311.42661) (xy 155.774336 -311.42661) (xy 155.723554 -311.418567)
			(xy 155.674655 -311.402679) (xy 155.628843 -311.379336) (xy 155.587247 -311.349115) (xy 155.550891 -311.312759)
			(xy 155.52067 -311.271163) (xy 155.497327 -311.225351) (xy 155.481439 -311.176452) (xy 155.473396 -311.12567)
			(xy 155.154718 -311.12567) (xy 155.147002 -311.173146) (xy 155.131418 -311.219827) (xy 155.108547 -311.263404)
			(xy 155.078982 -311.302748) (xy 155.043489 -311.33684) (xy 155.002986 -311.364796) (xy 154.958524 -311.385894)
			(xy 154.911253 -311.399586) (xy 154.862398 -311.405518) (xy 154.813223 -311.403537) (xy 154.765004 -311.393693)
			(xy 154.718988 -311.376241) (xy 154.676367 -311.351634) (xy 154.638246 -311.320509) (xy 154.605611 -311.283672)
			(xy 154.579308 -311.242076) (xy 154.560017 -311.1968) (xy 154.54824 -311.149016) (xy 154.54428 -311.099962)
			(xy 154.205178 -311.099962) (xy 154.204683 -311.124569) (xy 154.196788 -311.173146) (xy 154.181204 -311.219827)
			(xy 154.158333 -311.263404) (xy 154.128768 -311.302748) (xy 154.093275 -311.33684) (xy 154.052772 -311.364796)
			(xy 154.00831 -311.385894) (xy 153.961039 -311.399586) (xy 153.912184 -311.405518) (xy 153.863009 -311.403537)
			(xy 153.81479 -311.393693) (xy 153.768774 -311.376241) (xy 153.726153 -311.351634) (xy 153.688032 -311.320509)
			(xy 153.655397 -311.283672) (xy 153.629094 -311.242076) (xy 153.609803 -311.1968) (xy 153.598026 -311.149016)
			(xy 153.594066 -311.099962) (xy 153.255218 -311.099962) (xy 153.254723 -311.124569) (xy 153.246828 -311.173146)
			(xy 153.231244 -311.219827) (xy 153.208373 -311.263404) (xy 153.178808 -311.302748) (xy 153.143315 -311.33684)
			(xy 153.102812 -311.364796) (xy 153.05835 -311.385894) (xy 153.011079 -311.399586) (xy 152.962224 -311.405518)
			(xy 152.913049 -311.403537) (xy 152.86483 -311.393693) (xy 152.818814 -311.376241) (xy 152.776193 -311.351634)
			(xy 152.738072 -311.320509) (xy 152.705437 -311.283672) (xy 152.679134 -311.242076) (xy 152.659843 -311.1968)
			(xy 152.648066 -311.149016) (xy 152.644106 -311.099962) (xy 151.126401 -311.099962) (xy 151.110637 -311.152357)
			(xy 151.086965 -311.202854) (xy 151.056192 -311.249367) (xy 151.018975 -311.290904) (xy 150.976107 -311.326579)
			(xy 150.928501 -311.355633) (xy 150.877172 -311.377445) (xy 150.823215 -311.391551) (xy 150.767778 -311.397651)
			(xy 150.712044 -311.395614) (xy 150.657201 -311.385484) (xy 150.604417 -311.367477) (xy 150.554817 -311.341976)
			(xy 150.509459 -311.309525) (xy 150.46931 -311.270816) (xy 150.435224 -311.226673) (xy 150.407928 -311.178038)
			(xy 150.388005 -311.125947) (xy 150.375879 -311.07151) (xy 150.371808 -311.015888) (xy 145.084725 -311.015888)
			(xy 145.083167 -311.019212) (xy 145.052394 -311.065725) (xy 145.015177 -311.107262) (xy 144.972309 -311.142937)
			(xy 144.924703 -311.171991) (xy 144.873374 -311.193803) (xy 144.819417 -311.207909) (xy 144.76398 -311.214009)
			(xy 144.708246 -311.211972) (xy 144.653403 -311.201842) (xy 144.600619 -311.183835) (xy 144.551019 -311.158334)
			(xy 144.505661 -311.125883) (xy 144.465512 -311.087174) (xy 144.431426 -311.043031) (xy 144.40413 -310.994396)
			(xy 144.384207 -310.942305) (xy 144.372081 -310.887868) (xy 144.36801 -310.832246) (xy 118.832884 -310.832246)
			(xy 118.832884 -311.7342) (xy 148.58949 -311.7342) (xy 148.593561 -311.678578) (xy 148.605687 -311.624141)
			(xy 148.62561 -311.57205) (xy 148.652906 -311.523415) (xy 148.686992 -311.479272) (xy 148.727141 -311.440563)
			(xy 148.772499 -311.408112) (xy 148.822099 -311.382611) (xy 148.874883 -311.364604) (xy 148.929726 -311.354474)
			(xy 148.98546 -311.352437) (xy 149.040897 -311.358537) (xy 149.094854 -311.372643) (xy 149.146183 -311.394455)
			(xy 149.193789 -311.423509) (xy 149.236657 -311.459184) (xy 149.273874 -311.500721) (xy 149.304647 -311.547234)
			(xy 149.328319 -311.597731) (xy 149.344387 -311.651138) (xy 149.352507 -311.706314) (xy 149.353016 -311.7342)
			(xy 149.352507 -311.762086) (xy 149.344387 -311.817262) (xy 149.328319 -311.870669) (xy 149.304647 -311.921166)
			(xy 149.273874 -311.967679) (xy 149.236657 -312.009216) (xy 149.193789 -312.044891) (xy 149.146183 -312.073945)
			(xy 149.094854 -312.095757) (xy 149.040897 -312.109863) (xy 148.98546 -312.115963) (xy 148.929726 -312.113926)
			(xy 148.874883 -312.103796) (xy 148.822099 -312.085789) (xy 148.772499 -312.060288) (xy 148.727141 -312.027837)
			(xy 148.686992 -311.989128) (xy 148.652906 -311.944985) (xy 148.62561 -311.89635) (xy 148.605687 -311.844259)
			(xy 148.593561 -311.789822) (xy 148.58949 -311.7342) (xy 118.832884 -311.7342) (xy 118.832884 -312.523378)
			(xy 147.832062 -312.523378) (xy 147.836133 -312.467756) (xy 147.848259 -312.413319) (xy 147.868182 -312.361228)
			(xy 147.895478 -312.312593) (xy 147.929564 -312.26845) (xy 147.969713 -312.229741) (xy 148.015071 -312.19729)
			(xy 148.064671 -312.171789) (xy 148.117455 -312.153782) (xy 148.172298 -312.143652) (xy 148.228032 -312.141615)
			(xy 148.283469 -312.147715) (xy 148.337426 -312.161821) (xy 148.388755 -312.183633) (xy 148.436361 -312.212687)
			(xy 148.479229 -312.248362) (xy 148.496921 -312.268108) (xy 150.210772 -312.268108) (xy 150.214843 -312.212486)
			(xy 150.226969 -312.158049) (xy 150.246892 -312.105958) (xy 150.274188 -312.057323) (xy 150.308274 -312.01318)
			(xy 150.348423 -311.974471) (xy 150.393781 -311.94202) (xy 150.443381 -311.916519) (xy 150.496165 -311.898512)
			(xy 150.551008 -311.888382) (xy 150.606742 -311.886345) (xy 150.662179 -311.892445) (xy 150.716136 -311.906551)
			(xy 150.767465 -311.928363) (xy 150.815071 -311.957417) (xy 150.857939 -311.993092) (xy 150.895156 -312.034629)
			(xy 150.905106 -312.049668) (xy 151.693892 -312.049668) (xy 151.697852 -312.000614) (xy 151.709629 -311.95283)
			(xy 151.72892 -311.907554) (xy 151.755223 -311.865958) (xy 151.787858 -311.829121) (xy 151.825979 -311.797996)
			(xy 151.8686 -311.773389) (xy 151.914616 -311.755937) (xy 151.962835 -311.746093) (xy 152.01201 -311.744112)
			(xy 152.060865 -311.750044) (xy 152.108136 -311.763736) (xy 152.152598 -311.784834) (xy 152.193101 -311.81279)
			(xy 152.228594 -311.846882) (xy 152.258159 -311.886226) (xy 152.28103 -311.929803) (xy 152.296614 -311.976484)
			(xy 152.304509 -312.025061) (xy 152.305004 -312.049668) (xy 152.304509 -312.074275) (xy 152.304289 -312.07563)
			(xy 152.623262 -312.07563) (xy 152.623262 -312.024214) (xy 152.631305 -311.973432) (xy 152.647193 -311.924533)
			(xy 152.670536 -311.878721) (xy 152.700757 -311.837125) (xy 152.737113 -311.800769) (xy 152.778709 -311.770548)
			(xy 152.824521 -311.747205) (xy 152.87342 -311.731317) (xy 152.924202 -311.723274) (xy 152.975618 -311.723274)
			(xy 153.0264 -311.731317) (xy 153.075299 -311.747205) (xy 153.121111 -311.770548) (xy 153.162707 -311.800769)
			(xy 153.199063 -311.837125) (xy 153.229284 -311.878721) (xy 153.252627 -311.924533) (xy 153.268515 -311.973432)
			(xy 153.276558 -312.024214) (xy 153.277062 -312.049922) (xy 153.276558 -312.07563) (xy 153.573222 -312.07563)
			(xy 153.573222 -312.024214) (xy 153.581265 -311.973432) (xy 153.597153 -311.924533) (xy 153.620496 -311.878721)
			(xy 153.650717 -311.837125) (xy 153.687073 -311.800769) (xy 153.728669 -311.770548) (xy 153.774481 -311.747205)
			(xy 153.82338 -311.731317) (xy 153.874162 -311.723274) (xy 153.925578 -311.723274) (xy 153.97636 -311.731317)
			(xy 154.025259 -311.747205) (xy 154.071071 -311.770548) (xy 154.112667 -311.800769) (xy 154.149023 -311.837125)
			(xy 154.179244 -311.878721) (xy 154.202587 -311.924533) (xy 154.218475 -311.973432) (xy 154.226518 -312.024214)
			(xy 154.227022 -312.049922) (xy 154.54428 -312.049922) (xy 154.54824 -312.000868) (xy 154.560017 -311.953084)
			(xy 154.579308 -311.907808) (xy 154.605611 -311.866212) (xy 154.638246 -311.829375) (xy 154.676367 -311.79825)
			(xy 154.718988 -311.773643) (xy 154.765004 -311.756191) (xy 154.813223 -311.746347) (xy 154.862398 -311.744366)
			(xy 154.911253 -311.750298) (xy 154.958524 -311.76399) (xy 155.002986 -311.785088) (xy 155.043489 -311.813044)
			(xy 155.078982 -311.847136) (xy 155.108547 -311.88648) (xy 155.131418 -311.930057) (xy 155.147002 -311.976738)
			(xy 155.154897 -312.025315) (xy 155.155392 -312.049922) (xy 155.154897 -312.074529) (xy 155.154718 -312.07563)
			(xy 155.473396 -312.07563) (xy 155.473396 -312.024214) (xy 155.481439 -311.973432) (xy 155.497327 -311.924533)
			(xy 155.52067 -311.878721) (xy 155.550891 -311.837125) (xy 155.587247 -311.800769) (xy 155.628843 -311.770548)
			(xy 155.674655 -311.747205) (xy 155.723554 -311.731317) (xy 155.774336 -311.723274) (xy 155.825752 -311.723274)
			(xy 155.876534 -311.731317) (xy 155.925433 -311.747205) (xy 155.971245 -311.770548) (xy 156.012841 -311.800769)
			(xy 156.049197 -311.837125) (xy 156.079418 -311.878721) (xy 156.102761 -311.924533) (xy 156.118649 -311.973432)
			(xy 156.126692 -312.024214) (xy 156.127196 -312.049922) (xy 156.4442 -312.049922) (xy 156.44816 -312.000868)
			(xy 156.459937 -311.953084) (xy 156.479228 -311.907808) (xy 156.505531 -311.866212) (xy 156.538166 -311.829375)
			(xy 156.576287 -311.79825) (xy 156.618908 -311.773643) (xy 156.664924 -311.756191) (xy 156.713143 -311.746347)
			(xy 156.762318 -311.744366) (xy 156.811173 -311.750298) (xy 156.858444 -311.76399) (xy 156.902906 -311.785088)
			(xy 156.943409 -311.813044) (xy 156.978902 -311.847136) (xy 157.008467 -311.88648) (xy 157.031338 -311.930057)
			(xy 157.046922 -311.976738) (xy 157.054817 -312.025315) (xy 157.055312 -312.049922) (xy 157.054817 -312.074529)
			(xy 157.054638 -312.07563) (xy 157.373316 -312.07563) (xy 157.373316 -312.024214) (xy 157.381359 -311.973432)
			(xy 157.397247 -311.924533) (xy 157.42059 -311.878721) (xy 157.450811 -311.837125) (xy 157.487167 -311.800769)
			(xy 157.528763 -311.770548) (xy 157.574575 -311.747205) (xy 157.623474 -311.731317) (xy 157.674256 -311.723274)
			(xy 157.725672 -311.723274) (xy 157.776454 -311.731317) (xy 157.825353 -311.747205) (xy 157.871165 -311.770548)
			(xy 157.912761 -311.800769) (xy 157.949117 -311.837125) (xy 157.979338 -311.878721) (xy 158.002681 -311.924533)
			(xy 158.018569 -311.973432) (xy 158.026612 -312.024214) (xy 158.027116 -312.049922) (xy 158.34412 -312.049922)
			(xy 158.34808 -312.000868) (xy 158.359857 -311.953084) (xy 158.379148 -311.907808) (xy 158.405451 -311.866212)
			(xy 158.438086 -311.829375) (xy 158.476207 -311.79825) (xy 158.518828 -311.773643) (xy 158.564844 -311.756191)
			(xy 158.613063 -311.746347) (xy 158.662238 -311.744366) (xy 158.711093 -311.750298) (xy 158.758364 -311.76399)
			(xy 158.802826 -311.785088) (xy 158.843329 -311.813044) (xy 158.878822 -311.847136) (xy 158.908387 -311.88648)
			(xy 158.931258 -311.930057) (xy 158.946842 -311.976738) (xy 158.954737 -312.025315) (xy 158.955232 -312.049922)
			(xy 158.954737 -312.074529) (xy 158.954558 -312.07563) (xy 159.273236 -312.07563) (xy 159.273236 -312.024214)
			(xy 159.281279 -311.973432) (xy 159.297167 -311.924533) (xy 159.32051 -311.878721) (xy 159.350731 -311.837125)
			(xy 159.387087 -311.800769) (xy 159.428683 -311.770548) (xy 159.474495 -311.747205) (xy 159.523394 -311.731317)
			(xy 159.574176 -311.723274) (xy 159.625592 -311.723274) (xy 159.676374 -311.731317) (xy 159.725273 -311.747205)
			(xy 159.771085 -311.770548) (xy 159.812681 -311.800769) (xy 159.849037 -311.837125) (xy 159.879258 -311.878721)
			(xy 159.902601 -311.924533) (xy 159.918489 -311.973432) (xy 159.926532 -312.024214) (xy 159.927036 -312.049922)
			(xy 160.24404 -312.049922) (xy 160.248 -312.000868) (xy 160.259777 -311.953084) (xy 160.279068 -311.907808)
			(xy 160.305371 -311.866212) (xy 160.338006 -311.829375) (xy 160.376127 -311.79825) (xy 160.418748 -311.773643)
			(xy 160.464764 -311.756191) (xy 160.512983 -311.746347) (xy 160.562158 -311.744366) (xy 160.611013 -311.750298)
			(xy 160.658284 -311.76399) (xy 160.702746 -311.785088) (xy 160.743249 -311.813044) (xy 160.778742 -311.847136)
			(xy 160.808307 -311.88648) (xy 160.831178 -311.930057) (xy 160.846762 -311.976738) (xy 160.854657 -312.025315)
			(xy 160.855152 -312.049922) (xy 160.854657 -312.074529) (xy 160.854478 -312.07563) (xy 161.17341 -312.07563)
			(xy 161.17341 -312.024214) (xy 161.181453 -311.973432) (xy 161.197341 -311.924533) (xy 161.220684 -311.878721)
			(xy 161.250905 -311.837125) (xy 161.287261 -311.800769) (xy 161.328857 -311.770548) (xy 161.374669 -311.747205)
			(xy 161.423568 -311.731317) (xy 161.47435 -311.723274) (xy 161.525766 -311.723274) (xy 161.576548 -311.731317)
			(xy 161.625447 -311.747205) (xy 161.671259 -311.770548) (xy 161.712855 -311.800769) (xy 161.749211 -311.837125)
			(xy 161.779432 -311.878721) (xy 161.802775 -311.924533) (xy 161.818663 -311.973432) (xy 161.826706 -312.024214)
			(xy 161.82721 -312.049922) (xy 162.144214 -312.049922) (xy 162.148174 -312.000868) (xy 162.159951 -311.953084)
			(xy 162.179242 -311.907808) (xy 162.205545 -311.866212) (xy 162.23818 -311.829375) (xy 162.276301 -311.79825)
			(xy 162.318922 -311.773643) (xy 162.364938 -311.756191) (xy 162.413157 -311.746347) (xy 162.462332 -311.744366)
			(xy 162.511187 -311.750298) (xy 162.558458 -311.76399) (xy 162.60292 -311.785088) (xy 162.643423 -311.813044)
			(xy 162.678916 -311.847136) (xy 162.708481 -311.88648) (xy 162.731352 -311.930057) (xy 162.746936 -311.976738)
			(xy 162.754831 -312.025315) (xy 162.755326 -312.049922) (xy 162.754831 -312.074529) (xy 162.754652 -312.07563)
			(xy 163.07333 -312.07563) (xy 163.07333 -312.024214) (xy 163.081373 -311.973432) (xy 163.097261 -311.924533)
			(xy 163.120604 -311.878721) (xy 163.150825 -311.837125) (xy 163.187181 -311.800769) (xy 163.228777 -311.770548)
			(xy 163.274589 -311.747205) (xy 163.323488 -311.731317) (xy 163.37427 -311.723274) (xy 163.425686 -311.723274)
			(xy 163.476468 -311.731317) (xy 163.525367 -311.747205) (xy 163.571179 -311.770548) (xy 163.612775 -311.800769)
			(xy 163.649131 -311.837125) (xy 163.679352 -311.878721) (xy 163.702695 -311.924533) (xy 163.718583 -311.973432)
			(xy 163.726626 -312.024214) (xy 163.72713 -312.049922) (xy 164.044134 -312.049922) (xy 164.048094 -312.000868)
			(xy 164.059871 -311.953084) (xy 164.079162 -311.907808) (xy 164.105465 -311.866212) (xy 164.1381 -311.829375)
			(xy 164.176221 -311.79825) (xy 164.218842 -311.773643) (xy 164.264858 -311.756191) (xy 164.313077 -311.746347)
			(xy 164.362252 -311.744366) (xy 164.411107 -311.750298) (xy 164.458378 -311.76399) (xy 164.50284 -311.785088)
			(xy 164.543343 -311.813044) (xy 164.578836 -311.847136) (xy 164.608401 -311.88648) (xy 164.631272 -311.930057)
			(xy 164.646856 -311.976738) (xy 164.654751 -312.025315) (xy 164.655246 -312.049922) (xy 164.654751 -312.074529)
			(xy 164.654572 -312.07563) (xy 164.97325 -312.07563) (xy 164.97325 -312.024214) (xy 164.981293 -311.973432)
			(xy 164.997181 -311.924533) (xy 165.020524 -311.878721) (xy 165.050745 -311.837125) (xy 165.087101 -311.800769)
			(xy 165.128697 -311.770548) (xy 165.174509 -311.747205) (xy 165.223408 -311.731317) (xy 165.27419 -311.723274)
			(xy 165.325606 -311.723274) (xy 165.376388 -311.731317) (xy 165.425287 -311.747205) (xy 165.471099 -311.770548)
			(xy 165.512695 -311.800769) (xy 165.549051 -311.837125) (xy 165.579272 -311.878721) (xy 165.602615 -311.924533)
			(xy 165.618503 -311.973432) (xy 165.626546 -312.024214) (xy 165.62705 -312.049922) (xy 165.944054 -312.049922)
			(xy 165.948014 -312.000868) (xy 165.959791 -311.953084) (xy 165.979082 -311.907808) (xy 166.005385 -311.866212)
			(xy 166.03802 -311.829375) (xy 166.076141 -311.79825) (xy 166.118762 -311.773643) (xy 166.164778 -311.756191)
			(xy 166.212997 -311.746347) (xy 166.262172 -311.744366) (xy 166.311027 -311.750298) (xy 166.358298 -311.76399)
			(xy 166.40276 -311.785088) (xy 166.443263 -311.813044) (xy 166.478756 -311.847136) (xy 166.508321 -311.88648)
			(xy 166.531192 -311.930057) (xy 166.546776 -311.976738) (xy 166.554671 -312.025315) (xy 166.555166 -312.049922)
			(xy 166.554671 -312.074529) (xy 166.554492 -312.07563) (xy 166.873424 -312.07563) (xy 166.873424 -312.024214)
			(xy 166.881467 -311.973432) (xy 166.897355 -311.924533) (xy 166.920698 -311.878721) (xy 166.950919 -311.837125)
			(xy 166.987275 -311.800769) (xy 167.028871 -311.770548) (xy 167.074683 -311.747205) (xy 167.123582 -311.731317)
			(xy 167.174364 -311.723274) (xy 167.22578 -311.723274) (xy 167.276562 -311.731317) (xy 167.325461 -311.747205)
			(xy 167.371273 -311.770548) (xy 167.412869 -311.800769) (xy 167.449225 -311.837125) (xy 167.479446 -311.878721)
			(xy 167.502789 -311.924533) (xy 167.518677 -311.973432) (xy 167.52672 -312.024214) (xy 167.527224 -312.049922)
			(xy 167.844228 -312.049922) (xy 167.848188 -312.000868) (xy 167.859965 -311.953084) (xy 167.879256 -311.907808)
			(xy 167.905559 -311.866212) (xy 167.938194 -311.829375) (xy 167.976315 -311.79825) (xy 168.018936 -311.773643)
			(xy 168.064952 -311.756191) (xy 168.113171 -311.746347) (xy 168.162346 -311.744366) (xy 168.211201 -311.750298)
			(xy 168.258472 -311.76399) (xy 168.302934 -311.785088) (xy 168.343437 -311.813044) (xy 168.37893 -311.847136)
			(xy 168.408495 -311.88648) (xy 168.431366 -311.930057) (xy 168.44695 -311.976738) (xy 168.454845 -312.025315)
			(xy 168.45534 -312.049922) (xy 168.454845 -312.074529) (xy 168.454666 -312.07563) (xy 168.773344 -312.07563)
			(xy 168.773344 -312.024214) (xy 168.781387 -311.973432) (xy 168.797275 -311.924533) (xy 168.820618 -311.878721)
			(xy 168.850839 -311.837125) (xy 168.887195 -311.800769) (xy 168.928791 -311.770548) (xy 168.974603 -311.747205)
			(xy 169.023502 -311.731317) (xy 169.074284 -311.723274) (xy 169.1257 -311.723274) (xy 169.176482 -311.731317)
			(xy 169.225381 -311.747205) (xy 169.271193 -311.770548) (xy 169.312789 -311.800769) (xy 169.349145 -311.837125)
			(xy 169.379366 -311.878721) (xy 169.402709 -311.924533) (xy 169.418597 -311.973432) (xy 169.42664 -312.024214)
			(xy 169.427144 -312.049922) (xy 169.744148 -312.049922) (xy 169.748108 -312.000868) (xy 169.759885 -311.953084)
			(xy 169.779176 -311.907808) (xy 169.805479 -311.866212) (xy 169.838114 -311.829375) (xy 169.876235 -311.79825)
			(xy 169.918856 -311.773643) (xy 169.964872 -311.756191) (xy 170.013091 -311.746347) (xy 170.062266 -311.744366)
			(xy 170.111121 -311.750298) (xy 170.158392 -311.76399) (xy 170.202854 -311.785088) (xy 170.243357 -311.813044)
			(xy 170.27885 -311.847136) (xy 170.308415 -311.88648) (xy 170.331286 -311.930057) (xy 170.34687 -311.976738)
			(xy 170.354765 -312.025315) (xy 170.35526 -312.049922) (xy 170.354765 -312.074529) (xy 170.354586 -312.07563)
			(xy 170.673264 -312.07563) (xy 170.673264 -312.024214) (xy 170.681307 -311.973432) (xy 170.697195 -311.924533)
			(xy 170.720538 -311.878721) (xy 170.750759 -311.837125) (xy 170.787115 -311.800769) (xy 170.828711 -311.770548)
			(xy 170.874523 -311.747205) (xy 170.923422 -311.731317) (xy 170.974204 -311.723274) (xy 171.02562 -311.723274)
			(xy 171.076402 -311.731317) (xy 171.125301 -311.747205) (xy 171.171113 -311.770548) (xy 171.212709 -311.800769)
			(xy 171.249065 -311.837125) (xy 171.279286 -311.878721) (xy 171.302629 -311.924533) (xy 171.318517 -311.973432)
			(xy 171.32656 -312.024214) (xy 171.327064 -312.049922) (xy 171.644068 -312.049922) (xy 171.648028 -312.000868)
			(xy 171.659805 -311.953084) (xy 171.679096 -311.907808) (xy 171.705399 -311.866212) (xy 171.738034 -311.829375)
			(xy 171.776155 -311.79825) (xy 171.818776 -311.773643) (xy 171.864792 -311.756191) (xy 171.913011 -311.746347)
			(xy 171.962186 -311.744366) (xy 172.011041 -311.750298) (xy 172.058312 -311.76399) (xy 172.102774 -311.785088)
			(xy 172.143277 -311.813044) (xy 172.17877 -311.847136) (xy 172.208335 -311.88648) (xy 172.231206 -311.930057)
			(xy 172.24679 -311.976738) (xy 172.254685 -312.025315) (xy 172.25518 -312.049922) (xy 172.254685 -312.074529)
			(xy 172.254506 -312.07563) (xy 172.573438 -312.07563) (xy 172.573438 -312.024214) (xy 172.581481 -311.973432)
			(xy 172.597369 -311.924533) (xy 172.620712 -311.878721) (xy 172.650933 -311.837125) (xy 172.687289 -311.800769)
			(xy 172.728885 -311.770548) (xy 172.774697 -311.747205) (xy 172.823596 -311.731317) (xy 172.874378 -311.723274)
			(xy 172.925794 -311.723274) (xy 172.976576 -311.731317) (xy 173.025475 -311.747205) (xy 173.071287 -311.770548)
			(xy 173.112883 -311.800769) (xy 173.149239 -311.837125) (xy 173.17946 -311.878721) (xy 173.202803 -311.924533)
			(xy 173.218691 -311.973432) (xy 173.226734 -312.024214) (xy 173.227238 -312.049922) (xy 173.544242 -312.049922)
			(xy 173.548202 -312.000868) (xy 173.559979 -311.953084) (xy 173.57927 -311.907808) (xy 173.605573 -311.866212)
			(xy 173.638208 -311.829375) (xy 173.676329 -311.79825) (xy 173.71895 -311.773643) (xy 173.764966 -311.756191)
			(xy 173.813185 -311.746347) (xy 173.86236 -311.744366) (xy 173.911215 -311.750298) (xy 173.958486 -311.76399)
			(xy 174.002948 -311.785088) (xy 174.043451 -311.813044) (xy 174.078944 -311.847136) (xy 174.108509 -311.88648)
			(xy 174.13138 -311.930057) (xy 174.146964 -311.976738) (xy 174.154859 -312.025315) (xy 174.155354 -312.049922)
			(xy 174.154859 -312.074529) (xy 174.15468 -312.07563) (xy 174.473358 -312.07563) (xy 174.473358 -312.024214)
			(xy 174.481401 -311.973432) (xy 174.497289 -311.924533) (xy 174.520632 -311.878721) (xy 174.550853 -311.837125)
			(xy 174.587209 -311.800769) (xy 174.628805 -311.770548) (xy 174.674617 -311.747205) (xy 174.723516 -311.731317)
			(xy 174.774298 -311.723274) (xy 174.825714 -311.723274) (xy 174.876496 -311.731317) (xy 174.925395 -311.747205)
			(xy 174.971207 -311.770548) (xy 175.012803 -311.800769) (xy 175.049159 -311.837125) (xy 175.07938 -311.878721)
			(xy 175.102723 -311.924533) (xy 175.118611 -311.973432) (xy 175.126654 -312.024214) (xy 175.127158 -312.049922)
			(xy 175.444162 -312.049922) (xy 175.448122 -312.000868) (xy 175.459899 -311.953084) (xy 175.47919 -311.907808)
			(xy 175.505493 -311.866212) (xy 175.538128 -311.829375) (xy 175.576249 -311.79825) (xy 175.61887 -311.773643)
			(xy 175.664886 -311.756191) (xy 175.713105 -311.746347) (xy 175.76228 -311.744366) (xy 175.811135 -311.750298)
			(xy 175.858406 -311.76399) (xy 175.902868 -311.785088) (xy 175.943371 -311.813044) (xy 175.978864 -311.847136)
			(xy 176.008429 -311.88648) (xy 176.0313 -311.930057) (xy 176.046884 -311.976738) (xy 176.054779 -312.025315)
			(xy 176.055274 -312.049922) (xy 176.054779 -312.074529) (xy 176.0546 -312.07563) (xy 176.373278 -312.07563)
			(xy 176.373278 -312.024214) (xy 176.381321 -311.973432) (xy 176.397209 -311.924533) (xy 176.420552 -311.878721)
			(xy 176.450773 -311.837125) (xy 176.487129 -311.800769) (xy 176.528725 -311.770548) (xy 176.574537 -311.747205)
			(xy 176.623436 -311.731317) (xy 176.674218 -311.723274) (xy 176.725634 -311.723274) (xy 176.776416 -311.731317)
			(xy 176.825315 -311.747205) (xy 176.871127 -311.770548) (xy 176.912723 -311.800769) (xy 176.949079 -311.837125)
			(xy 176.9793 -311.878721) (xy 177.002643 -311.924533) (xy 177.018531 -311.973432) (xy 177.026574 -312.024214)
			(xy 177.027078 -312.049922) (xy 177.344082 -312.049922) (xy 177.348042 -312.000868) (xy 177.359819 -311.953084)
			(xy 177.37911 -311.907808) (xy 177.405413 -311.866212) (xy 177.438048 -311.829375) (xy 177.476169 -311.79825)
			(xy 177.51879 -311.773643) (xy 177.564806 -311.756191) (xy 177.613025 -311.746347) (xy 177.6622 -311.744366)
			(xy 177.711055 -311.750298) (xy 177.758326 -311.76399) (xy 177.802788 -311.785088) (xy 177.843291 -311.813044)
			(xy 177.878784 -311.847136) (xy 177.908349 -311.88648) (xy 177.93122 -311.930057) (xy 177.946804 -311.976738)
			(xy 177.954699 -312.025315) (xy 177.955194 -312.049922) (xy 177.954699 -312.074529) (xy 177.95452 -312.07563)
			(xy 178.273198 -312.07563) (xy 178.273198 -312.024214) (xy 178.281241 -311.973432) (xy 178.297129 -311.924533)
			(xy 178.320472 -311.878721) (xy 178.350693 -311.837125) (xy 178.387049 -311.800769) (xy 178.428645 -311.770548)
			(xy 178.474457 -311.747205) (xy 178.523356 -311.731317) (xy 178.574138 -311.723274) (xy 178.625554 -311.723274)
			(xy 178.676336 -311.731317) (xy 178.725235 -311.747205) (xy 178.771047 -311.770548) (xy 178.812643 -311.800769)
			(xy 178.848999 -311.837125) (xy 178.87922 -311.878721) (xy 178.902563 -311.924533) (xy 178.918451 -311.973432)
			(xy 178.926494 -312.024214) (xy 178.926998 -312.049922) (xy 179.244256 -312.049922) (xy 179.248216 -312.000868)
			(xy 179.259993 -311.953084) (xy 179.279284 -311.907808) (xy 179.305587 -311.866212) (xy 179.338222 -311.829375)
			(xy 179.376343 -311.79825) (xy 179.418964 -311.773643) (xy 179.46498 -311.756191) (xy 179.513199 -311.746347)
			(xy 179.562374 -311.744366) (xy 179.611229 -311.750298) (xy 179.6585 -311.76399) (xy 179.702962 -311.785088)
			(xy 179.743465 -311.813044) (xy 179.778958 -311.847136) (xy 179.808523 -311.88648) (xy 179.831394 -311.930057)
			(xy 179.846978 -311.976738) (xy 179.854873 -312.025315) (xy 179.855368 -312.049922) (xy 179.854873 -312.074529)
			(xy 179.854694 -312.07563) (xy 180.173372 -312.07563) (xy 180.173372 -312.024214) (xy 180.181415 -311.973432)
			(xy 180.197303 -311.924533) (xy 180.220646 -311.878721) (xy 180.250867 -311.837125) (xy 180.287223 -311.800769)
			(xy 180.328819 -311.770548) (xy 180.374631 -311.747205) (xy 180.42353 -311.731317) (xy 180.474312 -311.723274)
			(xy 180.525728 -311.723274) (xy 180.57651 -311.731317) (xy 180.625409 -311.747205) (xy 180.671221 -311.770548)
			(xy 180.712817 -311.800769) (xy 180.749173 -311.837125) (xy 180.779394 -311.878721) (xy 180.802737 -311.924533)
			(xy 180.818625 -311.973432) (xy 180.826668 -312.024214) (xy 180.827172 -312.049922) (xy 181.144176 -312.049922)
			(xy 181.148136 -312.000868) (xy 181.159913 -311.953084) (xy 181.179204 -311.907808) (xy 181.205507 -311.866212)
			(xy 181.238142 -311.829375) (xy 181.276263 -311.79825) (xy 181.318884 -311.773643) (xy 181.3649 -311.756191)
			(xy 181.413119 -311.746347) (xy 181.462294 -311.744366) (xy 181.511149 -311.750298) (xy 181.55842 -311.76399)
			(xy 181.602882 -311.785088) (xy 181.643385 -311.813044) (xy 181.678878 -311.847136) (xy 181.708443 -311.88648)
			(xy 181.731314 -311.930057) (xy 181.746898 -311.976738) (xy 181.754793 -312.025315) (xy 181.755288 -312.049922)
			(xy 181.754793 -312.074529) (xy 181.754614 -312.07563) (xy 182.073292 -312.07563) (xy 182.073292 -312.024214)
			(xy 182.081335 -311.973432) (xy 182.097223 -311.924533) (xy 182.120566 -311.878721) (xy 182.150787 -311.837125)
			(xy 182.187143 -311.800769) (xy 182.228739 -311.770548) (xy 182.274551 -311.747205) (xy 182.32345 -311.731317)
			(xy 182.374232 -311.723274) (xy 182.425648 -311.723274) (xy 182.47643 -311.731317) (xy 182.525329 -311.747205)
			(xy 182.571141 -311.770548) (xy 182.612737 -311.800769) (xy 182.649093 -311.837125) (xy 182.679314 -311.878721)
			(xy 182.702657 -311.924533) (xy 182.718545 -311.973432) (xy 182.726588 -312.024214) (xy 182.727092 -312.049922)
			(xy 183.044096 -312.049922) (xy 183.048056 -312.000868) (xy 183.059833 -311.953084) (xy 183.079124 -311.907808)
			(xy 183.105427 -311.866212) (xy 183.138062 -311.829375) (xy 183.176183 -311.79825) (xy 183.218804 -311.773643)
			(xy 183.26482 -311.756191) (xy 183.313039 -311.746347) (xy 183.362214 -311.744366) (xy 183.411069 -311.750298)
			(xy 183.45834 -311.76399) (xy 183.502802 -311.785088) (xy 183.543305 -311.813044) (xy 183.578798 -311.847136)
			(xy 183.608363 -311.88648) (xy 183.631234 -311.930057) (xy 183.646818 -311.976738) (xy 183.654713 -312.025315)
			(xy 183.655208 -312.049922) (xy 183.654713 -312.074529) (xy 183.654534 -312.07563) (xy 183.973212 -312.07563)
			(xy 183.973212 -312.024214) (xy 183.981255 -311.973432) (xy 183.997143 -311.924533) (xy 184.020486 -311.878721)
			(xy 184.050707 -311.837125) (xy 184.087063 -311.800769) (xy 184.128659 -311.770548) (xy 184.174471 -311.747205)
			(xy 184.22337 -311.731317) (xy 184.274152 -311.723274) (xy 184.325568 -311.723274) (xy 184.37635 -311.731317)
			(xy 184.425249 -311.747205) (xy 184.471061 -311.770548) (xy 184.512657 -311.800769) (xy 184.549013 -311.837125)
			(xy 184.579234 -311.878721) (xy 184.602577 -311.924533) (xy 184.618465 -311.973432) (xy 184.626508 -312.024214)
			(xy 184.627012 -312.049922) (xy 184.626508 -312.07563) (xy 184.618465 -312.126412) (xy 184.602577 -312.175311)
			(xy 184.579234 -312.221123) (xy 184.549013 -312.262719) (xy 184.512657 -312.299075) (xy 184.471061 -312.329296)
			(xy 184.425249 -312.352639) (xy 184.37635 -312.368527) (xy 184.325568 -312.37657) (xy 184.274152 -312.37657)
			(xy 184.22337 -312.368527) (xy 184.174471 -312.352639) (xy 184.128659 -312.329296) (xy 184.087063 -312.299075)
			(xy 184.050707 -312.262719) (xy 184.020486 -312.221123) (xy 183.997143 -312.175311) (xy 183.981255 -312.126412)
			(xy 183.973212 -312.07563) (xy 183.654534 -312.07563) (xy 183.646818 -312.123106) (xy 183.631234 -312.169787)
			(xy 183.608363 -312.213364) (xy 183.578798 -312.252708) (xy 183.543305 -312.2868) (xy 183.502802 -312.314756)
			(xy 183.45834 -312.335854) (xy 183.411069 -312.349546) (xy 183.362214 -312.355478) (xy 183.313039 -312.353497)
			(xy 183.26482 -312.343653) (xy 183.218804 -312.326201) (xy 183.176183 -312.301594) (xy 183.138062 -312.270469)
			(xy 183.105427 -312.233632) (xy 183.079124 -312.192036) (xy 183.059833 -312.14676) (xy 183.048056 -312.098976)
			(xy 183.044096 -312.049922) (xy 182.727092 -312.049922) (xy 182.726588 -312.07563) (xy 182.718545 -312.126412)
			(xy 182.702657 -312.175311) (xy 182.679314 -312.221123) (xy 182.649093 -312.262719) (xy 182.612737 -312.299075)
			(xy 182.571141 -312.329296) (xy 182.525329 -312.352639) (xy 182.47643 -312.368527) (xy 182.425648 -312.37657)
			(xy 182.374232 -312.37657) (xy 182.32345 -312.368527) (xy 182.274551 -312.352639) (xy 182.228739 -312.329296)
			(xy 182.187143 -312.299075) (xy 182.150787 -312.262719) (xy 182.120566 -312.221123) (xy 182.097223 -312.175311)
			(xy 182.081335 -312.126412) (xy 182.073292 -312.07563) (xy 181.754614 -312.07563) (xy 181.746898 -312.123106)
			(xy 181.731314 -312.169787) (xy 181.708443 -312.213364) (xy 181.678878 -312.252708) (xy 181.643385 -312.2868)
			(xy 181.602882 -312.314756) (xy 181.55842 -312.335854) (xy 181.511149 -312.349546) (xy 181.462294 -312.355478)
			(xy 181.413119 -312.353497) (xy 181.3649 -312.343653) (xy 181.318884 -312.326201) (xy 181.276263 -312.301594)
			(xy 181.238142 -312.270469) (xy 181.205507 -312.233632) (xy 181.179204 -312.192036) (xy 181.159913 -312.14676)
			(xy 181.148136 -312.098976) (xy 181.144176 -312.049922) (xy 180.827172 -312.049922) (xy 180.826668 -312.07563)
			(xy 180.818625 -312.126412) (xy 180.802737 -312.175311) (xy 180.779394 -312.221123) (xy 180.749173 -312.262719)
			(xy 180.712817 -312.299075) (xy 180.671221 -312.329296) (xy 180.625409 -312.352639) (xy 180.57651 -312.368527)
			(xy 180.525728 -312.37657) (xy 180.474312 -312.37657) (xy 180.42353 -312.368527) (xy 180.374631 -312.352639)
			(xy 180.328819 -312.329296) (xy 180.287223 -312.299075) (xy 180.250867 -312.262719) (xy 180.220646 -312.221123)
			(xy 180.197303 -312.175311) (xy 180.181415 -312.126412) (xy 180.173372 -312.07563) (xy 179.854694 -312.07563)
			(xy 179.846978 -312.123106) (xy 179.831394 -312.169787) (xy 179.808523 -312.213364) (xy 179.778958 -312.252708)
			(xy 179.743465 -312.2868) (xy 179.702962 -312.314756) (xy 179.6585 -312.335854) (xy 179.611229 -312.349546)
			(xy 179.562374 -312.355478) (xy 179.513199 -312.353497) (xy 179.46498 -312.343653) (xy 179.418964 -312.326201)
			(xy 179.376343 -312.301594) (xy 179.338222 -312.270469) (xy 179.305587 -312.233632) (xy 179.279284 -312.192036)
			(xy 179.259993 -312.14676) (xy 179.248216 -312.098976) (xy 179.244256 -312.049922) (xy 178.926998 -312.049922)
			(xy 178.926494 -312.07563) (xy 178.918451 -312.126412) (xy 178.902563 -312.175311) (xy 178.87922 -312.221123)
			(xy 178.848999 -312.262719) (xy 178.812643 -312.299075) (xy 178.771047 -312.329296) (xy 178.725235 -312.352639)
			(xy 178.676336 -312.368527) (xy 178.625554 -312.37657) (xy 178.574138 -312.37657) (xy 178.523356 -312.368527)
			(xy 178.474457 -312.352639) (xy 178.428645 -312.329296) (xy 178.387049 -312.299075) (xy 178.350693 -312.262719)
			(xy 178.320472 -312.221123) (xy 178.297129 -312.175311) (xy 178.281241 -312.126412) (xy 178.273198 -312.07563)
			(xy 177.95452 -312.07563) (xy 177.946804 -312.123106) (xy 177.93122 -312.169787) (xy 177.908349 -312.213364)
			(xy 177.878784 -312.252708) (xy 177.843291 -312.2868) (xy 177.802788 -312.314756) (xy 177.758326 -312.335854)
			(xy 177.711055 -312.349546) (xy 177.6622 -312.355478) (xy 177.613025 -312.353497) (xy 177.564806 -312.343653)
			(xy 177.51879 -312.326201) (xy 177.476169 -312.301594) (xy 177.438048 -312.270469) (xy 177.405413 -312.233632)
			(xy 177.37911 -312.192036) (xy 177.359819 -312.14676) (xy 177.348042 -312.098976) (xy 177.344082 -312.049922)
			(xy 177.027078 -312.049922) (xy 177.026574 -312.07563) (xy 177.018531 -312.126412) (xy 177.002643 -312.175311)
			(xy 176.9793 -312.221123) (xy 176.949079 -312.262719) (xy 176.912723 -312.299075) (xy 176.871127 -312.329296)
			(xy 176.825315 -312.352639) (xy 176.776416 -312.368527) (xy 176.725634 -312.37657) (xy 176.674218 -312.37657)
			(xy 176.623436 -312.368527) (xy 176.574537 -312.352639) (xy 176.528725 -312.329296) (xy 176.487129 -312.299075)
			(xy 176.450773 -312.262719) (xy 176.420552 -312.221123) (xy 176.397209 -312.175311) (xy 176.381321 -312.126412)
			(xy 176.373278 -312.07563) (xy 176.0546 -312.07563) (xy 176.046884 -312.123106) (xy 176.0313 -312.169787)
			(xy 176.008429 -312.213364) (xy 175.978864 -312.252708) (xy 175.943371 -312.2868) (xy 175.902868 -312.314756)
			(xy 175.858406 -312.335854) (xy 175.811135 -312.349546) (xy 175.76228 -312.355478) (xy 175.713105 -312.353497)
			(xy 175.664886 -312.343653) (xy 175.61887 -312.326201) (xy 175.576249 -312.301594) (xy 175.538128 -312.270469)
			(xy 175.505493 -312.233632) (xy 175.47919 -312.192036) (xy 175.459899 -312.14676) (xy 175.448122 -312.098976)
			(xy 175.444162 -312.049922) (xy 175.127158 -312.049922) (xy 175.126654 -312.07563) (xy 175.118611 -312.126412)
			(xy 175.102723 -312.175311) (xy 175.07938 -312.221123) (xy 175.049159 -312.262719) (xy 175.012803 -312.299075)
			(xy 174.971207 -312.329296) (xy 174.925395 -312.352639) (xy 174.876496 -312.368527) (xy 174.825714 -312.37657)
			(xy 174.774298 -312.37657) (xy 174.723516 -312.368527) (xy 174.674617 -312.352639) (xy 174.628805 -312.329296)
			(xy 174.587209 -312.299075) (xy 174.550853 -312.262719) (xy 174.520632 -312.221123) (xy 174.497289 -312.175311)
			(xy 174.481401 -312.126412) (xy 174.473358 -312.07563) (xy 174.15468 -312.07563) (xy 174.146964 -312.123106)
			(xy 174.13138 -312.169787) (xy 174.108509 -312.213364) (xy 174.078944 -312.252708) (xy 174.043451 -312.2868)
			(xy 174.002948 -312.314756) (xy 173.958486 -312.335854) (xy 173.911215 -312.349546) (xy 173.86236 -312.355478)
			(xy 173.813185 -312.353497) (xy 173.764966 -312.343653) (xy 173.71895 -312.326201) (xy 173.676329 -312.301594)
			(xy 173.638208 -312.270469) (xy 173.605573 -312.233632) (xy 173.57927 -312.192036) (xy 173.559979 -312.14676)
			(xy 173.548202 -312.098976) (xy 173.544242 -312.049922) (xy 173.227238 -312.049922) (xy 173.226734 -312.07563)
			(xy 173.218691 -312.126412) (xy 173.202803 -312.175311) (xy 173.17946 -312.221123) (xy 173.149239 -312.262719)
			(xy 173.112883 -312.299075) (xy 173.071287 -312.329296) (xy 173.025475 -312.352639) (xy 172.976576 -312.368527)
			(xy 172.925794 -312.37657) (xy 172.874378 -312.37657) (xy 172.823596 -312.368527) (xy 172.774697 -312.352639)
			(xy 172.728885 -312.329296) (xy 172.687289 -312.299075) (xy 172.650933 -312.262719) (xy 172.620712 -312.221123)
			(xy 172.597369 -312.175311) (xy 172.581481 -312.126412) (xy 172.573438 -312.07563) (xy 172.254506 -312.07563)
			(xy 172.24679 -312.123106) (xy 172.231206 -312.169787) (xy 172.208335 -312.213364) (xy 172.17877 -312.252708)
			(xy 172.143277 -312.2868) (xy 172.102774 -312.314756) (xy 172.058312 -312.335854) (xy 172.011041 -312.349546)
			(xy 171.962186 -312.355478) (xy 171.913011 -312.353497) (xy 171.864792 -312.343653) (xy 171.818776 -312.326201)
			(xy 171.776155 -312.301594) (xy 171.738034 -312.270469) (xy 171.705399 -312.233632) (xy 171.679096 -312.192036)
			(xy 171.659805 -312.14676) (xy 171.648028 -312.098976) (xy 171.644068 -312.049922) (xy 171.327064 -312.049922)
			(xy 171.32656 -312.07563) (xy 171.318517 -312.126412) (xy 171.302629 -312.175311) (xy 171.279286 -312.221123)
			(xy 171.249065 -312.262719) (xy 171.212709 -312.299075) (xy 171.171113 -312.329296) (xy 171.125301 -312.352639)
			(xy 171.076402 -312.368527) (xy 171.02562 -312.37657) (xy 170.974204 -312.37657) (xy 170.923422 -312.368527)
			(xy 170.874523 -312.352639) (xy 170.828711 -312.329296) (xy 170.787115 -312.299075) (xy 170.750759 -312.262719)
			(xy 170.720538 -312.221123) (xy 170.697195 -312.175311) (xy 170.681307 -312.126412) (xy 170.673264 -312.07563)
			(xy 170.354586 -312.07563) (xy 170.34687 -312.123106) (xy 170.331286 -312.169787) (xy 170.308415 -312.213364)
			(xy 170.27885 -312.252708) (xy 170.243357 -312.2868) (xy 170.202854 -312.314756) (xy 170.158392 -312.335854)
			(xy 170.111121 -312.349546) (xy 170.062266 -312.355478) (xy 170.013091 -312.353497) (xy 169.964872 -312.343653)
			(xy 169.918856 -312.326201) (xy 169.876235 -312.301594) (xy 169.838114 -312.270469) (xy 169.805479 -312.233632)
			(xy 169.779176 -312.192036) (xy 169.759885 -312.14676) (xy 169.748108 -312.098976) (xy 169.744148 -312.049922)
			(xy 169.427144 -312.049922) (xy 169.42664 -312.07563) (xy 169.418597 -312.126412) (xy 169.402709 -312.175311)
			(xy 169.379366 -312.221123) (xy 169.349145 -312.262719) (xy 169.312789 -312.299075) (xy 169.271193 -312.329296)
			(xy 169.225381 -312.352639) (xy 169.176482 -312.368527) (xy 169.1257 -312.37657) (xy 169.074284 -312.37657)
			(xy 169.023502 -312.368527) (xy 168.974603 -312.352639) (xy 168.928791 -312.329296) (xy 168.887195 -312.299075)
			(xy 168.850839 -312.262719) (xy 168.820618 -312.221123) (xy 168.797275 -312.175311) (xy 168.781387 -312.126412)
			(xy 168.773344 -312.07563) (xy 168.454666 -312.07563) (xy 168.44695 -312.123106) (xy 168.431366 -312.169787)
			(xy 168.408495 -312.213364) (xy 168.37893 -312.252708) (xy 168.343437 -312.2868) (xy 168.302934 -312.314756)
			(xy 168.258472 -312.335854) (xy 168.211201 -312.349546) (xy 168.162346 -312.355478) (xy 168.113171 -312.353497)
			(xy 168.064952 -312.343653) (xy 168.018936 -312.326201) (xy 167.976315 -312.301594) (xy 167.938194 -312.270469)
			(xy 167.905559 -312.233632) (xy 167.879256 -312.192036) (xy 167.859965 -312.14676) (xy 167.848188 -312.098976)
			(xy 167.844228 -312.049922) (xy 167.527224 -312.049922) (xy 167.52672 -312.07563) (xy 167.518677 -312.126412)
			(xy 167.502789 -312.175311) (xy 167.479446 -312.221123) (xy 167.449225 -312.262719) (xy 167.412869 -312.299075)
			(xy 167.371273 -312.329296) (xy 167.325461 -312.352639) (xy 167.276562 -312.368527) (xy 167.22578 -312.37657)
			(xy 167.174364 -312.37657) (xy 167.123582 -312.368527) (xy 167.074683 -312.352639) (xy 167.028871 -312.329296)
			(xy 166.987275 -312.299075) (xy 166.950919 -312.262719) (xy 166.920698 -312.221123) (xy 166.897355 -312.175311)
			(xy 166.881467 -312.126412) (xy 166.873424 -312.07563) (xy 166.554492 -312.07563) (xy 166.546776 -312.123106)
			(xy 166.531192 -312.169787) (xy 166.508321 -312.213364) (xy 166.478756 -312.252708) (xy 166.443263 -312.2868)
			(xy 166.40276 -312.314756) (xy 166.358298 -312.335854) (xy 166.311027 -312.349546) (xy 166.262172 -312.355478)
			(xy 166.212997 -312.353497) (xy 166.164778 -312.343653) (xy 166.118762 -312.326201) (xy 166.076141 -312.301594)
			(xy 166.03802 -312.270469) (xy 166.005385 -312.233632) (xy 165.979082 -312.192036) (xy 165.959791 -312.14676)
			(xy 165.948014 -312.098976) (xy 165.944054 -312.049922) (xy 165.62705 -312.049922) (xy 165.626546 -312.07563)
			(xy 165.618503 -312.126412) (xy 165.602615 -312.175311) (xy 165.579272 -312.221123) (xy 165.549051 -312.262719)
			(xy 165.512695 -312.299075) (xy 165.471099 -312.329296) (xy 165.425287 -312.352639) (xy 165.376388 -312.368527)
			(xy 165.325606 -312.37657) (xy 165.27419 -312.37657) (xy 165.223408 -312.368527) (xy 165.174509 -312.352639)
			(xy 165.128697 -312.329296) (xy 165.087101 -312.299075) (xy 165.050745 -312.262719) (xy 165.020524 -312.221123)
			(xy 164.997181 -312.175311) (xy 164.981293 -312.126412) (xy 164.97325 -312.07563) (xy 164.654572 -312.07563)
			(xy 164.646856 -312.123106) (xy 164.631272 -312.169787) (xy 164.608401 -312.213364) (xy 164.578836 -312.252708)
			(xy 164.543343 -312.2868) (xy 164.50284 -312.314756) (xy 164.458378 -312.335854) (xy 164.411107 -312.349546)
			(xy 164.362252 -312.355478) (xy 164.313077 -312.353497) (xy 164.264858 -312.343653) (xy 164.218842 -312.326201)
			(xy 164.176221 -312.301594) (xy 164.1381 -312.270469) (xy 164.105465 -312.233632) (xy 164.079162 -312.192036)
			(xy 164.059871 -312.14676) (xy 164.048094 -312.098976) (xy 164.044134 -312.049922) (xy 163.72713 -312.049922)
			(xy 163.726626 -312.07563) (xy 163.718583 -312.126412) (xy 163.702695 -312.175311) (xy 163.679352 -312.221123)
			(xy 163.649131 -312.262719) (xy 163.612775 -312.299075) (xy 163.571179 -312.329296) (xy 163.525367 -312.352639)
			(xy 163.476468 -312.368527) (xy 163.425686 -312.37657) (xy 163.37427 -312.37657) (xy 163.323488 -312.368527)
			(xy 163.274589 -312.352639) (xy 163.228777 -312.329296) (xy 163.187181 -312.299075) (xy 163.150825 -312.262719)
			(xy 163.120604 -312.221123) (xy 163.097261 -312.175311) (xy 163.081373 -312.126412) (xy 163.07333 -312.07563)
			(xy 162.754652 -312.07563) (xy 162.746936 -312.123106) (xy 162.731352 -312.169787) (xy 162.708481 -312.213364)
			(xy 162.678916 -312.252708) (xy 162.643423 -312.2868) (xy 162.60292 -312.314756) (xy 162.558458 -312.335854)
			(xy 162.511187 -312.349546) (xy 162.462332 -312.355478) (xy 162.413157 -312.353497) (xy 162.364938 -312.343653)
			(xy 162.318922 -312.326201) (xy 162.276301 -312.301594) (xy 162.23818 -312.270469) (xy 162.205545 -312.233632)
			(xy 162.179242 -312.192036) (xy 162.159951 -312.14676) (xy 162.148174 -312.098976) (xy 162.144214 -312.049922)
			(xy 161.82721 -312.049922) (xy 161.826706 -312.07563) (xy 161.818663 -312.126412) (xy 161.802775 -312.175311)
			(xy 161.779432 -312.221123) (xy 161.749211 -312.262719) (xy 161.712855 -312.299075) (xy 161.671259 -312.329296)
			(xy 161.625447 -312.352639) (xy 161.576548 -312.368527) (xy 161.525766 -312.37657) (xy 161.47435 -312.37657)
			(xy 161.423568 -312.368527) (xy 161.374669 -312.352639) (xy 161.328857 -312.329296) (xy 161.287261 -312.299075)
			(xy 161.250905 -312.262719) (xy 161.220684 -312.221123) (xy 161.197341 -312.175311) (xy 161.181453 -312.126412)
			(xy 161.17341 -312.07563) (xy 160.854478 -312.07563) (xy 160.846762 -312.123106) (xy 160.831178 -312.169787)
			(xy 160.808307 -312.213364) (xy 160.778742 -312.252708) (xy 160.743249 -312.2868) (xy 160.702746 -312.314756)
			(xy 160.658284 -312.335854) (xy 160.611013 -312.349546) (xy 160.562158 -312.355478) (xy 160.512983 -312.353497)
			(xy 160.464764 -312.343653) (xy 160.418748 -312.326201) (xy 160.376127 -312.301594) (xy 160.338006 -312.270469)
			(xy 160.305371 -312.233632) (xy 160.279068 -312.192036) (xy 160.259777 -312.14676) (xy 160.248 -312.098976)
			(xy 160.24404 -312.049922) (xy 159.927036 -312.049922) (xy 159.926532 -312.07563) (xy 159.918489 -312.126412)
			(xy 159.902601 -312.175311) (xy 159.879258 -312.221123) (xy 159.849037 -312.262719) (xy 159.812681 -312.299075)
			(xy 159.771085 -312.329296) (xy 159.725273 -312.352639) (xy 159.676374 -312.368527) (xy 159.625592 -312.37657)
			(xy 159.574176 -312.37657) (xy 159.523394 -312.368527) (xy 159.474495 -312.352639) (xy 159.428683 -312.329296)
			(xy 159.387087 -312.299075) (xy 159.350731 -312.262719) (xy 159.32051 -312.221123) (xy 159.297167 -312.175311)
			(xy 159.281279 -312.126412) (xy 159.273236 -312.07563) (xy 158.954558 -312.07563) (xy 158.946842 -312.123106)
			(xy 158.931258 -312.169787) (xy 158.908387 -312.213364) (xy 158.878822 -312.252708) (xy 158.843329 -312.2868)
			(xy 158.802826 -312.314756) (xy 158.758364 -312.335854) (xy 158.711093 -312.349546) (xy 158.662238 -312.355478)
			(xy 158.613063 -312.353497) (xy 158.564844 -312.343653) (xy 158.518828 -312.326201) (xy 158.476207 -312.301594)
			(xy 158.438086 -312.270469) (xy 158.405451 -312.233632) (xy 158.379148 -312.192036) (xy 158.359857 -312.14676)
			(xy 158.34808 -312.098976) (xy 158.34412 -312.049922) (xy 158.027116 -312.049922) (xy 158.026612 -312.07563)
			(xy 158.018569 -312.126412) (xy 158.002681 -312.175311) (xy 157.979338 -312.221123) (xy 157.949117 -312.262719)
			(xy 157.912761 -312.299075) (xy 157.871165 -312.329296) (xy 157.825353 -312.352639) (xy 157.776454 -312.368527)
			(xy 157.725672 -312.37657) (xy 157.674256 -312.37657) (xy 157.623474 -312.368527) (xy 157.574575 -312.352639)
			(xy 157.528763 -312.329296) (xy 157.487167 -312.299075) (xy 157.450811 -312.262719) (xy 157.42059 -312.221123)
			(xy 157.397247 -312.175311) (xy 157.381359 -312.126412) (xy 157.373316 -312.07563) (xy 157.054638 -312.07563)
			(xy 157.046922 -312.123106) (xy 157.031338 -312.169787) (xy 157.008467 -312.213364) (xy 156.978902 -312.252708)
			(xy 156.943409 -312.2868) (xy 156.902906 -312.314756) (xy 156.858444 -312.335854) (xy 156.811173 -312.349546)
			(xy 156.762318 -312.355478) (xy 156.713143 -312.353497) (xy 156.664924 -312.343653) (xy 156.618908 -312.326201)
			(xy 156.576287 -312.301594) (xy 156.538166 -312.270469) (xy 156.505531 -312.233632) (xy 156.479228 -312.192036)
			(xy 156.459937 -312.14676) (xy 156.44816 -312.098976) (xy 156.4442 -312.049922) (xy 156.127196 -312.049922)
			(xy 156.126692 -312.07563) (xy 156.118649 -312.126412) (xy 156.102761 -312.175311) (xy 156.079418 -312.221123)
			(xy 156.049197 -312.262719) (xy 156.012841 -312.299075) (xy 155.971245 -312.329296) (xy 155.925433 -312.352639)
			(xy 155.876534 -312.368527) (xy 155.825752 -312.37657) (xy 155.774336 -312.37657) (xy 155.723554 -312.368527)
			(xy 155.674655 -312.352639) (xy 155.628843 -312.329296) (xy 155.587247 -312.299075) (xy 155.550891 -312.262719)
			(xy 155.52067 -312.221123) (xy 155.497327 -312.175311) (xy 155.481439 -312.126412) (xy 155.473396 -312.07563)
			(xy 155.154718 -312.07563) (xy 155.147002 -312.123106) (xy 155.131418 -312.169787) (xy 155.108547 -312.213364)
			(xy 155.078982 -312.252708) (xy 155.043489 -312.2868) (xy 155.002986 -312.314756) (xy 154.958524 -312.335854)
			(xy 154.911253 -312.349546) (xy 154.862398 -312.355478) (xy 154.813223 -312.353497) (xy 154.765004 -312.343653)
			(xy 154.718988 -312.326201) (xy 154.676367 -312.301594) (xy 154.638246 -312.270469) (xy 154.605611 -312.233632)
			(xy 154.579308 -312.192036) (xy 154.560017 -312.14676) (xy 154.54824 -312.098976) (xy 154.54428 -312.049922)
			(xy 154.227022 -312.049922) (xy 154.226518 -312.07563) (xy 154.218475 -312.126412) (xy 154.202587 -312.175311)
			(xy 154.179244 -312.221123) (xy 154.149023 -312.262719) (xy 154.112667 -312.299075) (xy 154.071071 -312.329296)
			(xy 154.025259 -312.352639) (xy 153.97636 -312.368527) (xy 153.925578 -312.37657) (xy 153.874162 -312.37657)
			(xy 153.82338 -312.368527) (xy 153.774481 -312.352639) (xy 153.728669 -312.329296) (xy 153.687073 -312.299075)
			(xy 153.650717 -312.262719) (xy 153.620496 -312.221123) (xy 153.597153 -312.175311) (xy 153.581265 -312.126412)
			(xy 153.573222 -312.07563) (xy 153.276558 -312.07563) (xy 153.268515 -312.126412) (xy 153.252627 -312.175311)
			(xy 153.229284 -312.221123) (xy 153.199063 -312.262719) (xy 153.162707 -312.299075) (xy 153.121111 -312.329296)
			(xy 153.075299 -312.352639) (xy 153.0264 -312.368527) (xy 152.975618 -312.37657) (xy 152.924202 -312.37657)
			(xy 152.87342 -312.368527) (xy 152.824521 -312.352639) (xy 152.778709 -312.329296) (xy 152.737113 -312.299075)
			(xy 152.700757 -312.262719) (xy 152.670536 -312.221123) (xy 152.647193 -312.175311) (xy 152.631305 -312.126412)
			(xy 152.623262 -312.07563) (xy 152.304289 -312.07563) (xy 152.296614 -312.122852) (xy 152.28103 -312.169533)
			(xy 152.258159 -312.21311) (xy 152.228594 -312.252454) (xy 152.193101 -312.286546) (xy 152.152598 -312.314502)
			(xy 152.108136 -312.3356) (xy 152.060865 -312.349292) (xy 152.01201 -312.355224) (xy 151.962835 -312.353243)
			(xy 151.914616 -312.343399) (xy 151.8686 -312.325947) (xy 151.825979 -312.30134) (xy 151.787858 -312.270215)
			(xy 151.755223 -312.233378) (xy 151.72892 -312.191782) (xy 151.709629 -312.146506) (xy 151.697852 -312.098722)
			(xy 151.693892 -312.049668) (xy 150.905106 -312.049668) (xy 150.925929 -312.081142) (xy 150.949601 -312.131639)
			(xy 150.965669 -312.185046) (xy 150.973789 -312.240222) (xy 150.974298 -312.268108) (xy 150.973789 -312.295994)
			(xy 150.965669 -312.35117) (xy 150.949601 -312.404577) (xy 150.925929 -312.455074) (xy 150.895156 -312.501587)
			(xy 150.857939 -312.543124) (xy 150.815071 -312.578799) (xy 150.767465 -312.607853) (xy 150.716136 -312.629665)
			(xy 150.662179 -312.643771) (xy 150.606742 -312.649871) (xy 150.551008 -312.647834) (xy 150.496165 -312.637704)
			(xy 150.443381 -312.619697) (xy 150.393781 -312.594196) (xy 150.348423 -312.561745) (xy 150.308274 -312.523036)
			(xy 150.274188 -312.478893) (xy 150.246892 -312.430258) (xy 150.226969 -312.378167) (xy 150.214843 -312.32373)
			(xy 150.210772 -312.268108) (xy 148.496921 -312.268108) (xy 148.516446 -312.289899) (xy 148.547219 -312.336412)
			(xy 148.570891 -312.386909) (xy 148.586959 -312.440316) (xy 148.595079 -312.495492) (xy 148.595588 -312.523378)
			(xy 148.595079 -312.551264) (xy 148.586959 -312.60644) (xy 148.570891 -312.659847) (xy 148.547219 -312.710344)
			(xy 148.516446 -312.756857) (xy 148.479229 -312.798394) (xy 148.436361 -312.834069) (xy 148.388755 -312.863123)
			(xy 148.337426 -312.884935) (xy 148.283469 -312.899041) (xy 148.228032 -312.905141) (xy 148.172298 -312.903104)
			(xy 148.117455 -312.892974) (xy 148.064671 -312.874967) (xy 148.015071 -312.849466) (xy 147.969713 -312.817015)
			(xy 147.929564 -312.778306) (xy 147.895478 -312.734163) (xy 147.868182 -312.685528) (xy 147.848259 -312.633437)
			(xy 147.836133 -312.579) (xy 147.832062 -312.523378) (xy 118.832884 -312.523378) (xy 118.832884 -312.999882)
			(xy 152.644106 -312.999882) (xy 152.648066 -312.950828) (xy 152.659843 -312.903044) (xy 152.679134 -312.857768)
			(xy 152.705437 -312.816172) (xy 152.738072 -312.779335) (xy 152.776193 -312.74821) (xy 152.818814 -312.723603)
			(xy 152.86483 -312.706151) (xy 152.913049 -312.696307) (xy 152.962224 -312.694326) (xy 153.011079 -312.700258)
			(xy 153.05835 -312.71395) (xy 153.102812 -312.735048) (xy 153.143315 -312.763004) (xy 153.178808 -312.797096)
			(xy 153.208373 -312.83644) (xy 153.231244 -312.880017) (xy 153.246828 -312.926698) (xy 153.254723 -312.975275)
			(xy 153.255218 -312.999882) (xy 153.594066 -312.999882) (xy 153.598026 -312.950828) (xy 153.609803 -312.903044)
			(xy 153.629094 -312.857768) (xy 153.655397 -312.816172) (xy 153.688032 -312.779335) (xy 153.726153 -312.74821)
			(xy 153.768774 -312.723603) (xy 153.81479 -312.706151) (xy 153.863009 -312.696307) (xy 153.912184 -312.694326)
			(xy 153.961039 -312.700258) (xy 154.00831 -312.71395) (xy 154.052772 -312.735048) (xy 154.093275 -312.763004)
			(xy 154.128768 -312.797096) (xy 154.158333 -312.83644) (xy 154.181204 -312.880017) (xy 154.196788 -312.926698)
			(xy 154.204683 -312.975275) (xy 154.205178 -312.999882) (xy 154.204683 -313.024489) (xy 154.204504 -313.02559)
			(xy 154.523436 -313.02559) (xy 154.523436 -312.974174) (xy 154.531479 -312.923392) (xy 154.547367 -312.874493)
			(xy 154.57071 -312.828681) (xy 154.600931 -312.787085) (xy 154.637287 -312.750729) (xy 154.678883 -312.720508)
			(xy 154.724695 -312.697165) (xy 154.773594 -312.681277) (xy 154.824376 -312.673234) (xy 154.875792 -312.673234)
			(xy 154.926574 -312.681277) (xy 154.975473 -312.697165) (xy 155.021285 -312.720508) (xy 155.062881 -312.750729)
			(xy 155.099237 -312.787085) (xy 155.129458 -312.828681) (xy 155.152801 -312.874493) (xy 155.168689 -312.923392)
			(xy 155.176732 -312.974174) (xy 155.177236 -312.999882) (xy 155.49424 -312.999882) (xy 155.4982 -312.950828)
			(xy 155.509977 -312.903044) (xy 155.529268 -312.857768) (xy 155.555571 -312.816172) (xy 155.588206 -312.779335)
			(xy 155.626327 -312.74821) (xy 155.668948 -312.723603) (xy 155.714964 -312.706151) (xy 155.763183 -312.696307)
			(xy 155.812358 -312.694326) (xy 155.861213 -312.700258) (xy 155.908484 -312.71395) (xy 155.952946 -312.735048)
			(xy 155.993449 -312.763004) (xy 156.028942 -312.797096) (xy 156.058507 -312.83644) (xy 156.081378 -312.880017)
			(xy 156.096962 -312.926698) (xy 156.104857 -312.975275) (xy 156.105352 -312.999882) (xy 156.104857 -313.024489)
			(xy 156.104678 -313.02559) (xy 156.423356 -313.02559) (xy 156.423356 -312.974174) (xy 156.431399 -312.923392)
			(xy 156.447287 -312.874493) (xy 156.47063 -312.828681) (xy 156.500851 -312.787085) (xy 156.537207 -312.750729)
			(xy 156.578803 -312.720508) (xy 156.624615 -312.697165) (xy 156.673514 -312.681277) (xy 156.724296 -312.673234)
			(xy 156.775712 -312.673234) (xy 156.826494 -312.681277) (xy 156.875393 -312.697165) (xy 156.921205 -312.720508)
			(xy 156.962801 -312.750729) (xy 156.999157 -312.787085) (xy 157.029378 -312.828681) (xy 157.052721 -312.874493)
			(xy 157.068609 -312.923392) (xy 157.076652 -312.974174) (xy 157.077156 -312.999882) (xy 157.076652 -313.02559)
			(xy 157.068609 -313.076372) (xy 157.052721 -313.125271) (xy 157.029378 -313.171083) (xy 156.999157 -313.212679)
			(xy 156.962801 -313.249035) (xy 156.921205 -313.279256) (xy 156.875393 -313.302599) (xy 156.826494 -313.318487)
			(xy 156.775712 -313.32653) (xy 156.724296 -313.32653) (xy 156.673514 -313.318487) (xy 156.624615 -313.302599)
			(xy 156.578803 -313.279256) (xy 156.537207 -313.249035) (xy 156.500851 -313.212679) (xy 156.47063 -313.171083)
			(xy 156.447287 -313.125271) (xy 156.431399 -313.076372) (xy 156.423356 -313.02559) (xy 156.104678 -313.02559)
			(xy 156.096962 -313.073066) (xy 156.081378 -313.119747) (xy 156.058507 -313.163324) (xy 156.028942 -313.202668)
			(xy 155.993449 -313.23676) (xy 155.952946 -313.264716) (xy 155.908484 -313.285814) (xy 155.861213 -313.299506)
			(xy 155.812358 -313.305438) (xy 155.763183 -313.303457) (xy 155.714964 -313.293613) (xy 155.668948 -313.276161)
			(xy 155.626327 -313.251554) (xy 155.588206 -313.220429) (xy 155.555571 -313.183592) (xy 155.529268 -313.141996)
			(xy 155.509977 -313.09672) (xy 155.4982 -313.048936) (xy 155.49424 -312.999882) (xy 155.177236 -312.999882)
			(xy 155.176732 -313.02559) (xy 155.168689 -313.076372) (xy 155.152801 -313.125271) (xy 155.129458 -313.171083)
			(xy 155.099237 -313.212679) (xy 155.062881 -313.249035) (xy 155.021285 -313.279256) (xy 154.975473 -313.302599)
			(xy 154.926574 -313.318487) (xy 154.875792 -313.32653) (xy 154.824376 -313.32653) (xy 154.773594 -313.318487)
			(xy 154.724695 -313.302599) (xy 154.678883 -313.279256) (xy 154.637287 -313.249035) (xy 154.600931 -313.212679)
			(xy 154.57071 -313.171083) (xy 154.547367 -313.125271) (xy 154.531479 -313.076372) (xy 154.523436 -313.02559)
			(xy 154.204504 -313.02559) (xy 154.196788 -313.073066) (xy 154.181204 -313.119747) (xy 154.158333 -313.163324)
			(xy 154.128768 -313.202668) (xy 154.093275 -313.23676) (xy 154.052772 -313.264716) (xy 154.00831 -313.285814)
			(xy 153.961039 -313.299506) (xy 153.912184 -313.305438) (xy 153.863009 -313.303457) (xy 153.81479 -313.293613)
			(xy 153.768774 -313.276161) (xy 153.726153 -313.251554) (xy 153.688032 -313.220429) (xy 153.655397 -313.183592)
			(xy 153.629094 -313.141996) (xy 153.609803 -313.09672) (xy 153.598026 -313.048936) (xy 153.594066 -312.999882)
			(xy 153.255218 -312.999882) (xy 153.254723 -313.024489) (xy 153.246828 -313.073066) (xy 153.231244 -313.119747)
			(xy 153.208373 -313.163324) (xy 153.178808 -313.202668) (xy 153.143315 -313.23676) (xy 153.102812 -313.264716)
			(xy 153.05835 -313.285814) (xy 153.011079 -313.299506) (xy 152.962224 -313.305438) (xy 152.913049 -313.303457)
			(xy 152.86483 -313.293613) (xy 152.818814 -313.276161) (xy 152.776193 -313.251554) (xy 152.738072 -313.220429)
			(xy 152.705437 -313.183592) (xy 152.679134 -313.141996) (xy 152.659843 -313.09672) (xy 152.648066 -313.048936)
			(xy 152.644106 -312.999882) (xy 118.832884 -312.999882) (xy 118.832884 -313.669934) (xy 150.147018 -313.669934)
			(xy 150.151089 -313.614312) (xy 150.163215 -313.559875) (xy 150.183138 -313.507784) (xy 150.210434 -313.459149)
			(xy 150.24452 -313.415006) (xy 150.284669 -313.376297) (xy 150.330027 -313.343846) (xy 150.379627 -313.318345)
			(xy 150.432411 -313.300338) (xy 150.487254 -313.290208) (xy 150.542988 -313.288171) (xy 150.598425 -313.294271)
			(xy 150.652382 -313.308377) (xy 150.703711 -313.330189) (xy 150.751317 -313.359243) (xy 150.794185 -313.394918)
			(xy 150.831402 -313.436455) (xy 150.862175 -313.482968) (xy 150.885847 -313.533465) (xy 150.901915 -313.586872)
			(xy 150.910035 -313.642048) (xy 150.910544 -313.669934) (xy 150.910035 -313.69782) (xy 150.901915 -313.752996)
			(xy 150.885847 -313.806403) (xy 150.862175 -313.8569) (xy 150.831402 -313.903413) (xy 150.794185 -313.94495)
			(xy 150.788307 -313.949842) (xy 152.644106 -313.949842) (xy 152.648066 -313.900788) (xy 152.659843 -313.853004)
			(xy 152.679134 -313.807728) (xy 152.705437 -313.766132) (xy 152.738072 -313.729295) (xy 152.776193 -313.69817)
			(xy 152.818814 -313.673563) (xy 152.86483 -313.656111) (xy 152.913049 -313.646267) (xy 152.962224 -313.644286)
			(xy 153.011079 -313.650218) (xy 153.05835 -313.66391) (xy 153.102812 -313.685008) (xy 153.143315 -313.712964)
			(xy 153.178808 -313.747056) (xy 153.208373 -313.7864) (xy 153.231244 -313.829977) (xy 153.246828 -313.876658)
			(xy 153.254723 -313.925235) (xy 153.255218 -313.949842) (xy 153.594066 -313.949842) (xy 153.598026 -313.900788)
			(xy 153.609803 -313.853004) (xy 153.629094 -313.807728) (xy 153.655397 -313.766132) (xy 153.688032 -313.729295)
			(xy 153.726153 -313.69817) (xy 153.768774 -313.673563) (xy 153.81479 -313.656111) (xy 153.863009 -313.646267)
			(xy 153.912184 -313.644286) (xy 153.961039 -313.650218) (xy 154.00831 -313.66391) (xy 154.052772 -313.685008)
			(xy 154.093275 -313.712964) (xy 154.128768 -313.747056) (xy 154.158333 -313.7864) (xy 154.181204 -313.829977)
			(xy 154.196788 -313.876658) (xy 154.204683 -313.925235) (xy 154.205178 -313.949842) (xy 154.204683 -313.974449)
			(xy 154.204504 -313.97555) (xy 154.523436 -313.97555) (xy 154.523436 -313.924134) (xy 154.531479 -313.873352)
			(xy 154.547367 -313.824453) (xy 154.57071 -313.778641) (xy 154.600931 -313.737045) (xy 154.637287 -313.700689)
			(xy 154.678883 -313.670468) (xy 154.724695 -313.647125) (xy 154.773594 -313.631237) (xy 154.824376 -313.623194)
			(xy 154.875792 -313.623194) (xy 154.926574 -313.631237) (xy 154.975473 -313.647125) (xy 155.021285 -313.670468)
			(xy 155.062881 -313.700689) (xy 155.099237 -313.737045) (xy 155.129458 -313.778641) (xy 155.152801 -313.824453)
			(xy 155.168689 -313.873352) (xy 155.176732 -313.924134) (xy 155.177236 -313.949842) (xy 155.49424 -313.949842)
			(xy 155.4982 -313.900788) (xy 155.509977 -313.853004) (xy 155.529268 -313.807728) (xy 155.555571 -313.766132)
			(xy 155.588206 -313.729295) (xy 155.626327 -313.69817) (xy 155.668948 -313.673563) (xy 155.714964 -313.656111)
			(xy 155.763183 -313.646267) (xy 155.812358 -313.644286) (xy 155.861213 -313.650218) (xy 155.908484 -313.66391)
			(xy 155.952946 -313.685008) (xy 155.993449 -313.712964) (xy 156.028942 -313.747056) (xy 156.058507 -313.7864)
			(xy 156.081378 -313.829977) (xy 156.096962 -313.876658) (xy 156.104857 -313.925235) (xy 156.105352 -313.949842)
			(xy 156.104857 -313.974449) (xy 156.104678 -313.97555) (xy 156.423356 -313.97555) (xy 156.423356 -313.924134)
			(xy 156.431399 -313.873352) (xy 156.447287 -313.824453) (xy 156.47063 -313.778641) (xy 156.500851 -313.737045)
			(xy 156.537207 -313.700689) (xy 156.578803 -313.670468) (xy 156.624615 -313.647125) (xy 156.673514 -313.631237)
			(xy 156.724296 -313.623194) (xy 156.775712 -313.623194) (xy 156.826494 -313.631237) (xy 156.875393 -313.647125)
			(xy 156.921205 -313.670468) (xy 156.962801 -313.700689) (xy 156.999157 -313.737045) (xy 157.029378 -313.778641)
			(xy 157.052721 -313.824453) (xy 157.068609 -313.873352) (xy 157.076652 -313.924134) (xy 157.077156 -313.949842)
			(xy 157.076652 -313.97555) (xy 157.068609 -314.026332) (xy 157.052721 -314.075231) (xy 157.029378 -314.121043)
			(xy 156.999157 -314.162639) (xy 156.962801 -314.198995) (xy 156.921205 -314.229216) (xy 156.875393 -314.252559)
			(xy 156.826494 -314.268447) (xy 156.775712 -314.27649) (xy 156.724296 -314.27649) (xy 156.673514 -314.268447)
			(xy 156.624615 -314.252559) (xy 156.578803 -314.229216) (xy 156.537207 -314.198995) (xy 156.500851 -314.162639)
			(xy 156.47063 -314.121043) (xy 156.447287 -314.075231) (xy 156.431399 -314.026332) (xy 156.423356 -313.97555)
			(xy 156.104678 -313.97555) (xy 156.096962 -314.023026) (xy 156.081378 -314.069707) (xy 156.058507 -314.113284)
			(xy 156.028942 -314.152628) (xy 155.993449 -314.18672) (xy 155.952946 -314.214676) (xy 155.908484 -314.235774)
			(xy 155.861213 -314.249466) (xy 155.812358 -314.255398) (xy 155.763183 -314.253417) (xy 155.714964 -314.243573)
			(xy 155.668948 -314.226121) (xy 155.626327 -314.201514) (xy 155.588206 -314.170389) (xy 155.555571 -314.133552)
			(xy 155.529268 -314.091956) (xy 155.509977 -314.04668) (xy 155.4982 -313.998896) (xy 155.49424 -313.949842)
			(xy 155.177236 -313.949842) (xy 155.176732 -313.97555) (xy 155.168689 -314.026332) (xy 155.152801 -314.075231)
			(xy 155.129458 -314.121043) (xy 155.099237 -314.162639) (xy 155.062881 -314.198995) (xy 155.021285 -314.229216)
			(xy 154.975473 -314.252559) (xy 154.926574 -314.268447) (xy 154.875792 -314.27649) (xy 154.824376 -314.27649)
			(xy 154.773594 -314.268447) (xy 154.724695 -314.252559) (xy 154.678883 -314.229216) (xy 154.637287 -314.198995)
			(xy 154.600931 -314.162639) (xy 154.57071 -314.121043) (xy 154.547367 -314.075231) (xy 154.531479 -314.026332)
			(xy 154.523436 -313.97555) (xy 154.204504 -313.97555) (xy 154.196788 -314.023026) (xy 154.181204 -314.069707)
			(xy 154.158333 -314.113284) (xy 154.128768 -314.152628) (xy 154.093275 -314.18672) (xy 154.052772 -314.214676)
			(xy 154.00831 -314.235774) (xy 153.961039 -314.249466) (xy 153.912184 -314.255398) (xy 153.863009 -314.253417)
			(xy 153.81479 -314.243573) (xy 153.768774 -314.226121) (xy 153.726153 -314.201514) (xy 153.688032 -314.170389)
			(xy 153.655397 -314.133552) (xy 153.629094 -314.091956) (xy 153.609803 -314.04668) (xy 153.598026 -313.998896)
			(xy 153.594066 -313.949842) (xy 153.255218 -313.949842) (xy 153.254723 -313.974449) (xy 153.246828 -314.023026)
			(xy 153.231244 -314.069707) (xy 153.208373 -314.113284) (xy 153.178808 -314.152628) (xy 153.143315 -314.18672)
			(xy 153.102812 -314.214676) (xy 153.05835 -314.235774) (xy 153.011079 -314.249466) (xy 152.962224 -314.255398)
			(xy 152.913049 -314.253417) (xy 152.86483 -314.243573) (xy 152.818814 -314.226121) (xy 152.776193 -314.201514)
			(xy 152.738072 -314.170389) (xy 152.705437 -314.133552) (xy 152.679134 -314.091956) (xy 152.659843 -314.04668)
			(xy 152.648066 -313.998896) (xy 152.644106 -313.949842) (xy 150.788307 -313.949842) (xy 150.751317 -313.980625)
			(xy 150.703711 -314.009679) (xy 150.652382 -314.031491) (xy 150.598425 -314.045597) (xy 150.542988 -314.051697)
			(xy 150.487254 -314.04966) (xy 150.432411 -314.03953) (xy 150.379627 -314.021523) (xy 150.330027 -313.996022)
			(xy 150.284669 -313.963571) (xy 150.24452 -313.924862) (xy 150.210434 -313.880719) (xy 150.183138 -313.832084)
			(xy 150.163215 -313.779993) (xy 150.151089 -313.725556) (xy 150.147018 -313.669934) (xy 118.832884 -313.669934)
			(xy 118.832884 -314.899548) (xy 151.693638 -314.899548) (xy 151.697598 -314.850494) (xy 151.709375 -314.80271)
			(xy 151.728666 -314.757434) (xy 151.754969 -314.715838) (xy 151.787604 -314.679001) (xy 151.825725 -314.647876)
			(xy 151.868346 -314.623269) (xy 151.914362 -314.605817) (xy 151.962581 -314.595973) (xy 152.011756 -314.593992)
			(xy 152.060611 -314.599924) (xy 152.107882 -314.613616) (xy 152.152344 -314.634714) (xy 152.192847 -314.66267)
			(xy 152.22834 -314.696762) (xy 152.257905 -314.736106) (xy 152.280776 -314.779683) (xy 152.29636 -314.826364)
			(xy 152.304255 -314.874941) (xy 152.30475 -314.899548) (xy 152.304255 -314.924155) (xy 152.304035 -314.92551)
			(xy 152.623262 -314.92551) (xy 152.623262 -314.874094) (xy 152.631305 -314.823312) (xy 152.647193 -314.774413)
			(xy 152.670536 -314.728601) (xy 152.700757 -314.687005) (xy 152.737113 -314.650649) (xy 152.778709 -314.620428)
			(xy 152.824521 -314.597085) (xy 152.87342 -314.581197) (xy 152.924202 -314.573154) (xy 152.975618 -314.573154)
			(xy 153.0264 -314.581197) (xy 153.075299 -314.597085) (xy 153.121111 -314.620428) (xy 153.162707 -314.650649)
			(xy 153.199063 -314.687005) (xy 153.229284 -314.728601) (xy 153.252627 -314.774413) (xy 153.268515 -314.823312)
			(xy 153.276558 -314.874094) (xy 153.277062 -314.899802) (xy 153.276558 -314.92551) (xy 153.573222 -314.92551)
			(xy 153.573222 -314.874094) (xy 153.581265 -314.823312) (xy 153.597153 -314.774413) (xy 153.620496 -314.728601)
			(xy 153.650717 -314.687005) (xy 153.687073 -314.650649) (xy 153.728669 -314.620428) (xy 153.774481 -314.597085)
			(xy 153.82338 -314.581197) (xy 153.874162 -314.573154) (xy 153.925578 -314.573154) (xy 153.97636 -314.581197)
			(xy 154.025259 -314.597085) (xy 154.071071 -314.620428) (xy 154.112667 -314.650649) (xy 154.149023 -314.687005)
			(xy 154.179244 -314.728601) (xy 154.202587 -314.774413) (xy 154.218475 -314.823312) (xy 154.226518 -314.874094)
			(xy 154.227022 -314.899802) (xy 154.54428 -314.899802) (xy 154.54824 -314.850748) (xy 154.560017 -314.802964)
			(xy 154.579308 -314.757688) (xy 154.605611 -314.716092) (xy 154.638246 -314.679255) (xy 154.676367 -314.64813)
			(xy 154.718988 -314.623523) (xy 154.765004 -314.606071) (xy 154.813223 -314.596227) (xy 154.862398 -314.594246)
			(xy 154.911253 -314.600178) (xy 154.958524 -314.61387) (xy 155.002986 -314.634968) (xy 155.043489 -314.662924)
			(xy 155.078982 -314.697016) (xy 155.108547 -314.73636) (xy 155.131418 -314.779937) (xy 155.147002 -314.826618)
			(xy 155.154897 -314.875195) (xy 155.155392 -314.899802) (xy 155.49424 -314.899802) (xy 155.4982 -314.850748)
			(xy 155.509977 -314.802964) (xy 155.529268 -314.757688) (xy 155.555571 -314.716092) (xy 155.588206 -314.679255)
			(xy 155.626327 -314.64813) (xy 155.668948 -314.623523) (xy 155.714964 -314.606071) (xy 155.763183 -314.596227)
			(xy 155.812358 -314.594246) (xy 155.861213 -314.600178) (xy 155.908484 -314.61387) (xy 155.952946 -314.634968)
			(xy 155.993449 -314.662924) (xy 156.028942 -314.697016) (xy 156.058507 -314.73636) (xy 156.081378 -314.779937)
			(xy 156.096962 -314.826618) (xy 156.104857 -314.875195) (xy 156.105352 -314.899802) (xy 156.4442 -314.899802)
			(xy 156.44816 -314.850748) (xy 156.459937 -314.802964) (xy 156.479228 -314.757688) (xy 156.505531 -314.716092)
			(xy 156.538166 -314.679255) (xy 156.576287 -314.64813) (xy 156.618908 -314.623523) (xy 156.664924 -314.606071)
			(xy 156.713143 -314.596227) (xy 156.762318 -314.594246) (xy 156.811173 -314.600178) (xy 156.858444 -314.61387)
			(xy 156.902906 -314.634968) (xy 156.943409 -314.662924) (xy 156.978902 -314.697016) (xy 157.008467 -314.73636)
			(xy 157.031338 -314.779937) (xy 157.046922 -314.826618) (xy 157.054817 -314.875195) (xy 157.055312 -314.899802)
			(xy 157.054817 -314.924409) (xy 157.046922 -314.972986) (xy 157.031338 -315.019667) (xy 157.008467 -315.063244)
			(xy 156.978902 -315.102588) (xy 156.943409 -315.13668) (xy 156.902906 -315.164636) (xy 156.858444 -315.185734)
			(xy 156.811173 -315.199426) (xy 156.762318 -315.205358) (xy 156.713143 -315.203377) (xy 156.664924 -315.193533)
			(xy 156.618908 -315.176081) (xy 156.576287 -315.151474) (xy 156.538166 -315.120349) (xy 156.505531 -315.083512)
			(xy 156.479228 -315.041916) (xy 156.459937 -314.99664) (xy 156.44816 -314.948856) (xy 156.4442 -314.899802)
			(xy 156.105352 -314.899802) (xy 156.104857 -314.924409) (xy 156.096962 -314.972986) (xy 156.081378 -315.019667)
			(xy 156.058507 -315.063244) (xy 156.028942 -315.102588) (xy 155.993449 -315.13668) (xy 155.952946 -315.164636)
			(xy 155.908484 -315.185734) (xy 155.861213 -315.199426) (xy 155.812358 -315.205358) (xy 155.763183 -315.203377)
			(xy 155.714964 -315.193533) (xy 155.668948 -315.176081) (xy 155.626327 -315.151474) (xy 155.588206 -315.120349)
			(xy 155.555571 -315.083512) (xy 155.529268 -315.041916) (xy 155.509977 -314.99664) (xy 155.4982 -314.948856)
			(xy 155.49424 -314.899802) (xy 155.155392 -314.899802) (xy 155.154897 -314.924409) (xy 155.147002 -314.972986)
			(xy 155.131418 -315.019667) (xy 155.108547 -315.063244) (xy 155.078982 -315.102588) (xy 155.043489 -315.13668)
			(xy 155.002986 -315.164636) (xy 154.958524 -315.185734) (xy 154.911253 -315.199426) (xy 154.862398 -315.205358)
			(xy 154.813223 -315.203377) (xy 154.765004 -315.193533) (xy 154.718988 -315.176081) (xy 154.676367 -315.151474)
			(xy 154.638246 -315.120349) (xy 154.605611 -315.083512) (xy 154.579308 -315.041916) (xy 154.560017 -314.99664)
			(xy 154.54824 -314.948856) (xy 154.54428 -314.899802) (xy 154.227022 -314.899802) (xy 154.226518 -314.92551)
			(xy 154.218475 -314.976292) (xy 154.202587 -315.025191) (xy 154.179244 -315.071003) (xy 154.149023 -315.112599)
			(xy 154.112667 -315.148955) (xy 154.071071 -315.179176) (xy 154.025259 -315.202519) (xy 153.97636 -315.218407)
			(xy 153.925578 -315.22645) (xy 153.874162 -315.22645) (xy 153.82338 -315.218407) (xy 153.774481 -315.202519)
			(xy 153.728669 -315.179176) (xy 153.687073 -315.148955) (xy 153.650717 -315.112599) (xy 153.620496 -315.071003)
			(xy 153.597153 -315.025191) (xy 153.581265 -314.976292) (xy 153.573222 -314.92551) (xy 153.276558 -314.92551)
			(xy 153.268515 -314.976292) (xy 153.252627 -315.025191) (xy 153.229284 -315.071003) (xy 153.199063 -315.112599)
			(xy 153.162707 -315.148955) (xy 153.121111 -315.179176) (xy 153.075299 -315.202519) (xy 153.0264 -315.218407)
			(xy 152.975618 -315.22645) (xy 152.924202 -315.22645) (xy 152.87342 -315.218407) (xy 152.824521 -315.202519)
			(xy 152.778709 -315.179176) (xy 152.737113 -315.148955) (xy 152.700757 -315.112599) (xy 152.670536 -315.071003)
			(xy 152.647193 -315.025191) (xy 152.631305 -314.976292) (xy 152.623262 -314.92551) (xy 152.304035 -314.92551)
			(xy 152.29636 -314.972732) (xy 152.280776 -315.019413) (xy 152.257905 -315.06299) (xy 152.22834 -315.102334)
			(xy 152.192847 -315.136426) (xy 152.152344 -315.164382) (xy 152.107882 -315.18548) (xy 152.060611 -315.199172)
			(xy 152.011756 -315.205104) (xy 151.962581 -315.203123) (xy 151.914362 -315.193279) (xy 151.868346 -315.175827)
			(xy 151.825725 -315.15122) (xy 151.787604 -315.120095) (xy 151.754969 -315.083258) (xy 151.728666 -315.041662)
			(xy 151.709375 -314.996386) (xy 151.697598 -314.948602) (xy 151.693638 -314.899548) (xy 118.832884 -314.899548)
			(xy 118.832884 -317.071502) (xy 118.833307 -317.081572) (xy 118.84102 -317.100178) (xy 118.84787 -317.10757)
			(xy 119.345202 -317.604902) (xy 119.352601 -317.611748) (xy 119.371199 -317.619481) (xy 119.38127 -317.619888)
		)
		(stroke
			(width 0)
			(type solid)
		)
		(fill yes)
		(layer "In15.Cu")
		(net "P0V8_PEX1")
	)
	(gr_poly
		(pts
			(xy 373.70258 -317.73876) (xy 373.712453 -317.73829) (xy 373.730741 -317.730838) (xy 373.73814 -317.724282)
			(xy 373.738394 -317.724028) (xy 375.368312 -316.09411) (xy 375.375711 -316.087265) (xy 375.394309 -316.079533)
			(xy 375.40438 -316.079124) (xy 380.340362 -316.079124) (xy 380.350427 -316.079559) (xy 380.369013 -316.087292)
			(xy 380.37643 -316.09411) (xy 381.081788 -316.799468) (xy 383.89358 -316.799468) (xy 383.89754 -316.750414)
			(xy 383.909317 -316.70263) (xy 383.928608 -316.657354) (xy 383.954911 -316.615758) (xy 383.987546 -316.578921)
			(xy 384.025667 -316.547796) (xy 384.068288 -316.523189) (xy 384.114304 -316.505737) (xy 384.162523 -316.495893)
			(xy 384.211698 -316.493912) (xy 384.260553 -316.499844) (xy 384.307824 -316.513536) (xy 384.352286 -316.534634)
			(xy 384.392789 -316.56259) (xy 384.428282 -316.596682) (xy 384.457847 -316.636026) (xy 384.480718 -316.679603)
			(xy 384.496302 -316.726284) (xy 384.504197 -316.774861) (xy 384.504692 -316.799468) (xy 384.504197 -316.824075)
			(xy 384.503977 -316.82543) (xy 384.823204 -316.82543) (xy 384.823204 -316.774014) (xy 384.831247 -316.723232)
			(xy 384.847135 -316.674333) (xy 384.870478 -316.628521) (xy 384.900699 -316.586925) (xy 384.937055 -316.550569)
			(xy 384.978651 -316.520348) (xy 385.024463 -316.497005) (xy 385.073362 -316.481117) (xy 385.124144 -316.473074)
			(xy 385.17556 -316.473074) (xy 385.226342 -316.481117) (xy 385.275241 -316.497005) (xy 385.321053 -316.520348)
			(xy 385.362649 -316.550569) (xy 385.399005 -316.586925) (xy 385.429226 -316.628521) (xy 385.452569 -316.674333)
			(xy 385.468457 -316.723232) (xy 385.4765 -316.774014) (xy 385.477004 -316.799722) (xy 385.4765 -316.82543)
			(xy 385.773164 -316.82543) (xy 385.773164 -316.774014) (xy 385.781207 -316.723232) (xy 385.797095 -316.674333)
			(xy 385.820438 -316.628521) (xy 385.850659 -316.586925) (xy 385.887015 -316.550569) (xy 385.928611 -316.520348)
			(xy 385.974423 -316.497005) (xy 386.023322 -316.481117) (xy 386.074104 -316.473074) (xy 386.12552 -316.473074)
			(xy 386.176302 -316.481117) (xy 386.225201 -316.497005) (xy 386.271013 -316.520348) (xy 386.312609 -316.550569)
			(xy 386.348965 -316.586925) (xy 386.379186 -316.628521) (xy 386.402529 -316.674333) (xy 386.418417 -316.723232)
			(xy 386.42646 -316.774014) (xy 386.426964 -316.799722) (xy 386.42646 -316.82543) (xy 386.418417 -316.876212)
			(xy 386.402529 -316.925111) (xy 386.379186 -316.970923) (xy 386.348965 -317.012519) (xy 386.312609 -317.048875)
			(xy 386.271013 -317.079096) (xy 386.225201 -317.102439) (xy 386.176302 -317.118327) (xy 386.12552 -317.12637)
			(xy 386.074104 -317.12637) (xy 386.023322 -317.118327) (xy 385.974423 -317.102439) (xy 385.928611 -317.079096)
			(xy 385.887015 -317.048875) (xy 385.850659 -317.012519) (xy 385.820438 -316.970923) (xy 385.797095 -316.925111)
			(xy 385.781207 -316.876212) (xy 385.773164 -316.82543) (xy 385.4765 -316.82543) (xy 385.468457 -316.876212)
			(xy 385.452569 -316.925111) (xy 385.429226 -316.970923) (xy 385.399005 -317.012519) (xy 385.362649 -317.048875)
			(xy 385.321053 -317.079096) (xy 385.275241 -317.102439) (xy 385.226342 -317.118327) (xy 385.17556 -317.12637)
			(xy 385.124144 -317.12637) (xy 385.073362 -317.118327) (xy 385.024463 -317.102439) (xy 384.978651 -317.079096)
			(xy 384.937055 -317.048875) (xy 384.900699 -317.012519) (xy 384.870478 -316.970923) (xy 384.847135 -316.925111)
			(xy 384.831247 -316.876212) (xy 384.823204 -316.82543) (xy 384.503977 -316.82543) (xy 384.496302 -316.872652)
			(xy 384.480718 -316.919333) (xy 384.457847 -316.96291) (xy 384.428282 -317.002254) (xy 384.392789 -317.036346)
			(xy 384.352286 -317.064302) (xy 384.307824 -317.0854) (xy 384.260553 -317.099092) (xy 384.211698 -317.105024)
			(xy 384.162523 -317.103043) (xy 384.114304 -317.093199) (xy 384.068288 -317.075747) (xy 384.025667 -317.05114)
			(xy 383.987546 -317.020015) (xy 383.954911 -316.983178) (xy 383.928608 -316.941582) (xy 383.909317 -316.896306)
			(xy 383.89754 -316.848522) (xy 383.89358 -316.799468) (xy 381.081788 -316.799468) (xy 382.006094 -317.723774)
			(xy 382.006602 -317.724282) (xy 382.013987 -317.730854) (xy 382.032286 -317.738282) (xy 382.042162 -317.73876)
			(xy 384.817874 -317.73876) (xy 384.846068 -317.715138) (xy 384.849116 -317.69685) (xy 384.853978 -317.672227)
			(xy 384.870666 -317.624895) (xy 384.894868 -317.580929) (xy 384.925934 -317.541512) (xy 384.963026 -317.507705)
			(xy 385.005147 -317.480418) (xy 385.051162 -317.460384) (xy 385.099834 -317.448145) (xy 385.149852 -317.444028)
			(xy 385.19987 -317.448145) (xy 385.248542 -317.460384) (xy 385.294557 -317.480418) (xy 385.336678 -317.507705)
			(xy 385.37377 -317.541512) (xy 385.404836 -317.580929) (xy 385.429038 -317.624895) (xy 385.445726 -317.672227)
			(xy 385.450588 -317.69685) (xy 385.453636 -317.715138) (xy 385.48183 -317.73876) (xy 385.767834 -317.73876)
			(xy 385.796028 -317.715138) (xy 385.799076 -317.69685) (xy 385.803938 -317.672227) (xy 385.820626 -317.624895)
			(xy 385.844828 -317.580929) (xy 385.875894 -317.541512) (xy 385.912986 -317.507705) (xy 385.955107 -317.480418)
			(xy 386.001122 -317.460384) (xy 386.049794 -317.448145) (xy 386.099812 -317.444028) (xy 386.14983 -317.448145)
			(xy 386.198502 -317.460384) (xy 386.244517 -317.480418) (xy 386.286638 -317.507705) (xy 386.32373 -317.541512)
			(xy 386.354796 -317.580929) (xy 386.378998 -317.624895) (xy 386.395686 -317.672227) (xy 386.400548 -317.69685)
			(xy 386.403596 -317.715138) (xy 386.43179 -317.73876) (xy 386.69595 -317.73876) (xy 386.724398 -317.71463)
			(xy 386.727446 -317.696342) (xy 386.732101 -317.671195) (xy 386.748191 -317.622654) (xy 386.771645 -317.577212)
			(xy 386.80189 -317.535977) (xy 386.838189 -317.499956) (xy 386.879655 -317.470028) (xy 386.925276 -317.446924)
			(xy 386.97394 -317.431208) (xy 387.024457 -317.423262) (xy 387.050026 -317.422784) (xy 387.084062 -317.424816)
			(xy 387.095746 -317.425832) (xy 387.117336 -317.418212) (xy 387.189472 -317.345314) (xy 387.197092 -317.323724)
			(xy 387.195568 -317.31204) (xy 387.1946 -317.302736) (xy 387.193582 -317.284056) (xy 387.193536 -317.274702)
			(xy 387.193536 -317.204344) (xy 387.193083 -317.193683) (xy 387.184404 -317.174209) (xy 387.176772 -317.166752)
			(xy 387.11251 -317.10884) (xy 387.092444 -317.102236) (xy 387.081522 -317.103506) (xy 387.050026 -317.10503)
			(xy 387.024765 -317.104539) (xy 386.974932 -317.096227) (xy 386.927146 -317.079826) (xy 386.882712 -317.055783)
			(xy 386.842842 -317.024754) (xy 386.808623 -316.987585) (xy 386.780989 -316.945291) (xy 386.760693 -316.899025)
			(xy 386.74829 -316.850049) (xy 386.744118 -316.7997) (xy 386.74829 -316.749351) (xy 386.760693 -316.700375)
			(xy 386.780989 -316.654109) (xy 386.808623 -316.611815) (xy 386.842842 -316.574646) (xy 386.882712 -316.543617)
			(xy 386.927146 -316.519574) (xy 386.974932 -316.503173) (xy 387.024765 -316.494861) (xy 387.050026 -316.494414)
			(xy 387.081522 -316.495938) (xy 387.092444 -316.497208) (xy 387.11251 -316.490604) (xy 387.176772 -316.432692)
			(xy 387.184278 -316.425146) (xy 387.192933 -316.405727) (xy 387.193536 -316.3951) (xy 387.193536 -316.324742)
			(xy 387.193698 -316.311088) (xy 387.195986 -316.283875) (xy 387.198108 -316.270386) (xy 387.199886 -316.258448)
			(xy 387.193028 -316.235842) (xy 387.12013 -316.159642) (xy 387.098032 -316.151514) (xy 387.08584 -316.153038)
			(xy 387.076918 -316.154001) (xy 387.059 -316.155019) (xy 387.050026 -316.15507) (xy 387.025208 -316.154586)
			(xy 386.976226 -316.146561) (xy 386.929188 -316.130716) (xy 386.885333 -316.107471) (xy 386.845816 -316.077436)
			(xy 386.811679 -316.041404) (xy 386.78382 -316.000325) (xy 386.762975 -315.955279) (xy 386.749691 -315.907454)
			(xy 386.74432 -315.858111) (xy 386.747002 -315.808548) (xy 386.757667 -315.760072) (xy 386.776035 -315.713961)
			(xy 386.80162 -315.671428) (xy 386.833749 -315.633594) (xy 386.871576 -315.601457) (xy 386.914103 -315.575863)
			(xy 386.960211 -315.557486) (xy 387.008685 -315.546811) (xy 387.058247 -315.544118) (xy 387.107591 -315.549479)
			(xy 387.155419 -315.562753) (xy 387.200469 -315.583589) (xy 387.241554 -315.611438) (xy 387.277593 -315.645568)
			(xy 387.307636 -315.685079) (xy 387.330891 -315.728929) (xy 387.346745 -315.775964) (xy 387.354781 -315.824945)
			(xy 387.355334 -315.849762) (xy 387.355288 -315.858799) (xy 387.354272 -315.876845) (xy 387.353302 -315.88583)
			(xy 387.351778 -315.898022) (xy 387.359652 -315.920374) (xy 387.436106 -315.993272) (xy 387.458712 -316.00013)
			(xy 387.47065 -315.998098) (xy 387.484017 -315.996052) (xy 387.510975 -315.993893) (xy 387.524498 -315.99378)
			(xy 387.533916 -315.993815) (xy 387.552724 -315.994829) (xy 387.56209 -315.995812) (xy 387.573774 -315.997336)
			(xy 387.595364 -315.989716) (xy 387.668262 -315.91758) (xy 387.676136 -315.89599) (xy 387.674866 -315.884306)
			(xy 387.673088 -315.849762) (xy 387.673595 -315.824074) (xy 387.681638 -315.77333) (xy 387.697519 -315.724469)
			(xy 387.720849 -315.678695) (xy 387.751052 -315.637133) (xy 387.787385 -315.600808) (xy 387.828953 -315.570614)
			(xy 387.874732 -315.547293) (xy 387.923596 -315.531422) (xy 387.974341 -315.523389) (xy 388.025718 -315.523394)
			(xy 388.076462 -315.531436) (xy 388.125323 -315.547316) (xy 388.171098 -315.570645) (xy 388.212661 -315.600847)
			(xy 388.248987 -315.637179) (xy 388.279182 -315.678746) (xy 388.302504 -315.724525) (xy 388.318376 -315.773388)
			(xy 388.32641 -315.824133) (xy 388.326406 -315.87551) (xy 388.318366 -315.926254) (xy 388.302487 -315.975116)
			(xy 388.279159 -316.020892) (xy 388.248958 -316.062455) (xy 388.212627 -316.098782) (xy 388.171061 -316.128978)
			(xy 388.125282 -316.1523) (xy 388.076419 -316.168174) (xy 388.025675 -316.176209) (xy 387.999986 -316.17666)
			(xy 387.965188 -316.174882) (xy 387.953504 -316.173612) (xy 387.931914 -316.181232) (xy 387.859524 -316.25413)
			(xy 387.851904 -316.27572) (xy 387.853428 -316.287404) (xy 387.854395 -316.296708) (xy 387.855411 -316.315388)
			(xy 387.85546 -316.324742) (xy 387.85546 -316.373256) (xy 387.855913 -316.383917) (xy 387.864591 -316.403391)
			(xy 387.872224 -316.410848) (xy 387.936232 -316.46876) (xy 387.956298 -316.475364) (xy 387.96722 -316.474348)
			(xy 387.999986 -316.472824) (xy 388.025676 -316.473301) (xy 388.076423 -316.481337) (xy 388.125289 -316.497213)
			(xy 388.171069 -316.520538) (xy 388.212636 -316.550739) (xy 388.248966 -316.58707) (xy 388.279166 -316.628638)
			(xy 388.30249 -316.674419) (xy 388.318365 -316.723284) (xy 388.3264 -316.774032) (xy 388.326884 -316.799722)
			(xy 388.326204 -316.831052) (xy 388.314315 -316.892573) (xy 388.303262 -316.921896) (xy 388.300006 -316.931159)
			(xy 388.300032 -316.950775) (xy 388.307428 -316.968943) (xy 388.321111 -316.983) (xy 388.339073 -316.990883)
			(xy 388.358681 -316.991439) (xy 388.368032 -316.988444) (xy 388.39648 -316.979554) (xy 388.40283 -316.977776)
			(xy 388.408418 -316.974474) (xy 388.41934 -316.966346) (xy 388.64667 -316.739016) (xy 388.653274 -316.727586)
			(xy 388.655052 -316.720982) (xy 388.662471 -316.695328) (xy 388.685011 -316.646918) (xy 388.715628 -316.603167)
			(xy 388.753389 -316.565409) (xy 388.797143 -316.534796) (xy 388.845555 -316.512261) (xy 388.871206 -316.504828)
			(xy 388.87781 -316.50305) (xy 388.88924 -316.496446) (xy 389.089138 -316.296548) (xy 389.09625 -316.282324)
			(xy 389.09752 -316.274196) (xy 389.098028 -316.270386) (xy 389.10006 -316.258448) (xy 389.093202 -316.235842)
			(xy 389.020304 -316.159388) (xy 388.997952 -316.151514) (xy 388.986014 -316.153038) (xy 388.97703 -316.15402)
			(xy 388.958984 -316.155036) (xy 388.949946 -316.15507) (xy 388.925128 -316.154588) (xy 388.876145 -316.146565)
			(xy 388.829105 -316.130723) (xy 388.785248 -316.10748) (xy 388.745729 -316.077447) (xy 388.711589 -316.041417)
			(xy 388.683728 -316.000338) (xy 388.66288 -315.955293) (xy 388.649594 -315.907468) (xy 388.64422 -315.858124)
			(xy 388.646901 -315.808561) (xy 388.657564 -315.760084) (xy 388.67593 -315.713971) (xy 388.701514 -315.671436)
			(xy 388.733642 -315.633601) (xy 388.771468 -315.601463) (xy 388.813995 -315.575867) (xy 388.860103 -315.557489)
			(xy 388.908577 -315.546812) (xy 388.95814 -315.544118) (xy 389.007486 -315.549478) (xy 389.055314 -315.562751)
			(xy 389.100365 -315.583586) (xy 389.141452 -315.611436) (xy 389.177491 -315.645566) (xy 389.207535 -315.685077)
			(xy 389.23079 -315.728928) (xy 389.246645 -315.775963) (xy 389.254681 -315.824944) (xy 389.255254 -315.849762)
			(xy 389.255156 -315.858866) (xy 389.254011 -315.877039) (xy 389.252968 -315.886084) (xy 389.251698 -315.898276)
			(xy 389.259572 -315.920374) (xy 389.336026 -315.993526) (xy 389.358378 -316.000384) (xy 389.37057 -315.998352)
			(xy 389.373872 -315.997844) (xy 389.382 -315.996574) (xy 389.396224 -315.989462) (xy 389.568944 -315.816742)
			(xy 389.576056 -315.802772) (xy 389.57758 -315.794898) (xy 389.582276 -315.770113) (xy 389.598282 -315.722278)
			(xy 389.621445 -315.677468) (xy 389.651215 -315.636748) (xy 389.686886 -315.601082) (xy 389.727612 -315.571319)
			(xy 389.772425 -315.548162) (xy 389.820263 -315.532163) (xy 389.845042 -315.527436) (xy 389.852916 -315.525912)
			(xy 389.866886 -315.5188) (xy 390.066276 -315.31941) (xy 390.074404 -315.308488) (xy 390.077706 -315.3029)
			(xy 390.079484 -315.29655) (xy 390.079484 -315.296296) (xy 390.083272 -315.282582) (xy 390.093066 -315.255868)
			(xy 390.099042 -315.242956) (xy 390.103086 -315.233314) (xy 390.103825 -315.21244) (xy 390.096176 -315.193004)
			(xy 390.08141 -315.178232) (xy 390.061976 -315.170578) (xy 390.041102 -315.171311) (xy 390.031478 -315.175392)
			(xy 390.010825 -315.184768) (xy 389.967444 -315.198002) (xy 389.922584 -315.204685) (xy 389.899906 -315.20511)
			(xy 389.874648 -315.204618) (xy 389.82482 -315.196304) (xy 389.777041 -315.179902) (xy 389.732613 -315.155859)
			(xy 389.692748 -315.124832) (xy 389.658533 -315.087666) (xy 389.630903 -315.045376) (xy 389.610611 -314.999114)
			(xy 389.59821 -314.950144) (xy 389.594038 -314.8998) (xy 389.59821 -314.849456) (xy 389.610611 -314.800486)
			(xy 389.630903 -314.754224) (xy 389.658533 -314.711934) (xy 389.692748 -314.674768) (xy 389.732613 -314.643741)
			(xy 389.777041 -314.619698) (xy 389.82482 -314.603296) (xy 389.874648 -314.594982) (xy 389.899906 -314.594494)
			(xy 389.908943 -314.594541) (xy 389.926988 -314.59556) (xy 389.935974 -314.596526) (xy 389.947912 -314.59805)
			(xy 389.970264 -314.590176) (xy 390.043162 -314.513722) (xy 390.050274 -314.491116) (xy 390.048242 -314.479178)
			(xy 390.04611 -314.46569) (xy 390.043821 -314.438477) (xy 390.04367 -314.424822) (xy 390.04367 -314.354464)
			(xy 390.043203 -314.343809) (xy 390.034507 -314.324355) (xy 390.026906 -314.316872) (xy 389.962644 -314.25896)
			(xy 389.942324 -314.252356) (xy 389.931656 -314.253626) (xy 389.899906 -314.25515) (xy 389.874644 -314.254658)
			(xy 389.82481 -314.246343) (xy 389.777025 -314.229939) (xy 389.732591 -314.205893) (xy 389.692721 -314.174862)
			(xy 389.658502 -314.137691) (xy 389.630868 -314.095395) (xy 389.610573 -314.049127) (xy 389.59817 -314.00015)
			(xy 389.593998 -313.9498) (xy 389.59817 -313.89945) (xy 389.610573 -313.850473) (xy 389.630868 -313.804205)
			(xy 389.658502 -313.761909) (xy 389.692721 -313.724738) (xy 389.732591 -313.693707) (xy 389.777025 -313.669661)
			(xy 389.82481 -313.653257) (xy 389.874644 -313.644942) (xy 389.899906 -313.644534) (xy 389.931656 -313.646058)
			(xy 389.942324 -313.647328) (xy 389.962644 -313.640724) (xy 390.026906 -313.582812) (xy 390.034411 -313.575265)
			(xy 390.043067 -313.555847) (xy 390.04367 -313.54522) (xy 390.04367 -313.474862) (xy 390.043831 -313.461208)
			(xy 390.046118 -313.433995) (xy 390.048242 -313.420506) (xy 390.05002 -313.408568) (xy 390.043162 -313.385962)
			(xy 389.970264 -313.309508) (xy 389.947912 -313.301634) (xy 389.935974 -313.303158) (xy 389.92699 -313.304139)
			(xy 389.908944 -313.305153) (xy 389.899906 -313.30519) (xy 389.875087 -313.304705) (xy 389.826102 -313.296675)
			(xy 389.779062 -313.280827) (xy 389.735205 -313.257577) (xy 389.695688 -313.227538) (xy 389.66155 -313.191501)
			(xy 389.633693 -313.150417) (xy 389.612849 -313.105367) (xy 389.599568 -313.057538) (xy 389.594199 -313.008191)
			(xy 389.596885 -312.958626) (xy 389.607554 -312.910147) (xy 389.625926 -312.864034) (xy 389.651515 -312.8215)
			(xy 389.683649 -312.783666) (xy 389.72148 -312.751529) (xy 389.764012 -312.725936) (xy 389.810124 -312.707561)
			(xy 389.858602 -312.696888) (xy 389.908167 -312.694199) (xy 389.957515 -312.699563) (xy 390.005344 -312.712841)
			(xy 390.050396 -312.733681) (xy 390.091483 -312.761535) (xy 390.127522 -312.79567) (xy 390.157564 -312.835185)
			(xy 390.180817 -312.87904) (xy 390.196669 -312.926079) (xy 390.204703 -312.975063) (xy 390.205214 -312.999882)
			(xy 390.205175 -313.008983) (xy 390.20416 -313.027156) (xy 390.203182 -313.036204) (xy 390.201658 -313.048142)
			(xy 390.209532 -313.070494) (xy 390.285986 -313.143392) (xy 390.308592 -313.15025) (xy 390.32053 -313.148472)
			(xy 390.333956 -313.146354) (xy 390.361041 -313.144065) (xy 390.374632 -313.1439) (xy 390.383014 -313.1439)
			(xy 390.392412 -313.144408) (xy 390.412224 -313.146186) (xy 390.423654 -313.147456) (xy 390.445498 -313.139836)
			(xy 390.518142 -313.0677) (xy 390.526016 -313.04611) (xy 390.524746 -313.034426) (xy 390.522968 -312.999882)
			(xy 390.523447 -312.974189) (xy 390.531488 -312.923437) (xy 390.54737 -312.874567) (xy 390.570701 -312.828784)
			(xy 390.600908 -312.787214) (xy 390.637245 -312.750881) (xy 390.678819 -312.72068) (xy 390.724605 -312.697354)
			(xy 390.773477 -312.681479) (xy 390.824231 -312.673444) (xy 390.875616 -312.673447) (xy 390.926368 -312.68149)
			(xy 390.975238 -312.697372) (xy 391.021021 -312.720704) (xy 391.06259 -312.750911) (xy 391.098923 -312.787249)
			(xy 391.129123 -312.828823) (xy 391.152448 -312.87461) (xy 391.168323 -312.923482) (xy 391.176357 -312.974236)
			(xy 391.176352 -313.025621) (xy 391.168309 -313.076374) (xy 391.152426 -313.125243) (xy 391.129093 -313.171026)
			(xy 391.098885 -313.212595) (xy 391.062547 -313.248926) (xy 391.020972 -313.279126) (xy 390.975185 -313.30245)
			(xy 390.926313 -313.318324) (xy 390.875559 -313.326357) (xy 390.849866 -313.32678) (xy 390.815322 -313.325002)
			(xy 390.803638 -313.323732) (xy 390.782048 -313.331606) (xy 390.709658 -313.40425) (xy 390.702292 -313.42584)
			(xy 390.703562 -313.437524) (xy 390.704529 -313.446828) (xy 390.705543 -313.465508) (xy 390.705594 -313.474862)
			(xy 390.705594 -313.523376) (xy 390.706048 -313.534037) (xy 390.714724 -313.553513) (xy 390.722358 -313.560968)
			(xy 390.786112 -313.61888) (xy 390.806432 -313.625484) (xy 390.817354 -313.624468) (xy 390.849866 -313.622944)
			(xy 390.875556 -313.623419) (xy 390.926305 -313.631453) (xy 390.975172 -313.647328) (xy 391.020953 -313.670652)
			(xy 391.062521 -313.700853) (xy 391.098852 -313.737185) (xy 391.129052 -313.778754) (xy 391.152375 -313.824536)
			(xy 391.168249 -313.873403) (xy 391.176281 -313.924152) (xy 391.176764 -313.949842) (xy 391.174986 -313.984386)
			(xy 391.173716 -313.99607) (xy 391.18159 -314.01766) (xy 391.254234 -314.09005) (xy 391.275824 -314.097416)
			(xy 391.287508 -314.096146) (xy 391.310425 -314.093977) (xy 391.35644 -314.095252) (xy 391.379202 -314.098686)
			(xy 391.39114 -314.100718) (xy 391.413746 -314.093606) (xy 391.4902 -314.020708) (xy 391.498074 -313.998356)
			(xy 391.496804 -313.986164) (xy 391.495754 -313.97712) (xy 391.494608 -313.958946) (xy 391.494518 -313.949842)
			(xy 391.494961 -313.925847) (xy 391.502463 -313.878448) (xy 391.517288 -313.832807) (xy 391.539071 -313.790047)
			(xy 391.567277 -313.751221) (xy 391.601209 -313.717287) (xy 391.640033 -313.68908) (xy 391.682792 -313.667294)
			(xy 391.728433 -313.652466) (xy 391.775831 -313.644962) (xy 391.799826 -313.644534) (xy 391.831576 -313.646312)
			(xy 391.842498 -313.647328) (xy 391.862818 -313.640724) (xy 391.92708 -313.582812) (xy 391.934589 -313.575267)
			(xy 391.943249 -313.555848) (xy 391.943844 -313.54522) (xy 391.943844 -313.474862) (xy 391.944005 -313.461208)
			(xy 391.946292 -313.433995) (xy 391.948416 -313.420506) (xy 391.950448 -313.408568) (xy 391.943336 -313.385962)
			(xy 391.870438 -313.309508) (xy 391.848086 -313.301634) (xy 391.836148 -313.303158) (xy 391.827101 -313.304147)
			(xy 391.808927 -313.305163) (xy 391.799826 -313.30519) (xy 391.775006 -313.304706) (xy 391.726021 -313.29668)
			(xy 391.678979 -313.280834) (xy 391.63512 -313.257586) (xy 391.5956 -313.227549) (xy 391.561461 -313.191514)
			(xy 391.533601 -313.150431) (xy 391.512754 -313.105381) (xy 391.499471 -313.057552) (xy 391.4941 -313.008205)
			(xy 391.496783 -312.958638) (xy 391.507451 -312.910159) (xy 391.525821 -312.864044) (xy 391.551409 -312.821508)
			(xy 391.583542 -312.783673) (xy 391.621373 -312.751535) (xy 391.663904 -312.72594) (xy 391.710017 -312.707564)
			(xy 391.758495 -312.696889) (xy 391.808061 -312.694199) (xy 391.857409 -312.699562) (xy 391.90524 -312.712839)
			(xy 391.950292 -312.733679) (xy 391.99138 -312.761533) (xy 392.02742 -312.795667) (xy 392.057462 -312.835183)
			(xy 392.080716 -312.879038) (xy 392.096569 -312.926078) (xy 392.104603 -312.975063) (xy 392.105134 -312.999882)
			(xy 392.105095 -313.008983) (xy 392.10408 -313.027156) (xy 392.103102 -313.036204) (xy 392.101578 -313.048142)
			(xy 392.109452 -313.070494) (xy 392.185906 -313.143392) (xy 392.208512 -313.150504) (xy 392.22045 -313.148472)
			(xy 392.233938 -313.146342) (xy 392.261151 -313.144053) (xy 392.274806 -313.1439) (xy 392.28416 -313.143943)
			(xy 392.30284 -313.144962) (xy 392.312144 -313.145932) (xy 392.323828 -313.147202) (xy 392.345418 -313.139836)
			(xy 392.418062 -313.067446) (xy 392.425936 -313.045856) (xy 392.424666 -313.034426) (xy 392.422888 -312.999882)
			(xy 392.423393 -312.974193) (xy 392.431433 -312.923449) (xy 392.447312 -312.874586) (xy 392.47064 -312.82881)
			(xy 392.500841 -312.787246) (xy 392.537172 -312.750919) (xy 392.578739 -312.720722) (xy 392.624518 -312.697399)
			(xy 392.673382 -312.681525) (xy 392.724128 -312.673491) (xy 392.775505 -312.673493) (xy 392.82625 -312.681533)
			(xy 392.875112 -312.697412) (xy 392.920889 -312.720739) (xy 392.962453 -312.75094) (xy 392.998781 -312.787271)
			(xy 393.028978 -312.828838) (xy 393.0523 -312.874617) (xy 393.068175 -312.923481) (xy 393.076209 -312.974226)
			(xy 393.076207 -313.025604) (xy 393.068167 -313.076349) (xy 393.052289 -313.125211) (xy 393.028962 -313.170988)
			(xy 392.998761 -313.212552) (xy 392.96243 -313.24888) (xy 392.920863 -313.279077) (xy 392.875084 -313.3024)
			(xy 392.82622 -313.318274) (xy 392.775475 -313.326309) (xy 392.749786 -313.32678) (xy 392.715242 -313.325002)
			(xy 392.703812 -313.323732) (xy 392.682222 -313.331606) (xy 392.609832 -313.40425) (xy 392.602466 -313.42584)
			(xy 392.603736 -313.437524) (xy 392.604703 -313.446828) (xy 392.605717 -313.465508) (xy 392.605768 -313.474862)
			(xy 392.605768 -313.523376) (xy 392.606222 -313.534038) (xy 392.614894 -313.553516) (xy 392.622532 -313.560968)
			(xy 392.686286 -313.61888) (xy 392.706606 -313.625484) (xy 392.717528 -313.624468) (xy 392.749786 -313.622944)
			(xy 392.775475 -313.623421) (xy 392.826222 -313.631457) (xy 392.875086 -313.647333) (xy 392.920864 -313.670659)
			(xy 392.96243 -313.70086) (xy 392.998758 -313.737192) (xy 393.028955 -313.77876) (xy 393.052277 -313.82454)
			(xy 393.06815 -313.873406) (xy 393.076181 -313.924153) (xy 393.076684 -313.949842) (xy 393.074906 -313.98464)
			(xy 393.073636 -313.99607) (xy 393.08151 -314.01766) (xy 393.154154 -314.09005) (xy 393.175998 -314.09767)
			(xy 393.187428 -314.096146) (xy 393.210409 -314.093978) (xy 393.25655 -314.095255) (xy 393.279376 -314.098686)
			(xy 393.291314 -314.100718) (xy 393.31392 -314.093606) (xy 393.390374 -314.020708) (xy 393.398248 -313.998356)
			(xy 393.396978 -313.986164) (xy 393.395928 -313.97712) (xy 393.394782 -313.958946) (xy 393.394692 -313.949842)
			(xy 393.395135 -313.925847) (xy 393.402637 -313.878446) (xy 393.417461 -313.832803) (xy 393.439245 -313.790041)
			(xy 393.467449 -313.751213) (xy 393.501381 -313.717277) (xy 393.540205 -313.689066) (xy 393.582964 -313.667278)
			(xy 393.628605 -313.652446) (xy 393.676005 -313.644938) (xy 393.7 -313.644534) (xy 393.73175 -313.646058)
			(xy 393.742418 -313.647328) (xy 393.762738 -313.640724) (xy 393.827 -313.582812) (xy 393.834506 -313.575266)
			(xy 393.843163 -313.555847) (xy 393.843764 -313.54522) (xy 393.843764 -313.474862) (xy 393.843925 -313.461208)
			(xy 393.846212 -313.433995) (xy 393.848336 -313.420506) (xy 393.850114 -313.408568) (xy 393.843256 -313.385962)
			(xy 393.770358 -313.309508) (xy 393.748006 -313.301634) (xy 393.736068 -313.303158) (xy 393.727084 -313.304142)
			(xy 393.709038 -313.305161) (xy 393.7 -313.30519) (xy 393.675181 -313.304704) (xy 393.626197 -313.296674)
			(xy 393.579157 -313.280824) (xy 393.535301 -313.257574) (xy 393.495784 -313.227534) (xy 393.461647 -313.191498)
			(xy 393.433791 -313.150413) (xy 393.412947 -313.105363) (xy 393.399667 -313.057534) (xy 393.394299 -313.008187)
			(xy 393.396986 -312.958622) (xy 393.407655 -312.910144) (xy 393.426027 -312.864031) (xy 393.451617 -312.821497)
			(xy 393.483751 -312.783664) (xy 393.521583 -312.751528) (xy 393.564115 -312.725935) (xy 393.610227 -312.707561)
			(xy 393.658704 -312.696888) (xy 393.708269 -312.694199) (xy 393.757617 -312.699564) (xy 393.805446 -312.712841)
			(xy 393.850497 -312.733682) (xy 393.891584 -312.761536) (xy 393.927622 -312.79567) (xy 393.957664 -312.835186)
			(xy 393.980917 -312.87904) (xy 393.996769 -312.926079) (xy 394.004803 -312.975063) (xy 394.005308 -312.999882)
			(xy 394.005269 -313.008983) (xy 394.004254 -313.027156) (xy 394.003276 -313.036204) (xy 394.001752 -313.048142)
			(xy 394.009626 -313.070494) (xy 394.08608 -313.143392) (xy 394.108686 -313.15025) (xy 394.120624 -313.148472)
			(xy 394.13405 -313.146354) (xy 394.161135 -313.144064) (xy 394.174726 -313.1439) (xy 394.184144 -313.143936)
			(xy 394.202951 -313.144951) (xy 394.212318 -313.145932) (xy 394.223748 -313.147456) (xy 394.245338 -313.139836)
			(xy 394.318236 -313.067446) (xy 394.32611 -313.04611) (xy 394.32484 -313.034426) (xy 394.322808 -312.999882)
			(xy 394.323313 -312.974199) (xy 394.331349 -312.923467) (xy 394.347222 -312.874615) (xy 394.37054 -312.828848)
			(xy 394.40073 -312.78729) (xy 394.437047 -312.750966) (xy 394.478599 -312.72077) (xy 394.524363 -312.697444)
			(xy 394.573211 -312.681563) (xy 394.623943 -312.673517) (xy 394.675308 -312.673506) (xy 394.726043 -312.681528)
			(xy 394.774899 -312.697387) (xy 394.820673 -312.720692) (xy 394.862239 -312.750869) (xy 394.898573 -312.787177)
			(xy 394.928782 -312.82872) (xy 394.952121 -312.874477) (xy 394.968016 -312.923321) (xy 394.976075 -312.97405)
			(xy 394.976102 -313.025416) (xy 394.968094 -313.076153) (xy 394.952249 -313.125013) (xy 394.928957 -313.170794)
			(xy 394.898791 -313.212368) (xy 394.862494 -313.248713) (xy 394.820959 -313.278933) (xy 394.775209 -313.302285)
			(xy 394.726369 -313.318194) (xy 394.675642 -313.326268) (xy 394.64996 -313.32678) (xy 394.615416 -313.325002)
			(xy 394.603732 -313.323732) (xy 394.582142 -313.331606) (xy 394.510006 -313.40425) (xy 394.502386 -313.42584)
			(xy 394.503656 -313.437524) (xy 394.505688 -313.465718) (xy 394.505688 -313.523376) (xy 394.506142 -313.534038)
			(xy 394.514817 -313.553514) (xy 394.522452 -313.560968) (xy 394.586206 -313.61888) (xy 394.606526 -313.625484)
			(xy 394.617448 -313.624468) (xy 394.64996 -313.622944) (xy 394.675657 -313.623444) (xy 394.72642 -313.631474)
			(xy 394.775303 -313.647344) (xy 394.821104 -313.670661) (xy 394.862694 -313.700854) (xy 394.899052 -313.737179)
			(xy 394.929283 -313.778742) (xy 394.952642 -313.824521) (xy 394.968556 -313.873389) (xy 394.976632 -313.924145)
			(xy 394.977112 -313.949842) (xy 394.97508 -313.984386) (xy 394.97381 -313.99607) (xy 394.981684 -314.01766)
			(xy 395.054328 -314.09005) (xy 395.075918 -314.097416) (xy 395.087602 -314.096146) (xy 395.110519 -314.093976)
			(xy 395.156534 -314.095251) (xy 395.179296 -314.098686) (xy 395.191234 -314.100718) (xy 395.21384 -314.093606)
			(xy 395.290294 -314.020708) (xy 395.298168 -313.998356) (xy 395.296898 -313.986164) (xy 395.295848 -313.97712)
			(xy 395.294702 -313.958946) (xy 395.294612 -313.949842) (xy 395.295055 -313.925847) (xy 395.302557 -313.878448)
			(xy 395.317382 -313.832806) (xy 395.339165 -313.790045) (xy 395.36737 -313.75122) (xy 395.401303 -313.717285)
			(xy 395.440127 -313.689077) (xy 395.482886 -313.66729) (xy 395.528526 -313.652462) (xy 395.575925 -313.644957)
			(xy 395.59992 -313.644534) (xy 395.63167 -313.646058) (xy 395.642338 -313.647328) (xy 395.662658 -313.640724)
			(xy 395.72692 -313.582812) (xy 395.734424 -313.575264) (xy 395.743077 -313.555846) (xy 395.743684 -313.54522)
			(xy 395.743684 -313.474862) (xy 395.743845 -313.461208) (xy 395.746132 -313.433995) (xy 395.748256 -313.420506)
			(xy 395.750034 -313.408568) (xy 395.743176 -313.385962) (xy 395.670278 -313.309508) (xy 395.647926 -313.301634)
			(xy 395.635988 -313.303158) (xy 395.627004 -313.304139) (xy 395.608958 -313.305154) (xy 395.59992 -313.30519)
			(xy 395.575101 -313.304706) (xy 395.526115 -313.296678) (xy 395.479074 -313.280832) (xy 395.435216 -313.257583)
			(xy 395.395697 -313.227546) (xy 395.361558 -313.19151) (xy 395.333698 -313.150426) (xy 395.312853 -313.105377)
			(xy 395.29957 -313.057548) (xy 395.2942 -313.008201) (xy 395.296884 -312.958634) (xy 395.307552 -312.910155)
			(xy 395.325922 -312.864041) (xy 395.351511 -312.821506) (xy 395.383644 -312.783671) (xy 395.421475 -312.751533)
			(xy 395.464007 -312.725939) (xy 395.510119 -312.707563) (xy 395.558597 -312.696889) (xy 395.608163 -312.694199)
			(xy 395.657511 -312.699563) (xy 395.705341 -312.712839) (xy 395.750393 -312.73368) (xy 395.791481 -312.761534)
			(xy 395.82752 -312.795668) (xy 395.857563 -312.835184) (xy 395.880817 -312.879039) (xy 395.896669 -312.926078)
			(xy 395.904703 -312.975063) (xy 395.905228 -312.999882) (xy 395.905189 -313.008983) (xy 395.904173 -313.027156)
			(xy 395.903196 -313.036204) (xy 395.901672 -313.048142) (xy 395.909546 -313.070494) (xy 395.986 -313.143392)
			(xy 396.008606 -313.15025) (xy 396.020544 -313.148472) (xy 396.03397 -313.146355) (xy 396.061055 -313.144067)
			(xy 396.074646 -313.1439) (xy 396.084064 -313.143936) (xy 396.102871 -313.144953) (xy 396.112238 -313.145932)
			(xy 396.123668 -313.147456) (xy 396.145258 -313.139836) (xy 396.218156 -313.067446) (xy 396.22603 -313.04611)
			(xy 396.22476 -313.034426) (xy 396.222728 -312.999882) (xy 396.223233 -312.974201) (xy 396.231269 -312.923472)
			(xy 396.24714 -312.874624) (xy 396.270456 -312.82886) (xy 396.300643 -312.787306) (xy 396.336957 -312.750984)
			(xy 396.378506 -312.720789) (xy 396.424266 -312.697464) (xy 396.473111 -312.681584) (xy 396.523838 -312.673538)
			(xy 396.5752 -312.673525) (xy 396.625931 -312.681545) (xy 396.674784 -312.697402) (xy 396.720555 -312.720704)
			(xy 396.762119 -312.750878) (xy 396.798451 -312.787182) (xy 396.828659 -312.828721) (xy 396.851998 -312.874474)
			(xy 396.867893 -312.923314) (xy 396.875954 -312.974039) (xy 396.875983 -313.0254) (xy 396.867978 -313.076134)
			(xy 396.852136 -313.124992) (xy 396.828848 -313.17077) (xy 396.798686 -313.212343) (xy 396.762394 -313.248687)
			(xy 396.720864 -313.278907) (xy 396.675118 -313.302259) (xy 396.626283 -313.31817) (xy 396.57556 -313.326247)
			(xy 396.54988 -313.32678) (xy 396.515336 -313.325002) (xy 396.503652 -313.323732) (xy 396.482062 -313.331606)
			(xy 396.409926 -313.40425) (xy 396.402306 -313.42584) (xy 396.403576 -313.437524) (xy 396.405608 -313.465718)
			(xy 396.405608 -313.523376) (xy 396.406063 -313.534037) (xy 396.414741 -313.553511) (xy 396.422372 -313.560968)
			(xy 396.486126 -313.61888) (xy 396.506446 -313.625484) (xy 396.517368 -313.624468) (xy 396.54988 -313.622944)
			(xy 396.575576 -313.623446) (xy 396.626337 -313.631478) (xy 396.675217 -313.647349) (xy 396.721015 -313.670668)
			(xy 396.762603 -313.700861) (xy 396.798958 -313.737186) (xy 396.829186 -313.778748) (xy 396.852544 -313.824526)
			(xy 396.868457 -313.873392) (xy 396.876532 -313.924146) (xy 396.877032 -313.949842) (xy 396.875 -313.984386)
			(xy 396.87373 -313.99607) (xy 396.881604 -314.01766) (xy 396.954248 -314.09005) (xy 396.975838 -314.097416)
			(xy 396.987522 -314.096146) (xy 397.010439 -314.093978) (xy 397.056453 -314.095255) (xy 397.079216 -314.098686)
			(xy 397.091154 -314.100718) (xy 397.11376 -314.093606) (xy 397.190214 -314.020708) (xy 397.198088 -313.998356)
			(xy 397.196818 -313.986164) (xy 397.195769 -313.97712) (xy 397.194622 -313.958946) (xy 397.194532 -313.949842)
			(xy 397.194975 -313.925848) (xy 397.202477 -313.87845) (xy 397.217302 -313.832809) (xy 397.239086 -313.79005)
			(xy 397.267292 -313.751226) (xy 397.301224 -313.717293) (xy 397.340048 -313.689087) (xy 397.382807 -313.667303)
			(xy 397.428448 -313.652477) (xy 397.475846 -313.644975) (xy 397.49984 -313.644534) (xy 397.531844 -313.646312)
			(xy 397.542766 -313.647328) (xy 397.563086 -313.640724) (xy 397.627348 -313.583066) (xy 397.635004 -313.575548)
			(xy 397.643676 -313.555942) (xy 397.644112 -313.54522) (xy 397.644112 -313.474862) (xy 397.644273 -313.461208)
			(xy 397.64656 -313.433995) (xy 397.648684 -313.420506) (xy 397.650716 -313.408568) (xy 397.643604 -313.385962)
			(xy 397.570706 -313.309508) (xy 397.548354 -313.301634) (xy 397.536162 -313.302904) (xy 397.527118 -313.303954)
			(xy 397.508944 -313.3051) (xy 397.49984 -313.30519) (xy 397.47502 -313.304707) (xy 397.426034 -313.296683)
			(xy 397.37899 -313.280839) (xy 397.33513 -313.257593) (xy 397.295609 -313.227557) (xy 397.261468 -313.191523)
			(xy 397.233606 -313.15044) (xy 397.212758 -313.105391) (xy 397.199472 -313.057562) (xy 397.1941 -313.008214)
			(xy 397.196782 -312.958647) (xy 397.207448 -312.910167) (xy 397.225817 -312.864051) (xy 397.251405 -312.821515)
			(xy 397.283537 -312.783678) (xy 397.321367 -312.751539) (xy 397.363899 -312.725943) (xy 397.410011 -312.707565)
			(xy 397.458489 -312.69689) (xy 397.508056 -312.694198) (xy 397.557405 -312.699561) (xy 397.605236 -312.712838)
			(xy 397.650289 -312.733677) (xy 397.691378 -312.761531) (xy 397.727418 -312.795666) (xy 397.757461 -312.835181)
			(xy 397.780716 -312.879037) (xy 397.796569 -312.926077) (xy 397.804603 -312.975062) (xy 397.805148 -312.999882)
			(xy 397.805049 -313.008986) (xy 397.803903 -313.027159) (xy 397.802862 -313.036204) (xy 397.801592 -313.048396)
			(xy 397.809466 -313.070748) (xy 397.88592 -313.143646) (xy 397.908526 -313.150758) (xy 397.920464 -313.148726)
			(xy 397.933952 -313.146596) (xy 397.961166 -313.14431) (xy 397.97482 -313.144154) (xy 397.984174 -313.144198)
			(xy 398.002854 -313.145215) (xy 398.012158 -313.146186) (xy 398.023842 -313.14771) (xy 398.045432 -313.14009)
			(xy 398.118076 -313.0677) (xy 398.12595 -313.04611) (xy 398.12468 -313.034426) (xy 398.122648 -312.999882)
			(xy 398.123153 -312.974203) (xy 398.131188 -312.923478) (xy 398.147058 -312.874634) (xy 398.170372 -312.828872)
			(xy 398.200556 -312.787321) (xy 398.236868 -312.751002) (xy 398.278413 -312.720808) (xy 398.324169 -312.697485)
			(xy 398.37301 -312.681604) (xy 398.423733 -312.673558) (xy 398.475091 -312.673544) (xy 398.525819 -312.681563)
			(xy 398.574668 -312.697417) (xy 398.620437 -312.720716) (xy 398.661998 -312.750887) (xy 398.698329 -312.787187)
			(xy 398.728536 -312.828722) (xy 398.751875 -312.874471) (xy 398.767771 -312.923306) (xy 398.775833 -312.974027)
			(xy 398.775849 -312.999882) (xy 399.09421 -312.999882) (xy 399.09817 -312.950828) (xy 399.109947 -312.903044)
			(xy 399.129238 -312.857768) (xy 399.155541 -312.816172) (xy 399.188176 -312.779335) (xy 399.226297 -312.74821)
			(xy 399.268918 -312.723603) (xy 399.314934 -312.706151) (xy 399.363153 -312.696307) (xy 399.412328 -312.694326)
			(xy 399.461183 -312.700258) (xy 399.508454 -312.71395) (xy 399.552916 -312.735048) (xy 399.593419 -312.763004)
			(xy 399.628912 -312.797096) (xy 399.658477 -312.83644) (xy 399.681348 -312.880017) (xy 399.696932 -312.926698)
			(xy 399.704827 -312.975275) (xy 399.705322 -312.999882) (xy 399.704827 -313.024489) (xy 399.704648 -313.02559)
			(xy 400.023326 -313.02559) (xy 400.023326 -312.974174) (xy 400.031369 -312.923392) (xy 400.047257 -312.874493)
			(xy 400.0706 -312.828681) (xy 400.100821 -312.787085) (xy 400.137177 -312.750729) (xy 400.178773 -312.720508)
			(xy 400.224585 -312.697165) (xy 400.273484 -312.681277) (xy 400.324266 -312.673234) (xy 400.375682 -312.673234)
			(xy 400.426464 -312.681277) (xy 400.475363 -312.697165) (xy 400.521175 -312.720508) (xy 400.562771 -312.750729)
			(xy 400.599127 -312.787085) (xy 400.629348 -312.828681) (xy 400.652691 -312.874493) (xy 400.668579 -312.923392)
			(xy 400.676622 -312.974174) (xy 400.677126 -312.999882) (xy 400.99413 -312.999882) (xy 400.99809 -312.950828)
			(xy 401.009867 -312.903044) (xy 401.029158 -312.857768) (xy 401.055461 -312.816172) (xy 401.088096 -312.779335)
			(xy 401.126217 -312.74821) (xy 401.168838 -312.723603) (xy 401.214854 -312.706151) (xy 401.263073 -312.696307)
			(xy 401.312248 -312.694326) (xy 401.361103 -312.700258) (xy 401.408374 -312.71395) (xy 401.452836 -312.735048)
			(xy 401.493339 -312.763004) (xy 401.528832 -312.797096) (xy 401.558397 -312.83644) (xy 401.581268 -312.880017)
			(xy 401.596852 -312.926698) (xy 401.604747 -312.975275) (xy 401.605242 -312.999882) (xy 401.604747 -313.024489)
			(xy 401.604568 -313.02559) (xy 401.923246 -313.02559) (xy 401.923246 -312.974174) (xy 401.931289 -312.923392)
			(xy 401.947177 -312.874493) (xy 401.97052 -312.828681) (xy 402.000741 -312.787085) (xy 402.037097 -312.750729)
			(xy 402.078693 -312.720508) (xy 402.124505 -312.697165) (xy 402.173404 -312.681277) (xy 402.224186 -312.673234)
			(xy 402.275602 -312.673234) (xy 402.326384 -312.681277) (xy 402.375283 -312.697165) (xy 402.421095 -312.720508)
			(xy 402.462691 -312.750729) (xy 402.499047 -312.787085) (xy 402.529268 -312.828681) (xy 402.552611 -312.874493)
			(xy 402.568499 -312.923392) (xy 402.576542 -312.974174) (xy 402.577046 -312.999882) (xy 402.89405 -312.999882)
			(xy 402.89801 -312.950828) (xy 402.909787 -312.903044) (xy 402.929078 -312.857768) (xy 402.955381 -312.816172)
			(xy 402.988016 -312.779335) (xy 403.026137 -312.74821) (xy 403.068758 -312.723603) (xy 403.114774 -312.706151)
			(xy 403.162993 -312.696307) (xy 403.212168 -312.694326) (xy 403.261023 -312.700258) (xy 403.308294 -312.71395)
			(xy 403.352756 -312.735048) (xy 403.393259 -312.763004) (xy 403.428752 -312.797096) (xy 403.458317 -312.83644)
			(xy 403.481188 -312.880017) (xy 403.496772 -312.926698) (xy 403.504667 -312.975275) (xy 403.505162 -312.999882)
			(xy 403.504667 -313.024489) (xy 403.504488 -313.02559) (xy 403.823166 -313.02559) (xy 403.823166 -312.974174)
			(xy 403.831209 -312.923392) (xy 403.847097 -312.874493) (xy 403.87044 -312.828681) (xy 403.900661 -312.787085)
			(xy 403.937017 -312.750729) (xy 403.978613 -312.720508) (xy 404.024425 -312.697165) (xy 404.073324 -312.681277)
			(xy 404.124106 -312.673234) (xy 404.175522 -312.673234) (xy 404.226304 -312.681277) (xy 404.275203 -312.697165)
			(xy 404.321015 -312.720508) (xy 404.362611 -312.750729) (xy 404.398967 -312.787085) (xy 404.429188 -312.828681)
			(xy 404.452531 -312.874493) (xy 404.468419 -312.923392) (xy 404.476462 -312.974174) (xy 404.476966 -312.999882)
			(xy 404.476462 -313.02559) (xy 404.468419 -313.076372) (xy 404.452531 -313.125271) (xy 404.429188 -313.171083)
			(xy 404.398967 -313.212679) (xy 404.362611 -313.249035) (xy 404.321015 -313.279256) (xy 404.275203 -313.302599)
			(xy 404.226304 -313.318487) (xy 404.175522 -313.32653) (xy 404.124106 -313.32653) (xy 404.073324 -313.318487)
			(xy 404.024425 -313.302599) (xy 403.978613 -313.279256) (xy 403.937017 -313.249035) (xy 403.900661 -313.212679)
			(xy 403.87044 -313.171083) (xy 403.847097 -313.125271) (xy 403.831209 -313.076372) (xy 403.823166 -313.02559)
			(xy 403.504488 -313.02559) (xy 403.496772 -313.073066) (xy 403.481188 -313.119747) (xy 403.458317 -313.163324)
			(xy 403.428752 -313.202668) (xy 403.393259 -313.23676) (xy 403.352756 -313.264716) (xy 403.308294 -313.285814)
			(xy 403.261023 -313.299506) (xy 403.212168 -313.305438) (xy 403.162993 -313.303457) (xy 403.114774 -313.293613)
			(xy 403.068758 -313.276161) (xy 403.026137 -313.251554) (xy 402.988016 -313.220429) (xy 402.955381 -313.183592)
			(xy 402.929078 -313.141996) (xy 402.909787 -313.09672) (xy 402.89801 -313.048936) (xy 402.89405 -312.999882)
			(xy 402.577046 -312.999882) (xy 402.576542 -313.02559) (xy 402.568499 -313.076372) (xy 402.552611 -313.125271)
			(xy 402.529268 -313.171083) (xy 402.499047 -313.212679) (xy 402.462691 -313.249035) (xy 402.421095 -313.279256)
			(xy 402.375283 -313.302599) (xy 402.326384 -313.318487) (xy 402.275602 -313.32653) (xy 402.224186 -313.32653)
			(xy 402.173404 -313.318487) (xy 402.124505 -313.302599) (xy 402.078693 -313.279256) (xy 402.037097 -313.249035)
			(xy 402.000741 -313.212679) (xy 401.97052 -313.171083) (xy 401.947177 -313.125271) (xy 401.931289 -313.076372)
			(xy 401.923246 -313.02559) (xy 401.604568 -313.02559) (xy 401.596852 -313.073066) (xy 401.581268 -313.119747)
			(xy 401.558397 -313.163324) (xy 401.528832 -313.202668) (xy 401.493339 -313.23676) (xy 401.452836 -313.264716)
			(xy 401.408374 -313.285814) (xy 401.361103 -313.299506) (xy 401.312248 -313.305438) (xy 401.263073 -313.303457)
			(xy 401.214854 -313.293613) (xy 401.168838 -313.276161) (xy 401.126217 -313.251554) (xy 401.088096 -313.220429)
			(xy 401.055461 -313.183592) (xy 401.029158 -313.141996) (xy 401.009867 -313.09672) (xy 400.99809 -313.048936)
			(xy 400.99413 -312.999882) (xy 400.677126 -312.999882) (xy 400.676622 -313.02559) (xy 400.668579 -313.076372)
			(xy 400.652691 -313.125271) (xy 400.629348 -313.171083) (xy 400.599127 -313.212679) (xy 400.562771 -313.249035)
			(xy 400.521175 -313.279256) (xy 400.475363 -313.302599) (xy 400.426464 -313.318487) (xy 400.375682 -313.32653)
			(xy 400.324266 -313.32653) (xy 400.273484 -313.318487) (xy 400.224585 -313.302599) (xy 400.178773 -313.279256)
			(xy 400.137177 -313.249035) (xy 400.100821 -313.212679) (xy 400.0706 -313.171083) (xy 400.047257 -313.125271)
			(xy 400.031369 -313.076372) (xy 400.023326 -313.02559) (xy 399.704648 -313.02559) (xy 399.696932 -313.073066)
			(xy 399.681348 -313.119747) (xy 399.658477 -313.163324) (xy 399.628912 -313.202668) (xy 399.593419 -313.23676)
			(xy 399.552916 -313.264716) (xy 399.508454 -313.285814) (xy 399.461183 -313.299506) (xy 399.412328 -313.305438)
			(xy 399.363153 -313.303457) (xy 399.314934 -313.293613) (xy 399.268918 -313.276161) (xy 399.226297 -313.251554)
			(xy 399.188176 -313.220429) (xy 399.155541 -313.183592) (xy 399.129238 -313.141996) (xy 399.109947 -313.09672)
			(xy 399.09817 -313.048936) (xy 399.09421 -312.999882) (xy 398.775849 -312.999882) (xy 398.775864 -313.025385)
			(xy 398.767862 -313.076116) (xy 398.752023 -313.12497) (xy 398.728739 -313.170746) (xy 398.698582 -313.212318)
			(xy 398.662294 -313.24866) (xy 398.620768 -313.27888) (xy 398.575027 -313.302234) (xy 398.526197 -313.318146)
			(xy 398.475478 -313.326225) (xy 398.4498 -313.32678) (xy 398.415256 -313.325002) (xy 398.403572 -313.323732)
			(xy 398.381982 -313.331606) (xy 398.309592 -313.40425) (xy 398.301972 -313.42584) (xy 398.303496 -313.437524)
			(xy 398.304464 -313.446828) (xy 398.305481 -313.465508) (xy 398.305528 -313.474862) (xy 398.305528 -313.523376)
			(xy 398.305983 -313.534036) (xy 398.314663 -313.553508) (xy 398.322292 -313.560968) (xy 398.386046 -313.61888)
			(xy 398.406366 -313.625484) (xy 398.417288 -313.624468) (xy 398.4498 -313.622944) (xy 398.475484 -313.623448)
			(xy 398.526221 -313.631484) (xy 398.575076 -313.647357) (xy 398.620846 -313.670678) (xy 398.662404 -313.700872)
			(xy 398.698728 -313.737196) (xy 398.728922 -313.778754) (xy 398.752243 -313.824524) (xy 398.768116 -313.873379)
			(xy 398.776152 -313.924116) (xy 398.776152 -313.949842) (xy 399.09421 -313.949842) (xy 399.09817 -313.900788)
			(xy 399.109947 -313.853004) (xy 399.129238 -313.807728) (xy 399.155541 -313.766132) (xy 399.188176 -313.729295)
			(xy 399.226297 -313.69817) (xy 399.268918 -313.673563) (xy 399.314934 -313.656111) (xy 399.363153 -313.646267)
			(xy 399.412328 -313.644286) (xy 399.461183 -313.650218) (xy 399.508454 -313.66391) (xy 399.552916 -313.685008)
			(xy 399.593419 -313.712964) (xy 399.628912 -313.747056) (xy 399.658477 -313.7864) (xy 399.681348 -313.829977)
			(xy 399.696932 -313.876658) (xy 399.704827 -313.925235) (xy 399.705322 -313.949842) (xy 399.704827 -313.974449)
			(xy 399.704648 -313.97555) (xy 400.023326 -313.97555) (xy 400.023326 -313.924134) (xy 400.031369 -313.873352)
			(xy 400.047257 -313.824453) (xy 400.0706 -313.778641) (xy 400.100821 -313.737045) (xy 400.137177 -313.700689)
			(xy 400.178773 -313.670468) (xy 400.224585 -313.647125) (xy 400.273484 -313.631237) (xy 400.324266 -313.623194)
			(xy 400.375682 -313.623194) (xy 400.426464 -313.631237) (xy 400.475363 -313.647125) (xy 400.521175 -313.670468)
			(xy 400.562771 -313.700689) (xy 400.599127 -313.737045) (xy 400.629348 -313.778641) (xy 400.652691 -313.824453)
			(xy 400.668579 -313.873352) (xy 400.676622 -313.924134) (xy 400.677126 -313.949842) (xy 400.99413 -313.949842)
			(xy 400.99809 -313.900788) (xy 401.009867 -313.853004) (xy 401.029158 -313.807728) (xy 401.055461 -313.766132)
			(xy 401.088096 -313.729295) (xy 401.126217 -313.69817) (xy 401.168838 -313.673563) (xy 401.214854 -313.656111)
			(xy 401.263073 -313.646267) (xy 401.312248 -313.644286) (xy 401.361103 -313.650218) (xy 401.408374 -313.66391)
			(xy 401.452836 -313.685008) (xy 401.493339 -313.712964) (xy 401.528832 -313.747056) (xy 401.558397 -313.7864)
			(xy 401.581268 -313.829977) (xy 401.596852 -313.876658) (xy 401.604747 -313.925235) (xy 401.605242 -313.949842)
			(xy 401.604747 -313.974449) (xy 401.604568 -313.97555) (xy 401.923246 -313.97555) (xy 401.923246 -313.924134)
			(xy 401.931289 -313.873352) (xy 401.947177 -313.824453) (xy 401.97052 -313.778641) (xy 402.000741 -313.737045)
			(xy 402.037097 -313.700689) (xy 402.078693 -313.670468) (xy 402.124505 -313.647125) (xy 402.173404 -313.631237)
			(xy 402.224186 -313.623194) (xy 402.275602 -313.623194) (xy 402.326384 -313.631237) (xy 402.375283 -313.647125)
			(xy 402.421095 -313.670468) (xy 402.462691 -313.700689) (xy 402.499047 -313.737045) (xy 402.529268 -313.778641)
			(xy 402.552611 -313.824453) (xy 402.568499 -313.873352) (xy 402.576542 -313.924134) (xy 402.577046 -313.949842)
			(xy 402.89405 -313.949842) (xy 402.89801 -313.900788) (xy 402.909787 -313.853004) (xy 402.929078 -313.807728)
			(xy 402.955381 -313.766132) (xy 402.988016 -313.729295) (xy 403.026137 -313.69817) (xy 403.068758 -313.673563)
			(xy 403.114774 -313.656111) (xy 403.162993 -313.646267) (xy 403.212168 -313.644286) (xy 403.261023 -313.650218)
			(xy 403.308294 -313.66391) (xy 403.352756 -313.685008) (xy 403.393259 -313.712964) (xy 403.428752 -313.747056)
			(xy 403.458317 -313.7864) (xy 403.481188 -313.829977) (xy 403.496772 -313.876658) (xy 403.504667 -313.925235)
			(xy 403.505162 -313.949842) (xy 403.504667 -313.974449) (xy 403.504488 -313.97555) (xy 403.823166 -313.97555)
			(xy 403.823166 -313.924134) (xy 403.831209 -313.873352) (xy 403.847097 -313.824453) (xy 403.87044 -313.778641)
			(xy 403.900661 -313.737045) (xy 403.937017 -313.700689) (xy 403.978613 -313.670468) (xy 404.024425 -313.647125)
			(xy 404.073324 -313.631237) (xy 404.124106 -313.623194) (xy 404.175522 -313.623194) (xy 404.226304 -313.631237)
			(xy 404.275203 -313.647125) (xy 404.321015 -313.670468) (xy 404.362611 -313.700689) (xy 404.398967 -313.737045)
			(xy 404.429188 -313.778641) (xy 404.452531 -313.824453) (xy 404.468419 -313.873352) (xy 404.476462 -313.924134)
			(xy 404.476966 -313.949842) (xy 404.476462 -313.97555) (xy 404.468419 -314.026332) (xy 404.452531 -314.075231)
			(xy 404.429188 -314.121043) (xy 404.398967 -314.162639) (xy 404.362611 -314.198995) (xy 404.321015 -314.229216)
			(xy 404.275203 -314.252559) (xy 404.226304 -314.268447) (xy 404.175522 -314.27649) (xy 404.124106 -314.27649)
			(xy 404.073324 -314.268447) (xy 404.024425 -314.252559) (xy 403.978613 -314.229216) (xy 403.937017 -314.198995)
			(xy 403.900661 -314.162639) (xy 403.87044 -314.121043) (xy 403.847097 -314.075231) (xy 403.831209 -314.026332)
			(xy 403.823166 -313.97555) (xy 403.504488 -313.97555) (xy 403.496772 -314.023026) (xy 403.481188 -314.069707)
			(xy 403.458317 -314.113284) (xy 403.428752 -314.152628) (xy 403.393259 -314.18672) (xy 403.352756 -314.214676)
			(xy 403.308294 -314.235774) (xy 403.261023 -314.249466) (xy 403.212168 -314.255398) (xy 403.162993 -314.253417)
			(xy 403.114774 -314.243573) (xy 403.068758 -314.226121) (xy 403.026137 -314.201514) (xy 402.988016 -314.170389)
			(xy 402.955381 -314.133552) (xy 402.929078 -314.091956) (xy 402.909787 -314.04668) (xy 402.89801 -313.998896)
			(xy 402.89405 -313.949842) (xy 402.577046 -313.949842) (xy 402.576542 -313.97555) (xy 402.568499 -314.026332)
			(xy 402.552611 -314.075231) (xy 402.529268 -314.121043) (xy 402.499047 -314.162639) (xy 402.462691 -314.198995)
			(xy 402.421095 -314.229216) (xy 402.375283 -314.252559) (xy 402.326384 -314.268447) (xy 402.275602 -314.27649)
			(xy 402.224186 -314.27649) (xy 402.173404 -314.268447) (xy 402.124505 -314.252559) (xy 402.078693 -314.229216)
			(xy 402.037097 -314.198995) (xy 402.000741 -314.162639) (xy 401.97052 -314.121043) (xy 401.947177 -314.075231)
			(xy 401.931289 -314.026332) (xy 401.923246 -313.97555) (xy 401.604568 -313.97555) (xy 401.596852 -314.023026)
			(xy 401.581268 -314.069707) (xy 401.558397 -314.113284) (xy 401.528832 -314.152628) (xy 401.493339 -314.18672)
			(xy 401.452836 -314.214676) (xy 401.408374 -314.235774) (xy 401.361103 -314.249466) (xy 401.312248 -314.255398)
			(xy 401.263073 -314.253417) (xy 401.214854 -314.243573) (xy 401.168838 -314.226121) (xy 401.126217 -314.201514)
			(xy 401.088096 -314.170389) (xy 401.055461 -314.133552) (xy 401.029158 -314.091956) (xy 401.009867 -314.04668)
			(xy 400.99809 -313.998896) (xy 400.99413 -313.949842) (xy 400.677126 -313.949842) (xy 400.676622 -313.97555)
			(xy 400.668579 -314.026332) (xy 400.652691 -314.075231) (xy 400.629348 -314.121043) (xy 400.599127 -314.162639)
			(xy 400.562771 -314.198995) (xy 400.521175 -314.229216) (xy 400.475363 -314.252559) (xy 400.426464 -314.268447)
			(xy 400.375682 -314.27649) (xy 400.324266 -314.27649) (xy 400.273484 -314.268447) (xy 400.224585 -314.252559)
			(xy 400.178773 -314.229216) (xy 400.137177 -314.198995) (xy 400.100821 -314.162639) (xy 400.0706 -314.121043)
			(xy 400.047257 -314.075231) (xy 400.031369 -314.026332) (xy 400.023326 -313.97555) (xy 399.704648 -313.97555)
			(xy 399.696932 -314.023026) (xy 399.681348 -314.069707) (xy 399.658477 -314.113284) (xy 399.628912 -314.152628)
			(xy 399.593419 -314.18672) (xy 399.552916 -314.214676) (xy 399.508454 -314.235774) (xy 399.461183 -314.249466)
			(xy 399.412328 -314.255398) (xy 399.363153 -314.253417) (xy 399.314934 -314.243573) (xy 399.268918 -314.226121)
			(xy 399.226297 -314.201514) (xy 399.188176 -314.170389) (xy 399.155541 -314.133552) (xy 399.129238 -314.091956)
			(xy 399.109947 -314.04668) (xy 399.09817 -313.998896) (xy 399.09421 -313.949842) (xy 398.776152 -313.949842)
			(xy 398.776152 -313.975484) (xy 398.768116 -314.026221) (xy 398.752243 -314.075076) (xy 398.728922 -314.120846)
			(xy 398.698728 -314.162404) (xy 398.662404 -314.198728) (xy 398.620846 -314.228922) (xy 398.575076 -314.252243)
			(xy 398.526221 -314.268116) (xy 398.475484 -314.276152) (xy 398.4498 -314.27674) (xy 398.417542 -314.275216)
			(xy 398.40662 -314.2742) (xy 398.3863 -314.280804) (xy 398.322546 -314.338716) (xy 398.315039 -314.346261)
			(xy 398.306384 -314.365681) (xy 398.305782 -314.376308) (xy 398.305782 -314.424822) (xy 398.305622 -314.438476)
			(xy 398.303336 -314.465689) (xy 398.30121 -314.479178) (xy 398.299178 -314.491116) (xy 398.30629 -314.513722)
			(xy 398.379188 -314.590176) (xy 398.40154 -314.59805) (xy 398.413478 -314.596526) (xy 398.422525 -314.595538)
			(xy 398.440699 -314.594523) (xy 398.4498 -314.594494) (xy 398.474973 -314.595001) (xy 398.52464 -314.60325)
			(xy 398.572278 -314.619541) (xy 398.616595 -314.643432) (xy 398.656388 -314.674274) (xy 398.690579 -314.711231)
			(xy 398.718238 -314.753299) (xy 398.738615 -314.799338) (xy 398.751158 -314.848097) (xy 398.753838 -314.873132)
			(xy 398.754854 -314.882784) (xy 398.763236 -314.899548) (xy 398.820894 -314.95238) (xy 398.828096 -314.958539)
			(xy 398.845716 -314.965471) (xy 398.855184 -314.965842) (xy 398.99463 -314.965842) (xy 399.004076 -314.965354)
			(xy 399.021665 -314.958448) (xy 399.02892 -314.95238) (xy 399.086578 -314.899548) (xy 399.09496 -314.882784)
			(xy 399.095976 -314.873132) (xy 399.098688 -314.848108) (xy 399.111252 -314.799371) (xy 399.131642 -314.753356)
			(xy 399.159306 -314.71131) (xy 399.193493 -314.674372) (xy 399.233277 -314.643544) (xy 399.27758 -314.619661)
			(xy 399.3252 -314.603369) (xy 399.374849 -314.595112) (xy 399.425179 -314.595112) (xy 399.474828 -314.603369)
			(xy 399.522448 -314.619661) (xy 399.566751 -314.643544) (xy 399.606535 -314.674372) (xy 399.640722 -314.71131)
			(xy 399.668386 -314.753356) (xy 399.688776 -314.799371) (xy 399.70134 -314.848108) (xy 399.704052 -314.873132)
			(xy 399.705068 -314.882784) (xy 399.71345 -314.899548) (xy 399.771108 -314.95238) (xy 399.77831 -314.958537)
			(xy 399.795931 -314.965464) (xy 399.805398 -314.965842) (xy 399.94459 -314.965842) (xy 399.954031 -314.965344)
			(xy 399.971607 -314.958423) (xy 399.97888 -314.95238) (xy 400.036538 -314.899548) (xy 400.04492 -314.882784)
			(xy 400.045936 -314.873132) (xy 400.048648 -314.848108) (xy 400.061212 -314.799371) (xy 400.081602 -314.753356)
			(xy 400.109266 -314.71131) (xy 400.143453 -314.674372) (xy 400.183237 -314.643544) (xy 400.22754 -314.619661)
			(xy 400.27516 -314.603369) (xy 400.324809 -314.595112) (xy 400.375139 -314.595112) (xy 400.424788 -314.603369)
			(xy 400.472408 -314.619661) (xy 400.516711 -314.643544) (xy 400.556495 -314.674372) (xy 400.590682 -314.71131)
			(xy 400.618346 -314.753356) (xy 400.638736 -314.799371) (xy 400.6513 -314.848108) (xy 400.654012 -314.873132)
			(xy 400.655028 -314.882784) (xy 400.66341 -314.899548) (xy 400.721068 -314.95238) (xy 400.728268 -314.958543)
			(xy 400.745889 -314.965483) (xy 400.755358 -314.965842) (xy 400.89455 -314.965842) (xy 400.903994 -314.965351)
			(xy 400.921579 -314.95844) (xy 400.92884 -314.95238) (xy 400.986498 -314.899548) (xy 400.99488 -314.882784)
			(xy 400.995896 -314.873132) (xy 400.998608 -314.848108) (xy 401.011172 -314.799371) (xy 401.031562 -314.753356)
			(xy 401.059226 -314.71131) (xy 401.093413 -314.674372) (xy 401.133197 -314.643544) (xy 401.1775 -314.619661)
			(xy 401.22512 -314.603369) (xy 401.274769 -314.595112) (xy 401.325099 -314.595112) (xy 401.374748 -314.603369)
			(xy 401.422368 -314.619661) (xy 401.466671 -314.643544) (xy 401.506455 -314.674372) (xy 401.540642 -314.71131)
			(xy 401.568306 -314.753356) (xy 401.588696 -314.799371) (xy 401.60126 -314.848108) (xy 401.603972 -314.873132)
			(xy 401.604988 -314.882784) (xy 401.61337 -314.899548) (xy 401.671028 -314.95238) (xy 401.678231 -314.958533)
			(xy 401.695852 -314.965453) (xy 401.705318 -314.965842) (xy 401.84451 -314.965842) (xy 401.853957 -314.965358)
			(xy 401.871552 -314.958457) (xy 401.8788 -314.95238) (xy 401.936458 -314.899548) (xy 401.94484 -314.882784)
			(xy 401.945856 -314.873132) (xy 401.948568 -314.848108) (xy 401.961132 -314.799371) (xy 401.981522 -314.753356)
			(xy 402.009186 -314.71131) (xy 402.043373 -314.674372) (xy 402.083157 -314.643544) (xy 402.12746 -314.619661)
			(xy 402.17508 -314.603369) (xy 402.224729 -314.595112) (xy 402.275059 -314.595112) (xy 402.324708 -314.603369)
			(xy 402.372328 -314.619661) (xy 402.416631 -314.643544) (xy 402.456415 -314.674372) (xy 402.490602 -314.71131)
			(xy 402.518266 -314.753356) (xy 402.538656 -314.799371) (xy 402.55122 -314.848108) (xy 402.553932 -314.873132)
			(xy 402.554948 -314.882784) (xy 402.56333 -314.899548) (xy 402.620988 -314.95238) (xy 402.628189 -314.95854)
			(xy 402.64581 -314.965474) (xy 402.655278 -314.965842) (xy 402.79447 -314.965842) (xy 402.803913 -314.965347)
			(xy 402.821493 -314.958432) (xy 402.82876 -314.95238) (xy 402.886418 -314.899548) (xy 402.8948 -314.882784)
			(xy 402.895816 -314.873132) (xy 402.898528 -314.848108) (xy 402.911092 -314.799371) (xy 402.931482 -314.753356)
			(xy 402.959146 -314.71131) (xy 402.993333 -314.674372) (xy 403.033117 -314.643544) (xy 403.07742 -314.619661)
			(xy 403.12504 -314.603369) (xy 403.174689 -314.595112) (xy 403.225019 -314.595112) (xy 403.274668 -314.603369)
			(xy 403.322288 -314.619661) (xy 403.366591 -314.643544) (xy 403.406375 -314.674372) (xy 403.440562 -314.71131)
			(xy 403.468226 -314.753356) (xy 403.488616 -314.799371) (xy 403.50118 -314.848108) (xy 403.503892 -314.873132)
			(xy 403.504908 -314.882784) (xy 403.51329 -314.899548) (xy 403.570948 -314.95238) (xy 403.578152 -314.958531)
			(xy 403.595773 -314.965443) (xy 403.605238 -314.965842) (xy 403.74443 -314.965842) (xy 403.753876 -314.965354)
			(xy 403.771465 -314.958448) (xy 403.77872 -314.95238) (xy 403.836378 -314.899548) (xy 403.84476 -314.882784)
			(xy 403.845776 -314.873132) (xy 403.848488 -314.848108) (xy 403.861052 -314.799371) (xy 403.881442 -314.753356)
			(xy 403.909106 -314.71131) (xy 403.943293 -314.674372) (xy 403.983077 -314.643544) (xy 404.02738 -314.619661)
			(xy 404.075 -314.603369) (xy 404.124649 -314.595112) (xy 404.174979 -314.595112) (xy 404.224628 -314.603369)
			(xy 404.272248 -314.619661) (xy 404.316551 -314.643544) (xy 404.356335 -314.674372) (xy 404.390522 -314.71131)
			(xy 404.418186 -314.753356) (xy 404.438576 -314.799371) (xy 404.45114 -314.848108) (xy 404.453852 -314.873132)
			(xy 404.454868 -314.882784) (xy 404.46325 -314.899548) (xy 404.520908 -314.95238) (xy 404.52811 -314.958537)
			(xy 404.545731 -314.965464) (xy 404.555198 -314.965842) (xy 404.694644 -314.965842) (xy 404.704088 -314.965352)
			(xy 404.721675 -314.958443) (xy 404.728934 -314.95238) (xy 404.786592 -314.899548) (xy 404.794974 -314.882784)
			(xy 404.79599 -314.873132) (xy 404.798707 -314.848108) (xy 404.811281 -314.799372) (xy 404.831676 -314.753357)
			(xy 404.859339 -314.711309) (xy 404.893524 -314.674367) (xy 404.933303 -314.64353) (xy 404.9776 -314.619633)
			(xy 405.025216 -314.603323) (xy 405.074862 -314.595042) (xy 405.100028 -314.594494) (xy 405.109129 -314.594534)
			(xy 405.127301 -314.595552) (xy 405.13635 -314.596526) (xy 405.148288 -314.59805) (xy 405.17064 -314.590176)
			(xy 405.243538 -314.513722) (xy 405.25065 -314.491116) (xy 405.248618 -314.479178) (xy 405.246487 -314.46569)
			(xy 405.244197 -314.438477) (xy 405.244046 -314.424822) (xy 405.244046 -314.354464) (xy 405.243578 -314.34381)
			(xy 405.23488 -314.324359) (xy 405.227282 -314.316872) (xy 405.16302 -314.25896) (xy 405.1427 -314.252356)
			(xy 405.131778 -314.253372) (xy 405.100028 -314.25515) (xy 405.074765 -314.254659) (xy 405.024928 -314.246347)
			(xy 404.977139 -314.229945) (xy 404.932702 -314.205901) (xy 404.892829 -314.174869) (xy 404.858608 -314.137698)
			(xy 404.830971 -314.095401) (xy 404.810675 -314.049132) (xy 404.798271 -314.000153) (xy 404.794098 -313.9498)
			(xy 404.798271 -313.899447) (xy 404.810675 -313.850468) (xy 404.830971 -313.804199) (xy 404.858608 -313.761902)
			(xy 404.892829 -313.724731) (xy 404.932702 -313.693699) (xy 404.97714 -313.669655) (xy 405.024928 -313.653253)
			(xy 405.074765 -313.644941) (xy 405.100028 -313.644534) (xy 405.132032 -313.646312) (xy 405.142954 -313.647328)
			(xy 405.163274 -313.640724) (xy 405.227536 -313.583066) (xy 405.235193 -313.575548) (xy 405.243868 -313.555943)
			(xy 405.2443 -313.54522) (xy 405.2443 -313.474862) (xy 405.244461 -313.461208) (xy 405.246748 -313.433995)
			(xy 405.248872 -313.420506) (xy 405.250904 -313.408568) (xy 405.243792 -313.385962) (xy 405.170894 -313.309508)
			(xy 405.148542 -313.301634) (xy 405.13635 -313.302904) (xy 405.127306 -313.303953) (xy 405.109132 -313.305099)
			(xy 405.100028 -313.30519) (xy 405.075208 -313.304706) (xy 405.026222 -313.29668) (xy 404.97918 -313.280835)
			(xy 404.935322 -313.257587) (xy 404.895802 -313.22755) (xy 404.861662 -313.191515) (xy 404.833801 -313.150432)
			(xy 404.812955 -313.105382) (xy 404.799671 -313.057554) (xy 404.7943 -313.008206) (xy 404.796983 -312.958639)
			(xy 404.80765 -312.91016) (xy 404.82602 -312.864045) (xy 404.851608 -312.821509) (xy 404.883741 -312.783674)
			(xy 404.921572 -312.751535) (xy 404.964104 -312.725941) (xy 405.010216 -312.707564) (xy 405.058694 -312.696889)
			(xy 405.10826 -312.694199) (xy 405.157608 -312.699562) (xy 405.205439 -312.712839) (xy 405.250492 -312.733679)
			(xy 405.291579 -312.761533) (xy 405.327619 -312.795667) (xy 405.357662 -312.835183) (xy 405.380916 -312.879038)
			(xy 405.396769 -312.926078) (xy 405.404803 -312.975062) (xy 405.405336 -312.999882) (xy 405.405237 -313.008986)
			(xy 405.404091 -313.027159) (xy 405.40305 -313.036204) (xy 405.40178 -313.048396) (xy 405.409654 -313.070748)
			(xy 405.486108 -313.143646) (xy 405.508714 -313.150758) (xy 405.520652 -313.148726) (xy 405.53414 -313.146596)
			(xy 405.561353 -313.144309) (xy 405.575008 -313.144154) (xy 405.584362 -313.144197) (xy 405.603042 -313.145214)
			(xy 405.612346 -313.146186) (xy 405.62403 -313.14771) (xy 405.64562 -313.14009) (xy 405.718264 -313.0677)
			(xy 405.726138 -313.04611) (xy 405.724868 -313.034426) (xy 405.722836 -312.999882) (xy 405.723341 -312.974202)
			(xy 405.731376 -312.923474) (xy 405.747247 -312.874628) (xy 405.770562 -312.828865) (xy 405.800748 -312.787312)
			(xy 405.837062 -312.750991) (xy 405.878609 -312.720797) (xy 405.924367 -312.697472) (xy 405.97321 -312.681592)
			(xy 406.023936 -312.673546) (xy 406.075296 -312.673533) (xy 406.126026 -312.681553) (xy 406.174878 -312.697408)
			(xy 406.220648 -312.720709) (xy 406.262211 -312.750882) (xy 406.298543 -312.787184) (xy 406.32875 -312.828722)
			(xy 406.352088 -312.874473) (xy 406.367984 -312.923311) (xy 406.376046 -312.974034) (xy 406.376061 -312.999882)
			(xy 406.694144 -312.999882) (xy 406.698104 -312.950828) (xy 406.709881 -312.903044) (xy 406.729172 -312.857768)
			(xy 406.755475 -312.816172) (xy 406.78811 -312.779335) (xy 406.826231 -312.74821) (xy 406.868852 -312.723603)
			(xy 406.914868 -312.706151) (xy 406.963087 -312.696307) (xy 407.012262 -312.694326) (xy 407.061117 -312.700258)
			(xy 407.108388 -312.71395) (xy 407.15285 -312.735048) (xy 407.193353 -312.763004) (xy 407.228846 -312.797096)
			(xy 407.258411 -312.83644) (xy 407.281282 -312.880017) (xy 407.296866 -312.926698) (xy 407.304761 -312.975275)
			(xy 407.305256 -312.999882) (xy 407.304761 -313.024489) (xy 407.296866 -313.073066) (xy 407.281282 -313.119747)
			(xy 407.258411 -313.163324) (xy 407.228846 -313.202668) (xy 407.193353 -313.23676) (xy 407.15285 -313.264716)
			(xy 407.108388 -313.285814) (xy 407.061117 -313.299506) (xy 407.012262 -313.305438) (xy 406.963087 -313.303457)
			(xy 406.914868 -313.293613) (xy 406.868852 -313.276161) (xy 406.826231 -313.251554) (xy 406.78811 -313.220429)
			(xy 406.755475 -313.183592) (xy 406.729172 -313.141996) (xy 406.709881 -313.09672) (xy 406.698104 -313.048936)
			(xy 406.694144 -312.999882) (xy 406.376061 -312.999882) (xy 406.376075 -313.025394) (xy 406.368071 -313.076127)
			(xy 406.352231 -313.124983) (xy 406.328944 -313.170761) (xy 406.298784 -313.212333) (xy 406.262494 -313.248676)
			(xy 406.220965 -313.278896) (xy 406.175222 -313.302249) (xy 406.126388 -313.31816) (xy 406.075668 -313.326238)
			(xy 406.049988 -313.32678) (xy 406.015444 -313.325002) (xy 406.00376 -313.323732) (xy 405.98217 -313.331606)
			(xy 405.90978 -313.40425) (xy 405.90216 -313.42584) (xy 405.903684 -313.437524) (xy 405.904652 -313.446828)
			(xy 405.905669 -313.465508) (xy 405.905716 -313.474862) (xy 405.905716 -313.523376) (xy 405.906171 -313.534037)
			(xy 405.91485 -313.55351) (xy 405.92248 -313.560968) (xy 405.986234 -313.61888) (xy 406.006554 -313.625484)
			(xy 406.017476 -313.624468) (xy 406.049988 -313.622944) (xy 406.075684 -313.623446) (xy 406.126444 -313.63148)
			(xy 406.175323 -313.647352) (xy 406.221119 -313.670671) (xy 406.262706 -313.700864) (xy 406.29906 -313.737188)
			(xy 406.329288 -313.77875) (xy 406.352645 -313.824527) (xy 406.368557 -313.873394) (xy 406.376633 -313.924147)
			(xy 406.37714 -313.949842) (xy 406.375108 -313.984386) (xy 406.373838 -313.99607) (xy 406.381712 -314.01766)
			(xy 406.454356 -314.09005) (xy 406.475946 -314.09767) (xy 406.48763 -314.096146) (xy 406.496934 -314.095178)
			(xy 406.515614 -314.094162) (xy 406.524968 -314.094114) (xy 406.538622 -314.094276) (xy 406.565835 -314.096565)
			(xy 406.579324 -314.098686) (xy 406.591262 -314.100718) (xy 406.613868 -314.093606) (xy 406.690322 -314.020708)
			(xy 406.698196 -313.998356) (xy 406.696926 -313.986164) (xy 406.695877 -313.97712) (xy 406.69473 -313.958946)
			(xy 406.69464 -313.949842) (xy 406.695122 -313.925025) (xy 406.703145 -313.876044) (xy 406.718987 -313.829006)
			(xy 406.74223 -313.785151) (xy 406.772261 -313.745634) (xy 406.80829 -313.711496) (xy 406.849368 -313.683636)
			(xy 406.894411 -313.662789) (xy 406.942234 -313.649504) (xy 406.991576 -313.64413) (xy 407.041137 -313.64681)
			(xy 407.089612 -313.657473) (xy 407.135723 -313.675838) (xy 407.178256 -313.70142) (xy 407.216089 -313.733547)
			(xy 407.248227 -313.771371) (xy 407.273822 -313.813896) (xy 407.292201 -313.860002) (xy 407.302878 -313.908474)
			(xy 407.305572 -313.958034) (xy 407.300213 -314.007378) (xy 407.286942 -314.055204) (xy 407.266108 -314.100254)
			(xy 407.238261 -314.14134) (xy 407.204133 -314.177379) (xy 407.164625 -314.207422) (xy 407.120776 -314.230677)
			(xy 407.073743 -314.246533) (xy 407.024765 -314.25457) (xy 406.999948 -314.25515) (xy 406.990844 -314.255052)
			(xy 406.972671 -314.253908) (xy 406.963626 -314.252864) (xy 406.951434 -314.251594) (xy 406.929082 -314.259468)
			(xy 406.856184 -314.335922) (xy 406.849326 -314.358528) (xy 406.851104 -314.370466) (xy 406.853047 -314.382634)
			(xy 406.855339 -314.40717) (xy 406.855676 -314.419488) (xy 406.855676 -314.419742) (xy 406.856091 -314.427033)
			(xy 406.860482 -314.440955) (xy 406.864312 -314.447174) (xy 406.878028 -314.467748) (xy 406.886918 -314.477908)
			(xy 406.894284 -314.484258) (xy 406.90165 -314.48756) (xy 406.941146 -314.504844) (xy 407.017185 -314.545485)
			(xy 407.089292 -314.592753) (xy 407.123392 -314.619132) (xy 407.13279 -314.624974) (xy 407.155579 -314.636573)
			(xy 407.197265 -314.666183) (xy 407.233453 -314.702305) (xy 407.263139 -314.743936) (xy 407.274776 -314.766706)
			(xy 407.280618 -314.776104) (xy 407.310111 -314.814251) (xy 407.362155 -314.89543) (xy 407.384504 -314.938156)
			(xy 407.389118 -314.946271) (xy 407.402983 -314.958747) (xy 407.420391 -314.965442) (xy 407.429716 -314.965842)
			(xy 407.544524 -314.965842) (xy 407.55397 -314.965355) (xy 407.571561 -314.958451) (xy 407.578814 -314.95238)
			(xy 407.636472 -314.899548) (xy 407.644854 -314.882784) (xy 407.64587 -314.873132) (xy 407.648587 -314.848107)
			(xy 407.66116 -314.79937) (xy 407.681555 -314.753353) (xy 407.709218 -314.711304) (xy 407.743402 -314.67436)
			(xy 407.783181 -314.64352) (xy 407.827478 -314.619621) (xy 407.875095 -314.603308) (xy 407.924742 -314.595024)
			(xy 407.949908 -314.594494) (xy 407.959012 -314.594591) (xy 407.977186 -314.595732) (xy 407.98623 -314.59678)
			(xy 407.998422 -314.59805) (xy 408.020774 -314.590176) (xy 408.093672 -314.513722) (xy 408.100784 -314.491116)
			(xy 408.098752 -314.479178) (xy 408.096621 -314.46569) (xy 408.094329 -314.438477) (xy 408.09418 -314.424822)
			(xy 408.09418 -314.376308) (xy 408.093722 -314.365649) (xy 408.085039 -314.346181) (xy 408.077416 -314.338716)
			(xy 408.013662 -314.280804) (xy 407.993342 -314.2742) (xy 407.98242 -314.275216) (xy 407.949908 -314.27674)
			(xy 407.924214 -314.276263) (xy 407.87346 -314.268226) (xy 407.824587 -314.252347) (xy 407.778801 -314.229019)
			(xy 407.737227 -314.198815) (xy 407.700891 -314.162479) (xy 407.670686 -314.120906) (xy 407.647356 -314.07512)
			(xy 407.631476 -314.026248) (xy 407.623438 -313.975494) (xy 407.623438 -313.924106) (xy 407.631476 -313.873352)
			(xy 407.647356 -313.82448) (xy 407.670686 -313.778694) (xy 407.700891 -313.737121) (xy 407.737227 -313.700785)
			(xy 407.778801 -313.670581) (xy 407.824587 -313.647253) (xy 407.87346 -313.631374) (xy 407.924214 -313.623337)
			(xy 407.949908 -313.622944) (xy 407.98242 -313.624468) (xy 407.993342 -313.625484) (xy 408.013662 -313.61888)
			(xy 408.077416 -313.560968) (xy 408.084913 -313.553418) (xy 408.093551 -313.533999) (xy 408.09418 -313.523376)
			(xy 408.09418 -313.474862) (xy 408.094221 -313.465508) (xy 408.095236 -313.446827) (xy 408.096212 -313.437524)
			(xy 408.097482 -313.42584) (xy 408.090116 -313.40425) (xy 408.017726 -313.331606) (xy 407.996136 -313.323732)
			(xy 407.984452 -313.325002) (xy 407.949908 -313.32678) (xy 407.924191 -313.326302) (xy 407.873391 -313.318256)
			(xy 407.824475 -313.30236) (xy 407.778649 -313.279007) (xy 407.737041 -313.248771) (xy 407.700676 -313.212398)
			(xy 407.670451 -313.170782) (xy 407.647109 -313.12495) (xy 407.631225 -313.076031) (xy 407.623192 -313.025228)
			(xy 407.623206 -312.973795) (xy 407.631267 -312.922997) (xy 407.647177 -312.874086) (xy 407.670544 -312.828266)
			(xy 407.700792 -312.786667) (xy 407.737176 -312.750314) (xy 407.7788 -312.7201) (xy 407.824639 -312.696772)
			(xy 407.873564 -312.680903) (xy 407.924368 -312.672884) (xy 407.975802 -312.672913) (xy 408.026597 -312.680989)
			(xy 408.075504 -312.696914) (xy 408.121316 -312.720294) (xy 408.162906 -312.750555) (xy 408.199249 -312.78695)
			(xy 408.22945 -312.828583) (xy 408.252765 -312.874429) (xy 408.26862 -312.923358) (xy 408.276623 -312.974165)
			(xy 408.27706 -312.999882) (xy 408.275028 -313.034426) (xy 408.273758 -313.04611) (xy 408.281632 -313.067446)
			(xy 408.35453 -313.139836) (xy 408.37612 -313.147456) (xy 408.38755 -313.145932) (xy 408.396917 -313.144958)
			(xy 408.415724 -313.143941) (xy 408.425142 -313.1439) (xy 408.438732 -313.144071) (xy 408.465817 -313.146363)
			(xy 408.479244 -313.148472) (xy 408.491182 -313.15025) (xy 408.513788 -313.143392) (xy 408.590242 -313.070494)
			(xy 408.598116 -313.048142) (xy 408.596592 -313.036204) (xy 408.595604 -313.027157) (xy 408.59459 -313.008983)
			(xy 408.59456 -312.999882) (xy 408.595047 -312.975058) (xy 408.603082 -312.926065) (xy 408.618938 -312.879018)
			(xy 408.642196 -312.835155) (xy 408.672244 -312.795633) (xy 408.70829 -312.761493) (xy 408.749384 -312.733635)
			(xy 408.794445 -312.712791) (xy 408.842283 -312.699513) (xy 408.89164 -312.694149) (xy 408.941214 -312.69684)
			(xy 408.9897 -312.707517) (xy 409.03582 -312.725897) (xy 409.078359 -312.751496) (xy 409.116196 -312.78364)
			(xy 409.148333 -312.821482) (xy 409.173926 -312.864025) (xy 409.192298 -312.910148) (xy 409.202967 -312.958635)
			(xy 409.20565 -313.00821) (xy 409.200278 -313.057566) (xy 409.186991 -313.105402) (xy 409.166141 -313.150459)
			(xy 409.138275 -313.191549) (xy 409.104129 -313.22759) (xy 409.064602 -313.257631) (xy 409.020736 -313.280882)
			(xy 408.973686 -313.29673) (xy 408.924692 -313.304757) (xy 408.899868 -313.30519) (xy 408.890831 -313.305145)
			(xy 408.872785 -313.30413) (xy 408.8638 -313.303158) (xy 408.851862 -313.301634) (xy 408.82951 -313.309508)
			(xy 408.756612 -313.385962) (xy 408.749754 -313.408568) (xy 408.751532 -313.420506) (xy 408.753664 -313.433994)
			(xy 408.755957 -313.461207) (xy 408.756104 -313.474862) (xy 408.756104 -313.54522) (xy 408.756568 -313.555877)
			(xy 408.765256 -313.575338) (xy 408.772868 -313.582812) (xy 408.83713 -313.640724) (xy 408.85745 -313.647328)
			(xy 408.868118 -313.646058) (xy 408.899868 -313.644534) (xy 408.923862 -313.644978) (xy 408.971258 -313.652481)
			(xy 409.016898 -313.667307) (xy 409.059655 -313.689091) (xy 409.098478 -313.717297) (xy 409.132409 -313.75123)
			(xy 409.160614 -313.790053) (xy 409.182397 -313.832812) (xy 409.197221 -313.878451) (xy 409.204723 -313.925848)
			(xy 409.205176 -313.949842) (xy 409.205078 -313.958946) (xy 409.203935 -313.977119) (xy 409.20289 -313.986164)
			(xy 409.20162 -313.998356) (xy 409.209494 -314.020708) (xy 409.285948 -314.093606) (xy 409.308554 -314.100718)
			(xy 409.320492 -314.098686) (xy 409.343255 -314.095263) (xy 409.389268 -314.093992) (xy 409.412186 -314.096146)
			(xy 409.42387 -314.097416) (xy 409.44546 -314.09005) (xy 409.518104 -314.01766) (xy 409.525978 -313.99607)
			(xy 409.524708 -313.984386) (xy 409.522676 -313.949842) (xy 409.523151 -313.924137) (xy 409.531191 -313.873358)
			(xy 409.54708 -313.824464) (xy 409.570425 -313.77866) (xy 409.600652 -313.737074) (xy 409.637015 -313.700731)
			(xy 409.678619 -313.670528) (xy 409.724437 -313.647209) (xy 409.77334 -313.631348) (xy 409.824122 -313.623337)
			(xy 409.849828 -313.622944) (xy 409.88234 -313.624468) (xy 409.893262 -313.625484) (xy 409.913582 -313.61888)
			(xy 409.977336 -313.560968) (xy 409.984843 -313.553423) (xy 409.993494 -313.534003) (xy 409.9941 -313.523376)
			(xy 409.9941 -313.474862) (xy 409.994142 -313.465508) (xy 409.995156 -313.446827) (xy 409.996132 -313.437524)
			(xy 409.997402 -313.42584) (xy 409.990036 -313.40425) (xy 409.917646 -313.331606) (xy 409.896056 -313.323732)
			(xy 409.884372 -313.325002) (xy 409.849828 -313.32678) (xy 409.824111 -313.326304) (xy 409.773309 -313.31826)
			(xy 409.724392 -313.302367) (xy 409.678564 -313.279016) (xy 409.636954 -313.248782) (xy 409.600587 -313.21241)
			(xy 409.570359 -313.170796) (xy 409.547015 -313.124964) (xy 409.531129 -313.076045) (xy 409.523093 -313.025242)
			(xy 409.523105 -312.973808) (xy 409.531164 -312.923009) (xy 409.547072 -312.874096) (xy 409.570438 -312.828276)
			(xy 409.600685 -312.786675) (xy 409.637069 -312.75032) (xy 409.678693 -312.720105) (xy 409.724531 -312.696775)
			(xy 409.773456 -312.680905) (xy 409.824261 -312.672885) (xy 409.875696 -312.672913) (xy 409.926492 -312.680988)
			(xy 409.975399 -312.696912) (xy 410.021212 -312.720292) (xy 410.062803 -312.750552) (xy 410.099147 -312.786948)
			(xy 410.129349 -312.828581) (xy 410.152665 -312.874427) (xy 410.16852 -312.923357) (xy 410.176523 -312.974164)
			(xy 410.17698 -312.999882) (xy 410.174948 -313.034426) (xy 410.173678 -313.04611) (xy 410.181552 -313.067446)
			(xy 410.25445 -313.139836) (xy 410.27604 -313.147456) (xy 410.28747 -313.145932) (xy 410.296837 -313.144959)
			(xy 410.315644 -313.143942) (xy 410.325062 -313.1439) (xy 410.338653 -313.144067) (xy 410.365739 -313.146353)
			(xy 410.379164 -313.148472) (xy 410.391102 -313.15025) (xy 410.413708 -313.143392) (xy 410.490162 -313.070494)
			(xy 410.498036 -313.048142) (xy 410.496512 -313.036204) (xy 410.495524 -313.027157) (xy 410.49451 -313.008983)
			(xy 410.49448 -312.999882) (xy 410.494967 -312.97506) (xy 410.503002 -312.926071) (xy 410.518856 -312.879027)
			(xy 410.542111 -312.835168) (xy 410.572157 -312.795649) (xy 410.608199 -312.761511) (xy 410.64929 -312.733654)
			(xy 410.694347 -312.712812) (xy 410.742181 -312.699534) (xy 410.791534 -312.694169) (xy 410.841105 -312.696859)
			(xy 410.889587 -312.707533) (xy 410.935703 -312.725911) (xy 410.97824 -312.751507) (xy 411.016074 -312.783647)
			(xy 411.048211 -312.821485) (xy 411.073803 -312.864023) (xy 411.092175 -312.910142) (xy 411.102845 -312.958625)
			(xy 411.10553 -313.008196) (xy 411.100161 -313.057548) (xy 411.086878 -313.105382) (xy 411.066031 -313.150436)
			(xy 411.03817 -313.191524) (xy 411.004029 -313.227563) (xy 410.964507 -313.257605) (xy 410.920645 -313.280856)
			(xy 410.8736 -313.296706) (xy 410.82461 -313.304735) (xy 410.799788 -313.30519) (xy 410.790751 -313.305142)
			(xy 410.772706 -313.304123) (xy 410.76372 -313.303158) (xy 410.751782 -313.301634) (xy 410.72943 -313.309508)
			(xy 410.656532 -313.385962) (xy 410.649674 -313.408568) (xy 410.651452 -313.420506) (xy 410.653583 -313.433994)
			(xy 410.655877 -313.461207) (xy 410.656024 -313.474862) (xy 410.656024 -313.54522) (xy 410.656488 -313.555877)
			(xy 410.665179 -313.575336) (xy 410.672788 -313.582812) (xy 410.73705 -313.640724) (xy 410.75737 -313.647328)
			(xy 410.768038 -313.646058) (xy 410.799788 -313.644534) (xy 410.823781 -313.644979) (xy 410.871175 -313.652485)
			(xy 410.916812 -313.667313) (xy 410.959566 -313.689098) (xy 410.998386 -313.717304) (xy 411.032315 -313.751237)
			(xy 411.060517 -313.790059) (xy 411.082299 -313.832816) (xy 411.097122 -313.878454) (xy 411.104623 -313.925849)
			(xy 411.105096 -313.949842) (xy 411.105002 -313.95901) (xy 411.103856 -313.97731) (xy 411.10281 -313.986418)
			(xy 411.10154 -313.998356) (xy 411.109414 -314.020708) (xy 411.185868 -314.093606) (xy 411.208474 -314.100718)
			(xy 411.220412 -314.098686) (xy 411.243235 -314.095215) (xy 411.289381 -314.093939) (xy 411.31236 -314.096146)
			(xy 411.324044 -314.097416) (xy 411.345634 -314.09005) (xy 411.418278 -314.01766) (xy 411.426152 -313.99607)
			(xy 411.424882 -313.984386) (xy 411.423104 -313.949842) (xy 411.423579 -313.92415) (xy 411.431611 -313.873398)
			(xy 411.447485 -313.824528) (xy 411.470808 -313.778742) (xy 411.501008 -313.73717) (xy 411.537339 -313.700834)
			(xy 411.578908 -313.670629) (xy 411.624691 -313.6473) (xy 411.673559 -313.63142) (xy 411.72431 -313.623382)
			(xy 411.750002 -313.622944) (xy 411.782768 -313.624468) (xy 411.79369 -313.625484) (xy 411.813756 -313.61888)
			(xy 411.877764 -313.560968) (xy 411.885268 -313.553421) (xy 411.893914 -313.534002) (xy 411.894528 -313.523376)
			(xy 411.894528 -313.474862) (xy 411.894572 -313.465508) (xy 411.89559 -313.446828) (xy 411.89656 -313.437524)
			(xy 411.898084 -313.42584) (xy 411.890464 -313.40425) (xy 411.818074 -313.331352) (xy 411.796484 -313.323732)
			(xy 411.7848 -313.325002) (xy 411.750002 -313.32678) (xy 411.724316 -313.326276) (xy 411.673576 -313.31824)
			(xy 411.624718 -313.302366) (xy 411.578945 -313.279044) (xy 411.537383 -313.248849) (xy 411.501057 -313.212524)
			(xy 411.470861 -313.170963) (xy 411.447538 -313.125191) (xy 411.431662 -313.076333) (xy 411.423624 -313.025593)
			(xy 411.423623 -312.974221) (xy 411.431658 -312.923481) (xy 411.447532 -312.874623) (xy 411.470853 -312.828849)
			(xy 411.501048 -312.787288) (xy 411.537372 -312.750961) (xy 411.578932 -312.720764) (xy 411.624705 -312.69744)
			(xy 411.673562 -312.681563) (xy 411.724301 -312.673525) (xy 411.775673 -312.673523) (xy 411.826414 -312.681557)
			(xy 411.875272 -312.69743) (xy 411.921046 -312.72075) (xy 411.962608 -312.750944) (xy 411.998936 -312.787268)
			(xy 412.029134 -312.828828) (xy 412.052458 -312.8746) (xy 412.068336 -312.923457) (xy 412.076375 -312.974196)
			(xy 412.0769 -312.999882) (xy 412.075122 -313.03468) (xy 412.073852 -313.04611) (xy 412.081726 -313.0677)
			(xy 412.15437 -313.14009) (xy 412.176214 -313.14771) (xy 412.187644 -313.146186) (xy 412.197011 -313.145212)
			(xy 412.215818 -313.144197) (xy 412.225236 -313.144154) (xy 412.238826 -313.144324) (xy 412.265912 -313.146613)
			(xy 412.279338 -313.148726) (xy 412.291276 -313.150504) (xy 412.313882 -313.143646) (xy 412.390336 -313.070748)
			(xy 412.39821 -313.048396) (xy 412.39694 -313.036204) (xy 412.395892 -313.02716) (xy 412.39475 -313.008986)
			(xy 412.394654 -312.999882) (xy 412.395141 -312.975058) (xy 412.403177 -312.926064) (xy 412.419033 -312.879015)
			(xy 412.442291 -312.835152) (xy 412.47234 -312.795629) (xy 412.508387 -312.761488) (xy 412.549483 -312.733629)
			(xy 412.594544 -312.712785) (xy 412.642384 -312.699507) (xy 412.691742 -312.694143) (xy 412.741317 -312.696834)
			(xy 412.789804 -312.707511) (xy 412.835925 -312.725892) (xy 412.878465 -312.751493) (xy 412.916302 -312.783638)
			(xy 412.94844 -312.821481) (xy 412.974033 -312.864025) (xy 412.992405 -312.910149) (xy 413.003073 -312.958638)
			(xy 413.005756 -313.008214) (xy 413.000383 -313.057571) (xy 412.987095 -313.105409) (xy 412.966244 -313.150466)
			(xy 412.938377 -313.191557) (xy 412.90423 -313.227597) (xy 412.864701 -313.257639) (xy 412.820833 -313.28089)
			(xy 412.773782 -313.296737) (xy 412.724786 -313.304763) (xy 412.699962 -313.30519) (xy 412.690861 -313.30515)
			(xy 412.672689 -313.304131) (xy 412.66364 -313.303158) (xy 412.651702 -313.301634) (xy 412.62935 -313.309508)
			(xy 412.556452 -313.385962) (xy 412.54934 -313.408568) (xy 412.551372 -313.420506) (xy 412.553504 -313.433994)
			(xy 412.555795 -313.461207) (xy 412.555944 -313.474862) (xy 412.555944 -313.54522) (xy 412.556409 -313.555876)
			(xy 412.565102 -313.575333) (xy 412.572708 -313.582812) (xy 412.63697 -313.640724) (xy 412.65729 -313.647328)
			(xy 412.668212 -313.646312) (xy 412.699962 -313.644534) (xy 412.723956 -313.644977) (xy 412.771354 -313.65248)
			(xy 412.816994 -313.667305) (xy 412.859752 -313.689089) (xy 412.898575 -313.717295) (xy 412.932508 -313.751228)
			(xy 412.960713 -313.790051) (xy 412.982496 -313.83281) (xy 412.997321 -313.87845) (xy 413.004823 -313.925848)
			(xy 413.00527 -313.949842) (xy 413.005172 -313.958946) (xy 413.004028 -313.977119) (xy 413.002984 -313.986164)
			(xy 413.001714 -313.998356) (xy 413.009588 -314.020708) (xy 413.086042 -314.093606) (xy 413.108648 -314.100718)
			(xy 413.120586 -314.098686) (xy 413.143349 -314.095262) (xy 413.189362 -314.093991) (xy 413.21228 -314.096146)
			(xy 413.223964 -314.097416) (xy 413.245554 -314.09005) (xy 413.318198 -314.01766) (xy 413.326072 -313.99607)
			(xy 413.324802 -313.984386) (xy 413.323024 -313.949842) (xy 413.323499 -313.924151) (xy 413.331531 -313.8734)
			(xy 413.347405 -313.824531) (xy 413.370729 -313.778747) (xy 413.400929 -313.737176) (xy 413.437261 -313.700842)
			(xy 413.47883 -313.670639) (xy 413.524612 -313.647313) (xy 413.57348 -313.631436) (xy 413.624231 -313.6234)
			(xy 413.649922 -313.622944) (xy 413.682688 -313.624468) (xy 413.69361 -313.625484) (xy 413.713676 -313.61888)
			(xy 413.777684 -313.560968) (xy 413.785185 -313.55342) (xy 413.793828 -313.534001) (xy 413.794448 -313.523376)
			(xy 413.794448 -313.474862) (xy 413.794492 -313.465508) (xy 413.79551 -313.446828) (xy 413.79648 -313.437524)
			(xy 413.798004 -313.42584) (xy 413.790384 -313.40425) (xy 413.717994 -313.331352) (xy 413.696404 -313.323732)
			(xy 413.68472 -313.325002) (xy 413.649922 -313.32678) (xy 413.624233 -313.326304) (xy 413.573489 -313.31827)
			(xy 413.524625 -313.302397) (xy 413.478846 -313.279075) (xy 413.43728 -313.24888) (xy 413.400948 -313.212553)
			(xy 413.370747 -313.17099) (xy 413.347419 -313.125214) (xy 413.33154 -313.076353) (xy 413.323499 -313.025609)
			(xy 413.323496 -312.974232) (xy 413.33153 -312.923487) (xy 413.347403 -312.874624) (xy 413.370725 -312.828845)
			(xy 413.400921 -312.787279) (xy 413.437248 -312.750947) (xy 413.478811 -312.720746) (xy 413.524587 -312.697419)
			(xy 413.573448 -312.681539) (xy 413.624192 -312.673499) (xy 413.675569 -312.673496) (xy 413.726314 -312.68153)
			(xy 413.775177 -312.697404) (xy 413.820956 -312.720726) (xy 413.862522 -312.750922) (xy 413.898854 -312.787249)
			(xy 413.929055 -312.828812) (xy 413.952382 -312.874588) (xy 413.968261 -312.92345) (xy 413.976301 -312.974194)
			(xy 413.97682 -312.999882) (xy 413.975042 -313.03468) (xy 413.973772 -313.04611) (xy 413.981646 -313.0677)
			(xy 414.05429 -313.14009) (xy 414.076134 -313.14771) (xy 414.087564 -313.146186) (xy 414.096931 -313.14521)
			(xy 414.115738 -313.144191) (xy 414.125156 -313.144154) (xy 414.138746 -313.144325) (xy 414.165831 -313.146616)
			(xy 414.179258 -313.148726) (xy 414.191196 -313.150504) (xy 414.213802 -313.143646) (xy 414.290256 -313.070748)
			(xy 414.29813 -313.048396) (xy 414.29686 -313.036204) (xy 414.295812 -313.02716) (xy 414.29467 -313.008986)
			(xy 414.294574 -312.999882) (xy 414.295061 -312.97506) (xy 414.303096 -312.92607) (xy 414.31895 -312.879025)
			(xy 414.342207 -312.835164) (xy 414.372253 -312.795644) (xy 414.408297 -312.761506) (xy 414.449389 -312.733648)
			(xy 414.494446 -312.712806) (xy 414.542282 -312.699527) (xy 414.591636 -312.694163) (xy 414.641207 -312.696853)
			(xy 414.689691 -312.707528) (xy 414.735808 -312.725906) (xy 414.778345 -312.751503) (xy 414.816181 -312.783645)
			(xy 414.848318 -312.821484) (xy 414.87391 -312.864024) (xy 414.892282 -312.910144) (xy 414.902952 -312.958628)
			(xy 414.905636 -313.0082) (xy 414.903744 -313.02559) (xy 415.223194 -313.02559) (xy 415.223194 -312.974174)
			(xy 415.231237 -312.923392) (xy 415.247125 -312.874493) (xy 415.270468 -312.828681) (xy 415.300689 -312.787085)
			(xy 415.337045 -312.750729) (xy 415.378641 -312.720508) (xy 415.424453 -312.697165) (xy 415.473352 -312.681277)
			(xy 415.524134 -312.673234) (xy 415.57555 -312.673234) (xy 415.626332 -312.681277) (xy 415.675231 -312.697165)
			(xy 415.721043 -312.720508) (xy 415.762639 -312.750729) (xy 415.798995 -312.787085) (xy 415.829216 -312.828681)
			(xy 415.852559 -312.874493) (xy 415.868447 -312.923392) (xy 415.87649 -312.974174) (xy 415.876994 -312.999882)
			(xy 416.193998 -312.999882) (xy 416.197958 -312.950828) (xy 416.209735 -312.903044) (xy 416.229026 -312.857768)
			(xy 416.255329 -312.816172) (xy 416.287964 -312.779335) (xy 416.326085 -312.74821) (xy 416.368706 -312.723603)
			(xy 416.414722 -312.706151) (xy 416.462941 -312.696307) (xy 416.512116 -312.694326) (xy 416.560971 -312.700258)
			(xy 416.608242 -312.71395) (xy 416.652704 -312.735048) (xy 416.693207 -312.763004) (xy 416.7287 -312.797096)
			(xy 416.758265 -312.83644) (xy 416.781136 -312.880017) (xy 416.79672 -312.926698) (xy 416.804615 -312.975275)
			(xy 416.80511 -312.999882) (xy 416.804615 -313.024489) (xy 416.79672 -313.073066) (xy 416.781136 -313.119747)
			(xy 416.758265 -313.163324) (xy 416.7287 -313.202668) (xy 416.693207 -313.23676) (xy 416.652704 -313.264716)
			(xy 416.608242 -313.285814) (xy 416.560971 -313.299506) (xy 416.512116 -313.305438) (xy 416.462941 -313.303457)
			(xy 416.414722 -313.293613) (xy 416.368706 -313.276161) (xy 416.326085 -313.251554) (xy 416.287964 -313.220429)
			(xy 416.255329 -313.183592) (xy 416.229026 -313.141996) (xy 416.209735 -313.09672) (xy 416.197958 -313.048936)
			(xy 416.193998 -312.999882) (xy 415.876994 -312.999882) (xy 415.87649 -313.02559) (xy 415.868447 -313.076372)
			(xy 415.852559 -313.125271) (xy 415.829216 -313.171083) (xy 415.798995 -313.212679) (xy 415.762639 -313.249035)
			(xy 415.721043 -313.279256) (xy 415.675231 -313.302599) (xy 415.626332 -313.318487) (xy 415.57555 -313.32653)
			(xy 415.524134 -313.32653) (xy 415.473352 -313.318487) (xy 415.424453 -313.302599) (xy 415.378641 -313.279256)
			(xy 415.337045 -313.249035) (xy 415.300689 -313.212679) (xy 415.270468 -313.171083) (xy 415.247125 -313.125271)
			(xy 415.231237 -313.076372) (xy 415.223194 -313.02559) (xy 414.903744 -313.02559) (xy 414.900266 -313.057554)
			(xy 414.886982 -313.105388) (xy 414.866134 -313.150443) (xy 414.838272 -313.191532) (xy 414.804129 -313.227571)
			(xy 414.764605 -313.257613) (xy 414.720742 -313.280864) (xy 414.673695 -313.296713) (xy 414.624704 -313.304742)
			(xy 414.599882 -313.30519) (xy 414.590781 -313.30515) (xy 414.572609 -313.304133) (xy 414.56356 -313.303158)
			(xy 414.551622 -313.301634) (xy 414.52927 -313.309508) (xy 414.456372 -313.385962) (xy 414.44926 -313.408568)
			(xy 414.451292 -313.420506) (xy 414.453424 -313.433994) (xy 414.455715 -313.461207) (xy 414.455864 -313.474862)
			(xy 414.455864 -313.54522) (xy 414.456329 -313.555875) (xy 414.465025 -313.57533) (xy 414.472628 -313.582812)
			(xy 414.53689 -313.640724) (xy 414.55721 -313.647328) (xy 414.568132 -313.646312) (xy 414.599882 -313.644534)
			(xy 414.625137 -313.645025) (xy 414.674959 -313.653336) (xy 414.722734 -313.669735) (xy 414.767157 -313.693773)
			(xy 414.807018 -313.724796) (xy 414.841229 -313.761957) (xy 414.868856 -313.804242) (xy 414.889147 -313.850497)
			(xy 414.901547 -313.899462) (xy 414.905718 -313.9498) (xy 414.903584 -313.97555) (xy 415.223194 -313.97555)
			(xy 415.223194 -313.924134) (xy 415.231237 -313.873352) (xy 415.247125 -313.824453) (xy 415.270468 -313.778641)
			(xy 415.300689 -313.737045) (xy 415.337045 -313.700689) (xy 415.378641 -313.670468) (xy 415.424453 -313.647125)
			(xy 415.473352 -313.631237) (xy 415.524134 -313.623194) (xy 415.57555 -313.623194) (xy 415.626332 -313.631237)
			(xy 415.675231 -313.647125) (xy 415.721043 -313.670468) (xy 415.762639 -313.700689) (xy 415.798995 -313.737045)
			(xy 415.829216 -313.778641) (xy 415.852559 -313.824453) (xy 415.868447 -313.873352) (xy 415.87649 -313.924134)
			(xy 415.876994 -313.949842) (xy 416.193998 -313.949842) (xy 416.197958 -313.900788) (xy 416.209735 -313.853004)
			(xy 416.229026 -313.807728) (xy 416.255329 -313.766132) (xy 416.287964 -313.729295) (xy 416.326085 -313.69817)
			(xy 416.368706 -313.673563) (xy 416.414722 -313.656111) (xy 416.462941 -313.646267) (xy 416.512116 -313.644286)
			(xy 416.560971 -313.650218) (xy 416.608242 -313.66391) (xy 416.652704 -313.685008) (xy 416.693207 -313.712964)
			(xy 416.7287 -313.747056) (xy 416.758265 -313.7864) (xy 416.781136 -313.829977) (xy 416.79672 -313.876658)
			(xy 416.804615 -313.925235) (xy 416.80511 -313.949842) (xy 416.804615 -313.974449) (xy 416.79672 -314.023026)
			(xy 416.781136 -314.069707) (xy 416.758265 -314.113284) (xy 416.7287 -314.152628) (xy 416.693207 -314.18672)
			(xy 416.652704 -314.214676) (xy 416.608242 -314.235774) (xy 416.560971 -314.249466) (xy 416.512116 -314.255398)
			(xy 416.462941 -314.253417) (xy 416.414722 -314.243573) (xy 416.368706 -314.226121) (xy 416.326085 -314.201514)
			(xy 416.287964 -314.170389) (xy 416.255329 -314.133552) (xy 416.229026 -314.091956) (xy 416.209735 -314.04668)
			(xy 416.197958 -313.998896) (xy 416.193998 -313.949842) (xy 415.876994 -313.949842) (xy 415.87649 -313.97555)
			(xy 415.868447 -314.026332) (xy 415.852559 -314.075231) (xy 415.829216 -314.121043) (xy 415.798995 -314.162639)
			(xy 415.762639 -314.198995) (xy 415.721043 -314.229216) (xy 415.675231 -314.252559) (xy 415.626332 -314.268447)
			(xy 415.57555 -314.27649) (xy 415.524134 -314.27649) (xy 415.473352 -314.268447) (xy 415.424453 -314.252559)
			(xy 415.378641 -314.229216) (xy 415.337045 -314.198995) (xy 415.300689 -314.162639) (xy 415.270468 -314.121043)
			(xy 415.247125 -314.075231) (xy 415.231237 -314.026332) (xy 415.223194 -313.97555) (xy 414.903584 -313.97555)
			(xy 414.901547 -314.000138) (xy 414.889147 -314.049103) (xy 414.868856 -314.095358) (xy 414.841229 -314.137643)
			(xy 414.807018 -314.174804) (xy 414.767157 -314.205827) (xy 414.722734 -314.229865) (xy 414.674959 -314.246264)
			(xy 414.625137 -314.254575) (xy 414.599882 -314.25515) (xy 414.568132 -314.253626) (xy 414.557464 -314.252356)
			(xy 414.537144 -314.25896) (xy 414.472882 -314.316872) (xy 414.465375 -314.324418) (xy 414.456715 -314.343837)
			(xy 414.456118 -314.354464) (xy 414.456118 -314.424822) (xy 414.455958 -314.438476) (xy 414.453672 -314.465689)
			(xy 414.451546 -314.479178) (xy 414.449768 -314.491116) (xy 414.456626 -314.513722) (xy 414.529524 -314.590176)
			(xy 414.551876 -314.59805) (xy 414.563814 -314.596526) (xy 414.572798 -314.595545) (xy 414.590844 -314.59453)
			(xy 414.599882 -314.594494) (xy 414.623494 -314.59494) (xy 414.670154 -314.60222) (xy 414.715139 -314.616592)
			(xy 414.757376 -314.637716) (xy 414.795859 -314.665088) (xy 414.829672 -314.698055) (xy 414.858009 -314.735833)
			(xy 414.880196 -314.777521) (xy 414.895703 -314.822127) (xy 414.904162 -314.868588) (xy 414.90519 -314.892182)
			(xy 414.90582 -314.902318) (xy 414.914044 -314.920867) (xy 414.92884 -314.934751) (xy 414.93821 -314.938664)
			(xy 414.994344 -314.961524) (xy 415.00425 -314.965842) (xy 415.144458 -314.965842) (xy 415.153901 -314.965349)
			(xy 415.171485 -314.958437) (xy 415.178748 -314.95238) (xy 415.236406 -314.899548) (xy 415.244788 -314.882784)
			(xy 415.245804 -314.873132) (xy 415.248516 -314.848108) (xy 415.26108 -314.799371) (xy 415.28147 -314.753356)
			(xy 415.309134 -314.71131) (xy 415.343321 -314.674372) (xy 415.383105 -314.643544) (xy 415.427408 -314.619661)
			(xy 415.475028 -314.603369) (xy 415.524677 -314.595112) (xy 415.575007 -314.595112) (xy 415.624656 -314.603369)
			(xy 415.672276 -314.619661) (xy 415.716579 -314.643544) (xy 415.756363 -314.674372) (xy 415.79055 -314.71131)
			(xy 415.818214 -314.753356) (xy 415.838604 -314.799371) (xy 415.851168 -314.848108) (xy 415.85388 -314.873132)
			(xy 415.854896 -314.882784) (xy 415.863278 -314.899548) (xy 415.920936 -314.95238) (xy 415.92814 -314.958532)
			(xy 415.945761 -314.965449) (xy 415.955226 -314.965842) (xy 416.095434 -314.965842) (xy 416.10534 -314.961524)
			(xy 416.161474 -314.938664) (xy 416.170804 -314.934689) (xy 416.185559 -314.9208) (xy 416.193829 -314.9023)
			(xy 416.194494 -314.892182) (xy 416.195603 -314.867339) (xy 416.20488 -314.818487) (xy 416.221949 -314.771783)
			(xy 416.246359 -314.728461) (xy 416.277465 -314.689666) (xy 416.314445 -314.656422) (xy 416.356322 -314.629609)
			(xy 416.401989 -314.609934) (xy 416.450241 -314.597917) (xy 416.499802 -314.593875) (xy 416.549363 -314.597917)
			(xy 416.597615 -314.609934) (xy 416.643282 -314.629609) (xy 416.685159 -314.656422) (xy 416.722139 -314.689666)
			(xy 416.753245 -314.728461) (xy 416.777655 -314.771783) (xy 416.794724 -314.818487) (xy 416.804001 -314.867339)
			(xy 416.80511 -314.892182) (xy 416.805741 -314.902317) (xy 416.813966 -314.920863) (xy 416.828765 -314.934741)
			(xy 416.83813 -314.938664) (xy 416.894264 -314.961524) (xy 416.90417 -314.965842) (xy 417.044632 -314.965842)
			(xy 417.054077 -314.965354) (xy 417.071667 -314.958448) (xy 417.078922 -314.95238) (xy 417.13658 -314.899548)
			(xy 417.144962 -314.882784) (xy 417.145978 -314.873132) (xy 417.148654 -314.848341) (xy 417.16103 -314.800042)
			(xy 417.181086 -314.754393) (xy 417.208288 -314.712607) (xy 417.241914 -314.675793) (xy 417.281072 -314.644928)
			(xy 417.324723 -314.620832) (xy 417.371707 -314.604144) (xy 417.420777 -314.595307) (xy 417.445698 -314.594494)
			(xy 417.455858 -314.594494) (xy 417.474146 -314.58662) (xy 417.531296 -314.528708) (xy 417.537982 -314.521299)
			(xy 417.545568 -314.502863) (xy 417.546028 -314.492894) (xy 417.546028 -314.37834) (xy 417.545517 -314.368438)
			(xy 417.537949 -314.35013) (xy 417.531296 -314.34278) (xy 417.473892 -314.284614) (xy 417.455858 -314.276994)
			(xy 417.445698 -314.27674) (xy 417.420218 -314.275932) (xy 417.369962 -314.26739) (xy 417.321641 -314.251151)
			(xy 417.276426 -314.227611) (xy 417.235411 -314.197338) (xy 417.199592 -314.161067) (xy 417.169836 -314.119676)
			(xy 417.146865 -314.074169) (xy 417.131234 -314.025648) (xy 417.123322 -313.975289) (xy 417.123322 -313.924312)
			(xy 417.131233 -313.873953) (xy 417.146864 -313.825432) (xy 417.169836 -313.779925) (xy 417.199592 -313.738534)
			(xy 417.235411 -313.702263) (xy 417.276425 -313.67199) (xy 417.32164 -313.648449) (xy 417.369961 -313.63221)
			(xy 417.420217 -313.623668) (xy 417.445698 -313.622944) (xy 417.455858 -313.62269) (xy 417.473892 -313.61507)
			(xy 417.531296 -313.556904) (xy 417.537946 -313.549548) (xy 417.545528 -313.531247) (xy 417.546028 -313.521344)
			(xy 417.546028 -313.42838) (xy 417.545506 -313.418482) (xy 417.537924 -313.40019) (xy 417.531296 -313.39282)
			(xy 417.473892 -313.334654) (xy 417.455858 -313.327034) (xy 417.445698 -313.32678) (xy 417.420223 -313.325973)
			(xy 417.369976 -313.317432) (xy 417.321664 -313.301196) (xy 417.276457 -313.277659) (xy 417.23545 -313.247392)
			(xy 417.199638 -313.211127) (xy 417.169887 -313.169744) (xy 417.14692 -313.124245) (xy 417.131292 -313.075733)
			(xy 417.123382 -313.025383) (xy 417.123382 -312.974416) (xy 417.131292 -312.924066) (xy 417.14692 -312.875554)
			(xy 417.169888 -312.830056) (xy 417.199638 -312.788672) (xy 417.235451 -312.752408) (xy 417.276457 -312.72214)
			(xy 417.321664 -312.698604) (xy 417.369976 -312.682368) (xy 417.420223 -312.673827) (xy 417.445698 -312.672984)
			(xy 417.455858 -312.67273) (xy 417.473892 -312.66511) (xy 417.531296 -312.606944) (xy 417.537952 -312.59959)
			(xy 417.545548 -312.58129) (xy 417.546028 -312.571384) (xy 417.546028 -312.45683) (xy 417.545542 -312.446867)
			(xy 417.537956 -312.428441) (xy 417.531296 -312.421016) (xy 417.474146 -312.363104) (xy 417.455858 -312.35523)
			(xy 417.445698 -312.35523) (xy 417.420674 -312.354375) (xy 417.371397 -312.345512) (xy 417.324227 -312.32873)
			(xy 417.280426 -312.304477) (xy 417.241168 -312.273404) (xy 417.207505 -312.236343) (xy 417.180338 -312.194286)
			(xy 417.160397 -312.148362) (xy 417.148214 -312.0998) (xy 417.144116 -312.0499) (xy 417.148214 -312.000001)
			(xy 417.160396 -311.951439) (xy 417.180338 -311.905514) (xy 417.207504 -311.863458) (xy 417.241167 -311.826397)
			(xy 417.280425 -311.795323) (xy 417.324226 -311.771071) (xy 417.371397 -311.754288) (xy 417.420673 -311.745425)
			(xy 417.445698 -311.744614) (xy 417.455858 -311.744614) (xy 417.474146 -311.73674) (xy 417.531296 -311.678828)
			(xy 417.537985 -311.67142) (xy 417.545578 -311.652984) (xy 417.546028 -311.643014) (xy 417.546028 -311.50687)
			(xy 417.545549 -311.496904) (xy 417.537974 -311.478468) (xy 417.531296 -311.471056) (xy 417.474146 -311.413144)
			(xy 417.455858 -311.40527) (xy 417.445698 -311.40527) (xy 417.420679 -311.404414) (xy 417.371412 -311.395553)
			(xy 417.324251 -311.378774) (xy 417.280458 -311.354526) (xy 417.241208 -311.323459) (xy 417.207552 -311.286405)
			(xy 417.180391 -311.244357) (xy 417.160454 -311.198442) (xy 417.148273 -311.149889) (xy 417.144177 -311.099999)
			(xy 417.148273 -311.05011) (xy 417.160454 -311.001557) (xy 417.180392 -310.955642) (xy 417.207553 -310.913594)
			(xy 417.241209 -310.87654) (xy 417.280459 -310.845473) (xy 417.324252 -310.821225) (xy 417.371413 -310.804446)
			(xy 417.42068 -310.795585) (xy 417.445698 -310.794654) (xy 417.455858 -310.794654) (xy 417.474146 -310.78678)
			(xy 417.531296 -310.728868) (xy 417.537975 -310.721457) (xy 417.545547 -310.703021) (xy 417.546028 -310.693054)
			(xy 417.546028 -310.556656) (xy 417.545547 -310.546691) (xy 417.537968 -310.528259) (xy 417.531296 -310.520842)
			(xy 417.474146 -310.46293) (xy 417.455858 -310.455056) (xy 417.445698 -310.455056) (xy 417.420672 -310.454201)
			(xy 417.371391 -310.445337) (xy 417.324216 -310.428553) (xy 417.280411 -310.404299) (xy 417.24115 -310.373223)
			(xy 417.207484 -310.336159) (xy 417.180316 -310.294099) (xy 417.160372 -310.248171) (xy 417.148188 -310.199604)
			(xy 417.14409 -310.149701) (xy 417.148188 -310.099797) (xy 417.160372 -310.051231) (xy 417.180315 -310.005302)
			(xy 417.207483 -309.963242) (xy 417.241149 -309.926178) (xy 417.28041 -309.895102) (xy 417.324215 -309.870847)
			(xy 417.37139 -309.854063) (xy 417.42067 -309.845199) (xy 417.445698 -309.84444) (xy 417.455858 -309.84444)
			(xy 417.474146 -309.836566) (xy 417.531296 -309.778654) (xy 417.537989 -309.771248) (xy 417.545592 -309.752812)
			(xy 417.546028 -309.74284) (xy 417.546028 -297.221656) (xy 417.546511 -297.211693) (xy 417.554096 -297.193265)
			(xy 417.56076 -297.185842) (xy 417.671758 -297.07459) (xy 417.678572 -297.067246) (xy 417.686307 -297.048783)
			(xy 417.686744 -297.038776) (xy 417.686744 -296.82821) (xy 417.687167 -296.81814) (xy 417.694883 -296.799537)
			(xy 417.70173 -296.792142) (xy 417.735512 -296.75836) (xy 417.742563 -296.750499) (xy 417.750157 -296.730821)
			(xy 417.750244 -296.72026) (xy 417.746434 -296.634408) (xy 417.737036 -296.615866) (xy 417.728908 -296.608754)
			(xy 417.708801 -296.59121) (xy 417.674461 -296.550371) (xy 417.64775 -296.50418) (xy 417.629481 -296.454046)
			(xy 417.620212 -296.401499) (xy 417.619688 -296.37482) (xy 417.620143 -296.350922) (xy 417.627577 -296.303707)
			(xy 417.642283 -296.258229) (xy 417.6639 -296.215601) (xy 417.6919 -296.176865) (xy 417.725597 -296.142968)
			(xy 417.764168 -296.114741) (xy 417.806668 -296.092873) (xy 417.829238 -296.085006) (xy 417.844986 -296.079672)
			(xy 417.864036 -296.053256) (xy 417.864036 -294.796464) (xy 417.844986 -294.770048) (xy 417.829238 -294.764714)
			(xy 417.8052 -294.756232) (xy 417.760131 -294.732423) (xy 417.719643 -294.701457) (xy 417.684861 -294.664197)
			(xy 417.656753 -294.621676) (xy 417.636098 -294.575077) (xy 417.623471 -294.525694) (xy 417.619223 -294.4749)
			(xy 417.623471 -294.424106) (xy 417.636098 -294.374723) (xy 417.656753 -294.328124) (xy 417.684861 -294.285603)
			(xy 417.719643 -294.248343) (xy 417.760131 -294.217377) (xy 417.8052 -294.193568) (xy 417.829238 -294.185086)
			(xy 417.844986 -294.179752) (xy 417.864036 -294.153336) (xy 417.864036 -294.124888) (xy 417.863609 -294.11482)
			(xy 417.855884 -294.096225) (xy 417.84905 -294.08882) (xy 417.70173 -293.9415) (xy 417.69488 -293.934103)
			(xy 417.687141 -293.915505) (xy 417.686744 -293.905432) (xy 417.686744 -293.773606) (xy 417.686387 -293.764588)
			(xy 417.680145 -293.747668) (xy 417.674552 -293.740586) (xy 417.657907 -293.720477) (xy 417.630515 -293.676043)
			(xy 417.610449 -293.627855) (xy 417.598207 -293.577112) (xy 417.594095 -293.525075) (xy 417.598215 -293.473039)
			(xy 417.610464 -293.422297) (xy 417.630538 -293.374113) (xy 417.657937 -293.329683) (xy 417.674552 -293.309548)
			(xy 417.680394 -293.302436) (xy 417.683442 -293.294054) (xy 417.684965 -293.289767) (xy 417.68662 -293.280822)
			(xy 417.686744 -293.276274) (xy 417.686744 -292.823392) (xy 417.686384 -292.814375) (xy 417.680139 -292.797458)
			(xy 417.674552 -292.790372) (xy 417.657908 -292.770263) (xy 417.630518 -292.725829) (xy 417.610454 -292.677642)
			(xy 417.598215 -292.6269) (xy 417.594105 -292.574864) (xy 417.598226 -292.52283) (xy 417.610476 -292.47209)
			(xy 417.630551 -292.423907) (xy 417.657951 -292.37948) (xy 417.674552 -292.359334) (xy 417.680394 -292.352222)
			(xy 417.683442 -292.34384) (xy 417.684967 -292.339553) (xy 417.686637 -292.330609) (xy 417.686744 -292.32606)
			(xy 417.686744 -291.873432) (xy 417.686391 -291.864413) (xy 417.680156 -291.847486) (xy 417.674552 -291.840412)
			(xy 417.657905 -291.820303) (xy 417.630509 -291.775868) (xy 417.610439 -291.727679) (xy 417.598194 -291.676934)
			(xy 417.594078 -291.624895) (xy 417.598195 -291.572856) (xy 417.610442 -291.522111) (xy 417.630514 -291.473922)
			(xy 417.657912 -291.429489) (xy 417.674552 -291.409374) (xy 417.680394 -291.402262) (xy 417.683442 -291.39388)
			(xy 417.684962 -291.389592) (xy 417.686621 -291.380648) (xy 417.686744 -291.3761) (xy 417.686744 -290.923472)
			(xy 417.686381 -290.914457) (xy 417.680131 -290.897544) (xy 417.674552 -290.890452) (xy 417.657902 -290.870343)
			(xy 417.6305 -290.825907) (xy 417.610423 -290.777716) (xy 417.598173 -290.726968) (xy 417.594052 -290.674925)
			(xy 417.598165 -290.622882) (xy 417.610408 -290.572132) (xy 417.630477 -290.523938) (xy 417.657873 -290.479498)
			(xy 417.674552 -290.459414) (xy 417.680394 -290.452302) (xy 417.683442 -290.44392) (xy 417.684965 -290.439632)
			(xy 417.686632 -290.430688) (xy 417.686744 -290.42614) (xy 417.686744 -289.973512) (xy 417.686388 -289.964494)
			(xy 417.680148 -289.947572) (xy 417.674552 -289.940492) (xy 417.657907 -289.920383) (xy 417.630514 -289.875949)
			(xy 417.610446 -289.82776) (xy 417.598204 -289.777017) (xy 417.594091 -289.724979) (xy 417.598211 -289.672943)
			(xy 417.610459 -289.622201) (xy 417.630532 -289.574015) (xy 417.657931 -289.529584) (xy 417.674552 -289.509454)
			(xy 417.680394 -289.502342) (xy 417.683442 -289.49396) (xy 417.684966 -289.489673) (xy 417.686622 -289.480728)
			(xy 417.686744 -289.47618) (xy 417.686744 -289.023552) (xy 417.686378 -289.014538) (xy 417.680122 -288.997629)
			(xy 417.674552 -288.990532) (xy 417.657904 -288.970423) (xy 417.630504 -288.925988) (xy 417.610431 -288.877797)
			(xy 417.598183 -288.827051) (xy 417.594065 -288.77501) (xy 417.59818 -288.722969) (xy 417.610425 -288.672221)
			(xy 417.630495 -288.62403) (xy 417.657892 -288.579593) (xy 417.674552 -288.559494) (xy 417.680394 -288.552382)
			(xy 417.683442 -288.544) (xy 417.684963 -288.539712) (xy 417.686626 -288.530768) (xy 417.686744 -288.52622)
			(xy 417.686744 -287.123632) (xy 417.686391 -287.114613) (xy 417.680156 -287.097686) (xy 417.674552 -287.090612)
			(xy 417.657905 -287.070503) (xy 417.630509 -287.026068) (xy 417.610439 -286.977879) (xy 417.598194 -286.927134)
			(xy 417.594078 -286.875095) (xy 417.598195 -286.823056) (xy 417.610442 -286.772311) (xy 417.630514 -286.724122)
			(xy 417.657912 -286.679689) (xy 417.674552 -286.659574) (xy 417.680394 -286.652462) (xy 417.683442 -286.64408)
			(xy 417.684962 -286.639792) (xy 417.686621 -286.630848) (xy 417.686744 -286.6263) (xy 417.686744 -286.182816)
			(xy 417.686619 -286.178269) (xy 417.684954 -286.169326) (xy 417.683442 -286.165036) (xy 417.674298 -286.140652)
			(xy 417.669218 -286.134302) (xy 417.651671 -286.111975) (xy 417.623699 -286.06256) (xy 417.604584 -286.009092)
			(xy 417.594888 -285.953143) (xy 417.594288 -285.924752) (xy 417.594801 -285.898984) (xy 417.602836 -285.848077)
			(xy 417.61029 -285.823406) (xy 417.61029 -285.822898) (xy 417.612203 -285.816266) (xy 417.612721 -285.802476)
			(xy 417.611306 -285.79572) (xy 417.609487 -285.788944) (xy 417.602659 -285.776692) (xy 417.597844 -285.77159)
			(xy 417.416996 -285.590742) (xy 417.409599 -285.583892) (xy 417.391001 -285.576152) (xy 417.380928 -285.575756)
			(xy 417.314888 -285.575756) (xy 417.290758 -285.590488) (xy 417.284154 -285.603188) (xy 417.235894 -285.69539)
			(xy 417.237672 -285.723584) (xy 417.2458 -285.735268) (xy 417.259865 -285.756223) (xy 417.282157 -285.8015)
			(xy 417.297315 -285.849638) (xy 417.304986 -285.899518) (xy 417.30549 -285.924752) (xy 417.30498 -285.950739)
			(xy 417.29685 -286.002074) (xy 417.280789 -286.051504) (xy 417.257193 -286.097814) (xy 417.226643 -286.139862)
			(xy 417.189892 -286.176613) (xy 417.147844 -286.207163) (xy 417.101534 -286.230759) (xy 417.052104 -286.24682)
			(xy 417.000769 -286.25495) (xy 416.948795 -286.25495) (xy 416.89746 -286.24682) (xy 416.84803 -286.230759)
			(xy 416.80172 -286.207163) (xy 416.759672 -286.176613) (xy 416.722921 -286.139862) (xy 416.692371 -286.097814)
			(xy 416.668775 -286.051504) (xy 416.652714 -286.002074) (xy 416.644584 -285.950739) (xy 416.644074 -285.924752)
			(xy 416.644074 -285.924498) (xy 416.644507 -285.899763) (xy 416.651869 -285.850845) (xy 416.666444 -285.803571)
			(xy 416.687905 -285.758999) (xy 416.701478 -285.738316) (xy 416.702748 -285.736538) (xy 416.711638 -285.7246)
			(xy 416.713924 -285.695644) (xy 416.66541 -285.603188) (xy 416.658806 -285.590488) (xy 416.634676 -285.575756)
			(xy 416.364928 -285.575756) (xy 416.340798 -285.590488) (xy 416.334194 -285.603188) (xy 416.285934 -285.69539)
			(xy 416.287712 -285.723584) (xy 416.29584 -285.735268) (xy 416.309904 -285.756224) (xy 416.332193 -285.801502)
			(xy 416.347349 -285.849639) (xy 416.355019 -285.899519) (xy 416.35553 -285.924752) (xy 416.35502 -285.950739)
			(xy 416.34689 -286.002074) (xy 416.330829 -286.051504) (xy 416.307233 -286.097814) (xy 416.276683 -286.139862)
			(xy 416.239932 -286.176613) (xy 416.197884 -286.207163) (xy 416.151574 -286.230759) (xy 416.102144 -286.24682)
			(xy 416.050809 -286.25495) (xy 415.998835 -286.25495) (xy 415.9475 -286.24682) (xy 415.89807 -286.230759)
			(xy 415.85176 -286.207163) (xy 415.809712 -286.176613) (xy 415.772961 -286.139862) (xy 415.742411 -286.097814)
			(xy 415.718815 -286.051504) (xy 415.702754 -286.002074) (xy 415.694624 -285.950739) (xy 415.694114 -285.924752)
			(xy 415.694114 -285.924498) (xy 415.694547 -285.899763) (xy 415.70191 -285.850845) (xy 415.716486 -285.803572)
			(xy 415.73795 -285.759002) (xy 415.751518 -285.738316) (xy 415.752788 -285.736538) (xy 415.761678 -285.7246)
			(xy 415.763964 -285.695644) (xy 415.71545 -285.603188) (xy 415.708846 -285.590488) (xy 415.684716 -285.575756)
			(xy 415.414968 -285.575756) (xy 415.390838 -285.590488) (xy 415.384234 -285.603188) (xy 415.335974 -285.69539)
			(xy 415.337752 -285.723584) (xy 415.34588 -285.735268) (xy 415.359946 -285.756223) (xy 415.382239 -285.8015)
			(xy 415.397398 -285.849637) (xy 415.40507 -285.899518) (xy 415.40557 -285.924752) (xy 415.40506 -285.950739)
			(xy 415.39693 -286.002074) (xy 415.380869 -286.051504) (xy 415.357273 -286.097814) (xy 415.326723 -286.139862)
			(xy 415.289972 -286.176613) (xy 415.247924 -286.207163) (xy 415.201614 -286.230759) (xy 415.152184 -286.24682)
			(xy 415.100849 -286.25495) (xy 415.048875 -286.25495) (xy 414.99754 -286.24682) (xy 414.94811 -286.230759)
			(xy 414.9018 -286.207163) (xy 414.859752 -286.176613) (xy 414.823001 -286.139862) (xy 414.792451 -286.097814)
			(xy 414.768855 -286.051504) (xy 414.752794 -286.002074) (xy 414.744664 -285.950739) (xy 414.744154 -285.924752)
			(xy 414.744154 -285.924498) (xy 414.744587 -285.899763) (xy 414.751949 -285.850844) (xy 414.766523 -285.80357)
			(xy 414.787983 -285.758998) (xy 414.801558 -285.738316) (xy 414.802828 -285.736538) (xy 414.811718 -285.7246)
			(xy 414.814004 -285.695644) (xy 414.76549 -285.603188) (xy 414.758886 -285.590488) (xy 414.734756 -285.575756)
			(xy 414.465008 -285.575756) (xy 414.440878 -285.590488) (xy 414.434274 -285.603188) (xy 414.386014 -285.69539)
			(xy 414.387792 -285.723584) (xy 414.39592 -285.735268) (xy 414.409984 -285.756224) (xy 414.432275 -285.801501)
			(xy 414.447432 -285.849638) (xy 414.455103 -285.899519) (xy 414.45561 -285.924752) (xy 414.4551 -285.950739)
			(xy 414.44697 -286.002074) (xy 414.430909 -286.051504) (xy 414.407313 -286.097814) (xy 414.376763 -286.139862)
			(xy 414.340012 -286.176613) (xy 414.297964 -286.207163) (xy 414.251654 -286.230759) (xy 414.202224 -286.24682)
			(xy 414.150889 -286.25495) (xy 414.098915 -286.25495) (xy 414.04758 -286.24682) (xy 413.99815 -286.230759)
			(xy 413.95184 -286.207163) (xy 413.909792 -286.176613) (xy 413.873041 -286.139862) (xy 413.842491 -286.097814)
			(xy 413.818895 -286.051504) (xy 413.802834 -286.002074) (xy 413.794704 -285.950739) (xy 413.794194 -285.924752)
			(xy 413.794194 -285.924498) (xy 413.794627 -285.899763) (xy 413.80199 -285.850845) (xy 413.816565 -285.803572)
			(xy 413.838028 -285.759) (xy 413.851598 -285.738316) (xy 413.852868 -285.736538) (xy 413.861758 -285.7246)
			(xy 413.864044 -285.695644) (xy 413.81553 -285.603188) (xy 413.808926 -285.590488) (xy 413.784796 -285.575756)
			(xy 413.515048 -285.575756) (xy 413.490918 -285.590488) (xy 413.484314 -285.603188) (xy 413.436054 -285.69539)
			(xy 413.437832 -285.723584) (xy 413.44596 -285.735268) (xy 413.460023 -285.756224) (xy 413.482311 -285.801502)
			(xy 413.497466 -285.849639) (xy 413.505136 -285.899519) (xy 413.50565 -285.924752) (xy 413.50514 -285.950739)
			(xy 413.49701 -286.002074) (xy 413.480949 -286.051504) (xy 413.457353 -286.097814) (xy 413.426803 -286.139862)
			(xy 413.390052 -286.176613) (xy 413.348004 -286.207163) (xy 413.301694 -286.230759) (xy 413.252264 -286.24682)
			(xy 413.200929 -286.25495) (xy 413.148955 -286.25495) (xy 413.09762 -286.24682) (xy 413.04819 -286.230759)
			(xy 413.00188 -286.207163) (xy 412.959832 -286.176613) (xy 412.923081 -286.139862) (xy 412.892531 -286.097814)
			(xy 412.868935 -286.051504) (xy 412.852874 -286.002074) (xy 412.844744 -285.950739) (xy 412.844234 -285.924752)
			(xy 412.844234 -285.924498) (xy 412.844667 -285.899763) (xy 412.85203 -285.850845) (xy 412.866608 -285.803573)
			(xy 412.888072 -285.759003) (xy 412.901638 -285.738316) (xy 412.902908 -285.736538) (xy 412.911798 -285.7246)
			(xy 412.914084 -285.695644) (xy 412.86557 -285.603188) (xy 412.858966 -285.590488) (xy 412.834836 -285.575756)
			(xy 412.565088 -285.575756) (xy 412.540958 -285.590488) (xy 412.534354 -285.603188) (xy 412.486094 -285.69539)
			(xy 412.487872 -285.723584) (xy 412.496 -285.735268) (xy 412.510065 -285.756223) (xy 412.532357 -285.8015)
			(xy 412.547515 -285.849638) (xy 412.555186 -285.899518) (xy 412.55569 -285.924752) (xy 412.55518 -285.950739)
			(xy 412.54705 -286.002074) (xy 412.530989 -286.051504) (xy 412.507393 -286.097814) (xy 412.476843 -286.139862)
			(xy 412.440092 -286.176613) (xy 412.398044 -286.207163) (xy 412.351734 -286.230759) (xy 412.302304 -286.24682)
			(xy 412.250969 -286.25495) (xy 412.198995 -286.25495) (xy 412.14766 -286.24682) (xy 412.09823 -286.230759)
			(xy 412.05192 -286.207163) (xy 412.009872 -286.176613) (xy 411.973121 -286.139862) (xy 411.942571 -286.097814)
			(xy 411.918975 -286.051504) (xy 411.902914 -286.002074) (xy 411.894784 -285.950739) (xy 411.894274 -285.924752)
			(xy 411.894274 -285.924498) (xy 411.894707 -285.899763) (xy 411.902069 -285.850845) (xy 411.916644 -285.803571)
			(xy 411.938105 -285.758999) (xy 411.951678 -285.738316) (xy 411.952948 -285.736538) (xy 411.961838 -285.7246)
			(xy 411.964124 -285.695644) (xy 411.91561 -285.603188) (xy 411.909006 -285.590488) (xy 411.884876 -285.575756)
			(xy 411.615128 -285.575756) (xy 411.590998 -285.590488) (xy 411.584394 -285.603188) (xy 411.536134 -285.69539)
			(xy 411.537912 -285.723584) (xy 411.54604 -285.735268) (xy 411.560104 -285.756224) (xy 411.582393 -285.801502)
			(xy 411.597549 -285.849639) (xy 411.605219 -285.899519) (xy 411.60573 -285.924752) (xy 411.60522 -285.950739)
			(xy 411.59709 -286.002074) (xy 411.581029 -286.051504) (xy 411.557433 -286.097814) (xy 411.526883 -286.139862)
			(xy 411.490132 -286.176613) (xy 411.448084 -286.207163) (xy 411.401774 -286.230759) (xy 411.352344 -286.24682)
			(xy 411.301009 -286.25495) (xy 411.249035 -286.25495) (xy 411.1977 -286.24682) (xy 411.14827 -286.230759)
			(xy 411.10196 -286.207163) (xy 411.059912 -286.176613) (xy 411.023161 -286.139862) (xy 410.992611 -286.097814)
			(xy 410.969015 -286.051504) (xy 410.952954 -286.002074) (xy 410.944824 -285.950739) (xy 410.944314 -285.924752)
			(xy 410.944314 -285.924498) (xy 410.944747 -285.899763) (xy 410.95211 -285.850845) (xy 410.966686 -285.803572)
			(xy 410.98815 -285.759002) (xy 411.001718 -285.738316) (xy 411.002988 -285.736538) (xy 411.011878 -285.7246)
			(xy 411.014164 -285.695644) (xy 410.96565 -285.603188) (xy 410.959046 -285.590488) (xy 410.934916 -285.575756)
			(xy 410.664914 -285.575756) (xy 410.640784 -285.590488) (xy 410.63418 -285.603188) (xy 410.58592 -285.69539)
			(xy 410.587698 -285.723584) (xy 410.595826 -285.735268) (xy 410.60989 -285.756224) (xy 410.632181 -285.801501)
			(xy 410.647337 -285.849638) (xy 410.655008 -285.899519) (xy 410.655516 -285.924752) (xy 410.655006 -285.950739)
			(xy 410.646876 -286.002074) (xy 410.630815 -286.051504) (xy 410.607219 -286.097814) (xy 410.576669 -286.139862)
			(xy 410.539918 -286.176613) (xy 410.49787 -286.207163) (xy 410.45156 -286.230759) (xy 410.40213 -286.24682)
			(xy 410.350795 -286.25495) (xy 410.298821 -286.25495) (xy 410.247486 -286.24682) (xy 410.198056 -286.230759)
			(xy 410.151746 -286.207163) (xy 410.109698 -286.176613) (xy 410.072947 -286.139862) (xy 410.042397 -286.097814)
			(xy 410.018801 -286.051504) (xy 410.00274 -286.002074) (xy 409.99461 -285.950739) (xy 409.9941 -285.924752)
			(xy 409.9941 -285.924498) (xy 409.994533 -285.899763) (xy 410.001896 -285.850845) (xy 410.016472 -285.803572)
			(xy 410.037934 -285.759001) (xy 410.051504 -285.738316) (xy 410.052774 -285.736538) (xy 410.061664 -285.7246)
			(xy 410.06395 -285.695644) (xy 410.015436 -285.603188) (xy 410.008832 -285.590488) (xy 409.984702 -285.575756)
			(xy 409.714954 -285.575756) (xy 409.690824 -285.590488) (xy 409.68422 -285.603188) (xy 409.63596 -285.69539)
			(xy 409.637738 -285.723584) (xy 409.645866 -285.735268) (xy 409.659933 -285.756223) (xy 409.682227 -285.801499)
			(xy 409.697386 -285.849637) (xy 409.705058 -285.899518) (xy 409.705556 -285.924752) (xy 409.705046 -285.950739)
			(xy 409.696916 -286.002074) (xy 409.680855 -286.051504) (xy 409.657259 -286.097814) (xy 409.626709 -286.139862)
			(xy 409.589958 -286.176613) (xy 409.54791 -286.207163) (xy 409.5016 -286.230759) (xy 409.45217 -286.24682)
			(xy 409.400835 -286.25495) (xy 409.348861 -286.25495) (xy 409.297526 -286.24682) (xy 409.248096 -286.230759)
			(xy 409.201786 -286.207163) (xy 409.159738 -286.176613) (xy 409.122987 -286.139862) (xy 409.092437 -286.097814)
			(xy 409.068841 -286.051504) (xy 409.05278 -286.002074) (xy 409.04465 -285.950739) (xy 409.04414 -285.924752)
			(xy 409.04414 -285.924498) (xy 409.044573 -285.899763) (xy 409.051934 -285.850844) (xy 409.066508 -285.803569)
			(xy 409.087968 -285.758997) (xy 409.101544 -285.738316) (xy 409.102814 -285.736538) (xy 409.111704 -285.7246)
			(xy 409.11399 -285.695644) (xy 409.065476 -285.603188) (xy 409.058872 -285.590488) (xy 409.034742 -285.575756)
			(xy 408.764994 -285.575756) (xy 408.740864 -285.590488) (xy 408.73426 -285.603188) (xy 408.686 -285.69539)
			(xy 408.687778 -285.723584) (xy 408.695906 -285.735268) (xy 408.709971 -285.756224) (xy 408.732263 -285.801501)
			(xy 408.74742 -285.849638) (xy 408.755091 -285.899518) (xy 408.755596 -285.924752) (xy 408.755086 -285.950739)
			(xy 408.746956 -286.002074) (xy 408.730895 -286.051504) (xy 408.707299 -286.097814) (xy 408.676749 -286.139862)
			(xy 408.639998 -286.176613) (xy 408.59795 -286.207163) (xy 408.55164 -286.230759) (xy 408.50221 -286.24682)
			(xy 408.450875 -286.25495) (xy 408.398901 -286.25495) (xy 408.347566 -286.24682) (xy 408.298136 -286.230759)
			(xy 408.251826 -286.207163) (xy 408.209778 -286.176613) (xy 408.173027 -286.139862) (xy 408.142477 -286.097814)
			(xy 408.118881 -286.051504) (xy 408.10282 -286.002074) (xy 408.09469 -285.950739) (xy 408.09418 -285.924752)
			(xy 408.09418 -285.924498) (xy 408.094613 -285.899763) (xy 408.101975 -285.850845) (xy 408.11655 -285.803571)
			(xy 408.138012 -285.758999) (xy 408.151584 -285.738316) (xy 408.152854 -285.736538) (xy 408.161744 -285.7246)
			(xy 408.16403 -285.695644) (xy 408.115516 -285.603188) (xy 408.108912 -285.590488) (xy 408.084782 -285.575756)
			(xy 406.865074 -285.575756) (xy 406.840944 -285.590488) (xy 406.83434 -285.603188) (xy 406.78608 -285.69539)
			(xy 406.787858 -285.723584) (xy 406.795986 -285.735268) (xy 406.810052 -285.756223) (xy 406.832345 -285.8015)
			(xy 406.847503 -285.849637) (xy 406.855175 -285.899518) (xy 406.855676 -285.924752) (xy 406.855166 -285.950739)
			(xy 406.847036 -286.002074) (xy 406.830975 -286.051504) (xy 406.807379 -286.097814) (xy 406.776829 -286.139862)
			(xy 406.740078 -286.176613) (xy 406.69803 -286.207163) (xy 406.65172 -286.230759) (xy 406.60229 -286.24682)
			(xy 406.550955 -286.25495) (xy 406.498981 -286.25495) (xy 406.447646 -286.24682) (xy 406.398216 -286.230759)
			(xy 406.351906 -286.207163) (xy 406.309858 -286.176613) (xy 406.273107 -286.139862) (xy 406.242557 -286.097814)
			(xy 406.218961 -286.051504) (xy 406.2029 -286.002074) (xy 406.19477 -285.950739) (xy 406.19426 -285.924752)
			(xy 406.19426 -285.924498) (xy 406.194693 -285.899763) (xy 406.202055 -285.850844) (xy 406.216629 -285.80357)
			(xy 406.23809 -285.758998) (xy 406.251664 -285.738316) (xy 406.252934 -285.736538) (xy 406.261824 -285.7246)
			(xy 406.26411 -285.695644) (xy 406.215596 -285.603188) (xy 406.208992 -285.590488) (xy 406.184862 -285.575756)
			(xy 405.915114 -285.575756) (xy 405.890984 -285.590488) (xy 405.88438 -285.603188) (xy 405.83612 -285.69539)
			(xy 405.837898 -285.723584) (xy 405.846026 -285.735268) (xy 405.86009 -285.756224) (xy 405.882381 -285.801501)
			(xy 405.897537 -285.849638) (xy 405.905208 -285.899519) (xy 405.905716 -285.924752) (xy 405.905206 -285.950739)
			(xy 405.897076 -286.002074) (xy 405.881015 -286.051504) (xy 405.857419 -286.097814) (xy 405.826869 -286.139862)
			(xy 405.790118 -286.176613) (xy 405.74807 -286.207163) (xy 405.70176 -286.230759) (xy 405.65233 -286.24682)
			(xy 405.600995 -286.25495) (xy 405.549021 -286.25495) (xy 405.497686 -286.24682) (xy 405.448256 -286.230759)
			(xy 405.401946 -286.207163) (xy 405.359898 -286.176613) (xy 405.323147 -286.139862) (xy 405.292597 -286.097814)
			(xy 405.269001 -286.051504) (xy 405.25294 -286.002074) (xy 405.24481 -285.950739) (xy 405.2443 -285.924752)
			(xy 405.2443 -285.924498) (xy 405.244733 -285.899763) (xy 405.252096 -285.850845) (xy 405.266672 -285.803572)
			(xy 405.288134 -285.759001) (xy 405.301704 -285.738316) (xy 405.302974 -285.736538) (xy 405.311864 -285.7246)
			(xy 405.31415 -285.695644) (xy 405.265636 -285.603188) (xy 405.259032 -285.590488) (xy 405.234902 -285.575756)
			(xy 404.9649 -285.575756) (xy 404.94077 -285.590488) (xy 404.934166 -285.603188) (xy 404.885906 -285.69539)
			(xy 404.887684 -285.723584) (xy 404.895812 -285.735268) (xy 404.909877 -285.756224) (xy 404.932168 -285.801501)
			(xy 404.947325 -285.849638) (xy 404.954996 -285.899519) (xy 404.955502 -285.924752) (xy 404.954992 -285.950739)
			(xy 404.946862 -286.002074) (xy 404.930801 -286.051504) (xy 404.907205 -286.097814) (xy 404.876655 -286.139862)
			(xy 404.839904 -286.176613) (xy 404.797856 -286.207163) (xy 404.751546 -286.230759) (xy 404.702116 -286.24682)
			(xy 404.650781 -286.25495) (xy 404.598807 -286.25495) (xy 404.547472 -286.24682) (xy 404.498042 -286.230759)
			(xy 404.451732 -286.207163) (xy 404.409684 -286.176613) (xy 404.372933 -286.139862) (xy 404.342383 -286.097814)
			(xy 404.318787 -286.051504) (xy 404.302726 -286.002074) (xy 404.294596 -285.950739) (xy 404.294086 -285.924752)
			(xy 404.294086 -285.924498) (xy 404.294519 -285.899763) (xy 404.301881 -285.850845) (xy 404.316457 -285.803571)
			(xy 404.337919 -285.759) (xy 404.35149 -285.738316) (xy 404.35276 -285.736538) (xy 404.36165 -285.7246)
			(xy 404.363936 -285.695644) (xy 404.315422 -285.603188) (xy 404.308818 -285.590488) (xy 404.284688 -285.575756)
			(xy 404.01494 -285.575756) (xy 403.99081 -285.590488) (xy 403.984206 -285.603188) (xy 403.935946 -285.69539)
			(xy 403.937724 -285.723584) (xy 403.945852 -285.735268) (xy 403.959915 -285.756224) (xy 403.982204 -285.801502)
			(xy 403.997359 -285.849639) (xy 404.005029 -285.899519) (xy 404.005542 -285.924752) (xy 404.005032 -285.950739)
			(xy 403.996902 -286.002074) (xy 403.980841 -286.051504) (xy 403.957245 -286.097814) (xy 403.926695 -286.139862)
			(xy 403.889944 -286.176613) (xy 403.847896 -286.207163) (xy 403.801586 -286.230759) (xy 403.752156 -286.24682)
			(xy 403.700821 -286.25495) (xy 403.648847 -286.25495) (xy 403.597512 -286.24682) (xy 403.548082 -286.230759)
			(xy 403.501772 -286.207163) (xy 403.459724 -286.176613) (xy 403.422973 -286.139862) (xy 403.392423 -286.097814)
			(xy 403.368827 -286.051504) (xy 403.352766 -286.002074) (xy 403.344636 -285.950739) (xy 403.344126 -285.924752)
			(xy 403.344126 -285.924498) (xy 403.344559 -285.899763) (xy 403.351922 -285.850845) (xy 403.366499 -285.803573)
			(xy 403.387963 -285.759003) (xy 403.40153 -285.738316) (xy 403.4028 -285.736538) (xy 403.41169 -285.7246)
			(xy 403.413976 -285.695644) (xy 403.365462 -285.603188) (xy 403.358858 -285.590488) (xy 403.334728 -285.575756)
			(xy 403.06498 -285.575756) (xy 403.04085 -285.590488) (xy 403.034246 -285.603188) (xy 402.985986 -285.69539)
			(xy 402.987764 -285.723584) (xy 402.995892 -285.735268) (xy 403.009958 -285.756223) (xy 403.03225 -285.8015)
			(xy 403.047408 -285.849637) (xy 403.05508 -285.899518) (xy 403.055582 -285.924752) (xy 403.055072 -285.950739)
			(xy 403.046942 -286.002074) (xy 403.030881 -286.051504) (xy 403.007285 -286.097814) (xy 402.976735 -286.139862)
			(xy 402.939984 -286.176613) (xy 402.897936 -286.207163) (xy 402.851626 -286.230759) (xy 402.802196 -286.24682)
			(xy 402.750861 -286.25495) (xy 402.698887 -286.25495) (xy 402.647552 -286.24682) (xy 402.598122 -286.230759)
			(xy 402.551812 -286.207163) (xy 402.509764 -286.176613) (xy 402.473013 -286.139862) (xy 402.442463 -286.097814)
			(xy 402.418867 -286.051504) (xy 402.402806 -286.002074) (xy 402.394676 -285.950739) (xy 402.394166 -285.924752)
			(xy 402.394166 -285.924498) (xy 402.394599 -285.899763) (xy 402.401961 -285.850844) (xy 402.416536 -285.80357)
			(xy 402.437997 -285.758998) (xy 402.45157 -285.738316) (xy 402.45284 -285.736538) (xy 402.46173 -285.7246)
			(xy 402.464016 -285.695644) (xy 402.415502 -285.603188) (xy 402.408898 -285.590488) (xy 402.384768 -285.575756)
			(xy 402.11502 -285.575756) (xy 402.09089 -285.590488) (xy 402.084286 -285.603188) (xy 402.036026 -285.69539)
			(xy 402.037804 -285.723584) (xy 402.045932 -285.735268) (xy 402.059996 -285.756224) (xy 402.082286 -285.801501)
			(xy 402.097442 -285.849638) (xy 402.105113 -285.899519) (xy 402.105622 -285.924752) (xy 402.105112 -285.950739)
			(xy 402.096982 -286.002074) (xy 402.080921 -286.051504) (xy 402.057325 -286.097814) (xy 402.026775 -286.139862)
			(xy 401.990024 -286.176613) (xy 401.947976 -286.207163) (xy 401.901666 -286.230759) (xy 401.852236 -286.24682)
			(xy 401.800901 -286.25495) (xy 401.748927 -286.25495) (xy 401.697592 -286.24682) (xy 401.648162 -286.230759)
			(xy 401.601852 -286.207163) (xy 401.559804 -286.176613) (xy 401.523053 -286.139862) (xy 401.492503 -286.097814)
			(xy 401.468907 -286.051504) (xy 401.452846 -286.002074) (xy 401.444716 -285.950739) (xy 401.444206 -285.924752)
			(xy 401.444206 -285.924498) (xy 401.444639 -285.899763) (xy 401.452002 -285.850845) (xy 401.466578 -285.803572)
			(xy 401.488041 -285.759001) (xy 401.50161 -285.738316) (xy 401.50288 -285.736538) (xy 401.51177 -285.7246)
			(xy 401.514056 -285.695644) (xy 401.465542 -285.603188) (xy 401.458938 -285.590488) (xy 401.434808 -285.575756)
			(xy 401.16506 -285.575756) (xy 401.14093 -285.590488) (xy 401.134326 -285.603188) (xy 401.086066 -285.69539)
			(xy 401.087844 -285.723584) (xy 401.095972 -285.735268) (xy 401.110038 -285.756223) (xy 401.132332 -285.8015)
			(xy 401.147491 -285.849637) (xy 401.155163 -285.899518) (xy 401.155662 -285.924752) (xy 401.155152 -285.950739)
			(xy 401.147022 -286.002074) (xy 401.130961 -286.051504) (xy 401.107365 -286.097814) (xy 401.076815 -286.139862)
			(xy 401.040064 -286.176613) (xy 400.998016 -286.207163) (xy 400.951706 -286.230759) (xy 400.902276 -286.24682)
			(xy 400.850941 -286.25495) (xy 400.798967 -286.25495) (xy 400.747632 -286.24682) (xy 400.698202 -286.230759)
			(xy 400.651892 -286.207163) (xy 400.609844 -286.176613) (xy 400.573093 -286.139862) (xy 400.542543 -286.097814)
			(xy 400.518947 -286.051504) (xy 400.502886 -286.002074) (xy 400.494756 -285.950739) (xy 400.494246 -285.924752)
			(xy 400.494246 -285.924498) (xy 400.494679 -285.899763) (xy 400.50204 -285.850844) (xy 400.516614 -285.80357)
			(xy 400.538074 -285.758997) (xy 400.55165 -285.738316) (xy 400.55292 -285.736538) (xy 400.56181 -285.7246)
			(xy 400.564096 -285.695644) (xy 400.515582 -285.603188) (xy 400.508978 -285.590488) (xy 400.484848 -285.575756)
			(xy 400.2151 -285.575756) (xy 400.19097 -285.590488) (xy 400.184366 -285.603188) (xy 400.136106 -285.69539)
			(xy 400.137884 -285.723584) (xy 400.146012 -285.735268) (xy 400.160077 -285.756224) (xy 400.182368 -285.801501)
			(xy 400.197525 -285.849638) (xy 400.205196 -285.899519) (xy 400.205702 -285.924752) (xy 400.205192 -285.950739)
			(xy 400.197062 -286.002074) (xy 400.181001 -286.051504) (xy 400.157405 -286.097814) (xy 400.126855 -286.139862)
			(xy 400.090104 -286.176613) (xy 400.048056 -286.207163) (xy 400.001746 -286.230759) (xy 399.952316 -286.24682)
			(xy 399.900981 -286.25495) (xy 399.849007 -286.25495) (xy 399.797672 -286.24682) (xy 399.748242 -286.230759)
			(xy 399.701932 -286.207163) (xy 399.659884 -286.176613) (xy 399.623133 -286.139862) (xy 399.592583 -286.097814)
			(xy 399.568987 -286.051504) (xy 399.552926 -286.002074) (xy 399.544796 -285.950739) (xy 399.544286 -285.924752)
			(xy 399.544286 -285.924498) (xy 399.544719 -285.899763) (xy 399.552081 -285.850845) (xy 399.566657 -285.803571)
			(xy 399.588119 -285.759) (xy 399.60169 -285.738316) (xy 399.60296 -285.736538) (xy 399.61185 -285.7246)
			(xy 399.614136 -285.695644) (xy 399.565622 -285.603188) (xy 399.559018 -285.590488) (xy 399.534888 -285.575756)
			(xy 399.26514 -285.575756) (xy 399.24101 -285.590488) (xy 399.234406 -285.603188) (xy 399.186146 -285.69539)
			(xy 399.187924 -285.723584) (xy 399.196052 -285.735268) (xy 399.210115 -285.756224) (xy 399.232404 -285.801502)
			(xy 399.247559 -285.849639) (xy 399.255229 -285.899519) (xy 399.255742 -285.924752) (xy 399.255232 -285.950739)
			(xy 399.247102 -286.002074) (xy 399.231041 -286.051504) (xy 399.207445 -286.097814) (xy 399.176895 -286.139862)
			(xy 399.140144 -286.176613) (xy 399.098096 -286.207163) (xy 399.051786 -286.230759) (xy 399.002356 -286.24682)
			(xy 398.951021 -286.25495) (xy 398.899047 -286.25495) (xy 398.847712 -286.24682) (xy 398.798282 -286.230759)
			(xy 398.751972 -286.207163) (xy 398.709924 -286.176613) (xy 398.673173 -286.139862) (xy 398.642623 -286.097814)
			(xy 398.619027 -286.051504) (xy 398.602966 -286.002074) (xy 398.594836 -285.950739) (xy 398.594326 -285.924752)
			(xy 398.594326 -285.924498) (xy 398.594759 -285.899763) (xy 398.602122 -285.850845) (xy 398.616699 -285.803573)
			(xy 398.638163 -285.759003) (xy 398.65173 -285.738316) (xy 398.653 -285.736538) (xy 398.66189 -285.7246)
			(xy 398.664176 -285.695644) (xy 398.615662 -285.603188) (xy 398.609058 -285.590488) (xy 398.584928 -285.575756)
			(xy 398.314926 -285.575756) (xy 398.290796 -285.590488) (xy 398.284192 -285.603188) (xy 398.235932 -285.69539)
			(xy 398.23771 -285.723584) (xy 398.245838 -285.735268) (xy 398.259902 -285.756224) (xy 398.282191 -285.801501)
			(xy 398.297347 -285.849639) (xy 398.305018 -285.899519) (xy 398.305528 -285.924752) (xy 398.305018 -285.950739)
			(xy 398.296888 -286.002074) (xy 398.280827 -286.051504) (xy 398.257231 -286.097814) (xy 398.226681 -286.139862)
			(xy 398.18993 -286.176613) (xy 398.147882 -286.207163) (xy 398.101572 -286.230759) (xy 398.052142 -286.24682)
			(xy 398.000807 -286.25495) (xy 397.948833 -286.25495) (xy 397.897498 -286.24682) (xy 397.848068 -286.230759)
			(xy 397.801758 -286.207163) (xy 397.75971 -286.176613) (xy 397.722959 -286.139862) (xy 397.692409 -286.097814)
			(xy 397.668813 -286.051504) (xy 397.652752 -286.002074) (xy 397.644622 -285.950739) (xy 397.644112 -285.924752)
			(xy 397.644112 -285.924498) (xy 397.644545 -285.899763) (xy 397.651908 -285.850845) (xy 397.666484 -285.803572)
			(xy 397.687948 -285.759002) (xy 397.701516 -285.738316) (xy 397.702786 -285.736538) (xy 397.711676 -285.7246)
			(xy 397.713962 -285.695644) (xy 397.665448 -285.603188) (xy 397.658844 -285.590488) (xy 397.634714 -285.575756)
			(xy 397.364966 -285.575756) (xy 397.340836 -285.590488) (xy 397.334232 -285.603188) (xy 397.285972 -285.69539)
			(xy 397.28775 -285.723584) (xy 397.295878 -285.735268) (xy 397.309944 -285.756223) (xy 397.332238 -285.8015)
			(xy 397.347396 -285.849637) (xy 397.355068 -285.899518) (xy 397.355568 -285.924752) (xy 397.355058 -285.950739)
			(xy 397.346928 -286.002074) (xy 397.330867 -286.051504) (xy 397.307271 -286.097814) (xy 397.276721 -286.139862)
			(xy 397.23997 -286.176613) (xy 397.197922 -286.207163) (xy 397.151612 -286.230759) (xy 397.102182 -286.24682)
			(xy 397.050847 -286.25495) (xy 396.998873 -286.25495) (xy 396.947538 -286.24682) (xy 396.898108 -286.230759)
			(xy 396.851798 -286.207163) (xy 396.80975 -286.176613) (xy 396.772999 -286.139862) (xy 396.742449 -286.097814)
			(xy 396.718853 -286.051504) (xy 396.702792 -286.002074) (xy 396.694662 -285.950739) (xy 396.694152 -285.924752)
			(xy 396.694152 -285.924498) (xy 396.694585 -285.899763) (xy 396.701947 -285.850844) (xy 396.716521 -285.80357)
			(xy 396.737981 -285.758997) (xy 396.751556 -285.738316) (xy 396.752826 -285.736538) (xy 396.761716 -285.7246)
			(xy 396.764002 -285.695644) (xy 396.715488 -285.603188) (xy 396.708884 -285.590488) (xy 396.684754 -285.575756)
			(xy 396.415006 -285.575756) (xy 396.390876 -285.590488) (xy 396.384272 -285.603188) (xy 396.336012 -285.69539)
			(xy 396.33779 -285.723584) (xy 396.345918 -285.735268) (xy 396.359983 -285.756224) (xy 396.382273 -285.801501)
			(xy 396.39743 -285.849638) (xy 396.405101 -285.899519) (xy 396.405608 -285.924752) (xy 396.405098 -285.950739)
			(xy 396.396968 -286.002074) (xy 396.380907 -286.051504) (xy 396.357311 -286.097814) (xy 396.326761 -286.139862)
			(xy 396.29001 -286.176613) (xy 396.247962 -286.207163) (xy 396.201652 -286.230759) (xy 396.152222 -286.24682)
			(xy 396.100887 -286.25495) (xy 396.048913 -286.25495) (xy 395.997578 -286.24682) (xy 395.948148 -286.230759)
			(xy 395.901838 -286.207163) (xy 395.85979 -286.176613) (xy 395.823039 -286.139862) (xy 395.792489 -286.097814)
			(xy 395.768893 -286.051504) (xy 395.752832 -286.002074) (xy 395.744702 -285.950739) (xy 395.744192 -285.924752)
			(xy 395.744192 -285.924498) (xy 395.744625 -285.899763) (xy 395.751988 -285.850845) (xy 395.766563 -285.803571)
			(xy 395.788026 -285.759) (xy 395.801596 -285.738316) (xy 395.802866 -285.736538) (xy 395.811756 -285.7246)
			(xy 395.814042 -285.695644) (xy 395.765528 -285.603188) (xy 395.758924 -285.590488) (xy 395.734794 -285.575756)
			(xy 395.465046 -285.575756) (xy 395.440916 -285.590488) (xy 395.434312 -285.603188) (xy 395.386052 -285.69539)
			(xy 395.38783 -285.723584) (xy 395.395958 -285.735268) (xy 395.410021 -285.756224) (xy 395.432309 -285.801502)
			(xy 395.447464 -285.849639) (xy 395.455134 -285.899519) (xy 395.455648 -285.924752) (xy 395.455138 -285.950739)
			(xy 395.447008 -286.002074) (xy 395.430947 -286.051504) (xy 395.407351 -286.097814) (xy 395.376801 -286.139862)
			(xy 395.34005 -286.176613) (xy 395.298002 -286.207163) (xy 395.251692 -286.230759) (xy 395.202262 -286.24682)
			(xy 395.150927 -286.25495) (xy 395.098953 -286.25495) (xy 395.047618 -286.24682) (xy 394.998188 -286.230759)
			(xy 394.951878 -286.207163) (xy 394.90983 -286.176613) (xy 394.873079 -286.139862) (xy 394.842529 -286.097814)
			(xy 394.818933 -286.051504) (xy 394.802872 -286.002074) (xy 394.794742 -285.950739) (xy 394.794232 -285.924752)
			(xy 394.794232 -285.924498) (xy 394.794665 -285.899763) (xy 394.802028 -285.850845) (xy 394.816605 -285.803573)
			(xy 394.83807 -285.759003) (xy 394.851636 -285.738316) (xy 394.852906 -285.736538) (xy 394.861796 -285.7246)
			(xy 394.864082 -285.695644) (xy 394.815568 -285.603188) (xy 394.808964 -285.590488) (xy 394.784834 -285.575756)
			(xy 394.515086 -285.575756) (xy 394.490956 -285.590488) (xy 394.484352 -285.603188) (xy 394.436092 -285.69539)
			(xy 394.43787 -285.723584) (xy 394.445998 -285.735268) (xy 394.460063 -285.756223) (xy 394.482356 -285.8015)
			(xy 394.497513 -285.849638) (xy 394.505185 -285.899518) (xy 394.505688 -285.924752) (xy 394.505178 -285.950739)
			(xy 394.497048 -286.002074) (xy 394.480987 -286.051504) (xy 394.457391 -286.097814) (xy 394.426841 -286.139862)
			(xy 394.39009 -286.176613) (xy 394.348042 -286.207163) (xy 394.301732 -286.230759) (xy 394.252302 -286.24682)
			(xy 394.200967 -286.25495) (xy 394.148993 -286.25495) (xy 394.097658 -286.24682) (xy 394.048228 -286.230759)
			(xy 394.001918 -286.207163) (xy 393.95987 -286.176613) (xy 393.923119 -286.139862) (xy 393.892569 -286.097814)
			(xy 393.868973 -286.051504) (xy 393.852912 -286.002074) (xy 393.844782 -285.950739) (xy 393.844272 -285.924752)
			(xy 393.844272 -285.924498) (xy 393.844705 -285.899763) (xy 393.852067 -285.850844) (xy 393.866642 -285.803571)
			(xy 393.888103 -285.758999) (xy 393.901676 -285.738316) (xy 393.902946 -285.736538) (xy 393.911836 -285.7246)
			(xy 393.914122 -285.695644) (xy 393.865608 -285.603188) (xy 393.859004 -285.590488) (xy 393.834874 -285.575756)
			(xy 393.565126 -285.575756) (xy 393.540996 -285.590488) (xy 393.534392 -285.603188) (xy 393.486132 -285.69539)
			(xy 393.48791 -285.723584) (xy 393.496038 -285.735268) (xy 393.510102 -285.756224) (xy 393.532391 -285.801501)
			(xy 393.547547 -285.849639) (xy 393.555218 -285.899519) (xy 393.555728 -285.924752) (xy 393.555218 -285.950739)
			(xy 393.547088 -286.002074) (xy 393.531027 -286.051504) (xy 393.507431 -286.097814) (xy 393.476881 -286.139862)
			(xy 393.44013 -286.176613) (xy 393.398082 -286.207163) (xy 393.351772 -286.230759) (xy 393.302342 -286.24682)
			(xy 393.251007 -286.25495) (xy 393.199033 -286.25495) (xy 393.147698 -286.24682) (xy 393.098268 -286.230759)
			(xy 393.051958 -286.207163) (xy 393.00991 -286.176613) (xy 392.973159 -286.139862) (xy 392.942609 -286.097814)
			(xy 392.919013 -286.051504) (xy 392.902952 -286.002074) (xy 392.894822 -285.950739) (xy 392.894312 -285.924752)
			(xy 392.894312 -285.924498) (xy 392.894745 -285.899763) (xy 392.902108 -285.850845) (xy 392.916684 -285.803572)
			(xy 392.938148 -285.759002) (xy 392.951716 -285.738316) (xy 392.952986 -285.736538) (xy 392.961876 -285.7246)
			(xy 392.964162 -285.695644) (xy 392.915648 -285.603188) (xy 392.909044 -285.590488) (xy 392.884914 -285.575756)
			(xy 389.765032 -285.575756) (xy 389.740902 -285.590488) (xy 389.734298 -285.603188) (xy 389.686038 -285.69539)
			(xy 389.687816 -285.723584) (xy 389.695944 -285.735268) (xy 389.710008 -285.756224) (xy 389.732297 -285.801502)
			(xy 389.747452 -285.849639) (xy 389.755123 -285.899519) (xy 389.755634 -285.924752) (xy 389.755154 -285.950744)
			(xy 389.747029 -286.00209) (xy 389.730972 -286.051533) (xy 389.707377 -286.097855) (xy 389.676826 -286.139915)
			(xy 389.640071 -286.176678) (xy 389.598018 -286.207238) (xy 389.551701 -286.230843) (xy 389.502262 -286.246912)
			(xy 389.450918 -286.255049) (xy 389.424926 -286.25546) (xy 389.399268 -286.254971) (xy 389.348569 -286.247037)
			(xy 389.299703 -286.23137) (xy 389.253841 -286.208346) (xy 389.212085 -286.178518) (xy 389.175434 -286.1426)
			(xy 389.144769 -286.101454) (xy 389.120823 -286.056067) (xy 389.104173 -286.007528) (xy 389.095216 -285.956999)
			(xy 389.094218 -285.931356) (xy 389.093964 -285.916624) (xy 389.078216 -285.892494) (xy 389.040878 -285.875222)
			(xy 389.031288 -285.871322) (xy 389.010612 -285.870766) (xy 388.991402 -285.87843) (xy 388.983728 -285.885382)
			(xy 388.746492 -286.122364) (xy 388.614412 -286.254444) (xy 388.610931 -286.257729) (xy 388.603004 -286.263093)
			(xy 388.598664 -286.265112) (xy 388.59841 -286.265112) (xy 388.589012 -286.269176) (xy 380.512574 -286.269176)
			(xy 380.503066 -286.269636) (xy 380.485347 -286.276548) (xy 380.47803 -286.282638) (xy 380.420372 -286.335724)
			(xy 380.41199 -286.352742) (xy 380.411228 -286.362394) (xy 380.408626 -286.389091) (xy 380.396885 -286.441429)
			(xy 380.377934 -286.491608) (xy 380.352145 -286.53864) (xy 380.320027 -286.5816) (xy 380.282211 -286.619641)
			(xy 380.261114 -286.636206) (xy 380.251462 -286.643318) (xy 380.241048 -286.664146) (xy 380.239524 -286.768032)
			(xy 380.24943 -286.789114) (xy 380.258574 -286.79648) (xy 380.280399 -286.81471) (xy 380.318927 -286.856532)
			(xy 380.350828 -286.903606) (xy 380.375396 -286.954889) (xy 380.392087 -287.009248) (xy 380.400532 -287.065482)
			(xy 380.401068 -287.093914) (xy 381.034542 -287.093914) (xy 381.038613 -287.038292) (xy 381.050739 -286.983855)
			(xy 381.070662 -286.931764) (xy 381.097958 -286.883129) (xy 381.132044 -286.838986) (xy 381.172193 -286.800277)
			(xy 381.217551 -286.767826) (xy 381.267151 -286.742325) (xy 381.319935 -286.724318) (xy 381.374778 -286.714188)
			(xy 381.430512 -286.712151) (xy 381.485949 -286.718251) (xy 381.539906 -286.732357) (xy 381.591235 -286.754169)
			(xy 381.638841 -286.783223) (xy 381.681709 -286.818898) (xy 381.718926 -286.860435) (xy 381.749699 -286.906948)
			(xy 381.773371 -286.957445) (xy 381.789439 -287.010852) (xy 381.797559 -287.066028) (xy 381.798068 -287.093914)
			(xy 381.921002 -287.093914) (xy 381.925073 -287.038292) (xy 381.937199 -286.983855) (xy 381.957122 -286.931764)
			(xy 381.984418 -286.883129) (xy 382.018504 -286.838986) (xy 382.058653 -286.800277) (xy 382.104011 -286.767826)
			(xy 382.153611 -286.742325) (xy 382.206395 -286.724318) (xy 382.261238 -286.714188) (xy 382.316972 -286.712151)
			(xy 382.372409 -286.718251) (xy 382.426366 -286.732357) (xy 382.477695 -286.754169) (xy 382.525301 -286.783223)
			(xy 382.568169 -286.818898) (xy 382.605386 -286.860435) (xy 382.615 -286.874966) (xy 384.369068 -286.874966)
			(xy 384.373028 -286.825912) (xy 384.384805 -286.778128) (xy 384.404096 -286.732852) (xy 384.430399 -286.691256)
			(xy 384.463034 -286.654419) (xy 384.501155 -286.623294) (xy 384.543776 -286.598687) (xy 384.589792 -286.581235)
			(xy 384.638011 -286.571391) (xy 384.687186 -286.56941) (xy 384.736041 -286.575342) (xy 384.783312 -286.589034)
			(xy 384.827774 -286.610132) (xy 384.868277 -286.638088) (xy 384.90377 -286.67218) (xy 384.933335 -286.711524)
			(xy 384.956206 -286.755101) (xy 384.97179 -286.801782) (xy 384.979685 -286.850359) (xy 384.98018 -286.874966)
			(xy 385.319028 -286.874966) (xy 385.322988 -286.825912) (xy 385.334765 -286.778128) (xy 385.354056 -286.732852)
			(xy 385.380359 -286.691256) (xy 385.412994 -286.654419) (xy 385.451115 -286.623294) (xy 385.493736 -286.598687)
			(xy 385.539752 -286.581235) (xy 385.587971 -286.571391) (xy 385.637146 -286.56941) (xy 385.686001 -286.575342)
			(xy 385.733272 -286.589034) (xy 385.777734 -286.610132) (xy 385.818237 -286.638088) (xy 385.85373 -286.67218)
			(xy 385.883295 -286.711524) (xy 385.906166 -286.755101) (xy 385.92175 -286.801782) (xy 385.929645 -286.850359)
			(xy 385.93014 -286.874966) (xy 386.269242 -286.874966) (xy 386.273202 -286.825912) (xy 386.284979 -286.778128)
			(xy 386.30427 -286.732852) (xy 386.330573 -286.691256) (xy 386.363208 -286.654419) (xy 386.401329 -286.623294)
			(xy 386.44395 -286.598687) (xy 386.489966 -286.581235) (xy 386.538185 -286.571391) (xy 386.58736 -286.56941)
			(xy 386.636215 -286.575342) (xy 386.683486 -286.589034) (xy 386.727948 -286.610132) (xy 386.768451 -286.638088)
			(xy 386.803944 -286.67218) (xy 386.833509 -286.711524) (xy 386.85638 -286.755101) (xy 386.871964 -286.801782)
			(xy 386.879859 -286.850359) (xy 386.880354 -286.874966) (xy 387.219202 -286.874966) (xy 387.223162 -286.825912)
			(xy 387.234939 -286.778128) (xy 387.25423 -286.732852) (xy 387.280533 -286.691256) (xy 387.313168 -286.654419)
			(xy 387.351289 -286.623294) (xy 387.39391 -286.598687) (xy 387.439926 -286.581235) (xy 387.488145 -286.571391)
			(xy 387.53732 -286.56941) (xy 387.586175 -286.575342) (xy 387.633446 -286.589034) (xy 387.677908 -286.610132)
			(xy 387.718411 -286.638088) (xy 387.753904 -286.67218) (xy 387.783469 -286.711524) (xy 387.80634 -286.755101)
			(xy 387.821924 -286.801782) (xy 387.829819 -286.850359) (xy 387.830314 -286.874966) (xy 388.169162 -286.874966)
			(xy 388.173122 -286.825912) (xy 388.184899 -286.778128) (xy 388.20419 -286.732852) (xy 388.230493 -286.691256)
			(xy 388.263128 -286.654419) (xy 388.301249 -286.623294) (xy 388.34387 -286.598687) (xy 388.389886 -286.581235)
			(xy 388.438105 -286.571391) (xy 388.48728 -286.56941) (xy 388.536135 -286.575342) (xy 388.583406 -286.589034)
			(xy 388.627868 -286.610132) (xy 388.668371 -286.638088) (xy 388.703864 -286.67218) (xy 388.733429 -286.711524)
			(xy 388.7563 -286.755101) (xy 388.771884 -286.801782) (xy 388.779779 -286.850359) (xy 388.780274 -286.874966)
			(xy 389.119122 -286.874966) (xy 389.123082 -286.825912) (xy 389.134859 -286.778128) (xy 389.15415 -286.732852)
			(xy 389.180453 -286.691256) (xy 389.213088 -286.654419) (xy 389.251209 -286.623294) (xy 389.29383 -286.598687)
			(xy 389.339846 -286.581235) (xy 389.388065 -286.571391) (xy 389.43724 -286.56941) (xy 389.486095 -286.575342)
			(xy 389.533366 -286.589034) (xy 389.577828 -286.610132) (xy 389.618331 -286.638088) (xy 389.653824 -286.67218)
			(xy 389.683389 -286.711524) (xy 389.70626 -286.755101) (xy 389.721844 -286.801782) (xy 389.729739 -286.850359)
			(xy 389.730234 -286.874966) (xy 390.069082 -286.874966) (xy 390.073042 -286.825912) (xy 390.084819 -286.778128)
			(xy 390.10411 -286.732852) (xy 390.130413 -286.691256) (xy 390.163048 -286.654419) (xy 390.201169 -286.623294)
			(xy 390.24379 -286.598687) (xy 390.289806 -286.581235) (xy 390.338025 -286.571391) (xy 390.3872 -286.56941)
			(xy 390.436055 -286.575342) (xy 390.483326 -286.589034) (xy 390.527788 -286.610132) (xy 390.568291 -286.638088)
			(xy 390.603784 -286.67218) (xy 390.633349 -286.711524) (xy 390.65622 -286.755101) (xy 390.671804 -286.801782)
			(xy 390.679699 -286.850359) (xy 390.680189 -286.874712) (xy 391.019042 -286.874712) (xy 391.023002 -286.825658)
			(xy 391.034779 -286.777874) (xy 391.05407 -286.732598) (xy 391.080373 -286.691002) (xy 391.113008 -286.654165)
			(xy 391.151129 -286.62304) (xy 391.19375 -286.598433) (xy 391.239766 -286.580981) (xy 391.287985 -286.571137)
			(xy 391.33716 -286.569156) (xy 391.386015 -286.575088) (xy 391.433286 -286.58878) (xy 391.477748 -286.609878)
			(xy 391.518251 -286.637834) (xy 391.553744 -286.671926) (xy 391.583309 -286.71127) (xy 391.60618 -286.754847)
			(xy 391.621764 -286.801528) (xy 391.629659 -286.850105) (xy 391.630154 -286.874712) (xy 391.969002 -286.874712)
			(xy 391.972962 -286.825658) (xy 391.984739 -286.777874) (xy 392.00403 -286.732598) (xy 392.030333 -286.691002)
			(xy 392.062968 -286.654165) (xy 392.101089 -286.62304) (xy 392.14371 -286.598433) (xy 392.189726 -286.580981)
			(xy 392.237945 -286.571137) (xy 392.28712 -286.569156) (xy 392.335975 -286.575088) (xy 392.383246 -286.58878)
			(xy 392.427708 -286.609878) (xy 392.468211 -286.637834) (xy 392.503704 -286.671926) (xy 392.533269 -286.71127)
			(xy 392.55614 -286.754847) (xy 392.571724 -286.801528) (xy 392.579619 -286.850105) (xy 392.580114 -286.874712)
			(xy 392.580109 -286.874966) (xy 392.919216 -286.874966) (xy 392.923176 -286.825912) (xy 392.934953 -286.778128)
			(xy 392.954244 -286.732852) (xy 392.980547 -286.691256) (xy 393.013182 -286.654419) (xy 393.051303 -286.623294)
			(xy 393.093924 -286.598687) (xy 393.13994 -286.581235) (xy 393.188159 -286.571391) (xy 393.237334 -286.56941)
			(xy 393.286189 -286.575342) (xy 393.33346 -286.589034) (xy 393.377922 -286.610132) (xy 393.418425 -286.638088)
			(xy 393.453918 -286.67218) (xy 393.483483 -286.711524) (xy 393.506354 -286.755101) (xy 393.521938 -286.801782)
			(xy 393.529833 -286.850359) (xy 393.530328 -286.874966) (xy 393.869176 -286.874966) (xy 393.873136 -286.825912)
			(xy 393.884913 -286.778128) (xy 393.904204 -286.732852) (xy 393.930507 -286.691256) (xy 393.963142 -286.654419)
			(xy 394.001263 -286.623294) (xy 394.043884 -286.598687) (xy 394.0899 -286.581235) (xy 394.138119 -286.571391)
			(xy 394.187294 -286.56941) (xy 394.236149 -286.575342) (xy 394.28342 -286.589034) (xy 394.327882 -286.610132)
			(xy 394.368385 -286.638088) (xy 394.403878 -286.67218) (xy 394.433443 -286.711524) (xy 394.456314 -286.755101)
			(xy 394.471898 -286.801782) (xy 394.479793 -286.850359) (xy 394.480288 -286.874966) (xy 394.819136 -286.874966)
			(xy 394.823096 -286.825912) (xy 394.834873 -286.778128) (xy 394.854164 -286.732852) (xy 394.880467 -286.691256)
			(xy 394.913102 -286.654419) (xy 394.951223 -286.623294) (xy 394.993844 -286.598687) (xy 395.03986 -286.581235)
			(xy 395.088079 -286.571391) (xy 395.137254 -286.56941) (xy 395.186109 -286.575342) (xy 395.23338 -286.589034)
			(xy 395.277842 -286.610132) (xy 395.318345 -286.638088) (xy 395.353838 -286.67218) (xy 395.383403 -286.711524)
			(xy 395.406274 -286.755101) (xy 395.421858 -286.801782) (xy 395.429753 -286.850359) (xy 395.430248 -286.874966)
			(xy 395.769096 -286.874966) (xy 395.773056 -286.825912) (xy 395.784833 -286.778128) (xy 395.804124 -286.732852)
			(xy 395.830427 -286.691256) (xy 395.863062 -286.654419) (xy 395.901183 -286.623294) (xy 395.943804 -286.598687)
			(xy 395.98982 -286.581235) (xy 396.038039 -286.571391) (xy 396.087214 -286.56941) (xy 396.136069 -286.575342)
			(xy 396.18334 -286.589034) (xy 396.227802 -286.610132) (xy 396.268305 -286.638088) (xy 396.303798 -286.67218)
			(xy 396.333363 -286.711524) (xy 396.356234 -286.755101) (xy 396.371818 -286.801782) (xy 396.379713 -286.850359)
			(xy 396.380208 -286.874966) (xy 396.719056 -286.874966) (xy 396.723016 -286.825912) (xy 396.734793 -286.778128)
			(xy 396.754084 -286.732852) (xy 396.780387 -286.691256) (xy 396.813022 -286.654419) (xy 396.851143 -286.623294)
			(xy 396.893764 -286.598687) (xy 396.93978 -286.581235) (xy 396.987999 -286.571391) (xy 397.037174 -286.56941)
			(xy 397.086029 -286.575342) (xy 397.1333 -286.589034) (xy 397.177762 -286.610132) (xy 397.218265 -286.638088)
			(xy 397.253758 -286.67218) (xy 397.283323 -286.711524) (xy 397.306194 -286.755101) (xy 397.321778 -286.801782)
			(xy 397.329673 -286.850359) (xy 397.330168 -286.874966) (xy 397.669016 -286.874966) (xy 397.672976 -286.825912)
			(xy 397.684753 -286.778128) (xy 397.704044 -286.732852) (xy 397.730347 -286.691256) (xy 397.762982 -286.654419)
			(xy 397.801103 -286.623294) (xy 397.843724 -286.598687) (xy 397.88974 -286.581235) (xy 397.937959 -286.571391)
			(xy 397.987134 -286.56941) (xy 398.035989 -286.575342) (xy 398.08326 -286.589034) (xy 398.127722 -286.610132)
			(xy 398.168225 -286.638088) (xy 398.203718 -286.67218) (xy 398.233283 -286.711524) (xy 398.256154 -286.755101)
			(xy 398.271738 -286.801782) (xy 398.279633 -286.850359) (xy 398.280128 -286.874966) (xy 398.61923 -286.874966)
			(xy 398.62319 -286.825912) (xy 398.634967 -286.778128) (xy 398.654258 -286.732852) (xy 398.680561 -286.691256)
			(xy 398.713196 -286.654419) (xy 398.751317 -286.623294) (xy 398.793938 -286.598687) (xy 398.839954 -286.581235)
			(xy 398.888173 -286.571391) (xy 398.937348 -286.56941) (xy 398.986203 -286.575342) (xy 399.033474 -286.589034)
			(xy 399.077936 -286.610132) (xy 399.118439 -286.638088) (xy 399.153932 -286.67218) (xy 399.183497 -286.711524)
			(xy 399.206368 -286.755101) (xy 399.221952 -286.801782) (xy 399.229847 -286.850359) (xy 399.230342 -286.874966)
			(xy 399.56919 -286.874966) (xy 399.57315 -286.825912) (xy 399.584927 -286.778128) (xy 399.604218 -286.732852)
			(xy 399.630521 -286.691256) (xy 399.663156 -286.654419) (xy 399.701277 -286.623294) (xy 399.743898 -286.598687)
			(xy 399.789914 -286.581235) (xy 399.838133 -286.571391) (xy 399.887308 -286.56941) (xy 399.936163 -286.575342)
			(xy 399.983434 -286.589034) (xy 400.027896 -286.610132) (xy 400.068399 -286.638088) (xy 400.103892 -286.67218)
			(xy 400.133457 -286.711524) (xy 400.156328 -286.755101) (xy 400.171912 -286.801782) (xy 400.179807 -286.850359)
			(xy 400.180302 -286.874966) (xy 400.51915 -286.874966) (xy 400.52311 -286.825912) (xy 400.534887 -286.778128)
			(xy 400.554178 -286.732852) (xy 400.580481 -286.691256) (xy 400.613116 -286.654419) (xy 400.651237 -286.623294)
			(xy 400.693858 -286.598687) (xy 400.739874 -286.581235) (xy 400.788093 -286.571391) (xy 400.837268 -286.56941)
			(xy 400.886123 -286.575342) (xy 400.933394 -286.589034) (xy 400.977856 -286.610132) (xy 401.018359 -286.638088)
			(xy 401.053852 -286.67218) (xy 401.083417 -286.711524) (xy 401.106288 -286.755101) (xy 401.121872 -286.801782)
			(xy 401.129767 -286.850359) (xy 401.130262 -286.874966) (xy 401.46911 -286.874966) (xy 401.47307 -286.825912)
			(xy 401.484847 -286.778128) (xy 401.504138 -286.732852) (xy 401.530441 -286.691256) (xy 401.563076 -286.654419)
			(xy 401.601197 -286.623294) (xy 401.643818 -286.598687) (xy 401.689834 -286.581235) (xy 401.738053 -286.571391)
			(xy 401.787228 -286.56941) (xy 401.836083 -286.575342) (xy 401.883354 -286.589034) (xy 401.927816 -286.610132)
			(xy 401.968319 -286.638088) (xy 402.003812 -286.67218) (xy 402.033377 -286.711524) (xy 402.056248 -286.755101)
			(xy 402.071832 -286.801782) (xy 402.079727 -286.850359) (xy 402.080222 -286.874966) (xy 402.41907 -286.874966)
			(xy 402.42303 -286.825912) (xy 402.434807 -286.778128) (xy 402.454098 -286.732852) (xy 402.480401 -286.691256)
			(xy 402.513036 -286.654419) (xy 402.551157 -286.623294) (xy 402.593778 -286.598687) (xy 402.639794 -286.581235)
			(xy 402.688013 -286.571391) (xy 402.737188 -286.56941) (xy 402.786043 -286.575342) (xy 402.833314 -286.589034)
			(xy 402.877776 -286.610132) (xy 402.918279 -286.638088) (xy 402.953772 -286.67218) (xy 402.983337 -286.711524)
			(xy 403.006208 -286.755101) (xy 403.021792 -286.801782) (xy 403.029687 -286.850359) (xy 403.030182 -286.874966)
			(xy 403.36903 -286.874966) (xy 403.37299 -286.825912) (xy 403.384767 -286.778128) (xy 403.404058 -286.732852)
			(xy 403.430361 -286.691256) (xy 403.462996 -286.654419) (xy 403.501117 -286.623294) (xy 403.543738 -286.598687)
			(xy 403.589754 -286.581235) (xy 403.637973 -286.571391) (xy 403.687148 -286.56941) (xy 403.736003 -286.575342)
			(xy 403.783274 -286.589034) (xy 403.827736 -286.610132) (xy 403.868239 -286.638088) (xy 403.903732 -286.67218)
			(xy 403.933297 -286.711524) (xy 403.956168 -286.755101) (xy 403.971752 -286.801782) (xy 403.979647 -286.850359)
			(xy 403.980142 -286.874966) (xy 404.31899 -286.874966) (xy 404.32295 -286.825912) (xy 404.334727 -286.778128)
			(xy 404.354018 -286.732852) (xy 404.380321 -286.691256) (xy 404.412956 -286.654419) (xy 404.451077 -286.623294)
			(xy 404.493698 -286.598687) (xy 404.539714 -286.581235) (xy 404.587933 -286.571391) (xy 404.637108 -286.56941)
			(xy 404.685963 -286.575342) (xy 404.733234 -286.589034) (xy 404.777696 -286.610132) (xy 404.818199 -286.638088)
			(xy 404.853692 -286.67218) (xy 404.883257 -286.711524) (xy 404.906128 -286.755101) (xy 404.921712 -286.801782)
			(xy 404.929607 -286.850359) (xy 404.930102 -286.874966) (xy 405.269204 -286.874966) (xy 405.273164 -286.825912)
			(xy 405.284941 -286.778128) (xy 405.304232 -286.732852) (xy 405.330535 -286.691256) (xy 405.36317 -286.654419)
			(xy 405.401291 -286.623294) (xy 405.443912 -286.598687) (xy 405.489928 -286.581235) (xy 405.538147 -286.571391)
			(xy 405.587322 -286.56941) (xy 405.636177 -286.575342) (xy 405.683448 -286.589034) (xy 405.72791 -286.610132)
			(xy 405.768413 -286.638088) (xy 405.803906 -286.67218) (xy 405.833471 -286.711524) (xy 405.856342 -286.755101)
			(xy 405.871926 -286.801782) (xy 405.879821 -286.850359) (xy 405.880316 -286.874966) (xy 406.219164 -286.874966)
			(xy 406.223124 -286.825912) (xy 406.234901 -286.778128) (xy 406.254192 -286.732852) (xy 406.280495 -286.691256)
			(xy 406.31313 -286.654419) (xy 406.351251 -286.623294) (xy 406.393872 -286.598687) (xy 406.439888 -286.581235)
			(xy 406.488107 -286.571391) (xy 406.537282 -286.56941) (xy 406.586137 -286.575342) (xy 406.633408 -286.589034)
			(xy 406.67787 -286.610132) (xy 406.718373 -286.638088) (xy 406.753866 -286.67218) (xy 406.783431 -286.711524)
			(xy 406.806302 -286.755101) (xy 406.821886 -286.801782) (xy 406.829781 -286.850359) (xy 406.830276 -286.874966)
			(xy 408.119084 -286.874966) (xy 408.123044 -286.825912) (xy 408.134821 -286.778128) (xy 408.154112 -286.732852)
			(xy 408.180415 -286.691256) (xy 408.21305 -286.654419) (xy 408.251171 -286.623294) (xy 408.293792 -286.598687)
			(xy 408.339808 -286.581235) (xy 408.388027 -286.571391) (xy 408.437202 -286.56941) (xy 408.486057 -286.575342)
			(xy 408.533328 -286.589034) (xy 408.57779 -286.610132) (xy 408.618293 -286.638088) (xy 408.653786 -286.67218)
			(xy 408.683351 -286.711524) (xy 408.706222 -286.755101) (xy 408.721806 -286.801782) (xy 408.729701 -286.850359)
			(xy 408.730196 -286.874966) (xy 409.069044 -286.874966) (xy 409.073004 -286.825912) (xy 409.084781 -286.778128)
			(xy 409.104072 -286.732852) (xy 409.130375 -286.691256) (xy 409.16301 -286.654419) (xy 409.201131 -286.623294)
			(xy 409.243752 -286.598687) (xy 409.289768 -286.581235) (xy 409.337987 -286.571391) (xy 409.387162 -286.56941)
			(xy 409.436017 -286.575342) (xy 409.483288 -286.589034) (xy 409.52775 -286.610132) (xy 409.568253 -286.638088)
			(xy 409.603746 -286.67218) (xy 409.633311 -286.711524) (xy 409.656182 -286.755101) (xy 409.671766 -286.801782)
			(xy 409.679661 -286.850359) (xy 409.680156 -286.874966) (xy 410.019004 -286.874966) (xy 410.022964 -286.825912)
			(xy 410.034741 -286.778128) (xy 410.054032 -286.732852) (xy 410.080335 -286.691256) (xy 410.11297 -286.654419)
			(xy 410.151091 -286.623294) (xy 410.193712 -286.598687) (xy 410.239728 -286.581235) (xy 410.287947 -286.571391)
			(xy 410.337122 -286.56941) (xy 410.385977 -286.575342) (xy 410.433248 -286.589034) (xy 410.47771 -286.610132)
			(xy 410.518213 -286.638088) (xy 410.553706 -286.67218) (xy 410.583271 -286.711524) (xy 410.606142 -286.755101)
			(xy 410.621726 -286.801782) (xy 410.629621 -286.850359) (xy 410.630116 -286.874966) (xy 410.969218 -286.874966)
			(xy 410.973178 -286.825912) (xy 410.984955 -286.778128) (xy 411.004246 -286.732852) (xy 411.030549 -286.691256)
			(xy 411.063184 -286.654419) (xy 411.101305 -286.623294) (xy 411.143926 -286.598687) (xy 411.189942 -286.581235)
			(xy 411.238161 -286.571391) (xy 411.287336 -286.56941) (xy 411.336191 -286.575342) (xy 411.383462 -286.589034)
			(xy 411.427924 -286.610132) (xy 411.468427 -286.638088) (xy 411.50392 -286.67218) (xy 411.533485 -286.711524)
			(xy 411.556356 -286.755101) (xy 411.57194 -286.801782) (xy 411.579835 -286.850359) (xy 411.58033 -286.874966)
			(xy 411.919178 -286.874966) (xy 411.923138 -286.825912) (xy 411.934915 -286.778128) (xy 411.954206 -286.732852)
			(xy 411.980509 -286.691256) (xy 412.013144 -286.654419) (xy 412.051265 -286.623294) (xy 412.093886 -286.598687)
			(xy 412.139902 -286.581235) (xy 412.188121 -286.571391) (xy 412.237296 -286.56941) (xy 412.286151 -286.575342)
			(xy 412.333422 -286.589034) (xy 412.377884 -286.610132) (xy 412.418387 -286.638088) (xy 412.45388 -286.67218)
			(xy 412.483445 -286.711524) (xy 412.506316 -286.755101) (xy 412.5219 -286.801782) (xy 412.529795 -286.850359)
			(xy 412.53029 -286.874966) (xy 412.869138 -286.874966) (xy 412.873098 -286.825912) (xy 412.884875 -286.778128)
			(xy 412.904166 -286.732852) (xy 412.930469 -286.691256) (xy 412.963104 -286.654419) (xy 413.001225 -286.623294)
			(xy 413.043846 -286.598687) (xy 413.089862 -286.581235) (xy 413.138081 -286.571391) (xy 413.187256 -286.56941)
			(xy 413.236111 -286.575342) (xy 413.283382 -286.589034) (xy 413.327844 -286.610132) (xy 413.368347 -286.638088)
			(xy 413.40384 -286.67218) (xy 413.433405 -286.711524) (xy 413.456276 -286.755101) (xy 413.47186 -286.801782)
			(xy 413.479755 -286.850359) (xy 413.48025 -286.874966) (xy 413.819098 -286.874966) (xy 413.823058 -286.825912)
			(xy 413.834835 -286.778128) (xy 413.854126 -286.732852) (xy 413.880429 -286.691256) (xy 413.913064 -286.654419)
			(xy 413.951185 -286.623294) (xy 413.993806 -286.598687) (xy 414.039822 -286.581235) (xy 414.088041 -286.571391)
			(xy 414.137216 -286.56941) (xy 414.186071 -286.575342) (xy 414.233342 -286.589034) (xy 414.277804 -286.610132)
			(xy 414.318307 -286.638088) (xy 414.3538 -286.67218) (xy 414.383365 -286.711524) (xy 414.406236 -286.755101)
			(xy 414.42182 -286.801782) (xy 414.429715 -286.850359) (xy 414.43021 -286.874966) (xy 414.769058 -286.874966)
			(xy 414.773018 -286.825912) (xy 414.784795 -286.778128) (xy 414.804086 -286.732852) (xy 414.830389 -286.691256)
			(xy 414.863024 -286.654419) (xy 414.901145 -286.623294) (xy 414.943766 -286.598687) (xy 414.989782 -286.581235)
			(xy 415.038001 -286.571391) (xy 415.087176 -286.56941) (xy 415.136031 -286.575342) (xy 415.183302 -286.589034)
			(xy 415.227764 -286.610132) (xy 415.268267 -286.638088) (xy 415.30376 -286.67218) (xy 415.333325 -286.711524)
			(xy 415.356196 -286.755101) (xy 415.37178 -286.801782) (xy 415.379675 -286.850359) (xy 415.38017 -286.874966)
			(xy 415.719018 -286.874966) (xy 415.722978 -286.825912) (xy 415.734755 -286.778128) (xy 415.754046 -286.732852)
			(xy 415.780349 -286.691256) (xy 415.812984 -286.654419) (xy 415.851105 -286.623294) (xy 415.893726 -286.598687)
			(xy 415.939742 -286.581235) (xy 415.987961 -286.571391) (xy 416.037136 -286.56941) (xy 416.085991 -286.575342)
			(xy 416.133262 -286.589034) (xy 416.177724 -286.610132) (xy 416.218227 -286.638088) (xy 416.25372 -286.67218)
			(xy 416.283285 -286.711524) (xy 416.306156 -286.755101) (xy 416.32174 -286.801782) (xy 416.329635 -286.850359)
			(xy 416.33013 -286.874966) (xy 416.668978 -286.874966) (xy 416.672938 -286.825912) (xy 416.684715 -286.778128)
			(xy 416.704006 -286.732852) (xy 416.730309 -286.691256) (xy 416.762944 -286.654419) (xy 416.801065 -286.623294)
			(xy 416.843686 -286.598687) (xy 416.889702 -286.581235) (xy 416.937921 -286.571391) (xy 416.987096 -286.56941)
			(xy 417.035951 -286.575342) (xy 417.083222 -286.589034) (xy 417.127684 -286.610132) (xy 417.168187 -286.638088)
			(xy 417.20368 -286.67218) (xy 417.233245 -286.711524) (xy 417.256116 -286.755101) (xy 417.2717 -286.801782)
			(xy 417.279595 -286.850359) (xy 417.28009 -286.874966) (xy 417.279595 -286.899573) (xy 417.2717 -286.94815)
			(xy 417.256116 -286.994831) (xy 417.233245 -287.038408) (xy 417.20368 -287.077752) (xy 417.168187 -287.111844)
			(xy 417.127684 -287.1398) (xy 417.083222 -287.160898) (xy 417.035951 -287.17459) (xy 416.987096 -287.180522)
			(xy 416.937921 -287.178541) (xy 416.889702 -287.168697) (xy 416.843686 -287.151245) (xy 416.801065 -287.126638)
			(xy 416.762944 -287.095513) (xy 416.730309 -287.058676) (xy 416.704006 -287.01708) (xy 416.684715 -286.971804)
			(xy 416.672938 -286.92402) (xy 416.668978 -286.874966) (xy 416.33013 -286.874966) (xy 416.329635 -286.899573)
			(xy 416.32174 -286.94815) (xy 416.306156 -286.994831) (xy 416.283285 -287.038408) (xy 416.25372 -287.077752)
			(xy 416.218227 -287.111844) (xy 416.177724 -287.1398) (xy 416.133262 -287.160898) (xy 416.085991 -287.17459)
			(xy 416.037136 -287.180522) (xy 415.987961 -287.178541) (xy 415.939742 -287.168697) (xy 415.893726 -287.151245)
			(xy 415.851105 -287.126638) (xy 415.812984 -287.095513) (xy 415.780349 -287.058676) (xy 415.754046 -287.01708)
			(xy 415.734755 -286.971804) (xy 415.722978 -286.92402) (xy 415.719018 -286.874966) (xy 415.38017 -286.874966)
			(xy 415.379675 -286.899573) (xy 415.37178 -286.94815) (xy 415.356196 -286.994831) (xy 415.333325 -287.038408)
			(xy 415.30376 -287.077752) (xy 415.268267 -287.111844) (xy 415.227764 -287.1398) (xy 415.183302 -287.160898)
			(xy 415.136031 -287.17459) (xy 415.087176 -287.180522) (xy 415.038001 -287.178541) (xy 414.989782 -287.168697)
			(xy 414.943766 -287.151245) (xy 414.901145 -287.126638) (xy 414.863024 -287.095513) (xy 414.830389 -287.058676)
			(xy 414.804086 -287.01708) (xy 414.784795 -286.971804) (xy 414.773018 -286.92402) (xy 414.769058 -286.874966)
			(xy 414.43021 -286.874966) (xy 414.429715 -286.899573) (xy 414.42182 -286.94815) (xy 414.406236 -286.994831)
			(xy 414.383365 -287.038408) (xy 414.3538 -287.077752) (xy 414.318307 -287.111844) (xy 414.277804 -287.1398)
			(xy 414.233342 -287.160898) (xy 414.186071 -287.17459) (xy 414.137216 -287.180522) (xy 414.088041 -287.178541)
			(xy 414.039822 -287.168697) (xy 413.993806 -287.151245) (xy 413.951185 -287.126638) (xy 413.913064 -287.095513)
			(xy 413.880429 -287.058676) (xy 413.854126 -287.01708) (xy 413.834835 -286.971804) (xy 413.823058 -286.92402)
			(xy 413.819098 -286.874966) (xy 413.48025 -286.874966) (xy 413.479755 -286.899573) (xy 413.47186 -286.94815)
			(xy 413.456276 -286.994831) (xy 413.433405 -287.038408) (xy 413.40384 -287.077752) (xy 413.368347 -287.111844)
			(xy 413.327844 -287.1398) (xy 413.283382 -287.160898) (xy 413.236111 -287.17459) (xy 413.187256 -287.180522)
			(xy 413.138081 -287.178541) (xy 413.089862 -287.168697) (xy 413.043846 -287.151245) (xy 413.001225 -287.126638)
			(xy 412.963104 -287.095513) (xy 412.930469 -287.058676) (xy 412.904166 -287.01708) (xy 412.884875 -286.971804)
			(xy 412.873098 -286.92402) (xy 412.869138 -286.874966) (xy 412.53029 -286.874966) (xy 412.529795 -286.899573)
			(xy 412.5219 -286.94815) (xy 412.506316 -286.994831) (xy 412.483445 -287.038408) (xy 412.45388 -287.077752)
			(xy 412.418387 -287.111844) (xy 412.377884 -287.1398) (xy 412.333422 -287.160898) (xy 412.286151 -287.17459)
			(xy 412.237296 -287.180522) (xy 412.188121 -287.178541) (xy 412.139902 -287.168697) (xy 412.093886 -287.151245)
			(xy 412.051265 -287.126638) (xy 412.013144 -287.095513) (xy 411.980509 -287.058676) (xy 411.954206 -287.01708)
			(xy 411.934915 -286.971804) (xy 411.923138 -286.92402) (xy 411.919178 -286.874966) (xy 411.58033 -286.874966)
			(xy 411.579835 -286.899573) (xy 411.57194 -286.94815) (xy 411.556356 -286.994831) (xy 411.533485 -287.038408)
			(xy 411.50392 -287.077752) (xy 411.468427 -287.111844) (xy 411.427924 -287.1398) (xy 411.383462 -287.160898)
			(xy 411.336191 -287.17459) (xy 411.287336 -287.180522) (xy 411.238161 -287.178541) (xy 411.189942 -287.168697)
			(xy 411.143926 -287.151245) (xy 411.101305 -287.126638) (xy 411.063184 -287.095513) (xy 411.030549 -287.058676)
			(xy 411.004246 -287.01708) (xy 410.984955 -286.971804) (xy 410.973178 -286.92402) (xy 410.969218 -286.874966)
			(xy 410.630116 -286.874966) (xy 410.629621 -286.899573) (xy 410.621726 -286.94815) (xy 410.606142 -286.994831)
			(xy 410.583271 -287.038408) (xy 410.553706 -287.077752) (xy 410.518213 -287.111844) (xy 410.47771 -287.1398)
			(xy 410.433248 -287.160898) (xy 410.385977 -287.17459) (xy 410.337122 -287.180522) (xy 410.287947 -287.178541)
			(xy 410.239728 -287.168697) (xy 410.193712 -287.151245) (xy 410.151091 -287.126638) (xy 410.11297 -287.095513)
			(xy 410.080335 -287.058676) (xy 410.054032 -287.01708) (xy 410.034741 -286.971804) (xy 410.022964 -286.92402)
			(xy 410.019004 -286.874966) (xy 409.680156 -286.874966) (xy 409.679661 -286.899573) (xy 409.671766 -286.94815)
			(xy 409.656182 -286.994831) (xy 409.633311 -287.038408) (xy 409.603746 -287.077752) (xy 409.568253 -287.111844)
			(xy 409.52775 -287.1398) (xy 409.483288 -287.160898) (xy 409.436017 -287.17459) (xy 409.387162 -287.180522)
			(xy 409.337987 -287.178541) (xy 409.289768 -287.168697) (xy 409.243752 -287.151245) (xy 409.201131 -287.126638)
			(xy 409.16301 -287.095513) (xy 409.130375 -287.058676) (xy 409.104072 -287.01708) (xy 409.084781 -286.971804)
			(xy 409.073004 -286.92402) (xy 409.069044 -286.874966) (xy 408.730196 -286.874966) (xy 408.729701 -286.899573)
			(xy 408.721806 -286.94815) (xy 408.706222 -286.994831) (xy 408.683351 -287.038408) (xy 408.653786 -287.077752)
			(xy 408.618293 -287.111844) (xy 408.57779 -287.1398) (xy 408.533328 -287.160898) (xy 408.486057 -287.17459)
			(xy 408.437202 -287.180522) (xy 408.388027 -287.178541) (xy 408.339808 -287.168697) (xy 408.293792 -287.151245)
			(xy 408.251171 -287.126638) (xy 408.21305 -287.095513) (xy 408.180415 -287.058676) (xy 408.154112 -287.01708)
			(xy 408.134821 -286.971804) (xy 408.123044 -286.92402) (xy 408.119084 -286.874966) (xy 406.830276 -286.874966)
			(xy 406.829781 -286.899573) (xy 406.821886 -286.94815) (xy 406.806302 -286.994831) (xy 406.783431 -287.038408)
			(xy 406.753866 -287.077752) (xy 406.718373 -287.111844) (xy 406.67787 -287.1398) (xy 406.633408 -287.160898)
			(xy 406.586137 -287.17459) (xy 406.537282 -287.180522) (xy 406.488107 -287.178541) (xy 406.439888 -287.168697)
			(xy 406.393872 -287.151245) (xy 406.351251 -287.126638) (xy 406.31313 -287.095513) (xy 406.280495 -287.058676)
			(xy 406.254192 -287.01708) (xy 406.234901 -286.971804) (xy 406.223124 -286.92402) (xy 406.219164 -286.874966)
			(xy 405.880316 -286.874966) (xy 405.879821 -286.899573) (xy 405.871926 -286.94815) (xy 405.856342 -286.994831)
			(xy 405.833471 -287.038408) (xy 405.803906 -287.077752) (xy 405.768413 -287.111844) (xy 405.72791 -287.1398)
			(xy 405.683448 -287.160898) (xy 405.636177 -287.17459) (xy 405.587322 -287.180522) (xy 405.538147 -287.178541)
			(xy 405.489928 -287.168697) (xy 405.443912 -287.151245) (xy 405.401291 -287.126638) (xy 405.36317 -287.095513)
			(xy 405.330535 -287.058676) (xy 405.304232 -287.01708) (xy 405.284941 -286.971804) (xy 405.273164 -286.92402)
			(xy 405.269204 -286.874966) (xy 404.930102 -286.874966) (xy 404.929607 -286.899573) (xy 404.921712 -286.94815)
			(xy 404.906128 -286.994831) (xy 404.883257 -287.038408) (xy 404.853692 -287.077752) (xy 404.818199 -287.111844)
			(xy 404.777696 -287.1398) (xy 404.733234 -287.160898) (xy 404.685963 -287.17459) (xy 404.637108 -287.180522)
			(xy 404.587933 -287.178541) (xy 404.539714 -287.168697) (xy 404.493698 -287.151245) (xy 404.451077 -287.126638)
			(xy 404.412956 -287.095513) (xy 404.380321 -287.058676) (xy 404.354018 -287.01708) (xy 404.334727 -286.971804)
			(xy 404.32295 -286.92402) (xy 404.31899 -286.874966) (xy 403.980142 -286.874966) (xy 403.979647 -286.899573)
			(xy 403.971752 -286.94815) (xy 403.956168 -286.994831) (xy 403.933297 -287.038408) (xy 403.903732 -287.077752)
			(xy 403.868239 -287.111844) (xy 403.827736 -287.1398) (xy 403.783274 -287.160898) (xy 403.736003 -287.17459)
			(xy 403.687148 -287.180522) (xy 403.637973 -287.178541) (xy 403.589754 -287.168697) (xy 403.543738 -287.151245)
			(xy 403.501117 -287.126638) (xy 403.462996 -287.095513) (xy 403.430361 -287.058676) (xy 403.404058 -287.01708)
			(xy 403.384767 -286.971804) (xy 403.37299 -286.92402) (xy 403.36903 -286.874966) (xy 403.030182 -286.874966)
			(xy 403.029687 -286.899573) (xy 403.021792 -286.94815) (xy 403.006208 -286.994831) (xy 402.983337 -287.038408)
			(xy 402.953772 -287.077752) (xy 402.918279 -287.111844) (xy 402.877776 -287.1398) (xy 402.833314 -287.160898)
			(xy 402.786043 -287.17459) (xy 402.737188 -287.180522) (xy 402.688013 -287.178541) (xy 402.639794 -287.168697)
			(xy 402.593778 -287.151245) (xy 402.551157 -287.126638) (xy 402.513036 -287.095513) (xy 402.480401 -287.058676)
			(xy 402.454098 -287.01708) (xy 402.434807 -286.971804) (xy 402.42303 -286.92402) (xy 402.41907 -286.874966)
			(xy 402.080222 -286.874966) (xy 402.079727 -286.899573) (xy 402.071832 -286.94815) (xy 402.056248 -286.994831)
			(xy 402.033377 -287.038408) (xy 402.003812 -287.077752) (xy 401.968319 -287.111844) (xy 401.927816 -287.1398)
			(xy 401.883354 -287.160898) (xy 401.836083 -287.17459) (xy 401.787228 -287.180522) (xy 401.738053 -287.178541)
			(xy 401.689834 -287.168697) (xy 401.643818 -287.151245) (xy 401.601197 -287.126638) (xy 401.563076 -287.095513)
			(xy 401.530441 -287.058676) (xy 401.504138 -287.01708) (xy 401.484847 -286.971804) (xy 401.47307 -286.92402)
			(xy 401.46911 -286.874966) (xy 401.130262 -286.874966) (xy 401.129767 -286.899573) (xy 401.121872 -286.94815)
			(xy 401.106288 -286.994831) (xy 401.083417 -287.038408) (xy 401.053852 -287.077752) (xy 401.018359 -287.111844)
			(xy 400.977856 -287.1398) (xy 400.933394 -287.160898) (xy 400.886123 -287.17459) (xy 400.837268 -287.180522)
			(xy 400.788093 -287.178541) (xy 400.739874 -287.168697) (xy 400.693858 -287.151245) (xy 400.651237 -287.126638)
			(xy 400.613116 -287.095513) (xy 400.580481 -287.058676) (xy 400.554178 -287.01708) (xy 400.534887 -286.971804)
			(xy 400.52311 -286.92402) (xy 400.51915 -286.874966) (xy 400.180302 -286.874966) (xy 400.179807 -286.899573)
			(xy 400.171912 -286.94815) (xy 400.156328 -286.994831) (xy 400.133457 -287.038408) (xy 400.103892 -287.077752)
			(xy 400.068399 -287.111844) (xy 400.027896 -287.1398) (xy 399.983434 -287.160898) (xy 399.936163 -287.17459)
			(xy 399.887308 -287.180522) (xy 399.838133 -287.178541) (xy 399.789914 -287.168697) (xy 399.743898 -287.151245)
			(xy 399.701277 -287.126638) (xy 399.663156 -287.095513) (xy 399.630521 -287.058676) (xy 399.604218 -287.01708)
			(xy 399.584927 -286.971804) (xy 399.57315 -286.92402) (xy 399.56919 -286.874966) (xy 399.230342 -286.874966)
			(xy 399.229847 -286.899573) (xy 399.221952 -286.94815) (xy 399.206368 -286.994831) (xy 399.183497 -287.038408)
			(xy 399.153932 -287.077752) (xy 399.118439 -287.111844) (xy 399.077936 -287.1398) (xy 399.033474 -287.160898)
			(xy 398.986203 -287.17459) (xy 398.937348 -287.180522) (xy 398.888173 -287.178541) (xy 398.839954 -287.168697)
			(xy 398.793938 -287.151245) (xy 398.751317 -287.126638) (xy 398.713196 -287.095513) (xy 398.680561 -287.058676)
			(xy 398.654258 -287.01708) (xy 398.634967 -286.971804) (xy 398.62319 -286.92402) (xy 398.61923 -286.874966)
			(xy 398.280128 -286.874966) (xy 398.279633 -286.899573) (xy 398.271738 -286.94815) (xy 398.256154 -286.994831)
			(xy 398.233283 -287.038408) (xy 398.203718 -287.077752) (xy 398.168225 -287.111844) (xy 398.127722 -287.1398)
			(xy 398.08326 -287.160898) (xy 398.035989 -287.17459) (xy 397.987134 -287.180522) (xy 397.937959 -287.178541)
			(xy 397.88974 -287.168697) (xy 397.843724 -287.151245) (xy 397.801103 -287.126638) (xy 397.762982 -287.095513)
			(xy 397.730347 -287.058676) (xy 397.704044 -287.01708) (xy 397.684753 -286.971804) (xy 397.672976 -286.92402)
			(xy 397.669016 -286.874966) (xy 397.330168 -286.874966) (xy 397.329673 -286.899573) (xy 397.321778 -286.94815)
			(xy 397.306194 -286.994831) (xy 397.283323 -287.038408) (xy 397.253758 -287.077752) (xy 397.218265 -287.111844)
			(xy 397.177762 -287.1398) (xy 397.1333 -287.160898) (xy 397.086029 -287.17459) (xy 397.037174 -287.180522)
			(xy 396.987999 -287.178541) (xy 396.93978 -287.168697) (xy 396.893764 -287.151245) (xy 396.851143 -287.126638)
			(xy 396.813022 -287.095513) (xy 396.780387 -287.058676) (xy 396.754084 -287.01708) (xy 396.734793 -286.971804)
			(xy 396.723016 -286.92402) (xy 396.719056 -286.874966) (xy 396.380208 -286.874966) (xy 396.379713 -286.899573)
			(xy 396.371818 -286.94815) (xy 396.356234 -286.994831) (xy 396.333363 -287.038408) (xy 396.303798 -287.077752)
			(xy 396.268305 -287.111844) (xy 396.227802 -287.1398) (xy 396.18334 -287.160898) (xy 396.136069 -287.17459)
			(xy 396.087214 -287.180522) (xy 396.038039 -287.178541) (xy 395.98982 -287.168697) (xy 395.943804 -287.151245)
			(xy 395.901183 -287.126638) (xy 395.863062 -287.095513) (xy 395.830427 -287.058676) (xy 395.804124 -287.01708)
			(xy 395.784833 -286.971804) (xy 395.773056 -286.92402) (xy 395.769096 -286.874966) (xy 395.430248 -286.874966)
			(xy 395.429753 -286.899573) (xy 395.421858 -286.94815) (xy 395.406274 -286.994831) (xy 395.383403 -287.038408)
			(xy 395.353838 -287.077752) (xy 395.318345 -287.111844) (xy 395.277842 -287.1398) (xy 395.23338 -287.160898)
			(xy 395.186109 -287.17459) (xy 395.137254 -287.180522) (xy 395.088079 -287.178541) (xy 395.03986 -287.168697)
			(xy 394.993844 -287.151245) (xy 394.951223 -287.126638) (xy 394.913102 -287.095513) (xy 394.880467 -287.058676)
			(xy 394.854164 -287.01708) (xy 394.834873 -286.971804) (xy 394.823096 -286.92402) (xy 394.819136 -286.874966)
			(xy 394.480288 -286.874966) (xy 394.479793 -286.899573) (xy 394.471898 -286.94815) (xy 394.456314 -286.994831)
			(xy 394.433443 -287.038408) (xy 394.403878 -287.077752) (xy 394.368385 -287.111844) (xy 394.327882 -287.1398)
			(xy 394.28342 -287.160898) (xy 394.236149 -287.17459) (xy 394.187294 -287.180522) (xy 394.138119 -287.178541)
			(xy 394.0899 -287.168697) (xy 394.043884 -287.151245) (xy 394.001263 -287.126638) (xy 393.963142 -287.095513)
			(xy 393.930507 -287.058676) (xy 393.904204 -287.01708) (xy 393.884913 -286.971804) (xy 393.873136 -286.92402)
			(xy 393.869176 -286.874966) (xy 393.530328 -286.874966) (xy 393.529833 -286.899573) (xy 393.521938 -286.94815)
			(xy 393.506354 -286.994831) (xy 393.483483 -287.038408) (xy 393.453918 -287.077752) (xy 393.418425 -287.111844)
			(xy 393.377922 -287.1398) (xy 393.33346 -287.160898) (xy 393.286189 -287.17459) (xy 393.237334 -287.180522)
			(xy 393.188159 -287.178541) (xy 393.13994 -287.168697) (xy 393.093924 -287.151245) (xy 393.051303 -287.126638)
			(xy 393.013182 -287.095513) (xy 392.980547 -287.058676) (xy 392.954244 -287.01708) (xy 392.934953 -286.971804)
			(xy 392.923176 -286.92402) (xy 392.919216 -286.874966) (xy 392.580109 -286.874966) (xy 392.579619 -286.899319)
			(xy 392.571724 -286.947896) (xy 392.55614 -286.994577) (xy 392.533269 -287.038154) (xy 392.503704 -287.077498)
			(xy 392.468211 -287.11159) (xy 392.427708 -287.139546) (xy 392.383246 -287.160644) (xy 392.335975 -287.174336)
			(xy 392.28712 -287.180268) (xy 392.237945 -287.178287) (xy 392.189726 -287.168443) (xy 392.14371 -287.150991)
			(xy 392.101089 -287.126384) (xy 392.062968 -287.095259) (xy 392.030333 -287.058422) (xy 392.00403 -287.016826)
			(xy 391.984739 -286.97155) (xy 391.972962 -286.923766) (xy 391.969002 -286.874712) (xy 391.630154 -286.874712)
			(xy 391.629659 -286.899319) (xy 391.621764 -286.947896) (xy 391.60618 -286.994577) (xy 391.583309 -287.038154)
			(xy 391.553744 -287.077498) (xy 391.518251 -287.11159) (xy 391.477748 -287.139546) (xy 391.433286 -287.160644)
			(xy 391.386015 -287.174336) (xy 391.33716 -287.180268) (xy 391.287985 -287.178287) (xy 391.239766 -287.168443)
			(xy 391.19375 -287.150991) (xy 391.151129 -287.126384) (xy 391.113008 -287.095259) (xy 391.080373 -287.058422)
			(xy 391.05407 -287.016826) (xy 391.034779 -286.97155) (xy 391.023002 -286.923766) (xy 391.019042 -286.874712)
			(xy 390.680189 -286.874712) (xy 390.680194 -286.874966) (xy 390.679699 -286.899573) (xy 390.671804 -286.94815)
			(xy 390.65622 -286.994831) (xy 390.633349 -287.038408) (xy 390.603784 -287.077752) (xy 390.568291 -287.111844)
			(xy 390.527788 -287.1398) (xy 390.483326 -287.160898) (xy 390.436055 -287.17459) (xy 390.3872 -287.180522)
			(xy 390.338025 -287.178541) (xy 390.289806 -287.168697) (xy 390.24379 -287.151245) (xy 390.201169 -287.126638)
			(xy 390.163048 -287.095513) (xy 390.130413 -287.058676) (xy 390.10411 -287.01708) (xy 390.084819 -286.971804)
			(xy 390.073042 -286.92402) (xy 390.069082 -286.874966) (xy 389.730234 -286.874966) (xy 389.729739 -286.899573)
			(xy 389.721844 -286.94815) (xy 389.70626 -286.994831) (xy 389.683389 -287.038408) (xy 389.653824 -287.077752)
			(xy 389.618331 -287.111844) (xy 389.577828 -287.1398) (xy 389.533366 -287.160898) (xy 389.486095 -287.17459)
			(xy 389.43724 -287.180522) (xy 389.388065 -287.178541) (xy 389.339846 -287.168697) (xy 389.29383 -287.151245)
			(xy 389.251209 -287.126638) (xy 389.213088 -287.095513) (xy 389.180453 -287.058676) (xy 389.15415 -287.01708)
			(xy 389.134859 -286.971804) (xy 389.123082 -286.92402) (xy 389.119122 -286.874966) (xy 388.780274 -286.874966)
			(xy 388.779779 -286.899573) (xy 388.771884 -286.94815) (xy 388.7563 -286.994831) (xy 388.733429 -287.038408)
			(xy 388.703864 -287.077752) (xy 388.668371 -287.111844) (xy 388.627868 -287.1398) (xy 388.583406 -287.160898)
			(xy 388.536135 -287.17459) (xy 388.48728 -287.180522) (xy 388.438105 -287.178541) (xy 388.389886 -287.168697)
			(xy 388.34387 -287.151245) (xy 388.301249 -287.126638) (xy 388.263128 -287.095513) (xy 388.230493 -287.058676)
			(xy 388.20419 -287.01708) (xy 388.184899 -286.971804) (xy 388.173122 -286.92402) (xy 388.169162 -286.874966)
			(xy 387.830314 -286.874966) (xy 387.829819 -286.899573) (xy 387.821924 -286.94815) (xy 387.80634 -286.994831)
			(xy 387.783469 -287.038408) (xy 387.753904 -287.077752) (xy 387.718411 -287.111844) (xy 387.677908 -287.1398)
			(xy 387.633446 -287.160898) (xy 387.586175 -287.17459) (xy 387.53732 -287.180522) (xy 387.488145 -287.178541)
			(xy 387.439926 -287.168697) (xy 387.39391 -287.151245) (xy 387.351289 -287.126638) (xy 387.313168 -287.095513)
			(xy 387.280533 -287.058676) (xy 387.25423 -287.01708) (xy 387.234939 -286.971804) (xy 387.223162 -286.92402)
			(xy 387.219202 -286.874966) (xy 386.880354 -286.874966) (xy 386.879859 -286.899573) (xy 386.871964 -286.94815)
			(xy 386.85638 -286.994831) (xy 386.833509 -287.038408) (xy 386.803944 -287.077752) (xy 386.768451 -287.111844)
			(xy 386.727948 -287.1398) (xy 386.683486 -287.160898) (xy 386.636215 -287.17459) (xy 386.58736 -287.180522)
			(xy 386.538185 -287.178541) (xy 386.489966 -287.168697) (xy 386.44395 -287.151245) (xy 386.401329 -287.126638)
			(xy 386.363208 -287.095513) (xy 386.330573 -287.058676) (xy 386.30427 -287.01708) (xy 386.284979 -286.971804)
			(xy 386.273202 -286.92402) (xy 386.269242 -286.874966) (xy 385.93014 -286.874966) (xy 385.929645 -286.899573)
			(xy 385.92175 -286.94815) (xy 385.906166 -286.994831) (xy 385.883295 -287.038408) (xy 385.85373 -287.077752)
			(xy 385.818237 -287.111844) (xy 385.777734 -287.1398) (xy 385.733272 -287.160898) (xy 385.686001 -287.17459)
			(xy 385.637146 -287.180522) (xy 385.587971 -287.178541) (xy 385.539752 -287.168697) (xy 385.493736 -287.151245)
			(xy 385.451115 -287.126638) (xy 385.412994 -287.095513) (xy 385.380359 -287.058676) (xy 385.354056 -287.01708)
			(xy 385.334765 -286.971804) (xy 385.322988 -286.92402) (xy 385.319028 -286.874966) (xy 384.98018 -286.874966)
			(xy 384.979685 -286.899573) (xy 384.97179 -286.94815) (xy 384.956206 -286.994831) (xy 384.933335 -287.038408)
			(xy 384.90377 -287.077752) (xy 384.868277 -287.111844) (xy 384.827774 -287.1398) (xy 384.783312 -287.160898)
			(xy 384.736041 -287.17459) (xy 384.687186 -287.180522) (xy 384.638011 -287.178541) (xy 384.589792 -287.168697)
			(xy 384.543776 -287.151245) (xy 384.501155 -287.126638) (xy 384.463034 -287.095513) (xy 384.430399 -287.058676)
			(xy 384.404096 -287.01708) (xy 384.384805 -286.971804) (xy 384.373028 -286.92402) (xy 384.369068 -286.874966)
			(xy 382.615 -286.874966) (xy 382.636159 -286.906948) (xy 382.659831 -286.957445) (xy 382.675899 -287.010852)
			(xy 382.684019 -287.066028) (xy 382.684528 -287.093914) (xy 382.684019 -287.1218) (xy 382.675899 -287.176976)
			(xy 382.659831 -287.230383) (xy 382.636159 -287.28088) (xy 382.605386 -287.327393) (xy 382.568169 -287.36893)
			(xy 382.525301 -287.404605) (xy 382.477695 -287.433659) (xy 382.426366 -287.455471) (xy 382.372409 -287.469577)
			(xy 382.316972 -287.475677) (xy 382.261238 -287.47364) (xy 382.206395 -287.46351) (xy 382.153611 -287.445503)
			(xy 382.104011 -287.420002) (xy 382.058653 -287.387551) (xy 382.018504 -287.348842) (xy 381.984418 -287.304699)
			(xy 381.957122 -287.256064) (xy 381.937199 -287.203973) (xy 381.925073 -287.149536) (xy 381.921002 -287.093914)
			(xy 381.798068 -287.093914) (xy 381.797559 -287.1218) (xy 381.789439 -287.176976) (xy 381.773371 -287.230383)
			(xy 381.749699 -287.28088) (xy 381.718926 -287.327393) (xy 381.681709 -287.36893) (xy 381.638841 -287.404605)
			(xy 381.591235 -287.433659) (xy 381.539906 -287.455471) (xy 381.485949 -287.469577) (xy 381.430512 -287.475677)
			(xy 381.374778 -287.47364) (xy 381.319935 -287.46351) (xy 381.267151 -287.445503) (xy 381.217551 -287.420002)
			(xy 381.172193 -287.387551) (xy 381.132044 -287.348842) (xy 381.097958 -287.304699) (xy 381.070662 -287.256064)
			(xy 381.050739 -287.203973) (xy 381.038613 -287.149536) (xy 381.034542 -287.093914) (xy 380.401068 -287.093914)
			(xy 380.400582 -287.121165) (xy 380.392826 -287.175113) (xy 380.377471 -287.227408) (xy 380.354829 -287.276985)
			(xy 380.325363 -287.322835) (xy 380.289672 -287.364026) (xy 380.248481 -287.399717) (xy 380.202631 -287.429183)
			(xy 380.153054 -287.451825) (xy 380.100759 -287.46718) (xy 380.046811 -287.474936) (xy 379.992309 -287.474936)
			(xy 379.938361 -287.46718) (xy 379.886066 -287.451825) (xy 379.836489 -287.429183) (xy 379.790639 -287.399717)
			(xy 379.749448 -287.364026) (xy 379.713757 -287.322835) (xy 379.684291 -287.276985) (xy 379.661649 -287.227408)
			(xy 379.646294 -287.175113) (xy 379.638538 -287.121165) (xy 379.638052 -287.093914) (xy 379.638591 -287.064543)
			(xy 379.647592 -287.006494) (xy 379.665384 -286.950511) (xy 379.691546 -286.897916) (xy 379.725459 -286.849952)
			(xy 379.766323 -286.807753) (xy 379.789436 -286.789622) (xy 379.794262 -286.786066) (xy 379.80112 -286.777684)
			(xy 379.803914 -286.77235) (xy 379.8065 -286.76705) (xy 379.809441 -286.755633) (xy 379.809756 -286.749744)
			(xy 379.811026 -286.657796) (xy 379.80112 -286.636714) (xy 379.791976 -286.629094) (xy 379.772097 -286.612543)
			(xy 379.736546 -286.574969) (xy 379.706393 -286.53294) (xy 379.682189 -286.487225) (xy 379.664378 -286.438661)
			(xy 379.653285 -286.388137) (xy 379.650752 -286.362394) (xy 379.64999 -286.352742) (xy 379.641608 -286.335724)
			(xy 379.58395 -286.282638) (xy 379.576688 -286.276462) (xy 379.558933 -286.26956) (xy 379.549406 -286.269176)
			(xy 377.339606 -286.269176) (xy 377.330095 -286.26963) (xy 377.312369 -286.276534) (xy 377.305062 -286.282638)
			(xy 377.247404 -286.335724) (xy 377.239022 -286.352742) (xy 377.23826 -286.362394) (xy 377.235462 -286.390711)
			(xy 377.222543 -286.446126) (xy 377.201538 -286.499008) (xy 377.172913 -286.548184) (xy 377.137303 -286.592564)
			(xy 377.095498 -286.631165) (xy 377.048424 -286.663129) (xy 376.997125 -286.687749) (xy 376.942739 -286.704478)
			(xy 376.886472 -286.712946) (xy 376.858022 -286.713422) (xy 376.830768 -286.712961) (xy 376.776814 -286.705206)
			(xy 376.724512 -286.689852) (xy 376.674928 -286.667211) (xy 376.629071 -286.637744) (xy 376.587875 -286.602051)
			(xy 376.552178 -286.560857) (xy 376.522706 -286.515003) (xy 376.50006 -286.465422) (xy 376.484701 -286.413122)
			(xy 376.476942 -286.359168) (xy 376.476514 -286.331914) (xy 376.476768 -286.3215) (xy 376.476768 -286.319976)
			(xy 376.476344 -286.30996) (xy 376.468668 -286.291457) (xy 376.454496 -286.2773) (xy 376.435984 -286.269645)
			(xy 376.425968 -286.269176) (xy 376.401076 -286.269176) (xy 376.39107 -286.269668) (xy 376.372582 -286.277331)
			(xy 376.358431 -286.291482) (xy 376.350768 -286.30997) (xy 376.350276 -286.319976) (xy 376.350276 -286.3215)
			(xy 376.35053 -286.331914) (xy 376.350043 -286.359165) (xy 376.342285 -286.413113) (xy 376.326929 -286.465407)
			(xy 376.304288 -286.514984) (xy 376.274821 -286.560834) (xy 376.23913 -286.602024) (xy 376.19794 -286.637716)
			(xy 376.152091 -286.667184) (xy 376.102514 -286.689826) (xy 376.05022 -286.705184) (xy 375.996273 -286.712943)
			(xy 375.969022 -286.713422) (xy 375.940572 -286.712898) (xy 375.884302 -286.704448) (xy 375.829913 -286.687733)
			(xy 375.77861 -286.663123) (xy 375.731532 -286.631165) (xy 375.689724 -286.592568) (xy 375.654113 -286.548189)
			(xy 375.625491 -286.499011) (xy 375.604492 -286.446128) (xy 375.591582 -286.390711) (xy 375.588784 -286.362394)
			(xy 375.588022 -286.352742) (xy 375.57964 -286.335724) (xy 375.521982 -286.282638) (xy 375.514722 -286.276457)
			(xy 375.496967 -286.269544) (xy 375.487438 -286.269176) (xy 374.97512 -286.269176) (xy 374.965597 -286.269571)
			(xy 374.947848 -286.276479) (xy 374.940576 -286.282638) (xy 374.882918 -286.335724) (xy 374.874536 -286.352742)
			(xy 374.873774 -286.362394) (xy 374.871136 -286.389361) (xy 374.859207 -286.442215) (xy 374.839919 -286.49285)
			(xy 374.813661 -286.540245) (xy 374.780959 -286.583448) (xy 374.742474 -286.621589) (xy 374.698978 -286.6539)
			(xy 374.651348 -286.679731) (xy 374.600543 -286.698563) (xy 374.547583 -286.710015) (xy 374.493536 -286.713859)
			(xy 374.439489 -286.710015) (xy 374.386529 -286.698563) (xy 374.335724 -286.679731) (xy 374.288094 -286.6539)
			(xy 374.244598 -286.621589) (xy 374.206113 -286.583448) (xy 374.173411 -286.540245) (xy 374.147153 -286.49285)
			(xy 374.127865 -286.442215) (xy 374.115936 -286.389361) (xy 374.113298 -286.362394) (xy 374.112536 -286.352742)
			(xy 374.104154 -286.335724) (xy 374.046496 -286.282638) (xy 374.039236 -286.276455) (xy 374.021481 -286.269537)
			(xy 374.011952 -286.269176) (xy 368.60099 -286.269176) (xy 368.590982 -286.269665) (xy 368.572489 -286.277326)
			(xy 368.558334 -286.291478) (xy 368.550668 -286.309968) (xy 368.55019 -286.319976) (xy 368.55019 -287.824926)
			(xy 384.369068 -287.824926) (xy 384.373028 -287.775872) (xy 384.384805 -287.728088) (xy 384.404096 -287.682812)
			(xy 384.430399 -287.641216) (xy 384.463034 -287.604379) (xy 384.501155 -287.573254) (xy 384.543776 -287.548647)
			(xy 384.589792 -287.531195) (xy 384.638011 -287.521351) (xy 384.687186 -287.51937) (xy 384.736041 -287.525302)
			(xy 384.783312 -287.538994) (xy 384.827774 -287.560092) (xy 384.868277 -287.588048) (xy 384.90377 -287.62214)
			(xy 384.933335 -287.661484) (xy 384.956206 -287.705061) (xy 384.97179 -287.751742) (xy 384.979685 -287.800319)
			(xy 384.98018 -287.824926) (xy 385.319028 -287.824926) (xy 385.322988 -287.775872) (xy 385.334765 -287.728088)
			(xy 385.354056 -287.682812) (xy 385.380359 -287.641216) (xy 385.412994 -287.604379) (xy 385.451115 -287.573254)
			(xy 385.493736 -287.548647) (xy 385.539752 -287.531195) (xy 385.587971 -287.521351) (xy 385.637146 -287.51937)
			(xy 385.686001 -287.525302) (xy 385.733272 -287.538994) (xy 385.777734 -287.560092) (xy 385.818237 -287.588048)
			(xy 385.85373 -287.62214) (xy 385.883295 -287.661484) (xy 385.906166 -287.705061) (xy 385.92175 -287.751742)
			(xy 385.929645 -287.800319) (xy 385.93014 -287.824926) (xy 386.269242 -287.824926) (xy 386.273202 -287.775872)
			(xy 386.284979 -287.728088) (xy 386.30427 -287.682812) (xy 386.330573 -287.641216) (xy 386.363208 -287.604379)
			(xy 386.401329 -287.573254) (xy 386.44395 -287.548647) (xy 386.489966 -287.531195) (xy 386.538185 -287.521351)
			(xy 386.58736 -287.51937) (xy 386.636215 -287.525302) (xy 386.683486 -287.538994) (xy 386.727948 -287.560092)
			(xy 386.768451 -287.588048) (xy 386.803944 -287.62214) (xy 386.833509 -287.661484) (xy 386.85638 -287.705061)
			(xy 386.871964 -287.751742) (xy 386.879859 -287.800319) (xy 386.880354 -287.824926) (xy 389.119122 -287.824926)
			(xy 389.123082 -287.775872) (xy 389.134859 -287.728088) (xy 389.15415 -287.682812) (xy 389.180453 -287.641216)
			(xy 389.213088 -287.604379) (xy 389.251209 -287.573254) (xy 389.29383 -287.548647) (xy 389.339846 -287.531195)
			(xy 389.388065 -287.521351) (xy 389.43724 -287.51937) (xy 389.486095 -287.525302) (xy 389.533366 -287.538994)
			(xy 389.577828 -287.560092) (xy 389.618331 -287.588048) (xy 389.653824 -287.62214) (xy 389.683389 -287.661484)
			(xy 389.70626 -287.705061) (xy 389.721844 -287.751742) (xy 389.729739 -287.800319) (xy 389.730234 -287.824926)
			(xy 392.919216 -287.824926) (xy 392.923176 -287.775872) (xy 392.934953 -287.728088) (xy 392.954244 -287.682812)
			(xy 392.980547 -287.641216) (xy 393.013182 -287.604379) (xy 393.051303 -287.573254) (xy 393.093924 -287.548647)
			(xy 393.13994 -287.531195) (xy 393.188159 -287.521351) (xy 393.237334 -287.51937) (xy 393.286189 -287.525302)
			(xy 393.33346 -287.538994) (xy 393.377922 -287.560092) (xy 393.418425 -287.588048) (xy 393.453918 -287.62214)
			(xy 393.483483 -287.661484) (xy 393.506354 -287.705061) (xy 393.521938 -287.751742) (xy 393.529833 -287.800319)
			(xy 393.530328 -287.824926) (xy 393.869176 -287.824926) (xy 393.873136 -287.775872) (xy 393.884913 -287.728088)
			(xy 393.904204 -287.682812) (xy 393.930507 -287.641216) (xy 393.963142 -287.604379) (xy 394.001263 -287.573254)
			(xy 394.043884 -287.548647) (xy 394.0899 -287.531195) (xy 394.138119 -287.521351) (xy 394.187294 -287.51937)
			(xy 394.236149 -287.525302) (xy 394.28342 -287.538994) (xy 394.327882 -287.560092) (xy 394.368385 -287.588048)
			(xy 394.403878 -287.62214) (xy 394.433443 -287.661484) (xy 394.456314 -287.705061) (xy 394.471898 -287.751742)
			(xy 394.479793 -287.800319) (xy 394.480288 -287.824926) (xy 394.819136 -287.824926) (xy 394.823096 -287.775872)
			(xy 394.834873 -287.728088) (xy 394.854164 -287.682812) (xy 394.880467 -287.641216) (xy 394.913102 -287.604379)
			(xy 394.951223 -287.573254) (xy 394.993844 -287.548647) (xy 395.03986 -287.531195) (xy 395.088079 -287.521351)
			(xy 395.137254 -287.51937) (xy 395.186109 -287.525302) (xy 395.23338 -287.538994) (xy 395.277842 -287.560092)
			(xy 395.318345 -287.588048) (xy 395.353838 -287.62214) (xy 395.383403 -287.661484) (xy 395.406274 -287.705061)
			(xy 395.421858 -287.751742) (xy 395.429753 -287.800319) (xy 395.430248 -287.824926) (xy 395.769096 -287.824926)
			(xy 395.773056 -287.775872) (xy 395.784833 -287.728088) (xy 395.804124 -287.682812) (xy 395.830427 -287.641216)
			(xy 395.863062 -287.604379) (xy 395.901183 -287.573254) (xy 395.943804 -287.548647) (xy 395.98982 -287.531195)
			(xy 396.038039 -287.521351) (xy 396.087214 -287.51937) (xy 396.136069 -287.525302) (xy 396.18334 -287.538994)
			(xy 396.227802 -287.560092) (xy 396.268305 -287.588048) (xy 396.303798 -287.62214) (xy 396.333363 -287.661484)
			(xy 396.356234 -287.705061) (xy 396.371818 -287.751742) (xy 396.379713 -287.800319) (xy 396.380208 -287.824926)
			(xy 396.719056 -287.824926) (xy 396.723016 -287.775872) (xy 396.734793 -287.728088) (xy 396.754084 -287.682812)
			(xy 396.780387 -287.641216) (xy 396.813022 -287.604379) (xy 396.851143 -287.573254) (xy 396.893764 -287.548647)
			(xy 396.93978 -287.531195) (xy 396.987999 -287.521351) (xy 397.037174 -287.51937) (xy 397.086029 -287.525302)
			(xy 397.1333 -287.538994) (xy 397.177762 -287.560092) (xy 397.218265 -287.588048) (xy 397.253758 -287.62214)
			(xy 397.283323 -287.661484) (xy 397.306194 -287.705061) (xy 397.321778 -287.751742) (xy 397.329673 -287.800319)
			(xy 397.330168 -287.824926) (xy 397.669016 -287.824926) (xy 397.672976 -287.775872) (xy 397.684753 -287.728088)
			(xy 397.704044 -287.682812) (xy 397.730347 -287.641216) (xy 397.762982 -287.604379) (xy 397.801103 -287.573254)
			(xy 397.843724 -287.548647) (xy 397.88974 -287.531195) (xy 397.937959 -287.521351) (xy 397.987134 -287.51937)
			(xy 398.035989 -287.525302) (xy 398.08326 -287.538994) (xy 398.127722 -287.560092) (xy 398.168225 -287.588048)
			(xy 398.203718 -287.62214) (xy 398.233283 -287.661484) (xy 398.256154 -287.705061) (xy 398.271738 -287.751742)
			(xy 398.279633 -287.800319) (xy 398.280128 -287.824926) (xy 398.61923 -287.824926) (xy 398.62319 -287.775872)
			(xy 398.634967 -287.728088) (xy 398.654258 -287.682812) (xy 398.680561 -287.641216) (xy 398.713196 -287.604379)
			(xy 398.751317 -287.573254) (xy 398.793938 -287.548647) (xy 398.839954 -287.531195) (xy 398.888173 -287.521351)
			(xy 398.937348 -287.51937) (xy 398.986203 -287.525302) (xy 399.033474 -287.538994) (xy 399.077936 -287.560092)
			(xy 399.118439 -287.588048) (xy 399.153932 -287.62214) (xy 399.183497 -287.661484) (xy 399.206368 -287.705061)
			(xy 399.221952 -287.751742) (xy 399.229847 -287.800319) (xy 399.230342 -287.824926) (xy 399.56919 -287.824926)
			(xy 399.57315 -287.775872) (xy 399.584927 -287.728088) (xy 399.604218 -287.682812) (xy 399.630521 -287.641216)
			(xy 399.663156 -287.604379) (xy 399.701277 -287.573254) (xy 399.743898 -287.548647) (xy 399.789914 -287.531195)
			(xy 399.838133 -287.521351) (xy 399.887308 -287.51937) (xy 399.936163 -287.525302) (xy 399.983434 -287.538994)
			(xy 400.027896 -287.560092) (xy 400.068399 -287.588048) (xy 400.103892 -287.62214) (xy 400.133457 -287.661484)
			(xy 400.156328 -287.705061) (xy 400.171912 -287.751742) (xy 400.179807 -287.800319) (xy 400.180302 -287.824926)
			(xy 400.51915 -287.824926) (xy 400.52311 -287.775872) (xy 400.534887 -287.728088) (xy 400.554178 -287.682812)
			(xy 400.580481 -287.641216) (xy 400.613116 -287.604379) (xy 400.651237 -287.573254) (xy 400.693858 -287.548647)
			(xy 400.739874 -287.531195) (xy 400.788093 -287.521351) (xy 400.837268 -287.51937) (xy 400.886123 -287.525302)
			(xy 400.933394 -287.538994) (xy 400.977856 -287.560092) (xy 401.018359 -287.588048) (xy 401.053852 -287.62214)
			(xy 401.083417 -287.661484) (xy 401.106288 -287.705061) (xy 401.121872 -287.751742) (xy 401.129767 -287.800319)
			(xy 401.130262 -287.824926) (xy 401.46911 -287.824926) (xy 401.47307 -287.775872) (xy 401.484847 -287.728088)
			(xy 401.504138 -287.682812) (xy 401.530441 -287.641216) (xy 401.563076 -287.604379) (xy 401.601197 -287.573254)
			(xy 401.643818 -287.548647) (xy 401.689834 -287.531195) (xy 401.738053 -287.521351) (xy 401.787228 -287.51937)
			(xy 401.836083 -287.525302) (xy 401.883354 -287.538994) (xy 401.927816 -287.560092) (xy 401.968319 -287.588048)
			(xy 402.003812 -287.62214) (xy 402.033377 -287.661484) (xy 402.056248 -287.705061) (xy 402.071832 -287.751742)
			(xy 402.079727 -287.800319) (xy 402.080222 -287.824926) (xy 402.41907 -287.824926) (xy 402.42303 -287.775872)
			(xy 402.434807 -287.728088) (xy 402.454098 -287.682812) (xy 402.480401 -287.641216) (xy 402.513036 -287.604379)
			(xy 402.551157 -287.573254) (xy 402.593778 -287.548647) (xy 402.639794 -287.531195) (xy 402.688013 -287.521351)
			(xy 402.737188 -287.51937) (xy 402.786043 -287.525302) (xy 402.833314 -287.538994) (xy 402.877776 -287.560092)
			(xy 402.918279 -287.588048) (xy 402.953772 -287.62214) (xy 402.983337 -287.661484) (xy 403.006208 -287.705061)
			(xy 403.021792 -287.751742) (xy 403.029687 -287.800319) (xy 403.030182 -287.824926) (xy 403.36903 -287.824926)
			(xy 403.37299 -287.775872) (xy 403.384767 -287.728088) (xy 403.404058 -287.682812) (xy 403.430361 -287.641216)
			(xy 403.462996 -287.604379) (xy 403.501117 -287.573254) (xy 403.543738 -287.548647) (xy 403.589754 -287.531195)
			(xy 403.637973 -287.521351) (xy 403.687148 -287.51937) (xy 403.736003 -287.525302) (xy 403.783274 -287.538994)
			(xy 403.827736 -287.560092) (xy 403.868239 -287.588048) (xy 403.903732 -287.62214) (xy 403.933297 -287.661484)
			(xy 403.956168 -287.705061) (xy 403.971752 -287.751742) (xy 403.979647 -287.800319) (xy 403.980142 -287.824926)
			(xy 404.31899 -287.824926) (xy 404.32295 -287.775872) (xy 404.334727 -287.728088) (xy 404.354018 -287.682812)
			(xy 404.380321 -287.641216) (xy 404.412956 -287.604379) (xy 404.451077 -287.573254) (xy 404.493698 -287.548647)
			(xy 404.539714 -287.531195) (xy 404.587933 -287.521351) (xy 404.637108 -287.51937) (xy 404.685963 -287.525302)
			(xy 404.733234 -287.538994) (xy 404.777696 -287.560092) (xy 404.818199 -287.588048) (xy 404.853692 -287.62214)
			(xy 404.883257 -287.661484) (xy 404.906128 -287.705061) (xy 404.921712 -287.751742) (xy 404.929607 -287.800319)
			(xy 404.930102 -287.824926) (xy 405.269204 -287.824926) (xy 405.273164 -287.775872) (xy 405.284941 -287.728088)
			(xy 405.304232 -287.682812) (xy 405.330535 -287.641216) (xy 405.36317 -287.604379) (xy 405.401291 -287.573254)
			(xy 405.443912 -287.548647) (xy 405.489928 -287.531195) (xy 405.538147 -287.521351) (xy 405.587322 -287.51937)
			(xy 405.636177 -287.525302) (xy 405.683448 -287.538994) (xy 405.72791 -287.560092) (xy 405.768413 -287.588048)
			(xy 405.803906 -287.62214) (xy 405.833471 -287.661484) (xy 405.853664 -287.699958) (xy 406.244056 -287.699958)
			(xy 406.248016 -287.650904) (xy 406.259793 -287.60312) (xy 406.279084 -287.557844) (xy 406.305387 -287.516248)
			(xy 406.338022 -287.479411) (xy 406.376143 -287.448286) (xy 406.418764 -287.423679) (xy 406.46478 -287.406227)
			(xy 406.512999 -287.396383) (xy 406.562174 -287.394402) (xy 406.611029 -287.400334) (xy 406.6583 -287.414026)
			(xy 406.702762 -287.435124) (xy 406.743265 -287.46308) (xy 406.778758 -287.497172) (xy 406.808323 -287.536516)
			(xy 406.831194 -287.580093) (xy 406.846778 -287.626774) (xy 406.854673 -287.675351) (xy 406.855168 -287.699958)
			(xy 406.854673 -287.724565) (xy 406.846778 -287.773142) (xy 406.831194 -287.819823) (xy 406.808323 -287.8634)
			(xy 406.780928 -287.899856) (xy 408.119084 -287.899856) (xy 408.123044 -287.850802) (xy 408.134821 -287.803018)
			(xy 408.154112 -287.757742) (xy 408.180415 -287.716146) (xy 408.21305 -287.679309) (xy 408.251171 -287.648184)
			(xy 408.293792 -287.623577) (xy 408.339808 -287.606125) (xy 408.388027 -287.596281) (xy 408.437202 -287.5943)
			(xy 408.486057 -287.600232) (xy 408.533328 -287.613924) (xy 408.57779 -287.635022) (xy 408.618293 -287.662978)
			(xy 408.653786 -287.69707) (xy 408.683351 -287.736414) (xy 408.706222 -287.779991) (xy 408.721223 -287.824926)
			(xy 409.069044 -287.824926) (xy 409.073004 -287.775872) (xy 409.084781 -287.728088) (xy 409.104072 -287.682812)
			(xy 409.130375 -287.641216) (xy 409.16301 -287.604379) (xy 409.201131 -287.573254) (xy 409.243752 -287.548647)
			(xy 409.289768 -287.531195) (xy 409.337987 -287.521351) (xy 409.387162 -287.51937) (xy 409.436017 -287.525302)
			(xy 409.483288 -287.538994) (xy 409.52775 -287.560092) (xy 409.568253 -287.588048) (xy 409.603746 -287.62214)
			(xy 409.633311 -287.661484) (xy 409.656182 -287.705061) (xy 409.671766 -287.751742) (xy 409.679661 -287.800319)
			(xy 409.680156 -287.824926) (xy 410.019004 -287.824926) (xy 410.022964 -287.775872) (xy 410.034741 -287.728088)
			(xy 410.054032 -287.682812) (xy 410.080335 -287.641216) (xy 410.11297 -287.604379) (xy 410.151091 -287.573254)
			(xy 410.193712 -287.548647) (xy 410.239728 -287.531195) (xy 410.287947 -287.521351) (xy 410.337122 -287.51937)
			(xy 410.385977 -287.525302) (xy 410.433248 -287.538994) (xy 410.47771 -287.560092) (xy 410.518213 -287.588048)
			(xy 410.553706 -287.62214) (xy 410.583271 -287.661484) (xy 410.606142 -287.705061) (xy 410.621726 -287.751742)
			(xy 410.629621 -287.800319) (xy 410.630116 -287.824926) (xy 410.969218 -287.824926) (xy 410.973178 -287.775872)
			(xy 410.984955 -287.728088) (xy 411.004246 -287.682812) (xy 411.030549 -287.641216) (xy 411.063184 -287.604379)
			(xy 411.101305 -287.573254) (xy 411.143926 -287.548647) (xy 411.189942 -287.531195) (xy 411.238161 -287.521351)
			(xy 411.287336 -287.51937) (xy 411.336191 -287.525302) (xy 411.383462 -287.538994) (xy 411.427924 -287.560092)
			(xy 411.468427 -287.588048) (xy 411.50392 -287.62214) (xy 411.533485 -287.661484) (xy 411.556356 -287.705061)
			(xy 411.57194 -287.751742) (xy 411.579835 -287.800319) (xy 411.58033 -287.824926) (xy 411.919178 -287.824926)
			(xy 411.923138 -287.775872) (xy 411.934915 -287.728088) (xy 411.954206 -287.682812) (xy 411.980509 -287.641216)
			(xy 412.013144 -287.604379) (xy 412.051265 -287.573254) (xy 412.093886 -287.548647) (xy 412.139902 -287.531195)
			(xy 412.188121 -287.521351) (xy 412.237296 -287.51937) (xy 412.286151 -287.525302) (xy 412.333422 -287.538994)
			(xy 412.377884 -287.560092) (xy 412.418387 -287.588048) (xy 412.45388 -287.62214) (xy 412.483445 -287.661484)
			(xy 412.506316 -287.705061) (xy 412.5219 -287.751742) (xy 412.529795 -287.800319) (xy 412.53029 -287.824926)
			(xy 412.869138 -287.824926) (xy 412.873098 -287.775872) (xy 412.884875 -287.728088) (xy 412.904166 -287.682812)
			(xy 412.930469 -287.641216) (xy 412.963104 -287.604379) (xy 413.001225 -287.573254) (xy 413.043846 -287.548647)
			(xy 413.089862 -287.531195) (xy 413.138081 -287.521351) (xy 413.187256 -287.51937) (xy 413.236111 -287.525302)
			(xy 413.283382 -287.538994) (xy 413.327844 -287.560092) (xy 413.368347 -287.588048) (xy 413.40384 -287.62214)
			(xy 413.433405 -287.661484) (xy 413.456276 -287.705061) (xy 413.47186 -287.751742) (xy 413.479755 -287.800319)
			(xy 413.48025 -287.824926) (xy 413.819098 -287.824926) (xy 413.823058 -287.775872) (xy 413.834835 -287.728088)
			(xy 413.854126 -287.682812) (xy 413.880429 -287.641216) (xy 413.913064 -287.604379) (xy 413.951185 -287.573254)
			(xy 413.993806 -287.548647) (xy 414.039822 -287.531195) (xy 414.088041 -287.521351) (xy 414.137216 -287.51937)
			(xy 414.186071 -287.525302) (xy 414.233342 -287.538994) (xy 414.277804 -287.560092) (xy 414.318307 -287.588048)
			(xy 414.3538 -287.62214) (xy 414.383365 -287.661484) (xy 414.406236 -287.705061) (xy 414.42182 -287.751742)
			(xy 414.429715 -287.800319) (xy 414.43021 -287.824926) (xy 414.769058 -287.824926) (xy 414.773018 -287.775872)
			(xy 414.784795 -287.728088) (xy 414.804086 -287.682812) (xy 414.830389 -287.641216) (xy 414.863024 -287.604379)
			(xy 414.901145 -287.573254) (xy 414.943766 -287.548647) (xy 414.989782 -287.531195) (xy 415.038001 -287.521351)
			(xy 415.087176 -287.51937) (xy 415.136031 -287.525302) (xy 415.183302 -287.538994) (xy 415.227764 -287.560092)
			(xy 415.268267 -287.588048) (xy 415.30376 -287.62214) (xy 415.333325 -287.661484) (xy 415.356196 -287.705061)
			(xy 415.37178 -287.751742) (xy 415.379675 -287.800319) (xy 415.38017 -287.824926) (xy 415.719018 -287.824926)
			(xy 415.722978 -287.775872) (xy 415.734755 -287.728088) (xy 415.754046 -287.682812) (xy 415.780349 -287.641216)
			(xy 415.812984 -287.604379) (xy 415.851105 -287.573254) (xy 415.893726 -287.548647) (xy 415.939742 -287.531195)
			(xy 415.987961 -287.521351) (xy 416.037136 -287.51937) (xy 416.085991 -287.525302) (xy 416.133262 -287.538994)
			(xy 416.177724 -287.560092) (xy 416.218227 -287.588048) (xy 416.25372 -287.62214) (xy 416.283285 -287.661484)
			(xy 416.306156 -287.705061) (xy 416.32174 -287.751742) (xy 416.329635 -287.800319) (xy 416.33013 -287.824926)
			(xy 416.668978 -287.824926) (xy 416.672938 -287.775872) (xy 416.684715 -287.728088) (xy 416.704006 -287.682812)
			(xy 416.730309 -287.641216) (xy 416.762944 -287.604379) (xy 416.801065 -287.573254) (xy 416.843686 -287.548647)
			(xy 416.889702 -287.531195) (xy 416.937921 -287.521351) (xy 416.987096 -287.51937) (xy 417.035951 -287.525302)
			(xy 417.083222 -287.538994) (xy 417.127684 -287.560092) (xy 417.168187 -287.588048) (xy 417.20368 -287.62214)
			(xy 417.233245 -287.661484) (xy 417.256116 -287.705061) (xy 417.2717 -287.751742) (xy 417.279595 -287.800319)
			(xy 417.28009 -287.824926) (xy 417.279595 -287.849533) (xy 417.2717 -287.89811) (xy 417.256116 -287.944791)
			(xy 417.233245 -287.988368) (xy 417.20368 -288.027712) (xy 417.168187 -288.061804) (xy 417.127684 -288.08976)
			(xy 417.083222 -288.110858) (xy 417.035951 -288.12455) (xy 416.987096 -288.130482) (xy 416.937921 -288.128501)
			(xy 416.889702 -288.118657) (xy 416.843686 -288.101205) (xy 416.801065 -288.076598) (xy 416.762944 -288.045473)
			(xy 416.730309 -288.008636) (xy 416.704006 -287.96704) (xy 416.684715 -287.921764) (xy 416.672938 -287.87398)
			(xy 416.668978 -287.824926) (xy 416.33013 -287.824926) (xy 416.329635 -287.849533) (xy 416.32174 -287.89811)
			(xy 416.306156 -287.944791) (xy 416.283285 -287.988368) (xy 416.25372 -288.027712) (xy 416.218227 -288.061804)
			(xy 416.177724 -288.08976) (xy 416.133262 -288.110858) (xy 416.085991 -288.12455) (xy 416.037136 -288.130482)
			(xy 415.987961 -288.128501) (xy 415.939742 -288.118657) (xy 415.893726 -288.101205) (xy 415.851105 -288.076598)
			(xy 415.812984 -288.045473) (xy 415.780349 -288.008636) (xy 415.754046 -287.96704) (xy 415.734755 -287.921764)
			(xy 415.722978 -287.87398) (xy 415.719018 -287.824926) (xy 415.38017 -287.824926) (xy 415.379675 -287.849533)
			(xy 415.37178 -287.89811) (xy 415.356196 -287.944791) (xy 415.333325 -287.988368) (xy 415.30376 -288.027712)
			(xy 415.268267 -288.061804) (xy 415.227764 -288.08976) (xy 415.183302 -288.110858) (xy 415.136031 -288.12455)
			(xy 415.087176 -288.130482) (xy 415.038001 -288.128501) (xy 414.989782 -288.118657) (xy 414.943766 -288.101205)
			(xy 414.901145 -288.076598) (xy 414.863024 -288.045473) (xy 414.830389 -288.008636) (xy 414.804086 -287.96704)
			(xy 414.784795 -287.921764) (xy 414.773018 -287.87398) (xy 414.769058 -287.824926) (xy 414.43021 -287.824926)
			(xy 414.429715 -287.849533) (xy 414.42182 -287.89811) (xy 414.406236 -287.944791) (xy 414.383365 -287.988368)
			(xy 414.3538 -288.027712) (xy 414.318307 -288.061804) (xy 414.277804 -288.08976) (xy 414.233342 -288.110858)
			(xy 414.186071 -288.12455) (xy 414.137216 -288.130482) (xy 414.088041 -288.128501) (xy 414.039822 -288.118657)
			(xy 413.993806 -288.101205) (xy 413.951185 -288.076598) (xy 413.913064 -288.045473) (xy 413.880429 -288.008636)
			(xy 413.854126 -287.96704) (xy 413.834835 -287.921764) (xy 413.823058 -287.87398) (xy 413.819098 -287.824926)
			(xy 413.48025 -287.824926) (xy 413.479755 -287.849533) (xy 413.47186 -287.89811) (xy 413.456276 -287.944791)
			(xy 413.433405 -287.988368) (xy 413.40384 -288.027712) (xy 413.368347 -288.061804) (xy 413.327844 -288.08976)
			(xy 413.283382 -288.110858) (xy 413.236111 -288.12455) (xy 413.187256 -288.130482) (xy 413.138081 -288.128501)
			(xy 413.089862 -288.118657) (xy 413.043846 -288.101205) (xy 413.001225 -288.076598) (xy 412.963104 -288.045473)
			(xy 412.930469 -288.008636) (xy 412.904166 -287.96704) (xy 412.884875 -287.921764) (xy 412.873098 -287.87398)
			(xy 412.869138 -287.824926) (xy 412.53029 -287.824926) (xy 412.529795 -287.849533) (xy 412.5219 -287.89811)
			(xy 412.506316 -287.944791) (xy 412.483445 -287.988368) (xy 412.45388 -288.027712) (xy 412.418387 -288.061804)
			(xy 412.377884 -288.08976) (xy 412.333422 -288.110858) (xy 412.286151 -288.12455) (xy 412.237296 -288.130482)
			(xy 412.188121 -288.128501) (xy 412.139902 -288.118657) (xy 412.093886 -288.101205) (xy 412.051265 -288.076598)
			(xy 412.013144 -288.045473) (xy 411.980509 -288.008636) (xy 411.954206 -287.96704) (xy 411.934915 -287.921764)
			(xy 411.923138 -287.87398) (xy 411.919178 -287.824926) (xy 411.58033 -287.824926) (xy 411.579835 -287.849533)
			(xy 411.57194 -287.89811) (xy 411.556356 -287.944791) (xy 411.533485 -287.988368) (xy 411.50392 -288.027712)
			(xy 411.468427 -288.061804) (xy 411.427924 -288.08976) (xy 411.383462 -288.110858) (xy 411.336191 -288.12455)
			(xy 411.287336 -288.130482) (xy 411.238161 -288.128501) (xy 411.189942 -288.118657) (xy 411.143926 -288.101205)
			(xy 411.101305 -288.076598) (xy 411.063184 -288.045473) (xy 411.030549 -288.008636) (xy 411.004246 -287.96704)
			(xy 410.984955 -287.921764) (xy 410.973178 -287.87398) (xy 410.969218 -287.824926) (xy 410.630116 -287.824926)
			(xy 410.629621 -287.849533) (xy 410.621726 -287.89811) (xy 410.606142 -287.944791) (xy 410.583271 -287.988368)
			(xy 410.553706 -288.027712) (xy 410.518213 -288.061804) (xy 410.47771 -288.08976) (xy 410.433248 -288.110858)
			(xy 410.385977 -288.12455) (xy 410.337122 -288.130482) (xy 410.287947 -288.128501) (xy 410.239728 -288.118657)
			(xy 410.193712 -288.101205) (xy 410.151091 -288.076598) (xy 410.11297 -288.045473) (xy 410.080335 -288.008636)
			(xy 410.054032 -287.96704) (xy 410.034741 -287.921764) (xy 410.022964 -287.87398) (xy 410.019004 -287.824926)
			(xy 409.680156 -287.824926) (xy 409.679661 -287.849533) (xy 409.671766 -287.89811) (xy 409.656182 -287.944791)
			(xy 409.633311 -287.988368) (xy 409.603746 -288.027712) (xy 409.568253 -288.061804) (xy 409.52775 -288.08976)
			(xy 409.483288 -288.110858) (xy 409.436017 -288.12455) (xy 409.387162 -288.130482) (xy 409.337987 -288.128501)
			(xy 409.289768 -288.118657) (xy 409.243752 -288.101205) (xy 409.201131 -288.076598) (xy 409.16301 -288.045473)
			(xy 409.130375 -288.008636) (xy 409.104072 -287.96704) (xy 409.084781 -287.921764) (xy 409.073004 -287.87398)
			(xy 409.069044 -287.824926) (xy 408.721223 -287.824926) (xy 408.721806 -287.826672) (xy 408.729701 -287.875249)
			(xy 408.730196 -287.899856) (xy 408.729701 -287.924463) (xy 408.721806 -287.97304) (xy 408.706222 -288.019721)
			(xy 408.683351 -288.063298) (xy 408.653786 -288.102642) (xy 408.618293 -288.136734) (xy 408.57779 -288.16469)
			(xy 408.533328 -288.185788) (xy 408.486057 -288.19948) (xy 408.437202 -288.205412) (xy 408.388027 -288.203431)
			(xy 408.339808 -288.193587) (xy 408.293792 -288.176135) (xy 408.251171 -288.151528) (xy 408.21305 -288.120403)
			(xy 408.180415 -288.083566) (xy 408.154112 -288.04197) (xy 408.134821 -287.996694) (xy 408.123044 -287.94891)
			(xy 408.119084 -287.899856) (xy 406.780928 -287.899856) (xy 406.778758 -287.902744) (xy 406.743265 -287.936836)
			(xy 406.702762 -287.964792) (xy 406.6583 -287.98589) (xy 406.611029 -287.999582) (xy 406.562174 -288.005514)
			(xy 406.512999 -288.003533) (xy 406.46478 -287.993689) (xy 406.418764 -287.976237) (xy 406.376143 -287.95163)
			(xy 406.338022 -287.920505) (xy 406.305387 -287.883668) (xy 406.279084 -287.842072) (xy 406.259793 -287.796796)
			(xy 406.248016 -287.749012) (xy 406.244056 -287.699958) (xy 405.853664 -287.699958) (xy 405.856342 -287.705061)
			(xy 405.871926 -287.751742) (xy 405.879821 -287.800319) (xy 405.880316 -287.824926) (xy 405.879821 -287.849533)
			(xy 405.871926 -287.89811) (xy 405.856342 -287.944791) (xy 405.833471 -287.988368) (xy 405.803906 -288.027712)
			(xy 405.768413 -288.061804) (xy 405.72791 -288.08976) (xy 405.683448 -288.110858) (xy 405.636177 -288.12455)
			(xy 405.587322 -288.130482) (xy 405.538147 -288.128501) (xy 405.489928 -288.118657) (xy 405.443912 -288.101205)
			(xy 405.401291 -288.076598) (xy 405.36317 -288.045473) (xy 405.330535 -288.008636) (xy 405.304232 -287.96704)
			(xy 405.284941 -287.921764) (xy 405.273164 -287.87398) (xy 405.269204 -287.824926) (xy 404.930102 -287.824926)
			(xy 404.929607 -287.849533) (xy 404.921712 -287.89811) (xy 404.906128 -287.944791) (xy 404.883257 -287.988368)
			(xy 404.853692 -288.027712) (xy 404.818199 -288.061804) (xy 404.777696 -288.08976) (xy 404.733234 -288.110858)
			(xy 404.685963 -288.12455) (xy 404.637108 -288.130482) (xy 404.587933 -288.128501) (xy 404.539714 -288.118657)
			(xy 404.493698 -288.101205) (xy 404.451077 -288.076598) (xy 404.412956 -288.045473) (xy 404.380321 -288.008636)
			(xy 404.354018 -287.96704) (xy 404.334727 -287.921764) (xy 404.32295 -287.87398) (xy 404.31899 -287.824926)
			(xy 403.980142 -287.824926) (xy 403.979647 -287.849533) (xy 403.971752 -287.89811) (xy 403.956168 -287.944791)
			(xy 403.933297 -287.988368) (xy 403.903732 -288.027712) (xy 403.868239 -288.061804) (xy 403.827736 -288.08976)
			(xy 403.783274 -288.110858) (xy 403.736003 -288.12455) (xy 403.687148 -288.130482) (xy 403.637973 -288.128501)
			(xy 403.589754 -288.118657) (xy 403.543738 -288.101205) (xy 403.501117 -288.076598) (xy 403.462996 -288.045473)
			(xy 403.430361 -288.008636) (xy 403.404058 -287.96704) (xy 403.384767 -287.921764) (xy 403.37299 -287.87398)
			(xy 403.36903 -287.824926) (xy 403.030182 -287.824926) (xy 403.029687 -287.849533) (xy 403.021792 -287.89811)
			(xy 403.006208 -287.944791) (xy 402.983337 -287.988368) (xy 402.953772 -288.027712) (xy 402.918279 -288.061804)
			(xy 402.877776 -288.08976) (xy 402.833314 -288.110858) (xy 402.786043 -288.12455) (xy 402.737188 -288.130482)
			(xy 402.688013 -288.128501) (xy 402.639794 -288.118657) (xy 402.593778 -288.101205) (xy 402.551157 -288.076598)
			(xy 402.513036 -288.045473) (xy 402.480401 -288.008636) (xy 402.454098 -287.96704) (xy 402.434807 -287.921764)
			(xy 402.42303 -287.87398) (xy 402.41907 -287.824926) (xy 402.080222 -287.824926) (xy 402.079727 -287.849533)
			(xy 402.071832 -287.89811) (xy 402.056248 -287.944791) (xy 402.033377 -287.988368) (xy 402.003812 -288.027712)
			(xy 401.968319 -288.061804) (xy 401.927816 -288.08976) (xy 401.883354 -288.110858) (xy 401.836083 -288.12455)
			(xy 401.787228 -288.130482) (xy 401.738053 -288.128501) (xy 401.689834 -288.118657) (xy 401.643818 -288.101205)
			(xy 401.601197 -288.076598) (xy 401.563076 -288.045473) (xy 401.530441 -288.008636) (xy 401.504138 -287.96704)
			(xy 401.484847 -287.921764) (xy 401.47307 -287.87398) (xy 401.46911 -287.824926) (xy 401.130262 -287.824926)
			(xy 401.129767 -287.849533) (xy 401.121872 -287.89811) (xy 401.106288 -287.944791) (xy 401.083417 -287.988368)
			(xy 401.053852 -288.027712) (xy 401.018359 -288.061804) (xy 400.977856 -288.08976) (xy 400.933394 -288.110858)
			(xy 400.886123 -288.12455) (xy 400.837268 -288.130482) (xy 400.788093 -288.128501) (xy 400.739874 -288.118657)
			(xy 400.693858 -288.101205) (xy 400.651237 -288.076598) (xy 400.613116 -288.045473) (xy 400.580481 -288.008636)
			(xy 400.554178 -287.96704) (xy 400.534887 -287.921764) (xy 400.52311 -287.87398) (xy 400.51915 -287.824926)
			(xy 400.180302 -287.824926) (xy 400.179807 -287.849533) (xy 400.171912 -287.89811) (xy 400.156328 -287.944791)
			(xy 400.133457 -287.988368) (xy 400.103892 -288.027712) (xy 400.068399 -288.061804) (xy 400.027896 -288.08976)
			(xy 399.983434 -288.110858) (xy 399.936163 -288.12455) (xy 399.887308 -288.130482) (xy 399.838133 -288.128501)
			(xy 399.789914 -288.118657) (xy 399.743898 -288.101205) (xy 399.701277 -288.076598) (xy 399.663156 -288.045473)
			(xy 399.630521 -288.008636) (xy 399.604218 -287.96704) (xy 399.584927 -287.921764) (xy 399.57315 -287.87398)
			(xy 399.56919 -287.824926) (xy 399.230342 -287.824926) (xy 399.229847 -287.849533) (xy 399.221952 -287.89811)
			(xy 399.206368 -287.944791) (xy 399.183497 -287.988368) (xy 399.153932 -288.027712) (xy 399.118439 -288.061804)
			(xy 399.077936 -288.08976) (xy 399.033474 -288.110858) (xy 398.986203 -288.12455) (xy 398.937348 -288.130482)
			(xy 398.888173 -288.128501) (xy 398.839954 -288.118657) (xy 398.793938 -288.101205) (xy 398.751317 -288.076598)
			(xy 398.713196 -288.045473) (xy 398.680561 -288.008636) (xy 398.654258 -287.96704) (xy 398.634967 -287.921764)
			(xy 398.62319 -287.87398) (xy 398.61923 -287.824926) (xy 398.280128 -287.824926) (xy 398.279633 -287.849533)
			(xy 398.271738 -287.89811) (xy 398.256154 -287.944791) (xy 398.233283 -287.988368) (xy 398.203718 -288.027712)
			(xy 398.168225 -288.061804) (xy 398.127722 -288.08976) (xy 398.08326 -288.110858) (xy 398.035989 -288.12455)
			(xy 397.987134 -288.130482) (xy 397.937959 -288.128501) (xy 397.88974 -288.118657) (xy 397.843724 -288.101205)
			(xy 397.801103 -288.076598) (xy 397.762982 -288.045473) (xy 397.730347 -288.008636) (xy 397.704044 -287.96704)
			(xy 397.684753 -287.921764) (xy 397.672976 -287.87398) (xy 397.669016 -287.824926) (xy 397.330168 -287.824926)
			(xy 397.329673 -287.849533) (xy 397.321778 -287.89811) (xy 397.306194 -287.944791) (xy 397.283323 -287.988368)
			(xy 397.253758 -288.027712) (xy 397.218265 -288.061804) (xy 397.177762 -288.08976) (xy 397.1333 -288.110858)
			(xy 397.086029 -288.12455) (xy 397.037174 -288.130482) (xy 396.987999 -288.128501) (xy 396.93978 -288.118657)
			(xy 396.893764 -288.101205) (xy 396.851143 -288.076598) (xy 396.813022 -288.045473) (xy 396.780387 -288.008636)
			(xy 396.754084 -287.96704) (xy 396.734793 -287.921764) (xy 396.723016 -287.87398) (xy 396.719056 -287.824926)
			(xy 396.380208 -287.824926) (xy 396.379713 -287.849533) (xy 396.371818 -287.89811) (xy 396.356234 -287.944791)
			(xy 396.333363 -287.988368) (xy 396.303798 -288.027712) (xy 396.268305 -288.061804) (xy 396.227802 -288.08976)
			(xy 396.18334 -288.110858) (xy 396.136069 -288.12455) (xy 396.087214 -288.130482) (xy 396.038039 -288.128501)
			(xy 395.98982 -288.118657) (xy 395.943804 -288.101205) (xy 395.901183 -288.076598) (xy 395.863062 -288.045473)
			(xy 395.830427 -288.008636) (xy 395.804124 -287.96704) (xy 395.784833 -287.921764) (xy 395.773056 -287.87398)
			(xy 395.769096 -287.824926) (xy 395.430248 -287.824926) (xy 395.429753 -287.849533) (xy 395.421858 -287.89811)
			(xy 395.406274 -287.944791) (xy 395.383403 -287.988368) (xy 395.353838 -288.027712) (xy 395.318345 -288.061804)
			(xy 395.277842 -288.08976) (xy 395.23338 -288.110858) (xy 395.186109 -288.12455) (xy 395.137254 -288.130482)
			(xy 395.088079 -288.128501) (xy 395.03986 -288.118657) (xy 394.993844 -288.101205) (xy 394.951223 -288.076598)
			(xy 394.913102 -288.045473) (xy 394.880467 -288.008636) (xy 394.854164 -287.96704) (xy 394.834873 -287.921764)
			(xy 394.823096 -287.87398) (xy 394.819136 -287.824926) (xy 394.480288 -287.824926) (xy 394.479793 -287.849533)
			(xy 394.471898 -287.89811) (xy 394.456314 -287.944791) (xy 394.433443 -287.988368) (xy 394.403878 -288.027712)
			(xy 394.368385 -288.061804) (xy 394.327882 -288.08976) (xy 394.28342 -288.110858) (xy 394.236149 -288.12455)
			(xy 394.187294 -288.130482) (xy 394.138119 -288.128501) (xy 394.0899 -288.118657) (xy 394.043884 -288.101205)
			(xy 394.001263 -288.076598) (xy 393.963142 -288.045473) (xy 393.930507 -288.008636) (xy 393.904204 -287.96704)
			(xy 393.884913 -287.921764) (xy 393.873136 -287.87398) (xy 393.869176 -287.824926) (xy 393.530328 -287.824926)
			(xy 393.529833 -287.849533) (xy 393.521938 -287.89811) (xy 393.506354 -287.944791) (xy 393.483483 -287.988368)
			(xy 393.453918 -288.027712) (xy 393.418425 -288.061804) (xy 393.377922 -288.08976) (xy 393.33346 -288.110858)
			(xy 393.286189 -288.12455) (xy 393.237334 -288.130482) (xy 393.188159 -288.128501) (xy 393.13994 -288.118657)
			(xy 393.093924 -288.101205) (xy 393.051303 -288.076598) (xy 393.013182 -288.045473) (xy 392.980547 -288.008636)
			(xy 392.954244 -287.96704) (xy 392.934953 -287.921764) (xy 392.923176 -287.87398) (xy 392.919216 -287.824926)
			(xy 389.730234 -287.824926) (xy 389.729739 -287.849533) (xy 389.721844 -287.89811) (xy 389.70626 -287.944791)
			(xy 389.683389 -287.988368) (xy 389.653824 -288.027712) (xy 389.618331 -288.061804) (xy 389.577828 -288.08976)
			(xy 389.533366 -288.110858) (xy 389.486095 -288.12455) (xy 389.43724 -288.130482) (xy 389.388065 -288.128501)
			(xy 389.339846 -288.118657) (xy 389.29383 -288.101205) (xy 389.251209 -288.076598) (xy 389.213088 -288.045473)
			(xy 389.180453 -288.008636) (xy 389.15415 -287.96704) (xy 389.134859 -287.921764) (xy 389.123082 -287.87398)
			(xy 389.119122 -287.824926) (xy 386.880354 -287.824926) (xy 386.879859 -287.849533) (xy 386.871964 -287.89811)
			(xy 386.85638 -287.944791) (xy 386.833509 -287.988368) (xy 386.803944 -288.027712) (xy 386.768451 -288.061804)
			(xy 386.727948 -288.08976) (xy 386.683486 -288.110858) (xy 386.636215 -288.12455) (xy 386.58736 -288.130482)
			(xy 386.538185 -288.128501) (xy 386.489966 -288.118657) (xy 386.44395 -288.101205) (xy 386.401329 -288.076598)
			(xy 386.363208 -288.045473) (xy 386.330573 -288.008636) (xy 386.30427 -287.96704) (xy 386.284979 -287.921764)
			(xy 386.273202 -287.87398) (xy 386.269242 -287.824926) (xy 385.93014 -287.824926) (xy 385.929645 -287.849533)
			(xy 385.92175 -287.89811) (xy 385.906166 -287.944791) (xy 385.883295 -287.988368) (xy 385.85373 -288.027712)
			(xy 385.818237 -288.061804) (xy 385.777734 -288.08976) (xy 385.733272 -288.110858) (xy 385.686001 -288.12455)
			(xy 385.637146 -288.130482) (xy 385.587971 -288.128501) (xy 385.539752 -288.118657) (xy 385.493736 -288.101205)
			(xy 385.451115 -288.076598) (xy 385.412994 -288.045473) (xy 385.380359 -288.008636) (xy 385.354056 -287.96704)
			(xy 385.334765 -287.921764) (xy 385.322988 -287.87398) (xy 385.319028 -287.824926) (xy 384.98018 -287.824926)
			(xy 384.979685 -287.849533) (xy 384.97179 -287.89811) (xy 384.956206 -287.944791) (xy 384.933335 -287.988368)
			(xy 384.90377 -288.027712) (xy 384.868277 -288.061804) (xy 384.827774 -288.08976) (xy 384.783312 -288.110858)
			(xy 384.736041 -288.12455) (xy 384.687186 -288.130482) (xy 384.638011 -288.128501) (xy 384.589792 -288.118657)
			(xy 384.543776 -288.101205) (xy 384.501155 -288.076598) (xy 384.463034 -288.045473) (xy 384.430399 -288.008636)
			(xy 384.404096 -287.96704) (xy 384.384805 -287.921764) (xy 384.373028 -287.87398) (xy 384.369068 -287.824926)
			(xy 368.55019 -287.824926) (xy 368.55019 -288.230056) (xy 374.111518 -288.230056) (xy 374.115589 -288.174434)
			(xy 374.127715 -288.119997) (xy 374.147638 -288.067906) (xy 374.174934 -288.019271) (xy 374.20902 -287.975128)
			(xy 374.249169 -287.936419) (xy 374.294527 -287.903968) (xy 374.344127 -287.878467) (xy 374.396911 -287.86046)
			(xy 374.451754 -287.85033) (xy 374.507488 -287.848293) (xy 374.562925 -287.854393) (xy 374.616882 -287.868499)
			(xy 374.668211 -287.890311) (xy 374.715817 -287.919365) (xy 374.758685 -287.95504) (xy 374.795902 -287.996577)
			(xy 374.826675 -288.04309) (xy 374.850347 -288.093587) (xy 374.866415 -288.146994) (xy 374.874535 -288.20217)
			(xy 374.875044 -288.230056) (xy 375.596656 -288.230056) (xy 375.600727 -288.174434) (xy 375.612853 -288.119997)
			(xy 375.632776 -288.067906) (xy 375.660072 -288.019271) (xy 375.694158 -287.975128) (xy 375.734307 -287.936419)
			(xy 375.779665 -287.903968) (xy 375.829265 -287.878467) (xy 375.882049 -287.86046) (xy 375.936892 -287.85033)
			(xy 375.992626 -287.848293) (xy 376.048063 -287.854393) (xy 376.10202 -287.868499) (xy 376.153349 -287.890311)
			(xy 376.200955 -287.919365) (xy 376.243823 -287.95504) (xy 376.28104 -287.996577) (xy 376.311813 -288.04309)
			(xy 376.335485 -288.093587) (xy 376.351553 -288.146994) (xy 376.359673 -288.20217) (xy 376.360182 -288.230056)
			(xy 376.359673 -288.257942) (xy 376.351553 -288.313118) (xy 376.335485 -288.366525) (xy 376.311813 -288.417022)
			(xy 376.28104 -288.463535) (xy 376.243823 -288.505072) (xy 376.200955 -288.540747) (xy 376.153349 -288.569801)
			(xy 376.10202 -288.591613) (xy 376.048063 -288.605719) (xy 375.992626 -288.611819) (xy 375.936892 -288.609782)
			(xy 375.882049 -288.599652) (xy 375.829265 -288.581645) (xy 375.779665 -288.556144) (xy 375.734307 -288.523693)
			(xy 375.694158 -288.484984) (xy 375.660072 -288.440841) (xy 375.632776 -288.392206) (xy 375.612853 -288.340115)
			(xy 375.600727 -288.285678) (xy 375.596656 -288.230056) (xy 374.875044 -288.230056) (xy 374.874535 -288.257942)
			(xy 374.866415 -288.313118) (xy 374.850347 -288.366525) (xy 374.826675 -288.417022) (xy 374.795902 -288.463535)
			(xy 374.758685 -288.505072) (xy 374.715817 -288.540747) (xy 374.668211 -288.569801) (xy 374.616882 -288.591613)
			(xy 374.562925 -288.605719) (xy 374.507488 -288.611819) (xy 374.451754 -288.609782) (xy 374.396911 -288.599652)
			(xy 374.344127 -288.581645) (xy 374.294527 -288.556144) (xy 374.249169 -288.523693) (xy 374.20902 -288.484984)
			(xy 374.174934 -288.440841) (xy 374.147638 -288.392206) (xy 374.127715 -288.340115) (xy 374.115589 -288.285678)
			(xy 374.111518 -288.230056) (xy 368.55019 -288.230056) (xy 368.55019 -288.774886) (xy 384.369068 -288.774886)
			(xy 384.373028 -288.725832) (xy 384.384805 -288.678048) (xy 384.404096 -288.632772) (xy 384.430399 -288.591176)
			(xy 384.463034 -288.554339) (xy 384.501155 -288.523214) (xy 384.543776 -288.498607) (xy 384.589792 -288.481155)
			(xy 384.638011 -288.471311) (xy 384.687186 -288.46933) (xy 384.736041 -288.475262) (xy 384.783312 -288.488954)
			(xy 384.827774 -288.510052) (xy 384.868277 -288.538008) (xy 384.90377 -288.5721) (xy 384.933335 -288.611444)
			(xy 384.956206 -288.655021) (xy 384.97179 -288.701702) (xy 384.979685 -288.750279) (xy 384.98018 -288.774886)
			(xy 385.319028 -288.774886) (xy 385.322988 -288.725832) (xy 385.334765 -288.678048) (xy 385.354056 -288.632772)
			(xy 385.380359 -288.591176) (xy 385.412994 -288.554339) (xy 385.451115 -288.523214) (xy 385.493736 -288.498607)
			(xy 385.539752 -288.481155) (xy 385.587971 -288.471311) (xy 385.637146 -288.46933) (xy 385.686001 -288.475262)
			(xy 385.733272 -288.488954) (xy 385.777734 -288.510052) (xy 385.818237 -288.538008) (xy 385.85373 -288.5721)
			(xy 385.883295 -288.611444) (xy 385.906166 -288.655021) (xy 385.92175 -288.701702) (xy 385.929645 -288.750279)
			(xy 385.93014 -288.774886) (xy 386.269242 -288.774886) (xy 386.273202 -288.725832) (xy 386.284979 -288.678048)
			(xy 386.30427 -288.632772) (xy 386.330573 -288.591176) (xy 386.363208 -288.554339) (xy 386.401329 -288.523214)
			(xy 386.44395 -288.498607) (xy 386.489966 -288.481155) (xy 386.538185 -288.471311) (xy 386.58736 -288.46933)
			(xy 386.636215 -288.475262) (xy 386.683486 -288.488954) (xy 386.727948 -288.510052) (xy 386.768451 -288.538008)
			(xy 386.803944 -288.5721) (xy 386.833509 -288.611444) (xy 386.85638 -288.655021) (xy 386.871964 -288.701702)
			(xy 386.879859 -288.750279) (xy 386.880354 -288.774886) (xy 391.019042 -288.774886) (xy 391.023002 -288.725832)
			(xy 391.034779 -288.678048) (xy 391.05407 -288.632772) (xy 391.080373 -288.591176) (xy 391.113008 -288.554339)
			(xy 391.151129 -288.523214) (xy 391.19375 -288.498607) (xy 391.239766 -288.481155) (xy 391.287985 -288.471311)
			(xy 391.33716 -288.46933) (xy 391.386015 -288.475262) (xy 391.433286 -288.488954) (xy 391.477748 -288.510052)
			(xy 391.518251 -288.538008) (xy 391.553744 -288.5721) (xy 391.583309 -288.611444) (xy 391.60618 -288.655021)
			(xy 391.621764 -288.701702) (xy 391.629659 -288.750279) (xy 391.630154 -288.774886) (xy 391.969002 -288.774886)
			(xy 391.972962 -288.725832) (xy 391.984739 -288.678048) (xy 392.00403 -288.632772) (xy 392.030333 -288.591176)
			(xy 392.062968 -288.554339) (xy 392.101089 -288.523214) (xy 392.14371 -288.498607) (xy 392.189726 -288.481155)
			(xy 392.237945 -288.471311) (xy 392.28712 -288.46933) (xy 392.335975 -288.475262) (xy 392.383246 -288.488954)
			(xy 392.427708 -288.510052) (xy 392.468211 -288.538008) (xy 392.503704 -288.5721) (xy 392.533269 -288.611444)
			(xy 392.55614 -288.655021) (xy 392.571724 -288.701702) (xy 392.579619 -288.750279) (xy 392.580114 -288.774886)
			(xy 392.919216 -288.774886) (xy 392.923176 -288.725832) (xy 392.934953 -288.678048) (xy 392.954244 -288.632772)
			(xy 392.980547 -288.591176) (xy 393.013182 -288.554339) (xy 393.051303 -288.523214) (xy 393.093924 -288.498607)
			(xy 393.13994 -288.481155) (xy 393.188159 -288.471311) (xy 393.237334 -288.46933) (xy 393.286189 -288.475262)
			(xy 393.33346 -288.488954) (xy 393.377922 -288.510052) (xy 393.418425 -288.538008) (xy 393.453918 -288.5721)
			(xy 393.483483 -288.611444) (xy 393.506354 -288.655021) (xy 393.521938 -288.701702) (xy 393.529833 -288.750279)
			(xy 393.530328 -288.774886) (xy 393.869176 -288.774886) (xy 393.873136 -288.725832) (xy 393.884913 -288.678048)
			(xy 393.904204 -288.632772) (xy 393.930507 -288.591176) (xy 393.963142 -288.554339) (xy 394.001263 -288.523214)
			(xy 394.043884 -288.498607) (xy 394.0899 -288.481155) (xy 394.138119 -288.471311) (xy 394.187294 -288.46933)
			(xy 394.236149 -288.475262) (xy 394.28342 -288.488954) (xy 394.327882 -288.510052) (xy 394.368385 -288.538008)
			(xy 394.403878 -288.5721) (xy 394.433443 -288.611444) (xy 394.456314 -288.655021) (xy 394.471898 -288.701702)
			(xy 394.479793 -288.750279) (xy 394.480288 -288.774886) (xy 394.819136 -288.774886) (xy 394.823096 -288.725832)
			(xy 394.834873 -288.678048) (xy 394.854164 -288.632772) (xy 394.880467 -288.591176) (xy 394.913102 -288.554339)
			(xy 394.951223 -288.523214) (xy 394.993844 -288.498607) (xy 395.03986 -288.481155) (xy 395.088079 -288.471311)
			(xy 395.137254 -288.46933) (xy 395.186109 -288.475262) (xy 395.23338 -288.488954) (xy 395.277842 -288.510052)
			(xy 395.318345 -288.538008) (xy 395.353838 -288.5721) (xy 395.383403 -288.611444) (xy 395.406274 -288.655021)
			(xy 395.421858 -288.701702) (xy 395.429753 -288.750279) (xy 395.430248 -288.774886) (xy 395.769096 -288.774886)
			(xy 395.773056 -288.725832) (xy 395.784833 -288.678048) (xy 395.804124 -288.632772) (xy 395.830427 -288.591176)
			(xy 395.863062 -288.554339) (xy 395.901183 -288.523214) (xy 395.943804 -288.498607) (xy 395.98982 -288.481155)
			(xy 396.038039 -288.471311) (xy 396.087214 -288.46933) (xy 396.136069 -288.475262) (xy 396.18334 -288.488954)
			(xy 396.227802 -288.510052) (xy 396.268305 -288.538008) (xy 396.303798 -288.5721) (xy 396.333363 -288.611444)
			(xy 396.356234 -288.655021) (xy 396.371818 -288.701702) (xy 396.379713 -288.750279) (xy 396.380208 -288.774886)
			(xy 396.719056 -288.774886) (xy 396.723016 -288.725832) (xy 396.734793 -288.678048) (xy 396.754084 -288.632772)
			(xy 396.780387 -288.591176) (xy 396.813022 -288.554339) (xy 396.851143 -288.523214) (xy 396.893764 -288.498607)
			(xy 396.93978 -288.481155) (xy 396.987999 -288.471311) (xy 397.037174 -288.46933) (xy 397.086029 -288.475262)
			(xy 397.1333 -288.488954) (xy 397.177762 -288.510052) (xy 397.218265 -288.538008) (xy 397.253758 -288.5721)
			(xy 397.283323 -288.611444) (xy 397.306194 -288.655021) (xy 397.321778 -288.701702) (xy 397.329673 -288.750279)
			(xy 397.330168 -288.774886) (xy 397.669016 -288.774886) (xy 397.672976 -288.725832) (xy 397.684753 -288.678048)
			(xy 397.704044 -288.632772) (xy 397.730347 -288.591176) (xy 397.762982 -288.554339) (xy 397.801103 -288.523214)
			(xy 397.843724 -288.498607) (xy 397.88974 -288.481155) (xy 397.937959 -288.471311) (xy 397.987134 -288.46933)
			(xy 398.035989 -288.475262) (xy 398.08326 -288.488954) (xy 398.127722 -288.510052) (xy 398.168225 -288.538008)
			(xy 398.203718 -288.5721) (xy 398.233283 -288.611444) (xy 398.256154 -288.655021) (xy 398.271738 -288.701702)
			(xy 398.279633 -288.750279) (xy 398.280128 -288.774886) (xy 398.61923 -288.774886) (xy 398.62319 -288.725832)
			(xy 398.634967 -288.678048) (xy 398.654258 -288.632772) (xy 398.680561 -288.591176) (xy 398.713196 -288.554339)
			(xy 398.751317 -288.523214) (xy 398.793938 -288.498607) (xy 398.839954 -288.481155) (xy 398.888173 -288.471311)
			(xy 398.937348 -288.46933) (xy 398.986203 -288.475262) (xy 399.033474 -288.488954) (xy 399.077936 -288.510052)
			(xy 399.118439 -288.538008) (xy 399.153932 -288.5721) (xy 399.183497 -288.611444) (xy 399.206368 -288.655021)
			(xy 399.221952 -288.701702) (xy 399.229847 -288.750279) (xy 399.230342 -288.774886) (xy 399.56919 -288.774886)
			(xy 399.57315 -288.725832) (xy 399.584927 -288.678048) (xy 399.604218 -288.632772) (xy 399.630521 -288.591176)
			(xy 399.663156 -288.554339) (xy 399.701277 -288.523214) (xy 399.743898 -288.498607) (xy 399.789914 -288.481155)
			(xy 399.838133 -288.471311) (xy 399.887308 -288.46933) (xy 399.936163 -288.475262) (xy 399.983434 -288.488954)
			(xy 400.027896 -288.510052) (xy 400.068399 -288.538008) (xy 400.103892 -288.5721) (xy 400.133457 -288.611444)
			(xy 400.156328 -288.655021) (xy 400.171912 -288.701702) (xy 400.179807 -288.750279) (xy 400.180302 -288.774886)
			(xy 400.51915 -288.774886) (xy 400.52311 -288.725832) (xy 400.534887 -288.678048) (xy 400.554178 -288.632772)
			(xy 400.580481 -288.591176) (xy 400.613116 -288.554339) (xy 400.651237 -288.523214) (xy 400.693858 -288.498607)
			(xy 400.739874 -288.481155) (xy 400.788093 -288.471311) (xy 400.837268 -288.46933) (xy 400.886123 -288.475262)
			(xy 400.933394 -288.488954) (xy 400.977856 -288.510052) (xy 401.018359 -288.538008) (xy 401.053852 -288.5721)
			(xy 401.083417 -288.611444) (xy 401.106288 -288.655021) (xy 401.121872 -288.701702) (xy 401.129767 -288.750279)
			(xy 401.130262 -288.774886) (xy 401.46911 -288.774886) (xy 401.47307 -288.725832) (xy 401.484847 -288.678048)
			(xy 401.504138 -288.632772) (xy 401.530441 -288.591176) (xy 401.563076 -288.554339) (xy 401.601197 -288.523214)
			(xy 401.643818 -288.498607) (xy 401.689834 -288.481155) (xy 401.738053 -288.471311) (xy 401.787228 -288.46933)
			(xy 401.836083 -288.475262) (xy 401.883354 -288.488954) (xy 401.927816 -288.510052) (xy 401.968319 -288.538008)
			(xy 402.003812 -288.5721) (xy 402.033377 -288.611444) (xy 402.056248 -288.655021) (xy 402.071832 -288.701702)
			(xy 402.079727 -288.750279) (xy 402.080222 -288.774886) (xy 402.41907 -288.774886) (xy 402.42303 -288.725832)
			(xy 402.434807 -288.678048) (xy 402.454098 -288.632772) (xy 402.480401 -288.591176) (xy 402.513036 -288.554339)
			(xy 402.551157 -288.523214) (xy 402.593778 -288.498607) (xy 402.639794 -288.481155) (xy 402.688013 -288.471311)
			(xy 402.737188 -288.46933) (xy 402.786043 -288.475262) (xy 402.833314 -288.488954) (xy 402.877776 -288.510052)
			(xy 402.918279 -288.538008) (xy 402.953772 -288.5721) (xy 402.983337 -288.611444) (xy 403.006208 -288.655021)
			(xy 403.021792 -288.701702) (xy 403.029687 -288.750279) (xy 403.030182 -288.774886) (xy 403.36903 -288.774886)
			(xy 403.37299 -288.725832) (xy 403.384767 -288.678048) (xy 403.404058 -288.632772) (xy 403.430361 -288.591176)
			(xy 403.462996 -288.554339) (xy 403.501117 -288.523214) (xy 403.543738 -288.498607) (xy 403.589754 -288.481155)
			(xy 403.637973 -288.471311) (xy 403.687148 -288.46933) (xy 403.736003 -288.475262) (xy 403.783274 -288.488954)
			(xy 403.827736 -288.510052) (xy 403.868239 -288.538008) (xy 403.903732 -288.5721) (xy 403.933297 -288.611444)
			(xy 403.956168 -288.655021) (xy 403.971752 -288.701702) (xy 403.979647 -288.750279) (xy 403.980142 -288.774886)
			(xy 404.31899 -288.774886) (xy 404.32295 -288.725832) (xy 404.334727 -288.678048) (xy 404.354018 -288.632772)
			(xy 404.380321 -288.591176) (xy 404.412956 -288.554339) (xy 404.451077 -288.523214) (xy 404.493698 -288.498607)
			(xy 404.539714 -288.481155) (xy 404.587933 -288.471311) (xy 404.637108 -288.46933) (xy 404.685963 -288.475262)
			(xy 404.733234 -288.488954) (xy 404.777696 -288.510052) (xy 404.818199 -288.538008) (xy 404.853692 -288.5721)
			(xy 404.883257 -288.611444) (xy 404.906128 -288.655021) (xy 404.921712 -288.701702) (xy 404.929607 -288.750279)
			(xy 404.930102 -288.774886) (xy 405.269204 -288.774886) (xy 405.273164 -288.725832) (xy 405.284941 -288.678048)
			(xy 405.304232 -288.632772) (xy 405.330535 -288.591176) (xy 405.36317 -288.554339) (xy 405.401291 -288.523214)
			(xy 405.443912 -288.498607) (xy 405.489928 -288.481155) (xy 405.538147 -288.471311) (xy 405.587322 -288.46933)
			(xy 405.636177 -288.475262) (xy 405.683448 -288.488954) (xy 405.72791 -288.510052) (xy 405.768413 -288.538008)
			(xy 405.803906 -288.5721) (xy 405.833471 -288.611444) (xy 405.856342 -288.655021) (xy 405.871926 -288.701702)
			(xy 405.879821 -288.750279) (xy 405.880316 -288.774886) (xy 406.219164 -288.774886) (xy 406.223124 -288.725832)
			(xy 406.234901 -288.678048) (xy 406.254192 -288.632772) (xy 406.280495 -288.591176) (xy 406.31313 -288.554339)
			(xy 406.351251 -288.523214) (xy 406.393872 -288.498607) (xy 406.439888 -288.481155) (xy 406.488107 -288.471311)
			(xy 406.537282 -288.46933) (xy 406.586137 -288.475262) (xy 406.633408 -288.488954) (xy 406.67787 -288.510052)
			(xy 406.718373 -288.538008) (xy 406.753866 -288.5721) (xy 406.783431 -288.611444) (xy 406.806302 -288.655021)
			(xy 406.821886 -288.701702) (xy 406.829781 -288.750279) (xy 406.830276 -288.774886) (xy 408.119084 -288.774886)
			(xy 408.123044 -288.725832) (xy 408.134821 -288.678048) (xy 408.154112 -288.632772) (xy 408.180415 -288.591176)
			(xy 408.21305 -288.554339) (xy 408.251171 -288.523214) (xy 408.293792 -288.498607) (xy 408.339808 -288.481155)
			(xy 408.388027 -288.471311) (xy 408.437202 -288.46933) (xy 408.486057 -288.475262) (xy 408.533328 -288.488954)
			(xy 408.57779 -288.510052) (xy 408.618293 -288.538008) (xy 408.653786 -288.5721) (xy 408.683351 -288.611444)
			(xy 408.706222 -288.655021) (xy 408.721806 -288.701702) (xy 408.729701 -288.750279) (xy 408.730196 -288.774886)
			(xy 409.069044 -288.774886) (xy 409.073004 -288.725832) (xy 409.084781 -288.678048) (xy 409.104072 -288.632772)
			(xy 409.130375 -288.591176) (xy 409.16301 -288.554339) (xy 409.201131 -288.523214) (xy 409.243752 -288.498607)
			(xy 409.289768 -288.481155) (xy 409.337987 -288.471311) (xy 409.387162 -288.46933) (xy 409.436017 -288.475262)
			(xy 409.483288 -288.488954) (xy 409.52775 -288.510052) (xy 409.568253 -288.538008) (xy 409.603746 -288.5721)
			(xy 409.633311 -288.611444) (xy 409.656182 -288.655021) (xy 409.671766 -288.701702) (xy 409.679661 -288.750279)
			(xy 409.680156 -288.774886) (xy 410.019004 -288.774886) (xy 410.022964 -288.725832) (xy 410.034741 -288.678048)
			(xy 410.054032 -288.632772) (xy 410.080335 -288.591176) (xy 410.11297 -288.554339) (xy 410.151091 -288.523214)
			(xy 410.193712 -288.498607) (xy 410.239728 -288.481155) (xy 410.287947 -288.471311) (xy 410.337122 -288.46933)
			(xy 410.385977 -288.475262) (xy 410.433248 -288.488954) (xy 410.47771 -288.510052) (xy 410.518213 -288.538008)
			(xy 410.553706 -288.5721) (xy 410.583271 -288.611444) (xy 410.606142 -288.655021) (xy 410.621726 -288.701702)
			(xy 410.629621 -288.750279) (xy 410.630116 -288.774886) (xy 410.969218 -288.774886) (xy 410.973178 -288.725832)
			(xy 410.984955 -288.678048) (xy 411.004246 -288.632772) (xy 411.030549 -288.591176) (xy 411.063184 -288.554339)
			(xy 411.101305 -288.523214) (xy 411.143926 -288.498607) (xy 411.189942 -288.481155) (xy 411.238161 -288.471311)
			(xy 411.287336 -288.46933) (xy 411.336191 -288.475262) (xy 411.383462 -288.488954) (xy 411.427924 -288.510052)
			(xy 411.468427 -288.538008) (xy 411.50392 -288.5721) (xy 411.533485 -288.611444) (xy 411.556356 -288.655021)
			(xy 411.57194 -288.701702) (xy 411.579835 -288.750279) (xy 411.58033 -288.774886) (xy 411.919178 -288.774886)
			(xy 411.923138 -288.725832) (xy 411.934915 -288.678048) (xy 411.954206 -288.632772) (xy 411.980509 -288.591176)
			(xy 412.013144 -288.554339) (xy 412.051265 -288.523214) (xy 412.093886 -288.498607) (xy 412.139902 -288.481155)
			(xy 412.188121 -288.471311) (xy 412.237296 -288.46933) (xy 412.286151 -288.475262) (xy 412.333422 -288.488954)
			(xy 412.377884 -288.510052) (xy 412.418387 -288.538008) (xy 412.45388 -288.5721) (xy 412.483445 -288.611444)
			(xy 412.506316 -288.655021) (xy 412.5219 -288.701702) (xy 412.529795 -288.750279) (xy 412.53029 -288.774886)
			(xy 412.869138 -288.774886) (xy 412.873098 -288.725832) (xy 412.884875 -288.678048) (xy 412.904166 -288.632772)
			(xy 412.930469 -288.591176) (xy 412.963104 -288.554339) (xy 413.001225 -288.523214) (xy 413.043846 -288.498607)
			(xy 413.089862 -288.481155) (xy 413.138081 -288.471311) (xy 413.187256 -288.46933) (xy 413.236111 -288.475262)
			(xy 413.283382 -288.488954) (xy 413.327844 -288.510052) (xy 413.368347 -288.538008) (xy 413.40384 -288.5721)
			(xy 413.433405 -288.611444) (xy 413.456276 -288.655021) (xy 413.47186 -288.701702) (xy 413.479755 -288.750279)
			(xy 413.48025 -288.774886) (xy 413.819098 -288.774886) (xy 413.823058 -288.725832) (xy 413.834835 -288.678048)
			(xy 413.854126 -288.632772) (xy 413.880429 -288.591176) (xy 413.913064 -288.554339) (xy 413.951185 -288.523214)
			(xy 413.993806 -288.498607) (xy 414.039822 -288.481155) (xy 414.088041 -288.471311) (xy 414.137216 -288.46933)
			(xy 414.186071 -288.475262) (xy 414.233342 -288.488954) (xy 414.277804 -288.510052) (xy 414.318307 -288.538008)
			(xy 414.3538 -288.5721) (xy 414.383365 -288.611444) (xy 414.406236 -288.655021) (xy 414.42182 -288.701702)
			(xy 414.429715 -288.750279) (xy 414.43021 -288.774886) (xy 414.769058 -288.774886) (xy 414.773018 -288.725832)
			(xy 414.784795 -288.678048) (xy 414.804086 -288.632772) (xy 414.830389 -288.591176) (xy 414.863024 -288.554339)
			(xy 414.901145 -288.523214) (xy 414.943766 -288.498607) (xy 414.989782 -288.481155) (xy 415.038001 -288.471311)
			(xy 415.087176 -288.46933) (xy 415.136031 -288.475262) (xy 415.183302 -288.488954) (xy 415.227764 -288.510052)
			(xy 415.268267 -288.538008) (xy 415.30376 -288.5721) (xy 415.333325 -288.611444) (xy 415.356196 -288.655021)
			(xy 415.37178 -288.701702) (xy 415.379675 -288.750279) (xy 415.38017 -288.774886) (xy 415.719018 -288.774886)
			(xy 415.722978 -288.725832) (xy 415.734755 -288.678048) (xy 415.754046 -288.632772) (xy 415.780349 -288.591176)
			(xy 415.812984 -288.554339) (xy 415.851105 -288.523214) (xy 415.893726 -288.498607) (xy 415.939742 -288.481155)
			(xy 415.987961 -288.471311) (xy 416.037136 -288.46933) (xy 416.085991 -288.475262) (xy 416.133262 -288.488954)
			(xy 416.177724 -288.510052) (xy 416.218227 -288.538008) (xy 416.25372 -288.5721) (xy 416.283285 -288.611444)
			(xy 416.306156 -288.655021) (xy 416.32174 -288.701702) (xy 416.329635 -288.750279) (xy 416.33013 -288.774886)
			(xy 416.668978 -288.774886) (xy 416.672938 -288.725832) (xy 416.684715 -288.678048) (xy 416.704006 -288.632772)
			(xy 416.730309 -288.591176) (xy 416.762944 -288.554339) (xy 416.801065 -288.523214) (xy 416.843686 -288.498607)
			(xy 416.889702 -288.481155) (xy 416.937921 -288.471311) (xy 416.987096 -288.46933) (xy 417.035951 -288.475262)
			(xy 417.083222 -288.488954) (xy 417.127684 -288.510052) (xy 417.168187 -288.538008) (xy 417.20368 -288.5721)
			(xy 417.233245 -288.611444) (xy 417.256116 -288.655021) (xy 417.2717 -288.701702) (xy 417.279595 -288.750279)
			(xy 417.28009 -288.774886) (xy 417.279595 -288.799493) (xy 417.2717 -288.84807) (xy 417.256116 -288.894751)
			(xy 417.233245 -288.938328) (xy 417.20368 -288.977672) (xy 417.168187 -289.011764) (xy 417.127684 -289.03972)
			(xy 417.083222 -289.060818) (xy 417.035951 -289.07451) (xy 416.987096 -289.080442) (xy 416.937921 -289.078461)
			(xy 416.889702 -289.068617) (xy 416.843686 -289.051165) (xy 416.801065 -289.026558) (xy 416.762944 -288.995433)
			(xy 416.730309 -288.958596) (xy 416.704006 -288.917) (xy 416.684715 -288.871724) (xy 416.672938 -288.82394)
			(xy 416.668978 -288.774886) (xy 416.33013 -288.774886) (xy 416.329635 -288.799493) (xy 416.32174 -288.84807)
			(xy 416.306156 -288.894751) (xy 416.283285 -288.938328) (xy 416.25372 -288.977672) (xy 416.218227 -289.011764)
			(xy 416.177724 -289.03972) (xy 416.133262 -289.060818) (xy 416.085991 -289.07451) (xy 416.037136 -289.080442)
			(xy 415.987961 -289.078461) (xy 415.939742 -289.068617) (xy 415.893726 -289.051165) (xy 415.851105 -289.026558)
			(xy 415.812984 -288.995433) (xy 415.780349 -288.958596) (xy 415.754046 -288.917) (xy 415.734755 -288.871724)
			(xy 415.722978 -288.82394) (xy 415.719018 -288.774886) (xy 415.38017 -288.774886) (xy 415.379675 -288.799493)
			(xy 415.37178 -288.84807) (xy 415.356196 -288.894751) (xy 415.333325 -288.938328) (xy 415.30376 -288.977672)
			(xy 415.268267 -289.011764) (xy 415.227764 -289.03972) (xy 415.183302 -289.060818) (xy 415.136031 -289.07451)
			(xy 415.087176 -289.080442) (xy 415.038001 -289.078461) (xy 414.989782 -289.068617) (xy 414.943766 -289.051165)
			(xy 414.901145 -289.026558) (xy 414.863024 -288.995433) (xy 414.830389 -288.958596) (xy 414.804086 -288.917)
			(xy 414.784795 -288.871724) (xy 414.773018 -288.82394) (xy 414.769058 -288.774886) (xy 414.43021 -288.774886)
			(xy 414.429715 -288.799493) (xy 414.42182 -288.84807) (xy 414.406236 -288.894751) (xy 414.383365 -288.938328)
			(xy 414.3538 -288.977672) (xy 414.318307 -289.011764) (xy 414.277804 -289.03972) (xy 414.233342 -289.060818)
			(xy 414.186071 -289.07451) (xy 414.137216 -289.080442) (xy 414.088041 -289.078461) (xy 414.039822 -289.068617)
			(xy 413.993806 -289.051165) (xy 413.951185 -289.026558) (xy 413.913064 -288.995433) (xy 413.880429 -288.958596)
			(xy 413.854126 -288.917) (xy 413.834835 -288.871724) (xy 413.823058 -288.82394) (xy 413.819098 -288.774886)
			(xy 413.48025 -288.774886) (xy 413.479755 -288.799493) (xy 413.47186 -288.84807) (xy 413.456276 -288.894751)
			(xy 413.433405 -288.938328) (xy 413.40384 -288.977672) (xy 413.368347 -289.011764) (xy 413.327844 -289.03972)
			(xy 413.283382 -289.060818) (xy 413.236111 -289.07451) (xy 413.187256 -289.080442) (xy 413.138081 -289.078461)
			(xy 413.089862 -289.068617) (xy 413.043846 -289.051165) (xy 413.001225 -289.026558) (xy 412.963104 -288.995433)
			(xy 412.930469 -288.958596) (xy 412.904166 -288.917) (xy 412.884875 -288.871724) (xy 412.873098 -288.82394)
			(xy 412.869138 -288.774886) (xy 412.53029 -288.774886) (xy 412.529795 -288.799493) (xy 412.5219 -288.84807)
			(xy 412.506316 -288.894751) (xy 412.483445 -288.938328) (xy 412.45388 -288.977672) (xy 412.418387 -289.011764)
			(xy 412.377884 -289.03972) (xy 412.333422 -289.060818) (xy 412.286151 -289.07451) (xy 412.237296 -289.080442)
			(xy 412.188121 -289.078461) (xy 412.139902 -289.068617) (xy 412.093886 -289.051165) (xy 412.051265 -289.026558)
			(xy 412.013144 -288.995433) (xy 411.980509 -288.958596) (xy 411.954206 -288.917) (xy 411.934915 -288.871724)
			(xy 411.923138 -288.82394) (xy 411.919178 -288.774886) (xy 411.58033 -288.774886) (xy 411.579835 -288.799493)
			(xy 411.57194 -288.84807) (xy 411.556356 -288.894751) (xy 411.533485 -288.938328) (xy 411.50392 -288.977672)
			(xy 411.468427 -289.011764) (xy 411.427924 -289.03972) (xy 411.383462 -289.060818) (xy 411.336191 -289.07451)
			(xy 411.287336 -289.080442) (xy 411.238161 -289.078461) (xy 411.189942 -289.068617) (xy 411.143926 -289.051165)
			(xy 411.101305 -289.026558) (xy 411.063184 -288.995433) (xy 411.030549 -288.958596) (xy 411.004246 -288.917)
			(xy 410.984955 -288.871724) (xy 410.973178 -288.82394) (xy 410.969218 -288.774886) (xy 410.630116 -288.774886)
			(xy 410.629621 -288.799493) (xy 410.621726 -288.84807) (xy 410.606142 -288.894751) (xy 410.583271 -288.938328)
			(xy 410.553706 -288.977672) (xy 410.518213 -289.011764) (xy 410.47771 -289.03972) (xy 410.433248 -289.060818)
			(xy 410.385977 -289.07451) (xy 410.337122 -289.080442) (xy 410.287947 -289.078461) (xy 410.239728 -289.068617)
			(xy 410.193712 -289.051165) (xy 410.151091 -289.026558) (xy 410.11297 -288.995433) (xy 410.080335 -288.958596)
			(xy 410.054032 -288.917) (xy 410.034741 -288.871724) (xy 410.022964 -288.82394) (xy 410.019004 -288.774886)
			(xy 409.680156 -288.774886) (xy 409.679661 -288.799493) (xy 409.671766 -288.84807) (xy 409.656182 -288.894751)
			(xy 409.633311 -288.938328) (xy 409.603746 -288.977672) (xy 409.568253 -289.011764) (xy 409.52775 -289.03972)
			(xy 409.483288 -289.060818) (xy 409.436017 -289.07451) (xy 409.387162 -289.080442) (xy 409.337987 -289.078461)
			(xy 409.289768 -289.068617) (xy 409.243752 -289.051165) (xy 409.201131 -289.026558) (xy 409.16301 -288.995433)
			(xy 409.130375 -288.958596) (xy 409.104072 -288.917) (xy 409.084781 -288.871724) (xy 409.073004 -288.82394)
			(xy 409.069044 -288.774886) (xy 408.730196 -288.774886) (xy 408.729701 -288.799493) (xy 408.721806 -288.84807)
			(xy 408.706222 -288.894751) (xy 408.683351 -288.938328) (xy 408.653786 -288.977672) (xy 408.618293 -289.011764)
			(xy 408.57779 -289.03972) (xy 408.533328 -289.060818) (xy 408.486057 -289.07451) (xy 408.437202 -289.080442)
			(xy 408.388027 -289.078461) (xy 408.339808 -289.068617) (xy 408.293792 -289.051165) (xy 408.251171 -289.026558)
			(xy 408.21305 -288.995433) (xy 408.180415 -288.958596) (xy 408.154112 -288.917) (xy 408.134821 -288.871724)
			(xy 408.123044 -288.82394) (xy 408.119084 -288.774886) (xy 406.830276 -288.774886) (xy 406.829781 -288.799493)
			(xy 406.821886 -288.84807) (xy 406.806302 -288.894751) (xy 406.783431 -288.938328) (xy 406.753866 -288.977672)
			(xy 406.718373 -289.011764) (xy 406.67787 -289.03972) (xy 406.633408 -289.060818) (xy 406.586137 -289.07451)
			(xy 406.537282 -289.080442) (xy 406.488107 -289.078461) (xy 406.439888 -289.068617) (xy 406.393872 -289.051165)
			(xy 406.351251 -289.026558) (xy 406.31313 -288.995433) (xy 406.280495 -288.958596) (xy 406.254192 -288.917)
			(xy 406.234901 -288.871724) (xy 406.223124 -288.82394) (xy 406.219164 -288.774886) (xy 405.880316 -288.774886)
			(xy 405.879821 -288.799493) (xy 405.871926 -288.84807) (xy 405.856342 -288.894751) (xy 405.833471 -288.938328)
			(xy 405.803906 -288.977672) (xy 405.768413 -289.011764) (xy 405.72791 -289.03972) (xy 405.683448 -289.060818)
			(xy 405.636177 -289.07451) (xy 405.587322 -289.080442) (xy 405.538147 -289.078461) (xy 405.489928 -289.068617)
			(xy 405.443912 -289.051165) (xy 405.401291 -289.026558) (xy 405.36317 -288.995433) (xy 405.330535 -288.958596)
			(xy 405.304232 -288.917) (xy 405.284941 -288.871724) (xy 405.273164 -288.82394) (xy 405.269204 -288.774886)
			(xy 404.930102 -288.774886) (xy 404.929607 -288.799493) (xy 404.921712 -288.84807) (xy 404.906128 -288.894751)
			(xy 404.883257 -288.938328) (xy 404.853692 -288.977672) (xy 404.818199 -289.011764) (xy 404.777696 -289.03972)
			(xy 404.733234 -289.060818) (xy 404.685963 -289.07451) (xy 404.637108 -289.080442) (xy 404.587933 -289.078461)
			(xy 404.539714 -289.068617) (xy 404.493698 -289.051165) (xy 404.451077 -289.026558) (xy 404.412956 -288.995433)
			(xy 404.380321 -288.958596) (xy 404.354018 -288.917) (xy 404.334727 -288.871724) (xy 404.32295 -288.82394)
			(xy 404.31899 -288.774886) (xy 403.980142 -288.774886) (xy 403.979647 -288.799493) (xy 403.971752 -288.84807)
			(xy 403.956168 -288.894751) (xy 403.933297 -288.938328) (xy 403.903732 -288.977672) (xy 403.868239 -289.011764)
			(xy 403.827736 -289.03972) (xy 403.783274 -289.060818) (xy 403.736003 -289.07451) (xy 403.687148 -289.080442)
			(xy 403.637973 -289.078461) (xy 403.589754 -289.068617) (xy 403.543738 -289.051165) (xy 403.501117 -289.026558)
			(xy 403.462996 -288.995433) (xy 403.430361 -288.958596) (xy 403.404058 -288.917) (xy 403.384767 -288.871724)
			(xy 403.37299 -288.82394) (xy 403.36903 -288.774886) (xy 403.030182 -288.774886) (xy 403.029687 -288.799493)
			(xy 403.021792 -288.84807) (xy 403.006208 -288.894751) (xy 402.983337 -288.938328) (xy 402.953772 -288.977672)
			(xy 402.918279 -289.011764) (xy 402.877776 -289.03972) (xy 402.833314 -289.060818) (xy 402.786043 -289.07451)
			(xy 402.737188 -289.080442) (xy 402.688013 -289.078461) (xy 402.639794 -289.068617) (xy 402.593778 -289.051165)
			(xy 402.551157 -289.026558) (xy 402.513036 -288.995433) (xy 402.480401 -288.958596) (xy 402.454098 -288.917)
			(xy 402.434807 -288.871724) (xy 402.42303 -288.82394) (xy 402.41907 -288.774886) (xy 402.080222 -288.774886)
			(xy 402.079727 -288.799493) (xy 402.071832 -288.84807) (xy 402.056248 -288.894751) (xy 402.033377 -288.938328)
			(xy 402.003812 -288.977672) (xy 401.968319 -289.011764) (xy 401.927816 -289.03972) (xy 401.883354 -289.060818)
			(xy 401.836083 -289.07451) (xy 401.787228 -289.080442) (xy 401.738053 -289.078461) (xy 401.689834 -289.068617)
			(xy 401.643818 -289.051165) (xy 401.601197 -289.026558) (xy 401.563076 -288.995433) (xy 401.530441 -288.958596)
			(xy 401.504138 -288.917) (xy 401.484847 -288.871724) (xy 401.47307 -288.82394) (xy 401.46911 -288.774886)
			(xy 401.130262 -288.774886) (xy 401.129767 -288.799493) (xy 401.121872 -288.84807) (xy 401.106288 -288.894751)
			(xy 401.083417 -288.938328) (xy 401.053852 -288.977672) (xy 401.018359 -289.011764) (xy 400.977856 -289.03972)
			(xy 400.933394 -289.060818) (xy 400.886123 -289.07451) (xy 400.837268 -289.080442) (xy 400.788093 -289.078461)
			(xy 400.739874 -289.068617) (xy 400.693858 -289.051165) (xy 400.651237 -289.026558) (xy 400.613116 -288.995433)
			(xy 400.580481 -288.958596) (xy 400.554178 -288.917) (xy 400.534887 -288.871724) (xy 400.52311 -288.82394)
			(xy 400.51915 -288.774886) (xy 400.180302 -288.774886) (xy 400.179807 -288.799493) (xy 400.171912 -288.84807)
			(xy 400.156328 -288.894751) (xy 400.133457 -288.938328) (xy 400.103892 -288.977672) (xy 400.068399 -289.011764)
			(xy 400.027896 -289.03972) (xy 399.983434 -289.060818) (xy 399.936163 -289.07451) (xy 399.887308 -289.080442)
			(xy 399.838133 -289.078461) (xy 399.789914 -289.068617) (xy 399.743898 -289.051165) (xy 399.701277 -289.026558)
			(xy 399.663156 -288.995433) (xy 399.630521 -288.958596) (xy 399.604218 -288.917) (xy 399.584927 -288.871724)
			(xy 399.57315 -288.82394) (xy 399.56919 -288.774886) (xy 399.230342 -288.774886) (xy 399.229847 -288.799493)
			(xy 399.221952 -288.84807) (xy 399.206368 -288.894751) (xy 399.183497 -288.938328) (xy 399.153932 -288.977672)
			(xy 399.118439 -289.011764) (xy 399.077936 -289.03972) (xy 399.033474 -289.060818) (xy 398.986203 -289.07451)
			(xy 398.937348 -289.080442) (xy 398.888173 -289.078461) (xy 398.839954 -289.068617) (xy 398.793938 -289.051165)
			(xy 398.751317 -289.026558) (xy 398.713196 -288.995433) (xy 398.680561 -288.958596) (xy 398.654258 -288.917)
			(xy 398.634967 -288.871724) (xy 398.62319 -288.82394) (xy 398.61923 -288.774886) (xy 398.280128 -288.774886)
			(xy 398.279633 -288.799493) (xy 398.271738 -288.84807) (xy 398.256154 -288.894751) (xy 398.233283 -288.938328)
			(xy 398.203718 -288.977672) (xy 398.168225 -289.011764) (xy 398.127722 -289.03972) (xy 398.08326 -289.060818)
			(xy 398.035989 -289.07451) (xy 397.987134 -289.080442) (xy 397.937959 -289.078461) (xy 397.88974 -289.068617)
			(xy 397.843724 -289.051165) (xy 397.801103 -289.026558) (xy 397.762982 -288.995433) (xy 397.730347 -288.958596)
			(xy 397.704044 -288.917) (xy 397.684753 -288.871724) (xy 397.672976 -288.82394) (xy 397.669016 -288.774886)
			(xy 397.330168 -288.774886) (xy 397.329673 -288.799493) (xy 397.321778 -288.84807) (xy 397.306194 -288.894751)
			(xy 397.283323 -288.938328) (xy 397.253758 -288.977672) (xy 397.218265 -289.011764) (xy 397.177762 -289.03972)
			(xy 397.1333 -289.060818) (xy 397.086029 -289.07451) (xy 397.037174 -289.080442) (xy 396.987999 -289.078461)
			(xy 396.93978 -289.068617) (xy 396.893764 -289.051165) (xy 396.851143 -289.026558) (xy 396.813022 -288.995433)
			(xy 396.780387 -288.958596) (xy 396.754084 -288.917) (xy 396.734793 -288.871724) (xy 396.723016 -288.82394)
			(xy 396.719056 -288.774886) (xy 396.380208 -288.774886) (xy 396.379713 -288.799493) (xy 396.371818 -288.84807)
			(xy 396.356234 -288.894751) (xy 396.333363 -288.938328) (xy 396.303798 -288.977672) (xy 396.268305 -289.011764)
			(xy 396.227802 -289.03972) (xy 396.18334 -289.060818) (xy 396.136069 -289.07451) (xy 396.087214 -289.080442)
			(xy 396.038039 -289.078461) (xy 395.98982 -289.068617) (xy 395.943804 -289.051165) (xy 395.901183 -289.026558)
			(xy 395.863062 -288.995433) (xy 395.830427 -288.958596) (xy 395.804124 -288.917) (xy 395.784833 -288.871724)
			(xy 395.773056 -288.82394) (xy 395.769096 -288.774886) (xy 395.430248 -288.774886) (xy 395.429753 -288.799493)
			(xy 395.421858 -288.84807) (xy 395.406274 -288.894751) (xy 395.383403 -288.938328) (xy 395.353838 -288.977672)
			(xy 395.318345 -289.011764) (xy 395.277842 -289.03972) (xy 395.23338 -289.060818) (xy 395.186109 -289.07451)
			(xy 395.137254 -289.080442) (xy 395.088079 -289.078461) (xy 395.03986 -289.068617) (xy 394.993844 -289.051165)
			(xy 394.951223 -289.026558) (xy 394.913102 -288.995433) (xy 394.880467 -288.958596) (xy 394.854164 -288.917)
			(xy 394.834873 -288.871724) (xy 394.823096 -288.82394) (xy 394.819136 -288.774886) (xy 394.480288 -288.774886)
			(xy 394.479793 -288.799493) (xy 394.471898 -288.84807) (xy 394.456314 -288.894751) (xy 394.433443 -288.938328)
			(xy 394.403878 -288.977672) (xy 394.368385 -289.011764) (xy 394.327882 -289.03972) (xy 394.28342 -289.060818)
			(xy 394.236149 -289.07451) (xy 394.187294 -289.080442) (xy 394.138119 -289.078461) (xy 394.0899 -289.068617)
			(xy 394.043884 -289.051165) (xy 394.001263 -289.026558) (xy 393.963142 -288.995433) (xy 393.930507 -288.958596)
			(xy 393.904204 -288.917) (xy 393.884913 -288.871724) (xy 393.873136 -288.82394) (xy 393.869176 -288.774886)
			(xy 393.530328 -288.774886) (xy 393.529833 -288.799493) (xy 393.521938 -288.84807) (xy 393.506354 -288.894751)
			(xy 393.483483 -288.938328) (xy 393.453918 -288.977672) (xy 393.418425 -289.011764) (xy 393.377922 -289.03972)
			(xy 393.33346 -289.060818) (xy 393.286189 -289.07451) (xy 393.237334 -289.080442) (xy 393.188159 -289.078461)
			(xy 393.13994 -289.068617) (xy 393.093924 -289.051165) (xy 393.051303 -289.026558) (xy 393.013182 -288.995433)
			(xy 392.980547 -288.958596) (xy 392.954244 -288.917) (xy 392.934953 -288.871724) (xy 392.923176 -288.82394)
			(xy 392.919216 -288.774886) (xy 392.580114 -288.774886) (xy 392.579619 -288.799493) (xy 392.571724 -288.84807)
			(xy 392.55614 -288.894751) (xy 392.533269 -288.938328) (xy 392.503704 -288.977672) (xy 392.468211 -289.011764)
			(xy 392.427708 -289.03972) (xy 392.383246 -289.060818) (xy 392.335975 -289.07451) (xy 392.28712 -289.080442)
			(xy 392.237945 -289.078461) (xy 392.189726 -289.068617) (xy 392.14371 -289.051165) (xy 392.101089 -289.026558)
			(xy 392.062968 -288.995433) (xy 392.030333 -288.958596) (xy 392.00403 -288.917) (xy 391.984739 -288.871724)
			(xy 391.972962 -288.82394) (xy 391.969002 -288.774886) (xy 391.630154 -288.774886) (xy 391.629659 -288.799493)
			(xy 391.621764 -288.84807) (xy 391.60618 -288.894751) (xy 391.583309 -288.938328) (xy 391.553744 -288.977672)
			(xy 391.518251 -289.011764) (xy 391.477748 -289.03972) (xy 391.433286 -289.060818) (xy 391.386015 -289.07451)
			(xy 391.33716 -289.080442) (xy 391.287985 -289.078461) (xy 391.239766 -289.068617) (xy 391.19375 -289.051165)
			(xy 391.151129 -289.026558) (xy 391.113008 -288.995433) (xy 391.080373 -288.958596) (xy 391.05407 -288.917)
			(xy 391.034779 -288.871724) (xy 391.023002 -288.82394) (xy 391.019042 -288.774886) (xy 386.880354 -288.774886)
			(xy 386.879859 -288.799493) (xy 386.871964 -288.84807) (xy 386.85638 -288.894751) (xy 386.833509 -288.938328)
			(xy 386.803944 -288.977672) (xy 386.768451 -289.011764) (xy 386.727948 -289.03972) (xy 386.683486 -289.060818)
			(xy 386.636215 -289.07451) (xy 386.58736 -289.080442) (xy 386.538185 -289.078461) (xy 386.489966 -289.068617)
			(xy 386.44395 -289.051165) (xy 386.401329 -289.026558) (xy 386.363208 -288.995433) (xy 386.330573 -288.958596)
			(xy 386.30427 -288.917) (xy 386.284979 -288.871724) (xy 386.273202 -288.82394) (xy 386.269242 -288.774886)
			(xy 385.93014 -288.774886) (xy 385.929645 -288.799493) (xy 385.92175 -288.84807) (xy 385.906166 -288.894751)
			(xy 385.883295 -288.938328) (xy 385.85373 -288.977672) (xy 385.818237 -289.011764) (xy 385.777734 -289.03972)
			(xy 385.733272 -289.060818) (xy 385.686001 -289.07451) (xy 385.637146 -289.080442) (xy 385.587971 -289.078461)
			(xy 385.539752 -289.068617) (xy 385.493736 -289.051165) (xy 385.451115 -289.026558) (xy 385.412994 -288.995433)
			(xy 385.380359 -288.958596) (xy 385.354056 -288.917) (xy 385.334765 -288.871724) (xy 385.322988 -288.82394)
			(xy 385.319028 -288.774886) (xy 384.98018 -288.774886) (xy 384.979685 -288.799493) (xy 384.97179 -288.84807)
			(xy 384.956206 -288.894751) (xy 384.933335 -288.938328) (xy 384.90377 -288.977672) (xy 384.868277 -289.011764)
			(xy 384.827774 -289.03972) (xy 384.783312 -289.060818) (xy 384.736041 -289.07451) (xy 384.687186 -289.080442)
			(xy 384.638011 -289.078461) (xy 384.589792 -289.068617) (xy 384.543776 -289.051165) (xy 384.501155 -289.026558)
			(xy 384.463034 -288.995433) (xy 384.430399 -288.958596) (xy 384.404096 -288.917) (xy 384.384805 -288.871724)
			(xy 384.373028 -288.82394) (xy 384.369068 -288.774886) (xy 368.55019 -288.774886) (xy 368.55019 -289.532314)
			(xy 374.111518 -289.532314) (xy 374.115589 -289.476692) (xy 374.127715 -289.422255) (xy 374.147638 -289.370164)
			(xy 374.174934 -289.321529) (xy 374.20902 -289.277386) (xy 374.249169 -289.238677) (xy 374.294527 -289.206226)
			(xy 374.344127 -289.180725) (xy 374.396911 -289.162718) (xy 374.451754 -289.152588) (xy 374.507488 -289.150551)
			(xy 374.562925 -289.156651) (xy 374.616882 -289.170757) (xy 374.668211 -289.192569) (xy 374.715817 -289.221623)
			(xy 374.758685 -289.257298) (xy 374.795902 -289.298835) (xy 374.826675 -289.345348) (xy 374.850347 -289.395845)
			(xy 374.866415 -289.449252) (xy 374.874535 -289.504428) (xy 374.875044 -289.532314) (xy 375.587004 -289.532314)
			(xy 375.591075 -289.476692) (xy 375.603201 -289.422255) (xy 375.623124 -289.370164) (xy 375.65042 -289.321529)
			(xy 375.684506 -289.277386) (xy 375.724655 -289.238677) (xy 375.770013 -289.206226) (xy 375.819613 -289.180725)
			(xy 375.872397 -289.162718) (xy 375.92724 -289.152588) (xy 375.982974 -289.150551) (xy 376.038411 -289.156651)
			(xy 376.092368 -289.170757) (xy 376.143697 -289.192569) (xy 376.191303 -289.221623) (xy 376.234171 -289.257298)
			(xy 376.271388 -289.298835) (xy 376.302161 -289.345348) (xy 376.325833 -289.395845) (xy 376.341901 -289.449252)
			(xy 376.350021 -289.504428) (xy 376.35053 -289.532314) (xy 376.476004 -289.532314) (xy 376.480075 -289.476692)
			(xy 376.492201 -289.422255) (xy 376.512124 -289.370164) (xy 376.53942 -289.321529) (xy 376.573506 -289.277386)
			(xy 376.613655 -289.238677) (xy 376.659013 -289.206226) (xy 376.708613 -289.180725) (xy 376.761397 -289.162718)
			(xy 376.81624 -289.152588) (xy 376.871974 -289.150551) (xy 376.927411 -289.156651) (xy 376.981368 -289.170757)
			(xy 377.032697 -289.192569) (xy 377.080303 -289.221623) (xy 377.123171 -289.257298) (xy 377.160388 -289.298835)
			(xy 377.191161 -289.345348) (xy 377.214833 -289.395845) (xy 377.230901 -289.449252) (xy 377.239021 -289.504428)
			(xy 377.23953 -289.532314) (xy 377.239021 -289.5602) (xy 377.230901 -289.615376) (xy 377.214833 -289.668783)
			(xy 377.191161 -289.71928) (xy 377.160388 -289.765793) (xy 377.123171 -289.80733) (xy 377.080303 -289.843005)
			(xy 377.032697 -289.872059) (xy 376.981368 -289.893871) (xy 376.927411 -289.907977) (xy 376.871974 -289.914077)
			(xy 376.81624 -289.91204) (xy 376.761397 -289.90191) (xy 376.708613 -289.883903) (xy 376.659013 -289.858402)
			(xy 376.613655 -289.825951) (xy 376.573506 -289.787242) (xy 376.53942 -289.743099) (xy 376.512124 -289.694464)
			(xy 376.492201 -289.642373) (xy 376.480075 -289.587936) (xy 376.476004 -289.532314) (xy 376.35053 -289.532314)
			(xy 376.350021 -289.5602) (xy 376.341901 -289.615376) (xy 376.325833 -289.668783) (xy 376.302161 -289.71928)
			(xy 376.271388 -289.765793) (xy 376.234171 -289.80733) (xy 376.191303 -289.843005) (xy 376.143697 -289.872059)
			(xy 376.092368 -289.893871) (xy 376.038411 -289.907977) (xy 375.982974 -289.914077) (xy 375.92724 -289.91204)
			(xy 375.872397 -289.90191) (xy 375.819613 -289.883903) (xy 375.770013 -289.858402) (xy 375.724655 -289.825951)
			(xy 375.684506 -289.787242) (xy 375.65042 -289.743099) (xy 375.623124 -289.694464) (xy 375.603201 -289.642373)
			(xy 375.591075 -289.587936) (xy 375.587004 -289.532314) (xy 374.875044 -289.532314) (xy 374.874535 -289.5602)
			(xy 374.866415 -289.615376) (xy 374.850347 -289.668783) (xy 374.826675 -289.71928) (xy 374.795902 -289.765793)
			(xy 374.758685 -289.80733) (xy 374.715817 -289.843005) (xy 374.668211 -289.872059) (xy 374.616882 -289.893871)
			(xy 374.562925 -289.907977) (xy 374.507488 -289.914077) (xy 374.451754 -289.91204) (xy 374.396911 -289.90191)
			(xy 374.344127 -289.883903) (xy 374.294527 -289.858402) (xy 374.249169 -289.825951) (xy 374.20902 -289.787242)
			(xy 374.174934 -289.743099) (xy 374.147638 -289.694464) (xy 374.127715 -289.642373) (xy 374.115589 -289.587936)
			(xy 374.111518 -289.532314) (xy 368.55019 -289.532314) (xy 368.55019 -290.294314) (xy 379.638052 -290.294314)
			(xy 379.638619 -290.264933) (xy 379.647646 -290.206868) (xy 379.665474 -290.150875) (xy 379.691681 -290.09828)
			(xy 379.725646 -290.050328) (xy 379.766565 -290.008154) (xy 379.78969 -289.990022) (xy 379.799088 -289.982656)
			(xy 379.809502 -289.962082) (xy 379.811026 -289.858196) (xy 379.80112 -289.837114) (xy 379.791976 -289.829748)
			(xy 379.770116 -289.811556) (xy 379.731578 -289.769734) (xy 379.699673 -289.722655) (xy 379.675108 -289.671363)
			(xy 379.658427 -289.616993) (xy 379.65 -289.56075) (xy 379.649482 -289.532314) (xy 379.649968 -289.505063)
			(xy 379.657724 -289.451115) (xy 379.673079 -289.39882) (xy 379.695721 -289.349243) (xy 379.725187 -289.303393)
			(xy 379.760878 -289.262202) (xy 379.802069 -289.226511) (xy 379.847919 -289.197045) (xy 379.897496 -289.174403)
			(xy 379.949791 -289.159048) (xy 380.003739 -289.151292) (xy 380.058241 -289.151292) (xy 380.112189 -289.159048)
			(xy 380.164484 -289.174403) (xy 380.214061 -289.197045) (xy 380.259911 -289.226511) (xy 380.301102 -289.262202)
			(xy 380.336793 -289.303393) (xy 380.366259 -289.349243) (xy 380.388901 -289.39882) (xy 380.404256 -289.451115)
			(xy 380.412012 -289.505063) (xy 380.412498 -289.532314) (xy 380.411971 -289.561697) (xy 380.402938 -289.619764)
			(xy 380.385103 -289.675759) (xy 380.360637 -289.724846) (xy 384.369068 -289.724846) (xy 384.373028 -289.675792)
			(xy 384.384805 -289.628008) (xy 384.404096 -289.582732) (xy 384.430399 -289.541136) (xy 384.463034 -289.504299)
			(xy 384.501155 -289.473174) (xy 384.543776 -289.448567) (xy 384.589792 -289.431115) (xy 384.638011 -289.421271)
			(xy 384.687186 -289.41929) (xy 384.736041 -289.425222) (xy 384.783312 -289.438914) (xy 384.827774 -289.460012)
			(xy 384.868277 -289.487968) (xy 384.90377 -289.52206) (xy 384.933335 -289.561404) (xy 384.956206 -289.604981)
			(xy 384.97179 -289.651662) (xy 384.979685 -289.700239) (xy 384.98018 -289.724846) (xy 385.319028 -289.724846)
			(xy 385.322988 -289.675792) (xy 385.334765 -289.628008) (xy 385.354056 -289.582732) (xy 385.380359 -289.541136)
			(xy 385.412994 -289.504299) (xy 385.451115 -289.473174) (xy 385.493736 -289.448567) (xy 385.539752 -289.431115)
			(xy 385.587971 -289.421271) (xy 385.637146 -289.41929) (xy 385.686001 -289.425222) (xy 385.733272 -289.438914)
			(xy 385.777734 -289.460012) (xy 385.818237 -289.487968) (xy 385.85373 -289.52206) (xy 385.883295 -289.561404)
			(xy 385.906166 -289.604981) (xy 385.92175 -289.651662) (xy 385.929645 -289.700239) (xy 385.93014 -289.724846)
			(xy 386.269242 -289.724846) (xy 386.273202 -289.675792) (xy 386.284979 -289.628008) (xy 386.30427 -289.582732)
			(xy 386.330573 -289.541136) (xy 386.363208 -289.504299) (xy 386.401329 -289.473174) (xy 386.44395 -289.448567)
			(xy 386.489966 -289.431115) (xy 386.538185 -289.421271) (xy 386.58736 -289.41929) (xy 386.636215 -289.425222)
			(xy 386.683486 -289.438914) (xy 386.727948 -289.460012) (xy 386.768451 -289.487968) (xy 386.803944 -289.52206)
			(xy 386.833509 -289.561404) (xy 386.85638 -289.604981) (xy 386.871964 -289.651662) (xy 386.879859 -289.700239)
			(xy 386.880354 -289.724846) (xy 387.219202 -289.724846) (xy 387.223162 -289.675792) (xy 387.234939 -289.628008)
			(xy 387.25423 -289.582732) (xy 387.280533 -289.541136) (xy 387.313168 -289.504299) (xy 387.351289 -289.473174)
			(xy 387.39391 -289.448567) (xy 387.439926 -289.431115) (xy 387.488145 -289.421271) (xy 387.53732 -289.41929)
			(xy 387.586175 -289.425222) (xy 387.633446 -289.438914) (xy 387.677908 -289.460012) (xy 387.718411 -289.487968)
			(xy 387.753904 -289.52206) (xy 387.783469 -289.561404) (xy 387.80634 -289.604981) (xy 387.821924 -289.651662)
			(xy 387.829819 -289.700239) (xy 387.830314 -289.724846) (xy 388.169162 -289.724846) (xy 388.173122 -289.675792)
			(xy 388.184899 -289.628008) (xy 388.20419 -289.582732) (xy 388.230493 -289.541136) (xy 388.263128 -289.504299)
			(xy 388.301249 -289.473174) (xy 388.34387 -289.448567) (xy 388.389886 -289.431115) (xy 388.438105 -289.421271)
			(xy 388.48728 -289.41929) (xy 388.536135 -289.425222) (xy 388.583406 -289.438914) (xy 388.627868 -289.460012)
			(xy 388.668371 -289.487968) (xy 388.703864 -289.52206) (xy 388.733429 -289.561404) (xy 388.7563 -289.604981)
			(xy 388.771884 -289.651662) (xy 388.779779 -289.700239) (xy 388.780274 -289.724846) (xy 389.119122 -289.724846)
			(xy 389.123082 -289.675792) (xy 389.134859 -289.628008) (xy 389.15415 -289.582732) (xy 389.180453 -289.541136)
			(xy 389.213088 -289.504299) (xy 389.251209 -289.473174) (xy 389.29383 -289.448567) (xy 389.339846 -289.431115)
			(xy 389.388065 -289.421271) (xy 389.43724 -289.41929) (xy 389.486095 -289.425222) (xy 389.533366 -289.438914)
			(xy 389.577828 -289.460012) (xy 389.618331 -289.487968) (xy 389.653824 -289.52206) (xy 389.683389 -289.561404)
			(xy 389.70626 -289.604981) (xy 389.721844 -289.651662) (xy 389.729739 -289.700239) (xy 389.730234 -289.724846)
			(xy 390.069082 -289.724846) (xy 390.073042 -289.675792) (xy 390.084819 -289.628008) (xy 390.10411 -289.582732)
			(xy 390.130413 -289.541136) (xy 390.163048 -289.504299) (xy 390.201169 -289.473174) (xy 390.24379 -289.448567)
			(xy 390.289806 -289.431115) (xy 390.338025 -289.421271) (xy 390.3872 -289.41929) (xy 390.436055 -289.425222)
			(xy 390.483326 -289.438914) (xy 390.527788 -289.460012) (xy 390.568291 -289.487968) (xy 390.603784 -289.52206)
			(xy 390.633349 -289.561404) (xy 390.65622 -289.604981) (xy 390.671804 -289.651662) (xy 390.679699 -289.700239)
			(xy 390.680194 -289.724846) (xy 391.019042 -289.724846) (xy 391.023002 -289.675792) (xy 391.034779 -289.628008)
			(xy 391.05407 -289.582732) (xy 391.080373 -289.541136) (xy 391.113008 -289.504299) (xy 391.151129 -289.473174)
			(xy 391.19375 -289.448567) (xy 391.239766 -289.431115) (xy 391.287985 -289.421271) (xy 391.33716 -289.41929)
			(xy 391.386015 -289.425222) (xy 391.433286 -289.438914) (xy 391.477748 -289.460012) (xy 391.518251 -289.487968)
			(xy 391.553744 -289.52206) (xy 391.583309 -289.561404) (xy 391.60618 -289.604981) (xy 391.621764 -289.651662)
			(xy 391.629659 -289.700239) (xy 391.630154 -289.724846) (xy 391.969002 -289.724846) (xy 391.972962 -289.675792)
			(xy 391.984739 -289.628008) (xy 392.00403 -289.582732) (xy 392.030333 -289.541136) (xy 392.062968 -289.504299)
			(xy 392.101089 -289.473174) (xy 392.14371 -289.448567) (xy 392.189726 -289.431115) (xy 392.237945 -289.421271)
			(xy 392.28712 -289.41929) (xy 392.335975 -289.425222) (xy 392.383246 -289.438914) (xy 392.427708 -289.460012)
			(xy 392.468211 -289.487968) (xy 392.503704 -289.52206) (xy 392.533269 -289.561404) (xy 392.55614 -289.604981)
			(xy 392.571724 -289.651662) (xy 392.579619 -289.700239) (xy 392.580114 -289.724846) (xy 392.919216 -289.724846)
			(xy 392.923176 -289.675792) (xy 392.934953 -289.628008) (xy 392.954244 -289.582732) (xy 392.980547 -289.541136)
			(xy 393.013182 -289.504299) (xy 393.051303 -289.473174) (xy 393.093924 -289.448567) (xy 393.13994 -289.431115)
			(xy 393.188159 -289.421271) (xy 393.237334 -289.41929) (xy 393.286189 -289.425222) (xy 393.33346 -289.438914)
			(xy 393.377922 -289.460012) (xy 393.418425 -289.487968) (xy 393.453918 -289.52206) (xy 393.483483 -289.561404)
			(xy 393.506354 -289.604981) (xy 393.521938 -289.651662) (xy 393.529833 -289.700239) (xy 393.530328 -289.724846)
			(xy 393.869176 -289.724846) (xy 393.873136 -289.675792) (xy 393.884913 -289.628008) (xy 393.904204 -289.582732)
			(xy 393.930507 -289.541136) (xy 393.963142 -289.504299) (xy 394.001263 -289.473174) (xy 394.043884 -289.448567)
			(xy 394.0899 -289.431115) (xy 394.138119 -289.421271) (xy 394.187294 -289.41929) (xy 394.236149 -289.425222)
			(xy 394.28342 -289.438914) (xy 394.327882 -289.460012) (xy 394.368385 -289.487968) (xy 394.403878 -289.52206)
			(xy 394.433443 -289.561404) (xy 394.456314 -289.604981) (xy 394.471898 -289.651662) (xy 394.479793 -289.700239)
			(xy 394.480288 -289.724846) (xy 394.819136 -289.724846) (xy 394.823096 -289.675792) (xy 394.834873 -289.628008)
			(xy 394.854164 -289.582732) (xy 394.880467 -289.541136) (xy 394.913102 -289.504299) (xy 394.951223 -289.473174)
			(xy 394.993844 -289.448567) (xy 395.03986 -289.431115) (xy 395.088079 -289.421271) (xy 395.137254 -289.41929)
			(xy 395.186109 -289.425222) (xy 395.23338 -289.438914) (xy 395.277842 -289.460012) (xy 395.318345 -289.487968)
			(xy 395.353838 -289.52206) (xy 395.383403 -289.561404) (xy 395.406274 -289.604981) (xy 395.421858 -289.651662)
			(xy 395.429753 -289.700239) (xy 395.430248 -289.724846) (xy 395.769096 -289.724846) (xy 395.773056 -289.675792)
			(xy 395.784833 -289.628008) (xy 395.804124 -289.582732) (xy 395.830427 -289.541136) (xy 395.863062 -289.504299)
			(xy 395.901183 -289.473174) (xy 395.943804 -289.448567) (xy 395.98982 -289.431115) (xy 396.038039 -289.421271)
			(xy 396.087214 -289.41929) (xy 396.136069 -289.425222) (xy 396.18334 -289.438914) (xy 396.227802 -289.460012)
			(xy 396.268305 -289.487968) (xy 396.303798 -289.52206) (xy 396.333363 -289.561404) (xy 396.356234 -289.604981)
			(xy 396.371818 -289.651662) (xy 396.379713 -289.700239) (xy 396.380208 -289.724846) (xy 396.719056 -289.724846)
			(xy 396.723016 -289.675792) (xy 396.734793 -289.628008) (xy 396.754084 -289.582732) (xy 396.780387 -289.541136)
			(xy 396.813022 -289.504299) (xy 396.851143 -289.473174) (xy 396.893764 -289.448567) (xy 396.93978 -289.431115)
			(xy 396.987999 -289.421271) (xy 397.037174 -289.41929) (xy 397.086029 -289.425222) (xy 397.1333 -289.438914)
			(xy 397.177762 -289.460012) (xy 397.218265 -289.487968) (xy 397.253758 -289.52206) (xy 397.283323 -289.561404)
			(xy 397.306194 -289.604981) (xy 397.321778 -289.651662) (xy 397.329673 -289.700239) (xy 397.330168 -289.724846)
			(xy 397.669016 -289.724846) (xy 397.672976 -289.675792) (xy 397.684753 -289.628008) (xy 397.704044 -289.582732)
			(xy 397.730347 -289.541136) (xy 397.762982 -289.504299) (xy 397.801103 -289.473174) (xy 397.843724 -289.448567)
			(xy 397.88974 -289.431115) (xy 397.937959 -289.421271) (xy 397.987134 -289.41929) (xy 398.035989 -289.425222)
			(xy 398.08326 -289.438914) (xy 398.127722 -289.460012) (xy 398.168225 -289.487968) (xy 398.203718 -289.52206)
			(xy 398.233283 -289.561404) (xy 398.256154 -289.604981) (xy 398.271738 -289.651662) (xy 398.279633 -289.700239)
			(xy 398.280128 -289.724846) (xy 398.61923 -289.724846) (xy 398.62319 -289.675792) (xy 398.634967 -289.628008)
			(xy 398.654258 -289.582732) (xy 398.680561 -289.541136) (xy 398.713196 -289.504299) (xy 398.751317 -289.473174)
			(xy 398.793938 -289.448567) (xy 398.839954 -289.431115) (xy 398.888173 -289.421271) (xy 398.937348 -289.41929)
			(xy 398.986203 -289.425222) (xy 399.033474 -289.438914) (xy 399.077936 -289.460012) (xy 399.118439 -289.487968)
			(xy 399.153932 -289.52206) (xy 399.183497 -289.561404) (xy 399.206368 -289.604981) (xy 399.221952 -289.651662)
			(xy 399.229847 -289.700239) (xy 399.230342 -289.724846) (xy 399.56919 -289.724846) (xy 399.57315 -289.675792)
			(xy 399.584927 -289.628008) (xy 399.604218 -289.582732) (xy 399.630521 -289.541136) (xy 399.663156 -289.504299)
			(xy 399.701277 -289.473174) (xy 399.743898 -289.448567) (xy 399.789914 -289.431115) (xy 399.838133 -289.421271)
			(xy 399.887308 -289.41929) (xy 399.936163 -289.425222) (xy 399.983434 -289.438914) (xy 400.027896 -289.460012)
			(xy 400.068399 -289.487968) (xy 400.103892 -289.52206) (xy 400.133457 -289.561404) (xy 400.156328 -289.604981)
			(xy 400.171912 -289.651662) (xy 400.179807 -289.700239) (xy 400.180302 -289.724846) (xy 400.51915 -289.724846)
			(xy 400.52311 -289.675792) (xy 400.534887 -289.628008) (xy 400.554178 -289.582732) (xy 400.580481 -289.541136)
			(xy 400.613116 -289.504299) (xy 400.651237 -289.473174) (xy 400.693858 -289.448567) (xy 400.739874 -289.431115)
			(xy 400.788093 -289.421271) (xy 400.837268 -289.41929) (xy 400.886123 -289.425222) (xy 400.933394 -289.438914)
			(xy 400.977856 -289.460012) (xy 401.018359 -289.487968) (xy 401.053852 -289.52206) (xy 401.083417 -289.561404)
			(xy 401.106288 -289.604981) (xy 401.121872 -289.651662) (xy 401.129767 -289.700239) (xy 401.130262 -289.724846)
			(xy 401.46911 -289.724846) (xy 401.47307 -289.675792) (xy 401.484847 -289.628008) (xy 401.504138 -289.582732)
			(xy 401.530441 -289.541136) (xy 401.563076 -289.504299) (xy 401.601197 -289.473174) (xy 401.643818 -289.448567)
			(xy 401.689834 -289.431115) (xy 401.738053 -289.421271) (xy 401.787228 -289.41929) (xy 401.836083 -289.425222)
			(xy 401.883354 -289.438914) (xy 401.927816 -289.460012) (xy 401.968319 -289.487968) (xy 402.003812 -289.52206)
			(xy 402.033377 -289.561404) (xy 402.056248 -289.604981) (xy 402.071832 -289.651662) (xy 402.079727 -289.700239)
			(xy 402.080222 -289.724846) (xy 402.41907 -289.724846) (xy 402.42303 -289.675792) (xy 402.434807 -289.628008)
			(xy 402.454098 -289.582732) (xy 402.480401 -289.541136) (xy 402.513036 -289.504299) (xy 402.551157 -289.473174)
			(xy 402.593778 -289.448567) (xy 402.639794 -289.431115) (xy 402.688013 -289.421271) (xy 402.737188 -289.41929)
			(xy 402.786043 -289.425222) (xy 402.833314 -289.438914) (xy 402.877776 -289.460012) (xy 402.918279 -289.487968)
			(xy 402.953772 -289.52206) (xy 402.983337 -289.561404) (xy 403.006208 -289.604981) (xy 403.021792 -289.651662)
			(xy 403.029687 -289.700239) (xy 403.030182 -289.724846) (xy 403.36903 -289.724846) (xy 403.37299 -289.675792)
			(xy 403.384767 -289.628008) (xy 403.404058 -289.582732) (xy 403.430361 -289.541136) (xy 403.462996 -289.504299)
			(xy 403.501117 -289.473174) (xy 403.543738 -289.448567) (xy 403.589754 -289.431115) (xy 403.637973 -289.421271)
			(xy 403.687148 -289.41929) (xy 403.736003 -289.425222) (xy 403.783274 -289.438914) (xy 403.827736 -289.460012)
			(xy 403.868239 -289.487968) (xy 403.903732 -289.52206) (xy 403.933297 -289.561404) (xy 403.956168 -289.604981)
			(xy 403.971752 -289.651662) (xy 403.979647 -289.700239) (xy 403.980142 -289.724846) (xy 404.31899 -289.724846)
			(xy 404.32295 -289.675792) (xy 404.334727 -289.628008) (xy 404.354018 -289.582732) (xy 404.380321 -289.541136)
			(xy 404.412956 -289.504299) (xy 404.451077 -289.473174) (xy 404.493698 -289.448567) (xy 404.539714 -289.431115)
			(xy 404.587933 -289.421271) (xy 404.637108 -289.41929) (xy 404.685963 -289.425222) (xy 404.733234 -289.438914)
			(xy 404.777696 -289.460012) (xy 404.818199 -289.487968) (xy 404.853692 -289.52206) (xy 404.883257 -289.561404)
			(xy 404.906128 -289.604981) (xy 404.921712 -289.651662) (xy 404.929607 -289.700239) (xy 404.930102 -289.724846)
			(xy 405.269204 -289.724846) (xy 405.273164 -289.675792) (xy 405.284941 -289.628008) (xy 405.304232 -289.582732)
			(xy 405.330535 -289.541136) (xy 405.36317 -289.504299) (xy 405.401291 -289.473174) (xy 405.443912 -289.448567)
			(xy 405.489928 -289.431115) (xy 405.538147 -289.421271) (xy 405.587322 -289.41929) (xy 405.636177 -289.425222)
			(xy 405.683448 -289.438914) (xy 405.72791 -289.460012) (xy 405.768413 -289.487968) (xy 405.803906 -289.52206)
			(xy 405.833471 -289.561404) (xy 405.856342 -289.604981) (xy 405.871926 -289.651662) (xy 405.879821 -289.700239)
			(xy 405.880316 -289.724846) (xy 406.219164 -289.724846) (xy 406.223124 -289.675792) (xy 406.234901 -289.628008)
			(xy 406.254192 -289.582732) (xy 406.280495 -289.541136) (xy 406.31313 -289.504299) (xy 406.351251 -289.473174)
			(xy 406.393872 -289.448567) (xy 406.439888 -289.431115) (xy 406.488107 -289.421271) (xy 406.537282 -289.41929)
			(xy 406.586137 -289.425222) (xy 406.633408 -289.438914) (xy 406.67787 -289.460012) (xy 406.718373 -289.487968)
			(xy 406.753866 -289.52206) (xy 406.783431 -289.561404) (xy 406.806302 -289.604981) (xy 406.821886 -289.651662)
			(xy 406.829781 -289.700239) (xy 406.830276 -289.724846) (xy 408.119084 -289.724846) (xy 408.123044 -289.675792)
			(xy 408.134821 -289.628008) (xy 408.154112 -289.582732) (xy 408.180415 -289.541136) (xy 408.21305 -289.504299)
			(xy 408.251171 -289.473174) (xy 408.293792 -289.448567) (xy 408.339808 -289.431115) (xy 408.388027 -289.421271)
			(xy 408.437202 -289.41929) (xy 408.486057 -289.425222) (xy 408.533328 -289.438914) (xy 408.57779 -289.460012)
			(xy 408.618293 -289.487968) (xy 408.653786 -289.52206) (xy 408.683351 -289.561404) (xy 408.706222 -289.604981)
			(xy 408.721806 -289.651662) (xy 408.729701 -289.700239) (xy 408.730196 -289.724846) (xy 409.069044 -289.724846)
			(xy 409.073004 -289.675792) (xy 409.084781 -289.628008) (xy 409.104072 -289.582732) (xy 409.130375 -289.541136)
			(xy 409.16301 -289.504299) (xy 409.201131 -289.473174) (xy 409.243752 -289.448567) (xy 409.289768 -289.431115)
			(xy 409.337987 -289.421271) (xy 409.387162 -289.41929) (xy 409.436017 -289.425222) (xy 409.483288 -289.438914)
			(xy 409.52775 -289.460012) (xy 409.568253 -289.487968) (xy 409.603746 -289.52206) (xy 409.633311 -289.561404)
			(xy 409.656182 -289.604981) (xy 409.671766 -289.651662) (xy 409.679661 -289.700239) (xy 409.680156 -289.724846)
			(xy 410.019004 -289.724846) (xy 410.022964 -289.675792) (xy 410.034741 -289.628008) (xy 410.054032 -289.582732)
			(xy 410.080335 -289.541136) (xy 410.11297 -289.504299) (xy 410.151091 -289.473174) (xy 410.193712 -289.448567)
			(xy 410.239728 -289.431115) (xy 410.287947 -289.421271) (xy 410.337122 -289.41929) (xy 410.385977 -289.425222)
			(xy 410.433248 -289.438914) (xy 410.47771 -289.460012) (xy 410.518213 -289.487968) (xy 410.553706 -289.52206)
			(xy 410.583271 -289.561404) (xy 410.606142 -289.604981) (xy 410.621726 -289.651662) (xy 410.629621 -289.700239)
			(xy 410.630116 -289.724846) (xy 410.969218 -289.724846) (xy 410.973178 -289.675792) (xy 410.984955 -289.628008)
			(xy 411.004246 -289.582732) (xy 411.030549 -289.541136) (xy 411.063184 -289.504299) (xy 411.101305 -289.473174)
			(xy 411.143926 -289.448567) (xy 411.189942 -289.431115) (xy 411.238161 -289.421271) (xy 411.287336 -289.41929)
			(xy 411.336191 -289.425222) (xy 411.383462 -289.438914) (xy 411.427924 -289.460012) (xy 411.468427 -289.487968)
			(xy 411.50392 -289.52206) (xy 411.533485 -289.561404) (xy 411.556356 -289.604981) (xy 411.57194 -289.651662)
			(xy 411.579835 -289.700239) (xy 411.58033 -289.724846) (xy 411.919178 -289.724846) (xy 411.923138 -289.675792)
			(xy 411.934915 -289.628008) (xy 411.954206 -289.582732) (xy 411.980509 -289.541136) (xy 412.013144 -289.504299)
			(xy 412.051265 -289.473174) (xy 412.093886 -289.448567) (xy 412.139902 -289.431115) (xy 412.188121 -289.421271)
			(xy 412.237296 -289.41929) (xy 412.286151 -289.425222) (xy 412.333422 -289.438914) (xy 412.377884 -289.460012)
			(xy 412.418387 -289.487968) (xy 412.45388 -289.52206) (xy 412.483445 -289.561404) (xy 412.506316 -289.604981)
			(xy 412.5219 -289.651662) (xy 412.529795 -289.700239) (xy 412.53029 -289.724846) (xy 412.869138 -289.724846)
			(xy 412.873098 -289.675792) (xy 412.884875 -289.628008) (xy 412.904166 -289.582732) (xy 412.930469 -289.541136)
			(xy 412.963104 -289.504299) (xy 413.001225 -289.473174) (xy 413.043846 -289.448567) (xy 413.089862 -289.431115)
			(xy 413.138081 -289.421271) (xy 413.187256 -289.41929) (xy 413.236111 -289.425222) (xy 413.283382 -289.438914)
			(xy 413.327844 -289.460012) (xy 413.368347 -289.487968) (xy 413.40384 -289.52206) (xy 413.433405 -289.561404)
			(xy 413.456276 -289.604981) (xy 413.47186 -289.651662) (xy 413.479755 -289.700239) (xy 413.48025 -289.724846)
			(xy 413.819098 -289.724846) (xy 413.823058 -289.675792) (xy 413.834835 -289.628008) (xy 413.854126 -289.582732)
			(xy 413.880429 -289.541136) (xy 413.913064 -289.504299) (xy 413.951185 -289.473174) (xy 413.993806 -289.448567)
			(xy 414.039822 -289.431115) (xy 414.088041 -289.421271) (xy 414.137216 -289.41929) (xy 414.186071 -289.425222)
			(xy 414.233342 -289.438914) (xy 414.277804 -289.460012) (xy 414.318307 -289.487968) (xy 414.3538 -289.52206)
			(xy 414.383365 -289.561404) (xy 414.406236 -289.604981) (xy 414.42182 -289.651662) (xy 414.429715 -289.700239)
			(xy 414.43021 -289.724846) (xy 414.769058 -289.724846) (xy 414.773018 -289.675792) (xy 414.784795 -289.628008)
			(xy 414.804086 -289.582732) (xy 414.830389 -289.541136) (xy 414.863024 -289.504299) (xy 414.901145 -289.473174)
			(xy 414.943766 -289.448567) (xy 414.989782 -289.431115) (xy 415.038001 -289.421271) (xy 415.087176 -289.41929)
			(xy 415.136031 -289.425222) (xy 415.183302 -289.438914) (xy 415.227764 -289.460012) (xy 415.268267 -289.487968)
			(xy 415.30376 -289.52206) (xy 415.333325 -289.561404) (xy 415.356196 -289.604981) (xy 415.37178 -289.651662)
			(xy 415.379675 -289.700239) (xy 415.38017 -289.724846) (xy 415.719018 -289.724846) (xy 415.722978 -289.675792)
			(xy 415.734755 -289.628008) (xy 415.754046 -289.582732) (xy 415.780349 -289.541136) (xy 415.812984 -289.504299)
			(xy 415.851105 -289.473174) (xy 415.893726 -289.448567) (xy 415.939742 -289.431115) (xy 415.987961 -289.421271)
			(xy 416.037136 -289.41929) (xy 416.085991 -289.425222) (xy 416.133262 -289.438914) (xy 416.177724 -289.460012)
			(xy 416.218227 -289.487968) (xy 416.25372 -289.52206) (xy 416.283285 -289.561404) (xy 416.306156 -289.604981)
			(xy 416.32174 -289.651662) (xy 416.329635 -289.700239) (xy 416.33013 -289.724846) (xy 416.668978 -289.724846)
			(xy 416.672938 -289.675792) (xy 416.684715 -289.628008) (xy 416.704006 -289.582732) (xy 416.730309 -289.541136)
			(xy 416.762944 -289.504299) (xy 416.801065 -289.473174) (xy 416.843686 -289.448567) (xy 416.889702 -289.431115)
			(xy 416.937921 -289.421271) (xy 416.987096 -289.41929) (xy 417.035951 -289.425222) (xy 417.083222 -289.438914)
			(xy 417.127684 -289.460012) (xy 417.168187 -289.487968) (xy 417.20368 -289.52206) (xy 417.233245 -289.561404)
			(xy 417.256116 -289.604981) (xy 417.2717 -289.651662) (xy 417.279595 -289.700239) (xy 417.28009 -289.724846)
			(xy 417.279595 -289.749453) (xy 417.2717 -289.79803) (xy 417.256116 -289.844711) (xy 417.233245 -289.888288)
			(xy 417.20368 -289.927632) (xy 417.168187 -289.961724) (xy 417.127684 -289.98968) (xy 417.083222 -290.010778)
			(xy 417.035951 -290.02447) (xy 416.987096 -290.030402) (xy 416.937921 -290.028421) (xy 416.889702 -290.018577)
			(xy 416.843686 -290.001125) (xy 416.801065 -289.976518) (xy 416.762944 -289.945393) (xy 416.730309 -289.908556)
			(xy 416.704006 -289.86696) (xy 416.684715 -289.821684) (xy 416.672938 -289.7739) (xy 416.668978 -289.724846)
			(xy 416.33013 -289.724846) (xy 416.329635 -289.749453) (xy 416.32174 -289.79803) (xy 416.306156 -289.844711)
			(xy 416.283285 -289.888288) (xy 416.25372 -289.927632) (xy 416.218227 -289.961724) (xy 416.177724 -289.98968)
			(xy 416.133262 -290.010778) (xy 416.085991 -290.02447) (xy 416.037136 -290.030402) (xy 415.987961 -290.028421)
			(xy 415.939742 -290.018577) (xy 415.893726 -290.001125) (xy 415.851105 -289.976518) (xy 415.812984 -289.945393)
			(xy 415.780349 -289.908556) (xy 415.754046 -289.86696) (xy 415.734755 -289.821684) (xy 415.722978 -289.7739)
			(xy 415.719018 -289.724846) (xy 415.38017 -289.724846) (xy 415.379675 -289.749453) (xy 415.37178 -289.79803)
			(xy 415.356196 -289.844711) (xy 415.333325 -289.888288) (xy 415.30376 -289.927632) (xy 415.268267 -289.961724)
			(xy 415.227764 -289.98968) (xy 415.183302 -290.010778) (xy 415.136031 -290.02447) (xy 415.087176 -290.030402)
			(xy 415.038001 -290.028421) (xy 414.989782 -290.018577) (xy 414.943766 -290.001125) (xy 414.901145 -289.976518)
			(xy 414.863024 -289.945393) (xy 414.830389 -289.908556) (xy 414.804086 -289.86696) (xy 414.784795 -289.821684)
			(xy 414.773018 -289.7739) (xy 414.769058 -289.724846) (xy 414.43021 -289.724846) (xy 414.429715 -289.749453)
			(xy 414.42182 -289.79803) (xy 414.406236 -289.844711) (xy 414.383365 -289.888288) (xy 414.3538 -289.927632)
			(xy 414.318307 -289.961724) (xy 414.277804 -289.98968) (xy 414.233342 -290.010778) (xy 414.186071 -290.02447)
			(xy 414.137216 -290.030402) (xy 414.088041 -290.028421) (xy 414.039822 -290.018577) (xy 413.993806 -290.001125)
			(xy 413.951185 -289.976518) (xy 413.913064 -289.945393) (xy 413.880429 -289.908556) (xy 413.854126 -289.86696)
			(xy 413.834835 -289.821684) (xy 413.823058 -289.7739) (xy 413.819098 -289.724846) (xy 413.48025 -289.724846)
			(xy 413.479755 -289.749453) (xy 413.47186 -289.79803) (xy 413.456276 -289.844711) (xy 413.433405 -289.888288)
			(xy 413.40384 -289.927632) (xy 413.368347 -289.961724) (xy 413.327844 -289.98968) (xy 413.283382 -290.010778)
			(xy 413.236111 -290.02447) (xy 413.187256 -290.030402) (xy 413.138081 -290.028421) (xy 413.089862 -290.018577)
			(xy 413.043846 -290.001125) (xy 413.001225 -289.976518) (xy 412.963104 -289.945393) (xy 412.930469 -289.908556)
			(xy 412.904166 -289.86696) (xy 412.884875 -289.821684) (xy 412.873098 -289.7739) (xy 412.869138 -289.724846)
			(xy 412.53029 -289.724846) (xy 412.529795 -289.749453) (xy 412.5219 -289.79803) (xy 412.506316 -289.844711)
			(xy 412.483445 -289.888288) (xy 412.45388 -289.927632) (xy 412.418387 -289.961724) (xy 412.377884 -289.98968)
			(xy 412.333422 -290.010778) (xy 412.286151 -290.02447) (xy 412.237296 -290.030402) (xy 412.188121 -290.028421)
			(xy 412.139902 -290.018577) (xy 412.093886 -290.001125) (xy 412.051265 -289.976518) (xy 412.013144 -289.945393)
			(xy 411.980509 -289.908556) (xy 411.954206 -289.86696) (xy 411.934915 -289.821684) (xy 411.923138 -289.7739)
			(xy 411.919178 -289.724846) (xy 411.58033 -289.724846) (xy 411.579835 -289.749453) (xy 411.57194 -289.79803)
			(xy 411.556356 -289.844711) (xy 411.533485 -289.888288) (xy 411.50392 -289.927632) (xy 411.468427 -289.961724)
			(xy 411.427924 -289.98968) (xy 411.383462 -290.010778) (xy 411.336191 -290.02447) (xy 411.287336 -290.030402)
			(xy 411.238161 -290.028421) (xy 411.189942 -290.018577) (xy 411.143926 -290.001125) (xy 411.101305 -289.976518)
			(xy 411.063184 -289.945393) (xy 411.030549 -289.908556) (xy 411.004246 -289.86696) (xy 410.984955 -289.821684)
			(xy 410.973178 -289.7739) (xy 410.969218 -289.724846) (xy 410.630116 -289.724846) (xy 410.629621 -289.749453)
			(xy 410.621726 -289.79803) (xy 410.606142 -289.844711) (xy 410.583271 -289.888288) (xy 410.553706 -289.927632)
			(xy 410.518213 -289.961724) (xy 410.47771 -289.98968) (xy 410.433248 -290.010778) (xy 410.385977 -290.02447)
			(xy 410.337122 -290.030402) (xy 410.287947 -290.028421) (xy 410.239728 -290.018577) (xy 410.193712 -290.001125)
			(xy 410.151091 -289.976518) (xy 410.11297 -289.945393) (xy 410.080335 -289.908556) (xy 410.054032 -289.86696)
			(xy 410.034741 -289.821684) (xy 410.022964 -289.7739) (xy 410.019004 -289.724846) (xy 409.680156 -289.724846)
			(xy 409.679661 -289.749453) (xy 409.671766 -289.79803) (xy 409.656182 -289.844711) (xy 409.633311 -289.888288)
			(xy 409.603746 -289.927632) (xy 409.568253 -289.961724) (xy 409.52775 -289.98968) (xy 409.483288 -290.010778)
			(xy 409.436017 -290.02447) (xy 409.387162 -290.030402) (xy 409.337987 -290.028421) (xy 409.289768 -290.018577)
			(xy 409.243752 -290.001125) (xy 409.201131 -289.976518) (xy 409.16301 -289.945393) (xy 409.130375 -289.908556)
			(xy 409.104072 -289.86696) (xy 409.084781 -289.821684) (xy 409.073004 -289.7739) (xy 409.069044 -289.724846)
			(xy 408.730196 -289.724846) (xy 408.729701 -289.749453) (xy 408.721806 -289.79803) (xy 408.706222 -289.844711)
			(xy 408.683351 -289.888288) (xy 408.653786 -289.927632) (xy 408.618293 -289.961724) (xy 408.57779 -289.98968)
			(xy 408.533328 -290.010778) (xy 408.486057 -290.02447) (xy 408.437202 -290.030402) (xy 408.388027 -290.028421)
			(xy 408.339808 -290.018577) (xy 408.293792 -290.001125) (xy 408.251171 -289.976518) (xy 408.21305 -289.945393)
			(xy 408.180415 -289.908556) (xy 408.154112 -289.86696) (xy 408.134821 -289.821684) (xy 408.123044 -289.7739)
			(xy 408.119084 -289.724846) (xy 406.830276 -289.724846) (xy 406.829781 -289.749453) (xy 406.821886 -289.79803)
			(xy 406.806302 -289.844711) (xy 406.783431 -289.888288) (xy 406.753866 -289.927632) (xy 406.718373 -289.961724)
			(xy 406.67787 -289.98968) (xy 406.633408 -290.010778) (xy 406.586137 -290.02447) (xy 406.537282 -290.030402)
			(xy 406.488107 -290.028421) (xy 406.439888 -290.018577) (xy 406.393872 -290.001125) (xy 406.351251 -289.976518)
			(xy 406.31313 -289.945393) (xy 406.280495 -289.908556) (xy 406.254192 -289.86696) (xy 406.234901 -289.821684)
			(xy 406.223124 -289.7739) (xy 406.219164 -289.724846) (xy 405.880316 -289.724846) (xy 405.879821 -289.749453)
			(xy 405.871926 -289.79803) (xy 405.856342 -289.844711) (xy 405.833471 -289.888288) (xy 405.803906 -289.927632)
			(xy 405.768413 -289.961724) (xy 405.72791 -289.98968) (xy 405.683448 -290.010778) (xy 405.636177 -290.02447)
			(xy 405.587322 -290.030402) (xy 405.538147 -290.028421) (xy 405.489928 -290.018577) (xy 405.443912 -290.001125)
			(xy 405.401291 -289.976518) (xy 405.36317 -289.945393) (xy 405.330535 -289.908556) (xy 405.304232 -289.86696)
			(xy 405.284941 -289.821684) (xy 405.273164 -289.7739) (xy 405.269204 -289.724846) (xy 404.930102 -289.724846)
			(xy 404.929607 -289.749453) (xy 404.921712 -289.79803) (xy 404.906128 -289.844711) (xy 404.883257 -289.888288)
			(xy 404.853692 -289.927632) (xy 404.818199 -289.961724) (xy 404.777696 -289.98968) (xy 404.733234 -290.010778)
			(xy 404.685963 -290.02447) (xy 404.637108 -290.030402) (xy 404.587933 -290.028421) (xy 404.539714 -290.018577)
			(xy 404.493698 -290.001125) (xy 404.451077 -289.976518) (xy 404.412956 -289.945393) (xy 404.380321 -289.908556)
			(xy 404.354018 -289.86696) (xy 404.334727 -289.821684) (xy 404.32295 -289.7739) (xy 404.31899 -289.724846)
			(xy 403.980142 -289.724846) (xy 403.979647 -289.749453) (xy 403.971752 -289.79803) (xy 403.956168 -289.844711)
			(xy 403.933297 -289.888288) (xy 403.903732 -289.927632) (xy 403.868239 -289.961724) (xy 403.827736 -289.98968)
			(xy 403.783274 -290.010778) (xy 403.736003 -290.02447) (xy 403.687148 -290.030402) (xy 403.637973 -290.028421)
			(xy 403.589754 -290.018577) (xy 403.543738 -290.001125) (xy 403.501117 -289.976518) (xy 403.462996 -289.945393)
			(xy 403.430361 -289.908556) (xy 403.404058 -289.86696) (xy 403.384767 -289.821684) (xy 403.37299 -289.7739)
			(xy 403.36903 -289.724846) (xy 403.030182 -289.724846) (xy 403.029687 -289.749453) (xy 403.021792 -289.79803)
			(xy 403.006208 -289.844711) (xy 402.983337 -289.888288) (xy 402.953772 -289.927632) (xy 402.918279 -289.961724)
			(xy 402.877776 -289.98968) (xy 402.833314 -290.010778) (xy 402.786043 -290.02447) (xy 402.737188 -290.030402)
			(xy 402.688013 -290.028421) (xy 402.639794 -290.018577) (xy 402.593778 -290.001125) (xy 402.551157 -289.976518)
			(xy 402.513036 -289.945393) (xy 402.480401 -289.908556) (xy 402.454098 -289.86696) (xy 402.434807 -289.821684)
			(xy 402.42303 -289.7739) (xy 402.41907 -289.724846) (xy 402.080222 -289.724846) (xy 402.079727 -289.749453)
			(xy 402.071832 -289.79803) (xy 402.056248 -289.844711) (xy 402.033377 -289.888288) (xy 402.003812 -289.927632)
			(xy 401.968319 -289.961724) (xy 401.927816 -289.98968) (xy 401.883354 -290.010778) (xy 401.836083 -290.02447)
			(xy 401.787228 -290.030402) (xy 401.738053 -290.028421) (xy 401.689834 -290.018577) (xy 401.643818 -290.001125)
			(xy 401.601197 -289.976518) (xy 401.563076 -289.945393) (xy 401.530441 -289.908556) (xy 401.504138 -289.86696)
			(xy 401.484847 -289.821684) (xy 401.47307 -289.7739) (xy 401.46911 -289.724846) (xy 401.130262 -289.724846)
			(xy 401.129767 -289.749453) (xy 401.121872 -289.79803) (xy 401.106288 -289.844711) (xy 401.083417 -289.888288)
			(xy 401.053852 -289.927632) (xy 401.018359 -289.961724) (xy 400.977856 -289.98968) (xy 400.933394 -290.010778)
			(xy 400.886123 -290.02447) (xy 400.837268 -290.030402) (xy 400.788093 -290.028421) (xy 400.739874 -290.018577)
			(xy 400.693858 -290.001125) (xy 400.651237 -289.976518) (xy 400.613116 -289.945393) (xy 400.580481 -289.908556)
			(xy 400.554178 -289.86696) (xy 400.534887 -289.821684) (xy 400.52311 -289.7739) (xy 400.51915 -289.724846)
			(xy 400.180302 -289.724846) (xy 400.179807 -289.749453) (xy 400.171912 -289.79803) (xy 400.156328 -289.844711)
			(xy 400.133457 -289.888288) (xy 400.103892 -289.927632) (xy 400.068399 -289.961724) (xy 400.027896 -289.98968)
			(xy 399.983434 -290.010778) (xy 399.936163 -290.02447) (xy 399.887308 -290.030402) (xy 399.838133 -290.028421)
			(xy 399.789914 -290.018577) (xy 399.743898 -290.001125) (xy 399.701277 -289.976518) (xy 399.663156 -289.945393)
			(xy 399.630521 -289.908556) (xy 399.604218 -289.86696) (xy 399.584927 -289.821684) (xy 399.57315 -289.7739)
			(xy 399.56919 -289.724846) (xy 399.230342 -289.724846) (xy 399.229847 -289.749453) (xy 399.221952 -289.79803)
			(xy 399.206368 -289.844711) (xy 399.183497 -289.888288) (xy 399.153932 -289.927632) (xy 399.118439 -289.961724)
			(xy 399.077936 -289.98968) (xy 399.033474 -290.010778) (xy 398.986203 -290.02447) (xy 398.937348 -290.030402)
			(xy 398.888173 -290.028421) (xy 398.839954 -290.018577) (xy 398.793938 -290.001125) (xy 398.751317 -289.976518)
			(xy 398.713196 -289.945393) (xy 398.680561 -289.908556) (xy 398.654258 -289.86696) (xy 398.634967 -289.821684)
			(xy 398.62319 -289.7739) (xy 398.61923 -289.724846) (xy 398.280128 -289.724846) (xy 398.279633 -289.749453)
			(xy 398.271738 -289.79803) (xy 398.256154 -289.844711) (xy 398.233283 -289.888288) (xy 398.203718 -289.927632)
			(xy 398.168225 -289.961724) (xy 398.127722 -289.98968) (xy 398.08326 -290.010778) (xy 398.035989 -290.02447)
			(xy 397.987134 -290.030402) (xy 397.937959 -290.028421) (xy 397.88974 -290.018577) (xy 397.843724 -290.001125)
			(xy 397.801103 -289.976518) (xy 397.762982 -289.945393) (xy 397.730347 -289.908556) (xy 397.704044 -289.86696)
			(xy 397.684753 -289.821684) (xy 397.672976 -289.7739) (xy 397.669016 -289.724846) (xy 397.330168 -289.724846)
			(xy 397.329673 -289.749453) (xy 397.321778 -289.79803) (xy 397.306194 -289.844711) (xy 397.283323 -289.888288)
			(xy 397.253758 -289.927632) (xy 397.218265 -289.961724) (xy 397.177762 -289.98968) (xy 397.1333 -290.010778)
			(xy 397.086029 -290.02447) (xy 397.037174 -290.030402) (xy 396.987999 -290.028421) (xy 396.93978 -290.018577)
			(xy 396.893764 -290.001125) (xy 396.851143 -289.976518) (xy 396.813022 -289.945393) (xy 396.780387 -289.908556)
			(xy 396.754084 -289.86696) (xy 396.734793 -289.821684) (xy 396.723016 -289.7739) (xy 396.719056 -289.724846)
			(xy 396.380208 -289.724846) (xy 396.379713 -289.749453) (xy 396.371818 -289.79803) (xy 396.356234 -289.844711)
			(xy 396.333363 -289.888288) (xy 396.303798 -289.927632) (xy 396.268305 -289.961724) (xy 396.227802 -289.98968)
			(xy 396.18334 -290.010778) (xy 396.136069 -290.02447) (xy 396.087214 -290.030402) (xy 396.038039 -290.028421)
			(xy 395.98982 -290.018577) (xy 395.943804 -290.001125) (xy 395.901183 -289.976518) (xy 395.863062 -289.945393)
			(xy 395.830427 -289.908556) (xy 395.804124 -289.86696) (xy 395.784833 -289.821684) (xy 395.773056 -289.7739)
			(xy 395.769096 -289.724846) (xy 395.430248 -289.724846) (xy 395.429753 -289.749453) (xy 395.421858 -289.79803)
			(xy 395.406274 -289.844711) (xy 395.383403 -289.888288) (xy 395.353838 -289.927632) (xy 395.318345 -289.961724)
			(xy 395.277842 -289.98968) (xy 395.23338 -290.010778) (xy 395.186109 -290.02447) (xy 395.137254 -290.030402)
			(xy 395.088079 -290.028421) (xy 395.03986 -290.018577) (xy 394.993844 -290.001125) (xy 394.951223 -289.976518)
			(xy 394.913102 -289.945393) (xy 394.880467 -289.908556) (xy 394.854164 -289.86696) (xy 394.834873 -289.821684)
			(xy 394.823096 -289.7739) (xy 394.819136 -289.724846) (xy 394.480288 -289.724846) (xy 394.479793 -289.749453)
			(xy 394.471898 -289.79803) (xy 394.456314 -289.844711) (xy 394.433443 -289.888288) (xy 394.403878 -289.927632)
			(xy 394.368385 -289.961724) (xy 394.327882 -289.98968) (xy 394.28342 -290.010778) (xy 394.236149 -290.02447)
			(xy 394.187294 -290.030402) (xy 394.138119 -290.028421) (xy 394.0899 -290.018577) (xy 394.043884 -290.001125)
			(xy 394.001263 -289.976518) (xy 393.963142 -289.945393) (xy 393.930507 -289.908556) (xy 393.904204 -289.86696)
			(xy 393.884913 -289.821684) (xy 393.873136 -289.7739) (xy 393.869176 -289.724846) (xy 393.530328 -289.724846)
			(xy 393.529833 -289.749453) (xy 393.521938 -289.79803) (xy 393.506354 -289.844711) (xy 393.483483 -289.888288)
			(xy 393.453918 -289.927632) (xy 393.418425 -289.961724) (xy 393.377922 -289.98968) (xy 393.33346 -290.010778)
			(xy 393.286189 -290.02447) (xy 393.237334 -290.030402) (xy 393.188159 -290.028421) (xy 393.13994 -290.018577)
			(xy 393.093924 -290.001125) (xy 393.051303 -289.976518) (xy 393.013182 -289.945393) (xy 392.980547 -289.908556)
			(xy 392.954244 -289.86696) (xy 392.934953 -289.821684) (xy 392.923176 -289.7739) (xy 392.919216 -289.724846)
			(xy 392.580114 -289.724846) (xy 392.579619 -289.749453) (xy 392.571724 -289.79803) (xy 392.55614 -289.844711)
			(xy 392.533269 -289.888288) (xy 392.503704 -289.927632) (xy 392.468211 -289.961724) (xy 392.427708 -289.98968)
			(xy 392.383246 -290.010778) (xy 392.335975 -290.02447) (xy 392.28712 -290.030402) (xy 392.237945 -290.028421)
			(xy 392.189726 -290.018577) (xy 392.14371 -290.001125) (xy 392.101089 -289.976518) (xy 392.062968 -289.945393)
			(xy 392.030333 -289.908556) (xy 392.00403 -289.86696) (xy 391.984739 -289.821684) (xy 391.972962 -289.7739)
			(xy 391.969002 -289.724846) (xy 391.630154 -289.724846) (xy 391.629659 -289.749453) (xy 391.621764 -289.79803)
			(xy 391.60618 -289.844711) (xy 391.583309 -289.888288) (xy 391.553744 -289.927632) (xy 391.518251 -289.961724)
			(xy 391.477748 -289.98968) (xy 391.433286 -290.010778) (xy 391.386015 -290.02447) (xy 391.33716 -290.030402)
			(xy 391.287985 -290.028421) (xy 391.239766 -290.018577) (xy 391.19375 -290.001125) (xy 391.151129 -289.976518)
			(xy 391.113008 -289.945393) (xy 391.080373 -289.908556) (xy 391.05407 -289.86696) (xy 391.034779 -289.821684)
			(xy 391.023002 -289.7739) (xy 391.019042 -289.724846) (xy 390.680194 -289.724846) (xy 390.679699 -289.749453)
			(xy 390.671804 -289.79803) (xy 390.65622 -289.844711) (xy 390.633349 -289.888288) (xy 390.603784 -289.927632)
			(xy 390.568291 -289.961724) (xy 390.527788 -289.98968) (xy 390.483326 -290.010778) (xy 390.436055 -290.02447)
			(xy 390.3872 -290.030402) (xy 390.338025 -290.028421) (xy 390.289806 -290.018577) (xy 390.24379 -290.001125)
			(xy 390.201169 -289.976518) (xy 390.163048 -289.945393) (xy 390.130413 -289.908556) (xy 390.10411 -289.86696)
			(xy 390.084819 -289.821684) (xy 390.073042 -289.7739) (xy 390.069082 -289.724846) (xy 389.730234 -289.724846)
			(xy 389.729739 -289.749453) (xy 389.721844 -289.79803) (xy 389.70626 -289.844711) (xy 389.683389 -289.888288)
			(xy 389.653824 -289.927632) (xy 389.618331 -289.961724) (xy 389.577828 -289.98968) (xy 389.533366 -290.010778)
			(xy 389.486095 -290.02447) (xy 389.43724 -290.030402) (xy 389.388065 -290.028421) (xy 389.339846 -290.018577)
			(xy 389.29383 -290.001125) (xy 389.251209 -289.976518) (xy 389.213088 -289.945393) (xy 389.180453 -289.908556)
			(xy 389.15415 -289.86696) (xy 389.134859 -289.821684) (xy 389.123082 -289.7739) (xy 389.119122 -289.724846)
			(xy 388.780274 -289.724846) (xy 388.779779 -289.749453) (xy 388.771884 -289.79803) (xy 388.7563 -289.844711)
			(xy 388.733429 -289.888288) (xy 388.703864 -289.927632) (xy 388.668371 -289.961724) (xy 388.627868 -289.98968)
			(xy 388.583406 -290.010778) (xy 388.536135 -290.02447) (xy 388.48728 -290.030402) (xy 388.438105 -290.028421)
			(xy 388.389886 -290.018577) (xy 388.34387 -290.001125) (xy 388.301249 -289.976518) (xy 388.263128 -289.945393)
			(xy 388.230493 -289.908556) (xy 388.20419 -289.86696) (xy 388.184899 -289.821684) (xy 388.173122 -289.7739)
			(xy 388.169162 -289.724846) (xy 387.830314 -289.724846) (xy 387.829819 -289.749453) (xy 387.821924 -289.79803)
			(xy 387.80634 -289.844711) (xy 387.783469 -289.888288) (xy 387.753904 -289.927632) (xy 387.718411 -289.961724)
			(xy 387.677908 -289.98968) (xy 387.633446 -290.010778) (xy 387.586175 -290.02447) (xy 387.53732 -290.030402)
			(xy 387.488145 -290.028421) (xy 387.439926 -290.018577) (xy 387.39391 -290.001125) (xy 387.351289 -289.976518)
			(xy 387.313168 -289.945393) (xy 387.280533 -289.908556) (xy 387.25423 -289.86696) (xy 387.234939 -289.821684)
			(xy 387.223162 -289.7739) (xy 387.219202 -289.724846) (xy 386.880354 -289.724846) (xy 386.879859 -289.749453)
			(xy 386.871964 -289.79803) (xy 386.85638 -289.844711) (xy 386.833509 -289.888288) (xy 386.803944 -289.927632)
			(xy 386.768451 -289.961724) (xy 386.727948 -289.98968) (xy 386.683486 -290.010778) (xy 386.636215 -290.02447)
			(xy 386.58736 -290.030402) (xy 386.538185 -290.028421) (xy 386.489966 -290.018577) (xy 386.44395 -290.001125)
			(xy 386.401329 -289.976518) (xy 386.363208 -289.945393) (xy 386.330573 -289.908556) (xy 386.30427 -289.86696)
			(xy 386.284979 -289.821684) (xy 386.273202 -289.7739) (xy 386.269242 -289.724846) (xy 385.93014 -289.724846)
			(xy 385.929645 -289.749453) (xy 385.92175 -289.79803) (xy 385.906166 -289.844711) (xy 385.883295 -289.888288)
			(xy 385.85373 -289.927632) (xy 385.818237 -289.961724) (xy 385.777734 -289.98968) (xy 385.733272 -290.010778)
			(xy 385.686001 -290.02447) (xy 385.637146 -290.030402) (xy 385.587971 -290.028421) (xy 385.539752 -290.018577)
			(xy 385.493736 -290.001125) (xy 385.451115 -289.976518) (xy 385.412994 -289.945393) (xy 385.380359 -289.908556)
			(xy 385.354056 -289.86696) (xy 385.334765 -289.821684) (xy 385.322988 -289.7739) (xy 385.319028 -289.724846)
			(xy 384.98018 -289.724846) (xy 384.979685 -289.749453) (xy 384.97179 -289.79803) (xy 384.956206 -289.844711)
			(xy 384.933335 -289.888288) (xy 384.90377 -289.927632) (xy 384.868277 -289.961724) (xy 384.827774 -289.98968)
			(xy 384.783312 -290.010778) (xy 384.736041 -290.02447) (xy 384.687186 -290.030402) (xy 384.638011 -290.028421)
			(xy 384.589792 -290.018577) (xy 384.543776 -290.001125) (xy 384.501155 -289.976518) (xy 384.463034 -289.945393)
			(xy 384.430399 -289.908556) (xy 384.404096 -289.86696) (xy 384.384805 -289.821684) (xy 384.373028 -289.7739)
			(xy 384.369068 -289.724846) (xy 380.360637 -289.724846) (xy 380.358889 -289.728354) (xy 380.324916 -289.776305)
			(xy 380.283989 -289.818476) (xy 380.26086 -289.836606) (xy 380.251462 -289.843972) (xy 380.241048 -289.864546)
			(xy 380.239524 -289.968432) (xy 380.24943 -289.989514) (xy 380.258574 -289.99688) (xy 380.280389 -290.015124)
			(xy 380.318933 -290.056934) (xy 380.350844 -290.104001) (xy 380.375417 -290.155284) (xy 380.392107 -290.209645)
			(xy 380.400545 -290.265881) (xy 380.401068 -290.294314) (xy 381.034542 -290.294314) (xy 381.038613 -290.238692)
			(xy 381.050739 -290.184255) (xy 381.070662 -290.132164) (xy 381.097958 -290.083529) (xy 381.132044 -290.039386)
			(xy 381.172193 -290.000677) (xy 381.217551 -289.968226) (xy 381.267151 -289.942725) (xy 381.319935 -289.924718)
			(xy 381.374778 -289.914588) (xy 381.430512 -289.912551) (xy 381.485949 -289.918651) (xy 381.539906 -289.932757)
			(xy 381.591235 -289.954569) (xy 381.638841 -289.983623) (xy 381.681709 -290.019298) (xy 381.718926 -290.060835)
			(xy 381.749699 -290.107348) (xy 381.773371 -290.157845) (xy 381.789439 -290.211252) (xy 381.797559 -290.266428)
			(xy 381.798068 -290.294314) (xy 381.921002 -290.294314) (xy 381.925073 -290.238692) (xy 381.937199 -290.184255)
			(xy 381.957122 -290.132164) (xy 381.984418 -290.083529) (xy 382.018504 -290.039386) (xy 382.058653 -290.000677)
			(xy 382.104011 -289.968226) (xy 382.153611 -289.942725) (xy 382.206395 -289.924718) (xy 382.261238 -289.914588)
			(xy 382.316972 -289.912551) (xy 382.372409 -289.918651) (xy 382.426366 -289.932757) (xy 382.477695 -289.954569)
			(xy 382.525301 -289.983623) (xy 382.568169 -290.019298) (xy 382.605386 -290.060835) (xy 382.636159 -290.107348)
			(xy 382.659831 -290.157845) (xy 382.675899 -290.211252) (xy 382.684019 -290.266428) (xy 382.684528 -290.294314)
			(xy 382.684019 -290.3222) (xy 382.675899 -290.377376) (xy 382.659831 -290.430783) (xy 382.636159 -290.48128)
			(xy 382.605386 -290.527793) (xy 382.568169 -290.56933) (xy 382.525301 -290.605005) (xy 382.477695 -290.634059)
			(xy 382.426366 -290.655871) (xy 382.372409 -290.669977) (xy 382.328523 -290.674806) (xy 384.369068 -290.674806)
			(xy 384.373028 -290.625752) (xy 384.384805 -290.577968) (xy 384.404096 -290.532692) (xy 384.430399 -290.491096)
			(xy 384.463034 -290.454259) (xy 384.501155 -290.423134) (xy 384.543776 -290.398527) (xy 384.589792 -290.381075)
			(xy 384.638011 -290.371231) (xy 384.687186 -290.36925) (xy 384.736041 -290.375182) (xy 384.783312 -290.388874)
			(xy 384.827774 -290.409972) (xy 384.868277 -290.437928) (xy 384.90377 -290.47202) (xy 384.933335 -290.511364)
			(xy 384.956206 -290.554941) (xy 384.97179 -290.601622) (xy 384.979685 -290.650199) (xy 384.98018 -290.674806)
			(xy 385.319028 -290.674806) (xy 385.322988 -290.625752) (xy 385.334765 -290.577968) (xy 385.354056 -290.532692)
			(xy 385.380359 -290.491096) (xy 385.412994 -290.454259) (xy 385.451115 -290.423134) (xy 385.493736 -290.398527)
			(xy 385.539752 -290.381075) (xy 385.587971 -290.371231) (xy 385.637146 -290.36925) (xy 385.686001 -290.375182)
			(xy 385.733272 -290.388874) (xy 385.777734 -290.409972) (xy 385.818237 -290.437928) (xy 385.85373 -290.47202)
			(xy 385.883295 -290.511364) (xy 385.906166 -290.554941) (xy 385.92175 -290.601622) (xy 385.929645 -290.650199)
			(xy 385.93014 -290.674806) (xy 386.269242 -290.674806) (xy 386.273202 -290.625752) (xy 386.284979 -290.577968)
			(xy 386.30427 -290.532692) (xy 386.330573 -290.491096) (xy 386.363208 -290.454259) (xy 386.401329 -290.423134)
			(xy 386.44395 -290.398527) (xy 386.489966 -290.381075) (xy 386.538185 -290.371231) (xy 386.58736 -290.36925)
			(xy 386.636215 -290.375182) (xy 386.683486 -290.388874) (xy 386.727948 -290.409972) (xy 386.768451 -290.437928)
			(xy 386.803944 -290.47202) (xy 386.833509 -290.511364) (xy 386.85638 -290.554941) (xy 386.871964 -290.601622)
			(xy 386.879859 -290.650199) (xy 386.880354 -290.674806) (xy 389.119122 -290.674806) (xy 389.123082 -290.625752)
			(xy 389.134859 -290.577968) (xy 389.15415 -290.532692) (xy 389.180453 -290.491096) (xy 389.213088 -290.454259)
			(xy 389.251209 -290.423134) (xy 389.29383 -290.398527) (xy 389.339846 -290.381075) (xy 389.388065 -290.371231)
			(xy 389.43724 -290.36925) (xy 389.486095 -290.375182) (xy 389.533366 -290.388874) (xy 389.577828 -290.409972)
			(xy 389.618331 -290.437928) (xy 389.653824 -290.47202) (xy 389.683389 -290.511364) (xy 389.70626 -290.554941)
			(xy 389.721844 -290.601622) (xy 389.729739 -290.650199) (xy 389.730234 -290.674806) (xy 390.069082 -290.674806)
			(xy 390.073042 -290.625752) (xy 390.084819 -290.577968) (xy 390.10411 -290.532692) (xy 390.130413 -290.491096)
			(xy 390.163048 -290.454259) (xy 390.201169 -290.423134) (xy 390.24379 -290.398527) (xy 390.289806 -290.381075)
			(xy 390.338025 -290.371231) (xy 390.3872 -290.36925) (xy 390.436055 -290.375182) (xy 390.483326 -290.388874)
			(xy 390.527788 -290.409972) (xy 390.568291 -290.437928) (xy 390.603784 -290.47202) (xy 390.633349 -290.511364)
			(xy 390.65622 -290.554941) (xy 390.671804 -290.601622) (xy 390.679699 -290.650199) (xy 390.680194 -290.674806)
			(xy 391.019042 -290.674806) (xy 391.023002 -290.625752) (xy 391.034779 -290.577968) (xy 391.05407 -290.532692)
			(xy 391.080373 -290.491096) (xy 391.113008 -290.454259) (xy 391.151129 -290.423134) (xy 391.19375 -290.398527)
			(xy 391.239766 -290.381075) (xy 391.287985 -290.371231) (xy 391.33716 -290.36925) (xy 391.386015 -290.375182)
			(xy 391.433286 -290.388874) (xy 391.477748 -290.409972) (xy 391.518251 -290.437928) (xy 391.553744 -290.47202)
			(xy 391.583309 -290.511364) (xy 391.60618 -290.554941) (xy 391.621764 -290.601622) (xy 391.629659 -290.650199)
			(xy 391.630154 -290.674806) (xy 391.969002 -290.674806) (xy 391.972962 -290.625752) (xy 391.984739 -290.577968)
			(xy 392.00403 -290.532692) (xy 392.030333 -290.491096) (xy 392.062968 -290.454259) (xy 392.101089 -290.423134)
			(xy 392.14371 -290.398527) (xy 392.189726 -290.381075) (xy 392.237945 -290.371231) (xy 392.28712 -290.36925)
			(xy 392.335975 -290.375182) (xy 392.383246 -290.388874) (xy 392.427708 -290.409972) (xy 392.468211 -290.437928)
			(xy 392.503704 -290.47202) (xy 392.533269 -290.511364) (xy 392.55614 -290.554941) (xy 392.571724 -290.601622)
			(xy 392.579619 -290.650199) (xy 392.580114 -290.674806) (xy 392.919216 -290.674806) (xy 392.923176 -290.625752)
			(xy 392.934953 -290.577968) (xy 392.954244 -290.532692) (xy 392.980547 -290.491096) (xy 393.013182 -290.454259)
			(xy 393.051303 -290.423134) (xy 393.093924 -290.398527) (xy 393.13994 -290.381075) (xy 393.188159 -290.371231)
			(xy 393.237334 -290.36925) (xy 393.286189 -290.375182) (xy 393.33346 -290.388874) (xy 393.377922 -290.409972)
			(xy 393.418425 -290.437928) (xy 393.453918 -290.47202) (xy 393.483483 -290.511364) (xy 393.506354 -290.554941)
			(xy 393.521938 -290.601622) (xy 393.529833 -290.650199) (xy 393.530328 -290.674806) (xy 393.869176 -290.674806)
			(xy 393.873136 -290.625752) (xy 393.884913 -290.577968) (xy 393.904204 -290.532692) (xy 393.930507 -290.491096)
			(xy 393.963142 -290.454259) (xy 394.001263 -290.423134) (xy 394.043884 -290.398527) (xy 394.0899 -290.381075)
			(xy 394.138119 -290.371231) (xy 394.187294 -290.36925) (xy 394.236149 -290.375182) (xy 394.28342 -290.388874)
			(xy 394.327882 -290.409972) (xy 394.368385 -290.437928) (xy 394.403878 -290.47202) (xy 394.433443 -290.511364)
			(xy 394.456314 -290.554941) (xy 394.471898 -290.601622) (xy 394.479793 -290.650199) (xy 394.480288 -290.674806)
			(xy 394.819136 -290.674806) (xy 394.823096 -290.625752) (xy 394.834873 -290.577968) (xy 394.854164 -290.532692)
			(xy 394.880467 -290.491096) (xy 394.913102 -290.454259) (xy 394.951223 -290.423134) (xy 394.993844 -290.398527)
			(xy 395.03986 -290.381075) (xy 395.088079 -290.371231) (xy 395.137254 -290.36925) (xy 395.186109 -290.375182)
			(xy 395.23338 -290.388874) (xy 395.277842 -290.409972) (xy 395.318345 -290.437928) (xy 395.353838 -290.47202)
			(xy 395.383403 -290.511364) (xy 395.406274 -290.554941) (xy 395.421858 -290.601622) (xy 395.429753 -290.650199)
			(xy 395.430248 -290.674806) (xy 395.769096 -290.674806) (xy 395.773056 -290.625752) (xy 395.784833 -290.577968)
			(xy 395.804124 -290.532692) (xy 395.830427 -290.491096) (xy 395.863062 -290.454259) (xy 395.901183 -290.423134)
			(xy 395.943804 -290.398527) (xy 395.98982 -290.381075) (xy 396.038039 -290.371231) (xy 396.087214 -290.36925)
			(xy 396.136069 -290.375182) (xy 396.18334 -290.388874) (xy 396.227802 -290.409972) (xy 396.268305 -290.437928)
			(xy 396.303798 -290.47202) (xy 396.333363 -290.511364) (xy 396.356234 -290.554941) (xy 396.371818 -290.601622)
			(xy 396.379713 -290.650199) (xy 396.380208 -290.674806) (xy 397.669016 -290.674806) (xy 397.672976 -290.625752)
			(xy 397.684753 -290.577968) (xy 397.704044 -290.532692) (xy 397.730347 -290.491096) (xy 397.762982 -290.454259)
			(xy 397.801103 -290.423134) (xy 397.843724 -290.398527) (xy 397.88974 -290.381075) (xy 397.937959 -290.371231)
			(xy 397.987134 -290.36925) (xy 398.035989 -290.375182) (xy 398.08326 -290.388874) (xy 398.127722 -290.409972)
			(xy 398.168225 -290.437928) (xy 398.203718 -290.47202) (xy 398.233283 -290.511364) (xy 398.256154 -290.554941)
			(xy 398.271738 -290.601622) (xy 398.279633 -290.650199) (xy 398.280128 -290.674806) (xy 398.61923 -290.674806)
			(xy 398.62319 -290.625752) (xy 398.634967 -290.577968) (xy 398.654258 -290.532692) (xy 398.680561 -290.491096)
			(xy 398.713196 -290.454259) (xy 398.751317 -290.423134) (xy 398.793938 -290.398527) (xy 398.839954 -290.381075)
			(xy 398.888173 -290.371231) (xy 398.937348 -290.36925) (xy 398.986203 -290.375182) (xy 399.033474 -290.388874)
			(xy 399.077936 -290.409972) (xy 399.118439 -290.437928) (xy 399.153932 -290.47202) (xy 399.183497 -290.511364)
			(xy 399.206368 -290.554941) (xy 399.221952 -290.601622) (xy 399.229847 -290.650199) (xy 399.230342 -290.674806)
			(xy 399.56919 -290.674806) (xy 399.57315 -290.625752) (xy 399.584927 -290.577968) (xy 399.604218 -290.532692)
			(xy 399.630521 -290.491096) (xy 399.663156 -290.454259) (xy 399.701277 -290.423134) (xy 399.743898 -290.398527)
			(xy 399.789914 -290.381075) (xy 399.838133 -290.371231) (xy 399.887308 -290.36925) (xy 399.936163 -290.375182)
			(xy 399.983434 -290.388874) (xy 400.027896 -290.409972) (xy 400.068399 -290.437928) (xy 400.103892 -290.47202)
			(xy 400.133457 -290.511364) (xy 400.156328 -290.554941) (xy 400.171912 -290.601622) (xy 400.179807 -290.650199)
			(xy 400.180302 -290.674806) (xy 400.51915 -290.674806) (xy 400.52311 -290.625752) (xy 400.534887 -290.577968)
			(xy 400.554178 -290.532692) (xy 400.580481 -290.491096) (xy 400.613116 -290.454259) (xy 400.651237 -290.423134)
			(xy 400.693858 -290.398527) (xy 400.739874 -290.381075) (xy 400.788093 -290.371231) (xy 400.837268 -290.36925)
			(xy 400.886123 -290.375182) (xy 400.933394 -290.388874) (xy 400.977856 -290.409972) (xy 401.018359 -290.437928)
			(xy 401.053852 -290.47202) (xy 401.083417 -290.511364) (xy 401.106288 -290.554941) (xy 401.121872 -290.601622)
			(xy 401.129767 -290.650199) (xy 401.130262 -290.674806) (xy 401.46911 -290.674806) (xy 401.47307 -290.625752)
			(xy 401.484847 -290.577968) (xy 401.504138 -290.532692) (xy 401.530441 -290.491096) (xy 401.563076 -290.454259)
			(xy 401.601197 -290.423134) (xy 401.643818 -290.398527) (xy 401.689834 -290.381075) (xy 401.738053 -290.371231)
			(xy 401.787228 -290.36925) (xy 401.836083 -290.375182) (xy 401.883354 -290.388874) (xy 401.927816 -290.409972)
			(xy 401.968319 -290.437928) (xy 402.003812 -290.47202) (xy 402.033377 -290.511364) (xy 402.056248 -290.554941)
			(xy 402.071832 -290.601622) (xy 402.079727 -290.650199) (xy 402.080222 -290.674806) (xy 402.41907 -290.674806)
			(xy 402.42303 -290.625752) (xy 402.434807 -290.577968) (xy 402.454098 -290.532692) (xy 402.480401 -290.491096)
			(xy 402.513036 -290.454259) (xy 402.551157 -290.423134) (xy 402.593778 -290.398527) (xy 402.639794 -290.381075)
			(xy 402.688013 -290.371231) (xy 402.737188 -290.36925) (xy 402.786043 -290.375182) (xy 402.833314 -290.388874)
			(xy 402.877776 -290.409972) (xy 402.918279 -290.437928) (xy 402.953772 -290.47202) (xy 402.983337 -290.511364)
			(xy 403.006208 -290.554941) (xy 403.021792 -290.601622) (xy 403.029687 -290.650199) (xy 403.030182 -290.674806)
			(xy 403.36903 -290.674806) (xy 403.37299 -290.625752) (xy 403.384767 -290.577968) (xy 403.404058 -290.532692)
			(xy 403.430361 -290.491096) (xy 403.462996 -290.454259) (xy 403.501117 -290.423134) (xy 403.543738 -290.398527)
			(xy 403.589754 -290.381075) (xy 403.637973 -290.371231) (xy 403.687148 -290.36925) (xy 403.736003 -290.375182)
			(xy 403.783274 -290.388874) (xy 403.827736 -290.409972) (xy 403.868239 -290.437928) (xy 403.903732 -290.47202)
			(xy 403.933297 -290.511364) (xy 403.956168 -290.554941) (xy 403.971752 -290.601622) (xy 403.979647 -290.650199)
			(xy 403.980142 -290.674806) (xy 404.31899 -290.674806) (xy 404.32295 -290.625752) (xy 404.334727 -290.577968)
			(xy 404.354018 -290.532692) (xy 404.380321 -290.491096) (xy 404.412956 -290.454259) (xy 404.451077 -290.423134)
			(xy 404.493698 -290.398527) (xy 404.539714 -290.381075) (xy 404.587933 -290.371231) (xy 404.637108 -290.36925)
			(xy 404.685963 -290.375182) (xy 404.733234 -290.388874) (xy 404.777696 -290.409972) (xy 404.818199 -290.437928)
			(xy 404.853692 -290.47202) (xy 404.883257 -290.511364) (xy 404.906128 -290.554941) (xy 404.921712 -290.601622)
			(xy 404.929607 -290.650199) (xy 404.930102 -290.674806) (xy 405.269204 -290.674806) (xy 405.273164 -290.625752)
			(xy 405.284941 -290.577968) (xy 405.304232 -290.532692) (xy 405.330535 -290.491096) (xy 405.36317 -290.454259)
			(xy 405.401291 -290.423134) (xy 405.443912 -290.398527) (xy 405.489928 -290.381075) (xy 405.538147 -290.371231)
			(xy 405.587322 -290.36925) (xy 405.636177 -290.375182) (xy 405.683448 -290.388874) (xy 405.72791 -290.409972)
			(xy 405.768413 -290.437928) (xy 405.803906 -290.47202) (xy 405.833471 -290.511364) (xy 405.856342 -290.554941)
			(xy 405.871926 -290.601622) (xy 405.879821 -290.650199) (xy 405.880316 -290.674806) (xy 406.219164 -290.674806)
			(xy 406.223124 -290.625752) (xy 406.234901 -290.577968) (xy 406.254192 -290.532692) (xy 406.280495 -290.491096)
			(xy 406.31313 -290.454259) (xy 406.351251 -290.423134) (xy 406.393872 -290.398527) (xy 406.439888 -290.381075)
			(xy 406.488107 -290.371231) (xy 406.537282 -290.36925) (xy 406.586137 -290.375182) (xy 406.633408 -290.388874)
			(xy 406.67787 -290.409972) (xy 406.718373 -290.437928) (xy 406.753866 -290.47202) (xy 406.783431 -290.511364)
			(xy 406.806302 -290.554941) (xy 406.821886 -290.601622) (xy 406.829781 -290.650199) (xy 406.830276 -290.674806)
			(xy 408.119084 -290.674806) (xy 408.123044 -290.625752) (xy 408.134821 -290.577968) (xy 408.154112 -290.532692)
			(xy 408.180415 -290.491096) (xy 408.21305 -290.454259) (xy 408.251171 -290.423134) (xy 408.293792 -290.398527)
			(xy 408.339808 -290.381075) (xy 408.388027 -290.371231) (xy 408.437202 -290.36925) (xy 408.486057 -290.375182)
			(xy 408.533328 -290.388874) (xy 408.57779 -290.409972) (xy 408.618293 -290.437928) (xy 408.653786 -290.47202)
			(xy 408.683351 -290.511364) (xy 408.706222 -290.554941) (xy 408.721806 -290.601622) (xy 408.729701 -290.650199)
			(xy 408.730196 -290.674806) (xy 409.069044 -290.674806) (xy 409.073004 -290.625752) (xy 409.084781 -290.577968)
			(xy 409.104072 -290.532692) (xy 409.130375 -290.491096) (xy 409.16301 -290.454259) (xy 409.201131 -290.423134)
			(xy 409.243752 -290.398527) (xy 409.289768 -290.381075) (xy 409.337987 -290.371231) (xy 409.387162 -290.36925)
			(xy 409.436017 -290.375182) (xy 409.483288 -290.388874) (xy 409.52775 -290.409972) (xy 409.568253 -290.437928)
			(xy 409.603746 -290.47202) (xy 409.633311 -290.511364) (xy 409.656182 -290.554941) (xy 409.671766 -290.601622)
			(xy 409.679661 -290.650199) (xy 409.680156 -290.674806) (xy 410.019004 -290.674806) (xy 410.022964 -290.625752)
			(xy 410.034741 -290.577968) (xy 410.054032 -290.532692) (xy 410.080335 -290.491096) (xy 410.11297 -290.454259)
			(xy 410.151091 -290.423134) (xy 410.193712 -290.398527) (xy 410.239728 -290.381075) (xy 410.287947 -290.371231)
			(xy 410.337122 -290.36925) (xy 410.385977 -290.375182) (xy 410.433248 -290.388874) (xy 410.47771 -290.409972)
			(xy 410.518213 -290.437928) (xy 410.553706 -290.47202) (xy 410.583271 -290.511364) (xy 410.606142 -290.554941)
			(xy 410.621726 -290.601622) (xy 410.629621 -290.650199) (xy 410.630116 -290.674806) (xy 410.969218 -290.674806)
			(xy 410.973178 -290.625752) (xy 410.984955 -290.577968) (xy 411.004246 -290.532692) (xy 411.030549 -290.491096)
			(xy 411.063184 -290.454259) (xy 411.101305 -290.423134) (xy 411.143926 -290.398527) (xy 411.189942 -290.381075)
			(xy 411.238161 -290.371231) (xy 411.287336 -290.36925) (xy 411.336191 -290.375182) (xy 411.383462 -290.388874)
			(xy 411.427924 -290.409972) (xy 411.468427 -290.437928) (xy 411.50392 -290.47202) (xy 411.533485 -290.511364)
			(xy 411.556356 -290.554941) (xy 411.57194 -290.601622) (xy 411.579835 -290.650199) (xy 411.58033 -290.674806)
			(xy 411.919178 -290.674806) (xy 411.923138 -290.625752) (xy 411.934915 -290.577968) (xy 411.954206 -290.532692)
			(xy 411.980509 -290.491096) (xy 412.013144 -290.454259) (xy 412.051265 -290.423134) (xy 412.093886 -290.398527)
			(xy 412.139902 -290.381075) (xy 412.188121 -290.371231) (xy 412.237296 -290.36925) (xy 412.286151 -290.375182)
			(xy 412.333422 -290.388874) (xy 412.377884 -290.409972) (xy 412.418387 -290.437928) (xy 412.45388 -290.47202)
			(xy 412.483445 -290.511364) (xy 412.506316 -290.554941) (xy 412.5219 -290.601622) (xy 412.529795 -290.650199)
			(xy 412.53029 -290.674806) (xy 412.869138 -290.674806) (xy 412.873098 -290.625752) (xy 412.884875 -290.577968)
			(xy 412.904166 -290.532692) (xy 412.930469 -290.491096) (xy 412.963104 -290.454259) (xy 413.001225 -290.423134)
			(xy 413.043846 -290.398527) (xy 413.089862 -290.381075) (xy 413.138081 -290.371231) (xy 413.187256 -290.36925)
			(xy 413.236111 -290.375182) (xy 413.283382 -290.388874) (xy 413.327844 -290.409972) (xy 413.368347 -290.437928)
			(xy 413.40384 -290.47202) (xy 413.433405 -290.511364) (xy 413.456276 -290.554941) (xy 413.47186 -290.601622)
			(xy 413.479755 -290.650199) (xy 413.48025 -290.674806) (xy 413.819098 -290.674806) (xy 413.823058 -290.625752)
			(xy 413.834835 -290.577968) (xy 413.854126 -290.532692) (xy 413.880429 -290.491096) (xy 413.913064 -290.454259)
			(xy 413.951185 -290.423134) (xy 413.993806 -290.398527) (xy 414.039822 -290.381075) (xy 414.088041 -290.371231)
			(xy 414.137216 -290.36925) (xy 414.186071 -290.375182) (xy 414.233342 -290.388874) (xy 414.277804 -290.409972)
			(xy 414.318307 -290.437928) (xy 414.3538 -290.47202) (xy 414.383365 -290.511364) (xy 414.406236 -290.554941)
			(xy 414.42182 -290.601622) (xy 414.429715 -290.650199) (xy 414.43021 -290.674806) (xy 414.769058 -290.674806)
			(xy 414.773018 -290.625752) (xy 414.784795 -290.577968) (xy 414.804086 -290.532692) (xy 414.830389 -290.491096)
			(xy 414.863024 -290.454259) (xy 414.901145 -290.423134) (xy 414.943766 -290.398527) (xy 414.989782 -290.381075)
			(xy 415.038001 -290.371231) (xy 415.087176 -290.36925) (xy 415.136031 -290.375182) (xy 415.183302 -290.388874)
			(xy 415.227764 -290.409972) (xy 415.268267 -290.437928) (xy 415.30376 -290.47202) (xy 415.333325 -290.511364)
			(xy 415.356196 -290.554941) (xy 415.37178 -290.601622) (xy 415.379675 -290.650199) (xy 415.38017 -290.674806)
			(xy 415.719018 -290.674806) (xy 415.722978 -290.625752) (xy 415.734755 -290.577968) (xy 415.754046 -290.532692)
			(xy 415.780349 -290.491096) (xy 415.812984 -290.454259) (xy 415.851105 -290.423134) (xy 415.893726 -290.398527)
			(xy 415.939742 -290.381075) (xy 415.987961 -290.371231) (xy 416.037136 -290.36925) (xy 416.085991 -290.375182)
			(xy 416.133262 -290.388874) (xy 416.177724 -290.409972) (xy 416.218227 -290.437928) (xy 416.25372 -290.47202)
			(xy 416.283285 -290.511364) (xy 416.306156 -290.554941) (xy 416.32174 -290.601622) (xy 416.329635 -290.650199)
			(xy 416.33013 -290.674806) (xy 416.668978 -290.674806) (xy 416.672938 -290.625752) (xy 416.684715 -290.577968)
			(xy 416.704006 -290.532692) (xy 416.730309 -290.491096) (xy 416.762944 -290.454259) (xy 416.801065 -290.423134)
			(xy 416.843686 -290.398527) (xy 416.889702 -290.381075) (xy 416.937921 -290.371231) (xy 416.987096 -290.36925)
			(xy 417.035951 -290.375182) (xy 417.083222 -290.388874) (xy 417.127684 -290.409972) (xy 417.168187 -290.437928)
			(xy 417.20368 -290.47202) (xy 417.233245 -290.511364) (xy 417.256116 -290.554941) (xy 417.2717 -290.601622)
			(xy 417.279595 -290.650199) (xy 417.28009 -290.674806) (xy 417.279595 -290.699413) (xy 417.2717 -290.74799)
			(xy 417.256116 -290.794671) (xy 417.233245 -290.838248) (xy 417.20368 -290.877592) (xy 417.168187 -290.911684)
			(xy 417.127684 -290.93964) (xy 417.083222 -290.960738) (xy 417.035951 -290.97443) (xy 416.987096 -290.980362)
			(xy 416.937921 -290.978381) (xy 416.889702 -290.968537) (xy 416.843686 -290.951085) (xy 416.801065 -290.926478)
			(xy 416.762944 -290.895353) (xy 416.730309 -290.858516) (xy 416.704006 -290.81692) (xy 416.684715 -290.771644)
			(xy 416.672938 -290.72386) (xy 416.668978 -290.674806) (xy 416.33013 -290.674806) (xy 416.329635 -290.699413)
			(xy 416.32174 -290.74799) (xy 416.306156 -290.794671) (xy 416.283285 -290.838248) (xy 416.25372 -290.877592)
			(xy 416.218227 -290.911684) (xy 416.177724 -290.93964) (xy 416.133262 -290.960738) (xy 416.085991 -290.97443)
			(xy 416.037136 -290.980362) (xy 415.987961 -290.978381) (xy 415.939742 -290.968537) (xy 415.893726 -290.951085)
			(xy 415.851105 -290.926478) (xy 415.812984 -290.895353) (xy 415.780349 -290.858516) (xy 415.754046 -290.81692)
			(xy 415.734755 -290.771644) (xy 415.722978 -290.72386) (xy 415.719018 -290.674806) (xy 415.38017 -290.674806)
			(xy 415.379675 -290.699413) (xy 415.37178 -290.74799) (xy 415.356196 -290.794671) (xy 415.333325 -290.838248)
			(xy 415.30376 -290.877592) (xy 415.268267 -290.911684) (xy 415.227764 -290.93964) (xy 415.183302 -290.960738)
			(xy 415.136031 -290.97443) (xy 415.087176 -290.980362) (xy 415.038001 -290.978381) (xy 414.989782 -290.968537)
			(xy 414.943766 -290.951085) (xy 414.901145 -290.926478) (xy 414.863024 -290.895353) (xy 414.830389 -290.858516)
			(xy 414.804086 -290.81692) (xy 414.784795 -290.771644) (xy 414.773018 -290.72386) (xy 414.769058 -290.674806)
			(xy 414.43021 -290.674806) (xy 414.429715 -290.699413) (xy 414.42182 -290.74799) (xy 414.406236 -290.794671)
			(xy 414.383365 -290.838248) (xy 414.3538 -290.877592) (xy 414.318307 -290.911684) (xy 414.277804 -290.93964)
			(xy 414.233342 -290.960738) (xy 414.186071 -290.97443) (xy 414.137216 -290.980362) (xy 414.088041 -290.978381)
			(xy 414.039822 -290.968537) (xy 413.993806 -290.951085) (xy 413.951185 -290.926478) (xy 413.913064 -290.895353)
			(xy 413.880429 -290.858516) (xy 413.854126 -290.81692) (xy 413.834835 -290.771644) (xy 413.823058 -290.72386)
			(xy 413.819098 -290.674806) (xy 413.48025 -290.674806) (xy 413.479755 -290.699413) (xy 413.47186 -290.74799)
			(xy 413.456276 -290.794671) (xy 413.433405 -290.838248) (xy 413.40384 -290.877592) (xy 413.368347 -290.911684)
			(xy 413.327844 -290.93964) (xy 413.283382 -290.960738) (xy 413.236111 -290.97443) (xy 413.187256 -290.980362)
			(xy 413.138081 -290.978381) (xy 413.089862 -290.968537) (xy 413.043846 -290.951085) (xy 413.001225 -290.926478)
			(xy 412.963104 -290.895353) (xy 412.930469 -290.858516) (xy 412.904166 -290.81692) (xy 412.884875 -290.771644)
			(xy 412.873098 -290.72386) (xy 412.869138 -290.674806) (xy 412.53029 -290.674806) (xy 412.529795 -290.699413)
			(xy 412.5219 -290.74799) (xy 412.506316 -290.794671) (xy 412.483445 -290.838248) (xy 412.45388 -290.877592)
			(xy 412.418387 -290.911684) (xy 412.377884 -290.93964) (xy 412.333422 -290.960738) (xy 412.286151 -290.97443)
			(xy 412.237296 -290.980362) (xy 412.188121 -290.978381) (xy 412.139902 -290.968537) (xy 412.093886 -290.951085)
			(xy 412.051265 -290.926478) (xy 412.013144 -290.895353) (xy 411.980509 -290.858516) (xy 411.954206 -290.81692)
			(xy 411.934915 -290.771644) (xy 411.923138 -290.72386) (xy 411.919178 -290.674806) (xy 411.58033 -290.674806)
			(xy 411.579835 -290.699413) (xy 411.57194 -290.74799) (xy 411.556356 -290.794671) (xy 411.533485 -290.838248)
			(xy 411.50392 -290.877592) (xy 411.468427 -290.911684) (xy 411.427924 -290.93964) (xy 411.383462 -290.960738)
			(xy 411.336191 -290.97443) (xy 411.287336 -290.980362) (xy 411.238161 -290.978381) (xy 411.189942 -290.968537)
			(xy 411.143926 -290.951085) (xy 411.101305 -290.926478) (xy 411.063184 -290.895353) (xy 411.030549 -290.858516)
			(xy 411.004246 -290.81692) (xy 410.984955 -290.771644) (xy 410.973178 -290.72386) (xy 410.969218 -290.674806)
			(xy 410.630116 -290.674806) (xy 410.629621 -290.699413) (xy 410.621726 -290.74799) (xy 410.606142 -290.794671)
			(xy 410.583271 -290.838248) (xy 410.553706 -290.877592) (xy 410.518213 -290.911684) (xy 410.47771 -290.93964)
			(xy 410.433248 -290.960738) (xy 410.385977 -290.97443) (xy 410.337122 -290.980362) (xy 410.287947 -290.978381)
			(xy 410.239728 -290.968537) (xy 410.193712 -290.951085) (xy 410.151091 -290.926478) (xy 410.11297 -290.895353)
			(xy 410.080335 -290.858516) (xy 410.054032 -290.81692) (xy 410.034741 -290.771644) (xy 410.022964 -290.72386)
			(xy 410.019004 -290.674806) (xy 409.680156 -290.674806) (xy 409.679661 -290.699413) (xy 409.671766 -290.74799)
			(xy 409.656182 -290.794671) (xy 409.633311 -290.838248) (xy 409.603746 -290.877592) (xy 409.568253 -290.911684)
			(xy 409.52775 -290.93964) (xy 409.483288 -290.960738) (xy 409.436017 -290.97443) (xy 409.387162 -290.980362)
			(xy 409.337987 -290.978381) (xy 409.289768 -290.968537) (xy 409.243752 -290.951085) (xy 409.201131 -290.926478)
			(xy 409.16301 -290.895353) (xy 409.130375 -290.858516) (xy 409.104072 -290.81692) (xy 409.084781 -290.771644)
			(xy 409.073004 -290.72386) (xy 409.069044 -290.674806) (xy 408.730196 -290.674806) (xy 408.729701 -290.699413)
			(xy 408.721806 -290.74799) (xy 408.706222 -290.794671) (xy 408.683351 -290.838248) (xy 408.653786 -290.877592)
			(xy 408.618293 -290.911684) (xy 408.57779 -290.93964) (xy 408.533328 -290.960738) (xy 408.486057 -290.97443)
			(xy 408.437202 -290.980362) (xy 408.388027 -290.978381) (xy 408.339808 -290.968537) (xy 408.293792 -290.951085)
			(xy 408.251171 -290.926478) (xy 408.21305 -290.895353) (xy 408.180415 -290.858516) (xy 408.154112 -290.81692)
			(xy 408.134821 -290.771644) (xy 408.123044 -290.72386) (xy 408.119084 -290.674806) (xy 406.830276 -290.674806)
			(xy 406.829781 -290.699413) (xy 406.821886 -290.74799) (xy 406.806302 -290.794671) (xy 406.783431 -290.838248)
			(xy 406.753866 -290.877592) (xy 406.718373 -290.911684) (xy 406.67787 -290.93964) (xy 406.633408 -290.960738)
			(xy 406.586137 -290.97443) (xy 406.537282 -290.980362) (xy 406.488107 -290.978381) (xy 406.439888 -290.968537)
			(xy 406.393872 -290.951085) (xy 406.351251 -290.926478) (xy 406.31313 -290.895353) (xy 406.280495 -290.858516)
			(xy 406.254192 -290.81692) (xy 406.234901 -290.771644) (xy 406.223124 -290.72386) (xy 406.219164 -290.674806)
			(xy 405.880316 -290.674806) (xy 405.879821 -290.699413) (xy 405.871926 -290.74799) (xy 405.856342 -290.794671)
			(xy 405.833471 -290.838248) (xy 405.803906 -290.877592) (xy 405.768413 -290.911684) (xy 405.72791 -290.93964)
			(xy 405.683448 -290.960738) (xy 405.636177 -290.97443) (xy 405.587322 -290.980362) (xy 405.538147 -290.978381)
			(xy 405.489928 -290.968537) (xy 405.443912 -290.951085) (xy 405.401291 -290.926478) (xy 405.36317 -290.895353)
			(xy 405.330535 -290.858516) (xy 405.304232 -290.81692) (xy 405.284941 -290.771644) (xy 405.273164 -290.72386)
			(xy 405.269204 -290.674806) (xy 404.930102 -290.674806) (xy 404.929607 -290.699413) (xy 404.921712 -290.74799)
			(xy 404.906128 -290.794671) (xy 404.883257 -290.838248) (xy 404.853692 -290.877592) (xy 404.818199 -290.911684)
			(xy 404.777696 -290.93964) (xy 404.733234 -290.960738) (xy 404.685963 -290.97443) (xy 404.637108 -290.980362)
			(xy 404.587933 -290.978381) (xy 404.539714 -290.968537) (xy 404.493698 -290.951085) (xy 404.451077 -290.926478)
			(xy 404.412956 -290.895353) (xy 404.380321 -290.858516) (xy 404.354018 -290.81692) (xy 404.334727 -290.771644)
			(xy 404.32295 -290.72386) (xy 404.31899 -290.674806) (xy 403.980142 -290.674806) (xy 403.979647 -290.699413)
			(xy 403.971752 -290.74799) (xy 403.956168 -290.794671) (xy 403.933297 -290.838248) (xy 403.903732 -290.877592)
			(xy 403.868239 -290.911684) (xy 403.827736 -290.93964) (xy 403.783274 -290.960738) (xy 403.736003 -290.97443)
			(xy 403.687148 -290.980362) (xy 403.637973 -290.978381) (xy 403.589754 -290.968537) (xy 403.543738 -290.951085)
			(xy 403.501117 -290.926478) (xy 403.462996 -290.895353) (xy 403.430361 -290.858516) (xy 403.404058 -290.81692)
			(xy 403.384767 -290.771644) (xy 403.37299 -290.72386) (xy 403.36903 -290.674806) (xy 403.030182 -290.674806)
			(xy 403.029687 -290.699413) (xy 403.021792 -290.74799) (xy 403.006208 -290.794671) (xy 402.983337 -290.838248)
			(xy 402.953772 -290.877592) (xy 402.918279 -290.911684) (xy 402.877776 -290.93964) (xy 402.833314 -290.960738)
			(xy 402.786043 -290.97443) (xy 402.737188 -290.980362) (xy 402.688013 -290.978381) (xy 402.639794 -290.968537)
			(xy 402.593778 -290.951085) (xy 402.551157 -290.926478) (xy 402.513036 -290.895353) (xy 402.480401 -290.858516)
			(xy 402.454098 -290.81692) (xy 402.434807 -290.771644) (xy 402.42303 -290.72386) (xy 402.41907 -290.674806)
			(xy 402.080222 -290.674806) (xy 402.079727 -290.699413) (xy 402.071832 -290.74799) (xy 402.056248 -290.794671)
			(xy 402.033377 -290.838248) (xy 402.003812 -290.877592) (xy 401.968319 -290.911684) (xy 401.927816 -290.93964)
			(xy 401.883354 -290.960738) (xy 401.836083 -290.97443) (xy 401.787228 -290.980362) (xy 401.738053 -290.978381)
			(xy 401.689834 -290.968537) (xy 401.643818 -290.951085) (xy 401.601197 -290.926478) (xy 401.563076 -290.895353)
			(xy 401.530441 -290.858516) (xy 401.504138 -290.81692) (xy 401.484847 -290.771644) (xy 401.47307 -290.72386)
			(xy 401.46911 -290.674806) (xy 401.130262 -290.674806) (xy 401.129767 -290.699413) (xy 401.121872 -290.74799)
			(xy 401.106288 -290.794671) (xy 401.083417 -290.838248) (xy 401.053852 -290.877592) (xy 401.018359 -290.911684)
			(xy 400.977856 -290.93964) (xy 400.933394 -290.960738) (xy 400.886123 -290.97443) (xy 400.837268 -290.980362)
			(xy 400.788093 -290.978381) (xy 400.739874 -290.968537) (xy 400.693858 -290.951085) (xy 400.651237 -290.926478)
			(xy 400.613116 -290.895353) (xy 400.580481 -290.858516) (xy 400.554178 -290.81692) (xy 400.534887 -290.771644)
			(xy 400.52311 -290.72386) (xy 400.51915 -290.674806) (xy 400.180302 -290.674806) (xy 400.179807 -290.699413)
			(xy 400.171912 -290.74799) (xy 400.156328 -290.794671) (xy 400.133457 -290.838248) (xy 400.103892 -290.877592)
			(xy 400.068399 -290.911684) (xy 400.027896 -290.93964) (xy 399.983434 -290.960738) (xy 399.936163 -290.97443)
			(xy 399.887308 -290.980362) (xy 399.838133 -290.978381) (xy 399.789914 -290.968537) (xy 399.743898 -290.951085)
			(xy 399.701277 -290.926478) (xy 399.663156 -290.895353) (xy 399.630521 -290.858516) (xy 399.604218 -290.81692)
			(xy 399.584927 -290.771644) (xy 399.57315 -290.72386) (xy 399.56919 -290.674806) (xy 399.230342 -290.674806)
			(xy 399.229847 -290.699413) (xy 399.221952 -290.74799) (xy 399.206368 -290.794671) (xy 399.183497 -290.838248)
			(xy 399.153932 -290.877592) (xy 399.118439 -290.911684) (xy 399.077936 -290.93964) (xy 399.033474 -290.960738)
			(xy 398.986203 -290.97443) (xy 398.937348 -290.980362) (xy 398.888173 -290.978381) (xy 398.839954 -290.968537)
			(xy 398.793938 -290.951085) (xy 398.751317 -290.926478) (xy 398.713196 -290.895353) (xy 398.680561 -290.858516)
			(xy 398.654258 -290.81692) (xy 398.634967 -290.771644) (xy 398.62319 -290.72386) (xy 398.61923 -290.674806)
			(xy 398.280128 -290.674806) (xy 398.279633 -290.699413) (xy 398.271738 -290.74799) (xy 398.256154 -290.794671)
			(xy 398.233283 -290.838248) (xy 398.203718 -290.877592) (xy 398.168225 -290.911684) (xy 398.127722 -290.93964)
			(xy 398.08326 -290.960738) (xy 398.035989 -290.97443) (xy 397.987134 -290.980362) (xy 397.937959 -290.978381)
			(xy 397.88974 -290.968537) (xy 397.843724 -290.951085) (xy 397.801103 -290.926478) (xy 397.762982 -290.895353)
			(xy 397.730347 -290.858516) (xy 397.704044 -290.81692) (xy 397.684753 -290.771644) (xy 397.672976 -290.72386)
			(xy 397.669016 -290.674806) (xy 396.380208 -290.674806) (xy 396.379713 -290.699413) (xy 396.371818 -290.74799)
			(xy 396.356234 -290.794671) (xy 396.333363 -290.838248) (xy 396.303798 -290.877592) (xy 396.268305 -290.911684)
			(xy 396.227802 -290.93964) (xy 396.18334 -290.960738) (xy 396.136069 -290.97443) (xy 396.087214 -290.980362)
			(xy 396.038039 -290.978381) (xy 395.98982 -290.968537) (xy 395.943804 -290.951085) (xy 395.901183 -290.926478)
			(xy 395.863062 -290.895353) (xy 395.830427 -290.858516) (xy 395.804124 -290.81692) (xy 395.784833 -290.771644)
			(xy 395.773056 -290.72386) (xy 395.769096 -290.674806) (xy 395.430248 -290.674806) (xy 395.429753 -290.699413)
			(xy 395.421858 -290.74799) (xy 395.406274 -290.794671) (xy 395.383403 -290.838248) (xy 395.353838 -290.877592)
			(xy 395.318345 -290.911684) (xy 395.277842 -290.93964) (xy 395.23338 -290.960738) (xy 395.186109 -290.97443)
			(xy 395.137254 -290.980362) (xy 395.088079 -290.978381) (xy 395.03986 -290.968537) (xy 394.993844 -290.951085)
			(xy 394.951223 -290.926478) (xy 394.913102 -290.895353) (xy 394.880467 -290.858516) (xy 394.854164 -290.81692)
			(xy 394.834873 -290.771644) (xy 394.823096 -290.72386) (xy 394.819136 -290.674806) (xy 394.480288 -290.674806)
			(xy 394.479793 -290.699413) (xy 394.471898 -290.74799) (xy 394.456314 -290.794671) (xy 394.433443 -290.838248)
			(xy 394.403878 -290.877592) (xy 394.368385 -290.911684) (xy 394.327882 -290.93964) (xy 394.28342 -290.960738)
			(xy 394.236149 -290.97443) (xy 394.187294 -290.980362) (xy 394.138119 -290.978381) (xy 394.0899 -290.968537)
			(xy 394.043884 -290.951085) (xy 394.001263 -290.926478) (xy 393.963142 -290.895353) (xy 393.930507 -290.858516)
			(xy 393.904204 -290.81692) (xy 393.884913 -290.771644) (xy 393.873136 -290.72386) (xy 393.869176 -290.674806)
			(xy 393.530328 -290.674806) (xy 393.529833 -290.699413) (xy 393.521938 -290.74799) (xy 393.506354 -290.794671)
			(xy 393.483483 -290.838248) (xy 393.453918 -290.877592) (xy 393.418425 -290.911684) (xy 393.377922 -290.93964)
			(xy 393.33346 -290.960738) (xy 393.286189 -290.97443) (xy 393.237334 -290.980362) (xy 393.188159 -290.978381)
			(xy 393.13994 -290.968537) (xy 393.093924 -290.951085) (xy 393.051303 -290.926478) (xy 393.013182 -290.895353)
			(xy 392.980547 -290.858516) (xy 392.954244 -290.81692) (xy 392.934953 -290.771644) (xy 392.923176 -290.72386)
			(xy 392.919216 -290.674806) (xy 392.580114 -290.674806) (xy 392.579619 -290.699413) (xy 392.571724 -290.74799)
			(xy 392.55614 -290.794671) (xy 392.533269 -290.838248) (xy 392.503704 -290.877592) (xy 392.468211 -290.911684)
			(xy 392.427708 -290.93964) (xy 392.383246 -290.960738) (xy 392.335975 -290.97443) (xy 392.28712 -290.980362)
			(xy 392.237945 -290.978381) (xy 392.189726 -290.968537) (xy 392.14371 -290.951085) (xy 392.101089 -290.926478)
			(xy 392.062968 -290.895353) (xy 392.030333 -290.858516) (xy 392.00403 -290.81692) (xy 391.984739 -290.771644)
			(xy 391.972962 -290.72386) (xy 391.969002 -290.674806) (xy 391.630154 -290.674806) (xy 391.629659 -290.699413)
			(xy 391.621764 -290.74799) (xy 391.60618 -290.794671) (xy 391.583309 -290.838248) (xy 391.553744 -290.877592)
			(xy 391.518251 -290.911684) (xy 391.477748 -290.93964) (xy 391.433286 -290.960738) (xy 391.386015 -290.97443)
			(xy 391.33716 -290.980362) (xy 391.287985 -290.978381) (xy 391.239766 -290.968537) (xy 391.19375 -290.951085)
			(xy 391.151129 -290.926478) (xy 391.113008 -290.895353) (xy 391.080373 -290.858516) (xy 391.05407 -290.81692)
			(xy 391.034779 -290.771644) (xy 391.023002 -290.72386) (xy 391.019042 -290.674806) (xy 390.680194 -290.674806)
			(xy 390.679699 -290.699413) (xy 390.671804 -290.74799) (xy 390.65622 -290.794671) (xy 390.633349 -290.838248)
			(xy 390.603784 -290.877592) (xy 390.568291 -290.911684) (xy 390.527788 -290.93964) (xy 390.483326 -290.960738)
			(xy 390.436055 -290.97443) (xy 390.3872 -290.980362) (xy 390.338025 -290.978381) (xy 390.289806 -290.968537)
			(xy 390.24379 -290.951085) (xy 390.201169 -290.926478) (xy 390.163048 -290.895353) (xy 390.130413 -290.858516)
			(xy 390.10411 -290.81692) (xy 390.084819 -290.771644) (xy 390.073042 -290.72386) (xy 390.069082 -290.674806)
			(xy 389.730234 -290.674806) (xy 389.729739 -290.699413) (xy 389.721844 -290.74799) (xy 389.70626 -290.794671)
			(xy 389.683389 -290.838248) (xy 389.653824 -290.877592) (xy 389.618331 -290.911684) (xy 389.577828 -290.93964)
			(xy 389.533366 -290.960738) (xy 389.486095 -290.97443) (xy 389.43724 -290.980362) (xy 389.388065 -290.978381)
			(xy 389.339846 -290.968537) (xy 389.29383 -290.951085) (xy 389.251209 -290.926478) (xy 389.213088 -290.895353)
			(xy 389.180453 -290.858516) (xy 389.15415 -290.81692) (xy 389.134859 -290.771644) (xy 389.123082 -290.72386)
			(xy 389.119122 -290.674806) (xy 386.880354 -290.674806) (xy 386.879859 -290.699413) (xy 386.871964 -290.74799)
			(xy 386.85638 -290.794671) (xy 386.833509 -290.838248) (xy 386.803944 -290.877592) (xy 386.768451 -290.911684)
			(xy 386.727948 -290.93964) (xy 386.683486 -290.960738) (xy 386.636215 -290.97443) (xy 386.58736 -290.980362)
			(xy 386.538185 -290.978381) (xy 386.489966 -290.968537) (xy 386.44395 -290.951085) (xy 386.401329 -290.926478)
			(xy 386.363208 -290.895353) (xy 386.330573 -290.858516) (xy 386.30427 -290.81692) (xy 386.284979 -290.771644)
			(xy 386.273202 -290.72386) (xy 386.269242 -290.674806) (xy 385.93014 -290.674806) (xy 385.929645 -290.699413)
			(xy 385.92175 -290.74799) (xy 385.906166 -290.794671) (xy 385.883295 -290.838248) (xy 385.85373 -290.877592)
			(xy 385.818237 -290.911684) (xy 385.777734 -290.93964) (xy 385.733272 -290.960738) (xy 385.686001 -290.97443)
			(xy 385.637146 -290.980362) (xy 385.587971 -290.978381) (xy 385.539752 -290.968537) (xy 385.493736 -290.951085)
			(xy 385.451115 -290.926478) (xy 385.412994 -290.895353) (xy 385.380359 -290.858516) (xy 385.354056 -290.81692)
			(xy 385.334765 -290.771644) (xy 385.322988 -290.72386) (xy 385.319028 -290.674806) (xy 384.98018 -290.674806)
			(xy 384.979685 -290.699413) (xy 384.97179 -290.74799) (xy 384.956206 -290.794671) (xy 384.933335 -290.838248)
			(xy 384.90377 -290.877592) (xy 384.868277 -290.911684) (xy 384.827774 -290.93964) (xy 384.783312 -290.960738)
			(xy 384.736041 -290.97443) (xy 384.687186 -290.980362) (xy 384.638011 -290.978381) (xy 384.589792 -290.968537)
			(xy 384.543776 -290.951085) (xy 384.501155 -290.926478) (xy 384.463034 -290.895353) (xy 384.430399 -290.858516)
			(xy 384.404096 -290.81692) (xy 384.384805 -290.771644) (xy 384.373028 -290.72386) (xy 384.369068 -290.674806)
			(xy 382.328523 -290.674806) (xy 382.316972 -290.676077) (xy 382.261238 -290.67404) (xy 382.206395 -290.66391)
			(xy 382.153611 -290.645903) (xy 382.104011 -290.620402) (xy 382.058653 -290.587951) (xy 382.018504 -290.549242)
			(xy 381.984418 -290.505099) (xy 381.957122 -290.456464) (xy 381.937199 -290.404373) (xy 381.925073 -290.349936)
			(xy 381.921002 -290.294314) (xy 381.798068 -290.294314) (xy 381.797559 -290.3222) (xy 381.789439 -290.377376)
			(xy 381.773371 -290.430783) (xy 381.749699 -290.48128) (xy 381.718926 -290.527793) (xy 381.681709 -290.56933)
			(xy 381.638841 -290.605005) (xy 381.591235 -290.634059) (xy 381.539906 -290.655871) (xy 381.485949 -290.669977)
			(xy 381.430512 -290.676077) (xy 381.374778 -290.67404) (xy 381.319935 -290.66391) (xy 381.267151 -290.645903)
			(xy 381.217551 -290.620402) (xy 381.172193 -290.587951) (xy 381.132044 -290.549242) (xy 381.097958 -290.505099)
			(xy 381.070662 -290.456464) (xy 381.050739 -290.404373) (xy 381.038613 -290.349936) (xy 381.034542 -290.294314)
			(xy 380.401068 -290.294314) (xy 380.400582 -290.321565) (xy 380.392826 -290.375513) (xy 380.377471 -290.427808)
			(xy 380.354829 -290.477385) (xy 380.325363 -290.523235) (xy 380.289672 -290.564426) (xy 380.248481 -290.600117)
			(xy 380.202631 -290.629583) (xy 380.153054 -290.652225) (xy 380.100759 -290.66758) (xy 380.046811 -290.675336)
			(xy 379.992309 -290.675336) (xy 379.938361 -290.66758) (xy 379.886066 -290.652225) (xy 379.836489 -290.629583)
			(xy 379.790639 -290.600117) (xy 379.749448 -290.564426) (xy 379.713757 -290.523235) (xy 379.684291 -290.477385)
			(xy 379.661649 -290.427808) (xy 379.646294 -290.375513) (xy 379.638538 -290.321565) (xy 379.638052 -290.294314)
			(xy 368.55019 -290.294314) (xy 368.55019 -291.430456) (xy 374.111518 -291.430456) (xy 374.115589 -291.374834)
			(xy 374.127715 -291.320397) (xy 374.147638 -291.268306) (xy 374.174934 -291.219671) (xy 374.20902 -291.175528)
			(xy 374.249169 -291.136819) (xy 374.294527 -291.104368) (xy 374.344127 -291.078867) (xy 374.396911 -291.06086)
			(xy 374.451754 -291.05073) (xy 374.507488 -291.048693) (xy 374.562925 -291.054793) (xy 374.616882 -291.068899)
			(xy 374.668211 -291.090711) (xy 374.715817 -291.119765) (xy 374.758685 -291.15544) (xy 374.795902 -291.196977)
			(xy 374.826675 -291.24349) (xy 374.850347 -291.293987) (xy 374.866415 -291.347394) (xy 374.874535 -291.40257)
			(xy 374.875044 -291.430456) (xy 375.596656 -291.430456) (xy 375.600727 -291.374834) (xy 375.612853 -291.320397)
			(xy 375.632776 -291.268306) (xy 375.660072 -291.219671) (xy 375.694158 -291.175528) (xy 375.734307 -291.136819)
			(xy 375.779665 -291.104368) (xy 375.829265 -291.078867) (xy 375.882049 -291.06086) (xy 375.936892 -291.05073)
			(xy 375.992626 -291.048693) (xy 376.048063 -291.054793) (xy 376.10202 -291.068899) (xy 376.153349 -291.090711)
			(xy 376.200955 -291.119765) (xy 376.243823 -291.15544) (xy 376.28104 -291.196977) (xy 376.311813 -291.24349)
			(xy 376.335485 -291.293987) (xy 376.351553 -291.347394) (xy 376.359673 -291.40257) (xy 376.360182 -291.430456)
			(xy 376.359673 -291.458342) (xy 376.351553 -291.513518) (xy 376.335485 -291.566925) (xy 376.311813 -291.617422)
			(xy 376.306954 -291.624766) (xy 384.369068 -291.624766) (xy 384.373028 -291.575712) (xy 384.384805 -291.527928)
			(xy 384.404096 -291.482652) (xy 384.430399 -291.441056) (xy 384.463034 -291.404219) (xy 384.501155 -291.373094)
			(xy 384.543776 -291.348487) (xy 384.589792 -291.331035) (xy 384.638011 -291.321191) (xy 384.687186 -291.31921)
			(xy 384.736041 -291.325142) (xy 384.783312 -291.338834) (xy 384.827774 -291.359932) (xy 384.868277 -291.387888)
			(xy 384.90377 -291.42198) (xy 384.933335 -291.461324) (xy 384.956206 -291.504901) (xy 384.97179 -291.551582)
			(xy 384.979685 -291.600159) (xy 384.98018 -291.624766) (xy 385.319028 -291.624766) (xy 385.322988 -291.575712)
			(xy 385.334765 -291.527928) (xy 385.354056 -291.482652) (xy 385.380359 -291.441056) (xy 385.412994 -291.404219)
			(xy 385.451115 -291.373094) (xy 385.493736 -291.348487) (xy 385.539752 -291.331035) (xy 385.587971 -291.321191)
			(xy 385.637146 -291.31921) (xy 385.686001 -291.325142) (xy 385.733272 -291.338834) (xy 385.777734 -291.359932)
			(xy 385.818237 -291.387888) (xy 385.85373 -291.42198) (xy 385.883295 -291.461324) (xy 385.906166 -291.504901)
			(xy 385.92175 -291.551582) (xy 385.929645 -291.600159) (xy 385.93014 -291.624766) (xy 386.269242 -291.624766)
			(xy 386.273202 -291.575712) (xy 386.284979 -291.527928) (xy 386.30427 -291.482652) (xy 386.330573 -291.441056)
			(xy 386.363208 -291.404219) (xy 386.401329 -291.373094) (xy 386.44395 -291.348487) (xy 386.489966 -291.331035)
			(xy 386.538185 -291.321191) (xy 386.58736 -291.31921) (xy 386.636215 -291.325142) (xy 386.683486 -291.338834)
			(xy 386.727948 -291.359932) (xy 386.768451 -291.387888) (xy 386.803944 -291.42198) (xy 386.833509 -291.461324)
			(xy 386.85638 -291.504901) (xy 386.871964 -291.551582) (xy 386.879859 -291.600159) (xy 386.880354 -291.624766)
			(xy 389.119122 -291.624766) (xy 389.123082 -291.575712) (xy 389.134859 -291.527928) (xy 389.15415 -291.482652)
			(xy 389.180453 -291.441056) (xy 389.213088 -291.404219) (xy 389.251209 -291.373094) (xy 389.29383 -291.348487)
			(xy 389.339846 -291.331035) (xy 389.388065 -291.321191) (xy 389.43724 -291.31921) (xy 389.486095 -291.325142)
			(xy 389.533366 -291.338834) (xy 389.577828 -291.359932) (xy 389.618331 -291.387888) (xy 389.653824 -291.42198)
			(xy 389.683389 -291.461324) (xy 389.70626 -291.504901) (xy 389.721844 -291.551582) (xy 389.729739 -291.600159)
			(xy 389.730234 -291.624766) (xy 390.069082 -291.624766) (xy 390.073042 -291.575712) (xy 390.084819 -291.527928)
			(xy 390.10411 -291.482652) (xy 390.130413 -291.441056) (xy 390.163048 -291.404219) (xy 390.201169 -291.373094)
			(xy 390.24379 -291.348487) (xy 390.289806 -291.331035) (xy 390.338025 -291.321191) (xy 390.3872 -291.31921)
			(xy 390.436055 -291.325142) (xy 390.483326 -291.338834) (xy 390.527788 -291.359932) (xy 390.568291 -291.387888)
			(xy 390.603784 -291.42198) (xy 390.633349 -291.461324) (xy 390.65622 -291.504901) (xy 390.671804 -291.551582)
			(xy 390.679699 -291.600159) (xy 390.680194 -291.624766) (xy 391.019042 -291.624766) (xy 391.023002 -291.575712)
			(xy 391.034779 -291.527928) (xy 391.05407 -291.482652) (xy 391.080373 -291.441056) (xy 391.113008 -291.404219)
			(xy 391.151129 -291.373094) (xy 391.19375 -291.348487) (xy 391.239766 -291.331035) (xy 391.287985 -291.321191)
			(xy 391.33716 -291.31921) (xy 391.386015 -291.325142) (xy 391.433286 -291.338834) (xy 391.477748 -291.359932)
			(xy 391.518251 -291.387888) (xy 391.553744 -291.42198) (xy 391.583309 -291.461324) (xy 391.60618 -291.504901)
			(xy 391.621764 -291.551582) (xy 391.629659 -291.600159) (xy 391.630154 -291.624766) (xy 391.969002 -291.624766)
			(xy 391.972962 -291.575712) (xy 391.984739 -291.527928) (xy 392.00403 -291.482652) (xy 392.030333 -291.441056)
			(xy 392.062968 -291.404219) (xy 392.101089 -291.373094) (xy 392.14371 -291.348487) (xy 392.189726 -291.331035)
			(xy 392.237945 -291.321191) (xy 392.28712 -291.31921) (xy 392.335975 -291.325142) (xy 392.383246 -291.338834)
			(xy 392.427708 -291.359932) (xy 392.468211 -291.387888) (xy 392.503704 -291.42198) (xy 392.533269 -291.461324)
			(xy 392.55614 -291.504901) (xy 392.571724 -291.551582) (xy 392.579619 -291.600159) (xy 392.580114 -291.624766)
			(xy 392.919216 -291.624766) (xy 392.923176 -291.575712) (xy 392.934953 -291.527928) (xy 392.954244 -291.482652)
			(xy 392.980547 -291.441056) (xy 393.013182 -291.404219) (xy 393.051303 -291.373094) (xy 393.093924 -291.348487)
			(xy 393.13994 -291.331035) (xy 393.188159 -291.321191) (xy 393.237334 -291.31921) (xy 393.286189 -291.325142)
			(xy 393.33346 -291.338834) (xy 393.377922 -291.359932) (xy 393.418425 -291.387888) (xy 393.453918 -291.42198)
			(xy 393.483483 -291.461324) (xy 393.506354 -291.504901) (xy 393.521938 -291.551582) (xy 393.529833 -291.600159)
			(xy 393.530328 -291.624766) (xy 393.869176 -291.624766) (xy 393.873136 -291.575712) (xy 393.884913 -291.527928)
			(xy 393.904204 -291.482652) (xy 393.930507 -291.441056) (xy 393.963142 -291.404219) (xy 394.001263 -291.373094)
			(xy 394.043884 -291.348487) (xy 394.0899 -291.331035) (xy 394.138119 -291.321191) (xy 394.187294 -291.31921)
			(xy 394.236149 -291.325142) (xy 394.28342 -291.338834) (xy 394.327882 -291.359932) (xy 394.368385 -291.387888)
			(xy 394.403878 -291.42198) (xy 394.433443 -291.461324) (xy 394.456314 -291.504901) (xy 394.471898 -291.551582)
			(xy 394.479793 -291.600159) (xy 394.480288 -291.624766) (xy 395.769096 -291.624766) (xy 395.773056 -291.575712)
			(xy 395.784833 -291.527928) (xy 395.804124 -291.482652) (xy 395.830427 -291.441056) (xy 395.863062 -291.404219)
			(xy 395.901183 -291.373094) (xy 395.943804 -291.348487) (xy 395.98982 -291.331035) (xy 396.038039 -291.321191)
			(xy 396.087214 -291.31921) (xy 396.136069 -291.325142) (xy 396.18334 -291.338834) (xy 396.227802 -291.359932)
			(xy 396.268305 -291.387888) (xy 396.303798 -291.42198) (xy 396.333363 -291.461324) (xy 396.356234 -291.504901)
			(xy 396.371818 -291.551582) (xy 396.379713 -291.600159) (xy 396.380208 -291.624766) (xy 396.719056 -291.624766)
			(xy 396.723016 -291.575712) (xy 396.734793 -291.527928) (xy 396.754084 -291.482652) (xy 396.780387 -291.441056)
			(xy 396.813022 -291.404219) (xy 396.851143 -291.373094) (xy 396.893764 -291.348487) (xy 396.93978 -291.331035)
			(xy 396.987999 -291.321191) (xy 397.037174 -291.31921) (xy 397.086029 -291.325142) (xy 397.1333 -291.338834)
			(xy 397.177762 -291.359932) (xy 397.218265 -291.387888) (xy 397.253758 -291.42198) (xy 397.283323 -291.461324)
			(xy 397.306194 -291.504901) (xy 397.321778 -291.551582) (xy 397.329673 -291.600159) (xy 397.330168 -291.624766)
			(xy 398.61923 -291.624766) (xy 398.62319 -291.575712) (xy 398.634967 -291.527928) (xy 398.654258 -291.482652)
			(xy 398.680561 -291.441056) (xy 398.713196 -291.404219) (xy 398.751317 -291.373094) (xy 398.793938 -291.348487)
			(xy 398.839954 -291.331035) (xy 398.888173 -291.321191) (xy 398.937348 -291.31921) (xy 398.986203 -291.325142)
			(xy 399.033474 -291.338834) (xy 399.077936 -291.359932) (xy 399.118439 -291.387888) (xy 399.153932 -291.42198)
			(xy 399.183497 -291.461324) (xy 399.206368 -291.504901) (xy 399.221952 -291.551582) (xy 399.229847 -291.600159)
			(xy 399.230342 -291.624766) (xy 399.56919 -291.624766) (xy 399.57315 -291.575712) (xy 399.584927 -291.527928)
			(xy 399.604218 -291.482652) (xy 399.630521 -291.441056) (xy 399.663156 -291.404219) (xy 399.701277 -291.373094)
			(xy 399.743898 -291.348487) (xy 399.789914 -291.331035) (xy 399.838133 -291.321191) (xy 399.887308 -291.31921)
			(xy 399.936163 -291.325142) (xy 399.983434 -291.338834) (xy 400.027896 -291.359932) (xy 400.068399 -291.387888)
			(xy 400.103892 -291.42198) (xy 400.133457 -291.461324) (xy 400.156328 -291.504901) (xy 400.171912 -291.551582)
			(xy 400.179807 -291.600159) (xy 400.180302 -291.624766) (xy 400.51915 -291.624766) (xy 400.52311 -291.575712)
			(xy 400.534887 -291.527928) (xy 400.554178 -291.482652) (xy 400.580481 -291.441056) (xy 400.613116 -291.404219)
			(xy 400.651237 -291.373094) (xy 400.693858 -291.348487) (xy 400.739874 -291.331035) (xy 400.788093 -291.321191)
			(xy 400.837268 -291.31921) (xy 400.886123 -291.325142) (xy 400.933394 -291.338834) (xy 400.977856 -291.359932)
			(xy 401.018359 -291.387888) (xy 401.053852 -291.42198) (xy 401.083417 -291.461324) (xy 401.106288 -291.504901)
			(xy 401.121872 -291.551582) (xy 401.129767 -291.600159) (xy 401.130262 -291.624766) (xy 401.46911 -291.624766)
			(xy 401.47307 -291.575712) (xy 401.484847 -291.527928) (xy 401.504138 -291.482652) (xy 401.530441 -291.441056)
			(xy 401.563076 -291.404219) (xy 401.601197 -291.373094) (xy 401.643818 -291.348487) (xy 401.689834 -291.331035)
			(xy 401.738053 -291.321191) (xy 401.787228 -291.31921) (xy 401.836083 -291.325142) (xy 401.883354 -291.338834)
			(xy 401.927816 -291.359932) (xy 401.968319 -291.387888) (xy 402.003812 -291.42198) (xy 402.033377 -291.461324)
			(xy 402.056248 -291.504901) (xy 402.071832 -291.551582) (xy 402.079727 -291.600159) (xy 402.080222 -291.624766)
			(xy 402.41907 -291.624766) (xy 402.42303 -291.575712) (xy 402.434807 -291.527928) (xy 402.454098 -291.482652)
			(xy 402.480401 -291.441056) (xy 402.513036 -291.404219) (xy 402.551157 -291.373094) (xy 402.593778 -291.348487)
			(xy 402.639794 -291.331035) (xy 402.688013 -291.321191) (xy 402.737188 -291.31921) (xy 402.786043 -291.325142)
			(xy 402.833314 -291.338834) (xy 402.877776 -291.359932) (xy 402.918279 -291.387888) (xy 402.953772 -291.42198)
			(xy 402.983337 -291.461324) (xy 403.006208 -291.504901) (xy 403.021792 -291.551582) (xy 403.029687 -291.600159)
			(xy 403.030182 -291.624766) (xy 403.36903 -291.624766) (xy 403.37299 -291.575712) (xy 403.384767 -291.527928)
			(xy 403.404058 -291.482652) (xy 403.430361 -291.441056) (xy 403.462996 -291.404219) (xy 403.501117 -291.373094)
			(xy 403.543738 -291.348487) (xy 403.589754 -291.331035) (xy 403.637973 -291.321191) (xy 403.687148 -291.31921)
			(xy 403.736003 -291.325142) (xy 403.783274 -291.338834) (xy 403.827736 -291.359932) (xy 403.868239 -291.387888)
			(xy 403.903732 -291.42198) (xy 403.933297 -291.461324) (xy 403.956168 -291.504901) (xy 403.971752 -291.551582)
			(xy 403.979647 -291.600159) (xy 403.980142 -291.624766) (xy 404.31899 -291.624766) (xy 404.32295 -291.575712)
			(xy 404.334727 -291.527928) (xy 404.354018 -291.482652) (xy 404.380321 -291.441056) (xy 404.412956 -291.404219)
			(xy 404.451077 -291.373094) (xy 404.493698 -291.348487) (xy 404.539714 -291.331035) (xy 404.587933 -291.321191)
			(xy 404.637108 -291.31921) (xy 404.685963 -291.325142) (xy 404.733234 -291.338834) (xy 404.777696 -291.359932)
			(xy 404.818199 -291.387888) (xy 404.853692 -291.42198) (xy 404.883257 -291.461324) (xy 404.906128 -291.504901)
			(xy 404.921712 -291.551582) (xy 404.929607 -291.600159) (xy 404.930102 -291.624766) (xy 405.269204 -291.624766)
			(xy 405.273164 -291.575712) (xy 405.284941 -291.527928) (xy 405.304232 -291.482652) (xy 405.330535 -291.441056)
			(xy 405.36317 -291.404219) (xy 405.401291 -291.373094) (xy 405.443912 -291.348487) (xy 405.489928 -291.331035)
			(xy 405.538147 -291.321191) (xy 405.587322 -291.31921) (xy 405.636177 -291.325142) (xy 405.683448 -291.338834)
			(xy 405.72791 -291.359932) (xy 405.768413 -291.387888) (xy 405.803906 -291.42198) (xy 405.833471 -291.461324)
			(xy 405.856342 -291.504901) (xy 405.871926 -291.551582) (xy 405.879821 -291.600159) (xy 405.880316 -291.624766)
			(xy 406.219164 -291.624766) (xy 406.223124 -291.575712) (xy 406.234901 -291.527928) (xy 406.254192 -291.482652)
			(xy 406.280495 -291.441056) (xy 406.31313 -291.404219) (xy 406.351251 -291.373094) (xy 406.393872 -291.348487)
			(xy 406.439888 -291.331035) (xy 406.488107 -291.321191) (xy 406.537282 -291.31921) (xy 406.586137 -291.325142)
			(xy 406.633408 -291.338834) (xy 406.67787 -291.359932) (xy 406.718373 -291.387888) (xy 406.753866 -291.42198)
			(xy 406.783431 -291.461324) (xy 406.806302 -291.504901) (xy 406.821886 -291.551582) (xy 406.829781 -291.600159)
			(xy 406.830276 -291.624766) (xy 408.119084 -291.624766) (xy 408.123044 -291.575712) (xy 408.134821 -291.527928)
			(xy 408.154112 -291.482652) (xy 408.180415 -291.441056) (xy 408.21305 -291.404219) (xy 408.251171 -291.373094)
			(xy 408.293792 -291.348487) (xy 408.339808 -291.331035) (xy 408.388027 -291.321191) (xy 408.437202 -291.31921)
			(xy 408.486057 -291.325142) (xy 408.533328 -291.338834) (xy 408.57779 -291.359932) (xy 408.618293 -291.387888)
			(xy 408.653786 -291.42198) (xy 408.683351 -291.461324) (xy 408.706222 -291.504901) (xy 408.721806 -291.551582)
			(xy 408.729701 -291.600159) (xy 408.730196 -291.624766) (xy 409.069044 -291.624766) (xy 409.073004 -291.575712)
			(xy 409.084781 -291.527928) (xy 409.104072 -291.482652) (xy 409.130375 -291.441056) (xy 409.16301 -291.404219)
			(xy 409.201131 -291.373094) (xy 409.243752 -291.348487) (xy 409.289768 -291.331035) (xy 409.337987 -291.321191)
			(xy 409.387162 -291.31921) (xy 409.436017 -291.325142) (xy 409.483288 -291.338834) (xy 409.52775 -291.359932)
			(xy 409.568253 -291.387888) (xy 409.603746 -291.42198) (xy 409.633311 -291.461324) (xy 409.656182 -291.504901)
			(xy 409.671766 -291.551582) (xy 409.679661 -291.600159) (xy 409.680156 -291.624766) (xy 410.019004 -291.624766)
			(xy 410.022964 -291.575712) (xy 410.034741 -291.527928) (xy 410.054032 -291.482652) (xy 410.080335 -291.441056)
			(xy 410.11297 -291.404219) (xy 410.151091 -291.373094) (xy 410.193712 -291.348487) (xy 410.239728 -291.331035)
			(xy 410.287947 -291.321191) (xy 410.337122 -291.31921) (xy 410.385977 -291.325142) (xy 410.433248 -291.338834)
			(xy 410.47771 -291.359932) (xy 410.518213 -291.387888) (xy 410.553706 -291.42198) (xy 410.583271 -291.461324)
			(xy 410.606142 -291.504901) (xy 410.621726 -291.551582) (xy 410.629621 -291.600159) (xy 410.630116 -291.624766)
			(xy 410.969218 -291.624766) (xy 410.973178 -291.575712) (xy 410.984955 -291.527928) (xy 411.004246 -291.482652)
			(xy 411.030549 -291.441056) (xy 411.063184 -291.404219) (xy 411.101305 -291.373094) (xy 411.143926 -291.348487)
			(xy 411.189942 -291.331035) (xy 411.238161 -291.321191) (xy 411.287336 -291.31921) (xy 411.336191 -291.325142)
			(xy 411.383462 -291.338834) (xy 411.427924 -291.359932) (xy 411.468427 -291.387888) (xy 411.50392 -291.42198)
			(xy 411.533485 -291.461324) (xy 411.556356 -291.504901) (xy 411.57194 -291.551582) (xy 411.579835 -291.600159)
			(xy 411.58033 -291.624766) (xy 411.919178 -291.624766) (xy 411.923138 -291.575712) (xy 411.934915 -291.527928)
			(xy 411.954206 -291.482652) (xy 411.980509 -291.441056) (xy 412.013144 -291.404219) (xy 412.051265 -291.373094)
			(xy 412.093886 -291.348487) (xy 412.139902 -291.331035) (xy 412.188121 -291.321191) (xy 412.237296 -291.31921)
			(xy 412.286151 -291.325142) (xy 412.333422 -291.338834) (xy 412.377884 -291.359932) (xy 412.418387 -291.387888)
			(xy 412.45388 -291.42198) (xy 412.483445 -291.461324) (xy 412.506316 -291.504901) (xy 412.5219 -291.551582)
			(xy 412.529795 -291.600159) (xy 412.53029 -291.624766) (xy 412.869138 -291.624766) (xy 412.873098 -291.575712)
			(xy 412.884875 -291.527928) (xy 412.904166 -291.482652) (xy 412.930469 -291.441056) (xy 412.963104 -291.404219)
			(xy 413.001225 -291.373094) (xy 413.043846 -291.348487) (xy 413.089862 -291.331035) (xy 413.138081 -291.321191)
			(xy 413.187256 -291.31921) (xy 413.236111 -291.325142) (xy 413.283382 -291.338834) (xy 413.327844 -291.359932)
			(xy 413.368347 -291.387888) (xy 413.40384 -291.42198) (xy 413.433405 -291.461324) (xy 413.456276 -291.504901)
			(xy 413.47186 -291.551582) (xy 413.479755 -291.600159) (xy 413.48025 -291.624766) (xy 413.819098 -291.624766)
			(xy 413.823058 -291.575712) (xy 413.834835 -291.527928) (xy 413.854126 -291.482652) (xy 413.880429 -291.441056)
			(xy 413.913064 -291.404219) (xy 413.951185 -291.373094) (xy 413.993806 -291.348487) (xy 414.039822 -291.331035)
			(xy 414.088041 -291.321191) (xy 414.137216 -291.31921) (xy 414.186071 -291.325142) (xy 414.233342 -291.338834)
			(xy 414.277804 -291.359932) (xy 414.318307 -291.387888) (xy 414.3538 -291.42198) (xy 414.383365 -291.461324)
			(xy 414.406236 -291.504901) (xy 414.42182 -291.551582) (xy 414.429715 -291.600159) (xy 414.43021 -291.624766)
			(xy 414.769058 -291.624766) (xy 414.773018 -291.575712) (xy 414.784795 -291.527928) (xy 414.804086 -291.482652)
			(xy 414.830389 -291.441056) (xy 414.863024 -291.404219) (xy 414.901145 -291.373094) (xy 414.943766 -291.348487)
			(xy 414.989782 -291.331035) (xy 415.038001 -291.321191) (xy 415.087176 -291.31921) (xy 415.136031 -291.325142)
			(xy 415.183302 -291.338834) (xy 415.227764 -291.359932) (xy 415.268267 -291.387888) (xy 415.30376 -291.42198)
			(xy 415.333325 -291.461324) (xy 415.356196 -291.504901) (xy 415.37178 -291.551582) (xy 415.379675 -291.600159)
			(xy 415.38017 -291.624766) (xy 415.719018 -291.624766) (xy 415.722978 -291.575712) (xy 415.734755 -291.527928)
			(xy 415.754046 -291.482652) (xy 415.780349 -291.441056) (xy 415.812984 -291.404219) (xy 415.851105 -291.373094)
			(xy 415.893726 -291.348487) (xy 415.939742 -291.331035) (xy 415.987961 -291.321191) (xy 416.037136 -291.31921)
			(xy 416.085991 -291.325142) (xy 416.133262 -291.338834) (xy 416.177724 -291.359932) (xy 416.218227 -291.387888)
			(xy 416.25372 -291.42198) (xy 416.283285 -291.461324) (xy 416.306156 -291.504901) (xy 416.32174 -291.551582)
			(xy 416.329635 -291.600159) (xy 416.33013 -291.624766) (xy 416.668978 -291.624766) (xy 416.672938 -291.575712)
			(xy 416.684715 -291.527928) (xy 416.704006 -291.482652) (xy 416.730309 -291.441056) (xy 416.762944 -291.404219)
			(xy 416.801065 -291.373094) (xy 416.843686 -291.348487) (xy 416.889702 -291.331035) (xy 416.937921 -291.321191)
			(xy 416.987096 -291.31921) (xy 417.035951 -291.325142) (xy 417.083222 -291.338834) (xy 417.127684 -291.359932)
			(xy 417.168187 -291.387888) (xy 417.20368 -291.42198) (xy 417.233245 -291.461324) (xy 417.256116 -291.504901)
			(xy 417.2717 -291.551582) (xy 417.279595 -291.600159) (xy 417.28009 -291.624766) (xy 417.279595 -291.649373)
			(xy 417.2717 -291.69795) (xy 417.256116 -291.744631) (xy 417.233245 -291.788208) (xy 417.20368 -291.827552)
			(xy 417.168187 -291.861644) (xy 417.127684 -291.8896) (xy 417.083222 -291.910698) (xy 417.035951 -291.92439)
			(xy 416.987096 -291.930322) (xy 416.937921 -291.928341) (xy 416.889702 -291.918497) (xy 416.843686 -291.901045)
			(xy 416.801065 -291.876438) (xy 416.762944 -291.845313) (xy 416.730309 -291.808476) (xy 416.704006 -291.76688)
			(xy 416.684715 -291.721604) (xy 416.672938 -291.67382) (xy 416.668978 -291.624766) (xy 416.33013 -291.624766)
			(xy 416.329635 -291.649373) (xy 416.32174 -291.69795) (xy 416.306156 -291.744631) (xy 416.283285 -291.788208)
			(xy 416.25372 -291.827552) (xy 416.218227 -291.861644) (xy 416.177724 -291.8896) (xy 416.133262 -291.910698)
			(xy 416.085991 -291.92439) (xy 416.037136 -291.930322) (xy 415.987961 -291.928341) (xy 415.939742 -291.918497)
			(xy 415.893726 -291.901045) (xy 415.851105 -291.876438) (xy 415.812984 -291.845313) (xy 415.780349 -291.808476)
			(xy 415.754046 -291.76688) (xy 415.734755 -291.721604) (xy 415.722978 -291.67382) (xy 415.719018 -291.624766)
			(xy 415.38017 -291.624766) (xy 415.379675 -291.649373) (xy 415.37178 -291.69795) (xy 415.356196 -291.744631)
			(xy 415.333325 -291.788208) (xy 415.30376 -291.827552) (xy 415.268267 -291.861644) (xy 415.227764 -291.8896)
			(xy 415.183302 -291.910698) (xy 415.136031 -291.92439) (xy 415.087176 -291.930322) (xy 415.038001 -291.928341)
			(xy 414.989782 -291.918497) (xy 414.943766 -291.901045) (xy 414.901145 -291.876438) (xy 414.863024 -291.845313)
			(xy 414.830389 -291.808476) (xy 414.804086 -291.76688) (xy 414.784795 -291.721604) (xy 414.773018 -291.67382)
			(xy 414.769058 -291.624766) (xy 414.43021 -291.624766) (xy 414.429715 -291.649373) (xy 414.42182 -291.69795)
			(xy 414.406236 -291.744631) (xy 414.383365 -291.788208) (xy 414.3538 -291.827552) (xy 414.318307 -291.861644)
			(xy 414.277804 -291.8896) (xy 414.233342 -291.910698) (xy 414.186071 -291.92439) (xy 414.137216 -291.930322)
			(xy 414.088041 -291.928341) (xy 414.039822 -291.918497) (xy 413.993806 -291.901045) (xy 413.951185 -291.876438)
			(xy 413.913064 -291.845313) (xy 413.880429 -291.808476) (xy 413.854126 -291.76688) (xy 413.834835 -291.721604)
			(xy 413.823058 -291.67382) (xy 413.819098 -291.624766) (xy 413.48025 -291.624766) (xy 413.479755 -291.649373)
			(xy 413.47186 -291.69795) (xy 413.456276 -291.744631) (xy 413.433405 -291.788208) (xy 413.40384 -291.827552)
			(xy 413.368347 -291.861644) (xy 413.327844 -291.8896) (xy 413.283382 -291.910698) (xy 413.236111 -291.92439)
			(xy 413.187256 -291.930322) (xy 413.138081 -291.928341) (xy 413.089862 -291.918497) (xy 413.043846 -291.901045)
			(xy 413.001225 -291.876438) (xy 412.963104 -291.845313) (xy 412.930469 -291.808476) (xy 412.904166 -291.76688)
			(xy 412.884875 -291.721604) (xy 412.873098 -291.67382) (xy 412.869138 -291.624766) (xy 412.53029 -291.624766)
			(xy 412.529795 -291.649373) (xy 412.5219 -291.69795) (xy 412.506316 -291.744631) (xy 412.483445 -291.788208)
			(xy 412.45388 -291.827552) (xy 412.418387 -291.861644) (xy 412.377884 -291.8896) (xy 412.333422 -291.910698)
			(xy 412.286151 -291.92439) (xy 412.237296 -291.930322) (xy 412.188121 -291.928341) (xy 412.139902 -291.918497)
			(xy 412.093886 -291.901045) (xy 412.051265 -291.876438) (xy 412.013144 -291.845313) (xy 411.980509 -291.808476)
			(xy 411.954206 -291.76688) (xy 411.934915 -291.721604) (xy 411.923138 -291.67382) (xy 411.919178 -291.624766)
			(xy 411.58033 -291.624766) (xy 411.579835 -291.649373) (xy 411.57194 -291.69795) (xy 411.556356 -291.744631)
			(xy 411.533485 -291.788208) (xy 411.50392 -291.827552) (xy 411.468427 -291.861644) (xy 411.427924 -291.8896)
			(xy 411.383462 -291.910698) (xy 411.336191 -291.92439) (xy 411.287336 -291.930322) (xy 411.238161 -291.928341)
			(xy 411.189942 -291.918497) (xy 411.143926 -291.901045) (xy 411.101305 -291.876438) (xy 411.063184 -291.845313)
			(xy 411.030549 -291.808476) (xy 411.004246 -291.76688) (xy 410.984955 -291.721604) (xy 410.973178 -291.67382)
			(xy 410.969218 -291.624766) (xy 410.630116 -291.624766) (xy 410.629621 -291.649373) (xy 410.621726 -291.69795)
			(xy 410.606142 -291.744631) (xy 410.583271 -291.788208) (xy 410.553706 -291.827552) (xy 410.518213 -291.861644)
			(xy 410.47771 -291.8896) (xy 410.433248 -291.910698) (xy 410.385977 -291.92439) (xy 410.337122 -291.930322)
			(xy 410.287947 -291.928341) (xy 410.239728 -291.918497) (xy 410.193712 -291.901045) (xy 410.151091 -291.876438)
			(xy 410.11297 -291.845313) (xy 410.080335 -291.808476) (xy 410.054032 -291.76688) (xy 410.034741 -291.721604)
			(xy 410.022964 -291.67382) (xy 410.019004 -291.624766) (xy 409.680156 -291.624766) (xy 409.679661 -291.649373)
			(xy 409.671766 -291.69795) (xy 409.656182 -291.744631) (xy 409.633311 -291.788208) (xy 409.603746 -291.827552)
			(xy 409.568253 -291.861644) (xy 409.52775 -291.8896) (xy 409.483288 -291.910698) (xy 409.436017 -291.92439)
			(xy 409.387162 -291.930322) (xy 409.337987 -291.928341) (xy 409.289768 -291.918497) (xy 409.243752 -291.901045)
			(xy 409.201131 -291.876438) (xy 409.16301 -291.845313) (xy 409.130375 -291.808476) (xy 409.104072 -291.76688)
			(xy 409.084781 -291.721604) (xy 409.073004 -291.67382) (xy 409.069044 -291.624766) (xy 408.730196 -291.624766)
			(xy 408.729701 -291.649373) (xy 408.721806 -291.69795) (xy 408.706222 -291.744631) (xy 408.683351 -291.788208)
			(xy 408.653786 -291.827552) (xy 408.618293 -291.861644) (xy 408.57779 -291.8896) (xy 408.533328 -291.910698)
			(xy 408.486057 -291.92439) (xy 408.437202 -291.930322) (xy 408.388027 -291.928341) (xy 408.339808 -291.918497)
			(xy 408.293792 -291.901045) (xy 408.251171 -291.876438) (xy 408.21305 -291.845313) (xy 408.180415 -291.808476)
			(xy 408.154112 -291.76688) (xy 408.134821 -291.721604) (xy 408.123044 -291.67382) (xy 408.119084 -291.624766)
			(xy 406.830276 -291.624766) (xy 406.829781 -291.649373) (xy 406.821886 -291.69795) (xy 406.806302 -291.744631)
			(xy 406.783431 -291.788208) (xy 406.753866 -291.827552) (xy 406.718373 -291.861644) (xy 406.67787 -291.8896)
			(xy 406.633408 -291.910698) (xy 406.586137 -291.92439) (xy 406.537282 -291.930322) (xy 406.488107 -291.928341)
			(xy 406.439888 -291.918497) (xy 406.393872 -291.901045) (xy 406.351251 -291.876438) (xy 406.31313 -291.845313)
			(xy 406.280495 -291.808476) (xy 406.254192 -291.76688) (xy 406.234901 -291.721604) (xy 406.223124 -291.67382)
			(xy 406.219164 -291.624766) (xy 405.880316 -291.624766) (xy 405.879821 -291.649373) (xy 405.871926 -291.69795)
			(xy 405.856342 -291.744631) (xy 405.833471 -291.788208) (xy 405.803906 -291.827552) (xy 405.768413 -291.861644)
			(xy 405.72791 -291.8896) (xy 405.683448 -291.910698) (xy 405.636177 -291.92439) (xy 405.587322 -291.930322)
			(xy 405.538147 -291.928341) (xy 405.489928 -291.918497) (xy 405.443912 -291.901045) (xy 405.401291 -291.876438)
			(xy 405.36317 -291.845313) (xy 405.330535 -291.808476) (xy 405.304232 -291.76688) (xy 405.284941 -291.721604)
			(xy 405.273164 -291.67382) (xy 405.269204 -291.624766) (xy 404.930102 -291.624766) (xy 404.929607 -291.649373)
			(xy 404.921712 -291.69795) (xy 404.906128 -291.744631) (xy 404.883257 -291.788208) (xy 404.853692 -291.827552)
			(xy 404.818199 -291.861644) (xy 404.777696 -291.8896) (xy 404.733234 -291.910698) (xy 404.685963 -291.92439)
			(xy 404.637108 -291.930322) (xy 404.587933 -291.928341) (xy 404.539714 -291.918497) (xy 404.493698 -291.901045)
			(xy 404.451077 -291.876438) (xy 404.412956 -291.845313) (xy 404.380321 -291.808476) (xy 404.354018 -291.76688)
			(xy 404.334727 -291.721604) (xy 404.32295 -291.67382) (xy 404.31899 -291.624766) (xy 403.980142 -291.624766)
			(xy 403.979647 -291.649373) (xy 403.971752 -291.69795) (xy 403.956168 -291.744631) (xy 403.933297 -291.788208)
			(xy 403.903732 -291.827552) (xy 403.868239 -291.861644) (xy 403.827736 -291.8896) (xy 403.783274 -291.910698)
			(xy 403.736003 -291.92439) (xy 403.687148 -291.930322) (xy 403.637973 -291.928341) (xy 403.589754 -291.918497)
			(xy 403.543738 -291.901045) (xy 403.501117 -291.876438) (xy 403.462996 -291.845313) (xy 403.430361 -291.808476)
			(xy 403.404058 -291.76688) (xy 403.384767 -291.721604) (xy 403.37299 -291.67382) (xy 403.36903 -291.624766)
			(xy 403.030182 -291.624766) (xy 403.029687 -291.649373) (xy 403.021792 -291.69795) (xy 403.006208 -291.744631)
			(xy 402.983337 -291.788208) (xy 402.953772 -291.827552) (xy 402.918279 -291.861644) (xy 402.877776 -291.8896)
			(xy 402.833314 -291.910698) (xy 402.786043 -291.92439) (xy 402.737188 -291.930322) (xy 402.688013 -291.928341)
			(xy 402.639794 -291.918497) (xy 402.593778 -291.901045) (xy 402.551157 -291.876438) (xy 402.513036 -291.845313)
			(xy 402.480401 -291.808476) (xy 402.454098 -291.76688) (xy 402.434807 -291.721604) (xy 402.42303 -291.67382)
			(xy 402.41907 -291.624766) (xy 402.080222 -291.624766) (xy 402.079727 -291.649373) (xy 402.071832 -291.69795)
			(xy 402.056248 -291.744631) (xy 402.033377 -291.788208) (xy 402.003812 -291.827552) (xy 401.968319 -291.861644)
			(xy 401.927816 -291.8896) (xy 401.883354 -291.910698) (xy 401.836083 -291.92439) (xy 401.787228 -291.930322)
			(xy 401.738053 -291.928341) (xy 401.689834 -291.918497) (xy 401.643818 -291.901045) (xy 401.601197 -291.876438)
			(xy 401.563076 -291.845313) (xy 401.530441 -291.808476) (xy 401.504138 -291.76688) (xy 401.484847 -291.721604)
			(xy 401.47307 -291.67382) (xy 401.46911 -291.624766) (xy 401.130262 -291.624766) (xy 401.129767 -291.649373)
			(xy 401.121872 -291.69795) (xy 401.106288 -291.744631) (xy 401.083417 -291.788208) (xy 401.053852 -291.827552)
			(xy 401.018359 -291.861644) (xy 400.977856 -291.8896) (xy 400.933394 -291.910698) (xy 400.886123 -291.92439)
			(xy 400.837268 -291.930322) (xy 400.788093 -291.928341) (xy 400.739874 -291.918497) (xy 400.693858 -291.901045)
			(xy 400.651237 -291.876438) (xy 400.613116 -291.845313) (xy 400.580481 -291.808476) (xy 400.554178 -291.76688)
			(xy 400.534887 -291.721604) (xy 400.52311 -291.67382) (xy 400.51915 -291.624766) (xy 400.180302 -291.624766)
			(xy 400.179807 -291.649373) (xy 400.171912 -291.69795) (xy 400.156328 -291.744631) (xy 400.133457 -291.788208)
			(xy 400.103892 -291.827552) (xy 400.068399 -291.861644) (xy 400.027896 -291.8896) (xy 399.983434 -291.910698)
			(xy 399.936163 -291.92439) (xy 399.887308 -291.930322) (xy 399.838133 -291.928341) (xy 399.789914 -291.918497)
			(xy 399.743898 -291.901045) (xy 399.701277 -291.876438) (xy 399.663156 -291.845313) (xy 399.630521 -291.808476)
			(xy 399.604218 -291.76688) (xy 399.584927 -291.721604) (xy 399.57315 -291.67382) (xy 399.56919 -291.624766)
			(xy 399.230342 -291.624766) (xy 399.229847 -291.649373) (xy 399.221952 -291.69795) (xy 399.206368 -291.744631)
			(xy 399.183497 -291.788208) (xy 399.153932 -291.827552) (xy 399.118439 -291.861644) (xy 399.077936 -291.8896)
			(xy 399.033474 -291.910698) (xy 398.986203 -291.92439) (xy 398.937348 -291.930322) (xy 398.888173 -291.928341)
			(xy 398.839954 -291.918497) (xy 398.793938 -291.901045) (xy 398.751317 -291.876438) (xy 398.713196 -291.845313)
			(xy 398.680561 -291.808476) (xy 398.654258 -291.76688) (xy 398.634967 -291.721604) (xy 398.62319 -291.67382)
			(xy 398.61923 -291.624766) (xy 397.330168 -291.624766) (xy 397.329673 -291.649373) (xy 397.321778 -291.69795)
			(xy 397.306194 -291.744631) (xy 397.283323 -291.788208) (xy 397.253758 -291.827552) (xy 397.218265 -291.861644)
			(xy 397.177762 -291.8896) (xy 397.1333 -291.910698) (xy 397.086029 -291.92439) (xy 397.037174 -291.930322)
			(xy 396.987999 -291.928341) (xy 396.93978 -291.918497) (xy 396.893764 -291.901045) (xy 396.851143 -291.876438)
			(xy 396.813022 -291.845313) (xy 396.780387 -291.808476) (xy 396.754084 -291.76688) (xy 396.734793 -291.721604)
			(xy 396.723016 -291.67382) (xy 396.719056 -291.624766) (xy 396.380208 -291.624766) (xy 396.379713 -291.649373)
			(xy 396.371818 -291.69795) (xy 396.356234 -291.744631) (xy 396.333363 -291.788208) (xy 396.303798 -291.827552)
			(xy 396.268305 -291.861644) (xy 396.227802 -291.8896) (xy 396.18334 -291.910698) (xy 396.136069 -291.92439)
			(xy 396.087214 -291.930322) (xy 396.038039 -291.928341) (xy 395.98982 -291.918497) (xy 395.943804 -291.901045)
			(xy 395.901183 -291.876438) (xy 395.863062 -291.845313) (xy 395.830427 -291.808476) (xy 395.804124 -291.76688)
			(xy 395.784833 -291.721604) (xy 395.773056 -291.67382) (xy 395.769096 -291.624766) (xy 394.480288 -291.624766)
			(xy 394.479793 -291.649373) (xy 394.471898 -291.69795) (xy 394.456314 -291.744631) (xy 394.433443 -291.788208)
			(xy 394.403878 -291.827552) (xy 394.368385 -291.861644) (xy 394.327882 -291.8896) (xy 394.28342 -291.910698)
			(xy 394.236149 -291.92439) (xy 394.187294 -291.930322) (xy 394.138119 -291.928341) (xy 394.0899 -291.918497)
			(xy 394.043884 -291.901045) (xy 394.001263 -291.876438) (xy 393.963142 -291.845313) (xy 393.930507 -291.808476)
			(xy 393.904204 -291.76688) (xy 393.884913 -291.721604) (xy 393.873136 -291.67382) (xy 393.869176 -291.624766)
			(xy 393.530328 -291.624766) (xy 393.529833 -291.649373) (xy 393.521938 -291.69795) (xy 393.506354 -291.744631)
			(xy 393.483483 -291.788208) (xy 393.453918 -291.827552) (xy 393.418425 -291.861644) (xy 393.377922 -291.8896)
			(xy 393.33346 -291.910698) (xy 393.286189 -291.92439) (xy 393.237334 -291.930322) (xy 393.188159 -291.928341)
			(xy 393.13994 -291.918497) (xy 393.093924 -291.901045) (xy 393.051303 -291.876438) (xy 393.013182 -291.845313)
			(xy 392.980547 -291.808476) (xy 392.954244 -291.76688) (xy 392.934953 -291.721604) (xy 392.923176 -291.67382)
			(xy 392.919216 -291.624766) (xy 392.580114 -291.624766) (xy 392.579619 -291.649373) (xy 392.571724 -291.69795)
			(xy 392.55614 -291.744631) (xy 392.533269 -291.788208) (xy 392.503704 -291.827552) (xy 392.468211 -291.861644)
			(xy 392.427708 -291.8896) (xy 392.383246 -291.910698) (xy 392.335975 -291.92439) (xy 392.28712 -291.930322)
			(xy 392.237945 -291.928341) (xy 392.189726 -291.918497) (xy 392.14371 -291.901045) (xy 392.101089 -291.876438)
			(xy 392.062968 -291.845313) (xy 392.030333 -291.808476) (xy 392.00403 -291.76688) (xy 391.984739 -291.721604)
			(xy 391.972962 -291.67382) (xy 391.969002 -291.624766) (xy 391.630154 -291.624766) (xy 391.629659 -291.649373)
			(xy 391.621764 -291.69795) (xy 391.60618 -291.744631) (xy 391.583309 -291.788208) (xy 391.553744 -291.827552)
			(xy 391.518251 -291.861644) (xy 391.477748 -291.8896) (xy 391.433286 -291.910698) (xy 391.386015 -291.92439)
			(xy 391.33716 -291.930322) (xy 391.287985 -291.928341) (xy 391.239766 -291.918497) (xy 391.19375 -291.901045)
			(xy 391.151129 -291.876438) (xy 391.113008 -291.845313) (xy 391.080373 -291.808476) (xy 391.05407 -291.76688)
			(xy 391.034779 -291.721604) (xy 391.023002 -291.67382) (xy 391.019042 -291.624766) (xy 390.680194 -291.624766)
			(xy 390.679699 -291.649373) (xy 390.671804 -291.69795) (xy 390.65622 -291.744631) (xy 390.633349 -291.788208)
			(xy 390.603784 -291.827552) (xy 390.568291 -291.861644) (xy 390.527788 -291.8896) (xy 390.483326 -291.910698)
			(xy 390.436055 -291.92439) (xy 390.3872 -291.930322) (xy 390.338025 -291.928341) (xy 390.289806 -291.918497)
			(xy 390.24379 -291.901045) (xy 390.201169 -291.876438) (xy 390.163048 -291.845313) (xy 390.130413 -291.808476)
			(xy 390.10411 -291.76688) (xy 390.084819 -291.721604) (xy 390.073042 -291.67382) (xy 390.069082 -291.624766)
			(xy 389.730234 -291.624766) (xy 389.729739 -291.649373) (xy 389.721844 -291.69795) (xy 389.70626 -291.744631)
			(xy 389.683389 -291.788208) (xy 389.653824 -291.827552) (xy 389.618331 -291.861644) (xy 389.577828 -291.8896)
			(xy 389.533366 -291.910698) (xy 389.486095 -291.92439) (xy 389.43724 -291.930322) (xy 389.388065 -291.928341)
			(xy 389.339846 -291.918497) (xy 389.29383 -291.901045) (xy 389.251209 -291.876438) (xy 389.213088 -291.845313)
			(xy 389.180453 -291.808476) (xy 389.15415 -291.76688) (xy 389.134859 -291.721604) (xy 389.123082 -291.67382)
			(xy 389.119122 -291.624766) (xy 386.880354 -291.624766) (xy 386.879859 -291.649373) (xy 386.871964 -291.69795)
			(xy 386.85638 -291.744631) (xy 386.833509 -291.788208) (xy 386.803944 -291.827552) (xy 386.768451 -291.861644)
			(xy 386.727948 -291.8896) (xy 386.683486 -291.910698) (xy 386.636215 -291.92439) (xy 386.58736 -291.930322)
			(xy 386.538185 -291.928341) (xy 386.489966 -291.918497) (xy 386.44395 -291.901045) (xy 386.401329 -291.876438)
			(xy 386.363208 -291.845313) (xy 386.330573 -291.808476) (xy 386.30427 -291.76688) (xy 386.284979 -291.721604)
			(xy 386.273202 -291.67382) (xy 386.269242 -291.624766) (xy 385.93014 -291.624766) (xy 385.929645 -291.649373)
			(xy 385.92175 -291.69795) (xy 385.906166 -291.744631) (xy 385.883295 -291.788208) (xy 385.85373 -291.827552)
			(xy 385.818237 -291.861644) (xy 385.777734 -291.8896) (xy 385.733272 -291.910698) (xy 385.686001 -291.92439)
			(xy 385.637146 -291.930322) (xy 385.587971 -291.928341) (xy 385.539752 -291.918497) (xy 385.493736 -291.901045)
			(xy 385.451115 -291.876438) (xy 385.412994 -291.845313) (xy 385.380359 -291.808476) (xy 385.354056 -291.76688)
			(xy 385.334765 -291.721604) (xy 385.322988 -291.67382) (xy 385.319028 -291.624766) (xy 384.98018 -291.624766)
			(xy 384.979685 -291.649373) (xy 384.97179 -291.69795) (xy 384.956206 -291.744631) (xy 384.933335 -291.788208)
			(xy 384.90377 -291.827552) (xy 384.868277 -291.861644) (xy 384.827774 -291.8896) (xy 384.783312 -291.910698)
			(xy 384.736041 -291.92439) (xy 384.687186 -291.930322) (xy 384.638011 -291.928341) (xy 384.589792 -291.918497)
			(xy 384.543776 -291.901045) (xy 384.501155 -291.876438) (xy 384.463034 -291.845313) (xy 384.430399 -291.808476)
			(xy 384.404096 -291.76688) (xy 384.384805 -291.721604) (xy 384.373028 -291.67382) (xy 384.369068 -291.624766)
			(xy 376.306954 -291.624766) (xy 376.28104 -291.663935) (xy 376.243823 -291.705472) (xy 376.200955 -291.741147)
			(xy 376.153349 -291.770201) (xy 376.10202 -291.792013) (xy 376.048063 -291.806119) (xy 375.992626 -291.812219)
			(xy 375.936892 -291.810182) (xy 375.882049 -291.800052) (xy 375.829265 -291.782045) (xy 375.779665 -291.756544)
			(xy 375.734307 -291.724093) (xy 375.694158 -291.685384) (xy 375.660072 -291.641241) (xy 375.632776 -291.592606)
			(xy 375.612853 -291.540515) (xy 375.600727 -291.486078) (xy 375.596656 -291.430456) (xy 374.875044 -291.430456)
			(xy 374.874535 -291.458342) (xy 374.866415 -291.513518) (xy 374.850347 -291.566925) (xy 374.826675 -291.617422)
			(xy 374.795902 -291.663935) (xy 374.758685 -291.705472) (xy 374.715817 -291.741147) (xy 374.668211 -291.770201)
			(xy 374.616882 -291.792013) (xy 374.562925 -291.806119) (xy 374.507488 -291.812219) (xy 374.451754 -291.810182)
			(xy 374.396911 -291.800052) (xy 374.344127 -291.782045) (xy 374.294527 -291.756544) (xy 374.249169 -291.724093)
			(xy 374.20902 -291.685384) (xy 374.174934 -291.641241) (xy 374.147638 -291.592606) (xy 374.127715 -291.540515)
			(xy 374.115589 -291.486078) (xy 374.111518 -291.430456) (xy 368.55019 -291.430456) (xy 368.55019 -292.372034)
			(xy 368.54976 -292.382101) (xy 368.542036 -292.400696) (xy 368.535204 -292.408102) (xy 368.210592 -292.732714)
			(xy 374.111518 -292.732714) (xy 374.115589 -292.677092) (xy 374.127715 -292.622655) (xy 374.147638 -292.570564)
			(xy 374.174934 -292.521929) (xy 374.20902 -292.477786) (xy 374.249169 -292.439077) (xy 374.294527 -292.406626)
			(xy 374.344127 -292.381125) (xy 374.396911 -292.363118) (xy 374.451754 -292.352988) (xy 374.507488 -292.350951)
			(xy 374.562925 -292.357051) (xy 374.616882 -292.371157) (xy 374.668211 -292.392969) (xy 374.715817 -292.422023)
			(xy 374.758685 -292.457698) (xy 374.795902 -292.499235) (xy 374.826675 -292.545748) (xy 374.850347 -292.596245)
			(xy 374.866415 -292.649652) (xy 374.874535 -292.704828) (xy 374.875044 -292.732714) (xy 375.587004 -292.732714)
			(xy 375.591075 -292.677092) (xy 375.603201 -292.622655) (xy 375.623124 -292.570564) (xy 375.65042 -292.521929)
			(xy 375.684506 -292.477786) (xy 375.724655 -292.439077) (xy 375.770013 -292.406626) (xy 375.819613 -292.381125)
			(xy 375.872397 -292.363118) (xy 375.92724 -292.352988) (xy 375.982974 -292.350951) (xy 376.038411 -292.357051)
			(xy 376.092368 -292.371157) (xy 376.143697 -292.392969) (xy 376.191303 -292.422023) (xy 376.234171 -292.457698)
			(xy 376.271388 -292.499235) (xy 376.302161 -292.545748) (xy 376.325833 -292.596245) (xy 376.341901 -292.649652)
			(xy 376.350021 -292.704828) (xy 376.35053 -292.732714) (xy 376.476004 -292.732714) (xy 376.480075 -292.677092)
			(xy 376.492201 -292.622655) (xy 376.512124 -292.570564) (xy 376.53942 -292.521929) (xy 376.573506 -292.477786)
			(xy 376.613655 -292.439077) (xy 376.659013 -292.406626) (xy 376.708613 -292.381125) (xy 376.761397 -292.363118)
			(xy 376.81624 -292.352988) (xy 376.871974 -292.350951) (xy 376.927411 -292.357051) (xy 376.981368 -292.371157)
			(xy 377.032697 -292.392969) (xy 377.080303 -292.422023) (xy 377.123171 -292.457698) (xy 377.160388 -292.499235)
			(xy 377.191161 -292.545748) (xy 377.214833 -292.596245) (xy 377.230901 -292.649652) (xy 377.239021 -292.704828)
			(xy 377.23953 -292.732714) (xy 377.239021 -292.7606) (xy 377.230901 -292.815776) (xy 377.214833 -292.869183)
			(xy 377.191161 -292.91968) (xy 377.160388 -292.966193) (xy 377.123171 -293.00773) (xy 377.080303 -293.043405)
			(xy 377.032697 -293.072459) (xy 376.981368 -293.094271) (xy 376.927411 -293.108377) (xy 376.871974 -293.114477)
			(xy 376.81624 -293.11244) (xy 376.761397 -293.10231) (xy 376.708613 -293.084303) (xy 376.659013 -293.058802)
			(xy 376.613655 -293.026351) (xy 376.573506 -292.987642) (xy 376.53942 -292.943499) (xy 376.512124 -292.894864)
			(xy 376.492201 -292.842773) (xy 376.480075 -292.788336) (xy 376.476004 -292.732714) (xy 376.35053 -292.732714)
			(xy 376.350021 -292.7606) (xy 376.341901 -292.815776) (xy 376.325833 -292.869183) (xy 376.302161 -292.91968)
			(xy 376.271388 -292.966193) (xy 376.234171 -293.00773) (xy 376.191303 -293.043405) (xy 376.143697 -293.072459)
			(xy 376.092368 -293.094271) (xy 376.038411 -293.108377) (xy 375.982974 -293.114477) (xy 375.92724 -293.11244)
			(xy 375.872397 -293.10231) (xy 375.819613 -293.084303) (xy 375.770013 -293.058802) (xy 375.724655 -293.026351)
			(xy 375.684506 -292.987642) (xy 375.65042 -292.943499) (xy 375.623124 -292.894864) (xy 375.603201 -292.842773)
			(xy 375.591075 -292.788336) (xy 375.587004 -292.732714) (xy 374.875044 -292.732714) (xy 374.874535 -292.7606)
			(xy 374.866415 -292.815776) (xy 374.850347 -292.869183) (xy 374.826675 -292.91968) (xy 374.795902 -292.966193)
			(xy 374.758685 -293.00773) (xy 374.715817 -293.043405) (xy 374.668211 -293.072459) (xy 374.616882 -293.094271)
			(xy 374.562925 -293.108377) (xy 374.507488 -293.114477) (xy 374.451754 -293.11244) (xy 374.396911 -293.10231)
			(xy 374.344127 -293.084303) (xy 374.294527 -293.058802) (xy 374.249169 -293.026351) (xy 374.20902 -292.987642)
			(xy 374.174934 -292.943499) (xy 374.147638 -292.894864) (xy 374.127715 -292.842773) (xy 374.115589 -292.788336)
			(xy 374.111518 -292.732714) (xy 368.210592 -292.732714) (xy 367.448592 -293.494714) (xy 379.638052 -293.494714)
			(xy 379.638619 -293.465333) (xy 379.647646 -293.407268) (xy 379.665474 -293.351275) (xy 379.691681 -293.29868)
			(xy 379.725646 -293.250728) (xy 379.766565 -293.208554) (xy 379.78969 -293.190422) (xy 379.799088 -293.183056)
			(xy 379.809502 -293.162482) (xy 379.811026 -293.058596) (xy 379.80112 -293.037514) (xy 379.791976 -293.030148)
			(xy 379.770116 -293.011956) (xy 379.731578 -292.970134) (xy 379.699673 -292.923055) (xy 379.675108 -292.871763)
			(xy 379.658427 -292.817393) (xy 379.65 -292.76115) (xy 379.649482 -292.732714) (xy 379.649968 -292.705463)
			(xy 379.657724 -292.651515) (xy 379.673079 -292.59922) (xy 379.695721 -292.549643) (xy 379.725187 -292.503793)
			(xy 379.760878 -292.462602) (xy 379.802069 -292.426911) (xy 379.847919 -292.397445) (xy 379.897496 -292.374803)
			(xy 379.949791 -292.359448) (xy 380.003739 -292.351692) (xy 380.058241 -292.351692) (xy 380.112189 -292.359448)
			(xy 380.164484 -292.374803) (xy 380.214061 -292.397445) (xy 380.259911 -292.426911) (xy 380.301102 -292.462602)
			(xy 380.336793 -292.503793) (xy 380.366259 -292.549643) (xy 380.377831 -292.57498) (xy 384.369068 -292.57498)
			(xy 384.373028 -292.525926) (xy 384.384805 -292.478142) (xy 384.404096 -292.432866) (xy 384.430399 -292.39127)
			(xy 384.463034 -292.354433) (xy 384.501155 -292.323308) (xy 384.543776 -292.298701) (xy 384.589792 -292.281249)
			(xy 384.638011 -292.271405) (xy 384.687186 -292.269424) (xy 384.736041 -292.275356) (xy 384.783312 -292.289048)
			(xy 384.827774 -292.310146) (xy 384.868277 -292.338102) (xy 384.90377 -292.372194) (xy 384.933335 -292.411538)
			(xy 384.956206 -292.455115) (xy 384.97179 -292.501796) (xy 384.979685 -292.550373) (xy 384.98018 -292.57498)
			(xy 385.319028 -292.57498) (xy 385.322988 -292.525926) (xy 385.334765 -292.478142) (xy 385.354056 -292.432866)
			(xy 385.380359 -292.39127) (xy 385.412994 -292.354433) (xy 385.451115 -292.323308) (xy 385.493736 -292.298701)
			(xy 385.539752 -292.281249) (xy 385.587971 -292.271405) (xy 385.637146 -292.269424) (xy 385.686001 -292.275356)
			(xy 385.733272 -292.289048) (xy 385.777734 -292.310146) (xy 385.818237 -292.338102) (xy 385.85373 -292.372194)
			(xy 385.883295 -292.411538) (xy 385.906166 -292.455115) (xy 385.92175 -292.501796) (xy 385.929645 -292.550373)
			(xy 385.93014 -292.57498) (xy 386.269242 -292.57498) (xy 386.273202 -292.525926) (xy 386.284979 -292.478142)
			(xy 386.30427 -292.432866) (xy 386.330573 -292.39127) (xy 386.363208 -292.354433) (xy 386.401329 -292.323308)
			(xy 386.44395 -292.298701) (xy 386.489966 -292.281249) (xy 386.538185 -292.271405) (xy 386.58736 -292.269424)
			(xy 386.636215 -292.275356) (xy 386.683486 -292.289048) (xy 386.727948 -292.310146) (xy 386.768451 -292.338102)
			(xy 386.803944 -292.372194) (xy 386.833509 -292.411538) (xy 386.85638 -292.455115) (xy 386.871964 -292.501796)
			(xy 386.879859 -292.550373) (xy 386.880349 -292.574726) (xy 387.219202 -292.574726) (xy 387.223162 -292.525672)
			(xy 387.234939 -292.477888) (xy 387.25423 -292.432612) (xy 387.280533 -292.391016) (xy 387.313168 -292.354179)
			(xy 387.351289 -292.323054) (xy 387.39391 -292.298447) (xy 387.439926 -292.280995) (xy 387.488145 -292.271151)
			(xy 387.53732 -292.26917) (xy 387.586175 -292.275102) (xy 387.633446 -292.288794) (xy 387.677908 -292.309892)
			(xy 387.718411 -292.337848) (xy 387.753904 -292.37194) (xy 387.783469 -292.411284) (xy 387.80634 -292.454861)
			(xy 387.821924 -292.501542) (xy 387.829819 -292.550119) (xy 387.830314 -292.574726) (xy 388.169162 -292.574726)
			(xy 388.173122 -292.525672) (xy 388.184899 -292.477888) (xy 388.20419 -292.432612) (xy 388.230493 -292.391016)
			(xy 388.263128 -292.354179) (xy 388.301249 -292.323054) (xy 388.34387 -292.298447) (xy 388.389886 -292.280995)
			(xy 388.438105 -292.271151) (xy 388.48728 -292.26917) (xy 388.536135 -292.275102) (xy 388.583406 -292.288794)
			(xy 388.627868 -292.309892) (xy 388.668371 -292.337848) (xy 388.703864 -292.37194) (xy 388.733429 -292.411284)
			(xy 388.7563 -292.454861) (xy 388.771884 -292.501542) (xy 388.779779 -292.550119) (xy 388.780274 -292.574726)
			(xy 388.780269 -292.57498) (xy 389.119122 -292.57498) (xy 389.123082 -292.525926) (xy 389.134859 -292.478142)
			(xy 389.15415 -292.432866) (xy 389.180453 -292.39127) (xy 389.213088 -292.354433) (xy 389.251209 -292.323308)
			(xy 389.29383 -292.298701) (xy 389.339846 -292.281249) (xy 389.388065 -292.271405) (xy 389.43724 -292.269424)
			(xy 389.486095 -292.275356) (xy 389.533366 -292.289048) (xy 389.577828 -292.310146) (xy 389.618331 -292.338102)
			(xy 389.653824 -292.372194) (xy 389.683389 -292.411538) (xy 389.70626 -292.455115) (xy 389.721844 -292.501796)
			(xy 389.729739 -292.550373) (xy 389.730234 -292.57498) (xy 389.729739 -292.599587) (xy 389.729407 -292.601629)
			(xy 390.019276 -292.601629) (xy 390.019276 -292.548331) (xy 390.027219 -292.495627) (xy 390.042929 -292.444697)
			(xy 390.066055 -292.396676) (xy 390.096079 -292.352639) (xy 390.132331 -292.313568) (xy 390.174002 -292.280337)
			(xy 390.22016 -292.253688) (xy 390.269774 -292.234216) (xy 390.321736 -292.222356) (xy 390.374886 -292.218373)
			(xy 390.428036 -292.222356) (xy 390.479998 -292.234216) (xy 390.529612 -292.253688) (xy 390.57577 -292.280337)
			(xy 390.617441 -292.313568) (xy 390.653693 -292.352639) (xy 390.683717 -292.396676) (xy 390.706843 -292.444697)
			(xy 390.722553 -292.495627) (xy 390.730496 -292.548331) (xy 390.730994 -292.57498) (xy 391.019042 -292.57498)
			(xy 391.023002 -292.525926) (xy 391.034779 -292.478142) (xy 391.05407 -292.432866) (xy 391.080373 -292.39127)
			(xy 391.113008 -292.354433) (xy 391.151129 -292.323308) (xy 391.19375 -292.298701) (xy 391.239766 -292.281249)
			(xy 391.287985 -292.271405) (xy 391.33716 -292.269424) (xy 391.386015 -292.275356) (xy 391.433286 -292.289048)
			(xy 391.477748 -292.310146) (xy 391.518251 -292.338102) (xy 391.553744 -292.372194) (xy 391.583309 -292.411538)
			(xy 391.60618 -292.455115) (xy 391.621764 -292.501796) (xy 391.629659 -292.550373) (xy 391.630154 -292.57498)
			(xy 391.969002 -292.57498) (xy 391.972962 -292.525926) (xy 391.984739 -292.478142) (xy 392.00403 -292.432866)
			(xy 392.030333 -292.39127) (xy 392.062968 -292.354433) (xy 392.101089 -292.323308) (xy 392.14371 -292.298701)
			(xy 392.189726 -292.281249) (xy 392.237945 -292.271405) (xy 392.28712 -292.269424) (xy 392.335975 -292.275356)
			(xy 392.383246 -292.289048) (xy 392.427708 -292.310146) (xy 392.468211 -292.338102) (xy 392.503704 -292.372194)
			(xy 392.533269 -292.411538) (xy 392.55614 -292.455115) (xy 392.571724 -292.501796) (xy 392.579619 -292.550373)
			(xy 392.580114 -292.57498) (xy 392.919216 -292.57498) (xy 392.923176 -292.525926) (xy 392.934953 -292.478142)
			(xy 392.954244 -292.432866) (xy 392.980547 -292.39127) (xy 393.013182 -292.354433) (xy 393.051303 -292.323308)
			(xy 393.093924 -292.298701) (xy 393.13994 -292.281249) (xy 393.188159 -292.271405) (xy 393.237334 -292.269424)
			(xy 393.286189 -292.275356) (xy 393.33346 -292.289048) (xy 393.377922 -292.310146) (xy 393.418425 -292.338102)
			(xy 393.453918 -292.372194) (xy 393.483483 -292.411538) (xy 393.506354 -292.455115) (xy 393.521938 -292.501796)
			(xy 393.529833 -292.550373) (xy 393.530328 -292.57498) (xy 393.869176 -292.57498) (xy 393.873136 -292.525926)
			(xy 393.884913 -292.478142) (xy 393.904204 -292.432866) (xy 393.930507 -292.39127) (xy 393.963142 -292.354433)
			(xy 394.001263 -292.323308) (xy 394.043884 -292.298701) (xy 394.0899 -292.281249) (xy 394.138119 -292.271405)
			(xy 394.187294 -292.269424) (xy 394.236149 -292.275356) (xy 394.28342 -292.289048) (xy 394.327882 -292.310146)
			(xy 394.368385 -292.338102) (xy 394.403878 -292.372194) (xy 394.433443 -292.411538) (xy 394.456314 -292.455115)
			(xy 394.471898 -292.501796) (xy 394.479793 -292.550373) (xy 394.480288 -292.57498) (xy 394.819136 -292.57498)
			(xy 394.823096 -292.525926) (xy 394.834873 -292.478142) (xy 394.854164 -292.432866) (xy 394.880467 -292.39127)
			(xy 394.913102 -292.354433) (xy 394.951223 -292.323308) (xy 394.993844 -292.298701) (xy 395.03986 -292.281249)
			(xy 395.088079 -292.271405) (xy 395.137254 -292.269424) (xy 395.186109 -292.275356) (xy 395.23338 -292.289048)
			(xy 395.277842 -292.310146) (xy 395.318345 -292.338102) (xy 395.353838 -292.372194) (xy 395.383403 -292.411538)
			(xy 395.406274 -292.455115) (xy 395.421858 -292.501796) (xy 395.429753 -292.550373) (xy 395.430248 -292.57498)
			(xy 395.769096 -292.57498) (xy 395.773056 -292.525926) (xy 395.784833 -292.478142) (xy 395.804124 -292.432866)
			(xy 395.830427 -292.39127) (xy 395.863062 -292.354433) (xy 395.901183 -292.323308) (xy 395.943804 -292.298701)
			(xy 395.98982 -292.281249) (xy 396.038039 -292.271405) (xy 396.087214 -292.269424) (xy 396.136069 -292.275356)
			(xy 396.18334 -292.289048) (xy 396.227802 -292.310146) (xy 396.268305 -292.338102) (xy 396.303798 -292.372194)
			(xy 396.333363 -292.411538) (xy 396.356234 -292.455115) (xy 396.371818 -292.501796) (xy 396.379713 -292.550373)
			(xy 396.380203 -292.574726) (xy 397.669016 -292.574726) (xy 397.672976 -292.525672) (xy 397.684753 -292.477888)
			(xy 397.704044 -292.432612) (xy 397.730347 -292.391016) (xy 397.762982 -292.354179) (xy 397.801103 -292.323054)
			(xy 397.843724 -292.298447) (xy 397.88974 -292.280995) (xy 397.937959 -292.271151) (xy 397.987134 -292.26917)
			(xy 398.035989 -292.275102) (xy 398.08326 -292.288794) (xy 398.127722 -292.309892) (xy 398.168225 -292.337848)
			(xy 398.203718 -292.37194) (xy 398.233283 -292.411284) (xy 398.256154 -292.454861) (xy 398.271738 -292.501542)
			(xy 398.279633 -292.550119) (xy 398.280128 -292.574726) (xy 398.280123 -292.57498) (xy 398.61923 -292.57498)
			(xy 398.62319 -292.525926) (xy 398.634967 -292.478142) (xy 398.654258 -292.432866) (xy 398.680561 -292.39127)
			(xy 398.713196 -292.354433) (xy 398.751317 -292.323308) (xy 398.793938 -292.298701) (xy 398.839954 -292.281249)
			(xy 398.888173 -292.271405) (xy 398.937348 -292.269424) (xy 398.986203 -292.275356) (xy 399.033474 -292.289048)
			(xy 399.077936 -292.310146) (xy 399.118439 -292.338102) (xy 399.153932 -292.372194) (xy 399.183497 -292.411538)
			(xy 399.206368 -292.455115) (xy 399.221952 -292.501796) (xy 399.229847 -292.550373) (xy 399.230342 -292.57498)
			(xy 399.56919 -292.57498) (xy 399.57315 -292.525926) (xy 399.584927 -292.478142) (xy 399.604218 -292.432866)
			(xy 399.630521 -292.39127) (xy 399.663156 -292.354433) (xy 399.701277 -292.323308) (xy 399.743898 -292.298701)
			(xy 399.789914 -292.281249) (xy 399.838133 -292.271405) (xy 399.887308 -292.269424) (xy 399.936163 -292.275356)
			(xy 399.983434 -292.289048) (xy 400.027896 -292.310146) (xy 400.068399 -292.338102) (xy 400.103892 -292.372194)
			(xy 400.133457 -292.411538) (xy 400.156328 -292.455115) (xy 400.171912 -292.501796) (xy 400.179807 -292.550373)
			(xy 400.180302 -292.57498) (xy 400.51915 -292.57498) (xy 400.52311 -292.525926) (xy 400.534887 -292.478142)
			(xy 400.554178 -292.432866) (xy 400.580481 -292.39127) (xy 400.613116 -292.354433) (xy 400.651237 -292.323308)
			(xy 400.693858 -292.298701) (xy 400.739874 -292.281249) (xy 400.788093 -292.271405) (xy 400.837268 -292.269424)
			(xy 400.886123 -292.275356) (xy 400.933394 -292.289048) (xy 400.977856 -292.310146) (xy 401.018359 -292.338102)
			(xy 401.053852 -292.372194) (xy 401.083417 -292.411538) (xy 401.106288 -292.455115) (xy 401.121872 -292.501796)
			(xy 401.129767 -292.550373) (xy 401.130262 -292.57498) (xy 401.46911 -292.57498) (xy 401.47307 -292.525926)
			(xy 401.484847 -292.478142) (xy 401.504138 -292.432866) (xy 401.530441 -292.39127) (xy 401.563076 -292.354433)
			(xy 401.601197 -292.323308) (xy 401.643818 -292.298701) (xy 401.689834 -292.281249) (xy 401.738053 -292.271405)
			(xy 401.787228 -292.269424) (xy 401.836083 -292.275356) (xy 401.883354 -292.289048) (xy 401.927816 -292.310146)
			(xy 401.968319 -292.338102) (xy 402.003812 -292.372194) (xy 402.033377 -292.411538) (xy 402.056248 -292.455115)
			(xy 402.071832 -292.501796) (xy 402.079727 -292.550373) (xy 402.080222 -292.57498) (xy 402.41907 -292.57498)
			(xy 402.42303 -292.525926) (xy 402.434807 -292.478142) (xy 402.454098 -292.432866) (xy 402.480401 -292.39127)
			(xy 402.513036 -292.354433) (xy 402.551157 -292.323308) (xy 402.593778 -292.298701) (xy 402.639794 -292.281249)
			(xy 402.688013 -292.271405) (xy 402.737188 -292.269424) (xy 402.786043 -292.275356) (xy 402.833314 -292.289048)
			(xy 402.877776 -292.310146) (xy 402.918279 -292.338102) (xy 402.953772 -292.372194) (xy 402.983337 -292.411538)
			(xy 403.006208 -292.455115) (xy 403.021792 -292.501796) (xy 403.029687 -292.550373) (xy 403.030182 -292.57498)
			(xy 403.36903 -292.57498) (xy 403.37299 -292.525926) (xy 403.384767 -292.478142) (xy 403.404058 -292.432866)
			(xy 403.430361 -292.39127) (xy 403.462996 -292.354433) (xy 403.501117 -292.323308) (xy 403.543738 -292.298701)
			(xy 403.589754 -292.281249) (xy 403.637973 -292.271405) (xy 403.687148 -292.269424) (xy 403.736003 -292.275356)
			(xy 403.783274 -292.289048) (xy 403.827736 -292.310146) (xy 403.868239 -292.338102) (xy 403.903732 -292.372194)
			(xy 403.933297 -292.411538) (xy 403.956168 -292.455115) (xy 403.971752 -292.501796) (xy 403.979647 -292.550373)
			(xy 403.980142 -292.57498) (xy 404.319244 -292.57498) (xy 404.323204 -292.525926) (xy 404.334981 -292.478142)
			(xy 404.354272 -292.432866) (xy 404.380575 -292.39127) (xy 404.41321 -292.354433) (xy 404.451331 -292.323308)
			(xy 404.493952 -292.298701) (xy 404.539968 -292.281249) (xy 404.588187 -292.271405) (xy 404.637362 -292.269424)
			(xy 404.686217 -292.275356) (xy 404.733488 -292.289048) (xy 404.77795 -292.310146) (xy 404.818453 -292.338102)
			(xy 404.853946 -292.372194) (xy 404.883511 -292.411538) (xy 404.906382 -292.455115) (xy 404.921966 -292.501796)
			(xy 404.929861 -292.550373) (xy 404.930356 -292.57498) (xy 405.269204 -292.57498) (xy 405.273164 -292.525926)
			(xy 405.284941 -292.478142) (xy 405.304232 -292.432866) (xy 405.330535 -292.39127) (xy 405.36317 -292.354433)
			(xy 405.401291 -292.323308) (xy 405.443912 -292.298701) (xy 405.489928 -292.281249) (xy 405.538147 -292.271405)
			(xy 405.587322 -292.269424) (xy 405.636177 -292.275356) (xy 405.683448 -292.289048) (xy 405.72791 -292.310146)
			(xy 405.768413 -292.338102) (xy 405.803906 -292.372194) (xy 405.833471 -292.411538) (xy 405.856342 -292.455115)
			(xy 405.871926 -292.501796) (xy 405.879821 -292.550373) (xy 405.880316 -292.57498) (xy 406.219164 -292.57498)
			(xy 406.223124 -292.525926) (xy 406.234901 -292.478142) (xy 406.254192 -292.432866) (xy 406.280495 -292.39127)
			(xy 406.31313 -292.354433) (xy 406.351251 -292.323308) (xy 406.393872 -292.298701) (xy 406.439888 -292.281249)
			(xy 406.488107 -292.271405) (xy 406.537282 -292.269424) (xy 406.586137 -292.275356) (xy 406.633408 -292.289048)
			(xy 406.67787 -292.310146) (xy 406.718373 -292.338102) (xy 406.753866 -292.372194) (xy 406.783431 -292.411538)
			(xy 406.806302 -292.455115) (xy 406.821886 -292.501796) (xy 406.829781 -292.550373) (xy 406.830271 -292.574726)
			(xy 408.119084 -292.574726) (xy 408.123044 -292.525672) (xy 408.134821 -292.477888) (xy 408.154112 -292.432612)
			(xy 408.180415 -292.391016) (xy 408.21305 -292.354179) (xy 408.251171 -292.323054) (xy 408.293792 -292.298447)
			(xy 408.339808 -292.280995) (xy 408.388027 -292.271151) (xy 408.437202 -292.26917) (xy 408.486057 -292.275102)
			(xy 408.533328 -292.288794) (xy 408.57779 -292.309892) (xy 408.618293 -292.337848) (xy 408.653786 -292.37194)
			(xy 408.683351 -292.411284) (xy 408.706222 -292.454861) (xy 408.721806 -292.501542) (xy 408.729701 -292.550119)
			(xy 408.730196 -292.574726) (xy 409.069044 -292.574726) (xy 409.073004 -292.525672) (xy 409.084781 -292.477888)
			(xy 409.104072 -292.432612) (xy 409.130375 -292.391016) (xy 409.16301 -292.354179) (xy 409.201131 -292.323054)
			(xy 409.243752 -292.298447) (xy 409.289768 -292.280995) (xy 409.337987 -292.271151) (xy 409.387162 -292.26917)
			(xy 409.436017 -292.275102) (xy 409.483288 -292.288794) (xy 409.52775 -292.309892) (xy 409.568253 -292.337848)
			(xy 409.603746 -292.37194) (xy 409.633311 -292.411284) (xy 409.656182 -292.454861) (xy 409.671766 -292.501542)
			(xy 409.679661 -292.550119) (xy 409.680156 -292.574726) (xy 410.019004 -292.574726) (xy 410.022964 -292.525672)
			(xy 410.034741 -292.477888) (xy 410.054032 -292.432612) (xy 410.080335 -292.391016) (xy 410.11297 -292.354179)
			(xy 410.151091 -292.323054) (xy 410.193712 -292.298447) (xy 410.239728 -292.280995) (xy 410.287947 -292.271151)
			(xy 410.337122 -292.26917) (xy 410.385977 -292.275102) (xy 410.433248 -292.288794) (xy 410.47771 -292.309892)
			(xy 410.518213 -292.337848) (xy 410.553706 -292.37194) (xy 410.583271 -292.411284) (xy 410.606142 -292.454861)
			(xy 410.621726 -292.501542) (xy 410.629621 -292.550119) (xy 410.630116 -292.574726) (xy 410.969218 -292.574726)
			(xy 410.973178 -292.525672) (xy 410.984955 -292.477888) (xy 411.004246 -292.432612) (xy 411.030549 -292.391016)
			(xy 411.063184 -292.354179) (xy 411.101305 -292.323054) (xy 411.143926 -292.298447) (xy 411.189942 -292.280995)
			(xy 411.238161 -292.271151) (xy 411.287336 -292.26917) (xy 411.336191 -292.275102) (xy 411.383462 -292.288794)
			(xy 411.427924 -292.309892) (xy 411.468427 -292.337848) (xy 411.50392 -292.37194) (xy 411.533485 -292.411284)
			(xy 411.556356 -292.454861) (xy 411.57194 -292.501542) (xy 411.579835 -292.550119) (xy 411.58033 -292.574726)
			(xy 411.919178 -292.574726) (xy 411.923138 -292.525672) (xy 411.934915 -292.477888) (xy 411.954206 -292.432612)
			(xy 411.980509 -292.391016) (xy 412.013144 -292.354179) (xy 412.051265 -292.323054) (xy 412.093886 -292.298447)
			(xy 412.139902 -292.280995) (xy 412.188121 -292.271151) (xy 412.237296 -292.26917) (xy 412.286151 -292.275102)
			(xy 412.333422 -292.288794) (xy 412.377884 -292.309892) (xy 412.418387 -292.337848) (xy 412.45388 -292.37194)
			(xy 412.483445 -292.411284) (xy 412.506316 -292.454861) (xy 412.5219 -292.501542) (xy 412.529795 -292.550119)
			(xy 412.53029 -292.574726) (xy 412.869138 -292.574726) (xy 412.873098 -292.525672) (xy 412.884875 -292.477888)
			(xy 412.904166 -292.432612) (xy 412.930469 -292.391016) (xy 412.963104 -292.354179) (xy 413.001225 -292.323054)
			(xy 413.043846 -292.298447) (xy 413.089862 -292.280995) (xy 413.138081 -292.271151) (xy 413.187256 -292.26917)
			(xy 413.236111 -292.275102) (xy 413.283382 -292.288794) (xy 413.327844 -292.309892) (xy 413.368347 -292.337848)
			(xy 413.40384 -292.37194) (xy 413.433405 -292.411284) (xy 413.456276 -292.454861) (xy 413.47186 -292.501542)
			(xy 413.479755 -292.550119) (xy 413.48025 -292.574726) (xy 413.819098 -292.574726) (xy 413.823058 -292.525672)
			(xy 413.834835 -292.477888) (xy 413.854126 -292.432612) (xy 413.880429 -292.391016) (xy 413.913064 -292.354179)
			(xy 413.951185 -292.323054) (xy 413.993806 -292.298447) (xy 414.039822 -292.280995) (xy 414.088041 -292.271151)
			(xy 414.137216 -292.26917) (xy 414.186071 -292.275102) (xy 414.233342 -292.288794) (xy 414.277804 -292.309892)
			(xy 414.318307 -292.337848) (xy 414.3538 -292.37194) (xy 414.383365 -292.411284) (xy 414.406236 -292.454861)
			(xy 414.42182 -292.501542) (xy 414.429715 -292.550119) (xy 414.43021 -292.574726) (xy 414.769058 -292.574726)
			(xy 414.773018 -292.525672) (xy 414.784795 -292.477888) (xy 414.804086 -292.432612) (xy 414.830389 -292.391016)
			(xy 414.863024 -292.354179) (xy 414.901145 -292.323054) (xy 414.943766 -292.298447) (xy 414.989782 -292.280995)
			(xy 415.038001 -292.271151) (xy 415.087176 -292.26917) (xy 415.136031 -292.275102) (xy 415.183302 -292.288794)
			(xy 415.227764 -292.309892) (xy 415.268267 -292.337848) (xy 415.30376 -292.37194) (xy 415.333325 -292.411284)
			(xy 415.356196 -292.454861) (xy 415.37178 -292.501542) (xy 415.379675 -292.550119) (xy 415.38017 -292.574726)
			(xy 415.719018 -292.574726) (xy 415.722978 -292.525672) (xy 415.734755 -292.477888) (xy 415.754046 -292.432612)
			(xy 415.780349 -292.391016) (xy 415.812984 -292.354179) (xy 415.851105 -292.323054) (xy 415.893726 -292.298447)
			(xy 415.939742 -292.280995) (xy 415.987961 -292.271151) (xy 416.037136 -292.26917) (xy 416.085991 -292.275102)
			(xy 416.133262 -292.288794) (xy 416.177724 -292.309892) (xy 416.218227 -292.337848) (xy 416.25372 -292.37194)
			(xy 416.283285 -292.411284) (xy 416.306156 -292.454861) (xy 416.32174 -292.501542) (xy 416.329635 -292.550119)
			(xy 416.33013 -292.574726) (xy 416.668978 -292.574726) (xy 416.672938 -292.525672) (xy 416.684715 -292.477888)
			(xy 416.704006 -292.432612) (xy 416.730309 -292.391016) (xy 416.762944 -292.354179) (xy 416.801065 -292.323054)
			(xy 416.843686 -292.298447) (xy 416.889702 -292.280995) (xy 416.937921 -292.271151) (xy 416.987096 -292.26917)
			(xy 417.035951 -292.275102) (xy 417.083222 -292.288794) (xy 417.127684 -292.309892) (xy 417.168187 -292.337848)
			(xy 417.20368 -292.37194) (xy 417.233245 -292.411284) (xy 417.256116 -292.454861) (xy 417.2717 -292.501542)
			(xy 417.279595 -292.550119) (xy 417.28009 -292.574726) (xy 417.279595 -292.599333) (xy 417.2717 -292.64791)
			(xy 417.256116 -292.694591) (xy 417.233245 -292.738168) (xy 417.20368 -292.777512) (xy 417.168187 -292.811604)
			(xy 417.127684 -292.83956) (xy 417.083222 -292.860658) (xy 417.035951 -292.87435) (xy 416.987096 -292.880282)
			(xy 416.937921 -292.878301) (xy 416.889702 -292.868457) (xy 416.843686 -292.851005) (xy 416.801065 -292.826398)
			(xy 416.762944 -292.795273) (xy 416.730309 -292.758436) (xy 416.704006 -292.71684) (xy 416.684715 -292.671564)
			(xy 416.672938 -292.62378) (xy 416.668978 -292.574726) (xy 416.33013 -292.574726) (xy 416.329635 -292.599333)
			(xy 416.32174 -292.64791) (xy 416.306156 -292.694591) (xy 416.283285 -292.738168) (xy 416.25372 -292.777512)
			(xy 416.218227 -292.811604) (xy 416.177724 -292.83956) (xy 416.133262 -292.860658) (xy 416.085991 -292.87435)
			(xy 416.037136 -292.880282) (xy 415.987961 -292.878301) (xy 415.939742 -292.868457) (xy 415.893726 -292.851005)
			(xy 415.851105 -292.826398) (xy 415.812984 -292.795273) (xy 415.780349 -292.758436) (xy 415.754046 -292.71684)
			(xy 415.734755 -292.671564) (xy 415.722978 -292.62378) (xy 415.719018 -292.574726) (xy 415.38017 -292.574726)
			(xy 415.379675 -292.599333) (xy 415.37178 -292.64791) (xy 415.356196 -292.694591) (xy 415.333325 -292.738168)
			(xy 415.30376 -292.777512) (xy 415.268267 -292.811604) (xy 415.227764 -292.83956) (xy 415.183302 -292.860658)
			(xy 415.136031 -292.87435) (xy 415.087176 -292.880282) (xy 415.038001 -292.878301) (xy 414.989782 -292.868457)
			(xy 414.943766 -292.851005) (xy 414.901145 -292.826398) (xy 414.863024 -292.795273) (xy 414.830389 -292.758436)
			(xy 414.804086 -292.71684) (xy 414.784795 -292.671564) (xy 414.773018 -292.62378) (xy 414.769058 -292.574726)
			(xy 414.43021 -292.574726) (xy 414.429715 -292.599333) (xy 414.42182 -292.64791) (xy 414.406236 -292.694591)
			(xy 414.383365 -292.738168) (xy 414.3538 -292.777512) (xy 414.318307 -292.811604) (xy 414.277804 -292.83956)
			(xy 414.233342 -292.860658) (xy 414.186071 -292.87435) (xy 414.137216 -292.880282) (xy 414.088041 -292.878301)
			(xy 414.039822 -292.868457) (xy 413.993806 -292.851005) (xy 413.951185 -292.826398) (xy 413.913064 -292.795273)
			(xy 413.880429 -292.758436) (xy 413.854126 -292.71684) (xy 413.834835 -292.671564) (xy 413.823058 -292.62378)
			(xy 413.819098 -292.574726) (xy 413.48025 -292.574726) (xy 413.479755 -292.599333) (xy 413.47186 -292.64791)
			(xy 413.456276 -292.694591) (xy 413.433405 -292.738168) (xy 413.40384 -292.777512) (xy 413.368347 -292.811604)
			(xy 413.327844 -292.83956) (xy 413.283382 -292.860658) (xy 413.236111 -292.87435) (xy 413.187256 -292.880282)
			(xy 413.138081 -292.878301) (xy 413.089862 -292.868457) (xy 413.043846 -292.851005) (xy 413.001225 -292.826398)
			(xy 412.963104 -292.795273) (xy 412.930469 -292.758436) (xy 412.904166 -292.71684) (xy 412.884875 -292.671564)
			(xy 412.873098 -292.62378) (xy 412.869138 -292.574726) (xy 412.53029 -292.574726) (xy 412.529795 -292.599333)
			(xy 412.5219 -292.64791) (xy 412.506316 -292.694591) (xy 412.483445 -292.738168) (xy 412.45388 -292.777512)
			(xy 412.418387 -292.811604) (xy 412.377884 -292.83956) (xy 412.333422 -292.860658) (xy 412.286151 -292.87435)
			(xy 412.237296 -292.880282) (xy 412.188121 -292.878301) (xy 412.139902 -292.868457) (xy 412.093886 -292.851005)
			(xy 412.051265 -292.826398) (xy 412.013144 -292.795273) (xy 411.980509 -292.758436) (xy 411.954206 -292.71684)
			(xy 411.934915 -292.671564) (xy 411.923138 -292.62378) (xy 411.919178 -292.574726) (xy 411.58033 -292.574726)
			(xy 411.579835 -292.599333) (xy 411.57194 -292.64791) (xy 411.556356 -292.694591) (xy 411.533485 -292.738168)
			(xy 411.50392 -292.777512) (xy 411.468427 -292.811604) (xy 411.427924 -292.83956) (xy 411.383462 -292.860658)
			(xy 411.336191 -292.87435) (xy 411.287336 -292.880282) (xy 411.238161 -292.878301) (xy 411.189942 -292.868457)
			(xy 411.143926 -292.851005) (xy 411.101305 -292.826398) (xy 411.063184 -292.795273) (xy 411.030549 -292.758436)
			(xy 411.004246 -292.71684) (xy 410.984955 -292.671564) (xy 410.973178 -292.62378) (xy 410.969218 -292.574726)
			(xy 410.630116 -292.574726) (xy 410.629621 -292.599333) (xy 410.621726 -292.64791) (xy 410.606142 -292.694591)
			(xy 410.583271 -292.738168) (xy 410.553706 -292.777512) (xy 410.518213 -292.811604) (xy 410.47771 -292.83956)
			(xy 410.433248 -292.860658) (xy 410.385977 -292.87435) (xy 410.337122 -292.880282) (xy 410.287947 -292.878301)
			(xy 410.239728 -292.868457) (xy 410.193712 -292.851005) (xy 410.151091 -292.826398) (xy 410.11297 -292.795273)
			(xy 410.080335 -292.758436) (xy 410.054032 -292.71684) (xy 410.034741 -292.671564) (xy 410.022964 -292.62378)
			(xy 410.019004 -292.574726) (xy 409.680156 -292.574726) (xy 409.679661 -292.599333) (xy 409.671766 -292.64791)
			(xy 409.656182 -292.694591) (xy 409.633311 -292.738168) (xy 409.603746 -292.777512) (xy 409.568253 -292.811604)
			(xy 409.52775 -292.83956) (xy 409.483288 -292.860658) (xy 409.436017 -292.87435) (xy 409.387162 -292.880282)
			(xy 409.337987 -292.878301) (xy 409.289768 -292.868457) (xy 409.243752 -292.851005) (xy 409.201131 -292.826398)
			(xy 409.16301 -292.795273) (xy 409.130375 -292.758436) (xy 409.104072 -292.71684) (xy 409.084781 -292.671564)
			(xy 409.073004 -292.62378) (xy 409.069044 -292.574726) (xy 408.730196 -292.574726) (xy 408.729701 -292.599333)
			(xy 408.721806 -292.64791) (xy 408.706222 -292.694591) (xy 408.683351 -292.738168) (xy 408.653786 -292.777512)
			(xy 408.618293 -292.811604) (xy 408.57779 -292.83956) (xy 408.533328 -292.860658) (xy 408.486057 -292.87435)
			(xy 408.437202 -292.880282) (xy 408.388027 -292.878301) (xy 408.339808 -292.868457) (xy 408.293792 -292.851005)
			(xy 408.251171 -292.826398) (xy 408.21305 -292.795273) (xy 408.180415 -292.758436) (xy 408.154112 -292.71684)
			(xy 408.134821 -292.671564) (xy 408.123044 -292.62378) (xy 408.119084 -292.574726) (xy 406.830271 -292.574726)
			(xy 406.830276 -292.57498) (xy 406.829781 -292.599587) (xy 406.821886 -292.648164) (xy 406.806302 -292.694845)
			(xy 406.783431 -292.738422) (xy 406.753866 -292.777766) (xy 406.718373 -292.811858) (xy 406.67787 -292.839814)
			(xy 406.633408 -292.860912) (xy 406.586137 -292.874604) (xy 406.537282 -292.880536) (xy 406.488107 -292.878555)
			(xy 406.439888 -292.868711) (xy 406.393872 -292.851259) (xy 406.351251 -292.826652) (xy 406.31313 -292.795527)
			(xy 406.280495 -292.75869) (xy 406.254192 -292.717094) (xy 406.234901 -292.671818) (xy 406.223124 -292.624034)
			(xy 406.219164 -292.57498) (xy 405.880316 -292.57498) (xy 405.879821 -292.599587) (xy 405.871926 -292.648164)
			(xy 405.856342 -292.694845) (xy 405.833471 -292.738422) (xy 405.803906 -292.777766) (xy 405.768413 -292.811858)
			(xy 405.72791 -292.839814) (xy 405.683448 -292.860912) (xy 405.636177 -292.874604) (xy 405.587322 -292.880536)
			(xy 405.538147 -292.878555) (xy 405.489928 -292.868711) (xy 405.443912 -292.851259) (xy 405.401291 -292.826652)
			(xy 405.36317 -292.795527) (xy 405.330535 -292.75869) (xy 405.304232 -292.717094) (xy 405.284941 -292.671818)
			(xy 405.273164 -292.624034) (xy 405.269204 -292.57498) (xy 404.930356 -292.57498) (xy 404.929861 -292.599587)
			(xy 404.921966 -292.648164) (xy 404.906382 -292.694845) (xy 404.883511 -292.738422) (xy 404.853946 -292.777766)
			(xy 404.818453 -292.811858) (xy 404.77795 -292.839814) (xy 404.733488 -292.860912) (xy 404.686217 -292.874604)
			(xy 404.637362 -292.880536) (xy 404.588187 -292.878555) (xy 404.539968 -292.868711) (xy 404.493952 -292.851259)
			(xy 404.451331 -292.826652) (xy 404.41321 -292.795527) (xy 404.380575 -292.75869) (xy 404.354272 -292.717094)
			(xy 404.334981 -292.671818) (xy 404.323204 -292.624034) (xy 404.319244 -292.57498) (xy 403.980142 -292.57498)
			(xy 403.979647 -292.599587) (xy 403.971752 -292.648164) (xy 403.956168 -292.694845) (xy 403.933297 -292.738422)
			(xy 403.903732 -292.777766) (xy 403.868239 -292.811858) (xy 403.827736 -292.839814) (xy 403.783274 -292.860912)
			(xy 403.736003 -292.874604) (xy 403.687148 -292.880536) (xy 403.637973 -292.878555) (xy 403.589754 -292.868711)
			(xy 403.543738 -292.851259) (xy 403.501117 -292.826652) (xy 403.462996 -292.795527) (xy 403.430361 -292.75869)
			(xy 403.404058 -292.717094) (xy 403.384767 -292.671818) (xy 403.37299 -292.624034) (xy 403.36903 -292.57498)
			(xy 403.030182 -292.57498) (xy 403.029687 -292.599587) (xy 403.021792 -292.648164) (xy 403.006208 -292.694845)
			(xy 402.983337 -292.738422) (xy 402.953772 -292.777766) (xy 402.918279 -292.811858) (xy 402.877776 -292.839814)
			(xy 402.833314 -292.860912) (xy 402.786043 -292.874604) (xy 402.737188 -292.880536) (xy 402.688013 -292.878555)
			(xy 402.639794 -292.868711) (xy 402.593778 -292.851259) (xy 402.551157 -292.826652) (xy 402.513036 -292.795527)
			(xy 402.480401 -292.75869) (xy 402.454098 -292.717094) (xy 402.434807 -292.671818) (xy 402.42303 -292.624034)
			(xy 402.41907 -292.57498) (xy 402.080222 -292.57498) (xy 402.079727 -292.599587) (xy 402.071832 -292.648164)
			(xy 402.056248 -292.694845) (xy 402.033377 -292.738422) (xy 402.003812 -292.777766) (xy 401.968319 -292.811858)
			(xy 401.927816 -292.839814) (xy 401.883354 -292.860912) (xy 401.836083 -292.874604) (xy 401.787228 -292.880536)
			(xy 401.738053 -292.878555) (xy 401.689834 -292.868711) (xy 401.643818 -292.851259) (xy 401.601197 -292.826652)
			(xy 401.563076 -292.795527) (xy 401.530441 -292.75869) (xy 401.504138 -292.717094) (xy 401.484847 -292.671818)
			(xy 401.47307 -292.624034) (xy 401.46911 -292.57498) (xy 401.130262 -292.57498) (xy 401.129767 -292.599587)
			(xy 401.121872 -292.648164) (xy 401.106288 -292.694845) (xy 401.083417 -292.738422) (xy 401.053852 -292.777766)
			(xy 401.018359 -292.811858) (xy 400.977856 -292.839814) (xy 400.933394 -292.860912) (xy 400.886123 -292.874604)
			(xy 400.837268 -292.880536) (xy 400.788093 -292.878555) (xy 400.739874 -292.868711) (xy 400.693858 -292.851259)
			(xy 400.651237 -292.826652) (xy 400.613116 -292.795527) (xy 400.580481 -292.75869) (xy 400.554178 -292.717094)
			(xy 400.534887 -292.671818) (xy 400.52311 -292.624034) (xy 400.51915 -292.57498) (xy 400.180302 -292.57498)
			(xy 400.179807 -292.599587) (xy 400.171912 -292.648164) (xy 400.156328 -292.694845) (xy 400.133457 -292.738422)
			(xy 400.103892 -292.777766) (xy 400.068399 -292.811858) (xy 400.027896 -292.839814) (xy 399.983434 -292.860912)
			(xy 399.936163 -292.874604) (xy 399.887308 -292.880536) (xy 399.838133 -292.878555) (xy 399.789914 -292.868711)
			(xy 399.743898 -292.851259) (xy 399.701277 -292.826652) (xy 399.663156 -292.795527) (xy 399.630521 -292.75869)
			(xy 399.604218 -292.717094) (xy 399.584927 -292.671818) (xy 399.57315 -292.624034) (xy 399.56919 -292.57498)
			(xy 399.230342 -292.57498) (xy 399.229847 -292.599587) (xy 399.221952 -292.648164) (xy 399.206368 -292.694845)
			(xy 399.183497 -292.738422) (xy 399.153932 -292.777766) (xy 399.118439 -292.811858) (xy 399.077936 -292.839814)
			(xy 399.033474 -292.860912) (xy 398.986203 -292.874604) (xy 398.937348 -292.880536) (xy 398.888173 -292.878555)
			(xy 398.839954 -292.868711) (xy 398.793938 -292.851259) (xy 398.751317 -292.826652) (xy 398.713196 -292.795527)
			(xy 398.680561 -292.75869) (xy 398.654258 -292.717094) (xy 398.634967 -292.671818) (xy 398.62319 -292.624034)
			(xy 398.61923 -292.57498) (xy 398.280123 -292.57498) (xy 398.279633 -292.599333) (xy 398.271738 -292.64791)
			(xy 398.256154 -292.694591) (xy 398.233283 -292.738168) (xy 398.203718 -292.777512) (xy 398.168225 -292.811604)
			(xy 398.127722 -292.83956) (xy 398.08326 -292.860658) (xy 398.035989 -292.87435) (xy 397.987134 -292.880282)
			(xy 397.937959 -292.878301) (xy 397.88974 -292.868457) (xy 397.843724 -292.851005) (xy 397.801103 -292.826398)
			(xy 397.762982 -292.795273) (xy 397.730347 -292.758436) (xy 397.704044 -292.71684) (xy 397.684753 -292.671564)
			(xy 397.672976 -292.62378) (xy 397.669016 -292.574726) (xy 396.380203 -292.574726) (xy 396.380208 -292.57498)
			(xy 396.379713 -292.599587) (xy 396.371818 -292.648164) (xy 396.356234 -292.694845) (xy 396.333363 -292.738422)
			(xy 396.303798 -292.777766) (xy 396.268305 -292.811858) (xy 396.227802 -292.839814) (xy 396.18334 -292.860912)
			(xy 396.136069 -292.874604) (xy 396.087214 -292.880536) (xy 396.038039 -292.878555) (xy 395.98982 -292.868711)
			(xy 395.943804 -292.851259) (xy 395.901183 -292.826652) (xy 395.863062 -292.795527) (xy 395.830427 -292.75869)
			(xy 395.804124 -292.717094) (xy 395.784833 -292.671818) (xy 395.773056 -292.624034) (xy 395.769096 -292.57498)
			(xy 395.430248 -292.57498) (xy 395.429753 -292.599587) (xy 395.421858 -292.648164) (xy 395.406274 -292.694845)
			(xy 395.383403 -292.738422) (xy 395.353838 -292.777766) (xy 395.318345 -292.811858) (xy 395.277842 -292.839814)
			(xy 395.23338 -292.860912) (xy 395.186109 -292.874604) (xy 395.137254 -292.880536) (xy 395.088079 -292.878555)
			(xy 395.03986 -292.868711) (xy 394.993844 -292.851259) (xy 394.951223 -292.826652) (xy 394.913102 -292.795527)
			(xy 394.880467 -292.75869) (xy 394.854164 -292.717094) (xy 394.834873 -292.671818) (xy 394.823096 -292.624034)
			(xy 394.819136 -292.57498) (xy 394.480288 -292.57498) (xy 394.479793 -292.599587) (xy 394.471898 -292.648164)
			(xy 394.456314 -292.694845) (xy 394.433443 -292.738422) (xy 394.403878 -292.777766) (xy 394.368385 -292.811858)
			(xy 394.327882 -292.839814) (xy 394.28342 -292.860912) (xy 394.236149 -292.874604) (xy 394.187294 -292.880536)
			(xy 394.138119 -292.878555) (xy 394.0899 -292.868711) (xy 394.043884 -292.851259) (xy 394.001263 -292.826652)
			(xy 393.963142 -292.795527) (xy 393.930507 -292.75869) (xy 393.904204 -292.717094) (xy 393.884913 -292.671818)
			(xy 393.873136 -292.624034) (xy 393.869176 -292.57498) (xy 393.530328 -292.57498) (xy 393.529833 -292.599587)
			(xy 393.521938 -292.648164) (xy 393.506354 -292.694845) (xy 393.483483 -292.738422) (xy 393.453918 -292.777766)
			(xy 393.418425 -292.811858) (xy 393.377922 -292.839814) (xy 393.33346 -292.860912) (xy 393.286189 -292.874604)
			(xy 393.237334 -292.880536) (xy 393.188159 -292.878555) (xy 393.13994 -292.868711) (xy 393.093924 -292.851259)
			(xy 393.051303 -292.826652) (xy 393.013182 -292.795527) (xy 392.980547 -292.75869) (xy 392.954244 -292.717094)
			(xy 392.934953 -292.671818) (xy 392.923176 -292.624034) (xy 392.919216 -292.57498) (xy 392.580114 -292.57498)
			(xy 392.579619 -292.599587) (xy 392.571724 -292.648164) (xy 392.55614 -292.694845) (xy 392.533269 -292.738422)
			(xy 392.503704 -292.777766) (xy 392.468211 -292.811858) (xy 392.427708 -292.839814) (xy 392.383246 -292.860912)
			(xy 392.335975 -292.874604) (xy 392.28712 -292.880536) (xy 392.237945 -292.878555) (xy 392.189726 -292.868711)
			(xy 392.14371 -292.851259) (xy 392.101089 -292.826652) (xy 392.062968 -292.795527) (xy 392.030333 -292.75869)
			(xy 392.00403 -292.717094) (xy 391.984739 -292.671818) (xy 391.972962 -292.624034) (xy 391.969002 -292.57498)
			(xy 391.630154 -292.57498) (xy 391.629659 -292.599587) (xy 391.621764 -292.648164) (xy 391.60618 -292.694845)
			(xy 391.583309 -292.738422) (xy 391.553744 -292.777766) (xy 391.518251 -292.811858) (xy 391.477748 -292.839814)
			(xy 391.433286 -292.860912) (xy 391.386015 -292.874604) (xy 391.33716 -292.880536) (xy 391.287985 -292.878555)
			(xy 391.239766 -292.868711) (xy 391.19375 -292.851259) (xy 391.151129 -292.826652) (xy 391.113008 -292.795527)
			(xy 391.080373 -292.75869) (xy 391.05407 -292.717094) (xy 391.034779 -292.671818) (xy 391.023002 -292.624034)
			(xy 391.019042 -292.57498) (xy 390.730994 -292.57498) (xy 390.730496 -292.601629) (xy 390.722553 -292.654333)
			(xy 390.706843 -292.705263) (xy 390.683717 -292.753284) (xy 390.653693 -292.797321) (xy 390.617441 -292.836392)
			(xy 390.57577 -292.869623) (xy 390.529612 -292.896272) (xy 390.479998 -292.915744) (xy 390.428036 -292.927604)
			(xy 390.374886 -292.931588) (xy 390.321736 -292.927604) (xy 390.269774 -292.915744) (xy 390.22016 -292.896272)
			(xy 390.174002 -292.869623) (xy 390.132331 -292.836392) (xy 390.096079 -292.797321) (xy 390.066055 -292.753284)
			(xy 390.042929 -292.705263) (xy 390.027219 -292.654333) (xy 390.019276 -292.601629) (xy 389.729407 -292.601629)
			(xy 389.721844 -292.648164) (xy 389.70626 -292.694845) (xy 389.683389 -292.738422) (xy 389.653824 -292.777766)
			(xy 389.618331 -292.811858) (xy 389.577828 -292.839814) (xy 389.533366 -292.860912) (xy 389.486095 -292.874604)
			(xy 389.43724 -292.880536) (xy 389.388065 -292.878555) (xy 389.339846 -292.868711) (xy 389.29383 -292.851259)
			(xy 389.251209 -292.826652) (xy 389.213088 -292.795527) (xy 389.180453 -292.75869) (xy 389.15415 -292.717094)
			(xy 389.134859 -292.671818) (xy 389.123082 -292.624034) (xy 389.119122 -292.57498) (xy 388.780269 -292.57498)
			(xy 388.779779 -292.599333) (xy 388.771884 -292.64791) (xy 388.7563 -292.694591) (xy 388.733429 -292.738168)
			(xy 388.703864 -292.777512) (xy 388.668371 -292.811604) (xy 388.627868 -292.83956) (xy 388.583406 -292.860658)
			(xy 388.536135 -292.87435) (xy 388.48728 -292.880282) (xy 388.438105 -292.878301) (xy 388.389886 -292.868457)
			(xy 388.34387 -292.851005) (xy 388.301249 -292.826398) (xy 388.263128 -292.795273) (xy 388.230493 -292.758436)
			(xy 388.20419 -292.71684) (xy 388.184899 -292.671564) (xy 388.173122 -292.62378) (xy 388.169162 -292.574726)
			(xy 387.830314 -292.574726) (xy 387.829819 -292.599333) (xy 387.821924 -292.64791) (xy 387.80634 -292.694591)
			(xy 387.783469 -292.738168) (xy 387.753904 -292.777512) (xy 387.718411 -292.811604) (xy 387.677908 -292.83956)
			(xy 387.633446 -292.860658) (xy 387.586175 -292.87435) (xy 387.53732 -292.880282) (xy 387.488145 -292.878301)
			(xy 387.439926 -292.868457) (xy 387.39391 -292.851005) (xy 387.351289 -292.826398) (xy 387.313168 -292.795273)
			(xy 387.280533 -292.758436) (xy 387.25423 -292.71684) (xy 387.234939 -292.671564) (xy 387.223162 -292.62378)
			(xy 387.219202 -292.574726) (xy 386.880349 -292.574726) (xy 386.880354 -292.57498) (xy 386.879859 -292.599587)
			(xy 386.871964 -292.648164) (xy 386.85638 -292.694845) (xy 386.833509 -292.738422) (xy 386.803944 -292.777766)
			(xy 386.768451 -292.811858) (xy 386.727948 -292.839814) (xy 386.683486 -292.860912) (xy 386.636215 -292.874604)
			(xy 386.58736 -292.880536) (xy 386.538185 -292.878555) (xy 386.489966 -292.868711) (xy 386.44395 -292.851259)
			(xy 386.401329 -292.826652) (xy 386.363208 -292.795527) (xy 386.330573 -292.75869) (xy 386.30427 -292.717094)
			(xy 386.284979 -292.671818) (xy 386.273202 -292.624034) (xy 386.269242 -292.57498) (xy 385.93014 -292.57498)
			(xy 385.929645 -292.599587) (xy 385.92175 -292.648164) (xy 385.906166 -292.694845) (xy 385.883295 -292.738422)
			(xy 385.85373 -292.777766) (xy 385.818237 -292.811858) (xy 385.777734 -292.839814) (xy 385.733272 -292.860912)
			(xy 385.686001 -292.874604) (xy 385.637146 -292.880536) (xy 385.587971 -292.878555) (xy 385.539752 -292.868711)
			(xy 385.493736 -292.851259) (xy 385.451115 -292.826652) (xy 385.412994 -292.795527) (xy 385.380359 -292.75869)
			(xy 385.354056 -292.717094) (xy 385.334765 -292.671818) (xy 385.322988 -292.624034) (xy 385.319028 -292.57498)
			(xy 384.98018 -292.57498) (xy 384.979685 -292.599587) (xy 384.97179 -292.648164) (xy 384.956206 -292.694845)
			(xy 384.933335 -292.738422) (xy 384.90377 -292.777766) (xy 384.868277 -292.811858) (xy 384.827774 -292.839814)
			(xy 384.783312 -292.860912) (xy 384.736041 -292.874604) (xy 384.687186 -292.880536) (xy 384.638011 -292.878555)
			(xy 384.589792 -292.868711) (xy 384.543776 -292.851259) (xy 384.501155 -292.826652) (xy 384.463034 -292.795527)
			(xy 384.430399 -292.75869) (xy 384.404096 -292.717094) (xy 384.384805 -292.671818) (xy 384.373028 -292.624034)
			(xy 384.369068 -292.57498) (xy 380.377831 -292.57498) (xy 380.388901 -292.59922) (xy 380.404256 -292.651515)
			(xy 380.412012 -292.705463) (xy 380.412498 -292.732714) (xy 380.411971 -292.762097) (xy 380.402938 -292.820164)
			(xy 380.385103 -292.876159) (xy 380.358889 -292.928754) (xy 380.324916 -292.976705) (xy 380.283989 -293.018876)
			(xy 380.26086 -293.037006) (xy 380.251462 -293.044372) (xy 380.241048 -293.064946) (xy 380.239524 -293.168832)
			(xy 380.24943 -293.189914) (xy 380.258574 -293.19728) (xy 380.280389 -293.215524) (xy 380.318933 -293.257334)
			(xy 380.350844 -293.304401) (xy 380.375417 -293.355684) (xy 380.392107 -293.410045) (xy 380.400545 -293.466281)
			(xy 380.401068 -293.494714) (xy 381.034542 -293.494714) (xy 381.038613 -293.439092) (xy 381.050739 -293.384655)
			(xy 381.070662 -293.332564) (xy 381.097958 -293.283929) (xy 381.132044 -293.239786) (xy 381.172193 -293.201077)
			(xy 381.217551 -293.168626) (xy 381.267151 -293.143125) (xy 381.319935 -293.125118) (xy 381.374778 -293.114988)
			(xy 381.430512 -293.112951) (xy 381.485949 -293.119051) (xy 381.539906 -293.133157) (xy 381.591235 -293.154969)
			(xy 381.638841 -293.184023) (xy 381.681709 -293.219698) (xy 381.718926 -293.261235) (xy 381.749699 -293.307748)
			(xy 381.773371 -293.358245) (xy 381.789439 -293.411652) (xy 381.797559 -293.466828) (xy 381.798068 -293.494714)
			(xy 381.921002 -293.494714) (xy 381.925073 -293.439092) (xy 381.937199 -293.384655) (xy 381.957122 -293.332564)
			(xy 381.984418 -293.283929) (xy 382.018504 -293.239786) (xy 382.058653 -293.201077) (xy 382.104011 -293.168626)
			(xy 382.153611 -293.143125) (xy 382.206395 -293.125118) (xy 382.261238 -293.114988) (xy 382.316972 -293.112951)
			(xy 382.372409 -293.119051) (xy 382.426366 -293.133157) (xy 382.477695 -293.154969) (xy 382.525301 -293.184023)
			(xy 382.568169 -293.219698) (xy 382.605386 -293.261235) (xy 382.636159 -293.307748) (xy 382.659831 -293.358245)
			(xy 382.675899 -293.411652) (xy 382.684019 -293.466828) (xy 382.684528 -293.494714) (xy 382.684019 -293.5226)
			(xy 382.683675 -293.52494) (xy 384.369068 -293.52494) (xy 384.373028 -293.475886) (xy 384.384805 -293.428102)
			(xy 384.404096 -293.382826) (xy 384.430399 -293.34123) (xy 384.463034 -293.304393) (xy 384.501155 -293.273268)
			(xy 384.543776 -293.248661) (xy 384.589792 -293.231209) (xy 384.638011 -293.221365) (xy 384.687186 -293.219384)
			(xy 384.736041 -293.225316) (xy 384.783312 -293.239008) (xy 384.827774 -293.260106) (xy 384.868277 -293.288062)
			(xy 384.90377 -293.322154) (xy 384.933335 -293.361498) (xy 384.956206 -293.405075) (xy 384.97179 -293.451756)
			(xy 384.979685 -293.500333) (xy 384.98018 -293.52494) (xy 385.319028 -293.52494) (xy 385.322988 -293.475886)
			(xy 385.334765 -293.428102) (xy 385.354056 -293.382826) (xy 385.380359 -293.34123) (xy 385.412994 -293.304393)
			(xy 385.451115 -293.273268) (xy 385.493736 -293.248661) (xy 385.539752 -293.231209) (xy 385.587971 -293.221365)
			(xy 385.637146 -293.219384) (xy 385.686001 -293.225316) (xy 385.733272 -293.239008) (xy 385.777734 -293.260106)
			(xy 385.818237 -293.288062) (xy 385.85373 -293.322154) (xy 385.883295 -293.361498) (xy 385.906166 -293.405075)
			(xy 385.92175 -293.451756) (xy 385.929645 -293.500333) (xy 385.93014 -293.52494) (xy 386.269242 -293.52494)
			(xy 386.273202 -293.475886) (xy 386.284979 -293.428102) (xy 386.30427 -293.382826) (xy 386.330573 -293.34123)
			(xy 386.363208 -293.304393) (xy 386.401329 -293.273268) (xy 386.44395 -293.248661) (xy 386.489966 -293.231209)
			(xy 386.538185 -293.221365) (xy 386.58736 -293.219384) (xy 386.636215 -293.225316) (xy 386.683486 -293.239008)
			(xy 386.727948 -293.260106) (xy 386.768451 -293.288062) (xy 386.803944 -293.322154) (xy 386.833509 -293.361498)
			(xy 386.85638 -293.405075) (xy 386.871964 -293.451756) (xy 386.879859 -293.500333) (xy 386.880354 -293.52494)
			(xy 387.219202 -293.52494) (xy 387.223162 -293.475886) (xy 387.234939 -293.428102) (xy 387.25423 -293.382826)
			(xy 387.280533 -293.34123) (xy 387.313168 -293.304393) (xy 387.351289 -293.273268) (xy 387.39391 -293.248661)
			(xy 387.439926 -293.231209) (xy 387.488145 -293.221365) (xy 387.53732 -293.219384) (xy 387.586175 -293.225316)
			(xy 387.633446 -293.239008) (xy 387.677908 -293.260106) (xy 387.718411 -293.288062) (xy 387.753904 -293.322154)
			(xy 387.783469 -293.361498) (xy 387.80634 -293.405075) (xy 387.821924 -293.451756) (xy 387.829819 -293.500333)
			(xy 387.830314 -293.52494) (xy 388.169162 -293.52494) (xy 388.173122 -293.475886) (xy 388.184899 -293.428102)
			(xy 388.20419 -293.382826) (xy 388.230493 -293.34123) (xy 388.263128 -293.304393) (xy 388.301249 -293.273268)
			(xy 388.34387 -293.248661) (xy 388.389886 -293.231209) (xy 388.438105 -293.221365) (xy 388.48728 -293.219384)
			(xy 388.536135 -293.225316) (xy 388.583406 -293.239008) (xy 388.627868 -293.260106) (xy 388.668371 -293.288062)
			(xy 388.703864 -293.322154) (xy 388.733429 -293.361498) (xy 388.7563 -293.405075) (xy 388.771884 -293.451756)
			(xy 388.779779 -293.500333) (xy 388.780274 -293.52494) (xy 389.119122 -293.52494) (xy 389.123082 -293.475886)
			(xy 389.134859 -293.428102) (xy 389.15415 -293.382826) (xy 389.180453 -293.34123) (xy 389.213088 -293.304393)
			(xy 389.251209 -293.273268) (xy 389.29383 -293.248661) (xy 389.339846 -293.231209) (xy 389.388065 -293.221365)
			(xy 389.43724 -293.219384) (xy 389.486095 -293.225316) (xy 389.533366 -293.239008) (xy 389.577828 -293.260106)
			(xy 389.618331 -293.288062) (xy 389.653824 -293.322154) (xy 389.683389 -293.361498) (xy 389.70626 -293.405075)
			(xy 389.721844 -293.451756) (xy 389.729739 -293.500333) (xy 389.730234 -293.52494) (xy 390.069082 -293.52494)
			(xy 390.073042 -293.475886) (xy 390.084819 -293.428102) (xy 390.10411 -293.382826) (xy 390.130413 -293.34123)
			(xy 390.163048 -293.304393) (xy 390.201169 -293.273268) (xy 390.24379 -293.248661) (xy 390.289806 -293.231209)
			(xy 390.338025 -293.221365) (xy 390.3872 -293.219384) (xy 390.436055 -293.225316) (xy 390.483326 -293.239008)
			(xy 390.527788 -293.260106) (xy 390.568291 -293.288062) (xy 390.603784 -293.322154) (xy 390.633349 -293.361498)
			(xy 390.65622 -293.405075) (xy 390.671804 -293.451756) (xy 390.679699 -293.500333) (xy 390.680194 -293.52494)
			(xy 390.679699 -293.549547) (xy 390.679367 -293.551589) (xy 390.969236 -293.551589) (xy 390.969236 -293.498291)
			(xy 390.977179 -293.445587) (xy 390.992889 -293.394657) (xy 391.016015 -293.346636) (xy 391.046039 -293.302599)
			(xy 391.082291 -293.263528) (xy 391.123962 -293.230297) (xy 391.17012 -293.203648) (xy 391.219734 -293.184176)
			(xy 391.271696 -293.172316) (xy 391.324846 -293.168333) (xy 391.377996 -293.172316) (xy 391.429958 -293.184176)
			(xy 391.479572 -293.203648) (xy 391.52573 -293.230297) (xy 391.567401 -293.263528) (xy 391.603653 -293.302599)
			(xy 391.633677 -293.346636) (xy 391.656803 -293.394657) (xy 391.672513 -293.445587) (xy 391.680456 -293.498291)
			(xy 391.680954 -293.52494) (xy 391.969002 -293.52494) (xy 391.972962 -293.475886) (xy 391.984739 -293.428102)
			(xy 392.00403 -293.382826) (xy 392.030333 -293.34123) (xy 392.062968 -293.304393) (xy 392.101089 -293.273268)
			(xy 392.14371 -293.248661) (xy 392.189726 -293.231209) (xy 392.237945 -293.221365) (xy 392.28712 -293.219384)
			(xy 392.335975 -293.225316) (xy 392.383246 -293.239008) (xy 392.427708 -293.260106) (xy 392.468211 -293.288062)
			(xy 392.503704 -293.322154) (xy 392.533269 -293.361498) (xy 392.55614 -293.405075) (xy 392.571724 -293.451756)
			(xy 392.579619 -293.500333) (xy 392.580114 -293.52494) (xy 393.869176 -293.52494) (xy 393.873136 -293.475886)
			(xy 393.884913 -293.428102) (xy 393.904204 -293.382826) (xy 393.930507 -293.34123) (xy 393.963142 -293.304393)
			(xy 394.001263 -293.273268) (xy 394.043884 -293.248661) (xy 394.0899 -293.231209) (xy 394.138119 -293.221365)
			(xy 394.187294 -293.219384) (xy 394.236149 -293.225316) (xy 394.28342 -293.239008) (xy 394.327882 -293.260106)
			(xy 394.368385 -293.288062) (xy 394.403878 -293.322154) (xy 394.433443 -293.361498) (xy 394.456314 -293.405075)
			(xy 394.471898 -293.451756) (xy 394.479793 -293.500333) (xy 394.480288 -293.52494) (xy 395.769096 -293.52494)
			(xy 395.773056 -293.475886) (xy 395.784833 -293.428102) (xy 395.804124 -293.382826) (xy 395.830427 -293.34123)
			(xy 395.863062 -293.304393) (xy 395.901183 -293.273268) (xy 395.943804 -293.248661) (xy 395.98982 -293.231209)
			(xy 396.038039 -293.221365) (xy 396.087214 -293.219384) (xy 396.136069 -293.225316) (xy 396.18334 -293.239008)
			(xy 396.227802 -293.260106) (xy 396.268305 -293.288062) (xy 396.303798 -293.322154) (xy 396.333363 -293.361498)
			(xy 396.356234 -293.405075) (xy 396.371818 -293.451756) (xy 396.379713 -293.500333) (xy 396.380208 -293.52494)
			(xy 396.719056 -293.52494) (xy 396.723016 -293.475886) (xy 396.734793 -293.428102) (xy 396.754084 -293.382826)
			(xy 396.780387 -293.34123) (xy 396.813022 -293.304393) (xy 396.851143 -293.273268) (xy 396.893764 -293.248661)
			(xy 396.93978 -293.231209) (xy 396.987999 -293.221365) (xy 397.037174 -293.219384) (xy 397.086029 -293.225316)
			(xy 397.1333 -293.239008) (xy 397.177762 -293.260106) (xy 397.218265 -293.288062) (xy 397.253758 -293.322154)
			(xy 397.283323 -293.361498) (xy 397.306194 -293.405075) (xy 397.321778 -293.451756) (xy 397.329673 -293.500333)
			(xy 397.330168 -293.52494) (xy 398.61923 -293.52494) (xy 398.62319 -293.475886) (xy 398.634967 -293.428102)
			(xy 398.654258 -293.382826) (xy 398.680561 -293.34123) (xy 398.713196 -293.304393) (xy 398.751317 -293.273268)
			(xy 398.793938 -293.248661) (xy 398.839954 -293.231209) (xy 398.888173 -293.221365) (xy 398.937348 -293.219384)
			(xy 398.986203 -293.225316) (xy 399.033474 -293.239008) (xy 399.077936 -293.260106) (xy 399.118439 -293.288062)
			(xy 399.153932 -293.322154) (xy 399.183497 -293.361498) (xy 399.206368 -293.405075) (xy 399.221952 -293.451756)
			(xy 399.229847 -293.500333) (xy 399.230342 -293.52494) (xy 400.51915 -293.52494) (xy 400.52311 -293.475886)
			(xy 400.534887 -293.428102) (xy 400.554178 -293.382826) (xy 400.580481 -293.34123) (xy 400.613116 -293.304393)
			(xy 400.651237 -293.273268) (xy 400.693858 -293.248661) (xy 400.739874 -293.231209) (xy 400.788093 -293.221365)
			(xy 400.837268 -293.219384) (xy 400.886123 -293.225316) (xy 400.933394 -293.239008) (xy 400.977856 -293.260106)
			(xy 401.018359 -293.288062) (xy 401.053852 -293.322154) (xy 401.083417 -293.361498) (xy 401.106288 -293.405075)
			(xy 401.121872 -293.451756) (xy 401.129767 -293.500333) (xy 401.130262 -293.52494) (xy 402.41907 -293.52494)
			(xy 402.42303 -293.475886) (xy 402.434807 -293.428102) (xy 402.454098 -293.382826) (xy 402.480401 -293.34123)
			(xy 402.513036 -293.304393) (xy 402.551157 -293.273268) (xy 402.593778 -293.248661) (xy 402.639794 -293.231209)
			(xy 402.688013 -293.221365) (xy 402.737188 -293.219384) (xy 402.786043 -293.225316) (xy 402.833314 -293.239008)
			(xy 402.877776 -293.260106) (xy 402.918279 -293.288062) (xy 402.953772 -293.322154) (xy 402.983337 -293.361498)
			(xy 403.006208 -293.405075) (xy 403.021792 -293.451756) (xy 403.029687 -293.500333) (xy 403.030182 -293.52494)
			(xy 404.31899 -293.52494) (xy 404.32295 -293.475886) (xy 404.334727 -293.428102) (xy 404.354018 -293.382826)
			(xy 404.380321 -293.34123) (xy 404.412956 -293.304393) (xy 404.451077 -293.273268) (xy 404.493698 -293.248661)
			(xy 404.539714 -293.231209) (xy 404.587933 -293.221365) (xy 404.637108 -293.219384) (xy 404.685963 -293.225316)
			(xy 404.733234 -293.239008) (xy 404.777696 -293.260106) (xy 404.818199 -293.288062) (xy 404.853692 -293.322154)
			(xy 404.883257 -293.361498) (xy 404.906128 -293.405075) (xy 404.921712 -293.451756) (xy 404.929607 -293.500333)
			(xy 404.930102 -293.52494) (xy 406.219164 -293.52494) (xy 406.223124 -293.475886) (xy 406.234901 -293.428102)
			(xy 406.254192 -293.382826) (xy 406.280495 -293.34123) (xy 406.31313 -293.304393) (xy 406.351251 -293.273268)
			(xy 406.393872 -293.248661) (xy 406.439888 -293.231209) (xy 406.488107 -293.221365) (xy 406.537282 -293.219384)
			(xy 406.586137 -293.225316) (xy 406.633408 -293.239008) (xy 406.67787 -293.260106) (xy 406.718373 -293.288062)
			(xy 406.753866 -293.322154) (xy 406.783431 -293.361498) (xy 406.806302 -293.405075) (xy 406.821886 -293.451756)
			(xy 406.829781 -293.500333) (xy 406.830276 -293.52494) (xy 409.069044 -293.52494) (xy 409.073004 -293.475886)
			(xy 409.084781 -293.428102) (xy 409.104072 -293.382826) (xy 409.130375 -293.34123) (xy 409.16301 -293.304393)
			(xy 409.201131 -293.273268) (xy 409.243752 -293.248661) (xy 409.289768 -293.231209) (xy 409.337987 -293.221365)
			(xy 409.387162 -293.219384) (xy 409.436017 -293.225316) (xy 409.483288 -293.239008) (xy 409.52775 -293.260106)
			(xy 409.568253 -293.288062) (xy 409.603746 -293.322154) (xy 409.633311 -293.361498) (xy 409.656182 -293.405075)
			(xy 409.671766 -293.451756) (xy 409.679661 -293.500333) (xy 409.680156 -293.52494) (xy 410.969218 -293.52494)
			(xy 410.973178 -293.475886) (xy 410.984955 -293.428102) (xy 411.004246 -293.382826) (xy 411.030549 -293.34123)
			(xy 411.063184 -293.304393) (xy 411.101305 -293.273268) (xy 411.143926 -293.248661) (xy 411.189942 -293.231209)
			(xy 411.238161 -293.221365) (xy 411.287336 -293.219384) (xy 411.336191 -293.225316) (xy 411.383462 -293.239008)
			(xy 411.427924 -293.260106) (xy 411.468427 -293.288062) (xy 411.50392 -293.322154) (xy 411.533485 -293.361498)
			(xy 411.556356 -293.405075) (xy 411.57194 -293.451756) (xy 411.579835 -293.500333) (xy 411.58033 -293.52494)
			(xy 412.869138 -293.52494) (xy 412.873098 -293.475886) (xy 412.884875 -293.428102) (xy 412.904166 -293.382826)
			(xy 412.930469 -293.34123) (xy 412.963104 -293.304393) (xy 413.001225 -293.273268) (xy 413.043846 -293.248661)
			(xy 413.089862 -293.231209) (xy 413.138081 -293.221365) (xy 413.187256 -293.219384) (xy 413.236111 -293.225316)
			(xy 413.283382 -293.239008) (xy 413.327844 -293.260106) (xy 413.368347 -293.288062) (xy 413.40384 -293.322154)
			(xy 413.433405 -293.361498) (xy 413.456276 -293.405075) (xy 413.47186 -293.451756) (xy 413.479755 -293.500333)
			(xy 413.48025 -293.52494) (xy 414.769058 -293.52494) (xy 414.773018 -293.475886) (xy 414.784795 -293.428102)
			(xy 414.804086 -293.382826) (xy 414.830389 -293.34123) (xy 414.863024 -293.304393) (xy 414.901145 -293.273268)
			(xy 414.943766 -293.248661) (xy 414.989782 -293.231209) (xy 415.038001 -293.221365) (xy 415.087176 -293.219384)
			(xy 415.136031 -293.225316) (xy 415.183302 -293.239008) (xy 415.227764 -293.260106) (xy 415.268267 -293.288062)
			(xy 415.30376 -293.322154) (xy 415.333325 -293.361498) (xy 415.356196 -293.405075) (xy 415.37178 -293.451756)
			(xy 415.379675 -293.500333) (xy 415.38017 -293.52494) (xy 416.668978 -293.52494) (xy 416.672938 -293.475886)
			(xy 416.684715 -293.428102) (xy 416.704006 -293.382826) (xy 416.730309 -293.34123) (xy 416.762944 -293.304393)
			(xy 416.801065 -293.273268) (xy 416.843686 -293.248661) (xy 416.889702 -293.231209) (xy 416.937921 -293.221365)
			(xy 416.987096 -293.219384) (xy 417.035951 -293.225316) (xy 417.083222 -293.239008) (xy 417.127684 -293.260106)
			(xy 417.168187 -293.288062) (xy 417.20368 -293.322154) (xy 417.233245 -293.361498) (xy 417.256116 -293.405075)
			(xy 417.2717 -293.451756) (xy 417.279595 -293.500333) (xy 417.28009 -293.52494) (xy 417.279595 -293.549547)
			(xy 417.2717 -293.598124) (xy 417.256116 -293.644805) (xy 417.233245 -293.688382) (xy 417.20368 -293.727726)
			(xy 417.168187 -293.761818) (xy 417.127684 -293.789774) (xy 417.083222 -293.810872) (xy 417.035951 -293.824564)
			(xy 416.987096 -293.830496) (xy 416.937921 -293.828515) (xy 416.889702 -293.818671) (xy 416.843686 -293.801219)
			(xy 416.801065 -293.776612) (xy 416.762944 -293.745487) (xy 416.730309 -293.70865) (xy 416.704006 -293.667054)
			(xy 416.684715 -293.621778) (xy 416.672938 -293.573994) (xy 416.668978 -293.52494) (xy 415.38017 -293.52494)
			(xy 415.379675 -293.549547) (xy 415.37178 -293.598124) (xy 415.356196 -293.644805) (xy 415.333325 -293.688382)
			(xy 415.30376 -293.727726) (xy 415.268267 -293.761818) (xy 415.227764 -293.789774) (xy 415.183302 -293.810872)
			(xy 415.136031 -293.824564) (xy 415.087176 -293.830496) (xy 415.038001 -293.828515) (xy 414.989782 -293.818671)
			(xy 414.943766 -293.801219) (xy 414.901145 -293.776612) (xy 414.863024 -293.745487) (xy 414.830389 -293.70865)
			(xy 414.804086 -293.667054) (xy 414.784795 -293.621778) (xy 414.773018 -293.573994) (xy 414.769058 -293.52494)
			(xy 413.48025 -293.52494) (xy 413.479755 -293.549547) (xy 413.47186 -293.598124) (xy 413.456276 -293.644805)
			(xy 413.433405 -293.688382) (xy 413.40384 -293.727726) (xy 413.368347 -293.761818) (xy 413.327844 -293.789774)
			(xy 413.283382 -293.810872) (xy 413.236111 -293.824564) (xy 413.187256 -293.830496) (xy 413.138081 -293.828515)
			(xy 413.089862 -293.818671) (xy 413.043846 -293.801219) (xy 413.001225 -293.776612) (xy 412.963104 -293.745487)
			(xy 412.930469 -293.70865) (xy 412.904166 -293.667054) (xy 412.884875 -293.621778) (xy 412.873098 -293.573994)
			(xy 412.869138 -293.52494) (xy 411.58033 -293.52494) (xy 411.579835 -293.549547) (xy 411.57194 -293.598124)
			(xy 411.556356 -293.644805) (xy 411.533485 -293.688382) (xy 411.50392 -293.727726) (xy 411.468427 -293.761818)
			(xy 411.427924 -293.789774) (xy 411.383462 -293.810872) (xy 411.336191 -293.824564) (xy 411.287336 -293.830496)
			(xy 411.238161 -293.828515) (xy 411.189942 -293.818671) (xy 411.143926 -293.801219) (xy 411.101305 -293.776612)
			(xy 411.063184 -293.745487) (xy 411.030549 -293.70865) (xy 411.004246 -293.667054) (xy 410.984955 -293.621778)
			(xy 410.973178 -293.573994) (xy 410.969218 -293.52494) (xy 409.680156 -293.52494) (xy 409.679661 -293.549547)
			(xy 409.671766 -293.598124) (xy 409.656182 -293.644805) (xy 409.633311 -293.688382) (xy 409.603746 -293.727726)
			(xy 409.568253 -293.761818) (xy 409.52775 -293.789774) (xy 409.483288 -293.810872) (xy 409.436017 -293.824564)
			(xy 409.387162 -293.830496) (xy 409.337987 -293.828515) (xy 409.289768 -293.818671) (xy 409.243752 -293.801219)
			(xy 409.201131 -293.776612) (xy 409.16301 -293.745487) (xy 409.130375 -293.70865) (xy 409.104072 -293.667054)
			(xy 409.084781 -293.621778) (xy 409.073004 -293.573994) (xy 409.069044 -293.52494) (xy 406.830276 -293.52494)
			(xy 406.829781 -293.549547) (xy 406.821886 -293.598124) (xy 406.806302 -293.644805) (xy 406.783431 -293.688382)
			(xy 406.753866 -293.727726) (xy 406.718373 -293.761818) (xy 406.67787 -293.789774) (xy 406.633408 -293.810872)
			(xy 406.586137 -293.824564) (xy 406.537282 -293.830496) (xy 406.488107 -293.828515) (xy 406.439888 -293.818671)
			(xy 406.393872 -293.801219) (xy 406.351251 -293.776612) (xy 406.31313 -293.745487) (xy 406.280495 -293.70865)
			(xy 406.254192 -293.667054) (xy 406.234901 -293.621778) (xy 406.223124 -293.573994) (xy 406.219164 -293.52494)
			(xy 404.930102 -293.52494) (xy 404.929607 -293.549547) (xy 404.921712 -293.598124) (xy 404.906128 -293.644805)
			(xy 404.883257 -293.688382) (xy 404.853692 -293.727726) (xy 404.818199 -293.761818) (xy 404.777696 -293.789774)
			(xy 404.733234 -293.810872) (xy 404.685963 -293.824564) (xy 404.637108 -293.830496) (xy 404.587933 -293.828515)
			(xy 404.539714 -293.818671) (xy 404.493698 -293.801219) (xy 404.451077 -293.776612) (xy 404.412956 -293.745487)
			(xy 404.380321 -293.70865) (xy 404.354018 -293.667054) (xy 404.334727 -293.621778) (xy 404.32295 -293.573994)
			(xy 404.31899 -293.52494) (xy 403.030182 -293.52494) (xy 403.029687 -293.549547) (xy 403.021792 -293.598124)
			(xy 403.006208 -293.644805) (xy 402.983337 -293.688382) (xy 402.953772 -293.727726) (xy 402.918279 -293.761818)
			(xy 402.877776 -293.789774) (xy 402.833314 -293.810872) (xy 402.786043 -293.824564) (xy 402.737188 -293.830496)
			(xy 402.688013 -293.828515) (xy 402.639794 -293.818671) (xy 402.593778 -293.801219) (xy 402.551157 -293.776612)
			(xy 402.513036 -293.745487) (xy 402.480401 -293.70865) (xy 402.454098 -293.667054) (xy 402.434807 -293.621778)
			(xy 402.42303 -293.573994) (xy 402.41907 -293.52494) (xy 401.130262 -293.52494) (xy 401.129767 -293.549547)
			(xy 401.121872 -293.598124) (xy 401.106288 -293.644805) (xy 401.083417 -293.688382) (xy 401.053852 -293.727726)
			(xy 401.018359 -293.761818) (xy 400.977856 -293.789774) (xy 400.933394 -293.810872) (xy 400.886123 -293.824564)
			(xy 400.837268 -293.830496) (xy 400.788093 -293.828515) (xy 400.739874 -293.818671) (xy 400.693858 -293.801219)
			(xy 400.651237 -293.776612) (xy 400.613116 -293.745487) (xy 400.580481 -293.70865) (xy 400.554178 -293.667054)
			(xy 400.534887 -293.621778) (xy 400.52311 -293.573994) (xy 400.51915 -293.52494) (xy 399.230342 -293.52494)
			(xy 399.229847 -293.549547) (xy 399.221952 -293.598124) (xy 399.206368 -293.644805) (xy 399.183497 -293.688382)
			(xy 399.153932 -293.727726) (xy 399.118439 -293.761818) (xy 399.077936 -293.789774) (xy 399.033474 -293.810872)
			(xy 398.986203 -293.824564) (xy 398.937348 -293.830496) (xy 398.888173 -293.828515) (xy 398.839954 -293.818671)
			(xy 398.793938 -293.801219) (xy 398.751317 -293.776612) (xy 398.713196 -293.745487) (xy 398.680561 -293.70865)
			(xy 398.654258 -293.667054) (xy 398.634967 -293.621778) (xy 398.62319 -293.573994) (xy 398.61923 -293.52494)
			(xy 397.330168 -293.52494) (xy 397.329673 -293.549547) (xy 397.321778 -293.598124) (xy 397.306194 -293.644805)
			(xy 397.283323 -293.688382) (xy 397.253758 -293.727726) (xy 397.218265 -293.761818) (xy 397.177762 -293.789774)
			(xy 397.1333 -293.810872) (xy 397.086029 -293.824564) (xy 397.037174 -293.830496) (xy 396.987999 -293.828515)
			(xy 396.93978 -293.818671) (xy 396.893764 -293.801219) (xy 396.851143 -293.776612) (xy 396.813022 -293.745487)
			(xy 396.780387 -293.70865) (xy 396.754084 -293.667054) (xy 396.734793 -293.621778) (xy 396.723016 -293.573994)
			(xy 396.719056 -293.52494) (xy 396.380208 -293.52494) (xy 396.379713 -293.549547) (xy 396.371818 -293.598124)
			(xy 396.356234 -293.644805) (xy 396.333363 -293.688382) (xy 396.303798 -293.727726) (xy 396.268305 -293.761818)
			(xy 396.227802 -293.789774) (xy 396.18334 -293.810872) (xy 396.136069 -293.824564) (xy 396.087214 -293.830496)
			(xy 396.038039 -293.828515) (xy 395.98982 -293.818671) (xy 395.943804 -293.801219) (xy 395.901183 -293.776612)
			(xy 395.863062 -293.745487) (xy 395.830427 -293.70865) (xy 395.804124 -293.667054) (xy 395.784833 -293.621778)
			(xy 395.773056 -293.573994) (xy 395.769096 -293.52494) (xy 394.480288 -293.52494) (xy 394.479793 -293.549547)
			(xy 394.471898 -293.598124) (xy 394.456314 -293.644805) (xy 394.433443 -293.688382) (xy 394.403878 -293.727726)
			(xy 394.368385 -293.761818) (xy 394.327882 -293.789774) (xy 394.28342 -293.810872) (xy 394.236149 -293.824564)
			(xy 394.187294 -293.830496) (xy 394.138119 -293.828515) (xy 394.0899 -293.818671) (xy 394.043884 -293.801219)
			(xy 394.001263 -293.776612) (xy 393.963142 -293.745487) (xy 393.930507 -293.70865) (xy 393.904204 -293.667054)
			(xy 393.884913 -293.621778) (xy 393.873136 -293.573994) (xy 393.869176 -293.52494) (xy 392.580114 -293.52494)
			(xy 392.579619 -293.549547) (xy 392.571724 -293.598124) (xy 392.55614 -293.644805) (xy 392.533269 -293.688382)
			(xy 392.503704 -293.727726) (xy 392.468211 -293.761818) (xy 392.427708 -293.789774) (xy 392.383246 -293.810872)
			(xy 392.335975 -293.824564) (xy 392.28712 -293.830496) (xy 392.237945 -293.828515) (xy 392.189726 -293.818671)
			(xy 392.14371 -293.801219) (xy 392.101089 -293.776612) (xy 392.062968 -293.745487) (xy 392.030333 -293.70865)
			(xy 392.00403 -293.667054) (xy 391.984739 -293.621778) (xy 391.972962 -293.573994) (xy 391.969002 -293.52494)
			(xy 391.680954 -293.52494) (xy 391.680456 -293.551589) (xy 391.672513 -293.604293) (xy 391.656803 -293.655223)
			(xy 391.633677 -293.703244) (xy 391.603653 -293.747281) (xy 391.567401 -293.786352) (xy 391.52573 -293.819583)
			(xy 391.479572 -293.846232) (xy 391.429958 -293.865704) (xy 391.377996 -293.877564) (xy 391.324846 -293.881548)
			(xy 391.271696 -293.877564) (xy 391.219734 -293.865704) (xy 391.17012 -293.846232) (xy 391.123962 -293.819583)
			(xy 391.082291 -293.786352) (xy 391.046039 -293.747281) (xy 391.016015 -293.703244) (xy 390.992889 -293.655223)
			(xy 390.977179 -293.604293) (xy 390.969236 -293.551589) (xy 390.679367 -293.551589) (xy 390.671804 -293.598124)
			(xy 390.65622 -293.644805) (xy 390.633349 -293.688382) (xy 390.603784 -293.727726) (xy 390.568291 -293.761818)
			(xy 390.527788 -293.789774) (xy 390.483326 -293.810872) (xy 390.436055 -293.824564) (xy 390.3872 -293.830496)
			(xy 390.338025 -293.828515) (xy 390.289806 -293.818671) (xy 390.24379 -293.801219) (xy 390.201169 -293.776612)
			(xy 390.163048 -293.745487) (xy 390.130413 -293.70865) (xy 390.10411 -293.667054) (xy 390.084819 -293.621778)
			(xy 390.073042 -293.573994) (xy 390.069082 -293.52494) (xy 389.730234 -293.52494) (xy 389.729739 -293.549547)
			(xy 389.721844 -293.598124) (xy 389.70626 -293.644805) (xy 389.683389 -293.688382) (xy 389.653824 -293.727726)
			(xy 389.618331 -293.761818) (xy 389.577828 -293.789774) (xy 389.533366 -293.810872) (xy 389.486095 -293.824564)
			(xy 389.43724 -293.830496) (xy 389.388065 -293.828515) (xy 389.339846 -293.818671) (xy 389.29383 -293.801219)
			(xy 389.251209 -293.776612) (xy 389.213088 -293.745487) (xy 389.180453 -293.70865) (xy 389.15415 -293.667054)
			(xy 389.134859 -293.621778) (xy 389.123082 -293.573994) (xy 389.119122 -293.52494) (xy 388.780274 -293.52494)
			(xy 388.779779 -293.549547) (xy 388.771884 -293.598124) (xy 388.7563 -293.644805) (xy 388.733429 -293.688382)
			(xy 388.703864 -293.727726) (xy 388.668371 -293.761818) (xy 388.627868 -293.789774) (xy 388.583406 -293.810872)
			(xy 388.536135 -293.824564) (xy 388.48728 -293.830496) (xy 388.438105 -293.828515) (xy 388.389886 -293.818671)
			(xy 388.34387 -293.801219) (xy 388.301249 -293.776612) (xy 388.263128 -293.745487) (xy 388.230493 -293.70865)
			(xy 388.20419 -293.667054) (xy 388.184899 -293.621778) (xy 388.173122 -293.573994) (xy 388.169162 -293.52494)
			(xy 387.830314 -293.52494) (xy 387.829819 -293.549547) (xy 387.821924 -293.598124) (xy 387.80634 -293.644805)
			(xy 387.783469 -293.688382) (xy 387.753904 -293.727726) (xy 387.718411 -293.761818) (xy 387.677908 -293.789774)
			(xy 387.633446 -293.810872) (xy 387.586175 -293.824564) (xy 387.53732 -293.830496) (xy 387.488145 -293.828515)
			(xy 387.439926 -293.818671) (xy 387.39391 -293.801219) (xy 387.351289 -293.776612) (xy 387.313168 -293.745487)
			(xy 387.280533 -293.70865) (xy 387.25423 -293.667054) (xy 387.234939 -293.621778) (xy 387.223162 -293.573994)
			(xy 387.219202 -293.52494) (xy 386.880354 -293.52494) (xy 386.879859 -293.549547) (xy 386.871964 -293.598124)
			(xy 386.85638 -293.644805) (xy 386.833509 -293.688382) (xy 386.803944 -293.727726) (xy 386.768451 -293.761818)
			(xy 386.727948 -293.789774) (xy 386.683486 -293.810872) (xy 386.636215 -293.824564) (xy 386.58736 -293.830496)
			(xy 386.538185 -293.828515) (xy 386.489966 -293.818671) (xy 386.44395 -293.801219) (xy 386.401329 -293.776612)
			(xy 386.363208 -293.745487) (xy 386.330573 -293.70865) (xy 386.30427 -293.667054) (xy 386.284979 -293.621778)
			(xy 386.273202 -293.573994) (xy 386.269242 -293.52494) (xy 385.93014 -293.52494) (xy 385.929645 -293.549547)
			(xy 385.92175 -293.598124) (xy 385.906166 -293.644805) (xy 385.883295 -293.688382) (xy 385.85373 -293.727726)
			(xy 385.818237 -293.761818) (xy 385.777734 -293.789774) (xy 385.733272 -293.810872) (xy 385.686001 -293.824564)
			(xy 385.637146 -293.830496) (xy 385.587971 -293.828515) (xy 385.539752 -293.818671) (xy 385.493736 -293.801219)
			(xy 385.451115 -293.776612) (xy 385.412994 -293.745487) (xy 385.380359 -293.70865) (xy 385.354056 -293.667054)
			(xy 385.334765 -293.621778) (xy 385.322988 -293.573994) (xy 385.319028 -293.52494) (xy 384.98018 -293.52494)
			(xy 384.979685 -293.549547) (xy 384.97179 -293.598124) (xy 384.956206 -293.644805) (xy 384.933335 -293.688382)
			(xy 384.90377 -293.727726) (xy 384.868277 -293.761818) (xy 384.827774 -293.789774) (xy 384.783312 -293.810872)
			(xy 384.736041 -293.824564) (xy 384.687186 -293.830496) (xy 384.638011 -293.828515) (xy 384.589792 -293.818671)
			(xy 384.543776 -293.801219) (xy 384.501155 -293.776612) (xy 384.463034 -293.745487) (xy 384.430399 -293.70865)
			(xy 384.404096 -293.667054) (xy 384.384805 -293.621778) (xy 384.373028 -293.573994) (xy 384.369068 -293.52494)
			(xy 382.683675 -293.52494) (xy 382.675899 -293.577776) (xy 382.659831 -293.631183) (xy 382.636159 -293.68168)
			(xy 382.605386 -293.728193) (xy 382.568169 -293.76973) (xy 382.525301 -293.805405) (xy 382.477695 -293.834459)
			(xy 382.426366 -293.856271) (xy 382.372409 -293.870377) (xy 382.316972 -293.876477) (xy 382.261238 -293.87444)
			(xy 382.206395 -293.86431) (xy 382.153611 -293.846303) (xy 382.104011 -293.820802) (xy 382.058653 -293.788351)
			(xy 382.018504 -293.749642) (xy 381.984418 -293.705499) (xy 381.957122 -293.656864) (xy 381.937199 -293.604773)
			(xy 381.925073 -293.550336) (xy 381.921002 -293.494714) (xy 381.798068 -293.494714) (xy 381.797559 -293.5226)
			(xy 381.789439 -293.577776) (xy 381.773371 -293.631183) (xy 381.749699 -293.68168) (xy 381.718926 -293.728193)
			(xy 381.681709 -293.76973) (xy 381.638841 -293.805405) (xy 381.591235 -293.834459) (xy 381.539906 -293.856271)
			(xy 381.485949 -293.870377) (xy 381.430512 -293.876477) (xy 381.374778 -293.87444) (xy 381.319935 -293.86431)
			(xy 381.267151 -293.846303) (xy 381.217551 -293.820802) (xy 381.172193 -293.788351) (xy 381.132044 -293.749642)
			(xy 381.097958 -293.705499) (xy 381.070662 -293.656864) (xy 381.050739 -293.604773) (xy 381.038613 -293.550336)
			(xy 381.034542 -293.494714) (xy 380.401068 -293.494714) (xy 380.400582 -293.521965) (xy 380.392826 -293.575913)
			(xy 380.377471 -293.628208) (xy 380.354829 -293.677785) (xy 380.325363 -293.723635) (xy 380.289672 -293.764826)
			(xy 380.248481 -293.800517) (xy 380.202631 -293.829983) (xy 380.153054 -293.852625) (xy 380.100759 -293.86798)
			(xy 380.046811 -293.875736) (xy 379.992309 -293.875736) (xy 379.938361 -293.86798) (xy 379.886066 -293.852625)
			(xy 379.836489 -293.829983) (xy 379.790639 -293.800517) (xy 379.749448 -293.764826) (xy 379.713757 -293.723635)
			(xy 379.684291 -293.677785) (xy 379.661649 -293.628208) (xy 379.646294 -293.575913) (xy 379.638538 -293.521965)
			(xy 379.638052 -293.494714) (xy 367.448592 -293.494714) (xy 366.96396 -293.979346) (xy 366.956562 -293.986192)
			(xy 366.937963 -293.99392) (xy 366.927892 -293.994332) (xy 351.818448 -293.994332) (xy 351.808383 -293.994765)
			(xy 351.789795 -294.002497) (xy 351.78238 -294.009318) (xy 351.160842 -294.630856) (xy 374.111518 -294.630856)
			(xy 374.115589 -294.575234) (xy 374.127715 -294.520797) (xy 374.147638 -294.468706) (xy 374.174934 -294.420071)
			(xy 374.20902 -294.375928) (xy 374.249169 -294.337219) (xy 374.294527 -294.304768) (xy 374.344127 -294.279267)
			(xy 374.396911 -294.26126) (xy 374.451754 -294.25113) (xy 374.507488 -294.249093) (xy 374.562925 -294.255193)
			(xy 374.616882 -294.269299) (xy 374.668211 -294.291111) (xy 374.715817 -294.320165) (xy 374.758685 -294.35584)
			(xy 374.795902 -294.397377) (xy 374.826675 -294.44389) (xy 374.850347 -294.494387) (xy 374.866415 -294.547794)
			(xy 374.874535 -294.60297) (xy 374.875044 -294.630856) (xy 375.596656 -294.630856) (xy 375.600727 -294.575234)
			(xy 375.612853 -294.520797) (xy 375.632776 -294.468706) (xy 375.660072 -294.420071) (xy 375.694158 -294.375928)
			(xy 375.734307 -294.337219) (xy 375.779665 -294.304768) (xy 375.829265 -294.279267) (xy 375.882049 -294.26126)
			(xy 375.936892 -294.25113) (xy 375.992626 -294.249093) (xy 376.048063 -294.255193) (xy 376.10202 -294.269299)
			(xy 376.153349 -294.291111) (xy 376.200955 -294.320165) (xy 376.243823 -294.35584) (xy 376.28104 -294.397377)
			(xy 376.311813 -294.44389) (xy 376.32635 -294.4749) (xy 384.369068 -294.4749) (xy 384.373028 -294.425846)
			(xy 384.384805 -294.378062) (xy 384.404096 -294.332786) (xy 384.430399 -294.29119) (xy 384.463034 -294.254353)
			(xy 384.501155 -294.223228) (xy 384.543776 -294.198621) (xy 384.589792 -294.181169) (xy 384.638011 -294.171325)
			(xy 384.687186 -294.169344) (xy 384.736041 -294.175276) (xy 384.783312 -294.188968) (xy 384.827774 -294.210066)
			(xy 384.868277 -294.238022) (xy 384.90377 -294.272114) (xy 384.933335 -294.311458) (xy 384.956206 -294.355035)
			(xy 384.97179 -294.401716) (xy 384.979685 -294.450293) (xy 384.98018 -294.4749) (xy 385.319028 -294.4749)
			(xy 385.322988 -294.425846) (xy 385.334765 -294.378062) (xy 385.354056 -294.332786) (xy 385.380359 -294.29119)
			(xy 385.412994 -294.254353) (xy 385.451115 -294.223228) (xy 385.493736 -294.198621) (xy 385.539752 -294.181169)
			(xy 385.587971 -294.171325) (xy 385.637146 -294.169344) (xy 385.686001 -294.175276) (xy 385.733272 -294.188968)
			(xy 385.777734 -294.210066) (xy 385.818237 -294.238022) (xy 385.85373 -294.272114) (xy 385.883295 -294.311458)
			(xy 385.906166 -294.355035) (xy 385.92175 -294.401716) (xy 385.929645 -294.450293) (xy 385.93014 -294.4749)
			(xy 386.269242 -294.4749) (xy 386.273202 -294.425846) (xy 386.284979 -294.378062) (xy 386.30427 -294.332786)
			(xy 386.330573 -294.29119) (xy 386.363208 -294.254353) (xy 386.401329 -294.223228) (xy 386.44395 -294.198621)
			(xy 386.489966 -294.181169) (xy 386.538185 -294.171325) (xy 386.58736 -294.169344) (xy 386.636215 -294.175276)
			(xy 386.683486 -294.188968) (xy 386.727948 -294.210066) (xy 386.768451 -294.238022) (xy 386.803944 -294.272114)
			(xy 386.833509 -294.311458) (xy 386.85638 -294.355035) (xy 386.871964 -294.401716) (xy 386.879859 -294.450293)
			(xy 386.880354 -294.4749) (xy 389.119122 -294.4749) (xy 389.123082 -294.425846) (xy 389.134859 -294.378062)
			(xy 389.15415 -294.332786) (xy 389.180453 -294.29119) (xy 389.213088 -294.254353) (xy 389.251209 -294.223228)
			(xy 389.29383 -294.198621) (xy 389.339846 -294.181169) (xy 389.388065 -294.171325) (xy 389.43724 -294.169344)
			(xy 389.486095 -294.175276) (xy 389.533366 -294.188968) (xy 389.577828 -294.210066) (xy 389.618331 -294.238022)
			(xy 389.653824 -294.272114) (xy 389.683389 -294.311458) (xy 389.70626 -294.355035) (xy 389.721844 -294.401716)
			(xy 389.729739 -294.450293) (xy 389.730234 -294.4749) (xy 389.729739 -294.499507) (xy 389.729407 -294.501549)
			(xy 390.019276 -294.501549) (xy 390.019276 -294.448251) (xy 390.027219 -294.395547) (xy 390.042929 -294.344617)
			(xy 390.066055 -294.296596) (xy 390.096079 -294.252559) (xy 390.132331 -294.213488) (xy 390.174002 -294.180257)
			(xy 390.22016 -294.153608) (xy 390.269774 -294.134136) (xy 390.321736 -294.122276) (xy 390.374886 -294.118293)
			(xy 390.428036 -294.122276) (xy 390.479998 -294.134136) (xy 390.529612 -294.153608) (xy 390.57577 -294.180257)
			(xy 390.617441 -294.213488) (xy 390.653693 -294.252559) (xy 390.683717 -294.296596) (xy 390.706843 -294.344617)
			(xy 390.722553 -294.395547) (xy 390.730496 -294.448251) (xy 390.730994 -294.4749) (xy 391.019042 -294.4749)
			(xy 391.023002 -294.425846) (xy 391.034779 -294.378062) (xy 391.05407 -294.332786) (xy 391.080373 -294.29119)
			(xy 391.113008 -294.254353) (xy 391.151129 -294.223228) (xy 391.19375 -294.198621) (xy 391.239766 -294.181169)
			(xy 391.287985 -294.171325) (xy 391.33716 -294.169344) (xy 391.386015 -294.175276) (xy 391.433286 -294.188968)
			(xy 391.477748 -294.210066) (xy 391.518251 -294.238022) (xy 391.553744 -294.272114) (xy 391.583309 -294.311458)
			(xy 391.60618 -294.355035) (xy 391.621764 -294.401716) (xy 391.629659 -294.450293) (xy 391.630154 -294.4749)
			(xy 391.969002 -294.4749) (xy 391.972962 -294.425846) (xy 391.984739 -294.378062) (xy 392.00403 -294.332786)
			(xy 392.030333 -294.29119) (xy 392.062968 -294.254353) (xy 392.101089 -294.223228) (xy 392.14371 -294.198621)
			(xy 392.189726 -294.181169) (xy 392.237945 -294.171325) (xy 392.28712 -294.169344) (xy 392.335975 -294.175276)
			(xy 392.383246 -294.188968) (xy 392.427708 -294.210066) (xy 392.468211 -294.238022) (xy 392.503704 -294.272114)
			(xy 392.533269 -294.311458) (xy 392.55614 -294.355035) (xy 392.571724 -294.401716) (xy 392.579619 -294.450293)
			(xy 392.580114 -294.4749) (xy 392.919216 -294.4749) (xy 392.923176 -294.425846) (xy 392.934953 -294.378062)
			(xy 392.954244 -294.332786) (xy 392.980547 -294.29119) (xy 393.013182 -294.254353) (xy 393.051303 -294.223228)
			(xy 393.093924 -294.198621) (xy 393.13994 -294.181169) (xy 393.188159 -294.171325) (xy 393.237334 -294.169344)
			(xy 393.286189 -294.175276) (xy 393.33346 -294.188968) (xy 393.377922 -294.210066) (xy 393.418425 -294.238022)
			(xy 393.453918 -294.272114) (xy 393.483483 -294.311458) (xy 393.506354 -294.355035) (xy 393.521938 -294.401716)
			(xy 393.529833 -294.450293) (xy 393.530328 -294.4749) (xy 393.869176 -294.4749) (xy 393.873136 -294.425846)
			(xy 393.884913 -294.378062) (xy 393.904204 -294.332786) (xy 393.930507 -294.29119) (xy 393.963142 -294.254353)
			(xy 394.001263 -294.223228) (xy 394.043884 -294.198621) (xy 394.0899 -294.181169) (xy 394.138119 -294.171325)
			(xy 394.187294 -294.169344) (xy 394.236149 -294.175276) (xy 394.28342 -294.188968) (xy 394.327882 -294.210066)
			(xy 394.368385 -294.238022) (xy 394.403878 -294.272114) (xy 394.433443 -294.311458) (xy 394.456314 -294.355035)
			(xy 394.471898 -294.401716) (xy 394.479793 -294.450293) (xy 394.480288 -294.4749) (xy 394.819136 -294.4749)
			(xy 394.823096 -294.425846) (xy 394.834873 -294.378062) (xy 394.854164 -294.332786) (xy 394.880467 -294.29119)
			(xy 394.913102 -294.254353) (xy 394.951223 -294.223228) (xy 394.993844 -294.198621) (xy 395.03986 -294.181169)
			(xy 395.088079 -294.171325) (xy 395.137254 -294.169344) (xy 395.186109 -294.175276) (xy 395.23338 -294.188968)
			(xy 395.277842 -294.210066) (xy 395.318345 -294.238022) (xy 395.353838 -294.272114) (xy 395.383403 -294.311458)
			(xy 395.406274 -294.355035) (xy 395.421858 -294.401716) (xy 395.429753 -294.450293) (xy 395.430248 -294.4749)
			(xy 395.769096 -294.4749) (xy 395.773056 -294.425846) (xy 395.784833 -294.378062) (xy 395.804124 -294.332786)
			(xy 395.830427 -294.29119) (xy 395.863062 -294.254353) (xy 395.901183 -294.223228) (xy 395.943804 -294.198621)
			(xy 395.98982 -294.181169) (xy 396.038039 -294.171325) (xy 396.087214 -294.169344) (xy 396.136069 -294.175276)
			(xy 396.18334 -294.188968) (xy 396.227802 -294.210066) (xy 396.268305 -294.238022) (xy 396.303798 -294.272114)
			(xy 396.333363 -294.311458) (xy 396.356234 -294.355035) (xy 396.371818 -294.401716) (xy 396.379713 -294.450293)
			(xy 396.380208 -294.4749) (xy 397.669016 -294.4749) (xy 397.672976 -294.425846) (xy 397.684753 -294.378062)
			(xy 397.704044 -294.332786) (xy 397.730347 -294.29119) (xy 397.762982 -294.254353) (xy 397.801103 -294.223228)
			(xy 397.843724 -294.198621) (xy 397.88974 -294.181169) (xy 397.937959 -294.171325) (xy 397.987134 -294.169344)
			(xy 398.035989 -294.175276) (xy 398.08326 -294.188968) (xy 398.127722 -294.210066) (xy 398.168225 -294.238022)
			(xy 398.203718 -294.272114) (xy 398.233283 -294.311458) (xy 398.256154 -294.355035) (xy 398.271738 -294.401716)
			(xy 398.279633 -294.450293) (xy 398.280128 -294.4749) (xy 399.56919 -294.4749) (xy 399.57315 -294.425846)
			(xy 399.584927 -294.378062) (xy 399.604218 -294.332786) (xy 399.630521 -294.29119) (xy 399.663156 -294.254353)
			(xy 399.701277 -294.223228) (xy 399.743898 -294.198621) (xy 399.789914 -294.181169) (xy 399.838133 -294.171325)
			(xy 399.887308 -294.169344) (xy 399.936163 -294.175276) (xy 399.983434 -294.188968) (xy 400.027896 -294.210066)
			(xy 400.068399 -294.238022) (xy 400.103892 -294.272114) (xy 400.133457 -294.311458) (xy 400.156328 -294.355035)
			(xy 400.171912 -294.401716) (xy 400.179807 -294.450293) (xy 400.180302 -294.4749) (xy 401.46911 -294.4749)
			(xy 401.47307 -294.425846) (xy 401.484847 -294.378062) (xy 401.504138 -294.332786) (xy 401.530441 -294.29119)
			(xy 401.563076 -294.254353) (xy 401.601197 -294.223228) (xy 401.643818 -294.198621) (xy 401.689834 -294.181169)
			(xy 401.738053 -294.171325) (xy 401.787228 -294.169344) (xy 401.836083 -294.175276) (xy 401.883354 -294.188968)
			(xy 401.927816 -294.210066) (xy 401.968319 -294.238022) (xy 402.003812 -294.272114) (xy 402.033377 -294.311458)
			(xy 402.056248 -294.355035) (xy 402.071832 -294.401716) (xy 402.079727 -294.450293) (xy 402.080222 -294.4749)
			(xy 403.36903 -294.4749) (xy 403.37299 -294.425846) (xy 403.384767 -294.378062) (xy 403.404058 -294.332786)
			(xy 403.430361 -294.29119) (xy 403.462996 -294.254353) (xy 403.501117 -294.223228) (xy 403.543738 -294.198621)
			(xy 403.589754 -294.181169) (xy 403.637973 -294.171325) (xy 403.687148 -294.169344) (xy 403.736003 -294.175276)
			(xy 403.783274 -294.188968) (xy 403.827736 -294.210066) (xy 403.868239 -294.238022) (xy 403.903732 -294.272114)
			(xy 403.933297 -294.311458) (xy 403.956168 -294.355035) (xy 403.971752 -294.401716) (xy 403.979647 -294.450293)
			(xy 403.980142 -294.4749) (xy 405.269204 -294.4749) (xy 405.273164 -294.425846) (xy 405.284941 -294.378062)
			(xy 405.304232 -294.332786) (xy 405.330535 -294.29119) (xy 405.36317 -294.254353) (xy 405.401291 -294.223228)
			(xy 405.443912 -294.198621) (xy 405.489928 -294.181169) (xy 405.538147 -294.171325) (xy 405.587322 -294.169344)
			(xy 405.636177 -294.175276) (xy 405.683448 -294.188968) (xy 405.72791 -294.210066) (xy 405.768413 -294.238022)
			(xy 405.803906 -294.272114) (xy 405.833471 -294.311458) (xy 405.856342 -294.355035) (xy 405.871926 -294.401716)
			(xy 405.879821 -294.450293) (xy 405.880316 -294.4749) (xy 408.119084 -294.4749) (xy 408.123044 -294.425846)
			(xy 408.134821 -294.378062) (xy 408.154112 -294.332786) (xy 408.180415 -294.29119) (xy 408.21305 -294.254353)
			(xy 408.251171 -294.223228) (xy 408.293792 -294.198621) (xy 408.339808 -294.181169) (xy 408.388027 -294.171325)
			(xy 408.437202 -294.169344) (xy 408.486057 -294.175276) (xy 408.533328 -294.188968) (xy 408.57779 -294.210066)
			(xy 408.618293 -294.238022) (xy 408.653786 -294.272114) (xy 408.683351 -294.311458) (xy 408.706222 -294.355035)
			(xy 408.721806 -294.401716) (xy 408.729701 -294.450293) (xy 408.730196 -294.4749) (xy 410.019004 -294.4749)
			(xy 410.022964 -294.425846) (xy 410.034741 -294.378062) (xy 410.054032 -294.332786) (xy 410.080335 -294.29119)
			(xy 410.11297 -294.254353) (xy 410.151091 -294.223228) (xy 410.193712 -294.198621) (xy 410.239728 -294.181169)
			(xy 410.287947 -294.171325) (xy 410.337122 -294.169344) (xy 410.385977 -294.175276) (xy 410.433248 -294.188968)
			(xy 410.47771 -294.210066) (xy 410.518213 -294.238022) (xy 410.553706 -294.272114) (xy 410.583271 -294.311458)
			(xy 410.606142 -294.355035) (xy 410.621726 -294.401716) (xy 410.629621 -294.450293) (xy 410.630116 -294.4749)
			(xy 411.919178 -294.4749) (xy 411.923138 -294.425846) (xy 411.934915 -294.378062) (xy 411.954206 -294.332786)
			(xy 411.980509 -294.29119) (xy 412.013144 -294.254353) (xy 412.051265 -294.223228) (xy 412.093886 -294.198621)
			(xy 412.139902 -294.181169) (xy 412.188121 -294.171325) (xy 412.237296 -294.169344) (xy 412.286151 -294.175276)
			(xy 412.333422 -294.188968) (xy 412.377884 -294.210066) (xy 412.418387 -294.238022) (xy 412.45388 -294.272114)
			(xy 412.483445 -294.311458) (xy 412.506316 -294.355035) (xy 412.5219 -294.401716) (xy 412.529795 -294.450293)
			(xy 412.53029 -294.4749) (xy 413.819098 -294.4749) (xy 413.823058 -294.425846) (xy 413.834835 -294.378062)
			(xy 413.854126 -294.332786) (xy 413.880429 -294.29119) (xy 413.913064 -294.254353) (xy 413.951185 -294.223228)
			(xy 413.993806 -294.198621) (xy 414.039822 -294.181169) (xy 414.088041 -294.171325) (xy 414.137216 -294.169344)
			(xy 414.186071 -294.175276) (xy 414.233342 -294.188968) (xy 414.277804 -294.210066) (xy 414.318307 -294.238022)
			(xy 414.3538 -294.272114) (xy 414.383365 -294.311458) (xy 414.406236 -294.355035) (xy 414.42182 -294.401716)
			(xy 414.429715 -294.450293) (xy 414.43021 -294.4749) (xy 414.769058 -294.4749) (xy 414.773018 -294.425846)
			(xy 414.784795 -294.378062) (xy 414.804086 -294.332786) (xy 414.830389 -294.29119) (xy 414.863024 -294.254353)
			(xy 414.901145 -294.223228) (xy 414.943766 -294.198621) (xy 414.989782 -294.181169) (xy 415.038001 -294.171325)
			(xy 415.087176 -294.169344) (xy 415.136031 -294.175276) (xy 415.183302 -294.188968) (xy 415.227764 -294.210066)
			(xy 415.268267 -294.238022) (xy 415.30376 -294.272114) (xy 415.333325 -294.311458) (xy 415.356196 -294.355035)
			(xy 415.37178 -294.401716) (xy 415.379675 -294.450293) (xy 415.38017 -294.4749) (xy 415.719018 -294.4749)
			(xy 415.722978 -294.425846) (xy 415.734755 -294.378062) (xy 415.754046 -294.332786) (xy 415.780349 -294.29119)
			(xy 415.812984 -294.254353) (xy 415.851105 -294.223228) (xy 415.893726 -294.198621) (xy 415.939742 -294.181169)
			(xy 415.987961 -294.171325) (xy 416.037136 -294.169344) (xy 416.085991 -294.175276) (xy 416.133262 -294.188968)
			(xy 416.177724 -294.210066) (xy 416.218227 -294.238022) (xy 416.25372 -294.272114) (xy 416.283285 -294.311458)
			(xy 416.306156 -294.355035) (xy 416.32174 -294.401716) (xy 416.329635 -294.450293) (xy 416.33013 -294.4749)
			(xy 416.668978 -294.4749) (xy 416.672938 -294.425846) (xy 416.684715 -294.378062) (xy 416.704006 -294.332786)
			(xy 416.730309 -294.29119) (xy 416.762944 -294.254353) (xy 416.801065 -294.223228) (xy 416.843686 -294.198621)
			(xy 416.889702 -294.181169) (xy 416.937921 -294.171325) (xy 416.987096 -294.169344) (xy 417.035951 -294.175276)
			(xy 417.083222 -294.188968) (xy 417.127684 -294.210066) (xy 417.168187 -294.238022) (xy 417.20368 -294.272114)
			(xy 417.233245 -294.311458) (xy 417.256116 -294.355035) (xy 417.2717 -294.401716) (xy 417.279595 -294.450293)
			(xy 417.28009 -294.4749) (xy 417.279595 -294.499507) (xy 417.2717 -294.548084) (xy 417.256116 -294.594765)
			(xy 417.233245 -294.638342) (xy 417.20368 -294.677686) (xy 417.168187 -294.711778) (xy 417.127684 -294.739734)
			(xy 417.083222 -294.760832) (xy 417.035951 -294.774524) (xy 416.987096 -294.780456) (xy 416.937921 -294.778475)
			(xy 416.889702 -294.768631) (xy 416.843686 -294.751179) (xy 416.801065 -294.726572) (xy 416.762944 -294.695447)
			(xy 416.730309 -294.65861) (xy 416.704006 -294.617014) (xy 416.684715 -294.571738) (xy 416.672938 -294.523954)
			(xy 416.668978 -294.4749) (xy 416.33013 -294.4749) (xy 416.329635 -294.499507) (xy 416.32174 -294.548084)
			(xy 416.306156 -294.594765) (xy 416.283285 -294.638342) (xy 416.25372 -294.677686) (xy 416.218227 -294.711778)
			(xy 416.177724 -294.739734) (xy 416.133262 -294.760832) (xy 416.085991 -294.774524) (xy 416.037136 -294.780456)
			(xy 415.987961 -294.778475) (xy 415.939742 -294.768631) (xy 415.893726 -294.751179) (xy 415.851105 -294.726572)
			(xy 415.812984 -294.695447) (xy 415.780349 -294.65861) (xy 415.754046 -294.617014) (xy 415.734755 -294.571738)
			(xy 415.722978 -294.523954) (xy 415.719018 -294.4749) (xy 415.38017 -294.4749) (xy 415.379675 -294.499507)
			(xy 415.37178 -294.548084) (xy 415.356196 -294.594765) (xy 415.333325 -294.638342) (xy 415.30376 -294.677686)
			(xy 415.268267 -294.711778) (xy 415.227764 -294.739734) (xy 415.183302 -294.760832) (xy 415.136031 -294.774524)
			(xy 415.087176 -294.780456) (xy 415.038001 -294.778475) (xy 414.989782 -294.768631) (xy 414.943766 -294.751179)
			(xy 414.901145 -294.726572) (xy 414.863024 -294.695447) (xy 414.830389 -294.65861) (xy 414.804086 -294.617014)
			(xy 414.784795 -294.571738) (xy 414.773018 -294.523954) (xy 414.769058 -294.4749) (xy 414.43021 -294.4749)
			(xy 414.429715 -294.499507) (xy 414.42182 -294.548084) (xy 414.406236 -294.594765) (xy 414.383365 -294.638342)
			(xy 414.3538 -294.677686) (xy 414.318307 -294.711778) (xy 414.277804 -294.739734) (xy 414.233342 -294.760832)
			(xy 414.186071 -294.774524) (xy 414.137216 -294.780456) (xy 414.088041 -294.778475) (xy 414.039822 -294.768631)
			(xy 413.993806 -294.751179) (xy 413.951185 -294.726572) (xy 413.913064 -294.695447) (xy 413.880429 -294.65861)
			(xy 413.854126 -294.617014) (xy 413.834835 -294.571738) (xy 413.823058 -294.523954) (xy 413.819098 -294.4749)
			(xy 412.53029 -294.4749) (xy 412.529795 -294.499507) (xy 412.5219 -294.548084) (xy 412.506316 -294.594765)
			(xy 412.483445 -294.638342) (xy 412.45388 -294.677686) (xy 412.418387 -294.711778) (xy 412.377884 -294.739734)
			(xy 412.333422 -294.760832) (xy 412.286151 -294.774524) (xy 412.237296 -294.780456) (xy 412.188121 -294.778475)
			(xy 412.139902 -294.768631) (xy 412.093886 -294.751179) (xy 412.051265 -294.726572) (xy 412.013144 -294.695447)
			(xy 411.980509 -294.65861) (xy 411.954206 -294.617014) (xy 411.934915 -294.571738) (xy 411.923138 -294.523954)
			(xy 411.919178 -294.4749) (xy 410.630116 -294.4749) (xy 410.629621 -294.499507) (xy 410.621726 -294.548084)
			(xy 410.606142 -294.594765) (xy 410.583271 -294.638342) (xy 410.553706 -294.677686) (xy 410.518213 -294.711778)
			(xy 410.47771 -294.739734) (xy 410.433248 -294.760832) (xy 410.385977 -294.774524) (xy 410.337122 -294.780456)
			(xy 410.287947 -294.778475) (xy 410.239728 -294.768631) (xy 410.193712 -294.751179) (xy 410.151091 -294.726572)
			(xy 410.11297 -294.695447) (xy 410.080335 -294.65861) (xy 410.054032 -294.617014) (xy 410.034741 -294.571738)
			(xy 410.022964 -294.523954) (xy 410.019004 -294.4749) (xy 408.730196 -294.4749) (xy 408.729701 -294.499507)
			(xy 408.721806 -294.548084) (xy 408.706222 -294.594765) (xy 408.683351 -294.638342) (xy 408.653786 -294.677686)
			(xy 408.618293 -294.711778) (xy 408.57779 -294.739734) (xy 408.533328 -294.760832) (xy 408.486057 -294.774524)
			(xy 408.437202 -294.780456) (xy 408.388027 -294.778475) (xy 408.339808 -294.768631) (xy 408.293792 -294.751179)
			(xy 408.251171 -294.726572) (xy 408.21305 -294.695447) (xy 408.180415 -294.65861) (xy 408.154112 -294.617014)
			(xy 408.134821 -294.571738) (xy 408.123044 -294.523954) (xy 408.119084 -294.4749) (xy 405.880316 -294.4749)
			(xy 405.879821 -294.499507) (xy 405.871926 -294.548084) (xy 405.856342 -294.594765) (xy 405.833471 -294.638342)
			(xy 405.803906 -294.677686) (xy 405.768413 -294.711778) (xy 405.72791 -294.739734) (xy 405.683448 -294.760832)
			(xy 405.636177 -294.774524) (xy 405.587322 -294.780456) (xy 405.538147 -294.778475) (xy 405.489928 -294.768631)
			(xy 405.443912 -294.751179) (xy 405.401291 -294.726572) (xy 405.36317 -294.695447) (xy 405.330535 -294.65861)
			(xy 405.304232 -294.617014) (xy 405.284941 -294.571738) (xy 405.273164 -294.523954) (xy 405.269204 -294.4749)
			(xy 403.980142 -294.4749) (xy 403.979647 -294.499507) (xy 403.971752 -294.548084) (xy 403.956168 -294.594765)
			(xy 403.933297 -294.638342) (xy 403.903732 -294.677686) (xy 403.868239 -294.711778) (xy 403.827736 -294.739734)
			(xy 403.783274 -294.760832) (xy 403.736003 -294.774524) (xy 403.687148 -294.780456) (xy 403.637973 -294.778475)
			(xy 403.589754 -294.768631) (xy 403.543738 -294.751179) (xy 403.501117 -294.726572) (xy 403.462996 -294.695447)
			(xy 403.430361 -294.65861) (xy 403.404058 -294.617014) (xy 403.384767 -294.571738) (xy 403.37299 -294.523954)
			(xy 403.36903 -294.4749) (xy 402.080222 -294.4749) (xy 402.079727 -294.499507) (xy 402.071832 -294.548084)
			(xy 402.056248 -294.594765) (xy 402.033377 -294.638342) (xy 402.003812 -294.677686) (xy 401.968319 -294.711778)
			(xy 401.927816 -294.739734) (xy 401.883354 -294.760832) (xy 401.836083 -294.774524) (xy 401.787228 -294.780456)
			(xy 401.738053 -294.778475) (xy 401.689834 -294.768631) (xy 401.643818 -294.751179) (xy 401.601197 -294.726572)
			(xy 401.563076 -294.695447) (xy 401.530441 -294.65861) (xy 401.504138 -294.617014) (xy 401.484847 -294.571738)
			(xy 401.47307 -294.523954) (xy 401.46911 -294.4749) (xy 400.180302 -294.4749) (xy 400.179807 -294.499507)
			(xy 400.171912 -294.548084) (xy 400.156328 -294.594765) (xy 400.133457 -294.638342) (xy 400.103892 -294.677686)
			(xy 400.068399 -294.711778) (xy 400.027896 -294.739734) (xy 399.983434 -294.760832) (xy 399.936163 -294.774524)
			(xy 399.887308 -294.780456) (xy 399.838133 -294.778475) (xy 399.789914 -294.768631) (xy 399.743898 -294.751179)
			(xy 399.701277 -294.726572) (xy 399.663156 -294.695447) (xy 399.630521 -294.65861) (xy 399.604218 -294.617014)
			(xy 399.584927 -294.571738) (xy 399.57315 -294.523954) (xy 399.56919 -294.4749) (xy 398.280128 -294.4749)
			(xy 398.279633 -294.499507) (xy 398.271738 -294.548084) (xy 398.256154 -294.594765) (xy 398.233283 -294.638342)
			(xy 398.203718 -294.677686) (xy 398.168225 -294.711778) (xy 398.127722 -294.739734) (xy 398.08326 -294.760832)
			(xy 398.035989 -294.774524) (xy 397.987134 -294.780456) (xy 397.937959 -294.778475) (xy 397.88974 -294.768631)
			(xy 397.843724 -294.751179) (xy 397.801103 -294.726572) (xy 397.762982 -294.695447) (xy 397.730347 -294.65861)
			(xy 397.704044 -294.617014) (xy 397.684753 -294.571738) (xy 397.672976 -294.523954) (xy 397.669016 -294.4749)
			(xy 396.380208 -294.4749) (xy 396.379713 -294.499507) (xy 396.371818 -294.548084) (xy 396.356234 -294.594765)
			(xy 396.333363 -294.638342) (xy 396.303798 -294.677686) (xy 396.268305 -294.711778) (xy 396.227802 -294.739734)
			(xy 396.18334 -294.760832) (xy 396.136069 -294.774524) (xy 396.087214 -294.780456) (xy 396.038039 -294.778475)
			(xy 395.98982 -294.768631) (xy 395.943804 -294.751179) (xy 395.901183 -294.726572) (xy 395.863062 -294.695447)
			(xy 395.830427 -294.65861) (xy 395.804124 -294.617014) (xy 395.784833 -294.571738) (xy 395.773056 -294.523954)
			(xy 395.769096 -294.4749) (xy 395.430248 -294.4749) (xy 395.429753 -294.499507) (xy 395.421858 -294.548084)
			(xy 395.406274 -294.594765) (xy 395.383403 -294.638342) (xy 395.353838 -294.677686) (xy 395.318345 -294.711778)
			(xy 395.277842 -294.739734) (xy 395.23338 -294.760832) (xy 395.186109 -294.774524) (xy 395.137254 -294.780456)
			(xy 395.088079 -294.778475) (xy 395.03986 -294.768631) (xy 394.993844 -294.751179) (xy 394.951223 -294.726572)
			(xy 394.913102 -294.695447) (xy 394.880467 -294.65861) (xy 394.854164 -294.617014) (xy 394.834873 -294.571738)
			(xy 394.823096 -294.523954) (xy 394.819136 -294.4749) (xy 394.480288 -294.4749) (xy 394.479793 -294.499507)
			(xy 394.471898 -294.548084) (xy 394.456314 -294.594765) (xy 394.433443 -294.638342) (xy 394.403878 -294.677686)
			(xy 394.368385 -294.711778) (xy 394.327882 -294.739734) (xy 394.28342 -294.760832) (xy 394.236149 -294.774524)
			(xy 394.187294 -294.780456) (xy 394.138119 -294.778475) (xy 394.0899 -294.768631) (xy 394.043884 -294.751179)
			(xy 394.001263 -294.726572) (xy 393.963142 -294.695447) (xy 393.930507 -294.65861) (xy 393.904204 -294.617014)
			(xy 393.884913 -294.571738) (xy 393.873136 -294.523954) (xy 393.869176 -294.4749) (xy 393.530328 -294.4749)
			(xy 393.529833 -294.499507) (xy 393.521938 -294.548084) (xy 393.506354 -294.594765) (xy 393.483483 -294.638342)
			(xy 393.453918 -294.677686) (xy 393.418425 -294.711778) (xy 393.377922 -294.739734) (xy 393.33346 -294.760832)
			(xy 393.286189 -294.774524) (xy 393.237334 -294.780456) (xy 393.188159 -294.778475) (xy 393.13994 -294.768631)
			(xy 393.093924 -294.751179) (xy 393.051303 -294.726572) (xy 393.013182 -294.695447) (xy 392.980547 -294.65861)
			(xy 392.954244 -294.617014) (xy 392.934953 -294.571738) (xy 392.923176 -294.523954) (xy 392.919216 -294.4749)
			(xy 392.580114 -294.4749) (xy 392.579619 -294.499507) (xy 392.571724 -294.548084) (xy 392.55614 -294.594765)
			(xy 392.533269 -294.638342) (xy 392.503704 -294.677686) (xy 392.468211 -294.711778) (xy 392.427708 -294.739734)
			(xy 392.383246 -294.760832) (xy 392.335975 -294.774524) (xy 392.28712 -294.780456) (xy 392.237945 -294.778475)
			(xy 392.189726 -294.768631) (xy 392.14371 -294.751179) (xy 392.101089 -294.726572) (xy 392.062968 -294.695447)
			(xy 392.030333 -294.65861) (xy 392.00403 -294.617014) (xy 391.984739 -294.571738) (xy 391.972962 -294.523954)
			(xy 391.969002 -294.4749) (xy 391.630154 -294.4749) (xy 391.629659 -294.499507) (xy 391.621764 -294.548084)
			(xy 391.60618 -294.594765) (xy 391.583309 -294.638342) (xy 391.553744 -294.677686) (xy 391.518251 -294.711778)
			(xy 391.477748 -294.739734) (xy 391.433286 -294.760832) (xy 391.386015 -294.774524) (xy 391.33716 -294.780456)
			(xy 391.287985 -294.778475) (xy 391.239766 -294.768631) (xy 391.19375 -294.751179) (xy 391.151129 -294.726572)
			(xy 391.113008 -294.695447) (xy 391.080373 -294.65861) (xy 391.05407 -294.617014) (xy 391.034779 -294.571738)
			(xy 391.023002 -294.523954) (xy 391.019042 -294.4749) (xy 390.730994 -294.4749) (xy 390.730496 -294.501549)
			(xy 390.722553 -294.554253) (xy 390.706843 -294.605183) (xy 390.683717 -294.653204) (xy 390.653693 -294.697241)
			(xy 390.617441 -294.736312) (xy 390.57577 -294.769543) (xy 390.529612 -294.796192) (xy 390.479998 -294.815664)
			(xy 390.428036 -294.827524) (xy 390.374886 -294.831508) (xy 390.321736 -294.827524) (xy 390.269774 -294.815664)
			(xy 390.22016 -294.796192) (xy 390.174002 -294.769543) (xy 390.132331 -294.736312) (xy 390.096079 -294.697241)
			(xy 390.066055 -294.653204) (xy 390.042929 -294.605183) (xy 390.027219 -294.554253) (xy 390.019276 -294.501549)
			(xy 389.729407 -294.501549) (xy 389.721844 -294.548084) (xy 389.70626 -294.594765) (xy 389.683389 -294.638342)
			(xy 389.653824 -294.677686) (xy 389.618331 -294.711778) (xy 389.577828 -294.739734) (xy 389.533366 -294.760832)
			(xy 389.486095 -294.774524) (xy 389.43724 -294.780456) (xy 389.388065 -294.778475) (xy 389.339846 -294.768631)
			(xy 389.29383 -294.751179) (xy 389.251209 -294.726572) (xy 389.213088 -294.695447) (xy 389.180453 -294.65861)
			(xy 389.15415 -294.617014) (xy 389.134859 -294.571738) (xy 389.123082 -294.523954) (xy 389.119122 -294.4749)
			(xy 386.880354 -294.4749) (xy 386.879859 -294.499507) (xy 386.871964 -294.548084) (xy 386.85638 -294.594765)
			(xy 386.833509 -294.638342) (xy 386.803944 -294.677686) (xy 386.768451 -294.711778) (xy 386.727948 -294.739734)
			(xy 386.683486 -294.760832) (xy 386.636215 -294.774524) (xy 386.58736 -294.780456) (xy 386.538185 -294.778475)
			(xy 386.489966 -294.768631) (xy 386.44395 -294.751179) (xy 386.401329 -294.726572) (xy 386.363208 -294.695447)
			(xy 386.330573 -294.65861) (xy 386.30427 -294.617014) (xy 386.284979 -294.571738) (xy 386.273202 -294.523954)
			(xy 386.269242 -294.4749) (xy 385.93014 -294.4749) (xy 385.929645 -294.499507) (xy 385.92175 -294.548084)
			(xy 385.906166 -294.594765) (xy 385.883295 -294.638342) (xy 385.85373 -294.677686) (xy 385.818237 -294.711778)
			(xy 385.777734 -294.739734) (xy 385.733272 -294.760832) (xy 385.686001 -294.774524) (xy 385.637146 -294.780456)
			(xy 385.587971 -294.778475) (xy 385.539752 -294.768631) (xy 385.493736 -294.751179) (xy 385.451115 -294.726572)
			(xy 385.412994 -294.695447) (xy 385.380359 -294.65861) (xy 385.354056 -294.617014) (xy 385.334765 -294.571738)
			(xy 385.322988 -294.523954) (xy 385.319028 -294.4749) (xy 384.98018 -294.4749) (xy 384.979685 -294.499507)
			(xy 384.97179 -294.548084) (xy 384.956206 -294.594765) (xy 384.933335 -294.638342) (xy 384.90377 -294.677686)
			(xy 384.868277 -294.711778) (xy 384.827774 -294.739734) (xy 384.783312 -294.760832) (xy 384.736041 -294.774524)
			(xy 384.687186 -294.780456) (xy 384.638011 -294.778475) (xy 384.589792 -294.768631) (xy 384.543776 -294.751179)
			(xy 384.501155 -294.726572) (xy 384.463034 -294.695447) (xy 384.430399 -294.65861) (xy 384.404096 -294.617014)
			(xy 384.384805 -294.571738) (xy 384.373028 -294.523954) (xy 384.369068 -294.4749) (xy 376.32635 -294.4749)
			(xy 376.335485 -294.494387) (xy 376.351553 -294.547794) (xy 376.359673 -294.60297) (xy 376.360182 -294.630856)
			(xy 376.359673 -294.658742) (xy 376.351553 -294.713918) (xy 376.335485 -294.767325) (xy 376.311813 -294.817822)
			(xy 376.28104 -294.864335) (xy 376.243823 -294.905872) (xy 376.200955 -294.941547) (xy 376.153349 -294.970601)
			(xy 376.10202 -294.992413) (xy 376.048063 -295.006519) (xy 375.992626 -295.012619) (xy 375.936892 -295.010582)
			(xy 375.882049 -295.000452) (xy 375.829265 -294.982445) (xy 375.779665 -294.956944) (xy 375.734307 -294.924493)
			(xy 375.694158 -294.885784) (xy 375.660072 -294.841641) (xy 375.632776 -294.793006) (xy 375.612853 -294.740915)
			(xy 375.600727 -294.686478) (xy 375.596656 -294.630856) (xy 374.875044 -294.630856) (xy 374.874535 -294.658742)
			(xy 374.866415 -294.713918) (xy 374.850347 -294.767325) (xy 374.826675 -294.817822) (xy 374.795902 -294.864335)
			(xy 374.758685 -294.905872) (xy 374.715817 -294.941547) (xy 374.668211 -294.970601) (xy 374.616882 -294.992413)
			(xy 374.562925 -295.006519) (xy 374.507488 -295.012619) (xy 374.451754 -295.010582) (xy 374.396911 -295.000452)
			(xy 374.344127 -294.982445) (xy 374.294527 -294.956944) (xy 374.249169 -294.924493) (xy 374.20902 -294.885784)
			(xy 374.174934 -294.841641) (xy 374.147638 -294.793006) (xy 374.127715 -294.740915) (xy 374.115589 -294.686478)
			(xy 374.111518 -294.630856) (xy 351.160842 -294.630856) (xy 351.098866 -294.692832) (xy 351.093751 -294.697632)
			(xy 351.081508 -294.704466) (xy 351.074736 -294.706294) (xy 351.067878 -294.708072) (xy 351.05594 -294.714676)
			(xy 351.048066 -294.72255) (xy 351.04122 -294.729948) (xy 351.033494 -294.748547) (xy 351.03308 -294.758618)
			(xy 351.03308 -295.933114) (xy 374.111518 -295.933114) (xy 374.115589 -295.877492) (xy 374.127715 -295.823055)
			(xy 374.147638 -295.770964) (xy 374.174934 -295.722329) (xy 374.20902 -295.678186) (xy 374.249169 -295.639477)
			(xy 374.294527 -295.607026) (xy 374.344127 -295.581525) (xy 374.396911 -295.563518) (xy 374.451754 -295.553388)
			(xy 374.507488 -295.551351) (xy 374.562925 -295.557451) (xy 374.616882 -295.571557) (xy 374.668211 -295.593369)
			(xy 374.715817 -295.622423) (xy 374.758685 -295.658098) (xy 374.795902 -295.699635) (xy 374.826675 -295.746148)
			(xy 374.850347 -295.796645) (xy 374.866415 -295.850052) (xy 374.874535 -295.905228) (xy 374.875044 -295.933114)
			(xy 375.587004 -295.933114) (xy 375.591075 -295.877492) (xy 375.603201 -295.823055) (xy 375.623124 -295.770964)
			(xy 375.65042 -295.722329) (xy 375.684506 -295.678186) (xy 375.724655 -295.639477) (xy 375.770013 -295.607026)
			(xy 375.819613 -295.581525) (xy 375.872397 -295.563518) (xy 375.92724 -295.553388) (xy 375.982974 -295.551351)
			(xy 376.038411 -295.557451) (xy 376.092368 -295.571557) (xy 376.143697 -295.593369) (xy 376.191303 -295.622423)
			(xy 376.234171 -295.658098) (xy 376.271388 -295.699635) (xy 376.302161 -295.746148) (xy 376.325833 -295.796645)
			(xy 376.341901 -295.850052) (xy 376.350021 -295.905228) (xy 376.35053 -295.933114) (xy 376.476004 -295.933114)
			(xy 376.480075 -295.877492) (xy 376.492201 -295.823055) (xy 376.512124 -295.770964) (xy 376.53942 -295.722329)
			(xy 376.573506 -295.678186) (xy 376.613655 -295.639477) (xy 376.659013 -295.607026) (xy 376.708613 -295.581525)
			(xy 376.761397 -295.563518) (xy 376.81624 -295.553388) (xy 376.871974 -295.551351) (xy 376.927411 -295.557451)
			(xy 376.981368 -295.571557) (xy 377.032697 -295.593369) (xy 377.080303 -295.622423) (xy 377.123171 -295.658098)
			(xy 377.160388 -295.699635) (xy 377.191161 -295.746148) (xy 377.214833 -295.796645) (xy 377.230901 -295.850052)
			(xy 377.239021 -295.905228) (xy 377.23953 -295.933114) (xy 377.239021 -295.961) (xy 377.230901 -296.016176)
			(xy 377.214833 -296.069583) (xy 377.191161 -296.12008) (xy 377.160388 -296.166593) (xy 377.123171 -296.20813)
			(xy 377.080303 -296.243805) (xy 377.032697 -296.272859) (xy 376.981368 -296.294671) (xy 376.927411 -296.308777)
			(xy 376.871974 -296.314877) (xy 376.81624 -296.31284) (xy 376.761397 -296.30271) (xy 376.708613 -296.284703)
			(xy 376.659013 -296.259202) (xy 376.613655 -296.226751) (xy 376.573506 -296.188042) (xy 376.53942 -296.143899)
			(xy 376.512124 -296.095264) (xy 376.492201 -296.043173) (xy 376.480075 -295.988736) (xy 376.476004 -295.933114)
			(xy 376.35053 -295.933114) (xy 376.350021 -295.961) (xy 376.341901 -296.016176) (xy 376.325833 -296.069583)
			(xy 376.302161 -296.12008) (xy 376.271388 -296.166593) (xy 376.234171 -296.20813) (xy 376.191303 -296.243805)
			(xy 376.143697 -296.272859) (xy 376.092368 -296.294671) (xy 376.038411 -296.308777) (xy 375.982974 -296.314877)
			(xy 375.92724 -296.31284) (xy 375.872397 -296.30271) (xy 375.819613 -296.284703) (xy 375.770013 -296.259202)
			(xy 375.724655 -296.226751) (xy 375.684506 -296.188042) (xy 375.65042 -296.143899) (xy 375.623124 -296.095264)
			(xy 375.603201 -296.043173) (xy 375.591075 -295.988736) (xy 375.587004 -295.933114) (xy 374.875044 -295.933114)
			(xy 374.874535 -295.961) (xy 374.866415 -296.016176) (xy 374.850347 -296.069583) (xy 374.826675 -296.12008)
			(xy 374.795902 -296.166593) (xy 374.758685 -296.20813) (xy 374.715817 -296.243805) (xy 374.668211 -296.272859)
			(xy 374.616882 -296.294671) (xy 374.562925 -296.308777) (xy 374.507488 -296.314877) (xy 374.451754 -296.31284)
			(xy 374.396911 -296.30271) (xy 374.344127 -296.284703) (xy 374.294527 -296.259202) (xy 374.249169 -296.226751)
			(xy 374.20902 -296.188042) (xy 374.174934 -296.143899) (xy 374.147638 -296.095264) (xy 374.127715 -296.043173)
			(xy 374.115589 -295.988736) (xy 374.111518 -295.933114) (xy 351.03308 -295.933114) (xy 351.03308 -296.695114)
			(xy 379.638052 -296.695114) (xy 379.638619 -296.665733) (xy 379.647646 -296.607668) (xy 379.665474 -296.551675)
			(xy 379.691681 -296.49908) (xy 379.725646 -296.451128) (xy 379.766565 -296.408954) (xy 379.78969 -296.390822)
			(xy 379.799088 -296.383456) (xy 379.809502 -296.362882) (xy 379.811026 -296.258996) (xy 379.80112 -296.237914)
			(xy 379.791976 -296.230548) (xy 379.770116 -296.212356) (xy 379.731578 -296.170534) (xy 379.699673 -296.123455)
			(xy 379.675108 -296.072163) (xy 379.658427 -296.017793) (xy 379.65 -295.96155) (xy 379.649482 -295.933114)
			(xy 379.649968 -295.905863) (xy 379.657724 -295.851915) (xy 379.673079 -295.79962) (xy 379.695721 -295.750043)
			(xy 379.725187 -295.704193) (xy 379.760878 -295.663002) (xy 379.802069 -295.627311) (xy 379.847919 -295.597845)
			(xy 379.897496 -295.575203) (xy 379.949791 -295.559848) (xy 380.003739 -295.552092) (xy 380.058241 -295.552092)
			(xy 380.112189 -295.559848) (xy 380.164484 -295.575203) (xy 380.214061 -295.597845) (xy 380.259911 -295.627311)
			(xy 380.301102 -295.663002) (xy 380.336793 -295.704193) (xy 380.366259 -295.750043) (xy 380.388901 -295.79962)
			(xy 380.404256 -295.851915) (xy 380.412012 -295.905863) (xy 380.412498 -295.933114) (xy 380.411971 -295.962497)
			(xy 380.402938 -296.020564) (xy 380.385103 -296.076559) (xy 380.358889 -296.129154) (xy 380.324916 -296.177105)
			(xy 380.283989 -296.219276) (xy 380.26086 -296.237406) (xy 380.251462 -296.244772) (xy 380.241048 -296.265346)
			(xy 380.239524 -296.369232) (xy 380.24943 -296.390314) (xy 380.258574 -296.39768) (xy 380.280389 -296.415924)
			(xy 380.318933 -296.457734) (xy 380.350844 -296.504801) (xy 380.375417 -296.556084) (xy 380.392107 -296.610445)
			(xy 380.400545 -296.666681) (xy 380.401068 -296.695114) (xy 381.034542 -296.695114) (xy 381.038613 -296.639492)
			(xy 381.050739 -296.585055) (xy 381.070662 -296.532964) (xy 381.097958 -296.484329) (xy 381.132044 -296.440186)
			(xy 381.172193 -296.401477) (xy 381.217551 -296.369026) (xy 381.267151 -296.343525) (xy 381.319935 -296.325518)
			(xy 381.374778 -296.315388) (xy 381.430512 -296.313351) (xy 381.485949 -296.319451) (xy 381.539906 -296.333557)
			(xy 381.591235 -296.355369) (xy 381.638841 -296.384423) (xy 381.681709 -296.420098) (xy 381.718926 -296.461635)
			(xy 381.749699 -296.508148) (xy 381.773371 -296.558645) (xy 381.789439 -296.612052) (xy 381.797559 -296.667228)
			(xy 381.798068 -296.695114) (xy 381.921002 -296.695114) (xy 381.925073 -296.639492) (xy 381.937199 -296.585055)
			(xy 381.957122 -296.532964) (xy 381.984418 -296.484329) (xy 382.018504 -296.440186) (xy 382.058653 -296.401477)
			(xy 382.104011 -296.369026) (xy 382.153611 -296.343525) (xy 382.206395 -296.325518) (xy 382.261238 -296.315388)
			(xy 382.316972 -296.313351) (xy 382.372409 -296.319451) (xy 382.426366 -296.333557) (xy 382.477695 -296.355369)
			(xy 382.50915 -296.374566) (xy 384.369068 -296.374566) (xy 384.373028 -296.325512) (xy 384.384805 -296.277728)
			(xy 384.404096 -296.232452) (xy 384.430399 -296.190856) (xy 384.463034 -296.154019) (xy 384.501155 -296.122894)
			(xy 384.543776 -296.098287) (xy 384.589792 -296.080835) (xy 384.638011 -296.070991) (xy 384.687186 -296.06901)
			(xy 384.736041 -296.074942) (xy 384.783312 -296.088634) (xy 384.827774 -296.109732) (xy 384.868277 -296.137688)
			(xy 384.90377 -296.17178) (xy 384.933335 -296.211124) (xy 384.956206 -296.254701) (xy 384.97179 -296.301382)
			(xy 384.979685 -296.349959) (xy 384.98018 -296.374566) (xy 384.980175 -296.37482) (xy 385.319282 -296.37482)
			(xy 385.323242 -296.325766) (xy 385.335019 -296.277982) (xy 385.35431 -296.232706) (xy 385.380613 -296.19111)
			(xy 385.413248 -296.154273) (xy 385.451369 -296.123148) (xy 385.49399 -296.098541) (xy 385.540006 -296.081089)
			(xy 385.588225 -296.071245) (xy 385.6374 -296.069264) (xy 385.686255 -296.075196) (xy 385.733526 -296.088888)
			(xy 385.777988 -296.109986) (xy 385.818491 -296.137942) (xy 385.853984 -296.172034) (xy 385.883549 -296.211378)
			(xy 385.90642 -296.254955) (xy 385.922004 -296.301636) (xy 385.929899 -296.350213) (xy 385.930394 -296.37482)
			(xy 386.268988 -296.37482) (xy 386.272948 -296.325766) (xy 386.284725 -296.277982) (xy 386.304016 -296.232706)
			(xy 386.330319 -296.19111) (xy 386.362954 -296.154273) (xy 386.401075 -296.123148) (xy 386.443696 -296.098541)
			(xy 386.489712 -296.081089) (xy 386.537931 -296.071245) (xy 386.587106 -296.069264) (xy 386.635961 -296.075196)
			(xy 386.683232 -296.088888) (xy 386.727694 -296.109986) (xy 386.768197 -296.137942) (xy 386.80369 -296.172034)
			(xy 386.833255 -296.211378) (xy 386.856126 -296.254955) (xy 386.87171 -296.301636) (xy 386.879605 -296.350213)
			(xy 386.8801 -296.37482) (xy 387.219202 -296.37482) (xy 387.223162 -296.325766) (xy 387.234939 -296.277982)
			(xy 387.25423 -296.232706) (xy 387.280533 -296.19111) (xy 387.313168 -296.154273) (xy 387.351289 -296.123148)
			(xy 387.39391 -296.098541) (xy 387.439926 -296.081089) (xy 387.488145 -296.071245) (xy 387.53732 -296.069264)
			(xy 387.586175 -296.075196) (xy 387.633446 -296.088888) (xy 387.677908 -296.109986) (xy 387.718411 -296.137942)
			(xy 387.753904 -296.172034) (xy 387.783469 -296.211378) (xy 387.80634 -296.254955) (xy 387.821924 -296.301636)
			(xy 387.829819 -296.350213) (xy 387.830314 -296.37482) (xy 388.169162 -296.37482) (xy 388.173122 -296.325766)
			(xy 388.184899 -296.277982) (xy 388.20419 -296.232706) (xy 388.230493 -296.19111) (xy 388.263128 -296.154273)
			(xy 388.301249 -296.123148) (xy 388.34387 -296.098541) (xy 388.389886 -296.081089) (xy 388.438105 -296.071245)
			(xy 388.48728 -296.069264) (xy 388.536135 -296.075196) (xy 388.583406 -296.088888) (xy 388.627868 -296.109986)
			(xy 388.668371 -296.137942) (xy 388.703864 -296.172034) (xy 388.733429 -296.211378) (xy 388.7563 -296.254955)
			(xy 388.771884 -296.301636) (xy 388.779779 -296.350213) (xy 388.780274 -296.37482) (xy 390.069082 -296.37482)
			(xy 390.073042 -296.325766) (xy 390.084819 -296.277982) (xy 390.10411 -296.232706) (xy 390.130413 -296.19111)
			(xy 390.163048 -296.154273) (xy 390.201169 -296.123148) (xy 390.24379 -296.098541) (xy 390.289806 -296.081089)
			(xy 390.338025 -296.071245) (xy 390.3872 -296.069264) (xy 390.436055 -296.075196) (xy 390.483326 -296.088888)
			(xy 390.527788 -296.109986) (xy 390.568291 -296.137942) (xy 390.603784 -296.172034) (xy 390.633349 -296.211378)
			(xy 390.65622 -296.254955) (xy 390.671804 -296.301636) (xy 390.679699 -296.350213) (xy 390.680194 -296.37482)
			(xy 391.969002 -296.37482) (xy 391.972962 -296.325766) (xy 391.984739 -296.277982) (xy 392.00403 -296.232706)
			(xy 392.030333 -296.19111) (xy 392.062968 -296.154273) (xy 392.101089 -296.123148) (xy 392.14371 -296.098541)
			(xy 392.189726 -296.081089) (xy 392.237945 -296.071245) (xy 392.28712 -296.069264) (xy 392.335975 -296.075196)
			(xy 392.383246 -296.088888) (xy 392.427708 -296.109986) (xy 392.468211 -296.137942) (xy 392.503704 -296.172034)
			(xy 392.533269 -296.211378) (xy 392.55614 -296.254955) (xy 392.571724 -296.301636) (xy 392.579619 -296.350213)
			(xy 392.580114 -296.37482) (xy 392.919216 -296.37482) (xy 392.923176 -296.325766) (xy 392.934953 -296.277982)
			(xy 392.954244 -296.232706) (xy 392.980547 -296.19111) (xy 393.013182 -296.154273) (xy 393.051303 -296.123148)
			(xy 393.093924 -296.098541) (xy 393.13994 -296.081089) (xy 393.188159 -296.071245) (xy 393.237334 -296.069264)
			(xy 393.286189 -296.075196) (xy 393.33346 -296.088888) (xy 393.377922 -296.109986) (xy 393.418425 -296.137942)
			(xy 393.453918 -296.172034) (xy 393.483483 -296.211378) (xy 393.506354 -296.254955) (xy 393.521938 -296.301636)
			(xy 393.529833 -296.350213) (xy 393.530328 -296.37482) (xy 393.869176 -296.37482) (xy 393.873136 -296.325766)
			(xy 393.884913 -296.277982) (xy 393.904204 -296.232706) (xy 393.930507 -296.19111) (xy 393.963142 -296.154273)
			(xy 394.001263 -296.123148) (xy 394.043884 -296.098541) (xy 394.0899 -296.081089) (xy 394.138119 -296.071245)
			(xy 394.187294 -296.069264) (xy 394.236149 -296.075196) (xy 394.28342 -296.088888) (xy 394.327882 -296.109986)
			(xy 394.368385 -296.137942) (xy 394.403878 -296.172034) (xy 394.433443 -296.211378) (xy 394.456314 -296.254955)
			(xy 394.471898 -296.301636) (xy 394.479793 -296.350213) (xy 394.480288 -296.37482) (xy 395.769096 -296.37482)
			(xy 395.773056 -296.325766) (xy 395.784833 -296.277982) (xy 395.804124 -296.232706) (xy 395.830427 -296.19111)
			(xy 395.863062 -296.154273) (xy 395.901183 -296.123148) (xy 395.943804 -296.098541) (xy 395.98982 -296.081089)
			(xy 396.038039 -296.071245) (xy 396.087214 -296.069264) (xy 396.136069 -296.075196) (xy 396.18334 -296.088888)
			(xy 396.227802 -296.109986) (xy 396.268305 -296.137942) (xy 396.303798 -296.172034) (xy 396.333363 -296.211378)
			(xy 396.356234 -296.254955) (xy 396.371818 -296.301636) (xy 396.379713 -296.350213) (xy 396.380208 -296.37482)
			(xy 396.719056 -296.37482) (xy 396.723016 -296.325766) (xy 396.734793 -296.277982) (xy 396.754084 -296.232706)
			(xy 396.780387 -296.19111) (xy 396.813022 -296.154273) (xy 396.851143 -296.123148) (xy 396.893764 -296.098541)
			(xy 396.93978 -296.081089) (xy 396.987999 -296.071245) (xy 397.037174 -296.069264) (xy 397.086029 -296.075196)
			(xy 397.1333 -296.088888) (xy 397.177762 -296.109986) (xy 397.218265 -296.137942) (xy 397.253758 -296.172034)
			(xy 397.283323 -296.211378) (xy 397.306194 -296.254955) (xy 397.321778 -296.301636) (xy 397.329673 -296.350213)
			(xy 397.330168 -296.37482) (xy 398.61923 -296.37482) (xy 398.62319 -296.325766) (xy 398.634967 -296.277982)
			(xy 398.654258 -296.232706) (xy 398.680561 -296.19111) (xy 398.713196 -296.154273) (xy 398.751317 -296.123148)
			(xy 398.793938 -296.098541) (xy 398.839954 -296.081089) (xy 398.888173 -296.071245) (xy 398.937348 -296.069264)
			(xy 398.986203 -296.075196) (xy 399.033474 -296.088888) (xy 399.077936 -296.109986) (xy 399.118439 -296.137942)
			(xy 399.153932 -296.172034) (xy 399.183497 -296.211378) (xy 399.206368 -296.254955) (xy 399.221952 -296.301636)
			(xy 399.229847 -296.350213) (xy 399.230342 -296.37482) (xy 400.51915 -296.37482) (xy 400.52311 -296.325766)
			(xy 400.534887 -296.277982) (xy 400.554178 -296.232706) (xy 400.580481 -296.19111) (xy 400.613116 -296.154273)
			(xy 400.651237 -296.123148) (xy 400.693858 -296.098541) (xy 400.739874 -296.081089) (xy 400.788093 -296.071245)
			(xy 400.837268 -296.069264) (xy 400.886123 -296.075196) (xy 400.933394 -296.088888) (xy 400.977856 -296.109986)
			(xy 401.018359 -296.137942) (xy 401.053852 -296.172034) (xy 401.083417 -296.211378) (xy 401.106288 -296.254955)
			(xy 401.121872 -296.301636) (xy 401.129767 -296.350213) (xy 401.130262 -296.37482) (xy 402.41907 -296.37482)
			(xy 402.42303 -296.325766) (xy 402.434807 -296.277982) (xy 402.454098 -296.232706) (xy 402.480401 -296.19111)
			(xy 402.513036 -296.154273) (xy 402.551157 -296.123148) (xy 402.593778 -296.098541) (xy 402.639794 -296.081089)
			(xy 402.688013 -296.071245) (xy 402.737188 -296.069264) (xy 402.786043 -296.075196) (xy 402.833314 -296.088888)
			(xy 402.877776 -296.109986) (xy 402.918279 -296.137942) (xy 402.953772 -296.172034) (xy 402.983337 -296.211378)
			(xy 403.006208 -296.254955) (xy 403.021792 -296.301636) (xy 403.029687 -296.350213) (xy 403.030182 -296.37482)
			(xy 404.319244 -296.37482) (xy 404.323204 -296.325766) (xy 404.334981 -296.277982) (xy 404.354272 -296.232706)
			(xy 404.380575 -296.19111) (xy 404.41321 -296.154273) (xy 404.451331 -296.123148) (xy 404.493952 -296.098541)
			(xy 404.539968 -296.081089) (xy 404.588187 -296.071245) (xy 404.637362 -296.069264) (xy 404.686217 -296.075196)
			(xy 404.733488 -296.088888) (xy 404.77795 -296.109986) (xy 404.818453 -296.137942) (xy 404.853946 -296.172034)
			(xy 404.883511 -296.211378) (xy 404.906382 -296.254955) (xy 404.921966 -296.301636) (xy 404.929861 -296.350213)
			(xy 404.930356 -296.37482) (xy 406.219164 -296.37482) (xy 406.223124 -296.325766) (xy 406.234901 -296.277982)
			(xy 406.254192 -296.232706) (xy 406.280495 -296.19111) (xy 406.31313 -296.154273) (xy 406.351251 -296.123148)
			(xy 406.393872 -296.098541) (xy 406.439888 -296.081089) (xy 406.488107 -296.071245) (xy 406.537282 -296.069264)
			(xy 406.586137 -296.075196) (xy 406.633408 -296.088888) (xy 406.67787 -296.109986) (xy 406.718373 -296.137942)
			(xy 406.753866 -296.172034) (xy 406.783431 -296.211378) (xy 406.806302 -296.254955) (xy 406.821886 -296.301636)
			(xy 406.829781 -296.350213) (xy 406.830276 -296.37482) (xy 409.069044 -296.37482) (xy 409.073004 -296.325766)
			(xy 409.084781 -296.277982) (xy 409.104072 -296.232706) (xy 409.130375 -296.19111) (xy 409.16301 -296.154273)
			(xy 409.201131 -296.123148) (xy 409.243752 -296.098541) (xy 409.289768 -296.081089) (xy 409.337987 -296.071245)
			(xy 409.387162 -296.069264) (xy 409.436017 -296.075196) (xy 409.483288 -296.088888) (xy 409.52775 -296.109986)
			(xy 409.568253 -296.137942) (xy 409.603746 -296.172034) (xy 409.633311 -296.211378) (xy 409.656182 -296.254955)
			(xy 409.671766 -296.301636) (xy 409.679661 -296.350213) (xy 409.680156 -296.37482) (xy 410.969218 -296.37482)
			(xy 410.973178 -296.325766) (xy 410.984955 -296.277982) (xy 411.004246 -296.232706) (xy 411.030549 -296.19111)
			(xy 411.063184 -296.154273) (xy 411.101305 -296.123148) (xy 411.143926 -296.098541) (xy 411.189942 -296.081089)
			(xy 411.238161 -296.071245) (xy 411.287336 -296.069264) (xy 411.336191 -296.075196) (xy 411.383462 -296.088888)
			(xy 411.427924 -296.109986) (xy 411.468427 -296.137942) (xy 411.50392 -296.172034) (xy 411.533485 -296.211378)
			(xy 411.556356 -296.254955) (xy 411.57194 -296.301636) (xy 411.579835 -296.350213) (xy 411.58033 -296.37482)
			(xy 412.869138 -296.37482) (xy 412.873098 -296.325766) (xy 412.884875 -296.277982) (xy 412.904166 -296.232706)
			(xy 412.930469 -296.19111) (xy 412.963104 -296.154273) (xy 413.001225 -296.123148) (xy 413.043846 -296.098541)
			(xy 413.089862 -296.081089) (xy 413.138081 -296.071245) (xy 413.187256 -296.069264) (xy 413.236111 -296.075196)
			(xy 413.283382 -296.088888) (xy 413.327844 -296.109986) (xy 413.368347 -296.137942) (xy 413.40384 -296.172034)
			(xy 413.433405 -296.211378) (xy 413.456276 -296.254955) (xy 413.47186 -296.301636) (xy 413.479755 -296.350213)
			(xy 413.48025 -296.37482) (xy 414.769058 -296.37482) (xy 414.773018 -296.325766) (xy 414.784795 -296.277982)
			(xy 414.804086 -296.232706) (xy 414.830389 -296.19111) (xy 414.863024 -296.154273) (xy 414.901145 -296.123148)
			(xy 414.943766 -296.098541) (xy 414.989782 -296.081089) (xy 415.038001 -296.071245) (xy 415.087176 -296.069264)
			(xy 415.136031 -296.075196) (xy 415.183302 -296.088888) (xy 415.227764 -296.109986) (xy 415.268267 -296.137942)
			(xy 415.30376 -296.172034) (xy 415.333325 -296.211378) (xy 415.356196 -296.254955) (xy 415.37178 -296.301636)
			(xy 415.379675 -296.350213) (xy 415.38017 -296.37482) (xy 415.719018 -296.37482) (xy 415.722978 -296.325766)
			(xy 415.734755 -296.277982) (xy 415.754046 -296.232706) (xy 415.780349 -296.19111) (xy 415.812984 -296.154273)
			(xy 415.851105 -296.123148) (xy 415.893726 -296.098541) (xy 415.939742 -296.081089) (xy 415.987961 -296.071245)
			(xy 416.037136 -296.069264) (xy 416.085991 -296.075196) (xy 416.133262 -296.088888) (xy 416.177724 -296.109986)
			(xy 416.218227 -296.137942) (xy 416.25372 -296.172034) (xy 416.283285 -296.211378) (xy 416.306156 -296.254955)
			(xy 416.32174 -296.301636) (xy 416.329635 -296.350213) (xy 416.33013 -296.37482) (xy 416.668978 -296.37482)
			(xy 416.672938 -296.325766) (xy 416.684715 -296.277982) (xy 416.704006 -296.232706) (xy 416.730309 -296.19111)
			(xy 416.762944 -296.154273) (xy 416.801065 -296.123148) (xy 416.843686 -296.098541) (xy 416.889702 -296.081089)
			(xy 416.937921 -296.071245) (xy 416.987096 -296.069264) (xy 417.035951 -296.075196) (xy 417.083222 -296.088888)
			(xy 417.127684 -296.109986) (xy 417.168187 -296.137942) (xy 417.20368 -296.172034) (xy 417.233245 -296.211378)
			(xy 417.256116 -296.254955) (xy 417.2717 -296.301636) (xy 417.279595 -296.350213) (xy 417.28009 -296.37482)
			(xy 417.279595 -296.399427) (xy 417.2717 -296.448004) (xy 417.256116 -296.494685) (xy 417.233245 -296.538262)
			(xy 417.20368 -296.577606) (xy 417.168187 -296.611698) (xy 417.127684 -296.639654) (xy 417.083222 -296.660752)
			(xy 417.035951 -296.674444) (xy 416.987096 -296.680376) (xy 416.937921 -296.678395) (xy 416.889702 -296.668551)
			(xy 416.843686 -296.651099) (xy 416.801065 -296.626492) (xy 416.762944 -296.595367) (xy 416.730309 -296.55853)
			(xy 416.704006 -296.516934) (xy 416.684715 -296.471658) (xy 416.672938 -296.423874) (xy 416.668978 -296.37482)
			(xy 416.33013 -296.37482) (xy 416.329635 -296.399427) (xy 416.32174 -296.448004) (xy 416.306156 -296.494685)
			(xy 416.283285 -296.538262) (xy 416.25372 -296.577606) (xy 416.218227 -296.611698) (xy 416.177724 -296.639654)
			(xy 416.133262 -296.660752) (xy 416.085991 -296.674444) (xy 416.037136 -296.680376) (xy 415.987961 -296.678395)
			(xy 415.939742 -296.668551) (xy 415.893726 -296.651099) (xy 415.851105 -296.626492) (xy 415.812984 -296.595367)
			(xy 415.780349 -296.55853) (xy 415.754046 -296.516934) (xy 415.734755 -296.471658) (xy 415.722978 -296.423874)
			(xy 415.719018 -296.37482) (xy 415.38017 -296.37482) (xy 415.379675 -296.399427) (xy 415.37178 -296.448004)
			(xy 415.356196 -296.494685) (xy 415.333325 -296.538262) (xy 415.30376 -296.577606) (xy 415.268267 -296.611698)
			(xy 415.227764 -296.639654) (xy 415.183302 -296.660752) (xy 415.136031 -296.674444) (xy 415.087176 -296.680376)
			(xy 415.038001 -296.678395) (xy 414.989782 -296.668551) (xy 414.943766 -296.651099) (xy 414.901145 -296.626492)
			(xy 414.863024 -296.595367) (xy 414.830389 -296.55853) (xy 414.804086 -296.516934) (xy 414.784795 -296.471658)
			(xy 414.773018 -296.423874) (xy 414.769058 -296.37482) (xy 413.48025 -296.37482) (xy 413.479755 -296.399427)
			(xy 413.47186 -296.448004) (xy 413.456276 -296.494685) (xy 413.433405 -296.538262) (xy 413.40384 -296.577606)
			(xy 413.368347 -296.611698) (xy 413.327844 -296.639654) (xy 413.283382 -296.660752) (xy 413.236111 -296.674444)
			(xy 413.187256 -296.680376) (xy 413.138081 -296.678395) (xy 413.089862 -296.668551) (xy 413.043846 -296.651099)
			(xy 413.001225 -296.626492) (xy 412.963104 -296.595367) (xy 412.930469 -296.55853) (xy 412.904166 -296.516934)
			(xy 412.884875 -296.471658) (xy 412.873098 -296.423874) (xy 412.869138 -296.37482) (xy 411.58033 -296.37482)
			(xy 411.579835 -296.399427) (xy 411.57194 -296.448004) (xy 411.556356 -296.494685) (xy 411.533485 -296.538262)
			(xy 411.50392 -296.577606) (xy 411.468427 -296.611698) (xy 411.427924 -296.639654) (xy 411.383462 -296.660752)
			(xy 411.336191 -296.674444) (xy 411.287336 -296.680376) (xy 411.238161 -296.678395) (xy 411.189942 -296.668551)
			(xy 411.143926 -296.651099) (xy 411.101305 -296.626492) (xy 411.063184 -296.595367) (xy 411.030549 -296.55853)
			(xy 411.004246 -296.516934) (xy 410.984955 -296.471658) (xy 410.973178 -296.423874) (xy 410.969218 -296.37482)
			(xy 409.680156 -296.37482) (xy 409.679661 -296.399427) (xy 409.671766 -296.448004) (xy 409.656182 -296.494685)
			(xy 409.633311 -296.538262) (xy 409.603746 -296.577606) (xy 409.568253 -296.611698) (xy 409.52775 -296.639654)
			(xy 409.483288 -296.660752) (xy 409.436017 -296.674444) (xy 409.387162 -296.680376) (xy 409.337987 -296.678395)
			(xy 409.289768 -296.668551) (xy 409.243752 -296.651099) (xy 409.201131 -296.626492) (xy 409.16301 -296.595367)
			(xy 409.130375 -296.55853) (xy 409.104072 -296.516934) (xy 409.084781 -296.471658) (xy 409.073004 -296.423874)
			(xy 409.069044 -296.37482) (xy 406.830276 -296.37482) (xy 406.829781 -296.399427) (xy 406.821886 -296.448004)
			(xy 406.806302 -296.494685) (xy 406.783431 -296.538262) (xy 406.753866 -296.577606) (xy 406.718373 -296.611698)
			(xy 406.67787 -296.639654) (xy 406.633408 -296.660752) (xy 406.586137 -296.674444) (xy 406.537282 -296.680376)
			(xy 406.488107 -296.678395) (xy 406.439888 -296.668551) (xy 406.393872 -296.651099) (xy 406.351251 -296.626492)
			(xy 406.31313 -296.595367) (xy 406.280495 -296.55853) (xy 406.254192 -296.516934) (xy 406.234901 -296.471658)
			(xy 406.223124 -296.423874) (xy 406.219164 -296.37482) (xy 404.930356 -296.37482) (xy 404.929861 -296.399427)
			(xy 404.921966 -296.448004) (xy 404.906382 -296.494685) (xy 404.883511 -296.538262) (xy 404.853946 -296.577606)
			(xy 404.818453 -296.611698) (xy 404.77795 -296.639654) (xy 404.733488 -296.660752) (xy 404.686217 -296.674444)
			(xy 404.637362 -296.680376) (xy 404.588187 -296.678395) (xy 404.539968 -296.668551) (xy 404.493952 -296.651099)
			(xy 404.451331 -296.626492) (xy 404.41321 -296.595367) (xy 404.380575 -296.55853) (xy 404.354272 -296.516934)
			(xy 404.334981 -296.471658) (xy 404.323204 -296.423874) (xy 404.319244 -296.37482) (xy 403.030182 -296.37482)
			(xy 403.029687 -296.399427) (xy 403.021792 -296.448004) (xy 403.006208 -296.494685) (xy 402.983337 -296.538262)
			(xy 402.953772 -296.577606) (xy 402.918279 -296.611698) (xy 402.877776 -296.639654) (xy 402.833314 -296.660752)
			(xy 402.786043 -296.674444) (xy 402.737188 -296.680376) (xy 402.688013 -296.678395) (xy 402.639794 -296.668551)
			(xy 402.593778 -296.651099) (xy 402.551157 -296.626492) (xy 402.513036 -296.595367) (xy 402.480401 -296.55853)
			(xy 402.454098 -296.516934) (xy 402.434807 -296.471658) (xy 402.42303 -296.423874) (xy 402.41907 -296.37482)
			(xy 401.130262 -296.37482) (xy 401.129767 -296.399427) (xy 401.121872 -296.448004) (xy 401.106288 -296.494685)
			(xy 401.083417 -296.538262) (xy 401.053852 -296.577606) (xy 401.018359 -296.611698) (xy 400.977856 -296.639654)
			(xy 400.933394 -296.660752) (xy 400.886123 -296.674444) (xy 400.837268 -296.680376) (xy 400.788093 -296.678395)
			(xy 400.739874 -296.668551) (xy 400.693858 -296.651099) (xy 400.651237 -296.626492) (xy 400.613116 -296.595367)
			(xy 400.580481 -296.55853) (xy 400.554178 -296.516934) (xy 400.534887 -296.471658) (xy 400.52311 -296.423874)
			(xy 400.51915 -296.37482) (xy 399.230342 -296.37482) (xy 399.229847 -296.399427) (xy 399.221952 -296.448004)
			(xy 399.206368 -296.494685) (xy 399.183497 -296.538262) (xy 399.153932 -296.577606) (xy 399.118439 -296.611698)
			(xy 399.077936 -296.639654) (xy 399.033474 -296.660752) (xy 398.986203 -296.674444) (xy 398.937348 -296.680376)
			(xy 398.888173 -296.678395) (xy 398.839954 -296.668551) (xy 398.793938 -296.651099) (xy 398.751317 -296.626492)
			(xy 398.713196 -296.595367) (xy 398.680561 -296.55853) (xy 398.654258 -296.516934) (xy 398.634967 -296.471658)
			(xy 398.62319 -296.423874) (xy 398.61923 -296.37482) (xy 397.330168 -296.37482) (xy 397.329673 -296.399427)
			(xy 397.321778 -296.448004) (xy 397.306194 -296.494685) (xy 397.283323 -296.538262) (xy 397.253758 -296.577606)
			(xy 397.218265 -296.611698) (xy 397.177762 -296.639654) (xy 397.1333 -296.660752) (xy 397.086029 -296.674444)
			(xy 397.037174 -296.680376) (xy 396.987999 -296.678395) (xy 396.93978 -296.668551) (xy 396.893764 -296.651099)
			(xy 396.851143 -296.626492) (xy 396.813022 -296.595367) (xy 396.780387 -296.55853) (xy 396.754084 -296.516934)
			(xy 396.734793 -296.471658) (xy 396.723016 -296.423874) (xy 396.719056 -296.37482) (xy 396.380208 -296.37482)
			(xy 396.379713 -296.399427) (xy 396.371818 -296.448004) (xy 396.356234 -296.494685) (xy 396.333363 -296.538262)
			(xy 396.303798 -296.577606) (xy 396.268305 -296.611698) (xy 396.227802 -296.639654) (xy 396.18334 -296.660752)
			(xy 396.136069 -296.674444) (xy 396.087214 -296.680376) (xy 396.038039 -296.678395) (xy 395.98982 -296.668551)
			(xy 395.943804 -296.651099) (xy 395.901183 -296.626492) (xy 395.863062 -296.595367) (xy 395.830427 -296.55853)
			(xy 395.804124 -296.516934) (xy 395.784833 -296.471658) (xy 395.773056 -296.423874) (xy 395.769096 -296.37482)
			(xy 394.480288 -296.37482) (xy 394.479793 -296.399427) (xy 394.471898 -296.448004) (xy 394.456314 -296.494685)
			(xy 394.433443 -296.538262) (xy 394.403878 -296.577606) (xy 394.368385 -296.611698) (xy 394.327882 -296.639654)
			(xy 394.28342 -296.660752) (xy 394.236149 -296.674444) (xy 394.187294 -296.680376) (xy 394.138119 -296.678395)
			(xy 394.0899 -296.668551) (xy 394.043884 -296.651099) (xy 394.001263 -296.626492) (xy 393.963142 -296.595367)
			(xy 393.930507 -296.55853) (xy 393.904204 -296.516934) (xy 393.884913 -296.471658) (xy 393.873136 -296.423874)
			(xy 393.869176 -296.37482) (xy 393.530328 -296.37482) (xy 393.529833 -296.399427) (xy 393.521938 -296.448004)
			(xy 393.506354 -296.494685) (xy 393.483483 -296.538262) (xy 393.453918 -296.577606) (xy 393.418425 -296.611698)
			(xy 393.377922 -296.639654) (xy 393.33346 -296.660752) (xy 393.286189 -296.674444) (xy 393.237334 -296.680376)
			(xy 393.188159 -296.678395) (xy 393.13994 -296.668551) (xy 393.093924 -296.651099) (xy 393.051303 -296.626492)
			(xy 393.013182 -296.595367) (xy 392.980547 -296.55853) (xy 392.954244 -296.516934) (xy 392.934953 -296.471658)
			(xy 392.923176 -296.423874) (xy 392.919216 -296.37482) (xy 392.580114 -296.37482) (xy 392.579619 -296.399427)
			(xy 392.571724 -296.448004) (xy 392.55614 -296.494685) (xy 392.533269 -296.538262) (xy 392.503704 -296.577606)
			(xy 392.468211 -296.611698) (xy 392.427708 -296.639654) (xy 392.383246 -296.660752) (xy 392.335975 -296.674444)
			(xy 392.28712 -296.680376) (xy 392.237945 -296.678395) (xy 392.189726 -296.668551) (xy 392.14371 -296.651099)
			(xy 392.101089 -296.626492) (xy 392.062968 -296.595367) (xy 392.030333 -296.55853) (xy 392.00403 -296.516934)
			(xy 391.984739 -296.471658) (xy 391.972962 -296.423874) (xy 391.969002 -296.37482) (xy 390.680194 -296.37482)
			(xy 390.679699 -296.399427) (xy 390.671804 -296.448004) (xy 390.65622 -296.494685) (xy 390.633349 -296.538262)
			(xy 390.603784 -296.577606) (xy 390.568291 -296.611698) (xy 390.527788 -296.639654) (xy 390.483326 -296.660752)
			(xy 390.436055 -296.674444) (xy 390.3872 -296.680376) (xy 390.338025 -296.678395) (xy 390.289806 -296.668551)
			(xy 390.24379 -296.651099) (xy 390.201169 -296.626492) (xy 390.163048 -296.595367) (xy 390.130413 -296.55853)
			(xy 390.10411 -296.516934) (xy 390.084819 -296.471658) (xy 390.073042 -296.423874) (xy 390.069082 -296.37482)
			(xy 388.780274 -296.37482) (xy 388.779779 -296.399427) (xy 388.771884 -296.448004) (xy 388.7563 -296.494685)
			(xy 388.733429 -296.538262) (xy 388.703864 -296.577606) (xy 388.668371 -296.611698) (xy 388.627868 -296.639654)
			(xy 388.583406 -296.660752) (xy 388.536135 -296.674444) (xy 388.48728 -296.680376) (xy 388.438105 -296.678395)
			(xy 388.389886 -296.668551) (xy 388.34387 -296.651099) (xy 388.301249 -296.626492) (xy 388.263128 -296.595367)
			(xy 388.230493 -296.55853) (xy 388.20419 -296.516934) (xy 388.184899 -296.471658) (xy 388.173122 -296.423874)
			(xy 388.169162 -296.37482) (xy 387.830314 -296.37482) (xy 387.829819 -296.399427) (xy 387.821924 -296.448004)
			(xy 387.80634 -296.494685) (xy 387.783469 -296.538262) (xy 387.753904 -296.577606) (xy 387.718411 -296.611698)
			(xy 387.677908 -296.639654) (xy 387.633446 -296.660752) (xy 387.586175 -296.674444) (xy 387.53732 -296.680376)
			(xy 387.488145 -296.678395) (xy 387.439926 -296.668551) (xy 387.39391 -296.651099) (xy 387.351289 -296.626492)
			(xy 387.313168 -296.595367) (xy 387.280533 -296.55853) (xy 387.25423 -296.516934) (xy 387.234939 -296.471658)
			(xy 387.223162 -296.423874) (xy 387.219202 -296.37482) (xy 386.8801 -296.37482) (xy 386.879605 -296.399427)
			(xy 386.87171 -296.448004) (xy 386.856126 -296.494685) (xy 386.833255 -296.538262) (xy 386.80369 -296.577606)
			(xy 386.768197 -296.611698) (xy 386.727694 -296.639654) (xy 386.683232 -296.660752) (xy 386.635961 -296.674444)
			(xy 386.587106 -296.680376) (xy 386.537931 -296.678395) (xy 386.489712 -296.668551) (xy 386.443696 -296.651099)
			(xy 386.401075 -296.626492) (xy 386.362954 -296.595367) (xy 386.330319 -296.55853) (xy 386.304016 -296.516934)
			(xy 386.284725 -296.471658) (xy 386.272948 -296.423874) (xy 386.268988 -296.37482) (xy 385.930394 -296.37482)
			(xy 385.929899 -296.399427) (xy 385.922004 -296.448004) (xy 385.90642 -296.494685) (xy 385.883549 -296.538262)
			(xy 385.853984 -296.577606) (xy 385.818491 -296.611698) (xy 385.777988 -296.639654) (xy 385.733526 -296.660752)
			(xy 385.686255 -296.674444) (xy 385.6374 -296.680376) (xy 385.588225 -296.678395) (xy 385.540006 -296.668551)
			(xy 385.49399 -296.651099) (xy 385.451369 -296.626492) (xy 385.413248 -296.595367) (xy 385.380613 -296.55853)
			(xy 385.35431 -296.516934) (xy 385.335019 -296.471658) (xy 385.323242 -296.423874) (xy 385.319282 -296.37482)
			(xy 384.980175 -296.37482) (xy 384.979685 -296.399173) (xy 384.97179 -296.44775) (xy 384.956206 -296.494431)
			(xy 384.933335 -296.538008) (xy 384.90377 -296.577352) (xy 384.868277 -296.611444) (xy 384.827774 -296.6394)
			(xy 384.783312 -296.660498) (xy 384.736041 -296.67419) (xy 384.687186 -296.680122) (xy 384.638011 -296.678141)
			(xy 384.589792 -296.668297) (xy 384.543776 -296.650845) (xy 384.501155 -296.626238) (xy 384.463034 -296.595113)
			(xy 384.430399 -296.558276) (xy 384.404096 -296.51668) (xy 384.384805 -296.471404) (xy 384.373028 -296.42362)
			(xy 384.369068 -296.374566) (xy 382.50915 -296.374566) (xy 382.525301 -296.384423) (xy 382.568169 -296.420098)
			(xy 382.605386 -296.461635) (xy 382.636159 -296.508148) (xy 382.659831 -296.558645) (xy 382.675899 -296.612052)
			(xy 382.684019 -296.667228) (xy 382.684528 -296.695114) (xy 382.684019 -296.723) (xy 382.675899 -296.778176)
			(xy 382.659831 -296.831583) (xy 382.636159 -296.88208) (xy 382.605386 -296.928593) (xy 382.568169 -296.97013)
			(xy 382.525301 -297.005805) (xy 382.477695 -297.034859) (xy 382.426366 -297.056671) (xy 382.372409 -297.070777)
			(xy 382.316972 -297.076877) (xy 382.261238 -297.07484) (xy 382.206395 -297.06471) (xy 382.153611 -297.046703)
			(xy 382.104011 -297.021202) (xy 382.058653 -296.988751) (xy 382.018504 -296.950042) (xy 381.984418 -296.905899)
			(xy 381.957122 -296.857264) (xy 381.937199 -296.805173) (xy 381.925073 -296.750736) (xy 381.921002 -296.695114)
			(xy 381.798068 -296.695114) (xy 381.797559 -296.723) (xy 381.789439 -296.778176) (xy 381.773371 -296.831583)
			(xy 381.749699 -296.88208) (xy 381.718926 -296.928593) (xy 381.681709 -296.97013) (xy 381.638841 -297.005805)
			(xy 381.591235 -297.034859) (xy 381.539906 -297.056671) (xy 381.485949 -297.070777) (xy 381.430512 -297.076877)
			(xy 381.374778 -297.07484) (xy 381.319935 -297.06471) (xy 381.267151 -297.046703) (xy 381.217551 -297.021202)
			(xy 381.172193 -296.988751) (xy 381.132044 -296.950042) (xy 381.097958 -296.905899) (xy 381.070662 -296.857264)
			(xy 381.050739 -296.805173) (xy 381.038613 -296.750736) (xy 381.034542 -296.695114) (xy 380.401068 -296.695114)
			(xy 380.400582 -296.722365) (xy 380.392826 -296.776313) (xy 380.377471 -296.828608) (xy 380.354829 -296.878185)
			(xy 380.325363 -296.924035) (xy 380.289672 -296.965226) (xy 380.248481 -297.000917) (xy 380.202631 -297.030383)
			(xy 380.153054 -297.053025) (xy 380.100759 -297.06838) (xy 380.046811 -297.076136) (xy 379.992309 -297.076136)
			(xy 379.938361 -297.06838) (xy 379.886066 -297.053025) (xy 379.836489 -297.030383) (xy 379.790639 -297.000917)
			(xy 379.749448 -296.965226) (xy 379.713757 -296.924035) (xy 379.684291 -296.878185) (xy 379.661649 -296.828608)
			(xy 379.646294 -296.776313) (xy 379.638538 -296.722365) (xy 379.638052 -296.695114) (xy 351.03308 -296.695114)
			(xy 351.03308 -297.3248) (xy 383.734049 -297.3248) (xy 383.73822 -297.274461) (xy 383.750619 -297.225496)
			(xy 383.770908 -297.179239) (xy 383.798533 -297.136952) (xy 383.832742 -297.099788) (xy 383.872601 -297.068761)
			(xy 383.917022 -297.044718) (xy 383.964795 -297.028314) (xy 384.014617 -297.019996) (xy 384.039872 -297.019472)
			(xy 384.065267 -297.019985) (xy 384.115357 -297.028398) (xy 384.163364 -297.044982) (xy 384.207966 -297.069279)
			(xy 384.247935 -297.100619) (xy 384.265424 -297.11904) (xy 384.273044 -297.127168) (xy 384.292856 -297.135804)
			(xy 384.39217 -297.13301) (xy 384.411728 -297.123612) (xy 384.41884 -297.114976) (xy 384.43463 -297.096405)
			(xy 384.470763 -297.063686) (xy 384.511304 -297.036619) (xy 384.555376 -297.01579) (xy 384.602026 -297.00165)
			(xy 384.650245 -296.994504) (xy 384.674618 -296.994072) (xy 385.624578 -296.994072) (xy 385.650567 -296.994593)
			(xy 385.701905 -297.002721) (xy 385.751339 -297.018781) (xy 385.797653 -297.042376) (xy 385.839705 -297.072926)
			(xy 385.87646 -297.109678) (xy 385.907013 -297.151728) (xy 385.930611 -297.19804) (xy 385.946673 -297.247474)
			(xy 385.954805 -297.298811) (xy 385.954805 -297.32478) (xy 386.268988 -297.32478) (xy 386.272948 -297.275726)
			(xy 386.284725 -297.227942) (xy 386.304016 -297.182666) (xy 386.330319 -297.14107) (xy 386.362954 -297.104233)
			(xy 386.401075 -297.073108) (xy 386.443696 -297.048501) (xy 386.489712 -297.031049) (xy 386.537931 -297.021205)
			(xy 386.587106 -297.019224) (xy 386.635961 -297.025156) (xy 386.683232 -297.038848) (xy 386.727694 -297.059946)
			(xy 386.768197 -297.087902) (xy 386.80369 -297.121994) (xy 386.833255 -297.161338) (xy 386.856126 -297.204915)
			(xy 386.87171 -297.251596) (xy 386.879605 -297.300173) (xy 386.8801 -297.32478) (xy 387.219202 -297.32478)
			(xy 387.223162 -297.275726) (xy 387.234939 -297.227942) (xy 387.25423 -297.182666) (xy 387.280533 -297.14107)
			(xy 387.313168 -297.104233) (xy 387.351289 -297.073108) (xy 387.39391 -297.048501) (xy 387.439926 -297.031049)
			(xy 387.488145 -297.021205) (xy 387.53732 -297.019224) (xy 387.586175 -297.025156) (xy 387.633446 -297.038848)
			(xy 387.677908 -297.059946) (xy 387.718411 -297.087902) (xy 387.753904 -297.121994) (xy 387.783469 -297.161338)
			(xy 387.80634 -297.204915) (xy 387.821924 -297.251596) (xy 387.829819 -297.300173) (xy 387.830314 -297.32478)
			(xy 390.069082 -297.32478) (xy 390.073042 -297.275726) (xy 390.084819 -297.227942) (xy 390.10411 -297.182666)
			(xy 390.130413 -297.14107) (xy 390.163048 -297.104233) (xy 390.201169 -297.073108) (xy 390.24379 -297.048501)
			(xy 390.289806 -297.031049) (xy 390.338025 -297.021205) (xy 390.3872 -297.019224) (xy 390.436055 -297.025156)
			(xy 390.483326 -297.038848) (xy 390.527788 -297.059946) (xy 390.568291 -297.087902) (xy 390.603784 -297.121994)
			(xy 390.633349 -297.161338) (xy 390.65622 -297.204915) (xy 390.671804 -297.251596) (xy 390.679699 -297.300173)
			(xy 390.680194 -297.32478) (xy 391.019042 -297.32478) (xy 391.023002 -297.275726) (xy 391.034779 -297.227942)
			(xy 391.05407 -297.182666) (xy 391.080373 -297.14107) (xy 391.113008 -297.104233) (xy 391.151129 -297.073108)
			(xy 391.19375 -297.048501) (xy 391.239766 -297.031049) (xy 391.287985 -297.021205) (xy 391.33716 -297.019224)
			(xy 391.386015 -297.025156) (xy 391.433286 -297.038848) (xy 391.477748 -297.059946) (xy 391.518251 -297.087902)
			(xy 391.553744 -297.121994) (xy 391.583309 -297.161338) (xy 391.60618 -297.204915) (xy 391.621764 -297.251596)
			(xy 391.629659 -297.300173) (xy 391.630154 -297.32478) (xy 391.969002 -297.32478) (xy 391.972962 -297.275726)
			(xy 391.984739 -297.227942) (xy 392.00403 -297.182666) (xy 392.030333 -297.14107) (xy 392.062968 -297.104233)
			(xy 392.101089 -297.073108) (xy 392.14371 -297.048501) (xy 392.189726 -297.031049) (xy 392.237945 -297.021205)
			(xy 392.28712 -297.019224) (xy 392.335975 -297.025156) (xy 392.383246 -297.038848) (xy 392.427708 -297.059946)
			(xy 392.468211 -297.087902) (xy 392.503704 -297.121994) (xy 392.533269 -297.161338) (xy 392.55614 -297.204915)
			(xy 392.571724 -297.251596) (xy 392.579619 -297.300173) (xy 392.580114 -297.32478) (xy 392.919216 -297.32478)
			(xy 392.923176 -297.275726) (xy 392.934953 -297.227942) (xy 392.954244 -297.182666) (xy 392.980547 -297.14107)
			(xy 393.013182 -297.104233) (xy 393.051303 -297.073108) (xy 393.093924 -297.048501) (xy 393.13994 -297.031049)
			(xy 393.188159 -297.021205) (xy 393.237334 -297.019224) (xy 393.286189 -297.025156) (xy 393.33346 -297.038848)
			(xy 393.377922 -297.059946) (xy 393.418425 -297.087902) (xy 393.453918 -297.121994) (xy 393.483483 -297.161338)
			(xy 393.506354 -297.204915) (xy 393.521938 -297.251596) (xy 393.529833 -297.300173) (xy 393.530328 -297.32478)
			(xy 393.869176 -297.32478) (xy 393.873136 -297.275726) (xy 393.884913 -297.227942) (xy 393.904204 -297.182666)
			(xy 393.930507 -297.14107) (xy 393.963142 -297.104233) (xy 394.001263 -297.073108) (xy 394.043884 -297.048501)
			(xy 394.0899 -297.031049) (xy 394.138119 -297.021205) (xy 394.187294 -297.019224) (xy 394.236149 -297.025156)
			(xy 394.28342 -297.038848) (xy 394.327882 -297.059946) (xy 394.368385 -297.087902) (xy 394.403878 -297.121994)
			(xy 394.433443 -297.161338) (xy 394.456314 -297.204915) (xy 394.471898 -297.251596) (xy 394.479793 -297.300173)
			(xy 394.480288 -297.32478) (xy 394.819136 -297.32478) (xy 394.823096 -297.275726) (xy 394.834873 -297.227942)
			(xy 394.854164 -297.182666) (xy 394.880467 -297.14107) (xy 394.913102 -297.104233) (xy 394.951223 -297.073108)
			(xy 394.993844 -297.048501) (xy 395.03986 -297.031049) (xy 395.088079 -297.021205) (xy 395.137254 -297.019224)
			(xy 395.186109 -297.025156) (xy 395.23338 -297.038848) (xy 395.277842 -297.059946) (xy 395.318345 -297.087902)
			(xy 395.353838 -297.121994) (xy 395.383403 -297.161338) (xy 395.406274 -297.204915) (xy 395.421858 -297.251596)
			(xy 395.429753 -297.300173) (xy 395.430248 -297.32478) (xy 395.769096 -297.32478) (xy 395.773056 -297.275726)
			(xy 395.784833 -297.227942) (xy 395.804124 -297.182666) (xy 395.830427 -297.14107) (xy 395.863062 -297.104233)
			(xy 395.901183 -297.073108) (xy 395.943804 -297.048501) (xy 395.98982 -297.031049) (xy 396.038039 -297.021205)
			(xy 396.087214 -297.019224) (xy 396.136069 -297.025156) (xy 396.18334 -297.038848) (xy 396.227802 -297.059946)
			(xy 396.268305 -297.087902) (xy 396.303798 -297.121994) (xy 396.333363 -297.161338) (xy 396.356234 -297.204915)
			(xy 396.371818 -297.251596) (xy 396.379713 -297.300173) (xy 396.380208 -297.32478) (xy 397.669016 -297.32478)
			(xy 397.672976 -297.275726) (xy 397.684753 -297.227942) (xy 397.704044 -297.182666) (xy 397.730347 -297.14107)
			(xy 397.762982 -297.104233) (xy 397.801103 -297.073108) (xy 397.843724 -297.048501) (xy 397.88974 -297.031049)
			(xy 397.937959 -297.021205) (xy 397.987134 -297.019224) (xy 398.035989 -297.025156) (xy 398.08326 -297.038848)
			(xy 398.127722 -297.059946) (xy 398.168225 -297.087902) (xy 398.203718 -297.121994) (xy 398.233283 -297.161338)
			(xy 398.256154 -297.204915) (xy 398.271738 -297.251596) (xy 398.279633 -297.300173) (xy 398.280128 -297.32478)
			(xy 399.56919 -297.32478) (xy 399.57315 -297.275726) (xy 399.584927 -297.227942) (xy 399.604218 -297.182666)
			(xy 399.630521 -297.14107) (xy 399.663156 -297.104233) (xy 399.701277 -297.073108) (xy 399.743898 -297.048501)
			(xy 399.789914 -297.031049) (xy 399.838133 -297.021205) (xy 399.887308 -297.019224) (xy 399.936163 -297.025156)
			(xy 399.983434 -297.038848) (xy 400.027896 -297.059946) (xy 400.068399 -297.087902) (xy 400.103892 -297.121994)
			(xy 400.133457 -297.161338) (xy 400.156328 -297.204915) (xy 400.171912 -297.251596) (xy 400.179807 -297.300173)
			(xy 400.180302 -297.32478) (xy 401.46911 -297.32478) (xy 401.47307 -297.275726) (xy 401.484847 -297.227942)
			(xy 401.504138 -297.182666) (xy 401.530441 -297.14107) (xy 401.563076 -297.104233) (xy 401.601197 -297.073108)
			(xy 401.643818 -297.048501) (xy 401.689834 -297.031049) (xy 401.738053 -297.021205) (xy 401.787228 -297.019224)
			(xy 401.836083 -297.025156) (xy 401.883354 -297.038848) (xy 401.927816 -297.059946) (xy 401.968319 -297.087902)
			(xy 402.003812 -297.121994) (xy 402.033377 -297.161338) (xy 402.056248 -297.204915) (xy 402.071832 -297.251596)
			(xy 402.079727 -297.300173) (xy 402.080222 -297.32478) (xy 403.36903 -297.32478) (xy 403.37299 -297.275726)
			(xy 403.384767 -297.227942) (xy 403.404058 -297.182666) (xy 403.430361 -297.14107) (xy 403.462996 -297.104233)
			(xy 403.501117 -297.073108) (xy 403.543738 -297.048501) (xy 403.589754 -297.031049) (xy 403.637973 -297.021205)
			(xy 403.687148 -297.019224) (xy 403.736003 -297.025156) (xy 403.783274 -297.038848) (xy 403.827736 -297.059946)
			(xy 403.868239 -297.087902) (xy 403.903732 -297.121994) (xy 403.933297 -297.161338) (xy 403.956168 -297.204915)
			(xy 403.971752 -297.251596) (xy 403.979647 -297.300173) (xy 403.980142 -297.32478) (xy 405.269204 -297.32478)
			(xy 405.273164 -297.275726) (xy 405.284941 -297.227942) (xy 405.304232 -297.182666) (xy 405.330535 -297.14107)
			(xy 405.36317 -297.104233) (xy 405.401291 -297.073108) (xy 405.443912 -297.048501) (xy 405.489928 -297.031049)
			(xy 405.538147 -297.021205) (xy 405.587322 -297.019224) (xy 405.636177 -297.025156) (xy 405.683448 -297.038848)
			(xy 405.72791 -297.059946) (xy 405.768413 -297.087902) (xy 405.803906 -297.121994) (xy 405.833471 -297.161338)
			(xy 405.856342 -297.204915) (xy 405.871926 -297.251596) (xy 405.879821 -297.300173) (xy 405.880316 -297.32478)
			(xy 408.119084 -297.32478) (xy 408.123044 -297.275726) (xy 408.134821 -297.227942) (xy 408.154112 -297.182666)
			(xy 408.180415 -297.14107) (xy 408.21305 -297.104233) (xy 408.251171 -297.073108) (xy 408.293792 -297.048501)
			(xy 408.339808 -297.031049) (xy 408.388027 -297.021205) (xy 408.437202 -297.019224) (xy 408.486057 -297.025156)
			(xy 408.533328 -297.038848) (xy 408.57779 -297.059946) (xy 408.618293 -297.087902) (xy 408.653786 -297.121994)
			(xy 408.683351 -297.161338) (xy 408.706222 -297.204915) (xy 408.721806 -297.251596) (xy 408.729701 -297.300173)
			(xy 408.730196 -297.32478) (xy 410.019004 -297.32478) (xy 410.022964 -297.275726) (xy 410.034741 -297.227942)
			(xy 410.054032 -297.182666) (xy 410.080335 -297.14107) (xy 410.11297 -297.104233) (xy 410.151091 -297.073108)
			(xy 410.193712 -297.048501) (xy 410.239728 -297.031049) (xy 410.287947 -297.021205) (xy 410.337122 -297.019224)
			(xy 410.385977 -297.025156) (xy 410.433248 -297.038848) (xy 410.47771 -297.059946) (xy 410.518213 -297.087902)
			(xy 410.553706 -297.121994) (xy 410.583271 -297.161338) (xy 410.606142 -297.204915) (xy 410.621726 -297.251596)
			(xy 410.629621 -297.300173) (xy 410.630116 -297.32478) (xy 411.919178 -297.32478) (xy 411.923138 -297.275726)
			(xy 411.934915 -297.227942) (xy 411.954206 -297.182666) (xy 411.980509 -297.14107) (xy 412.013144 -297.104233)
			(xy 412.051265 -297.073108) (xy 412.093886 -297.048501) (xy 412.139902 -297.031049) (xy 412.188121 -297.021205)
			(xy 412.237296 -297.019224) (xy 412.286151 -297.025156) (xy 412.333422 -297.038848) (xy 412.377884 -297.059946)
			(xy 412.418387 -297.087902) (xy 412.45388 -297.121994) (xy 412.483445 -297.161338) (xy 412.506316 -297.204915)
			(xy 412.5219 -297.251596) (xy 412.529795 -297.300173) (xy 412.53029 -297.32478) (xy 413.819098 -297.32478)
			(xy 413.823058 -297.275726) (xy 413.834835 -297.227942) (xy 413.854126 -297.182666) (xy 413.880429 -297.14107)
			(xy 413.913064 -297.104233) (xy 413.951185 -297.073108) (xy 413.993806 -297.048501) (xy 414.039822 -297.031049)
			(xy 414.088041 -297.021205) (xy 414.137216 -297.019224) (xy 414.186071 -297.025156) (xy 414.233342 -297.038848)
			(xy 414.277804 -297.059946) (xy 414.318307 -297.087902) (xy 414.3538 -297.121994) (xy 414.383365 -297.161338)
			(xy 414.406236 -297.204915) (xy 414.42182 -297.251596) (xy 414.429715 -297.300173) (xy 414.43021 -297.32478)
			(xy 414.769058 -297.32478) (xy 414.773018 -297.275726) (xy 414.784795 -297.227942) (xy 414.804086 -297.182666)
			(xy 414.830389 -297.14107) (xy 414.863024 -297.104233) (xy 414.901145 -297.073108) (xy 414.943766 -297.048501)
			(xy 414.989782 -297.031049) (xy 415.038001 -297.021205) (xy 415.087176 -297.019224) (xy 415.136031 -297.025156)
			(xy 415.183302 -297.038848) (xy 415.227764 -297.059946) (xy 415.268267 -297.087902) (xy 415.30376 -297.121994)
			(xy 415.333325 -297.161338) (xy 415.356196 -297.204915) (xy 415.37178 -297.251596) (xy 415.379675 -297.300173)
			(xy 415.38017 -297.32478) (xy 415.719018 -297.32478) (xy 415.722978 -297.275726) (xy 415.734755 -297.227942)
			(xy 415.754046 -297.182666) (xy 415.780349 -297.14107) (xy 415.812984 -297.104233) (xy 415.851105 -297.073108)
			(xy 415.893726 -297.048501) (xy 415.939742 -297.031049) (xy 415.987961 -297.021205) (xy 416.037136 -297.019224)
			(xy 416.085991 -297.025156) (xy 416.133262 -297.038848) (xy 416.177724 -297.059946) (xy 416.218227 -297.087902)
			(xy 416.25372 -297.121994) (xy 416.283285 -297.161338) (xy 416.306156 -297.204915) (xy 416.32174 -297.251596)
			(xy 416.329635 -297.300173) (xy 416.33013 -297.32478) (xy 416.668978 -297.32478) (xy 416.672938 -297.275726)
			(xy 416.684715 -297.227942) (xy 416.704006 -297.182666) (xy 416.730309 -297.14107) (xy 416.762944 -297.104233)
			(xy 416.801065 -297.073108) (xy 416.843686 -297.048501) (xy 416.889702 -297.031049) (xy 416.937921 -297.021205)
			(xy 416.987096 -297.019224) (xy 417.035951 -297.025156) (xy 417.083222 -297.038848) (xy 417.127684 -297.059946)
			(xy 417.168187 -297.087902) (xy 417.20368 -297.121994) (xy 417.233245 -297.161338) (xy 417.256116 -297.204915)
			(xy 417.2717 -297.251596) (xy 417.279595 -297.300173) (xy 417.28009 -297.32478) (xy 417.279595 -297.349387)
			(xy 417.2717 -297.397964) (xy 417.256116 -297.444645) (xy 417.233245 -297.488222) (xy 417.20368 -297.527566)
			(xy 417.168187 -297.561658) (xy 417.127684 -297.589614) (xy 417.083222 -297.610712) (xy 417.035951 -297.624404)
			(xy 416.987096 -297.630336) (xy 416.937921 -297.628355) (xy 416.889702 -297.618511) (xy 416.843686 -297.601059)
			(xy 416.801065 -297.576452) (xy 416.762944 -297.545327) (xy 416.730309 -297.50849) (xy 416.704006 -297.466894)
			(xy 416.684715 -297.421618) (xy 416.672938 -297.373834) (xy 416.668978 -297.32478) (xy 416.33013 -297.32478)
			(xy 416.329635 -297.349387) (xy 416.32174 -297.397964) (xy 416.306156 -297.444645) (xy 416.283285 -297.488222)
			(xy 416.25372 -297.527566) (xy 416.218227 -297.561658) (xy 416.177724 -297.589614) (xy 416.133262 -297.610712)
			(xy 416.085991 -297.624404) (xy 416.037136 -297.630336) (xy 415.987961 -297.628355) (xy 415.939742 -297.618511)
			(xy 415.893726 -297.601059) (xy 415.851105 -297.576452) (xy 415.812984 -297.545327) (xy 415.780349 -297.50849)
			(xy 415.754046 -297.466894) (xy 415.734755 -297.421618) (xy 415.722978 -297.373834) (xy 415.719018 -297.32478)
			(xy 415.38017 -297.32478) (xy 415.379675 -297.349387) (xy 415.37178 -297.397964) (xy 415.356196 -297.444645)
			(xy 415.333325 -297.488222) (xy 415.30376 -297.527566) (xy 415.268267 -297.561658) (xy 415.227764 -297.589614)
			(xy 415.183302 -297.610712) (xy 415.136031 -297.624404) (xy 415.087176 -297.630336) (xy 415.038001 -297.628355)
			(xy 414.989782 -297.618511) (xy 414.943766 -297.601059) (xy 414.901145 -297.576452) (xy 414.863024 -297.545327)
			(xy 414.830389 -297.50849) (xy 414.804086 -297.466894) (xy 414.784795 -297.421618) (xy 414.773018 -297.373834)
			(xy 414.769058 -297.32478) (xy 414.43021 -297.32478) (xy 414.429715 -297.349387) (xy 414.42182 -297.397964)
			(xy 414.406236 -297.444645) (xy 414.383365 -297.488222) (xy 414.3538 -297.527566) (xy 414.318307 -297.561658)
			(xy 414.277804 -297.589614) (xy 414.233342 -297.610712) (xy 414.186071 -297.624404) (xy 414.137216 -297.630336)
			(xy 414.088041 -297.628355) (xy 414.039822 -297.618511) (xy 413.993806 -297.601059) (xy 413.951185 -297.576452)
			(xy 413.913064 -297.545327) (xy 413.880429 -297.50849) (xy 413.854126 -297.466894) (xy 413.834835 -297.421618)
			(xy 413.823058 -297.373834) (xy 413.819098 -297.32478) (xy 412.53029 -297.32478) (xy 412.529795 -297.349387)
			(xy 412.5219 -297.397964) (xy 412.506316 -297.444645) (xy 412.483445 -297.488222) (xy 412.45388 -297.527566)
			(xy 412.418387 -297.561658) (xy 412.377884 -297.589614) (xy 412.333422 -297.610712) (xy 412.286151 -297.624404)
			(xy 412.237296 -297.630336) (xy 412.188121 -297.628355) (xy 412.139902 -297.618511) (xy 412.093886 -297.601059)
			(xy 412.051265 -297.576452) (xy 412.013144 -297.545327) (xy 411.980509 -297.50849) (xy 411.954206 -297.466894)
			(xy 411.934915 -297.421618) (xy 411.923138 -297.373834) (xy 411.919178 -297.32478) (xy 410.630116 -297.32478)
			(xy 410.629621 -297.349387) (xy 410.621726 -297.397964) (xy 410.606142 -297.444645) (xy 410.583271 -297.488222)
			(xy 410.553706 -297.527566) (xy 410.518213 -297.561658) (xy 410.47771 -297.589614) (xy 410.433248 -297.610712)
			(xy 410.385977 -297.624404) (xy 410.337122 -297.630336) (xy 410.287947 -297.628355) (xy 410.239728 -297.618511)
			(xy 410.193712 -297.601059) (xy 410.151091 -297.576452) (xy 410.11297 -297.545327) (xy 410.080335 -297.50849)
			(xy 410.054032 -297.466894) (xy 410.034741 -297.421618) (xy 410.022964 -297.373834) (xy 410.019004 -297.32478)
			(xy 408.730196 -297.32478) (xy 408.729701 -297.349387) (xy 408.721806 -297.397964) (xy 408.706222 -297.444645)
			(xy 408.683351 -297.488222) (xy 408.653786 -297.527566) (xy 408.618293 -297.561658) (xy 408.57779 -297.589614)
			(xy 408.533328 -297.610712) (xy 408.486057 -297.624404) (xy 408.437202 -297.630336) (xy 408.388027 -297.628355)
			(xy 408.339808 -297.618511) (xy 408.293792 -297.601059) (xy 408.251171 -297.576452) (xy 408.21305 -297.545327)
			(xy 408.180415 -297.50849) (xy 408.154112 -297.466894) (xy 408.134821 -297.421618) (xy 408.123044 -297.373834)
			(xy 408.119084 -297.32478) (xy 405.880316 -297.32478) (xy 405.879821 -297.349387) (xy 405.871926 -297.397964)
			(xy 405.856342 -297.444645) (xy 405.833471 -297.488222) (xy 405.803906 -297.527566) (xy 405.768413 -297.561658)
			(xy 405.72791 -297.589614) (xy 405.683448 -297.610712) (xy 405.636177 -297.624404) (xy 405.587322 -297.630336)
			(xy 405.538147 -297.628355) (xy 405.489928 -297.618511) (xy 405.443912 -297.601059) (xy 405.401291 -297.576452)
			(xy 405.36317 -297.545327) (xy 405.330535 -297.50849) (xy 405.304232 -297.466894) (xy 405.284941 -297.421618)
			(xy 405.273164 -297.373834) (xy 405.269204 -297.32478) (xy 403.980142 -297.32478) (xy 403.979647 -297.349387)
			(xy 403.971752 -297.397964) (xy 403.956168 -297.444645) (xy 403.933297 -297.488222) (xy 403.903732 -297.527566)
			(xy 403.868239 -297.561658) (xy 403.827736 -297.589614) (xy 403.783274 -297.610712) (xy 403.736003 -297.624404)
			(xy 403.687148 -297.630336) (xy 403.637973 -297.628355) (xy 403.589754 -297.618511) (xy 403.543738 -297.601059)
			(xy 403.501117 -297.576452) (xy 403.462996 -297.545327) (xy 403.430361 -297.50849) (xy 403.404058 -297.466894)
			(xy 403.384767 -297.421618) (xy 403.37299 -297.373834) (xy 403.36903 -297.32478) (xy 402.080222 -297.32478)
			(xy 402.079727 -297.349387) (xy 402.071832 -297.397964) (xy 402.056248 -297.444645) (xy 402.033377 -297.488222)
			(xy 402.003812 -297.527566) (xy 401.968319 -297.561658) (xy 401.927816 -297.589614) (xy 401.883354 -297.610712)
			(xy 401.836083 -297.624404) (xy 401.787228 -297.630336) (xy 401.738053 -297.628355) (xy 401.689834 -297.618511)
			(xy 401.643818 -297.601059) (xy 401.601197 -297.576452) (xy 401.563076 -297.545327) (xy 401.530441 -297.50849)
			(xy 401.504138 -297.466894) (xy 401.484847 -297.421618) (xy 401.47307 -297.373834) (xy 401.46911 -297.32478)
			(xy 400.180302 -297.32478) (xy 400.179807 -297.349387) (xy 400.171912 -297.397964) (xy 400.156328 -297.444645)
			(xy 400.133457 -297.488222) (xy 400.103892 -297.527566) (xy 400.068399 -297.561658) (xy 400.027896 -297.589614)
			(xy 399.983434 -297.610712) (xy 399.936163 -297.624404) (xy 399.887308 -297.630336) (xy 399.838133 -297.628355)
			(xy 399.789914 -297.618511) (xy 399.743898 -297.601059) (xy 399.701277 -297.576452) (xy 399.663156 -297.545327)
			(xy 399.630521 -297.50849) (xy 399.604218 -297.466894) (xy 399.584927 -297.421618) (xy 399.57315 -297.373834)
			(xy 399.56919 -297.32478) (xy 398.280128 -297.32478) (xy 398.279633 -297.349387) (xy 398.271738 -297.397964)
			(xy 398.256154 -297.444645) (xy 398.233283 -297.488222) (xy 398.203718 -297.527566) (xy 398.168225 -297.561658)
			(xy 398.127722 -297.589614) (xy 398.08326 -297.610712) (xy 398.035989 -297.624404) (xy 397.987134 -297.630336)
			(xy 397.937959 -297.628355) (xy 397.88974 -297.618511) (xy 397.843724 -297.601059) (xy 397.801103 -297.576452)
			(xy 397.762982 -297.545327) (xy 397.730347 -297.50849) (xy 397.704044 -297.466894) (xy 397.684753 -297.421618)
			(xy 397.672976 -297.373834) (xy 397.669016 -297.32478) (xy 396.380208 -297.32478) (xy 396.379713 -297.349387)
			(xy 396.371818 -297.397964) (xy 396.356234 -297.444645) (xy 396.333363 -297.488222) (xy 396.303798 -297.527566)
			(xy 396.268305 -297.561658) (xy 396.227802 -297.589614) (xy 396.18334 -297.610712) (xy 396.136069 -297.624404)
			(xy 396.087214 -297.630336) (xy 396.038039 -297.628355) (xy 395.98982 -297.618511) (xy 395.943804 -297.601059)
			(xy 395.901183 -297.576452) (xy 395.863062 -297.545327) (xy 395.830427 -297.50849) (xy 395.804124 -297.466894)
			(xy 395.784833 -297.421618) (xy 395.773056 -297.373834) (xy 395.769096 -297.32478) (xy 395.430248 -297.32478)
			(xy 395.429753 -297.349387) (xy 395.421858 -297.397964) (xy 395.406274 -297.444645) (xy 395.383403 -297.488222)
			(xy 395.353838 -297.527566) (xy 395.318345 -297.561658) (xy 395.277842 -297.589614) (xy 395.23338 -297.610712)
			(xy 395.186109 -297.624404) (xy 395.137254 -297.630336) (xy 395.088079 -297.628355) (xy 395.03986 -297.618511)
			(xy 394.993844 -297.601059) (xy 394.951223 -297.576452) (xy 394.913102 -297.545327) (xy 394.880467 -297.50849)
			(xy 394.854164 -297.466894) (xy 394.834873 -297.421618) (xy 394.823096 -297.373834) (xy 394.819136 -297.32478)
			(xy 394.480288 -297.32478) (xy 394.479793 -297.349387) (xy 394.471898 -297.397964) (xy 394.456314 -297.444645)
			(xy 394.433443 -297.488222) (xy 394.403878 -297.527566) (xy 394.368385 -297.561658) (xy 394.327882 -297.589614)
			(xy 394.28342 -297.610712) (xy 394.236149 -297.624404) (xy 394.187294 -297.630336) (xy 394.138119 -297.628355)
			(xy 394.0899 -297.618511) (xy 394.043884 -297.601059) (xy 394.001263 -297.576452) (xy 393.963142 -297.545327)
			(xy 393.930507 -297.50849) (xy 393.904204 -297.466894) (xy 393.884913 -297.421618) (xy 393.873136 -297.373834)
			(xy 393.869176 -297.32478) (xy 393.530328 -297.32478) (xy 393.529833 -297.349387) (xy 393.521938 -297.397964)
			(xy 393.506354 -297.444645) (xy 393.483483 -297.488222) (xy 393.453918 -297.527566) (xy 393.418425 -297.561658)
			(xy 393.377922 -297.589614) (xy 393.33346 -297.610712) (xy 393.286189 -297.624404) (xy 393.237334 -297.630336)
			(xy 393.188159 -297.628355) (xy 393.13994 -297.618511) (xy 393.093924 -297.601059) (xy 393.051303 -297.576452)
			(xy 393.013182 -297.545327) (xy 392.980547 -297.50849) (xy 392.954244 -297.466894) (xy 392.934953 -297.421618)
			(xy 392.923176 -297.373834) (xy 392.919216 -297.32478) (xy 392.580114 -297.32478) (xy 392.579619 -297.349387)
			(xy 392.571724 -297.397964) (xy 392.55614 -297.444645) (xy 392.533269 -297.488222) (xy 392.503704 -297.527566)
			(xy 392.468211 -297.561658) (xy 392.427708 -297.589614) (xy 392.383246 -297.610712) (xy 392.335975 -297.624404)
			(xy 392.28712 -297.630336) (xy 392.237945 -297.628355) (xy 392.189726 -297.618511) (xy 392.14371 -297.601059)
			(xy 392.101089 -297.576452) (xy 392.062968 -297.545327) (xy 392.030333 -297.50849) (xy 392.00403 -297.466894)
			(xy 391.984739 -297.421618) (xy 391.972962 -297.373834) (xy 391.969002 -297.32478) (xy 391.630154 -297.32478)
			(xy 391.629659 -297.349387) (xy 391.621764 -297.397964) (xy 391.60618 -297.444645) (xy 391.583309 -297.488222)
			(xy 391.553744 -297.527566) (xy 391.518251 -297.561658) (xy 391.477748 -297.589614) (xy 391.433286 -297.610712)
			(xy 391.386015 -297.624404) (xy 391.33716 -297.630336) (xy 391.287985 -297.628355) (xy 391.239766 -297.618511)
			(xy 391.19375 -297.601059) (xy 391.151129 -297.576452) (xy 391.113008 -297.545327) (xy 391.080373 -297.50849)
			(xy 391.05407 -297.466894) (xy 391.034779 -297.421618) (xy 391.023002 -297.373834) (xy 391.019042 -297.32478)
			(xy 390.680194 -297.32478) (xy 390.679699 -297.349387) (xy 390.671804 -297.397964) (xy 390.65622 -297.444645)
			(xy 390.633349 -297.488222) (xy 390.603784 -297.527566) (xy 390.568291 -297.561658) (xy 390.527788 -297.589614)
			(xy 390.483326 -297.610712) (xy 390.436055 -297.624404) (xy 390.3872 -297.630336) (xy 390.338025 -297.628355)
			(xy 390.289806 -297.618511) (xy 390.24379 -297.601059) (xy 390.201169 -297.576452) (xy 390.163048 -297.545327)
			(xy 390.130413 -297.50849) (xy 390.10411 -297.466894) (xy 390.084819 -297.421618) (xy 390.073042 -297.373834)
			(xy 390.069082 -297.32478) (xy 387.830314 -297.32478) (xy 387.829819 -297.349387) (xy 387.821924 -297.397964)
			(xy 387.80634 -297.444645) (xy 387.783469 -297.488222) (xy 387.753904 -297.527566) (xy 387.718411 -297.561658)
			(xy 387.677908 -297.589614) (xy 387.633446 -297.610712) (xy 387.586175 -297.624404) (xy 387.53732 -297.630336)
			(xy 387.488145 -297.628355) (xy 387.439926 -297.618511) (xy 387.39391 -297.601059) (xy 387.351289 -297.576452)
			(xy 387.313168 -297.545327) (xy 387.280533 -297.50849) (xy 387.25423 -297.466894) (xy 387.234939 -297.421618)
			(xy 387.223162 -297.373834) (xy 387.219202 -297.32478) (xy 386.8801 -297.32478) (xy 386.879605 -297.349387)
			(xy 386.87171 -297.397964) (xy 386.856126 -297.444645) (xy 386.833255 -297.488222) (xy 386.80369 -297.527566)
			(xy 386.768197 -297.561658) (xy 386.727694 -297.589614) (xy 386.683232 -297.610712) (xy 386.635961 -297.624404)
			(xy 386.587106 -297.630336) (xy 386.537931 -297.628355) (xy 386.489712 -297.618511) (xy 386.443696 -297.601059)
			(xy 386.401075 -297.576452) (xy 386.362954 -297.545327) (xy 386.330319 -297.50849) (xy 386.304016 -297.466894)
			(xy 386.284725 -297.421618) (xy 386.272948 -297.373834) (xy 386.268988 -297.32478) (xy 385.954805 -297.32478)
			(xy 385.954805 -297.350789) (xy 385.946673 -297.402126) (xy 385.930611 -297.45156) (xy 385.907013 -297.497872)
			(xy 385.87646 -297.539922) (xy 385.839705 -297.576674) (xy 385.797653 -297.607224) (xy 385.751339 -297.630819)
			(xy 385.701905 -297.646879) (xy 385.650567 -297.655007) (xy 385.624578 -297.655488) (xy 384.674618 -297.655488)
			(xy 384.650244 -297.655085) (xy 384.602024 -297.647936) (xy 384.555373 -297.633791) (xy 384.511303 -297.612954)
			(xy 384.470767 -297.585877) (xy 384.434642 -297.553147) (xy 384.41884 -297.534584) (xy 384.411728 -297.525948)
			(xy 384.39217 -297.51655) (xy 384.292856 -297.513756) (xy 384.273044 -297.522392) (xy 384.265424 -297.53052)
			(xy 384.247939 -297.548946) (xy 384.207975 -297.580297) (xy 384.163372 -297.604598) (xy 384.115362 -297.621181)
			(xy 384.065269 -297.629585) (xy 384.039872 -297.630088) (xy 384.014617 -297.629604) (xy 383.964795 -297.621286)
			(xy 383.917022 -297.604882) (xy 383.872601 -297.580839) (xy 383.832742 -297.549812) (xy 383.798533 -297.512648)
			(xy 383.770908 -297.470361) (xy 383.750619 -297.424104) (xy 383.73822 -297.375139) (xy 383.734049 -297.3248)
			(xy 351.03308 -297.3248) (xy 351.03308 -297.831256) (xy 374.111518 -297.831256) (xy 374.115589 -297.775634)
			(xy 374.127715 -297.721197) (xy 374.147638 -297.669106) (xy 374.174934 -297.620471) (xy 374.20902 -297.576328)
			(xy 374.249169 -297.537619) (xy 374.294527 -297.505168) (xy 374.344127 -297.479667) (xy 374.396911 -297.46166)
			(xy 374.451754 -297.45153) (xy 374.507488 -297.449493) (xy 374.562925 -297.455593) (xy 374.616882 -297.469699)
			(xy 374.668211 -297.491511) (xy 374.715817 -297.520565) (xy 374.758685 -297.55624) (xy 374.795902 -297.597777)
			(xy 374.826675 -297.64429) (xy 374.850347 -297.694787) (xy 374.866415 -297.748194) (xy 374.874535 -297.80337)
			(xy 374.875044 -297.831256) (xy 375.596656 -297.831256) (xy 375.600727 -297.775634) (xy 375.612853 -297.721197)
			(xy 375.632776 -297.669106) (xy 375.660072 -297.620471) (xy 375.694158 -297.576328) (xy 375.734307 -297.537619)
			(xy 375.779665 -297.505168) (xy 375.829265 -297.479667) (xy 375.882049 -297.46166) (xy 375.936892 -297.45153)
			(xy 375.992626 -297.449493) (xy 376.048063 -297.455593) (xy 376.10202 -297.469699) (xy 376.153349 -297.491511)
			(xy 376.200955 -297.520565) (xy 376.243823 -297.55624) (xy 376.28104 -297.597777) (xy 376.311813 -297.64429)
			(xy 376.335485 -297.694787) (xy 376.351553 -297.748194) (xy 376.359673 -297.80337) (xy 376.360182 -297.831256)
			(xy 376.359673 -297.859142) (xy 376.351553 -297.914318) (xy 376.335485 -297.967725) (xy 376.311813 -298.018222)
			(xy 376.28104 -298.064735) (xy 376.243823 -298.106272) (xy 376.200955 -298.141947) (xy 376.153349 -298.171001)
			(xy 376.10202 -298.192813) (xy 376.048063 -298.206919) (xy 375.992626 -298.213019) (xy 375.936892 -298.210982)
			(xy 375.882049 -298.200852) (xy 375.829265 -298.182845) (xy 375.779665 -298.157344) (xy 375.734307 -298.124893)
			(xy 375.694158 -298.086184) (xy 375.660072 -298.042041) (xy 375.632776 -297.993406) (xy 375.612853 -297.941315)
			(xy 375.600727 -297.886878) (xy 375.596656 -297.831256) (xy 374.875044 -297.831256) (xy 374.874535 -297.859142)
			(xy 374.866415 -297.914318) (xy 374.850347 -297.967725) (xy 374.826675 -298.018222) (xy 374.795902 -298.064735)
			(xy 374.758685 -298.106272) (xy 374.715817 -298.141947) (xy 374.668211 -298.171001) (xy 374.616882 -298.192813)
			(xy 374.562925 -298.206919) (xy 374.507488 -298.213019) (xy 374.451754 -298.210982) (xy 374.396911 -298.200852)
			(xy 374.344127 -298.182845) (xy 374.294527 -298.157344) (xy 374.249169 -298.124893) (xy 374.20902 -298.086184)
			(xy 374.174934 -298.042041) (xy 374.147638 -297.993406) (xy 374.127715 -297.941315) (xy 374.115589 -297.886878)
			(xy 374.111518 -297.831256) (xy 351.03308 -297.831256) (xy 351.03308 -298.274486) (xy 384.369068 -298.274486)
			(xy 384.373028 -298.225432) (xy 384.384805 -298.177648) (xy 384.404096 -298.132372) (xy 384.430399 -298.090776)
			(xy 384.463034 -298.053939) (xy 384.501155 -298.022814) (xy 384.543776 -297.998207) (xy 384.589792 -297.980755)
			(xy 384.638011 -297.970911) (xy 384.687186 -297.96893) (xy 384.736041 -297.974862) (xy 384.783312 -297.988554)
			(xy 384.827774 -298.009652) (xy 384.868277 -298.037608) (xy 384.90377 -298.0717) (xy 384.933335 -298.111044)
			(xy 384.956206 -298.154621) (xy 384.97179 -298.201302) (xy 384.979685 -298.249879) (xy 384.98018 -298.274486)
			(xy 384.980175 -298.27474) (xy 385.318774 -298.27474) (xy 385.322734 -298.225686) (xy 385.334511 -298.177902)
			(xy 385.353802 -298.132626) (xy 385.380105 -298.09103) (xy 385.41274 -298.054193) (xy 385.450861 -298.023068)
			(xy 385.493482 -297.998461) (xy 385.539498 -297.981009) (xy 385.587717 -297.971165) (xy 385.636892 -297.969184)
			(xy 385.685747 -297.975116) (xy 385.733018 -297.988808) (xy 385.77748 -298.009906) (xy 385.817983 -298.037862)
			(xy 385.853476 -298.071954) (xy 385.883041 -298.111298) (xy 385.905912 -298.154875) (xy 385.921496 -298.201556)
			(xy 385.929391 -298.250133) (xy 385.929886 -298.27474) (xy 386.268988 -298.27474) (xy 386.272948 -298.225686)
			(xy 386.284725 -298.177902) (xy 386.304016 -298.132626) (xy 386.330319 -298.09103) (xy 386.362954 -298.054193)
			(xy 386.401075 -298.023068) (xy 386.443696 -297.998461) (xy 386.489712 -297.981009) (xy 386.537931 -297.971165)
			(xy 386.587106 -297.969184) (xy 386.635961 -297.975116) (xy 386.683232 -297.988808) (xy 386.727694 -298.009906)
			(xy 386.768197 -298.037862) (xy 386.80369 -298.071954) (xy 386.833255 -298.111298) (xy 386.856126 -298.154875)
			(xy 386.87171 -298.201556) (xy 386.879605 -298.250133) (xy 386.8801 -298.27474) (xy 386.879934 -298.282973)
			(xy 387.219275 -298.282973) (xy 387.221964 -298.233401) (xy 387.232638 -298.184918) (xy 387.251015 -298.138801)
			(xy 387.276612 -298.096264) (xy 387.308753 -298.058429) (xy 387.346591 -298.026292) (xy 387.389131 -298.0007)
			(xy 387.435251 -297.982328) (xy 387.483735 -297.97166) (xy 387.533307 -297.968976) (xy 387.58266 -297.974347)
			(xy 387.630493 -297.987633) (xy 387.675547 -298.008482) (xy 387.716634 -298.036346) (xy 387.752672 -298.07049)
			(xy 387.782711 -298.110015) (xy 387.80596 -298.153879) (xy 387.821806 -298.200927) (xy 387.829831 -298.249918)
			(xy 387.830314 -298.27474) (xy 387.830224 -298.283844) (xy 387.829078 -298.302018) (xy 387.828028 -298.311062)
			(xy 387.826758 -298.323254) (xy 387.834632 -298.345352) (xy 387.911086 -298.418504) (xy 387.933692 -298.425362)
			(xy 387.94563 -298.42333) (xy 387.959123 -298.42127) (xy 387.986336 -298.41911) (xy 387.999986 -298.419012)
			(xy 388.070344 -298.419012) (xy 388.081003 -298.418398) (xy 388.100426 -298.409585) (xy 388.107936 -298.401994)
			(xy 388.165848 -298.337732) (xy 388.172452 -298.317666) (xy 388.171436 -298.306744) (xy 388.169658 -298.27474)
			(xy 388.17018 -298.249485) (xy 388.178493 -298.199663) (xy 388.194894 -298.151889) (xy 388.218935 -298.107466)
			(xy 388.249959 -298.067606) (xy 388.287121 -298.033396) (xy 388.329407 -298.00577) (xy 388.375663 -297.98548)
			(xy 388.424628 -297.97308) (xy 388.474966 -297.968909) (xy 388.525304 -297.97308) (xy 388.574269 -297.98548)
			(xy 388.620525 -298.00577) (xy 388.662811 -298.033396) (xy 388.699973 -298.067606) (xy 388.730997 -298.107466)
			(xy 388.755038 -298.151889) (xy 388.771439 -298.199663) (xy 388.779752 -298.249485) (xy 388.780274 -298.27474)
			(xy 388.778496 -298.306744) (xy 388.77748 -298.317666) (xy 388.784084 -298.337732) (xy 388.841996 -298.401994)
			(xy 388.849451 -298.409662) (xy 388.868908 -298.418485) (xy 388.879588 -298.419012) (xy 388.949946 -298.419012)
			(xy 388.963596 -298.419096) (xy 388.990809 -298.421261) (xy 389.004302 -298.42333) (xy 389.01624 -298.425362)
			(xy 389.038846 -298.418504) (xy 389.1153 -298.345352) (xy 389.123174 -298.323254) (xy 389.121904 -298.311062)
			(xy 389.120859 -298.302017) (xy 389.119716 -298.283844) (xy 389.119618 -298.27474) (xy 389.12014 -298.249485)
			(xy 389.128453 -298.199663) (xy 389.144854 -298.151889) (xy 389.168895 -298.107466) (xy 389.199919 -298.067606)
			(xy 389.237081 -298.033396) (xy 389.279367 -298.00577) (xy 389.325623 -297.98548) (xy 389.374588 -297.97308)
			(xy 389.424926 -297.968909) (xy 389.475264 -297.97308) (xy 389.524229 -297.98548) (xy 389.570485 -298.00577)
			(xy 389.612771 -298.033396) (xy 389.649933 -298.067606) (xy 389.680957 -298.107466) (xy 389.704998 -298.151889)
			(xy 389.721399 -298.199663) (xy 389.729712 -298.249485) (xy 389.730234 -298.27474) (xy 389.730062 -298.288923)
			(xy 389.727387 -298.317163) (xy 389.7249 -298.331128) (xy 389.722614 -298.343574) (xy 389.72998 -298.367196)
			(xy 389.80745 -298.444666) (xy 389.831072 -298.452032) (xy 389.843518 -298.449746) (xy 389.857484 -298.447271)
			(xy 389.885724 -298.444598) (xy 389.899906 -298.444412) (xy 389.914089 -298.444587) (xy 389.942329 -298.44726)
			(xy 389.956294 -298.449746) (xy 389.96874 -298.452032) (xy 389.992362 -298.444666) (xy 390.069832 -298.367196)
			(xy 390.077198 -298.343574) (xy 390.074912 -298.331128) (xy 390.07243 -298.317163) (xy 390.069762 -298.288923)
			(xy 390.069578 -298.27474) (xy 390.070035 -298.249915) (xy 390.078061 -298.200918) (xy 390.093909 -298.153865)
			(xy 390.117161 -298.109996) (xy 390.147203 -298.070467) (xy 390.183246 -298.036319) (xy 390.224338 -298.008452)
			(xy 390.269397 -297.9876) (xy 390.317236 -297.974314) (xy 390.366595 -297.968942) (xy 390.416172 -297.971626)
			(xy 390.464662 -297.982296) (xy 390.510787 -298.000671) (xy 390.553331 -298.026266) (xy 390.591174 -298.058407)
			(xy 390.623319 -298.096247) (xy 390.648917 -298.13879) (xy 390.667296 -298.184913) (xy 390.67797 -298.233402)
			(xy 390.680212 -298.27474) (xy 391.019042 -298.27474) (xy 391.023002 -298.225686) (xy 391.034779 -298.177902)
			(xy 391.05407 -298.132626) (xy 391.080373 -298.09103) (xy 391.113008 -298.054193) (xy 391.151129 -298.023068)
			(xy 391.19375 -297.998461) (xy 391.239766 -297.981009) (xy 391.287985 -297.971165) (xy 391.33716 -297.969184)
			(xy 391.386015 -297.975116) (xy 391.433286 -297.988808) (xy 391.477748 -298.009906) (xy 391.518251 -298.037862)
			(xy 391.553744 -298.071954) (xy 391.583309 -298.111298) (xy 391.60618 -298.154875) (xy 391.621764 -298.201556)
			(xy 391.629659 -298.250133) (xy 391.630154 -298.27474) (xy 391.969002 -298.27474) (xy 391.972962 -298.225686)
			(xy 391.984739 -298.177902) (xy 392.00403 -298.132626) (xy 392.030333 -298.09103) (xy 392.062968 -298.054193)
			(xy 392.101089 -298.023068) (xy 392.14371 -297.998461) (xy 392.189726 -297.981009) (xy 392.237945 -297.971165)
			(xy 392.28712 -297.969184) (xy 392.335975 -297.975116) (xy 392.383246 -297.988808) (xy 392.427708 -298.009906)
			(xy 392.468211 -298.037862) (xy 392.503704 -298.071954) (xy 392.533269 -298.111298) (xy 392.55614 -298.154875)
			(xy 392.571724 -298.201556) (xy 392.579619 -298.250133) (xy 392.580114 -298.27474) (xy 392.919216 -298.27474)
			(xy 392.923176 -298.225686) (xy 392.934953 -298.177902) (xy 392.954244 -298.132626) (xy 392.980547 -298.09103)
			(xy 393.013182 -298.054193) (xy 393.051303 -298.023068) (xy 393.093924 -297.998461) (xy 393.13994 -297.981009)
			(xy 393.188159 -297.971165) (xy 393.237334 -297.969184) (xy 393.286189 -297.975116) (xy 393.33346 -297.988808)
			(xy 393.377922 -298.009906) (xy 393.418425 -298.037862) (xy 393.453918 -298.071954) (xy 393.483483 -298.111298)
			(xy 393.506354 -298.154875) (xy 393.521938 -298.201556) (xy 393.529833 -298.250133) (xy 393.530328 -298.27474)
			(xy 393.869176 -298.27474) (xy 393.873136 -298.225686) (xy 393.884913 -298.177902) (xy 393.904204 -298.132626)
			(xy 393.930507 -298.09103) (xy 393.963142 -298.054193) (xy 394.001263 -298.023068) (xy 394.043884 -297.998461)
			(xy 394.0899 -297.981009) (xy 394.138119 -297.971165) (xy 394.187294 -297.969184) (xy 394.236149 -297.975116)
			(xy 394.28342 -297.988808) (xy 394.327882 -298.009906) (xy 394.368385 -298.037862) (xy 394.403878 -298.071954)
			(xy 394.433443 -298.111298) (xy 394.456314 -298.154875) (xy 394.471898 -298.201556) (xy 394.479793 -298.250133)
			(xy 394.480288 -298.27474) (xy 395.769096 -298.27474) (xy 395.773056 -298.225686) (xy 395.784833 -298.177902)
			(xy 395.804124 -298.132626) (xy 395.830427 -298.09103) (xy 395.863062 -298.054193) (xy 395.901183 -298.023068)
			(xy 395.943804 -297.998461) (xy 395.98982 -297.981009) (xy 396.038039 -297.971165) (xy 396.087214 -297.969184)
			(xy 396.136069 -297.975116) (xy 396.18334 -297.988808) (xy 396.227802 -298.009906) (xy 396.268305 -298.037862)
			(xy 396.303798 -298.071954) (xy 396.333363 -298.111298) (xy 396.356234 -298.154875) (xy 396.371818 -298.201556)
			(xy 396.379713 -298.250133) (xy 396.380208 -298.27474) (xy 396.719056 -298.27474) (xy 396.723016 -298.225686)
			(xy 396.734793 -298.177902) (xy 396.754084 -298.132626) (xy 396.780387 -298.09103) (xy 396.813022 -298.054193)
			(xy 396.851143 -298.023068) (xy 396.893764 -297.998461) (xy 396.93978 -297.981009) (xy 396.987999 -297.971165)
			(xy 397.037174 -297.969184) (xy 397.086029 -297.975116) (xy 397.1333 -297.988808) (xy 397.177762 -298.009906)
			(xy 397.218265 -298.037862) (xy 397.253758 -298.071954) (xy 397.283323 -298.111298) (xy 397.306194 -298.154875)
			(xy 397.321778 -298.201556) (xy 397.329673 -298.250133) (xy 397.330168 -298.27474) (xy 398.61923 -298.27474)
			(xy 398.62319 -298.225686) (xy 398.634967 -298.177902) (xy 398.654258 -298.132626) (xy 398.680561 -298.09103)
			(xy 398.713196 -298.054193) (xy 398.751317 -298.023068) (xy 398.793938 -297.998461) (xy 398.839954 -297.981009)
			(xy 398.888173 -297.971165) (xy 398.937348 -297.969184) (xy 398.986203 -297.975116) (xy 399.033474 -297.988808)
			(xy 399.077936 -298.009906) (xy 399.118439 -298.037862) (xy 399.153932 -298.071954) (xy 399.183497 -298.111298)
			(xy 399.206368 -298.154875) (xy 399.221952 -298.201556) (xy 399.229847 -298.250133) (xy 399.230342 -298.27474)
			(xy 400.51915 -298.27474) (xy 400.52311 -298.225686) (xy 400.534887 -298.177902) (xy 400.554178 -298.132626)
			(xy 400.580481 -298.09103) (xy 400.613116 -298.054193) (xy 400.651237 -298.023068) (xy 400.693858 -297.998461)
			(xy 400.739874 -297.981009) (xy 400.788093 -297.971165) (xy 400.837268 -297.969184) (xy 400.886123 -297.975116)
			(xy 400.933394 -297.988808) (xy 400.977856 -298.009906) (xy 401.018359 -298.037862) (xy 401.053852 -298.071954)
			(xy 401.083417 -298.111298) (xy 401.106288 -298.154875) (xy 401.121872 -298.201556) (xy 401.129767 -298.250133)
			(xy 401.130262 -298.27474) (xy 402.41907 -298.27474) (xy 402.42303 -298.225686) (xy 402.434807 -298.177902)
			(xy 402.454098 -298.132626) (xy 402.480401 -298.09103) (xy 402.513036 -298.054193) (xy 402.551157 -298.023068)
			(xy 402.593778 -297.998461) (xy 402.639794 -297.981009) (xy 402.688013 -297.971165) (xy 402.737188 -297.969184)
			(xy 402.786043 -297.975116) (xy 402.833314 -297.988808) (xy 402.877776 -298.009906) (xy 402.918279 -298.037862)
			(xy 402.953772 -298.071954) (xy 402.983337 -298.111298) (xy 403.006208 -298.154875) (xy 403.021792 -298.201556)
			(xy 403.029687 -298.250133) (xy 403.030182 -298.27474) (xy 404.31899 -298.27474) (xy 404.32295 -298.225686)
			(xy 404.334727 -298.177902) (xy 404.354018 -298.132626) (xy 404.380321 -298.09103) (xy 404.412956 -298.054193)
			(xy 404.451077 -298.023068) (xy 404.493698 -297.998461) (xy 404.539714 -297.981009) (xy 404.587933 -297.971165)
			(xy 404.637108 -297.969184) (xy 404.685963 -297.975116) (xy 404.733234 -297.988808) (xy 404.777696 -298.009906)
			(xy 404.818199 -298.037862) (xy 404.853692 -298.071954) (xy 404.883257 -298.111298) (xy 404.906128 -298.154875)
			(xy 404.921712 -298.201556) (xy 404.929607 -298.250133) (xy 404.930102 -298.27474) (xy 406.219164 -298.27474)
			(xy 406.223124 -298.225686) (xy 406.234901 -298.177902) (xy 406.254192 -298.132626) (xy 406.280495 -298.09103)
			(xy 406.31313 -298.054193) (xy 406.351251 -298.023068) (xy 406.393872 -297.998461) (xy 406.439888 -297.981009)
			(xy 406.488107 -297.971165) (xy 406.537282 -297.969184) (xy 406.586137 -297.975116) (xy 406.633408 -297.988808)
			(xy 406.67787 -298.009906) (xy 406.718373 -298.037862) (xy 406.753866 -298.071954) (xy 406.783431 -298.111298)
			(xy 406.806302 -298.154875) (xy 406.821886 -298.201556) (xy 406.829781 -298.250133) (xy 406.830276 -298.27474)
			(xy 409.069044 -298.27474) (xy 409.073004 -298.225686) (xy 409.084781 -298.177902) (xy 409.104072 -298.132626)
			(xy 409.130375 -298.09103) (xy 409.16301 -298.054193) (xy 409.201131 -298.023068) (xy 409.243752 -297.998461)
			(xy 409.289768 -297.981009) (xy 409.337987 -297.971165) (xy 409.387162 -297.969184) (xy 409.436017 -297.975116)
			(xy 409.483288 -297.988808) (xy 409.52775 -298.009906) (xy 409.568253 -298.037862) (xy 409.603746 -298.071954)
			(xy 409.633311 -298.111298) (xy 409.656182 -298.154875) (xy 409.671766 -298.201556) (xy 409.679661 -298.250133)
			(xy 409.680156 -298.27474) (xy 410.969218 -298.27474) (xy 410.973178 -298.225686) (xy 410.984955 -298.177902)
			(xy 411.004246 -298.132626) (xy 411.030549 -298.09103) (xy 411.063184 -298.054193) (xy 411.101305 -298.023068)
			(xy 411.143926 -297.998461) (xy 411.189942 -297.981009) (xy 411.238161 -297.971165) (xy 411.287336 -297.969184)
			(xy 411.336191 -297.975116) (xy 411.383462 -297.988808) (xy 411.427924 -298.009906) (xy 411.468427 -298.037862)
			(xy 411.50392 -298.071954) (xy 411.533485 -298.111298) (xy 411.556356 -298.154875) (xy 411.57194 -298.201556)
			(xy 411.579835 -298.250133) (xy 411.58033 -298.27474) (xy 412.869138 -298.27474) (xy 412.873098 -298.225686)
			(xy 412.884875 -298.177902) (xy 412.904166 -298.132626) (xy 412.930469 -298.09103) (xy 412.963104 -298.054193)
			(xy 413.001225 -298.023068) (xy 413.043846 -297.998461) (xy 413.089862 -297.981009) (xy 413.138081 -297.971165)
			(xy 413.187256 -297.969184) (xy 413.236111 -297.975116) (xy 413.283382 -297.988808) (xy 413.327844 -298.009906)
			(xy 413.368347 -298.037862) (xy 413.40384 -298.071954) (xy 413.433405 -298.111298) (xy 413.456276 -298.154875)
			(xy 413.47186 -298.201556) (xy 413.479755 -298.250133) (xy 413.48025 -298.27474) (xy 414.769058 -298.27474)
			(xy 414.773018 -298.225686) (xy 414.784795 -298.177902) (xy 414.804086 -298.132626) (xy 414.830389 -298.09103)
			(xy 414.863024 -298.054193) (xy 414.901145 -298.023068) (xy 414.943766 -297.998461) (xy 414.989782 -297.981009)
			(xy 415.038001 -297.971165) (xy 415.087176 -297.969184) (xy 415.136031 -297.975116) (xy 415.183302 -297.988808)
			(xy 415.227764 -298.009906) (xy 415.268267 -298.037862) (xy 415.30376 -298.071954) (xy 415.333325 -298.111298)
			(xy 415.356196 -298.154875) (xy 415.37178 -298.201556) (xy 415.379675 -298.250133) (xy 415.38017 -298.27474)
			(xy 416.668978 -298.27474) (xy 416.672938 -298.225686) (xy 416.684715 -298.177902) (xy 416.704006 -298.132626)
			(xy 416.730309 -298.09103) (xy 416.762944 -298.054193) (xy 416.801065 -298.023068) (xy 416.843686 -297.998461)
			(xy 416.889702 -297.981009) (xy 416.937921 -297.971165) (xy 416.987096 -297.969184) (xy 417.035951 -297.975116)
			(xy 417.083222 -297.988808) (xy 417.127684 -298.009906) (xy 417.168187 -298.037862) (xy 417.20368 -298.071954)
			(xy 417.233245 -298.111298) (xy 417.256116 -298.154875) (xy 417.2717 -298.201556) (xy 417.279595 -298.250133)
			(xy 417.28009 -298.27474) (xy 417.279595 -298.299347) (xy 417.2717 -298.347924) (xy 417.256116 -298.394605)
			(xy 417.233245 -298.438182) (xy 417.20368 -298.477526) (xy 417.168187 -298.511618) (xy 417.127684 -298.539574)
			(xy 417.083222 -298.560672) (xy 417.035951 -298.574364) (xy 416.987096 -298.580296) (xy 416.937921 -298.578315)
			(xy 416.889702 -298.568471) (xy 416.843686 -298.551019) (xy 416.801065 -298.526412) (xy 416.762944 -298.495287)
			(xy 416.730309 -298.45845) (xy 416.704006 -298.416854) (xy 416.684715 -298.371578) (xy 416.672938 -298.323794)
			(xy 416.668978 -298.27474) (xy 415.38017 -298.27474) (xy 415.379675 -298.299347) (xy 415.37178 -298.347924)
			(xy 415.356196 -298.394605) (xy 415.333325 -298.438182) (xy 415.30376 -298.477526) (xy 415.268267 -298.511618)
			(xy 415.227764 -298.539574) (xy 415.183302 -298.560672) (xy 415.136031 -298.574364) (xy 415.087176 -298.580296)
			(xy 415.038001 -298.578315) (xy 414.989782 -298.568471) (xy 414.943766 -298.551019) (xy 414.901145 -298.526412)
			(xy 414.863024 -298.495287) (xy 414.830389 -298.45845) (xy 414.804086 -298.416854) (xy 414.784795 -298.371578)
			(xy 414.773018 -298.323794) (xy 414.769058 -298.27474) (xy 413.48025 -298.27474) (xy 413.479755 -298.299347)
			(xy 413.47186 -298.347924) (xy 413.456276 -298.394605) (xy 413.433405 -298.438182) (xy 413.40384 -298.477526)
			(xy 413.368347 -298.511618) (xy 413.327844 -298.539574) (xy 413.283382 -298.560672) (xy 413.236111 -298.574364)
			(xy 413.187256 -298.580296) (xy 413.138081 -298.578315) (xy 413.089862 -298.568471) (xy 413.043846 -298.551019)
			(xy 413.001225 -298.526412) (xy 412.963104 -298.495287) (xy 412.930469 -298.45845) (xy 412.904166 -298.416854)
			(xy 412.884875 -298.371578) (xy 412.873098 -298.323794) (xy 412.869138 -298.27474) (xy 411.58033 -298.27474)
			(xy 411.579835 -298.299347) (xy 411.57194 -298.347924) (xy 411.556356 -298.394605) (xy 411.533485 -298.438182)
			(xy 411.50392 -298.477526) (xy 411.468427 -298.511618) (xy 411.427924 -298.539574) (xy 411.383462 -298.560672)
			(xy 411.336191 -298.574364) (xy 411.287336 -298.580296) (xy 411.238161 -298.578315) (xy 411.189942 -298.568471)
			(xy 411.143926 -298.551019) (xy 411.101305 -298.526412) (xy 411.063184 -298.495287) (xy 411.030549 -298.45845)
			(xy 411.004246 -298.416854) (xy 410.984955 -298.371578) (xy 410.973178 -298.323794) (xy 410.969218 -298.27474)
			(xy 409.680156 -298.27474) (xy 409.679661 -298.299347) (xy 409.671766 -298.347924) (xy 409.656182 -298.394605)
			(xy 409.633311 -298.438182) (xy 409.603746 -298.477526) (xy 409.568253 -298.511618) (xy 409.52775 -298.539574)
			(xy 409.483288 -298.560672) (xy 409.436017 -298.574364) (xy 409.387162 -298.580296) (xy 409.337987 -298.578315)
			(xy 409.289768 -298.568471) (xy 409.243752 -298.551019) (xy 409.201131 -298.526412) (xy 409.16301 -298.495287)
			(xy 409.130375 -298.45845) (xy 409.104072 -298.416854) (xy 409.084781 -298.371578) (xy 409.073004 -298.323794)
			(xy 409.069044 -298.27474) (xy 406.830276 -298.27474) (xy 406.829781 -298.299347) (xy 406.821886 -298.347924)
			(xy 406.806302 -298.394605) (xy 406.783431 -298.438182) (xy 406.753866 -298.477526) (xy 406.718373 -298.511618)
			(xy 406.67787 -298.539574) (xy 406.633408 -298.560672) (xy 406.586137 -298.574364) (xy 406.537282 -298.580296)
			(xy 406.488107 -298.578315) (xy 406.439888 -298.568471) (xy 406.393872 -298.551019) (xy 406.351251 -298.526412)
			(xy 406.31313 -298.495287) (xy 406.280495 -298.45845) (xy 406.254192 -298.416854) (xy 406.234901 -298.371578)
			(xy 406.223124 -298.323794) (xy 406.219164 -298.27474) (xy 404.930102 -298.27474) (xy 404.929607 -298.299347)
			(xy 404.921712 -298.347924) (xy 404.906128 -298.394605) (xy 404.883257 -298.438182) (xy 404.853692 -298.477526)
			(xy 404.818199 -298.511618) (xy 404.777696 -298.539574) (xy 404.733234 -298.560672) (xy 404.685963 -298.574364)
			(xy 404.637108 -298.580296) (xy 404.587933 -298.578315) (xy 404.539714 -298.568471) (xy 404.493698 -298.551019)
			(xy 404.451077 -298.526412) (xy 404.412956 -298.495287) (xy 404.380321 -298.45845) (xy 404.354018 -298.416854)
			(xy 404.334727 -298.371578) (xy 404.32295 -298.323794) (xy 404.31899 -298.27474) (xy 403.030182 -298.27474)
			(xy 403.029687 -298.299347) (xy 403.021792 -298.347924) (xy 403.006208 -298.394605) (xy 402.983337 -298.438182)
			(xy 402.953772 -298.477526) (xy 402.918279 -298.511618) (xy 402.877776 -298.539574) (xy 402.833314 -298.560672)
			(xy 402.786043 -298.574364) (xy 402.737188 -298.580296) (xy 402.688013 -298.578315) (xy 402.639794 -298.568471)
			(xy 402.593778 -298.551019) (xy 402.551157 -298.526412) (xy 402.513036 -298.495287) (xy 402.480401 -298.45845)
			(xy 402.454098 -298.416854) (xy 402.434807 -298.371578) (xy 402.42303 -298.323794) (xy 402.41907 -298.27474)
			(xy 401.130262 -298.27474) (xy 401.129767 -298.299347) (xy 401.121872 -298.347924) (xy 401.106288 -298.394605)
			(xy 401.083417 -298.438182) (xy 401.053852 -298.477526) (xy 401.018359 -298.511618) (xy 400.977856 -298.539574)
			(xy 400.933394 -298.560672) (xy 400.886123 -298.574364) (xy 400.837268 -298.580296) (xy 400.788093 -298.578315)
			(xy 400.739874 -298.568471) (xy 400.693858 -298.551019) (xy 400.651237 -298.526412) (xy 400.613116 -298.495287)
			(xy 400.580481 -298.45845) (xy 400.554178 -298.416854) (xy 400.534887 -298.371578) (xy 400.52311 -298.323794)
			(xy 400.51915 -298.27474) (xy 399.230342 -298.27474) (xy 399.229847 -298.299347) (xy 399.221952 -298.347924)
			(xy 399.206368 -298.394605) (xy 399.183497 -298.438182) (xy 399.153932 -298.477526) (xy 399.118439 -298.511618)
			(xy 399.077936 -298.539574) (xy 399.033474 -298.560672) (xy 398.986203 -298.574364) (xy 398.937348 -298.580296)
			(xy 398.888173 -298.578315) (xy 398.839954 -298.568471) (xy 398.793938 -298.551019) (xy 398.751317 -298.526412)
			(xy 398.713196 -298.495287) (xy 398.680561 -298.45845) (xy 398.654258 -298.416854) (xy 398.634967 -298.371578)
			(xy 398.62319 -298.323794) (xy 398.61923 -298.27474) (xy 397.330168 -298.27474) (xy 397.329673 -298.299347)
			(xy 397.321778 -298.347924) (xy 397.306194 -298.394605) (xy 397.283323 -298.438182) (xy 397.253758 -298.477526)
			(xy 397.218265 -298.511618) (xy 397.177762 -298.539574) (xy 397.1333 -298.560672) (xy 397.086029 -298.574364)
			(xy 397.037174 -298.580296) (xy 396.987999 -298.578315) (xy 396.93978 -298.568471) (xy 396.893764 -298.551019)
			(xy 396.851143 -298.526412) (xy 396.813022 -298.495287) (xy 396.780387 -298.45845) (xy 396.754084 -298.416854)
			(xy 396.734793 -298.371578) (xy 396.723016 -298.323794) (xy 396.719056 -298.27474) (xy 396.380208 -298.27474)
			(xy 396.379713 -298.299347) (xy 396.371818 -298.347924) (xy 396.356234 -298.394605) (xy 396.333363 -298.438182)
			(xy 396.303798 -298.477526) (xy 396.268305 -298.511618) (xy 396.227802 -298.539574) (xy 396.18334 -298.560672)
			(xy 396.136069 -298.574364) (xy 396.087214 -298.580296) (xy 396.038039 -298.578315) (xy 395.98982 -298.568471)
			(xy 395.943804 -298.551019) (xy 395.901183 -298.526412) (xy 395.863062 -298.495287) (xy 395.830427 -298.45845)
			(xy 395.804124 -298.416854) (xy 395.784833 -298.371578) (xy 395.773056 -298.323794) (xy 395.769096 -298.27474)
			(xy 394.480288 -298.27474) (xy 394.479793 -298.299347) (xy 394.471898 -298.347924) (xy 394.456314 -298.394605)
			(xy 394.433443 -298.438182) (xy 394.403878 -298.477526) (xy 394.368385 -298.511618) (xy 394.327882 -298.539574)
			(xy 394.28342 -298.560672) (xy 394.236149 -298.574364) (xy 394.187294 -298.580296) (xy 394.138119 -298.578315)
			(xy 394.0899 -298.568471) (xy 394.043884 -298.551019) (xy 394.001263 -298.526412) (xy 393.963142 -298.495287)
			(xy 393.930507 -298.45845) (xy 393.904204 -298.416854) (xy 393.884913 -298.371578) (xy 393.873136 -298.323794)
			(xy 393.869176 -298.27474) (xy 393.530328 -298.27474) (xy 393.529833 -298.299347) (xy 393.521938 -298.347924)
			(xy 393.506354 -298.394605) (xy 393.483483 -298.438182) (xy 393.453918 -298.477526) (xy 393.418425 -298.511618)
			(xy 393.377922 -298.539574) (xy 393.33346 -298.560672) (xy 393.286189 -298.574364) (xy 393.237334 -298.580296)
			(xy 393.188159 -298.578315) (xy 393.13994 -298.568471) (xy 393.093924 -298.551019) (xy 393.051303 -298.526412)
			(xy 393.013182 -298.495287) (xy 392.980547 -298.45845) (xy 392.954244 -298.416854) (xy 392.934953 -298.371578)
			(xy 392.923176 -298.323794) (xy 392.919216 -298.27474) (xy 392.580114 -298.27474) (xy 392.579619 -298.299347)
			(xy 392.571724 -298.347924) (xy 392.55614 -298.394605) (xy 392.533269 -298.438182) (xy 392.503704 -298.477526)
			(xy 392.468211 -298.511618) (xy 392.427708 -298.539574) (xy 392.383246 -298.560672) (xy 392.335975 -298.574364)
			(xy 392.28712 -298.580296) (xy 392.237945 -298.578315) (xy 392.189726 -298.568471) (xy 392.14371 -298.551019)
			(xy 392.101089 -298.526412) (xy 392.062968 -298.495287) (xy 392.030333 -298.45845) (xy 392.00403 -298.416854)
			(xy 391.984739 -298.371578) (xy 391.972962 -298.323794) (xy 391.969002 -298.27474) (xy 391.630154 -298.27474)
			(xy 391.629659 -298.299347) (xy 391.621764 -298.347924) (xy 391.60618 -298.394605) (xy 391.583309 -298.438182)
			(xy 391.553744 -298.477526) (xy 391.518251 -298.511618) (xy 391.477748 -298.539574) (xy 391.433286 -298.560672)
			(xy 391.386015 -298.574364) (xy 391.33716 -298.580296) (xy 391.287985 -298.578315) (xy 391.239766 -298.568471)
			(xy 391.19375 -298.551019) (xy 391.151129 -298.526412) (xy 391.113008 -298.495287) (xy 391.080373 -298.45845)
			(xy 391.05407 -298.416854) (xy 391.034779 -298.371578) (xy 391.023002 -298.323794) (xy 391.019042 -298.27474)
			(xy 390.680212 -298.27474) (xy 390.680659 -298.282979) (xy 390.675291 -298.332338) (xy 390.662009 -298.380179)
			(xy 390.641161 -298.42524) (xy 390.613298 -298.466334) (xy 390.579153 -298.502379) (xy 390.539626 -298.532425)
			(xy 390.495759 -298.555681) (xy 390.448707 -298.571533) (xy 390.399711 -298.579563) (xy 390.374886 -298.580048)
			(xy 390.360703 -298.579873) (xy 390.332463 -298.5772) (xy 390.318498 -298.574714) (xy 390.306052 -298.572428)
			(xy 390.28243 -298.579794) (xy 390.20496 -298.657264) (xy 390.197594 -298.680886) (xy 390.19988 -298.693332)
			(xy 390.202357 -298.707298) (xy 390.205028 -298.735537) (xy 390.205214 -298.74972) (xy 390.204756 -298.773711)
			(xy 390.197247 -298.821103) (xy 390.182417 -298.866737) (xy 390.160632 -298.909489) (xy 390.132427 -298.948308)
			(xy 390.098497 -298.982236) (xy 390.059677 -299.010439) (xy 390.016924 -299.032223) (xy 389.97129 -299.04705)
			(xy 389.923897 -299.054557) (xy 389.899906 -299.055028) (xy 389.885723 -299.05485) (xy 389.857483 -299.052179)
			(xy 389.843518 -299.049694) (xy 389.831072 -299.047408) (xy 389.807196 -299.054774) (xy 389.72998 -299.13199)
			(xy 389.722614 -299.15612) (xy 389.7249 -299.168312) (xy 389.727384 -299.182341) (xy 389.730056 -299.210708)
			(xy 389.730234 -299.224954) (xy 389.729719 -299.248945) (xy 389.72222 -299.296336) (xy 389.7074 -299.341971)
			(xy 389.685622 -299.384725) (xy 389.657425 -299.423546) (xy 389.623501 -299.457478) (xy 389.584687 -299.485685)
			(xy 389.541937 -299.507472) (xy 389.496306 -299.522304) (xy 389.448916 -299.529814) (xy 389.424926 -299.530262)
			(xy 389.410743 -299.530082) (xy 389.382503 -299.527412) (xy 389.368538 -299.524928) (xy 389.356092 -299.522642)
			(xy 389.33247 -299.530008) (xy 389.255 -299.607478) (xy 389.247634 -299.6311) (xy 389.24992 -299.643546)
			(xy 389.252399 -299.657511) (xy 389.255069 -299.685751) (xy 389.255254 -299.6999) (xy 390.544103 -299.6999)
			(xy 390.548273 -299.649571) (xy 390.56067 -299.600615) (xy 390.580954 -299.554366) (xy 390.608574 -299.512087)
			(xy 390.642776 -299.47493) (xy 390.682627 -299.443909) (xy 390.72704 -299.419869) (xy 390.774803 -299.403467)
			(xy 390.824615 -299.39515) (xy 390.849866 -299.394626) (xy 390.864049 -299.394807) (xy 390.892289 -299.397476)
			(xy 390.906254 -299.39996) (xy 390.9187 -299.402246) (xy 390.942576 -299.39488) (xy 391.019792 -299.317664)
			(xy 391.027158 -299.293534) (xy 391.024872 -299.281342) (xy 391.022382 -299.267314) (xy 391.019714 -299.238946)
			(xy 391.019538 -299.2247) (xy 391.019978 -299.19988) (xy 391.028008 -299.150894) (xy 391.043858 -299.103852)
			(xy 391.067109 -299.059994) (xy 391.097149 -299.020475) (xy 391.133187 -298.986337) (xy 391.174273 -298.958478)
			(xy 391.219324 -298.937633) (xy 391.267154 -298.924351) (xy 391.316503 -298.918982) (xy 391.366071 -298.921666)
			(xy 391.414551 -298.932335) (xy 391.460667 -298.950706) (xy 391.503203 -298.976295) (xy 391.541039 -299.008429)
			(xy 391.573178 -299.04626) (xy 391.598774 -299.088792) (xy 391.617152 -299.134905) (xy 391.627827 -299.183384)
			(xy 391.630086 -299.224954) (xy 391.969002 -299.224954) (xy 391.972962 -299.1759) (xy 391.984739 -299.128116)
			(xy 392.00403 -299.08284) (xy 392.030333 -299.041244) (xy 392.062968 -299.004407) (xy 392.101089 -298.973282)
			(xy 392.14371 -298.948675) (xy 392.189726 -298.931223) (xy 392.237945 -298.921379) (xy 392.28712 -298.919398)
			(xy 392.335975 -298.92533) (xy 392.383246 -298.939022) (xy 392.427708 -298.96012) (xy 392.468211 -298.988076)
			(xy 392.503704 -299.022168) (xy 392.533269 -299.061512) (xy 392.55614 -299.105089) (xy 392.571724 -299.15177)
			(xy 392.579619 -299.200347) (xy 392.580114 -299.224954) (xy 392.919216 -299.224954) (xy 392.923176 -299.1759)
			(xy 392.934953 -299.128116) (xy 392.954244 -299.08284) (xy 392.980547 -299.041244) (xy 393.013182 -299.004407)
			(xy 393.051303 -298.973282) (xy 393.093924 -298.948675) (xy 393.13994 -298.931223) (xy 393.188159 -298.921379)
			(xy 393.237334 -298.919398) (xy 393.286189 -298.92533) (xy 393.33346 -298.939022) (xy 393.377922 -298.96012)
			(xy 393.418425 -298.988076) (xy 393.453918 -299.022168) (xy 393.483483 -299.061512) (xy 393.506354 -299.105089)
			(xy 393.521938 -299.15177) (xy 393.529833 -299.200347) (xy 393.530328 -299.224954) (xy 393.869176 -299.224954)
			(xy 393.873136 -299.1759) (xy 393.884913 -299.128116) (xy 393.904204 -299.08284) (xy 393.930507 -299.041244)
			(xy 393.963142 -299.004407) (xy 394.001263 -298.973282) (xy 394.043884 -298.948675) (xy 394.0899 -298.931223)
			(xy 394.138119 -298.921379) (xy 394.187294 -298.919398) (xy 394.236149 -298.92533) (xy 394.28342 -298.939022)
			(xy 394.327882 -298.96012) (xy 394.368385 -298.988076) (xy 394.403878 -299.022168) (xy 394.433443 -299.061512)
			(xy 394.456314 -299.105089) (xy 394.471898 -299.15177) (xy 394.479793 -299.200347) (xy 394.480288 -299.224954)
			(xy 394.819136 -299.224954) (xy 394.823096 -299.1759) (xy 394.834873 -299.128116) (xy 394.854164 -299.08284)
			(xy 394.880467 -299.041244) (xy 394.913102 -299.004407) (xy 394.951223 -298.973282) (xy 394.993844 -298.948675)
			(xy 395.03986 -298.931223) (xy 395.088079 -298.921379) (xy 395.137254 -298.919398) (xy 395.186109 -298.92533)
			(xy 395.23338 -298.939022) (xy 395.277842 -298.96012) (xy 395.318345 -298.988076) (xy 395.353838 -299.022168)
			(xy 395.383403 -299.061512) (xy 395.406274 -299.105089) (xy 395.421858 -299.15177) (xy 395.429753 -299.200347)
			(xy 395.430248 -299.224954) (xy 395.769096 -299.224954) (xy 395.773056 -299.1759) (xy 395.784833 -299.128116)
			(xy 395.804124 -299.08284) (xy 395.830427 -299.041244) (xy 395.863062 -299.004407) (xy 395.901183 -298.973282)
			(xy 395.943804 -298.948675) (xy 395.98982 -298.931223) (xy 396.038039 -298.921379) (xy 396.087214 -298.919398)
			(xy 396.136069 -298.92533) (xy 396.18334 -298.939022) (xy 396.227802 -298.96012) (xy 396.268305 -298.988076)
			(xy 396.303798 -299.022168) (xy 396.333363 -299.061512) (xy 396.356234 -299.105089) (xy 396.371818 -299.15177)
			(xy 396.379713 -299.200347) (xy 396.380208 -299.224954) (xy 397.669016 -299.224954) (xy 397.672976 -299.1759)
			(xy 397.684753 -299.128116) (xy 397.704044 -299.08284) (xy 397.730347 -299.041244) (xy 397.762982 -299.004407)
			(xy 397.801103 -298.973282) (xy 397.843724 -298.948675) (xy 397.88974 -298.931223) (xy 397.937959 -298.921379)
			(xy 397.987134 -298.919398) (xy 398.035989 -298.92533) (xy 398.08326 -298.939022) (xy 398.127722 -298.96012)
			(xy 398.168225 -298.988076) (xy 398.203718 -299.022168) (xy 398.233283 -299.061512) (xy 398.256154 -299.105089)
			(xy 398.271738 -299.15177) (xy 398.279633 -299.200347) (xy 398.280128 -299.224954) (xy 398.61923 -299.224954)
			(xy 398.62319 -299.1759) (xy 398.634967 -299.128116) (xy 398.654258 -299.08284) (xy 398.680561 -299.041244)
			(xy 398.713196 -299.004407) (xy 398.751317 -298.973282) (xy 398.793938 -298.948675) (xy 398.839954 -298.931223)
			(xy 398.888173 -298.921379) (xy 398.937348 -298.919398) (xy 398.986203 -298.92533) (xy 399.033474 -298.939022)
			(xy 399.077936 -298.96012) (xy 399.118439 -298.988076) (xy 399.153932 -299.022168) (xy 399.183497 -299.061512)
			(xy 399.206368 -299.105089) (xy 399.221952 -299.15177) (xy 399.229847 -299.200347) (xy 399.230342 -299.224954)
			(xy 399.56919 -299.224954) (xy 399.57315 -299.1759) (xy 399.584927 -299.128116) (xy 399.604218 -299.08284)
			(xy 399.630521 -299.041244) (xy 399.663156 -299.004407) (xy 399.701277 -298.973282) (xy 399.743898 -298.948675)
			(xy 399.789914 -298.931223) (xy 399.838133 -298.921379) (xy 399.887308 -298.919398) (xy 399.936163 -298.92533)
			(xy 399.983434 -298.939022) (xy 400.027896 -298.96012) (xy 400.068399 -298.988076) (xy 400.103892 -299.022168)
			(xy 400.133457 -299.061512) (xy 400.156328 -299.105089) (xy 400.171912 -299.15177) (xy 400.179807 -299.200347)
			(xy 400.180302 -299.224954) (xy 400.51915 -299.224954) (xy 400.52311 -299.1759) (xy 400.534887 -299.128116)
			(xy 400.554178 -299.08284) (xy 400.580481 -299.041244) (xy 400.613116 -299.004407) (xy 400.651237 -298.973282)
			(xy 400.693858 -298.948675) (xy 400.739874 -298.931223) (xy 400.788093 -298.921379) (xy 400.837268 -298.919398)
			(xy 400.886123 -298.92533) (xy 400.933394 -298.939022) (xy 400.977856 -298.96012) (xy 401.018359 -298.988076)
			(xy 401.053852 -299.022168) (xy 401.083417 -299.061512) (xy 401.106288 -299.105089) (xy 401.121872 -299.15177)
			(xy 401.129767 -299.200347) (xy 401.130262 -299.224954) (xy 401.46911 -299.224954) (xy 401.47307 -299.1759)
			(xy 401.484847 -299.128116) (xy 401.504138 -299.08284) (xy 401.530441 -299.041244) (xy 401.563076 -299.004407)
			(xy 401.601197 -298.973282) (xy 401.643818 -298.948675) (xy 401.689834 -298.931223) (xy 401.738053 -298.921379)
			(xy 401.787228 -298.919398) (xy 401.836083 -298.92533) (xy 401.883354 -298.939022) (xy 401.927816 -298.96012)
			(xy 401.968319 -298.988076) (xy 402.003812 -299.022168) (xy 402.033377 -299.061512) (xy 402.056248 -299.105089)
			(xy 402.071832 -299.15177) (xy 402.079727 -299.200347) (xy 402.080222 -299.224954) (xy 402.41907 -299.224954)
			(xy 402.42303 -299.1759) (xy 402.434807 -299.128116) (xy 402.454098 -299.08284) (xy 402.480401 -299.041244)
			(xy 402.513036 -299.004407) (xy 402.551157 -298.973282) (xy 402.593778 -298.948675) (xy 402.639794 -298.931223)
			(xy 402.688013 -298.921379) (xy 402.737188 -298.919398) (xy 402.786043 -298.92533) (xy 402.833314 -298.939022)
			(xy 402.877776 -298.96012) (xy 402.918279 -298.988076) (xy 402.953772 -299.022168) (xy 402.983337 -299.061512)
			(xy 403.006208 -299.105089) (xy 403.021792 -299.15177) (xy 403.029687 -299.200347) (xy 403.030182 -299.224954)
			(xy 403.36903 -299.224954) (xy 403.37299 -299.1759) (xy 403.384767 -299.128116) (xy 403.404058 -299.08284)
			(xy 403.430361 -299.041244) (xy 403.462996 -299.004407) (xy 403.501117 -298.973282) (xy 403.543738 -298.948675)
			(xy 403.589754 -298.931223) (xy 403.637973 -298.921379) (xy 403.687148 -298.919398) (xy 403.736003 -298.92533)
			(xy 403.783274 -298.939022) (xy 403.827736 -298.96012) (xy 403.868239 -298.988076) (xy 403.903732 -299.022168)
			(xy 403.933297 -299.061512) (xy 403.956168 -299.105089) (xy 403.971752 -299.15177) (xy 403.979647 -299.200347)
			(xy 403.980142 -299.224954) (xy 404.31899 -299.224954) (xy 404.32295 -299.1759) (xy 404.334727 -299.128116)
			(xy 404.354018 -299.08284) (xy 404.380321 -299.041244) (xy 404.412956 -299.004407) (xy 404.451077 -298.973282)
			(xy 404.493698 -298.948675) (xy 404.539714 -298.931223) (xy 404.587933 -298.921379) (xy 404.637108 -298.919398)
			(xy 404.685963 -298.92533) (xy 404.733234 -298.939022) (xy 404.777696 -298.96012) (xy 404.818199 -298.988076)
			(xy 404.853692 -299.022168) (xy 404.883257 -299.061512) (xy 404.906128 -299.105089) (xy 404.921712 -299.15177)
			(xy 404.929607 -299.200347) (xy 404.930102 -299.224954) (xy 405.269204 -299.224954) (xy 405.273164 -299.1759)
			(xy 405.284941 -299.128116) (xy 405.304232 -299.08284) (xy 405.330535 -299.041244) (xy 405.36317 -299.004407)
			(xy 405.401291 -298.973282) (xy 405.443912 -298.948675) (xy 405.489928 -298.931223) (xy 405.538147 -298.921379)
			(xy 405.587322 -298.919398) (xy 405.636177 -298.92533) (xy 405.683448 -298.939022) (xy 405.72791 -298.96012)
			(xy 405.768413 -298.988076) (xy 405.803906 -299.022168) (xy 405.833471 -299.061512) (xy 405.856342 -299.105089)
			(xy 405.871926 -299.15177) (xy 405.879821 -299.200347) (xy 405.880316 -299.224954) (xy 406.219164 -299.224954)
			(xy 406.223124 -299.1759) (xy 406.234901 -299.128116) (xy 406.254192 -299.08284) (xy 406.280495 -299.041244)
			(xy 406.31313 -299.004407) (xy 406.351251 -298.973282) (xy 406.393872 -298.948675) (xy 406.439888 -298.931223)
			(xy 406.488107 -298.921379) (xy 406.537282 -298.919398) (xy 406.586137 -298.92533) (xy 406.633408 -298.939022)
			(xy 406.67787 -298.96012) (xy 406.718373 -298.988076) (xy 406.753866 -299.022168) (xy 406.783431 -299.061512)
			(xy 406.806302 -299.105089) (xy 406.821886 -299.15177) (xy 406.829781 -299.200347) (xy 406.830276 -299.224954)
			(xy 408.119084 -299.224954) (xy 408.123044 -299.1759) (xy 408.134821 -299.128116) (xy 408.154112 -299.08284)
			(xy 408.180415 -299.041244) (xy 408.21305 -299.004407) (xy 408.251171 -298.973282) (xy 408.293792 -298.948675)
			(xy 408.339808 -298.931223) (xy 408.388027 -298.921379) (xy 408.437202 -298.919398) (xy 408.486057 -298.92533)
			(xy 408.533328 -298.939022) (xy 408.57779 -298.96012) (xy 408.618293 -298.988076) (xy 408.653786 -299.022168)
			(xy 408.683351 -299.061512) (xy 408.706222 -299.105089) (xy 408.721806 -299.15177) (xy 408.729701 -299.200347)
			(xy 408.730196 -299.224954) (xy 409.069044 -299.224954) (xy 409.073004 -299.1759) (xy 409.084781 -299.128116)
			(xy 409.104072 -299.08284) (xy 409.130375 -299.041244) (xy 409.16301 -299.004407) (xy 409.201131 -298.973282)
			(xy 409.243752 -298.948675) (xy 409.289768 -298.931223) (xy 409.337987 -298.921379) (xy 409.387162 -298.919398)
			(xy 409.436017 -298.92533) (xy 409.483288 -298.939022) (xy 409.52775 -298.96012) (xy 409.568253 -298.988076)
			(xy 409.603746 -299.022168) (xy 409.633311 -299.061512) (xy 409.656182 -299.105089) (xy 409.671766 -299.15177)
			(xy 409.679661 -299.200347) (xy 409.680156 -299.224954) (xy 410.019004 -299.224954) (xy 410.022964 -299.1759)
			(xy 410.034741 -299.128116) (xy 410.054032 -299.08284) (xy 410.080335 -299.041244) (xy 410.11297 -299.004407)
			(xy 410.151091 -298.973282) (xy 410.193712 -298.948675) (xy 410.239728 -298.931223) (xy 410.287947 -298.921379)
			(xy 410.337122 -298.919398) (xy 410.385977 -298.92533) (xy 410.433248 -298.939022) (xy 410.47771 -298.96012)
			(xy 410.518213 -298.988076) (xy 410.553706 -299.022168) (xy 410.583271 -299.061512) (xy 410.606142 -299.105089)
			(xy 410.621726 -299.15177) (xy 410.629621 -299.200347) (xy 410.630116 -299.224954) (xy 410.969218 -299.224954)
			(xy 410.973178 -299.1759) (xy 410.984955 -299.128116) (xy 411.004246 -299.08284) (xy 411.030549 -299.041244)
			(xy 411.063184 -299.004407) (xy 411.101305 -298.973282) (xy 411.143926 -298.948675) (xy 411.189942 -298.931223)
			(xy 411.238161 -298.921379) (xy 411.287336 -298.919398) (xy 411.336191 -298.92533) (xy 411.383462 -298.939022)
			(xy 411.427924 -298.96012) (xy 411.468427 -298.988076) (xy 411.50392 -299.022168) (xy 411.533485 -299.061512)
			(xy 411.556356 -299.105089) (xy 411.57194 -299.15177) (xy 411.579835 -299.200347) (xy 411.58033 -299.224954)
			(xy 411.919178 -299.224954) (xy 411.923138 -299.1759) (xy 411.934915 -299.128116) (xy 411.954206 -299.08284)
			(xy 411.980509 -299.041244) (xy 412.013144 -299.004407) (xy 412.051265 -298.973282) (xy 412.093886 -298.948675)
			(xy 412.139902 -298.931223) (xy 412.188121 -298.921379) (xy 412.237296 -298.919398) (xy 412.286151 -298.92533)
			(xy 412.333422 -298.939022) (xy 412.377884 -298.96012) (xy 412.418387 -298.988076) (xy 412.45388 -299.022168)
			(xy 412.483445 -299.061512) (xy 412.506316 -299.105089) (xy 412.5219 -299.15177) (xy 412.529795 -299.200347)
			(xy 412.53029 -299.224954) (xy 412.869138 -299.224954) (xy 412.873098 -299.1759) (xy 412.884875 -299.128116)
			(xy 412.904166 -299.08284) (xy 412.930469 -299.041244) (xy 412.963104 -299.004407) (xy 413.001225 -298.973282)
			(xy 413.043846 -298.948675) (xy 413.089862 -298.931223) (xy 413.138081 -298.921379) (xy 413.187256 -298.919398)
			(xy 413.236111 -298.92533) (xy 413.283382 -298.939022) (xy 413.327844 -298.96012) (xy 413.368347 -298.988076)
			(xy 413.40384 -299.022168) (xy 413.433405 -299.061512) (xy 413.456276 -299.105089) (xy 413.47186 -299.15177)
			(xy 413.479755 -299.200347) (xy 413.48025 -299.224954) (xy 413.819098 -299.224954) (xy 413.823058 -299.1759)
			(xy 413.834835 -299.128116) (xy 413.854126 -299.08284) (xy 413.880429 -299.041244) (xy 413.913064 -299.004407)
			(xy 413.951185 -298.973282) (xy 413.993806 -298.948675) (xy 414.039822 -298.931223) (xy 414.088041 -298.921379)
			(xy 414.137216 -298.919398) (xy 414.186071 -298.92533) (xy 414.233342 -298.939022) (xy 414.277804 -298.96012)
			(xy 414.318307 -298.988076) (xy 414.3538 -299.022168) (xy 414.383365 -299.061512) (xy 414.406236 -299.105089)
			(xy 414.42182 -299.15177) (xy 414.429715 -299.200347) (xy 414.43021 -299.224954) (xy 414.769058 -299.224954)
			(xy 414.773018 -299.1759) (xy 414.784795 -299.128116) (xy 414.804086 -299.08284) (xy 414.830389 -299.041244)
			(xy 414.863024 -299.004407) (xy 414.901145 -298.973282) (xy 414.943766 -298.948675) (xy 414.989782 -298.931223)
			(xy 415.038001 -298.921379) (xy 415.087176 -298.919398) (xy 415.136031 -298.92533) (xy 415.183302 -298.939022)
			(xy 415.227764 -298.96012) (xy 415.268267 -298.988076) (xy 415.30376 -299.022168) (xy 415.333325 -299.061512)
			(xy 415.356196 -299.105089) (xy 415.37178 -299.15177) (xy 415.379675 -299.200347) (xy 415.38017 -299.224954)
			(xy 415.719018 -299.224954) (xy 415.722978 -299.1759) (xy 415.734755 -299.128116) (xy 415.754046 -299.08284)
			(xy 415.780349 -299.041244) (xy 415.812984 -299.004407) (xy 415.851105 -298.973282) (xy 415.893726 -298.948675)
			(xy 415.939742 -298.931223) (xy 415.987961 -298.921379) (xy 416.037136 -298.919398) (xy 416.085991 -298.92533)
			(xy 416.133262 -298.939022) (xy 416.177724 -298.96012) (xy 416.218227 -298.988076) (xy 416.25372 -299.022168)
			(xy 416.283285 -299.061512) (xy 416.306156 -299.105089) (xy 416.32174 -299.15177) (xy 416.329635 -299.200347)
			(xy 416.33013 -299.224954) (xy 416.668978 -299.224954) (xy 416.672938 -299.1759) (xy 416.684715 -299.128116)
			(xy 416.704006 -299.08284) (xy 416.730309 -299.041244) (xy 416.762944 -299.004407) (xy 416.801065 -298.973282)
			(xy 416.843686 -298.948675) (xy 416.889702 -298.931223) (xy 416.937921 -298.921379) (xy 416.987096 -298.919398)
			(xy 417.035951 -298.92533) (xy 417.083222 -298.939022) (xy 417.127684 -298.96012) (xy 417.168187 -298.988076)
			(xy 417.20368 -299.022168) (xy 417.233245 -299.061512) (xy 417.256116 -299.105089) (xy 417.2717 -299.15177)
			(xy 417.279595 -299.200347) (xy 417.28009 -299.224954) (xy 417.279595 -299.249561) (xy 417.2717 -299.298138)
			(xy 417.256116 -299.344819) (xy 417.233245 -299.388396) (xy 417.20368 -299.42774) (xy 417.168187 -299.461832)
			(xy 417.127684 -299.489788) (xy 417.083222 -299.510886) (xy 417.035951 -299.524578) (xy 416.987096 -299.53051)
			(xy 416.937921 -299.528529) (xy 416.889702 -299.518685) (xy 416.843686 -299.501233) (xy 416.801065 -299.476626)
			(xy 416.762944 -299.445501) (xy 416.730309 -299.408664) (xy 416.704006 -299.367068) (xy 416.684715 -299.321792)
			(xy 416.672938 -299.274008) (xy 416.668978 -299.224954) (xy 416.33013 -299.224954) (xy 416.329635 -299.249561)
			(xy 416.32174 -299.298138) (xy 416.306156 -299.344819) (xy 416.283285 -299.388396) (xy 416.25372 -299.42774)
			(xy 416.218227 -299.461832) (xy 416.177724 -299.489788) (xy 416.133262 -299.510886) (xy 416.085991 -299.524578)
			(xy 416.037136 -299.53051) (xy 415.987961 -299.528529) (xy 415.939742 -299.518685) (xy 415.893726 -299.501233)
			(xy 415.851105 -299.476626) (xy 415.812984 -299.445501) (xy 415.780349 -299.408664) (xy 415.754046 -299.367068)
			(xy 415.734755 -299.321792) (xy 415.722978 -299.274008) (xy 415.719018 -299.224954) (xy 415.38017 -299.224954)
			(xy 415.379675 -299.249561) (xy 415.37178 -299.298138) (xy 415.356196 -299.344819) (xy 415.333325 -299.388396)
			(xy 415.30376 -299.42774) (xy 415.268267 -299.461832) (xy 415.227764 -299.489788) (xy 415.183302 -299.510886)
			(xy 415.136031 -299.524578) (xy 415.087176 -299.53051) (xy 415.038001 -299.528529) (xy 414.989782 -299.518685)
			(xy 414.943766 -299.501233) (xy 414.901145 -299.476626) (xy 414.863024 -299.445501) (xy 414.830389 -299.408664)
			(xy 414.804086 -299.367068) (xy 414.784795 -299.321792) (xy 414.773018 -299.274008) (xy 414.769058 -299.224954)
			(xy 414.43021 -299.224954) (xy 414.429715 -299.249561) (xy 414.42182 -299.298138) (xy 414.406236 -299.344819)
			(xy 414.383365 -299.388396) (xy 414.3538 -299.42774) (xy 414.318307 -299.461832) (xy 414.277804 -299.489788)
			(xy 414.233342 -299.510886) (xy 414.186071 -299.524578) (xy 414.137216 -299.53051) (xy 414.088041 -299.528529)
			(xy 414.039822 -299.518685) (xy 413.993806 -299.501233) (xy 413.951185 -299.476626) (xy 413.913064 -299.445501)
			(xy 413.880429 -299.408664) (xy 413.854126 -299.367068) (xy 413.834835 -299.321792) (xy 413.823058 -299.274008)
			(xy 413.819098 -299.224954) (xy 413.48025 -299.224954) (xy 413.479755 -299.249561) (xy 413.47186 -299.298138)
			(xy 413.456276 -299.344819) (xy 413.433405 -299.388396) (xy 413.40384 -299.42774) (xy 413.368347 -299.461832)
			(xy 413.327844 -299.489788) (xy 413.283382 -299.510886) (xy 413.236111 -299.524578) (xy 413.187256 -299.53051)
			(xy 413.138081 -299.528529) (xy 413.089862 -299.518685) (xy 413.043846 -299.501233) (xy 413.001225 -299.476626)
			(xy 412.963104 -299.445501) (xy 412.930469 -299.408664) (xy 412.904166 -299.367068) (xy 412.884875 -299.321792)
			(xy 412.873098 -299.274008) (xy 412.869138 -299.224954) (xy 412.53029 -299.224954) (xy 412.529795 -299.249561)
			(xy 412.5219 -299.298138) (xy 412.506316 -299.344819) (xy 412.483445 -299.388396) (xy 412.45388 -299.42774)
			(xy 412.418387 -299.461832) (xy 412.377884 -299.489788) (xy 412.333422 -299.510886) (xy 412.286151 -299.524578)
			(xy 412.237296 -299.53051) (xy 412.188121 -299.528529) (xy 412.139902 -299.518685) (xy 412.093886 -299.501233)
			(xy 412.051265 -299.476626) (xy 412.013144 -299.445501) (xy 411.980509 -299.408664) (xy 411.954206 -299.367068)
			(xy 411.934915 -299.321792) (xy 411.923138 -299.274008) (xy 411.919178 -299.224954) (xy 411.58033 -299.224954)
			(xy 411.579835 -299.249561) (xy 411.57194 -299.298138) (xy 411.556356 -299.344819) (xy 411.533485 -299.388396)
			(xy 411.50392 -299.42774) (xy 411.468427 -299.461832) (xy 411.427924 -299.489788) (xy 411.383462 -299.510886)
			(xy 411.336191 -299.524578) (xy 411.287336 -299.53051) (xy 411.238161 -299.528529) (xy 411.189942 -299.518685)
			(xy 411.143926 -299.501233) (xy 411.101305 -299.476626) (xy 411.063184 -299.445501) (xy 411.030549 -299.408664)
			(xy 411.004246 -299.367068) (xy 410.984955 -299.321792) (xy 410.973178 -299.274008) (xy 410.969218 -299.224954)
			(xy 410.630116 -299.224954) (xy 410.629621 -299.249561) (xy 410.621726 -299.298138) (xy 410.606142 -299.344819)
			(xy 410.583271 -299.388396) (xy 410.553706 -299.42774) (xy 410.518213 -299.461832) (xy 410.47771 -299.489788)
			(xy 410.433248 -299.510886) (xy 410.385977 -299.524578) (xy 410.337122 -299.53051) (xy 410.287947 -299.528529)
			(xy 410.239728 -299.518685) (xy 410.193712 -299.501233) (xy 410.151091 -299.476626) (xy 410.11297 -299.445501)
			(xy 410.080335 -299.408664) (xy 410.054032 -299.367068) (xy 410.034741 -299.321792) (xy 410.022964 -299.274008)
			(xy 410.019004 -299.224954) (xy 409.680156 -299.224954) (xy 409.679661 -299.249561) (xy 409.671766 -299.298138)
			(xy 409.656182 -299.344819) (xy 409.633311 -299.388396) (xy 409.603746 -299.42774) (xy 409.568253 -299.461832)
			(xy 409.52775 -299.489788) (xy 409.483288 -299.510886) (xy 409.436017 -299.524578) (xy 409.387162 -299.53051)
			(xy 409.337987 -299.528529) (xy 409.289768 -299.518685) (xy 409.243752 -299.501233) (xy 409.201131 -299.476626)
			(xy 409.16301 -299.445501) (xy 409.130375 -299.408664) (xy 409.104072 -299.367068) (xy 409.084781 -299.321792)
			(xy 409.073004 -299.274008) (xy 409.069044 -299.224954) (xy 408.730196 -299.224954) (xy 408.729701 -299.249561)
			(xy 408.721806 -299.298138) (xy 408.706222 -299.344819) (xy 408.683351 -299.388396) (xy 408.653786 -299.42774)
			(xy 408.618293 -299.461832) (xy 408.57779 -299.489788) (xy 408.533328 -299.510886) (xy 408.486057 -299.524578)
			(xy 408.437202 -299.53051) (xy 408.388027 -299.528529) (xy 408.339808 -299.518685) (xy 408.293792 -299.501233)
			(xy 408.251171 -299.476626) (xy 408.21305 -299.445501) (xy 408.180415 -299.408664) (xy 408.154112 -299.367068)
			(xy 408.134821 -299.321792) (xy 408.123044 -299.274008) (xy 408.119084 -299.224954) (xy 406.830276 -299.224954)
			(xy 406.829781 -299.249561) (xy 406.821886 -299.298138) (xy 406.806302 -299.344819) (xy 406.783431 -299.388396)
			(xy 406.753866 -299.42774) (xy 406.718373 -299.461832) (xy 406.67787 -299.489788) (xy 406.633408 -299.510886)
			(xy 406.586137 -299.524578) (xy 406.537282 -299.53051) (xy 406.488107 -299.528529) (xy 406.439888 -299.518685)
			(xy 406.393872 -299.501233) (xy 406.351251 -299.476626) (xy 406.31313 -299.445501) (xy 406.280495 -299.408664)
			(xy 406.254192 -299.367068) (xy 406.234901 -299.321792) (xy 406.223124 -299.274008) (xy 406.219164 -299.224954)
			(xy 405.880316 -299.224954) (xy 405.879821 -299.249561) (xy 405.871926 -299.298138) (xy 405.856342 -299.344819)
			(xy 405.833471 -299.388396) (xy 405.803906 -299.42774) (xy 405.768413 -299.461832) (xy 405.72791 -299.489788)
			(xy 405.683448 -299.510886) (xy 405.636177 -299.524578) (xy 405.587322 -299.53051) (xy 405.538147 -299.528529)
			(xy 405.489928 -299.518685) (xy 405.443912 -299.501233) (xy 405.401291 -299.476626) (xy 405.36317 -299.445501)
			(xy 405.330535 -299.408664) (xy 405.304232 -299.367068) (xy 405.284941 -299.321792) (xy 405.273164 -299.274008)
			(xy 405.269204 -299.224954) (xy 404.930102 -299.224954) (xy 404.929607 -299.249561) (xy 404.921712 -299.298138)
			(xy 404.906128 -299.344819) (xy 404.883257 -299.388396) (xy 404.853692 -299.42774) (xy 404.818199 -299.461832)
			(xy 404.777696 -299.489788) (xy 404.733234 -299.510886) (xy 404.685963 -299.524578) (xy 404.637108 -299.53051)
			(xy 404.587933 -299.528529) (xy 404.539714 -299.518685) (xy 404.493698 -299.501233) (xy 404.451077 -299.476626)
			(xy 404.412956 -299.445501) (xy 404.380321 -299.408664) (xy 404.354018 -299.367068) (xy 404.334727 -299.321792)
			(xy 404.32295 -299.274008) (xy 404.31899 -299.224954) (xy 403.980142 -299.224954) (xy 403.979647 -299.249561)
			(xy 403.971752 -299.298138) (xy 403.956168 -299.344819) (xy 403.933297 -299.388396) (xy 403.903732 -299.42774)
			(xy 403.868239 -299.461832) (xy 403.827736 -299.489788) (xy 403.783274 -299.510886) (xy 403.736003 -299.524578)
			(xy 403.687148 -299.53051) (xy 403.637973 -299.528529) (xy 403.589754 -299.518685) (xy 403.543738 -299.501233)
			(xy 403.501117 -299.476626) (xy 403.462996 -299.445501) (xy 403.430361 -299.408664) (xy 403.404058 -299.367068)
			(xy 403.384767 -299.321792) (xy 403.37299 -299.274008) (xy 403.36903 -299.224954) (xy 403.030182 -299.224954)
			(xy 403.029687 -299.249561) (xy 403.021792 -299.298138) (xy 403.006208 -299.344819) (xy 402.983337 -299.388396)
			(xy 402.953772 -299.42774) (xy 402.918279 -299.461832) (xy 402.877776 -299.489788) (xy 402.833314 -299.510886)
			(xy 402.786043 -299.524578) (xy 402.737188 -299.53051) (xy 402.688013 -299.528529) (xy 402.639794 -299.518685)
			(xy 402.593778 -299.501233) (xy 402.551157 -299.476626) (xy 402.513036 -299.445501) (xy 402.480401 -299.408664)
			(xy 402.454098 -299.367068) (xy 402.434807 -299.321792) (xy 402.42303 -299.274008) (xy 402.41907 -299.224954)
			(xy 402.080222 -299.224954) (xy 402.079727 -299.249561) (xy 402.071832 -299.298138) (xy 402.056248 -299.344819)
			(xy 402.033377 -299.388396) (xy 402.003812 -299.42774) (xy 401.968319 -299.461832) (xy 401.927816 -299.489788)
			(xy 401.883354 -299.510886) (xy 401.836083 -299.524578) (xy 401.787228 -299.53051) (xy 401.738053 -299.528529)
			(xy 401.689834 -299.518685) (xy 401.643818 -299.501233) (xy 401.601197 -299.476626) (xy 401.563076 -299.445501)
			(xy 401.530441 -299.408664) (xy 401.504138 -299.367068) (xy 401.484847 -299.321792) (xy 401.47307 -299.274008)
			(xy 401.46911 -299.224954) (xy 401.130262 -299.224954) (xy 401.129767 -299.249561) (xy 401.121872 -299.298138)
			(xy 401.106288 -299.344819) (xy 401.083417 -299.388396) (xy 401.053852 -299.42774) (xy 401.018359 -299.461832)
			(xy 400.977856 -299.489788) (xy 400.933394 -299.510886) (xy 400.886123 -299.524578) (xy 400.837268 -299.53051)
			(xy 400.788093 -299.528529) (xy 400.739874 -299.518685) (xy 400.693858 -299.501233) (xy 400.651237 -299.476626)
			(xy 400.613116 -299.445501) (xy 400.580481 -299.408664) (xy 400.554178 -299.367068) (xy 400.534887 -299.321792)
			(xy 400.52311 -299.274008) (xy 400.51915 -299.224954) (xy 400.180302 -299.224954) (xy 400.179807 -299.249561)
			(xy 400.171912 -299.298138) (xy 400.156328 -299.344819) (xy 400.133457 -299.388396) (xy 400.103892 -299.42774)
			(xy 400.068399 -299.461832) (xy 400.027896 -299.489788) (xy 399.983434 -299.510886) (xy 399.936163 -299.524578)
			(xy 399.887308 -299.53051) (xy 399.838133 -299.528529) (xy 399.789914 -299.518685) (xy 399.743898 -299.501233)
			(xy 399.701277 -299.476626) (xy 399.663156 -299.445501) (xy 399.630521 -299.408664) (xy 399.604218 -299.367068)
			(xy 399.584927 -299.321792) (xy 399.57315 -299.274008) (xy 399.56919 -299.224954) (xy 399.230342 -299.224954)
			(xy 399.229847 -299.249561) (xy 399.221952 -299.298138) (xy 399.206368 -299.344819) (xy 399.183497 -299.388396)
			(xy 399.153932 -299.42774) (xy 399.118439 -299.461832) (xy 399.077936 -299.489788) (xy 399.033474 -299.510886)
			(xy 398.986203 -299.524578) (xy 398.937348 -299.53051) (xy 398.888173 -299.528529) (xy 398.839954 -299.518685)
			(xy 398.793938 -299.501233) (xy 398.751317 -299.476626) (xy 398.713196 -299.445501) (xy 398.680561 -299.408664)
			(xy 398.654258 -299.367068) (xy 398.634967 -299.321792) (xy 398.62319 -299.274008) (xy 398.61923 -299.224954)
			(xy 398.280128 -299.224954) (xy 398.279633 -299.249561) (xy 398.271738 -299.298138) (xy 398.256154 -299.344819)
			(xy 398.233283 -299.388396) (xy 398.203718 -299.42774) (xy 398.168225 -299.461832) (xy 398.127722 -299.489788)
			(xy 398.08326 -299.510886) (xy 398.035989 -299.524578) (xy 397.987134 -299.53051) (xy 397.937959 -299.528529)
			(xy 397.88974 -299.518685) (xy 397.843724 -299.501233) (xy 397.801103 -299.476626) (xy 397.762982 -299.445501)
			(xy 397.730347 -299.408664) (xy 397.704044 -299.367068) (xy 397.684753 -299.321792) (xy 397.672976 -299.274008)
			(xy 397.669016 -299.224954) (xy 396.380208 -299.224954) (xy 396.379713 -299.249561) (xy 396.371818 -299.298138)
			(xy 396.356234 -299.344819) (xy 396.333363 -299.388396) (xy 396.303798 -299.42774) (xy 396.268305 -299.461832)
			(xy 396.227802 -299.489788) (xy 396.18334 -299.510886) (xy 396.136069 -299.524578) (xy 396.087214 -299.53051)
			(xy 396.038039 -299.528529) (xy 395.98982 -299.518685) (xy 395.943804 -299.501233) (xy 395.901183 -299.476626)
			(xy 395.863062 -299.445501) (xy 395.830427 -299.408664) (xy 395.804124 -299.367068) (xy 395.784833 -299.321792)
			(xy 395.773056 -299.274008) (xy 395.769096 -299.224954) (xy 395.430248 -299.224954) (xy 395.429753 -299.249561)
			(xy 395.421858 -299.298138) (xy 395.406274 -299.344819) (xy 395.383403 -299.388396) (xy 395.353838 -299.42774)
			(xy 395.318345 -299.461832) (xy 395.277842 -299.489788) (xy 395.23338 -299.510886) (xy 395.186109 -299.524578)
			(xy 395.137254 -299.53051) (xy 395.088079 -299.528529) (xy 395.03986 -299.518685) (xy 394.993844 -299.501233)
			(xy 394.951223 -299.476626) (xy 394.913102 -299.445501) (xy 394.880467 -299.408664) (xy 394.854164 -299.367068)
			(xy 394.834873 -299.321792) (xy 394.823096 -299.274008) (xy 394.819136 -299.224954) (xy 394.480288 -299.224954)
			(xy 394.479793 -299.249561) (xy 394.471898 -299.298138) (xy 394.456314 -299.344819) (xy 394.433443 -299.388396)
			(xy 394.403878 -299.42774) (xy 394.368385 -299.461832) (xy 394.327882 -299.489788) (xy 394.28342 -299.510886)
			(xy 394.236149 -299.524578) (xy 394.187294 -299.53051) (xy 394.138119 -299.528529) (xy 394.0899 -299.518685)
			(xy 394.043884 -299.501233) (xy 394.001263 -299.476626) (xy 393.963142 -299.445501) (xy 393.930507 -299.408664)
			(xy 393.904204 -299.367068) (xy 393.884913 -299.321792) (xy 393.873136 -299.274008) (xy 393.869176 -299.224954)
			(xy 393.530328 -299.224954) (xy 393.529833 -299.249561) (xy 393.521938 -299.298138) (xy 393.506354 -299.344819)
			(xy 393.483483 -299.388396) (xy 393.453918 -299.42774) (xy 393.418425 -299.461832) (xy 393.377922 -299.489788)
			(xy 393.33346 -299.510886) (xy 393.286189 -299.524578) (xy 393.237334 -299.53051) (xy 393.188159 -299.528529)
			(xy 393.13994 -299.518685) (xy 393.093924 -299.501233) (xy 393.051303 -299.476626) (xy 393.013182 -299.445501)
			(xy 392.980547 -299.408664) (xy 392.954244 -299.367068) (xy 392.934953 -299.321792) (xy 392.923176 -299.274008)
			(xy 392.919216 -299.224954) (xy 392.580114 -299.224954) (xy 392.579619 -299.249561) (xy 392.571724 -299.298138)
			(xy 392.55614 -299.344819) (xy 392.533269 -299.388396) (xy 392.503704 -299.42774) (xy 392.468211 -299.461832)
			(xy 392.427708 -299.489788) (xy 392.383246 -299.510886) (xy 392.335975 -299.524578) (xy 392.28712 -299.53051)
			(xy 392.237945 -299.528529) (xy 392.189726 -299.518685) (xy 392.14371 -299.501233) (xy 392.101089 -299.476626)
			(xy 392.062968 -299.445501) (xy 392.030333 -299.408664) (xy 392.00403 -299.367068) (xy 391.984739 -299.321792)
			(xy 391.972962 -299.274008) (xy 391.969002 -299.224954) (xy 391.630086 -299.224954) (xy 391.63052 -299.232951)
			(xy 391.625158 -299.2823) (xy 391.611883 -299.330133) (xy 391.591045 -299.375187) (xy 391.563192 -299.416277)
			(xy 391.529059 -299.45232) (xy 391.489545 -299.482366) (xy 391.44569 -299.505624) (xy 391.398651 -299.52148)
			(xy 391.349666 -299.529518) (xy 391.324846 -299.530008) (xy 391.310663 -299.529825) (xy 391.282423 -299.527157)
			(xy 391.268458 -299.524674) (xy 391.256012 -299.522388) (xy 391.232136 -299.529754) (xy 391.15492 -299.60697)
			(xy 391.147554 -299.6311) (xy 391.14984 -299.643292) (xy 391.152321 -299.657321) (xy 391.154995 -299.685688)
			(xy 391.155174 -299.699934) (xy 391.155003 -299.714117) (xy 391.152327 -299.742357) (xy 391.14984 -299.756322)
			(xy 391.147554 -299.768768) (xy 391.15492 -299.79239) (xy 391.23239 -299.86986) (xy 391.256012 -299.877226)
			(xy 391.268458 -299.87494) (xy 391.282423 -299.87246) (xy 391.310663 -299.86979) (xy 391.324846 -299.869606)
			(xy 391.348839 -299.87002) (xy 391.396234 -299.877534) (xy 391.44187 -299.892368) (xy 391.484623 -299.914159)
			(xy 391.523442 -299.942369) (xy 391.55737 -299.976304) (xy 391.585573 -300.015128) (xy 391.607355 -300.057886)
			(xy 391.62218 -300.103525) (xy 391.629684 -300.150921) (xy 391.630154 -300.174914) (xy 391.629979 -300.189097)
			(xy 391.627306 -300.217337) (xy 391.62482 -300.231302) (xy 391.622534 -300.243748) (xy 391.6299 -300.26737)
			(xy 391.70737 -300.34484) (xy 391.730992 -300.352206) (xy 391.743438 -300.34992) (xy 391.757404 -300.347442)
			(xy 391.785643 -300.344771) (xy 391.799826 -300.344586) (xy 391.814009 -300.344759) (xy 391.842249 -300.347434)
			(xy 391.856214 -300.34992) (xy 391.86866 -300.352206) (xy 391.892282 -300.34484) (xy 391.969752 -300.26737)
			(xy 391.977118 -300.243748) (xy 391.974832 -300.231302) (xy 391.97236 -300.217335) (xy 391.969685 -300.189096)
			(xy 391.969498 -300.174914) (xy 391.969963 -300.150092) (xy 391.977992 -300.101101) (xy 391.993842 -300.054055)
			(xy 392.017093 -300.010193) (xy 392.047135 -299.97067) (xy 392.083175 -299.936528) (xy 392.124264 -299.908667)
			(xy 392.169319 -299.88782) (xy 392.217153 -299.874537) (xy 392.266507 -299.869167) (xy 392.316078 -299.871853)
			(xy 392.364562 -299.882524) (xy 392.410681 -299.900897) (xy 392.45322 -299.92649) (xy 392.491058 -299.958628)
			(xy 392.523198 -299.996464) (xy 392.548794 -300.039001) (xy 392.56717 -300.085119) (xy 392.577844 -300.133602)
			(xy 392.580085 -300.174914) (xy 392.919216 -300.174914) (xy 392.923176 -300.12586) (xy 392.934953 -300.078076)
			(xy 392.954244 -300.0328) (xy 392.980547 -299.991204) (xy 393.013182 -299.954367) (xy 393.051303 -299.923242)
			(xy 393.093924 -299.898635) (xy 393.13994 -299.881183) (xy 393.188159 -299.871339) (xy 393.237334 -299.869358)
			(xy 393.286189 -299.87529) (xy 393.33346 -299.888982) (xy 393.377922 -299.91008) (xy 393.418425 -299.938036)
			(xy 393.453918 -299.972128) (xy 393.483483 -300.011472) (xy 393.506354 -300.055049) (xy 393.521938 -300.10173)
			(xy 393.529833 -300.150307) (xy 393.530328 -300.174914) (xy 393.869176 -300.174914) (xy 393.873136 -300.12586)
			(xy 393.884913 -300.078076) (xy 393.904204 -300.0328) (xy 393.930507 -299.991204) (xy 393.963142 -299.954367)
			(xy 394.001263 -299.923242) (xy 394.043884 -299.898635) (xy 394.0899 -299.881183) (xy 394.138119 -299.871339)
			(xy 394.187294 -299.869358) (xy 394.236149 -299.87529) (xy 394.28342 -299.888982) (xy 394.327882 -299.91008)
			(xy 394.368385 -299.938036) (xy 394.403878 -299.972128) (xy 394.433443 -300.011472) (xy 394.456314 -300.055049)
			(xy 394.471898 -300.10173) (xy 394.479793 -300.150307) (xy 394.480288 -300.174914) (xy 395.769096 -300.174914)
			(xy 395.773056 -300.12586) (xy 395.784833 -300.078076) (xy 395.804124 -300.0328) (xy 395.830427 -299.991204)
			(xy 395.863062 -299.954367) (xy 395.901183 -299.923242) (xy 395.943804 -299.898635) (xy 395.98982 -299.881183)
			(xy 396.038039 -299.871339) (xy 396.087214 -299.869358) (xy 396.136069 -299.87529) (xy 396.18334 -299.888982)
			(xy 396.227802 -299.91008) (xy 396.268305 -299.938036) (xy 396.303798 -299.972128) (xy 396.333363 -300.011472)
			(xy 396.356234 -300.055049) (xy 396.371818 -300.10173) (xy 396.379713 -300.150307) (xy 396.380208 -300.174914)
			(xy 396.719056 -300.174914) (xy 396.723016 -300.12586) (xy 396.734793 -300.078076) (xy 396.754084 -300.0328)
			(xy 396.780387 -299.991204) (xy 396.813022 -299.954367) (xy 396.851143 -299.923242) (xy 396.893764 -299.898635)
			(xy 396.93978 -299.881183) (xy 396.987999 -299.871339) (xy 397.037174 -299.869358) (xy 397.086029 -299.87529)
			(xy 397.1333 -299.888982) (xy 397.177762 -299.91008) (xy 397.218265 -299.938036) (xy 397.253758 -299.972128)
			(xy 397.283323 -300.011472) (xy 397.306194 -300.055049) (xy 397.321778 -300.10173) (xy 397.329673 -300.150307)
			(xy 397.330168 -300.174914) (xy 398.61923 -300.174914) (xy 398.62319 -300.12586) (xy 398.634967 -300.078076)
			(xy 398.654258 -300.0328) (xy 398.680561 -299.991204) (xy 398.713196 -299.954367) (xy 398.751317 -299.923242)
			(xy 398.793938 -299.898635) (xy 398.839954 -299.881183) (xy 398.888173 -299.871339) (xy 398.937348 -299.869358)
			(xy 398.986203 -299.87529) (xy 399.033474 -299.888982) (xy 399.077936 -299.91008) (xy 399.118439 -299.938036)
			(xy 399.153932 -299.972128) (xy 399.183497 -300.011472) (xy 399.206368 -300.055049) (xy 399.221952 -300.10173)
			(xy 399.229847 -300.150307) (xy 399.230342 -300.174914) (xy 399.56919 -300.174914) (xy 399.57315 -300.12586)
			(xy 399.584927 -300.078076) (xy 399.604218 -300.0328) (xy 399.630521 -299.991204) (xy 399.663156 -299.954367)
			(xy 399.701277 -299.923242) (xy 399.743898 -299.898635) (xy 399.789914 -299.881183) (xy 399.838133 -299.871339)
			(xy 399.887308 -299.869358) (xy 399.936163 -299.87529) (xy 399.983434 -299.888982) (xy 400.027896 -299.91008)
			(xy 400.068399 -299.938036) (xy 400.103892 -299.972128) (xy 400.133457 -300.011472) (xy 400.156328 -300.055049)
			(xy 400.171912 -300.10173) (xy 400.179807 -300.150307) (xy 400.180302 -300.174914) (xy 400.51915 -300.174914)
			(xy 400.52311 -300.12586) (xy 400.534887 -300.078076) (xy 400.554178 -300.0328) (xy 400.580481 -299.991204)
			(xy 400.613116 -299.954367) (xy 400.651237 -299.923242) (xy 400.693858 -299.898635) (xy 400.739874 -299.881183)
			(xy 400.788093 -299.871339) (xy 400.837268 -299.869358) (xy 400.886123 -299.87529) (xy 400.933394 -299.888982)
			(xy 400.977856 -299.91008) (xy 401.018359 -299.938036) (xy 401.053852 -299.972128) (xy 401.083417 -300.011472)
			(xy 401.106288 -300.055049) (xy 401.121872 -300.10173) (xy 401.129767 -300.150307) (xy 401.130262 -300.174914)
			(xy 401.46911 -300.174914) (xy 401.47307 -300.12586) (xy 401.484847 -300.078076) (xy 401.504138 -300.0328)
			(xy 401.530441 -299.991204) (xy 401.563076 -299.954367) (xy 401.601197 -299.923242) (xy 401.643818 -299.898635)
			(xy 401.689834 -299.881183) (xy 401.738053 -299.871339) (xy 401.787228 -299.869358) (xy 401.836083 -299.87529)
			(xy 401.883354 -299.888982) (xy 401.927816 -299.91008) (xy 401.968319 -299.938036) (xy 402.003812 -299.972128)
			(xy 402.033377 -300.011472) (xy 402.056248 -300.055049) (xy 402.071832 -300.10173) (xy 402.079727 -300.150307)
			(xy 402.080222 -300.174914) (xy 402.41907 -300.174914) (xy 402.42303 -300.12586) (xy 402.434807 -300.078076)
			(xy 402.454098 -300.0328) (xy 402.480401 -299.991204) (xy 402.513036 -299.954367) (xy 402.551157 -299.923242)
			(xy 402.593778 -299.898635) (xy 402.639794 -299.881183) (xy 402.688013 -299.871339) (xy 402.737188 -299.869358)
			(xy 402.786043 -299.87529) (xy 402.833314 -299.888982) (xy 402.877776 -299.91008) (xy 402.918279 -299.938036)
			(xy 402.953772 -299.972128) (xy 402.983337 -300.011472) (xy 403.006208 -300.055049) (xy 403.021792 -300.10173)
			(xy 403.029687 -300.150307) (xy 403.030182 -300.174914) (xy 403.36903 -300.174914) (xy 403.37299 -300.12586)
			(xy 403.384767 -300.078076) (xy 403.404058 -300.0328) (xy 403.430361 -299.991204) (xy 403.462996 -299.954367)
			(xy 403.501117 -299.923242) (xy 403.543738 -299.898635) (xy 403.589754 -299.881183) (xy 403.637973 -299.871339)
			(xy 403.687148 -299.869358) (xy 403.736003 -299.87529) (xy 403.783274 -299.888982) (xy 403.827736 -299.91008)
			(xy 403.868239 -299.938036) (xy 403.903732 -299.972128) (xy 403.933297 -300.011472) (xy 403.956168 -300.055049)
			(xy 403.971752 -300.10173) (xy 403.979647 -300.150307) (xy 403.980142 -300.174914) (xy 404.31899 -300.174914)
			(xy 404.32295 -300.12586) (xy 404.334727 -300.078076) (xy 404.354018 -300.0328) (xy 404.380321 -299.991204)
			(xy 404.412956 -299.954367) (xy 404.451077 -299.923242) (xy 404.493698 -299.898635) (xy 404.539714 -299.881183)
			(xy 404.587933 -299.871339) (xy 404.637108 -299.869358) (xy 404.685963 -299.87529) (xy 404.733234 -299.888982)
			(xy 404.777696 -299.91008) (xy 404.818199 -299.938036) (xy 404.853692 -299.972128) (xy 404.883257 -300.011472)
			(xy 404.906128 -300.055049) (xy 404.921712 -300.10173) (xy 404.929607 -300.150307) (xy 404.930102 -300.174914)
			(xy 405.269204 -300.174914) (xy 405.273164 -300.12586) (xy 405.284941 -300.078076) (xy 405.304232 -300.0328)
			(xy 405.330535 -299.991204) (xy 405.36317 -299.954367) (xy 405.401291 -299.923242) (xy 405.443912 -299.898635)
			(xy 405.489928 -299.881183) (xy 405.538147 -299.871339) (xy 405.587322 -299.869358) (xy 405.636177 -299.87529)
			(xy 405.683448 -299.888982) (xy 405.72791 -299.91008) (xy 405.768413 -299.938036) (xy 405.803906 -299.972128)
			(xy 405.833471 -300.011472) (xy 405.856342 -300.055049) (xy 405.871926 -300.10173) (xy 405.879821 -300.150307)
			(xy 405.880316 -300.174914) (xy 406.219164 -300.174914) (xy 406.223124 -300.12586) (xy 406.234901 -300.078076)
			(xy 406.254192 -300.0328) (xy 406.280495 -299.991204) (xy 406.31313 -299.954367) (xy 406.351251 -299.923242)
			(xy 406.393872 -299.898635) (xy 406.439888 -299.881183) (xy 406.488107 -299.871339) (xy 406.537282 -299.869358)
			(xy 406.586137 -299.87529) (xy 406.633408 -299.888982) (xy 406.67787 -299.91008) (xy 406.718373 -299.938036)
			(xy 406.753866 -299.972128) (xy 406.783431 -300.011472) (xy 406.806302 -300.055049) (xy 406.821886 -300.10173)
			(xy 406.829781 -300.150307) (xy 406.830276 -300.174914) (xy 408.119084 -300.174914) (xy 408.123044 -300.12586)
			(xy 408.134821 -300.078076) (xy 408.154112 -300.0328) (xy 408.180415 -299.991204) (xy 408.21305 -299.954367)
			(xy 408.251171 -299.923242) (xy 408.293792 -299.898635) (xy 408.339808 -299.881183) (xy 408.388027 -299.871339)
			(xy 408.437202 -299.869358) (xy 408.486057 -299.87529) (xy 408.533328 -299.888982) (xy 408.57779 -299.91008)
			(xy 408.618293 -299.938036) (xy 408.653786 -299.972128) (xy 408.683351 -300.011472) (xy 408.706222 -300.055049)
			(xy 408.721806 -300.10173) (xy 408.729701 -300.150307) (xy 408.730196 -300.174914) (xy 409.069044 -300.174914)
			(xy 409.073004 -300.12586) (xy 409.084781 -300.078076) (xy 409.104072 -300.0328) (xy 409.130375 -299.991204)
			(xy 409.16301 -299.954367) (xy 409.201131 -299.923242) (xy 409.243752 -299.898635) (xy 409.289768 -299.881183)
			(xy 409.337987 -299.871339) (xy 409.387162 -299.869358) (xy 409.436017 -299.87529) (xy 409.483288 -299.888982)
			(xy 409.52775 -299.91008) (xy 409.568253 -299.938036) (xy 409.603746 -299.972128) (xy 409.633311 -300.011472)
			(xy 409.656182 -300.055049) (xy 409.671766 -300.10173) (xy 409.679661 -300.150307) (xy 409.680156 -300.174914)
			(xy 410.019004 -300.174914) (xy 410.022964 -300.12586) (xy 410.034741 -300.078076) (xy 410.054032 -300.0328)
			(xy 410.080335 -299.991204) (xy 410.11297 -299.954367) (xy 410.151091 -299.923242) (xy 410.193712 -299.898635)
			(xy 410.239728 -299.881183) (xy 410.287947 -299.871339) (xy 410.337122 -299.869358) (xy 410.385977 -299.87529)
			(xy 410.433248 -299.888982) (xy 410.47771 -299.91008) (xy 410.518213 -299.938036) (xy 410.553706 -299.972128)
			(xy 410.583271 -300.011472) (xy 410.606142 -300.055049) (xy 410.621726 -300.10173) (xy 410.629621 -300.150307)
			(xy 410.630116 -300.174914) (xy 410.969218 -300.174914) (xy 410.973178 -300.12586) (xy 410.984955 -300.078076)
			(xy 411.004246 -300.0328) (xy 411.030549 -299.991204) (xy 411.063184 -299.954367) (xy 411.101305 -299.923242)
			(xy 411.143926 -299.898635) (xy 411.189942 -299.881183) (xy 411.238161 -299.871339) (xy 411.287336 -299.869358)
			(xy 411.336191 -299.87529) (xy 411.383462 -299.888982) (xy 411.427924 -299.91008) (xy 411.468427 -299.938036)
			(xy 411.50392 -299.972128) (xy 411.533485 -300.011472) (xy 411.556356 -300.055049) (xy 411.57194 -300.10173)
			(xy 411.579835 -300.150307) (xy 411.58033 -300.174914) (xy 411.919178 -300.174914) (xy 411.923138 -300.12586)
			(xy 411.934915 -300.078076) (xy 411.954206 -300.0328) (xy 411.980509 -299.991204) (xy 412.013144 -299.954367)
			(xy 412.051265 -299.923242) (xy 412.093886 -299.898635) (xy 412.139902 -299.881183) (xy 412.188121 -299.871339)
			(xy 412.237296 -299.869358) (xy 412.286151 -299.87529) (xy 412.333422 -299.888982) (xy 412.377884 -299.91008)
			(xy 412.418387 -299.938036) (xy 412.45388 -299.972128) (xy 412.483445 -300.011472) (xy 412.506316 -300.055049)
			(xy 412.5219 -300.10173) (xy 412.529795 -300.150307) (xy 412.53029 -300.174914) (xy 412.869138 -300.174914)
			(xy 412.873098 -300.12586) (xy 412.884875 -300.078076) (xy 412.904166 -300.0328) (xy 412.930469 -299.991204)
			(xy 412.963104 -299.954367) (xy 413.001225 -299.923242) (xy 413.043846 -299.898635) (xy 413.089862 -299.881183)
			(xy 413.138081 -299.871339) (xy 413.187256 -299.869358) (xy 413.236111 -299.87529) (xy 413.283382 -299.888982)
			(xy 413.327844 -299.91008) (xy 413.368347 -299.938036) (xy 413.40384 -299.972128) (xy 413.433405 -300.011472)
			(xy 413.456276 -300.055049) (xy 413.47186 -300.10173) (xy 413.479755 -300.150307) (xy 413.48025 -300.174914)
			(xy 413.819098 -300.174914) (xy 413.823058 -300.12586) (xy 413.834835 -300.078076) (xy 413.854126 -300.0328)
			(xy 413.880429 -299.991204) (xy 413.913064 -299.954367) (xy 413.951185 -299.923242) (xy 413.993806 -299.898635)
			(xy 414.039822 -299.881183) (xy 414.088041 -299.871339) (xy 414.137216 -299.869358) (xy 414.186071 -299.87529)
			(xy 414.233342 -299.888982) (xy 414.277804 -299.91008) (xy 414.318307 -299.938036) (xy 414.3538 -299.972128)
			(xy 414.383365 -300.011472) (xy 414.406236 -300.055049) (xy 414.42182 -300.10173) (xy 414.429715 -300.150307)
			(xy 414.43021 -300.174914) (xy 414.769058 -300.174914) (xy 414.773018 -300.12586) (xy 414.784795 -300.078076)
			(xy 414.804086 -300.0328) (xy 414.830389 -299.991204) (xy 414.863024 -299.954367) (xy 414.901145 -299.923242)
			(xy 414.943766 -299.898635) (xy 414.989782 -299.881183) (xy 415.038001 -299.871339) (xy 415.087176 -299.869358)
			(xy 415.136031 -299.87529) (xy 415.183302 -299.888982) (xy 415.227764 -299.91008) (xy 415.268267 -299.938036)
			(xy 415.30376 -299.972128) (xy 415.333325 -300.011472) (xy 415.356196 -300.055049) (xy 415.37178 -300.10173)
			(xy 415.379675 -300.150307) (xy 415.38017 -300.174914) (xy 415.719018 -300.174914) (xy 415.722978 -300.12586)
			(xy 415.734755 -300.078076) (xy 415.754046 -300.0328) (xy 415.780349 -299.991204) (xy 415.812984 -299.954367)
			(xy 415.851105 -299.923242) (xy 415.893726 -299.898635) (xy 415.939742 -299.881183) (xy 415.987961 -299.871339)
			(xy 416.037136 -299.869358) (xy 416.085991 -299.87529) (xy 416.133262 -299.888982) (xy 416.177724 -299.91008)
			(xy 416.218227 -299.938036) (xy 416.25372 -299.972128) (xy 416.283285 -300.011472) (xy 416.306156 -300.055049)
			(xy 416.32174 -300.10173) (xy 416.329635 -300.150307) (xy 416.33013 -300.174914) (xy 416.668978 -300.174914)
			(xy 416.672938 -300.12586) (xy 416.684715 -300.078076) (xy 416.704006 -300.0328) (xy 416.730309 -299.991204)
			(xy 416.762944 -299.954367) (xy 416.801065 -299.923242) (xy 416.843686 -299.898635) (xy 416.889702 -299.881183)
			(xy 416.937921 -299.871339) (xy 416.987096 -299.869358) (xy 417.035951 -299.87529) (xy 417.083222 -299.888982)
			(xy 417.127684 -299.91008) (xy 417.168187 -299.938036) (xy 417.20368 -299.972128) (xy 417.233245 -300.011472)
			(xy 417.256116 -300.055049) (xy 417.2717 -300.10173) (xy 417.279595 -300.150307) (xy 417.28009 -300.174914)
			(xy 417.279595 -300.199521) (xy 417.2717 -300.248098) (xy 417.256116 -300.294779) (xy 417.233245 -300.338356)
			(xy 417.20368 -300.3777) (xy 417.168187 -300.411792) (xy 417.127684 -300.439748) (xy 417.083222 -300.460846)
			(xy 417.035951 -300.474538) (xy 416.987096 -300.48047) (xy 416.937921 -300.478489) (xy 416.889702 -300.468645)
			(xy 416.843686 -300.451193) (xy 416.801065 -300.426586) (xy 416.762944 -300.395461) (xy 416.730309 -300.358624)
			(xy 416.704006 -300.317028) (xy 416.684715 -300.271752) (xy 416.672938 -300.223968) (xy 416.668978 -300.174914)
			(xy 416.33013 -300.174914) (xy 416.329635 -300.199521) (xy 416.32174 -300.248098) (xy 416.306156 -300.294779)
			(xy 416.283285 -300.338356) (xy 416.25372 -300.3777) (xy 416.218227 -300.411792) (xy 416.177724 -300.439748)
			(xy 416.133262 -300.460846) (xy 416.085991 -300.474538) (xy 416.037136 -300.48047) (xy 415.987961 -300.478489)
			(xy 415.939742 -300.468645) (xy 415.893726 -300.451193) (xy 415.851105 -300.426586) (xy 415.812984 -300.395461)
			(xy 415.780349 -300.358624) (xy 415.754046 -300.317028) (xy 415.734755 -300.271752) (xy 415.722978 -300.223968)
			(xy 415.719018 -300.174914) (xy 415.38017 -300.174914) (xy 415.379675 -300.199521) (xy 415.37178 -300.248098)
			(xy 415.356196 -300.294779) (xy 415.333325 -300.338356) (xy 415.30376 -300.3777) (xy 415.268267 -300.411792)
			(xy 415.227764 -300.439748) (xy 415.183302 -300.460846) (xy 415.136031 -300.474538) (xy 415.087176 -300.48047)
			(xy 415.038001 -300.478489) (xy 414.989782 -300.468645) (xy 414.943766 -300.451193) (xy 414.901145 -300.426586)
			(xy 414.863024 -300.395461) (xy 414.830389 -300.358624) (xy 414.804086 -300.317028) (xy 414.784795 -300.271752)
			(xy 414.773018 -300.223968) (xy 414.769058 -300.174914) (xy 414.43021 -300.174914) (xy 414.429715 -300.199521)
			(xy 414.42182 -300.248098) (xy 414.406236 -300.294779) (xy 414.383365 -300.338356) (xy 414.3538 -300.3777)
			(xy 414.318307 -300.411792) (xy 414.277804 -300.439748) (xy 414.233342 -300.460846) (xy 414.186071 -300.474538)
			(xy 414.137216 -300.48047) (xy 414.088041 -300.478489) (xy 414.039822 -300.468645) (xy 413.993806 -300.451193)
			(xy 413.951185 -300.426586) (xy 413.913064 -300.395461) (xy 413.880429 -300.358624) (xy 413.854126 -300.317028)
			(xy 413.834835 -300.271752) (xy 413.823058 -300.223968) (xy 413.819098 -300.174914) (xy 413.48025 -300.174914)
			(xy 413.479755 -300.199521) (xy 413.47186 -300.248098) (xy 413.456276 -300.294779) (xy 413.433405 -300.338356)
			(xy 413.40384 -300.3777) (xy 413.368347 -300.411792) (xy 413.327844 -300.439748) (xy 413.283382 -300.460846)
			(xy 413.236111 -300.474538) (xy 413.187256 -300.48047) (xy 413.138081 -300.478489) (xy 413.089862 -300.468645)
			(xy 413.043846 -300.451193) (xy 413.001225 -300.426586) (xy 412.963104 -300.395461) (xy 412.930469 -300.358624)
			(xy 412.904166 -300.317028) (xy 412.884875 -300.271752) (xy 412.873098 -300.223968) (xy 412.869138 -300.174914)
			(xy 412.53029 -300.174914) (xy 412.529795 -300.199521) (xy 412.5219 -300.248098) (xy 412.506316 -300.294779)
			(xy 412.483445 -300.338356) (xy 412.45388 -300.3777) (xy 412.418387 -300.411792) (xy 412.377884 -300.439748)
			(xy 412.333422 -300.460846) (xy 412.286151 -300.474538) (xy 412.237296 -300.48047) (xy 412.188121 -300.478489)
			(xy 412.139902 -300.468645) (xy 412.093886 -300.451193) (xy 412.051265 -300.426586) (xy 412.013144 -300.395461)
			(xy 411.980509 -300.358624) (xy 411.954206 -300.317028) (xy 411.934915 -300.271752) (xy 411.923138 -300.223968)
			(xy 411.919178 -300.174914) (xy 411.58033 -300.174914) (xy 411.579835 -300.199521) (xy 411.57194 -300.248098)
			(xy 411.556356 -300.294779) (xy 411.533485 -300.338356) (xy 411.50392 -300.3777) (xy 411.468427 -300.411792)
			(xy 411.427924 -300.439748) (xy 411.383462 -300.460846) (xy 411.336191 -300.474538) (xy 411.287336 -300.48047)
			(xy 411.238161 -300.478489) (xy 411.189942 -300.468645) (xy 411.143926 -300.451193) (xy 411.101305 -300.426586)
			(xy 411.063184 -300.395461) (xy 411.030549 -300.358624) (xy 411.004246 -300.317028) (xy 410.984955 -300.271752)
			(xy 410.973178 -300.223968) (xy 410.969218 -300.174914) (xy 410.630116 -300.174914) (xy 410.629621 -300.199521)
			(xy 410.621726 -300.248098) (xy 410.606142 -300.294779) (xy 410.583271 -300.338356) (xy 410.553706 -300.3777)
			(xy 410.518213 -300.411792) (xy 410.47771 -300.439748) (xy 410.433248 -300.460846) (xy 410.385977 -300.474538)
			(xy 410.337122 -300.48047) (xy 410.287947 -300.478489) (xy 410.239728 -300.468645) (xy 410.193712 -300.451193)
			(xy 410.151091 -300.426586) (xy 410.11297 -300.395461) (xy 410.080335 -300.358624) (xy 410.054032 -300.317028)
			(xy 410.034741 -300.271752) (xy 410.022964 -300.223968) (xy 410.019004 -300.174914) (xy 409.680156 -300.174914)
			(xy 409.679661 -300.199521) (xy 409.671766 -300.248098) (xy 409.656182 -300.294779) (xy 409.633311 -300.338356)
			(xy 409.603746 -300.3777) (xy 409.568253 -300.411792) (xy 409.52775 -300.439748) (xy 409.483288 -300.460846)
			(xy 409.436017 -300.474538) (xy 409.387162 -300.48047) (xy 409.337987 -300.478489) (xy 409.289768 -300.468645)
			(xy 409.243752 -300.451193) (xy 409.201131 -300.426586) (xy 409.16301 -300.395461) (xy 409.130375 -300.358624)
			(xy 409.104072 -300.317028) (xy 409.084781 -300.271752) (xy 409.073004 -300.223968) (xy 409.069044 -300.174914)
			(xy 408.730196 -300.174914) (xy 408.729701 -300.199521) (xy 408.721806 -300.248098) (xy 408.706222 -300.294779)
			(xy 408.683351 -300.338356) (xy 408.653786 -300.3777) (xy 408.618293 -300.411792) (xy 408.57779 -300.439748)
			(xy 408.533328 -300.460846) (xy 408.486057 -300.474538) (xy 408.437202 -300.48047) (xy 408.388027 -300.478489)
			(xy 408.339808 -300.468645) (xy 408.293792 -300.451193) (xy 408.251171 -300.426586) (xy 408.21305 -300.395461)
			(xy 408.180415 -300.358624) (xy 408.154112 -300.317028) (xy 408.134821 -300.271752) (xy 408.123044 -300.223968)
			(xy 408.119084 -300.174914) (xy 406.830276 -300.174914) (xy 406.829781 -300.199521) (xy 406.821886 -300.248098)
			(xy 406.806302 -300.294779) (xy 406.783431 -300.338356) (xy 406.753866 -300.3777) (xy 406.718373 -300.411792)
			(xy 406.67787 -300.439748) (xy 406.633408 -300.460846) (xy 406.586137 -300.474538) (xy 406.537282 -300.48047)
			(xy 406.488107 -300.478489) (xy 406.439888 -300.468645) (xy 406.393872 -300.451193) (xy 406.351251 -300.426586)
			(xy 406.31313 -300.395461) (xy 406.280495 -300.358624) (xy 406.254192 -300.317028) (xy 406.234901 -300.271752)
			(xy 406.223124 -300.223968) (xy 406.219164 -300.174914) (xy 405.880316 -300.174914) (xy 405.879821 -300.199521)
			(xy 405.871926 -300.248098) (xy 405.856342 -300.294779) (xy 405.833471 -300.338356) (xy 405.803906 -300.3777)
			(xy 405.768413 -300.411792) (xy 405.72791 -300.439748) (xy 405.683448 -300.460846) (xy 405.636177 -300.474538)
			(xy 405.587322 -300.48047) (xy 405.538147 -300.478489) (xy 405.489928 -300.468645) (xy 405.443912 -300.451193)
			(xy 405.401291 -300.426586) (xy 405.36317 -300.395461) (xy 405.330535 -300.358624) (xy 405.304232 -300.317028)
			(xy 405.284941 -300.271752) (xy 405.273164 -300.223968) (xy 405.269204 -300.174914) (xy 404.930102 -300.174914)
			(xy 404.929607 -300.199521) (xy 404.921712 -300.248098) (xy 404.906128 -300.294779) (xy 404.883257 -300.338356)
			(xy 404.853692 -300.3777) (xy 404.818199 -300.411792) (xy 404.777696 -300.439748) (xy 404.733234 -300.460846)
			(xy 404.685963 -300.474538) (xy 404.637108 -300.48047) (xy 404.587933 -300.478489) (xy 404.539714 -300.468645)
			(xy 404.493698 -300.451193) (xy 404.451077 -300.426586) (xy 404.412956 -300.395461) (xy 404.380321 -300.358624)
			(xy 404.354018 -300.317028) (xy 404.334727 -300.271752) (xy 404.32295 -300.223968) (xy 404.31899 -300.174914)
			(xy 403.980142 -300.174914) (xy 403.979647 -300.199521) (xy 403.971752 -300.248098) (xy 403.956168 -300.294779)
			(xy 403.933297 -300.338356) (xy 403.903732 -300.3777) (xy 403.868239 -300.411792) (xy 403.827736 -300.439748)
			(xy 403.783274 -300.460846) (xy 403.736003 -300.474538) (xy 403.687148 -300.48047) (xy 403.637973 -300.478489)
			(xy 403.589754 -300.468645) (xy 403.543738 -300.451193) (xy 403.501117 -300.426586) (xy 403.462996 -300.395461)
			(xy 403.430361 -300.358624) (xy 403.404058 -300.317028) (xy 403.384767 -300.271752) (xy 403.37299 -300.223968)
			(xy 403.36903 -300.174914) (xy 403.030182 -300.174914) (xy 403.029687 -300.199521) (xy 403.021792 -300.248098)
			(xy 403.006208 -300.294779) (xy 402.983337 -300.338356) (xy 402.953772 -300.3777) (xy 402.918279 -300.411792)
			(xy 402.877776 -300.439748) (xy 402.833314 -300.460846) (xy 402.786043 -300.474538) (xy 402.737188 -300.48047)
			(xy 402.688013 -300.478489) (xy 402.639794 -300.468645) (xy 402.593778 -300.451193) (xy 402.551157 -300.426586)
			(xy 402.513036 -300.395461) (xy 402.480401 -300.358624) (xy 402.454098 -300.317028) (xy 402.434807 -300.271752)
			(xy 402.42303 -300.223968) (xy 402.41907 -300.174914) (xy 402.080222 -300.174914) (xy 402.079727 -300.199521)
			(xy 402.071832 -300.248098) (xy 402.056248 -300.294779) (xy 402.033377 -300.338356) (xy 402.003812 -300.3777)
			(xy 401.968319 -300.411792) (xy 401.927816 -300.439748) (xy 401.883354 -300.460846) (xy 401.836083 -300.474538)
			(xy 401.787228 -300.48047) (xy 401.738053 -300.478489) (xy 401.689834 -300.468645) (xy 401.643818 -300.451193)
			(xy 401.601197 -300.426586) (xy 401.563076 -300.395461) (xy 401.530441 -300.358624) (xy 401.504138 -300.317028)
			(xy 401.484847 -300.271752) (xy 401.47307 -300.223968) (xy 401.46911 -300.174914) (xy 401.130262 -300.174914)
			(xy 401.129767 -300.199521) (xy 401.121872 -300.248098) (xy 401.106288 -300.294779) (xy 401.083417 -300.338356)
			(xy 401.053852 -300.3777) (xy 401.018359 -300.411792) (xy 400.977856 -300.439748) (xy 400.933394 -300.460846)
			(xy 400.886123 -300.474538) (xy 400.837268 -300.48047) (xy 400.788093 -300.478489) (xy 400.739874 -300.468645)
			(xy 400.693858 -300.451193) (xy 400.651237 -300.426586) (xy 400.613116 -300.395461) (xy 400.580481 -300.358624)
			(xy 400.554178 -300.317028) (xy 400.534887 -300.271752) (xy 400.52311 -300.223968) (xy 400.51915 -300.174914)
			(xy 400.180302 -300.174914) (xy 400.179807 -300.199521) (xy 400.171912 -300.248098) (xy 400.156328 -300.294779)
			(xy 400.133457 -300.338356) (xy 400.103892 -300.3777) (xy 400.068399 -300.411792) (xy 400.027896 -300.439748)
			(xy 399.983434 -300.460846) (xy 399.936163 -300.474538) (xy 399.887308 -300.48047) (xy 399.838133 -300.478489)
			(xy 399.789914 -300.468645) (xy 399.743898 -300.451193) (xy 399.701277 -300.426586) (xy 399.663156 -300.395461)
			(xy 399.630521 -300.358624) (xy 399.604218 -300.317028) (xy 399.584927 -300.271752) (xy 399.57315 -300.223968)
			(xy 399.56919 -300.174914) (xy 399.230342 -300.174914) (xy 399.229847 -300.199521) (xy 399.221952 -300.248098)
			(xy 399.206368 -300.294779) (xy 399.183497 -300.338356) (xy 399.153932 -300.3777) (xy 399.118439 -300.411792)
			(xy 399.077936 -300.439748) (xy 399.033474 -300.460846) (xy 398.986203 -300.474538) (xy 398.937348 -300.48047)
			(xy 398.888173 -300.478489) (xy 398.839954 -300.468645) (xy 398.793938 -300.451193) (xy 398.751317 -300.426586)
			(xy 398.713196 -300.395461) (xy 398.680561 -300.358624) (xy 398.654258 -300.317028) (xy 398.634967 -300.271752)
			(xy 398.62319 -300.223968) (xy 398.61923 -300.174914) (xy 397.330168 -300.174914) (xy 397.329673 -300.199521)
			(xy 397.321778 -300.248098) (xy 397.306194 -300.294779) (xy 397.283323 -300.338356) (xy 397.253758 -300.3777)
			(xy 397.218265 -300.411792) (xy 397.177762 -300.439748) (xy 397.1333 -300.460846) (xy 397.086029 -300.474538)
			(xy 397.037174 -300.48047) (xy 396.987999 -300.478489) (xy 396.93978 -300.468645) (xy 396.893764 -300.451193)
			(xy 396.851143 -300.426586) (xy 396.813022 -300.395461) (xy 396.780387 -300.358624) (xy 396.754084 -300.317028)
			(xy 396.734793 -300.271752) (xy 396.723016 -300.223968) (xy 396.719056 -300.174914) (xy 396.380208 -300.174914)
			(xy 396.379713 -300.199521) (xy 396.371818 -300.248098) (xy 396.356234 -300.294779) (xy 396.333363 -300.338356)
			(xy 396.303798 -300.3777) (xy 396.268305 -300.411792) (xy 396.227802 -300.439748) (xy 396.18334 -300.460846)
			(xy 396.136069 -300.474538) (xy 396.087214 -300.48047) (xy 396.038039 -300.478489) (xy 395.98982 -300.468645)
			(xy 395.943804 -300.451193) (xy 395.901183 -300.426586) (xy 395.863062 -300.395461) (xy 395.830427 -300.358624)
			(xy 395.804124 -300.317028) (xy 395.784833 -300.271752) (xy 395.773056 -300.223968) (xy 395.769096 -300.174914)
			(xy 394.480288 -300.174914) (xy 394.479793 -300.199521) (xy 394.471898 -300.248098) (xy 394.456314 -300.294779)
			(xy 394.433443 -300.338356) (xy 394.403878 -300.3777) (xy 394.368385 -300.411792) (xy 394.327882 -300.439748)
			(xy 394.28342 -300.460846) (xy 394.236149 -300.474538) (xy 394.187294 -300.48047) (xy 394.138119 -300.478489)
			(xy 394.0899 -300.468645) (xy 394.043884 -300.451193) (xy 394.001263 -300.426586) (xy 393.963142 -300.395461)
			(xy 393.930507 -300.358624) (xy 393.904204 -300.317028) (xy 393.884913 -300.271752) (xy 393.873136 -300.223968)
			(xy 393.869176 -300.174914) (xy 393.530328 -300.174914) (xy 393.529833 -300.199521) (xy 393.521938 -300.248098)
			(xy 393.506354 -300.294779) (xy 393.483483 -300.338356) (xy 393.453918 -300.3777) (xy 393.418425 -300.411792)
			(xy 393.377922 -300.439748) (xy 393.33346 -300.460846) (xy 393.286189 -300.474538) (xy 393.237334 -300.48047)
			(xy 393.188159 -300.478489) (xy 393.13994 -300.468645) (xy 393.093924 -300.451193) (xy 393.051303 -300.426586)
			(xy 393.013182 -300.395461) (xy 392.980547 -300.358624) (xy 392.954244 -300.317028) (xy 392.934953 -300.271752)
			(xy 392.923176 -300.223968) (xy 392.919216 -300.174914) (xy 392.580085 -300.174914) (xy 392.580533 -300.183173)
			(xy 392.575167 -300.232527) (xy 392.561887 -300.280362) (xy 392.541043 -300.325418) (xy 392.513184 -300.366509)
			(xy 392.479045 -300.402551) (xy 392.439524 -300.432596) (xy 392.395663 -300.455851) (xy 392.348618 -300.471703)
			(xy 392.299628 -300.479736) (xy 392.274806 -300.480222) (xy 392.260623 -300.480044) (xy 392.232383 -300.477373)
			(xy 392.218418 -300.474888) (xy 392.205972 -300.472602) (xy 392.18235 -300.479968) (xy 392.10488 -300.557438)
			(xy 392.097514 -300.58106) (xy 392.0998 -300.593506) (xy 392.102273 -300.607472) (xy 392.104947 -300.635712)
			(xy 392.105134 -300.649894) (xy 392.104612 -300.675149) (xy 392.096299 -300.724971) (xy 392.079898 -300.772745)
			(xy 392.055857 -300.817168) (xy 392.024833 -300.857028) (xy 391.987671 -300.891238) (xy 391.945385 -300.918864)
			(xy 391.899129 -300.939154) (xy 391.850164 -300.951554) (xy 391.799826 -300.955725) (xy 391.749488 -300.951554)
			(xy 391.700523 -300.939154) (xy 391.654267 -300.918864) (xy 391.611981 -300.891238) (xy 391.574819 -300.857028)
			(xy 391.543795 -300.817168) (xy 391.519754 -300.772745) (xy 391.503353 -300.724971) (xy 391.49504 -300.675149)
			(xy 391.494518 -300.649894) (xy 391.494693 -300.635711) (xy 391.497366 -300.607471) (xy 391.499852 -300.593506)
			(xy 391.502138 -300.58106) (xy 391.494772 -300.557438) (xy 391.417302 -300.479968) (xy 391.39368 -300.472602)
			(xy 391.381234 -300.474888) (xy 391.367269 -300.477369) (xy 391.339029 -300.480038) (xy 391.324846 -300.480222)
			(xy 391.310663 -300.480039) (xy 391.282423 -300.477371) (xy 391.268458 -300.474888) (xy 391.256012 -300.472602)
			(xy 391.23239 -300.479968) (xy 391.15492 -300.557438) (xy 391.147554 -300.58106) (xy 391.14984 -300.593506)
			(xy 391.152313 -300.607472) (xy 391.154987 -300.635712) (xy 391.155174 -300.649894) (xy 391.154729 -300.674715)
			(xy 391.146699 -300.723703) (xy 391.130849 -300.770746) (xy 391.107598 -300.814606) (xy 391.077557 -300.854126)
			(xy 391.041519 -300.888266) (xy 391.000432 -300.916126) (xy 390.955379 -300.936972) (xy 390.907548 -300.950255)
			(xy 390.858197 -300.955624) (xy 390.808628 -300.952939) (xy 390.760146 -300.942271) (xy 390.714029 -300.923899)
			(xy 390.671492 -300.898309) (xy 390.633655 -300.866174) (xy 390.601515 -300.828341) (xy 390.575919 -300.785807)
			(xy 390.557541 -300.739692) (xy 390.546866 -300.691212) (xy 390.544174 -300.641643) (xy 390.549538 -300.592292)
			(xy 390.562814 -300.544458) (xy 390.583654 -300.499403) (xy 390.611509 -300.458312) (xy 390.645644 -300.42227)
			(xy 390.68516 -300.392224) (xy 390.729017 -300.368967) (xy 390.776058 -300.353111) (xy 390.825045 -300.345075)
			(xy 390.849866 -300.344586) (xy 390.864049 -300.344767) (xy 390.892289 -300.347436) (xy 390.906254 -300.34992)
			(xy 390.9187 -300.352206) (xy 390.942322 -300.34484) (xy 391.019792 -300.26737) (xy 391.027158 -300.243748)
			(xy 391.024872 -300.231302) (xy 391.022399 -300.217335) (xy 391.019725 -300.189096) (xy 391.019538 -300.174914)
			(xy 391.019716 -300.160731) (xy 391.022387 -300.132491) (xy 391.024872 -300.118526) (xy 391.027158 -300.10608)
			(xy 391.019792 -300.082458) (xy 390.942322 -300.004988) (xy 390.9187 -299.997622) (xy 390.906254 -299.999908)
			(xy 390.892289 -300.002387) (xy 390.864049 -300.005057) (xy 390.849866 -300.005242) (xy 390.824615 -300.00465)
			(xy 390.774803 -299.996333) (xy 390.72704 -299.979931) (xy 390.682627 -299.955891) (xy 390.642776 -299.92487)
			(xy 390.608574 -299.887713) (xy 390.580954 -299.845434) (xy 390.56067 -299.799185) (xy 390.548273 -299.750229)
			(xy 390.544103 -299.6999) (xy 389.255254 -299.6999) (xy 389.255254 -299.699934) (xy 389.254685 -299.724752)
			(xy 389.24665 -299.773734) (xy 389.230795 -299.820771) (xy 389.20754 -299.864622) (xy 389.177497 -299.904134)
			(xy 389.141457 -299.938265) (xy 389.10037 -299.966116) (xy 389.055318 -299.986952) (xy 389.007489 -300.000225)
			(xy 388.958143 -300.005586) (xy 388.908579 -300.002892) (xy 388.860105 -299.992216) (xy 388.813996 -299.973838)
			(xy 388.771467 -299.948242) (xy 388.733641 -299.916103) (xy 388.701511 -299.878267) (xy 388.675927 -299.835733)
			(xy 388.657561 -299.789619) (xy 388.646897 -299.741141) (xy 388.644216 -299.691577) (xy 388.64959 -299.642232)
			(xy 388.662876 -299.594407) (xy 388.683724 -299.549361) (xy 388.711585 -299.508281) (xy 388.745725 -299.47225)
			(xy 388.785245 -299.442217) (xy 388.829103 -299.418973) (xy 388.876144 -299.403131) (xy 388.925128 -299.395108)
			(xy 388.949946 -299.394626) (xy 388.964129 -299.39481) (xy 388.992369 -299.397477) (xy 389.006334 -299.39996)
			(xy 389.01878 -299.402246) (xy 389.042402 -299.39488) (xy 389.119872 -299.31741) (xy 389.127238 -299.293788)
			(xy 389.124952 -299.281342) (xy 389.122472 -299.267377) (xy 389.119802 -299.239137) (xy 389.119618 -299.224954)
			(xy 389.119704 -299.215786) (xy 389.120849 -299.197486) (xy 389.121904 -299.188378) (xy 389.123174 -299.176186)
			(xy 389.1153 -299.154088) (xy 389.038846 -299.080936) (xy 389.01624 -299.074078) (xy 389.004302 -299.07611)
			(xy 388.990808 -299.078167) (xy 388.963595 -299.080329) (xy 388.949946 -299.080428) (xy 387.999986 -299.080428)
			(xy 387.973989 -299.079966) (xy 387.922636 -299.071833) (xy 387.873186 -299.055772) (xy 387.826856 -299.032175)
			(xy 387.784786 -299.001625) (xy 387.748009 -298.964871) (xy 387.717433 -298.92282) (xy 387.693807 -298.876504)
			(xy 387.677715 -298.827064) (xy 387.669551 -298.775716) (xy 387.669024 -298.74972) (xy 387.669178 -298.736066)
			(xy 387.671467 -298.708852) (xy 387.673596 -298.695364) (xy 387.675628 -298.683426) (xy 387.66877 -298.66082)
			(xy 387.595618 -298.584366) (xy 387.57352 -298.576492) (xy 387.561328 -298.577762) (xy 387.552284 -298.57881)
			(xy 387.53411 -298.579951) (xy 387.525006 -298.580048) (xy 387.500184 -298.579529) (xy 387.451193 -298.571498)
			(xy 387.404148 -298.555647) (xy 387.360286 -298.532393) (xy 387.320765 -298.50235) (xy 387.286625 -298.466308)
			(xy 387.258766 -298.425217) (xy 387.237921 -298.380161) (xy 387.224641 -298.332326) (xy 387.219275 -298.282973)
			(xy 386.879934 -298.282973) (xy 386.879605 -298.299347) (xy 386.87171 -298.347924) (xy 386.856126 -298.394605)
			(xy 386.833255 -298.438182) (xy 386.80369 -298.477526) (xy 386.768197 -298.511618) (xy 386.727694 -298.539574)
			(xy 386.683232 -298.560672) (xy 386.635961 -298.574364) (xy 386.587106 -298.580296) (xy 386.537931 -298.578315)
			(xy 386.489712 -298.568471) (xy 386.443696 -298.551019) (xy 386.401075 -298.526412) (xy 386.362954 -298.495287)
			(xy 386.330319 -298.45845) (xy 386.304016 -298.416854) (xy 386.284725 -298.371578) (xy 386.272948 -298.323794)
			(xy 386.268988 -298.27474) (xy 385.929886 -298.27474) (xy 385.929391 -298.299347) (xy 385.921496 -298.347924)
			(xy 385.905912 -298.394605) (xy 385.883041 -298.438182) (xy 385.853476 -298.477526) (xy 385.817983 -298.511618)
			(xy 385.77748 -298.539574) (xy 385.733018 -298.560672) (xy 385.685747 -298.574364) (xy 385.636892 -298.580296)
			(xy 385.587717 -298.578315) (xy 385.539498 -298.568471) (xy 385.493482 -298.551019) (xy 385.450861 -298.526412)
			(xy 385.41274 -298.495287) (xy 385.380105 -298.45845) (xy 385.353802 -298.416854) (xy 385.334511 -298.371578)
			(xy 385.322734 -298.323794) (xy 385.318774 -298.27474) (xy 384.980175 -298.27474) (xy 384.979685 -298.299093)
			(xy 384.97179 -298.34767) (xy 384.956206 -298.394351) (xy 384.933335 -298.437928) (xy 384.90377 -298.477272)
			(xy 384.868277 -298.511364) (xy 384.827774 -298.53932) (xy 384.783312 -298.560418) (xy 384.736041 -298.57411)
			(xy 384.687186 -298.580042) (xy 384.638011 -298.578061) (xy 384.589792 -298.568217) (xy 384.543776 -298.550765)
			(xy 384.501155 -298.526158) (xy 384.463034 -298.495033) (xy 384.430399 -298.458196) (xy 384.404096 -298.4166)
			(xy 384.384805 -298.371324) (xy 384.373028 -298.32354) (xy 384.369068 -298.274486) (xy 351.03308 -298.274486)
			(xy 351.03308 -299.133514) (xy 374.111518 -299.133514) (xy 374.115589 -299.077892) (xy 374.127715 -299.023455)
			(xy 374.147638 -298.971364) (xy 374.174934 -298.922729) (xy 374.20902 -298.878586) (xy 374.249169 -298.839877)
			(xy 374.294527 -298.807426) (xy 374.344127 -298.781925) (xy 374.396911 -298.763918) (xy 374.451754 -298.753788)
			(xy 374.507488 -298.751751) (xy 374.562925 -298.757851) (xy 374.616882 -298.771957) (xy 374.668211 -298.793769)
			(xy 374.715817 -298.822823) (xy 374.758685 -298.858498) (xy 374.795902 -298.900035) (xy 374.826675 -298.946548)
			(xy 374.850347 -298.997045) (xy 374.866415 -299.050452) (xy 374.874535 -299.105628) (xy 374.875044 -299.133514)
			(xy 375.587004 -299.133514) (xy 375.591075 -299.077892) (xy 375.603201 -299.023455) (xy 375.623124 -298.971364)
			(xy 375.65042 -298.922729) (xy 375.684506 -298.878586) (xy 375.724655 -298.839877) (xy 375.770013 -298.807426)
			(xy 375.819613 -298.781925) (xy 375.872397 -298.763918) (xy 375.92724 -298.753788) (xy 375.982974 -298.751751)
			(xy 376.038411 -298.757851) (xy 376.092368 -298.771957) (xy 376.143697 -298.793769) (xy 376.191303 -298.822823)
			(xy 376.234171 -298.858498) (xy 376.271388 -298.900035) (xy 376.302161 -298.946548) (xy 376.325833 -298.997045)
			(xy 376.341901 -299.050452) (xy 376.350021 -299.105628) (xy 376.35053 -299.133514) (xy 376.476004 -299.133514)
			(xy 376.480075 -299.077892) (xy 376.492201 -299.023455) (xy 376.512124 -298.971364) (xy 376.53942 -298.922729)
			(xy 376.573506 -298.878586) (xy 376.613655 -298.839877) (xy 376.659013 -298.807426) (xy 376.708613 -298.781925)
			(xy 376.761397 -298.763918) (xy 376.81624 -298.753788) (xy 376.871974 -298.751751) (xy 376.927411 -298.757851)
			(xy 376.981368 -298.771957) (xy 377.032697 -298.793769) (xy 377.080303 -298.822823) (xy 377.123171 -298.858498)
			(xy 377.160388 -298.900035) (xy 377.191161 -298.946548) (xy 377.214833 -298.997045) (xy 377.230901 -299.050452)
			(xy 377.239021 -299.105628) (xy 377.23953 -299.133514) (xy 377.239021 -299.1614) (xy 377.230901 -299.216576)
			(xy 377.214833 -299.269983) (xy 377.191161 -299.32048) (xy 377.160388 -299.366993) (xy 377.123171 -299.40853)
			(xy 377.080303 -299.444205) (xy 377.032697 -299.473259) (xy 376.981368 -299.495071) (xy 376.927411 -299.509177)
			(xy 376.871974 -299.515277) (xy 376.81624 -299.51324) (xy 376.761397 -299.50311) (xy 376.708613 -299.485103)
			(xy 376.659013 -299.459602) (xy 376.613655 -299.427151) (xy 376.573506 -299.388442) (xy 376.53942 -299.344299)
			(xy 376.512124 -299.295664) (xy 376.492201 -299.243573) (xy 376.480075 -299.189136) (xy 376.476004 -299.133514)
			(xy 376.35053 -299.133514) (xy 376.350021 -299.1614) (xy 376.341901 -299.216576) (xy 376.325833 -299.269983)
			(xy 376.302161 -299.32048) (xy 376.271388 -299.366993) (xy 376.234171 -299.40853) (xy 376.191303 -299.444205)
			(xy 376.143697 -299.473259) (xy 376.092368 -299.495071) (xy 376.038411 -299.509177) (xy 375.982974 -299.515277)
			(xy 375.92724 -299.51324) (xy 375.872397 -299.50311) (xy 375.819613 -299.485103) (xy 375.770013 -299.459602)
			(xy 375.724655 -299.427151) (xy 375.684506 -299.388442) (xy 375.65042 -299.344299) (xy 375.623124 -299.295664)
			(xy 375.603201 -299.243573) (xy 375.591075 -299.189136) (xy 375.587004 -299.133514) (xy 374.875044 -299.133514)
			(xy 374.874535 -299.1614) (xy 374.866415 -299.216576) (xy 374.850347 -299.269983) (xy 374.826675 -299.32048)
			(xy 374.795902 -299.366993) (xy 374.758685 -299.40853) (xy 374.715817 -299.444205) (xy 374.668211 -299.473259)
			(xy 374.616882 -299.495071) (xy 374.562925 -299.509177) (xy 374.507488 -299.515277) (xy 374.451754 -299.51324)
			(xy 374.396911 -299.50311) (xy 374.344127 -299.485103) (xy 374.294527 -299.459602) (xy 374.249169 -299.427151)
			(xy 374.20902 -299.388442) (xy 374.174934 -299.344299) (xy 374.147638 -299.295664) (xy 374.127715 -299.243573)
			(xy 374.115589 -299.189136) (xy 374.111518 -299.133514) (xy 351.03308 -299.133514) (xy 351.03308 -299.895514)
			(xy 379.638052 -299.895514) (xy 379.638619 -299.866133) (xy 379.647646 -299.808068) (xy 379.665474 -299.752075)
			(xy 379.691681 -299.69948) (xy 379.725646 -299.651528) (xy 379.766565 -299.609354) (xy 379.78969 -299.591222)
			(xy 379.799088 -299.583856) (xy 379.809502 -299.563282) (xy 379.811026 -299.459396) (xy 379.80112 -299.438314)
			(xy 379.791976 -299.430948) (xy 379.770116 -299.412756) (xy 379.731578 -299.370934) (xy 379.699673 -299.323855)
			(xy 379.675108 -299.272563) (xy 379.658427 -299.218193) (xy 379.65 -299.16195) (xy 379.649482 -299.133514)
			(xy 379.649968 -299.106263) (xy 379.657724 -299.052315) (xy 379.673079 -299.00002) (xy 379.695721 -298.950443)
			(xy 379.725187 -298.904593) (xy 379.760878 -298.863402) (xy 379.802069 -298.827711) (xy 379.847919 -298.798245)
			(xy 379.897496 -298.775603) (xy 379.949791 -298.760248) (xy 380.003739 -298.752492) (xy 380.058241 -298.752492)
			(xy 380.112189 -298.760248) (xy 380.164484 -298.775603) (xy 380.214061 -298.798245) (xy 380.259911 -298.827711)
			(xy 380.301102 -298.863402) (xy 380.336793 -298.904593) (xy 380.366259 -298.950443) (xy 380.388901 -299.00002)
			(xy 380.404256 -299.052315) (xy 380.412012 -299.106263) (xy 380.412498 -299.133514) (xy 380.411971 -299.162897)
			(xy 380.402938 -299.220964) (xy 380.401748 -299.2247) (xy 383.734069 -299.2247) (xy 383.73824 -299.174365)
			(xy 383.750638 -299.125402) (xy 383.770925 -299.079148) (xy 383.798549 -299.036864) (xy 383.832755 -298.999703)
			(xy 383.872611 -298.968678) (xy 383.91703 -298.944636) (xy 383.9648 -298.928233) (xy 384.014618 -298.919916)
			(xy 384.039872 -298.919392) (xy 384.065268 -298.919898) (xy 384.115358 -298.928313) (xy 384.163365 -298.944897)
			(xy 384.207968 -298.969196) (xy 384.247936 -299.000538) (xy 384.265424 -299.01896) (xy 384.273044 -299.027342)
			(xy 384.29311 -299.035724) (xy 384.392424 -299.033184) (xy 384.411728 -299.023786) (xy 384.419094 -299.014896)
			(xy 384.434899 -298.996367) (xy 384.47099 -298.963668) (xy 384.511482 -298.936611) (xy 384.555502 -298.915779)
			(xy 384.602099 -298.901621) (xy 384.650268 -298.894444) (xy 384.674618 -298.893992) (xy 385.624578 -298.893992)
			(xy 385.650585 -298.894566) (xy 385.701958 -298.902699) (xy 385.751427 -298.91877) (xy 385.797772 -298.942381)
			(xy 385.839853 -298.972952) (xy 385.876634 -299.00973) (xy 385.907207 -299.051809) (xy 385.930822 -299.098153)
			(xy 385.946896 -299.14762) (xy 385.955033 -299.198993) (xy 385.955033 -299.233291) (xy 386.269089 -299.233291)
			(xy 386.271775 -299.183725) (xy 386.282444 -299.135247) (xy 386.300815 -299.089133) (xy 386.326404 -299.046598)
			(xy 386.358537 -299.008764) (xy 386.396368 -298.976626) (xy 386.438899 -298.951032) (xy 386.485011 -298.932655)
			(xy 386.533488 -298.92198) (xy 386.583053 -298.919288) (xy 386.632401 -298.924651) (xy 386.680232 -298.937925)
			(xy 386.725285 -298.958763) (xy 386.766373 -298.986615) (xy 386.802415 -299.020747) (xy 386.83246 -299.06026)
			(xy 386.855717 -299.104113) (xy 386.871573 -299.151151) (xy 386.87961 -299.200135) (xy 386.8801 -299.224954)
			(xy 386.879917 -299.239137) (xy 386.877249 -299.267377) (xy 386.874766 -299.281342) (xy 386.872579 -299.295304)
			(xy 386.875168 -299.323435) (xy 386.885364 -299.349782) (xy 386.902388 -299.372327) (xy 386.924937 -299.389346)
			(xy 386.951285 -299.399537) (xy 386.979417 -299.40212) (xy 386.993384 -299.39996) (xy 387.007414 -299.39748)
			(xy 387.03578 -299.394805) (xy 387.050026 -299.394626) (xy 387.074844 -299.395106) (xy 387.123825 -299.40314)
			(xy 387.170861 -299.418992) (xy 387.214713 -299.442244) (xy 387.254225 -299.472285) (xy 387.288358 -299.508322)
			(xy 387.316211 -299.549405) (xy 387.33705 -299.594454) (xy 387.350328 -299.642281) (xy 387.355693 -299.691625)
			(xy 387.355242 -299.699934) (xy 387.694182 -299.699934) (xy 387.698142 -299.65088) (xy 387.709919 -299.603096)
			(xy 387.72921 -299.55782) (xy 387.755513 -299.516224) (xy 387.788148 -299.479387) (xy 387.826269 -299.448262)
			(xy 387.86889 -299.423655) (xy 387.914906 -299.406203) (xy 387.963125 -299.396359) (xy 388.0123 -299.394378)
			(xy 388.061155 -299.40031) (xy 388.108426 -299.414002) (xy 388.152888 -299.4351) (xy 388.193391 -299.463056)
			(xy 388.228884 -299.497148) (xy 388.258449 -299.536492) (xy 388.28132 -299.580069) (xy 388.296904 -299.62675)
			(xy 388.304799 -299.675327) (xy 388.305294 -299.699934) (xy 388.304799 -299.724541) (xy 388.296904 -299.773118)
			(xy 388.28132 -299.819799) (xy 388.258449 -299.863376) (xy 388.228884 -299.90272) (xy 388.193391 -299.936812)
			(xy 388.152888 -299.964768) (xy 388.108426 -299.985866) (xy 388.061155 -299.999558) (xy 388.0123 -300.00549)
			(xy 387.963125 -300.003509) (xy 387.914906 -299.993665) (xy 387.86889 -299.976213) (xy 387.826269 -299.951606)
			(xy 387.788148 -299.920481) (xy 387.755513 -299.883644) (xy 387.72921 -299.842048) (xy 387.709919 -299.796772)
			(xy 387.698142 -299.748988) (xy 387.694182 -299.699934) (xy 387.355242 -299.699934) (xy 387.353005 -299.741188)
			(xy 387.342334 -299.789663) (xy 387.323962 -299.835773) (xy 387.298373 -299.878303) (xy 387.26624 -299.916134)
			(xy 387.22841 -299.948268) (xy 387.18588 -299.973859) (xy 387.13977 -299.992232) (xy 387.091296 -300.002904)
			(xy 387.041733 -300.005593) (xy 386.992389 -300.000229) (xy 386.944562 -299.986953) (xy 386.899512 -299.966115)
			(xy 386.858428 -299.938263) (xy 386.82239 -299.904131) (xy 386.792349 -299.864619) (xy 386.769095 -299.820768)
			(xy 386.753242 -299.773732) (xy 386.745206 -299.724752) (xy 386.744718 -299.699934) (xy 386.744899 -299.685751)
			(xy 386.747568 -299.657511) (xy 386.750052 -299.643546) (xy 386.75223 -299.629584) (xy 386.749639 -299.601455)
			(xy 386.739442 -299.575112) (xy 386.72242 -299.552569) (xy 386.699874 -299.53555) (xy 386.673529 -299.525358)
			(xy 386.6454 -299.522771) (xy 386.631434 -299.524928) (xy 386.617406 -299.527419) (xy 386.589038 -299.530087)
			(xy 386.574792 -299.530262) (xy 386.549973 -299.529814) (xy 386.500988 -299.521782) (xy 386.453948 -299.505932)
			(xy 386.410092 -299.48268) (xy 386.370575 -299.45264) (xy 386.336439 -299.416603) (xy 386.308582 -299.375518)
			(xy 386.287738 -299.330468) (xy 386.274458 -299.282639) (xy 386.269089 -299.233291) (xy 385.955033 -299.233291)
			(xy 385.955033 -299.251007) (xy 385.946896 -299.30238) (xy 385.930822 -299.351847) (xy 385.907207 -299.398191)
			(xy 385.876634 -299.44027) (xy 385.839853 -299.477048) (xy 385.797772 -299.507619) (xy 385.751427 -299.53123)
			(xy 385.701958 -299.547301) (xy 385.650585 -299.555434) (xy 385.624578 -299.555916) (xy 384.674618 -299.555916)
			(xy 384.650234 -299.555483) (xy 384.601997 -299.54831) (xy 384.555336 -299.53413) (xy 384.511263 -299.513252)
			(xy 384.470734 -299.486128) (xy 384.434627 -299.453346) (xy 384.41884 -299.434758) (xy 384.411728 -299.426122)
			(xy 384.39217 -299.41647) (xy 384.292856 -299.41393) (xy 384.27279 -299.422312) (xy 384.26517 -299.430694)
			(xy 384.247686 -299.449071) (xy 384.207755 -299.480345) (xy 384.163203 -299.504586) (xy 384.115255 -299.521125)
			(xy 384.065232 -299.529508) (xy 384.039872 -299.530008) (xy 384.014618 -299.529484) (xy 383.9648 -299.521167)
			(xy 383.91703 -299.504764) (xy 383.872611 -299.480722) (xy 383.832755 -299.449697) (xy 383.798549 -299.412536)
			(xy 383.770925 -299.370252) (xy 383.750638 -299.323998) (xy 383.73824 -299.275035) (xy 383.734069 -299.2247)
			(xy 380.401748 -299.2247) (xy 380.385103 -299.276959) (xy 380.358889 -299.329554) (xy 380.324916 -299.377505)
			(xy 380.283989 -299.419676) (xy 380.26086 -299.437806) (xy 380.251462 -299.445172) (xy 380.241048 -299.465746)
			(xy 380.239524 -299.569632) (xy 380.24943 -299.590714) (xy 380.258574 -299.59808) (xy 380.280389 -299.616324)
			(xy 380.318933 -299.658134) (xy 380.350844 -299.705201) (xy 380.375417 -299.756484) (xy 380.392107 -299.810845)
			(xy 380.400545 -299.867081) (xy 380.401068 -299.895514) (xy 381.034542 -299.895514) (xy 381.038613 -299.839892)
			(xy 381.050739 -299.785455) (xy 381.070662 -299.733364) (xy 381.097958 -299.684729) (xy 381.132044 -299.640586)
			(xy 381.172193 -299.601877) (xy 381.217551 -299.569426) (xy 381.267151 -299.543925) (xy 381.319935 -299.525918)
			(xy 381.374778 -299.515788) (xy 381.430512 -299.513751) (xy 381.485949 -299.519851) (xy 381.539906 -299.533957)
			(xy 381.591235 -299.555769) (xy 381.638841 -299.584823) (xy 381.681709 -299.620498) (xy 381.718926 -299.662035)
			(xy 381.749699 -299.708548) (xy 381.773371 -299.759045) (xy 381.789439 -299.812452) (xy 381.797559 -299.867628)
			(xy 381.798068 -299.895514) (xy 381.921002 -299.895514) (xy 381.925073 -299.839892) (xy 381.937199 -299.785455)
			(xy 381.957122 -299.733364) (xy 381.984418 -299.684729) (xy 382.018504 -299.640586) (xy 382.058653 -299.601877)
			(xy 382.104011 -299.569426) (xy 382.153611 -299.543925) (xy 382.206395 -299.525918) (xy 382.261238 -299.515788)
			(xy 382.316972 -299.513751) (xy 382.372409 -299.519851) (xy 382.426366 -299.533957) (xy 382.477695 -299.555769)
			(xy 382.525301 -299.584823) (xy 382.568169 -299.620498) (xy 382.605386 -299.662035) (xy 382.636159 -299.708548)
			(xy 382.659831 -299.759045) (xy 382.675899 -299.812452) (xy 382.684019 -299.867628) (xy 382.684528 -299.895514)
			(xy 382.684019 -299.9234) (xy 382.675899 -299.978576) (xy 382.659831 -300.031983) (xy 382.636159 -300.08248)
			(xy 382.605386 -300.128993) (xy 382.568169 -300.17053) (xy 382.553215 -300.182975) (xy 384.369209 -300.182975)
			(xy 384.371897 -300.133413) (xy 384.382567 -300.084939) (xy 384.400939 -300.038829) (xy 384.426528 -299.996299)
			(xy 384.45866 -299.958469) (xy 384.496489 -299.926335) (xy 384.539019 -299.900744) (xy 384.585127 -299.882371)
			(xy 384.633601 -299.871699) (xy 384.683163 -299.869009) (xy 384.732507 -299.874372) (xy 384.780334 -299.887647)
			(xy 384.825383 -299.908485) (xy 384.866467 -299.936336) (xy 384.902505 -299.970467) (xy 384.932547 -300.009977)
			(xy 384.955801 -300.053828) (xy 384.971655 -300.100863) (xy 384.979691 -300.149843) (xy 384.98018 -300.17466)
			(xy 384.980015 -300.188907) (xy 384.977341 -300.217274) (xy 384.974846 -300.231302) (xy 384.97256 -300.243494)
			(xy 384.979926 -300.267624) (xy 385.057142 -300.34484) (xy 385.081018 -300.352206) (xy 385.093464 -300.34992)
			(xy 385.107429 -300.347439) (xy 385.135669 -300.34477) (xy 385.149852 -300.344586) (xy 385.163966 -300.34472)
			(xy 385.192077 -300.347267) (xy 385.205986 -300.349666) (xy 385.218686 -300.352206) (xy 385.242308 -300.34484)
			(xy 385.319524 -300.26737) (xy 385.32689 -300.243748) (xy 385.324604 -300.231302) (xy 385.322132 -300.217335)
			(xy 385.319457 -300.189096) (xy 385.31927 -300.174914) (xy 385.319792 -300.149659) (xy 385.328105 -300.099837)
			(xy 385.344506 -300.052063) (xy 385.368547 -300.00764) (xy 385.399571 -299.96778) (xy 385.436733 -299.93357)
			(xy 385.479019 -299.905944) (xy 385.525275 -299.885654) (xy 385.57424 -299.873254) (xy 385.624578 -299.869083)
			(xy 385.674916 -299.873254) (xy 385.723881 -299.885654) (xy 385.770137 -299.905944) (xy 385.812423 -299.93357)
			(xy 385.849585 -299.96778) (xy 385.880609 -300.00764) (xy 385.90465 -300.052063) (xy 385.921051 -300.099837)
			(xy 385.929364 -300.149659) (xy 385.929886 -300.174914) (xy 385.929712 -300.189097) (xy 385.927038 -300.217337)
			(xy 385.924552 -300.231302) (xy 385.922266 -300.243748) (xy 385.929632 -300.267624) (xy 386.006848 -300.34484)
			(xy 386.030978 -300.352206) (xy 386.04317 -300.34992) (xy 386.057198 -300.347428) (xy 386.085566 -300.344761)
			(xy 386.099812 -300.344586) (xy 386.124632 -300.345091) (xy 386.173617 -300.353123) (xy 386.220658 -300.368975)
			(xy 386.264514 -300.392228) (xy 386.30403 -300.422271) (xy 386.338166 -300.45831) (xy 386.366022 -300.499397)
			(xy 386.386863 -300.544449) (xy 386.400142 -300.59228) (xy 386.405507 -300.641629) (xy 386.405059 -300.649894)
			(xy 386.744222 -300.649894) (xy 386.748182 -300.60084) (xy 386.759959 -300.553056) (xy 386.77925 -300.50778)
			(xy 386.805553 -300.466184) (xy 386.838188 -300.429347) (xy 386.876309 -300.398222) (xy 386.91893 -300.373615)
			(xy 386.964946 -300.356163) (xy 387.013165 -300.346319) (xy 387.06234 -300.344338) (xy 387.111195 -300.35027)
			(xy 387.158466 -300.363962) (xy 387.202928 -300.38506) (xy 387.243431 -300.413016) (xy 387.278924 -300.447108)
			(xy 387.308489 -300.486452) (xy 387.33136 -300.530029) (xy 387.346944 -300.57671) (xy 387.354839 -300.625287)
			(xy 387.355334 -300.649894) (xy 387.694182 -300.649894) (xy 387.698142 -300.60084) (xy 387.709919 -300.553056)
			(xy 387.72921 -300.50778) (xy 387.755513 -300.466184) (xy 387.788148 -300.429347) (xy 387.826269 -300.398222)
			(xy 387.86889 -300.373615) (xy 387.914906 -300.356163) (xy 387.963125 -300.346319) (xy 388.0123 -300.344338)
			(xy 388.061155 -300.35027) (xy 388.108426 -300.363962) (xy 388.152888 -300.38506) (xy 388.193391 -300.413016)
			(xy 388.228884 -300.447108) (xy 388.258449 -300.486452) (xy 388.28132 -300.530029) (xy 388.296904 -300.57671)
			(xy 388.304799 -300.625287) (xy 388.305294 -300.649894) (xy 388.644142 -300.649894) (xy 388.648102 -300.60084)
			(xy 388.659879 -300.553056) (xy 388.67917 -300.50778) (xy 388.705473 -300.466184) (xy 388.738108 -300.429347)
			(xy 388.776229 -300.398222) (xy 388.81885 -300.373615) (xy 388.864866 -300.356163) (xy 388.913085 -300.346319)
			(xy 388.96226 -300.344338) (xy 389.011115 -300.35027) (xy 389.058386 -300.363962) (xy 389.102848 -300.38506)
			(xy 389.143351 -300.413016) (xy 389.178844 -300.447108) (xy 389.208409 -300.486452) (xy 389.23128 -300.530029)
			(xy 389.246864 -300.57671) (xy 389.254759 -300.625287) (xy 389.255254 -300.649894) (xy 389.594102 -300.649894)
			(xy 389.598062 -300.60084) (xy 389.609839 -300.553056) (xy 389.62913 -300.50778) (xy 389.655433 -300.466184)
			(xy 389.688068 -300.429347) (xy 389.726189 -300.398222) (xy 389.76881 -300.373615) (xy 389.814826 -300.356163)
			(xy 389.863045 -300.346319) (xy 389.91222 -300.344338) (xy 389.961075 -300.35027) (xy 390.008346 -300.363962)
			(xy 390.052808 -300.38506) (xy 390.093311 -300.413016) (xy 390.128804 -300.447108) (xy 390.158369 -300.486452)
			(xy 390.18124 -300.530029) (xy 390.196824 -300.57671) (xy 390.204719 -300.625287) (xy 390.205214 -300.649894)
			(xy 390.204719 -300.674501) (xy 390.196824 -300.723078) (xy 390.18124 -300.769759) (xy 390.158369 -300.813336)
			(xy 390.128804 -300.85268) (xy 390.093311 -300.886772) (xy 390.052808 -300.914728) (xy 390.008346 -300.935826)
			(xy 389.961075 -300.949518) (xy 389.91222 -300.95545) (xy 389.863045 -300.953469) (xy 389.814826 -300.943625)
			(xy 389.76881 -300.926173) (xy 389.726189 -300.901566) (xy 389.688068 -300.870441) (xy 389.655433 -300.833604)
			(xy 389.62913 -300.792008) (xy 389.609839 -300.746732) (xy 389.598062 -300.698948) (xy 389.594102 -300.649894)
			(xy 389.255254 -300.649894) (xy 389.254759 -300.674501) (xy 389.246864 -300.723078) (xy 389.23128 -300.769759)
			(xy 389.208409 -300.813336) (xy 389.178844 -300.85268) (xy 389.143351 -300.886772) (xy 389.102848 -300.914728)
			(xy 389.058386 -300.935826) (xy 389.011115 -300.949518) (xy 388.96226 -300.95545) (xy 388.913085 -300.953469)
			(xy 388.864866 -300.943625) (xy 388.81885 -300.926173) (xy 388.776229 -300.901566) (xy 388.738108 -300.870441)
			(xy 388.705473 -300.833604) (xy 388.67917 -300.792008) (xy 388.659879 -300.746732) (xy 388.648102 -300.698948)
			(xy 388.644142 -300.649894) (xy 388.305294 -300.649894) (xy 388.304799 -300.674501) (xy 388.296904 -300.723078)
			(xy 388.28132 -300.769759) (xy 388.258449 -300.813336) (xy 388.228884 -300.85268) (xy 388.193391 -300.886772)
			(xy 388.152888 -300.914728) (xy 388.108426 -300.935826) (xy 388.061155 -300.949518) (xy 388.0123 -300.95545)
			(xy 387.963125 -300.953469) (xy 387.914906 -300.943625) (xy 387.86889 -300.926173) (xy 387.826269 -300.901566)
			(xy 387.788148 -300.870441) (xy 387.755513 -300.833604) (xy 387.72921 -300.792008) (xy 387.709919 -300.746732)
			(xy 387.698142 -300.698948) (xy 387.694182 -300.649894) (xy 387.355334 -300.649894) (xy 387.354839 -300.674501)
			(xy 387.346944 -300.723078) (xy 387.33136 -300.769759) (xy 387.308489 -300.813336) (xy 387.278924 -300.85268)
			(xy 387.243431 -300.886772) (xy 387.202928 -300.914728) (xy 387.158466 -300.935826) (xy 387.111195 -300.949518)
			(xy 387.06234 -300.95545) (xy 387.013165 -300.953469) (xy 386.964946 -300.943625) (xy 386.91893 -300.926173)
			(xy 386.876309 -300.901566) (xy 386.838188 -300.870441) (xy 386.805553 -300.833604) (xy 386.77925 -300.792008)
			(xy 386.759959 -300.746732) (xy 386.748182 -300.698948) (xy 386.744222 -300.649894) (xy 386.405059 -300.649894)
			(xy 386.402818 -300.691195) (xy 386.392145 -300.739674) (xy 386.373771 -300.785787) (xy 386.348177 -300.828321)
			(xy 386.31604 -300.866153) (xy 386.278206 -300.898288) (xy 386.235671 -300.923879) (xy 386.189557 -300.942251)
			(xy 386.141077 -300.952921) (xy 386.091511 -300.955607) (xy 386.042162 -300.950238) (xy 385.994332 -300.936957)
			(xy 385.949281 -300.916113) (xy 385.908196 -300.888255) (xy 385.872158 -300.854117) (xy 385.842119 -300.814599)
			(xy 385.818868 -300.770741) (xy 385.803019 -300.7237) (xy 385.794989 -300.674714) (xy 385.794504 -300.649894)
			(xy 385.79468 -300.635711) (xy 385.797352 -300.607471) (xy 385.799838 -300.593506) (xy 385.802124 -300.58106)
			(xy 385.794758 -300.557184) (xy 385.717542 -300.479968) (xy 385.693412 -300.472602) (xy 385.68122 -300.474888)
			(xy 385.66719 -300.477368) (xy 385.638824 -300.480043) (xy 385.624578 -300.480222) (xy 385.610465 -300.480084)
			(xy 385.582353 -300.47754) (xy 385.568444 -300.475142) (xy 385.555744 -300.472602) (xy 385.532122 -300.479968)
			(xy 385.454906 -300.557438) (xy 385.44754 -300.58106) (xy 385.449826 -300.593506) (xy 385.4523 -300.607472)
			(xy 385.454973 -300.635712) (xy 385.45516 -300.649894) (xy 385.454638 -300.675149) (xy 385.446325 -300.724971)
			(xy 385.429924 -300.772745) (xy 385.405883 -300.817168) (xy 385.374859 -300.857028) (xy 385.337697 -300.891238)
			(xy 385.295411 -300.918864) (xy 385.249155 -300.939154) (xy 385.20019 -300.951554) (xy 385.149852 -300.955725)
			(xy 385.099514 -300.951554) (xy 385.050549 -300.939154) (xy 385.004293 -300.918864) (xy 384.962007 -300.891238)
			(xy 384.924845 -300.857028) (xy 384.893821 -300.817168) (xy 384.86978 -300.772745) (xy 384.853379 -300.724971)
			(xy 384.845066 -300.675149) (xy 384.844544 -300.649894) (xy 384.844711 -300.635647) (xy 384.84738 -300.607279)
			(xy 384.849878 -300.593252) (xy 384.852164 -300.58106) (xy 384.844798 -300.55693) (xy 384.767582 -300.479714)
			(xy 384.743706 -300.472348) (xy 384.73126 -300.474634) (xy 384.717294 -300.477111) (xy 384.689055 -300.479783)
			(xy 384.674872 -300.479968) (xy 384.650055 -300.479492) (xy 384.601074 -300.471458) (xy 384.554039 -300.455606)
			(xy 384.510188 -300.432353) (xy 384.470675 -300.402313) (xy 384.436544 -300.366277) (xy 384.408691 -300.325193)
			(xy 384.387852 -300.280145) (xy 384.374574 -300.232319) (xy 384.369209 -300.182975) (xy 382.553215 -300.182975)
			(xy 382.525301 -300.206205) (xy 382.477695 -300.235259) (xy 382.426366 -300.257071) (xy 382.372409 -300.271177)
			(xy 382.316972 -300.277277) (xy 382.261238 -300.27524) (xy 382.206395 -300.26511) (xy 382.153611 -300.247103)
			(xy 382.104011 -300.221602) (xy 382.058653 -300.189151) (xy 382.018504 -300.150442) (xy 381.984418 -300.106299)
			(xy 381.957122 -300.057664) (xy 381.937199 -300.005573) (xy 381.925073 -299.951136) (xy 381.921002 -299.895514)
			(xy 381.798068 -299.895514) (xy 381.797559 -299.9234) (xy 381.789439 -299.978576) (xy 381.773371 -300.031983)
			(xy 381.749699 -300.08248) (xy 381.718926 -300.128993) (xy 381.681709 -300.17053) (xy 381.638841 -300.206205)
			(xy 381.591235 -300.235259) (xy 381.539906 -300.257071) (xy 381.485949 -300.271177) (xy 381.430512 -300.277277)
			(xy 381.374778 -300.27524) (xy 381.319935 -300.26511) (xy 381.267151 -300.247103) (xy 381.217551 -300.221602)
			(xy 381.172193 -300.189151) (xy 381.132044 -300.150442) (xy 381.097958 -300.106299) (xy 381.070662 -300.057664)
			(xy 381.050739 -300.005573) (xy 381.038613 -299.951136) (xy 381.034542 -299.895514) (xy 380.401068 -299.895514)
			(xy 380.400582 -299.922765) (xy 380.392826 -299.976713) (xy 380.377471 -300.029008) (xy 380.354829 -300.078585)
			(xy 380.325363 -300.124435) (xy 380.289672 -300.165626) (xy 380.248481 -300.201317) (xy 380.202631 -300.230783)
			(xy 380.153054 -300.253425) (xy 380.100759 -300.26878) (xy 380.046811 -300.276536) (xy 379.992309 -300.276536)
			(xy 379.938361 -300.26878) (xy 379.886066 -300.253425) (xy 379.836489 -300.230783) (xy 379.790639 -300.201317)
			(xy 379.749448 -300.165626) (xy 379.713757 -300.124435) (xy 379.684291 -300.078585) (xy 379.661649 -300.029008)
			(xy 379.646294 -299.976713) (xy 379.638538 -299.922765) (xy 379.638052 -299.895514) (xy 351.03308 -299.895514)
			(xy 351.03308 -301.031656) (xy 374.111518 -301.031656) (xy 374.115589 -300.976034) (xy 374.127715 -300.921597)
			(xy 374.147638 -300.869506) (xy 374.174934 -300.820871) (xy 374.20902 -300.776728) (xy 374.249169 -300.738019)
			(xy 374.294527 -300.705568) (xy 374.344127 -300.680067) (xy 374.396911 -300.66206) (xy 374.451754 -300.65193)
			(xy 374.507488 -300.649893) (xy 374.562925 -300.655993) (xy 374.616882 -300.670099) (xy 374.668211 -300.691911)
			(xy 374.715817 -300.720965) (xy 374.758685 -300.75664) (xy 374.795902 -300.798177) (xy 374.826675 -300.84469)
			(xy 374.850347 -300.895187) (xy 374.866415 -300.948594) (xy 374.874535 -301.00377) (xy 374.875044 -301.031656)
			(xy 375.596656 -301.031656) (xy 375.600727 -300.976034) (xy 375.612853 -300.921597) (xy 375.632776 -300.869506)
			(xy 375.660072 -300.820871) (xy 375.694158 -300.776728) (xy 375.734307 -300.738019) (xy 375.779665 -300.705568)
			(xy 375.829265 -300.680067) (xy 375.882049 -300.66206) (xy 375.936892 -300.65193) (xy 375.992626 -300.649893)
			(xy 376.048063 -300.655993) (xy 376.10202 -300.670099) (xy 376.153349 -300.691911) (xy 376.200955 -300.720965)
			(xy 376.243823 -300.75664) (xy 376.28104 -300.798177) (xy 376.311813 -300.84469) (xy 376.335485 -300.895187)
			(xy 376.351553 -300.948594) (xy 376.359673 -301.00377) (xy 376.360182 -301.031656) (xy 376.359673 -301.059542)
			(xy 376.351553 -301.114718) (xy 376.335485 -301.168125) (xy 376.311813 -301.218622) (xy 376.28104 -301.265135)
			(xy 376.243823 -301.306672) (xy 376.200955 -301.342347) (xy 376.153349 -301.371401) (xy 376.10202 -301.393213)
			(xy 376.048063 -301.407319) (xy 375.992626 -301.413419) (xy 375.936892 -301.411382) (xy 375.882049 -301.401252)
			(xy 375.829265 -301.383245) (xy 375.779665 -301.357744) (xy 375.734307 -301.325293) (xy 375.694158 -301.286584)
			(xy 375.660072 -301.242441) (xy 375.632776 -301.193806) (xy 375.612853 -301.141715) (xy 375.600727 -301.087278)
			(xy 375.596656 -301.031656) (xy 374.875044 -301.031656) (xy 374.874535 -301.059542) (xy 374.866415 -301.114718)
			(xy 374.850347 -301.168125) (xy 374.826675 -301.218622) (xy 374.795902 -301.265135) (xy 374.758685 -301.306672)
			(xy 374.715817 -301.342347) (xy 374.668211 -301.371401) (xy 374.616882 -301.393213) (xy 374.562925 -301.407319)
			(xy 374.507488 -301.413419) (xy 374.451754 -301.411382) (xy 374.396911 -301.401252) (xy 374.344127 -301.383245)
			(xy 374.294527 -301.357744) (xy 374.249169 -301.325293) (xy 374.20902 -301.286584) (xy 374.174934 -301.242441)
			(xy 374.147638 -301.193806) (xy 374.127715 -301.141715) (xy 374.115589 -301.087278) (xy 374.111518 -301.031656)
			(xy 351.03308 -301.031656) (xy 351.03308 -301.599854) (xy 384.844048 -301.599854) (xy 384.848008 -301.5508)
			(xy 384.859785 -301.503016) (xy 384.879076 -301.45774) (xy 384.905379 -301.416144) (xy 384.938014 -301.379307)
			(xy 384.976135 -301.348182) (xy 385.018756 -301.323575) (xy 385.064772 -301.306123) (xy 385.112991 -301.296279)
			(xy 385.162166 -301.294298) (xy 385.211021 -301.30023) (xy 385.258292 -301.313922) (xy 385.302754 -301.33502)
			(xy 385.343257 -301.362976) (xy 385.37875 -301.397068) (xy 385.408315 -301.436412) (xy 385.431186 -301.479989)
			(xy 385.44677 -301.52667) (xy 385.454665 -301.575247) (xy 385.45516 -301.599854) (xy 385.794008 -301.599854)
			(xy 385.797968 -301.5508) (xy 385.809745 -301.503016) (xy 385.829036 -301.45774) (xy 385.855339 -301.416144)
			(xy 385.887974 -301.379307) (xy 385.926095 -301.348182) (xy 385.968716 -301.323575) (xy 386.014732 -301.306123)
			(xy 386.062951 -301.296279) (xy 386.112126 -301.294298) (xy 386.160981 -301.30023) (xy 386.208252 -301.313922)
			(xy 386.252714 -301.33502) (xy 386.293217 -301.362976) (xy 386.32871 -301.397068) (xy 386.358275 -301.436412)
			(xy 386.381146 -301.479989) (xy 386.39673 -301.52667) (xy 386.404625 -301.575247) (xy 386.40512 -301.599854)
			(xy 386.404625 -301.624461) (xy 386.404446 -301.625562) (xy 386.723378 -301.625562) (xy 386.723378 -301.574146)
			(xy 386.731421 -301.523364) (xy 386.747309 -301.474465) (xy 386.770652 -301.428653) (xy 386.800873 -301.387057)
			(xy 386.837229 -301.350701) (xy 386.878825 -301.32048) (xy 386.924637 -301.297137) (xy 386.973536 -301.281249)
			(xy 387.024318 -301.273206) (xy 387.075734 -301.273206) (xy 387.126516 -301.281249) (xy 387.175415 -301.297137)
			(xy 387.221227 -301.32048) (xy 387.262823 -301.350701) (xy 387.299179 -301.387057) (xy 387.3294 -301.428653)
			(xy 387.352743 -301.474465) (xy 387.368631 -301.523364) (xy 387.376674 -301.574146) (xy 387.377178 -301.599854)
			(xy 387.376674 -301.625562) (xy 387.673338 -301.625562) (xy 387.673338 -301.574146) (xy 387.681381 -301.523364)
			(xy 387.697269 -301.474465) (xy 387.720612 -301.428653) (xy 387.750833 -301.387057) (xy 387.787189 -301.350701)
			(xy 387.828785 -301.32048) (xy 387.874597 -301.297137) (xy 387.923496 -301.281249) (xy 387.974278 -301.273206)
			(xy 388.025694 -301.273206) (xy 388.076476 -301.281249) (xy 388.125375 -301.297137) (xy 388.171187 -301.32048)
			(xy 388.212783 -301.350701) (xy 388.249139 -301.387057) (xy 388.27936 -301.428653) (xy 388.302703 -301.474465)
			(xy 388.318591 -301.523364) (xy 388.326634 -301.574146) (xy 388.327138 -301.599854) (xy 388.644142 -301.599854)
			(xy 388.648102 -301.5508) (xy 388.659879 -301.503016) (xy 388.67917 -301.45774) (xy 388.705473 -301.416144)
			(xy 388.738108 -301.379307) (xy 388.776229 -301.348182) (xy 388.81885 -301.323575) (xy 388.864866 -301.306123)
			(xy 388.913085 -301.296279) (xy 388.96226 -301.294298) (xy 389.011115 -301.30023) (xy 389.058386 -301.313922)
			(xy 389.102848 -301.33502) (xy 389.143351 -301.362976) (xy 389.178844 -301.397068) (xy 389.208409 -301.436412)
			(xy 389.23128 -301.479989) (xy 389.246864 -301.52667) (xy 389.254759 -301.575247) (xy 389.255254 -301.599854)
			(xy 389.254759 -301.624461) (xy 389.25458 -301.625562) (xy 389.573258 -301.625562) (xy 389.573258 -301.574146)
			(xy 389.581301 -301.523364) (xy 389.597189 -301.474465) (xy 389.620532 -301.428653) (xy 389.650753 -301.387057)
			(xy 389.687109 -301.350701) (xy 389.728705 -301.32048) (xy 389.774517 -301.297137) (xy 389.823416 -301.281249)
			(xy 389.874198 -301.273206) (xy 389.925614 -301.273206) (xy 389.976396 -301.281249) (xy 390.025295 -301.297137)
			(xy 390.071107 -301.32048) (xy 390.112703 -301.350701) (xy 390.149059 -301.387057) (xy 390.17928 -301.428653)
			(xy 390.202623 -301.474465) (xy 390.218511 -301.523364) (xy 390.226554 -301.574146) (xy 390.227058 -301.599854)
			(xy 390.226554 -301.625562) (xy 390.523218 -301.625562) (xy 390.523218 -301.574146) (xy 390.531261 -301.523364)
			(xy 390.547149 -301.474465) (xy 390.570492 -301.428653) (xy 390.600713 -301.387057) (xy 390.637069 -301.350701)
			(xy 390.678665 -301.32048) (xy 390.724477 -301.297137) (xy 390.773376 -301.281249) (xy 390.824158 -301.273206)
			(xy 390.875574 -301.273206) (xy 390.926356 -301.281249) (xy 390.975255 -301.297137) (xy 391.021067 -301.32048)
			(xy 391.062663 -301.350701) (xy 391.099019 -301.387057) (xy 391.12924 -301.428653) (xy 391.152583 -301.474465)
			(xy 391.168471 -301.523364) (xy 391.176514 -301.574146) (xy 391.177018 -301.599854) (xy 391.494022 -301.599854)
			(xy 391.497982 -301.5508) (xy 391.509759 -301.503016) (xy 391.52905 -301.45774) (xy 391.555353 -301.416144)
			(xy 391.587988 -301.379307) (xy 391.626109 -301.348182) (xy 391.66873 -301.323575) (xy 391.714746 -301.306123)
			(xy 391.762965 -301.296279) (xy 391.81214 -301.294298) (xy 391.860995 -301.30023) (xy 391.908266 -301.313922)
			(xy 391.952728 -301.33502) (xy 391.993231 -301.362976) (xy 392.028724 -301.397068) (xy 392.058289 -301.436412)
			(xy 392.08116 -301.479989) (xy 392.096744 -301.52667) (xy 392.104639 -301.575247) (xy 392.104969 -301.591642)
			(xy 392.444034 -301.591642) (xy 392.449398 -301.542282) (xy 392.462678 -301.49444) (xy 392.483522 -301.449377)
			(xy 392.511382 -301.40828) (xy 392.545525 -301.372232) (xy 392.585049 -301.342183) (xy 392.628914 -301.318924)
			(xy 392.675965 -301.303068) (xy 392.724961 -301.295033) (xy 392.749786 -301.294546) (xy 392.764033 -301.294716)
			(xy 392.792401 -301.297383) (xy 392.806428 -301.29988) (xy 392.81862 -301.302166) (xy 392.84275 -301.2948)
			(xy 392.919966 -301.217584) (xy 392.927332 -301.193708) (xy 392.925046 -301.181262) (xy 392.922569 -301.167296)
			(xy 392.919897 -301.139057) (xy 392.919712 -301.124874) (xy 392.920234 -301.099619) (xy 392.928547 -301.049797)
			(xy 392.944948 -301.002023) (xy 392.968989 -300.9576) (xy 393.000013 -300.91774) (xy 393.037175 -300.88353)
			(xy 393.079461 -300.855904) (xy 393.125717 -300.835614) (xy 393.174682 -300.823214) (xy 393.22502 -300.819043)
			(xy 393.275358 -300.823214) (xy 393.324323 -300.835614) (xy 393.370579 -300.855904) (xy 393.412865 -300.88353)
			(xy 393.450027 -300.91774) (xy 393.481051 -300.9576) (xy 393.505092 -301.002023) (xy 393.521493 -301.049797)
			(xy 393.529806 -301.099619) (xy 393.530328 -301.124874) (xy 393.530147 -301.139057) (xy 393.527478 -301.167297)
			(xy 393.524994 -301.181262) (xy 393.522708 -301.193708) (xy 393.530074 -301.21733) (xy 393.607544 -301.2948)
			(xy 393.631166 -301.302166) (xy 393.643612 -301.29988) (xy 393.657578 -301.297406) (xy 393.685818 -301.294732)
			(xy 393.7 -301.294546) (xy 393.714183 -301.294723) (xy 393.742423 -301.297395) (xy 393.756388 -301.29988)
			(xy 393.768834 -301.302166) (xy 393.792456 -301.2948) (xy 393.869926 -301.21733) (xy 393.877292 -301.193708)
			(xy 393.875006 -301.181262) (xy 393.872528 -301.167296) (xy 393.869857 -301.139057) (xy 393.869672 -301.124874)
			(xy 393.870206 -301.100055) (xy 393.87824 -301.051073) (xy 393.894094 -301.004035) (xy 393.917348 -300.960182)
			(xy 393.94739 -300.920668) (xy 393.98343 -300.886536) (xy 394.024516 -300.858683) (xy 394.069567 -300.837845)
			(xy 394.117396 -300.824569) (xy 394.166743 -300.819206) (xy 394.216307 -300.821898) (xy 394.264783 -300.832572)
			(xy 394.310894 -300.850948) (xy 394.353424 -300.876542) (xy 394.391253 -300.90868) (xy 394.423385 -300.946514)
			(xy 394.448972 -300.989048) (xy 394.467342 -301.035161) (xy 394.478009 -301.083638) (xy 394.480241 -301.124874)
			(xy 394.819136 -301.124874) (xy 394.823096 -301.07582) (xy 394.834873 -301.028036) (xy 394.854164 -300.98276)
			(xy 394.880467 -300.941164) (xy 394.913102 -300.904327) (xy 394.951223 -300.873202) (xy 394.993844 -300.848595)
			(xy 395.03986 -300.831143) (xy 395.088079 -300.821299) (xy 395.137254 -300.819318) (xy 395.186109 -300.82525)
			(xy 395.23338 -300.838942) (xy 395.277842 -300.86004) (xy 395.318345 -300.887996) (xy 395.353838 -300.922088)
			(xy 395.383403 -300.961432) (xy 395.406274 -301.005009) (xy 395.421858 -301.05169) (xy 395.429753 -301.100267)
			(xy 395.430248 -301.124874) (xy 395.769096 -301.124874) (xy 395.773056 -301.07582) (xy 395.784833 -301.028036)
			(xy 395.804124 -300.98276) (xy 395.830427 -300.941164) (xy 395.863062 -300.904327) (xy 395.901183 -300.873202)
			(xy 395.943804 -300.848595) (xy 395.98982 -300.831143) (xy 396.038039 -300.821299) (xy 396.087214 -300.819318)
			(xy 396.136069 -300.82525) (xy 396.18334 -300.838942) (xy 396.227802 -300.86004) (xy 396.268305 -300.887996)
			(xy 396.303798 -300.922088) (xy 396.333363 -300.961432) (xy 396.356234 -301.005009) (xy 396.371818 -301.05169)
			(xy 396.379713 -301.100267) (xy 396.380208 -301.124874) (xy 397.669016 -301.124874) (xy 397.672976 -301.07582)
			(xy 397.684753 -301.028036) (xy 397.704044 -300.98276) (xy 397.730347 -300.941164) (xy 397.762982 -300.904327)
			(xy 397.801103 -300.873202) (xy 397.843724 -300.848595) (xy 397.88974 -300.831143) (xy 397.937959 -300.821299)
			(xy 397.987134 -300.819318) (xy 398.035989 -300.82525) (xy 398.08326 -300.838942) (xy 398.127722 -300.86004)
			(xy 398.168225 -300.887996) (xy 398.203718 -300.922088) (xy 398.233283 -300.961432) (xy 398.256154 -301.005009)
			(xy 398.271738 -301.05169) (xy 398.279633 -301.100267) (xy 398.280128 -301.124874) (xy 398.61923 -301.124874)
			(xy 398.62319 -301.07582) (xy 398.634967 -301.028036) (xy 398.654258 -300.98276) (xy 398.680561 -300.941164)
			(xy 398.713196 -300.904327) (xy 398.751317 -300.873202) (xy 398.793938 -300.848595) (xy 398.839954 -300.831143)
			(xy 398.888173 -300.821299) (xy 398.937348 -300.819318) (xy 398.986203 -300.82525) (xy 399.033474 -300.838942)
			(xy 399.077936 -300.86004) (xy 399.118439 -300.887996) (xy 399.153932 -300.922088) (xy 399.183497 -300.961432)
			(xy 399.206368 -301.005009) (xy 399.221952 -301.05169) (xy 399.229847 -301.100267) (xy 399.230342 -301.124874)
			(xy 399.56919 -301.124874) (xy 399.57315 -301.07582) (xy 399.584927 -301.028036) (xy 399.604218 -300.98276)
			(xy 399.630521 -300.941164) (xy 399.663156 -300.904327) (xy 399.701277 -300.873202) (xy 399.743898 -300.848595)
			(xy 399.789914 -300.831143) (xy 399.838133 -300.821299) (xy 399.887308 -300.819318) (xy 399.936163 -300.82525)
			(xy 399.983434 -300.838942) (xy 400.027896 -300.86004) (xy 400.068399 -300.887996) (xy 400.103892 -300.922088)
			(xy 400.133457 -300.961432) (xy 400.156328 -301.005009) (xy 400.171912 -301.05169) (xy 400.179807 -301.100267)
			(xy 400.180302 -301.124874) (xy 400.51915 -301.124874) (xy 400.52311 -301.07582) (xy 400.534887 -301.028036)
			(xy 400.554178 -300.98276) (xy 400.580481 -300.941164) (xy 400.613116 -300.904327) (xy 400.651237 -300.873202)
			(xy 400.693858 -300.848595) (xy 400.739874 -300.831143) (xy 400.788093 -300.821299) (xy 400.837268 -300.819318)
			(xy 400.886123 -300.82525) (xy 400.933394 -300.838942) (xy 400.977856 -300.86004) (xy 401.018359 -300.887996)
			(xy 401.053852 -300.922088) (xy 401.083417 -300.961432) (xy 401.106288 -301.005009) (xy 401.121872 -301.05169)
			(xy 401.129767 -301.100267) (xy 401.130262 -301.124874) (xy 401.46911 -301.124874) (xy 401.47307 -301.07582)
			(xy 401.484847 -301.028036) (xy 401.504138 -300.98276) (xy 401.530441 -300.941164) (xy 401.563076 -300.904327)
			(xy 401.601197 -300.873202) (xy 401.643818 -300.848595) (xy 401.689834 -300.831143) (xy 401.738053 -300.821299)
			(xy 401.787228 -300.819318) (xy 401.836083 -300.82525) (xy 401.883354 -300.838942) (xy 401.927816 -300.86004)
			(xy 401.968319 -300.887996) (xy 402.003812 -300.922088) (xy 402.033377 -300.961432) (xy 402.056248 -301.005009)
			(xy 402.071832 -301.05169) (xy 402.079727 -301.100267) (xy 402.080222 -301.124874) (xy 402.41907 -301.124874)
			(xy 402.42303 -301.07582) (xy 402.434807 -301.028036) (xy 402.454098 -300.98276) (xy 402.480401 -300.941164)
			(xy 402.513036 -300.904327) (xy 402.551157 -300.873202) (xy 402.593778 -300.848595) (xy 402.639794 -300.831143)
			(xy 402.688013 -300.821299) (xy 402.737188 -300.819318) (xy 402.786043 -300.82525) (xy 402.833314 -300.838942)
			(xy 402.877776 -300.86004) (xy 402.918279 -300.887996) (xy 402.953772 -300.922088) (xy 402.983337 -300.961432)
			(xy 403.006208 -301.005009) (xy 403.021792 -301.05169) (xy 403.029687 -301.100267) (xy 403.030182 -301.124874)
			(xy 403.36903 -301.124874) (xy 403.37299 -301.07582) (xy 403.384767 -301.028036) (xy 403.404058 -300.98276)
			(xy 403.430361 -300.941164) (xy 403.462996 -300.904327) (xy 403.501117 -300.873202) (xy 403.543738 -300.848595)
			(xy 403.589754 -300.831143) (xy 403.637973 -300.821299) (xy 403.687148 -300.819318) (xy 403.736003 -300.82525)
			(xy 403.783274 -300.838942) (xy 403.827736 -300.86004) (xy 403.868239 -300.887996) (xy 403.903732 -300.922088)
			(xy 403.933297 -300.961432) (xy 403.956168 -301.005009) (xy 403.971752 -301.05169) (xy 403.979647 -301.100267)
			(xy 403.980142 -301.124874) (xy 404.31899 -301.124874) (xy 404.32295 -301.07582) (xy 404.334727 -301.028036)
			(xy 404.354018 -300.98276) (xy 404.380321 -300.941164) (xy 404.412956 -300.904327) (xy 404.451077 -300.873202)
			(xy 404.493698 -300.848595) (xy 404.539714 -300.831143) (xy 404.587933 -300.821299) (xy 404.637108 -300.819318)
			(xy 404.685963 -300.82525) (xy 404.733234 -300.838942) (xy 404.777696 -300.86004) (xy 404.818199 -300.887996)
			(xy 404.853692 -300.922088) (xy 404.883257 -300.961432) (xy 404.906128 -301.005009) (xy 404.921712 -301.05169)
			(xy 404.929607 -301.100267) (xy 404.930102 -301.124874) (xy 405.269204 -301.124874) (xy 405.273164 -301.07582)
			(xy 405.284941 -301.028036) (xy 405.304232 -300.98276) (xy 405.330535 -300.941164) (xy 405.36317 -300.904327)
			(xy 405.401291 -300.873202) (xy 405.443912 -300.848595) (xy 405.489928 -300.831143) (xy 405.538147 -300.821299)
			(xy 405.587322 -300.819318) (xy 405.636177 -300.82525) (xy 405.683448 -300.838942) (xy 405.72791 -300.86004)
			(xy 405.768413 -300.887996) (xy 405.803906 -300.922088) (xy 405.833471 -300.961432) (xy 405.856342 -301.005009)
			(xy 405.871926 -301.05169) (xy 405.879821 -301.100267) (xy 405.880316 -301.124874) (xy 406.219164 -301.124874)
			(xy 406.223124 -301.07582) (xy 406.234901 -301.028036) (xy 406.254192 -300.98276) (xy 406.280495 -300.941164)
			(xy 406.31313 -300.904327) (xy 406.351251 -300.873202) (xy 406.393872 -300.848595) (xy 406.439888 -300.831143)
			(xy 406.488107 -300.821299) (xy 406.537282 -300.819318) (xy 406.586137 -300.82525) (xy 406.633408 -300.838942)
			(xy 406.67787 -300.86004) (xy 406.718373 -300.887996) (xy 406.753866 -300.922088) (xy 406.783431 -300.961432)
			(xy 406.806302 -301.005009) (xy 406.821886 -301.05169) (xy 406.829781 -301.100267) (xy 406.830276 -301.124874)
			(xy 408.119084 -301.124874) (xy 408.123044 -301.07582) (xy 408.134821 -301.028036) (xy 408.154112 -300.98276)
			(xy 408.180415 -300.941164) (xy 408.21305 -300.904327) (xy 408.251171 -300.873202) (xy 408.293792 -300.848595)
			(xy 408.339808 -300.831143) (xy 408.388027 -300.821299) (xy 408.437202 -300.819318) (xy 408.486057 -300.82525)
			(xy 408.533328 -300.838942) (xy 408.57779 -300.86004) (xy 408.618293 -300.887996) (xy 408.653786 -300.922088)
			(xy 408.683351 -300.961432) (xy 408.706222 -301.005009) (xy 408.721806 -301.05169) (xy 408.729701 -301.100267)
			(xy 408.730196 -301.124874) (xy 409.069044 -301.124874) (xy 409.073004 -301.07582) (xy 409.084781 -301.028036)
			(xy 409.104072 -300.98276) (xy 409.130375 -300.941164) (xy 409.16301 -300.904327) (xy 409.201131 -300.873202)
			(xy 409.243752 -300.848595) (xy 409.289768 -300.831143) (xy 409.337987 -300.821299) (xy 409.387162 -300.819318)
			(xy 409.436017 -300.82525) (xy 409.483288 -300.838942) (xy 409.52775 -300.86004) (xy 409.568253 -300.887996)
			(xy 409.603746 -300.922088) (xy 409.633311 -300.961432) (xy 409.656182 -301.005009) (xy 409.671766 -301.05169)
			(xy 409.679661 -301.100267) (xy 409.680156 -301.124874) (xy 410.019004 -301.124874) (xy 410.022964 -301.07582)
			(xy 410.034741 -301.028036) (xy 410.054032 -300.98276) (xy 410.080335 -300.941164) (xy 410.11297 -300.904327)
			(xy 410.151091 -300.873202) (xy 410.193712 -300.848595) (xy 410.239728 -300.831143) (xy 410.287947 -300.821299)
			(xy 410.337122 -300.819318) (xy 410.385977 -300.82525) (xy 410.433248 -300.838942) (xy 410.47771 -300.86004)
			(xy 410.518213 -300.887996) (xy 410.553706 -300.922088) (xy 410.583271 -300.961432) (xy 410.606142 -301.005009)
			(xy 410.621726 -301.05169) (xy 410.629621 -301.100267) (xy 410.630116 -301.124874) (xy 410.969218 -301.124874)
			(xy 410.973178 -301.07582) (xy 410.984955 -301.028036) (xy 411.004246 -300.98276) (xy 411.030549 -300.941164)
			(xy 411.063184 -300.904327) (xy 411.101305 -300.873202) (xy 411.143926 -300.848595) (xy 411.189942 -300.831143)
			(xy 411.238161 -300.821299) (xy 411.287336 -300.819318) (xy 411.336191 -300.82525) (xy 411.383462 -300.838942)
			(xy 411.427924 -300.86004) (xy 411.468427 -300.887996) (xy 411.50392 -300.922088) (xy 411.533485 -300.961432)
			(xy 411.556356 -301.005009) (xy 411.57194 -301.05169) (xy 411.579835 -301.100267) (xy 411.58033 -301.124874)
			(xy 411.919178 -301.124874) (xy 411.923138 -301.07582) (xy 411.934915 -301.028036) (xy 411.954206 -300.98276)
			(xy 411.980509 -300.941164) (xy 412.013144 -300.904327) (xy 412.051265 -300.873202) (xy 412.093886 -300.848595)
			(xy 412.139902 -300.831143) (xy 412.188121 -300.821299) (xy 412.237296 -300.819318) (xy 412.286151 -300.82525)
			(xy 412.333422 -300.838942) (xy 412.377884 -300.86004) (xy 412.418387 -300.887996) (xy 412.45388 -300.922088)
			(xy 412.483445 -300.961432) (xy 412.506316 -301.005009) (xy 412.5219 -301.05169) (xy 412.529795 -301.100267)
			(xy 412.53029 -301.124874) (xy 412.869138 -301.124874) (xy 412.873098 -301.07582) (xy 412.884875 -301.028036)
			(xy 412.904166 -300.98276) (xy 412.930469 -300.941164) (xy 412.963104 -300.904327) (xy 413.001225 -300.873202)
			(xy 413.043846 -300.848595) (xy 413.089862 -300.831143) (xy 413.138081 -300.821299) (xy 413.187256 -300.819318)
			(xy 413.236111 -300.82525) (xy 413.283382 -300.838942) (xy 413.327844 -300.86004) (xy 413.368347 -300.887996)
			(xy 413.40384 -300.922088) (xy 413.433405 -300.961432) (xy 413.456276 -301.005009) (xy 413.47186 -301.05169)
			(xy 413.479755 -301.100267) (xy 413.48025 -301.124874) (xy 413.819098 -301.124874) (xy 413.823058 -301.07582)
			(xy 413.834835 -301.028036) (xy 413.854126 -300.98276) (xy 413.880429 -300.941164) (xy 413.913064 -300.904327)
			(xy 413.951185 -300.873202) (xy 413.993806 -300.848595) (xy 414.039822 -300.831143) (xy 414.088041 -300.821299)
			(xy 414.137216 -300.819318) (xy 414.186071 -300.82525) (xy 414.233342 -300.838942) (xy 414.277804 -300.86004)
			(xy 414.318307 -300.887996) (xy 414.3538 -300.922088) (xy 414.383365 -300.961432) (xy 414.406236 -301.005009)
			(xy 414.42182 -301.05169) (xy 414.429715 -301.100267) (xy 414.43021 -301.124874) (xy 414.769058 -301.124874)
			(xy 414.773018 -301.07582) (xy 414.784795 -301.028036) (xy 414.804086 -300.98276) (xy 414.830389 -300.941164)
			(xy 414.863024 -300.904327) (xy 414.901145 -300.873202) (xy 414.943766 -300.848595) (xy 414.989782 -300.831143)
			(xy 415.038001 -300.821299) (xy 415.087176 -300.819318) (xy 415.136031 -300.82525) (xy 415.183302 -300.838942)
			(xy 415.227764 -300.86004) (xy 415.268267 -300.887996) (xy 415.30376 -300.922088) (xy 415.333325 -300.961432)
			(xy 415.356196 -301.005009) (xy 415.37178 -301.05169) (xy 415.379675 -301.100267) (xy 415.38017 -301.124874)
			(xy 415.719018 -301.124874) (xy 415.722978 -301.07582) (xy 415.734755 -301.028036) (xy 415.754046 -300.98276)
			(xy 415.780349 -300.941164) (xy 415.812984 -300.904327) (xy 415.851105 -300.873202) (xy 415.893726 -300.848595)
			(xy 415.939742 -300.831143) (xy 415.987961 -300.821299) (xy 416.037136 -300.819318) (xy 416.085991 -300.82525)
			(xy 416.133262 -300.838942) (xy 416.177724 -300.86004) (xy 416.218227 -300.887996) (xy 416.25372 -300.922088)
			(xy 416.283285 -300.961432) (xy 416.306156 -301.005009) (xy 416.32174 -301.05169) (xy 416.329635 -301.100267)
			(xy 416.33013 -301.124874) (xy 416.668978 -301.124874) (xy 416.672938 -301.07582) (xy 416.684715 -301.028036)
			(xy 416.704006 -300.98276) (xy 416.730309 -300.941164) (xy 416.762944 -300.904327) (xy 416.801065 -300.873202)
			(xy 416.843686 -300.848595) (xy 416.889702 -300.831143) (xy 416.937921 -300.821299) (xy 416.987096 -300.819318)
			(xy 417.035951 -300.82525) (xy 417.083222 -300.838942) (xy 417.127684 -300.86004) (xy 417.168187 -300.887996)
			(xy 417.20368 -300.922088) (xy 417.233245 -300.961432) (xy 417.256116 -301.005009) (xy 417.2717 -301.05169)
			(xy 417.279595 -301.100267) (xy 417.28009 -301.124874) (xy 417.279595 -301.149481) (xy 417.2717 -301.198058)
			(xy 417.256116 -301.244739) (xy 417.233245 -301.288316) (xy 417.20368 -301.32766) (xy 417.168187 -301.361752)
			(xy 417.127684 -301.389708) (xy 417.083222 -301.410806) (xy 417.035951 -301.424498) (xy 416.987096 -301.43043)
			(xy 416.937921 -301.428449) (xy 416.889702 -301.418605) (xy 416.843686 -301.401153) (xy 416.801065 -301.376546)
			(xy 416.762944 -301.345421) (xy 416.730309 -301.308584) (xy 416.704006 -301.266988) (xy 416.684715 -301.221712)
			(xy 416.672938 -301.173928) (xy 416.668978 -301.124874) (xy 416.33013 -301.124874) (xy 416.329635 -301.149481)
			(xy 416.32174 -301.198058) (xy 416.306156 -301.244739) (xy 416.283285 -301.288316) (xy 416.25372 -301.32766)
			(xy 416.218227 -301.361752) (xy 416.177724 -301.389708) (xy 416.133262 -301.410806) (xy 416.085991 -301.424498)
			(xy 416.037136 -301.43043) (xy 415.987961 -301.428449) (xy 415.939742 -301.418605) (xy 415.893726 -301.401153)
			(xy 415.851105 -301.376546) (xy 415.812984 -301.345421) (xy 415.780349 -301.308584) (xy 415.754046 -301.266988)
			(xy 415.734755 -301.221712) (xy 415.722978 -301.173928) (xy 415.719018 -301.124874) (xy 415.38017 -301.124874)
			(xy 415.379675 -301.149481) (xy 415.37178 -301.198058) (xy 415.356196 -301.244739) (xy 415.333325 -301.288316)
			(xy 415.30376 -301.32766) (xy 415.268267 -301.361752) (xy 415.227764 -301.389708) (xy 415.183302 -301.410806)
			(xy 415.136031 -301.424498) (xy 415.087176 -301.43043) (xy 415.038001 -301.428449) (xy 414.989782 -301.418605)
			(xy 414.943766 -301.401153) (xy 414.901145 -301.376546) (xy 414.863024 -301.345421) (xy 414.830389 -301.308584)
			(xy 414.804086 -301.266988) (xy 414.784795 -301.221712) (xy 414.773018 -301.173928) (xy 414.769058 -301.124874)
			(xy 414.43021 -301.124874) (xy 414.429715 -301.149481) (xy 414.42182 -301.198058) (xy 414.406236 -301.244739)
			(xy 414.383365 -301.288316) (xy 414.3538 -301.32766) (xy 414.318307 -301.361752) (xy 414.277804 -301.389708)
			(xy 414.233342 -301.410806) (xy 414.186071 -301.424498) (xy 414.137216 -301.43043) (xy 414.088041 -301.428449)
			(xy 414.039822 -301.418605) (xy 413.993806 -301.401153) (xy 413.951185 -301.376546) (xy 413.913064 -301.345421)
			(xy 413.880429 -301.308584) (xy 413.854126 -301.266988) (xy 413.834835 -301.221712) (xy 413.823058 -301.173928)
			(xy 413.819098 -301.124874) (xy 413.48025 -301.124874) (xy 413.479755 -301.149481) (xy 413.47186 -301.198058)
			(xy 413.456276 -301.244739) (xy 413.433405 -301.288316) (xy 413.40384 -301.32766) (xy 413.368347 -301.361752)
			(xy 413.327844 -301.389708) (xy 413.283382 -301.410806) (xy 413.236111 -301.424498) (xy 413.187256 -301.43043)
			(xy 413.138081 -301.428449) (xy 413.089862 -301.418605) (xy 413.043846 -301.401153) (xy 413.001225 -301.376546)
			(xy 412.963104 -301.345421) (xy 412.930469 -301.308584) (xy 412.904166 -301.266988) (xy 412.884875 -301.221712)
			(xy 412.873098 -301.173928) (xy 412.869138 -301.124874) (xy 412.53029 -301.124874) (xy 412.529795 -301.149481)
			(xy 412.5219 -301.198058) (xy 412.506316 -301.244739) (xy 412.483445 -301.288316) (xy 412.45388 -301.32766)
			(xy 412.418387 -301.361752) (xy 412.377884 -301.389708) (xy 412.333422 -301.410806) (xy 412.286151 -301.424498)
			(xy 412.237296 -301.43043) (xy 412.188121 -301.428449) (xy 412.139902 -301.418605) (xy 412.093886 -301.401153)
			(xy 412.051265 -301.376546) (xy 412.013144 -301.345421) (xy 411.980509 -301.308584) (xy 411.954206 -301.266988)
			(xy 411.934915 -301.221712) (xy 411.923138 -301.173928) (xy 411.919178 -301.124874) (xy 411.58033 -301.124874)
			(xy 411.579835 -301.149481) (xy 411.57194 -301.198058) (xy 411.556356 -301.244739) (xy 411.533485 -301.288316)
			(xy 411.50392 -301.32766) (xy 411.468427 -301.361752) (xy 411.427924 -301.389708) (xy 411.383462 -301.410806)
			(xy 411.336191 -301.424498) (xy 411.287336 -301.43043) (xy 411.238161 -301.428449) (xy 411.189942 -301.418605)
			(xy 411.143926 -301.401153) (xy 411.101305 -301.376546) (xy 411.063184 -301.345421) (xy 411.030549 -301.308584)
			(xy 411.004246 -301.266988) (xy 410.984955 -301.221712) (xy 410.973178 -301.173928) (xy 410.969218 -301.124874)
			(xy 410.630116 -301.124874) (xy 410.629621 -301.149481) (xy 410.621726 -301.198058) (xy 410.606142 -301.244739)
			(xy 410.583271 -301.288316) (xy 410.553706 -301.32766) (xy 410.518213 -301.361752) (xy 410.47771 -301.389708)
			(xy 410.433248 -301.410806) (xy 410.385977 -301.424498) (xy 410.337122 -301.43043) (xy 410.287947 -301.428449)
			(xy 410.239728 -301.418605) (xy 410.193712 -301.401153) (xy 410.151091 -301.376546) (xy 410.11297 -301.345421)
			(xy 410.080335 -301.308584) (xy 410.054032 -301.266988) (xy 410.034741 -301.221712) (xy 410.022964 -301.173928)
			(xy 410.019004 -301.124874) (xy 409.680156 -301.124874) (xy 409.679661 -301.149481) (xy 409.671766 -301.198058)
			(xy 409.656182 -301.244739) (xy 409.633311 -301.288316) (xy 409.603746 -301.32766) (xy 409.568253 -301.361752)
			(xy 409.52775 -301.389708) (xy 409.483288 -301.410806) (xy 409.436017 -301.424498) (xy 409.387162 -301.43043)
			(xy 409.337987 -301.428449) (xy 409.289768 -301.418605) (xy 409.243752 -301.401153) (xy 409.201131 -301.376546)
			(xy 409.16301 -301.345421) (xy 409.130375 -301.308584) (xy 409.104072 -301.266988) (xy 409.084781 -301.221712)
			(xy 409.073004 -301.173928) (xy 409.069044 -301.124874) (xy 408.730196 -301.124874) (xy 408.729701 -301.149481)
			(xy 408.721806 -301.198058) (xy 408.706222 -301.244739) (xy 408.683351 -301.288316) (xy 408.653786 -301.32766)
			(xy 408.618293 -301.361752) (xy 408.57779 -301.389708) (xy 408.533328 -301.410806) (xy 408.486057 -301.424498)
			(xy 408.437202 -301.43043) (xy 408.388027 -301.428449) (xy 408.339808 -301.418605) (xy 408.293792 -301.401153)
			(xy 408.251171 -301.376546) (xy 408.21305 -301.345421) (xy 408.180415 -301.308584) (xy 408.154112 -301.266988)
			(xy 408.134821 -301.221712) (xy 408.123044 -301.173928) (xy 408.119084 -301.124874) (xy 406.830276 -301.124874)
			(xy 406.829781 -301.149481) (xy 406.821886 -301.198058) (xy 406.806302 -301.244739) (xy 406.783431 -301.288316)
			(xy 406.753866 -301.32766) (xy 406.718373 -301.361752) (xy 406.67787 -301.389708) (xy 406.633408 -301.410806)
			(xy 406.586137 -301.424498) (xy 406.537282 -301.43043) (xy 406.488107 -301.428449) (xy 406.439888 -301.418605)
			(xy 406.393872 -301.401153) (xy 406.351251 -301.376546) (xy 406.31313 -301.345421) (xy 406.280495 -301.308584)
			(xy 406.254192 -301.266988) (xy 406.234901 -301.221712) (xy 406.223124 -301.173928) (xy 406.219164 -301.124874)
			(xy 405.880316 -301.124874) (xy 405.879821 -301.149481) (xy 405.871926 -301.198058) (xy 405.856342 -301.244739)
			(xy 405.833471 -301.288316) (xy 405.803906 -301.32766) (xy 405.768413 -301.361752) (xy 405.72791 -301.389708)
			(xy 405.683448 -301.410806) (xy 405.636177 -301.424498) (xy 405.587322 -301.43043) (xy 405.538147 -301.428449)
			(xy 405.489928 -301.418605) (xy 405.443912 -301.401153) (xy 405.401291 -301.376546) (xy 405.36317 -301.345421)
			(xy 405.330535 -301.308584) (xy 405.304232 -301.266988) (xy 405.284941 -301.221712) (xy 405.273164 -301.173928)
			(xy 405.269204 -301.124874) (xy 404.930102 -301.124874) (xy 404.929607 -301.149481) (xy 404.921712 -301.198058)
			(xy 404.906128 -301.244739) (xy 404.883257 -301.288316) (xy 404.853692 -301.32766) (xy 404.818199 -301.361752)
			(xy 404.777696 -301.389708) (xy 404.733234 -301.410806) (xy 404.685963 -301.424498) (xy 404.637108 -301.43043)
			(xy 404.587933 -301.428449) (xy 404.539714 -301.418605) (xy 404.493698 -301.401153) (xy 404.451077 -301.376546)
			(xy 404.412956 -301.345421) (xy 404.380321 -301.308584) (xy 404.354018 -301.266988) (xy 404.334727 -301.221712)
			(xy 404.32295 -301.173928) (xy 404.31899 -301.124874) (xy 403.980142 -301.124874) (xy 403.979647 -301.149481)
			(xy 403.971752 -301.198058) (xy 403.956168 -301.244739) (xy 403.933297 -301.288316) (xy 403.903732 -301.32766)
			(xy 403.868239 -301.361752) (xy 403.827736 -301.389708) (xy 403.783274 -301.410806) (xy 403.736003 -301.424498)
			(xy 403.687148 -301.43043) (xy 403.637973 -301.428449) (xy 403.589754 -301.418605) (xy 403.543738 -301.401153)
			(xy 403.501117 -301.376546) (xy 403.462996 -301.345421) (xy 403.430361 -301.308584) (xy 403.404058 -301.266988)
			(xy 403.384767 -301.221712) (xy 403.37299 -301.173928) (xy 403.36903 -301.124874) (xy 403.030182 -301.124874)
			(xy 403.029687 -301.149481) (xy 403.021792 -301.198058) (xy 403.006208 -301.244739) (xy 402.983337 -301.288316)
			(xy 402.953772 -301.32766) (xy 402.918279 -301.361752) (xy 402.877776 -301.389708) (xy 402.833314 -301.410806)
			(xy 402.786043 -301.424498) (xy 402.737188 -301.43043) (xy 402.688013 -301.428449) (xy 402.639794 -301.418605)
			(xy 402.593778 -301.401153) (xy 402.551157 -301.376546) (xy 402.513036 -301.345421) (xy 402.480401 -301.308584)
			(xy 402.454098 -301.266988) (xy 402.434807 -301.221712) (xy 402.42303 -301.173928) (xy 402.41907 -301.124874)
			(xy 402.080222 -301.124874) (xy 402.079727 -301.149481) (xy 402.071832 -301.198058) (xy 402.056248 -301.244739)
			(xy 402.033377 -301.288316) (xy 402.003812 -301.32766) (xy 401.968319 -301.361752) (xy 401.927816 -301.389708)
			(xy 401.883354 -301.410806) (xy 401.836083 -301.424498) (xy 401.787228 -301.43043) (xy 401.738053 -301.428449)
			(xy 401.689834 -301.418605) (xy 401.643818 -301.401153) (xy 401.601197 -301.376546) (xy 401.563076 -301.345421)
			(xy 401.530441 -301.308584) (xy 401.504138 -301.266988) (xy 401.484847 -301.221712) (xy 401.47307 -301.173928)
			(xy 401.46911 -301.124874) (xy 401.130262 -301.124874) (xy 401.129767 -301.149481) (xy 401.121872 -301.198058)
			(xy 401.106288 -301.244739) (xy 401.083417 -301.288316) (xy 401.053852 -301.32766) (xy 401.018359 -301.361752)
			(xy 400.977856 -301.389708) (xy 400.933394 -301.410806) (xy 400.886123 -301.424498) (xy 400.837268 -301.43043)
			(xy 400.788093 -301.428449) (xy 400.739874 -301.418605) (xy 400.693858 -301.401153) (xy 400.651237 -301.376546)
			(xy 400.613116 -301.345421) (xy 400.580481 -301.308584) (xy 400.554178 -301.266988) (xy 400.534887 -301.221712)
			(xy 400.52311 -301.173928) (xy 400.51915 -301.124874) (xy 400.180302 -301.124874) (xy 400.179807 -301.149481)
			(xy 400.171912 -301.198058) (xy 400.156328 -301.244739) (xy 400.133457 -301.288316) (xy 400.103892 -301.32766)
			(xy 400.068399 -301.361752) (xy 400.027896 -301.389708) (xy 399.983434 -301.410806) (xy 399.936163 -301.424498)
			(xy 399.887308 -301.43043) (xy 399.838133 -301.428449) (xy 399.789914 -301.418605) (xy 399.743898 -301.401153)
			(xy 399.701277 -301.376546) (xy 399.663156 -301.345421) (xy 399.630521 -301.308584) (xy 399.604218 -301.266988)
			(xy 399.584927 -301.221712) (xy 399.57315 -301.173928) (xy 399.56919 -301.124874) (xy 399.230342 -301.124874)
			(xy 399.229847 -301.149481) (xy 399.221952 -301.198058) (xy 399.206368 -301.244739) (xy 399.183497 -301.288316)
			(xy 399.153932 -301.32766) (xy 399.118439 -301.361752) (xy 399.077936 -301.389708) (xy 399.033474 -301.410806)
			(xy 398.986203 -301.424498) (xy 398.937348 -301.43043) (xy 398.888173 -301.428449) (xy 398.839954 -301.418605)
			(xy 398.793938 -301.401153) (xy 398.751317 -301.376546) (xy 398.713196 -301.345421) (xy 398.680561 -301.308584)
			(xy 398.654258 -301.266988) (xy 398.634967 -301.221712) (xy 398.62319 -301.173928) (xy 398.61923 -301.124874)
			(xy 398.280128 -301.124874) (xy 398.279633 -301.149481) (xy 398.271738 -301.198058) (xy 398.256154 -301.244739)
			(xy 398.233283 -301.288316) (xy 398.203718 -301.32766) (xy 398.168225 -301.361752) (xy 398.127722 -301.389708)
			(xy 398.08326 -301.410806) (xy 398.035989 -301.424498) (xy 397.987134 -301.43043) (xy 397.937959 -301.428449)
			(xy 397.88974 -301.418605) (xy 397.843724 -301.401153) (xy 397.801103 -301.376546) (xy 397.762982 -301.345421)
			(xy 397.730347 -301.308584) (xy 397.704044 -301.266988) (xy 397.684753 -301.221712) (xy 397.672976 -301.173928)
			(xy 397.669016 -301.124874) (xy 396.380208 -301.124874) (xy 396.379713 -301.149481) (xy 396.371818 -301.198058)
			(xy 396.356234 -301.244739) (xy 396.333363 -301.288316) (xy 396.303798 -301.32766) (xy 396.268305 -301.361752)
			(xy 396.227802 -301.389708) (xy 396.18334 -301.410806) (xy 396.136069 -301.424498) (xy 396.087214 -301.43043)
			(xy 396.038039 -301.428449) (xy 395.98982 -301.418605) (xy 395.943804 -301.401153) (xy 395.901183 -301.376546)
			(xy 395.863062 -301.345421) (xy 395.830427 -301.308584) (xy 395.804124 -301.266988) (xy 395.784833 -301.221712)
			(xy 395.773056 -301.173928) (xy 395.769096 -301.124874) (xy 395.430248 -301.124874) (xy 395.429753 -301.149481)
			(xy 395.421858 -301.198058) (xy 395.406274 -301.244739) (xy 395.383403 -301.288316) (xy 395.353838 -301.32766)
			(xy 395.318345 -301.361752) (xy 395.277842 -301.389708) (xy 395.23338 -301.410806) (xy 395.186109 -301.424498)
			(xy 395.137254 -301.43043) (xy 395.088079 -301.428449) (xy 395.03986 -301.418605) (xy 394.993844 -301.401153)
			(xy 394.951223 -301.376546) (xy 394.913102 -301.345421) (xy 394.880467 -301.308584) (xy 394.854164 -301.266988)
			(xy 394.834873 -301.221712) (xy 394.823096 -301.173928) (xy 394.819136 -301.124874) (xy 394.480241 -301.124874)
			(xy 394.480692 -301.133203) (xy 394.475322 -301.182549) (xy 394.462039 -301.230376) (xy 394.441194 -301.275424)
			(xy 394.413335 -301.316506) (xy 394.379197 -301.35254) (xy 394.339679 -301.382577) (xy 394.295823 -301.405825)
			(xy 394.248783 -301.421671) (xy 394.199799 -301.429698) (xy 394.17498 -301.430182) (xy 394.160797 -301.430009)
			(xy 394.132557 -301.427334) (xy 394.118592 -301.424848) (xy 394.106146 -301.422562) (xy 394.082524 -301.429928)
			(xy 394.005054 -301.507398) (xy 393.997688 -301.53102) (xy 393.999974 -301.543466) (xy 394.002455 -301.557431)
			(xy 394.005124 -301.585671) (xy 394.005308 -301.599854) (xy 394.005125 -301.614037) (xy 394.002457 -301.642277)
			(xy 393.999974 -301.656242) (xy 393.997688 -301.668688) (xy 394.005054 -301.69231) (xy 394.082524 -301.76978)
			(xy 394.106146 -301.777146) (xy 394.118592 -301.77486) (xy 394.132559 -301.772389) (xy 394.160798 -301.769714)
			(xy 394.17498 -301.769526) (xy 394.200242 -301.769949) (xy 394.250076 -301.778262) (xy 394.297863 -301.794665)
			(xy 394.342298 -301.818709) (xy 394.382169 -301.849739) (xy 394.416388 -301.886909) (xy 394.444023 -301.929205)
			(xy 394.464318 -301.975472) (xy 394.476722 -302.024449) (xy 394.480894 -302.0748) (xy 394.480891 -302.074834)
			(xy 397.669016 -302.074834) (xy 397.672976 -302.02578) (xy 397.684753 -301.977996) (xy 397.704044 -301.93272)
			(xy 397.730347 -301.891124) (xy 397.762982 -301.854287) (xy 397.801103 -301.823162) (xy 397.843724 -301.798555)
			(xy 397.88974 -301.781103) (xy 397.937959 -301.771259) (xy 397.987134 -301.769278) (xy 398.035989 -301.77521)
			(xy 398.08326 -301.788902) (xy 398.127722 -301.81) (xy 398.168225 -301.837956) (xy 398.203718 -301.872048)
			(xy 398.233283 -301.911392) (xy 398.256154 -301.954969) (xy 398.271738 -302.00165) (xy 398.279633 -302.050227)
			(xy 398.280128 -302.074834) (xy 398.61923 -302.074834) (xy 398.62319 -302.02578) (xy 398.634967 -301.977996)
			(xy 398.654258 -301.93272) (xy 398.680561 -301.891124) (xy 398.713196 -301.854287) (xy 398.751317 -301.823162)
			(xy 398.793938 -301.798555) (xy 398.839954 -301.781103) (xy 398.888173 -301.771259) (xy 398.937348 -301.769278)
			(xy 398.986203 -301.77521) (xy 399.033474 -301.788902) (xy 399.077936 -301.81) (xy 399.118439 -301.837956)
			(xy 399.153932 -301.872048) (xy 399.183497 -301.911392) (xy 399.206368 -301.954969) (xy 399.221952 -302.00165)
			(xy 399.229847 -302.050227) (xy 399.230342 -302.074834) (xy 399.56919 -302.074834) (xy 399.57315 -302.02578)
			(xy 399.584927 -301.977996) (xy 399.604218 -301.93272) (xy 399.630521 -301.891124) (xy 399.663156 -301.854287)
			(xy 399.701277 -301.823162) (xy 399.743898 -301.798555) (xy 399.789914 -301.781103) (xy 399.838133 -301.771259)
			(xy 399.887308 -301.769278) (xy 399.936163 -301.77521) (xy 399.983434 -301.788902) (xy 400.027896 -301.81)
			(xy 400.068399 -301.837956) (xy 400.103892 -301.872048) (xy 400.133457 -301.911392) (xy 400.156328 -301.954969)
			(xy 400.171912 -302.00165) (xy 400.179807 -302.050227) (xy 400.180302 -302.074834) (xy 400.51915 -302.074834)
			(xy 400.52311 -302.02578) (xy 400.534887 -301.977996) (xy 400.554178 -301.93272) (xy 400.580481 -301.891124)
			(xy 400.613116 -301.854287) (xy 400.651237 -301.823162) (xy 400.693858 -301.798555) (xy 400.739874 -301.781103)
			(xy 400.788093 -301.771259) (xy 400.837268 -301.769278) (xy 400.886123 -301.77521) (xy 400.933394 -301.788902)
			(xy 400.977856 -301.81) (xy 401.018359 -301.837956) (xy 401.053852 -301.872048) (xy 401.083417 -301.911392)
			(xy 401.106288 -301.954969) (xy 401.121872 -302.00165) (xy 401.129767 -302.050227) (xy 401.130262 -302.074834)
			(xy 401.46911 -302.074834) (xy 401.47307 -302.02578) (xy 401.484847 -301.977996) (xy 401.504138 -301.93272)
			(xy 401.530441 -301.891124) (xy 401.563076 -301.854287) (xy 401.601197 -301.823162) (xy 401.643818 -301.798555)
			(xy 401.689834 -301.781103) (xy 401.738053 -301.771259) (xy 401.787228 -301.769278) (xy 401.836083 -301.77521)
			(xy 401.883354 -301.788902) (xy 401.927816 -301.81) (xy 401.968319 -301.837956) (xy 402.003812 -301.872048)
			(xy 402.033377 -301.911392) (xy 402.056248 -301.954969) (xy 402.071832 -302.00165) (xy 402.079727 -302.050227)
			(xy 402.080222 -302.074834) (xy 402.41907 -302.074834) (xy 402.42303 -302.02578) (xy 402.434807 -301.977996)
			(xy 402.454098 -301.93272) (xy 402.480401 -301.891124) (xy 402.513036 -301.854287) (xy 402.551157 -301.823162)
			(xy 402.593778 -301.798555) (xy 402.639794 -301.781103) (xy 402.688013 -301.771259) (xy 402.737188 -301.769278)
			(xy 402.786043 -301.77521) (xy 402.833314 -301.788902) (xy 402.877776 -301.81) (xy 402.918279 -301.837956)
			(xy 402.953772 -301.872048) (xy 402.983337 -301.911392) (xy 403.006208 -301.954969) (xy 403.021792 -302.00165)
			(xy 403.029687 -302.050227) (xy 403.030182 -302.074834) (xy 403.36903 -302.074834) (xy 403.37299 -302.02578)
			(xy 403.384767 -301.977996) (xy 403.404058 -301.93272) (xy 403.430361 -301.891124) (xy 403.462996 -301.854287)
			(xy 403.501117 -301.823162) (xy 403.543738 -301.798555) (xy 403.589754 -301.781103) (xy 403.637973 -301.771259)
			(xy 403.687148 -301.769278) (xy 403.736003 -301.77521) (xy 403.783274 -301.788902) (xy 403.827736 -301.81)
			(xy 403.868239 -301.837956) (xy 403.903732 -301.872048) (xy 403.933297 -301.911392) (xy 403.956168 -301.954969)
			(xy 403.971752 -302.00165) (xy 403.979647 -302.050227) (xy 403.980142 -302.074834) (xy 404.31899 -302.074834)
			(xy 404.32295 -302.02578) (xy 404.334727 -301.977996) (xy 404.354018 -301.93272) (xy 404.380321 -301.891124)
			(xy 404.412956 -301.854287) (xy 404.451077 -301.823162) (xy 404.493698 -301.798555) (xy 404.539714 -301.781103)
			(xy 404.587933 -301.771259) (xy 404.637108 -301.769278) (xy 404.685963 -301.77521) (xy 404.733234 -301.788902)
			(xy 404.777696 -301.81) (xy 404.818199 -301.837956) (xy 404.853692 -301.872048) (xy 404.883257 -301.911392)
			(xy 404.906128 -301.954969) (xy 404.921712 -302.00165) (xy 404.929607 -302.050227) (xy 404.930102 -302.074834)
			(xy 405.269204 -302.074834) (xy 405.273164 -302.02578) (xy 405.284941 -301.977996) (xy 405.304232 -301.93272)
			(xy 405.330535 -301.891124) (xy 405.36317 -301.854287) (xy 405.401291 -301.823162) (xy 405.443912 -301.798555)
			(xy 405.489928 -301.781103) (xy 405.538147 -301.771259) (xy 405.587322 -301.769278) (xy 405.636177 -301.77521)
			(xy 405.683448 -301.788902) (xy 405.72791 -301.81) (xy 405.768413 -301.837956) (xy 405.803906 -301.872048)
			(xy 405.833471 -301.911392) (xy 405.856342 -301.954969) (xy 405.871926 -302.00165) (xy 405.879821 -302.050227)
			(xy 405.880316 -302.074834) (xy 406.219164 -302.074834) (xy 406.223124 -302.02578) (xy 406.234901 -301.977996)
			(xy 406.254192 -301.93272) (xy 406.280495 -301.891124) (xy 406.31313 -301.854287) (xy 406.351251 -301.823162)
			(xy 406.393872 -301.798555) (xy 406.439888 -301.781103) (xy 406.488107 -301.771259) (xy 406.537282 -301.769278)
			(xy 406.586137 -301.77521) (xy 406.633408 -301.788902) (xy 406.67787 -301.81) (xy 406.718373 -301.837956)
			(xy 406.753866 -301.872048) (xy 406.783431 -301.911392) (xy 406.806302 -301.954969) (xy 406.821886 -302.00165)
			(xy 406.829781 -302.050227) (xy 406.830276 -302.074834) (xy 408.119084 -302.074834) (xy 408.123044 -302.02578)
			(xy 408.134821 -301.977996) (xy 408.154112 -301.93272) (xy 408.180415 -301.891124) (xy 408.21305 -301.854287)
			(xy 408.251171 -301.823162) (xy 408.293792 -301.798555) (xy 408.339808 -301.781103) (xy 408.388027 -301.771259)
			(xy 408.437202 -301.769278) (xy 408.486057 -301.77521) (xy 408.533328 -301.788902) (xy 408.57779 -301.81)
			(xy 408.618293 -301.837956) (xy 408.653786 -301.872048) (xy 408.683351 -301.911392) (xy 408.706222 -301.954969)
			(xy 408.721806 -302.00165) (xy 408.729701 -302.050227) (xy 408.730196 -302.074834) (xy 409.069044 -302.074834)
			(xy 409.073004 -302.02578) (xy 409.084781 -301.977996) (xy 409.104072 -301.93272) (xy 409.130375 -301.891124)
			(xy 409.16301 -301.854287) (xy 409.201131 -301.823162) (xy 409.243752 -301.798555) (xy 409.289768 -301.781103)
			(xy 409.337987 -301.771259) (xy 409.387162 -301.769278) (xy 409.436017 -301.77521) (xy 409.483288 -301.788902)
			(xy 409.52775 -301.81) (xy 409.568253 -301.837956) (xy 409.603746 -301.872048) (xy 409.633311 -301.911392)
			(xy 409.656182 -301.954969) (xy 409.671766 -302.00165) (xy 409.679661 -302.050227) (xy 409.680156 -302.074834)
			(xy 410.019004 -302.074834) (xy 410.022964 -302.02578) (xy 410.034741 -301.977996) (xy 410.054032 -301.93272)
			(xy 410.080335 -301.891124) (xy 410.11297 -301.854287) (xy 410.151091 -301.823162) (xy 410.193712 -301.798555)
			(xy 410.239728 -301.781103) (xy 410.287947 -301.771259) (xy 410.337122 -301.769278) (xy 410.385977 -301.77521)
			(xy 410.433248 -301.788902) (xy 410.47771 -301.81) (xy 410.518213 -301.837956) (xy 410.553706 -301.872048)
			(xy 410.583271 -301.911392) (xy 410.606142 -301.954969) (xy 410.621726 -302.00165) (xy 410.629621 -302.050227)
			(xy 410.630116 -302.074834) (xy 410.969218 -302.074834) (xy 410.973178 -302.02578) (xy 410.984955 -301.977996)
			(xy 411.004246 -301.93272) (xy 411.030549 -301.891124) (xy 411.063184 -301.854287) (xy 411.101305 -301.823162)
			(xy 411.143926 -301.798555) (xy 411.189942 -301.781103) (xy 411.238161 -301.771259) (xy 411.287336 -301.769278)
			(xy 411.336191 -301.77521) (xy 411.383462 -301.788902) (xy 411.427924 -301.81) (xy 411.468427 -301.837956)
			(xy 411.50392 -301.872048) (xy 411.533485 -301.911392) (xy 411.556356 -301.954969) (xy 411.57194 -302.00165)
			(xy 411.579835 -302.050227) (xy 411.58033 -302.074834) (xy 411.919178 -302.074834) (xy 411.923138 -302.02578)
			(xy 411.934915 -301.977996) (xy 411.954206 -301.93272) (xy 411.980509 -301.891124) (xy 412.013144 -301.854287)
			(xy 412.051265 -301.823162) (xy 412.093886 -301.798555) (xy 412.139902 -301.781103) (xy 412.188121 -301.771259)
			(xy 412.237296 -301.769278) (xy 412.286151 -301.77521) (xy 412.333422 -301.788902) (xy 412.377884 -301.81)
			(xy 412.418387 -301.837956) (xy 412.45388 -301.872048) (xy 412.483445 -301.911392) (xy 412.506316 -301.954969)
			(xy 412.5219 -302.00165) (xy 412.529795 -302.050227) (xy 412.53029 -302.074834) (xy 412.869138 -302.074834)
			(xy 412.873098 -302.02578) (xy 412.884875 -301.977996) (xy 412.904166 -301.93272) (xy 412.930469 -301.891124)
			(xy 412.963104 -301.854287) (xy 413.001225 -301.823162) (xy 413.043846 -301.798555) (xy 413.089862 -301.781103)
			(xy 413.138081 -301.771259) (xy 413.187256 -301.769278) (xy 413.236111 -301.77521) (xy 413.283382 -301.788902)
			(xy 413.327844 -301.81) (xy 413.368347 -301.837956) (xy 413.40384 -301.872048) (xy 413.433405 -301.911392)
			(xy 413.456276 -301.954969) (xy 413.47186 -302.00165) (xy 413.479755 -302.050227) (xy 413.48025 -302.074834)
			(xy 413.819098 -302.074834) (xy 413.823058 -302.02578) (xy 413.834835 -301.977996) (xy 413.854126 -301.93272)
			(xy 413.880429 -301.891124) (xy 413.913064 -301.854287) (xy 413.951185 -301.823162) (xy 413.993806 -301.798555)
			(xy 414.039822 -301.781103) (xy 414.088041 -301.771259) (xy 414.137216 -301.769278) (xy 414.186071 -301.77521)
			(xy 414.233342 -301.788902) (xy 414.277804 -301.81) (xy 414.318307 -301.837956) (xy 414.3538 -301.872048)
			(xy 414.383365 -301.911392) (xy 414.406236 -301.954969) (xy 414.42182 -302.00165) (xy 414.429715 -302.050227)
			(xy 414.43021 -302.074834) (xy 414.769058 -302.074834) (xy 414.773018 -302.02578) (xy 414.784795 -301.977996)
			(xy 414.804086 -301.93272) (xy 414.830389 -301.891124) (xy 414.863024 -301.854287) (xy 414.901145 -301.823162)
			(xy 414.943766 -301.798555) (xy 414.989782 -301.781103) (xy 415.038001 -301.771259) (xy 415.087176 -301.769278)
			(xy 415.136031 -301.77521) (xy 415.183302 -301.788902) (xy 415.227764 -301.81) (xy 415.268267 -301.837956)
			(xy 415.30376 -301.872048) (xy 415.333325 -301.911392) (xy 415.356196 -301.954969) (xy 415.37178 -302.00165)
			(xy 415.379675 -302.050227) (xy 415.38017 -302.074834) (xy 415.719018 -302.074834) (xy 415.722978 -302.02578)
			(xy 415.734755 -301.977996) (xy 415.754046 -301.93272) (xy 415.780349 -301.891124) (xy 415.812984 -301.854287)
			(xy 415.851105 -301.823162) (xy 415.893726 -301.798555) (xy 415.939742 -301.781103) (xy 415.987961 -301.771259)
			(xy 416.037136 -301.769278) (xy 416.085991 -301.77521) (xy 416.133262 -301.788902) (xy 416.177724 -301.81)
			(xy 416.218227 -301.837956) (xy 416.25372 -301.872048) (xy 416.283285 -301.911392) (xy 416.306156 -301.954969)
			(xy 416.32174 -302.00165) (xy 416.329635 -302.050227) (xy 416.33013 -302.074834) (xy 416.668978 -302.074834)
			(xy 416.672938 -302.02578) (xy 416.684715 -301.977996) (xy 416.704006 -301.93272) (xy 416.730309 -301.891124)
			(xy 416.762944 -301.854287) (xy 416.801065 -301.823162) (xy 416.843686 -301.798555) (xy 416.889702 -301.781103)
			(xy 416.937921 -301.771259) (xy 416.987096 -301.769278) (xy 417.035951 -301.77521) (xy 417.083222 -301.788902)
			(xy 417.127684 -301.81) (xy 417.168187 -301.837956) (xy 417.20368 -301.872048) (xy 417.233245 -301.911392)
			(xy 417.256116 -301.954969) (xy 417.2717 -302.00165) (xy 417.279595 -302.050227) (xy 417.28009 -302.074834)
			(xy 417.279595 -302.099441) (xy 417.2717 -302.148018) (xy 417.256116 -302.194699) (xy 417.233245 -302.238276)
			(xy 417.20368 -302.27762) (xy 417.168187 -302.311712) (xy 417.127684 -302.339668) (xy 417.083222 -302.360766)
			(xy 417.035951 -302.374458) (xy 416.987096 -302.38039) (xy 416.937921 -302.378409) (xy 416.889702 -302.368565)
			(xy 416.843686 -302.351113) (xy 416.801065 -302.326506) (xy 416.762944 -302.295381) (xy 416.730309 -302.258544)
			(xy 416.704006 -302.216948) (xy 416.684715 -302.171672) (xy 416.672938 -302.123888) (xy 416.668978 -302.074834)
			(xy 416.33013 -302.074834) (xy 416.329635 -302.099441) (xy 416.32174 -302.148018) (xy 416.306156 -302.194699)
			(xy 416.283285 -302.238276) (xy 416.25372 -302.27762) (xy 416.218227 -302.311712) (xy 416.177724 -302.339668)
			(xy 416.133262 -302.360766) (xy 416.085991 -302.374458) (xy 416.037136 -302.38039) (xy 415.987961 -302.378409)
			(xy 415.939742 -302.368565) (xy 415.893726 -302.351113) (xy 415.851105 -302.326506) (xy 415.812984 -302.295381)
			(xy 415.780349 -302.258544) (xy 415.754046 -302.216948) (xy 415.734755 -302.171672) (xy 415.722978 -302.123888)
			(xy 415.719018 -302.074834) (xy 415.38017 -302.074834) (xy 415.379675 -302.099441) (xy 415.37178 -302.148018)
			(xy 415.356196 -302.194699) (xy 415.333325 -302.238276) (xy 415.30376 -302.27762) (xy 415.268267 -302.311712)
			(xy 415.227764 -302.339668) (xy 415.183302 -302.360766) (xy 415.136031 -302.374458) (xy 415.087176 -302.38039)
			(xy 415.038001 -302.378409) (xy 414.989782 -302.368565) (xy 414.943766 -302.351113) (xy 414.901145 -302.326506)
			(xy 414.863024 -302.295381) (xy 414.830389 -302.258544) (xy 414.804086 -302.216948) (xy 414.784795 -302.171672)
			(xy 414.773018 -302.123888) (xy 414.769058 -302.074834) (xy 414.43021 -302.074834) (xy 414.429715 -302.099441)
			(xy 414.42182 -302.148018) (xy 414.406236 -302.194699) (xy 414.383365 -302.238276) (xy 414.3538 -302.27762)
			(xy 414.318307 -302.311712) (xy 414.277804 -302.339668) (xy 414.233342 -302.360766) (xy 414.186071 -302.374458)
			(xy 414.137216 -302.38039) (xy 414.088041 -302.378409) (xy 414.039822 -302.368565) (xy 413.993806 -302.351113)
			(xy 413.951185 -302.326506) (xy 413.913064 -302.295381) (xy 413.880429 -302.258544) (xy 413.854126 -302.216948)
			(xy 413.834835 -302.171672) (xy 413.823058 -302.123888) (xy 413.819098 -302.074834) (xy 413.48025 -302.074834)
			(xy 413.479755 -302.099441) (xy 413.47186 -302.148018) (xy 413.456276 -302.194699) (xy 413.433405 -302.238276)
			(xy 413.40384 -302.27762) (xy 413.368347 -302.311712) (xy 413.327844 -302.339668) (xy 413.283382 -302.360766)
			(xy 413.236111 -302.374458) (xy 413.187256 -302.38039) (xy 413.138081 -302.378409) (xy 413.089862 -302.368565)
			(xy 413.043846 -302.351113) (xy 413.001225 -302.326506) (xy 412.963104 -302.295381) (xy 412.930469 -302.258544)
			(xy 412.904166 -302.216948) (xy 412.884875 -302.171672) (xy 412.873098 -302.123888) (xy 412.869138 -302.074834)
			(xy 412.53029 -302.074834) (xy 412.529795 -302.099441) (xy 412.5219 -302.148018) (xy 412.506316 -302.194699)
			(xy 412.483445 -302.238276) (xy 412.45388 -302.27762) (xy 412.418387 -302.311712) (xy 412.377884 -302.339668)
			(xy 412.333422 -302.360766) (xy 412.286151 -302.374458) (xy 412.237296 -302.38039) (xy 412.188121 -302.378409)
			(xy 412.139902 -302.368565) (xy 412.093886 -302.351113) (xy 412.051265 -302.326506) (xy 412.013144 -302.295381)
			(xy 411.980509 -302.258544) (xy 411.954206 -302.216948) (xy 411.934915 -302.171672) (xy 411.923138 -302.123888)
			(xy 411.919178 -302.074834) (xy 411.58033 -302.074834) (xy 411.579835 -302.099441) (xy 411.57194 -302.148018)
			(xy 411.556356 -302.194699) (xy 411.533485 -302.238276) (xy 411.50392 -302.27762) (xy 411.468427 -302.311712)
			(xy 411.427924 -302.339668) (xy 411.383462 -302.360766) (xy 411.336191 -302.374458) (xy 411.287336 -302.38039)
			(xy 411.238161 -302.378409) (xy 411.189942 -302.368565) (xy 411.143926 -302.351113) (xy 411.101305 -302.326506)
			(xy 411.063184 -302.295381) (xy 411.030549 -302.258544) (xy 411.004246 -302.216948) (xy 410.984955 -302.171672)
			(xy 410.973178 -302.123888) (xy 410.969218 -302.074834) (xy 410.630116 -302.074834) (xy 410.629621 -302.099441)
			(xy 410.621726 -302.148018) (xy 410.606142 -302.194699) (xy 410.583271 -302.238276) (xy 410.553706 -302.27762)
			(xy 410.518213 -302.311712) (xy 410.47771 -302.339668) (xy 410.433248 -302.360766) (xy 410.385977 -302.374458)
			(xy 410.337122 -302.38039) (xy 410.287947 -302.378409) (xy 410.239728 -302.368565) (xy 410.193712 -302.351113)
			(xy 410.151091 -302.326506) (xy 410.11297 -302.295381) (xy 410.080335 -302.258544) (xy 410.054032 -302.216948)
			(xy 410.034741 -302.171672) (xy 410.022964 -302.123888) (xy 410.019004 -302.074834) (xy 409.680156 -302.074834)
			(xy 409.679661 -302.099441) (xy 409.671766 -302.148018) (xy 409.656182 -302.194699) (xy 409.633311 -302.238276)
			(xy 409.603746 -302.27762) (xy 409.568253 -302.311712) (xy 409.52775 -302.339668) (xy 409.483288 -302.360766)
			(xy 409.436017 -302.374458) (xy 409.387162 -302.38039) (xy 409.337987 -302.378409) (xy 409.289768 -302.368565)
			(xy 409.243752 -302.351113) (xy 409.201131 -302.326506) (xy 409.16301 -302.295381) (xy 409.130375 -302.258544)
			(xy 409.104072 -302.216948) (xy 409.084781 -302.171672) (xy 409.073004 -302.123888) (xy 409.069044 -302.074834)
			(xy 408.730196 -302.074834) (xy 408.729701 -302.099441) (xy 408.721806 -302.148018) (xy 408.706222 -302.194699)
			(xy 408.683351 -302.238276) (xy 408.653786 -302.27762) (xy 408.618293 -302.311712) (xy 408.57779 -302.339668)
			(xy 408.533328 -302.360766) (xy 408.486057 -302.374458) (xy 408.437202 -302.38039) (xy 408.388027 -302.378409)
			(xy 408.339808 -302.368565) (xy 408.293792 -302.351113) (xy 408.251171 -302.326506) (xy 408.21305 -302.295381)
			(xy 408.180415 -302.258544) (xy 408.154112 -302.216948) (xy 408.134821 -302.171672) (xy 408.123044 -302.123888)
			(xy 408.119084 -302.074834) (xy 406.830276 -302.074834) (xy 406.829781 -302.099441) (xy 406.821886 -302.148018)
			(xy 406.806302 -302.194699) (xy 406.783431 -302.238276) (xy 406.753866 -302.27762) (xy 406.718373 -302.311712)
			(xy 406.67787 -302.339668) (xy 406.633408 -302.360766) (xy 406.586137 -302.374458) (xy 406.537282 -302.38039)
			(xy 406.488107 -302.378409) (xy 406.439888 -302.368565) (xy 406.393872 -302.351113) (xy 406.351251 -302.326506)
			(xy 406.31313 -302.295381) (xy 406.280495 -302.258544) (xy 406.254192 -302.216948) (xy 406.234901 -302.171672)
			(xy 406.223124 -302.123888) (xy 406.219164 -302.074834) (xy 405.880316 -302.074834) (xy 405.879821 -302.099441)
			(xy 405.871926 -302.148018) (xy 405.856342 -302.194699) (xy 405.833471 -302.238276) (xy 405.803906 -302.27762)
			(xy 405.768413 -302.311712) (xy 405.72791 -302.339668) (xy 405.683448 -302.360766) (xy 405.636177 -302.374458)
			(xy 405.587322 -302.38039) (xy 405.538147 -302.378409) (xy 405.489928 -302.368565) (xy 405.443912 -302.351113)
			(xy 405.401291 -302.326506) (xy 405.36317 -302.295381) (xy 405.330535 -302.258544) (xy 405.304232 -302.216948)
			(xy 405.284941 -302.171672) (xy 405.273164 -302.123888) (xy 405.269204 -302.074834) (xy 404.930102 -302.074834)
			(xy 404.929607 -302.099441) (xy 404.921712 -302.148018) (xy 404.906128 -302.194699) (xy 404.883257 -302.238276)
			(xy 404.853692 -302.27762) (xy 404.818199 -302.311712) (xy 404.777696 -302.339668) (xy 404.733234 -302.360766)
			(xy 404.685963 -302.374458) (xy 404.637108 -302.38039) (xy 404.587933 -302.378409) (xy 404.539714 -302.368565)
			(xy 404.493698 -302.351113) (xy 404.451077 -302.326506) (xy 404.412956 -302.295381) (xy 404.380321 -302.258544)
			(xy 404.354018 -302.216948) (xy 404.334727 -302.171672) (xy 404.32295 -302.123888) (xy 404.31899 -302.074834)
			(xy 403.980142 -302.074834) (xy 403.979647 -302.099441) (xy 403.971752 -302.148018) (xy 403.956168 -302.194699)
			(xy 403.933297 -302.238276) (xy 403.903732 -302.27762) (xy 403.868239 -302.311712) (xy 403.827736 -302.339668)
			(xy 403.783274 -302.360766) (xy 403.736003 -302.374458) (xy 403.687148 -302.38039) (xy 403.637973 -302.378409)
			(xy 403.589754 -302.368565) (xy 403.543738 -302.351113) (xy 403.501117 -302.326506) (xy 403.462996 -302.295381)
			(xy 403.430361 -302.258544) (xy 403.404058 -302.216948) (xy 403.384767 -302.171672) (xy 403.37299 -302.123888)
			(xy 403.36903 -302.074834) (xy 403.030182 -302.074834) (xy 403.029687 -302.099441) (xy 403.021792 -302.148018)
			(xy 403.006208 -302.194699) (xy 402.983337 -302.238276) (xy 402.953772 -302.27762) (xy 402.918279 -302.311712)
			(xy 402.877776 -302.339668) (xy 402.833314 -302.360766) (xy 402.786043 -302.374458) (xy 402.737188 -302.38039)
			(xy 402.688013 -302.378409) (xy 402.639794 -302.368565) (xy 402.593778 -302.351113) (xy 402.551157 -302.326506)
			(xy 402.513036 -302.295381) (xy 402.480401 -302.258544) (xy 402.454098 -302.216948) (xy 402.434807 -302.171672)
			(xy 402.42303 -302.123888) (xy 402.41907 -302.074834) (xy 402.080222 -302.074834) (xy 402.079727 -302.099441)
			(xy 402.071832 -302.148018) (xy 402.056248 -302.194699) (xy 402.033377 -302.238276) (xy 402.003812 -302.27762)
			(xy 401.968319 -302.311712) (xy 401.927816 -302.339668) (xy 401.883354 -302.360766) (xy 401.836083 -302.374458)
			(xy 401.787228 -302.38039) (xy 401.738053 -302.378409) (xy 401.689834 -302.368565) (xy 401.643818 -302.351113)
			(xy 401.601197 -302.326506) (xy 401.563076 -302.295381) (xy 401.530441 -302.258544) (xy 401.504138 -302.216948)
			(xy 401.484847 -302.171672) (xy 401.47307 -302.123888) (xy 401.46911 -302.074834) (xy 401.130262 -302.074834)
			(xy 401.129767 -302.099441) (xy 401.121872 -302.148018) (xy 401.106288 -302.194699) (xy 401.083417 -302.238276)
			(xy 401.053852 -302.27762) (xy 401.018359 -302.311712) (xy 400.977856 -302.339668) (xy 400.933394 -302.360766)
			(xy 400.886123 -302.374458) (xy 400.837268 -302.38039) (xy 400.788093 -302.378409) (xy 400.739874 -302.368565)
			(xy 400.693858 -302.351113) (xy 400.651237 -302.326506) (xy 400.613116 -302.295381) (xy 400.580481 -302.258544)
			(xy 400.554178 -302.216948) (xy 400.534887 -302.171672) (xy 400.52311 -302.123888) (xy 400.51915 -302.074834)
			(xy 400.180302 -302.074834) (xy 400.179807 -302.099441) (xy 400.171912 -302.148018) (xy 400.156328 -302.194699)
			(xy 400.133457 -302.238276) (xy 400.103892 -302.27762) (xy 400.068399 -302.311712) (xy 400.027896 -302.339668)
			(xy 399.983434 -302.360766) (xy 399.936163 -302.374458) (xy 399.887308 -302.38039) (xy 399.838133 -302.378409)
			(xy 399.789914 -302.368565) (xy 399.743898 -302.351113) (xy 399.701277 -302.326506) (xy 399.663156 -302.295381)
			(xy 399.630521 -302.258544) (xy 399.604218 -302.216948) (xy 399.584927 -302.171672) (xy 399.57315 -302.123888)
			(xy 399.56919 -302.074834) (xy 399.230342 -302.074834) (xy 399.229847 -302.099441) (xy 399.221952 -302.148018)
			(xy 399.206368 -302.194699) (xy 399.183497 -302.238276) (xy 399.153932 -302.27762) (xy 399.118439 -302.311712)
			(xy 399.077936 -302.339668) (xy 399.033474 -302.360766) (xy 398.986203 -302.374458) (xy 398.937348 -302.38039)
			(xy 398.888173 -302.378409) (xy 398.839954 -302.368565) (xy 398.793938 -302.351113) (xy 398.751317 -302.326506)
			(xy 398.713196 -302.295381) (xy 398.680561 -302.258544) (xy 398.654258 -302.216948) (xy 398.634967 -302.171672)
			(xy 398.62319 -302.123888) (xy 398.61923 -302.074834) (xy 398.280128 -302.074834) (xy 398.279633 -302.099441)
			(xy 398.271738 -302.148018) (xy 398.256154 -302.194699) (xy 398.233283 -302.238276) (xy 398.203718 -302.27762)
			(xy 398.168225 -302.311712) (xy 398.127722 -302.339668) (xy 398.08326 -302.360766) (xy 398.035989 -302.374458)
			(xy 397.987134 -302.38039) (xy 397.937959 -302.378409) (xy 397.88974 -302.368565) (xy 397.843724 -302.351113)
			(xy 397.801103 -302.326506) (xy 397.762982 -302.295381) (xy 397.730347 -302.258544) (xy 397.704044 -302.216948)
			(xy 397.684753 -302.171672) (xy 397.672976 -302.123888) (xy 397.669016 -302.074834) (xy 394.480891 -302.074834)
			(xy 394.476722 -302.125151) (xy 394.464318 -302.174128) (xy 394.444023 -302.220395) (xy 394.416388 -302.262691)
			(xy 394.382169 -302.299861) (xy 394.342298 -302.330891) (xy 394.297863 -302.354935) (xy 394.250076 -302.371338)
			(xy 394.200242 -302.379651) (xy 394.17498 -302.380142) (xy 394.160797 -302.379968) (xy 394.132557 -302.377294)
			(xy 394.118592 -302.374808) (xy 394.106146 -302.372522) (xy 394.082524 -302.379888) (xy 394.005054 -302.457358)
			(xy 393.997688 -302.48098) (xy 393.999974 -302.493426) (xy 394.00245 -302.507392) (xy 394.005122 -302.535631)
			(xy 394.005308 -302.549814) (xy 394.005133 -302.563997) (xy 394.00246 -302.592237) (xy 393.999974 -302.606202)
			(xy 393.997688 -302.618648) (xy 394.005054 -302.64227) (xy 394.082524 -302.71974) (xy 394.106146 -302.727106)
			(xy 394.118592 -302.72482) (xy 394.132559 -302.722349) (xy 394.160798 -302.719673) (xy 394.17498 -302.719486)
			(xy 394.200238 -302.719989) (xy 394.250066 -302.728301) (xy 394.297847 -302.744701) (xy 394.342276 -302.768742)
			(xy 394.382142 -302.799769) (xy 394.416357 -302.836934) (xy 394.443988 -302.879224) (xy 394.464281 -302.925485)
			(xy 394.476682 -302.974456) (xy 394.480854 -303.024794) (xy 394.819136 -303.024794) (xy 394.823096 -302.97574)
			(xy 394.834873 -302.927956) (xy 394.854164 -302.88268) (xy 394.880467 -302.841084) (xy 394.913102 -302.804247)
			(xy 394.951223 -302.773122) (xy 394.993844 -302.748515) (xy 395.03986 -302.731063) (xy 395.088079 -302.721219)
			(xy 395.137254 -302.719238) (xy 395.186109 -302.72517) (xy 395.23338 -302.738862) (xy 395.277842 -302.75996)
			(xy 395.318345 -302.787916) (xy 395.353838 -302.822008) (xy 395.383403 -302.861352) (xy 395.406274 -302.904929)
			(xy 395.421858 -302.95161) (xy 395.429753 -303.000187) (xy 395.430248 -303.024794) (xy 395.769096 -303.024794)
			(xy 395.773056 -302.97574) (xy 395.784833 -302.927956) (xy 395.804124 -302.88268) (xy 395.830427 -302.841084)
			(xy 395.863062 -302.804247) (xy 395.901183 -302.773122) (xy 395.943804 -302.748515) (xy 395.98982 -302.731063)
			(xy 396.038039 -302.721219) (xy 396.087214 -302.719238) (xy 396.136069 -302.72517) (xy 396.18334 -302.738862)
			(xy 396.227802 -302.75996) (xy 396.268305 -302.787916) (xy 396.303798 -302.822008) (xy 396.333363 -302.861352)
			(xy 396.356234 -302.904929) (xy 396.371818 -302.95161) (xy 396.379713 -303.000187) (xy 396.380208 -303.024794)
			(xy 396.719056 -303.024794) (xy 396.723016 -302.97574) (xy 396.734793 -302.927956) (xy 396.754084 -302.88268)
			(xy 396.780387 -302.841084) (xy 396.813022 -302.804247) (xy 396.851143 -302.773122) (xy 396.893764 -302.748515)
			(xy 396.93978 -302.731063) (xy 396.987999 -302.721219) (xy 397.037174 -302.719238) (xy 397.086029 -302.72517)
			(xy 397.1333 -302.738862) (xy 397.177762 -302.75996) (xy 397.218265 -302.787916) (xy 397.253758 -302.822008)
			(xy 397.283323 -302.861352) (xy 397.306194 -302.904929) (xy 397.321778 -302.95161) (xy 397.329673 -303.000187)
			(xy 397.330168 -303.024794) (xy 397.669016 -303.024794) (xy 397.672976 -302.97574) (xy 397.684753 -302.927956)
			(xy 397.704044 -302.88268) (xy 397.730347 -302.841084) (xy 397.762982 -302.804247) (xy 397.801103 -302.773122)
			(xy 397.843724 -302.748515) (xy 397.88974 -302.731063) (xy 397.937959 -302.721219) (xy 397.987134 -302.719238)
			(xy 398.035989 -302.72517) (xy 398.08326 -302.738862) (xy 398.127722 -302.75996) (xy 398.168225 -302.787916)
			(xy 398.203718 -302.822008) (xy 398.233283 -302.861352) (xy 398.256154 -302.904929) (xy 398.271738 -302.95161)
			(xy 398.279633 -303.000187) (xy 398.280128 -303.024794) (xy 398.61923 -303.024794) (xy 398.62319 -302.97574)
			(xy 398.634967 -302.927956) (xy 398.654258 -302.88268) (xy 398.680561 -302.841084) (xy 398.713196 -302.804247)
			(xy 398.751317 -302.773122) (xy 398.793938 -302.748515) (xy 398.839954 -302.731063) (xy 398.888173 -302.721219)
			(xy 398.937348 -302.719238) (xy 398.986203 -302.72517) (xy 399.033474 -302.738862) (xy 399.077936 -302.75996)
			(xy 399.118439 -302.787916) (xy 399.153932 -302.822008) (xy 399.183497 -302.861352) (xy 399.206368 -302.904929)
			(xy 399.221952 -302.95161) (xy 399.229847 -303.000187) (xy 399.230342 -303.024794) (xy 399.56919 -303.024794)
			(xy 399.57315 -302.97574) (xy 399.584927 -302.927956) (xy 399.604218 -302.88268) (xy 399.630521 -302.841084)
			(xy 399.663156 -302.804247) (xy 399.701277 -302.773122) (xy 399.743898 -302.748515) (xy 399.789914 -302.731063)
			(xy 399.838133 -302.721219) (xy 399.887308 -302.719238) (xy 399.936163 -302.72517) (xy 399.983434 -302.738862)
			(xy 400.027896 -302.75996) (xy 400.068399 -302.787916) (xy 400.103892 -302.822008) (xy 400.133457 -302.861352)
			(xy 400.156328 -302.904929) (xy 400.171912 -302.95161) (xy 400.179807 -303.000187) (xy 400.180302 -303.024794)
			(xy 400.51915 -303.024794) (xy 400.52311 -302.97574) (xy 400.534887 -302.927956) (xy 400.554178 -302.88268)
			(xy 400.580481 -302.841084) (xy 400.613116 -302.804247) (xy 400.651237 -302.773122) (xy 400.693858 -302.748515)
			(xy 400.739874 -302.731063) (xy 400.788093 -302.721219) (xy 400.837268 -302.719238) (xy 400.886123 -302.72517)
			(xy 400.933394 -302.738862) (xy 400.977856 -302.75996) (xy 401.018359 -302.787916) (xy 401.053852 -302.822008)
			(xy 401.083417 -302.861352) (xy 401.106288 -302.904929) (xy 401.121872 -302.95161) (xy 401.129767 -303.000187)
			(xy 401.130262 -303.024794) (xy 401.46911 -303.024794) (xy 401.47307 -302.97574) (xy 401.484847 -302.927956)
			(xy 401.504138 -302.88268) (xy 401.530441 -302.841084) (xy 401.563076 -302.804247) (xy 401.601197 -302.773122)
			(xy 401.643818 -302.748515) (xy 401.689834 -302.731063) (xy 401.738053 -302.721219) (xy 401.787228 -302.719238)
			(xy 401.836083 -302.72517) (xy 401.883354 -302.738862) (xy 401.927816 -302.75996) (xy 401.968319 -302.787916)
			(xy 402.003812 -302.822008) (xy 402.033377 -302.861352) (xy 402.056248 -302.904929) (xy 402.071832 -302.95161)
			(xy 402.079727 -303.000187) (xy 402.080222 -303.024794) (xy 402.41907 -303.024794) (xy 402.42303 -302.97574)
			(xy 402.434807 -302.927956) (xy 402.454098 -302.88268) (xy 402.480401 -302.841084) (xy 402.513036 -302.804247)
			(xy 402.551157 -302.773122) (xy 402.593778 -302.748515) (xy 402.639794 -302.731063) (xy 402.688013 -302.721219)
			(xy 402.737188 -302.719238) (xy 402.786043 -302.72517) (xy 402.833314 -302.738862) (xy 402.877776 -302.75996)
			(xy 402.918279 -302.787916) (xy 402.953772 -302.822008) (xy 402.983337 -302.861352) (xy 403.006208 -302.904929)
			(xy 403.021792 -302.95161) (xy 403.029687 -303.000187) (xy 403.030182 -303.024794) (xy 403.36903 -303.024794)
			(xy 403.37299 -302.97574) (xy 403.384767 -302.927956) (xy 403.404058 -302.88268) (xy 403.430361 -302.841084)
			(xy 403.462996 -302.804247) (xy 403.501117 -302.773122) (xy 403.543738 -302.748515) (xy 403.589754 -302.731063)
			(xy 403.637973 -302.721219) (xy 403.687148 -302.719238) (xy 403.736003 -302.72517) (xy 403.783274 -302.738862)
			(xy 403.827736 -302.75996) (xy 403.868239 -302.787916) (xy 403.903732 -302.822008) (xy 403.933297 -302.861352)
			(xy 403.956168 -302.904929) (xy 403.971752 -302.95161) (xy 403.979647 -303.000187) (xy 403.980142 -303.024794)
			(xy 404.31899 -303.024794) (xy 404.32295 -302.97574) (xy 404.334727 -302.927956) (xy 404.354018 -302.88268)
			(xy 404.380321 -302.841084) (xy 404.412956 -302.804247) (xy 404.451077 -302.773122) (xy 404.493698 -302.748515)
			(xy 404.539714 -302.731063) (xy 404.587933 -302.721219) (xy 404.637108 -302.719238) (xy 404.685963 -302.72517)
			(xy 404.733234 -302.738862) (xy 404.777696 -302.75996) (xy 404.818199 -302.787916) (xy 404.853692 -302.822008)
			(xy 404.883257 -302.861352) (xy 404.906128 -302.904929) (xy 404.921712 -302.95161) (xy 404.929607 -303.000187)
			(xy 404.930102 -303.024794) (xy 405.269204 -303.024794) (xy 405.273164 -302.97574) (xy 405.284941 -302.927956)
			(xy 405.304232 -302.88268) (xy 405.330535 -302.841084) (xy 405.36317 -302.804247) (xy 405.401291 -302.773122)
			(xy 405.443912 -302.748515) (xy 405.489928 -302.731063) (xy 405.538147 -302.721219) (xy 405.587322 -302.719238)
			(xy 405.636177 -302.72517) (xy 405.683448 -302.738862) (xy 405.72791 -302.75996) (xy 405.768413 -302.787916)
			(xy 405.803906 -302.822008) (xy 405.833471 -302.861352) (xy 405.856342 -302.904929) (xy 405.871926 -302.95161)
			(xy 405.879821 -303.000187) (xy 405.880316 -303.024794) (xy 406.219164 -303.024794) (xy 406.223124 -302.97574)
			(xy 406.234901 -302.927956) (xy 406.254192 -302.88268) (xy 406.280495 -302.841084) (xy 406.31313 -302.804247)
			(xy 406.351251 -302.773122) (xy 406.393872 -302.748515) (xy 406.439888 -302.731063) (xy 406.488107 -302.721219)
			(xy 406.537282 -302.719238) (xy 406.586137 -302.72517) (xy 406.633408 -302.738862) (xy 406.67787 -302.75996)
			(xy 406.718373 -302.787916) (xy 406.753866 -302.822008) (xy 406.783431 -302.861352) (xy 406.806302 -302.904929)
			(xy 406.821886 -302.95161) (xy 406.829781 -303.000187) (xy 406.830276 -303.024794) (xy 408.119084 -303.024794)
			(xy 408.123044 -302.97574) (xy 408.134821 -302.927956) (xy 408.154112 -302.88268) (xy 408.180415 -302.841084)
			(xy 408.21305 -302.804247) (xy 408.251171 -302.773122) (xy 408.293792 -302.748515) (xy 408.339808 -302.731063)
			(xy 408.388027 -302.721219) (xy 408.437202 -302.719238) (xy 408.486057 -302.72517) (xy 408.533328 -302.738862)
			(xy 408.57779 -302.75996) (xy 408.618293 -302.787916) (xy 408.653786 -302.822008) (xy 408.683351 -302.861352)
			(xy 408.706222 -302.904929) (xy 408.721806 -302.95161) (xy 408.729701 -303.000187) (xy 408.730196 -303.024794)
			(xy 409.069044 -303.024794) (xy 409.073004 -302.97574) (xy 409.084781 -302.927956) (xy 409.104072 -302.88268)
			(xy 409.130375 -302.841084) (xy 409.16301 -302.804247) (xy 409.201131 -302.773122) (xy 409.243752 -302.748515)
			(xy 409.289768 -302.731063) (xy 409.337987 -302.721219) (xy 409.387162 -302.719238) (xy 409.436017 -302.72517)
			(xy 409.483288 -302.738862) (xy 409.52775 -302.75996) (xy 409.568253 -302.787916) (xy 409.603746 -302.822008)
			(xy 409.633311 -302.861352) (xy 409.656182 -302.904929) (xy 409.671766 -302.95161) (xy 409.679661 -303.000187)
			(xy 409.680156 -303.024794) (xy 410.019004 -303.024794) (xy 410.022964 -302.97574) (xy 410.034741 -302.927956)
			(xy 410.054032 -302.88268) (xy 410.080335 -302.841084) (xy 410.11297 -302.804247) (xy 410.151091 -302.773122)
			(xy 410.193712 -302.748515) (xy 410.239728 -302.731063) (xy 410.287947 -302.721219) (xy 410.337122 -302.719238)
			(xy 410.385977 -302.72517) (xy 410.433248 -302.738862) (xy 410.47771 -302.75996) (xy 410.518213 -302.787916)
			(xy 410.553706 -302.822008) (xy 410.583271 -302.861352) (xy 410.606142 -302.904929) (xy 410.621726 -302.95161)
			(xy 410.629621 -303.000187) (xy 410.630116 -303.024794) (xy 410.969218 -303.024794) (xy 410.973178 -302.97574)
			(xy 410.984955 -302.927956) (xy 411.004246 -302.88268) (xy 411.030549 -302.841084) (xy 411.063184 -302.804247)
			(xy 411.101305 -302.773122) (xy 411.143926 -302.748515) (xy 411.189942 -302.731063) (xy 411.238161 -302.721219)
			(xy 411.287336 -302.719238) (xy 411.336191 -302.72517) (xy 411.383462 -302.738862) (xy 411.427924 -302.75996)
			(xy 411.468427 -302.787916) (xy 411.50392 -302.822008) (xy 411.533485 -302.861352) (xy 411.556356 -302.904929)
			(xy 411.57194 -302.95161) (xy 411.579835 -303.000187) (xy 411.58033 -303.024794) (xy 411.919178 -303.024794)
			(xy 411.923138 -302.97574) (xy 411.934915 -302.927956) (xy 411.954206 -302.88268) (xy 411.980509 -302.841084)
			(xy 412.013144 -302.804247) (xy 412.051265 -302.773122) (xy 412.093886 -302.748515) (xy 412.139902 -302.731063)
			(xy 412.188121 -302.721219) (xy 412.237296 -302.719238) (xy 412.286151 -302.72517) (xy 412.333422 -302.738862)
			(xy 412.377884 -302.75996) (xy 412.418387 -302.787916) (xy 412.45388 -302.822008) (xy 412.483445 -302.861352)
			(xy 412.506316 -302.904929) (xy 412.5219 -302.95161) (xy 412.529795 -303.000187) (xy 412.53029 -303.024794)
			(xy 412.869138 -303.024794) (xy 412.873098 -302.97574) (xy 412.884875 -302.927956) (xy 412.904166 -302.88268)
			(xy 412.930469 -302.841084) (xy 412.963104 -302.804247) (xy 413.001225 -302.773122) (xy 413.043846 -302.748515)
			(xy 413.089862 -302.731063) (xy 413.138081 -302.721219) (xy 413.187256 -302.719238) (xy 413.236111 -302.72517)
			(xy 413.283382 -302.738862) (xy 413.327844 -302.75996) (xy 413.368347 -302.787916) (xy 413.40384 -302.822008)
			(xy 413.433405 -302.861352) (xy 413.456276 -302.904929) (xy 413.47186 -302.95161) (xy 413.479755 -303.000187)
			(xy 413.48025 -303.024794) (xy 413.819098 -303.024794) (xy 413.823058 -302.97574) (xy 413.834835 -302.927956)
			(xy 413.854126 -302.88268) (xy 413.880429 -302.841084) (xy 413.913064 -302.804247) (xy 413.951185 -302.773122)
			(xy 413.993806 -302.748515) (xy 414.039822 -302.731063) (xy 414.088041 -302.721219) (xy 414.137216 -302.719238)
			(xy 414.186071 -302.72517) (xy 414.233342 -302.738862) (xy 414.277804 -302.75996) (xy 414.318307 -302.787916)
			(xy 414.3538 -302.822008) (xy 414.383365 -302.861352) (xy 414.406236 -302.904929) (xy 414.42182 -302.95161)
			(xy 414.429715 -303.000187) (xy 414.43021 -303.024794) (xy 414.769058 -303.024794) (xy 414.773018 -302.97574)
			(xy 414.784795 -302.927956) (xy 414.804086 -302.88268) (xy 414.830389 -302.841084) (xy 414.863024 -302.804247)
			(xy 414.901145 -302.773122) (xy 414.943766 -302.748515) (xy 414.989782 -302.731063) (xy 415.038001 -302.721219)
			(xy 415.087176 -302.719238) (xy 415.136031 -302.72517) (xy 415.183302 -302.738862) (xy 415.227764 -302.75996)
			(xy 415.268267 -302.787916) (xy 415.30376 -302.822008) (xy 415.333325 -302.861352) (xy 415.356196 -302.904929)
			(xy 415.37178 -302.95161) (xy 415.379675 -303.000187) (xy 415.38017 -303.024794) (xy 415.719018 -303.024794)
			(xy 415.722978 -302.97574) (xy 415.734755 -302.927956) (xy 415.754046 -302.88268) (xy 415.780349 -302.841084)
			(xy 415.812984 -302.804247) (xy 415.851105 -302.773122) (xy 415.893726 -302.748515) (xy 415.939742 -302.731063)
			(xy 415.987961 -302.721219) (xy 416.037136 -302.719238) (xy 416.085991 -302.72517) (xy 416.133262 -302.738862)
			(xy 416.177724 -302.75996) (xy 416.218227 -302.787916) (xy 416.25372 -302.822008) (xy 416.283285 -302.861352)
			(xy 416.306156 -302.904929) (xy 416.32174 -302.95161) (xy 416.329635 -303.000187) (xy 416.33013 -303.024794)
			(xy 416.668978 -303.024794) (xy 416.672938 -302.97574) (xy 416.684715 -302.927956) (xy 416.704006 -302.88268)
			(xy 416.730309 -302.841084) (xy 416.762944 -302.804247) (xy 416.801065 -302.773122) (xy 416.843686 -302.748515)
			(xy 416.889702 -302.731063) (xy 416.937921 -302.721219) (xy 416.987096 -302.719238) (xy 417.035951 -302.72517)
			(xy 417.083222 -302.738862) (xy 417.127684 -302.75996) (xy 417.168187 -302.787916) (xy 417.20368 -302.822008)
			(xy 417.233245 -302.861352) (xy 417.256116 -302.904929) (xy 417.2717 -302.95161) (xy 417.279595 -303.000187)
			(xy 417.28009 -303.024794) (xy 417.279595 -303.049401) (xy 417.2717 -303.097978) (xy 417.256116 -303.144659)
			(xy 417.233245 -303.188236) (xy 417.20368 -303.22758) (xy 417.168187 -303.261672) (xy 417.127684 -303.289628)
			(xy 417.083222 -303.310726) (xy 417.035951 -303.324418) (xy 416.987096 -303.33035) (xy 416.937921 -303.328369)
			(xy 416.889702 -303.318525) (xy 416.843686 -303.301073) (xy 416.801065 -303.276466) (xy 416.762944 -303.245341)
			(xy 416.730309 -303.208504) (xy 416.704006 -303.166908) (xy 416.684715 -303.121632) (xy 416.672938 -303.073848)
			(xy 416.668978 -303.024794) (xy 416.33013 -303.024794) (xy 416.329635 -303.049401) (xy 416.32174 -303.097978)
			(xy 416.306156 -303.144659) (xy 416.283285 -303.188236) (xy 416.25372 -303.22758) (xy 416.218227 -303.261672)
			(xy 416.177724 -303.289628) (xy 416.133262 -303.310726) (xy 416.085991 -303.324418) (xy 416.037136 -303.33035)
			(xy 415.987961 -303.328369) (xy 415.939742 -303.318525) (xy 415.893726 -303.301073) (xy 415.851105 -303.276466)
			(xy 415.812984 -303.245341) (xy 415.780349 -303.208504) (xy 415.754046 -303.166908) (xy 415.734755 -303.121632)
			(xy 415.722978 -303.073848) (xy 415.719018 -303.024794) (xy 415.38017 -303.024794) (xy 415.379675 -303.049401)
			(xy 415.37178 -303.097978) (xy 415.356196 -303.144659) (xy 415.333325 -303.188236) (xy 415.30376 -303.22758)
			(xy 415.268267 -303.261672) (xy 415.227764 -303.289628) (xy 415.183302 -303.310726) (xy 415.136031 -303.324418)
			(xy 415.087176 -303.33035) (xy 415.038001 -303.328369) (xy 414.989782 -303.318525) (xy 414.943766 -303.301073)
			(xy 414.901145 -303.276466) (xy 414.863024 -303.245341) (xy 414.830389 -303.208504) (xy 414.804086 -303.166908)
			(xy 414.784795 -303.121632) (xy 414.773018 -303.073848) (xy 414.769058 -303.024794) (xy 414.43021 -303.024794)
			(xy 414.429715 -303.049401) (xy 414.42182 -303.097978) (xy 414.406236 -303.144659) (xy 414.383365 -303.188236)
			(xy 414.3538 -303.22758) (xy 414.318307 -303.261672) (xy 414.277804 -303.289628) (xy 414.233342 -303.310726)
			(xy 414.186071 -303.324418) (xy 414.137216 -303.33035) (xy 414.088041 -303.328369) (xy 414.039822 -303.318525)
			(xy 413.993806 -303.301073) (xy 413.951185 -303.276466) (xy 413.913064 -303.245341) (xy 413.880429 -303.208504)
			(xy 413.854126 -303.166908) (xy 413.834835 -303.121632) (xy 413.823058 -303.073848) (xy 413.819098 -303.024794)
			(xy 413.48025 -303.024794) (xy 413.479755 -303.049401) (xy 413.47186 -303.097978) (xy 413.456276 -303.144659)
			(xy 413.433405 -303.188236) (xy 413.40384 -303.22758) (xy 413.368347 -303.261672) (xy 413.327844 -303.289628)
			(xy 413.283382 -303.310726) (xy 413.236111 -303.324418) (xy 413.187256 -303.33035) (xy 413.138081 -303.328369)
			(xy 413.089862 -303.318525) (xy 413.043846 -303.301073) (xy 413.001225 -303.276466) (xy 412.963104 -303.245341)
			(xy 412.930469 -303.208504) (xy 412.904166 -303.166908) (xy 412.884875 -303.121632) (xy 412.873098 -303.073848)
			(xy 412.869138 -303.024794) (xy 412.53029 -303.024794) (xy 412.529795 -303.049401) (xy 412.5219 -303.097978)
			(xy 412.506316 -303.144659) (xy 412.483445 -303.188236) (xy 412.45388 -303.22758) (xy 412.418387 -303.261672)
			(xy 412.377884 -303.289628) (xy 412.333422 -303.310726) (xy 412.286151 -303.324418) (xy 412.237296 -303.33035)
			(xy 412.188121 -303.328369) (xy 412.139902 -303.318525) (xy 412.093886 -303.301073) (xy 412.051265 -303.276466)
			(xy 412.013144 -303.245341) (xy 411.980509 -303.208504) (xy 411.954206 -303.166908) (xy 411.934915 -303.121632)
			(xy 411.923138 -303.073848) (xy 411.919178 -303.024794) (xy 411.58033 -303.024794) (xy 411.579835 -303.049401)
			(xy 411.57194 -303.097978) (xy 411.556356 -303.144659) (xy 411.533485 -303.188236) (xy 411.50392 -303.22758)
			(xy 411.468427 -303.261672) (xy 411.427924 -303.289628) (xy 411.383462 -303.310726) (xy 411.336191 -303.324418)
			(xy 411.287336 -303.33035) (xy 411.238161 -303.328369) (xy 411.189942 -303.318525) (xy 411.143926 -303.301073)
			(xy 411.101305 -303.276466) (xy 411.063184 -303.245341) (xy 411.030549 -303.208504) (xy 411.004246 -303.166908)
			(xy 410.984955 -303.121632) (xy 410.973178 -303.073848) (xy 410.969218 -303.024794) (xy 410.630116 -303.024794)
			(xy 410.629621 -303.049401) (xy 410.621726 -303.097978) (xy 410.606142 -303.144659) (xy 410.583271 -303.188236)
			(xy 410.553706 -303.22758) (xy 410.518213 -303.261672) (xy 410.47771 -303.289628) (xy 410.433248 -303.310726)
			(xy 410.385977 -303.324418) (xy 410.337122 -303.33035) (xy 410.287947 -303.328369) (xy 410.239728 -303.318525)
			(xy 410.193712 -303.301073) (xy 410.151091 -303.276466) (xy 410.11297 -303.245341) (xy 410.080335 -303.208504)
			(xy 410.054032 -303.166908) (xy 410.034741 -303.121632) (xy 410.022964 -303.073848) (xy 410.019004 -303.024794)
			(xy 409.680156 -303.024794) (xy 409.679661 -303.049401) (xy 409.671766 -303.097978) (xy 409.656182 -303.144659)
			(xy 409.633311 -303.188236) (xy 409.603746 -303.22758) (xy 409.568253 -303.261672) (xy 409.52775 -303.289628)
			(xy 409.483288 -303.310726) (xy 409.436017 -303.324418) (xy 409.387162 -303.33035) (xy 409.337987 -303.328369)
			(xy 409.289768 -303.318525) (xy 409.243752 -303.301073) (xy 409.201131 -303.276466) (xy 409.16301 -303.245341)
			(xy 409.130375 -303.208504) (xy 409.104072 -303.166908) (xy 409.084781 -303.121632) (xy 409.073004 -303.073848)
			(xy 409.069044 -303.024794) (xy 408.730196 -303.024794) (xy 408.729701 -303.049401) (xy 408.721806 -303.097978)
			(xy 408.706222 -303.144659) (xy 408.683351 -303.188236) (xy 408.653786 -303.22758) (xy 408.618293 -303.261672)
			(xy 408.57779 -303.289628) (xy 408.533328 -303.310726) (xy 408.486057 -303.324418) (xy 408.437202 -303.33035)
			(xy 408.388027 -303.328369) (xy 408.339808 -303.318525) (xy 408.293792 -303.301073) (xy 408.251171 -303.276466)
			(xy 408.21305 -303.245341) (xy 408.180415 -303.208504) (xy 408.154112 -303.166908) (xy 408.134821 -303.121632)
			(xy 408.123044 -303.073848) (xy 408.119084 -303.024794) (xy 406.830276 -303.024794) (xy 406.829781 -303.049401)
			(xy 406.821886 -303.097978) (xy 406.806302 -303.144659) (xy 406.783431 -303.188236) (xy 406.753866 -303.22758)
			(xy 406.718373 -303.261672) (xy 406.67787 -303.289628) (xy 406.633408 -303.310726) (xy 406.586137 -303.324418)
			(xy 406.537282 -303.33035) (xy 406.488107 -303.328369) (xy 406.439888 -303.318525) (xy 406.393872 -303.301073)
			(xy 406.351251 -303.276466) (xy 406.31313 -303.245341) (xy 406.280495 -303.208504) (xy 406.254192 -303.166908)
			(xy 406.234901 -303.121632) (xy 406.223124 -303.073848) (xy 406.219164 -303.024794) (xy 405.880316 -303.024794)
			(xy 405.879821 -303.049401) (xy 405.871926 -303.097978) (xy 405.856342 -303.144659) (xy 405.833471 -303.188236)
			(xy 405.803906 -303.22758) (xy 405.768413 -303.261672) (xy 405.72791 -303.289628) (xy 405.683448 -303.310726)
			(xy 405.636177 -303.324418) (xy 405.587322 -303.33035) (xy 405.538147 -303.328369) (xy 405.489928 -303.318525)
			(xy 405.443912 -303.301073) (xy 405.401291 -303.276466) (xy 405.36317 -303.245341) (xy 405.330535 -303.208504)
			(xy 405.304232 -303.166908) (xy 405.284941 -303.121632) (xy 405.273164 -303.073848) (xy 405.269204 -303.024794)
			(xy 404.930102 -303.024794) (xy 404.929607 -303.049401) (xy 404.921712 -303.097978) (xy 404.906128 -303.144659)
			(xy 404.883257 -303.188236) (xy 404.853692 -303.22758) (xy 404.818199 -303.261672) (xy 404.777696 -303.289628)
			(xy 404.733234 -303.310726) (xy 404.685963 -303.324418) (xy 404.637108 -303.33035) (xy 404.587933 -303.328369)
			(xy 404.539714 -303.318525) (xy 404.493698 -303.301073) (xy 404.451077 -303.276466) (xy 404.412956 -303.245341)
			(xy 404.380321 -303.208504) (xy 404.354018 -303.166908) (xy 404.334727 -303.121632) (xy 404.32295 -303.073848)
			(xy 404.31899 -303.024794) (xy 403.980142 -303.024794) (xy 403.979647 -303.049401) (xy 403.971752 -303.097978)
			(xy 403.956168 -303.144659) (xy 403.933297 -303.188236) (xy 403.903732 -303.22758) (xy 403.868239 -303.261672)
			(xy 403.827736 -303.289628) (xy 403.783274 -303.310726) (xy 403.736003 -303.324418) (xy 403.687148 -303.33035)
			(xy 403.637973 -303.328369) (xy 403.589754 -303.318525) (xy 403.543738 -303.301073) (xy 403.501117 -303.276466)
			(xy 403.462996 -303.245341) (xy 403.430361 -303.208504) (xy 403.404058 -303.166908) (xy 403.384767 -303.121632)
			(xy 403.37299 -303.073848) (xy 403.36903 -303.024794) (xy 403.030182 -303.024794) (xy 403.029687 -303.049401)
			(xy 403.021792 -303.097978) (xy 403.006208 -303.144659) (xy 402.983337 -303.188236) (xy 402.953772 -303.22758)
			(xy 402.918279 -303.261672) (xy 402.877776 -303.289628) (xy 402.833314 -303.310726) (xy 402.786043 -303.324418)
			(xy 402.737188 -303.33035) (xy 402.688013 -303.328369) (xy 402.639794 -303.318525) (xy 402.593778 -303.301073)
			(xy 402.551157 -303.276466) (xy 402.513036 -303.245341) (xy 402.480401 -303.208504) (xy 402.454098 -303.166908)
			(xy 402.434807 -303.121632) (xy 402.42303 -303.073848) (xy 402.41907 -303.024794) (xy 402.080222 -303.024794)
			(xy 402.079727 -303.049401) (xy 402.071832 -303.097978) (xy 402.056248 -303.144659) (xy 402.033377 -303.188236)
			(xy 402.003812 -303.22758) (xy 401.968319 -303.261672) (xy 401.927816 -303.289628) (xy 401.883354 -303.310726)
			(xy 401.836083 -303.324418) (xy 401.787228 -303.33035) (xy 401.738053 -303.328369) (xy 401.689834 -303.318525)
			(xy 401.643818 -303.301073) (xy 401.601197 -303.276466) (xy 401.563076 -303.245341) (xy 401.530441 -303.208504)
			(xy 401.504138 -303.166908) (xy 401.484847 -303.121632) (xy 401.47307 -303.073848) (xy 401.46911 -303.024794)
			(xy 401.130262 -303.024794) (xy 401.129767 -303.049401) (xy 401.121872 -303.097978) (xy 401.106288 -303.144659)
			(xy 401.083417 -303.188236) (xy 401.053852 -303.22758) (xy 401.018359 -303.261672) (xy 400.977856 -303.289628)
			(xy 400.933394 -303.310726) (xy 400.886123 -303.324418) (xy 400.837268 -303.33035) (xy 400.788093 -303.328369)
			(xy 400.739874 -303.318525) (xy 400.693858 -303.301073) (xy 400.651237 -303.276466) (xy 400.613116 -303.245341)
			(xy 400.580481 -303.208504) (xy 400.554178 -303.166908) (xy 400.534887 -303.121632) (xy 400.52311 -303.073848)
			(xy 400.51915 -303.024794) (xy 400.180302 -303.024794) (xy 400.179807 -303.049401) (xy 400.171912 -303.097978)
			(xy 400.156328 -303.144659) (xy 400.133457 -303.188236) (xy 400.103892 -303.22758) (xy 400.068399 -303.261672)
			(xy 400.027896 -303.289628) (xy 399.983434 -303.310726) (xy 399.936163 -303.324418) (xy 399.887308 -303.33035)
			(xy 399.838133 -303.328369) (xy 399.789914 -303.318525) (xy 399.743898 -303.301073) (xy 399.701277 -303.276466)
			(xy 399.663156 -303.245341) (xy 399.630521 -303.208504) (xy 399.604218 -303.166908) (xy 399.584927 -303.121632)
			(xy 399.57315 -303.073848) (xy 399.56919 -303.024794) (xy 399.230342 -303.024794) (xy 399.229847 -303.049401)
			(xy 399.221952 -303.097978) (xy 399.206368 -303.144659) (xy 399.183497 -303.188236) (xy 399.153932 -303.22758)
			(xy 399.118439 -303.261672) (xy 399.077936 -303.289628) (xy 399.033474 -303.310726) (xy 398.986203 -303.324418)
			(xy 398.937348 -303.33035) (xy 398.888173 -303.328369) (xy 398.839954 -303.318525) (xy 398.793938 -303.301073)
			(xy 398.751317 -303.276466) (xy 398.713196 -303.245341) (xy 398.680561 -303.208504) (xy 398.654258 -303.166908)
			(xy 398.634967 -303.121632) (xy 398.62319 -303.073848) (xy 398.61923 -303.024794) (xy 398.280128 -303.024794)
			(xy 398.279633 -303.049401) (xy 398.271738 -303.097978) (xy 398.256154 -303.144659) (xy 398.233283 -303.188236)
			(xy 398.203718 -303.22758) (xy 398.168225 -303.261672) (xy 398.127722 -303.289628) (xy 398.08326 -303.310726)
			(xy 398.035989 -303.324418) (xy 397.987134 -303.33035) (xy 397.937959 -303.328369) (xy 397.88974 -303.318525)
			(xy 397.843724 -303.301073) (xy 397.801103 -303.276466) (xy 397.762982 -303.245341) (xy 397.730347 -303.208504)
			(xy 397.704044 -303.166908) (xy 397.684753 -303.121632) (xy 397.672976 -303.073848) (xy 397.669016 -303.024794)
			(xy 397.330168 -303.024794) (xy 397.329673 -303.049401) (xy 397.321778 -303.097978) (xy 397.306194 -303.144659)
			(xy 397.283323 -303.188236) (xy 397.253758 -303.22758) (xy 397.218265 -303.261672) (xy 397.177762 -303.289628)
			(xy 397.1333 -303.310726) (xy 397.086029 -303.324418) (xy 397.037174 -303.33035) (xy 396.987999 -303.328369)
			(xy 396.93978 -303.318525) (xy 396.893764 -303.301073) (xy 396.851143 -303.276466) (xy 396.813022 -303.245341)
			(xy 396.780387 -303.208504) (xy 396.754084 -303.166908) (xy 396.734793 -303.121632) (xy 396.723016 -303.073848)
			(xy 396.719056 -303.024794) (xy 396.380208 -303.024794) (xy 396.379713 -303.049401) (xy 396.371818 -303.097978)
			(xy 396.356234 -303.144659) (xy 396.333363 -303.188236) (xy 396.303798 -303.22758) (xy 396.268305 -303.261672)
			(xy 396.227802 -303.289628) (xy 396.18334 -303.310726) (xy 396.136069 -303.324418) (xy 396.087214 -303.33035)
			(xy 396.038039 -303.328369) (xy 395.98982 -303.318525) (xy 395.943804 -303.301073) (xy 395.901183 -303.276466)
			(xy 395.863062 -303.245341) (xy 395.830427 -303.208504) (xy 395.804124 -303.166908) (xy 395.784833 -303.121632)
			(xy 395.773056 -303.073848) (xy 395.769096 -303.024794) (xy 395.430248 -303.024794) (xy 395.429753 -303.049401)
			(xy 395.421858 -303.097978) (xy 395.406274 -303.144659) (xy 395.383403 -303.188236) (xy 395.353838 -303.22758)
			(xy 395.318345 -303.261672) (xy 395.277842 -303.289628) (xy 395.23338 -303.310726) (xy 395.186109 -303.324418)
			(xy 395.137254 -303.33035) (xy 395.088079 -303.328369) (xy 395.03986 -303.318525) (xy 394.993844 -303.301073)
			(xy 394.951223 -303.276466) (xy 394.913102 -303.245341) (xy 394.880467 -303.208504) (xy 394.854164 -303.166908)
			(xy 394.834873 -303.121632) (xy 394.823096 -303.073848) (xy 394.819136 -303.024794) (xy 394.480854 -303.024794)
			(xy 394.480854 -303.0248) (xy 394.476682 -303.075144) (xy 394.464281 -303.124115) (xy 394.443988 -303.170376)
			(xy 394.416357 -303.212666) (xy 394.382142 -303.249831) (xy 394.342276 -303.280858) (xy 394.297847 -303.304899)
			(xy 394.250066 -303.321299) (xy 394.200238 -303.329611) (xy 394.17498 -303.330102) (xy 394.160797 -303.329928)
			(xy 394.132557 -303.327254) (xy 394.118592 -303.324768) (xy 394.106146 -303.322482) (xy 394.082524 -303.329848)
			(xy 394.005054 -303.407318) (xy 393.997688 -303.43094) (xy 393.999974 -303.443386) (xy 394.002444 -303.457353)
			(xy 394.00512 -303.485592) (xy 394.005308 -303.499774) (xy 394.00485 -303.524597) (xy 393.996822 -303.573591)
			(xy 393.980974 -303.62064) (xy 393.957722 -303.664505) (xy 393.92768 -303.704031) (xy 393.891639 -303.738176)
			(xy 393.850549 -303.76604) (xy 393.805492 -303.786889) (xy 393.757655 -303.800174) (xy 393.7083 -303.805544)
			(xy 393.658726 -303.802859) (xy 393.610239 -303.792189) (xy 393.564117 -303.773815) (xy 393.521576 -303.748222)
			(xy 393.483736 -303.716083) (xy 393.451593 -303.678245) (xy 393.425996 -303.635706) (xy 393.407618 -303.589586)
			(xy 393.396944 -303.5411) (xy 393.394255 -303.491526) (xy 393.399621 -303.44217) (xy 393.412902 -303.394333)
			(xy 393.433747 -303.349274) (xy 393.461608 -303.308181) (xy 393.495749 -303.272138) (xy 393.535273 -303.242092)
			(xy 393.579136 -303.218837) (xy 393.626184 -303.202984) (xy 393.675177 -303.194952) (xy 393.7 -303.194466)
			(xy 393.714183 -303.194643) (xy 393.742423 -303.197315) (xy 393.756388 -303.1998) (xy 393.768834 -303.202086)
			(xy 393.792456 -303.19472) (xy 393.869926 -303.11725) (xy 393.877292 -303.093628) (xy 393.875006 -303.081182)
			(xy 393.872531 -303.067216) (xy 393.869858 -303.038976) (xy 393.869672 -303.024794) (xy 393.869848 -303.010611)
			(xy 393.872521 -302.982371) (xy 393.875006 -302.968406) (xy 393.877292 -302.95596) (xy 393.869926 -302.932338)
			(xy 393.792456 -302.854868) (xy 393.768834 -302.847502) (xy 393.756388 -302.849788) (xy 393.742422 -302.852262)
			(xy 393.714182 -302.854935) (xy 393.7 -302.855122) (xy 393.674746 -302.854572) (xy 393.624926 -302.846259)
			(xy 393.577155 -302.829859) (xy 393.532734 -302.80582) (xy 393.492876 -302.774797) (xy 393.458667 -302.737637)
			(xy 393.431042 -302.695353) (xy 393.410753 -302.649099) (xy 393.398354 -302.600136) (xy 393.394183 -302.5498)
			(xy 393.398354 -302.499464) (xy 393.410753 -302.450501) (xy 393.431042 -302.404247) (xy 393.458667 -302.361963)
			(xy 393.492876 -302.324803) (xy 393.532734 -302.29378) (xy 393.577155 -302.269741) (xy 393.624926 -302.253341)
			(xy 393.674746 -302.245028) (xy 393.7 -302.244506) (xy 393.714183 -302.244682) (xy 393.742423 -302.247355)
			(xy 393.756388 -302.24984) (xy 393.768834 -302.252126) (xy 393.792456 -302.24476) (xy 393.869926 -302.16729)
			(xy 393.877292 -302.143668) (xy 393.875006 -302.131222) (xy 393.872523 -302.117257) (xy 393.869855 -302.089017)
			(xy 393.869672 -302.074834) (xy 393.869854 -302.060651) (xy 393.872522 -302.032411) (xy 393.875006 -302.018446)
			(xy 393.877292 -302.006) (xy 393.869926 -301.982378) (xy 393.792456 -301.904908) (xy 393.768834 -301.897542)
			(xy 393.756388 -301.899828) (xy 393.742422 -301.902302) (xy 393.714182 -301.904976) (xy 393.7 -301.905162)
			(xy 393.676005 -301.904762) (xy 393.628605 -301.897253) (xy 393.582963 -301.882422) (xy 393.540204 -301.860633)
			(xy 393.50138 -301.832422) (xy 393.467448 -301.798485) (xy 393.439243 -301.759657) (xy 393.41746 -301.716894)
			(xy 393.402636 -301.671251) (xy 393.395135 -301.62385) (xy 393.394692 -301.599854) (xy 393.394876 -301.585671)
			(xy 393.397543 -301.557431) (xy 393.400026 -301.543466) (xy 393.402312 -301.53102) (xy 393.394946 -301.507398)
			(xy 393.317476 -301.429928) (xy 393.293854 -301.422562) (xy 393.281408 -301.424848) (xy 393.267441 -301.427319)
			(xy 393.239202 -301.429995) (xy 393.22502 -301.430182) (xy 393.210773 -301.43002) (xy 393.182405 -301.427344)
			(xy 393.168378 -301.424848) (xy 393.156186 -301.422562) (xy 393.132056 -301.429928) (xy 393.05484 -301.507144)
			(xy 393.047474 -301.53102) (xy 393.04976 -301.543466) (xy 393.052241 -301.557431) (xy 393.05491 -301.585671)
			(xy 393.055094 -301.599854) (xy 393.054672 -301.624679) (xy 393.046647 -301.673677) (xy 393.0308 -301.72073)
			(xy 393.00755 -301.7646) (xy 392.977508 -301.804131) (xy 392.941466 -301.83828) (xy 392.900375 -301.866148)
			(xy 392.855316 -301.887002) (xy 392.807477 -301.90029) (xy 392.758119 -301.905664) (xy 392.708541 -301.902982)
			(xy 392.66005 -301.892314) (xy 392.613924 -301.873942) (xy 392.571378 -301.848348) (xy 392.533533 -301.816209)
			(xy 392.501387 -301.778371) (xy 392.475785 -301.73583) (xy 392.457404 -301.689708) (xy 392.446726 -301.641219)
			(xy 392.444034 -301.591642) (xy 392.104969 -301.591642) (xy 392.105134 -301.599854) (xy 392.104639 -301.624461)
			(xy 392.096744 -301.673038) (xy 392.08116 -301.719719) (xy 392.058289 -301.763296) (xy 392.028724 -301.80264)
			(xy 391.993231 -301.836732) (xy 391.952728 -301.864688) (xy 391.908266 -301.885786) (xy 391.860995 -301.899478)
			(xy 391.81214 -301.90541) (xy 391.762965 -301.903429) (xy 391.714746 -301.893585) (xy 391.66873 -301.876133)
			(xy 391.626109 -301.851526) (xy 391.587988 -301.820401) (xy 391.555353 -301.783564) (xy 391.52905 -301.741968)
			(xy 391.509759 -301.696692) (xy 391.497982 -301.648908) (xy 391.494022 -301.599854) (xy 391.177018 -301.599854)
			(xy 391.176514 -301.625562) (xy 391.168471 -301.676344) (xy 391.152583 -301.725243) (xy 391.12924 -301.771055)
			(xy 391.099019 -301.812651) (xy 391.062663 -301.849007) (xy 391.021067 -301.879228) (xy 390.975255 -301.902571)
			(xy 390.926356 -301.918459) (xy 390.875574 -301.926502) (xy 390.824158 -301.926502) (xy 390.773376 -301.918459)
			(xy 390.724477 -301.902571) (xy 390.678665 -301.879228) (xy 390.637069 -301.849007) (xy 390.600713 -301.812651)
			(xy 390.570492 -301.771055) (xy 390.547149 -301.725243) (xy 390.531261 -301.676344) (xy 390.523218 -301.625562)
			(xy 390.226554 -301.625562) (xy 390.218511 -301.676344) (xy 390.202623 -301.725243) (xy 390.17928 -301.771055)
			(xy 390.149059 -301.812651) (xy 390.112703 -301.849007) (xy 390.071107 -301.879228) (xy 390.025295 -301.902571)
			(xy 389.976396 -301.918459) (xy 389.925614 -301.926502) (xy 389.874198 -301.926502) (xy 389.823416 -301.918459)
			(xy 389.774517 -301.902571) (xy 389.728705 -301.879228) (xy 389.687109 -301.849007) (xy 389.650753 -301.812651)
			(xy 389.620532 -301.771055) (xy 389.597189 -301.725243) (xy 389.581301 -301.676344) (xy 389.573258 -301.625562)
			(xy 389.25458 -301.625562) (xy 389.246864 -301.673038) (xy 389.23128 -301.719719) (xy 389.208409 -301.763296)
			(xy 389.178844 -301.80264) (xy 389.143351 -301.836732) (xy 389.102848 -301.864688) (xy 389.058386 -301.885786)
			(xy 389.011115 -301.899478) (xy 388.96226 -301.90541) (xy 388.913085 -301.903429) (xy 388.864866 -301.893585)
			(xy 388.81885 -301.876133) (xy 388.776229 -301.851526) (xy 388.738108 -301.820401) (xy 388.705473 -301.783564)
			(xy 388.67917 -301.741968) (xy 388.659879 -301.696692) (xy 388.648102 -301.648908) (xy 388.644142 -301.599854)
			(xy 388.327138 -301.599854) (xy 388.326634 -301.625562) (xy 388.318591 -301.676344) (xy 388.302703 -301.725243)
			(xy 388.27936 -301.771055) (xy 388.249139 -301.812651) (xy 388.212783 -301.849007) (xy 388.171187 -301.879228)
			(xy 388.125375 -301.902571) (xy 388.076476 -301.918459) (xy 388.025694 -301.926502) (xy 387.974278 -301.926502)
			(xy 387.923496 -301.918459) (xy 387.874597 -301.902571) (xy 387.828785 -301.879228) (xy 387.787189 -301.849007)
			(xy 387.750833 -301.812651) (xy 387.720612 -301.771055) (xy 387.697269 -301.725243) (xy 387.681381 -301.676344)
			(xy 387.673338 -301.625562) (xy 387.376674 -301.625562) (xy 387.368631 -301.676344) (xy 387.352743 -301.725243)
			(xy 387.3294 -301.771055) (xy 387.299179 -301.812651) (xy 387.262823 -301.849007) (xy 387.221227 -301.879228)
			(xy 387.175415 -301.902571) (xy 387.126516 -301.918459) (xy 387.075734 -301.926502) (xy 387.024318 -301.926502)
			(xy 386.973536 -301.918459) (xy 386.924637 -301.902571) (xy 386.878825 -301.879228) (xy 386.837229 -301.849007)
			(xy 386.800873 -301.812651) (xy 386.770652 -301.771055) (xy 386.747309 -301.725243) (xy 386.731421 -301.676344)
			(xy 386.723378 -301.625562) (xy 386.404446 -301.625562) (xy 386.39673 -301.673038) (xy 386.381146 -301.719719)
			(xy 386.358275 -301.763296) (xy 386.32871 -301.80264) (xy 386.293217 -301.836732) (xy 386.252714 -301.864688)
			(xy 386.208252 -301.885786) (xy 386.160981 -301.899478) (xy 386.112126 -301.90541) (xy 386.062951 -301.903429)
			(xy 386.014732 -301.893585) (xy 385.968716 -301.876133) (xy 385.926095 -301.851526) (xy 385.887974 -301.820401)
			(xy 385.855339 -301.783564) (xy 385.829036 -301.741968) (xy 385.809745 -301.696692) (xy 385.797968 -301.648908)
			(xy 385.794008 -301.599854) (xy 385.45516 -301.599854) (xy 385.454665 -301.624461) (xy 385.44677 -301.673038)
			(xy 385.431186 -301.719719) (xy 385.408315 -301.763296) (xy 385.37875 -301.80264) (xy 385.343257 -301.836732)
			(xy 385.302754 -301.864688) (xy 385.258292 -301.885786) (xy 385.211021 -301.899478) (xy 385.162166 -301.90541)
			(xy 385.112991 -301.903429) (xy 385.064772 -301.893585) (xy 385.018756 -301.876133) (xy 384.976135 -301.851526)
			(xy 384.938014 -301.820401) (xy 384.905379 -301.783564) (xy 384.879076 -301.741968) (xy 384.859785 -301.696692)
			(xy 384.848008 -301.648908) (xy 384.844048 -301.599854) (xy 351.03308 -301.599854) (xy 351.03308 -302.550068)
			(xy 383.893834 -302.550068) (xy 383.897794 -302.501014) (xy 383.909571 -302.45323) (xy 383.928862 -302.407954)
			(xy 383.955165 -302.366358) (xy 383.9878 -302.329521) (xy 384.025921 -302.298396) (xy 384.068542 -302.273789)
			(xy 384.114558 -302.256337) (xy 384.162777 -302.246493) (xy 384.211952 -302.244512) (xy 384.260807 -302.250444)
			(xy 384.308078 -302.264136) (xy 384.35254 -302.285234) (xy 384.393043 -302.31319) (xy 384.428536 -302.347282)
			(xy 384.458101 -302.386626) (xy 384.480972 -302.430203) (xy 384.496556 -302.476884) (xy 384.504451 -302.525461)
			(xy 384.504946 -302.550068) (xy 384.504451 -302.574675) (xy 384.504313 -302.575522) (xy 384.823204 -302.575522)
			(xy 384.823204 -302.524106) (xy 384.831247 -302.473324) (xy 384.847135 -302.424425) (xy 384.870478 -302.378613)
			(xy 384.900699 -302.337017) (xy 384.937055 -302.300661) (xy 384.978651 -302.27044) (xy 385.024463 -302.247097)
			(xy 385.073362 -302.231209) (xy 385.124144 -302.223166) (xy 385.17556 -302.223166) (xy 385.226342 -302.231209)
			(xy 385.275241 -302.247097) (xy 385.321053 -302.27044) (xy 385.362649 -302.300661) (xy 385.399005 -302.337017)
			(xy 385.429226 -302.378613) (xy 385.452569 -302.424425) (xy 385.468457 -302.473324) (xy 385.4765 -302.524106)
			(xy 385.477004 -302.549814) (xy 385.4765 -302.575522) (xy 385.773164 -302.575522) (xy 385.773164 -302.524106)
			(xy 385.781207 -302.473324) (xy 385.797095 -302.424425) (xy 385.820438 -302.378613) (xy 385.850659 -302.337017)
			(xy 385.887015 -302.300661) (xy 385.928611 -302.27044) (xy 385.974423 -302.247097) (xy 386.023322 -302.231209)
			(xy 386.074104 -302.223166) (xy 386.12552 -302.223166) (xy 386.176302 -302.231209) (xy 386.225201 -302.247097)
			(xy 386.271013 -302.27044) (xy 386.312609 -302.300661) (xy 386.348965 -302.337017) (xy 386.379186 -302.378613)
			(xy 386.402529 -302.424425) (xy 386.418417 -302.473324) (xy 386.42646 -302.524106) (xy 386.426964 -302.549814)
			(xy 386.744222 -302.549814) (xy 386.748182 -302.50076) (xy 386.759959 -302.452976) (xy 386.77925 -302.4077)
			(xy 386.805553 -302.366104) (xy 386.838188 -302.329267) (xy 386.876309 -302.298142) (xy 386.91893 -302.273535)
			(xy 386.964946 -302.256083) (xy 387.013165 -302.246239) (xy 387.06234 -302.244258) (xy 387.111195 -302.25019)
			(xy 387.158466 -302.263882) (xy 387.202928 -302.28498) (xy 387.243431 -302.312936) (xy 387.278924 -302.347028)
			(xy 387.308489 -302.386372) (xy 387.33136 -302.429949) (xy 387.346944 -302.47663) (xy 387.354839 -302.525207)
			(xy 387.355334 -302.549814) (xy 387.694182 -302.549814) (xy 387.698142 -302.50076) (xy 387.709919 -302.452976)
			(xy 387.72921 -302.4077) (xy 387.755513 -302.366104) (xy 387.788148 -302.329267) (xy 387.826269 -302.298142)
			(xy 387.86889 -302.273535) (xy 387.914906 -302.256083) (xy 387.963125 -302.246239) (xy 388.0123 -302.244258)
			(xy 388.061155 -302.25019) (xy 388.108426 -302.263882) (xy 388.152888 -302.28498) (xy 388.193391 -302.312936)
			(xy 388.228884 -302.347028) (xy 388.258449 -302.386372) (xy 388.28132 -302.429949) (xy 388.296904 -302.47663)
			(xy 388.304799 -302.525207) (xy 388.305294 -302.549814) (xy 388.644142 -302.549814) (xy 388.648102 -302.50076)
			(xy 388.659879 -302.452976) (xy 388.67917 -302.4077) (xy 388.705473 -302.366104) (xy 388.738108 -302.329267)
			(xy 388.776229 -302.298142) (xy 388.81885 -302.273535) (xy 388.864866 -302.256083) (xy 388.913085 -302.246239)
			(xy 388.96226 -302.244258) (xy 389.011115 -302.25019) (xy 389.058386 -302.263882) (xy 389.102848 -302.28498)
			(xy 389.143351 -302.312936) (xy 389.178844 -302.347028) (xy 389.208409 -302.386372) (xy 389.23128 -302.429949)
			(xy 389.246864 -302.47663) (xy 389.254759 -302.525207) (xy 389.255254 -302.549814) (xy 389.594102 -302.549814)
			(xy 389.598062 -302.50076) (xy 389.609839 -302.452976) (xy 389.62913 -302.4077) (xy 389.655433 -302.366104)
			(xy 389.688068 -302.329267) (xy 389.726189 -302.298142) (xy 389.76881 -302.273535) (xy 389.814826 -302.256083)
			(xy 389.863045 -302.246239) (xy 389.91222 -302.244258) (xy 389.961075 -302.25019) (xy 390.008346 -302.263882)
			(xy 390.052808 -302.28498) (xy 390.093311 -302.312936) (xy 390.128804 -302.347028) (xy 390.158369 -302.386372)
			(xy 390.18124 -302.429949) (xy 390.196824 -302.47663) (xy 390.204719 -302.525207) (xy 390.205214 -302.549814)
			(xy 390.544062 -302.549814) (xy 390.548022 -302.50076) (xy 390.559799 -302.452976) (xy 390.57909 -302.4077)
			(xy 390.605393 -302.366104) (xy 390.638028 -302.329267) (xy 390.676149 -302.298142) (xy 390.71877 -302.273535)
			(xy 390.764786 -302.256083) (xy 390.813005 -302.246239) (xy 390.86218 -302.244258) (xy 390.911035 -302.25019)
			(xy 390.958306 -302.263882) (xy 391.002768 -302.28498) (xy 391.043271 -302.312936) (xy 391.078764 -302.347028)
			(xy 391.108329 -302.386372) (xy 391.1312 -302.429949) (xy 391.146784 -302.47663) (xy 391.154679 -302.525207)
			(xy 391.155174 -302.549814) (xy 391.154679 -302.574421) (xy 391.1545 -302.575522) (xy 391.473178 -302.575522)
			(xy 391.473178 -302.524106) (xy 391.481221 -302.473324) (xy 391.497109 -302.424425) (xy 391.520452 -302.378613)
			(xy 391.550673 -302.337017) (xy 391.587029 -302.300661) (xy 391.628625 -302.27044) (xy 391.674437 -302.247097)
			(xy 391.723336 -302.231209) (xy 391.774118 -302.223166) (xy 391.825534 -302.223166) (xy 391.876316 -302.231209)
			(xy 391.925215 -302.247097) (xy 391.971027 -302.27044) (xy 392.012623 -302.300661) (xy 392.048979 -302.337017)
			(xy 392.0792 -302.378613) (xy 392.102543 -302.424425) (xy 392.118431 -302.473324) (xy 392.126474 -302.524106)
			(xy 392.126978 -302.549814) (xy 392.126474 -302.575522) (xy 392.423138 -302.575522) (xy 392.423138 -302.524106)
			(xy 392.431181 -302.473324) (xy 392.447069 -302.424425) (xy 392.470412 -302.378613) (xy 392.500633 -302.337017)
			(xy 392.536989 -302.300661) (xy 392.578585 -302.27044) (xy 392.624397 -302.247097) (xy 392.673296 -302.231209)
			(xy 392.724078 -302.223166) (xy 392.775494 -302.223166) (xy 392.826276 -302.231209) (xy 392.875175 -302.247097)
			(xy 392.920987 -302.27044) (xy 392.962583 -302.300661) (xy 392.998939 -302.337017) (xy 393.02916 -302.378613)
			(xy 393.052503 -302.424425) (xy 393.068391 -302.473324) (xy 393.076434 -302.524106) (xy 393.076938 -302.549814)
			(xy 393.076434 -302.575522) (xy 393.068391 -302.626304) (xy 393.052503 -302.675203) (xy 393.02916 -302.721015)
			(xy 392.998939 -302.762611) (xy 392.962583 -302.798967) (xy 392.920987 -302.829188) (xy 392.875175 -302.852531)
			(xy 392.826276 -302.868419) (xy 392.775494 -302.876462) (xy 392.724078 -302.876462) (xy 392.673296 -302.868419)
			(xy 392.624397 -302.852531) (xy 392.578585 -302.829188) (xy 392.536989 -302.798967) (xy 392.500633 -302.762611)
			(xy 392.470412 -302.721015) (xy 392.447069 -302.675203) (xy 392.431181 -302.626304) (xy 392.423138 -302.575522)
			(xy 392.126474 -302.575522) (xy 392.118431 -302.626304) (xy 392.102543 -302.675203) (xy 392.0792 -302.721015)
			(xy 392.048979 -302.762611) (xy 392.012623 -302.798967) (xy 391.971027 -302.829188) (xy 391.925215 -302.852531)
			(xy 391.876316 -302.868419) (xy 391.825534 -302.876462) (xy 391.774118 -302.876462) (xy 391.723336 -302.868419)
			(xy 391.674437 -302.852531) (xy 391.628625 -302.829188) (xy 391.587029 -302.798967) (xy 391.550673 -302.762611)
			(xy 391.520452 -302.721015) (xy 391.497109 -302.675203) (xy 391.481221 -302.626304) (xy 391.473178 -302.575522)
			(xy 391.1545 -302.575522) (xy 391.146784 -302.622998) (xy 391.1312 -302.669679) (xy 391.108329 -302.713256)
			(xy 391.078764 -302.7526) (xy 391.043271 -302.786692) (xy 391.002768 -302.814648) (xy 390.958306 -302.835746)
			(xy 390.911035 -302.849438) (xy 390.86218 -302.85537) (xy 390.813005 -302.853389) (xy 390.764786 -302.843545)
			(xy 390.71877 -302.826093) (xy 390.676149 -302.801486) (xy 390.638028 -302.770361) (xy 390.605393 -302.733524)
			(xy 390.57909 -302.691928) (xy 390.559799 -302.646652) (xy 390.548022 -302.598868) (xy 390.544062 -302.549814)
			(xy 390.205214 -302.549814) (xy 390.204719 -302.574421) (xy 390.196824 -302.622998) (xy 390.18124 -302.669679)
			(xy 390.158369 -302.713256) (xy 390.128804 -302.7526) (xy 390.093311 -302.786692) (xy 390.052808 -302.814648)
			(xy 390.008346 -302.835746) (xy 389.961075 -302.849438) (xy 389.91222 -302.85537) (xy 389.863045 -302.853389)
			(xy 389.814826 -302.843545) (xy 389.76881 -302.826093) (xy 389.726189 -302.801486) (xy 389.688068 -302.770361)
			(xy 389.655433 -302.733524) (xy 389.62913 -302.691928) (xy 389.609839 -302.646652) (xy 389.598062 -302.598868)
			(xy 389.594102 -302.549814) (xy 389.255254 -302.549814) (xy 389.254759 -302.574421) (xy 389.246864 -302.622998)
			(xy 389.23128 -302.669679) (xy 389.208409 -302.713256) (xy 389.178844 -302.7526) (xy 389.143351 -302.786692)
			(xy 389.102848 -302.814648) (xy 389.058386 -302.835746) (xy 389.011115 -302.849438) (xy 388.96226 -302.85537)
			(xy 388.913085 -302.853389) (xy 388.864866 -302.843545) (xy 388.81885 -302.826093) (xy 388.776229 -302.801486)
			(xy 388.738108 -302.770361) (xy 388.705473 -302.733524) (xy 388.67917 -302.691928) (xy 388.659879 -302.646652)
			(xy 388.648102 -302.598868) (xy 388.644142 -302.549814) (xy 388.305294 -302.549814) (xy 388.304799 -302.574421)
			(xy 388.296904 -302.622998) (xy 388.28132 -302.669679) (xy 388.258449 -302.713256) (xy 388.228884 -302.7526)
			(xy 388.193391 -302.786692) (xy 388.152888 -302.814648) (xy 388.108426 -302.835746) (xy 388.061155 -302.849438)
			(xy 388.0123 -302.85537) (xy 387.963125 -302.853389) (xy 387.914906 -302.843545) (xy 387.86889 -302.826093)
			(xy 387.826269 -302.801486) (xy 387.788148 -302.770361) (xy 387.755513 -302.733524) (xy 387.72921 -302.691928)
			(xy 387.709919 -302.646652) (xy 387.698142 -302.598868) (xy 387.694182 -302.549814) (xy 387.355334 -302.549814)
			(xy 387.354839 -302.574421) (xy 387.346944 -302.622998) (xy 387.33136 -302.669679) (xy 387.308489 -302.713256)
			(xy 387.278924 -302.7526) (xy 387.243431 -302.786692) (xy 387.202928 -302.814648) (xy 387.158466 -302.835746)
			(xy 387.111195 -302.849438) (xy 387.06234 -302.85537) (xy 387.013165 -302.853389) (xy 386.964946 -302.843545)
			(xy 386.91893 -302.826093) (xy 386.876309 -302.801486) (xy 386.838188 -302.770361) (xy 386.805553 -302.733524)
			(xy 386.77925 -302.691928) (xy 386.759959 -302.646652) (xy 386.748182 -302.598868) (xy 386.744222 -302.549814)
			(xy 386.426964 -302.549814) (xy 386.42646 -302.575522) (xy 386.418417 -302.626304) (xy 386.402529 -302.675203)
			(xy 386.379186 -302.721015) (xy 386.348965 -302.762611) (xy 386.312609 -302.798967) (xy 386.271013 -302.829188)
			(xy 386.225201 -302.852531) (xy 386.176302 -302.868419) (xy 386.12552 -302.876462) (xy 386.074104 -302.876462)
			(xy 386.023322 -302.868419) (xy 385.974423 -302.852531) (xy 385.928611 -302.829188) (xy 385.887015 -302.798967)
			(xy 385.850659 -302.762611) (xy 385.820438 -302.721015) (xy 385.797095 -302.675203) (xy 385.781207 -302.626304)
			(xy 385.773164 -302.575522) (xy 385.4765 -302.575522) (xy 385.468457 -302.626304) (xy 385.452569 -302.675203)
			(xy 385.429226 -302.721015) (xy 385.399005 -302.762611) (xy 385.362649 -302.798967) (xy 385.321053 -302.829188)
			(xy 385.275241 -302.852531) (xy 385.226342 -302.868419) (xy 385.17556 -302.876462) (xy 385.124144 -302.876462)
			(xy 385.073362 -302.868419) (xy 385.024463 -302.852531) (xy 384.978651 -302.829188) (xy 384.937055 -302.798967)
			(xy 384.900699 -302.762611) (xy 384.870478 -302.721015) (xy 384.847135 -302.675203) (xy 384.831247 -302.626304)
			(xy 384.823204 -302.575522) (xy 384.504313 -302.575522) (xy 384.496556 -302.623252) (xy 384.480972 -302.669933)
			(xy 384.458101 -302.71351) (xy 384.428536 -302.752854) (xy 384.393043 -302.786946) (xy 384.35254 -302.814902)
			(xy 384.308078 -302.836) (xy 384.260807 -302.849692) (xy 384.211952 -302.855624) (xy 384.162777 -302.853643)
			(xy 384.114558 -302.843799) (xy 384.068542 -302.826347) (xy 384.025921 -302.80174) (xy 383.9878 -302.770615)
			(xy 383.955165 -302.733778) (xy 383.928862 -302.692182) (xy 383.909571 -302.646906) (xy 383.897794 -302.599122)
			(xy 383.893834 -302.550068) (xy 351.03308 -302.550068) (xy 351.03308 -303.499774) (xy 384.844048 -303.499774)
			(xy 384.848008 -303.45072) (xy 384.859785 -303.402936) (xy 384.879076 -303.35766) (xy 384.905379 -303.316064)
			(xy 384.938014 -303.279227) (xy 384.976135 -303.248102) (xy 385.018756 -303.223495) (xy 385.064772 -303.206043)
			(xy 385.112991 -303.196199) (xy 385.162166 -303.194218) (xy 385.211021 -303.20015) (xy 385.258292 -303.213842)
			(xy 385.302754 -303.23494) (xy 385.343257 -303.262896) (xy 385.37875 -303.296988) (xy 385.408315 -303.336332)
			(xy 385.431186 -303.379909) (xy 385.44677 -303.42659) (xy 385.454665 -303.475167) (xy 385.45516 -303.499774)
			(xy 385.794008 -303.499774) (xy 385.797968 -303.45072) (xy 385.809745 -303.402936) (xy 385.829036 -303.35766)
			(xy 385.855339 -303.316064) (xy 385.887974 -303.279227) (xy 385.926095 -303.248102) (xy 385.968716 -303.223495)
			(xy 386.014732 -303.206043) (xy 386.062951 -303.196199) (xy 386.112126 -303.194218) (xy 386.160981 -303.20015)
			(xy 386.208252 -303.213842) (xy 386.252714 -303.23494) (xy 386.293217 -303.262896) (xy 386.32871 -303.296988)
			(xy 386.358275 -303.336332) (xy 386.381146 -303.379909) (xy 386.39673 -303.42659) (xy 386.404625 -303.475167)
			(xy 386.40512 -303.499774) (xy 386.404625 -303.524381) (xy 386.404446 -303.525482) (xy 386.723378 -303.525482)
			(xy 386.723378 -303.474066) (xy 386.731421 -303.423284) (xy 386.747309 -303.374385) (xy 386.770652 -303.328573)
			(xy 386.800873 -303.286977) (xy 386.837229 -303.250621) (xy 386.878825 -303.2204) (xy 386.924637 -303.197057)
			(xy 386.973536 -303.181169) (xy 387.024318 -303.173126) (xy 387.075734 -303.173126) (xy 387.126516 -303.181169)
			(xy 387.175415 -303.197057) (xy 387.221227 -303.2204) (xy 387.262823 -303.250621) (xy 387.299179 -303.286977)
			(xy 387.3294 -303.328573) (xy 387.352743 -303.374385) (xy 387.368631 -303.423284) (xy 387.376674 -303.474066)
			(xy 387.377178 -303.499774) (xy 387.376674 -303.525482) (xy 387.673338 -303.525482) (xy 387.673338 -303.474066)
			(xy 387.681381 -303.423284) (xy 387.697269 -303.374385) (xy 387.720612 -303.328573) (xy 387.750833 -303.286977)
			(xy 387.787189 -303.250621) (xy 387.828785 -303.2204) (xy 387.874597 -303.197057) (xy 387.923496 -303.181169)
			(xy 387.974278 -303.173126) (xy 388.025694 -303.173126) (xy 388.076476 -303.181169) (xy 388.125375 -303.197057)
			(xy 388.171187 -303.2204) (xy 388.212783 -303.250621) (xy 388.249139 -303.286977) (xy 388.27936 -303.328573)
			(xy 388.302703 -303.374385) (xy 388.318591 -303.423284) (xy 388.326634 -303.474066) (xy 388.327138 -303.499774)
			(xy 388.644142 -303.499774) (xy 388.648102 -303.45072) (xy 388.659879 -303.402936) (xy 388.67917 -303.35766)
			(xy 388.705473 -303.316064) (xy 388.738108 -303.279227) (xy 388.776229 -303.248102) (xy 388.81885 -303.223495)
			(xy 388.864866 -303.206043) (xy 388.913085 -303.196199) (xy 388.96226 -303.194218) (xy 389.011115 -303.20015)
			(xy 389.058386 -303.213842) (xy 389.102848 -303.23494) (xy 389.143351 -303.262896) (xy 389.178844 -303.296988)
			(xy 389.208409 -303.336332) (xy 389.23128 -303.379909) (xy 389.246864 -303.42659) (xy 389.254759 -303.475167)
			(xy 389.255254 -303.499774) (xy 389.254759 -303.524381) (xy 389.25458 -303.525482) (xy 389.573258 -303.525482)
			(xy 389.573258 -303.474066) (xy 389.581301 -303.423284) (xy 389.597189 -303.374385) (xy 389.620532 -303.328573)
			(xy 389.650753 -303.286977) (xy 389.687109 -303.250621) (xy 389.728705 -303.2204) (xy 389.774517 -303.197057)
			(xy 389.823416 -303.181169) (xy 389.874198 -303.173126) (xy 389.925614 -303.173126) (xy 389.976396 -303.181169)
			(xy 390.025295 -303.197057) (xy 390.071107 -303.2204) (xy 390.112703 -303.250621) (xy 390.149059 -303.286977)
			(xy 390.17928 -303.328573) (xy 390.202623 -303.374385) (xy 390.218511 -303.423284) (xy 390.226554 -303.474066)
			(xy 390.227058 -303.499774) (xy 390.226554 -303.525482) (xy 390.523218 -303.525482) (xy 390.523218 -303.474066)
			(xy 390.531261 -303.423284) (xy 390.547149 -303.374385) (xy 390.570492 -303.328573) (xy 390.600713 -303.286977)
			(xy 390.637069 -303.250621) (xy 390.678665 -303.2204) (xy 390.724477 -303.197057) (xy 390.773376 -303.181169)
			(xy 390.824158 -303.173126) (xy 390.875574 -303.173126) (xy 390.926356 -303.181169) (xy 390.975255 -303.197057)
			(xy 391.021067 -303.2204) (xy 391.062663 -303.250621) (xy 391.099019 -303.286977) (xy 391.12924 -303.328573)
			(xy 391.152583 -303.374385) (xy 391.168471 -303.423284) (xy 391.176514 -303.474066) (xy 391.177018 -303.499774)
			(xy 391.494022 -303.499774) (xy 391.497982 -303.45072) (xy 391.509759 -303.402936) (xy 391.52905 -303.35766)
			(xy 391.555353 -303.316064) (xy 391.587988 -303.279227) (xy 391.626109 -303.248102) (xy 391.66873 -303.223495)
			(xy 391.714746 -303.206043) (xy 391.762965 -303.196199) (xy 391.81214 -303.194218) (xy 391.860995 -303.20015)
			(xy 391.908266 -303.213842) (xy 391.952728 -303.23494) (xy 391.993231 -303.262896) (xy 392.028724 -303.296988)
			(xy 392.058289 -303.336332) (xy 392.08116 -303.379909) (xy 392.096744 -303.42659) (xy 392.104639 -303.475167)
			(xy 392.105134 -303.499774) (xy 392.443982 -303.499774) (xy 392.447942 -303.45072) (xy 392.459719 -303.402936)
			(xy 392.47901 -303.35766) (xy 392.505313 -303.316064) (xy 392.537948 -303.279227) (xy 392.576069 -303.248102)
			(xy 392.61869 -303.223495) (xy 392.664706 -303.206043) (xy 392.712925 -303.196199) (xy 392.7621 -303.194218)
			(xy 392.810955 -303.20015) (xy 392.858226 -303.213842) (xy 392.902688 -303.23494) (xy 392.943191 -303.262896)
			(xy 392.978684 -303.296988) (xy 393.008249 -303.336332) (xy 393.03112 -303.379909) (xy 393.046704 -303.42659)
			(xy 393.054599 -303.475167) (xy 393.055094 -303.499774) (xy 393.054599 -303.524381) (xy 393.046704 -303.572958)
			(xy 393.03112 -303.619639) (xy 393.008249 -303.663216) (xy 392.978684 -303.70256) (xy 392.943191 -303.736652)
			(xy 392.902688 -303.764608) (xy 392.858226 -303.785706) (xy 392.810955 -303.799398) (xy 392.7621 -303.80533)
			(xy 392.712925 -303.803349) (xy 392.664706 -303.793505) (xy 392.61869 -303.776053) (xy 392.576069 -303.751446)
			(xy 392.537948 -303.720321) (xy 392.505313 -303.683484) (xy 392.47901 -303.641888) (xy 392.459719 -303.596612)
			(xy 392.447942 -303.548828) (xy 392.443982 -303.499774) (xy 392.105134 -303.499774) (xy 392.104639 -303.524381)
			(xy 392.096744 -303.572958) (xy 392.08116 -303.619639) (xy 392.058289 -303.663216) (xy 392.028724 -303.70256)
			(xy 391.993231 -303.736652) (xy 391.952728 -303.764608) (xy 391.908266 -303.785706) (xy 391.860995 -303.799398)
			(xy 391.81214 -303.80533) (xy 391.762965 -303.803349) (xy 391.714746 -303.793505) (xy 391.66873 -303.776053)
			(xy 391.626109 -303.751446) (xy 391.587988 -303.720321) (xy 391.555353 -303.683484) (xy 391.52905 -303.641888)
			(xy 391.509759 -303.596612) (xy 391.497982 -303.548828) (xy 391.494022 -303.499774) (xy 391.177018 -303.499774)
			(xy 391.176514 -303.525482) (xy 391.168471 -303.576264) (xy 391.152583 -303.625163) (xy 391.12924 -303.670975)
			(xy 391.099019 -303.712571) (xy 391.062663 -303.748927) (xy 391.021067 -303.779148) (xy 390.975255 -303.802491)
			(xy 390.926356 -303.818379) (xy 390.875574 -303.826422) (xy 390.824158 -303.826422) (xy 390.773376 -303.818379)
			(xy 390.724477 -303.802491) (xy 390.678665 -303.779148) (xy 390.637069 -303.748927) (xy 390.600713 -303.712571)
			(xy 390.570492 -303.670975) (xy 390.547149 -303.625163) (xy 390.531261 -303.576264) (xy 390.523218 -303.525482)
			(xy 390.226554 -303.525482) (xy 390.218511 -303.576264) (xy 390.202623 -303.625163) (xy 390.17928 -303.670975)
			(xy 390.149059 -303.712571) (xy 390.112703 -303.748927) (xy 390.071107 -303.779148) (xy 390.025295 -303.802491)
			(xy 389.976396 -303.818379) (xy 389.925614 -303.826422) (xy 389.874198 -303.826422) (xy 389.823416 -303.818379)
			(xy 389.774517 -303.802491) (xy 389.728705 -303.779148) (xy 389.687109 -303.748927) (xy 389.650753 -303.712571)
			(xy 389.620532 -303.670975) (xy 389.597189 -303.625163) (xy 389.581301 -303.576264) (xy 389.573258 -303.525482)
			(xy 389.25458 -303.525482) (xy 389.246864 -303.572958) (xy 389.23128 -303.619639) (xy 389.208409 -303.663216)
			(xy 389.178844 -303.70256) (xy 389.143351 -303.736652) (xy 389.102848 -303.764608) (xy 389.058386 -303.785706)
			(xy 389.011115 -303.799398) (xy 388.96226 -303.80533) (xy 388.913085 -303.803349) (xy 388.864866 -303.793505)
			(xy 388.81885 -303.776053) (xy 388.776229 -303.751446) (xy 388.738108 -303.720321) (xy 388.705473 -303.683484)
			(xy 388.67917 -303.641888) (xy 388.659879 -303.596612) (xy 388.648102 -303.548828) (xy 388.644142 -303.499774)
			(xy 388.327138 -303.499774) (xy 388.326634 -303.525482) (xy 388.318591 -303.576264) (xy 388.302703 -303.625163)
			(xy 388.27936 -303.670975) (xy 388.249139 -303.712571) (xy 388.212783 -303.748927) (xy 388.171187 -303.779148)
			(xy 388.125375 -303.802491) (xy 388.076476 -303.818379) (xy 388.025694 -303.826422) (xy 387.974278 -303.826422)
			(xy 387.923496 -303.818379) (xy 387.874597 -303.802491) (xy 387.828785 -303.779148) (xy 387.787189 -303.748927)
			(xy 387.750833 -303.712571) (xy 387.720612 -303.670975) (xy 387.697269 -303.625163) (xy 387.681381 -303.576264)
			(xy 387.673338 -303.525482) (xy 387.376674 -303.525482) (xy 387.368631 -303.576264) (xy 387.352743 -303.625163)
			(xy 387.3294 -303.670975) (xy 387.299179 -303.712571) (xy 387.262823 -303.748927) (xy 387.221227 -303.779148)
			(xy 387.175415 -303.802491) (xy 387.126516 -303.818379) (xy 387.075734 -303.826422) (xy 387.024318 -303.826422)
			(xy 386.973536 -303.818379) (xy 386.924637 -303.802491) (xy 386.878825 -303.779148) (xy 386.837229 -303.748927)
			(xy 386.800873 -303.712571) (xy 386.770652 -303.670975) (xy 386.747309 -303.625163) (xy 386.731421 -303.576264)
			(xy 386.723378 -303.525482) (xy 386.404446 -303.525482) (xy 386.39673 -303.572958) (xy 386.381146 -303.619639)
			(xy 386.358275 -303.663216) (xy 386.32871 -303.70256) (xy 386.293217 -303.736652) (xy 386.252714 -303.764608)
			(xy 386.208252 -303.785706) (xy 386.160981 -303.799398) (xy 386.112126 -303.80533) (xy 386.062951 -303.803349)
			(xy 386.014732 -303.793505) (xy 385.968716 -303.776053) (xy 385.926095 -303.751446) (xy 385.887974 -303.720321)
			(xy 385.855339 -303.683484) (xy 385.829036 -303.641888) (xy 385.809745 -303.596612) (xy 385.797968 -303.548828)
			(xy 385.794008 -303.499774) (xy 385.45516 -303.499774) (xy 385.454665 -303.524381) (xy 385.44677 -303.572958)
			(xy 385.431186 -303.619639) (xy 385.408315 -303.663216) (xy 385.37875 -303.70256) (xy 385.343257 -303.736652)
			(xy 385.302754 -303.764608) (xy 385.258292 -303.785706) (xy 385.211021 -303.799398) (xy 385.162166 -303.80533)
			(xy 385.112991 -303.803349) (xy 385.064772 -303.793505) (xy 385.018756 -303.776053) (xy 384.976135 -303.751446)
			(xy 384.938014 -303.720321) (xy 384.905379 -303.683484) (xy 384.879076 -303.641888) (xy 384.859785 -303.596612)
			(xy 384.848008 -303.548828) (xy 384.844048 -303.499774) (xy 351.03308 -303.499774) (xy 351.03308 -303.974754)
			(xy 394.819136 -303.974754) (xy 394.823096 -303.9257) (xy 394.834873 -303.877916) (xy 394.854164 -303.83264)
			(xy 394.880467 -303.791044) (xy 394.913102 -303.754207) (xy 394.951223 -303.723082) (xy 394.993844 -303.698475)
			(xy 395.03986 -303.681023) (xy 395.088079 -303.671179) (xy 395.137254 -303.669198) (xy 395.186109 -303.67513)
			(xy 395.23338 -303.688822) (xy 395.277842 -303.70992) (xy 395.318345 -303.737876) (xy 395.353838 -303.771968)
			(xy 395.383403 -303.811312) (xy 395.406274 -303.854889) (xy 395.421858 -303.90157) (xy 395.429753 -303.950147)
			(xy 395.430248 -303.974754) (xy 395.769096 -303.974754) (xy 395.773056 -303.9257) (xy 395.784833 -303.877916)
			(xy 395.804124 -303.83264) (xy 395.830427 -303.791044) (xy 395.863062 -303.754207) (xy 395.901183 -303.723082)
			(xy 395.943804 -303.698475) (xy 395.98982 -303.681023) (xy 396.038039 -303.671179) (xy 396.087214 -303.669198)
			(xy 396.136069 -303.67513) (xy 396.18334 -303.688822) (xy 396.227802 -303.70992) (xy 396.268305 -303.737876)
			(xy 396.303798 -303.771968) (xy 396.333363 -303.811312) (xy 396.356234 -303.854889) (xy 396.371818 -303.90157)
			(xy 396.379713 -303.950147) (xy 396.380208 -303.974754) (xy 396.719056 -303.974754) (xy 396.723016 -303.9257)
			(xy 396.734793 -303.877916) (xy 396.754084 -303.83264) (xy 396.780387 -303.791044) (xy 396.813022 -303.754207)
			(xy 396.851143 -303.723082) (xy 396.893764 -303.698475) (xy 396.93978 -303.681023) (xy 396.987999 -303.671179)
			(xy 397.037174 -303.669198) (xy 397.086029 -303.67513) (xy 397.1333 -303.688822) (xy 397.177762 -303.70992)
			(xy 397.218265 -303.737876) (xy 397.253758 -303.771968) (xy 397.283323 -303.811312) (xy 397.306194 -303.854889)
			(xy 397.321778 -303.90157) (xy 397.329673 -303.950147) (xy 397.330168 -303.974754) (xy 397.669016 -303.974754)
			(xy 397.672976 -303.9257) (xy 397.684753 -303.877916) (xy 397.704044 -303.83264) (xy 397.730347 -303.791044)
			(xy 397.762982 -303.754207) (xy 397.801103 -303.723082) (xy 397.843724 -303.698475) (xy 397.88974 -303.681023)
			(xy 397.937959 -303.671179) (xy 397.987134 -303.669198) (xy 398.035989 -303.67513) (xy 398.08326 -303.688822)
			(xy 398.127722 -303.70992) (xy 398.168225 -303.737876) (xy 398.203718 -303.771968) (xy 398.233283 -303.811312)
			(xy 398.256154 -303.854889) (xy 398.271738 -303.90157) (xy 398.279633 -303.950147) (xy 398.280128 -303.974754)
			(xy 398.61923 -303.974754) (xy 398.62319 -303.9257) (xy 398.634967 -303.877916) (xy 398.654258 -303.83264)
			(xy 398.680561 -303.791044) (xy 398.713196 -303.754207) (xy 398.751317 -303.723082) (xy 398.793938 -303.698475)
			(xy 398.839954 -303.681023) (xy 398.888173 -303.671179) (xy 398.937348 -303.669198) (xy 398.986203 -303.67513)
			(xy 399.033474 -303.688822) (xy 399.077936 -303.70992) (xy 399.118439 -303.737876) (xy 399.153932 -303.771968)
			(xy 399.183497 -303.811312) (xy 399.206368 -303.854889) (xy 399.221952 -303.90157) (xy 399.229847 -303.950147)
			(xy 399.230342 -303.974754) (xy 399.56919 -303.974754) (xy 399.57315 -303.9257) (xy 399.584927 -303.877916)
			(xy 399.604218 -303.83264) (xy 399.630521 -303.791044) (xy 399.663156 -303.754207) (xy 399.701277 -303.723082)
			(xy 399.743898 -303.698475) (xy 399.789914 -303.681023) (xy 399.838133 -303.671179) (xy 399.887308 -303.669198)
			(xy 399.936163 -303.67513) (xy 399.983434 -303.688822) (xy 400.027896 -303.70992) (xy 400.068399 -303.737876)
			(xy 400.103892 -303.771968) (xy 400.133457 -303.811312) (xy 400.156328 -303.854889) (xy 400.171912 -303.90157)
			(xy 400.179807 -303.950147) (xy 400.180302 -303.974754) (xy 400.51915 -303.974754) (xy 400.52311 -303.9257)
			(xy 400.534887 -303.877916) (xy 400.554178 -303.83264) (xy 400.580481 -303.791044) (xy 400.613116 -303.754207)
			(xy 400.651237 -303.723082) (xy 400.693858 -303.698475) (xy 400.739874 -303.681023) (xy 400.788093 -303.671179)
			(xy 400.837268 -303.669198) (xy 400.886123 -303.67513) (xy 400.933394 -303.688822) (xy 400.977856 -303.70992)
			(xy 401.018359 -303.737876) (xy 401.053852 -303.771968) (xy 401.083417 -303.811312) (xy 401.106288 -303.854889)
			(xy 401.121872 -303.90157) (xy 401.129767 -303.950147) (xy 401.130262 -303.974754) (xy 401.46911 -303.974754)
			(xy 401.47307 -303.9257) (xy 401.484847 -303.877916) (xy 401.504138 -303.83264) (xy 401.530441 -303.791044)
			(xy 401.563076 -303.754207) (xy 401.601197 -303.723082) (xy 401.643818 -303.698475) (xy 401.689834 -303.681023)
			(xy 401.738053 -303.671179) (xy 401.787228 -303.669198) (xy 401.836083 -303.67513) (xy 401.883354 -303.688822)
			(xy 401.927816 -303.70992) (xy 401.968319 -303.737876) (xy 402.003812 -303.771968) (xy 402.033377 -303.811312)
			(xy 402.056248 -303.854889) (xy 402.071832 -303.90157) (xy 402.079727 -303.950147) (xy 402.080222 -303.974754)
			(xy 402.41907 -303.974754) (xy 402.42303 -303.9257) (xy 402.434807 -303.877916) (xy 402.454098 -303.83264)
			(xy 402.480401 -303.791044) (xy 402.513036 -303.754207) (xy 402.551157 -303.723082) (xy 402.593778 -303.698475)
			(xy 402.639794 -303.681023) (xy 402.688013 -303.671179) (xy 402.737188 -303.669198) (xy 402.786043 -303.67513)
			(xy 402.833314 -303.688822) (xy 402.877776 -303.70992) (xy 402.918279 -303.737876) (xy 402.953772 -303.771968)
			(xy 402.983337 -303.811312) (xy 403.006208 -303.854889) (xy 403.021792 -303.90157) (xy 403.029687 -303.950147)
			(xy 403.030182 -303.974754) (xy 403.36903 -303.974754) (xy 403.37299 -303.9257) (xy 403.384767 -303.877916)
			(xy 403.404058 -303.83264) (xy 403.430361 -303.791044) (xy 403.462996 -303.754207) (xy 403.501117 -303.723082)
			(xy 403.543738 -303.698475) (xy 403.589754 -303.681023) (xy 403.637973 -303.671179) (xy 403.687148 -303.669198)
			(xy 403.736003 -303.67513) (xy 403.783274 -303.688822) (xy 403.827736 -303.70992) (xy 403.868239 -303.737876)
			(xy 403.903732 -303.771968) (xy 403.933297 -303.811312) (xy 403.956168 -303.854889) (xy 403.971752 -303.90157)
			(xy 403.979647 -303.950147) (xy 403.980142 -303.974754) (xy 404.31899 -303.974754) (xy 404.32295 -303.9257)
			(xy 404.334727 -303.877916) (xy 404.354018 -303.83264) (xy 404.380321 -303.791044) (xy 404.412956 -303.754207)
			(xy 404.451077 -303.723082) (xy 404.493698 -303.698475) (xy 404.539714 -303.681023) (xy 404.587933 -303.671179)
			(xy 404.637108 -303.669198) (xy 404.685963 -303.67513) (xy 404.733234 -303.688822) (xy 404.777696 -303.70992)
			(xy 404.818199 -303.737876) (xy 404.853692 -303.771968) (xy 404.883257 -303.811312) (xy 404.906128 -303.854889)
			(xy 404.921712 -303.90157) (xy 404.929607 -303.950147) (xy 404.930102 -303.974754) (xy 405.269204 -303.974754)
			(xy 405.273164 -303.9257) (xy 405.284941 -303.877916) (xy 405.304232 -303.83264) (xy 405.330535 -303.791044)
			(xy 405.36317 -303.754207) (xy 405.401291 -303.723082) (xy 405.443912 -303.698475) (xy 405.489928 -303.681023)
			(xy 405.538147 -303.671179) (xy 405.587322 -303.669198) (xy 405.636177 -303.67513) (xy 405.683448 -303.688822)
			(xy 405.72791 -303.70992) (xy 405.768413 -303.737876) (xy 405.803906 -303.771968) (xy 405.833471 -303.811312)
			(xy 405.856342 -303.854889) (xy 405.871926 -303.90157) (xy 405.879821 -303.950147) (xy 405.880316 -303.974754)
			(xy 406.219164 -303.974754) (xy 406.223124 -303.9257) (xy 406.234901 -303.877916) (xy 406.254192 -303.83264)
			(xy 406.280495 -303.791044) (xy 406.31313 -303.754207) (xy 406.351251 -303.723082) (xy 406.393872 -303.698475)
			(xy 406.439888 -303.681023) (xy 406.488107 -303.671179) (xy 406.537282 -303.669198) (xy 406.586137 -303.67513)
			(xy 406.633408 -303.688822) (xy 406.67787 -303.70992) (xy 406.718373 -303.737876) (xy 406.753866 -303.771968)
			(xy 406.783431 -303.811312) (xy 406.806302 -303.854889) (xy 406.821886 -303.90157) (xy 406.829781 -303.950147)
			(xy 406.830276 -303.974754) (xy 408.119084 -303.974754) (xy 408.123044 -303.9257) (xy 408.134821 -303.877916)
			(xy 408.154112 -303.83264) (xy 408.180415 -303.791044) (xy 408.21305 -303.754207) (xy 408.251171 -303.723082)
			(xy 408.293792 -303.698475) (xy 408.339808 -303.681023) (xy 408.388027 -303.671179) (xy 408.437202 -303.669198)
			(xy 408.486057 -303.67513) (xy 408.533328 -303.688822) (xy 408.57779 -303.70992) (xy 408.618293 -303.737876)
			(xy 408.653786 -303.771968) (xy 408.683351 -303.811312) (xy 408.706222 -303.854889) (xy 408.721806 -303.90157)
			(xy 408.729701 -303.950147) (xy 408.730196 -303.974754) (xy 409.069044 -303.974754) (xy 409.073004 -303.9257)
			(xy 409.084781 -303.877916) (xy 409.104072 -303.83264) (xy 409.130375 -303.791044) (xy 409.16301 -303.754207)
			(xy 409.201131 -303.723082) (xy 409.243752 -303.698475) (xy 409.289768 -303.681023) (xy 409.337987 -303.671179)
			(xy 409.387162 -303.669198) (xy 409.436017 -303.67513) (xy 409.483288 -303.688822) (xy 409.52775 -303.70992)
			(xy 409.568253 -303.737876) (xy 409.603746 -303.771968) (xy 409.633311 -303.811312) (xy 409.656182 -303.854889)
			(xy 409.671766 -303.90157) (xy 409.679661 -303.950147) (xy 409.680156 -303.974754) (xy 410.019004 -303.974754)
			(xy 410.022964 -303.9257) (xy 410.034741 -303.877916) (xy 410.054032 -303.83264) (xy 410.080335 -303.791044)
			(xy 410.11297 -303.754207) (xy 410.151091 -303.723082) (xy 410.193712 -303.698475) (xy 410.239728 -303.681023)
			(xy 410.287947 -303.671179) (xy 410.337122 -303.669198) (xy 410.385977 -303.67513) (xy 410.433248 -303.688822)
			(xy 410.47771 -303.70992) (xy 410.518213 -303.737876) (xy 410.553706 -303.771968) (xy 410.583271 -303.811312)
			(xy 410.606142 -303.854889) (xy 410.621726 -303.90157) (xy 410.629621 -303.950147) (xy 410.630116 -303.974754)
			(xy 410.969218 -303.974754) (xy 410.973178 -303.9257) (xy 410.984955 -303.877916) (xy 411.004246 -303.83264)
			(xy 411.030549 -303.791044) (xy 411.063184 -303.754207) (xy 411.101305 -303.723082) (xy 411.143926 -303.698475)
			(xy 411.189942 -303.681023) (xy 411.238161 -303.671179) (xy 411.287336 -303.669198) (xy 411.336191 -303.67513)
			(xy 411.383462 -303.688822) (xy 411.427924 -303.70992) (xy 411.468427 -303.737876) (xy 411.50392 -303.771968)
			(xy 411.533485 -303.811312) (xy 411.556356 -303.854889) (xy 411.57194 -303.90157) (xy 411.579835 -303.950147)
			(xy 411.58033 -303.974754) (xy 411.919178 -303.974754) (xy 411.923138 -303.9257) (xy 411.934915 -303.877916)
			(xy 411.954206 -303.83264) (xy 411.980509 -303.791044) (xy 412.013144 -303.754207) (xy 412.051265 -303.723082)
			(xy 412.093886 -303.698475) (xy 412.139902 -303.681023) (xy 412.188121 -303.671179) (xy 412.237296 -303.669198)
			(xy 412.286151 -303.67513) (xy 412.333422 -303.688822) (xy 412.377884 -303.70992) (xy 412.418387 -303.737876)
			(xy 412.45388 -303.771968) (xy 412.483445 -303.811312) (xy 412.506316 -303.854889) (xy 412.5219 -303.90157)
			(xy 412.529795 -303.950147) (xy 412.53029 -303.974754) (xy 412.869138 -303.974754) (xy 412.873098 -303.9257)
			(xy 412.884875 -303.877916) (xy 412.904166 -303.83264) (xy 412.930469 -303.791044) (xy 412.963104 -303.754207)
			(xy 413.001225 -303.723082) (xy 413.043846 -303.698475) (xy 413.089862 -303.681023) (xy 413.138081 -303.671179)
			(xy 413.187256 -303.669198) (xy 413.236111 -303.67513) (xy 413.283382 -303.688822) (xy 413.327844 -303.70992)
			(xy 413.368347 -303.737876) (xy 413.40384 -303.771968) (xy 413.433405 -303.811312) (xy 413.456276 -303.854889)
			(xy 413.47186 -303.90157) (xy 413.479755 -303.950147) (xy 413.48025 -303.974754) (xy 413.819098 -303.974754)
			(xy 413.823058 -303.9257) (xy 413.834835 -303.877916) (xy 413.854126 -303.83264) (xy 413.880429 -303.791044)
			(xy 413.913064 -303.754207) (xy 413.951185 -303.723082) (xy 413.993806 -303.698475) (xy 414.039822 -303.681023)
			(xy 414.088041 -303.671179) (xy 414.137216 -303.669198) (xy 414.186071 -303.67513) (xy 414.233342 -303.688822)
			(xy 414.277804 -303.70992) (xy 414.318307 -303.737876) (xy 414.3538 -303.771968) (xy 414.383365 -303.811312)
			(xy 414.406236 -303.854889) (xy 414.42182 -303.90157) (xy 414.429715 -303.950147) (xy 414.43021 -303.974754)
			(xy 414.769058 -303.974754) (xy 414.773018 -303.9257) (xy 414.784795 -303.877916) (xy 414.804086 -303.83264)
			(xy 414.830389 -303.791044) (xy 414.863024 -303.754207) (xy 414.901145 -303.723082) (xy 414.943766 -303.698475)
			(xy 414.989782 -303.681023) (xy 415.038001 -303.671179) (xy 415.087176 -303.669198) (xy 415.136031 -303.67513)
			(xy 415.183302 -303.688822) (xy 415.227764 -303.70992) (xy 415.268267 -303.737876) (xy 415.30376 -303.771968)
			(xy 415.333325 -303.811312) (xy 415.356196 -303.854889) (xy 415.37178 -303.90157) (xy 415.379675 -303.950147)
			(xy 415.38017 -303.974754) (xy 415.719018 -303.974754) (xy 415.722978 -303.9257) (xy 415.734755 -303.877916)
			(xy 415.754046 -303.83264) (xy 415.780349 -303.791044) (xy 415.812984 -303.754207) (xy 415.851105 -303.723082)
			(xy 415.893726 -303.698475) (xy 415.939742 -303.681023) (xy 415.987961 -303.671179) (xy 416.037136 -303.669198)
			(xy 416.085991 -303.67513) (xy 416.133262 -303.688822) (xy 416.177724 -303.70992) (xy 416.218227 -303.737876)
			(xy 416.25372 -303.771968) (xy 416.283285 -303.811312) (xy 416.306156 -303.854889) (xy 416.32174 -303.90157)
			(xy 416.329635 -303.950147) (xy 416.330033 -303.969928) (xy 416.674058 -303.969928) (xy 416.678018 -303.920874)
			(xy 416.689795 -303.87309) (xy 416.709086 -303.827814) (xy 416.735389 -303.786218) (xy 416.768024 -303.749381)
			(xy 416.806145 -303.718256) (xy 416.848766 -303.693649) (xy 416.894782 -303.676197) (xy 416.943001 -303.666353)
			(xy 416.992176 -303.664372) (xy 417.041031 -303.670304) (xy 417.088302 -303.683996) (xy 417.132764 -303.705094)
			(xy 417.173267 -303.73305) (xy 417.20876 -303.767142) (xy 417.238325 -303.806486) (xy 417.261196 -303.850063)
			(xy 417.27678 -303.896744) (xy 417.284675 -303.945321) (xy 417.28517 -303.969928) (xy 417.284675 -303.994535)
			(xy 417.27678 -304.043112) (xy 417.261196 -304.089793) (xy 417.238325 -304.13337) (xy 417.20876 -304.172714)
			(xy 417.173267 -304.206806) (xy 417.132764 -304.234762) (xy 417.088302 -304.25586) (xy 417.041031 -304.269552)
			(xy 416.992176 -304.275484) (xy 416.943001 -304.273503) (xy 416.894782 -304.263659) (xy 416.848766 -304.246207)
			(xy 416.806145 -304.2216) (xy 416.768024 -304.190475) (xy 416.735389 -304.153638) (xy 416.709086 -304.112042)
			(xy 416.689795 -304.066766) (xy 416.678018 -304.018982) (xy 416.674058 -303.969928) (xy 416.330033 -303.969928)
			(xy 416.33013 -303.974754) (xy 416.329635 -303.999361) (xy 416.32174 -304.047938) (xy 416.306156 -304.094619)
			(xy 416.283285 -304.138196) (xy 416.25372 -304.17754) (xy 416.218227 -304.211632) (xy 416.177724 -304.239588)
			(xy 416.133262 -304.260686) (xy 416.085991 -304.274378) (xy 416.037136 -304.28031) (xy 415.987961 -304.278329)
			(xy 415.939742 -304.268485) (xy 415.893726 -304.251033) (xy 415.851105 -304.226426) (xy 415.812984 -304.195301)
			(xy 415.780349 -304.158464) (xy 415.754046 -304.116868) (xy 415.734755 -304.071592) (xy 415.722978 -304.023808)
			(xy 415.719018 -303.974754) (xy 415.38017 -303.974754) (xy 415.379675 -303.999361) (xy 415.37178 -304.047938)
			(xy 415.356196 -304.094619) (xy 415.333325 -304.138196) (xy 415.30376 -304.17754) (xy 415.268267 -304.211632)
			(xy 415.227764 -304.239588) (xy 415.183302 -304.260686) (xy 415.136031 -304.274378) (xy 415.087176 -304.28031)
			(xy 415.038001 -304.278329) (xy 414.989782 -304.268485) (xy 414.943766 -304.251033) (xy 414.901145 -304.226426)
			(xy 414.863024 -304.195301) (xy 414.830389 -304.158464) (xy 414.804086 -304.116868) (xy 414.784795 -304.071592)
			(xy 414.773018 -304.023808) (xy 414.769058 -303.974754) (xy 414.43021 -303.974754) (xy 414.429715 -303.999361)
			(xy 414.42182 -304.047938) (xy 414.406236 -304.094619) (xy 414.383365 -304.138196) (xy 414.3538 -304.17754)
			(xy 414.318307 -304.211632) (xy 414.277804 -304.239588) (xy 414.233342 -304.260686) (xy 414.186071 -304.274378)
			(xy 414.137216 -304.28031) (xy 414.088041 -304.278329) (xy 414.039822 -304.268485) (xy 413.993806 -304.251033)
			(xy 413.951185 -304.226426) (xy 413.913064 -304.195301) (xy 413.880429 -304.158464) (xy 413.854126 -304.116868)
			(xy 413.834835 -304.071592) (xy 413.823058 -304.023808) (xy 413.819098 -303.974754) (xy 413.48025 -303.974754)
			(xy 413.479755 -303.999361) (xy 413.47186 -304.047938) (xy 413.456276 -304.094619) (xy 413.433405 -304.138196)
			(xy 413.40384 -304.17754) (xy 413.368347 -304.211632) (xy 413.327844 -304.239588) (xy 413.283382 -304.260686)
			(xy 413.236111 -304.274378) (xy 413.187256 -304.28031) (xy 413.138081 -304.278329) (xy 413.089862 -304.268485)
			(xy 413.043846 -304.251033) (xy 413.001225 -304.226426) (xy 412.963104 -304.195301) (xy 412.930469 -304.158464)
			(xy 412.904166 -304.116868) (xy 412.884875 -304.071592) (xy 412.873098 -304.023808) (xy 412.869138 -303.974754)
			(xy 412.53029 -303.974754) (xy 412.529795 -303.999361) (xy 412.5219 -304.047938) (xy 412.506316 -304.094619)
			(xy 412.483445 -304.138196) (xy 412.45388 -304.17754) (xy 412.418387 -304.211632) (xy 412.377884 -304.239588)
			(xy 412.333422 -304.260686) (xy 412.286151 -304.274378) (xy 412.237296 -304.28031) (xy 412.188121 -304.278329)
			(xy 412.139902 -304.268485) (xy 412.093886 -304.251033) (xy 412.051265 -304.226426) (xy 412.013144 -304.195301)
			(xy 411.980509 -304.158464) (xy 411.954206 -304.116868) (xy 411.934915 -304.071592) (xy 411.923138 -304.023808)
			(xy 411.919178 -303.974754) (xy 411.58033 -303.974754) (xy 411.579835 -303.999361) (xy 411.57194 -304.047938)
			(xy 411.556356 -304.094619) (xy 411.533485 -304.138196) (xy 411.50392 -304.17754) (xy 411.468427 -304.211632)
			(xy 411.427924 -304.239588) (xy 411.383462 -304.260686) (xy 411.336191 -304.274378) (xy 411.287336 -304.28031)
			(xy 411.238161 -304.278329) (xy 411.189942 -304.268485) (xy 411.143926 -304.251033) (xy 411.101305 -304.226426)
			(xy 411.063184 -304.195301) (xy 411.030549 -304.158464) (xy 411.004246 -304.116868) (xy 410.984955 -304.071592)
			(xy 410.973178 -304.023808) (xy 410.969218 -303.974754) (xy 410.630116 -303.974754) (xy 410.629621 -303.999361)
			(xy 410.621726 -304.047938) (xy 410.606142 -304.094619) (xy 410.583271 -304.138196) (xy 410.553706 -304.17754)
			(xy 410.518213 -304.211632) (xy 410.47771 -304.239588) (xy 410.433248 -304.260686) (xy 410.385977 -304.274378)
			(xy 410.337122 -304.28031) (xy 410.287947 -304.278329) (xy 410.239728 -304.268485) (xy 410.193712 -304.251033)
			(xy 410.151091 -304.226426) (xy 410.11297 -304.195301) (xy 410.080335 -304.158464) (xy 410.054032 -304.116868)
			(xy 410.034741 -304.071592) (xy 410.022964 -304.023808) (xy 410.019004 -303.974754) (xy 409.680156 -303.974754)
			(xy 409.679661 -303.999361) (xy 409.671766 -304.047938) (xy 409.656182 -304.094619) (xy 409.633311 -304.138196)
			(xy 409.603746 -304.17754) (xy 409.568253 -304.211632) (xy 409.52775 -304.239588) (xy 409.483288 -304.260686)
			(xy 409.436017 -304.274378) (xy 409.387162 -304.28031) (xy 409.337987 -304.278329) (xy 409.289768 -304.268485)
			(xy 409.243752 -304.251033) (xy 409.201131 -304.226426) (xy 409.16301 -304.195301) (xy 409.130375 -304.158464)
			(xy 409.104072 -304.116868) (xy 409.084781 -304.071592) (xy 409.073004 -304.023808) (xy 409.069044 -303.974754)
			(xy 408.730196 -303.974754) (xy 408.729701 -303.999361) (xy 408.721806 -304.047938) (xy 408.706222 -304.094619)
			(xy 408.683351 -304.138196) (xy 408.653786 -304.17754) (xy 408.618293 -304.211632) (xy 408.57779 -304.239588)
			(xy 408.533328 -304.260686) (xy 408.486057 -304.274378) (xy 408.437202 -304.28031) (xy 408.388027 -304.278329)
			(xy 408.339808 -304.268485) (xy 408.293792 -304.251033) (xy 408.251171 -304.226426) (xy 408.21305 -304.195301)
			(xy 408.180415 -304.158464) (xy 408.154112 -304.116868) (xy 408.134821 -304.071592) (xy 408.123044 -304.023808)
			(xy 408.119084 -303.974754) (xy 406.830276 -303.974754) (xy 406.829781 -303.999361) (xy 406.821886 -304.047938)
			(xy 406.806302 -304.094619) (xy 406.783431 -304.138196) (xy 406.753866 -304.17754) (xy 406.718373 -304.211632)
			(xy 406.67787 -304.239588) (xy 406.633408 -304.260686) (xy 406.586137 -304.274378) (xy 406.537282 -304.28031)
			(xy 406.488107 -304.278329) (xy 406.439888 -304.268485) (xy 406.393872 -304.251033) (xy 406.351251 -304.226426)
			(xy 406.31313 -304.195301) (xy 406.280495 -304.158464) (xy 406.254192 -304.116868) (xy 406.234901 -304.071592)
			(xy 406.223124 -304.023808) (xy 406.219164 -303.974754) (xy 405.880316 -303.974754) (xy 405.879821 -303.999361)
			(xy 405.871926 -304.047938) (xy 405.856342 -304.094619) (xy 405.833471 -304.138196) (xy 405.803906 -304.17754)
			(xy 405.768413 -304.211632) (xy 405.72791 -304.239588) (xy 405.683448 -304.260686) (xy 405.636177 -304.274378)
			(xy 405.587322 -304.28031) (xy 405.538147 -304.278329) (xy 405.489928 -304.268485) (xy 405.443912 -304.251033)
			(xy 405.401291 -304.226426) (xy 405.36317 -304.195301) (xy 405.330535 -304.158464) (xy 405.304232 -304.116868)
			(xy 405.284941 -304.071592) (xy 405.273164 -304.023808) (xy 405.269204 -303.974754) (xy 404.930102 -303.974754)
			(xy 404.929607 -303.999361) (xy 404.921712 -304.047938) (xy 404.906128 -304.094619) (xy 404.883257 -304.138196)
			(xy 404.853692 -304.17754) (xy 404.818199 -304.211632) (xy 404.777696 -304.239588) (xy 404.733234 -304.260686)
			(xy 404.685963 -304.274378) (xy 404.637108 -304.28031) (xy 404.587933 -304.278329) (xy 404.539714 -304.268485)
			(xy 404.493698 -304.251033) (xy 404.451077 -304.226426) (xy 404.412956 -304.195301) (xy 404.380321 -304.158464)
			(xy 404.354018 -304.116868) (xy 404.334727 -304.071592) (xy 404.32295 -304.023808) (xy 404.31899 -303.974754)
			(xy 403.980142 -303.974754) (xy 403.979647 -303.999361) (xy 403.971752 -304.047938) (xy 403.956168 -304.094619)
			(xy 403.933297 -304.138196) (xy 403.903732 -304.17754) (xy 403.868239 -304.211632) (xy 403.827736 -304.239588)
			(xy 403.783274 -304.260686) (xy 403.736003 -304.274378) (xy 403.687148 -304.28031) (xy 403.637973 -304.278329)
			(xy 403.589754 -304.268485) (xy 403.543738 -304.251033) (xy 403.501117 -304.226426) (xy 403.462996 -304.195301)
			(xy 403.430361 -304.158464) (xy 403.404058 -304.116868) (xy 403.384767 -304.071592) (xy 403.37299 -304.023808)
			(xy 403.36903 -303.974754) (xy 403.030182 -303.974754) (xy 403.029687 -303.999361) (xy 403.021792 -304.047938)
			(xy 403.006208 -304.094619) (xy 402.983337 -304.138196) (xy 402.953772 -304.17754) (xy 402.918279 -304.211632)
			(xy 402.877776 -304.239588) (xy 402.833314 -304.260686) (xy 402.786043 -304.274378) (xy 402.737188 -304.28031)
			(xy 402.688013 -304.278329) (xy 402.639794 -304.268485) (xy 402.593778 -304.251033) (xy 402.551157 -304.226426)
			(xy 402.513036 -304.195301) (xy 402.480401 -304.158464) (xy 402.454098 -304.116868) (xy 402.434807 -304.071592)
			(xy 402.42303 -304.023808) (xy 402.41907 -303.974754) (xy 402.080222 -303.974754) (xy 402.079727 -303.999361)
			(xy 402.071832 -304.047938) (xy 402.056248 -304.094619) (xy 402.033377 -304.138196) (xy 402.003812 -304.17754)
			(xy 401.968319 -304.211632) (xy 401.927816 -304.239588) (xy 401.883354 -304.260686) (xy 401.836083 -304.274378)
			(xy 401.787228 -304.28031) (xy 401.738053 -304.278329) (xy 401.689834 -304.268485) (xy 401.643818 -304.251033)
			(xy 401.601197 -304.226426) (xy 401.563076 -304.195301) (xy 401.530441 -304.158464) (xy 401.504138 -304.116868)
			(xy 401.484847 -304.071592) (xy 401.47307 -304.023808) (xy 401.46911 -303.974754) (xy 401.130262 -303.974754)
			(xy 401.129767 -303.999361) (xy 401.121872 -304.047938) (xy 401.106288 -304.094619) (xy 401.083417 -304.138196)
			(xy 401.053852 -304.17754) (xy 401.018359 -304.211632) (xy 400.977856 -304.239588) (xy 400.933394 -304.260686)
			(xy 400.886123 -304.274378) (xy 400.837268 -304.28031) (xy 400.788093 -304.278329) (xy 400.739874 -304.268485)
			(xy 400.693858 -304.251033) (xy 400.651237 -304.226426) (xy 400.613116 -304.195301) (xy 400.580481 -304.158464)
			(xy 400.554178 -304.116868) (xy 400.534887 -304.071592) (xy 400.52311 -304.023808) (xy 400.51915 -303.974754)
			(xy 400.180302 -303.974754) (xy 400.179807 -303.999361) (xy 400.171912 -304.047938) (xy 400.156328 -304.094619)
			(xy 400.133457 -304.138196) (xy 400.103892 -304.17754) (xy 400.068399 -304.211632) (xy 400.027896 -304.239588)
			(xy 399.983434 -304.260686) (xy 399.936163 -304.274378) (xy 399.887308 -304.28031) (xy 399.838133 -304.278329)
			(xy 399.789914 -304.268485) (xy 399.743898 -304.251033) (xy 399.701277 -304.226426) (xy 399.663156 -304.195301)
			(xy 399.630521 -304.158464) (xy 399.604218 -304.116868) (xy 399.584927 -304.071592) (xy 399.57315 -304.023808)
			(xy 399.56919 -303.974754) (xy 399.230342 -303.974754) (xy 399.229847 -303.999361) (xy 399.221952 -304.047938)
			(xy 399.206368 -304.094619) (xy 399.183497 -304.138196) (xy 399.153932 -304.17754) (xy 399.118439 -304.211632)
			(xy 399.077936 -304.239588) (xy 399.033474 -304.260686) (xy 398.986203 -304.274378) (xy 398.937348 -304.28031)
			(xy 398.888173 -304.278329) (xy 398.839954 -304.268485) (xy 398.793938 -304.251033) (xy 398.751317 -304.226426)
			(xy 398.713196 -304.195301) (xy 398.680561 -304.158464) (xy 398.654258 -304.116868) (xy 398.634967 -304.071592)
			(xy 398.62319 -304.023808) (xy 398.61923 -303.974754) (xy 398.280128 -303.974754) (xy 398.279633 -303.999361)
			(xy 398.271738 -304.047938) (xy 398.256154 -304.094619) (xy 398.233283 -304.138196) (xy 398.203718 -304.17754)
			(xy 398.168225 -304.211632) (xy 398.127722 -304.239588) (xy 398.08326 -304.260686) (xy 398.035989 -304.274378)
			(xy 397.987134 -304.28031) (xy 397.937959 -304.278329) (xy 397.88974 -304.268485) (xy 397.843724 -304.251033)
			(xy 397.801103 -304.226426) (xy 397.762982 -304.195301) (xy 397.730347 -304.158464) (xy 397.704044 -304.116868)
			(xy 397.684753 -304.071592) (xy 397.672976 -304.023808) (xy 397.669016 -303.974754) (xy 397.330168 -303.974754)
			(xy 397.329673 -303.999361) (xy 397.321778 -304.047938) (xy 397.306194 -304.094619) (xy 397.283323 -304.138196)
			(xy 397.253758 -304.17754) (xy 397.218265 -304.211632) (xy 397.177762 -304.239588) (xy 397.1333 -304.260686)
			(xy 397.086029 -304.274378) (xy 397.037174 -304.28031) (xy 396.987999 -304.278329) (xy 396.93978 -304.268485)
			(xy 396.893764 -304.251033) (xy 396.851143 -304.226426) (xy 396.813022 -304.195301) (xy 396.780387 -304.158464)
			(xy 396.754084 -304.116868) (xy 396.734793 -304.071592) (xy 396.723016 -304.023808) (xy 396.719056 -303.974754)
			(xy 396.380208 -303.974754) (xy 396.379713 -303.999361) (xy 396.371818 -304.047938) (xy 396.356234 -304.094619)
			(xy 396.333363 -304.138196) (xy 396.303798 -304.17754) (xy 396.268305 -304.211632) (xy 396.227802 -304.239588)
			(xy 396.18334 -304.260686) (xy 396.136069 -304.274378) (xy 396.087214 -304.28031) (xy 396.038039 -304.278329)
			(xy 395.98982 -304.268485) (xy 395.943804 -304.251033) (xy 395.901183 -304.226426) (xy 395.863062 -304.195301)
			(xy 395.830427 -304.158464) (xy 395.804124 -304.116868) (xy 395.784833 -304.071592) (xy 395.773056 -304.023808)
			(xy 395.769096 -303.974754) (xy 395.430248 -303.974754) (xy 395.429753 -303.999361) (xy 395.421858 -304.047938)
			(xy 395.406274 -304.094619) (xy 395.383403 -304.138196) (xy 395.353838 -304.17754) (xy 395.318345 -304.211632)
			(xy 395.277842 -304.239588) (xy 395.23338 -304.260686) (xy 395.186109 -304.274378) (xy 395.137254 -304.28031)
			(xy 395.088079 -304.278329) (xy 395.03986 -304.268485) (xy 394.993844 -304.251033) (xy 394.951223 -304.226426)
			(xy 394.913102 -304.195301) (xy 394.880467 -304.158464) (xy 394.854164 -304.116868) (xy 394.834873 -304.071592)
			(xy 394.823096 -304.023808) (xy 394.819136 -303.974754) (xy 351.03308 -303.974754) (xy 351.03308 -305.008534)
			(xy 353.029012 -305.008534) (xy 353.029495 -304.981164) (xy 353.037308 -304.926986) (xy 353.052793 -304.874483)
			(xy 353.075631 -304.824736) (xy 353.105352 -304.778768) (xy 353.122992 -304.757836) (xy 353.129088 -304.750724)
			(xy 353.135438 -304.733706) (xy 353.135438 -304.648362) (xy 353.129088 -304.631344) (xy 353.122992 -304.624232)
			(xy 353.105353 -304.6033) (xy 353.075642 -304.557327) (xy 353.052806 -304.507579) (xy 353.037315 -304.455079)
			(xy 353.029486 -304.400903) (xy 353.029012 -304.373534) (xy 353.029498 -304.346283) (xy 353.037254 -304.292335)
			(xy 353.052609 -304.24004) (xy 353.075251 -304.190463) (xy 353.104717 -304.144613) (xy 353.140408 -304.103422)
			(xy 353.181599 -304.067731) (xy 353.227449 -304.038265) (xy 353.277026 -304.015623) (xy 353.329321 -304.000268)
			(xy 353.383269 -303.992512) (xy 353.437771 -303.992512) (xy 353.491719 -304.000268) (xy 353.544014 -304.015623)
			(xy 353.593591 -304.038265) (xy 353.639441 -304.067731) (xy 353.680632 -304.103422) (xy 353.716323 -304.144613)
			(xy 353.745789 -304.190463) (xy 353.768431 -304.24004) (xy 353.783786 -304.292335) (xy 353.791542 -304.346283)
			(xy 353.792028 -304.373534) (xy 353.791599 -304.400906) (xy 353.783775 -304.455087) (xy 353.768278 -304.507591)
			(xy 353.745428 -304.557338) (xy 353.715694 -304.603302) (xy 353.698048 -304.624232) (xy 353.691952 -304.631344)
			(xy 353.685602 -304.648362) (xy 353.685602 -304.733706) (xy 353.691952 -304.750724) (xy 353.698048 -304.757836)
			(xy 353.715662 -304.778788) (xy 353.74538 -304.824755) (xy 353.768221 -304.874497) (xy 353.783718 -304.926993)
			(xy 353.791551 -304.981166) (xy 353.792028 -305.008534) (xy 356.449122 -305.008534) (xy 356.449603 -304.981164)
			(xy 356.457416 -304.926986) (xy 356.472902 -304.874482) (xy 356.49574 -304.824735) (xy 356.525462 -304.778768)
			(xy 356.543102 -304.757836) (xy 356.549198 -304.750724) (xy 356.555548 -304.733706) (xy 356.555548 -304.648362)
			(xy 356.549198 -304.631344) (xy 356.543102 -304.624232) (xy 356.525465 -304.603298) (xy 356.495753 -304.557326)
			(xy 356.472916 -304.507579) (xy 356.457425 -304.455079) (xy 356.449596 -304.400903) (xy 356.449122 -304.373534)
			(xy 356.449608 -304.346283) (xy 356.457364 -304.292335) (xy 356.472719 -304.24004) (xy 356.495361 -304.190463)
			(xy 356.524827 -304.144613) (xy 356.560518 -304.103422) (xy 356.601709 -304.067731) (xy 356.647559 -304.038265)
			(xy 356.697136 -304.015623) (xy 356.749431 -304.000268) (xy 356.803379 -303.992512) (xy 356.857881 -303.992512)
			(xy 356.911829 -304.000268) (xy 356.964124 -304.015623) (xy 357.013701 -304.038265) (xy 357.059551 -304.067731)
			(xy 357.100742 -304.103422) (xy 357.136433 -304.144613) (xy 357.165899 -304.190463) (xy 357.188541 -304.24004)
			(xy 357.203896 -304.292335) (xy 357.211652 -304.346283) (xy 357.212138 -304.373534) (xy 357.211707 -304.400906)
			(xy 357.203883 -304.455087) (xy 357.188387 -304.507591) (xy 357.165537 -304.557337) (xy 357.135804 -304.603302)
			(xy 357.118158 -304.624232) (xy 357.112062 -304.631344) (xy 357.105712 -304.648362) (xy 357.105712 -304.733706)
			(xy 357.112062 -304.750724) (xy 357.118158 -304.757836) (xy 357.135774 -304.778787) (xy 357.165491 -304.824754)
			(xy 357.188332 -304.874496) (xy 357.203828 -304.926993) (xy 357.211661 -304.981166) (xy 357.212138 -305.008534)
			(xy 357.837232 -305.008534) (xy 357.83771 -304.981164) (xy 357.845524 -304.926985) (xy 357.86101 -304.874482)
			(xy 357.883849 -304.824735) (xy 357.913572 -304.778768) (xy 357.931212 -304.757836) (xy 357.937308 -304.750724)
			(xy 357.943658 -304.733706) (xy 357.943658 -304.648362) (xy 357.937308 -304.631344) (xy 357.931212 -304.624232)
			(xy 357.913576 -304.603297) (xy 357.883864 -304.557325) (xy 357.861027 -304.507579) (xy 357.845535 -304.455078)
			(xy 357.837706 -304.400903) (xy 357.837232 -304.373534) (xy 357.837718 -304.346283) (xy 357.845474 -304.292335)
			(xy 357.860829 -304.24004) (xy 357.883471 -304.190463) (xy 357.912937 -304.144613) (xy 357.948628 -304.103422)
			(xy 357.989819 -304.067731) (xy 358.035669 -304.038265) (xy 358.085246 -304.015623) (xy 358.137541 -304.000268)
			(xy 358.191489 -303.992512) (xy 358.245991 -303.992512) (xy 358.299939 -304.000268) (xy 358.352234 -304.015623)
			(xy 358.401811 -304.038265) (xy 358.447661 -304.067731) (xy 358.488852 -304.103422) (xy 358.524543 -304.144613)
			(xy 358.554009 -304.190463) (xy 358.576651 -304.24004) (xy 358.592006 -304.292335) (xy 358.599762 -304.346283)
			(xy 358.600248 -304.373534) (xy 358.599815 -304.400906) (xy 358.591991 -304.455087) (xy 358.576495 -304.507591)
			(xy 358.553645 -304.557337) (xy 358.523913 -304.603302) (xy 358.506268 -304.624232) (xy 358.500172 -304.631344)
			(xy 358.493822 -304.648362) (xy 358.493822 -304.733706) (xy 358.500172 -304.750724) (xy 358.506268 -304.757836)
			(xy 358.523886 -304.778785) (xy 358.553602 -304.824753) (xy 358.576442 -304.874496) (xy 358.591938 -304.926993)
			(xy 358.599772 -304.981166) (xy 358.600248 -305.008534) (xy 359.869232 -305.008534) (xy 359.86971 -304.981164)
			(xy 359.877524 -304.926985) (xy 359.89301 -304.874482) (xy 359.915849 -304.824735) (xy 359.945572 -304.778768)
			(xy 359.963212 -304.757836) (xy 359.969308 -304.750724) (xy 359.975658 -304.733706) (xy 359.975658 -304.648362)
			(xy 359.969308 -304.631344) (xy 359.963212 -304.624232) (xy 359.945576 -304.603297) (xy 359.915864 -304.557325)
			(xy 359.893027 -304.507579) (xy 359.877535 -304.455078) (xy 359.869706 -304.400903) (xy 359.869232 -304.373534)
			(xy 359.869718 -304.346283) (xy 359.877474 -304.292335) (xy 359.892829 -304.24004) (xy 359.915471 -304.190463)
			(xy 359.944937 -304.144613) (xy 359.980628 -304.103422) (xy 360.021819 -304.067731) (xy 360.067669 -304.038265)
			(xy 360.117246 -304.015623) (xy 360.169541 -304.000268) (xy 360.223489 -303.992512) (xy 360.277991 -303.992512)
			(xy 360.331939 -304.000268) (xy 360.384234 -304.015623) (xy 360.433811 -304.038265) (xy 360.479661 -304.067731)
			(xy 360.520852 -304.103422) (xy 360.556543 -304.144613) (xy 360.586009 -304.190463) (xy 360.608651 -304.24004)
			(xy 360.624006 -304.292335) (xy 360.631762 -304.346283) (xy 360.632248 -304.373534) (xy 360.631815 -304.400906)
			(xy 360.623991 -304.455087) (xy 360.608495 -304.507591) (xy 360.585645 -304.557337) (xy 360.555913 -304.603302)
			(xy 360.538268 -304.624232) (xy 360.532172 -304.631344) (xy 360.525822 -304.648362) (xy 360.525822 -304.733706)
			(xy 360.532172 -304.750724) (xy 360.538268 -304.757836) (xy 360.555886 -304.778785) (xy 360.585602 -304.824753)
			(xy 360.608442 -304.874496) (xy 360.623938 -304.926993) (xy 360.631772 -304.981166) (xy 360.632248 -305.008534)
			(xy 364.677452 -305.008534) (xy 364.677925 -304.981164) (xy 364.685739 -304.926985) (xy 364.701226 -304.874481)
			(xy 364.724067 -304.824734) (xy 364.753791 -304.778767) (xy 364.771432 -304.757836) (xy 364.777528 -304.750724)
			(xy 364.783878 -304.733706) (xy 364.783878 -304.648362) (xy 364.777528 -304.631344) (xy 364.771432 -304.624232)
			(xy 364.753799 -304.603295) (xy 364.724086 -304.557324) (xy 364.701248 -304.507578) (xy 364.685755 -304.455078)
			(xy 364.677926 -304.400903) (xy 364.677452 -304.373534) (xy 364.677938 -304.346283) (xy 364.685694 -304.292335)
			(xy 364.701049 -304.24004) (xy 364.723691 -304.190463) (xy 364.753157 -304.144613) (xy 364.788848 -304.103422)
			(xy 364.830039 -304.067731) (xy 364.875889 -304.038265) (xy 364.925466 -304.015623) (xy 364.977761 -304.000268)
			(xy 365.031709 -303.992512) (xy 365.086211 -303.992512) (xy 365.140159 -304.000268) (xy 365.192454 -304.015623)
			(xy 365.242031 -304.038265) (xy 365.287881 -304.067731) (xy 365.329072 -304.103422) (xy 365.364763 -304.144613)
			(xy 365.394229 -304.190463) (xy 365.416871 -304.24004) (xy 365.432226 -304.292335) (xy 365.439982 -304.346283)
			(xy 365.440468 -304.373534) (xy 365.44003 -304.400905) (xy 365.432206 -304.455086) (xy 365.416711 -304.50759)
			(xy 365.393863 -304.557336) (xy 365.364132 -304.603301) (xy 365.346488 -304.624232) (xy 365.340392 -304.631344)
			(xy 365.334042 -304.648362) (xy 365.334042 -304.733706) (xy 365.340392 -304.750724) (xy 365.346488 -304.757836)
			(xy 365.364109 -304.778783) (xy 365.393824 -304.824751) (xy 365.416663 -304.874495) (xy 365.432159 -304.926993)
			(xy 365.439992 -304.981166) (xy 365.440468 -305.008534) (xy 365.439982 -305.035785) (xy 365.432226 -305.089733)
			(xy 365.416871 -305.142028) (xy 365.394229 -305.191605) (xy 365.364763 -305.237455) (xy 365.329072 -305.278646)
			(xy 365.287881 -305.314337) (xy 365.242031 -305.343803) (xy 365.203422 -305.361436) (xy 375.710316 -305.361436)
			(xy 375.710319 -305.306922) (xy 375.71808 -305.252964) (xy 375.733442 -305.200659) (xy 375.756091 -305.151073)
			(xy 375.785568 -305.105216) (xy 375.82127 -305.06402) (xy 375.862473 -305.028325) (xy 375.908336 -304.998858)
			(xy 375.957926 -304.976217) (xy 376.010233 -304.960865) (xy 376.064193 -304.953113) (xy 376.09145 -304.952654)
			(xy 376.11939 -304.95367) (xy 376.130566 -304.954432) (xy 376.151648 -304.946558) (xy 376.221752 -304.873914)
			(xy 376.229118 -304.852578) (xy 376.227848 -304.841402) (xy 376.226788 -304.831148) (xy 376.225643 -304.810562)
			(xy 376.225562 -304.800254) (xy 376.226127 -304.773006) (xy 376.233889 -304.719067) (xy 376.249249 -304.66678)
			(xy 376.271893 -304.617212) (xy 376.30136 -304.571371) (xy 376.337052 -304.530191) (xy 376.378241 -304.494508)
			(xy 376.424089 -304.465051) (xy 376.473662 -304.442418) (xy 376.525951 -304.427071) (xy 376.579893 -304.419321)
			(xy 376.634388 -304.419327) (xy 376.688328 -304.427088) (xy 376.740615 -304.442447) (xy 376.757123 -304.449988)
			(xy 383.893834 -304.449988) (xy 383.897794 -304.400934) (xy 383.909571 -304.35315) (xy 383.928862 -304.307874)
			(xy 383.955165 -304.266278) (xy 383.9878 -304.229441) (xy 384.025921 -304.198316) (xy 384.068542 -304.173709)
			(xy 384.114558 -304.156257) (xy 384.162777 -304.146413) (xy 384.211952 -304.144432) (xy 384.260807 -304.150364)
			(xy 384.308078 -304.164056) (xy 384.35254 -304.185154) (xy 384.393043 -304.21311) (xy 384.428536 -304.247202)
			(xy 384.458101 -304.286546) (xy 384.480972 -304.330123) (xy 384.496556 -304.376804) (xy 384.504451 -304.425381)
			(xy 384.504946 -304.449988) (xy 384.504451 -304.474595) (xy 384.504313 -304.475442) (xy 384.823204 -304.475442)
			(xy 384.823204 -304.424026) (xy 384.831247 -304.373244) (xy 384.847135 -304.324345) (xy 384.870478 -304.278533)
			(xy 384.900699 -304.236937) (xy 384.937055 -304.200581) (xy 384.978651 -304.17036) (xy 385.024463 -304.147017)
			(xy 385.073362 -304.131129) (xy 385.124144 -304.123086) (xy 385.17556 -304.123086) (xy 385.226342 -304.131129)
			(xy 385.275241 -304.147017) (xy 385.321053 -304.17036) (xy 385.362649 -304.200581) (xy 385.399005 -304.236937)
			(xy 385.429226 -304.278533) (xy 385.452569 -304.324345) (xy 385.468457 -304.373244) (xy 385.4765 -304.424026)
			(xy 385.477004 -304.449734) (xy 385.4765 -304.475442) (xy 385.773164 -304.475442) (xy 385.773164 -304.424026)
			(xy 385.781207 -304.373244) (xy 385.797095 -304.324345) (xy 385.820438 -304.278533) (xy 385.850659 -304.236937)
			(xy 385.887015 -304.200581) (xy 385.928611 -304.17036) (xy 385.974423 -304.147017) (xy 386.023322 -304.131129)
			(xy 386.074104 -304.123086) (xy 386.12552 -304.123086) (xy 386.176302 -304.131129) (xy 386.225201 -304.147017)
			(xy 386.271013 -304.17036) (xy 386.312609 -304.200581) (xy 386.348965 -304.236937) (xy 386.379186 -304.278533)
			(xy 386.402529 -304.324345) (xy 386.418417 -304.373244) (xy 386.42646 -304.424026) (xy 386.426964 -304.449734)
			(xy 386.744222 -304.449734) (xy 386.748182 -304.40068) (xy 386.759959 -304.352896) (xy 386.77925 -304.30762)
			(xy 386.805553 -304.266024) (xy 386.838188 -304.229187) (xy 386.876309 -304.198062) (xy 386.91893 -304.173455)
			(xy 386.964946 -304.156003) (xy 387.013165 -304.146159) (xy 387.06234 -304.144178) (xy 387.111195 -304.15011)
			(xy 387.158466 -304.163802) (xy 387.202928 -304.1849) (xy 387.243431 -304.212856) (xy 387.278924 -304.246948)
			(xy 387.308489 -304.286292) (xy 387.33136 -304.329869) (xy 387.346944 -304.37655) (xy 387.354839 -304.425127)
			(xy 387.355334 -304.449734) (xy 387.694182 -304.449734) (xy 387.698142 -304.40068) (xy 387.709919 -304.352896)
			(xy 387.72921 -304.30762) (xy 387.755513 -304.266024) (xy 387.788148 -304.229187) (xy 387.826269 -304.198062)
			(xy 387.86889 -304.173455) (xy 387.914906 -304.156003) (xy 387.963125 -304.146159) (xy 388.0123 -304.144178)
			(xy 388.061155 -304.15011) (xy 388.108426 -304.163802) (xy 388.152888 -304.1849) (xy 388.193391 -304.212856)
			(xy 388.228884 -304.246948) (xy 388.258449 -304.286292) (xy 388.28132 -304.329869) (xy 388.296904 -304.37655)
			(xy 388.304799 -304.425127) (xy 388.305294 -304.449734) (xy 388.644142 -304.449734) (xy 388.648102 -304.40068)
			(xy 388.659879 -304.352896) (xy 388.67917 -304.30762) (xy 388.705473 -304.266024) (xy 388.738108 -304.229187)
			(xy 388.776229 -304.198062) (xy 388.81885 -304.173455) (xy 388.864866 -304.156003) (xy 388.913085 -304.146159)
			(xy 388.96226 -304.144178) (xy 389.011115 -304.15011) (xy 389.058386 -304.163802) (xy 389.102848 -304.1849)
			(xy 389.143351 -304.212856) (xy 389.178844 -304.246948) (xy 389.208409 -304.286292) (xy 389.23128 -304.329869)
			(xy 389.246864 -304.37655) (xy 389.254759 -304.425127) (xy 389.255254 -304.449734) (xy 389.594102 -304.449734)
			(xy 389.598062 -304.40068) (xy 389.609839 -304.352896) (xy 389.62913 -304.30762) (xy 389.655433 -304.266024)
			(xy 389.688068 -304.229187) (xy 389.726189 -304.198062) (xy 389.76881 -304.173455) (xy 389.814826 -304.156003)
			(xy 389.863045 -304.146159) (xy 389.91222 -304.144178) (xy 389.961075 -304.15011) (xy 390.008346 -304.163802)
			(xy 390.052808 -304.1849) (xy 390.093311 -304.212856) (xy 390.128804 -304.246948) (xy 390.158369 -304.286292)
			(xy 390.18124 -304.329869) (xy 390.196824 -304.37655) (xy 390.204719 -304.425127) (xy 390.205214 -304.449734)
			(xy 390.544062 -304.449734) (xy 390.548022 -304.40068) (xy 390.559799 -304.352896) (xy 390.57909 -304.30762)
			(xy 390.605393 -304.266024) (xy 390.638028 -304.229187) (xy 390.676149 -304.198062) (xy 390.71877 -304.173455)
			(xy 390.764786 -304.156003) (xy 390.813005 -304.146159) (xy 390.86218 -304.144178) (xy 390.911035 -304.15011)
			(xy 390.958306 -304.163802) (xy 391.002768 -304.1849) (xy 391.043271 -304.212856) (xy 391.078764 -304.246948)
			(xy 391.108329 -304.286292) (xy 391.1312 -304.329869) (xy 391.146784 -304.37655) (xy 391.154679 -304.425127)
			(xy 391.155174 -304.449734) (xy 391.154679 -304.474341) (xy 391.1545 -304.475442) (xy 391.473178 -304.475442)
			(xy 391.473178 -304.424026) (xy 391.481221 -304.373244) (xy 391.497109 -304.324345) (xy 391.520452 -304.278533)
			(xy 391.550673 -304.236937) (xy 391.587029 -304.200581) (xy 391.628625 -304.17036) (xy 391.674437 -304.147017)
			(xy 391.723336 -304.131129) (xy 391.774118 -304.123086) (xy 391.825534 -304.123086) (xy 391.876316 -304.131129)
			(xy 391.925215 -304.147017) (xy 391.971027 -304.17036) (xy 392.012623 -304.200581) (xy 392.048979 -304.236937)
			(xy 392.0792 -304.278533) (xy 392.102543 -304.324345) (xy 392.118431 -304.373244) (xy 392.126474 -304.424026)
			(xy 392.126978 -304.449734) (xy 392.126474 -304.475442) (xy 392.423138 -304.475442) (xy 392.423138 -304.424026)
			(xy 392.431181 -304.373244) (xy 392.447069 -304.324345) (xy 392.470412 -304.278533) (xy 392.500633 -304.236937)
			(xy 392.536989 -304.200581) (xy 392.578585 -304.17036) (xy 392.624397 -304.147017) (xy 392.673296 -304.131129)
			(xy 392.724078 -304.123086) (xy 392.775494 -304.123086) (xy 392.826276 -304.131129) (xy 392.875175 -304.147017)
			(xy 392.920987 -304.17036) (xy 392.962583 -304.200581) (xy 392.998939 -304.236937) (xy 393.02916 -304.278533)
			(xy 393.052503 -304.324345) (xy 393.068391 -304.373244) (xy 393.076434 -304.424026) (xy 393.076938 -304.449734)
			(xy 393.394196 -304.449734) (xy 393.398156 -304.40068) (xy 393.409933 -304.352896) (xy 393.429224 -304.30762)
			(xy 393.455527 -304.266024) (xy 393.488162 -304.229187) (xy 393.526283 -304.198062) (xy 393.568904 -304.173455)
			(xy 393.61492 -304.156003) (xy 393.663139 -304.146159) (xy 393.712314 -304.144178) (xy 393.761169 -304.15011)
			(xy 393.80844 -304.163802) (xy 393.852902 -304.1849) (xy 393.893405 -304.212856) (xy 393.928898 -304.246948)
			(xy 393.958463 -304.286292) (xy 393.981334 -304.329869) (xy 393.996918 -304.37655) (xy 394.004813 -304.425127)
			(xy 394.005308 -304.449734) (xy 394.004813 -304.474341) (xy 393.996918 -304.522918) (xy 393.981334 -304.569599)
			(xy 393.958463 -304.613176) (xy 393.928898 -304.65252) (xy 393.893405 -304.686612) (xy 393.852902 -304.714568)
			(xy 393.80844 -304.735666) (xy 393.761169 -304.749358) (xy 393.712314 -304.75529) (xy 393.663139 -304.753309)
			(xy 393.61492 -304.743465) (xy 393.568904 -304.726013) (xy 393.526283 -304.701406) (xy 393.488162 -304.670281)
			(xy 393.455527 -304.633444) (xy 393.429224 -304.591848) (xy 393.409933 -304.546572) (xy 393.398156 -304.498788)
			(xy 393.394196 -304.449734) (xy 393.076938 -304.449734) (xy 393.076434 -304.475442) (xy 393.068391 -304.526224)
			(xy 393.052503 -304.575123) (xy 393.02916 -304.620935) (xy 392.998939 -304.662531) (xy 392.962583 -304.698887)
			(xy 392.920987 -304.729108) (xy 392.875175 -304.752451) (xy 392.826276 -304.768339) (xy 392.775494 -304.776382)
			(xy 392.724078 -304.776382) (xy 392.673296 -304.768339) (xy 392.624397 -304.752451) (xy 392.578585 -304.729108)
			(xy 392.536989 -304.698887) (xy 392.500633 -304.662531) (xy 392.470412 -304.620935) (xy 392.447069 -304.575123)
			(xy 392.431181 -304.526224) (xy 392.423138 -304.475442) (xy 392.126474 -304.475442) (xy 392.118431 -304.526224)
			(xy 392.102543 -304.575123) (xy 392.0792 -304.620935) (xy 392.048979 -304.662531) (xy 392.012623 -304.698887)
			(xy 391.971027 -304.729108) (xy 391.925215 -304.752451) (xy 391.876316 -304.768339) (xy 391.825534 -304.776382)
			(xy 391.774118 -304.776382) (xy 391.723336 -304.768339) (xy 391.674437 -304.752451) (xy 391.628625 -304.729108)
			(xy 391.587029 -304.698887) (xy 391.550673 -304.662531) (xy 391.520452 -304.620935) (xy 391.497109 -304.575123)
			(xy 391.481221 -304.526224) (xy 391.473178 -304.475442) (xy 391.1545 -304.475442) (xy 391.146784 -304.522918)
			(xy 391.1312 -304.569599) (xy 391.108329 -304.613176) (xy 391.078764 -304.65252) (xy 391.043271 -304.686612)
			(xy 391.002768 -304.714568) (xy 390.958306 -304.735666) (xy 390.911035 -304.749358) (xy 390.86218 -304.75529)
			(xy 390.813005 -304.753309) (xy 390.764786 -304.743465) (xy 390.71877 -304.726013) (xy 390.676149 -304.701406)
			(xy 390.638028 -304.670281) (xy 390.605393 -304.633444) (xy 390.57909 -304.591848) (xy 390.559799 -304.546572)
			(xy 390.548022 -304.498788) (xy 390.544062 -304.449734) (xy 390.205214 -304.449734) (xy 390.204719 -304.474341)
			(xy 390.196824 -304.522918) (xy 390.18124 -304.569599) (xy 390.158369 -304.613176) (xy 390.128804 -304.65252)
			(xy 390.093311 -304.686612) (xy 390.052808 -304.714568) (xy 390.008346 -304.735666) (xy 389.961075 -304.749358)
			(xy 389.91222 -304.75529) (xy 389.863045 -304.753309) (xy 389.814826 -304.743465) (xy 389.76881 -304.726013)
			(xy 389.726189 -304.701406) (xy 389.688068 -304.670281) (xy 389.655433 -304.633444) (xy 389.62913 -304.591848)
			(xy 389.609839 -304.546572) (xy 389.598062 -304.498788) (xy 389.594102 -304.449734) (xy 389.255254 -304.449734)
			(xy 389.254759 -304.474341) (xy 389.246864 -304.522918) (xy 389.23128 -304.569599) (xy 389.208409 -304.613176)
			(xy 389.178844 -304.65252) (xy 389.143351 -304.686612) (xy 389.102848 -304.714568) (xy 389.058386 -304.735666)
			(xy 389.011115 -304.749358) (xy 388.96226 -304.75529) (xy 388.913085 -304.753309) (xy 388.864866 -304.743465)
			(xy 388.81885 -304.726013) (xy 388.776229 -304.701406) (xy 388.738108 -304.670281) (xy 388.705473 -304.633444)
			(xy 388.67917 -304.591848) (xy 388.659879 -304.546572) (xy 388.648102 -304.498788) (xy 388.644142 -304.449734)
			(xy 388.305294 -304.449734) (xy 388.304799 -304.474341) (xy 388.296904 -304.522918) (xy 388.28132 -304.569599)
			(xy 388.258449 -304.613176) (xy 388.228884 -304.65252) (xy 388.193391 -304.686612) (xy 388.152888 -304.714568)
			(xy 388.108426 -304.735666) (xy 388.061155 -304.749358) (xy 388.0123 -304.75529) (xy 387.963125 -304.753309)
			(xy 387.914906 -304.743465) (xy 387.86889 -304.726013) (xy 387.826269 -304.701406) (xy 387.788148 -304.670281)
			(xy 387.755513 -304.633444) (xy 387.72921 -304.591848) (xy 387.709919 -304.546572) (xy 387.698142 -304.498788)
			(xy 387.694182 -304.449734) (xy 387.355334 -304.449734) (xy 387.354839 -304.474341) (xy 387.346944 -304.522918)
			(xy 387.33136 -304.569599) (xy 387.308489 -304.613176) (xy 387.278924 -304.65252) (xy 387.243431 -304.686612)
			(xy 387.202928 -304.714568) (xy 387.158466 -304.735666) (xy 387.111195 -304.749358) (xy 387.06234 -304.75529)
			(xy 387.013165 -304.753309) (xy 386.964946 -304.743465) (xy 386.91893 -304.726013) (xy 386.876309 -304.701406)
			(xy 386.838188 -304.670281) (xy 386.805553 -304.633444) (xy 386.77925 -304.591848) (xy 386.759959 -304.546572)
			(xy 386.748182 -304.498788) (xy 386.744222 -304.449734) (xy 386.426964 -304.449734) (xy 386.42646 -304.475442)
			(xy 386.418417 -304.526224) (xy 386.402529 -304.575123) (xy 386.379186 -304.620935) (xy 386.348965 -304.662531)
			(xy 386.312609 -304.698887) (xy 386.271013 -304.729108) (xy 386.225201 -304.752451) (xy 386.176302 -304.768339)
			(xy 386.12552 -304.776382) (xy 386.074104 -304.776382) (xy 386.023322 -304.768339) (xy 385.974423 -304.752451)
			(xy 385.928611 -304.729108) (xy 385.887015 -304.698887) (xy 385.850659 -304.662531) (xy 385.820438 -304.620935)
			(xy 385.797095 -304.575123) (xy 385.781207 -304.526224) (xy 385.773164 -304.475442) (xy 385.4765 -304.475442)
			(xy 385.468457 -304.526224) (xy 385.452569 -304.575123) (xy 385.429226 -304.620935) (xy 385.399005 -304.662531)
			(xy 385.362649 -304.698887) (xy 385.321053 -304.729108) (xy 385.275241 -304.752451) (xy 385.226342 -304.768339)
			(xy 385.17556 -304.776382) (xy 385.124144 -304.776382) (xy 385.073362 -304.768339) (xy 385.024463 -304.752451)
			(xy 384.978651 -304.729108) (xy 384.937055 -304.698887) (xy 384.900699 -304.662531) (xy 384.870478 -304.620935)
			(xy 384.847135 -304.575123) (xy 384.831247 -304.526224) (xy 384.823204 -304.475442) (xy 384.504313 -304.475442)
			(xy 384.496556 -304.523172) (xy 384.480972 -304.569853) (xy 384.458101 -304.61343) (xy 384.428536 -304.652774)
			(xy 384.393043 -304.686866) (xy 384.35254 -304.714822) (xy 384.308078 -304.73592) (xy 384.260807 -304.749612)
			(xy 384.211952 -304.755544) (xy 384.162777 -304.753563) (xy 384.114558 -304.743719) (xy 384.068542 -304.726267)
			(xy 384.025921 -304.70166) (xy 383.9878 -304.670535) (xy 383.955165 -304.633698) (xy 383.928862 -304.592102)
			(xy 383.909571 -304.546826) (xy 383.897794 -304.499042) (xy 383.893834 -304.449988) (xy 376.757123 -304.449988)
			(xy 376.790183 -304.46509) (xy 376.836024 -304.494557) (xy 376.877206 -304.530248) (xy 376.912888 -304.571437)
			(xy 376.942346 -304.617284) (xy 376.96498 -304.666857) (xy 376.980328 -304.719146) (xy 376.988078 -304.773088)
			(xy 376.988073 -304.827583) (xy 376.980313 -304.881523) (xy 376.967627 -304.924714) (xy 394.819136 -304.924714)
			(xy 394.823096 -304.87566) (xy 394.834873 -304.827876) (xy 394.854164 -304.7826) (xy 394.880467 -304.741004)
			(xy 394.913102 -304.704167) (xy 394.951223 -304.673042) (xy 394.993844 -304.648435) (xy 395.03986 -304.630983)
			(xy 395.088079 -304.621139) (xy 395.137254 -304.619158) (xy 395.186109 -304.62509) (xy 395.23338 -304.638782)
			(xy 395.277842 -304.65988) (xy 395.318345 -304.687836) (xy 395.353838 -304.721928) (xy 395.383403 -304.761272)
			(xy 395.406274 -304.804849) (xy 395.421858 -304.85153) (xy 395.429753 -304.900107) (xy 395.430248 -304.924714)
			(xy 395.769096 -304.924714) (xy 395.773056 -304.87566) (xy 395.784833 -304.827876) (xy 395.804124 -304.7826)
			(xy 395.830427 -304.741004) (xy 395.863062 -304.704167) (xy 395.901183 -304.673042) (xy 395.943804 -304.648435)
			(xy 395.98982 -304.630983) (xy 396.038039 -304.621139) (xy 396.087214 -304.619158) (xy 396.136069 -304.62509)
			(xy 396.18334 -304.638782) (xy 396.227802 -304.65988) (xy 396.268305 -304.687836) (xy 396.303798 -304.721928)
			(xy 396.333363 -304.761272) (xy 396.356234 -304.804849) (xy 396.371818 -304.85153) (xy 396.379713 -304.900107)
			(xy 396.380208 -304.924714) (xy 396.719056 -304.924714) (xy 396.723016 -304.87566) (xy 396.734793 -304.827876)
			(xy 396.754084 -304.7826) (xy 396.780387 -304.741004) (xy 396.813022 -304.704167) (xy 396.851143 -304.673042)
			(xy 396.893764 -304.648435) (xy 396.93978 -304.630983) (xy 396.987999 -304.621139) (xy 397.037174 -304.619158)
			(xy 397.086029 -304.62509) (xy 397.1333 -304.638782) (xy 397.177762 -304.65988) (xy 397.218265 -304.687836)
			(xy 397.253758 -304.721928) (xy 397.283323 -304.761272) (xy 397.306194 -304.804849) (xy 397.321778 -304.85153)
			(xy 397.329673 -304.900107) (xy 397.330168 -304.924714) (xy 397.669016 -304.924714) (xy 397.672976 -304.87566)
			(xy 397.684753 -304.827876) (xy 397.704044 -304.7826) (xy 397.730347 -304.741004) (xy 397.762982 -304.704167)
			(xy 397.801103 -304.673042) (xy 397.843724 -304.648435) (xy 397.88974 -304.630983) (xy 397.937959 -304.621139)
			(xy 397.987134 -304.619158) (xy 398.035989 -304.62509) (xy 398.08326 -304.638782) (xy 398.127722 -304.65988)
			(xy 398.168225 -304.687836) (xy 398.203718 -304.721928) (xy 398.233283 -304.761272) (xy 398.256154 -304.804849)
			(xy 398.271738 -304.85153) (xy 398.279633 -304.900107) (xy 398.280128 -304.924714) (xy 398.61923 -304.924714)
			(xy 398.62319 -304.87566) (xy 398.634967 -304.827876) (xy 398.654258 -304.7826) (xy 398.680561 -304.741004)
			(xy 398.713196 -304.704167) (xy 398.751317 -304.673042) (xy 398.793938 -304.648435) (xy 398.839954 -304.630983)
			(xy 398.888173 -304.621139) (xy 398.937348 -304.619158) (xy 398.986203 -304.62509) (xy 399.033474 -304.638782)
			(xy 399.077936 -304.65988) (xy 399.118439 -304.687836) (xy 399.153932 -304.721928) (xy 399.183497 -304.761272)
			(xy 399.206368 -304.804849) (xy 399.221952 -304.85153) (xy 399.229847 -304.900107) (xy 399.230342 -304.924714)
			(xy 399.56919 -304.924714) (xy 399.57315 -304.87566) (xy 399.584927 -304.827876) (xy 399.604218 -304.7826)
			(xy 399.630521 -304.741004) (xy 399.663156 -304.704167) (xy 399.701277 -304.673042) (xy 399.743898 -304.648435)
			(xy 399.789914 -304.630983) (xy 399.838133 -304.621139) (xy 399.887308 -304.619158) (xy 399.936163 -304.62509)
			(xy 399.983434 -304.638782) (xy 400.027896 -304.65988) (xy 400.068399 -304.687836) (xy 400.103892 -304.721928)
			(xy 400.133457 -304.761272) (xy 400.156328 -304.804849) (xy 400.171912 -304.85153) (xy 400.179807 -304.900107)
			(xy 400.180302 -304.924714) (xy 400.51915 -304.924714) (xy 400.52311 -304.87566) (xy 400.534887 -304.827876)
			(xy 400.554178 -304.7826) (xy 400.580481 -304.741004) (xy 400.613116 -304.704167) (xy 400.651237 -304.673042)
			(xy 400.693858 -304.648435) (xy 400.739874 -304.630983) (xy 400.788093 -304.621139) (xy 400.837268 -304.619158)
			(xy 400.886123 -304.62509) (xy 400.933394 -304.638782) (xy 400.977856 -304.65988) (xy 401.018359 -304.687836)
			(xy 401.053852 -304.721928) (xy 401.083417 -304.761272) (xy 401.106288 -304.804849) (xy 401.121872 -304.85153)
			(xy 401.129767 -304.900107) (xy 401.130262 -304.924714) (xy 401.46911 -304.924714) (xy 401.47307 -304.87566)
			(xy 401.484847 -304.827876) (xy 401.504138 -304.7826) (xy 401.530441 -304.741004) (xy 401.563076 -304.704167)
			(xy 401.601197 -304.673042) (xy 401.643818 -304.648435) (xy 401.689834 -304.630983) (xy 401.738053 -304.621139)
			(xy 401.787228 -304.619158) (xy 401.836083 -304.62509) (xy 401.883354 -304.638782) (xy 401.927816 -304.65988)
			(xy 401.968319 -304.687836) (xy 402.003812 -304.721928) (xy 402.033377 -304.761272) (xy 402.056248 -304.804849)
			(xy 402.071832 -304.85153) (xy 402.079727 -304.900107) (xy 402.080222 -304.924714) (xy 402.41907 -304.924714)
			(xy 402.42303 -304.87566) (xy 402.434807 -304.827876) (xy 402.454098 -304.7826) (xy 402.480401 -304.741004)
			(xy 402.513036 -304.704167) (xy 402.551157 -304.673042) (xy 402.593778 -304.648435) (xy 402.639794 -304.630983)
			(xy 402.688013 -304.621139) (xy 402.737188 -304.619158) (xy 402.786043 -304.62509) (xy 402.833314 -304.638782)
			(xy 402.877776 -304.65988) (xy 402.918279 -304.687836) (xy 402.953772 -304.721928) (xy 402.983337 -304.761272)
			(xy 403.006208 -304.804849) (xy 403.021792 -304.85153) (xy 403.029687 -304.900107) (xy 403.030182 -304.924714)
			(xy 403.36903 -304.924714) (xy 403.37299 -304.87566) (xy 403.384767 -304.827876) (xy 403.404058 -304.7826)
			(xy 403.430361 -304.741004) (xy 403.462996 -304.704167) (xy 403.501117 -304.673042) (xy 403.543738 -304.648435)
			(xy 403.589754 -304.630983) (xy 403.637973 -304.621139) (xy 403.687148 -304.619158) (xy 403.736003 -304.62509)
			(xy 403.783274 -304.638782) (xy 403.827736 -304.65988) (xy 403.868239 -304.687836) (xy 403.903732 -304.721928)
			(xy 403.933297 -304.761272) (xy 403.956168 -304.804849) (xy 403.971752 -304.85153) (xy 403.979647 -304.900107)
			(xy 403.980142 -304.924714) (xy 404.31899 -304.924714) (xy 404.32295 -304.87566) (xy 404.334727 -304.827876)
			(xy 404.354018 -304.7826) (xy 404.380321 -304.741004) (xy 404.412956 -304.704167) (xy 404.451077 -304.673042)
			(xy 404.493698 -304.648435) (xy 404.539714 -304.630983) (xy 404.587933 -304.621139) (xy 404.637108 -304.619158)
			(xy 404.685963 -304.62509) (xy 404.733234 -304.638782) (xy 404.777696 -304.65988) (xy 404.818199 -304.687836)
			(xy 404.853692 -304.721928) (xy 404.883257 -304.761272) (xy 404.906128 -304.804849) (xy 404.921712 -304.85153)
			(xy 404.929607 -304.900107) (xy 404.930102 -304.924714) (xy 405.269204 -304.924714) (xy 405.273164 -304.87566)
			(xy 405.284941 -304.827876) (xy 405.304232 -304.7826) (xy 405.330535 -304.741004) (xy 405.36317 -304.704167)
			(xy 405.401291 -304.673042) (xy 405.443912 -304.648435) (xy 405.489928 -304.630983) (xy 405.538147 -304.621139)
			(xy 405.587322 -304.619158) (xy 405.636177 -304.62509) (xy 405.683448 -304.638782) (xy 405.72791 -304.65988)
			(xy 405.768413 -304.687836) (xy 405.803906 -304.721928) (xy 405.833471 -304.761272) (xy 405.856342 -304.804849)
			(xy 405.871926 -304.85153) (xy 405.879821 -304.900107) (xy 405.880316 -304.924714) (xy 406.219164 -304.924714)
			(xy 406.223124 -304.87566) (xy 406.234901 -304.827876) (xy 406.254192 -304.7826) (xy 406.280495 -304.741004)
			(xy 406.31313 -304.704167) (xy 406.351251 -304.673042) (xy 406.393872 -304.648435) (xy 406.439888 -304.630983)
			(xy 406.488107 -304.621139) (xy 406.537282 -304.619158) (xy 406.586137 -304.62509) (xy 406.633408 -304.638782)
			(xy 406.67787 -304.65988) (xy 406.718373 -304.687836) (xy 406.753866 -304.721928) (xy 406.783431 -304.761272)
			(xy 406.806302 -304.804849) (xy 406.821886 -304.85153) (xy 406.829781 -304.900107) (xy 406.830276 -304.924714)
			(xy 408.119084 -304.924714) (xy 408.123044 -304.87566) (xy 408.134821 -304.827876) (xy 408.154112 -304.7826)
			(xy 408.180415 -304.741004) (xy 408.21305 -304.704167) (xy 408.251171 -304.673042) (xy 408.293792 -304.648435)
			(xy 408.339808 -304.630983) (xy 408.388027 -304.621139) (xy 408.437202 -304.619158) (xy 408.486057 -304.62509)
			(xy 408.533328 -304.638782) (xy 408.57779 -304.65988) (xy 408.618293 -304.687836) (xy 408.653786 -304.721928)
			(xy 408.683351 -304.761272) (xy 408.706222 -304.804849) (xy 408.721806 -304.85153) (xy 408.729701 -304.900107)
			(xy 408.730196 -304.924714) (xy 409.069044 -304.924714) (xy 409.073004 -304.87566) (xy 409.084781 -304.827876)
			(xy 409.104072 -304.7826) (xy 409.130375 -304.741004) (xy 409.16301 -304.704167) (xy 409.201131 -304.673042)
			(xy 409.243752 -304.648435) (xy 409.289768 -304.630983) (xy 409.337987 -304.621139) (xy 409.387162 -304.619158)
			(xy 409.436017 -304.62509) (xy 409.483288 -304.638782) (xy 409.52775 -304.65988) (xy 409.568253 -304.687836)
			(xy 409.603746 -304.721928) (xy 409.633311 -304.761272) (xy 409.656182 -304.804849) (xy 409.671766 -304.85153)
			(xy 409.679661 -304.900107) (xy 409.680156 -304.924714) (xy 410.019004 -304.924714) (xy 410.022964 -304.87566)
			(xy 410.034741 -304.827876) (xy 410.054032 -304.7826) (xy 410.080335 -304.741004) (xy 410.11297 -304.704167)
			(xy 410.151091 -304.673042) (xy 410.193712 -304.648435) (xy 410.239728 -304.630983) (xy 410.287947 -304.621139)
			(xy 410.337122 -304.619158) (xy 410.385977 -304.62509) (xy 410.433248 -304.638782) (xy 410.47771 -304.65988)
			(xy 410.518213 -304.687836) (xy 410.553706 -304.721928) (xy 410.583271 -304.761272) (xy 410.606142 -304.804849)
			(xy 410.621726 -304.85153) (xy 410.629621 -304.900107) (xy 410.630116 -304.924714) (xy 410.969218 -304.924714)
			(xy 410.973178 -304.87566) (xy 410.984955 -304.827876) (xy 411.004246 -304.7826) (xy 411.030549 -304.741004)
			(xy 411.063184 -304.704167) (xy 411.101305 -304.673042) (xy 411.143926 -304.648435) (xy 411.189942 -304.630983)
			(xy 411.238161 -304.621139) (xy 411.287336 -304.619158) (xy 411.336191 -304.62509) (xy 411.383462 -304.638782)
			(xy 411.427924 -304.65988) (xy 411.468427 -304.687836) (xy 411.50392 -304.721928) (xy 411.533485 -304.761272)
			(xy 411.556356 -304.804849) (xy 411.57194 -304.85153) (xy 411.579835 -304.900107) (xy 411.58033 -304.924714)
			(xy 411.919178 -304.924714) (xy 411.923138 -304.87566) (xy 411.934915 -304.827876) (xy 411.954206 -304.7826)
			(xy 411.980509 -304.741004) (xy 412.013144 -304.704167) (xy 412.051265 -304.673042) (xy 412.093886 -304.648435)
			(xy 412.139902 -304.630983) (xy 412.188121 -304.621139) (xy 412.237296 -304.619158) (xy 412.286151 -304.62509)
			(xy 412.333422 -304.638782) (xy 412.377884 -304.65988) (xy 412.418387 -304.687836) (xy 412.45388 -304.721928)
			(xy 412.483445 -304.761272) (xy 412.506316 -304.804849) (xy 412.5219 -304.85153) (xy 412.529795 -304.900107)
			(xy 412.53029 -304.924714) (xy 412.869138 -304.924714) (xy 412.873098 -304.87566) (xy 412.884875 -304.827876)
			(xy 412.904166 -304.7826) (xy 412.930469 -304.741004) (xy 412.963104 -304.704167) (xy 413.001225 -304.673042)
			(xy 413.043846 -304.648435) (xy 413.089862 -304.630983) (xy 413.138081 -304.621139) (xy 413.187256 -304.619158)
			(xy 413.236111 -304.62509) (xy 413.283382 -304.638782) (xy 413.327844 -304.65988) (xy 413.368347 -304.687836)
			(xy 413.40384 -304.721928) (xy 413.433405 -304.761272) (xy 413.456276 -304.804849) (xy 413.47186 -304.85153)
			(xy 413.479755 -304.900107) (xy 413.48025 -304.924714) (xy 413.819098 -304.924714) (xy 413.823058 -304.87566)
			(xy 413.834835 -304.827876) (xy 413.854126 -304.7826) (xy 413.880429 -304.741004) (xy 413.913064 -304.704167)
			(xy 413.951185 -304.673042) (xy 413.993806 -304.648435) (xy 414.039822 -304.630983) (xy 414.088041 -304.621139)
			(xy 414.137216 -304.619158) (xy 414.186071 -304.62509) (xy 414.233342 -304.638782) (xy 414.277804 -304.65988)
			(xy 414.318307 -304.687836) (xy 414.3538 -304.721928) (xy 414.383365 -304.761272) (xy 414.406236 -304.804849)
			(xy 414.42182 -304.85153) (xy 414.429715 -304.900107) (xy 414.43021 -304.924714) (xy 414.769058 -304.924714)
			(xy 414.773018 -304.87566) (xy 414.784795 -304.827876) (xy 414.804086 -304.7826) (xy 414.830389 -304.741004)
			(xy 414.863024 -304.704167) (xy 414.901145 -304.673042) (xy 414.943766 -304.648435) (xy 414.989782 -304.630983)
			(xy 415.038001 -304.621139) (xy 415.087176 -304.619158) (xy 415.136031 -304.62509) (xy 415.183302 -304.638782)
			(xy 415.227764 -304.65988) (xy 415.268267 -304.687836) (xy 415.30376 -304.721928) (xy 415.333325 -304.761272)
			(xy 415.356196 -304.804849) (xy 415.37178 -304.85153) (xy 415.379675 -304.900107) (xy 415.38017 -304.924714)
			(xy 415.719018 -304.924714) (xy 415.722978 -304.87566) (xy 415.734755 -304.827876) (xy 415.754046 -304.7826)
			(xy 415.780349 -304.741004) (xy 415.812984 -304.704167) (xy 415.851105 -304.673042) (xy 415.893726 -304.648435)
			(xy 415.939742 -304.630983) (xy 415.987961 -304.621139) (xy 416.037136 -304.619158) (xy 416.085991 -304.62509)
			(xy 416.133262 -304.638782) (xy 416.177724 -304.65988) (xy 416.218227 -304.687836) (xy 416.25372 -304.721928)
			(xy 416.283285 -304.761272) (xy 416.306156 -304.804849) (xy 416.32174 -304.85153) (xy 416.329635 -304.900107)
			(xy 416.33013 -304.924714) (xy 416.668978 -304.924714) (xy 416.672938 -304.87566) (xy 416.684715 -304.827876)
			(xy 416.704006 -304.7826) (xy 416.730309 -304.741004) (xy 416.762944 -304.704167) (xy 416.801065 -304.673042)
			(xy 416.843686 -304.648435) (xy 416.889702 -304.630983) (xy 416.937921 -304.621139) (xy 416.987096 -304.619158)
			(xy 417.035951 -304.62509) (xy 417.083222 -304.638782) (xy 417.127684 -304.65988) (xy 417.168187 -304.687836)
			(xy 417.20368 -304.721928) (xy 417.233245 -304.761272) (xy 417.256116 -304.804849) (xy 417.2717 -304.85153)
			(xy 417.279595 -304.900107) (xy 417.28009 -304.924714) (xy 417.279595 -304.949321) (xy 417.2717 -304.997898)
			(xy 417.256116 -305.044579) (xy 417.233245 -305.088156) (xy 417.20368 -305.1275) (xy 417.168187 -305.161592)
			(xy 417.127684 -305.189548) (xy 417.083222 -305.210646) (xy 417.035951 -305.224338) (xy 416.987096 -305.23027)
			(xy 416.937921 -305.228289) (xy 416.889702 -305.218445) (xy 416.843686 -305.200993) (xy 416.801065 -305.176386)
			(xy 416.762944 -305.145261) (xy 416.730309 -305.108424) (xy 416.704006 -305.066828) (xy 416.684715 -305.021552)
			(xy 416.672938 -304.973768) (xy 416.668978 -304.924714) (xy 416.33013 -304.924714) (xy 416.329635 -304.949321)
			(xy 416.32174 -304.997898) (xy 416.306156 -305.044579) (xy 416.283285 -305.088156) (xy 416.25372 -305.1275)
			(xy 416.218227 -305.161592) (xy 416.177724 -305.189548) (xy 416.133262 -305.210646) (xy 416.085991 -305.224338)
			(xy 416.037136 -305.23027) (xy 415.987961 -305.228289) (xy 415.939742 -305.218445) (xy 415.893726 -305.200993)
			(xy 415.851105 -305.176386) (xy 415.812984 -305.145261) (xy 415.780349 -305.108424) (xy 415.754046 -305.066828)
			(xy 415.734755 -305.021552) (xy 415.722978 -304.973768) (xy 415.719018 -304.924714) (xy 415.38017 -304.924714)
			(xy 415.379675 -304.949321) (xy 415.37178 -304.997898) (xy 415.356196 -305.044579) (xy 415.333325 -305.088156)
			(xy 415.30376 -305.1275) (xy 415.268267 -305.161592) (xy 415.227764 -305.189548) (xy 415.183302 -305.210646)
			(xy 415.136031 -305.224338) (xy 415.087176 -305.23027) (xy 415.038001 -305.228289) (xy 414.989782 -305.218445)
			(xy 414.943766 -305.200993) (xy 414.901145 -305.176386) (xy 414.863024 -305.145261) (xy 414.830389 -305.108424)
			(xy 414.804086 -305.066828) (xy 414.784795 -305.021552) (xy 414.773018 -304.973768) (xy 414.769058 -304.924714)
			(xy 414.43021 -304.924714) (xy 414.429715 -304.949321) (xy 414.42182 -304.997898) (xy 414.406236 -305.044579)
			(xy 414.383365 -305.088156) (xy 414.3538 -305.1275) (xy 414.318307 -305.161592) (xy 414.277804 -305.189548)
			(xy 414.233342 -305.210646) (xy 414.186071 -305.224338) (xy 414.137216 -305.23027) (xy 414.088041 -305.228289)
			(xy 414.039822 -305.218445) (xy 413.993806 -305.200993) (xy 413.951185 -305.176386) (xy 413.913064 -305.145261)
			(xy 413.880429 -305.108424) (xy 413.854126 -305.066828) (xy 413.834835 -305.021552) (xy 413.823058 -304.973768)
			(xy 413.819098 -304.924714) (xy 413.48025 -304.924714) (xy 413.479755 -304.949321) (xy 413.47186 -304.997898)
			(xy 413.456276 -305.044579) (xy 413.433405 -305.088156) (xy 413.40384 -305.1275) (xy 413.368347 -305.161592)
			(xy 413.327844 -305.189548) (xy 413.283382 -305.210646) (xy 413.236111 -305.224338) (xy 413.187256 -305.23027)
			(xy 413.138081 -305.228289) (xy 413.089862 -305.218445) (xy 413.043846 -305.200993) (xy 413.001225 -305.176386)
			(xy 412.963104 -305.145261) (xy 412.930469 -305.108424) (xy 412.904166 -305.066828) (xy 412.884875 -305.021552)
			(xy 412.873098 -304.973768) (xy 412.869138 -304.924714) (xy 412.53029 -304.924714) (xy 412.529795 -304.949321)
			(xy 412.5219 -304.997898) (xy 412.506316 -305.044579) (xy 412.483445 -305.088156) (xy 412.45388 -305.1275)
			(xy 412.418387 -305.161592) (xy 412.377884 -305.189548) (xy 412.333422 -305.210646) (xy 412.286151 -305.224338)
			(xy 412.237296 -305.23027) (xy 412.188121 -305.228289) (xy 412.139902 -305.218445) (xy 412.093886 -305.200993)
			(xy 412.051265 -305.176386) (xy 412.013144 -305.145261) (xy 411.980509 -305.108424) (xy 411.954206 -305.066828)
			(xy 411.934915 -305.021552) (xy 411.923138 -304.973768) (xy 411.919178 -304.924714) (xy 411.58033 -304.924714)
			(xy 411.579835 -304.949321) (xy 411.57194 -304.997898) (xy 411.556356 -305.044579) (xy 411.533485 -305.088156)
			(xy 411.50392 -305.1275) (xy 411.468427 -305.161592) (xy 411.427924 -305.189548) (xy 411.383462 -305.210646)
			(xy 411.336191 -305.224338) (xy 411.287336 -305.23027) (xy 411.238161 -305.228289) (xy 411.189942 -305.218445)
			(xy 411.143926 -305.200993) (xy 411.101305 -305.176386) (xy 411.063184 -305.145261) (xy 411.030549 -305.108424)
			(xy 411.004246 -305.066828) (xy 410.984955 -305.021552) (xy 410.973178 -304.973768) (xy 410.969218 -304.924714)
			(xy 410.630116 -304.924714) (xy 410.629621 -304.949321) (xy 410.621726 -304.997898) (xy 410.606142 -305.044579)
			(xy 410.583271 -305.088156) (xy 410.553706 -305.1275) (xy 410.518213 -305.161592) (xy 410.47771 -305.189548)
			(xy 410.433248 -305.210646) (xy 410.385977 -305.224338) (xy 410.337122 -305.23027) (xy 410.287947 -305.228289)
			(xy 410.239728 -305.218445) (xy 410.193712 -305.200993) (xy 410.151091 -305.176386) (xy 410.11297 -305.145261)
			(xy 410.080335 -305.108424) (xy 410.054032 -305.066828) (xy 410.034741 -305.021552) (xy 410.022964 -304.973768)
			(xy 410.019004 -304.924714) (xy 409.680156 -304.924714) (xy 409.679661 -304.949321) (xy 409.671766 -304.997898)
			(xy 409.656182 -305.044579) (xy 409.633311 -305.088156) (xy 409.603746 -305.1275) (xy 409.568253 -305.161592)
			(xy 409.52775 -305.189548) (xy 409.483288 -305.210646) (xy 409.436017 -305.224338) (xy 409.387162 -305.23027)
			(xy 409.337987 -305.228289) (xy 409.289768 -305.218445) (xy 409.243752 -305.200993) (xy 409.201131 -305.176386)
			(xy 409.16301 -305.145261) (xy 409.130375 -305.108424) (xy 409.104072 -305.066828) (xy 409.084781 -305.021552)
			(xy 409.073004 -304.973768) (xy 409.069044 -304.924714) (xy 408.730196 -304.924714) (xy 408.729701 -304.949321)
			(xy 408.721806 -304.997898) (xy 408.706222 -305.044579) (xy 408.683351 -305.088156) (xy 408.653786 -305.1275)
			(xy 408.618293 -305.161592) (xy 408.57779 -305.189548) (xy 408.533328 -305.210646) (xy 408.486057 -305.224338)
			(xy 408.437202 -305.23027) (xy 408.388027 -305.228289) (xy 408.339808 -305.218445) (xy 408.293792 -305.200993)
			(xy 408.251171 -305.176386) (xy 408.21305 -305.145261) (xy 408.180415 -305.108424) (xy 408.154112 -305.066828)
			(xy 408.134821 -305.021552) (xy 408.123044 -304.973768) (xy 408.119084 -304.924714) (xy 406.830276 -304.924714)
			(xy 406.829781 -304.949321) (xy 406.821886 -304.997898) (xy 406.806302 -305.044579) (xy 406.783431 -305.088156)
			(xy 406.753866 -305.1275) (xy 406.718373 -305.161592) (xy 406.67787 -305.189548) (xy 406.633408 -305.210646)
			(xy 406.586137 -305.224338) (xy 406.537282 -305.23027) (xy 406.488107 -305.228289) (xy 406.439888 -305.218445)
			(xy 406.393872 -305.200993) (xy 406.351251 -305.176386) (xy 406.31313 -305.145261) (xy 406.280495 -305.108424)
			(xy 406.254192 -305.066828) (xy 406.234901 -305.021552) (xy 406.223124 -304.973768) (xy 406.219164 -304.924714)
			(xy 405.880316 -304.924714) (xy 405.879821 -304.949321) (xy 405.871926 -304.997898) (xy 405.856342 -305.044579)
			(xy 405.833471 -305.088156) (xy 405.803906 -305.1275) (xy 405.768413 -305.161592) (xy 405.72791 -305.189548)
			(xy 405.683448 -305.210646) (xy 405.636177 -305.224338) (xy 405.587322 -305.23027) (xy 405.538147 -305.228289)
			(xy 405.489928 -305.218445) (xy 405.443912 -305.200993) (xy 405.401291 -305.176386) (xy 405.36317 -305.145261)
			(xy 405.330535 -305.108424) (xy 405.304232 -305.066828) (xy 405.284941 -305.021552) (xy 405.273164 -304.973768)
			(xy 405.269204 -304.924714) (xy 404.930102 -304.924714) (xy 404.929607 -304.949321) (xy 404.921712 -304.997898)
			(xy 404.906128 -305.044579) (xy 404.883257 -305.088156) (xy 404.853692 -305.1275) (xy 404.818199 -305.161592)
			(xy 404.777696 -305.189548) (xy 404.733234 -305.210646) (xy 404.685963 -305.224338) (xy 404.637108 -305.23027)
			(xy 404.587933 -305.228289) (xy 404.539714 -305.218445) (xy 404.493698 -305.200993) (xy 404.451077 -305.176386)
			(xy 404.412956 -305.145261) (xy 404.380321 -305.108424) (xy 404.354018 -305.066828) (xy 404.334727 -305.021552)
			(xy 404.32295 -304.973768) (xy 404.31899 -304.924714) (xy 403.980142 -304.924714) (xy 403.979647 -304.949321)
			(xy 403.971752 -304.997898) (xy 403.956168 -305.044579) (xy 403.933297 -305.088156) (xy 403.903732 -305.1275)
			(xy 403.868239 -305.161592) (xy 403.827736 -305.189548) (xy 403.783274 -305.210646) (xy 403.736003 -305.224338)
			(xy 403.687148 -305.23027) (xy 403.637973 -305.228289) (xy 403.589754 -305.218445) (xy 403.543738 -305.200993)
			(xy 403.501117 -305.176386) (xy 403.462996 -305.145261) (xy 403.430361 -305.108424) (xy 403.404058 -305.066828)
			(xy 403.384767 -305.021552) (xy 403.37299 -304.973768) (xy 403.36903 -304.924714) (xy 403.030182 -304.924714)
			(xy 403.029687 -304.949321) (xy 403.021792 -304.997898) (xy 403.006208 -305.044579) (xy 402.983337 -305.088156)
			(xy 402.953772 -305.1275) (xy 402.918279 -305.161592) (xy 402.877776 -305.189548) (xy 402.833314 -305.210646)
			(xy 402.786043 -305.224338) (xy 402.737188 -305.23027) (xy 402.688013 -305.228289) (xy 402.639794 -305.218445)
			(xy 402.593778 -305.200993) (xy 402.551157 -305.176386) (xy 402.513036 -305.145261) (xy 402.480401 -305.108424)
			(xy 402.454098 -305.066828) (xy 402.434807 -305.021552) (xy 402.42303 -304.973768) (xy 402.41907 -304.924714)
			(xy 402.080222 -304.924714) (xy 402.079727 -304.949321) (xy 402.071832 -304.997898) (xy 402.056248 -305.044579)
			(xy 402.033377 -305.088156) (xy 402.003812 -305.1275) (xy 401.968319 -305.161592) (xy 401.927816 -305.189548)
			(xy 401.883354 -305.210646) (xy 401.836083 -305.224338) (xy 401.787228 -305.23027) (xy 401.738053 -305.228289)
			(xy 401.689834 -305.218445) (xy 401.643818 -305.200993) (xy 401.601197 -305.176386) (xy 401.563076 -305.145261)
			(xy 401.530441 -305.108424) (xy 401.504138 -305.066828) (xy 401.484847 -305.021552) (xy 401.47307 -304.973768)
			(xy 401.46911 -304.924714) (xy 401.130262 -304.924714) (xy 401.129767 -304.949321) (xy 401.121872 -304.997898)
			(xy 401.106288 -305.044579) (xy 401.083417 -305.088156) (xy 401.053852 -305.1275) (xy 401.018359 -305.161592)
			(xy 400.977856 -305.189548) (xy 400.933394 -305.210646) (xy 400.886123 -305.224338) (xy 400.837268 -305.23027)
			(xy 400.788093 -305.228289) (xy 400.739874 -305.218445) (xy 400.693858 -305.200993) (xy 400.651237 -305.176386)
			(xy 400.613116 -305.145261) (xy 400.580481 -305.108424) (xy 400.554178 -305.066828) (xy 400.534887 -305.021552)
			(xy 400.52311 -304.973768) (xy 400.51915 -304.924714) (xy 400.180302 -304.924714) (xy 400.179807 -304.949321)
			(xy 400.171912 -304.997898) (xy 400.156328 -305.044579) (xy 400.133457 -305.088156) (xy 400.103892 -305.1275)
			(xy 400.068399 -305.161592) (xy 400.027896 -305.189548) (xy 399.983434 -305.210646) (xy 399.936163 -305.224338)
			(xy 399.887308 -305.23027) (xy 399.838133 -305.228289) (xy 399.789914 -305.218445) (xy 399.743898 -305.200993)
			(xy 399.701277 -305.176386) (xy 399.663156 -305.145261) (xy 399.630521 -305.108424) (xy 399.604218 -305.066828)
			(xy 399.584927 -305.021552) (xy 399.57315 -304.973768) (xy 399.56919 -304.924714) (xy 399.230342 -304.924714)
			(xy 399.229847 -304.949321) (xy 399.221952 -304.997898) (xy 399.206368 -305.044579) (xy 399.183497 -305.088156)
			(xy 399.153932 -305.1275) (xy 399.118439 -305.161592) (xy 399.077936 -305.189548) (xy 399.033474 -305.210646)
			(xy 398.986203 -305.224338) (xy 398.937348 -305.23027) (xy 398.888173 -305.228289) (xy 398.839954 -305.218445)
			(xy 398.793938 -305.200993) (xy 398.751317 -305.176386) (xy 398.713196 -305.145261) (xy 398.680561 -305.108424)
			(xy 398.654258 -305.066828) (xy 398.634967 -305.021552) (xy 398.62319 -304.973768) (xy 398.61923 -304.924714)
			(xy 398.280128 -304.924714) (xy 398.279633 -304.949321) (xy 398.271738 -304.997898) (xy 398.256154 -305.044579)
			(xy 398.233283 -305.088156) (xy 398.203718 -305.1275) (xy 398.168225 -305.161592) (xy 398.127722 -305.189548)
			(xy 398.08326 -305.210646) (xy 398.035989 -305.224338) (xy 397.987134 -305.23027) (xy 397.937959 -305.228289)
			(xy 397.88974 -305.218445) (xy 397.843724 -305.200993) (xy 397.801103 -305.176386) (xy 397.762982 -305.145261)
			(xy 397.730347 -305.108424) (xy 397.704044 -305.066828) (xy 397.684753 -305.021552) (xy 397.672976 -304.973768)
			(xy 397.669016 -304.924714) (xy 397.330168 -304.924714) (xy 397.329673 -304.949321) (xy 397.321778 -304.997898)
			(xy 397.306194 -305.044579) (xy 397.283323 -305.088156) (xy 397.253758 -305.1275) (xy 397.218265 -305.161592)
			(xy 397.177762 -305.189548) (xy 397.1333 -305.210646) (xy 397.086029 -305.224338) (xy 397.037174 -305.23027)
			(xy 396.987999 -305.228289) (xy 396.93978 -305.218445) (xy 396.893764 -305.200993) (xy 396.851143 -305.176386)
			(xy 396.813022 -305.145261) (xy 396.780387 -305.108424) (xy 396.754084 -305.066828) (xy 396.734793 -305.021552)
			(xy 396.723016 -304.973768) (xy 396.719056 -304.924714) (xy 396.380208 -304.924714) (xy 396.379713 -304.949321)
			(xy 396.371818 -304.997898) (xy 396.356234 -305.044579) (xy 396.333363 -305.088156) (xy 396.303798 -305.1275)
			(xy 396.268305 -305.161592) (xy 396.227802 -305.189548) (xy 396.18334 -305.210646) (xy 396.136069 -305.224338)
			(xy 396.087214 -305.23027) (xy 396.038039 -305.228289) (xy 395.98982 -305.218445) (xy 395.943804 -305.200993)
			(xy 395.901183 -305.176386) (xy 395.863062 -305.145261) (xy 395.830427 -305.108424) (xy 395.804124 -305.066828)
			(xy 395.784833 -305.021552) (xy 395.773056 -304.973768) (xy 395.769096 -304.924714) (xy 395.430248 -304.924714)
			(xy 395.429753 -304.949321) (xy 395.421858 -304.997898) (xy 395.406274 -305.044579) (xy 395.383403 -305.088156)
			(xy 395.353838 -305.1275) (xy 395.318345 -305.161592) (xy 395.277842 -305.189548) (xy 395.23338 -305.210646)
			(xy 395.186109 -305.224338) (xy 395.137254 -305.23027) (xy 395.088079 -305.228289) (xy 395.03986 -305.218445)
			(xy 394.993844 -305.200993) (xy 394.951223 -305.176386) (xy 394.913102 -305.145261) (xy 394.880467 -305.108424)
			(xy 394.854164 -305.066828) (xy 394.834873 -305.021552) (xy 394.823096 -304.973768) (xy 394.819136 -304.924714)
			(xy 376.967627 -304.924714) (xy 376.964955 -304.93381) (xy 376.942312 -304.983378) (xy 376.912846 -305.02922)
			(xy 376.877156 -305.070402) (xy 376.835968 -305.106085) (xy 376.790121 -305.135544) (xy 376.740548 -305.158178)
			(xy 376.688259 -305.173527) (xy 376.634318 -305.181278) (xy 376.60707 -305.181762) (xy 376.57913 -305.180746)
			(xy 376.567954 -305.179984) (xy 376.546872 -305.187858) (xy 376.476768 -305.260502) (xy 376.469402 -305.281838)
			(xy 376.470672 -305.293014) (xy 376.471734 -305.303268) (xy 376.472877 -305.323853) (xy 376.472958 -305.334162)
			(xy 376.472486 -305.361419) (xy 376.46695 -305.399948) (xy 384.844048 -305.399948) (xy 384.848008 -305.350894)
			(xy 384.859785 -305.30311) (xy 384.879076 -305.257834) (xy 384.905379 -305.216238) (xy 384.938014 -305.179401)
			(xy 384.976135 -305.148276) (xy 385.018756 -305.123669) (xy 385.064772 -305.106217) (xy 385.112991 -305.096373)
			(xy 385.162166 -305.094392) (xy 385.211021 -305.100324) (xy 385.258292 -305.114016) (xy 385.302754 -305.135114)
			(xy 385.343257 -305.16307) (xy 385.37875 -305.197162) (xy 385.408315 -305.236506) (xy 385.431186 -305.280083)
			(xy 385.44677 -305.326764) (xy 385.454665 -305.375341) (xy 385.45516 -305.399948) (xy 385.794008 -305.399948)
			(xy 385.797968 -305.350894) (xy 385.809745 -305.30311) (xy 385.829036 -305.257834) (xy 385.855339 -305.216238)
			(xy 385.887974 -305.179401) (xy 385.926095 -305.148276) (xy 385.968716 -305.123669) (xy 386.014732 -305.106217)
			(xy 386.062951 -305.096373) (xy 386.112126 -305.094392) (xy 386.160981 -305.100324) (xy 386.208252 -305.114016)
			(xy 386.252714 -305.135114) (xy 386.293217 -305.16307) (xy 386.32871 -305.197162) (xy 386.358275 -305.236506)
			(xy 386.381146 -305.280083) (xy 386.39673 -305.326764) (xy 386.404625 -305.375341) (xy 386.40512 -305.399948)
			(xy 386.404625 -305.424555) (xy 386.404446 -305.425656) (xy 386.723378 -305.425656) (xy 386.723378 -305.37424)
			(xy 386.731421 -305.323458) (xy 386.747309 -305.274559) (xy 386.770652 -305.228747) (xy 386.800873 -305.187151)
			(xy 386.837229 -305.150795) (xy 386.878825 -305.120574) (xy 386.924637 -305.097231) (xy 386.973536 -305.081343)
			(xy 387.024318 -305.0733) (xy 387.075734 -305.0733) (xy 387.126516 -305.081343) (xy 387.175415 -305.097231)
			(xy 387.221227 -305.120574) (xy 387.262823 -305.150795) (xy 387.299179 -305.187151) (xy 387.3294 -305.228747)
			(xy 387.352743 -305.274559) (xy 387.368631 -305.323458) (xy 387.376674 -305.37424) (xy 387.377178 -305.399948)
			(xy 387.376674 -305.425656) (xy 387.673338 -305.425656) (xy 387.673338 -305.37424) (xy 387.681381 -305.323458)
			(xy 387.697269 -305.274559) (xy 387.720612 -305.228747) (xy 387.750833 -305.187151) (xy 387.787189 -305.150795)
			(xy 387.828785 -305.120574) (xy 387.874597 -305.097231) (xy 387.923496 -305.081343) (xy 387.974278 -305.0733)
			(xy 388.025694 -305.0733) (xy 388.076476 -305.081343) (xy 388.125375 -305.097231) (xy 388.171187 -305.120574)
			(xy 388.212783 -305.150795) (xy 388.249139 -305.187151) (xy 388.27936 -305.228747) (xy 388.302703 -305.274559)
			(xy 388.318591 -305.323458) (xy 388.326634 -305.37424) (xy 388.327138 -305.399948) (xy 388.644142 -305.399948)
			(xy 388.648102 -305.350894) (xy 388.659879 -305.30311) (xy 388.67917 -305.257834) (xy 388.705473 -305.216238)
			(xy 388.738108 -305.179401) (xy 388.776229 -305.148276) (xy 388.81885 -305.123669) (xy 388.864866 -305.106217)
			(xy 388.913085 -305.096373) (xy 388.96226 -305.094392) (xy 389.011115 -305.100324) (xy 389.058386 -305.114016)
			(xy 389.102848 -305.135114) (xy 389.143351 -305.16307) (xy 389.178844 -305.197162) (xy 389.208409 -305.236506)
			(xy 389.23128 -305.280083) (xy 389.246864 -305.326764) (xy 389.254759 -305.375341) (xy 389.255254 -305.399948)
			(xy 389.254759 -305.424555) (xy 389.25458 -305.425656) (xy 389.573258 -305.425656) (xy 389.573258 -305.37424)
			(xy 389.581301 -305.323458) (xy 389.597189 -305.274559) (xy 389.620532 -305.228747) (xy 389.650753 -305.187151)
			(xy 389.687109 -305.150795) (xy 389.728705 -305.120574) (xy 389.774517 -305.097231) (xy 389.823416 -305.081343)
			(xy 389.874198 -305.0733) (xy 389.925614 -305.0733) (xy 389.976396 -305.081343) (xy 390.025295 -305.097231)
			(xy 390.071107 -305.120574) (xy 390.112703 -305.150795) (xy 390.149059 -305.187151) (xy 390.17928 -305.228747)
			(xy 390.202623 -305.274559) (xy 390.218511 -305.323458) (xy 390.226554 -305.37424) (xy 390.227058 -305.399948)
			(xy 390.226554 -305.425656) (xy 390.523218 -305.425656) (xy 390.523218 -305.37424) (xy 390.531261 -305.323458)
			(xy 390.547149 -305.274559) (xy 390.570492 -305.228747) (xy 390.600713 -305.187151) (xy 390.637069 -305.150795)
			(xy 390.678665 -305.120574) (xy 390.724477 -305.097231) (xy 390.773376 -305.081343) (xy 390.824158 -305.0733)
			(xy 390.875574 -305.0733) (xy 390.926356 -305.081343) (xy 390.975255 -305.097231) (xy 391.021067 -305.120574)
			(xy 391.062663 -305.150795) (xy 391.099019 -305.187151) (xy 391.12924 -305.228747) (xy 391.152583 -305.274559)
			(xy 391.168471 -305.323458) (xy 391.176514 -305.37424) (xy 391.177018 -305.399948) (xy 391.494022 -305.399948)
			(xy 391.497982 -305.350894) (xy 391.509759 -305.30311) (xy 391.52905 -305.257834) (xy 391.555353 -305.216238)
			(xy 391.587988 -305.179401) (xy 391.626109 -305.148276) (xy 391.66873 -305.123669) (xy 391.714746 -305.106217)
			(xy 391.762965 -305.096373) (xy 391.81214 -305.094392) (xy 391.860995 -305.100324) (xy 391.908266 -305.114016)
			(xy 391.952728 -305.135114) (xy 391.993231 -305.16307) (xy 392.028724 -305.197162) (xy 392.058289 -305.236506)
			(xy 392.08116 -305.280083) (xy 392.096744 -305.326764) (xy 392.104639 -305.375341) (xy 392.105134 -305.399948)
			(xy 392.443982 -305.399948) (xy 392.447942 -305.350894) (xy 392.459719 -305.30311) (xy 392.47901 -305.257834)
			(xy 392.505313 -305.216238) (xy 392.537948 -305.179401) (xy 392.576069 -305.148276) (xy 392.61869 -305.123669)
			(xy 392.664706 -305.106217) (xy 392.712925 -305.096373) (xy 392.7621 -305.094392) (xy 392.810955 -305.100324)
			(xy 392.858226 -305.114016) (xy 392.902688 -305.135114) (xy 392.943191 -305.16307) (xy 392.978684 -305.197162)
			(xy 393.008249 -305.236506) (xy 393.03112 -305.280083) (xy 393.046704 -305.326764) (xy 393.054599 -305.375341)
			(xy 393.055094 -305.399948) (xy 393.394196 -305.399948) (xy 393.398156 -305.350894) (xy 393.409933 -305.30311)
			(xy 393.429224 -305.257834) (xy 393.455527 -305.216238) (xy 393.488162 -305.179401) (xy 393.526283 -305.148276)
			(xy 393.568904 -305.123669) (xy 393.61492 -305.106217) (xy 393.663139 -305.096373) (xy 393.712314 -305.094392)
			(xy 393.761169 -305.100324) (xy 393.80844 -305.114016) (xy 393.852902 -305.135114) (xy 393.893405 -305.16307)
			(xy 393.928898 -305.197162) (xy 393.958463 -305.236506) (xy 393.981334 -305.280083) (xy 393.996918 -305.326764)
			(xy 394.004813 -305.375341) (xy 394.005308 -305.399948) (xy 394.004813 -305.424555) (xy 393.996918 -305.473132)
			(xy 393.981334 -305.519813) (xy 393.958463 -305.56339) (xy 393.928898 -305.602734) (xy 393.893405 -305.636826)
			(xy 393.852902 -305.664782) (xy 393.80844 -305.68588) (xy 393.761169 -305.699572) (xy 393.712314 -305.705504)
			(xy 393.663139 -305.703523) (xy 393.61492 -305.693679) (xy 393.568904 -305.676227) (xy 393.526283 -305.65162)
			(xy 393.488162 -305.620495) (xy 393.455527 -305.583658) (xy 393.429224 -305.542062) (xy 393.409933 -305.496786)
			(xy 393.398156 -305.449002) (xy 393.394196 -305.399948) (xy 393.055094 -305.399948) (xy 393.054599 -305.424555)
			(xy 393.046704 -305.473132) (xy 393.03112 -305.519813) (xy 393.008249 -305.56339) (xy 392.978684 -305.602734)
			(xy 392.943191 -305.636826) (xy 392.902688 -305.664782) (xy 392.858226 -305.68588) (xy 392.810955 -305.699572)
			(xy 392.7621 -305.705504) (xy 392.712925 -305.703523) (xy 392.664706 -305.693679) (xy 392.61869 -305.676227)
			(xy 392.576069 -305.65162) (xy 392.537948 -305.620495) (xy 392.505313 -305.583658) (xy 392.47901 -305.542062)
			(xy 392.459719 -305.496786) (xy 392.447942 -305.449002) (xy 392.443982 -305.399948) (xy 392.105134 -305.399948)
			(xy 392.104639 -305.424555) (xy 392.096744 -305.473132) (xy 392.08116 -305.519813) (xy 392.058289 -305.56339)
			(xy 392.028724 -305.602734) (xy 391.993231 -305.636826) (xy 391.952728 -305.664782) (xy 391.908266 -305.68588)
			(xy 391.860995 -305.699572) (xy 391.81214 -305.705504) (xy 391.762965 -305.703523) (xy 391.714746 -305.693679)
			(xy 391.66873 -305.676227) (xy 391.626109 -305.65162) (xy 391.587988 -305.620495) (xy 391.555353 -305.583658)
			(xy 391.52905 -305.542062) (xy 391.509759 -305.496786) (xy 391.497982 -305.449002) (xy 391.494022 -305.399948)
			(xy 391.177018 -305.399948) (xy 391.176514 -305.425656) (xy 391.168471 -305.476438) (xy 391.152583 -305.525337)
			(xy 391.12924 -305.571149) (xy 391.099019 -305.612745) (xy 391.062663 -305.649101) (xy 391.021067 -305.679322)
			(xy 390.975255 -305.702665) (xy 390.926356 -305.718553) (xy 390.875574 -305.726596) (xy 390.824158 -305.726596)
			(xy 390.773376 -305.718553) (xy 390.724477 -305.702665) (xy 390.678665 -305.679322) (xy 390.637069 -305.649101)
			(xy 390.600713 -305.612745) (xy 390.570492 -305.571149) (xy 390.547149 -305.525337) (xy 390.531261 -305.476438)
			(xy 390.523218 -305.425656) (xy 390.226554 -305.425656) (xy 390.218511 -305.476438) (xy 390.202623 -305.525337)
			(xy 390.17928 -305.571149) (xy 390.149059 -305.612745) (xy 390.112703 -305.649101) (xy 390.071107 -305.679322)
			(xy 390.025295 -305.702665) (xy 389.976396 -305.718553) (xy 389.925614 -305.726596) (xy 389.874198 -305.726596)
			(xy 389.823416 -305.718553) (xy 389.774517 -305.702665) (xy 389.728705 -305.679322) (xy 389.687109 -305.649101)
			(xy 389.650753 -305.612745) (xy 389.620532 -305.571149) (xy 389.597189 -305.525337) (xy 389.581301 -305.476438)
			(xy 389.573258 -305.425656) (xy 389.25458 -305.425656) (xy 389.246864 -305.473132) (xy 389.23128 -305.519813)
			(xy 389.208409 -305.56339) (xy 389.178844 -305.602734) (xy 389.143351 -305.636826) (xy 389.102848 -305.664782)
			(xy 389.058386 -305.68588) (xy 389.011115 -305.699572) (xy 388.96226 -305.705504) (xy 388.913085 -305.703523)
			(xy 388.864866 -305.693679) (xy 388.81885 -305.676227) (xy 388.776229 -305.65162) (xy 388.738108 -305.620495)
			(xy 388.705473 -305.583658) (xy 388.67917 -305.542062) (xy 388.659879 -305.496786) (xy 388.648102 -305.449002)
			(xy 388.644142 -305.399948) (xy 388.327138 -305.399948) (xy 388.326634 -305.425656) (xy 388.318591 -305.476438)
			(xy 388.302703 -305.525337) (xy 388.27936 -305.571149) (xy 388.249139 -305.612745) (xy 388.212783 -305.649101)
			(xy 388.171187 -305.679322) (xy 388.125375 -305.702665) (xy 388.076476 -305.718553) (xy 388.025694 -305.726596)
			(xy 387.974278 -305.726596) (xy 387.923496 -305.718553) (xy 387.874597 -305.702665) (xy 387.828785 -305.679322)
			(xy 387.787189 -305.649101) (xy 387.750833 -305.612745) (xy 387.720612 -305.571149) (xy 387.697269 -305.525337)
			(xy 387.681381 -305.476438) (xy 387.673338 -305.425656) (xy 387.376674 -305.425656) (xy 387.368631 -305.476438)
			(xy 387.352743 -305.525337) (xy 387.3294 -305.571149) (xy 387.299179 -305.612745) (xy 387.262823 -305.649101)
			(xy 387.221227 -305.679322) (xy 387.175415 -305.702665) (xy 387.126516 -305.718553) (xy 387.075734 -305.726596)
			(xy 387.024318 -305.726596) (xy 386.973536 -305.718553) (xy 386.924637 -305.702665) (xy 386.878825 -305.679322)
			(xy 386.837229 -305.649101) (xy 386.800873 -305.612745) (xy 386.770652 -305.571149) (xy 386.747309 -305.525337)
			(xy 386.731421 -305.476438) (xy 386.723378 -305.425656) (xy 386.404446 -305.425656) (xy 386.39673 -305.473132)
			(xy 386.381146 -305.519813) (xy 386.358275 -305.56339) (xy 386.32871 -305.602734) (xy 386.293217 -305.636826)
			(xy 386.252714 -305.664782) (xy 386.208252 -305.68588) (xy 386.160981 -305.699572) (xy 386.112126 -305.705504)
			(xy 386.062951 -305.703523) (xy 386.014732 -305.693679) (xy 385.968716 -305.676227) (xy 385.926095 -305.65162)
			(xy 385.887974 -305.620495) (xy 385.855339 -305.583658) (xy 385.829036 -305.542062) (xy 385.809745 -305.496786)
			(xy 385.797968 -305.449002) (xy 385.794008 -305.399948) (xy 385.45516 -305.399948) (xy 385.454665 -305.424555)
			(xy 385.44677 -305.473132) (xy 385.431186 -305.519813) (xy 385.408315 -305.56339) (xy 385.37875 -305.602734)
			(xy 385.343257 -305.636826) (xy 385.302754 -305.664782) (xy 385.258292 -305.68588) (xy 385.211021 -305.699572)
			(xy 385.162166 -305.705504) (xy 385.112991 -305.703523) (xy 385.064772 -305.693679) (xy 385.018756 -305.676227)
			(xy 384.976135 -305.65162) (xy 384.938014 -305.620495) (xy 384.905379 -305.583658) (xy 384.879076 -305.542062)
			(xy 384.859785 -305.496786) (xy 384.848008 -305.449002) (xy 384.844048 -305.399948) (xy 376.46695 -305.399948)
			(xy 376.464733 -305.415379) (xy 376.449379 -305.467686) (xy 376.426737 -305.517275) (xy 376.397268 -305.563137)
			(xy 376.361571 -305.604338) (xy 376.320374 -305.64004) (xy 376.274516 -305.669514) (xy 376.224929 -305.692162)
			(xy 376.172624 -305.707523) (xy 376.118666 -305.715282) (xy 376.064152 -305.715284) (xy 376.010193 -305.707526)
			(xy 375.957887 -305.692168) (xy 375.908299 -305.669523) (xy 375.862439 -305.64005) (xy 375.821241 -305.60435)
			(xy 375.785543 -305.563151) (xy 375.756072 -305.51729) (xy 375.733427 -305.467702) (xy 375.718071 -305.415396)
			(xy 375.710316 -305.361436) (xy 365.203422 -305.361436) (xy 365.192454 -305.366445) (xy 365.140159 -305.3818)
			(xy 365.086211 -305.389556) (xy 365.031709 -305.389556) (xy 364.977761 -305.3818) (xy 364.925466 -305.366445)
			(xy 364.875889 -305.343803) (xy 364.830039 -305.314337) (xy 364.788848 -305.278646) (xy 364.753157 -305.237455)
			(xy 364.723691 -305.191605) (xy 364.701049 -305.142028) (xy 364.685694 -305.089733) (xy 364.677938 -305.035785)
			(xy 364.677452 -305.008534) (xy 360.632248 -305.008534) (xy 360.631762 -305.035785) (xy 360.624006 -305.089733)
			(xy 360.608651 -305.142028) (xy 360.586009 -305.191605) (xy 360.556543 -305.237455) (xy 360.520852 -305.278646)
			(xy 360.479661 -305.314337) (xy 360.433811 -305.343803) (xy 360.384234 -305.366445) (xy 360.331939 -305.3818)
			(xy 360.277991 -305.389556) (xy 360.223489 -305.389556) (xy 360.169541 -305.3818) (xy 360.117246 -305.366445)
			(xy 360.067669 -305.343803) (xy 360.021819 -305.314337) (xy 359.980628 -305.278646) (xy 359.944937 -305.237455)
			(xy 359.915471 -305.191605) (xy 359.892829 -305.142028) (xy 359.877474 -305.089733) (xy 359.869718 -305.035785)
			(xy 359.869232 -305.008534) (xy 358.600248 -305.008534) (xy 358.599762 -305.035785) (xy 358.592006 -305.089733)
			(xy 358.576651 -305.142028) (xy 358.554009 -305.191605) (xy 358.524543 -305.237455) (xy 358.488852 -305.278646)
			(xy 358.447661 -305.314337) (xy 358.401811 -305.343803) (xy 358.352234 -305.366445) (xy 358.299939 -305.3818)
			(xy 358.245991 -305.389556) (xy 358.191489 -305.389556) (xy 358.137541 -305.3818) (xy 358.085246 -305.366445)
			(xy 358.035669 -305.343803) (xy 357.989819 -305.314337) (xy 357.948628 -305.278646) (xy 357.912937 -305.237455)
			(xy 357.883471 -305.191605) (xy 357.860829 -305.142028) (xy 357.845474 -305.089733) (xy 357.837718 -305.035785)
			(xy 357.837232 -305.008534) (xy 357.212138 -305.008534) (xy 357.211652 -305.035785) (xy 357.203896 -305.089733)
			(xy 357.188541 -305.142028) (xy 357.165899 -305.191605) (xy 357.136433 -305.237455) (xy 357.100742 -305.278646)
			(xy 357.059551 -305.314337) (xy 357.013701 -305.343803) (xy 356.964124 -305.366445) (xy 356.911829 -305.3818)
			(xy 356.857881 -305.389556) (xy 356.803379 -305.389556) (xy 356.749431 -305.3818) (xy 356.697136 -305.366445)
			(xy 356.647559 -305.343803) (xy 356.601709 -305.314337) (xy 356.560518 -305.278646) (xy 356.524827 -305.237455)
			(xy 356.495361 -305.191605) (xy 356.472719 -305.142028) (xy 356.457364 -305.089733) (xy 356.449608 -305.035785)
			(xy 356.449122 -305.008534) (xy 353.792028 -305.008534) (xy 353.791542 -305.035785) (xy 353.783786 -305.089733)
			(xy 353.768431 -305.142028) (xy 353.745789 -305.191605) (xy 353.716323 -305.237455) (xy 353.680632 -305.278646)
			(xy 353.639441 -305.314337) (xy 353.593591 -305.343803) (xy 353.544014 -305.366445) (xy 353.491719 -305.3818)
			(xy 353.437771 -305.389556) (xy 353.383269 -305.389556) (xy 353.329321 -305.3818) (xy 353.277026 -305.366445)
			(xy 353.227449 -305.343803) (xy 353.181599 -305.314337) (xy 353.140408 -305.278646) (xy 353.104717 -305.237455)
			(xy 353.075251 -305.191605) (xy 353.052609 -305.142028) (xy 353.037254 -305.089733) (xy 353.029498 -305.035785)
			(xy 353.029012 -305.008534) (xy 351.03308 -305.008534) (xy 351.03308 -307.82387) (xy 353.617022 -307.82387)
			(xy 353.617465 -307.796499) (xy 353.625288 -307.742319) (xy 353.640782 -307.689815) (xy 353.663629 -307.640069)
			(xy 353.693358 -307.594103) (xy 353.711002 -307.573172) (xy 353.717098 -307.56606) (xy 353.723448 -307.549042)
			(xy 353.723448 -307.463698) (xy 353.717098 -307.44668) (xy 353.711002 -307.439568) (xy 353.693333 -307.418659)
			(xy 353.663611 -307.372686) (xy 353.640769 -307.322936) (xy 353.625276 -307.27043) (xy 353.617451 -307.216249)
			(xy 353.617454 -307.161506) (xy 353.625286 -307.107325) (xy 353.640785 -307.054822) (xy 353.663633 -307.005074)
			(xy 353.69336 -306.959105) (xy 353.711002 -306.938172) (xy 353.717098 -306.93106) (xy 353.723448 -306.914042)
			(xy 353.723448 -306.828698) (xy 353.717098 -306.81168) (xy 353.711002 -306.804568) (xy 353.693333 -306.783659)
			(xy 353.663611 -306.737686) (xy 353.640769 -306.687936) (xy 353.625276 -306.63543) (xy 353.617451 -306.581249)
			(xy 353.617454 -306.526506) (xy 353.625286 -306.472325) (xy 353.640785 -306.419822) (xy 353.663633 -306.370074)
			(xy 353.69336 -306.324105) (xy 353.711002 -306.303172) (xy 353.717098 -306.29606) (xy 353.723448 -306.279042)
			(xy 353.723448 -306.193698) (xy 353.717098 -306.17668) (xy 353.711002 -306.169568) (xy 353.693382 -306.148621)
			(xy 353.663667 -306.102652) (xy 353.640827 -306.052909) (xy 353.625332 -306.000411) (xy 353.617499 -305.946238)
			(xy 353.617022 -305.91887) (xy 353.617508 -305.891619) (xy 353.625264 -305.837671) (xy 353.640619 -305.785376)
			(xy 353.663261 -305.735799) (xy 353.692727 -305.689949) (xy 353.728418 -305.648758) (xy 353.769609 -305.613067)
			(xy 353.815459 -305.583601) (xy 353.865036 -305.560959) (xy 353.917331 -305.545604) (xy 353.971279 -305.537848)
			(xy 354.025781 -305.537848) (xy 354.079729 -305.545604) (xy 354.132024 -305.560959) (xy 354.181601 -305.583601)
			(xy 354.227451 -305.613067) (xy 354.268642 -305.648758) (xy 354.304333 -305.689949) (xy 354.333799 -305.735799)
			(xy 354.356441 -305.785376) (xy 354.371796 -305.837671) (xy 354.379552 -305.891619) (xy 354.380038 -305.91887)
			(xy 354.379569 -305.94624) (xy 354.371755 -306.00042) (xy 354.356267 -306.052924) (xy 354.333425 -306.102671)
			(xy 354.3037 -306.148637) (xy 354.286058 -306.169568) (xy 354.279962 -306.17668) (xy 354.273612 -306.193698)
			(xy 354.273612 -306.279042) (xy 354.279962 -306.29606) (xy 354.286058 -306.303172) (xy 354.30367 -306.324128)
			(xy 354.333397 -306.370092) (xy 354.356245 -306.419834) (xy 354.371744 -306.472332) (xy 354.379576 -306.526508)
			(xy 354.379579 -306.581247) (xy 354.371754 -306.635423) (xy 354.356261 -306.687924) (xy 354.333419 -306.737669)
			(xy 354.303697 -306.783636) (xy 354.286058 -306.804568) (xy 354.279962 -306.81168) (xy 354.273612 -306.828698)
			(xy 354.273612 -306.914042) (xy 354.279962 -306.93106) (xy 354.286058 -306.938172) (xy 354.30367 -306.959128)
			(xy 354.333397 -307.005092) (xy 354.356245 -307.054834) (xy 354.371744 -307.107332) (xy 354.379576 -307.161508)
			(xy 354.379579 -307.216247) (xy 354.371754 -307.270423) (xy 354.356261 -307.322924) (xy 354.333419 -307.372669)
			(xy 354.303697 -307.418636) (xy 354.286058 -307.439568) (xy 354.279962 -307.44668) (xy 354.273612 -307.463698)
			(xy 354.273612 -307.549042) (xy 354.279962 -307.56606) (xy 354.286058 -307.573172) (xy 354.303691 -307.594109)
			(xy 354.333405 -307.64008) (xy 354.356243 -307.689826) (xy 354.371735 -307.742326) (xy 354.379564 -307.796501)
			(xy 354.380038 -307.82387) (xy 354.379552 -307.851121) (xy 354.375728 -307.877718) (xy 357.249222 -307.877718)
			(xy 357.249693 -307.850348) (xy 357.257509 -307.796169) (xy 357.272997 -307.743666) (xy 357.295837 -307.693919)
			(xy 357.325561 -307.647952) (xy 357.343202 -307.62702) (xy 357.349298 -307.619908) (xy 357.355648 -307.60289)
			(xy 357.355648 -307.517546) (xy 357.349298 -307.500528) (xy 357.343202 -307.493416) (xy 357.32558 -307.472468)
			(xy 357.295856 -307.426503) (xy 357.273011 -307.376759) (xy 357.257515 -307.324259) (xy 357.249685 -307.270083)
			(xy 357.249683 -307.215344) (xy 357.257509 -307.161167) (xy 357.273002 -307.108667) (xy 357.295843 -307.058921)
			(xy 357.325564 -307.012953) (xy 357.343202 -306.99202) (xy 357.349298 -306.984908) (xy 357.355648 -306.96789)
			(xy 357.355648 -306.882546) (xy 357.349298 -306.865528) (xy 357.343202 -306.858416) (xy 357.32558 -306.837468)
			(xy 357.295856 -306.791503) (xy 357.273011 -306.741759) (xy 357.257515 -306.689259) (xy 357.249685 -306.635083)
			(xy 357.249683 -306.580344) (xy 357.257509 -306.526167) (xy 357.273002 -306.473667) (xy 357.295843 -306.423921)
			(xy 357.325564 -306.377953) (xy 357.343202 -306.35702) (xy 357.349298 -306.349908) (xy 357.355648 -306.33289)
			(xy 357.355648 -306.247546) (xy 357.349298 -306.230528) (xy 357.343202 -306.223416) (xy 357.325557 -306.202488)
			(xy 357.295846 -306.156514) (xy 357.273011 -306.106766) (xy 357.257522 -306.054264) (xy 357.249695 -306.000087)
			(xy 357.249222 -305.972718) (xy 357.249708 -305.945467) (xy 357.257464 -305.891519) (xy 357.272819 -305.839224)
			(xy 357.295461 -305.789647) (xy 357.324927 -305.743797) (xy 357.360618 -305.702606) (xy 357.401809 -305.666915)
			(xy 357.447659 -305.637449) (xy 357.497236 -305.614807) (xy 357.549531 -305.599452) (xy 357.603479 -305.591696)
			(xy 357.657981 -305.591696) (xy 357.711929 -305.599452) (xy 357.764224 -305.614807) (xy 357.813801 -305.637449)
			(xy 357.859651 -305.666915) (xy 357.900842 -305.702606) (xy 357.936533 -305.743797) (xy 357.965999 -305.789647)
			(xy 357.988641 -305.839224) (xy 358.003996 -305.891519) (xy 358.011752 -305.945467) (xy 358.012238 -305.972718)
			(xy 358.011798 -306.000089) (xy 358.003976 -306.05427) (xy 357.988482 -306.106774) (xy 357.965634 -306.156521)
			(xy 357.935903 -306.202486) (xy 357.918258 -306.223416) (xy 357.912162 -306.230528) (xy 357.905812 -306.247546)
			(xy 357.905812 -306.33289) (xy 357.912162 -306.349908) (xy 357.918258 -306.35702) (xy 357.935917 -306.377938)
			(xy 357.965642 -306.423908) (xy 357.988487 -306.473657) (xy 358.003983 -306.526161) (xy 358.01181 -306.580342)
			(xy 358.011808 -306.635085) (xy 358.003977 -306.689265) (xy 357.988478 -306.741769) (xy 357.965629 -306.791516)
			(xy 357.935901 -306.837484) (xy 357.918258 -306.858416) (xy 357.912162 -306.865528) (xy 357.905812 -306.882546)
			(xy 357.905812 -306.96789) (xy 357.912162 -306.984908) (xy 357.918258 -306.99202) (xy 357.935917 -307.012938)
			(xy 357.965642 -307.058908) (xy 357.988487 -307.108657) (xy 358.003983 -307.161161) (xy 358.007986 -307.18887)
			(xy 360.457242 -307.18887) (xy 360.45768 -307.161499) (xy 360.465503 -307.107318) (xy 360.480998 -307.054814)
			(xy 360.503846 -307.005068) (xy 360.533578 -306.959102) (xy 360.551222 -306.938172) (xy 360.557318 -306.93106)
			(xy 360.563668 -306.914042) (xy 360.563668 -306.828698) (xy 360.557318 -306.81168) (xy 360.551222 -306.804568)
			(xy 360.533552 -306.783659) (xy 360.503829 -306.737687) (xy 360.480986 -306.687937) (xy 360.465492 -306.635431)
			(xy 360.457666 -306.581249) (xy 360.457669 -306.526505) (xy 360.465502 -306.472325) (xy 360.481002 -306.419821)
			(xy 360.503851 -306.370073) (xy 360.533579 -306.324105) (xy 360.551222 -306.303172) (xy 360.557318 -306.29606)
			(xy 360.563668 -306.279042) (xy 360.563668 -306.193698) (xy 360.557318 -306.17668) (xy 360.551222 -306.169568)
			(xy 360.533605 -306.148618) (xy 360.503889 -306.102651) (xy 360.481048 -306.052908) (xy 360.465552 -306.000411)
			(xy 360.457719 -305.946238) (xy 360.457242 -305.91887) (xy 360.457728 -305.891619) (xy 360.465484 -305.837671)
			(xy 360.480839 -305.785376) (xy 360.503481 -305.735799) (xy 360.532947 -305.689949) (xy 360.568638 -305.648758)
			(xy 360.609829 -305.613067) (xy 360.655679 -305.583601) (xy 360.705256 -305.560959) (xy 360.757551 -305.545604)
			(xy 360.811499 -305.537848) (xy 360.866001 -305.537848) (xy 360.919949 -305.545604) (xy 360.972244 -305.560959)
			(xy 361.021821 -305.583601) (xy 361.067671 -305.613067) (xy 361.108862 -305.648758) (xy 361.144553 -305.689949)
			(xy 361.174019 -305.735799) (xy 361.196661 -305.785376) (xy 361.212016 -305.837671) (xy 361.219772 -305.891619)
			(xy 361.220258 -305.91887) (xy 361.219785 -305.94624) (xy 361.21197 -306.000419) (xy 361.196483 -306.052923)
			(xy 361.173643 -306.10267) (xy 361.143919 -306.148636) (xy 361.126278 -306.169568) (xy 361.120182 -306.17668)
			(xy 361.113832 -306.193698) (xy 361.113832 -306.279042) (xy 361.120182 -306.29606) (xy 361.126278 -306.303172)
			(xy 361.143889 -306.324129) (xy 361.173615 -306.370092) (xy 361.196462 -306.419835) (xy 361.21196 -306.472333)
			(xy 361.219791 -306.526508) (xy 361.219794 -306.581247) (xy 361.21197 -306.635423) (xy 361.196477 -306.687923)
			(xy 361.173637 -306.737668) (xy 361.143916 -306.783635) (xy 361.126278 -306.804568) (xy 361.120182 -306.81168)
			(xy 361.113832 -306.828698) (xy 361.113832 -306.914042) (xy 361.120182 -306.93106) (xy 361.126278 -306.938172)
			(xy 361.143914 -306.959107) (xy 361.173627 -307.005078) (xy 361.196464 -307.054825) (xy 361.211956 -307.107325)
			(xy 361.219784 -307.161501) (xy 361.220258 -307.18887) (xy 361.219772 -307.216121) (xy 361.212016 -307.270069)
			(xy 361.196661 -307.322364) (xy 361.174019 -307.371941) (xy 361.144553 -307.417791) (xy 361.108862 -307.458982)
			(xy 361.067671 -307.494673) (xy 361.021821 -307.524139) (xy 360.972244 -307.546781) (xy 360.919949 -307.562136)
			(xy 360.866001 -307.569892) (xy 360.811499 -307.569892) (xy 360.757551 -307.562136) (xy 360.705256 -307.546781)
			(xy 360.655679 -307.524139) (xy 360.609829 -307.494673) (xy 360.568638 -307.458982) (xy 360.532947 -307.417791)
			(xy 360.503481 -307.371941) (xy 360.480839 -307.322364) (xy 360.465484 -307.270069) (xy 360.457728 -307.216121)
			(xy 360.457242 -307.18887) (xy 358.007986 -307.18887) (xy 358.01181 -307.215342) (xy 358.011808 -307.270085)
			(xy 358.003977 -307.324265) (xy 357.988478 -307.376769) (xy 357.965629 -307.426516) (xy 357.935901 -307.472484)
			(xy 357.918258 -307.493416) (xy 357.912162 -307.500528) (xy 357.905812 -307.517546) (xy 357.905812 -307.60289)
			(xy 357.912162 -307.619908) (xy 357.918258 -307.62702) (xy 357.935867 -307.647977) (xy 357.965584 -307.693942)
			(xy 357.988427 -307.743683) (xy 358.003925 -307.796179) (xy 358.01176 -307.85035) (xy 358.012238 -307.877718)
			(xy 364.089442 -307.877718) (xy 364.089908 -307.850348) (xy 364.097725 -307.796168) (xy 364.113213 -307.743665)
			(xy 364.136055 -307.693918) (xy 364.16578 -307.647951) (xy 364.183422 -307.62702) (xy 364.189518 -307.619908)
			(xy 364.195868 -307.60289) (xy 364.195868 -307.517546) (xy 364.189518 -307.500528) (xy 364.183422 -307.493416)
			(xy 364.165799 -307.472469) (xy 364.136074 -307.426503) (xy 364.113228 -307.37676) (xy 364.09773 -307.32426)
			(xy 364.0899 -307.270083) (xy 364.089898 -307.215344) (xy 364.097725 -307.161167) (xy 364.113218 -307.108666)
			(xy 364.136061 -307.05892) (xy 364.165783 -307.012953) (xy 364.183422 -306.99202) (xy 364.189518 -306.984908)
			(xy 364.195868 -306.96789) (xy 364.195868 -306.882546) (xy 364.189518 -306.865528) (xy 364.183422 -306.858416)
			(xy 364.165799 -306.837469) (xy 364.136074 -306.791503) (xy 364.113228 -306.74176) (xy 364.09773 -306.68926)
			(xy 364.0899 -306.635083) (xy 364.089898 -306.580344) (xy 364.097725 -306.526167) (xy 364.113218 -306.473666)
			(xy 364.136061 -306.42392) (xy 364.165783 -306.377953) (xy 364.183422 -306.35702) (xy 364.189518 -306.349908)
			(xy 364.195868 -306.33289) (xy 364.195868 -306.247546) (xy 364.189518 -306.230528) (xy 364.183422 -306.223416)
			(xy 364.16578 -306.202486) (xy 364.136068 -306.156513) (xy 364.113232 -306.106765) (xy 364.097742 -306.054264)
			(xy 364.089915 -306.000087) (xy 364.089442 -305.972718) (xy 364.089928 -305.945467) (xy 364.097684 -305.891519)
			(xy 364.113039 -305.839224) (xy 364.135681 -305.789647) (xy 364.165147 -305.743797) (xy 364.200838 -305.702606)
			(xy 364.242029 -305.666915) (xy 364.287879 -305.637449) (xy 364.337456 -305.614807) (xy 364.389751 -305.599452)
			(xy 364.443699 -305.591696) (xy 364.498201 -305.591696) (xy 364.552149 -305.599452) (xy 364.604444 -305.614807)
			(xy 364.654021 -305.637449) (xy 364.699871 -305.666915) (xy 364.741062 -305.702606) (xy 364.776753 -305.743797)
			(xy 364.806219 -305.789647) (xy 364.828861 -305.839224) (xy 364.844216 -305.891519) (xy 364.851972 -305.945467)
			(xy 364.852458 -305.972718) (xy 364.852013 -306.000089) (xy 364.844413 -306.052728) (xy 374.990866 -306.052728)
			(xy 374.994937 -305.997106) (xy 375.007063 -305.942669) (xy 375.026986 -305.890578) (xy 375.054282 -305.841943)
			(xy 375.088368 -305.7978) (xy 375.128517 -305.759091) (xy 375.173875 -305.72664) (xy 375.223475 -305.701139)
			(xy 375.276259 -305.683132) (xy 375.331102 -305.673002) (xy 375.386836 -305.670965) (xy 375.442273 -305.677065)
			(xy 375.49623 -305.691171) (xy 375.547559 -305.712983) (xy 375.595165 -305.742037) (xy 375.638033 -305.777712)
			(xy 375.67525 -305.819249) (xy 375.706023 -305.865762) (xy 375.71032 -305.874928) (xy 394.819136 -305.874928)
			(xy 394.823096 -305.825874) (xy 394.834873 -305.77809) (xy 394.854164 -305.732814) (xy 394.880467 -305.691218)
			(xy 394.913102 -305.654381) (xy 394.951223 -305.623256) (xy 394.993844 -305.598649) (xy 395.03986 -305.581197)
			(xy 395.088079 -305.571353) (xy 395.137254 -305.569372) (xy 395.186109 -305.575304) (xy 395.23338 -305.588996)
			(xy 395.277842 -305.610094) (xy 395.318345 -305.63805) (xy 395.353838 -305.672142) (xy 395.383403 -305.711486)
			(xy 395.406274 -305.755063) (xy 395.421858 -305.801744) (xy 395.429753 -305.850321) (xy 395.430248 -305.874928)
			(xy 395.769096 -305.874928) (xy 395.773056 -305.825874) (xy 395.784833 -305.77809) (xy 395.804124 -305.732814)
			(xy 395.830427 -305.691218) (xy 395.863062 -305.654381) (xy 395.901183 -305.623256) (xy 395.943804 -305.598649)
			(xy 395.98982 -305.581197) (xy 396.038039 -305.571353) (xy 396.087214 -305.569372) (xy 396.136069 -305.575304)
			(xy 396.18334 -305.588996) (xy 396.227802 -305.610094) (xy 396.268305 -305.63805) (xy 396.303798 -305.672142)
			(xy 396.333363 -305.711486) (xy 396.356234 -305.755063) (xy 396.371818 -305.801744) (xy 396.379713 -305.850321)
			(xy 396.380208 -305.874928) (xy 396.719056 -305.874928) (xy 396.723016 -305.825874) (xy 396.734793 -305.77809)
			(xy 396.754084 -305.732814) (xy 396.780387 -305.691218) (xy 396.813022 -305.654381) (xy 396.851143 -305.623256)
			(xy 396.893764 -305.598649) (xy 396.93978 -305.581197) (xy 396.987999 -305.571353) (xy 397.037174 -305.569372)
			(xy 397.086029 -305.575304) (xy 397.1333 -305.588996) (xy 397.177762 -305.610094) (xy 397.218265 -305.63805)
			(xy 397.253758 -305.672142) (xy 397.283323 -305.711486) (xy 397.306194 -305.755063) (xy 397.321778 -305.801744)
			(xy 397.329673 -305.850321) (xy 397.330168 -305.874928) (xy 397.669016 -305.874928) (xy 397.672976 -305.825874)
			(xy 397.684753 -305.77809) (xy 397.704044 -305.732814) (xy 397.730347 -305.691218) (xy 397.762982 -305.654381)
			(xy 397.801103 -305.623256) (xy 397.843724 -305.598649) (xy 397.88974 -305.581197) (xy 397.937959 -305.571353)
			(xy 397.987134 -305.569372) (xy 398.035989 -305.575304) (xy 398.08326 -305.588996) (xy 398.127722 -305.610094)
			(xy 398.168225 -305.63805) (xy 398.203718 -305.672142) (xy 398.233283 -305.711486) (xy 398.256154 -305.755063)
			(xy 398.271738 -305.801744) (xy 398.279633 -305.850321) (xy 398.280128 -305.874928) (xy 398.61923 -305.874928)
			(xy 398.62319 -305.825874) (xy 398.634967 -305.77809) (xy 398.654258 -305.732814) (xy 398.680561 -305.691218)
			(xy 398.713196 -305.654381) (xy 398.751317 -305.623256) (xy 398.793938 -305.598649) (xy 398.839954 -305.581197)
			(xy 398.888173 -305.571353) (xy 398.937348 -305.569372) (xy 398.986203 -305.575304) (xy 399.033474 -305.588996)
			(xy 399.077936 -305.610094) (xy 399.118439 -305.63805) (xy 399.153932 -305.672142) (xy 399.183497 -305.711486)
			(xy 399.206368 -305.755063) (xy 399.221952 -305.801744) (xy 399.229847 -305.850321) (xy 399.230342 -305.874928)
			(xy 399.56919 -305.874928) (xy 399.57315 -305.825874) (xy 399.584927 -305.77809) (xy 399.604218 -305.732814)
			(xy 399.630521 -305.691218) (xy 399.663156 -305.654381) (xy 399.701277 -305.623256) (xy 399.743898 -305.598649)
			(xy 399.789914 -305.581197) (xy 399.838133 -305.571353) (xy 399.887308 -305.569372) (xy 399.936163 -305.575304)
			(xy 399.983434 -305.588996) (xy 400.027896 -305.610094) (xy 400.068399 -305.63805) (xy 400.103892 -305.672142)
			(xy 400.133457 -305.711486) (xy 400.156328 -305.755063) (xy 400.171912 -305.801744) (xy 400.179807 -305.850321)
			(xy 400.180302 -305.874928) (xy 400.51915 -305.874928) (xy 400.52311 -305.825874) (xy 400.534887 -305.77809)
			(xy 400.554178 -305.732814) (xy 400.580481 -305.691218) (xy 400.613116 -305.654381) (xy 400.651237 -305.623256)
			(xy 400.693858 -305.598649) (xy 400.739874 -305.581197) (xy 400.788093 -305.571353) (xy 400.837268 -305.569372)
			(xy 400.886123 -305.575304) (xy 400.933394 -305.588996) (xy 400.977856 -305.610094) (xy 401.018359 -305.63805)
			(xy 401.053852 -305.672142) (xy 401.083417 -305.711486) (xy 401.106288 -305.755063) (xy 401.121872 -305.801744)
			(xy 401.129767 -305.850321) (xy 401.130262 -305.874928) (xy 401.46911 -305.874928) (xy 401.47307 -305.825874)
			(xy 401.484847 -305.77809) (xy 401.504138 -305.732814) (xy 401.530441 -305.691218) (xy 401.563076 -305.654381)
			(xy 401.601197 -305.623256) (xy 401.643818 -305.598649) (xy 401.689834 -305.581197) (xy 401.738053 -305.571353)
			(xy 401.787228 -305.569372) (xy 401.836083 -305.575304) (xy 401.883354 -305.588996) (xy 401.927816 -305.610094)
			(xy 401.968319 -305.63805) (xy 402.003812 -305.672142) (xy 402.033377 -305.711486) (xy 402.056248 -305.755063)
			(xy 402.071832 -305.801744) (xy 402.079727 -305.850321) (xy 402.080222 -305.874928) (xy 402.41907 -305.874928)
			(xy 402.42303 -305.825874) (xy 402.434807 -305.77809) (xy 402.454098 -305.732814) (xy 402.480401 -305.691218)
			(xy 402.513036 -305.654381) (xy 402.551157 -305.623256) (xy 402.593778 -305.598649) (xy 402.639794 -305.581197)
			(xy 402.688013 -305.571353) (xy 402.737188 -305.569372) (xy 402.786043 -305.575304) (xy 402.833314 -305.588996)
			(xy 402.877776 -305.610094) (xy 402.918279 -305.63805) (xy 402.953772 -305.672142) (xy 402.983337 -305.711486)
			(xy 403.006208 -305.755063) (xy 403.021792 -305.801744) (xy 403.029687 -305.850321) (xy 403.030182 -305.874928)
			(xy 403.36903 -305.874928) (xy 403.37299 -305.825874) (xy 403.384767 -305.77809) (xy 403.404058 -305.732814)
			(xy 403.430361 -305.691218) (xy 403.462996 -305.654381) (xy 403.501117 -305.623256) (xy 403.543738 -305.598649)
			(xy 403.589754 -305.581197) (xy 403.637973 -305.571353) (xy 403.687148 -305.569372) (xy 403.736003 -305.575304)
			(xy 403.783274 -305.588996) (xy 403.827736 -305.610094) (xy 403.868239 -305.63805) (xy 403.903732 -305.672142)
			(xy 403.933297 -305.711486) (xy 403.956168 -305.755063) (xy 403.971752 -305.801744) (xy 403.979647 -305.850321)
			(xy 403.980142 -305.874928) (xy 404.31899 -305.874928) (xy 404.32295 -305.825874) (xy 404.334727 -305.77809)
			(xy 404.354018 -305.732814) (xy 404.380321 -305.691218) (xy 404.412956 -305.654381) (xy 404.451077 -305.623256)
			(xy 404.493698 -305.598649) (xy 404.539714 -305.581197) (xy 404.587933 -305.571353) (xy 404.637108 -305.569372)
			(xy 404.685963 -305.575304) (xy 404.733234 -305.588996) (xy 404.777696 -305.610094) (xy 404.818199 -305.63805)
			(xy 404.853692 -305.672142) (xy 404.883257 -305.711486) (xy 404.906128 -305.755063) (xy 404.921712 -305.801744)
			(xy 404.929607 -305.850321) (xy 404.930102 -305.874928) (xy 405.269204 -305.874928) (xy 405.273164 -305.825874)
			(xy 405.284941 -305.77809) (xy 405.304232 -305.732814) (xy 405.330535 -305.691218) (xy 405.36317 -305.654381)
			(xy 405.401291 -305.623256) (xy 405.443912 -305.598649) (xy 405.489928 -305.581197) (xy 405.538147 -305.571353)
			(xy 405.587322 -305.569372) (xy 405.636177 -305.575304) (xy 405.683448 -305.588996) (xy 405.72791 -305.610094)
			(xy 405.768413 -305.63805) (xy 405.803906 -305.672142) (xy 405.833471 -305.711486) (xy 405.856342 -305.755063)
			(xy 405.871926 -305.801744) (xy 405.879821 -305.850321) (xy 405.880316 -305.874928) (xy 406.219164 -305.874928)
			(xy 406.223124 -305.825874) (xy 406.234901 -305.77809) (xy 406.254192 -305.732814) (xy 406.280495 -305.691218)
			(xy 406.31313 -305.654381) (xy 406.351251 -305.623256) (xy 406.393872 -305.598649) (xy 406.439888 -305.581197)
			(xy 406.488107 -305.571353) (xy 406.537282 -305.569372) (xy 406.586137 -305.575304) (xy 406.633408 -305.588996)
			(xy 406.67787 -305.610094) (xy 406.718373 -305.63805) (xy 406.753866 -305.672142) (xy 406.783431 -305.711486)
			(xy 406.806302 -305.755063) (xy 406.821886 -305.801744) (xy 406.829781 -305.850321) (xy 406.830276 -305.874928)
			(xy 408.119084 -305.874928) (xy 408.123044 -305.825874) (xy 408.134821 -305.77809) (xy 408.154112 -305.732814)
			(xy 408.180415 -305.691218) (xy 408.21305 -305.654381) (xy 408.251171 -305.623256) (xy 408.293792 -305.598649)
			(xy 408.339808 -305.581197) (xy 408.388027 -305.571353) (xy 408.437202 -305.569372) (xy 408.486057 -305.575304)
			(xy 408.533328 -305.588996) (xy 408.57779 -305.610094) (xy 408.618293 -305.63805) (xy 408.653786 -305.672142)
			(xy 408.683351 -305.711486) (xy 408.706222 -305.755063) (xy 408.721806 -305.801744) (xy 408.729701 -305.850321)
			(xy 408.730196 -305.874928) (xy 409.069044 -305.874928) (xy 409.073004 -305.825874) (xy 409.084781 -305.77809)
			(xy 409.104072 -305.732814) (xy 409.130375 -305.691218) (xy 409.16301 -305.654381) (xy 409.201131 -305.623256)
			(xy 409.243752 -305.598649) (xy 409.289768 -305.581197) (xy 409.337987 -305.571353) (xy 409.387162 -305.569372)
			(xy 409.436017 -305.575304) (xy 409.483288 -305.588996) (xy 409.52775 -305.610094) (xy 409.568253 -305.63805)
			(xy 409.603746 -305.672142) (xy 409.633311 -305.711486) (xy 409.656182 -305.755063) (xy 409.671766 -305.801744)
			(xy 409.679661 -305.850321) (xy 409.680156 -305.874928) (xy 410.019004 -305.874928) (xy 410.022964 -305.825874)
			(xy 410.034741 -305.77809) (xy 410.054032 -305.732814) (xy 410.080335 -305.691218) (xy 410.11297 -305.654381)
			(xy 410.151091 -305.623256) (xy 410.193712 -305.598649) (xy 410.239728 -305.581197) (xy 410.287947 -305.571353)
			(xy 410.337122 -305.569372) (xy 410.385977 -305.575304) (xy 410.433248 -305.588996) (xy 410.47771 -305.610094)
			(xy 410.518213 -305.63805) (xy 410.553706 -305.672142) (xy 410.583271 -305.711486) (xy 410.606142 -305.755063)
			(xy 410.621726 -305.801744) (xy 410.629621 -305.850321) (xy 410.630116 -305.874928) (xy 410.969218 -305.874928)
			(xy 410.973178 -305.825874) (xy 410.984955 -305.77809) (xy 411.004246 -305.732814) (xy 411.030549 -305.691218)
			(xy 411.063184 -305.654381) (xy 411.101305 -305.623256) (xy 411.143926 -305.598649) (xy 411.189942 -305.581197)
			(xy 411.238161 -305.571353) (xy 411.287336 -305.569372) (xy 411.336191 -305.575304) (xy 411.383462 -305.588996)
			(xy 411.427924 -305.610094) (xy 411.468427 -305.63805) (xy 411.50392 -305.672142) (xy 411.533485 -305.711486)
			(xy 411.556356 -305.755063) (xy 411.57194 -305.801744) (xy 411.579835 -305.850321) (xy 411.58033 -305.874928)
			(xy 411.919178 -305.874928) (xy 411.923138 -305.825874) (xy 411.934915 -305.77809) (xy 411.954206 -305.732814)
			(xy 411.980509 -305.691218) (xy 412.013144 -305.654381) (xy 412.051265 -305.623256) (xy 412.093886 -305.598649)
			(xy 412.139902 -305.581197) (xy 412.188121 -305.571353) (xy 412.237296 -305.569372) (xy 412.286151 -305.575304)
			(xy 412.333422 -305.588996) (xy 412.377884 -305.610094) (xy 412.418387 -305.63805) (xy 412.45388 -305.672142)
			(xy 412.483445 -305.711486) (xy 412.506316 -305.755063) (xy 412.5219 -305.801744) (xy 412.529795 -305.850321)
			(xy 412.53029 -305.874928) (xy 412.869138 -305.874928) (xy 412.873098 -305.825874) (xy 412.884875 -305.77809)
			(xy 412.904166 -305.732814) (xy 412.930469 -305.691218) (xy 412.963104 -305.654381) (xy 413.001225 -305.623256)
			(xy 413.043846 -305.598649) (xy 413.089862 -305.581197) (xy 413.138081 -305.571353) (xy 413.187256 -305.569372)
			(xy 413.236111 -305.575304) (xy 413.283382 -305.588996) (xy 413.327844 -305.610094) (xy 413.368347 -305.63805)
			(xy 413.40384 -305.672142) (xy 413.433405 -305.711486) (xy 413.456276 -305.755063) (xy 413.47186 -305.801744)
			(xy 413.479755 -305.850321) (xy 413.48025 -305.874928) (xy 413.819098 -305.874928) (xy 413.823058 -305.825874)
			(xy 413.834835 -305.77809) (xy 413.854126 -305.732814) (xy 413.880429 -305.691218) (xy 413.913064 -305.654381)
			(xy 413.951185 -305.623256) (xy 413.993806 -305.598649) (xy 414.039822 -305.581197) (xy 414.088041 -305.571353)
			(xy 414.137216 -305.569372) (xy 414.186071 -305.575304) (xy 414.233342 -305.588996) (xy 414.277804 -305.610094)
			(xy 414.318307 -305.63805) (xy 414.3538 -305.672142) (xy 414.383365 -305.711486) (xy 414.406236 -305.755063)
			(xy 414.42182 -305.801744) (xy 414.429715 -305.850321) (xy 414.43021 -305.874928) (xy 414.769058 -305.874928)
			(xy 414.773018 -305.825874) (xy 414.784795 -305.77809) (xy 414.804086 -305.732814) (xy 414.830389 -305.691218)
			(xy 414.863024 -305.654381) (xy 414.901145 -305.623256) (xy 414.943766 -305.598649) (xy 414.989782 -305.581197)
			(xy 415.038001 -305.571353) (xy 415.087176 -305.569372) (xy 415.136031 -305.575304) (xy 415.183302 -305.588996)
			(xy 415.227764 -305.610094) (xy 415.268267 -305.63805) (xy 415.30376 -305.672142) (xy 415.333325 -305.711486)
			(xy 415.356196 -305.755063) (xy 415.37178 -305.801744) (xy 415.379675 -305.850321) (xy 415.38017 -305.874928)
			(xy 415.719018 -305.874928) (xy 415.722978 -305.825874) (xy 415.734755 -305.77809) (xy 415.754046 -305.732814)
			(xy 415.780349 -305.691218) (xy 415.812984 -305.654381) (xy 415.851105 -305.623256) (xy 415.893726 -305.598649)
			(xy 415.939742 -305.581197) (xy 415.987961 -305.571353) (xy 416.037136 -305.569372) (xy 416.085991 -305.575304)
			(xy 416.133262 -305.588996) (xy 416.177724 -305.610094) (xy 416.218227 -305.63805) (xy 416.25372 -305.672142)
			(xy 416.283285 -305.711486) (xy 416.306156 -305.755063) (xy 416.32174 -305.801744) (xy 416.329635 -305.850321)
			(xy 416.33013 -305.874928) (xy 416.668978 -305.874928) (xy 416.672938 -305.825874) (xy 416.684715 -305.77809)
			(xy 416.704006 -305.732814) (xy 416.730309 -305.691218) (xy 416.762944 -305.654381) (xy 416.801065 -305.623256)
			(xy 416.843686 -305.598649) (xy 416.889702 -305.581197) (xy 416.937921 -305.571353) (xy 416.987096 -305.569372)
			(xy 417.035951 -305.575304) (xy 417.083222 -305.588996) (xy 417.127684 -305.610094) (xy 417.168187 -305.63805)
			(xy 417.20368 -305.672142) (xy 417.233245 -305.711486) (xy 417.256116 -305.755063) (xy 417.2717 -305.801744)
			(xy 417.279595 -305.850321) (xy 417.28009 -305.874928) (xy 417.279595 -305.899535) (xy 417.2717 -305.948112)
			(xy 417.256116 -305.994793) (xy 417.233245 -306.03837) (xy 417.20368 -306.077714) (xy 417.168187 -306.111806)
			(xy 417.127684 -306.139762) (xy 417.083222 -306.16086) (xy 417.035951 -306.174552) (xy 416.987096 -306.180484)
			(xy 416.937921 -306.178503) (xy 416.889702 -306.168659) (xy 416.843686 -306.151207) (xy 416.801065 -306.1266)
			(xy 416.762944 -306.095475) (xy 416.730309 -306.058638) (xy 416.704006 -306.017042) (xy 416.684715 -305.971766)
			(xy 416.672938 -305.923982) (xy 416.668978 -305.874928) (xy 416.33013 -305.874928) (xy 416.329635 -305.899535)
			(xy 416.32174 -305.948112) (xy 416.306156 -305.994793) (xy 416.283285 -306.03837) (xy 416.25372 -306.077714)
			(xy 416.218227 -306.111806) (xy 416.177724 -306.139762) (xy 416.133262 -306.16086) (xy 416.085991 -306.174552)
			(xy 416.037136 -306.180484) (xy 415.987961 -306.178503) (xy 415.939742 -306.168659) (xy 415.893726 -306.151207)
			(xy 415.851105 -306.1266) (xy 415.812984 -306.095475) (xy 415.780349 -306.058638) (xy 415.754046 -306.017042)
			(xy 415.734755 -305.971766) (xy 415.722978 -305.923982) (xy 415.719018 -305.874928) (xy 415.38017 -305.874928)
			(xy 415.379675 -305.899535) (xy 415.37178 -305.948112) (xy 415.356196 -305.994793) (xy 415.333325 -306.03837)
			(xy 415.30376 -306.077714) (xy 415.268267 -306.111806) (xy 415.227764 -306.139762) (xy 415.183302 -306.16086)
			(xy 415.136031 -306.174552) (xy 415.087176 -306.180484) (xy 415.038001 -306.178503) (xy 414.989782 -306.168659)
			(xy 414.943766 -306.151207) (xy 414.901145 -306.1266) (xy 414.863024 -306.095475) (xy 414.830389 -306.058638)
			(xy 414.804086 -306.017042) (xy 414.784795 -305.971766) (xy 414.773018 -305.923982) (xy 414.769058 -305.874928)
			(xy 414.43021 -305.874928) (xy 414.429715 -305.899535) (xy 414.42182 -305.948112) (xy 414.406236 -305.994793)
			(xy 414.383365 -306.03837) (xy 414.3538 -306.077714) (xy 414.318307 -306.111806) (xy 414.277804 -306.139762)
			(xy 414.233342 -306.16086) (xy 414.186071 -306.174552) (xy 414.137216 -306.180484) (xy 414.088041 -306.178503)
			(xy 414.039822 -306.168659) (xy 413.993806 -306.151207) (xy 413.951185 -306.1266) (xy 413.913064 -306.095475)
			(xy 413.880429 -306.058638) (xy 413.854126 -306.017042) (xy 413.834835 -305.971766) (xy 413.823058 -305.923982)
			(xy 413.819098 -305.874928) (xy 413.48025 -305.874928) (xy 413.479755 -305.899535) (xy 413.47186 -305.948112)
			(xy 413.456276 -305.994793) (xy 413.433405 -306.03837) (xy 413.40384 -306.077714) (xy 413.368347 -306.111806)
			(xy 413.327844 -306.139762) (xy 413.283382 -306.16086) (xy 413.236111 -306.174552) (xy 413.187256 -306.180484)
			(xy 413.138081 -306.178503) (xy 413.089862 -306.168659) (xy 413.043846 -306.151207) (xy 413.001225 -306.1266)
			(xy 412.963104 -306.095475) (xy 412.930469 -306.058638) (xy 412.904166 -306.017042) (xy 412.884875 -305.971766)
			(xy 412.873098 -305.923982) (xy 412.869138 -305.874928) (xy 412.53029 -305.874928) (xy 412.529795 -305.899535)
			(xy 412.5219 -305.948112) (xy 412.506316 -305.994793) (xy 412.483445 -306.03837) (xy 412.45388 -306.077714)
			(xy 412.418387 -306.111806) (xy 412.377884 -306.139762) (xy 412.333422 -306.16086) (xy 412.286151 -306.174552)
			(xy 412.237296 -306.180484) (xy 412.188121 -306.178503) (xy 412.139902 -306.168659) (xy 412.093886 -306.151207)
			(xy 412.051265 -306.1266) (xy 412.013144 -306.095475) (xy 411.980509 -306.058638) (xy 411.954206 -306.017042)
			(xy 411.934915 -305.971766) (xy 411.923138 -305.923982) (xy 411.919178 -305.874928) (xy 411.58033 -305.874928)
			(xy 411.579835 -305.899535) (xy 411.57194 -305.948112) (xy 411.556356 -305.994793) (xy 411.533485 -306.03837)
			(xy 411.50392 -306.077714) (xy 411.468427 -306.111806) (xy 411.427924 -306.139762) (xy 411.383462 -306.16086)
			(xy 411.336191 -306.174552) (xy 411.287336 -306.180484) (xy 411.238161 -306.178503) (xy 411.189942 -306.168659)
			(xy 411.143926 -306.151207) (xy 411.101305 -306.1266) (xy 411.063184 -306.095475) (xy 411.030549 -306.058638)
			(xy 411.004246 -306.017042) (xy 410.984955 -305.971766) (xy 410.973178 -305.923982) (xy 410.969218 -305.874928)
			(xy 410.630116 -305.874928) (xy 410.629621 -305.899535) (xy 410.621726 -305.948112) (xy 410.606142 -305.994793)
			(xy 410.583271 -306.03837) (xy 410.553706 -306.077714) (xy 410.518213 -306.111806) (xy 410.47771 -306.139762)
			(xy 410.433248 -306.16086) (xy 410.385977 -306.174552) (xy 410.337122 -306.180484) (xy 410.287947 -306.178503)
			(xy 410.239728 -306.168659) (xy 410.193712 -306.151207) (xy 410.151091 -306.1266) (xy 410.11297 -306.095475)
			(xy 410.080335 -306.058638) (xy 410.054032 -306.017042) (xy 410.034741 -305.971766) (xy 410.022964 -305.923982)
			(xy 410.019004 -305.874928) (xy 409.680156 -305.874928) (xy 409.679661 -305.899535) (xy 409.671766 -305.948112)
			(xy 409.656182 -305.994793) (xy 409.633311 -306.03837) (xy 409.603746 -306.077714) (xy 409.568253 -306.111806)
			(xy 409.52775 -306.139762) (xy 409.483288 -306.16086) (xy 409.436017 -306.174552) (xy 409.387162 -306.180484)
			(xy 409.337987 -306.178503) (xy 409.289768 -306.168659) (xy 409.243752 -306.151207) (xy 409.201131 -306.1266)
			(xy 409.16301 -306.095475) (xy 409.130375 -306.058638) (xy 409.104072 -306.017042) (xy 409.084781 -305.971766)
			(xy 409.073004 -305.923982) (xy 409.069044 -305.874928) (xy 408.730196 -305.874928) (xy 408.729701 -305.899535)
			(xy 408.721806 -305.948112) (xy 408.706222 -305.994793) (xy 408.683351 -306.03837) (xy 408.653786 -306.077714)
			(xy 408.618293 -306.111806) (xy 408.57779 -306.139762) (xy 408.533328 -306.16086) (xy 408.486057 -306.174552)
			(xy 408.437202 -306.180484) (xy 408.388027 -306.178503) (xy 408.339808 -306.168659) (xy 408.293792 -306.151207)
			(xy 408.251171 -306.1266) (xy 408.21305 -306.095475) (xy 408.180415 -306.058638) (xy 408.154112 -306.017042)
			(xy 408.134821 -305.971766) (xy 408.123044 -305.923982) (xy 408.119084 -305.874928) (xy 406.830276 -305.874928)
			(xy 406.829781 -305.899535) (xy 406.821886 -305.948112) (xy 406.806302 -305.994793) (xy 406.783431 -306.03837)
			(xy 406.753866 -306.077714) (xy 406.718373 -306.111806) (xy 406.67787 -306.139762) (xy 406.633408 -306.16086)
			(xy 406.586137 -306.174552) (xy 406.537282 -306.180484) (xy 406.488107 -306.178503) (xy 406.439888 -306.168659)
			(xy 406.393872 -306.151207) (xy 406.351251 -306.1266) (xy 406.31313 -306.095475) (xy 406.280495 -306.058638)
			(xy 406.254192 -306.017042) (xy 406.234901 -305.971766) (xy 406.223124 -305.923982) (xy 406.219164 -305.874928)
			(xy 405.880316 -305.874928) (xy 405.879821 -305.899535) (xy 405.871926 -305.948112) (xy 405.856342 -305.994793)
			(xy 405.833471 -306.03837) (xy 405.803906 -306.077714) (xy 405.768413 -306.111806) (xy 405.72791 -306.139762)
			(xy 405.683448 -306.16086) (xy 405.636177 -306.174552) (xy 405.587322 -306.180484) (xy 405.538147 -306.178503)
			(xy 405.489928 -306.168659) (xy 405.443912 -306.151207) (xy 405.401291 -306.1266) (xy 405.36317 -306.095475)
			(xy 405.330535 -306.058638) (xy 405.304232 -306.017042) (xy 405.284941 -305.971766) (xy 405.273164 -305.923982)
			(xy 405.269204 -305.874928) (xy 404.930102 -305.874928) (xy 404.929607 -305.899535) (xy 404.921712 -305.948112)
			(xy 404.906128 -305.994793) (xy 404.883257 -306.03837) (xy 404.853692 -306.077714) (xy 404.818199 -306.111806)
			(xy 404.777696 -306.139762) (xy 404.733234 -306.16086) (xy 404.685963 -306.174552) (xy 404.637108 -306.180484)
			(xy 404.587933 -306.178503) (xy 404.539714 -306.168659) (xy 404.493698 -306.151207) (xy 404.451077 -306.1266)
			(xy 404.412956 -306.095475) (xy 404.380321 -306.058638) (xy 404.354018 -306.017042) (xy 404.334727 -305.971766)
			(xy 404.32295 -305.923982) (xy 404.31899 -305.874928) (xy 403.980142 -305.874928) (xy 403.979647 -305.899535)
			(xy 403.971752 -305.948112) (xy 403.956168 -305.994793) (xy 403.933297 -306.03837) (xy 403.903732 -306.077714)
			(xy 403.868239 -306.111806) (xy 403.827736 -306.139762) (xy 403.783274 -306.16086) (xy 403.736003 -306.174552)
			(xy 403.687148 -306.180484) (xy 403.637973 -306.178503) (xy 403.589754 -306.168659) (xy 403.543738 -306.151207)
			(xy 403.501117 -306.1266) (xy 403.462996 -306.095475) (xy 403.430361 -306.058638) (xy 403.404058 -306.017042)
			(xy 403.384767 -305.971766) (xy 403.37299 -305.923982) (xy 403.36903 -305.874928) (xy 403.030182 -305.874928)
			(xy 403.029687 -305.899535) (xy 403.021792 -305.948112) (xy 403.006208 -305.994793) (xy 402.983337 -306.03837)
			(xy 402.953772 -306.077714) (xy 402.918279 -306.111806) (xy 402.877776 -306.139762) (xy 402.833314 -306.16086)
			(xy 402.786043 -306.174552) (xy 402.737188 -306.180484) (xy 402.688013 -306.178503) (xy 402.639794 -306.168659)
			(xy 402.593778 -306.151207) (xy 402.551157 -306.1266) (xy 402.513036 -306.095475) (xy 402.480401 -306.058638)
			(xy 402.454098 -306.017042) (xy 402.434807 -305.971766) (xy 402.42303 -305.923982) (xy 402.41907 -305.874928)
			(xy 402.080222 -305.874928) (xy 402.079727 -305.899535) (xy 402.071832 -305.948112) (xy 402.056248 -305.994793)
			(xy 402.033377 -306.03837) (xy 402.003812 -306.077714) (xy 401.968319 -306.111806) (xy 401.927816 -306.139762)
			(xy 401.883354 -306.16086) (xy 401.836083 -306.174552) (xy 401.787228 -306.180484) (xy 401.738053 -306.178503)
			(xy 401.689834 -306.168659) (xy 401.643818 -306.151207) (xy 401.601197 -306.1266) (xy 401.563076 -306.095475)
			(xy 401.530441 -306.058638) (xy 401.504138 -306.017042) (xy 401.484847 -305.971766) (xy 401.47307 -305.923982)
			(xy 401.46911 -305.874928) (xy 401.130262 -305.874928) (xy 401.129767 -305.899535) (xy 401.121872 -305.948112)
			(xy 401.106288 -305.994793) (xy 401.083417 -306.03837) (xy 401.053852 -306.077714) (xy 401.018359 -306.111806)
			(xy 400.977856 -306.139762) (xy 400.933394 -306.16086) (xy 400.886123 -306.174552) (xy 400.837268 -306.180484)
			(xy 400.788093 -306.178503) (xy 400.739874 -306.168659) (xy 400.693858 -306.151207) (xy 400.651237 -306.1266)
			(xy 400.613116 -306.095475) (xy 400.580481 -306.058638) (xy 400.554178 -306.017042) (xy 400.534887 -305.971766)
			(xy 400.52311 -305.923982) (xy 400.51915 -305.874928) (xy 400.180302 -305.874928) (xy 400.179807 -305.899535)
			(xy 400.171912 -305.948112) (xy 400.156328 -305.994793) (xy 400.133457 -306.03837) (xy 400.103892 -306.077714)
			(xy 400.068399 -306.111806) (xy 400.027896 -306.139762) (xy 399.983434 -306.16086) (xy 399.936163 -306.174552)
			(xy 399.887308 -306.180484) (xy 399.838133 -306.178503) (xy 399.789914 -306.168659) (xy 399.743898 -306.151207)
			(xy 399.701277 -306.1266) (xy 399.663156 -306.095475) (xy 399.630521 -306.058638) (xy 399.604218 -306.017042)
			(xy 399.584927 -305.971766) (xy 399.57315 -305.923982) (xy 399.56919 -305.874928) (xy 399.230342 -305.874928)
			(xy 399.229847 -305.899535) (xy 399.221952 -305.948112) (xy 399.206368 -305.994793) (xy 399.183497 -306.03837)
			(xy 399.153932 -306.077714) (xy 399.118439 -306.111806) (xy 399.077936 -306.139762) (xy 399.033474 -306.16086)
			(xy 398.986203 -306.174552) (xy 398.937348 -306.180484) (xy 398.888173 -306.178503) (xy 398.839954 -306.168659)
			(xy 398.793938 -306.151207) (xy 398.751317 -306.1266) (xy 398.713196 -306.095475) (xy 398.680561 -306.058638)
			(xy 398.654258 -306.017042) (xy 398.634967 -305.971766) (xy 398.62319 -305.923982) (xy 398.61923 -305.874928)
			(xy 398.280128 -305.874928) (xy 398.279633 -305.899535) (xy 398.271738 -305.948112) (xy 398.256154 -305.994793)
			(xy 398.233283 -306.03837) (xy 398.203718 -306.077714) (xy 398.168225 -306.111806) (xy 398.127722 -306.139762)
			(xy 398.08326 -306.16086) (xy 398.035989 -306.174552) (xy 397.987134 -306.180484) (xy 397.937959 -306.178503)
			(xy 397.88974 -306.168659) (xy 397.843724 -306.151207) (xy 397.801103 -306.1266) (xy 397.762982 -306.095475)
			(xy 397.730347 -306.058638) (xy 397.704044 -306.017042) (xy 397.684753 -305.971766) (xy 397.672976 -305.923982)
			(xy 397.669016 -305.874928) (xy 397.330168 -305.874928) (xy 397.329673 -305.899535) (xy 397.321778 -305.948112)
			(xy 397.306194 -305.994793) (xy 397.283323 -306.03837) (xy 397.253758 -306.077714) (xy 397.218265 -306.111806)
			(xy 397.177762 -306.139762) (xy 397.1333 -306.16086) (xy 397.086029 -306.174552) (xy 397.037174 -306.180484)
			(xy 396.987999 -306.178503) (xy 396.93978 -306.168659) (xy 396.893764 -306.151207) (xy 396.851143 -306.1266)
			(xy 396.813022 -306.095475) (xy 396.780387 -306.058638) (xy 396.754084 -306.017042) (xy 396.734793 -305.971766)
			(xy 396.723016 -305.923982) (xy 396.719056 -305.874928) (xy 396.380208 -305.874928) (xy 396.379713 -305.899535)
			(xy 396.371818 -305.948112) (xy 396.356234 -305.994793) (xy 396.333363 -306.03837) (xy 396.303798 -306.077714)
			(xy 396.268305 -306.111806) (xy 396.227802 -306.139762) (xy 396.18334 -306.16086) (xy 396.136069 -306.174552)
			(xy 396.087214 -306.180484) (xy 396.038039 -306.178503) (xy 395.98982 -306.168659) (xy 395.943804 -306.151207)
			(xy 395.901183 -306.1266) (xy 395.863062 -306.095475) (xy 395.830427 -306.058638) (xy 395.804124 -306.017042)
			(xy 395.784833 -305.971766) (xy 395.773056 -305.923982) (xy 395.769096 -305.874928) (xy 395.430248 -305.874928)
			(xy 395.429753 -305.899535) (xy 395.421858 -305.948112) (xy 395.406274 -305.994793) (xy 395.383403 -306.03837)
			(xy 395.353838 -306.077714) (xy 395.318345 -306.111806) (xy 395.277842 -306.139762) (xy 395.23338 -306.16086)
			(xy 395.186109 -306.174552) (xy 395.137254 -306.180484) (xy 395.088079 -306.178503) (xy 395.03986 -306.168659)
			(xy 394.993844 -306.151207) (xy 394.951223 -306.1266) (xy 394.913102 -306.095475) (xy 394.880467 -306.058638)
			(xy 394.854164 -306.017042) (xy 394.834873 -305.971766) (xy 394.823096 -305.923982) (xy 394.819136 -305.874928)
			(xy 375.71032 -305.874928) (xy 375.729695 -305.916259) (xy 375.745763 -305.969666) (xy 375.753883 -306.024842)
			(xy 375.754392 -306.052728) (xy 375.753883 -306.080614) (xy 375.745763 -306.13579) (xy 375.729695 -306.189197)
			(xy 375.706023 -306.239694) (xy 375.67525 -306.286207) (xy 375.638033 -306.327744) (xy 375.611095 -306.350162)
			(xy 383.893834 -306.350162) (xy 383.897794 -306.301108) (xy 383.909571 -306.253324) (xy 383.928862 -306.208048)
			(xy 383.955165 -306.166452) (xy 383.9878 -306.129615) (xy 384.025921 -306.09849) (xy 384.068542 -306.073883)
			(xy 384.114558 -306.056431) (xy 384.162777 -306.046587) (xy 384.211952 -306.044606) (xy 384.260807 -306.050538)
			(xy 384.308078 -306.06423) (xy 384.35254 -306.085328) (xy 384.393043 -306.113284) (xy 384.428536 -306.147376)
			(xy 384.458101 -306.18672) (xy 384.480972 -306.230297) (xy 384.496556 -306.276978) (xy 384.504451 -306.325555)
			(xy 384.504946 -306.350162) (xy 384.504451 -306.374769) (xy 384.504313 -306.375616) (xy 384.823204 -306.375616)
			(xy 384.823204 -306.3242) (xy 384.831247 -306.273418) (xy 384.847135 -306.224519) (xy 384.870478 -306.178707)
			(xy 384.900699 -306.137111) (xy 384.937055 -306.100755) (xy 384.978651 -306.070534) (xy 385.024463 -306.047191)
			(xy 385.073362 -306.031303) (xy 385.124144 -306.02326) (xy 385.17556 -306.02326) (xy 385.226342 -306.031303)
			(xy 385.275241 -306.047191) (xy 385.321053 -306.070534) (xy 385.362649 -306.100755) (xy 385.399005 -306.137111)
			(xy 385.429226 -306.178707) (xy 385.452569 -306.224519) (xy 385.468457 -306.273418) (xy 385.4765 -306.3242)
			(xy 385.477004 -306.349908) (xy 385.4765 -306.375616) (xy 385.773164 -306.375616) (xy 385.773164 -306.3242)
			(xy 385.781207 -306.273418) (xy 385.797095 -306.224519) (xy 385.820438 -306.178707) (xy 385.850659 -306.137111)
			(xy 385.887015 -306.100755) (xy 385.928611 -306.070534) (xy 385.974423 -306.047191) (xy 386.023322 -306.031303)
			(xy 386.074104 -306.02326) (xy 386.12552 -306.02326) (xy 386.176302 -306.031303) (xy 386.225201 -306.047191)
			(xy 386.271013 -306.070534) (xy 386.312609 -306.100755) (xy 386.348965 -306.137111) (xy 386.379186 -306.178707)
			(xy 386.402529 -306.224519) (xy 386.418417 -306.273418) (xy 386.42646 -306.3242) (xy 386.426964 -306.349908)
			(xy 386.744222 -306.349908) (xy 386.748182 -306.300854) (xy 386.759959 -306.25307) (xy 386.77925 -306.207794)
			(xy 386.805553 -306.166198) (xy 386.838188 -306.129361) (xy 386.876309 -306.098236) (xy 386.91893 -306.073629)
			(xy 386.964946 -306.056177) (xy 387.013165 -306.046333) (xy 387.06234 -306.044352) (xy 387.111195 -306.050284)
			(xy 387.158466 -306.063976) (xy 387.202928 -306.085074) (xy 387.243431 -306.11303) (xy 387.278924 -306.147122)
			(xy 387.308489 -306.186466) (xy 387.33136 -306.230043) (xy 387.346944 -306.276724) (xy 387.354839 -306.325301)
			(xy 387.355334 -306.349908) (xy 387.694182 -306.349908) (xy 387.698142 -306.300854) (xy 387.709919 -306.25307)
			(xy 387.72921 -306.207794) (xy 387.755513 -306.166198) (xy 387.788148 -306.129361) (xy 387.826269 -306.098236)
			(xy 387.86889 -306.073629) (xy 387.914906 -306.056177) (xy 387.963125 -306.046333) (xy 388.0123 -306.044352)
			(xy 388.061155 -306.050284) (xy 388.108426 -306.063976) (xy 388.152888 -306.085074) (xy 388.193391 -306.11303)
			(xy 388.228884 -306.147122) (xy 388.258449 -306.186466) (xy 388.28132 -306.230043) (xy 388.296904 -306.276724)
			(xy 388.304799 -306.325301) (xy 388.305294 -306.349908) (xy 388.644142 -306.349908) (xy 388.648102 -306.300854)
			(xy 388.659879 -306.25307) (xy 388.67917 -306.207794) (xy 388.705473 -306.166198) (xy 388.738108 -306.129361)
			(xy 388.776229 -306.098236) (xy 388.81885 -306.073629) (xy 388.864866 -306.056177) (xy 388.913085 -306.046333)
			(xy 388.96226 -306.044352) (xy 389.011115 -306.050284) (xy 389.058386 -306.063976) (xy 389.102848 -306.085074)
			(xy 389.143351 -306.11303) (xy 389.178844 -306.147122) (xy 389.208409 -306.186466) (xy 389.23128 -306.230043)
			(xy 389.246864 -306.276724) (xy 389.254759 -306.325301) (xy 389.255254 -306.349908) (xy 389.594102 -306.349908)
			(xy 389.598062 -306.300854) (xy 389.609839 -306.25307) (xy 389.62913 -306.207794) (xy 389.655433 -306.166198)
			(xy 389.688068 -306.129361) (xy 389.726189 -306.098236) (xy 389.76881 -306.073629) (xy 389.814826 -306.056177)
			(xy 389.863045 -306.046333) (xy 389.91222 -306.044352) (xy 389.961075 -306.050284) (xy 390.008346 -306.063976)
			(xy 390.052808 -306.085074) (xy 390.093311 -306.11303) (xy 390.128804 -306.147122) (xy 390.158369 -306.186466)
			(xy 390.18124 -306.230043) (xy 390.196824 -306.276724) (xy 390.204719 -306.325301) (xy 390.205214 -306.349908)
			(xy 390.544062 -306.349908) (xy 390.548022 -306.300854) (xy 390.559799 -306.25307) (xy 390.57909 -306.207794)
			(xy 390.605393 -306.166198) (xy 390.638028 -306.129361) (xy 390.676149 -306.098236) (xy 390.71877 -306.073629)
			(xy 390.764786 -306.056177) (xy 390.813005 -306.046333) (xy 390.86218 -306.044352) (xy 390.911035 -306.050284)
			(xy 390.958306 -306.063976) (xy 391.002768 -306.085074) (xy 391.043271 -306.11303) (xy 391.078764 -306.147122)
			(xy 391.108329 -306.186466) (xy 391.1312 -306.230043) (xy 391.146784 -306.276724) (xy 391.154679 -306.325301)
			(xy 391.155174 -306.349908) (xy 391.154679 -306.374515) (xy 391.1545 -306.375616) (xy 391.473178 -306.375616)
			(xy 391.473178 -306.3242) (xy 391.481221 -306.273418) (xy 391.497109 -306.224519) (xy 391.520452 -306.178707)
			(xy 391.550673 -306.137111) (xy 391.587029 -306.100755) (xy 391.628625 -306.070534) (xy 391.674437 -306.047191)
			(xy 391.723336 -306.031303) (xy 391.774118 -306.02326) (xy 391.825534 -306.02326) (xy 391.876316 -306.031303)
			(xy 391.925215 -306.047191) (xy 391.971027 -306.070534) (xy 392.012623 -306.100755) (xy 392.048979 -306.137111)
			(xy 392.0792 -306.178707) (xy 392.102543 -306.224519) (xy 392.118431 -306.273418) (xy 392.126474 -306.3242)
			(xy 392.126978 -306.349908) (xy 392.126474 -306.375616) (xy 392.423138 -306.375616) (xy 392.423138 -306.3242)
			(xy 392.431181 -306.273418) (xy 392.447069 -306.224519) (xy 392.470412 -306.178707) (xy 392.500633 -306.137111)
			(xy 392.536989 -306.100755) (xy 392.578585 -306.070534) (xy 392.624397 -306.047191) (xy 392.673296 -306.031303)
			(xy 392.724078 -306.02326) (xy 392.775494 -306.02326) (xy 392.826276 -306.031303) (xy 392.875175 -306.047191)
			(xy 392.920987 -306.070534) (xy 392.962583 -306.100755) (xy 392.998939 -306.137111) (xy 393.02916 -306.178707)
			(xy 393.052503 -306.224519) (xy 393.068391 -306.273418) (xy 393.076434 -306.3242) (xy 393.076938 -306.349908)
			(xy 393.394196 -306.349908) (xy 393.398156 -306.300854) (xy 393.409933 -306.25307) (xy 393.429224 -306.207794)
			(xy 393.455527 -306.166198) (xy 393.488162 -306.129361) (xy 393.526283 -306.098236) (xy 393.568904 -306.073629)
			(xy 393.61492 -306.056177) (xy 393.663139 -306.046333) (xy 393.712314 -306.044352) (xy 393.761169 -306.050284)
			(xy 393.80844 -306.063976) (xy 393.852902 -306.085074) (xy 393.893405 -306.11303) (xy 393.928898 -306.147122)
			(xy 393.958463 -306.186466) (xy 393.981334 -306.230043) (xy 393.996918 -306.276724) (xy 394.004813 -306.325301)
			(xy 394.005308 -306.349908) (xy 394.004813 -306.374515) (xy 393.996918 -306.423092) (xy 393.981334 -306.469773)
			(xy 393.958463 -306.51335) (xy 393.928898 -306.552694) (xy 393.893405 -306.586786) (xy 393.852902 -306.614742)
			(xy 393.80844 -306.63584) (xy 393.761169 -306.649532) (xy 393.712314 -306.655464) (xy 393.663139 -306.653483)
			(xy 393.61492 -306.643639) (xy 393.568904 -306.626187) (xy 393.526283 -306.60158) (xy 393.488162 -306.570455)
			(xy 393.455527 -306.533618) (xy 393.429224 -306.492022) (xy 393.409933 -306.446746) (xy 393.398156 -306.398962)
			(xy 393.394196 -306.349908) (xy 393.076938 -306.349908) (xy 393.076434 -306.375616) (xy 393.068391 -306.426398)
			(xy 393.052503 -306.475297) (xy 393.02916 -306.521109) (xy 392.998939 -306.562705) (xy 392.962583 -306.599061)
			(xy 392.920987 -306.629282) (xy 392.875175 -306.652625) (xy 392.826276 -306.668513) (xy 392.775494 -306.676556)
			(xy 392.724078 -306.676556) (xy 392.673296 -306.668513) (xy 392.624397 -306.652625) (xy 392.578585 -306.629282)
			(xy 392.536989 -306.599061) (xy 392.500633 -306.562705) (xy 392.470412 -306.521109) (xy 392.447069 -306.475297)
			(xy 392.431181 -306.426398) (xy 392.423138 -306.375616) (xy 392.126474 -306.375616) (xy 392.118431 -306.426398)
			(xy 392.102543 -306.475297) (xy 392.0792 -306.521109) (xy 392.048979 -306.562705) (xy 392.012623 -306.599061)
			(xy 391.971027 -306.629282) (xy 391.925215 -306.652625) (xy 391.876316 -306.668513) (xy 391.825534 -306.676556)
			(xy 391.774118 -306.676556) (xy 391.723336 -306.668513) (xy 391.674437 -306.652625) (xy 391.628625 -306.629282)
			(xy 391.587029 -306.599061) (xy 391.550673 -306.562705) (xy 391.520452 -306.521109) (xy 391.497109 -306.475297)
			(xy 391.481221 -306.426398) (xy 391.473178 -306.375616) (xy 391.1545 -306.375616) (xy 391.146784 -306.423092)
			(xy 391.1312 -306.469773) (xy 391.108329 -306.51335) (xy 391.078764 -306.552694) (xy 391.043271 -306.586786)
			(xy 391.002768 -306.614742) (xy 390.958306 -306.63584) (xy 390.911035 -306.649532) (xy 390.86218 -306.655464)
			(xy 390.813005 -306.653483) (xy 390.764786 -306.643639) (xy 390.71877 -306.626187) (xy 390.676149 -306.60158)
			(xy 390.638028 -306.570455) (xy 390.605393 -306.533618) (xy 390.57909 -306.492022) (xy 390.559799 -306.446746)
			(xy 390.548022 -306.398962) (xy 390.544062 -306.349908) (xy 390.205214 -306.349908) (xy 390.204719 -306.374515)
			(xy 390.196824 -306.423092) (xy 390.18124 -306.469773) (xy 390.158369 -306.51335) (xy 390.128804 -306.552694)
			(xy 390.093311 -306.586786) (xy 390.052808 -306.614742) (xy 390.008346 -306.63584) (xy 389.961075 -306.649532)
			(xy 389.91222 -306.655464) (xy 389.863045 -306.653483) (xy 389.814826 -306.643639) (xy 389.76881 -306.626187)
			(xy 389.726189 -306.60158) (xy 389.688068 -306.570455) (xy 389.655433 -306.533618) (xy 389.62913 -306.492022)
			(xy 389.609839 -306.446746) (xy 389.598062 -306.398962) (xy 389.594102 -306.349908) (xy 389.255254 -306.349908)
			(xy 389.254759 -306.374515) (xy 389.246864 -306.423092) (xy 389.23128 -306.469773) (xy 389.208409 -306.51335)
			(xy 389.178844 -306.552694) (xy 389.143351 -306.586786) (xy 389.102848 -306.614742) (xy 389.058386 -306.63584)
			(xy 389.011115 -306.649532) (xy 388.96226 -306.655464) (xy 388.913085 -306.653483) (xy 388.864866 -306.643639)
			(xy 388.81885 -306.626187) (xy 388.776229 -306.60158) (xy 388.738108 -306.570455) (xy 388.705473 -306.533618)
			(xy 388.67917 -306.492022) (xy 388.659879 -306.446746) (xy 388.648102 -306.398962) (xy 388.644142 -306.349908)
			(xy 388.305294 -306.349908) (xy 388.304799 -306.374515) (xy 388.296904 -306.423092) (xy 388.28132 -306.469773)
			(xy 388.258449 -306.51335) (xy 388.228884 -306.552694) (xy 388.193391 -306.586786) (xy 388.152888 -306.614742)
			(xy 388.108426 -306.63584) (xy 388.061155 -306.649532) (xy 388.0123 -306.655464) (xy 387.963125 -306.653483)
			(xy 387.914906 -306.643639) (xy 387.86889 -306.626187) (xy 387.826269 -306.60158) (xy 387.788148 -306.570455)
			(xy 387.755513 -306.533618) (xy 387.72921 -306.492022) (xy 387.709919 -306.446746) (xy 387.698142 -306.398962)
			(xy 387.694182 -306.349908) (xy 387.355334 -306.349908) (xy 387.354839 -306.374515) (xy 387.346944 -306.423092)
			(xy 387.33136 -306.469773) (xy 387.308489 -306.51335) (xy 387.278924 -306.552694) (xy 387.243431 -306.586786)
			(xy 387.202928 -306.614742) (xy 387.158466 -306.63584) (xy 387.111195 -306.649532) (xy 387.06234 -306.655464)
			(xy 387.013165 -306.653483) (xy 386.964946 -306.643639) (xy 386.91893 -306.626187) (xy 386.876309 -306.60158)
			(xy 386.838188 -306.570455) (xy 386.805553 -306.533618) (xy 386.77925 -306.492022) (xy 386.759959 -306.446746)
			(xy 386.748182 -306.398962) (xy 386.744222 -306.349908) (xy 386.426964 -306.349908) (xy 386.42646 -306.375616)
			(xy 386.418417 -306.426398) (xy 386.402529 -306.475297) (xy 386.379186 -306.521109) (xy 386.348965 -306.562705)
			(xy 386.312609 -306.599061) (xy 386.271013 -306.629282) (xy 386.225201 -306.652625) (xy 386.176302 -306.668513)
			(xy 386.12552 -306.676556) (xy 386.074104 -306.676556) (xy 386.023322 -306.668513) (xy 385.974423 -306.652625)
			(xy 385.928611 -306.629282) (xy 385.887015 -306.599061) (xy 385.850659 -306.562705) (xy 385.820438 -306.521109)
			(xy 385.797095 -306.475297) (xy 385.781207 -306.426398) (xy 385.773164 -306.375616) (xy 385.4765 -306.375616)
			(xy 385.468457 -306.426398) (xy 385.452569 -306.475297) (xy 385.429226 -306.521109) (xy 385.399005 -306.562705)
			(xy 385.362649 -306.599061) (xy 385.321053 -306.629282) (xy 385.275241 -306.652625) (xy 385.226342 -306.668513)
			(xy 385.17556 -306.676556) (xy 385.124144 -306.676556) (xy 385.073362 -306.668513) (xy 385.024463 -306.652625)
			(xy 384.978651 -306.629282) (xy 384.937055 -306.599061) (xy 384.900699 -306.562705) (xy 384.870478 -306.521109)
			(xy 384.847135 -306.475297) (xy 384.831247 -306.426398) (xy 384.823204 -306.375616) (xy 384.504313 -306.375616)
			(xy 384.496556 -306.423346) (xy 384.480972 -306.470027) (xy 384.458101 -306.513604) (xy 384.428536 -306.552948)
			(xy 384.393043 -306.58704) (xy 384.35254 -306.614996) (xy 384.308078 -306.636094) (xy 384.260807 -306.649786)
			(xy 384.211952 -306.655718) (xy 384.162777 -306.653737) (xy 384.114558 -306.643893) (xy 384.068542 -306.626441)
			(xy 384.025921 -306.601834) (xy 383.9878 -306.570709) (xy 383.955165 -306.533872) (xy 383.928862 -306.492276)
			(xy 383.909571 -306.447) (xy 383.897794 -306.399216) (xy 383.893834 -306.350162) (xy 375.611095 -306.350162)
			(xy 375.595165 -306.363419) (xy 375.547559 -306.392473) (xy 375.49623 -306.414285) (xy 375.442273 -306.428391)
			(xy 375.386836 -306.434491) (xy 375.331102 -306.432454) (xy 375.276259 -306.422324) (xy 375.223475 -306.404317)
			(xy 375.173875 -306.378816) (xy 375.128517 -306.346365) (xy 375.088368 -306.307656) (xy 375.054282 -306.263513)
			(xy 375.026986 -306.214878) (xy 375.007063 -306.162787) (xy 374.994937 -306.10835) (xy 374.990866 -306.052728)
			(xy 364.844413 -306.052728) (xy 364.844191 -306.054269) (xy 364.828698 -306.106773) (xy 364.805851 -306.15652)
			(xy 364.776122 -306.202485) (xy 364.758478 -306.223416) (xy 364.752382 -306.230528) (xy 364.746032 -306.247546)
			(xy 364.746032 -306.33289) (xy 364.752382 -306.349908) (xy 364.758478 -306.35702) (xy 364.776136 -306.377939)
			(xy 364.80586 -306.423909) (xy 364.828704 -306.473658) (xy 364.844198 -306.526162) (xy 364.852025 -306.580342)
			(xy 364.852023 -306.635085) (xy 364.844193 -306.689265) (xy 364.828694 -306.741768) (xy 364.817933 -306.765198)
			(xy 378.025404 -306.765198) (xy 378.029475 -306.709576) (xy 378.041601 -306.655139) (xy 378.061524 -306.603048)
			(xy 378.08882 -306.554413) (xy 378.122906 -306.51027) (xy 378.163055 -306.471561) (xy 378.208413 -306.43911)
			(xy 378.258013 -306.413609) (xy 378.310797 -306.395602) (xy 378.36564 -306.385472) (xy 378.421374 -306.383435)
			(xy 378.476811 -306.389535) (xy 378.530768 -306.403641) (xy 378.582097 -306.425453) (xy 378.629703 -306.454507)
			(xy 378.672571 -306.490182) (xy 378.709788 -306.531719) (xy 378.740561 -306.578232) (xy 378.764233 -306.628729)
			(xy 378.780301 -306.682136) (xy 378.788421 -306.737312) (xy 378.78893 -306.765198) (xy 378.788421 -306.793084)
			(xy 378.783741 -306.824888) (xy 394.819136 -306.824888) (xy 394.823096 -306.775834) (xy 394.834873 -306.72805)
			(xy 394.854164 -306.682774) (xy 394.880467 -306.641178) (xy 394.913102 -306.604341) (xy 394.951223 -306.573216)
			(xy 394.993844 -306.548609) (xy 395.03986 -306.531157) (xy 395.088079 -306.521313) (xy 395.137254 -306.519332)
			(xy 395.186109 -306.525264) (xy 395.23338 -306.538956) (xy 395.277842 -306.560054) (xy 395.318345 -306.58801)
			(xy 395.353838 -306.622102) (xy 395.383403 -306.661446) (xy 395.406274 -306.705023) (xy 395.421858 -306.751704)
			(xy 395.429753 -306.800281) (xy 395.430248 -306.824888) (xy 395.769096 -306.824888) (xy 395.773056 -306.775834)
			(xy 395.784833 -306.72805) (xy 395.804124 -306.682774) (xy 395.830427 -306.641178) (xy 395.863062 -306.604341)
			(xy 395.901183 -306.573216) (xy 395.943804 -306.548609) (xy 395.98982 -306.531157) (xy 396.038039 -306.521313)
			(xy 396.087214 -306.519332) (xy 396.136069 -306.525264) (xy 396.18334 -306.538956) (xy 396.227802 -306.560054)
			(xy 396.268305 -306.58801) (xy 396.303798 -306.622102) (xy 396.333363 -306.661446) (xy 396.356234 -306.705023)
			(xy 396.371818 -306.751704) (xy 396.379713 -306.800281) (xy 396.380208 -306.824888) (xy 396.719056 -306.824888)
			(xy 396.723016 -306.775834) (xy 396.734793 -306.72805) (xy 396.754084 -306.682774) (xy 396.780387 -306.641178)
			(xy 396.813022 -306.604341) (xy 396.851143 -306.573216) (xy 396.893764 -306.548609) (xy 396.93978 -306.531157)
			(xy 396.987999 -306.521313) (xy 397.037174 -306.519332) (xy 397.086029 -306.525264) (xy 397.1333 -306.538956)
			(xy 397.177762 -306.560054) (xy 397.218265 -306.58801) (xy 397.253758 -306.622102) (xy 397.283323 -306.661446)
			(xy 397.306194 -306.705023) (xy 397.321778 -306.751704) (xy 397.329673 -306.800281) (xy 397.330168 -306.824888)
			(xy 397.669016 -306.824888) (xy 397.672976 -306.775834) (xy 397.684753 -306.72805) (xy 397.704044 -306.682774)
			(xy 397.730347 -306.641178) (xy 397.762982 -306.604341) (xy 397.801103 -306.573216) (xy 397.843724 -306.548609)
			(xy 397.88974 -306.531157) (xy 397.937959 -306.521313) (xy 397.987134 -306.519332) (xy 398.035989 -306.525264)
			(xy 398.08326 -306.538956) (xy 398.127722 -306.560054) (xy 398.168225 -306.58801) (xy 398.203718 -306.622102)
			(xy 398.233283 -306.661446) (xy 398.256154 -306.705023) (xy 398.271738 -306.751704) (xy 398.279633 -306.800281)
			(xy 398.280128 -306.824888) (xy 398.61923 -306.824888) (xy 398.62319 -306.775834) (xy 398.634967 -306.72805)
			(xy 398.654258 -306.682774) (xy 398.680561 -306.641178) (xy 398.713196 -306.604341) (xy 398.751317 -306.573216)
			(xy 398.793938 -306.548609) (xy 398.839954 -306.531157) (xy 398.888173 -306.521313) (xy 398.937348 -306.519332)
			(xy 398.986203 -306.525264) (xy 399.033474 -306.538956) (xy 399.077936 -306.560054) (xy 399.118439 -306.58801)
			(xy 399.153932 -306.622102) (xy 399.183497 -306.661446) (xy 399.206368 -306.705023) (xy 399.221952 -306.751704)
			(xy 399.229847 -306.800281) (xy 399.230342 -306.824888) (xy 399.56919 -306.824888) (xy 399.57315 -306.775834)
			(xy 399.584927 -306.72805) (xy 399.604218 -306.682774) (xy 399.630521 -306.641178) (xy 399.663156 -306.604341)
			(xy 399.701277 -306.573216) (xy 399.743898 -306.548609) (xy 399.789914 -306.531157) (xy 399.838133 -306.521313)
			(xy 399.887308 -306.519332) (xy 399.936163 -306.525264) (xy 399.983434 -306.538956) (xy 400.027896 -306.560054)
			(xy 400.068399 -306.58801) (xy 400.103892 -306.622102) (xy 400.133457 -306.661446) (xy 400.156328 -306.705023)
			(xy 400.171912 -306.751704) (xy 400.179807 -306.800281) (xy 400.180302 -306.824888) (xy 400.51915 -306.824888)
			(xy 400.52311 -306.775834) (xy 400.534887 -306.72805) (xy 400.554178 -306.682774) (xy 400.580481 -306.641178)
			(xy 400.613116 -306.604341) (xy 400.651237 -306.573216) (xy 400.693858 -306.548609) (xy 400.739874 -306.531157)
			(xy 400.788093 -306.521313) (xy 400.837268 -306.519332) (xy 400.886123 -306.525264) (xy 400.933394 -306.538956)
			(xy 400.977856 -306.560054) (xy 401.018359 -306.58801) (xy 401.053852 -306.622102) (xy 401.083417 -306.661446)
			(xy 401.106288 -306.705023) (xy 401.121872 -306.751704) (xy 401.129767 -306.800281) (xy 401.130262 -306.824888)
			(xy 401.46911 -306.824888) (xy 401.47307 -306.775834) (xy 401.484847 -306.72805) (xy 401.504138 -306.682774)
			(xy 401.530441 -306.641178) (xy 401.563076 -306.604341) (xy 401.601197 -306.573216) (xy 401.643818 -306.548609)
			(xy 401.689834 -306.531157) (xy 401.738053 -306.521313) (xy 401.787228 -306.519332) (xy 401.836083 -306.525264)
			(xy 401.883354 -306.538956) (xy 401.927816 -306.560054) (xy 401.968319 -306.58801) (xy 402.003812 -306.622102)
			(xy 402.033377 -306.661446) (xy 402.056248 -306.705023) (xy 402.071832 -306.751704) (xy 402.079727 -306.800281)
			(xy 402.080222 -306.824888) (xy 402.41907 -306.824888) (xy 402.42303 -306.775834) (xy 402.434807 -306.72805)
			(xy 402.454098 -306.682774) (xy 402.480401 -306.641178) (xy 402.513036 -306.604341) (xy 402.551157 -306.573216)
			(xy 402.593778 -306.548609) (xy 402.639794 -306.531157) (xy 402.688013 -306.521313) (xy 402.737188 -306.519332)
			(xy 402.786043 -306.525264) (xy 402.833314 -306.538956) (xy 402.877776 -306.560054) (xy 402.918279 -306.58801)
			(xy 402.953772 -306.622102) (xy 402.983337 -306.661446) (xy 403.006208 -306.705023) (xy 403.021792 -306.751704)
			(xy 403.029687 -306.800281) (xy 403.030182 -306.824888) (xy 403.36903 -306.824888) (xy 403.37299 -306.775834)
			(xy 403.384767 -306.72805) (xy 403.404058 -306.682774) (xy 403.430361 -306.641178) (xy 403.462996 -306.604341)
			(xy 403.501117 -306.573216) (xy 403.543738 -306.548609) (xy 403.589754 -306.531157) (xy 403.637973 -306.521313)
			(xy 403.687148 -306.519332) (xy 403.736003 -306.525264) (xy 403.783274 -306.538956) (xy 403.827736 -306.560054)
			(xy 403.868239 -306.58801) (xy 403.903732 -306.622102) (xy 403.933297 -306.661446) (xy 403.956168 -306.705023)
			(xy 403.971752 -306.751704) (xy 403.979647 -306.800281) (xy 403.980142 -306.824888) (xy 404.31899 -306.824888)
			(xy 404.32295 -306.775834) (xy 404.334727 -306.72805) (xy 404.354018 -306.682774) (xy 404.380321 -306.641178)
			(xy 404.412956 -306.604341) (xy 404.451077 -306.573216) (xy 404.493698 -306.548609) (xy 404.539714 -306.531157)
			(xy 404.587933 -306.521313) (xy 404.637108 -306.519332) (xy 404.685963 -306.525264) (xy 404.733234 -306.538956)
			(xy 404.777696 -306.560054) (xy 404.818199 -306.58801) (xy 404.853692 -306.622102) (xy 404.883257 -306.661446)
			(xy 404.906128 -306.705023) (xy 404.921712 -306.751704) (xy 404.929607 -306.800281) (xy 404.930102 -306.824888)
			(xy 405.269204 -306.824888) (xy 405.273164 -306.775834) (xy 405.284941 -306.72805) (xy 405.304232 -306.682774)
			(xy 405.330535 -306.641178) (xy 405.36317 -306.604341) (xy 405.401291 -306.573216) (xy 405.443912 -306.548609)
			(xy 405.489928 -306.531157) (xy 405.538147 -306.521313) (xy 405.587322 -306.519332) (xy 405.636177 -306.525264)
			(xy 405.683448 -306.538956) (xy 405.72791 -306.560054) (xy 405.768413 -306.58801) (xy 405.803906 -306.622102)
			(xy 405.833471 -306.661446) (xy 405.856342 -306.705023) (xy 405.871926 -306.751704) (xy 405.879821 -306.800281)
			(xy 405.880316 -306.824888) (xy 406.219164 -306.824888) (xy 406.223124 -306.775834) (xy 406.234901 -306.72805)
			(xy 406.254192 -306.682774) (xy 406.280495 -306.641178) (xy 406.31313 -306.604341) (xy 406.351251 -306.573216)
			(xy 406.393872 -306.548609) (xy 406.439888 -306.531157) (xy 406.488107 -306.521313) (xy 406.537282 -306.519332)
			(xy 406.586137 -306.525264) (xy 406.633408 -306.538956) (xy 406.67787 -306.560054) (xy 406.718373 -306.58801)
			(xy 406.753866 -306.622102) (xy 406.783431 -306.661446) (xy 406.806302 -306.705023) (xy 406.821886 -306.751704)
			(xy 406.829781 -306.800281) (xy 406.830276 -306.824888) (xy 408.119084 -306.824888) (xy 408.123044 -306.775834)
			(xy 408.134821 -306.72805) (xy 408.154112 -306.682774) (xy 408.180415 -306.641178) (xy 408.21305 -306.604341)
			(xy 408.251171 -306.573216) (xy 408.293792 -306.548609) (xy 408.339808 -306.531157) (xy 408.388027 -306.521313)
			(xy 408.437202 -306.519332) (xy 408.486057 -306.525264) (xy 408.533328 -306.538956) (xy 408.57779 -306.560054)
			(xy 408.618293 -306.58801) (xy 408.653786 -306.622102) (xy 408.683351 -306.661446) (xy 408.706222 -306.705023)
			(xy 408.721806 -306.751704) (xy 408.729701 -306.800281) (xy 408.730196 -306.824888) (xy 409.069044 -306.824888)
			(xy 409.073004 -306.775834) (xy 409.084781 -306.72805) (xy 409.104072 -306.682774) (xy 409.130375 -306.641178)
			(xy 409.16301 -306.604341) (xy 409.201131 -306.573216) (xy 409.243752 -306.548609) (xy 409.289768 -306.531157)
			(xy 409.337987 -306.521313) (xy 409.387162 -306.519332) (xy 409.436017 -306.525264) (xy 409.483288 -306.538956)
			(xy 409.52775 -306.560054) (xy 409.568253 -306.58801) (xy 409.603746 -306.622102) (xy 409.633311 -306.661446)
			(xy 409.656182 -306.705023) (xy 409.671766 -306.751704) (xy 409.679661 -306.800281) (xy 409.680156 -306.824888)
			(xy 410.019004 -306.824888) (xy 410.022964 -306.775834) (xy 410.034741 -306.72805) (xy 410.054032 -306.682774)
			(xy 410.080335 -306.641178) (xy 410.11297 -306.604341) (xy 410.151091 -306.573216) (xy 410.193712 -306.548609)
			(xy 410.239728 -306.531157) (xy 410.287947 -306.521313) (xy 410.337122 -306.519332) (xy 410.385977 -306.525264)
			(xy 410.433248 -306.538956) (xy 410.47771 -306.560054) (xy 410.518213 -306.58801) (xy 410.553706 -306.622102)
			(xy 410.583271 -306.661446) (xy 410.606142 -306.705023) (xy 410.621726 -306.751704) (xy 410.629621 -306.800281)
			(xy 410.630116 -306.824888) (xy 410.969218 -306.824888) (xy 410.973178 -306.775834) (xy 410.984955 -306.72805)
			(xy 411.004246 -306.682774) (xy 411.030549 -306.641178) (xy 411.063184 -306.604341) (xy 411.101305 -306.573216)
			(xy 411.143926 -306.548609) (xy 411.189942 -306.531157) (xy 411.238161 -306.521313) (xy 411.287336 -306.519332)
			(xy 411.336191 -306.525264) (xy 411.383462 -306.538956) (xy 411.427924 -306.560054) (xy 411.468427 -306.58801)
			(xy 411.50392 -306.622102) (xy 411.533485 -306.661446) (xy 411.556356 -306.705023) (xy 411.57194 -306.751704)
			(xy 411.579835 -306.800281) (xy 411.58033 -306.824888) (xy 411.919178 -306.824888) (xy 411.923138 -306.775834)
			(xy 411.934915 -306.72805) (xy 411.954206 -306.682774) (xy 411.980509 -306.641178) (xy 412.013144 -306.604341)
			(xy 412.051265 -306.573216) (xy 412.093886 -306.548609) (xy 412.139902 -306.531157) (xy 412.188121 -306.521313)
			(xy 412.237296 -306.519332) (xy 412.286151 -306.525264) (xy 412.333422 -306.538956) (xy 412.377884 -306.560054)
			(xy 412.418387 -306.58801) (xy 412.45388 -306.622102) (xy 412.483445 -306.661446) (xy 412.506316 -306.705023)
			(xy 412.5219 -306.751704) (xy 412.529795 -306.800281) (xy 412.53029 -306.824888) (xy 412.869138 -306.824888)
			(xy 412.873098 -306.775834) (xy 412.884875 -306.72805) (xy 412.904166 -306.682774) (xy 412.930469 -306.641178)
			(xy 412.963104 -306.604341) (xy 413.001225 -306.573216) (xy 413.043846 -306.548609) (xy 413.089862 -306.531157)
			(xy 413.138081 -306.521313) (xy 413.187256 -306.519332) (xy 413.236111 -306.525264) (xy 413.283382 -306.538956)
			(xy 413.327844 -306.560054) (xy 413.368347 -306.58801) (xy 413.40384 -306.622102) (xy 413.433405 -306.661446)
			(xy 413.456276 -306.705023) (xy 413.47186 -306.751704) (xy 413.479755 -306.800281) (xy 413.48025 -306.824888)
			(xy 413.819098 -306.824888) (xy 413.823058 -306.775834) (xy 413.834835 -306.72805) (xy 413.854126 -306.682774)
			(xy 413.880429 -306.641178) (xy 413.913064 -306.604341) (xy 413.951185 -306.573216) (xy 413.993806 -306.548609)
			(xy 414.039822 -306.531157) (xy 414.088041 -306.521313) (xy 414.137216 -306.519332) (xy 414.186071 -306.525264)
			(xy 414.233342 -306.538956) (xy 414.277804 -306.560054) (xy 414.318307 -306.58801) (xy 414.3538 -306.622102)
			(xy 414.383365 -306.661446) (xy 414.406236 -306.705023) (xy 414.42182 -306.751704) (xy 414.429715 -306.800281)
			(xy 414.43021 -306.824888) (xy 414.769058 -306.824888) (xy 414.773018 -306.775834) (xy 414.784795 -306.72805)
			(xy 414.804086 -306.682774) (xy 414.830389 -306.641178) (xy 414.863024 -306.604341) (xy 414.901145 -306.573216)
			(xy 414.943766 -306.548609) (xy 414.989782 -306.531157) (xy 415.038001 -306.521313) (xy 415.087176 -306.519332)
			(xy 415.136031 -306.525264) (xy 415.183302 -306.538956) (xy 415.227764 -306.560054) (xy 415.268267 -306.58801)
			(xy 415.30376 -306.622102) (xy 415.333325 -306.661446) (xy 415.356196 -306.705023) (xy 415.37178 -306.751704)
			(xy 415.379675 -306.800281) (xy 415.38017 -306.824888) (xy 415.719018 -306.824888) (xy 415.722978 -306.775834)
			(xy 415.734755 -306.72805) (xy 415.754046 -306.682774) (xy 415.780349 -306.641178) (xy 415.812984 -306.604341)
			(xy 415.851105 -306.573216) (xy 415.893726 -306.548609) (xy 415.939742 -306.531157) (xy 415.987961 -306.521313)
			(xy 416.037136 -306.519332) (xy 416.085991 -306.525264) (xy 416.133262 -306.538956) (xy 416.177724 -306.560054)
			(xy 416.218227 -306.58801) (xy 416.25372 -306.622102) (xy 416.283285 -306.661446) (xy 416.306156 -306.705023)
			(xy 416.32174 -306.751704) (xy 416.329635 -306.800281) (xy 416.33013 -306.824888) (xy 416.668978 -306.824888)
			(xy 416.672938 -306.775834) (xy 416.684715 -306.72805) (xy 416.704006 -306.682774) (xy 416.730309 -306.641178)
			(xy 416.762944 -306.604341) (xy 416.801065 -306.573216) (xy 416.843686 -306.548609) (xy 416.889702 -306.531157)
			(xy 416.937921 -306.521313) (xy 416.987096 -306.519332) (xy 417.035951 -306.525264) (xy 417.083222 -306.538956)
			(xy 417.127684 -306.560054) (xy 417.168187 -306.58801) (xy 417.20368 -306.622102) (xy 417.233245 -306.661446)
			(xy 417.256116 -306.705023) (xy 417.2717 -306.751704) (xy 417.279595 -306.800281) (xy 417.28009 -306.824888)
			(xy 417.279595 -306.849495) (xy 417.2717 -306.898072) (xy 417.256116 -306.944753) (xy 417.233245 -306.98833)
			(xy 417.20368 -307.027674) (xy 417.168187 -307.061766) (xy 417.127684 -307.089722) (xy 417.083222 -307.11082)
			(xy 417.035951 -307.124512) (xy 416.987096 -307.130444) (xy 416.937921 -307.128463) (xy 416.889702 -307.118619)
			(xy 416.843686 -307.101167) (xy 416.801065 -307.07656) (xy 416.762944 -307.045435) (xy 416.730309 -307.008598)
			(xy 416.704006 -306.967002) (xy 416.684715 -306.921726) (xy 416.672938 -306.873942) (xy 416.668978 -306.824888)
			(xy 416.33013 -306.824888) (xy 416.329635 -306.849495) (xy 416.32174 -306.898072) (xy 416.306156 -306.944753)
			(xy 416.283285 -306.98833) (xy 416.25372 -307.027674) (xy 416.218227 -307.061766) (xy 416.177724 -307.089722)
			(xy 416.133262 -307.11082) (xy 416.085991 -307.124512) (xy 416.037136 -307.130444) (xy 415.987961 -307.128463)
			(xy 415.939742 -307.118619) (xy 415.893726 -307.101167) (xy 415.851105 -307.07656) (xy 415.812984 -307.045435)
			(xy 415.780349 -307.008598) (xy 415.754046 -306.967002) (xy 415.734755 -306.921726) (xy 415.722978 -306.873942)
			(xy 415.719018 -306.824888) (xy 415.38017 -306.824888) (xy 415.379675 -306.849495) (xy 415.37178 -306.898072)
			(xy 415.356196 -306.944753) (xy 415.333325 -306.98833) (xy 415.30376 -307.027674) (xy 415.268267 -307.061766)
			(xy 415.227764 -307.089722) (xy 415.183302 -307.11082) (xy 415.136031 -307.124512) (xy 415.087176 -307.130444)
			(xy 415.038001 -307.128463) (xy 414.989782 -307.118619) (xy 414.943766 -307.101167) (xy 414.901145 -307.07656)
			(xy 414.863024 -307.045435) (xy 414.830389 -307.008598) (xy 414.804086 -306.967002) (xy 414.784795 -306.921726)
			(xy 414.773018 -306.873942) (xy 414.769058 -306.824888) (xy 414.43021 -306.824888) (xy 414.429715 -306.849495)
			(xy 414.42182 -306.898072) (xy 414.406236 -306.944753) (xy 414.383365 -306.98833) (xy 414.3538 -307.027674)
			(xy 414.318307 -307.061766) (xy 414.277804 -307.089722) (xy 414.233342 -307.11082) (xy 414.186071 -307.124512)
			(xy 414.137216 -307.130444) (xy 414.088041 -307.128463) (xy 414.039822 -307.118619) (xy 413.993806 -307.101167)
			(xy 413.951185 -307.07656) (xy 413.913064 -307.045435) (xy 413.880429 -307.008598) (xy 413.854126 -306.967002)
			(xy 413.834835 -306.921726) (xy 413.823058 -306.873942) (xy 413.819098 -306.824888) (xy 413.48025 -306.824888)
			(xy 413.479755 -306.849495) (xy 413.47186 -306.898072) (xy 413.456276 -306.944753) (xy 413.433405 -306.98833)
			(xy 413.40384 -307.027674) (xy 413.368347 -307.061766) (xy 413.327844 -307.089722) (xy 413.283382 -307.11082)
			(xy 413.236111 -307.124512) (xy 413.187256 -307.130444) (xy 413.138081 -307.128463) (xy 413.089862 -307.118619)
			(xy 413.043846 -307.101167) (xy 413.001225 -307.07656) (xy 412.963104 -307.045435) (xy 412.930469 -307.008598)
			(xy 412.904166 -306.967002) (xy 412.884875 -306.921726) (xy 412.873098 -306.873942) (xy 412.869138 -306.824888)
			(xy 412.53029 -306.824888) (xy 412.529795 -306.849495) (xy 412.5219 -306.898072) (xy 412.506316 -306.944753)
			(xy 412.483445 -306.98833) (xy 412.45388 -307.027674) (xy 412.418387 -307.061766) (xy 412.377884 -307.089722)
			(xy 412.333422 -307.11082) (xy 412.286151 -307.124512) (xy 412.237296 -307.130444) (xy 412.188121 -307.128463)
			(xy 412.139902 -307.118619) (xy 412.093886 -307.101167) (xy 412.051265 -307.07656) (xy 412.013144 -307.045435)
			(xy 411.980509 -307.008598) (xy 411.954206 -306.967002) (xy 411.934915 -306.921726) (xy 411.923138 -306.873942)
			(xy 411.919178 -306.824888) (xy 411.58033 -306.824888) (xy 411.579835 -306.849495) (xy 411.57194 -306.898072)
			(xy 411.556356 -306.944753) (xy 411.533485 -306.98833) (xy 411.50392 -307.027674) (xy 411.468427 -307.061766)
			(xy 411.427924 -307.089722) (xy 411.383462 -307.11082) (xy 411.336191 -307.124512) (xy 411.287336 -307.130444)
			(xy 411.238161 -307.128463) (xy 411.189942 -307.118619) (xy 411.143926 -307.101167) (xy 411.101305 -307.07656)
			(xy 411.063184 -307.045435) (xy 411.030549 -307.008598) (xy 411.004246 -306.967002) (xy 410.984955 -306.921726)
			(xy 410.973178 -306.873942) (xy 410.969218 -306.824888) (xy 410.630116 -306.824888) (xy 410.629621 -306.849495)
			(xy 410.621726 -306.898072) (xy 410.606142 -306.944753) (xy 410.583271 -306.98833) (xy 410.553706 -307.027674)
			(xy 410.518213 -307.061766) (xy 410.47771 -307.089722) (xy 410.433248 -307.11082) (xy 410.385977 -307.124512)
			(xy 410.337122 -307.130444) (xy 410.287947 -307.128463) (xy 410.239728 -307.118619) (xy 410.193712 -307.101167)
			(xy 410.151091 -307.07656) (xy 410.11297 -307.045435) (xy 410.080335 -307.008598) (xy 410.054032 -306.967002)
			(xy 410.034741 -306.921726) (xy 410.022964 -306.873942) (xy 410.019004 -306.824888) (xy 409.680156 -306.824888)
			(xy 409.679661 -306.849495) (xy 409.671766 -306.898072) (xy 409.656182 -306.944753) (xy 409.633311 -306.98833)
			(xy 409.603746 -307.027674) (xy 409.568253 -307.061766) (xy 409.52775 -307.089722) (xy 409.483288 -307.11082)
			(xy 409.436017 -307.124512) (xy 409.387162 -307.130444) (xy 409.337987 -307.128463) (xy 409.289768 -307.118619)
			(xy 409.243752 -307.101167) (xy 409.201131 -307.07656) (xy 409.16301 -307.045435) (xy 409.130375 -307.008598)
			(xy 409.104072 -306.967002) (xy 409.084781 -306.921726) (xy 409.073004 -306.873942) (xy 409.069044 -306.824888)
			(xy 408.730196 -306.824888) (xy 408.729701 -306.849495) (xy 408.721806 -306.898072) (xy 408.706222 -306.944753)
			(xy 408.683351 -306.98833) (xy 408.653786 -307.027674) (xy 408.618293 -307.061766) (xy 408.57779 -307.089722)
			(xy 408.533328 -307.11082) (xy 408.486057 -307.124512) (xy 408.437202 -307.130444) (xy 408.388027 -307.128463)
			(xy 408.339808 -307.118619) (xy 408.293792 -307.101167) (xy 408.251171 -307.07656) (xy 408.21305 -307.045435)
			(xy 408.180415 -307.008598) (xy 408.154112 -306.967002) (xy 408.134821 -306.921726) (xy 408.123044 -306.873942)
			(xy 408.119084 -306.824888) (xy 406.830276 -306.824888) (xy 406.829781 -306.849495) (xy 406.821886 -306.898072)
			(xy 406.806302 -306.944753) (xy 406.783431 -306.98833) (xy 406.753866 -307.027674) (xy 406.718373 -307.061766)
			(xy 406.67787 -307.089722) (xy 406.633408 -307.11082) (xy 406.586137 -307.124512) (xy 406.537282 -307.130444)
			(xy 406.488107 -307.128463) (xy 406.439888 -307.118619) (xy 406.393872 -307.101167) (xy 406.351251 -307.07656)
			(xy 406.31313 -307.045435) (xy 406.280495 -307.008598) (xy 406.254192 -306.967002) (xy 406.234901 -306.921726)
			(xy 406.223124 -306.873942) (xy 406.219164 -306.824888) (xy 405.880316 -306.824888) (xy 405.879821 -306.849495)
			(xy 405.871926 -306.898072) (xy 405.856342 -306.944753) (xy 405.833471 -306.98833) (xy 405.803906 -307.027674)
			(xy 405.768413 -307.061766) (xy 405.72791 -307.089722) (xy 405.683448 -307.11082) (xy 405.636177 -307.124512)
			(xy 405.587322 -307.130444) (xy 405.538147 -307.128463) (xy 405.489928 -307.118619) (xy 405.443912 -307.101167)
			(xy 405.401291 -307.07656) (xy 405.36317 -307.045435) (xy 405.330535 -307.008598) (xy 405.304232 -306.967002)
			(xy 405.284941 -306.921726) (xy 405.273164 -306.873942) (xy 405.269204 -306.824888) (xy 404.930102 -306.824888)
			(xy 404.929607 -306.849495) (xy 404.921712 -306.898072) (xy 404.906128 -306.944753) (xy 404.883257 -306.98833)
			(xy 404.853692 -307.027674) (xy 404.818199 -307.061766) (xy 404.777696 -307.089722) (xy 404.733234 -307.11082)
			(xy 404.685963 -307.124512) (xy 404.637108 -307.130444) (xy 404.587933 -307.128463) (xy 404.539714 -307.118619)
			(xy 404.493698 -307.101167) (xy 404.451077 -307.07656) (xy 404.412956 -307.045435) (xy 404.380321 -307.008598)
			(xy 404.354018 -306.967002) (xy 404.334727 -306.921726) (xy 404.32295 -306.873942) (xy 404.31899 -306.824888)
			(xy 403.980142 -306.824888) (xy 403.979647 -306.849495) (xy 403.971752 -306.898072) (xy 403.956168 -306.944753)
			(xy 403.933297 -306.98833) (xy 403.903732 -307.027674) (xy 403.868239 -307.061766) (xy 403.827736 -307.089722)
			(xy 403.783274 -307.11082) (xy 403.736003 -307.124512) (xy 403.687148 -307.130444) (xy 403.637973 -307.128463)
			(xy 403.589754 -307.118619) (xy 403.543738 -307.101167) (xy 403.501117 -307.07656) (xy 403.462996 -307.045435)
			(xy 403.430361 -307.008598) (xy 403.404058 -306.967002) (xy 403.384767 -306.921726) (xy 403.37299 -306.873942)
			(xy 403.36903 -306.824888) (xy 403.030182 -306.824888) (xy 403.029687 -306.849495) (xy 403.021792 -306.898072)
			(xy 403.006208 -306.944753) (xy 402.983337 -306.98833) (xy 402.953772 -307.027674) (xy 402.918279 -307.061766)
			(xy 402.877776 -307.089722) (xy 402.833314 -307.11082) (xy 402.786043 -307.124512) (xy 402.737188 -307.130444)
			(xy 402.688013 -307.128463) (xy 402.639794 -307.118619) (xy 402.593778 -307.101167) (xy 402.551157 -307.07656)
			(xy 402.513036 -307.045435) (xy 402.480401 -307.008598) (xy 402.454098 -306.967002) (xy 402.434807 -306.921726)
			(xy 402.42303 -306.873942) (xy 402.41907 -306.824888) (xy 402.080222 -306.824888) (xy 402.079727 -306.849495)
			(xy 402.071832 -306.898072) (xy 402.056248 -306.944753) (xy 402.033377 -306.98833) (xy 402.003812 -307.027674)
			(xy 401.968319 -307.061766) (xy 401.927816 -307.089722) (xy 401.883354 -307.11082) (xy 401.836083 -307.124512)
			(xy 401.787228 -307.130444) (xy 401.738053 -307.128463) (xy 401.689834 -307.118619) (xy 401.643818 -307.101167)
			(xy 401.601197 -307.07656) (xy 401.563076 -307.045435) (xy 401.530441 -307.008598) (xy 401.504138 -306.967002)
			(xy 401.484847 -306.921726) (xy 401.47307 -306.873942) (xy 401.46911 -306.824888) (xy 401.130262 -306.824888)
			(xy 401.129767 -306.849495) (xy 401.121872 -306.898072) (xy 401.106288 -306.944753) (xy 401.083417 -306.98833)
			(xy 401.053852 -307.027674) (xy 401.018359 -307.061766) (xy 400.977856 -307.089722) (xy 400.933394 -307.11082)
			(xy 400.886123 -307.124512) (xy 400.837268 -307.130444) (xy 400.788093 -307.128463) (xy 400.739874 -307.118619)
			(xy 400.693858 -307.101167) (xy 400.651237 -307.07656) (xy 400.613116 -307.045435) (xy 400.580481 -307.008598)
			(xy 400.554178 -306.967002) (xy 400.534887 -306.921726) (xy 400.52311 -306.873942) (xy 400.51915 -306.824888)
			(xy 400.180302 -306.824888) (xy 400.179807 -306.849495) (xy 400.171912 -306.898072) (xy 400.156328 -306.944753)
			(xy 400.133457 -306.98833) (xy 400.103892 -307.027674) (xy 400.068399 -307.061766) (xy 400.027896 -307.089722)
			(xy 399.983434 -307.11082) (xy 399.936163 -307.124512) (xy 399.887308 -307.130444) (xy 399.838133 -307.128463)
			(xy 399.789914 -307.118619) (xy 399.743898 -307.101167) (xy 399.701277 -307.07656) (xy 399.663156 -307.045435)
			(xy 399.630521 -307.008598) (xy 399.604218 -306.967002) (xy 399.584927 -306.921726) (xy 399.57315 -306.873942)
			(xy 399.56919 -306.824888) (xy 399.230342 -306.824888) (xy 399.229847 -306.849495) (xy 399.221952 -306.898072)
			(xy 399.206368 -306.944753) (xy 399.183497 -306.98833) (xy 399.153932 -307.027674) (xy 399.118439 -307.061766)
			(xy 399.077936 -307.089722) (xy 399.033474 -307.11082) (xy 398.986203 -307.124512) (xy 398.937348 -307.130444)
			(xy 398.888173 -307.128463) (xy 398.839954 -307.118619) (xy 398.793938 -307.101167) (xy 398.751317 -307.07656)
			(xy 398.713196 -307.045435) (xy 398.680561 -307.008598) (xy 398.654258 -306.967002) (xy 398.634967 -306.921726)
			(xy 398.62319 -306.873942) (xy 398.61923 -306.824888) (xy 398.280128 -306.824888) (xy 398.279633 -306.849495)
			(xy 398.271738 -306.898072) (xy 398.256154 -306.944753) (xy 398.233283 -306.98833) (xy 398.203718 -307.027674)
			(xy 398.168225 -307.061766) (xy 398.127722 -307.089722) (xy 398.08326 -307.11082) (xy 398.035989 -307.124512)
			(xy 397.987134 -307.130444) (xy 397.937959 -307.128463) (xy 397.88974 -307.118619) (xy 397.843724 -307.101167)
			(xy 397.801103 -307.07656) (xy 397.762982 -307.045435) (xy 397.730347 -307.008598) (xy 397.704044 -306.967002)
			(xy 397.684753 -306.921726) (xy 397.672976 -306.873942) (xy 397.669016 -306.824888) (xy 397.330168 -306.824888)
			(xy 397.329673 -306.849495) (xy 397.321778 -306.898072) (xy 397.306194 -306.944753) (xy 397.283323 -306.98833)
			(xy 397.253758 -307.027674) (xy 397.218265 -307.061766) (xy 397.177762 -307.089722) (xy 397.1333 -307.11082)
			(xy 397.086029 -307.124512) (xy 397.037174 -307.130444) (xy 396.987999 -307.128463) (xy 396.93978 -307.118619)
			(xy 396.893764 -307.101167) (xy 396.851143 -307.07656) (xy 396.813022 -307.045435) (xy 396.780387 -307.008598)
			(xy 396.754084 -306.967002) (xy 396.734793 -306.921726) (xy 396.723016 -306.873942) (xy 396.719056 -306.824888)
			(xy 396.380208 -306.824888) (xy 396.379713 -306.849495) (xy 396.371818 -306.898072) (xy 396.356234 -306.944753)
			(xy 396.333363 -306.98833) (xy 396.303798 -307.027674) (xy 396.268305 -307.061766) (xy 396.227802 -307.089722)
			(xy 396.18334 -307.11082) (xy 396.136069 -307.124512) (xy 396.087214 -307.130444) (xy 396.038039 -307.128463)
			(xy 395.98982 -307.118619) (xy 395.943804 -307.101167) (xy 395.901183 -307.07656) (xy 395.863062 -307.045435)
			(xy 395.830427 -307.008598) (xy 395.804124 -306.967002) (xy 395.784833 -306.921726) (xy 395.773056 -306.873942)
			(xy 395.769096 -306.824888) (xy 395.430248 -306.824888) (xy 395.429753 -306.849495) (xy 395.421858 -306.898072)
			(xy 395.406274 -306.944753) (xy 395.383403 -306.98833) (xy 395.353838 -307.027674) (xy 395.318345 -307.061766)
			(xy 395.277842 -307.089722) (xy 395.23338 -307.11082) (xy 395.186109 -307.124512) (xy 395.137254 -307.130444)
			(xy 395.088079 -307.128463) (xy 395.03986 -307.118619) (xy 394.993844 -307.101167) (xy 394.951223 -307.07656)
			(xy 394.913102 -307.045435) (xy 394.880467 -307.008598) (xy 394.854164 -306.967002) (xy 394.834873 -306.921726)
			(xy 394.823096 -306.873942) (xy 394.819136 -306.824888) (xy 378.783741 -306.824888) (xy 378.780301 -306.84826)
			(xy 378.764233 -306.901667) (xy 378.740561 -306.952164) (xy 378.709788 -306.998677) (xy 378.672571 -307.040214)
			(xy 378.629703 -307.075889) (xy 378.582097 -307.104943) (xy 378.530768 -307.126755) (xy 378.476811 -307.140861)
			(xy 378.421374 -307.146961) (xy 378.36564 -307.144924) (xy 378.310797 -307.134794) (xy 378.258013 -307.116787)
			(xy 378.208413 -307.091286) (xy 378.163055 -307.058835) (xy 378.122906 -307.020126) (xy 378.08882 -306.975983)
			(xy 378.061524 -306.927348) (xy 378.041601 -306.875257) (xy 378.029475 -306.82082) (xy 378.025404 -306.765198)
			(xy 364.817933 -306.765198) (xy 364.805847 -306.791515) (xy 364.77612 -306.837483) (xy 364.758478 -306.858416)
			(xy 364.752382 -306.865528) (xy 364.746032 -306.882546) (xy 364.746032 -306.96789) (xy 364.752382 -306.984908)
			(xy 364.758478 -306.99202) (xy 364.776136 -307.012939) (xy 364.80586 -307.058909) (xy 364.828704 -307.108658)
			(xy 364.844198 -307.161162) (xy 364.852025 -307.215342) (xy 364.852024 -307.240178) (xy 380.16002 -307.240178)
			(xy 380.164091 -307.184556) (xy 380.176217 -307.130119) (xy 380.19614 -307.078028) (xy 380.223436 -307.029393)
			(xy 380.257522 -306.98525) (xy 380.297671 -306.946541) (xy 380.343029 -306.91409) (xy 380.392629 -306.888589)
			(xy 380.445413 -306.870582) (xy 380.500256 -306.860452) (xy 380.55599 -306.858415) (xy 380.611427 -306.864515)
			(xy 380.665384 -306.878621) (xy 380.716713 -306.900433) (xy 380.764319 -306.929487) (xy 380.807187 -306.965162)
			(xy 380.844404 -307.006699) (xy 380.875177 -307.053212) (xy 380.898849 -307.103709) (xy 380.914917 -307.157116)
			(xy 380.923037 -307.212292) (xy 380.923546 -307.240178) (xy 380.923037 -307.268064) (xy 380.918357 -307.299868)
			(xy 384.844048 -307.299868) (xy 384.848008 -307.250814) (xy 384.859785 -307.20303) (xy 384.879076 -307.157754)
			(xy 384.905379 -307.116158) (xy 384.938014 -307.079321) (xy 384.976135 -307.048196) (xy 385.018756 -307.023589)
			(xy 385.064772 -307.006137) (xy 385.112991 -306.996293) (xy 385.162166 -306.994312) (xy 385.211021 -307.000244)
			(xy 385.258292 -307.013936) (xy 385.302754 -307.035034) (xy 385.343257 -307.06299) (xy 385.37875 -307.097082)
			(xy 385.408315 -307.136426) (xy 385.431186 -307.180003) (xy 385.44677 -307.226684) (xy 385.454665 -307.275261)
			(xy 385.45516 -307.299868) (xy 385.794008 -307.299868) (xy 385.797968 -307.250814) (xy 385.809745 -307.20303)
			(xy 385.829036 -307.157754) (xy 385.855339 -307.116158) (xy 385.887974 -307.079321) (xy 385.926095 -307.048196)
			(xy 385.968716 -307.023589) (xy 386.014732 -307.006137) (xy 386.062951 -306.996293) (xy 386.112126 -306.994312)
			(xy 386.160981 -307.000244) (xy 386.208252 -307.013936) (xy 386.252714 -307.035034) (xy 386.293217 -307.06299)
			(xy 386.32871 -307.097082) (xy 386.358275 -307.136426) (xy 386.381146 -307.180003) (xy 386.39673 -307.226684)
			(xy 386.404625 -307.275261) (xy 386.40512 -307.299868) (xy 386.404625 -307.324475) (xy 386.404446 -307.325576)
			(xy 386.723378 -307.325576) (xy 386.723378 -307.27416) (xy 386.731421 -307.223378) (xy 386.747309 -307.174479)
			(xy 386.770652 -307.128667) (xy 386.800873 -307.087071) (xy 386.837229 -307.050715) (xy 386.878825 -307.020494)
			(xy 386.924637 -306.997151) (xy 386.973536 -306.981263) (xy 387.024318 -306.97322) (xy 387.075734 -306.97322)
			(xy 387.126516 -306.981263) (xy 387.175415 -306.997151) (xy 387.221227 -307.020494) (xy 387.262823 -307.050715)
			(xy 387.299179 -307.087071) (xy 387.3294 -307.128667) (xy 387.352743 -307.174479) (xy 387.368631 -307.223378)
			(xy 387.376674 -307.27416) (xy 387.377178 -307.299868) (xy 387.376674 -307.325576) (xy 387.673338 -307.325576)
			(xy 387.673338 -307.27416) (xy 387.681381 -307.223378) (xy 387.697269 -307.174479) (xy 387.720612 -307.128667)
			(xy 387.750833 -307.087071) (xy 387.787189 -307.050715) (xy 387.828785 -307.020494) (xy 387.874597 -306.997151)
			(xy 387.923496 -306.981263) (xy 387.974278 -306.97322) (xy 388.025694 -306.97322) (xy 388.076476 -306.981263)
			(xy 388.125375 -306.997151) (xy 388.171187 -307.020494) (xy 388.212783 -307.050715) (xy 388.249139 -307.087071)
			(xy 388.27936 -307.128667) (xy 388.302703 -307.174479) (xy 388.318591 -307.223378) (xy 388.326634 -307.27416)
			(xy 388.327138 -307.299868) (xy 388.644142 -307.299868) (xy 388.648102 -307.250814) (xy 388.659879 -307.20303)
			(xy 388.67917 -307.157754) (xy 388.705473 -307.116158) (xy 388.738108 -307.079321) (xy 388.776229 -307.048196)
			(xy 388.81885 -307.023589) (xy 388.864866 -307.006137) (xy 388.913085 -306.996293) (xy 388.96226 -306.994312)
			(xy 389.011115 -307.000244) (xy 389.058386 -307.013936) (xy 389.102848 -307.035034) (xy 389.143351 -307.06299)
			(xy 389.178844 -307.097082) (xy 389.208409 -307.136426) (xy 389.23128 -307.180003) (xy 389.246864 -307.226684)
			(xy 389.254759 -307.275261) (xy 389.255254 -307.299868) (xy 389.254759 -307.324475) (xy 389.25458 -307.325576)
			(xy 389.573258 -307.325576) (xy 389.573258 -307.27416) (xy 389.581301 -307.223378) (xy 389.597189 -307.174479)
			(xy 389.620532 -307.128667) (xy 389.650753 -307.087071) (xy 389.687109 -307.050715) (xy 389.728705 -307.020494)
			(xy 389.774517 -306.997151) (xy 389.823416 -306.981263) (xy 389.874198 -306.97322) (xy 389.925614 -306.97322)
			(xy 389.976396 -306.981263) (xy 390.025295 -306.997151) (xy 390.071107 -307.020494) (xy 390.112703 -307.050715)
			(xy 390.149059 -307.087071) (xy 390.17928 -307.128667) (xy 390.202623 -307.174479) (xy 390.218511 -307.223378)
			(xy 390.226554 -307.27416) (xy 390.227058 -307.299868) (xy 390.226554 -307.325576) (xy 390.523218 -307.325576)
			(xy 390.523218 -307.27416) (xy 390.531261 -307.223378) (xy 390.547149 -307.174479) (xy 390.570492 -307.128667)
			(xy 390.600713 -307.087071) (xy 390.637069 -307.050715) (xy 390.678665 -307.020494) (xy 390.724477 -306.997151)
			(xy 390.773376 -306.981263) (xy 390.824158 -306.97322) (xy 390.875574 -306.97322) (xy 390.926356 -306.981263)
			(xy 390.975255 -306.997151) (xy 391.021067 -307.020494) (xy 391.062663 -307.050715) (xy 391.099019 -307.087071)
			(xy 391.12924 -307.128667) (xy 391.152583 -307.174479) (xy 391.168471 -307.223378) (xy 391.176514 -307.27416)
			(xy 391.177018 -307.299868) (xy 391.494022 -307.299868) (xy 391.497982 -307.250814) (xy 391.509759 -307.20303)
			(xy 391.52905 -307.157754) (xy 391.555353 -307.116158) (xy 391.587988 -307.079321) (xy 391.626109 -307.048196)
			(xy 391.66873 -307.023589) (xy 391.714746 -307.006137) (xy 391.762965 -306.996293) (xy 391.81214 -306.994312)
			(xy 391.860995 -307.000244) (xy 391.908266 -307.013936) (xy 391.952728 -307.035034) (xy 391.993231 -307.06299)
			(xy 392.028724 -307.097082) (xy 392.058289 -307.136426) (xy 392.08116 -307.180003) (xy 392.096744 -307.226684)
			(xy 392.104639 -307.275261) (xy 392.105134 -307.299868) (xy 392.443982 -307.299868) (xy 392.447942 -307.250814)
			(xy 392.459719 -307.20303) (xy 392.47901 -307.157754) (xy 392.505313 -307.116158) (xy 392.537948 -307.079321)
			(xy 392.576069 -307.048196) (xy 392.61869 -307.023589) (xy 392.664706 -307.006137) (xy 392.712925 -306.996293)
			(xy 392.7621 -306.994312) (xy 392.810955 -307.000244) (xy 392.858226 -307.013936) (xy 392.902688 -307.035034)
			(xy 392.943191 -307.06299) (xy 392.978684 -307.097082) (xy 393.008249 -307.136426) (xy 393.03112 -307.180003)
			(xy 393.046704 -307.226684) (xy 393.054599 -307.275261) (xy 393.055094 -307.299868) (xy 393.394196 -307.299868)
			(xy 393.398156 -307.250814) (xy 393.409933 -307.20303) (xy 393.429224 -307.157754) (xy 393.455527 -307.116158)
			(xy 393.488162 -307.079321) (xy 393.526283 -307.048196) (xy 393.568904 -307.023589) (xy 393.61492 -307.006137)
			(xy 393.663139 -306.996293) (xy 393.712314 -306.994312) (xy 393.761169 -307.000244) (xy 393.80844 -307.013936)
			(xy 393.852902 -307.035034) (xy 393.893405 -307.06299) (xy 393.928898 -307.097082) (xy 393.958463 -307.136426)
			(xy 393.981334 -307.180003) (xy 393.996918 -307.226684) (xy 394.004813 -307.275261) (xy 394.005308 -307.299868)
			(xy 394.004813 -307.324475) (xy 393.996918 -307.373052) (xy 393.981334 -307.419733) (xy 393.958463 -307.46331)
			(xy 393.928898 -307.502654) (xy 393.893405 -307.536746) (xy 393.852902 -307.564702) (xy 393.80844 -307.5858)
			(xy 393.761169 -307.599492) (xy 393.712314 -307.605424) (xy 393.663139 -307.603443) (xy 393.61492 -307.593599)
			(xy 393.568904 -307.576147) (xy 393.526283 -307.55154) (xy 393.488162 -307.520415) (xy 393.455527 -307.483578)
			(xy 393.429224 -307.441982) (xy 393.409933 -307.396706) (xy 393.398156 -307.348922) (xy 393.394196 -307.299868)
			(xy 393.055094 -307.299868) (xy 393.054599 -307.324475) (xy 393.046704 -307.373052) (xy 393.03112 -307.419733)
			(xy 393.008249 -307.46331) (xy 392.978684 -307.502654) (xy 392.943191 -307.536746) (xy 392.902688 -307.564702)
			(xy 392.858226 -307.5858) (xy 392.810955 -307.599492) (xy 392.7621 -307.605424) (xy 392.712925 -307.603443)
			(xy 392.664706 -307.593599) (xy 392.61869 -307.576147) (xy 392.576069 -307.55154) (xy 392.537948 -307.520415)
			(xy 392.505313 -307.483578) (xy 392.47901 -307.441982) (xy 392.459719 -307.396706) (xy 392.447942 -307.348922)
			(xy 392.443982 -307.299868) (xy 392.105134 -307.299868) (xy 392.104639 -307.324475) (xy 392.096744 -307.373052)
			(xy 392.08116 -307.419733) (xy 392.058289 -307.46331) (xy 392.028724 -307.502654) (xy 391.993231 -307.536746)
			(xy 391.952728 -307.564702) (xy 391.908266 -307.5858) (xy 391.860995 -307.599492) (xy 391.81214 -307.605424)
			(xy 391.762965 -307.603443) (xy 391.714746 -307.593599) (xy 391.66873 -307.576147) (xy 391.626109 -307.55154)
			(xy 391.587988 -307.520415) (xy 391.555353 -307.483578) (xy 391.52905 -307.441982) (xy 391.509759 -307.396706)
			(xy 391.497982 -307.348922) (xy 391.494022 -307.299868) (xy 391.177018 -307.299868) (xy 391.176514 -307.325576)
			(xy 391.168471 -307.376358) (xy 391.152583 -307.425257) (xy 391.12924 -307.471069) (xy 391.099019 -307.512665)
			(xy 391.062663 -307.549021) (xy 391.021067 -307.579242) (xy 390.975255 -307.602585) (xy 390.926356 -307.618473)
			(xy 390.875574 -307.626516) (xy 390.824158 -307.626516) (xy 390.773376 -307.618473) (xy 390.724477 -307.602585)
			(xy 390.678665 -307.579242) (xy 390.637069 -307.549021) (xy 390.600713 -307.512665) (xy 390.570492 -307.471069)
			(xy 390.547149 -307.425257) (xy 390.531261 -307.376358) (xy 390.523218 -307.325576) (xy 390.226554 -307.325576)
			(xy 390.218511 -307.376358) (xy 390.202623 -307.425257) (xy 390.17928 -307.471069) (xy 390.149059 -307.512665)
			(xy 390.112703 -307.549021) (xy 390.071107 -307.579242) (xy 390.025295 -307.602585) (xy 389.976396 -307.618473)
			(xy 389.925614 -307.626516) (xy 389.874198 -307.626516) (xy 389.823416 -307.618473) (xy 389.774517 -307.602585)
			(xy 389.728705 -307.579242) (xy 389.687109 -307.549021) (xy 389.650753 -307.512665) (xy 389.620532 -307.471069)
			(xy 389.597189 -307.425257) (xy 389.581301 -307.376358) (xy 389.573258 -307.325576) (xy 389.25458 -307.325576)
			(xy 389.246864 -307.373052) (xy 389.23128 -307.419733) (xy 389.208409 -307.46331) (xy 389.178844 -307.502654)
			(xy 389.143351 -307.536746) (xy 389.102848 -307.564702) (xy 389.058386 -307.5858) (xy 389.011115 -307.599492)
			(xy 388.96226 -307.605424) (xy 388.913085 -307.603443) (xy 388.864866 -307.593599) (xy 388.81885 -307.576147)
			(xy 388.776229 -307.55154) (xy 388.738108 -307.520415) (xy 388.705473 -307.483578) (xy 388.67917 -307.441982)
			(xy 388.659879 -307.396706) (xy 388.648102 -307.348922) (xy 388.644142 -307.299868) (xy 388.327138 -307.299868)
			(xy 388.326634 -307.325576) (xy 388.318591 -307.376358) (xy 388.302703 -307.425257) (xy 388.27936 -307.471069)
			(xy 388.249139 -307.512665) (xy 388.212783 -307.549021) (xy 388.171187 -307.579242) (xy 388.125375 -307.602585)
			(xy 388.076476 -307.618473) (xy 388.025694 -307.626516) (xy 387.974278 -307.626516) (xy 387.923496 -307.618473)
			(xy 387.874597 -307.602585) (xy 387.828785 -307.579242) (xy 387.787189 -307.549021) (xy 387.750833 -307.512665)
			(xy 387.720612 -307.471069) (xy 387.697269 -307.425257) (xy 387.681381 -307.376358) (xy 387.673338 -307.325576)
			(xy 387.376674 -307.325576) (xy 387.368631 -307.376358) (xy 387.352743 -307.425257) (xy 387.3294 -307.471069)
			(xy 387.299179 -307.512665) (xy 387.262823 -307.549021) (xy 387.221227 -307.579242) (xy 387.175415 -307.602585)
			(xy 387.126516 -307.618473) (xy 387.075734 -307.626516) (xy 387.024318 -307.626516) (xy 386.973536 -307.618473)
			(xy 386.924637 -307.602585) (xy 386.878825 -307.579242) (xy 386.837229 -307.549021) (xy 386.800873 -307.512665)
			(xy 386.770652 -307.471069) (xy 386.747309 -307.425257) (xy 386.731421 -307.376358) (xy 386.723378 -307.325576)
			(xy 386.404446 -307.325576) (xy 386.39673 -307.373052) (xy 386.381146 -307.419733) (xy 386.358275 -307.46331)
			(xy 386.32871 -307.502654) (xy 386.293217 -307.536746) (xy 386.252714 -307.564702) (xy 386.208252 -307.5858)
			(xy 386.160981 -307.599492) (xy 386.112126 -307.605424) (xy 386.062951 -307.603443) (xy 386.014732 -307.593599)
			(xy 385.968716 -307.576147) (xy 385.926095 -307.55154) (xy 385.887974 -307.520415) (xy 385.855339 -307.483578)
			(xy 385.829036 -307.441982) (xy 385.809745 -307.396706) (xy 385.797968 -307.348922) (xy 385.794008 -307.299868)
			(xy 385.45516 -307.299868) (xy 385.454665 -307.324475) (xy 385.44677 -307.373052) (xy 385.431186 -307.419733)
			(xy 385.408315 -307.46331) (xy 385.37875 -307.502654) (xy 385.343257 -307.536746) (xy 385.302754 -307.564702)
			(xy 385.258292 -307.5858) (xy 385.211021 -307.599492) (xy 385.162166 -307.605424) (xy 385.112991 -307.603443)
			(xy 385.064772 -307.593599) (xy 385.018756 -307.576147) (xy 384.976135 -307.55154) (xy 384.938014 -307.520415)
			(xy 384.905379 -307.483578) (xy 384.879076 -307.441982) (xy 384.859785 -307.396706) (xy 384.848008 -307.348922)
			(xy 384.844048 -307.299868) (xy 380.918357 -307.299868) (xy 380.914917 -307.32324) (xy 380.898849 -307.376647)
			(xy 380.875177 -307.427144) (xy 380.844404 -307.473657) (xy 380.807187 -307.515194) (xy 380.764319 -307.550869)
			(xy 380.716713 -307.579923) (xy 380.665384 -307.601735) (xy 380.611427 -307.615841) (xy 380.55599 -307.621941)
			(xy 380.500256 -307.619904) (xy 380.445413 -307.609774) (xy 380.392629 -307.591767) (xy 380.343029 -307.566266)
			(xy 380.297671 -307.533815) (xy 380.257522 -307.495106) (xy 380.223436 -307.450963) (xy 380.19614 -307.402328)
			(xy 380.176217 -307.350237) (xy 380.164091 -307.2958) (xy 380.16002 -307.240178) (xy 364.852024 -307.240178)
			(xy 364.852023 -307.270085) (xy 364.844193 -307.324265) (xy 364.828694 -307.376768) (xy 364.805847 -307.426515)
			(xy 364.77612 -307.472483) (xy 364.758478 -307.493416) (xy 364.752382 -307.500528) (xy 364.746032 -307.517546)
			(xy 364.746032 -307.60289) (xy 364.752382 -307.619908) (xy 364.758478 -307.62702) (xy 364.77609 -307.647974)
			(xy 364.805806 -307.693941) (xy 364.828648 -307.743682) (xy 364.837848 -307.774848) (xy 394.819136 -307.774848)
			(xy 394.823096 -307.725794) (xy 394.834873 -307.67801) (xy 394.854164 -307.632734) (xy 394.880467 -307.591138)
			(xy 394.913102 -307.554301) (xy 394.951223 -307.523176) (xy 394.993844 -307.498569) (xy 395.03986 -307.481117)
			(xy 395.088079 -307.471273) (xy 395.137254 -307.469292) (xy 395.186109 -307.475224) (xy 395.23338 -307.488916)
			(xy 395.277842 -307.510014) (xy 395.318345 -307.53797) (xy 395.353838 -307.572062) (xy 395.383403 -307.611406)
			(xy 395.406274 -307.654983) (xy 395.421858 -307.701664) (xy 395.429753 -307.750241) (xy 395.430248 -307.774848)
			(xy 395.769096 -307.774848) (xy 395.773056 -307.725794) (xy 395.784833 -307.67801) (xy 395.804124 -307.632734)
			(xy 395.830427 -307.591138) (xy 395.863062 -307.554301) (xy 395.901183 -307.523176) (xy 395.943804 -307.498569)
			(xy 395.98982 -307.481117) (xy 396.038039 -307.471273) (xy 396.087214 -307.469292) (xy 396.136069 -307.475224)
			(xy 396.18334 -307.488916) (xy 396.227802 -307.510014) (xy 396.268305 -307.53797) (xy 396.303798 -307.572062)
			(xy 396.333363 -307.611406) (xy 396.356234 -307.654983) (xy 396.371818 -307.701664) (xy 396.379713 -307.750241)
			(xy 396.380208 -307.774848) (xy 396.719056 -307.774848) (xy 396.723016 -307.725794) (xy 396.734793 -307.67801)
			(xy 396.754084 -307.632734) (xy 396.780387 -307.591138) (xy 396.813022 -307.554301) (xy 396.851143 -307.523176)
			(xy 396.893764 -307.498569) (xy 396.93978 -307.481117) (xy 396.987999 -307.471273) (xy 397.037174 -307.469292)
			(xy 397.086029 -307.475224) (xy 397.1333 -307.488916) (xy 397.177762 -307.510014) (xy 397.218265 -307.53797)
			(xy 397.253758 -307.572062) (xy 397.283323 -307.611406) (xy 397.306194 -307.654983) (xy 397.321778 -307.701664)
			(xy 397.329673 -307.750241) (xy 397.330168 -307.774848) (xy 397.669016 -307.774848) (xy 397.672976 -307.725794)
			(xy 397.684753 -307.67801) (xy 397.704044 -307.632734) (xy 397.730347 -307.591138) (xy 397.762982 -307.554301)
			(xy 397.801103 -307.523176) (xy 397.843724 -307.498569) (xy 397.88974 -307.481117) (xy 397.937959 -307.471273)
			(xy 397.987134 -307.469292) (xy 398.035989 -307.475224) (xy 398.08326 -307.488916) (xy 398.127722 -307.510014)
			(xy 398.168225 -307.53797) (xy 398.203718 -307.572062) (xy 398.233283 -307.611406) (xy 398.256154 -307.654983)
			(xy 398.271738 -307.701664) (xy 398.279633 -307.750241) (xy 398.280128 -307.774848) (xy 398.61923 -307.774848)
			(xy 398.62319 -307.725794) (xy 398.634967 -307.67801) (xy 398.654258 -307.632734) (xy 398.680561 -307.591138)
			(xy 398.713196 -307.554301) (xy 398.751317 -307.523176) (xy 398.793938 -307.498569) (xy 398.839954 -307.481117)
			(xy 398.888173 -307.471273) (xy 398.937348 -307.469292) (xy 398.986203 -307.475224) (xy 399.033474 -307.488916)
			(xy 399.077936 -307.510014) (xy 399.118439 -307.53797) (xy 399.153932 -307.572062) (xy 399.183497 -307.611406)
			(xy 399.206368 -307.654983) (xy 399.221952 -307.701664) (xy 399.229847 -307.750241) (xy 399.230342 -307.774848)
			(xy 399.56919 -307.774848) (xy 399.57315 -307.725794) (xy 399.584927 -307.67801) (xy 399.604218 -307.632734)
			(xy 399.630521 -307.591138) (xy 399.663156 -307.554301) (xy 399.701277 -307.523176) (xy 399.743898 -307.498569)
			(xy 399.789914 -307.481117) (xy 399.838133 -307.471273) (xy 399.887308 -307.469292) (xy 399.936163 -307.475224)
			(xy 399.983434 -307.488916) (xy 400.027896 -307.510014) (xy 400.068399 -307.53797) (xy 400.103892 -307.572062)
			(xy 400.133457 -307.611406) (xy 400.156328 -307.654983) (xy 400.171912 -307.701664) (xy 400.179807 -307.750241)
			(xy 400.180302 -307.774848) (xy 400.51915 -307.774848) (xy 400.52311 -307.725794) (xy 400.534887 -307.67801)
			(xy 400.554178 -307.632734) (xy 400.580481 -307.591138) (xy 400.613116 -307.554301) (xy 400.651237 -307.523176)
			(xy 400.693858 -307.498569) (xy 400.739874 -307.481117) (xy 400.788093 -307.471273) (xy 400.837268 -307.469292)
			(xy 400.886123 -307.475224) (xy 400.933394 -307.488916) (xy 400.977856 -307.510014) (xy 401.018359 -307.53797)
			(xy 401.053852 -307.572062) (xy 401.083417 -307.611406) (xy 401.106288 -307.654983) (xy 401.121872 -307.701664)
			(xy 401.129767 -307.750241) (xy 401.130262 -307.774848) (xy 401.46911 -307.774848) (xy 401.47307 -307.725794)
			(xy 401.484847 -307.67801) (xy 401.504138 -307.632734) (xy 401.530441 -307.591138) (xy 401.563076 -307.554301)
			(xy 401.601197 -307.523176) (xy 401.643818 -307.498569) (xy 401.689834 -307.481117) (xy 401.738053 -307.471273)
			(xy 401.787228 -307.469292) (xy 401.836083 -307.475224) (xy 401.883354 -307.488916) (xy 401.927816 -307.510014)
			(xy 401.968319 -307.53797) (xy 402.003812 -307.572062) (xy 402.033377 -307.611406) (xy 402.056248 -307.654983)
			(xy 402.071832 -307.701664) (xy 402.079727 -307.750241) (xy 402.080222 -307.774848) (xy 402.41907 -307.774848)
			(xy 402.42303 -307.725794) (xy 402.434807 -307.67801) (xy 402.454098 -307.632734) (xy 402.480401 -307.591138)
			(xy 402.513036 -307.554301) (xy 402.551157 -307.523176) (xy 402.593778 -307.498569) (xy 402.639794 -307.481117)
			(xy 402.688013 -307.471273) (xy 402.737188 -307.469292) (xy 402.786043 -307.475224) (xy 402.833314 -307.488916)
			(xy 402.877776 -307.510014) (xy 402.918279 -307.53797) (xy 402.953772 -307.572062) (xy 402.983337 -307.611406)
			(xy 403.006208 -307.654983) (xy 403.021792 -307.701664) (xy 403.029687 -307.750241) (xy 403.030182 -307.774848)
			(xy 403.36903 -307.774848) (xy 403.37299 -307.725794) (xy 403.384767 -307.67801) (xy 403.404058 -307.632734)
			(xy 403.430361 -307.591138) (xy 403.462996 -307.554301) (xy 403.501117 -307.523176) (xy 403.543738 -307.498569)
			(xy 403.589754 -307.481117) (xy 403.637973 -307.471273) (xy 403.687148 -307.469292) (xy 403.736003 -307.475224)
			(xy 403.783274 -307.488916) (xy 403.827736 -307.510014) (xy 403.868239 -307.53797) (xy 403.903732 -307.572062)
			(xy 403.933297 -307.611406) (xy 403.956168 -307.654983) (xy 403.971752 -307.701664) (xy 403.979647 -307.750241)
			(xy 403.980142 -307.774848) (xy 404.319244 -307.774848) (xy 404.323204 -307.725794) (xy 404.334981 -307.67801)
			(xy 404.354272 -307.632734) (xy 404.380575 -307.591138) (xy 404.41321 -307.554301) (xy 404.451331 -307.523176)
			(xy 404.493952 -307.498569) (xy 404.539968 -307.481117) (xy 404.588187 -307.471273) (xy 404.637362 -307.469292)
			(xy 404.686217 -307.475224) (xy 404.733488 -307.488916) (xy 404.77795 -307.510014) (xy 404.818453 -307.53797)
			(xy 404.853946 -307.572062) (xy 404.883511 -307.611406) (xy 404.906382 -307.654983) (xy 404.921966 -307.701664)
			(xy 404.929861 -307.750241) (xy 404.930356 -307.774848) (xy 405.269204 -307.774848) (xy 405.273164 -307.725794)
			(xy 405.284941 -307.67801) (xy 405.304232 -307.632734) (xy 405.330535 -307.591138) (xy 405.36317 -307.554301)
			(xy 405.401291 -307.523176) (xy 405.443912 -307.498569) (xy 405.489928 -307.481117) (xy 405.538147 -307.471273)
			(xy 405.587322 -307.469292) (xy 405.636177 -307.475224) (xy 405.683448 -307.488916) (xy 405.72791 -307.510014)
			(xy 405.768413 -307.53797) (xy 405.803906 -307.572062) (xy 405.833471 -307.611406) (xy 405.856342 -307.654983)
			(xy 405.871926 -307.701664) (xy 405.879821 -307.750241) (xy 405.880316 -307.774848) (xy 406.219164 -307.774848)
			(xy 406.223124 -307.725794) (xy 406.234901 -307.67801) (xy 406.254192 -307.632734) (xy 406.280495 -307.591138)
			(xy 406.31313 -307.554301) (xy 406.351251 -307.523176) (xy 406.393872 -307.498569) (xy 406.439888 -307.481117)
			(xy 406.488107 -307.471273) (xy 406.537282 -307.469292) (xy 406.586137 -307.475224) (xy 406.633408 -307.488916)
			(xy 406.67787 -307.510014) (xy 406.718373 -307.53797) (xy 406.753866 -307.572062) (xy 406.783431 -307.611406)
			(xy 406.806302 -307.654983) (xy 406.821886 -307.701664) (xy 406.829781 -307.750241) (xy 406.830276 -307.774848)
			(xy 408.119084 -307.774848) (xy 408.123044 -307.725794) (xy 408.134821 -307.67801) (xy 408.154112 -307.632734)
			(xy 408.180415 -307.591138) (xy 408.21305 -307.554301) (xy 408.251171 -307.523176) (xy 408.293792 -307.498569)
			(xy 408.339808 -307.481117) (xy 408.388027 -307.471273) (xy 408.437202 -307.469292) (xy 408.486057 -307.475224)
			(xy 408.533328 -307.488916) (xy 408.57779 -307.510014) (xy 408.618293 -307.53797) (xy 408.653786 -307.572062)
			(xy 408.683351 -307.611406) (xy 408.706222 -307.654983) (xy 408.721806 -307.701664) (xy 408.729701 -307.750241)
			(xy 408.730196 -307.774848) (xy 409.069044 -307.774848) (xy 409.073004 -307.725794) (xy 409.084781 -307.67801)
			(xy 409.104072 -307.632734) (xy 409.130375 -307.591138) (xy 409.16301 -307.554301) (xy 409.201131 -307.523176)
			(xy 409.243752 -307.498569) (xy 409.289768 -307.481117) (xy 409.337987 -307.471273) (xy 409.387162 -307.469292)
			(xy 409.436017 -307.475224) (xy 409.483288 -307.488916) (xy 409.52775 -307.510014) (xy 409.568253 -307.53797)
			(xy 409.603746 -307.572062) (xy 409.633311 -307.611406) (xy 409.656182 -307.654983) (xy 409.671766 -307.701664)
			(xy 409.679661 -307.750241) (xy 409.680156 -307.774848) (xy 410.019004 -307.774848) (xy 410.022964 -307.725794)
			(xy 410.034741 -307.67801) (xy 410.054032 -307.632734) (xy 410.080335 -307.591138) (xy 410.11297 -307.554301)
			(xy 410.151091 -307.523176) (xy 410.193712 -307.498569) (xy 410.239728 -307.481117) (xy 410.287947 -307.471273)
			(xy 410.337122 -307.469292) (xy 410.385977 -307.475224) (xy 410.433248 -307.488916) (xy 410.47771 -307.510014)
			(xy 410.518213 -307.53797) (xy 410.553706 -307.572062) (xy 410.583271 -307.611406) (xy 410.606142 -307.654983)
			(xy 410.621726 -307.701664) (xy 410.629621 -307.750241) (xy 410.630111 -307.774594) (xy 410.968964 -307.774594)
			(xy 410.972924 -307.72554) (xy 410.984701 -307.677756) (xy 411.003992 -307.63248) (xy 411.030295 -307.590884)
			(xy 411.06293 -307.554047) (xy 411.101051 -307.522922) (xy 411.143672 -307.498315) (xy 411.189688 -307.480863)
			(xy 411.237907 -307.471019) (xy 411.287082 -307.469038) (xy 411.335937 -307.47497) (xy 411.383208 -307.488662)
			(xy 411.42767 -307.50976) (xy 411.468173 -307.537716) (xy 411.503666 -307.571808) (xy 411.533231 -307.611152)
			(xy 411.556102 -307.654729) (xy 411.571686 -307.70141) (xy 411.579581 -307.749987) (xy 411.580076 -307.774594)
			(xy 411.919178 -307.774594) (xy 411.923138 -307.72554) (xy 411.934915 -307.677756) (xy 411.954206 -307.63248)
			(xy 411.980509 -307.590884) (xy 412.013144 -307.554047) (xy 412.051265 -307.522922) (xy 412.093886 -307.498315)
			(xy 412.139902 -307.480863) (xy 412.188121 -307.471019) (xy 412.237296 -307.469038) (xy 412.286151 -307.47497)
			(xy 412.333422 -307.488662) (xy 412.377884 -307.50976) (xy 412.418387 -307.537716) (xy 412.45388 -307.571808)
			(xy 412.483445 -307.611152) (xy 412.506316 -307.654729) (xy 412.5219 -307.70141) (xy 412.529795 -307.749987)
			(xy 412.53029 -307.774594) (xy 412.530285 -307.774848) (xy 412.869138 -307.774848) (xy 412.873098 -307.725794)
			(xy 412.884875 -307.67801) (xy 412.904166 -307.632734) (xy 412.930469 -307.591138) (xy 412.963104 -307.554301)
			(xy 413.001225 -307.523176) (xy 413.043846 -307.498569) (xy 413.089862 -307.481117) (xy 413.138081 -307.471273)
			(xy 413.187256 -307.469292) (xy 413.236111 -307.475224) (xy 413.283382 -307.488916) (xy 413.327844 -307.510014)
			(xy 413.368347 -307.53797) (xy 413.40384 -307.572062) (xy 413.433405 -307.611406) (xy 413.456276 -307.654983)
			(xy 413.47186 -307.701664) (xy 413.479755 -307.750241) (xy 413.48025 -307.774848) (xy 413.819098 -307.774848)
			(xy 413.823058 -307.725794) (xy 413.834835 -307.67801) (xy 413.854126 -307.632734) (xy 413.880429 -307.591138)
			(xy 413.913064 -307.554301) (xy 413.951185 -307.523176) (xy 413.993806 -307.498569) (xy 414.039822 -307.481117)
			(xy 414.088041 -307.471273) (xy 414.137216 -307.469292) (xy 414.186071 -307.475224) (xy 414.233342 -307.488916)
			(xy 414.277804 -307.510014) (xy 414.318307 -307.53797) (xy 414.3538 -307.572062) (xy 414.383365 -307.611406)
			(xy 414.406236 -307.654983) (xy 414.42182 -307.701664) (xy 414.429715 -307.750241) (xy 414.43021 -307.774848)
			(xy 414.769058 -307.774848) (xy 414.773018 -307.725794) (xy 414.784795 -307.67801) (xy 414.804086 -307.632734)
			(xy 414.830389 -307.591138) (xy 414.863024 -307.554301) (xy 414.901145 -307.523176) (xy 414.943766 -307.498569)
			(xy 414.989782 -307.481117) (xy 415.038001 -307.471273) (xy 415.087176 -307.469292) (xy 415.136031 -307.475224)
			(xy 415.183302 -307.488916) (xy 415.227764 -307.510014) (xy 415.268267 -307.53797) (xy 415.30376 -307.572062)
			(xy 415.333325 -307.611406) (xy 415.356196 -307.654983) (xy 415.37178 -307.701664) (xy 415.379675 -307.750241)
			(xy 415.38017 -307.774848) (xy 415.719018 -307.774848) (xy 415.722978 -307.725794) (xy 415.734755 -307.67801)
			(xy 415.754046 -307.632734) (xy 415.780349 -307.591138) (xy 415.812984 -307.554301) (xy 415.851105 -307.523176)
			(xy 415.893726 -307.498569) (xy 415.939742 -307.481117) (xy 415.987961 -307.471273) (xy 416.037136 -307.469292)
			(xy 416.085991 -307.475224) (xy 416.133262 -307.488916) (xy 416.177724 -307.510014) (xy 416.218227 -307.53797)
			(xy 416.25372 -307.572062) (xy 416.283285 -307.611406) (xy 416.306156 -307.654983) (xy 416.32174 -307.701664)
			(xy 416.329635 -307.750241) (xy 416.33013 -307.774848) (xy 416.668978 -307.774848) (xy 416.672938 -307.725794)
			(xy 416.684715 -307.67801) (xy 416.704006 -307.632734) (xy 416.730309 -307.591138) (xy 416.762944 -307.554301)
			(xy 416.801065 -307.523176) (xy 416.843686 -307.498569) (xy 416.889702 -307.481117) (xy 416.937921 -307.471273)
			(xy 416.987096 -307.469292) (xy 417.035951 -307.475224) (xy 417.083222 -307.488916) (xy 417.127684 -307.510014)
			(xy 417.168187 -307.53797) (xy 417.20368 -307.572062) (xy 417.233245 -307.611406) (xy 417.256116 -307.654983)
			(xy 417.2717 -307.701664) (xy 417.279595 -307.750241) (xy 417.28009 -307.774848) (xy 417.279595 -307.799455)
			(xy 417.2717 -307.848032) (xy 417.256116 -307.894713) (xy 417.233245 -307.93829) (xy 417.20368 -307.977634)
			(xy 417.168187 -308.011726) (xy 417.127684 -308.039682) (xy 417.083222 -308.06078) (xy 417.035951 -308.074472)
			(xy 416.987096 -308.080404) (xy 416.937921 -308.078423) (xy 416.889702 -308.068579) (xy 416.843686 -308.051127)
			(xy 416.801065 -308.02652) (xy 416.762944 -307.995395) (xy 416.730309 -307.958558) (xy 416.704006 -307.916962)
			(xy 416.684715 -307.871686) (xy 416.672938 -307.823902) (xy 416.668978 -307.774848) (xy 416.33013 -307.774848)
			(xy 416.329635 -307.799455) (xy 416.32174 -307.848032) (xy 416.306156 -307.894713) (xy 416.283285 -307.93829)
			(xy 416.25372 -307.977634) (xy 416.218227 -308.011726) (xy 416.177724 -308.039682) (xy 416.133262 -308.06078)
			(xy 416.085991 -308.074472) (xy 416.037136 -308.080404) (xy 415.987961 -308.078423) (xy 415.939742 -308.068579)
			(xy 415.893726 -308.051127) (xy 415.851105 -308.02652) (xy 415.812984 -307.995395) (xy 415.780349 -307.958558)
			(xy 415.754046 -307.916962) (xy 415.734755 -307.871686) (xy 415.722978 -307.823902) (xy 415.719018 -307.774848)
			(xy 415.38017 -307.774848) (xy 415.379675 -307.799455) (xy 415.37178 -307.848032) (xy 415.356196 -307.894713)
			(xy 415.333325 -307.93829) (xy 415.30376 -307.977634) (xy 415.268267 -308.011726) (xy 415.227764 -308.039682)
			(xy 415.183302 -308.06078) (xy 415.136031 -308.074472) (xy 415.087176 -308.080404) (xy 415.038001 -308.078423)
			(xy 414.989782 -308.068579) (xy 414.943766 -308.051127) (xy 414.901145 -308.02652) (xy 414.863024 -307.995395)
			(xy 414.830389 -307.958558) (xy 414.804086 -307.916962) (xy 414.784795 -307.871686) (xy 414.773018 -307.823902)
			(xy 414.769058 -307.774848) (xy 414.43021 -307.774848) (xy 414.429715 -307.799455) (xy 414.42182 -307.848032)
			(xy 414.406236 -307.894713) (xy 414.383365 -307.93829) (xy 414.3538 -307.977634) (xy 414.318307 -308.011726)
			(xy 414.277804 -308.039682) (xy 414.233342 -308.06078) (xy 414.186071 -308.074472) (xy 414.137216 -308.080404)
			(xy 414.088041 -308.078423) (xy 414.039822 -308.068579) (xy 413.993806 -308.051127) (xy 413.951185 -308.02652)
			(xy 413.913064 -307.995395) (xy 413.880429 -307.958558) (xy 413.854126 -307.916962) (xy 413.834835 -307.871686)
			(xy 413.823058 -307.823902) (xy 413.819098 -307.774848) (xy 413.48025 -307.774848) (xy 413.479755 -307.799455)
			(xy 413.47186 -307.848032) (xy 413.456276 -307.894713) (xy 413.433405 -307.93829) (xy 413.40384 -307.977634)
			(xy 413.368347 -308.011726) (xy 413.327844 -308.039682) (xy 413.283382 -308.06078) (xy 413.236111 -308.074472)
			(xy 413.187256 -308.080404) (xy 413.138081 -308.078423) (xy 413.089862 -308.068579) (xy 413.043846 -308.051127)
			(xy 413.001225 -308.02652) (xy 412.963104 -307.995395) (xy 412.930469 -307.958558) (xy 412.904166 -307.916962)
			(xy 412.884875 -307.871686) (xy 412.873098 -307.823902) (xy 412.869138 -307.774848) (xy 412.530285 -307.774848)
			(xy 412.529795 -307.799201) (xy 412.5219 -307.847778) (xy 412.506316 -307.894459) (xy 412.483445 -307.938036)
			(xy 412.45388 -307.97738) (xy 412.418387 -308.011472) (xy 412.377884 -308.039428) (xy 412.333422 -308.060526)
			(xy 412.286151 -308.074218) (xy 412.237296 -308.08015) (xy 412.188121 -308.078169) (xy 412.139902 -308.068325)
			(xy 412.093886 -308.050873) (xy 412.051265 -308.026266) (xy 412.013144 -307.995141) (xy 411.980509 -307.958304)
			(xy 411.954206 -307.916708) (xy 411.934915 -307.871432) (xy 411.923138 -307.823648) (xy 411.919178 -307.774594)
			(xy 411.580076 -307.774594) (xy 411.579581 -307.799201) (xy 411.571686 -307.847778) (xy 411.556102 -307.894459)
			(xy 411.533231 -307.938036) (xy 411.503666 -307.97738) (xy 411.468173 -308.011472) (xy 411.42767 -308.039428)
			(xy 411.383208 -308.060526) (xy 411.335937 -308.074218) (xy 411.287082 -308.08015) (xy 411.237907 -308.078169)
			(xy 411.189688 -308.068325) (xy 411.143672 -308.050873) (xy 411.101051 -308.026266) (xy 411.06293 -307.995141)
			(xy 411.030295 -307.958304) (xy 411.003992 -307.916708) (xy 410.984701 -307.871432) (xy 410.972924 -307.823648)
			(xy 410.968964 -307.774594) (xy 410.630111 -307.774594) (xy 410.630116 -307.774848) (xy 410.629621 -307.799455)
			(xy 410.621726 -307.848032) (xy 410.606142 -307.894713) (xy 410.583271 -307.93829) (xy 410.553706 -307.977634)
			(xy 410.518213 -308.011726) (xy 410.47771 -308.039682) (xy 410.433248 -308.06078) (xy 410.385977 -308.074472)
			(xy 410.337122 -308.080404) (xy 410.287947 -308.078423) (xy 410.239728 -308.068579) (xy 410.193712 -308.051127)
			(xy 410.151091 -308.02652) (xy 410.11297 -307.995395) (xy 410.080335 -307.958558) (xy 410.054032 -307.916962)
			(xy 410.034741 -307.871686) (xy 410.022964 -307.823902) (xy 410.019004 -307.774848) (xy 409.680156 -307.774848)
			(xy 409.679661 -307.799455) (xy 409.671766 -307.848032) (xy 409.656182 -307.894713) (xy 409.633311 -307.93829)
			(xy 409.603746 -307.977634) (xy 409.568253 -308.011726) (xy 409.52775 -308.039682) (xy 409.483288 -308.06078)
			(xy 409.436017 -308.074472) (xy 409.387162 -308.080404) (xy 409.337987 -308.078423) (xy 409.289768 -308.068579)
			(xy 409.243752 -308.051127) (xy 409.201131 -308.02652) (xy 409.16301 -307.995395) (xy 409.130375 -307.958558)
			(xy 409.104072 -307.916962) (xy 409.084781 -307.871686) (xy 409.073004 -307.823902) (xy 409.069044 -307.774848)
			(xy 408.730196 -307.774848) (xy 408.729701 -307.799455) (xy 408.721806 -307.848032) (xy 408.706222 -307.894713)
			(xy 408.683351 -307.93829) (xy 408.653786 -307.977634) (xy 408.618293 -308.011726) (xy 408.57779 -308.039682)
			(xy 408.533328 -308.06078) (xy 408.486057 -308.074472) (xy 408.437202 -308.080404) (xy 408.388027 -308.078423)
			(xy 408.339808 -308.068579) (xy 408.293792 -308.051127) (xy 408.251171 -308.02652) (xy 408.21305 -307.995395)
			(xy 408.180415 -307.958558) (xy 408.154112 -307.916962) (xy 408.134821 -307.871686) (xy 408.123044 -307.823902)
			(xy 408.119084 -307.774848) (xy 406.830276 -307.774848) (xy 406.829781 -307.799455) (xy 406.821886 -307.848032)
			(xy 406.806302 -307.894713) (xy 406.783431 -307.93829) (xy 406.753866 -307.977634) (xy 406.718373 -308.011726)
			(xy 406.67787 -308.039682) (xy 406.633408 -308.06078) (xy 406.586137 -308.074472) (xy 406.537282 -308.080404)
			(xy 406.488107 -308.078423) (xy 406.439888 -308.068579) (xy 406.393872 -308.051127) (xy 406.351251 -308.02652)
			(xy 406.31313 -307.995395) (xy 406.280495 -307.958558) (xy 406.254192 -307.916962) (xy 406.234901 -307.871686)
			(xy 406.223124 -307.823902) (xy 406.219164 -307.774848) (xy 405.880316 -307.774848) (xy 405.879821 -307.799455)
			(xy 405.871926 -307.848032) (xy 405.856342 -307.894713) (xy 405.833471 -307.93829) (xy 405.803906 -307.977634)
			(xy 405.768413 -308.011726) (xy 405.72791 -308.039682) (xy 405.683448 -308.06078) (xy 405.636177 -308.074472)
			(xy 405.587322 -308.080404) (xy 405.538147 -308.078423) (xy 405.489928 -308.068579) (xy 405.443912 -308.051127)
			(xy 405.401291 -308.02652) (xy 405.36317 -307.995395) (xy 405.330535 -307.958558) (xy 405.304232 -307.916962)
			(xy 405.284941 -307.871686) (xy 405.273164 -307.823902) (xy 405.269204 -307.774848) (xy 404.930356 -307.774848)
			(xy 404.929861 -307.799455) (xy 404.921966 -307.848032) (xy 404.906382 -307.894713) (xy 404.883511 -307.93829)
			(xy 404.853946 -307.977634) (xy 404.818453 -308.011726) (xy 404.77795 -308.039682) (xy 404.733488 -308.06078)
			(xy 404.686217 -308.074472) (xy 404.637362 -308.080404) (xy 404.588187 -308.078423) (xy 404.539968 -308.068579)
			(xy 404.493952 -308.051127) (xy 404.451331 -308.02652) (xy 404.41321 -307.995395) (xy 404.380575 -307.958558)
			(xy 404.354272 -307.916962) (xy 404.334981 -307.871686) (xy 404.323204 -307.823902) (xy 404.319244 -307.774848)
			(xy 403.980142 -307.774848) (xy 403.979647 -307.799455) (xy 403.971752 -307.848032) (xy 403.956168 -307.894713)
			(xy 403.933297 -307.93829) (xy 403.903732 -307.977634) (xy 403.868239 -308.011726) (xy 403.827736 -308.039682)
			(xy 403.783274 -308.06078) (xy 403.736003 -308.074472) (xy 403.687148 -308.080404) (xy 403.637973 -308.078423)
			(xy 403.589754 -308.068579) (xy 403.543738 -308.051127) (xy 403.501117 -308.02652) (xy 403.462996 -307.995395)
			(xy 403.430361 -307.958558) (xy 403.404058 -307.916962) (xy 403.384767 -307.871686) (xy 403.37299 -307.823902)
			(xy 403.36903 -307.774848) (xy 403.030182 -307.774848) (xy 403.029687 -307.799455) (xy 403.021792 -307.848032)
			(xy 403.006208 -307.894713) (xy 402.983337 -307.93829) (xy 402.953772 -307.977634) (xy 402.918279 -308.011726)
			(xy 402.877776 -308.039682) (xy 402.833314 -308.06078) (xy 402.786043 -308.074472) (xy 402.737188 -308.080404)
			(xy 402.688013 -308.078423) (xy 402.639794 -308.068579) (xy 402.593778 -308.051127) (xy 402.551157 -308.02652)
			(xy 402.513036 -307.995395) (xy 402.480401 -307.958558) (xy 402.454098 -307.916962) (xy 402.434807 -307.871686)
			(xy 402.42303 -307.823902) (xy 402.41907 -307.774848) (xy 402.080222 -307.774848) (xy 402.079727 -307.799455)
			(xy 402.071832 -307.848032) (xy 402.056248 -307.894713) (xy 402.033377 -307.93829) (xy 402.003812 -307.977634)
			(xy 401.968319 -308.011726) (xy 401.927816 -308.039682) (xy 401.883354 -308.06078) (xy 401.836083 -308.074472)
			(xy 401.787228 -308.080404) (xy 401.738053 -308.078423) (xy 401.689834 -308.068579) (xy 401.643818 -308.051127)
			(xy 401.601197 -308.02652) (xy 401.563076 -307.995395) (xy 401.530441 -307.958558) (xy 401.504138 -307.916962)
			(xy 401.484847 -307.871686) (xy 401.47307 -307.823902) (xy 401.46911 -307.774848) (xy 401.130262 -307.774848)
			(xy 401.129767 -307.799455) (xy 401.121872 -307.848032) (xy 401.106288 -307.894713) (xy 401.083417 -307.93829)
			(xy 401.053852 -307.977634) (xy 401.018359 -308.011726) (xy 400.977856 -308.039682) (xy 400.933394 -308.06078)
			(xy 400.886123 -308.074472) (xy 400.837268 -308.080404) (xy 400.788093 -308.078423) (xy 400.739874 -308.068579)
			(xy 400.693858 -308.051127) (xy 400.651237 -308.02652) (xy 400.613116 -307.995395) (xy 400.580481 -307.958558)
			(xy 400.554178 -307.916962) (xy 400.534887 -307.871686) (xy 400.52311 -307.823902) (xy 400.51915 -307.774848)
			(xy 400.180302 -307.774848) (xy 400.179807 -307.799455) (xy 400.171912 -307.848032) (xy 400.156328 -307.894713)
			(xy 400.133457 -307.93829) (xy 400.103892 -307.977634) (xy 400.068399 -308.011726) (xy 400.027896 -308.039682)
			(xy 399.983434 -308.06078) (xy 399.936163 -308.074472) (xy 399.887308 -308.080404) (xy 399.838133 -308.078423)
			(xy 399.789914 -308.068579) (xy 399.743898 -308.051127) (xy 399.701277 -308.02652) (xy 399.663156 -307.995395)
			(xy 399.630521 -307.958558) (xy 399.604218 -307.916962) (xy 399.584927 -307.871686) (xy 399.57315 -307.823902)
			(xy 399.56919 -307.774848) (xy 399.230342 -307.774848) (xy 399.229847 -307.799455) (xy 399.221952 -307.848032)
			(xy 399.206368 -307.894713) (xy 399.183497 -307.93829) (xy 399.153932 -307.977634) (xy 399.118439 -308.011726)
			(xy 399.077936 -308.039682) (xy 399.033474 -308.06078) (xy 398.986203 -308.074472) (xy 398.937348 -308.080404)
			(xy 398.888173 -308.078423) (xy 398.839954 -308.068579) (xy 398.793938 -308.051127) (xy 398.751317 -308.02652)
			(xy 398.713196 -307.995395) (xy 398.680561 -307.958558) (xy 398.654258 -307.916962) (xy 398.634967 -307.871686)
			(xy 398.62319 -307.823902) (xy 398.61923 -307.774848) (xy 398.280128 -307.774848) (xy 398.279633 -307.799455)
			(xy 398.271738 -307.848032) (xy 398.256154 -307.894713) (xy 398.233283 -307.93829) (xy 398.203718 -307.977634)
			(xy 398.168225 -308.011726) (xy 398.127722 -308.039682) (xy 398.08326 -308.06078) (xy 398.035989 -308.074472)
			(xy 397.987134 -308.080404) (xy 397.937959 -308.078423) (xy 397.88974 -308.068579) (xy 397.843724 -308.051127)
			(xy 397.801103 -308.02652) (xy 397.762982 -307.995395) (xy 397.730347 -307.958558) (xy 397.704044 -307.916962)
			(xy 397.684753 -307.871686) (xy 397.672976 -307.823902) (xy 397.669016 -307.774848) (xy 397.330168 -307.774848)
			(xy 397.329673 -307.799455) (xy 397.321778 -307.848032) (xy 397.306194 -307.894713) (xy 397.283323 -307.93829)
			(xy 397.253758 -307.977634) (xy 397.218265 -308.011726) (xy 397.177762 -308.039682) (xy 397.1333 -308.06078)
			(xy 397.086029 -308.074472) (xy 397.037174 -308.080404) (xy 396.987999 -308.078423) (xy 396.93978 -308.068579)
			(xy 396.893764 -308.051127) (xy 396.851143 -308.02652) (xy 396.813022 -307.995395) (xy 396.780387 -307.958558)
			(xy 396.754084 -307.916962) (xy 396.734793 -307.871686) (xy 396.723016 -307.823902) (xy 396.719056 -307.774848)
			(xy 396.380208 -307.774848) (xy 396.379713 -307.799455) (xy 396.371818 -307.848032) (xy 396.356234 -307.894713)
			(xy 396.333363 -307.93829) (xy 396.303798 -307.977634) (xy 396.268305 -308.011726) (xy 396.227802 -308.039682)
			(xy 396.18334 -308.06078) (xy 396.136069 -308.074472) (xy 396.087214 -308.080404) (xy 396.038039 -308.078423)
			(xy 395.98982 -308.068579) (xy 395.943804 -308.051127) (xy 395.901183 -308.02652) (xy 395.863062 -307.995395)
			(xy 395.830427 -307.958558) (xy 395.804124 -307.916962) (xy 395.784833 -307.871686) (xy 395.773056 -307.823902)
			(xy 395.769096 -307.774848) (xy 395.430248 -307.774848) (xy 395.429753 -307.799455) (xy 395.421858 -307.848032)
			(xy 395.406274 -307.894713) (xy 395.383403 -307.93829) (xy 395.353838 -307.977634) (xy 395.318345 -308.011726)
			(xy 395.277842 -308.039682) (xy 395.23338 -308.06078) (xy 395.186109 -308.074472) (xy 395.137254 -308.080404)
			(xy 395.088079 -308.078423) (xy 395.03986 -308.068579) (xy 394.993844 -308.051127) (xy 394.951223 -308.02652)
			(xy 394.913102 -307.995395) (xy 394.880467 -307.958558) (xy 394.854164 -307.916962) (xy 394.834873 -307.871686)
			(xy 394.823096 -307.823902) (xy 394.819136 -307.774848) (xy 364.837848 -307.774848) (xy 364.844145 -307.796178)
			(xy 364.85198 -307.85035) (xy 364.852458 -307.877718) (xy 364.851972 -307.904969) (xy 364.844216 -307.958917)
			(xy 364.828861 -308.011212) (xy 364.806219 -308.060789) (xy 364.776753 -308.106639) (xy 364.741062 -308.14783)
			(xy 364.699871 -308.183521) (xy 364.654021 -308.212987) (xy 364.604444 -308.235629) (xy 364.552149 -308.250984)
			(xy 364.498201 -308.25874) (xy 364.443699 -308.25874) (xy 364.389751 -308.250984) (xy 364.337456 -308.235629)
			(xy 364.287879 -308.212987) (xy 364.242029 -308.183521) (xy 364.200838 -308.14783) (xy 364.165147 -308.106639)
			(xy 364.135681 -308.060789) (xy 364.113039 -308.011212) (xy 364.097684 -307.958917) (xy 364.089928 -307.904969)
			(xy 364.089442 -307.877718) (xy 358.012238 -307.877718) (xy 358.011752 -307.904969) (xy 358.003996 -307.958917)
			(xy 357.988641 -308.011212) (xy 357.965999 -308.060789) (xy 357.936533 -308.106639) (xy 357.900842 -308.14783)
			(xy 357.859651 -308.183521) (xy 357.813801 -308.212987) (xy 357.764224 -308.235629) (xy 357.711929 -308.250984)
			(xy 357.657981 -308.25874) (xy 357.603479 -308.25874) (xy 357.549531 -308.250984) (xy 357.497236 -308.235629)
			(xy 357.447659 -308.212987) (xy 357.401809 -308.183521) (xy 357.360618 -308.14783) (xy 357.324927 -308.106639)
			(xy 357.295461 -308.060789) (xy 357.272819 -308.011212) (xy 357.257464 -307.958917) (xy 357.249708 -307.904969)
			(xy 357.249222 -307.877718) (xy 354.375728 -307.877718) (xy 354.371796 -307.905069) (xy 354.356441 -307.957364)
			(xy 354.333799 -308.006941) (xy 354.304333 -308.052791) (xy 354.268642 -308.093982) (xy 354.227451 -308.129673)
			(xy 354.181601 -308.159139) (xy 354.132024 -308.181781) (xy 354.079729 -308.197136) (xy 354.025781 -308.204892)
			(xy 353.971279 -308.204892) (xy 353.917331 -308.197136) (xy 353.865036 -308.181781) (xy 353.815459 -308.159139)
			(xy 353.769609 -308.129673) (xy 353.728418 -308.093982) (xy 353.692727 -308.052791) (xy 353.663261 -308.006941)
			(xy 353.640619 -307.957364) (xy 353.625264 -307.905069) (xy 353.617508 -307.851121) (xy 353.617022 -307.82387)
			(xy 351.03308 -307.82387) (xy 351.03308 -308.450488) (xy 376.378214 -308.450488) (xy 376.382285 -308.394866)
			(xy 376.394411 -308.340429) (xy 376.414334 -308.288338) (xy 376.44163 -308.239703) (xy 376.475716 -308.19556)
			(xy 376.515865 -308.156851) (xy 376.561223 -308.1244) (xy 376.610823 -308.098899) (xy 376.663607 -308.080892)
			(xy 376.71845 -308.070762) (xy 376.774184 -308.068725) (xy 376.829621 -308.074825) (xy 376.883578 -308.088931)
			(xy 376.934907 -308.110743) (xy 376.982513 -308.139797) (xy 377.025381 -308.175472) (xy 377.062598 -308.217009)
			(xy 377.084479 -308.250082) (xy 383.893834 -308.250082) (xy 383.897794 -308.201028) (xy 383.909571 -308.153244)
			(xy 383.928862 -308.107968) (xy 383.955165 -308.066372) (xy 383.9878 -308.029535) (xy 384.025921 -307.99841)
			(xy 384.068542 -307.973803) (xy 384.114558 -307.956351) (xy 384.162777 -307.946507) (xy 384.211952 -307.944526)
			(xy 384.260807 -307.950458) (xy 384.308078 -307.96415) (xy 384.35254 -307.985248) (xy 384.393043 -308.013204)
			(xy 384.428536 -308.047296) (xy 384.458101 -308.08664) (xy 384.480972 -308.130217) (xy 384.496556 -308.176898)
			(xy 384.504451 -308.225475) (xy 384.504946 -308.250082) (xy 384.504451 -308.274689) (xy 384.504313 -308.275536)
			(xy 384.823204 -308.275536) (xy 384.823204 -308.22412) (xy 384.831247 -308.173338) (xy 384.847135 -308.124439)
			(xy 384.870478 -308.078627) (xy 384.900699 -308.037031) (xy 384.937055 -308.000675) (xy 384.978651 -307.970454)
			(xy 385.024463 -307.947111) (xy 385.073362 -307.931223) (xy 385.124144 -307.92318) (xy 385.17556 -307.92318)
			(xy 385.226342 -307.931223) (xy 385.275241 -307.947111) (xy 385.321053 -307.970454) (xy 385.362649 -308.000675)
			(xy 385.399005 -308.037031) (xy 385.429226 -308.078627) (xy 385.452569 -308.124439) (xy 385.468457 -308.173338)
			(xy 385.4765 -308.22412) (xy 385.477004 -308.249828) (xy 385.4765 -308.275536) (xy 385.773164 -308.275536)
			(xy 385.773164 -308.22412) (xy 385.781207 -308.173338) (xy 385.797095 -308.124439) (xy 385.820438 -308.078627)
			(xy 385.850659 -308.037031) (xy 385.887015 -308.000675) (xy 385.928611 -307.970454) (xy 385.974423 -307.947111)
			(xy 386.023322 -307.931223) (xy 386.074104 -307.92318) (xy 386.12552 -307.92318) (xy 386.176302 -307.931223)
			(xy 386.225201 -307.947111) (xy 386.271013 -307.970454) (xy 386.312609 -308.000675) (xy 386.348965 -308.037031)
			(xy 386.379186 -308.078627) (xy 386.402529 -308.124439) (xy 386.418417 -308.173338) (xy 386.42646 -308.22412)
			(xy 386.426964 -308.249828) (xy 386.744222 -308.249828) (xy 386.748182 -308.200774) (xy 386.759959 -308.15299)
			(xy 386.77925 -308.107714) (xy 386.805553 -308.066118) (xy 386.838188 -308.029281) (xy 386.876309 -307.998156)
			(xy 386.91893 -307.973549) (xy 386.964946 -307.956097) (xy 387.013165 -307.946253) (xy 387.06234 -307.944272)
			(xy 387.111195 -307.950204) (xy 387.158466 -307.963896) (xy 387.202928 -307.984994) (xy 387.243431 -308.01295)
			(xy 387.278924 -308.047042) (xy 387.308489 -308.086386) (xy 387.33136 -308.129963) (xy 387.346944 -308.176644)
			(xy 387.354839 -308.225221) (xy 387.355334 -308.249828) (xy 387.694182 -308.249828) (xy 387.698142 -308.200774)
			(xy 387.709919 -308.15299) (xy 387.72921 -308.107714) (xy 387.755513 -308.066118) (xy 387.788148 -308.029281)
			(xy 387.826269 -307.998156) (xy 387.86889 -307.973549) (xy 387.914906 -307.956097) (xy 387.963125 -307.946253)
			(xy 388.0123 -307.944272) (xy 388.061155 -307.950204) (xy 388.108426 -307.963896) (xy 388.152888 -307.984994)
			(xy 388.193391 -308.01295) (xy 388.228884 -308.047042) (xy 388.258449 -308.086386) (xy 388.28132 -308.129963)
			(xy 388.296904 -308.176644) (xy 388.304799 -308.225221) (xy 388.305294 -308.249828) (xy 388.644142 -308.249828)
			(xy 388.648102 -308.200774) (xy 388.659879 -308.15299) (xy 388.67917 -308.107714) (xy 388.705473 -308.066118)
			(xy 388.738108 -308.029281) (xy 388.776229 -307.998156) (xy 388.81885 -307.973549) (xy 388.864866 -307.956097)
			(xy 388.913085 -307.946253) (xy 388.96226 -307.944272) (xy 389.011115 -307.950204) (xy 389.058386 -307.963896)
			(xy 389.102848 -307.984994) (xy 389.143351 -308.01295) (xy 389.178844 -308.047042) (xy 389.208409 -308.086386)
			(xy 389.23128 -308.129963) (xy 389.246864 -308.176644) (xy 389.254759 -308.225221) (xy 389.255254 -308.249828)
			(xy 389.594102 -308.249828) (xy 389.598062 -308.200774) (xy 389.609839 -308.15299) (xy 389.62913 -308.107714)
			(xy 389.655433 -308.066118) (xy 389.688068 -308.029281) (xy 389.726189 -307.998156) (xy 389.76881 -307.973549)
			(xy 389.814826 -307.956097) (xy 389.863045 -307.946253) (xy 389.91222 -307.944272) (xy 389.961075 -307.950204)
			(xy 390.008346 -307.963896) (xy 390.052808 -307.984994) (xy 390.093311 -308.01295) (xy 390.128804 -308.047042)
			(xy 390.158369 -308.086386) (xy 390.18124 -308.129963) (xy 390.196824 -308.176644) (xy 390.204719 -308.225221)
			(xy 390.205214 -308.249828) (xy 390.544062 -308.249828) (xy 390.548022 -308.200774) (xy 390.559799 -308.15299)
			(xy 390.57909 -308.107714) (xy 390.605393 -308.066118) (xy 390.638028 -308.029281) (xy 390.676149 -307.998156)
			(xy 390.71877 -307.973549) (xy 390.764786 -307.956097) (xy 390.813005 -307.946253) (xy 390.86218 -307.944272)
			(xy 390.911035 -307.950204) (xy 390.958306 -307.963896) (xy 391.002768 -307.984994) (xy 391.043271 -308.01295)
			(xy 391.078764 -308.047042) (xy 391.108329 -308.086386) (xy 391.1312 -308.129963) (xy 391.146784 -308.176644)
			(xy 391.154679 -308.225221) (xy 391.155174 -308.249828) (xy 391.154679 -308.274435) (xy 391.1545 -308.275536)
			(xy 391.473178 -308.275536) (xy 391.473178 -308.22412) (xy 391.481221 -308.173338) (xy 391.497109 -308.124439)
			(xy 391.520452 -308.078627) (xy 391.550673 -308.037031) (xy 391.587029 -308.000675) (xy 391.628625 -307.970454)
			(xy 391.674437 -307.947111) (xy 391.723336 -307.931223) (xy 391.774118 -307.92318) (xy 391.825534 -307.92318)
			(xy 391.876316 -307.931223) (xy 391.925215 -307.947111) (xy 391.971027 -307.970454) (xy 392.012623 -308.000675)
			(xy 392.048979 -308.037031) (xy 392.0792 -308.078627) (xy 392.102543 -308.124439) (xy 392.118431 -308.173338)
			(xy 392.126474 -308.22412) (xy 392.126978 -308.249828) (xy 392.126474 -308.275536) (xy 392.423138 -308.275536)
			(xy 392.423138 -308.22412) (xy 392.431181 -308.173338) (xy 392.447069 -308.124439) (xy 392.470412 -308.078627)
			(xy 392.500633 -308.037031) (xy 392.536989 -308.000675) (xy 392.578585 -307.970454) (xy 392.624397 -307.947111)
			(xy 392.673296 -307.931223) (xy 392.724078 -307.92318) (xy 392.775494 -307.92318) (xy 392.826276 -307.931223)
			(xy 392.875175 -307.947111) (xy 392.920987 -307.970454) (xy 392.962583 -308.000675) (xy 392.998939 -308.037031)
			(xy 393.02916 -308.078627) (xy 393.052503 -308.124439) (xy 393.068391 -308.173338) (xy 393.076434 -308.22412)
			(xy 393.076938 -308.249828) (xy 393.394196 -308.249828) (xy 393.398156 -308.200774) (xy 393.409933 -308.15299)
			(xy 393.429224 -308.107714) (xy 393.455527 -308.066118) (xy 393.488162 -308.029281) (xy 393.526283 -307.998156)
			(xy 393.568904 -307.973549) (xy 393.61492 -307.956097) (xy 393.663139 -307.946253) (xy 393.712314 -307.944272)
			(xy 393.761169 -307.950204) (xy 393.80844 -307.963896) (xy 393.852902 -307.984994) (xy 393.893405 -308.01295)
			(xy 393.928898 -308.047042) (xy 393.958463 -308.086386) (xy 393.981334 -308.129963) (xy 393.996918 -308.176644)
			(xy 394.004813 -308.225221) (xy 394.005308 -308.249828) (xy 394.004813 -308.274435) (xy 393.996918 -308.323012)
			(xy 393.981334 -308.369693) (xy 393.958463 -308.41327) (xy 393.928898 -308.452614) (xy 393.893405 -308.486706)
			(xy 393.852902 -308.514662) (xy 393.80844 -308.53576) (xy 393.761169 -308.549452) (xy 393.712314 -308.555384)
			(xy 393.663139 -308.553403) (xy 393.61492 -308.543559) (xy 393.568904 -308.526107) (xy 393.526283 -308.5015)
			(xy 393.488162 -308.470375) (xy 393.455527 -308.433538) (xy 393.429224 -308.391942) (xy 393.409933 -308.346666)
			(xy 393.398156 -308.298882) (xy 393.394196 -308.249828) (xy 393.076938 -308.249828) (xy 393.076434 -308.275536)
			(xy 393.068391 -308.326318) (xy 393.052503 -308.375217) (xy 393.02916 -308.421029) (xy 392.998939 -308.462625)
			(xy 392.962583 -308.498981) (xy 392.920987 -308.529202) (xy 392.875175 -308.552545) (xy 392.826276 -308.568433)
			(xy 392.775494 -308.576476) (xy 392.724078 -308.576476) (xy 392.673296 -308.568433) (xy 392.624397 -308.552545)
			(xy 392.578585 -308.529202) (xy 392.536989 -308.498981) (xy 392.500633 -308.462625) (xy 392.470412 -308.421029)
			(xy 392.447069 -308.375217) (xy 392.431181 -308.326318) (xy 392.423138 -308.275536) (xy 392.126474 -308.275536)
			(xy 392.118431 -308.326318) (xy 392.102543 -308.375217) (xy 392.0792 -308.421029) (xy 392.048979 -308.462625)
			(xy 392.012623 -308.498981) (xy 391.971027 -308.529202) (xy 391.925215 -308.552545) (xy 391.876316 -308.568433)
			(xy 391.825534 -308.576476) (xy 391.774118 -308.576476) (xy 391.723336 -308.568433) (xy 391.674437 -308.552545)
			(xy 391.628625 -308.529202) (xy 391.587029 -308.498981) (xy 391.550673 -308.462625) (xy 391.520452 -308.421029)
			(xy 391.497109 -308.375217) (xy 391.481221 -308.326318) (xy 391.473178 -308.275536) (xy 391.1545 -308.275536)
			(xy 391.146784 -308.323012) (xy 391.1312 -308.369693) (xy 391.108329 -308.41327) (xy 391.078764 -308.452614)
			(xy 391.043271 -308.486706) (xy 391.002768 -308.514662) (xy 390.958306 -308.53576) (xy 390.911035 -308.549452)
			(xy 390.86218 -308.555384) (xy 390.813005 -308.553403) (xy 390.764786 -308.543559) (xy 390.71877 -308.526107)
			(xy 390.676149 -308.5015) (xy 390.638028 -308.470375) (xy 390.605393 -308.433538) (xy 390.57909 -308.391942)
			(xy 390.559799 -308.346666) (xy 390.548022 -308.298882) (xy 390.544062 -308.249828) (xy 390.205214 -308.249828)
			(xy 390.204719 -308.274435) (xy 390.196824 -308.323012) (xy 390.18124 -308.369693) (xy 390.158369 -308.41327)
			(xy 390.128804 -308.452614) (xy 390.093311 -308.486706) (xy 390.052808 -308.514662) (xy 390.008346 -308.53576)
			(xy 389.961075 -308.549452) (xy 389.91222 -308.555384) (xy 389.863045 -308.553403) (xy 389.814826 -308.543559)
			(xy 389.76881 -308.526107) (xy 389.726189 -308.5015) (xy 389.688068 -308.470375) (xy 389.655433 -308.433538)
			(xy 389.62913 -308.391942) (xy 389.609839 -308.346666) (xy 389.598062 -308.298882) (xy 389.594102 -308.249828)
			(xy 389.255254 -308.249828) (xy 389.254759 -308.274435) (xy 389.246864 -308.323012) (xy 389.23128 -308.369693)
			(xy 389.208409 -308.41327) (xy 389.178844 -308.452614) (xy 389.143351 -308.486706) (xy 389.102848 -308.514662)
			(xy 389.058386 -308.53576) (xy 389.011115 -308.549452) (xy 388.96226 -308.555384) (xy 388.913085 -308.553403)
			(xy 388.864866 -308.543559) (xy 388.81885 -308.526107) (xy 388.776229 -308.5015) (xy 388.738108 -308.470375)
			(xy 388.705473 -308.433538) (xy 388.67917 -308.391942) (xy 388.659879 -308.346666) (xy 388.648102 -308.298882)
			(xy 388.644142 -308.249828) (xy 388.305294 -308.249828) (xy 388.304799 -308.274435) (xy 388.296904 -308.323012)
			(xy 388.28132 -308.369693) (xy 388.258449 -308.41327) (xy 388.228884 -308.452614) (xy 388.193391 -308.486706)
			(xy 388.152888 -308.514662) (xy 388.108426 -308.53576) (xy 388.061155 -308.549452) (xy 388.0123 -308.555384)
			(xy 387.963125 -308.553403) (xy 387.914906 -308.543559) (xy 387.86889 -308.526107) (xy 387.826269 -308.5015)
			(xy 387.788148 -308.470375) (xy 387.755513 -308.433538) (xy 387.72921 -308.391942) (xy 387.709919 -308.346666)
			(xy 387.698142 -308.298882) (xy 387.694182 -308.249828) (xy 387.355334 -308.249828) (xy 387.354839 -308.274435)
			(xy 387.346944 -308.323012) (xy 387.33136 -308.369693) (xy 387.308489 -308.41327) (xy 387.278924 -308.452614)
			(xy 387.243431 -308.486706) (xy 387.202928 -308.514662) (xy 387.158466 -308.53576) (xy 387.111195 -308.549452)
			(xy 387.06234 -308.555384) (xy 387.013165 -308.553403) (xy 386.964946 -308.543559) (xy 386.91893 -308.526107)
			(xy 386.876309 -308.5015) (xy 386.838188 -308.470375) (xy 386.805553 -308.433538) (xy 386.77925 -308.391942)
			(xy 386.759959 -308.346666) (xy 386.748182 -308.298882) (xy 386.744222 -308.249828) (xy 386.426964 -308.249828)
			(xy 386.42646 -308.275536) (xy 386.418417 -308.326318) (xy 386.402529 -308.375217) (xy 386.379186 -308.421029)
			(xy 386.348965 -308.462625) (xy 386.312609 -308.498981) (xy 386.271013 -308.529202) (xy 386.225201 -308.552545)
			(xy 386.176302 -308.568433) (xy 386.12552 -308.576476) (xy 386.074104 -308.576476) (xy 386.023322 -308.568433)
			(xy 385.974423 -308.552545) (xy 385.928611 -308.529202) (xy 385.887015 -308.498981) (xy 385.850659 -308.462625)
			(xy 385.820438 -308.421029) (xy 385.797095 -308.375217) (xy 385.781207 -308.326318) (xy 385.773164 -308.275536)
			(xy 385.4765 -308.275536) (xy 385.468457 -308.326318) (xy 385.452569 -308.375217) (xy 385.429226 -308.421029)
			(xy 385.399005 -308.462625) (xy 385.362649 -308.498981) (xy 385.321053 -308.529202) (xy 385.275241 -308.552545)
			(xy 385.226342 -308.568433) (xy 385.17556 -308.576476) (xy 385.124144 -308.576476) (xy 385.073362 -308.568433)
			(xy 385.024463 -308.552545) (xy 384.978651 -308.529202) (xy 384.937055 -308.498981) (xy 384.900699 -308.462625)
			(xy 384.870478 -308.421029) (xy 384.847135 -308.375217) (xy 384.831247 -308.326318) (xy 384.823204 -308.275536)
			(xy 384.504313 -308.275536) (xy 384.496556 -308.323266) (xy 384.480972 -308.369947) (xy 384.458101 -308.413524)
			(xy 384.428536 -308.452868) (xy 384.393043 -308.48696) (xy 384.35254 -308.514916) (xy 384.308078 -308.536014)
			(xy 384.260807 -308.549706) (xy 384.211952 -308.555638) (xy 384.162777 -308.553657) (xy 384.114558 -308.543813)
			(xy 384.068542 -308.526361) (xy 384.025921 -308.501754) (xy 383.9878 -308.470629) (xy 383.955165 -308.433792)
			(xy 383.928862 -308.392196) (xy 383.909571 -308.34692) (xy 383.897794 -308.299136) (xy 383.893834 -308.250082)
			(xy 377.084479 -308.250082) (xy 377.093371 -308.263522) (xy 377.117043 -308.314019) (xy 377.133111 -308.367426)
			(xy 377.141231 -308.422602) (xy 377.14174 -308.450488) (xy 377.141231 -308.478374) (xy 377.133111 -308.53355)
			(xy 377.117043 -308.586957) (xy 377.093371 -308.637454) (xy 377.078766 -308.65953) (xy 378.705616 -308.65953)
			(xy 378.709687 -308.603908) (xy 378.721813 -308.549471) (xy 378.741736 -308.49738) (xy 378.769032 -308.448745)
			(xy 378.803118 -308.404602) (xy 378.843267 -308.365893) (xy 378.888625 -308.333442) (xy 378.938225 -308.307941)
			(xy 378.991009 -308.289934) (xy 379.045852 -308.279804) (xy 379.101586 -308.277767) (xy 379.157023 -308.283867)
			(xy 379.21098 -308.297973) (xy 379.262309 -308.319785) (xy 379.309915 -308.348839) (xy 379.352783 -308.384514)
			(xy 379.39 -308.426051) (xy 379.420773 -308.472564) (xy 379.444445 -308.523061) (xy 379.460513 -308.576468)
			(xy 379.468633 -308.631644) (xy 379.469142 -308.65953) (xy 379.468633 -308.687416) (xy 379.460513 -308.742592)
			(xy 379.444445 -308.795999) (xy 379.420773 -308.846496) (xy 379.39 -308.893009) (xy 379.352783 -308.934546)
			(xy 379.309915 -308.970221) (xy 379.262309 -308.999275) (xy 379.21098 -309.021087) (xy 379.157023 -309.035193)
			(xy 379.101586 -309.041293) (xy 379.045852 -309.039256) (xy 378.991009 -309.029126) (xy 378.938225 -309.011119)
			(xy 378.888625 -308.985618) (xy 378.843267 -308.953167) (xy 378.803118 -308.914458) (xy 378.769032 -308.870315)
			(xy 378.741736 -308.82168) (xy 378.721813 -308.769589) (xy 378.709687 -308.715152) (xy 378.705616 -308.65953)
			(xy 377.078766 -308.65953) (xy 377.062598 -308.683967) (xy 377.025381 -308.725504) (xy 376.982513 -308.761179)
			(xy 376.934907 -308.790233) (xy 376.883578 -308.812045) (xy 376.829621 -308.826151) (xy 376.774184 -308.832251)
			(xy 376.71845 -308.830214) (xy 376.663607 -308.820084) (xy 376.610823 -308.802077) (xy 376.561223 -308.776576)
			(xy 376.515865 -308.744125) (xy 376.475716 -308.705416) (xy 376.44163 -308.661273) (xy 376.414334 -308.612638)
			(xy 376.394411 -308.560547) (xy 376.382285 -308.50611) (xy 376.378214 -308.450488) (xy 351.03308 -308.450488)
			(xy 351.03308 -309.414926) (xy 375.299984 -309.414926) (xy 375.304055 -309.359304) (xy 375.316181 -309.304867)
			(xy 375.336104 -309.252776) (xy 375.3634 -309.204141) (xy 375.397486 -309.159998) (xy 375.437635 -309.121289)
			(xy 375.482993 -309.088838) (xy 375.532593 -309.063337) (xy 375.585377 -309.04533) (xy 375.64022 -309.0352)
			(xy 375.695954 -309.033163) (xy 375.751391 -309.039263) (xy 375.805348 -309.053369) (xy 375.856677 -309.075181)
			(xy 375.904283 -309.104235) (xy 375.947151 -309.13991) (xy 375.984368 -309.181447) (xy 375.996502 -309.199788)
			(xy 384.844048 -309.199788) (xy 384.848008 -309.150734) (xy 384.859785 -309.10295) (xy 384.879076 -309.057674)
			(xy 384.905379 -309.016078) (xy 384.938014 -308.979241) (xy 384.976135 -308.948116) (xy 385.018756 -308.923509)
			(xy 385.064772 -308.906057) (xy 385.112991 -308.896213) (xy 385.162166 -308.894232) (xy 385.211021 -308.900164)
			(xy 385.258292 -308.913856) (xy 385.302754 -308.934954) (xy 385.343257 -308.96291) (xy 385.37875 -308.997002)
			(xy 385.408315 -309.036346) (xy 385.431186 -309.079923) (xy 385.44677 -309.126604) (xy 385.454665 -309.175181)
			(xy 385.45516 -309.199788) (xy 385.794008 -309.199788) (xy 385.797968 -309.150734) (xy 385.809745 -309.10295)
			(xy 385.829036 -309.057674) (xy 385.855339 -309.016078) (xy 385.887974 -308.979241) (xy 385.926095 -308.948116)
			(xy 385.968716 -308.923509) (xy 386.014732 -308.906057) (xy 386.062951 -308.896213) (xy 386.112126 -308.894232)
			(xy 386.160981 -308.900164) (xy 386.208252 -308.913856) (xy 386.252714 -308.934954) (xy 386.293217 -308.96291)
			(xy 386.32871 -308.997002) (xy 386.358275 -309.036346) (xy 386.381146 -309.079923) (xy 386.39673 -309.126604)
			(xy 386.404625 -309.175181) (xy 386.40512 -309.199788) (xy 386.404625 -309.224395) (xy 386.404446 -309.225496)
			(xy 386.723378 -309.225496) (xy 386.723378 -309.17408) (xy 386.731421 -309.123298) (xy 386.747309 -309.074399)
			(xy 386.770652 -309.028587) (xy 386.800873 -308.986991) (xy 386.837229 -308.950635) (xy 386.878825 -308.920414)
			(xy 386.924637 -308.897071) (xy 386.973536 -308.881183) (xy 387.024318 -308.87314) (xy 387.075734 -308.87314)
			(xy 387.126516 -308.881183) (xy 387.175415 -308.897071) (xy 387.221227 -308.920414) (xy 387.262823 -308.950635)
			(xy 387.299179 -308.986991) (xy 387.3294 -309.028587) (xy 387.352743 -309.074399) (xy 387.368631 -309.123298)
			(xy 387.376674 -309.17408) (xy 387.377178 -309.199788) (xy 387.376674 -309.225496) (xy 387.673338 -309.225496)
			(xy 387.673338 -309.17408) (xy 387.681381 -309.123298) (xy 387.697269 -309.074399) (xy 387.720612 -309.028587)
			(xy 387.750833 -308.986991) (xy 387.787189 -308.950635) (xy 387.828785 -308.920414) (xy 387.874597 -308.897071)
			(xy 387.923496 -308.881183) (xy 387.974278 -308.87314) (xy 388.025694 -308.87314) (xy 388.076476 -308.881183)
			(xy 388.125375 -308.897071) (xy 388.171187 -308.920414) (xy 388.212783 -308.950635) (xy 388.249139 -308.986991)
			(xy 388.27936 -309.028587) (xy 388.302703 -309.074399) (xy 388.318591 -309.123298) (xy 388.326634 -309.17408)
			(xy 388.327138 -309.199788) (xy 388.644142 -309.199788) (xy 388.648102 -309.150734) (xy 388.659879 -309.10295)
			(xy 388.67917 -309.057674) (xy 388.705473 -309.016078) (xy 388.738108 -308.979241) (xy 388.776229 -308.948116)
			(xy 388.81885 -308.923509) (xy 388.864866 -308.906057) (xy 388.913085 -308.896213) (xy 388.96226 -308.894232)
			(xy 389.011115 -308.900164) (xy 389.058386 -308.913856) (xy 389.102848 -308.934954) (xy 389.143351 -308.96291)
			(xy 389.178844 -308.997002) (xy 389.208409 -309.036346) (xy 389.23128 -309.079923) (xy 389.246864 -309.126604)
			(xy 389.254759 -309.175181) (xy 389.255254 -309.199788) (xy 389.254759 -309.224395) (xy 389.25458 -309.225496)
			(xy 389.573258 -309.225496) (xy 389.573258 -309.17408) (xy 389.581301 -309.123298) (xy 389.597189 -309.074399)
			(xy 389.620532 -309.028587) (xy 389.650753 -308.986991) (xy 389.687109 -308.950635) (xy 389.728705 -308.920414)
			(xy 389.774517 -308.897071) (xy 389.823416 -308.881183) (xy 389.874198 -308.87314) (xy 389.925614 -308.87314)
			(xy 389.976396 -308.881183) (xy 390.025295 -308.897071) (xy 390.071107 -308.920414) (xy 390.112703 -308.950635)
			(xy 390.149059 -308.986991) (xy 390.17928 -309.028587) (xy 390.202623 -309.074399) (xy 390.218511 -309.123298)
			(xy 390.226554 -309.17408) (xy 390.227058 -309.199788) (xy 390.226554 -309.225496) (xy 390.523218 -309.225496)
			(xy 390.523218 -309.17408) (xy 390.531261 -309.123298) (xy 390.547149 -309.074399) (xy 390.570492 -309.028587)
			(xy 390.600713 -308.986991) (xy 390.637069 -308.950635) (xy 390.678665 -308.920414) (xy 390.724477 -308.897071)
			(xy 390.773376 -308.881183) (xy 390.824158 -308.87314) (xy 390.875574 -308.87314) (xy 390.926356 -308.881183)
			(xy 390.975255 -308.897071) (xy 391.021067 -308.920414) (xy 391.062663 -308.950635) (xy 391.099019 -308.986991)
			(xy 391.12924 -309.028587) (xy 391.152583 -309.074399) (xy 391.168471 -309.123298) (xy 391.176514 -309.17408)
			(xy 391.177018 -309.199788) (xy 391.494022 -309.199788) (xy 391.497982 -309.150734) (xy 391.509759 -309.10295)
			(xy 391.52905 -309.057674) (xy 391.555353 -309.016078) (xy 391.587988 -308.979241) (xy 391.626109 -308.948116)
			(xy 391.66873 -308.923509) (xy 391.714746 -308.906057) (xy 391.762965 -308.896213) (xy 391.81214 -308.894232)
			(xy 391.860995 -308.900164) (xy 391.908266 -308.913856) (xy 391.952728 -308.934954) (xy 391.993231 -308.96291)
			(xy 392.028724 -308.997002) (xy 392.058289 -309.036346) (xy 392.08116 -309.079923) (xy 392.096744 -309.126604)
			(xy 392.104639 -309.175181) (xy 392.105134 -309.199788) (xy 392.443982 -309.199788) (xy 392.447942 -309.150734)
			(xy 392.459719 -309.10295) (xy 392.47901 -309.057674) (xy 392.505313 -309.016078) (xy 392.537948 -308.979241)
			(xy 392.576069 -308.948116) (xy 392.61869 -308.923509) (xy 392.664706 -308.906057) (xy 392.712925 -308.896213)
			(xy 392.7621 -308.894232) (xy 392.810955 -308.900164) (xy 392.858226 -308.913856) (xy 392.902688 -308.934954)
			(xy 392.943191 -308.96291) (xy 392.978684 -308.997002) (xy 393.008249 -309.036346) (xy 393.03112 -309.079923)
			(xy 393.046704 -309.126604) (xy 393.054599 -309.175181) (xy 393.055094 -309.199788) (xy 393.394196 -309.199788)
			(xy 393.398156 -309.150734) (xy 393.409933 -309.10295) (xy 393.429224 -309.057674) (xy 393.455527 -309.016078)
			(xy 393.488162 -308.979241) (xy 393.526283 -308.948116) (xy 393.568904 -308.923509) (xy 393.61492 -308.906057)
			(xy 393.663139 -308.896213) (xy 393.712314 -308.894232) (xy 393.761169 -308.900164) (xy 393.80844 -308.913856)
			(xy 393.852902 -308.934954) (xy 393.893405 -308.96291) (xy 393.928898 -308.997002) (xy 393.958463 -309.036346)
			(xy 393.981334 -309.079923) (xy 393.996918 -309.126604) (xy 394.004813 -309.175181) (xy 394.005142 -309.191549)
			(xy 394.344268 -309.191549) (xy 394.349631 -309.142197) (xy 394.362906 -309.094362) (xy 394.383746 -309.049305)
			(xy 394.4116 -309.008213) (xy 394.445735 -308.972169) (xy 394.485252 -308.942122) (xy 394.529109 -308.918864)
			(xy 394.576151 -308.903007) (xy 394.625139 -308.894969) (xy 394.64996 -308.89448) (xy 394.664143 -308.894662)
			(xy 394.692383 -308.897331) (xy 394.706348 -308.899814) (xy 394.720306 -308.902031) (xy 394.748443 -308.89944)
			(xy 394.774793 -308.88924) (xy 394.797341 -308.872212) (xy 394.814361 -308.849657) (xy 394.82455 -308.823302)
			(xy 394.827129 -308.795165) (xy 394.824966 -308.781196) (xy 394.822494 -308.767229) (xy 394.819819 -308.73899)
			(xy 394.819632 -308.724808) (xy 394.820069 -308.699987) (xy 394.828099 -308.650999) (xy 394.843948 -308.603955)
			(xy 394.867199 -308.560095) (xy 394.89724 -308.520574) (xy 394.933278 -308.486434) (xy 394.974365 -308.458573)
			(xy 395.019417 -308.437727) (xy 395.067249 -308.424444) (xy 395.1166 -308.419074) (xy 395.166169 -308.421758)
			(xy 395.214651 -308.432426) (xy 395.260768 -308.450798) (xy 395.303306 -308.476388) (xy 395.341144 -308.508522)
			(xy 395.373284 -308.546355) (xy 395.398881 -308.588889) (xy 395.417259 -308.635003) (xy 395.427935 -308.683484)
			(xy 395.43018 -308.724808) (xy 395.769096 -308.724808) (xy 395.773056 -308.675754) (xy 395.784833 -308.62797)
			(xy 395.804124 -308.582694) (xy 395.830427 -308.541098) (xy 395.863062 -308.504261) (xy 395.901183 -308.473136)
			(xy 395.943804 -308.448529) (xy 395.98982 -308.431077) (xy 396.038039 -308.421233) (xy 396.087214 -308.419252)
			(xy 396.136069 -308.425184) (xy 396.18334 -308.438876) (xy 396.227802 -308.459974) (xy 396.268305 -308.48793)
			(xy 396.303798 -308.522022) (xy 396.333363 -308.561366) (xy 396.356234 -308.604943) (xy 396.371818 -308.651624)
			(xy 396.379713 -308.700201) (xy 396.380208 -308.724808) (xy 396.719056 -308.724808) (xy 396.723016 -308.675754)
			(xy 396.734793 -308.62797) (xy 396.754084 -308.582694) (xy 396.780387 -308.541098) (xy 396.813022 -308.504261)
			(xy 396.851143 -308.473136) (xy 396.893764 -308.448529) (xy 396.93978 -308.431077) (xy 396.987999 -308.421233)
			(xy 397.037174 -308.419252) (xy 397.086029 -308.425184) (xy 397.1333 -308.438876) (xy 397.177762 -308.459974)
			(xy 397.218265 -308.48793) (xy 397.253758 -308.522022) (xy 397.283323 -308.561366) (xy 397.306194 -308.604943)
			(xy 397.321778 -308.651624) (xy 397.329673 -308.700201) (xy 397.330168 -308.724808) (xy 397.669016 -308.724808)
			(xy 397.672976 -308.675754) (xy 397.684753 -308.62797) (xy 397.704044 -308.582694) (xy 397.730347 -308.541098)
			(xy 397.762982 -308.504261) (xy 397.801103 -308.473136) (xy 397.843724 -308.448529) (xy 397.88974 -308.431077)
			(xy 397.937959 -308.421233) (xy 397.987134 -308.419252) (xy 398.035989 -308.425184) (xy 398.08326 -308.438876)
			(xy 398.127722 -308.459974) (xy 398.168225 -308.48793) (xy 398.203718 -308.522022) (xy 398.233283 -308.561366)
			(xy 398.256154 -308.604943) (xy 398.271738 -308.651624) (xy 398.279633 -308.700201) (xy 398.280128 -308.724808)
			(xy 398.61923 -308.724808) (xy 398.62319 -308.675754) (xy 398.634967 -308.62797) (xy 398.654258 -308.582694)
			(xy 398.680561 -308.541098) (xy 398.713196 -308.504261) (xy 398.751317 -308.473136) (xy 398.793938 -308.448529)
			(xy 398.839954 -308.431077) (xy 398.888173 -308.421233) (xy 398.937348 -308.419252) (xy 398.986203 -308.425184)
			(xy 399.033474 -308.438876) (xy 399.077936 -308.459974) (xy 399.118439 -308.48793) (xy 399.153932 -308.522022)
			(xy 399.183497 -308.561366) (xy 399.206368 -308.604943) (xy 399.221952 -308.651624) (xy 399.229847 -308.700201)
			(xy 399.230342 -308.724808) (xy 399.56919 -308.724808) (xy 399.57315 -308.675754) (xy 399.584927 -308.62797)
			(xy 399.604218 -308.582694) (xy 399.630521 -308.541098) (xy 399.663156 -308.504261) (xy 399.701277 -308.473136)
			(xy 399.743898 -308.448529) (xy 399.789914 -308.431077) (xy 399.838133 -308.421233) (xy 399.887308 -308.419252)
			(xy 399.936163 -308.425184) (xy 399.983434 -308.438876) (xy 400.027896 -308.459974) (xy 400.068399 -308.48793)
			(xy 400.103892 -308.522022) (xy 400.133457 -308.561366) (xy 400.156328 -308.604943) (xy 400.171912 -308.651624)
			(xy 400.179807 -308.700201) (xy 400.180302 -308.724808) (xy 400.51915 -308.724808) (xy 400.52311 -308.675754)
			(xy 400.534887 -308.62797) (xy 400.554178 -308.582694) (xy 400.580481 -308.541098) (xy 400.613116 -308.504261)
			(xy 400.651237 -308.473136) (xy 400.693858 -308.448529) (xy 400.739874 -308.431077) (xy 400.788093 -308.421233)
			(xy 400.837268 -308.419252) (xy 400.886123 -308.425184) (xy 400.933394 -308.438876) (xy 400.977856 -308.459974)
			(xy 401.018359 -308.48793) (xy 401.053852 -308.522022) (xy 401.083417 -308.561366) (xy 401.106288 -308.604943)
			(xy 401.121872 -308.651624) (xy 401.129767 -308.700201) (xy 401.130262 -308.724808) (xy 401.46911 -308.724808)
			(xy 401.47307 -308.675754) (xy 401.484847 -308.62797) (xy 401.504138 -308.582694) (xy 401.530441 -308.541098)
			(xy 401.563076 -308.504261) (xy 401.601197 -308.473136) (xy 401.643818 -308.448529) (xy 401.689834 -308.431077)
			(xy 401.738053 -308.421233) (xy 401.787228 -308.419252) (xy 401.836083 -308.425184) (xy 401.883354 -308.438876)
			(xy 401.927816 -308.459974) (xy 401.968319 -308.48793) (xy 402.003812 -308.522022) (xy 402.033377 -308.561366)
			(xy 402.056248 -308.604943) (xy 402.071832 -308.651624) (xy 402.079727 -308.700201) (xy 402.080222 -308.724808)
			(xy 402.41907 -308.724808) (xy 402.42303 -308.675754) (xy 402.434807 -308.62797) (xy 402.454098 -308.582694)
			(xy 402.480401 -308.541098) (xy 402.513036 -308.504261) (xy 402.551157 -308.473136) (xy 402.593778 -308.448529)
			(xy 402.639794 -308.431077) (xy 402.688013 -308.421233) (xy 402.737188 -308.419252) (xy 402.786043 -308.425184)
			(xy 402.833314 -308.438876) (xy 402.877776 -308.459974) (xy 402.918279 -308.48793) (xy 402.953772 -308.522022)
			(xy 402.983337 -308.561366) (xy 403.006208 -308.604943) (xy 403.021792 -308.651624) (xy 403.029687 -308.700201)
			(xy 403.030182 -308.724808) (xy 403.030015 -308.733103) (xy 403.369048 -308.733103) (xy 403.371732 -308.683527)
			(xy 403.382403 -308.635038) (xy 403.400777 -308.588915) (xy 403.426371 -308.546372) (xy 403.458512 -308.50853)
			(xy 403.496351 -308.476387) (xy 403.538892 -308.450789) (xy 403.585013 -308.43241) (xy 403.633501 -308.421736)
			(xy 403.683077 -308.419047) (xy 403.732435 -308.424414) (xy 403.780274 -308.437696) (xy 403.825334 -308.458543)
			(xy 403.866428 -308.486405) (xy 403.902472 -308.520548) (xy 403.932518 -308.560073) (xy 403.955773 -308.603939)
			(xy 403.971625 -308.650989) (xy 403.979657 -308.699984) (xy 403.980142 -308.724808) (xy 403.979966 -308.738991)
			(xy 403.977293 -308.767231) (xy 403.974808 -308.781196) (xy 403.972522 -308.793642) (xy 403.979888 -308.817264)
			(xy 404.057358 -308.894734) (xy 404.08098 -308.9021) (xy 404.093426 -308.899814) (xy 404.107392 -308.897338)
			(xy 404.135631 -308.894666) (xy 404.149814 -308.89448) (xy 404.164061 -308.894646) (xy 404.192429 -308.897316)
			(xy 404.206456 -308.899814) (xy 404.218648 -308.9021) (xy 404.242778 -308.894734) (xy 404.319994 -308.817518)
			(xy 404.32736 -308.793642) (xy 404.325074 -308.781196) (xy 404.322601 -308.76723) (xy 404.319927 -308.73899)
			(xy 404.31974 -308.724808) (xy 404.320169 -308.699987) (xy 404.328199 -308.650999) (xy 404.344048 -308.603956)
			(xy 404.367299 -308.560096) (xy 404.397339 -308.520575) (xy 404.433377 -308.486435) (xy 404.474463 -308.458574)
			(xy 404.519515 -308.437728) (xy 404.567347 -308.424444) (xy 404.616697 -308.419074) (xy 404.666266 -308.421758)
			(xy 404.714748 -308.432426) (xy 404.760865 -308.450796) (xy 404.803403 -308.476385) (xy 404.841241 -308.508519)
			(xy 404.873382 -308.546351) (xy 404.898979 -308.588885) (xy 404.917358 -308.634999) (xy 404.928035 -308.683478)
			(xy 404.93028 -308.724808) (xy 406.219164 -308.724808) (xy 406.223124 -308.675754) (xy 406.234901 -308.62797)
			(xy 406.254192 -308.582694) (xy 406.280495 -308.541098) (xy 406.31313 -308.504261) (xy 406.351251 -308.473136)
			(xy 406.393872 -308.448529) (xy 406.439888 -308.431077) (xy 406.488107 -308.421233) (xy 406.537282 -308.419252)
			(xy 406.586137 -308.425184) (xy 406.633408 -308.438876) (xy 406.67787 -308.459974) (xy 406.718373 -308.48793)
			(xy 406.753866 -308.522022) (xy 406.783431 -308.561366) (xy 406.806302 -308.604943) (xy 406.821886 -308.651624)
			(xy 406.829781 -308.700201) (xy 406.830276 -308.724808) (xy 406.83011 -308.733071) (xy 408.119193 -308.733071)
			(xy 408.121882 -308.683504) (xy 408.132555 -308.635025) (xy 408.15093 -308.588912) (xy 408.176523 -308.546379)
			(xy 408.20866 -308.508546) (xy 408.246495 -308.476411) (xy 408.28903 -308.450821) (xy 408.335144 -308.432449)
			(xy 408.383624 -308.421779) (xy 408.433191 -308.419093) (xy 408.482539 -308.424462) (xy 408.530369 -308.437743)
			(xy 408.57542 -308.458588) (xy 408.616505 -308.486446) (xy 408.652543 -308.520584) (xy 408.682582 -308.560103)
			(xy 408.705833 -308.603961) (xy 408.721681 -308.651002) (xy 408.729711 -308.699988) (xy 408.730196 -308.724808)
			(xy 408.730021 -308.738991) (xy 408.727348 -308.767231) (xy 408.724862 -308.781196) (xy 408.722576 -308.793642)
			(xy 408.729942 -308.817264) (xy 408.807412 -308.894734) (xy 408.831034 -308.9021) (xy 408.84348 -308.899814)
			(xy 408.857445 -308.897331) (xy 408.885685 -308.894663) (xy 408.899868 -308.89448) (xy 408.914051 -308.894661)
			(xy 408.942291 -308.89733) (xy 408.956256 -308.899814) (xy 408.968702 -308.9021) (xy 408.992324 -308.894734)
			(xy 409.069794 -308.817264) (xy 409.07716 -308.793642) (xy 409.074874 -308.781196) (xy 409.072401 -308.76723)
			(xy 409.069727 -308.73899) (xy 409.06954 -308.724808) (xy 409.070062 -308.699553) (xy 409.078375 -308.649731)
			(xy 409.094776 -308.601957) (xy 409.118817 -308.557534) (xy 409.149841 -308.517674) (xy 409.187003 -308.483464)
			(xy 409.229289 -308.455838) (xy 409.275545 -308.435548) (xy 409.32451 -308.423148) (xy 409.374848 -308.418977)
			(xy 409.425186 -308.423148) (xy 409.474151 -308.435548) (xy 409.520407 -308.455838) (xy 409.562693 -308.483464)
			(xy 409.599855 -308.517674) (xy 409.630879 -308.557534) (xy 409.65492 -308.601957) (xy 409.671321 -308.649731)
			(xy 409.679634 -308.699553) (xy 409.680156 -308.724808) (xy 409.679981 -308.738991) (xy 409.677308 -308.767231)
			(xy 409.674822 -308.781196) (xy 409.672536 -308.793642) (xy 409.679902 -308.817264) (xy 409.757372 -308.894734)
			(xy 409.780994 -308.9021) (xy 409.79344 -308.899814) (xy 409.807406 -308.897336) (xy 409.835645 -308.894665)
			(xy 409.849828 -308.89448) (xy 409.864011 -308.894653) (xy 409.892251 -308.897328) (xy 409.906216 -308.899814)
			(xy 409.918662 -308.9021) (xy 409.942284 -308.894734) (xy 410.019754 -308.817264) (xy 410.02712 -308.793642)
			(xy 410.024834 -308.781196) (xy 410.022361 -308.76723) (xy 410.019687 -308.73899) (xy 410.0195 -308.724808)
			(xy 410.019969 -308.699986) (xy 410.027999 -308.650997) (xy 410.043849 -308.603952) (xy 410.067101 -308.560092)
			(xy 410.097143 -308.52057) (xy 410.133183 -308.48643) (xy 410.174271 -308.45857) (xy 410.219325 -308.437724)
			(xy 410.267158 -308.424442) (xy 410.31651 -308.419073) (xy 410.36608 -308.42176) (xy 410.414563 -308.43243)
			(xy 410.460681 -308.450804) (xy 410.503218 -308.476396) (xy 410.541055 -308.508534) (xy 410.573194 -308.546369)
			(xy 410.598789 -308.588905) (xy 410.617165 -308.635022) (xy 410.627838 -308.683504) (xy 410.630065 -308.724554)
			(xy 410.968964 -308.724554) (xy 410.972924 -308.6755) (xy 410.984701 -308.627716) (xy 411.003992 -308.58244)
			(xy 411.030295 -308.540844) (xy 411.06293 -308.504007) (xy 411.101051 -308.472882) (xy 411.143672 -308.448275)
			(xy 411.189688 -308.430823) (xy 411.237907 -308.420979) (xy 411.287082 -308.418998) (xy 411.335937 -308.42493)
			(xy 411.383208 -308.438622) (xy 411.42767 -308.45972) (xy 411.468173 -308.487676) (xy 411.503666 -308.521768)
			(xy 411.533231 -308.561112) (xy 411.556102 -308.604689) (xy 411.571686 -308.65137) (xy 411.579581 -308.699947)
			(xy 411.580076 -308.724554) (xy 411.580071 -308.724808) (xy 411.919178 -308.724808) (xy 411.923138 -308.675754)
			(xy 411.934915 -308.62797) (xy 411.954206 -308.582694) (xy 411.980509 -308.541098) (xy 412.013144 -308.504261)
			(xy 412.051265 -308.473136) (xy 412.093886 -308.448529) (xy 412.139902 -308.431077) (xy 412.188121 -308.421233)
			(xy 412.237296 -308.419252) (xy 412.286151 -308.425184) (xy 412.333422 -308.438876) (xy 412.377884 -308.459974)
			(xy 412.418387 -308.48793) (xy 412.45388 -308.522022) (xy 412.483445 -308.561366) (xy 412.506316 -308.604943)
			(xy 412.5219 -308.651624) (xy 412.529795 -308.700201) (xy 412.53029 -308.724808) (xy 412.869138 -308.724808)
			(xy 412.873098 -308.675754) (xy 412.884875 -308.62797) (xy 412.904166 -308.582694) (xy 412.930469 -308.541098)
			(xy 412.963104 -308.504261) (xy 413.001225 -308.473136) (xy 413.043846 -308.448529) (xy 413.089862 -308.431077)
			(xy 413.138081 -308.421233) (xy 413.187256 -308.419252) (xy 413.236111 -308.425184) (xy 413.283382 -308.438876)
			(xy 413.327844 -308.459974) (xy 413.368347 -308.48793) (xy 413.40384 -308.522022) (xy 413.433405 -308.561366)
			(xy 413.456276 -308.604943) (xy 413.47186 -308.651624) (xy 413.479755 -308.700201) (xy 413.48025 -308.724808)
			(xy 413.819098 -308.724808) (xy 413.823058 -308.675754) (xy 413.834835 -308.62797) (xy 413.854126 -308.582694)
			(xy 413.880429 -308.541098) (xy 413.913064 -308.504261) (xy 413.951185 -308.473136) (xy 413.993806 -308.448529)
			(xy 414.039822 -308.431077) (xy 414.088041 -308.421233) (xy 414.137216 -308.419252) (xy 414.186071 -308.425184)
			(xy 414.233342 -308.438876) (xy 414.277804 -308.459974) (xy 414.318307 -308.48793) (xy 414.3538 -308.522022)
			(xy 414.383365 -308.561366) (xy 414.406236 -308.604943) (xy 414.42182 -308.651624) (xy 414.429715 -308.700201)
			(xy 414.43021 -308.724808) (xy 414.769058 -308.724808) (xy 414.773018 -308.675754) (xy 414.784795 -308.62797)
			(xy 414.804086 -308.582694) (xy 414.830389 -308.541098) (xy 414.863024 -308.504261) (xy 414.901145 -308.473136)
			(xy 414.943766 -308.448529) (xy 414.989782 -308.431077) (xy 415.038001 -308.421233) (xy 415.087176 -308.419252)
			(xy 415.136031 -308.425184) (xy 415.183302 -308.438876) (xy 415.227764 -308.459974) (xy 415.268267 -308.48793)
			(xy 415.30376 -308.522022) (xy 415.333325 -308.561366) (xy 415.356196 -308.604943) (xy 415.37178 -308.651624)
			(xy 415.379675 -308.700201) (xy 415.38017 -308.724808) (xy 415.719018 -308.724808) (xy 415.722978 -308.675754)
			(xy 415.734755 -308.62797) (xy 415.754046 -308.582694) (xy 415.780349 -308.541098) (xy 415.812984 -308.504261)
			(xy 415.851105 -308.473136) (xy 415.893726 -308.448529) (xy 415.939742 -308.431077) (xy 415.987961 -308.421233)
			(xy 416.037136 -308.419252) (xy 416.085991 -308.425184) (xy 416.133262 -308.438876) (xy 416.177724 -308.459974)
			(xy 416.218227 -308.48793) (xy 416.25372 -308.522022) (xy 416.283285 -308.561366) (xy 416.306156 -308.604943)
			(xy 416.32174 -308.651624) (xy 416.329635 -308.700201) (xy 416.33013 -308.724808) (xy 416.669232 -308.724808)
			(xy 416.673192 -308.675754) (xy 416.684969 -308.62797) (xy 416.70426 -308.582694) (xy 416.730563 -308.541098)
			(xy 416.763198 -308.504261) (xy 416.801319 -308.473136) (xy 416.84394 -308.448529) (xy 416.889956 -308.431077)
			(xy 416.938175 -308.421233) (xy 416.98735 -308.419252) (xy 417.036205 -308.425184) (xy 417.083476 -308.438876)
			(xy 417.127938 -308.459974) (xy 417.168441 -308.48793) (xy 417.203934 -308.522022) (xy 417.233499 -308.561366)
			(xy 417.25637 -308.604943) (xy 417.271954 -308.651624) (xy 417.279849 -308.700201) (xy 417.280344 -308.724808)
			(xy 417.279849 -308.749415) (xy 417.271954 -308.797992) (xy 417.25637 -308.844673) (xy 417.233499 -308.88825)
			(xy 417.203934 -308.927594) (xy 417.168441 -308.961686) (xy 417.127938 -308.989642) (xy 417.083476 -309.01074)
			(xy 417.036205 -309.024432) (xy 416.98735 -309.030364) (xy 416.938175 -309.028383) (xy 416.889956 -309.018539)
			(xy 416.84394 -309.001087) (xy 416.801319 -308.97648) (xy 416.763198 -308.945355) (xy 416.730563 -308.908518)
			(xy 416.70426 -308.866922) (xy 416.684969 -308.821646) (xy 416.673192 -308.773862) (xy 416.669232 -308.724808)
			(xy 416.33013 -308.724808) (xy 416.329635 -308.749415) (xy 416.32174 -308.797992) (xy 416.306156 -308.844673)
			(xy 416.283285 -308.88825) (xy 416.25372 -308.927594) (xy 416.218227 -308.961686) (xy 416.177724 -308.989642)
			(xy 416.133262 -309.01074) (xy 416.085991 -309.024432) (xy 416.037136 -309.030364) (xy 415.987961 -309.028383)
			(xy 415.939742 -309.018539) (xy 415.893726 -309.001087) (xy 415.851105 -308.97648) (xy 415.812984 -308.945355)
			(xy 415.780349 -308.908518) (xy 415.754046 -308.866922) (xy 415.734755 -308.821646) (xy 415.722978 -308.773862)
			(xy 415.719018 -308.724808) (xy 415.38017 -308.724808) (xy 415.379675 -308.749415) (xy 415.37178 -308.797992)
			(xy 415.356196 -308.844673) (xy 415.333325 -308.88825) (xy 415.30376 -308.927594) (xy 415.268267 -308.961686)
			(xy 415.227764 -308.989642) (xy 415.183302 -309.01074) (xy 415.136031 -309.024432) (xy 415.087176 -309.030364)
			(xy 415.038001 -309.028383) (xy 414.989782 -309.018539) (xy 414.943766 -309.001087) (xy 414.901145 -308.97648)
			(xy 414.863024 -308.945355) (xy 414.830389 -308.908518) (xy 414.804086 -308.866922) (xy 414.784795 -308.821646)
			(xy 414.773018 -308.773862) (xy 414.769058 -308.724808) (xy 414.43021 -308.724808) (xy 414.429715 -308.749415)
			(xy 414.42182 -308.797992) (xy 414.406236 -308.844673) (xy 414.383365 -308.88825) (xy 414.3538 -308.927594)
			(xy 414.318307 -308.961686) (xy 414.277804 -308.989642) (xy 414.233342 -309.01074) (xy 414.186071 -309.024432)
			(xy 414.137216 -309.030364) (xy 414.088041 -309.028383) (xy 414.039822 -309.018539) (xy 413.993806 -309.001087)
			(xy 413.951185 -308.97648) (xy 413.913064 -308.945355) (xy 413.880429 -308.908518) (xy 413.854126 -308.866922)
			(xy 413.834835 -308.821646) (xy 413.823058 -308.773862) (xy 413.819098 -308.724808) (xy 413.48025 -308.724808)
			(xy 413.479755 -308.749415) (xy 413.47186 -308.797992) (xy 413.456276 -308.844673) (xy 413.433405 -308.88825)
			(xy 413.40384 -308.927594) (xy 413.368347 -308.961686) (xy 413.327844 -308.989642) (xy 413.283382 -309.01074)
			(xy 413.236111 -309.024432) (xy 413.187256 -309.030364) (xy 413.138081 -309.028383) (xy 413.089862 -309.018539)
			(xy 413.043846 -309.001087) (xy 413.001225 -308.97648) (xy 412.963104 -308.945355) (xy 412.930469 -308.908518)
			(xy 412.904166 -308.866922) (xy 412.884875 -308.821646) (xy 412.873098 -308.773862) (xy 412.869138 -308.724808)
			(xy 412.53029 -308.724808) (xy 412.529795 -308.749415) (xy 412.5219 -308.797992) (xy 412.506316 -308.844673)
			(xy 412.483445 -308.88825) (xy 412.45388 -308.927594) (xy 412.418387 -308.961686) (xy 412.377884 -308.989642)
			(xy 412.333422 -309.01074) (xy 412.286151 -309.024432) (xy 412.237296 -309.030364) (xy 412.188121 -309.028383)
			(xy 412.139902 -309.018539) (xy 412.093886 -309.001087) (xy 412.051265 -308.97648) (xy 412.013144 -308.945355)
			(xy 411.980509 -308.908518) (xy 411.954206 -308.866922) (xy 411.934915 -308.821646) (xy 411.923138 -308.773862)
			(xy 411.919178 -308.724808) (xy 411.580071 -308.724808) (xy 411.579581 -308.749161) (xy 411.571686 -308.797738)
			(xy 411.556102 -308.844419) (xy 411.533231 -308.887996) (xy 411.503666 -308.92734) (xy 411.468173 -308.961432)
			(xy 411.42767 -308.989388) (xy 411.383208 -309.010486) (xy 411.335937 -309.024178) (xy 411.287082 -309.03011)
			(xy 411.237907 -309.028129) (xy 411.189688 -309.018285) (xy 411.143672 -309.000833) (xy 411.101051 -308.976226)
			(xy 411.06293 -308.945101) (xy 411.030295 -308.908264) (xy 411.003992 -308.866668) (xy 410.984701 -308.821392)
			(xy 410.972924 -308.773608) (xy 410.968964 -308.724554) (xy 410.630065 -308.724554) (xy 410.630527 -308.733074)
			(xy 410.625161 -308.782426) (xy 410.611881 -308.83026) (xy 410.591038 -308.875315) (xy 410.56318 -308.916405)
			(xy 410.529042 -308.952446) (xy 410.489522 -308.98249) (xy 410.445662 -309.005744) (xy 410.398618 -309.021597)
			(xy 410.349629 -309.029629) (xy 410.324808 -309.030116) (xy 410.310625 -309.029938) (xy 410.282385 -309.027267)
			(xy 410.26842 -309.024782) (xy 410.255974 -309.022496) (xy 410.232352 -309.029862) (xy 410.154882 -309.107332)
			(xy 410.147516 -309.130954) (xy 410.149802 -309.1434) (xy 410.152275 -309.157367) (xy 410.154949 -309.185606)
			(xy 410.155136 -309.199788) (xy 410.154614 -309.225043) (xy 410.146301 -309.274865) (xy 410.1299 -309.322639)
			(xy 410.105859 -309.367062) (xy 410.074835 -309.406922) (xy 410.037673 -309.441132) (xy 409.995387 -309.468758)
			(xy 409.949131 -309.489048) (xy 409.900166 -309.501448) (xy 409.849828 -309.505619) (xy 409.79949 -309.501448)
			(xy 409.750525 -309.489048) (xy 409.704269 -309.468758) (xy 409.661983 -309.441132) (xy 409.624821 -309.406922)
			(xy 409.593797 -309.367062) (xy 409.569756 -309.322639) (xy 409.553355 -309.274865) (xy 409.545042 -309.225043)
			(xy 409.54452 -309.199788) (xy 409.544695 -309.185605) (xy 409.547368 -309.157365) (xy 409.549854 -309.1434)
			(xy 409.55214 -309.130954) (xy 409.544774 -309.107332) (xy 409.467304 -309.029862) (xy 409.443682 -309.022496)
			(xy 409.431236 -309.024782) (xy 409.417271 -309.027263) (xy 409.389031 -309.029932) (xy 409.374848 -309.030116)
			(xy 409.360665 -309.029933) (xy 409.332425 -309.027265) (xy 409.31846 -309.024782) (xy 409.306014 -309.022496)
			(xy 409.282392 -309.029862) (xy 409.204922 -309.107332) (xy 409.197556 -309.130954) (xy 409.199842 -309.1434)
			(xy 409.202314 -309.157367) (xy 409.204989 -309.185606) (xy 409.205176 -309.199788) (xy 409.204654 -309.225043)
			(xy 409.196341 -309.274865) (xy 409.17994 -309.322639) (xy 409.155899 -309.367062) (xy 409.124875 -309.406922)
			(xy 409.087713 -309.441132) (xy 409.045427 -309.468758) (xy 408.999171 -309.489048) (xy 408.950206 -309.501448)
			(xy 408.899868 -309.505619) (xy 408.84953 -309.501448) (xy 408.800565 -309.489048) (xy 408.754309 -309.468758)
			(xy 408.712023 -309.441132) (xy 408.674861 -309.406922) (xy 408.643837 -309.367062) (xy 408.619796 -309.322639)
			(xy 408.603395 -309.274865) (xy 408.595082 -309.225043) (xy 408.59456 -309.199788) (xy 408.594736 -309.185605)
			(xy 408.597408 -309.157365) (xy 408.599894 -309.1434) (xy 408.60218 -309.130954) (xy 408.594814 -309.107332)
			(xy 408.517344 -309.029862) (xy 408.493722 -309.022496) (xy 408.481276 -309.024782) (xy 408.46731 -309.027258)
			(xy 408.43907 -309.02993) (xy 408.424888 -309.030116) (xy 408.400068 -309.029609) (xy 408.351083 -309.021576)
			(xy 408.304042 -309.005725) (xy 408.260186 -308.982471) (xy 408.220669 -308.952429) (xy 408.186534 -308.91639)
			(xy 408.158678 -308.875303) (xy 408.137836 -308.83025) (xy 408.124558 -308.78242) (xy 408.119193 -308.733071)
			(xy 406.83011 -308.733071) (xy 406.829781 -308.749415) (xy 406.821886 -308.797992) (xy 406.806302 -308.844673)
			(xy 406.783431 -308.88825) (xy 406.753866 -308.927594) (xy 406.718373 -308.961686) (xy 406.67787 -308.989642)
			(xy 406.633408 -309.01074) (xy 406.586137 -309.024432) (xy 406.537282 -309.030364) (xy 406.488107 -309.028383)
			(xy 406.439888 -309.018539) (xy 406.393872 -309.001087) (xy 406.351251 -308.97648) (xy 406.31313 -308.945355)
			(xy 406.280495 -308.908518) (xy 406.254192 -308.866922) (xy 406.234901 -308.821646) (xy 406.223124 -308.773862)
			(xy 406.219164 -308.724808) (xy 404.93028 -308.724808) (xy 404.930728 -308.733047) (xy 404.925366 -308.782398)
			(xy 404.912092 -308.830232) (xy 404.891253 -308.875288) (xy 404.8634 -308.91638) (xy 404.829267 -308.952424)
			(xy 404.789752 -308.982471) (xy 404.745896 -309.00573) (xy 404.698855 -309.021588) (xy 404.649869 -309.029626)
			(xy 404.625048 -309.030116) (xy 404.610801 -309.029949) (xy 404.582434 -309.027276) (xy 404.568406 -309.024782)
			(xy 404.556214 -309.022496) (xy 404.532084 -309.029862) (xy 404.454868 -309.107078) (xy 404.447502 -309.130954)
			(xy 404.449788 -309.1434) (xy 404.45226 -309.157367) (xy 404.454935 -309.185606) (xy 404.455122 -309.199788)
			(xy 404.454943 -309.213971) (xy 404.452273 -309.242211) (xy 404.449788 -309.256176) (xy 404.447502 -309.268622)
			(xy 404.454868 -309.292244) (xy 404.532338 -309.369714) (xy 404.55596 -309.37708) (xy 404.568406 -309.374794)
			(xy 404.582372 -309.372321) (xy 404.610612 -309.369647) (xy 404.624794 -309.36946) (xy 404.648783 -309.369968)
			(xy 404.696172 -309.377472) (xy 404.741803 -309.392297) (xy 404.784554 -309.414077) (xy 404.823371 -309.442276)
			(xy 404.857299 -309.4762) (xy 404.885503 -309.515014) (xy 404.907289 -309.557762) (xy 404.922119 -309.603391)
			(xy 404.929629 -309.650779) (xy 404.930102 -309.674768) (xy 404.929921 -309.688951) (xy 404.927252 -309.717191)
			(xy 404.924768 -309.731156) (xy 404.922482 -309.743602) (xy 404.929848 -309.767478) (xy 405.007064 -309.844694)
			(xy 405.031194 -309.85206) (xy 405.043386 -309.849774) (xy 405.057416 -309.847294) (xy 405.085782 -309.844619)
			(xy 405.100028 -309.84444) (xy 405.114211 -309.844612) (xy 405.142451 -309.847287) (xy 405.156416 -309.849774)
			(xy 405.168862 -309.85206) (xy 405.192484 -309.844694) (xy 405.269954 -309.767224) (xy 405.27732 -309.743602)
			(xy 405.275034 -309.731156) (xy 405.272556 -309.71719) (xy 405.269885 -309.688951) (xy 405.2697 -309.674768)
			(xy 405.270222 -309.649513) (xy 405.278535 -309.599691) (xy 405.294936 -309.551917) (xy 405.318977 -309.507494)
			(xy 405.350001 -309.467634) (xy 405.387163 -309.433424) (xy 405.429449 -309.405798) (xy 405.475705 -309.385508)
			(xy 405.52467 -309.373108) (xy 405.575008 -309.368937) (xy 405.625346 -309.373108) (xy 405.674311 -309.385508)
			(xy 405.720567 -309.405798) (xy 405.762853 -309.433424) (xy 405.800015 -309.467634) (xy 405.831039 -309.507494)
			(xy 405.85508 -309.551917) (xy 405.871481 -309.599691) (xy 405.879794 -309.649513) (xy 405.880316 -309.674768)
			(xy 405.880135 -309.688951) (xy 405.877466 -309.717191) (xy 405.874982 -309.731156) (xy 405.872696 -309.743602)
			(xy 405.880062 -309.767224) (xy 405.957532 -309.844694) (xy 405.981154 -309.85206) (xy 405.9936 -309.849774)
			(xy 406.007566 -309.847301) (xy 406.035806 -309.844627) (xy 406.049988 -309.84444) (xy 406.074809 -309.844865)
			(xy 406.123798 -309.852894) (xy 406.170843 -309.868743) (xy 406.214703 -309.891993) (xy 406.254225 -309.922033)
			(xy 406.288366 -309.958072) (xy 406.316228 -309.999158) (xy 406.337075 -310.044211) (xy 406.350359 -310.092043)
			(xy 406.35573 -310.141394) (xy 406.355278 -310.149748) (xy 406.694144 -310.149748) (xy 406.698104 -310.100694)
			(xy 406.709881 -310.05291) (xy 406.729172 -310.007634) (xy 406.755475 -309.966038) (xy 406.78811 -309.929201)
			(xy 406.826231 -309.898076) (xy 406.868852 -309.873469) (xy 406.914868 -309.856017) (xy 406.963087 -309.846173)
			(xy 407.012262 -309.844192) (xy 407.061117 -309.850124) (xy 407.108388 -309.863816) (xy 407.15285 -309.884914)
			(xy 407.193353 -309.91287) (xy 407.228846 -309.946962) (xy 407.258411 -309.986306) (xy 407.281282 -310.029883)
			(xy 407.296866 -310.076564) (xy 407.304761 -310.125141) (xy 407.305256 -310.149748) (xy 407.644104 -310.149748)
			(xy 407.648064 -310.100694) (xy 407.659841 -310.05291) (xy 407.679132 -310.007634) (xy 407.705435 -309.966038)
			(xy 407.73807 -309.929201) (xy 407.776191 -309.898076) (xy 407.818812 -309.873469) (xy 407.864828 -309.856017)
			(xy 407.913047 -309.846173) (xy 407.962222 -309.844192) (xy 408.011077 -309.850124) (xy 408.058348 -309.863816)
			(xy 408.10281 -309.884914) (xy 408.143313 -309.91287) (xy 408.178806 -309.946962) (xy 408.208371 -309.986306)
			(xy 408.231242 -310.029883) (xy 408.246826 -310.076564) (xy 408.254721 -310.125141) (xy 408.255216 -310.149748)
			(xy 408.594064 -310.149748) (xy 408.598024 -310.100694) (xy 408.609801 -310.05291) (xy 408.629092 -310.007634)
			(xy 408.655395 -309.966038) (xy 408.68803 -309.929201) (xy 408.726151 -309.898076) (xy 408.768772 -309.873469)
			(xy 408.814788 -309.856017) (xy 408.863007 -309.846173) (xy 408.912182 -309.844192) (xy 408.961037 -309.850124)
			(xy 409.008308 -309.863816) (xy 409.05277 -309.884914) (xy 409.093273 -309.91287) (xy 409.128766 -309.946962)
			(xy 409.158331 -309.986306) (xy 409.181202 -310.029883) (xy 409.196786 -310.076564) (xy 409.204681 -310.125141)
			(xy 409.205176 -310.149748) (xy 409.544024 -310.149748) (xy 409.547984 -310.100694) (xy 409.559761 -310.05291)
			(xy 409.579052 -310.007634) (xy 409.605355 -309.966038) (xy 409.63799 -309.929201) (xy 409.676111 -309.898076)
			(xy 409.718732 -309.873469) (xy 409.764748 -309.856017) (xy 409.812967 -309.846173) (xy 409.862142 -309.844192)
			(xy 409.910997 -309.850124) (xy 409.958268 -309.863816) (xy 410.00273 -309.884914) (xy 410.043233 -309.91287)
			(xy 410.078726 -309.946962) (xy 410.108291 -309.986306) (xy 410.131162 -310.029883) (xy 410.146746 -310.076564)
			(xy 410.154641 -310.125141) (xy 410.155136 -310.149748) (xy 410.493984 -310.149748) (xy 410.497944 -310.100694)
			(xy 410.509721 -310.05291) (xy 410.529012 -310.007634) (xy 410.555315 -309.966038) (xy 410.58795 -309.929201)
			(xy 410.626071 -309.898076) (xy 410.668692 -309.873469) (xy 410.714708 -309.856017) (xy 410.762927 -309.846173)
			(xy 410.812102 -309.844192) (xy 410.860957 -309.850124) (xy 410.908228 -309.863816) (xy 410.95269 -309.884914)
			(xy 410.993193 -309.91287) (xy 411.028686 -309.946962) (xy 411.058251 -309.986306) (xy 411.081122 -310.029883)
			(xy 411.096706 -310.076564) (xy 411.104601 -310.125141) (xy 411.105096 -310.149748) (xy 411.444198 -310.149748)
			(xy 411.448158 -310.100694) (xy 411.459935 -310.05291) (xy 411.479226 -310.007634) (xy 411.505529 -309.966038)
			(xy 411.538164 -309.929201) (xy 411.576285 -309.898076) (xy 411.618906 -309.873469) (xy 411.664922 -309.856017)
			(xy 411.713141 -309.846173) (xy 411.762316 -309.844192) (xy 411.811171 -309.850124) (xy 411.858442 -309.863816)
			(xy 411.902904 -309.884914) (xy 411.943407 -309.91287) (xy 411.9789 -309.946962) (xy 412.008465 -309.986306)
			(xy 412.031336 -310.029883) (xy 412.04692 -310.076564) (xy 412.054815 -310.125141) (xy 412.05531 -310.149748)
			(xy 412.394158 -310.149748) (xy 412.398118 -310.100694) (xy 412.409895 -310.05291) (xy 412.429186 -310.007634)
			(xy 412.455489 -309.966038) (xy 412.488124 -309.929201) (xy 412.526245 -309.898076) (xy 412.568866 -309.873469)
			(xy 412.614882 -309.856017) (xy 412.663101 -309.846173) (xy 412.712276 -309.844192) (xy 412.761131 -309.850124)
			(xy 412.808402 -309.863816) (xy 412.852864 -309.884914) (xy 412.893367 -309.91287) (xy 412.92886 -309.946962)
			(xy 412.958425 -309.986306) (xy 412.981296 -310.029883) (xy 412.99688 -310.076564) (xy 413.004775 -310.125141)
			(xy 413.00527 -310.149748) (xy 413.344118 -310.149748) (xy 413.348078 -310.100694) (xy 413.359855 -310.05291)
			(xy 413.379146 -310.007634) (xy 413.405449 -309.966038) (xy 413.438084 -309.929201) (xy 413.476205 -309.898076)
			(xy 413.518826 -309.873469) (xy 413.564842 -309.856017) (xy 413.613061 -309.846173) (xy 413.662236 -309.844192)
			(xy 413.711091 -309.850124) (xy 413.758362 -309.863816) (xy 413.802824 -309.884914) (xy 413.843327 -309.91287)
			(xy 413.87882 -309.946962) (xy 413.908385 -309.986306) (xy 413.931256 -310.029883) (xy 413.94684 -310.076564)
			(xy 413.954735 -310.125141) (xy 413.95523 -310.149748) (xy 414.294078 -310.149748) (xy 414.298038 -310.100694)
			(xy 414.309815 -310.05291) (xy 414.329106 -310.007634) (xy 414.355409 -309.966038) (xy 414.388044 -309.929201)
			(xy 414.426165 -309.898076) (xy 414.468786 -309.873469) (xy 414.514802 -309.856017) (xy 414.563021 -309.846173)
			(xy 414.612196 -309.844192) (xy 414.661051 -309.850124) (xy 414.708322 -309.863816) (xy 414.752784 -309.884914)
			(xy 414.793287 -309.91287) (xy 414.82878 -309.946962) (xy 414.858345 -309.986306) (xy 414.881216 -310.029883)
			(xy 414.8968 -310.076564) (xy 414.904695 -310.125141) (xy 414.90519 -310.149748) (xy 415.244038 -310.149748)
			(xy 415.247998 -310.100694) (xy 415.259775 -310.05291) (xy 415.279066 -310.007634) (xy 415.305369 -309.966038)
			(xy 415.338004 -309.929201) (xy 415.376125 -309.898076) (xy 415.418746 -309.873469) (xy 415.464762 -309.856017)
			(xy 415.512981 -309.846173) (xy 415.562156 -309.844192) (xy 415.611011 -309.850124) (xy 415.658282 -309.863816)
			(xy 415.702744 -309.884914) (xy 415.743247 -309.91287) (xy 415.77874 -309.946962) (xy 415.808305 -309.986306)
			(xy 415.831176 -310.029883) (xy 415.84676 -310.076564) (xy 415.854655 -310.125141) (xy 415.85515 -310.149748)
			(xy 416.193998 -310.149748) (xy 416.197958 -310.100694) (xy 416.209735 -310.05291) (xy 416.229026 -310.007634)
			(xy 416.255329 -309.966038) (xy 416.287964 -309.929201) (xy 416.326085 -309.898076) (xy 416.368706 -309.873469)
			(xy 416.414722 -309.856017) (xy 416.462941 -309.846173) (xy 416.512116 -309.844192) (xy 416.560971 -309.850124)
			(xy 416.608242 -309.863816) (xy 416.652704 -309.884914) (xy 416.693207 -309.91287) (xy 416.7287 -309.946962)
			(xy 416.758265 -309.986306) (xy 416.781136 -310.029883) (xy 416.79672 -310.076564) (xy 416.804615 -310.125141)
			(xy 416.80511 -310.149748) (xy 416.804615 -310.174355) (xy 416.79672 -310.222932) (xy 416.781136 -310.269613)
			(xy 416.758265 -310.31319) (xy 416.7287 -310.352534) (xy 416.693207 -310.386626) (xy 416.652704 -310.414582)
			(xy 416.608242 -310.43568) (xy 416.560971 -310.449372) (xy 416.512116 -310.455304) (xy 416.462941 -310.453323)
			(xy 416.414722 -310.443479) (xy 416.368706 -310.426027) (xy 416.326085 -310.40142) (xy 416.287964 -310.370295)
			(xy 416.255329 -310.333458) (xy 416.229026 -310.291862) (xy 416.209735 -310.246586) (xy 416.197958 -310.198802)
			(xy 416.193998 -310.149748) (xy 415.85515 -310.149748) (xy 415.854655 -310.174355) (xy 415.84676 -310.222932)
			(xy 415.831176 -310.269613) (xy 415.808305 -310.31319) (xy 415.77874 -310.352534) (xy 415.743247 -310.386626)
			(xy 415.702744 -310.414582) (xy 415.658282 -310.43568) (xy 415.611011 -310.449372) (xy 415.562156 -310.455304)
			(xy 415.512981 -310.453323) (xy 415.464762 -310.443479) (xy 415.418746 -310.426027) (xy 415.376125 -310.40142)
			(xy 415.338004 -310.370295) (xy 415.305369 -310.333458) (xy 415.279066 -310.291862) (xy 415.259775 -310.246586)
			(xy 415.247998 -310.198802) (xy 415.244038 -310.149748) (xy 414.90519 -310.149748) (xy 414.904695 -310.174355)
			(xy 414.8968 -310.222932) (xy 414.881216 -310.269613) (xy 414.858345 -310.31319) (xy 414.82878 -310.352534)
			(xy 414.793287 -310.386626) (xy 414.752784 -310.414582) (xy 414.708322 -310.43568) (xy 414.661051 -310.449372)
			(xy 414.612196 -310.455304) (xy 414.563021 -310.453323) (xy 414.514802 -310.443479) (xy 414.468786 -310.426027)
			(xy 414.426165 -310.40142) (xy 414.388044 -310.370295) (xy 414.355409 -310.333458) (xy 414.329106 -310.291862)
			(xy 414.309815 -310.246586) (xy 414.298038 -310.198802) (xy 414.294078 -310.149748) (xy 413.95523 -310.149748)
			(xy 413.954735 -310.174355) (xy 413.94684 -310.222932) (xy 413.931256 -310.269613) (xy 413.908385 -310.31319)
			(xy 413.87882 -310.352534) (xy 413.843327 -310.386626) (xy 413.802824 -310.414582) (xy 413.758362 -310.43568)
			(xy 413.711091 -310.449372) (xy 413.662236 -310.455304) (xy 413.613061 -310.453323) (xy 413.564842 -310.443479)
			(xy 413.518826 -310.426027) (xy 413.476205 -310.40142) (xy 413.438084 -310.370295) (xy 413.405449 -310.333458)
			(xy 413.379146 -310.291862) (xy 413.359855 -310.246586) (xy 413.348078 -310.198802) (xy 413.344118 -310.149748)
			(xy 413.00527 -310.149748) (xy 413.004775 -310.174355) (xy 412.99688 -310.222932) (xy 412.981296 -310.269613)
			(xy 412.958425 -310.31319) (xy 412.92886 -310.352534) (xy 412.893367 -310.386626) (xy 412.852864 -310.414582)
			(xy 412.808402 -310.43568) (xy 412.761131 -310.449372) (xy 412.712276 -310.455304) (xy 412.663101 -310.453323)
			(xy 412.614882 -310.443479) (xy 412.568866 -310.426027) (xy 412.526245 -310.40142) (xy 412.488124 -310.370295)
			(xy 412.455489 -310.333458) (xy 412.429186 -310.291862) (xy 412.409895 -310.246586) (xy 412.398118 -310.198802)
			(xy 412.394158 -310.149748) (xy 412.05531 -310.149748) (xy 412.054815 -310.174355) (xy 412.04692 -310.222932)
			(xy 412.031336 -310.269613) (xy 412.008465 -310.31319) (xy 411.9789 -310.352534) (xy 411.943407 -310.386626)
			(xy 411.902904 -310.414582) (xy 411.858442 -310.43568) (xy 411.811171 -310.449372) (xy 411.762316 -310.455304)
			(xy 411.713141 -310.453323) (xy 411.664922 -310.443479) (xy 411.618906 -310.426027) (xy 411.576285 -310.40142)
			(xy 411.538164 -310.370295) (xy 411.505529 -310.333458) (xy 411.479226 -310.291862) (xy 411.459935 -310.246586)
			(xy 411.448158 -310.198802) (xy 411.444198 -310.149748) (xy 411.105096 -310.149748) (xy 411.104601 -310.174355)
			(xy 411.096706 -310.222932) (xy 411.081122 -310.269613) (xy 411.058251 -310.31319) (xy 411.028686 -310.352534)
			(xy 410.993193 -310.386626) (xy 410.95269 -310.414582) (xy 410.908228 -310.43568) (xy 410.860957 -310.449372)
			(xy 410.812102 -310.455304) (xy 410.762927 -310.453323) (xy 410.714708 -310.443479) (xy 410.668692 -310.426027)
			(xy 410.626071 -310.40142) (xy 410.58795 -310.370295) (xy 410.555315 -310.333458) (xy 410.529012 -310.291862)
			(xy 410.509721 -310.246586) (xy 410.497944 -310.198802) (xy 410.493984 -310.149748) (xy 410.155136 -310.149748)
			(xy 410.154641 -310.174355) (xy 410.146746 -310.222932) (xy 410.131162 -310.269613) (xy 410.108291 -310.31319)
			(xy 410.078726 -310.352534) (xy 410.043233 -310.386626) (xy 410.00273 -310.414582) (xy 409.958268 -310.43568)
			(xy 409.910997 -310.449372) (xy 409.862142 -310.455304) (xy 409.812967 -310.453323) (xy 409.764748 -310.443479)
			(xy 409.718732 -310.426027) (xy 409.676111 -310.40142) (xy 409.63799 -310.370295) (xy 409.605355 -310.333458)
			(xy 409.579052 -310.291862) (xy 409.559761 -310.246586) (xy 409.547984 -310.198802) (xy 409.544024 -310.149748)
			(xy 409.205176 -310.149748) (xy 409.204681 -310.174355) (xy 409.196786 -310.222932) (xy 409.181202 -310.269613)
			(xy 409.158331 -310.31319) (xy 409.128766 -310.352534) (xy 409.093273 -310.386626) (xy 409.05277 -310.414582)
			(xy 409.008308 -310.43568) (xy 408.961037 -310.449372) (xy 408.912182 -310.455304) (xy 408.863007 -310.453323)
			(xy 408.814788 -310.443479) (xy 408.768772 -310.426027) (xy 408.726151 -310.40142) (xy 408.68803 -310.370295)
			(xy 408.655395 -310.333458) (xy 408.629092 -310.291862) (xy 408.609801 -310.246586) (xy 408.598024 -310.198802)
			(xy 408.594064 -310.149748) (xy 408.255216 -310.149748) (xy 408.254721 -310.174355) (xy 408.246826 -310.222932)
			(xy 408.231242 -310.269613) (xy 408.208371 -310.31319) (xy 408.178806 -310.352534) (xy 408.143313 -310.386626)
			(xy 408.10281 -310.414582) (xy 408.058348 -310.43568) (xy 408.011077 -310.449372) (xy 407.962222 -310.455304)
			(xy 407.913047 -310.453323) (xy 407.864828 -310.443479) (xy 407.818812 -310.426027) (xy 407.776191 -310.40142)
			(xy 407.73807 -310.370295) (xy 407.705435 -310.333458) (xy 407.679132 -310.291862) (xy 407.659841 -310.246586)
			(xy 407.648064 -310.198802) (xy 407.644104 -310.149748) (xy 407.305256 -310.149748) (xy 407.304761 -310.174355)
			(xy 407.296866 -310.222932) (xy 407.281282 -310.269613) (xy 407.258411 -310.31319) (xy 407.228846 -310.352534)
			(xy 407.193353 -310.386626) (xy 407.15285 -310.414582) (xy 407.108388 -310.43568) (xy 407.061117 -310.449372)
			(xy 407.012262 -310.455304) (xy 406.963087 -310.453323) (xy 406.914868 -310.443479) (xy 406.868852 -310.426027)
			(xy 406.826231 -310.40142) (xy 406.78811 -310.370295) (xy 406.755475 -310.333458) (xy 406.729172 -310.291862)
			(xy 406.709881 -310.246586) (xy 406.698104 -310.198802) (xy 406.694144 -310.149748) (xy 406.355278 -310.149748)
			(xy 406.353047 -310.190964) (xy 406.342379 -310.239447) (xy 406.324009 -310.285565) (xy 406.298419 -310.328104)
			(xy 406.266285 -310.365942) (xy 406.228453 -310.398084) (xy 406.185919 -310.423682) (xy 406.139804 -310.442061)
			(xy 406.091324 -310.452738) (xy 406.041754 -310.455432) (xy 405.992402 -310.45007) (xy 405.944568 -310.436796)
			(xy 405.899511 -310.415957) (xy 405.858418 -310.388104) (xy 405.822374 -310.35397) (xy 405.792326 -310.314454)
			(xy 405.769066 -310.270598) (xy 405.753209 -310.223556) (xy 405.74517 -310.174569) (xy 405.74468 -310.149748)
			(xy 405.744864 -310.135565) (xy 405.747531 -310.107325) (xy 405.750014 -310.09336) (xy 405.7523 -310.080914)
			(xy 405.744934 -310.057292) (xy 405.667464 -309.979822) (xy 405.643842 -309.972456) (xy 405.631396 -309.974742)
			(xy 405.617429 -309.977215) (xy 405.58919 -309.979889) (xy 405.575008 -309.980076) (xy 405.560825 -309.979899)
			(xy 405.532585 -309.977227) (xy 405.51862 -309.974742) (xy 405.506174 -309.972456) (xy 405.482552 -309.979822)
			(xy 405.405082 -310.057292) (xy 405.397716 -310.080914) (xy 405.400002 -310.09336) (xy 405.402483 -310.107325)
			(xy 405.405152 -310.135565) (xy 405.405336 -310.149748) (xy 405.404814 -310.175003) (xy 405.396501 -310.224825)
			(xy 405.3801 -310.272599) (xy 405.356059 -310.317022) (xy 405.325035 -310.356882) (xy 405.287873 -310.391092)
			(xy 405.245587 -310.418718) (xy 405.199331 -310.439008) (xy 405.150366 -310.451408) (xy 405.100028 -310.455579)
			(xy 405.04969 -310.451408) (xy 405.000725 -310.439008) (xy 404.954469 -310.418718) (xy 404.912183 -310.391092)
			(xy 404.875021 -310.356882) (xy 404.843997 -310.317022) (xy 404.819956 -310.272599) (xy 404.803555 -310.224825)
			(xy 404.795242 -310.175003) (xy 404.79472 -310.149748) (xy 404.794903 -310.135565) (xy 404.797571 -310.107325)
			(xy 404.800054 -310.09336) (xy 404.80234 -310.080914) (xy 404.794974 -310.057038) (xy 404.717758 -309.979822)
			(xy 404.693628 -309.972456) (xy 404.681436 -309.974742) (xy 404.667408 -309.977233) (xy 404.63904 -309.979901)
			(xy 404.624794 -309.980076) (xy 404.610611 -309.979901) (xy 404.582371 -309.977228) (xy 404.568406 -309.974742)
			(xy 404.55596 -309.972456) (xy 404.532338 -309.979822) (xy 404.454868 -310.057292) (xy 404.447502 -310.080914)
			(xy 404.449788 -310.09336) (xy 404.452269 -310.107325) (xy 404.454938 -310.135565) (xy 404.455122 -310.149748)
			(xy 404.45457 -310.174564) (xy 404.446533 -310.223542) (xy 404.430678 -310.270574) (xy 404.407424 -310.314422)
			(xy 404.377382 -310.35393) (xy 404.341344 -310.388057) (xy 404.300259 -310.415905) (xy 404.255211 -310.43674)
			(xy 404.207386 -310.450012) (xy 404.158044 -310.455372) (xy 404.108484 -310.452679) (xy 404.060013 -310.442004)
			(xy 404.013907 -310.423628) (xy 403.971382 -310.398035) (xy 403.933557 -310.365899) (xy 403.901429 -310.328068)
			(xy 403.875845 -310.285537) (xy 403.857478 -310.239428) (xy 403.846813 -310.190955) (xy 403.84413 -310.141394)
			(xy 403.8495 -310.092053) (xy 403.862782 -310.04423) (xy 403.883625 -309.999186) (xy 403.911481 -309.958108)
			(xy 403.945616 -309.922077) (xy 403.98513 -309.892043) (xy 404.028983 -309.868797) (xy 404.076018 -309.852952)
			(xy 404.124998 -309.844925) (xy 404.149814 -309.84444) (xy 404.163997 -309.844614) (xy 404.192237 -309.847288)
			(xy 404.206202 -309.849774) (xy 404.218648 -309.85206) (xy 404.24227 -309.844694) (xy 404.31974 -309.767224)
			(xy 404.327106 -309.743602) (xy 404.32482 -309.731156) (xy 404.322342 -309.71719) (xy 404.319671 -309.688951)
			(xy 404.319486 -309.674768) (xy 404.319658 -309.660585) (xy 404.322333 -309.632345) (xy 404.32482 -309.61838)
			(xy 404.327106 -309.605934) (xy 404.31974 -309.582312) (xy 404.24227 -309.504842) (xy 404.218648 -309.497476)
			(xy 404.206202 -309.499762) (xy 404.192235 -309.502234) (xy 404.163996 -309.504909) (xy 404.149814 -309.505096)
			(xy 404.125821 -309.504649) (xy 404.078424 -309.497144) (xy 404.032786 -309.482316) (xy 403.990029 -309.460532)
			(xy 403.951207 -309.432326) (xy 403.917275 -309.398395) (xy 403.889069 -309.359573) (xy 403.867284 -309.316816)
			(xy 403.852457 -309.271177) (xy 403.844951 -309.223781) (xy 403.844506 -309.199788) (xy 403.844681 -309.185605)
			(xy 403.847354 -309.157365) (xy 403.84984 -309.1434) (xy 403.852126 -309.130954) (xy 403.84476 -309.107332)
			(xy 403.76729 -309.029862) (xy 403.743668 -309.022496) (xy 403.731222 -309.024782) (xy 403.717257 -309.027265)
			(xy 403.689017 -309.029933) (xy 403.674834 -309.030116) (xy 403.65001 -309.029659) (xy 403.601014 -309.021632)
			(xy 403.553963 -309.005784) (xy 403.510095 -308.982532) (xy 403.470568 -308.95249) (xy 403.436421 -308.916448)
			(xy 403.408555 -308.875356) (xy 403.387705 -308.830298) (xy 403.374419 -308.78246) (xy 403.369048 -308.733103)
			(xy 403.030015 -308.733103) (xy 403.029687 -308.749415) (xy 403.021792 -308.797992) (xy 403.006208 -308.844673)
			(xy 402.983337 -308.88825) (xy 402.953772 -308.927594) (xy 402.918279 -308.961686) (xy 402.877776 -308.989642)
			(xy 402.833314 -309.01074) (xy 402.786043 -309.024432) (xy 402.737188 -309.030364) (xy 402.688013 -309.028383)
			(xy 402.639794 -309.018539) (xy 402.593778 -309.001087) (xy 402.551157 -308.97648) (xy 402.513036 -308.945355)
			(xy 402.480401 -308.908518) (xy 402.454098 -308.866922) (xy 402.434807 -308.821646) (xy 402.42303 -308.773862)
			(xy 402.41907 -308.724808) (xy 402.080222 -308.724808) (xy 402.079727 -308.749415) (xy 402.071832 -308.797992)
			(xy 402.056248 -308.844673) (xy 402.033377 -308.88825) (xy 402.003812 -308.927594) (xy 401.968319 -308.961686)
			(xy 401.927816 -308.989642) (xy 401.883354 -309.01074) (xy 401.836083 -309.024432) (xy 401.787228 -309.030364)
			(xy 401.738053 -309.028383) (xy 401.689834 -309.018539) (xy 401.643818 -309.001087) (xy 401.601197 -308.97648)
			(xy 401.563076 -308.945355) (xy 401.530441 -308.908518) (xy 401.504138 -308.866922) (xy 401.484847 -308.821646)
			(xy 401.47307 -308.773862) (xy 401.46911 -308.724808) (xy 401.130262 -308.724808) (xy 401.129767 -308.749415)
			(xy 401.121872 -308.797992) (xy 401.106288 -308.844673) (xy 401.083417 -308.88825) (xy 401.053852 -308.927594)
			(xy 401.018359 -308.961686) (xy 400.977856 -308.989642) (xy 400.933394 -309.01074) (xy 400.886123 -309.024432)
			(xy 400.837268 -309.030364) (xy 400.788093 -309.028383) (xy 400.739874 -309.018539) (xy 400.693858 -309.001087)
			(xy 400.651237 -308.97648) (xy 400.613116 -308.945355) (xy 400.580481 -308.908518) (xy 400.554178 -308.866922)
			(xy 400.534887 -308.821646) (xy 400.52311 -308.773862) (xy 400.51915 -308.724808) (xy 400.180302 -308.724808)
			(xy 400.179807 -308.749415) (xy 400.171912 -308.797992) (xy 400.156328 -308.844673) (xy 400.133457 -308.88825)
			(xy 400.103892 -308.927594) (xy 400.068399 -308.961686) (xy 400.027896 -308.989642) (xy 399.983434 -309.01074)
			(xy 399.936163 -309.024432) (xy 399.887308 -309.030364) (xy 399.838133 -309.028383) (xy 399.789914 -309.018539)
			(xy 399.743898 -309.001087) (xy 399.701277 -308.97648) (xy 399.663156 -308.945355) (xy 399.630521 -308.908518)
			(xy 399.604218 -308.866922) (xy 399.584927 -308.821646) (xy 399.57315 -308.773862) (xy 399.56919 -308.724808)
			(xy 399.230342 -308.724808) (xy 399.229847 -308.749415) (xy 399.221952 -308.797992) (xy 399.206368 -308.844673)
			(xy 399.183497 -308.88825) (xy 399.153932 -308.927594) (xy 399.118439 -308.961686) (xy 399.077936 -308.989642)
			(xy 399.033474 -309.01074) (xy 398.986203 -309.024432) (xy 398.937348 -309.030364) (xy 398.888173 -309.028383)
			(xy 398.839954 -309.018539) (xy 398.793938 -309.001087) (xy 398.751317 -308.97648) (xy 398.713196 -308.945355)
			(xy 398.680561 -308.908518) (xy 398.654258 -308.866922) (xy 398.634967 -308.821646) (xy 398.62319 -308.773862)
			(xy 398.61923 -308.724808) (xy 398.280128 -308.724808) (xy 398.279633 -308.749415) (xy 398.271738 -308.797992)
			(xy 398.256154 -308.844673) (xy 398.233283 -308.88825) (xy 398.203718 -308.927594) (xy 398.168225 -308.961686)
			(xy 398.127722 -308.989642) (xy 398.08326 -309.01074) (xy 398.035989 -309.024432) (xy 397.987134 -309.030364)
			(xy 397.937959 -309.028383) (xy 397.88974 -309.018539) (xy 397.843724 -309.001087) (xy 397.801103 -308.97648)
			(xy 397.762982 -308.945355) (xy 397.730347 -308.908518) (xy 397.704044 -308.866922) (xy 397.684753 -308.821646)
			(xy 397.672976 -308.773862) (xy 397.669016 -308.724808) (xy 397.330168 -308.724808) (xy 397.329673 -308.749415)
			(xy 397.321778 -308.797992) (xy 397.306194 -308.844673) (xy 397.283323 -308.88825) (xy 397.253758 -308.927594)
			(xy 397.218265 -308.961686) (xy 397.177762 -308.989642) (xy 397.1333 -309.01074) (xy 397.086029 -309.024432)
			(xy 397.037174 -309.030364) (xy 396.987999 -309.028383) (xy 396.93978 -309.018539) (xy 396.893764 -309.001087)
			(xy 396.851143 -308.97648) (xy 396.813022 -308.945355) (xy 396.780387 -308.908518) (xy 396.754084 -308.866922)
			(xy 396.734793 -308.821646) (xy 396.723016 -308.773862) (xy 396.719056 -308.724808) (xy 396.380208 -308.724808)
			(xy 396.379713 -308.749415) (xy 396.371818 -308.797992) (xy 396.356234 -308.844673) (xy 396.333363 -308.88825)
			(xy 396.303798 -308.927594) (xy 396.268305 -308.961686) (xy 396.227802 -308.989642) (xy 396.18334 -309.01074)
			(xy 396.136069 -309.024432) (xy 396.087214 -309.030364) (xy 396.038039 -309.028383) (xy 395.98982 -309.018539)
			(xy 395.943804 -309.001087) (xy 395.901183 -308.97648) (xy 395.863062 -308.945355) (xy 395.830427 -308.908518)
			(xy 395.804124 -308.866922) (xy 395.784833 -308.821646) (xy 395.773056 -308.773862) (xy 395.769096 -308.724808)
			(xy 395.43018 -308.724808) (xy 395.430628 -308.733052) (xy 395.425265 -308.782404) (xy 395.41199 -308.830238)
			(xy 395.39115 -308.875294) (xy 395.363296 -308.916385) (xy 395.329162 -308.952428) (xy 395.289646 -308.982475)
			(xy 395.245789 -309.005733) (xy 395.198748 -309.021589) (xy 395.149761 -309.029627) (xy 395.12494 -309.030116)
			(xy 395.110757 -309.029934) (xy 395.082517 -309.027265) (xy 395.068552 -309.024782) (xy 395.054593 -309.02257)
			(xy 395.026457 -309.02516) (xy 395.000108 -309.03536) (xy 394.977561 -309.052388) (xy 394.960541 -309.074941)
			(xy 394.950352 -309.101295) (xy 394.947772 -309.129432) (xy 394.949934 -309.1434) (xy 394.952406 -309.157367)
			(xy 394.955081 -309.185606) (xy 394.955268 -309.199788) (xy 394.954835 -309.224609) (xy 394.946806 -309.273598)
			(xy 394.930957 -309.320643) (xy 394.907706 -309.364504) (xy 394.877666 -309.404026) (xy 394.841627 -309.438167)
			(xy 394.80054 -309.466028) (xy 394.755487 -309.486876) (xy 394.707655 -309.50016) (xy 394.658303 -309.50553)
			(xy 394.608733 -309.502846) (xy 394.56025 -309.492178) (xy 394.514132 -309.473807) (xy 394.471593 -309.448217)
			(xy 394.433755 -309.416082) (xy 394.401613 -309.378249) (xy 394.376016 -309.335715) (xy 394.357637 -309.289599)
			(xy 394.346961 -309.241118) (xy 394.344268 -309.191549) (xy 394.005142 -309.191549) (xy 394.005308 -309.199788)
			(xy 394.004813 -309.224395) (xy 393.996918 -309.272972) (xy 393.981334 -309.319653) (xy 393.958463 -309.36323)
			(xy 393.928898 -309.402574) (xy 393.893405 -309.436666) (xy 393.852902 -309.464622) (xy 393.80844 -309.48572)
			(xy 393.761169 -309.499412) (xy 393.712314 -309.505344) (xy 393.663139 -309.503363) (xy 393.61492 -309.493519)
			(xy 393.568904 -309.476067) (xy 393.526283 -309.45146) (xy 393.488162 -309.420335) (xy 393.455527 -309.383498)
			(xy 393.429224 -309.341902) (xy 393.409933 -309.296626) (xy 393.398156 -309.248842) (xy 393.394196 -309.199788)
			(xy 393.055094 -309.199788) (xy 393.054599 -309.224395) (xy 393.046704 -309.272972) (xy 393.03112 -309.319653)
			(xy 393.008249 -309.36323) (xy 392.978684 -309.402574) (xy 392.943191 -309.436666) (xy 392.902688 -309.464622)
			(xy 392.858226 -309.48572) (xy 392.810955 -309.499412) (xy 392.7621 -309.505344) (xy 392.712925 -309.503363)
			(xy 392.664706 -309.493519) (xy 392.61869 -309.476067) (xy 392.576069 -309.45146) (xy 392.537948 -309.420335)
			(xy 392.505313 -309.383498) (xy 392.47901 -309.341902) (xy 392.459719 -309.296626) (xy 392.447942 -309.248842)
			(xy 392.443982 -309.199788) (xy 392.105134 -309.199788) (xy 392.104639 -309.224395) (xy 392.096744 -309.272972)
			(xy 392.08116 -309.319653) (xy 392.058289 -309.36323) (xy 392.028724 -309.402574) (xy 391.993231 -309.436666)
			(xy 391.952728 -309.464622) (xy 391.908266 -309.48572) (xy 391.860995 -309.499412) (xy 391.81214 -309.505344)
			(xy 391.762965 -309.503363) (xy 391.714746 -309.493519) (xy 391.66873 -309.476067) (xy 391.626109 -309.45146)
			(xy 391.587988 -309.420335) (xy 391.555353 -309.383498) (xy 391.52905 -309.341902) (xy 391.509759 -309.296626)
			(xy 391.497982 -309.248842) (xy 391.494022 -309.199788) (xy 391.177018 -309.199788) (xy 391.176514 -309.225496)
			(xy 391.168471 -309.276278) (xy 391.152583 -309.325177) (xy 391.12924 -309.370989) (xy 391.099019 -309.412585)
			(xy 391.062663 -309.448941) (xy 391.021067 -309.479162) (xy 390.975255 -309.502505) (xy 390.926356 -309.518393)
			(xy 390.875574 -309.526436) (xy 390.824158 -309.526436) (xy 390.773376 -309.518393) (xy 390.724477 -309.502505)
			(xy 390.678665 -309.479162) (xy 390.637069 -309.448941) (xy 390.600713 -309.412585) (xy 390.570492 -309.370989)
			(xy 390.547149 -309.325177) (xy 390.531261 -309.276278) (xy 390.523218 -309.225496) (xy 390.226554 -309.225496)
			(xy 390.218511 -309.276278) (xy 390.202623 -309.325177) (xy 390.17928 -309.370989) (xy 390.149059 -309.412585)
			(xy 390.112703 -309.448941) (xy 390.071107 -309.479162) (xy 390.025295 -309.502505) (xy 389.976396 -309.518393)
			(xy 389.925614 -309.526436) (xy 389.874198 -309.526436) (xy 389.823416 -309.518393) (xy 389.774517 -309.502505)
			(xy 389.728705 -309.479162) (xy 389.687109 -309.448941) (xy 389.650753 -309.412585) (xy 389.620532 -309.370989)
			(xy 389.597189 -309.325177) (xy 389.581301 -309.276278) (xy 389.573258 -309.225496) (xy 389.25458 -309.225496)
			(xy 389.246864 -309.272972) (xy 389.23128 -309.319653) (xy 389.208409 -309.36323) (xy 389.178844 -309.402574)
			(xy 389.143351 -309.436666) (xy 389.102848 -309.464622) (xy 389.058386 -309.48572) (xy 389.011115 -309.499412)
			(xy 388.96226 -309.505344) (xy 388.913085 -309.503363) (xy 388.864866 -309.493519) (xy 388.81885 -309.476067)
			(xy 388.776229 -309.45146) (xy 388.738108 -309.420335) (xy 388.705473 -309.383498) (xy 388.67917 -309.341902)
			(xy 388.659879 -309.296626) (xy 388.648102 -309.248842) (xy 388.644142 -309.199788) (xy 388.327138 -309.199788)
			(xy 388.326634 -309.225496) (xy 388.318591 -309.276278) (xy 388.302703 -309.325177) (xy 388.27936 -309.370989)
			(xy 388.249139 -309.412585) (xy 388.212783 -309.448941) (xy 388.171187 -309.479162) (xy 388.125375 -309.502505)
			(xy 388.076476 -309.518393) (xy 388.025694 -309.526436) (xy 387.974278 -309.526436) (xy 387.923496 -309.518393)
			(xy 387.874597 -309.502505) (xy 387.828785 -309.479162) (xy 387.787189 -309.448941) (xy 387.750833 -309.412585)
			(xy 387.720612 -309.370989) (xy 387.697269 -309.325177) (xy 387.681381 -309.276278) (xy 387.673338 -309.225496)
			(xy 387.376674 -309.225496) (xy 387.368631 -309.276278) (xy 387.352743 -309.325177) (xy 387.3294 -309.370989)
			(xy 387.299179 -309.412585) (xy 387.262823 -309.448941) (xy 387.221227 -309.479162) (xy 387.175415 -309.502505)
			(xy 387.126516 -309.518393) (xy 387.075734 -309.526436) (xy 387.024318 -309.526436) (xy 386.973536 -309.518393)
			(xy 386.924637 -309.502505) (xy 386.878825 -309.479162) (xy 386.837229 -309.448941) (xy 386.800873 -309.412585)
			(xy 386.770652 -309.370989) (xy 386.747309 -309.325177) (xy 386.731421 -309.276278) (xy 386.723378 -309.225496)
			(xy 386.404446 -309.225496) (xy 386.39673 -309.272972) (xy 386.381146 -309.319653) (xy 386.358275 -309.36323)
			(xy 386.32871 -309.402574) (xy 386.293217 -309.436666) (xy 386.252714 -309.464622) (xy 386.208252 -309.48572)
			(xy 386.160981 -309.499412) (xy 386.112126 -309.505344) (xy 386.062951 -309.503363) (xy 386.014732 -309.493519)
			(xy 385.968716 -309.476067) (xy 385.926095 -309.45146) (xy 385.887974 -309.420335) (xy 385.855339 -309.383498)
			(xy 385.829036 -309.341902) (xy 385.809745 -309.296626) (xy 385.797968 -309.248842) (xy 385.794008 -309.199788)
			(xy 385.45516 -309.199788) (xy 385.454665 -309.224395) (xy 385.44677 -309.272972) (xy 385.431186 -309.319653)
			(xy 385.408315 -309.36323) (xy 385.37875 -309.402574) (xy 385.343257 -309.436666) (xy 385.302754 -309.464622)
			(xy 385.258292 -309.48572) (xy 385.211021 -309.499412) (xy 385.162166 -309.505344) (xy 385.112991 -309.503363)
			(xy 385.064772 -309.493519) (xy 385.018756 -309.476067) (xy 384.976135 -309.45146) (xy 384.938014 -309.420335)
			(xy 384.905379 -309.383498) (xy 384.879076 -309.341902) (xy 384.859785 -309.296626) (xy 384.848008 -309.248842)
			(xy 384.844048 -309.199788) (xy 375.996502 -309.199788) (xy 376.015141 -309.22796) (xy 376.038813 -309.278457)
			(xy 376.054881 -309.331864) (xy 376.063001 -309.38704) (xy 376.06351 -309.414926) (xy 376.063001 -309.442812)
			(xy 376.054881 -309.497988) (xy 376.038813 -309.551395) (xy 376.015141 -309.601892) (xy 375.984368 -309.648405)
			(xy 375.947151 -309.689942) (xy 375.904283 -309.725617) (xy 375.856677 -309.754671) (xy 375.805348 -309.776483)
			(xy 375.751391 -309.790589) (xy 375.695954 -309.796689) (xy 375.64022 -309.794652) (xy 375.585377 -309.784522)
			(xy 375.532593 -309.766515) (xy 375.482993 -309.741014) (xy 375.437635 -309.708563) (xy 375.397486 -309.669854)
			(xy 375.3634 -309.625711) (xy 375.336104 -309.577076) (xy 375.316181 -309.524985) (xy 375.304055 -309.470548)
			(xy 375.299984 -309.414926) (xy 351.03308 -309.414926) (xy 351.03308 -309.897272) (xy 382.740406 -309.897272)
			(xy 382.744477 -309.84165) (xy 382.756603 -309.787213) (xy 382.776526 -309.735122) (xy 382.803822 -309.686487)
			(xy 382.837908 -309.642344) (xy 382.878057 -309.603635) (xy 382.923415 -309.571184) (xy 382.973015 -309.545683)
			(xy 383.025799 -309.527676) (xy 383.080642 -309.517546) (xy 383.136376 -309.515509) (xy 383.191813 -309.521609)
			(xy 383.24577 -309.535715) (xy 383.297099 -309.557527) (xy 383.344705 -309.586581) (xy 383.387573 -309.622256)
			(xy 383.42479 -309.663793) (xy 383.455563 -309.710306) (xy 383.479235 -309.760803) (xy 383.495303 -309.81421)
			(xy 383.503423 -309.869386) (xy 383.503932 -309.897272) (xy 383.503423 -309.925158) (xy 383.495303 -309.980334)
			(xy 383.479235 -310.033741) (xy 383.455563 -310.084238) (xy 383.42479 -310.130751) (xy 383.407541 -310.150002)
			(xy 383.893834 -310.150002) (xy 383.897794 -310.100948) (xy 383.909571 -310.053164) (xy 383.928862 -310.007888)
			(xy 383.955165 -309.966292) (xy 383.9878 -309.929455) (xy 384.025921 -309.89833) (xy 384.068542 -309.873723)
			(xy 384.114558 -309.856271) (xy 384.162777 -309.846427) (xy 384.211952 -309.844446) (xy 384.260807 -309.850378)
			(xy 384.308078 -309.86407) (xy 384.35254 -309.885168) (xy 384.393043 -309.913124) (xy 384.428536 -309.947216)
			(xy 384.458101 -309.98656) (xy 384.480972 -310.030137) (xy 384.496556 -310.076818) (xy 384.504451 -310.125395)
			(xy 384.504946 -310.150002) (xy 384.504451 -310.174609) (xy 384.504313 -310.175456) (xy 384.823204 -310.175456)
			(xy 384.823204 -310.12404) (xy 384.831247 -310.073258) (xy 384.847135 -310.024359) (xy 384.870478 -309.978547)
			(xy 384.900699 -309.936951) (xy 384.937055 -309.900595) (xy 384.978651 -309.870374) (xy 385.024463 -309.847031)
			(xy 385.073362 -309.831143) (xy 385.124144 -309.8231) (xy 385.17556 -309.8231) (xy 385.226342 -309.831143)
			(xy 385.275241 -309.847031) (xy 385.321053 -309.870374) (xy 385.362649 -309.900595) (xy 385.399005 -309.936951)
			(xy 385.429226 -309.978547) (xy 385.452569 -310.024359) (xy 385.468457 -310.073258) (xy 385.4765 -310.12404)
			(xy 385.477004 -310.149748) (xy 385.4765 -310.175456) (xy 385.773164 -310.175456) (xy 385.773164 -310.12404)
			(xy 385.781207 -310.073258) (xy 385.797095 -310.024359) (xy 385.820438 -309.978547) (xy 385.850659 -309.936951)
			(xy 385.887015 -309.900595) (xy 385.928611 -309.870374) (xy 385.974423 -309.847031) (xy 386.023322 -309.831143)
			(xy 386.074104 -309.8231) (xy 386.12552 -309.8231) (xy 386.176302 -309.831143) (xy 386.225201 -309.847031)
			(xy 386.271013 -309.870374) (xy 386.312609 -309.900595) (xy 386.348965 -309.936951) (xy 386.379186 -309.978547)
			(xy 386.402529 -310.024359) (xy 386.418417 -310.073258) (xy 386.42646 -310.12404) (xy 386.426964 -310.149748)
			(xy 386.744222 -310.149748) (xy 386.748182 -310.100694) (xy 386.759959 -310.05291) (xy 386.77925 -310.007634)
			(xy 386.805553 -309.966038) (xy 386.838188 -309.929201) (xy 386.876309 -309.898076) (xy 386.91893 -309.873469)
			(xy 386.964946 -309.856017) (xy 387.013165 -309.846173) (xy 387.06234 -309.844192) (xy 387.111195 -309.850124)
			(xy 387.158466 -309.863816) (xy 387.202928 -309.884914) (xy 387.243431 -309.91287) (xy 387.278924 -309.946962)
			(xy 387.308489 -309.986306) (xy 387.33136 -310.029883) (xy 387.346944 -310.076564) (xy 387.354839 -310.125141)
			(xy 387.355334 -310.149748) (xy 387.694182 -310.149748) (xy 387.698142 -310.100694) (xy 387.709919 -310.05291)
			(xy 387.72921 -310.007634) (xy 387.755513 -309.966038) (xy 387.788148 -309.929201) (xy 387.826269 -309.898076)
			(xy 387.86889 -309.873469) (xy 387.914906 -309.856017) (xy 387.963125 -309.846173) (xy 388.0123 -309.844192)
			(xy 388.061155 -309.850124) (xy 388.108426 -309.863816) (xy 388.152888 -309.884914) (xy 388.193391 -309.91287)
			(xy 388.228884 -309.946962) (xy 388.258449 -309.986306) (xy 388.28132 -310.029883) (xy 388.296904 -310.076564)
			(xy 388.304799 -310.125141) (xy 388.305294 -310.149748) (xy 388.644142 -310.149748) (xy 388.648102 -310.100694)
			(xy 388.659879 -310.05291) (xy 388.67917 -310.007634) (xy 388.705473 -309.966038) (xy 388.738108 -309.929201)
			(xy 388.776229 -309.898076) (xy 388.81885 -309.873469) (xy 388.864866 -309.856017) (xy 388.913085 -309.846173)
			(xy 388.96226 -309.844192) (xy 389.011115 -309.850124) (xy 389.058386 -309.863816) (xy 389.102848 -309.884914)
			(xy 389.143351 -309.91287) (xy 389.178844 -309.946962) (xy 389.208409 -309.986306) (xy 389.23128 -310.029883)
			(xy 389.246864 -310.076564) (xy 389.254759 -310.125141) (xy 389.255254 -310.149748) (xy 389.594102 -310.149748)
			(xy 389.598062 -310.100694) (xy 389.609839 -310.05291) (xy 389.62913 -310.007634) (xy 389.655433 -309.966038)
			(xy 389.688068 -309.929201) (xy 389.726189 -309.898076) (xy 389.76881 -309.873469) (xy 389.814826 -309.856017)
			(xy 389.863045 -309.846173) (xy 389.91222 -309.844192) (xy 389.961075 -309.850124) (xy 390.008346 -309.863816)
			(xy 390.052808 -309.884914) (xy 390.093311 -309.91287) (xy 390.128804 -309.946962) (xy 390.158369 -309.986306)
			(xy 390.18124 -310.029883) (xy 390.196824 -310.076564) (xy 390.204719 -310.125141) (xy 390.205214 -310.149748)
			(xy 390.544062 -310.149748) (xy 390.548022 -310.100694) (xy 390.559799 -310.05291) (xy 390.57909 -310.007634)
			(xy 390.605393 -309.966038) (xy 390.638028 -309.929201) (xy 390.676149 -309.898076) (xy 390.71877 -309.873469)
			(xy 390.764786 -309.856017) (xy 390.813005 -309.846173) (xy 390.86218 -309.844192) (xy 390.911035 -309.850124)
			(xy 390.958306 -309.863816) (xy 391.002768 -309.884914) (xy 391.043271 -309.91287) (xy 391.078764 -309.946962)
			(xy 391.108329 -309.986306) (xy 391.1312 -310.029883) (xy 391.146784 -310.076564) (xy 391.154679 -310.125141)
			(xy 391.155174 -310.149748) (xy 391.494022 -310.149748) (xy 391.497982 -310.100694) (xy 391.509759 -310.05291)
			(xy 391.52905 -310.007634) (xy 391.555353 -309.966038) (xy 391.587988 -309.929201) (xy 391.626109 -309.898076)
			(xy 391.66873 -309.873469) (xy 391.714746 -309.856017) (xy 391.762965 -309.846173) (xy 391.81214 -309.844192)
			(xy 391.860995 -309.850124) (xy 391.908266 -309.863816) (xy 391.952728 -309.884914) (xy 391.993231 -309.91287)
			(xy 392.028724 -309.946962) (xy 392.058289 -309.986306) (xy 392.08116 -310.029883) (xy 392.096744 -310.076564)
			(xy 392.104639 -310.125141) (xy 392.105134 -310.149748) (xy 392.443982 -310.149748) (xy 392.447942 -310.100694)
			(xy 392.459719 -310.05291) (xy 392.47901 -310.007634) (xy 392.505313 -309.966038) (xy 392.537948 -309.929201)
			(xy 392.576069 -309.898076) (xy 392.61869 -309.873469) (xy 392.664706 -309.856017) (xy 392.712925 -309.846173)
			(xy 392.7621 -309.844192) (xy 392.810955 -309.850124) (xy 392.858226 -309.863816) (xy 392.902688 -309.884914)
			(xy 392.943191 -309.91287) (xy 392.978684 -309.946962) (xy 393.008249 -309.986306) (xy 393.03112 -310.029883)
			(xy 393.046704 -310.076564) (xy 393.054599 -310.125141) (xy 393.055094 -310.149748) (xy 393.394196 -310.149748)
			(xy 393.398156 -310.100694) (xy 393.409933 -310.05291) (xy 393.429224 -310.007634) (xy 393.455527 -309.966038)
			(xy 393.488162 -309.929201) (xy 393.526283 -309.898076) (xy 393.568904 -309.873469) (xy 393.61492 -309.856017)
			(xy 393.663139 -309.846173) (xy 393.712314 -309.844192) (xy 393.761169 -309.850124) (xy 393.80844 -309.863816)
			(xy 393.852902 -309.884914) (xy 393.893405 -309.91287) (xy 393.928898 -309.946962) (xy 393.958463 -309.986306)
			(xy 393.981334 -310.029883) (xy 393.996918 -310.076564) (xy 394.004813 -310.125141) (xy 394.005308 -310.149748)
			(xy 394.344156 -310.149748) (xy 394.348116 -310.100694) (xy 394.359893 -310.05291) (xy 394.379184 -310.007634)
			(xy 394.405487 -309.966038) (xy 394.438122 -309.929201) (xy 394.476243 -309.898076) (xy 394.518864 -309.873469)
			(xy 394.56488 -309.856017) (xy 394.613099 -309.846173) (xy 394.662274 -309.844192) (xy 394.711129 -309.850124)
			(xy 394.7584 -309.863816) (xy 394.802862 -309.884914) (xy 394.843365 -309.91287) (xy 394.878858 -309.946962)
			(xy 394.908423 -309.986306) (xy 394.931294 -310.029883) (xy 394.946878 -310.076564) (xy 394.954773 -310.125141)
			(xy 394.955268 -310.149748) (xy 395.294116 -310.149748) (xy 395.298076 -310.100694) (xy 395.309853 -310.05291)
			(xy 395.329144 -310.007634) (xy 395.355447 -309.966038) (xy 395.388082 -309.929201) (xy 395.426203 -309.898076)
			(xy 395.468824 -309.873469) (xy 395.51484 -309.856017) (xy 395.563059 -309.846173) (xy 395.612234 -309.844192)
			(xy 395.661089 -309.850124) (xy 395.70836 -309.863816) (xy 395.752822 -309.884914) (xy 395.793325 -309.91287)
			(xy 395.828818 -309.946962) (xy 395.858383 -309.986306) (xy 395.881254 -310.029883) (xy 395.896838 -310.076564)
			(xy 395.904733 -310.125141) (xy 395.90506 -310.141417) (xy 396.244229 -310.141417) (xy 396.249595 -310.092077)
			(xy 396.262873 -310.044254) (xy 396.283712 -309.999209) (xy 396.311564 -309.958129) (xy 396.345695 -309.922096)
			(xy 396.385205 -309.892059) (xy 396.429054 -309.868809) (xy 396.476087 -309.85296) (xy 396.525064 -309.844927)
			(xy 396.54988 -309.84444) (xy 396.564063 -309.844619) (xy 396.592303 -309.847289) (xy 396.606268 -309.849774)
			(xy 396.618714 -309.85206) (xy 396.642336 -309.844694) (xy 396.719806 -309.767224) (xy 396.727172 -309.743602)
			(xy 396.724886 -309.731156) (xy 396.722407 -309.71719) (xy 396.719737 -309.688951) (xy 396.719552 -309.674768)
			(xy 396.720074 -309.649513) (xy 396.728387 -309.599691) (xy 396.744788 -309.551917) (xy 396.768829 -309.507494)
			(xy 396.799853 -309.467634) (xy 396.837015 -309.433424) (xy 396.879301 -309.405798) (xy 396.925557 -309.385508)
			(xy 396.974522 -309.373108) (xy 397.02486 -309.368937) (xy 397.075198 -309.373108) (xy 397.124163 -309.385508)
			(xy 397.170419 -309.405798) (xy 397.212705 -309.433424) (xy 397.249867 -309.467634) (xy 397.280891 -309.507494)
			(xy 397.304932 -309.551917) (xy 397.321333 -309.599691) (xy 397.329646 -309.649513) (xy 397.330168 -309.674768)
			(xy 397.329988 -309.688951) (xy 397.327318 -309.717191) (xy 397.324834 -309.731156) (xy 397.322548 -309.743602)
			(xy 397.329914 -309.767224) (xy 397.407384 -309.844694) (xy 397.431006 -309.85206) (xy 397.443452 -309.849774)
			(xy 397.457417 -309.847294) (xy 397.485657 -309.844625) (xy 397.49984 -309.84444) (xy 397.514023 -309.84461)
			(xy 397.542263 -309.847287) (xy 397.556228 -309.849774) (xy 397.568674 -309.85206) (xy 397.592296 -309.844694)
			(xy 397.669766 -309.767224) (xy 397.677132 -309.743602) (xy 397.674846 -309.731156) (xy 397.672368 -309.71719)
			(xy 397.669697 -309.688951) (xy 397.669512 -309.674768) (xy 397.670034 -309.649513) (xy 397.678347 -309.599691)
			(xy 397.694748 -309.551917) (xy 397.718789 -309.507494) (xy 397.749813 -309.467634) (xy 397.786975 -309.433424)
			(xy 397.829261 -309.405798) (xy 397.875517 -309.385508) (xy 397.924482 -309.373108) (xy 397.97482 -309.368937)
			(xy 398.025158 -309.373108) (xy 398.074123 -309.385508) (xy 398.120379 -309.405798) (xy 398.162665 -309.433424)
			(xy 398.199827 -309.467634) (xy 398.230851 -309.507494) (xy 398.254892 -309.551917) (xy 398.271293 -309.599691)
			(xy 398.279606 -309.649513) (xy 398.280128 -309.674768) (xy 398.279947 -309.688951) (xy 398.277278 -309.717191)
			(xy 398.274794 -309.731156) (xy 398.272508 -309.743602) (xy 398.279874 -309.767224) (xy 398.357344 -309.844694)
			(xy 398.380966 -309.85206) (xy 398.393412 -309.849774) (xy 398.407378 -309.8473) (xy 398.435618 -309.844626)
			(xy 398.4498 -309.84444) (xy 398.47462 -309.844878) (xy 398.523606 -309.852908) (xy 398.570648 -309.868758)
			(xy 398.614506 -309.892009) (xy 398.654025 -309.922049) (xy 398.688163 -309.958087) (xy 398.716022 -309.999172)
			(xy 398.736867 -310.044224) (xy 398.750149 -310.092054) (xy 398.755518 -310.141403) (xy 398.755066 -310.149748)
			(xy 399.09421 -310.149748) (xy 399.09817 -310.100694) (xy 399.109947 -310.05291) (xy 399.129238 -310.007634)
			(xy 399.155541 -309.966038) (xy 399.188176 -309.929201) (xy 399.226297 -309.898076) (xy 399.268918 -309.873469)
			(xy 399.314934 -309.856017) (xy 399.363153 -309.846173) (xy 399.412328 -309.844192) (xy 399.461183 -309.850124)
			(xy 399.508454 -309.863816) (xy 399.552916 -309.884914) (xy 399.593419 -309.91287) (xy 399.628912 -309.946962)
			(xy 399.658477 -309.986306) (xy 399.681348 -310.029883) (xy 399.696932 -310.076564) (xy 399.704827 -310.125141)
			(xy 399.705322 -310.149748) (xy 400.04417 -310.149748) (xy 400.04813 -310.100694) (xy 400.059907 -310.05291)
			(xy 400.079198 -310.007634) (xy 400.105501 -309.966038) (xy 400.138136 -309.929201) (xy 400.176257 -309.898076)
			(xy 400.218878 -309.873469) (xy 400.264894 -309.856017) (xy 400.313113 -309.846173) (xy 400.362288 -309.844192)
			(xy 400.411143 -309.850124) (xy 400.458414 -309.863816) (xy 400.502876 -309.884914) (xy 400.543379 -309.91287)
			(xy 400.578872 -309.946962) (xy 400.608437 -309.986306) (xy 400.631308 -310.029883) (xy 400.646892 -310.076564)
			(xy 400.654787 -310.125141) (xy 400.655282 -310.149748) (xy 400.99413 -310.149748) (xy 400.99809 -310.100694)
			(xy 401.009867 -310.05291) (xy 401.029158 -310.007634) (xy 401.055461 -309.966038) (xy 401.088096 -309.929201)
			(xy 401.126217 -309.898076) (xy 401.168838 -309.873469) (xy 401.214854 -309.856017) (xy 401.263073 -309.846173)
			(xy 401.312248 -309.844192) (xy 401.361103 -309.850124) (xy 401.408374 -309.863816) (xy 401.452836 -309.884914)
			(xy 401.493339 -309.91287) (xy 401.528832 -309.946962) (xy 401.558397 -309.986306) (xy 401.581268 -310.029883)
			(xy 401.596852 -310.076564) (xy 401.604747 -310.125141) (xy 401.605242 -310.149748) (xy 401.94409 -310.149748)
			(xy 401.94805 -310.100694) (xy 401.959827 -310.05291) (xy 401.979118 -310.007634) (xy 402.005421 -309.966038)
			(xy 402.038056 -309.929201) (xy 402.076177 -309.898076) (xy 402.118798 -309.873469) (xy 402.164814 -309.856017)
			(xy 402.213033 -309.846173) (xy 402.262208 -309.844192) (xy 402.311063 -309.850124) (xy 402.358334 -309.863816)
			(xy 402.402796 -309.884914) (xy 402.443299 -309.91287) (xy 402.478792 -309.946962) (xy 402.508357 -309.986306)
			(xy 402.531228 -310.029883) (xy 402.546812 -310.076564) (xy 402.554707 -310.125141) (xy 402.555202 -310.149748)
			(xy 402.89405 -310.149748) (xy 402.89801 -310.100694) (xy 402.909787 -310.05291) (xy 402.929078 -310.007634)
			(xy 402.955381 -309.966038) (xy 402.988016 -309.929201) (xy 403.026137 -309.898076) (xy 403.068758 -309.873469)
			(xy 403.114774 -309.856017) (xy 403.162993 -309.846173) (xy 403.212168 -309.844192) (xy 403.261023 -309.850124)
			(xy 403.308294 -309.863816) (xy 403.352756 -309.884914) (xy 403.393259 -309.91287) (xy 403.428752 -309.946962)
			(xy 403.458317 -309.986306) (xy 403.481188 -310.029883) (xy 403.496772 -310.076564) (xy 403.504667 -310.125141)
			(xy 403.505162 -310.149748) (xy 403.504667 -310.174355) (xy 403.496772 -310.222932) (xy 403.481188 -310.269613)
			(xy 403.458317 -310.31319) (xy 403.428752 -310.352534) (xy 403.393259 -310.386626) (xy 403.352756 -310.414582)
			(xy 403.308294 -310.43568) (xy 403.261023 -310.449372) (xy 403.212168 -310.455304) (xy 403.162993 -310.453323)
			(xy 403.114774 -310.443479) (xy 403.068758 -310.426027) (xy 403.026137 -310.40142) (xy 402.988016 -310.370295)
			(xy 402.955381 -310.333458) (xy 402.929078 -310.291862) (xy 402.909787 -310.246586) (xy 402.89801 -310.198802)
			(xy 402.89405 -310.149748) (xy 402.555202 -310.149748) (xy 402.554707 -310.174355) (xy 402.546812 -310.222932)
			(xy 402.531228 -310.269613) (xy 402.508357 -310.31319) (xy 402.478792 -310.352534) (xy 402.443299 -310.386626)
			(xy 402.402796 -310.414582) (xy 402.358334 -310.43568) (xy 402.311063 -310.449372) (xy 402.262208 -310.455304)
			(xy 402.213033 -310.453323) (xy 402.164814 -310.443479) (xy 402.118798 -310.426027) (xy 402.076177 -310.40142)
			(xy 402.038056 -310.370295) (xy 402.005421 -310.333458) (xy 401.979118 -310.291862) (xy 401.959827 -310.246586)
			(xy 401.94805 -310.198802) (xy 401.94409 -310.149748) (xy 401.605242 -310.149748) (xy 401.604747 -310.174355)
			(xy 401.596852 -310.222932) (xy 401.581268 -310.269613) (xy 401.558397 -310.31319) (xy 401.528832 -310.352534)
			(xy 401.493339 -310.386626) (xy 401.452836 -310.414582) (xy 401.408374 -310.43568) (xy 401.361103 -310.449372)
			(xy 401.312248 -310.455304) (xy 401.263073 -310.453323) (xy 401.214854 -310.443479) (xy 401.168838 -310.426027)
			(xy 401.126217 -310.40142) (xy 401.088096 -310.370295) (xy 401.055461 -310.333458) (xy 401.029158 -310.291862)
			(xy 401.009867 -310.246586) (xy 400.99809 -310.198802) (xy 400.99413 -310.149748) (xy 400.655282 -310.149748)
			(xy 400.654787 -310.174355) (xy 400.646892 -310.222932) (xy 400.631308 -310.269613) (xy 400.608437 -310.31319)
			(xy 400.578872 -310.352534) (xy 400.543379 -310.386626) (xy 400.502876 -310.414582) (xy 400.458414 -310.43568)
			(xy 400.411143 -310.449372) (xy 400.362288 -310.455304) (xy 400.313113 -310.453323) (xy 400.264894 -310.443479)
			(xy 400.218878 -310.426027) (xy 400.176257 -310.40142) (xy 400.138136 -310.370295) (xy 400.105501 -310.333458)
			(xy 400.079198 -310.291862) (xy 400.059907 -310.246586) (xy 400.04813 -310.198802) (xy 400.04417 -310.149748)
			(xy 399.705322 -310.149748) (xy 399.704827 -310.174355) (xy 399.696932 -310.222932) (xy 399.681348 -310.269613)
			(xy 399.658477 -310.31319) (xy 399.628912 -310.352534) (xy 399.593419 -310.386626) (xy 399.552916 -310.414582)
			(xy 399.508454 -310.43568) (xy 399.461183 -310.449372) (xy 399.412328 -310.455304) (xy 399.363153 -310.453323)
			(xy 399.314934 -310.443479) (xy 399.268918 -310.426027) (xy 399.226297 -310.40142) (xy 399.188176 -310.370295)
			(xy 399.155541 -310.333458) (xy 399.129238 -310.291862) (xy 399.109947 -310.246586) (xy 399.09817 -310.198802)
			(xy 399.09421 -310.149748) (xy 398.755066 -310.149748) (xy 398.752834 -310.19097) (xy 398.742165 -310.23945)
			(xy 398.723795 -310.285566) (xy 398.698206 -310.328102) (xy 398.666072 -310.365938) (xy 398.628241 -310.398078)
			(xy 398.585709 -310.423673) (xy 398.539596 -310.442051) (xy 398.491118 -310.452727) (xy 398.441551 -310.45542)
			(xy 398.392201 -310.450058) (xy 398.344369 -310.436783) (xy 398.299314 -310.415945) (xy 398.258224 -310.388093)
			(xy 398.222181 -310.35396) (xy 398.192135 -310.314446) (xy 398.168877 -310.270592) (xy 398.15302 -310.223553)
			(xy 398.144982 -310.174568) (xy 398.144492 -310.149748) (xy 398.144675 -310.135565) (xy 398.147343 -310.107325)
			(xy 398.149826 -310.09336) (xy 398.152112 -310.080914) (xy 398.144746 -310.057292) (xy 398.067276 -309.979822)
			(xy 398.043654 -309.972456) (xy 398.031208 -309.974742) (xy 398.017241 -309.977213) (xy 397.989002 -309.979889)
			(xy 397.97482 -309.980076) (xy 397.960637 -309.979897) (xy 397.932397 -309.977227) (xy 397.918432 -309.974742)
			(xy 397.905986 -309.972456) (xy 397.882364 -309.979822) (xy 397.804894 -310.057292) (xy 397.797528 -310.080914)
			(xy 397.799814 -310.09336) (xy 397.802295 -310.107325) (xy 397.804964 -310.135565) (xy 397.805148 -310.149748)
			(xy 397.804626 -310.175003) (xy 397.796313 -310.224825) (xy 397.779912 -310.272599) (xy 397.755871 -310.317022)
			(xy 397.724847 -310.356882) (xy 397.687685 -310.391092) (xy 397.645399 -310.418718) (xy 397.599143 -310.439008)
			(xy 397.550178 -310.451408) (xy 397.49984 -310.455579) (xy 397.449502 -310.451408) (xy 397.400537 -310.439008)
			(xy 397.354281 -310.418718) (xy 397.311995 -310.391092) (xy 397.274833 -310.356882) (xy 397.243809 -310.317022)
			(xy 397.219768 -310.272599) (xy 397.203367 -310.224825) (xy 397.195054 -310.175003) (xy 397.194532 -310.149748)
			(xy 397.194715 -310.135565) (xy 397.197383 -310.107325) (xy 397.199866 -310.09336) (xy 397.202152 -310.080914)
			(xy 397.194786 -310.057292) (xy 397.117316 -309.979822) (xy 397.093694 -309.972456) (xy 397.081248 -309.974742)
			(xy 397.067283 -309.977221) (xy 397.039043 -309.979891) (xy 397.02486 -309.980076) (xy 397.010677 -309.979905)
			(xy 396.982437 -309.977229) (xy 396.968472 -309.974742) (xy 396.956026 -309.972456) (xy 396.932404 -309.979822)
			(xy 396.854934 -310.057292) (xy 396.847568 -310.080914) (xy 396.849854 -310.09336) (xy 396.852334 -310.107325)
			(xy 396.855004 -310.135565) (xy 396.855188 -310.149748) (xy 396.85467 -310.174564) (xy 396.846634 -310.22354)
			(xy 396.83078 -310.270572) (xy 396.807526 -310.314419) (xy 396.777485 -310.353926) (xy 396.741449 -310.388053)
			(xy 396.700366 -310.415901) (xy 396.65532 -310.436737) (xy 396.607496 -310.45001) (xy 396.558155 -310.455372)
			(xy 396.508596 -310.452681) (xy 396.460126 -310.442008) (xy 396.41402 -310.423634) (xy 396.371495 -310.398044)
			(xy 396.333669 -310.365911) (xy 396.30154 -310.328083) (xy 396.275953 -310.285555) (xy 396.257584 -310.239448)
			(xy 396.246916 -310.190976) (xy 396.244229 -310.141417) (xy 395.90506 -310.141417) (xy 395.905228 -310.149748)
			(xy 395.904733 -310.174355) (xy 395.896838 -310.222932) (xy 395.881254 -310.269613) (xy 395.858383 -310.31319)
			(xy 395.828818 -310.352534) (xy 395.793325 -310.386626) (xy 395.752822 -310.414582) (xy 395.70836 -310.43568)
			(xy 395.661089 -310.449372) (xy 395.612234 -310.455304) (xy 395.563059 -310.453323) (xy 395.51484 -310.443479)
			(xy 395.468824 -310.426027) (xy 395.426203 -310.40142) (xy 395.388082 -310.370295) (xy 395.355447 -310.333458)
			(xy 395.329144 -310.291862) (xy 395.309853 -310.246586) (xy 395.298076 -310.198802) (xy 395.294116 -310.149748)
			(xy 394.955268 -310.149748) (xy 394.954773 -310.174355) (xy 394.946878 -310.222932) (xy 394.931294 -310.269613)
			(xy 394.908423 -310.31319) (xy 394.878858 -310.352534) (xy 394.843365 -310.386626) (xy 394.802862 -310.414582)
			(xy 394.7584 -310.43568) (xy 394.711129 -310.449372) (xy 394.662274 -310.455304) (xy 394.613099 -310.453323)
			(xy 394.56488 -310.443479) (xy 394.518864 -310.426027) (xy 394.476243 -310.40142) (xy 394.438122 -310.370295)
			(xy 394.405487 -310.333458) (xy 394.379184 -310.291862) (xy 394.359893 -310.246586) (xy 394.348116 -310.198802)
			(xy 394.344156 -310.149748) (xy 394.005308 -310.149748) (xy 394.004813 -310.174355) (xy 393.996918 -310.222932)
			(xy 393.981334 -310.269613) (xy 393.958463 -310.31319) (xy 393.928898 -310.352534) (xy 393.893405 -310.386626)
			(xy 393.852902 -310.414582) (xy 393.80844 -310.43568) (xy 393.761169 -310.449372) (xy 393.712314 -310.455304)
			(xy 393.663139 -310.453323) (xy 393.61492 -310.443479) (xy 393.568904 -310.426027) (xy 393.526283 -310.40142)
			(xy 393.488162 -310.370295) (xy 393.455527 -310.333458) (xy 393.429224 -310.291862) (xy 393.409933 -310.246586)
			(xy 393.398156 -310.198802) (xy 393.394196 -310.149748) (xy 393.055094 -310.149748) (xy 393.054599 -310.174355)
			(xy 393.046704 -310.222932) (xy 393.03112 -310.269613) (xy 393.008249 -310.31319) (xy 392.978684 -310.352534)
			(xy 392.943191 -310.386626) (xy 392.902688 -310.414582) (xy 392.858226 -310.43568) (xy 392.810955 -310.449372)
			(xy 392.7621 -310.455304) (xy 392.712925 -310.453323) (xy 392.664706 -310.443479) (xy 392.61869 -310.426027)
			(xy 392.576069 -310.40142) (xy 392.537948 -310.370295) (xy 392.505313 -310.333458) (xy 392.47901 -310.291862)
			(xy 392.459719 -310.246586) (xy 392.447942 -310.198802) (xy 392.443982 -310.149748) (xy 392.105134 -310.149748)
			(xy 392.104639 -310.174355) (xy 392.096744 -310.222932) (xy 392.08116 -310.269613) (xy 392.058289 -310.31319)
			(xy 392.028724 -310.352534) (xy 391.993231 -310.386626) (xy 391.952728 -310.414582) (xy 391.908266 -310.43568)
			(xy 391.860995 -310.449372) (xy 391.81214 -310.455304) (xy 391.762965 -310.453323) (xy 391.714746 -310.443479)
			(xy 391.66873 -310.426027) (xy 391.626109 -310.40142) (xy 391.587988 -310.370295) (xy 391.555353 -310.333458)
			(xy 391.52905 -310.291862) (xy 391.509759 -310.246586) (xy 391.497982 -310.198802) (xy 391.494022 -310.149748)
			(xy 391.155174 -310.149748) (xy 391.154679 -310.174355) (xy 391.146784 -310.222932) (xy 391.1312 -310.269613)
			(xy 391.108329 -310.31319) (xy 391.078764 -310.352534) (xy 391.043271 -310.386626) (xy 391.002768 -310.414582)
			(xy 390.958306 -310.43568) (xy 390.911035 -310.449372) (xy 390.86218 -310.455304) (xy 390.813005 -310.453323)
			(xy 390.764786 -310.443479) (xy 390.71877 -310.426027) (xy 390.676149 -310.40142) (xy 390.638028 -310.370295)
			(xy 390.605393 -310.333458) (xy 390.57909 -310.291862) (xy 390.559799 -310.246586) (xy 390.548022 -310.198802)
			(xy 390.544062 -310.149748) (xy 390.205214 -310.149748) (xy 390.204719 -310.174355) (xy 390.196824 -310.222932)
			(xy 390.18124 -310.269613) (xy 390.158369 -310.31319) (xy 390.128804 -310.352534) (xy 390.093311 -310.386626)
			(xy 390.052808 -310.414582) (xy 390.008346 -310.43568) (xy 389.961075 -310.449372) (xy 389.91222 -310.455304)
			(xy 389.863045 -310.453323) (xy 389.814826 -310.443479) (xy 389.76881 -310.426027) (xy 389.726189 -310.40142)
			(xy 389.688068 -310.370295) (xy 389.655433 -310.333458) (xy 389.62913 -310.291862) (xy 389.609839 -310.246586)
			(xy 389.598062 -310.198802) (xy 389.594102 -310.149748) (xy 389.255254 -310.149748) (xy 389.254759 -310.174355)
			(xy 389.246864 -310.222932) (xy 389.23128 -310.269613) (xy 389.208409 -310.31319) (xy 389.178844 -310.352534)
			(xy 389.143351 -310.386626) (xy 389.102848 -310.414582) (xy 389.058386 -310.43568) (xy 389.011115 -310.449372)
			(xy 388.96226 -310.455304) (xy 388.913085 -310.453323) (xy 388.864866 -310.443479) (xy 388.81885 -310.426027)
			(xy 388.776229 -310.40142) (xy 388.738108 -310.370295) (xy 388.705473 -310.333458) (xy 388.67917 -310.291862)
			(xy 388.659879 -310.246586) (xy 388.648102 -310.198802) (xy 388.644142 -310.149748) (xy 388.305294 -310.149748)
			(xy 388.304799 -310.174355) (xy 388.296904 -310.222932) (xy 388.28132 -310.269613) (xy 388.258449 -310.31319)
			(xy 388.228884 -310.352534) (xy 388.193391 -310.386626) (xy 388.152888 -310.414582) (xy 388.108426 -310.43568)
			(xy 388.061155 -310.449372) (xy 388.0123 -310.455304) (xy 387.963125 -310.453323) (xy 387.914906 -310.443479)
			(xy 387.86889 -310.426027) (xy 387.826269 -310.40142) (xy 387.788148 -310.370295) (xy 387.755513 -310.333458)
			(xy 387.72921 -310.291862) (xy 387.709919 -310.246586) (xy 387.698142 -310.198802) (xy 387.694182 -310.149748)
			(xy 387.355334 -310.149748) (xy 387.354839 -310.174355) (xy 387.346944 -310.222932) (xy 387.33136 -310.269613)
			(xy 387.308489 -310.31319) (xy 387.278924 -310.352534) (xy 387.243431 -310.386626) (xy 387.202928 -310.414582)
			(xy 387.158466 -310.43568) (xy 387.111195 -310.449372) (xy 387.06234 -310.455304) (xy 387.013165 -310.453323)
			(xy 386.964946 -310.443479) (xy 386.91893 -310.426027) (xy 386.876309 -310.40142) (xy 386.838188 -310.370295)
			(xy 386.805553 -310.333458) (xy 386.77925 -310.291862) (xy 386.759959 -310.246586) (xy 386.748182 -310.198802)
			(xy 386.744222 -310.149748) (xy 386.426964 -310.149748) (xy 386.42646 -310.175456) (xy 386.418417 -310.226238)
			(xy 386.402529 -310.275137) (xy 386.379186 -310.320949) (xy 386.348965 -310.362545) (xy 386.312609 -310.398901)
			(xy 386.271013 -310.429122) (xy 386.225201 -310.452465) (xy 386.176302 -310.468353) (xy 386.12552 -310.476396)
			(xy 386.074104 -310.476396) (xy 386.023322 -310.468353) (xy 385.974423 -310.452465) (xy 385.928611 -310.429122)
			(xy 385.887015 -310.398901) (xy 385.850659 -310.362545) (xy 385.820438 -310.320949) (xy 385.797095 -310.275137)
			(xy 385.781207 -310.226238) (xy 385.773164 -310.175456) (xy 385.4765 -310.175456) (xy 385.468457 -310.226238)
			(xy 385.452569 -310.275137) (xy 385.429226 -310.320949) (xy 385.399005 -310.362545) (xy 385.362649 -310.398901)
			(xy 385.321053 -310.429122) (xy 385.275241 -310.452465) (xy 385.226342 -310.468353) (xy 385.17556 -310.476396)
			(xy 385.124144 -310.476396) (xy 385.073362 -310.468353) (xy 385.024463 -310.452465) (xy 384.978651 -310.429122)
			(xy 384.937055 -310.398901) (xy 384.900699 -310.362545) (xy 384.870478 -310.320949) (xy 384.847135 -310.275137)
			(xy 384.831247 -310.226238) (xy 384.823204 -310.175456) (xy 384.504313 -310.175456) (xy 384.496556 -310.223186)
			(xy 384.480972 -310.269867) (xy 384.458101 -310.313444) (xy 384.428536 -310.352788) (xy 384.393043 -310.38688)
			(xy 384.35254 -310.414836) (xy 384.308078 -310.435934) (xy 384.260807 -310.449626) (xy 384.211952 -310.455558)
			(xy 384.162777 -310.453577) (xy 384.114558 -310.443733) (xy 384.068542 -310.426281) (xy 384.025921 -310.401674)
			(xy 383.9878 -310.370549) (xy 383.955165 -310.333712) (xy 383.928862 -310.292116) (xy 383.909571 -310.24684)
			(xy 383.897794 -310.199056) (xy 383.893834 -310.150002) (xy 383.407541 -310.150002) (xy 383.387573 -310.172288)
			(xy 383.344705 -310.207963) (xy 383.297099 -310.237017) (xy 383.24577 -310.258829) (xy 383.191813 -310.272935)
			(xy 383.136376 -310.279035) (xy 383.080642 -310.276998) (xy 383.025799 -310.266868) (xy 382.973015 -310.248861)
			(xy 382.923415 -310.22336) (xy 382.878057 -310.190909) (xy 382.837908 -310.1522) (xy 382.803822 -310.108057)
			(xy 382.776526 -310.059422) (xy 382.756603 -310.007331) (xy 382.744477 -309.952894) (xy 382.740406 -309.897272)
			(xy 351.03308 -309.897272) (xy 351.03308 -310.832246) (xy 376.567952 -310.832246) (xy 376.572023 -310.776624)
			(xy 376.584149 -310.722187) (xy 376.604072 -310.670096) (xy 376.631368 -310.621461) (xy 376.665454 -310.577318)
			(xy 376.705603 -310.538609) (xy 376.750961 -310.506158) (xy 376.800561 -310.480657) (xy 376.853345 -310.46265)
			(xy 376.908188 -310.45252) (xy 376.963922 -310.450483) (xy 377.019359 -310.456583) (xy 377.073316 -310.470689)
			(xy 377.124645 -310.492501) (xy 377.172251 -310.521555) (xy 377.215119 -310.55723) (xy 377.252336 -310.598767)
			(xy 377.283109 -310.64528) (xy 377.306781 -310.695777) (xy 377.322849 -310.749184) (xy 377.330969 -310.80436)
			(xy 377.331478 -310.832246) (xy 377.330969 -310.860132) (xy 377.322849 -310.915308) (xy 377.306781 -310.968715)
			(xy 377.284667 -311.015888) (xy 382.57175 -311.015888) (xy 382.575821 -310.960266) (xy 382.587947 -310.905829)
			(xy 382.60787 -310.853738) (xy 382.635166 -310.805103) (xy 382.669252 -310.76096) (xy 382.709401 -310.722251)
			(xy 382.754759 -310.6898) (xy 382.804359 -310.664299) (xy 382.857143 -310.646292) (xy 382.911986 -310.636162)
			(xy 382.96772 -310.634125) (xy 383.023157 -310.640225) (xy 383.077114 -310.654331) (xy 383.128443 -310.676143)
			(xy 383.176049 -310.705197) (xy 383.218917 -310.740872) (xy 383.256134 -310.782409) (xy 383.286907 -310.828922)
			(xy 383.310579 -310.879419) (xy 383.326647 -310.932826) (xy 383.334767 -310.988002) (xy 383.335276 -311.015888)
			(xy 383.334767 -311.043774) (xy 383.326647 -311.09895) (xy 383.326343 -311.099962) (xy 384.844048 -311.099962)
			(xy 384.848008 -311.050908) (xy 384.859785 -311.003124) (xy 384.879076 -310.957848) (xy 384.905379 -310.916252)
			(xy 384.938014 -310.879415) (xy 384.976135 -310.84829) (xy 385.018756 -310.823683) (xy 385.064772 -310.806231)
			(xy 385.112991 -310.796387) (xy 385.162166 -310.794406) (xy 385.211021 -310.800338) (xy 385.258292 -310.81403)
			(xy 385.302754 -310.835128) (xy 385.343257 -310.863084) (xy 385.37875 -310.897176) (xy 385.408315 -310.93652)
			(xy 385.431186 -310.980097) (xy 385.44677 -311.026778) (xy 385.454665 -311.075355) (xy 385.45516 -311.099962)
			(xy 385.794008 -311.099962) (xy 385.797968 -311.050908) (xy 385.809745 -311.003124) (xy 385.829036 -310.957848)
			(xy 385.855339 -310.916252) (xy 385.887974 -310.879415) (xy 385.926095 -310.84829) (xy 385.968716 -310.823683)
			(xy 386.014732 -310.806231) (xy 386.062951 -310.796387) (xy 386.112126 -310.794406) (xy 386.160981 -310.800338)
			(xy 386.208252 -310.81403) (xy 386.252714 -310.835128) (xy 386.293217 -310.863084) (xy 386.32871 -310.897176)
			(xy 386.358275 -310.93652) (xy 386.381146 -310.980097) (xy 386.39673 -311.026778) (xy 386.404625 -311.075355)
			(xy 386.40512 -311.099962) (xy 386.744222 -311.099962) (xy 386.748182 -311.050908) (xy 386.759959 -311.003124)
			(xy 386.77925 -310.957848) (xy 386.805553 -310.916252) (xy 386.838188 -310.879415) (xy 386.876309 -310.84829)
			(xy 386.91893 -310.823683) (xy 386.964946 -310.806231) (xy 387.013165 -310.796387) (xy 387.06234 -310.794406)
			(xy 387.111195 -310.800338) (xy 387.158466 -310.81403) (xy 387.202928 -310.835128) (xy 387.243431 -310.863084)
			(xy 387.278924 -310.897176) (xy 387.308489 -310.93652) (xy 387.33136 -310.980097) (xy 387.346944 -311.026778)
			(xy 387.354839 -311.075355) (xy 387.355334 -311.099962) (xy 387.354839 -311.124569) (xy 387.35466 -311.12567)
			(xy 387.673338 -311.12567) (xy 387.673338 -311.074254) (xy 387.681381 -311.023472) (xy 387.697269 -310.974573)
			(xy 387.720612 -310.928761) (xy 387.750833 -310.887165) (xy 387.787189 -310.850809) (xy 387.828785 -310.820588)
			(xy 387.874597 -310.797245) (xy 387.923496 -310.781357) (xy 387.974278 -310.773314) (xy 388.025694 -310.773314)
			(xy 388.076476 -310.781357) (xy 388.125375 -310.797245) (xy 388.171187 -310.820588) (xy 388.212783 -310.850809)
			(xy 388.249139 -310.887165) (xy 388.27936 -310.928761) (xy 388.302703 -310.974573) (xy 388.318591 -311.023472)
			(xy 388.326634 -311.074254) (xy 388.327138 -311.099962) (xy 388.644142 -311.099962) (xy 388.648102 -311.050908)
			(xy 388.659879 -311.003124) (xy 388.67917 -310.957848) (xy 388.705473 -310.916252) (xy 388.738108 -310.879415)
			(xy 388.776229 -310.84829) (xy 388.81885 -310.823683) (xy 388.864866 -310.806231) (xy 388.913085 -310.796387)
			(xy 388.96226 -310.794406) (xy 389.011115 -310.800338) (xy 389.058386 -310.81403) (xy 389.102848 -310.835128)
			(xy 389.143351 -310.863084) (xy 389.178844 -310.897176) (xy 389.208409 -310.93652) (xy 389.23128 -310.980097)
			(xy 389.246864 -311.026778) (xy 389.254759 -311.075355) (xy 389.255254 -311.099962) (xy 389.254759 -311.124569)
			(xy 389.25458 -311.12567) (xy 389.573258 -311.12567) (xy 389.573258 -311.074254) (xy 389.581301 -311.023472)
			(xy 389.597189 -310.974573) (xy 389.620532 -310.928761) (xy 389.650753 -310.887165) (xy 389.687109 -310.850809)
			(xy 389.728705 -310.820588) (xy 389.774517 -310.797245) (xy 389.823416 -310.781357) (xy 389.874198 -310.773314)
			(xy 389.925614 -310.773314) (xy 389.976396 -310.781357) (xy 390.025295 -310.797245) (xy 390.071107 -310.820588)
			(xy 390.112703 -310.850809) (xy 390.149059 -310.887165) (xy 390.17928 -310.928761) (xy 390.202623 -310.974573)
			(xy 390.218511 -311.023472) (xy 390.226554 -311.074254) (xy 390.227058 -311.099962) (xy 390.544062 -311.099962)
			(xy 390.548022 -311.050908) (xy 390.559799 -311.003124) (xy 390.57909 -310.957848) (xy 390.605393 -310.916252)
			(xy 390.638028 -310.879415) (xy 390.676149 -310.84829) (xy 390.71877 -310.823683) (xy 390.764786 -310.806231)
			(xy 390.813005 -310.796387) (xy 390.86218 -310.794406) (xy 390.911035 -310.800338) (xy 390.958306 -310.81403)
			(xy 391.002768 -310.835128) (xy 391.043271 -310.863084) (xy 391.078764 -310.897176) (xy 391.108329 -310.93652)
			(xy 391.1312 -310.980097) (xy 391.146784 -311.026778) (xy 391.154679 -311.075355) (xy 391.155174 -311.099962)
			(xy 391.154679 -311.124569) (xy 391.1545 -311.12567) (xy 391.473178 -311.12567) (xy 391.473178 -311.074254)
			(xy 391.481221 -311.023472) (xy 391.497109 -310.974573) (xy 391.520452 -310.928761) (xy 391.550673 -310.887165)
			(xy 391.587029 -310.850809) (xy 391.628625 -310.820588) (xy 391.674437 -310.797245) (xy 391.723336 -310.781357)
			(xy 391.774118 -310.773314) (xy 391.825534 -310.773314) (xy 391.876316 -310.781357) (xy 391.925215 -310.797245)
			(xy 391.971027 -310.820588) (xy 392.012623 -310.850809) (xy 392.048979 -310.887165) (xy 392.0792 -310.928761)
			(xy 392.102543 -310.974573) (xy 392.118431 -311.023472) (xy 392.126474 -311.074254) (xy 392.126978 -311.099962)
			(xy 392.443982 -311.099962) (xy 392.447942 -311.050908) (xy 392.459719 -311.003124) (xy 392.47901 -310.957848)
			(xy 392.505313 -310.916252) (xy 392.537948 -310.879415) (xy 392.576069 -310.84829) (xy 392.61869 -310.823683)
			(xy 392.664706 -310.806231) (xy 392.712925 -310.796387) (xy 392.7621 -310.794406) (xy 392.810955 -310.800338)
			(xy 392.858226 -310.81403) (xy 392.902688 -310.835128) (xy 392.943191 -310.863084) (xy 392.978684 -310.897176)
			(xy 393.008249 -310.93652) (xy 393.03112 -310.980097) (xy 393.046704 -311.026778) (xy 393.054599 -311.075355)
			(xy 393.055094 -311.099962) (xy 393.054599 -311.124569) (xy 393.05442 -311.12567) (xy 393.373352 -311.12567)
			(xy 393.373352 -311.074254) (xy 393.381395 -311.023472) (xy 393.397283 -310.974573) (xy 393.420626 -310.928761)
			(xy 393.450847 -310.887165) (xy 393.487203 -310.850809) (xy 393.528799 -310.820588) (xy 393.574611 -310.797245)
			(xy 393.62351 -310.781357) (xy 393.674292 -310.773314) (xy 393.725708 -310.773314) (xy 393.77649 -310.781357)
			(xy 393.825389 -310.797245) (xy 393.871201 -310.820588) (xy 393.912797 -310.850809) (xy 393.949153 -310.887165)
			(xy 393.979374 -310.928761) (xy 394.002717 -310.974573) (xy 394.018605 -311.023472) (xy 394.026648 -311.074254)
			(xy 394.027152 -311.099962) (xy 394.344156 -311.099962) (xy 394.348116 -311.050908) (xy 394.359893 -311.003124)
			(xy 394.379184 -310.957848) (xy 394.405487 -310.916252) (xy 394.438122 -310.879415) (xy 394.476243 -310.84829)
			(xy 394.518864 -310.823683) (xy 394.56488 -310.806231) (xy 394.613099 -310.796387) (xy 394.662274 -310.794406)
			(xy 394.711129 -310.800338) (xy 394.7584 -310.81403) (xy 394.802862 -310.835128) (xy 394.843365 -310.863084)
			(xy 394.878858 -310.897176) (xy 394.908423 -310.93652) (xy 394.931294 -310.980097) (xy 394.946878 -311.026778)
			(xy 394.954773 -311.075355) (xy 394.955268 -311.099962) (xy 394.954773 -311.124569) (xy 394.954594 -311.12567)
			(xy 395.273272 -311.12567) (xy 395.273272 -311.074254) (xy 395.281315 -311.023472) (xy 395.297203 -310.974573)
			(xy 395.320546 -310.928761) (xy 395.350767 -310.887165) (xy 395.387123 -310.850809) (xy 395.428719 -310.820588)
			(xy 395.474531 -310.797245) (xy 395.52343 -310.781357) (xy 395.574212 -310.773314) (xy 395.625628 -310.773314)
			(xy 395.67641 -310.781357) (xy 395.725309 -310.797245) (xy 395.771121 -310.820588) (xy 395.812717 -310.850809)
			(xy 395.849073 -310.887165) (xy 395.879294 -310.928761) (xy 395.902637 -310.974573) (xy 395.918525 -311.023472)
			(xy 395.926568 -311.074254) (xy 395.927072 -311.099962) (xy 396.244076 -311.099962) (xy 396.248036 -311.050908)
			(xy 396.259813 -311.003124) (xy 396.279104 -310.957848) (xy 396.305407 -310.916252) (xy 396.338042 -310.879415)
			(xy 396.376163 -310.84829) (xy 396.418784 -310.823683) (xy 396.4648 -310.806231) (xy 396.513019 -310.796387)
			(xy 396.562194 -310.794406) (xy 396.611049 -310.800338) (xy 396.65832 -310.81403) (xy 396.702782 -310.835128)
			(xy 396.743285 -310.863084) (xy 396.778778 -310.897176) (xy 396.808343 -310.93652) (xy 396.831214 -310.980097)
			(xy 396.846798 -311.026778) (xy 396.854693 -311.075355) (xy 396.855188 -311.099962) (xy 396.854693 -311.124569)
			(xy 396.854514 -311.12567) (xy 397.173192 -311.12567) (xy 397.173192 -311.074254) (xy 397.181235 -311.023472)
			(xy 397.197123 -310.974573) (xy 397.220466 -310.928761) (xy 397.250687 -310.887165) (xy 397.287043 -310.850809)
			(xy 397.328639 -310.820588) (xy 397.374451 -310.797245) (xy 397.42335 -310.781357) (xy 397.474132 -310.773314)
			(xy 397.525548 -310.773314) (xy 397.57633 -310.781357) (xy 397.625229 -310.797245) (xy 397.671041 -310.820588)
			(xy 397.712637 -310.850809) (xy 397.748993 -310.887165) (xy 397.779214 -310.928761) (xy 397.802557 -310.974573)
			(xy 397.818445 -311.023472) (xy 397.826488 -311.074254) (xy 397.826992 -311.099962) (xy 398.143996 -311.099962)
			(xy 398.147956 -311.050908) (xy 398.159733 -311.003124) (xy 398.179024 -310.957848) (xy 398.205327 -310.916252)
			(xy 398.237962 -310.879415) (xy 398.276083 -310.84829) (xy 398.318704 -310.823683) (xy 398.36472 -310.806231)
			(xy 398.412939 -310.796387) (xy 398.462114 -310.794406) (xy 398.510969 -310.800338) (xy 398.55824 -310.81403)
			(xy 398.602702 -310.835128) (xy 398.643205 -310.863084) (xy 398.678698 -310.897176) (xy 398.708263 -310.93652)
			(xy 398.731134 -310.980097) (xy 398.746718 -311.026778) (xy 398.754613 -311.075355) (xy 398.755108 -311.099962)
			(xy 398.754613 -311.124569) (xy 398.754434 -311.12567) (xy 399.073366 -311.12567) (xy 399.073366 -311.074254)
			(xy 399.081409 -311.023472) (xy 399.097297 -310.974573) (xy 399.12064 -310.928761) (xy 399.150861 -310.887165)
			(xy 399.187217 -310.850809) (xy 399.228813 -310.820588) (xy 399.274625 -310.797245) (xy 399.323524 -310.781357)
			(xy 399.374306 -310.773314) (xy 399.425722 -310.773314) (xy 399.476504 -310.781357) (xy 399.525403 -310.797245)
			(xy 399.571215 -310.820588) (xy 399.612811 -310.850809) (xy 399.649167 -310.887165) (xy 399.679388 -310.928761)
			(xy 399.702731 -310.974573) (xy 399.718619 -311.023472) (xy 399.726662 -311.074254) (xy 399.727166 -311.099962)
			(xy 400.04417 -311.099962) (xy 400.04813 -311.050908) (xy 400.059907 -311.003124) (xy 400.079198 -310.957848)
			(xy 400.105501 -310.916252) (xy 400.138136 -310.879415) (xy 400.176257 -310.84829) (xy 400.218878 -310.823683)
			(xy 400.264894 -310.806231) (xy 400.313113 -310.796387) (xy 400.362288 -310.794406) (xy 400.411143 -310.800338)
			(xy 400.458414 -310.81403) (xy 400.502876 -310.835128) (xy 400.543379 -310.863084) (xy 400.578872 -310.897176)
			(xy 400.608437 -310.93652) (xy 400.631308 -310.980097) (xy 400.646892 -311.026778) (xy 400.654787 -311.075355)
			(xy 400.655282 -311.099962) (xy 400.654787 -311.124569) (xy 400.654608 -311.12567) (xy 400.973286 -311.12567)
			(xy 400.973286 -311.074254) (xy 400.981329 -311.023472) (xy 400.997217 -310.974573) (xy 401.02056 -310.928761)
			(xy 401.050781 -310.887165) (xy 401.087137 -310.850809) (xy 401.128733 -310.820588) (xy 401.174545 -310.797245)
			(xy 401.223444 -310.781357) (xy 401.274226 -310.773314) (xy 401.325642 -310.773314) (xy 401.376424 -310.781357)
			(xy 401.425323 -310.797245) (xy 401.471135 -310.820588) (xy 401.512731 -310.850809) (xy 401.549087 -310.887165)
			(xy 401.579308 -310.928761) (xy 401.602651 -310.974573) (xy 401.618539 -311.023472) (xy 401.626582 -311.074254)
			(xy 401.627086 -311.099962) (xy 401.94409 -311.099962) (xy 401.94805 -311.050908) (xy 401.959827 -311.003124)
			(xy 401.979118 -310.957848) (xy 402.005421 -310.916252) (xy 402.038056 -310.879415) (xy 402.076177 -310.84829)
			(xy 402.118798 -310.823683) (xy 402.164814 -310.806231) (xy 402.213033 -310.796387) (xy 402.262208 -310.794406)
			(xy 402.311063 -310.800338) (xy 402.358334 -310.81403) (xy 402.402796 -310.835128) (xy 402.443299 -310.863084)
			(xy 402.478792 -310.897176) (xy 402.508357 -310.93652) (xy 402.531228 -310.980097) (xy 402.546812 -311.026778)
			(xy 402.554707 -311.075355) (xy 402.555202 -311.099962) (xy 402.554707 -311.124569) (xy 402.554528 -311.12567)
			(xy 402.873206 -311.12567) (xy 402.873206 -311.074254) (xy 402.881249 -311.023472) (xy 402.897137 -310.974573)
			(xy 402.92048 -310.928761) (xy 402.950701 -310.887165) (xy 402.987057 -310.850809) (xy 403.028653 -310.820588)
			(xy 403.074465 -310.797245) (xy 403.123364 -310.781357) (xy 403.174146 -310.773314) (xy 403.225562 -310.773314)
			(xy 403.276344 -310.781357) (xy 403.325243 -310.797245) (xy 403.371055 -310.820588) (xy 403.412651 -310.850809)
			(xy 403.449007 -310.887165) (xy 403.479228 -310.928761) (xy 403.502571 -310.974573) (xy 403.518459 -311.023472)
			(xy 403.526502 -311.074254) (xy 403.527006 -311.099962) (xy 403.84401 -311.099962) (xy 403.84797 -311.050908)
			(xy 403.859747 -311.003124) (xy 403.879038 -310.957848) (xy 403.905341 -310.916252) (xy 403.937976 -310.879415)
			(xy 403.976097 -310.84829) (xy 404.018718 -310.823683) (xy 404.064734 -310.806231) (xy 404.112953 -310.796387)
			(xy 404.162128 -310.794406) (xy 404.210983 -310.800338) (xy 404.258254 -310.81403) (xy 404.302716 -310.835128)
			(xy 404.343219 -310.863084) (xy 404.378712 -310.897176) (xy 404.408277 -310.93652) (xy 404.431148 -310.980097)
			(xy 404.446732 -311.026778) (xy 404.454627 -311.075355) (xy 404.455122 -311.099962) (xy 404.454627 -311.124569)
			(xy 404.454448 -311.12567) (xy 404.77338 -311.12567) (xy 404.77338 -311.074254) (xy 404.781423 -311.023472)
			(xy 404.797311 -310.974573) (xy 404.820654 -310.928761) (xy 404.850875 -310.887165) (xy 404.887231 -310.850809)
			(xy 404.928827 -310.820588) (xy 404.974639 -310.797245) (xy 405.023538 -310.781357) (xy 405.07432 -310.773314)
			(xy 405.125736 -310.773314) (xy 405.176518 -310.781357) (xy 405.225417 -310.797245) (xy 405.271229 -310.820588)
			(xy 405.312825 -310.850809) (xy 405.349181 -310.887165) (xy 405.379402 -310.928761) (xy 405.402745 -310.974573)
			(xy 405.418633 -311.023472) (xy 405.426676 -311.074254) (xy 405.42718 -311.099962) (xy 405.744184 -311.099962)
			(xy 405.748144 -311.050908) (xy 405.759921 -311.003124) (xy 405.779212 -310.957848) (xy 405.805515 -310.916252)
			(xy 405.83815 -310.879415) (xy 405.876271 -310.84829) (xy 405.918892 -310.823683) (xy 405.964908 -310.806231)
			(xy 406.013127 -310.796387) (xy 406.062302 -310.794406) (xy 406.111157 -310.800338) (xy 406.158428 -310.81403)
			(xy 406.20289 -310.835128) (xy 406.243393 -310.863084) (xy 406.278886 -310.897176) (xy 406.308451 -310.93652)
			(xy 406.331322 -310.980097) (xy 406.346906 -311.026778) (xy 406.354801 -311.075355) (xy 406.355296 -311.099962)
			(xy 406.354801 -311.124569) (xy 406.354622 -311.12567) (xy 406.6733 -311.12567) (xy 406.6733 -311.074254)
			(xy 406.681343 -311.023472) (xy 406.697231 -310.974573) (xy 406.720574 -310.928761) (xy 406.750795 -310.887165)
			(xy 406.787151 -310.850809) (xy 406.828747 -310.820588) (xy 406.874559 -310.797245) (xy 406.923458 -310.781357)
			(xy 406.97424 -310.773314) (xy 407.025656 -310.773314) (xy 407.076438 -310.781357) (xy 407.125337 -310.797245)
			(xy 407.171149 -310.820588) (xy 407.212745 -310.850809) (xy 407.249101 -310.887165) (xy 407.279322 -310.928761)
			(xy 407.302665 -310.974573) (xy 407.318553 -311.023472) (xy 407.326596 -311.074254) (xy 407.3271 -311.099962)
			(xy 407.644104 -311.099962) (xy 407.648064 -311.050908) (xy 407.659841 -311.003124) (xy 407.679132 -310.957848)
			(xy 407.705435 -310.916252) (xy 407.73807 -310.879415) (xy 407.776191 -310.84829) (xy 407.818812 -310.823683)
			(xy 407.864828 -310.806231) (xy 407.913047 -310.796387) (xy 407.962222 -310.794406) (xy 408.011077 -310.800338)
			(xy 408.058348 -310.81403) (xy 408.10281 -310.835128) (xy 408.143313 -310.863084) (xy 408.178806 -310.897176)
			(xy 408.208371 -310.93652) (xy 408.231242 -310.980097) (xy 408.246826 -311.026778) (xy 408.254721 -311.075355)
			(xy 408.255216 -311.099962) (xy 408.254721 -311.124569) (xy 408.254542 -311.12567) (xy 408.57322 -311.12567)
			(xy 408.57322 -311.074254) (xy 408.581263 -311.023472) (xy 408.597151 -310.974573) (xy 408.620494 -310.928761)
			(xy 408.650715 -310.887165) (xy 408.687071 -310.850809) (xy 408.728667 -310.820588) (xy 408.774479 -310.797245)
			(xy 408.823378 -310.781357) (xy 408.87416 -310.773314) (xy 408.925576 -310.773314) (xy 408.976358 -310.781357)
			(xy 409.025257 -310.797245) (xy 409.071069 -310.820588) (xy 409.112665 -310.850809) (xy 409.149021 -310.887165)
			(xy 409.179242 -310.928761) (xy 409.202585 -310.974573) (xy 409.218473 -311.023472) (xy 409.226516 -311.074254)
			(xy 409.22702 -311.099962) (xy 409.544024 -311.099962) (xy 409.547984 -311.050908) (xy 409.559761 -311.003124)
			(xy 409.579052 -310.957848) (xy 409.605355 -310.916252) (xy 409.63799 -310.879415) (xy 409.676111 -310.84829)
			(xy 409.718732 -310.823683) (xy 409.764748 -310.806231) (xy 409.812967 -310.796387) (xy 409.862142 -310.794406)
			(xy 409.910997 -310.800338) (xy 409.958268 -310.81403) (xy 410.00273 -310.835128) (xy 410.043233 -310.863084)
			(xy 410.078726 -310.897176) (xy 410.108291 -310.93652) (xy 410.131162 -310.980097) (xy 410.146746 -311.026778)
			(xy 410.154641 -311.075355) (xy 410.155136 -311.099962) (xy 410.154641 -311.124569) (xy 410.154462 -311.12567)
			(xy 410.47314 -311.12567) (xy 410.47314 -311.074254) (xy 410.481183 -311.023472) (xy 410.497071 -310.974573)
			(xy 410.520414 -310.928761) (xy 410.550635 -310.887165) (xy 410.586991 -310.850809) (xy 410.628587 -310.820588)
			(xy 410.674399 -310.797245) (xy 410.723298 -310.781357) (xy 410.77408 -310.773314) (xy 410.825496 -310.773314)
			(xy 410.876278 -310.781357) (xy 410.925177 -310.797245) (xy 410.970989 -310.820588) (xy 411.012585 -310.850809)
			(xy 411.048941 -310.887165) (xy 411.079162 -310.928761) (xy 411.102505 -310.974573) (xy 411.118393 -311.023472)
			(xy 411.126436 -311.074254) (xy 411.12694 -311.099962) (xy 411.444198 -311.099962) (xy 411.448158 -311.050908)
			(xy 411.459935 -311.003124) (xy 411.479226 -310.957848) (xy 411.505529 -310.916252) (xy 411.538164 -310.879415)
			(xy 411.576285 -310.84829) (xy 411.618906 -310.823683) (xy 411.664922 -310.806231) (xy 411.713141 -310.796387)
			(xy 411.762316 -310.794406) (xy 411.811171 -310.800338) (xy 411.858442 -310.81403) (xy 411.902904 -310.835128)
			(xy 411.943407 -310.863084) (xy 411.9789 -310.897176) (xy 412.008465 -310.93652) (xy 412.031336 -310.980097)
			(xy 412.04692 -311.026778) (xy 412.054815 -311.075355) (xy 412.05531 -311.099962) (xy 412.054815 -311.124569)
			(xy 412.054636 -311.12567) (xy 412.373314 -311.12567) (xy 412.373314 -311.074254) (xy 412.381357 -311.023472)
			(xy 412.397245 -310.974573) (xy 412.420588 -310.928761) (xy 412.450809 -310.887165) (xy 412.487165 -310.850809)
			(xy 412.528761 -310.820588) (xy 412.574573 -310.797245) (xy 412.623472 -310.781357) (xy 412.674254 -310.773314)
			(xy 412.72567 -310.773314) (xy 412.776452 -310.781357) (xy 412.825351 -310.797245) (xy 412.871163 -310.820588)
			(xy 412.912759 -310.850809) (xy 412.949115 -310.887165) (xy 412.979336 -310.928761) (xy 413.002679 -310.974573)
			(xy 413.018567 -311.023472) (xy 413.02661 -311.074254) (xy 413.027114 -311.099962) (xy 413.344118 -311.099962)
			(xy 413.348078 -311.050908) (xy 413.359855 -311.003124) (xy 413.379146 -310.957848) (xy 413.405449 -310.916252)
			(xy 413.438084 -310.879415) (xy 413.476205 -310.84829) (xy 413.518826 -310.823683) (xy 413.564842 -310.806231)
			(xy 413.613061 -310.796387) (xy 413.662236 -310.794406) (xy 413.711091 -310.800338) (xy 413.758362 -310.81403)
			(xy 413.802824 -310.835128) (xy 413.843327 -310.863084) (xy 413.87882 -310.897176) (xy 413.908385 -310.93652)
			(xy 413.931256 -310.980097) (xy 413.94684 -311.026778) (xy 413.954735 -311.075355) (xy 413.95523 -311.099962)
			(xy 413.954735 -311.124569) (xy 413.954556 -311.12567) (xy 414.273234 -311.12567) (xy 414.273234 -311.074254)
			(xy 414.281277 -311.023472) (xy 414.297165 -310.974573) (xy 414.320508 -310.928761) (xy 414.350729 -310.887165)
			(xy 414.387085 -310.850809) (xy 414.428681 -310.820588) (xy 414.474493 -310.797245) (xy 414.523392 -310.781357)
			(xy 414.574174 -310.773314) (xy 414.62559 -310.773314) (xy 414.676372 -310.781357) (xy 414.725271 -310.797245)
			(xy 414.771083 -310.820588) (xy 414.812679 -310.850809) (xy 414.849035 -310.887165) (xy 414.879256 -310.928761)
			(xy 414.902599 -310.974573) (xy 414.918487 -311.023472) (xy 414.92653 -311.074254) (xy 414.927034 -311.099962)
			(xy 415.244038 -311.099962) (xy 415.247998 -311.050908) (xy 415.259775 -311.003124) (xy 415.279066 -310.957848)
			(xy 415.305369 -310.916252) (xy 415.338004 -310.879415) (xy 415.376125 -310.84829) (xy 415.418746 -310.823683)
			(xy 415.464762 -310.806231) (xy 415.512981 -310.796387) (xy 415.562156 -310.794406) (xy 415.611011 -310.800338)
			(xy 415.658282 -310.81403) (xy 415.702744 -310.835128) (xy 415.743247 -310.863084) (xy 415.77874 -310.897176)
			(xy 415.808305 -310.93652) (xy 415.831176 -310.980097) (xy 415.84676 -311.026778) (xy 415.854655 -311.075355)
			(xy 415.85515 -311.099962) (xy 415.854655 -311.124569) (xy 415.854476 -311.12567) (xy 416.173154 -311.12567)
			(xy 416.173154 -311.074254) (xy 416.181197 -311.023472) (xy 416.197085 -310.974573) (xy 416.220428 -310.928761)
			(xy 416.250649 -310.887165) (xy 416.287005 -310.850809) (xy 416.328601 -310.820588) (xy 416.374413 -310.797245)
			(xy 416.423312 -310.781357) (xy 416.474094 -310.773314) (xy 416.52551 -310.773314) (xy 416.576292 -310.781357)
			(xy 416.625191 -310.797245) (xy 416.671003 -310.820588) (xy 416.712599 -310.850809) (xy 416.748955 -310.887165)
			(xy 416.779176 -310.928761) (xy 416.802519 -310.974573) (xy 416.818407 -311.023472) (xy 416.82645 -311.074254)
			(xy 416.826954 -311.099962) (xy 416.82645 -311.12567) (xy 416.818407 -311.176452) (xy 416.802519 -311.225351)
			(xy 416.779176 -311.271163) (xy 416.748955 -311.312759) (xy 416.712599 -311.349115) (xy 416.671003 -311.379336)
			(xy 416.625191 -311.402679) (xy 416.576292 -311.418567) (xy 416.52551 -311.42661) (xy 416.474094 -311.42661)
			(xy 416.423312 -311.418567) (xy 416.374413 -311.402679) (xy 416.328601 -311.379336) (xy 416.287005 -311.349115)
			(xy 416.250649 -311.312759) (xy 416.220428 -311.271163) (xy 416.197085 -311.225351) (xy 416.181197 -311.176452)
			(xy 416.173154 -311.12567) (xy 415.854476 -311.12567) (xy 415.84676 -311.173146) (xy 415.831176 -311.219827)
			(xy 415.808305 -311.263404) (xy 415.77874 -311.302748) (xy 415.743247 -311.33684) (xy 415.702744 -311.364796)
			(xy 415.658282 -311.385894) (xy 415.611011 -311.399586) (xy 415.562156 -311.405518) (xy 415.512981 -311.403537)
			(xy 415.464762 -311.393693) (xy 415.418746 -311.376241) (xy 415.376125 -311.351634) (xy 415.338004 -311.320509)
			(xy 415.305369 -311.283672) (xy 415.279066 -311.242076) (xy 415.259775 -311.1968) (xy 415.247998 -311.149016)
			(xy 415.244038 -311.099962) (xy 414.927034 -311.099962) (xy 414.92653 -311.12567) (xy 414.918487 -311.176452)
			(xy 414.902599 -311.225351) (xy 414.879256 -311.271163) (xy 414.849035 -311.312759) (xy 414.812679 -311.349115)
			(xy 414.771083 -311.379336) (xy 414.725271 -311.402679) (xy 414.676372 -311.418567) (xy 414.62559 -311.42661)
			(xy 414.574174 -311.42661) (xy 414.523392 -311.418567) (xy 414.474493 -311.402679) (xy 414.428681 -311.379336)
			(xy 414.387085 -311.349115) (xy 414.350729 -311.312759) (xy 414.320508 -311.271163) (xy 414.297165 -311.225351)
			(xy 414.281277 -311.176452) (xy 414.273234 -311.12567) (xy 413.954556 -311.12567) (xy 413.94684 -311.173146)
			(xy 413.931256 -311.219827) (xy 413.908385 -311.263404) (xy 413.87882 -311.302748) (xy 413.843327 -311.33684)
			(xy 413.802824 -311.364796) (xy 413.758362 -311.385894) (xy 413.711091 -311.399586) (xy 413.662236 -311.405518)
			(xy 413.613061 -311.403537) (xy 413.564842 -311.393693) (xy 413.518826 -311.376241) (xy 413.476205 -311.351634)
			(xy 413.438084 -311.320509) (xy 413.405449 -311.283672) (xy 413.379146 -311.242076) (xy 413.359855 -311.1968)
			(xy 413.348078 -311.149016) (xy 413.344118 -311.099962) (xy 413.027114 -311.099962) (xy 413.02661 -311.12567)
			(xy 413.018567 -311.176452) (xy 413.002679 -311.225351) (xy 412.979336 -311.271163) (xy 412.949115 -311.312759)
			(xy 412.912759 -311.349115) (xy 412.871163 -311.379336) (xy 412.825351 -311.402679) (xy 412.776452 -311.418567)
			(xy 412.72567 -311.42661) (xy 412.674254 -311.42661) (xy 412.623472 -311.418567) (xy 412.574573 -311.402679)
			(xy 412.528761 -311.379336) (xy 412.487165 -311.349115) (xy 412.450809 -311.312759) (xy 412.420588 -311.271163)
			(xy 412.397245 -311.225351) (xy 412.381357 -311.176452) (xy 412.373314 -311.12567) (xy 412.054636 -311.12567)
			(xy 412.04692 -311.173146) (xy 412.031336 -311.219827) (xy 412.008465 -311.263404) (xy 411.9789 -311.302748)
			(xy 411.943407 -311.33684) (xy 411.902904 -311.364796) (xy 411.858442 -311.385894) (xy 411.811171 -311.399586)
			(xy 411.762316 -311.405518) (xy 411.713141 -311.403537) (xy 411.664922 -311.393693) (xy 411.618906 -311.376241)
			(xy 411.576285 -311.351634) (xy 411.538164 -311.320509) (xy 411.505529 -311.283672) (xy 411.479226 -311.242076)
			(xy 411.459935 -311.1968) (xy 411.448158 -311.149016) (xy 411.444198 -311.099962) (xy 411.12694 -311.099962)
			(xy 411.126436 -311.12567) (xy 411.118393 -311.176452) (xy 411.102505 -311.225351) (xy 411.079162 -311.271163)
			(xy 411.048941 -311.312759) (xy 411.012585 -311.349115) (xy 410.970989 -311.379336) (xy 410.925177 -311.402679)
			(xy 410.876278 -311.418567) (xy 410.825496 -311.42661) (xy 410.77408 -311.42661) (xy 410.723298 -311.418567)
			(xy 410.674399 -311.402679) (xy 410.628587 -311.379336) (xy 410.586991 -311.349115) (xy 410.550635 -311.312759)
			(xy 410.520414 -311.271163) (xy 410.497071 -311.225351) (xy 410.481183 -311.176452) (xy 410.47314 -311.12567)
			(xy 410.154462 -311.12567) (xy 410.146746 -311.173146) (xy 410.131162 -311.219827) (xy 410.108291 -311.263404)
			(xy 410.078726 -311.302748) (xy 410.043233 -311.33684) (xy 410.00273 -311.364796) (xy 409.958268 -311.385894)
			(xy 409.910997 -311.399586) (xy 409.862142 -311.405518) (xy 409.812967 -311.403537) (xy 409.764748 -311.393693)
			(xy 409.718732 -311.376241) (xy 409.676111 -311.351634) (xy 409.63799 -311.320509) (xy 409.605355 -311.283672)
			(xy 409.579052 -311.242076) (xy 409.559761 -311.1968) (xy 409.547984 -311.149016) (xy 409.544024 -311.099962)
			(xy 409.22702 -311.099962) (xy 409.226516 -311.12567) (xy 409.218473 -311.176452) (xy 409.202585 -311.225351)
			(xy 409.179242 -311.271163) (xy 409.149021 -311.312759) (xy 409.112665 -311.349115) (xy 409.071069 -311.379336)
			(xy 409.025257 -311.402679) (xy 408.976358 -311.418567) (xy 408.925576 -311.42661) (xy 408.87416 -311.42661)
			(xy 408.823378 -311.418567) (xy 408.774479 -311.402679) (xy 408.728667 -311.379336) (xy 408.687071 -311.349115)
			(xy 408.650715 -311.312759) (xy 408.620494 -311.271163) (xy 408.597151 -311.225351) (xy 408.581263 -311.176452)
			(xy 408.57322 -311.12567) (xy 408.254542 -311.12567) (xy 408.246826 -311.173146) (xy 408.231242 -311.219827)
			(xy 408.208371 -311.263404) (xy 408.178806 -311.302748) (xy 408.143313 -311.33684) (xy 408.10281 -311.364796)
			(xy 408.058348 -311.385894) (xy 408.011077 -311.399586) (xy 407.962222 -311.405518) (xy 407.913047 -311.403537)
			(xy 407.864828 -311.393693) (xy 407.818812 -311.376241) (xy 407.776191 -311.351634) (xy 407.73807 -311.320509)
			(xy 407.705435 -311.283672) (xy 407.679132 -311.242076) (xy 407.659841 -311.1968) (xy 407.648064 -311.149016)
			(xy 407.644104 -311.099962) (xy 407.3271 -311.099962) (xy 407.326596 -311.12567) (xy 407.318553 -311.176452)
			(xy 407.302665 -311.225351) (xy 407.279322 -311.271163) (xy 407.249101 -311.312759) (xy 407.212745 -311.349115)
			(xy 407.171149 -311.379336) (xy 407.125337 -311.402679) (xy 407.076438 -311.418567) (xy 407.025656 -311.42661)
			(xy 406.97424 -311.42661) (xy 406.923458 -311.418567) (xy 406.874559 -311.402679) (xy 406.828747 -311.379336)
			(xy 406.787151 -311.349115) (xy 406.750795 -311.312759) (xy 406.720574 -311.271163) (xy 406.697231 -311.225351)
			(xy 406.681343 -311.176452) (xy 406.6733 -311.12567) (xy 406.354622 -311.12567) (xy 406.346906 -311.173146)
			(xy 406.331322 -311.219827) (xy 406.308451 -311.263404) (xy 406.278886 -311.302748) (xy 406.243393 -311.33684)
			(xy 406.20289 -311.364796) (xy 406.158428 -311.385894) (xy 406.111157 -311.399586) (xy 406.062302 -311.405518)
			(xy 406.013127 -311.403537) (xy 405.964908 -311.393693) (xy 405.918892 -311.376241) (xy 405.876271 -311.351634)
			(xy 405.83815 -311.320509) (xy 405.805515 -311.283672) (xy 405.779212 -311.242076) (xy 405.759921 -311.1968)
			(xy 405.748144 -311.149016) (xy 405.744184 -311.099962) (xy 405.42718 -311.099962) (xy 405.426676 -311.12567)
			(xy 405.418633 -311.176452) (xy 405.402745 -311.225351) (xy 405.379402 -311.271163) (xy 405.349181 -311.312759)
			(xy 405.312825 -311.349115) (xy 405.271229 -311.379336) (xy 405.225417 -311.402679) (xy 405.176518 -311.418567)
			(xy 405.125736 -311.42661) (xy 405.07432 -311.42661) (xy 405.023538 -311.418567) (xy 404.974639 -311.402679)
			(xy 404.928827 -311.379336) (xy 404.887231 -311.349115) (xy 404.850875 -311.312759) (xy 404.820654 -311.271163)
			(xy 404.797311 -311.225351) (xy 404.781423 -311.176452) (xy 404.77338 -311.12567) (xy 404.454448 -311.12567)
			(xy 404.446732 -311.173146) (xy 404.431148 -311.219827) (xy 404.408277 -311.263404) (xy 404.378712 -311.302748)
			(xy 404.343219 -311.33684) (xy 404.302716 -311.364796) (xy 404.258254 -311.385894) (xy 404.210983 -311.399586)
			(xy 404.162128 -311.405518) (xy 404.112953 -311.403537) (xy 404.064734 -311.393693) (xy 404.018718 -311.376241)
			(xy 403.976097 -311.351634) (xy 403.937976 -311.320509) (xy 403.905341 -311.283672) (xy 403.879038 -311.242076)
			(xy 403.859747 -311.1968) (xy 403.84797 -311.149016) (xy 403.84401 -311.099962) (xy 403.527006 -311.099962)
			(xy 403.526502 -311.12567) (xy 403.518459 -311.176452) (xy 403.502571 -311.225351) (xy 403.479228 -311.271163)
			(xy 403.449007 -311.312759) (xy 403.412651 -311.349115) (xy 403.371055 -311.379336) (xy 403.325243 -311.402679)
			(xy 403.276344 -311.418567) (xy 403.225562 -311.42661) (xy 403.174146 -311.42661) (xy 403.123364 -311.418567)
			(xy 403.074465 -311.402679) (xy 403.028653 -311.379336) (xy 402.987057 -311.349115) (xy 402.950701 -311.312759)
			(xy 402.92048 -311.271163) (xy 402.897137 -311.225351) (xy 402.881249 -311.176452) (xy 402.873206 -311.12567)
			(xy 402.554528 -311.12567) (xy 402.546812 -311.173146) (xy 402.531228 -311.219827) (xy 402.508357 -311.263404)
			(xy 402.478792 -311.302748) (xy 402.443299 -311.33684) (xy 402.402796 -311.364796) (xy 402.358334 -311.385894)
			(xy 402.311063 -311.399586) (xy 402.262208 -311.405518) (xy 402.213033 -311.403537) (xy 402.164814 -311.393693)
			(xy 402.118798 -311.376241) (xy 402.076177 -311.351634) (xy 402.038056 -311.320509) (xy 402.005421 -311.283672)
			(xy 401.979118 -311.242076) (xy 401.959827 -311.1968) (xy 401.94805 -311.149016) (xy 401.94409 -311.099962)
			(xy 401.627086 -311.099962) (xy 401.626582 -311.12567) (xy 401.618539 -311.176452) (xy 401.602651 -311.225351)
			(xy 401.579308 -311.271163) (xy 401.549087 -311.312759) (xy 401.512731 -311.349115) (xy 401.471135 -311.379336)
			(xy 401.425323 -311.402679) (xy 401.376424 -311.418567) (xy 401.325642 -311.42661) (xy 401.274226 -311.42661)
			(xy 401.223444 -311.418567) (xy 401.174545 -311.402679) (xy 401.128733 -311.379336) (xy 401.087137 -311.349115)
			(xy 401.050781 -311.312759) (xy 401.02056 -311.271163) (xy 400.997217 -311.225351) (xy 400.981329 -311.176452)
			(xy 400.973286 -311.12567) (xy 400.654608 -311.12567) (xy 400.646892 -311.173146) (xy 400.631308 -311.219827)
			(xy 400.608437 -311.263404) (xy 400.578872 -311.302748) (xy 400.543379 -311.33684) (xy 400.502876 -311.364796)
			(xy 400.458414 -311.385894) (xy 400.411143 -311.399586) (xy 400.362288 -311.405518) (xy 400.313113 -311.403537)
			(xy 400.264894 -311.393693) (xy 400.218878 -311.376241) (xy 400.176257 -311.351634) (xy 400.138136 -311.320509)
			(xy 400.105501 -311.283672) (xy 400.079198 -311.242076) (xy 400.059907 -311.1968) (xy 400.04813 -311.149016)
			(xy 400.04417 -311.099962) (xy 399.727166 -311.099962) (xy 399.726662 -311.12567) (xy 399.718619 -311.176452)
			(xy 399.702731 -311.225351) (xy 399.679388 -311.271163) (xy 399.649167 -311.312759) (xy 399.612811 -311.349115)
			(xy 399.571215 -311.379336) (xy 399.525403 -311.402679) (xy 399.476504 -311.418567) (xy 399.425722 -311.42661)
			(xy 399.374306 -311.42661) (xy 399.323524 -311.418567) (xy 399.274625 -311.402679) (xy 399.228813 -311.379336)
			(xy 399.187217 -311.349115) (xy 399.150861 -311.312759) (xy 399.12064 -311.271163) (xy 399.097297 -311.225351)
			(xy 399.081409 -311.176452) (xy 399.073366 -311.12567) (xy 398.754434 -311.12567) (xy 398.746718 -311.173146)
			(xy 398.731134 -311.219827) (xy 398.708263 -311.263404) (xy 398.678698 -311.302748) (xy 398.643205 -311.33684)
			(xy 398.602702 -311.364796) (xy 398.55824 -311.385894) (xy 398.510969 -311.399586) (xy 398.462114 -311.405518)
			(xy 398.412939 -311.403537) (xy 398.36472 -311.393693) (xy 398.318704 -311.376241) (xy 398.276083 -311.351634)
			(xy 398.237962 -311.320509) (xy 398.205327 -311.283672) (xy 398.179024 -311.242076) (xy 398.159733 -311.1968)
			(xy 398.147956 -311.149016) (xy 398.143996 -311.099962) (xy 397.826992 -311.099962) (xy 397.826488 -311.12567)
			(xy 397.818445 -311.176452) (xy 397.802557 -311.225351) (xy 397.779214 -311.271163) (xy 397.748993 -311.312759)
			(xy 397.712637 -311.349115) (xy 397.671041 -311.379336) (xy 397.625229 -311.402679) (xy 397.57633 -311.418567)
			(xy 397.525548 -311.42661) (xy 397.474132 -311.42661) (xy 397.42335 -311.418567) (xy 397.374451 -311.402679)
			(xy 397.328639 -311.379336) (xy 397.287043 -311.349115) (xy 397.250687 -311.312759) (xy 397.220466 -311.271163)
			(xy 397.197123 -311.225351) (xy 397.181235 -311.176452) (xy 397.173192 -311.12567) (xy 396.854514 -311.12567)
			(xy 396.846798 -311.173146) (xy 396.831214 -311.219827) (xy 396.808343 -311.263404) (xy 396.778778 -311.302748)
			(xy 396.743285 -311.33684) (xy 396.702782 -311.364796) (xy 396.65832 -311.385894) (xy 396.611049 -311.399586)
			(xy 396.562194 -311.405518) (xy 396.513019 -311.403537) (xy 396.4648 -311.393693) (xy 396.418784 -311.376241)
			(xy 396.376163 -311.351634) (xy 396.338042 -311.320509) (xy 396.305407 -311.283672) (xy 396.279104 -311.242076)
			(xy 396.259813 -311.1968) (xy 396.248036 -311.149016) (xy 396.244076 -311.099962) (xy 395.927072 -311.099962)
			(xy 395.926568 -311.12567) (xy 395.918525 -311.176452) (xy 395.902637 -311.225351) (xy 395.879294 -311.271163)
			(xy 395.849073 -311.312759) (xy 395.812717 -311.349115) (xy 395.771121 -311.379336) (xy 395.725309 -311.402679)
			(xy 395.67641 -311.418567) (xy 395.625628 -311.42661) (xy 395.574212 -311.42661) (xy 395.52343 -311.418567)
			(xy 395.474531 -311.402679) (xy 395.428719 -311.379336) (xy 395.387123 -311.349115) (xy 395.350767 -311.312759)
			(xy 395.320546 -311.271163) (xy 395.297203 -311.225351) (xy 395.281315 -311.176452) (xy 395.273272 -311.12567)
			(xy 394.954594 -311.12567) (xy 394.946878 -311.173146) (xy 394.931294 -311.219827) (xy 394.908423 -311.263404)
			(xy 394.878858 -311.302748) (xy 394.843365 -311.33684) (xy 394.802862 -311.364796) (xy 394.7584 -311.385894)
			(xy 394.711129 -311.399586) (xy 394.662274 -311.405518) (xy 394.613099 -311.403537) (xy 394.56488 -311.393693)
			(xy 394.518864 -311.376241) (xy 394.476243 -311.351634) (xy 394.438122 -311.320509) (xy 394.405487 -311.283672)
			(xy 394.379184 -311.242076) (xy 394.359893 -311.1968) (xy 394.348116 -311.149016) (xy 394.344156 -311.099962)
			(xy 394.027152 -311.099962) (xy 394.026648 -311.12567) (xy 394.018605 -311.176452) (xy 394.002717 -311.225351)
			(xy 393.979374 -311.271163) (xy 393.949153 -311.312759) (xy 393.912797 -311.349115) (xy 393.871201 -311.379336)
			(xy 393.825389 -311.402679) (xy 393.77649 -311.418567) (xy 393.725708 -311.42661) (xy 393.674292 -311.42661)
			(xy 393.62351 -311.418567) (xy 393.574611 -311.402679) (xy 393.528799 -311.379336) (xy 393.487203 -311.349115)
			(xy 393.450847 -311.312759) (xy 393.420626 -311.271163) (xy 393.397283 -311.225351) (xy 393.381395 -311.176452)
			(xy 393.373352 -311.12567) (xy 393.05442 -311.12567) (xy 393.046704 -311.173146) (xy 393.03112 -311.219827)
			(xy 393.008249 -311.263404) (xy 392.978684 -311.302748) (xy 392.943191 -311.33684) (xy 392.902688 -311.364796)
			(xy 392.858226 -311.385894) (xy 392.810955 -311.399586) (xy 392.7621 -311.405518) (xy 392.712925 -311.403537)
			(xy 392.664706 -311.393693) (xy 392.61869 -311.376241) (xy 392.576069 -311.351634) (xy 392.537948 -311.320509)
			(xy 392.505313 -311.283672) (xy 392.47901 -311.242076) (xy 392.459719 -311.1968) (xy 392.447942 -311.149016)
			(xy 392.443982 -311.099962) (xy 392.126978 -311.099962) (xy 392.126474 -311.12567) (xy 392.118431 -311.176452)
			(xy 392.102543 -311.225351) (xy 392.0792 -311.271163) (xy 392.048979 -311.312759) (xy 392.012623 -311.349115)
			(xy 391.971027 -311.379336) (xy 391.925215 -311.402679) (xy 391.876316 -311.418567) (xy 391.825534 -311.42661)
			(xy 391.774118 -311.42661) (xy 391.723336 -311.418567) (xy 391.674437 -311.402679) (xy 391.628625 -311.379336)
			(xy 391.587029 -311.349115) (xy 391.550673 -311.312759) (xy 391.520452 -311.271163) (xy 391.497109 -311.225351)
			(xy 391.481221 -311.176452) (xy 391.473178 -311.12567) (xy 391.1545 -311.12567) (xy 391.146784 -311.173146)
			(xy 391.1312 -311.219827) (xy 391.108329 -311.263404) (xy 391.078764 -311.302748) (xy 391.043271 -311.33684)
			(xy 391.002768 -311.364796) (xy 390.958306 -311.385894) (xy 390.911035 -311.399586) (xy 390.86218 -311.405518)
			(xy 390.813005 -311.403537) (xy 390.764786 -311.393693) (xy 390.71877 -311.376241) (xy 390.676149 -311.351634)
			(xy 390.638028 -311.320509) (xy 390.605393 -311.283672) (xy 390.57909 -311.242076) (xy 390.559799 -311.1968)
			(xy 390.548022 -311.149016) (xy 390.544062 -311.099962) (xy 390.227058 -311.099962) (xy 390.226554 -311.12567)
			(xy 390.218511 -311.176452) (xy 390.202623 -311.225351) (xy 390.17928 -311.271163) (xy 390.149059 -311.312759)
			(xy 390.112703 -311.349115) (xy 390.071107 -311.379336) (xy 390.025295 -311.402679) (xy 389.976396 -311.418567)
			(xy 389.925614 -311.42661) (xy 389.874198 -311.42661) (xy 389.823416 -311.418567) (xy 389.774517 -311.402679)
			(xy 389.728705 -311.379336) (xy 389.687109 -311.349115) (xy 389.650753 -311.312759) (xy 389.620532 -311.271163)
			(xy 389.597189 -311.225351) (xy 389.581301 -311.176452) (xy 389.573258 -311.12567) (xy 389.25458 -311.12567)
			(xy 389.246864 -311.173146) (xy 389.23128 -311.219827) (xy 389.208409 -311.263404) (xy 389.178844 -311.302748)
			(xy 389.143351 -311.33684) (xy 389.102848 -311.364796) (xy 389.058386 -311.385894) (xy 389.011115 -311.399586)
			(xy 388.96226 -311.405518) (xy 388.913085 -311.403537) (xy 388.864866 -311.393693) (xy 388.81885 -311.376241)
			(xy 388.776229 -311.351634) (xy 388.738108 -311.320509) (xy 388.705473 -311.283672) (xy 388.67917 -311.242076)
			(xy 388.659879 -311.1968) (xy 388.648102 -311.149016) (xy 388.644142 -311.099962) (xy 388.327138 -311.099962)
			(xy 388.326634 -311.12567) (xy 388.318591 -311.176452) (xy 388.302703 -311.225351) (xy 388.27936 -311.271163)
			(xy 388.249139 -311.312759) (xy 388.212783 -311.349115) (xy 388.171187 -311.379336) (xy 388.125375 -311.402679)
			(xy 388.076476 -311.418567) (xy 388.025694 -311.42661) (xy 387.974278 -311.42661) (xy 387.923496 -311.418567)
			(xy 387.874597 -311.402679) (xy 387.828785 -311.379336) (xy 387.787189 -311.349115) (xy 387.750833 -311.312759)
			(xy 387.720612 -311.271163) (xy 387.697269 -311.225351) (xy 387.681381 -311.176452) (xy 387.673338 -311.12567)
			(xy 387.35466 -311.12567) (xy 387.346944 -311.173146) (xy 387.33136 -311.219827) (xy 387.308489 -311.263404)
			(xy 387.278924 -311.302748) (xy 387.243431 -311.33684) (xy 387.202928 -311.364796) (xy 387.158466 -311.385894)
			(xy 387.111195 -311.399586) (xy 387.06234 -311.405518) (xy 387.013165 -311.403537) (xy 386.964946 -311.393693)
			(xy 386.91893 -311.376241) (xy 386.876309 -311.351634) (xy 386.838188 -311.320509) (xy 386.805553 -311.283672)
			(xy 386.77925 -311.242076) (xy 386.759959 -311.1968) (xy 386.748182 -311.149016) (xy 386.744222 -311.099962)
			(xy 386.40512 -311.099962) (xy 386.404625 -311.124569) (xy 386.39673 -311.173146) (xy 386.381146 -311.219827)
			(xy 386.358275 -311.263404) (xy 386.32871 -311.302748) (xy 386.293217 -311.33684) (xy 386.252714 -311.364796)
			(xy 386.208252 -311.385894) (xy 386.160981 -311.399586) (xy 386.112126 -311.405518) (xy 386.062951 -311.403537)
			(xy 386.014732 -311.393693) (xy 385.968716 -311.376241) (xy 385.926095 -311.351634) (xy 385.887974 -311.320509)
			(xy 385.855339 -311.283672) (xy 385.829036 -311.242076) (xy 385.809745 -311.1968) (xy 385.797968 -311.149016)
			(xy 385.794008 -311.099962) (xy 385.45516 -311.099962) (xy 385.454665 -311.124569) (xy 385.44677 -311.173146)
			(xy 385.431186 -311.219827) (xy 385.408315 -311.263404) (xy 385.37875 -311.302748) (xy 385.343257 -311.33684)
			(xy 385.302754 -311.364796) (xy 385.258292 -311.385894) (xy 385.211021 -311.399586) (xy 385.162166 -311.405518)
			(xy 385.112991 -311.403537) (xy 385.064772 -311.393693) (xy 385.018756 -311.376241) (xy 384.976135 -311.351634)
			(xy 384.938014 -311.320509) (xy 384.905379 -311.283672) (xy 384.879076 -311.242076) (xy 384.859785 -311.1968)
			(xy 384.848008 -311.149016) (xy 384.844048 -311.099962) (xy 383.326343 -311.099962) (xy 383.310579 -311.152357)
			(xy 383.286907 -311.202854) (xy 383.256134 -311.249367) (xy 383.218917 -311.290904) (xy 383.176049 -311.326579)
			(xy 383.128443 -311.355633) (xy 383.077114 -311.377445) (xy 383.023157 -311.391551) (xy 382.96772 -311.397651)
			(xy 382.911986 -311.395614) (xy 382.857143 -311.385484) (xy 382.804359 -311.367477) (xy 382.754759 -311.341976)
			(xy 382.709401 -311.309525) (xy 382.669252 -311.270816) (xy 382.635166 -311.226673) (xy 382.60787 -311.178038)
			(xy 382.587947 -311.125947) (xy 382.575821 -311.07151) (xy 382.57175 -311.015888) (xy 377.284667 -311.015888)
			(xy 377.283109 -311.019212) (xy 377.252336 -311.065725) (xy 377.215119 -311.107262) (xy 377.172251 -311.142937)
			(xy 377.124645 -311.171991) (xy 377.073316 -311.193803) (xy 377.019359 -311.207909) (xy 376.963922 -311.214009)
			(xy 376.908188 -311.211972) (xy 376.853345 -311.201842) (xy 376.800561 -311.183835) (xy 376.750961 -311.158334)
			(xy 376.705603 -311.125883) (xy 376.665454 -311.087174) (xy 376.631368 -311.043031) (xy 376.604072 -310.994396)
			(xy 376.584149 -310.942305) (xy 376.572023 -310.887868) (xy 376.567952 -310.832246) (xy 351.03308 -310.832246)
			(xy 351.03308 -311.7342) (xy 380.789432 -311.7342) (xy 380.793503 -311.678578) (xy 380.805629 -311.624141)
			(xy 380.825552 -311.57205) (xy 380.852848 -311.523415) (xy 380.886934 -311.479272) (xy 380.927083 -311.440563)
			(xy 380.972441 -311.408112) (xy 381.022041 -311.382611) (xy 381.074825 -311.364604) (xy 381.129668 -311.354474)
			(xy 381.185402 -311.352437) (xy 381.240839 -311.358537) (xy 381.294796 -311.372643) (xy 381.346125 -311.394455)
			(xy 381.393731 -311.423509) (xy 381.436599 -311.459184) (xy 381.473816 -311.500721) (xy 381.504589 -311.547234)
			(xy 381.528261 -311.597731) (xy 381.544329 -311.651138) (xy 381.552449 -311.706314) (xy 381.552958 -311.7342)
			(xy 381.552449 -311.762086) (xy 381.544329 -311.817262) (xy 381.528261 -311.870669) (xy 381.504589 -311.921166)
			(xy 381.473816 -311.967679) (xy 381.436599 -312.009216) (xy 381.393731 -312.044891) (xy 381.346125 -312.073945)
			(xy 381.294796 -312.095757) (xy 381.240839 -312.109863) (xy 381.185402 -312.115963) (xy 381.129668 -312.113926)
			(xy 381.074825 -312.103796) (xy 381.022041 -312.085789) (xy 380.972441 -312.060288) (xy 380.927083 -312.027837)
			(xy 380.886934 -311.989128) (xy 380.852848 -311.944985) (xy 380.825552 -311.89635) (xy 380.805629 -311.844259)
			(xy 380.793503 -311.789822) (xy 380.789432 -311.7342) (xy 351.03308 -311.7342) (xy 351.03308 -312.523378)
			(xy 380.032004 -312.523378) (xy 380.036075 -312.467756) (xy 380.048201 -312.413319) (xy 380.068124 -312.361228)
			(xy 380.09542 -312.312593) (xy 380.129506 -312.26845) (xy 380.169655 -312.229741) (xy 380.215013 -312.19729)
			(xy 380.264613 -312.171789) (xy 380.317397 -312.153782) (xy 380.37224 -312.143652) (xy 380.427974 -312.141615)
			(xy 380.483411 -312.147715) (xy 380.537368 -312.161821) (xy 380.588697 -312.183633) (xy 380.636303 -312.212687)
			(xy 380.679171 -312.248362) (xy 380.696863 -312.268108) (xy 382.410714 -312.268108) (xy 382.414785 -312.212486)
			(xy 382.426911 -312.158049) (xy 382.446834 -312.105958) (xy 382.47413 -312.057323) (xy 382.508216 -312.01318)
			(xy 382.548365 -311.974471) (xy 382.593723 -311.94202) (xy 382.643323 -311.916519) (xy 382.696107 -311.898512)
			(xy 382.75095 -311.888382) (xy 382.806684 -311.886345) (xy 382.862121 -311.892445) (xy 382.916078 -311.906551)
			(xy 382.967407 -311.928363) (xy 383.015013 -311.957417) (xy 383.057881 -311.993092) (xy 383.095098 -312.034629)
			(xy 383.105048 -312.049668) (xy 383.893834 -312.049668) (xy 383.897794 -312.000614) (xy 383.909571 -311.95283)
			(xy 383.928862 -311.907554) (xy 383.955165 -311.865958) (xy 383.9878 -311.829121) (xy 384.025921 -311.797996)
			(xy 384.068542 -311.773389) (xy 384.114558 -311.755937) (xy 384.162777 -311.746093) (xy 384.211952 -311.744112)
			(xy 384.260807 -311.750044) (xy 384.308078 -311.763736) (xy 384.35254 -311.784834) (xy 384.393043 -311.81279)
			(xy 384.428536 -311.846882) (xy 384.458101 -311.886226) (xy 384.480972 -311.929803) (xy 384.496556 -311.976484)
			(xy 384.504451 -312.025061) (xy 384.504946 -312.049668) (xy 384.504451 -312.074275) (xy 384.504231 -312.07563)
			(xy 384.823204 -312.07563) (xy 384.823204 -312.024214) (xy 384.831247 -311.973432) (xy 384.847135 -311.924533)
			(xy 384.870478 -311.878721) (xy 384.900699 -311.837125) (xy 384.937055 -311.800769) (xy 384.978651 -311.770548)
			(xy 385.024463 -311.747205) (xy 385.073362 -311.731317) (xy 385.124144 -311.723274) (xy 385.17556 -311.723274)
			(xy 385.226342 -311.731317) (xy 385.275241 -311.747205) (xy 385.321053 -311.770548) (xy 385.362649 -311.800769)
			(xy 385.399005 -311.837125) (xy 385.429226 -311.878721) (xy 385.452569 -311.924533) (xy 385.468457 -311.973432)
			(xy 385.4765 -312.024214) (xy 385.477004 -312.049922) (xy 385.4765 -312.07563) (xy 385.773164 -312.07563)
			(xy 385.773164 -312.024214) (xy 385.781207 -311.973432) (xy 385.797095 -311.924533) (xy 385.820438 -311.878721)
			(xy 385.850659 -311.837125) (xy 385.887015 -311.800769) (xy 385.928611 -311.770548) (xy 385.974423 -311.747205)
			(xy 386.023322 -311.731317) (xy 386.074104 -311.723274) (xy 386.12552 -311.723274) (xy 386.176302 -311.731317)
			(xy 386.225201 -311.747205) (xy 386.271013 -311.770548) (xy 386.312609 -311.800769) (xy 386.348965 -311.837125)
			(xy 386.379186 -311.878721) (xy 386.402529 -311.924533) (xy 386.418417 -311.973432) (xy 386.42646 -312.024214)
			(xy 386.426964 -312.049922) (xy 386.744222 -312.049922) (xy 386.748182 -312.000868) (xy 386.759959 -311.953084)
			(xy 386.77925 -311.907808) (xy 386.805553 -311.866212) (xy 386.838188 -311.829375) (xy 386.876309 -311.79825)
			(xy 386.91893 -311.773643) (xy 386.964946 -311.756191) (xy 387.013165 -311.746347) (xy 387.06234 -311.744366)
			(xy 387.111195 -311.750298) (xy 387.158466 -311.76399) (xy 387.202928 -311.785088) (xy 387.243431 -311.813044)
			(xy 387.278924 -311.847136) (xy 387.308489 -311.88648) (xy 387.33136 -311.930057) (xy 387.346944 -311.976738)
			(xy 387.354839 -312.025315) (xy 387.355334 -312.049922) (xy 387.354839 -312.074529) (xy 387.35466 -312.07563)
			(xy 387.673338 -312.07563) (xy 387.673338 -312.024214) (xy 387.681381 -311.973432) (xy 387.697269 -311.924533)
			(xy 387.720612 -311.878721) (xy 387.750833 -311.837125) (xy 387.787189 -311.800769) (xy 387.828785 -311.770548)
			(xy 387.874597 -311.747205) (xy 387.923496 -311.731317) (xy 387.974278 -311.723274) (xy 388.025694 -311.723274)
			(xy 388.076476 -311.731317) (xy 388.125375 -311.747205) (xy 388.171187 -311.770548) (xy 388.212783 -311.800769)
			(xy 388.249139 -311.837125) (xy 388.27936 -311.878721) (xy 388.302703 -311.924533) (xy 388.318591 -311.973432)
			(xy 388.326634 -312.024214) (xy 388.327138 -312.049922) (xy 388.644142 -312.049922) (xy 388.648102 -312.000868)
			(xy 388.659879 -311.953084) (xy 388.67917 -311.907808) (xy 388.705473 -311.866212) (xy 388.738108 -311.829375)
			(xy 388.776229 -311.79825) (xy 388.81885 -311.773643) (xy 388.864866 -311.756191) (xy 388.913085 -311.746347)
			(xy 388.96226 -311.744366) (xy 389.011115 -311.750298) (xy 389.058386 -311.76399) (xy 389.102848 -311.785088)
			(xy 389.143351 -311.813044) (xy 389.178844 -311.847136) (xy 389.208409 -311.88648) (xy 389.23128 -311.930057)
			(xy 389.246864 -311.976738) (xy 389.254759 -312.025315) (xy 389.255254 -312.049922) (xy 389.254759 -312.074529)
			(xy 389.25458 -312.07563) (xy 389.573258 -312.07563) (xy 389.573258 -312.024214) (xy 389.581301 -311.973432)
			(xy 389.597189 -311.924533) (xy 389.620532 -311.878721) (xy 389.650753 -311.837125) (xy 389.687109 -311.800769)
			(xy 389.728705 -311.770548) (xy 389.774517 -311.747205) (xy 389.823416 -311.731317) (xy 389.874198 -311.723274)
			(xy 389.925614 -311.723274) (xy 389.976396 -311.731317) (xy 390.025295 -311.747205) (xy 390.071107 -311.770548)
			(xy 390.112703 -311.800769) (xy 390.149059 -311.837125) (xy 390.17928 -311.878721) (xy 390.202623 -311.924533)
			(xy 390.218511 -311.973432) (xy 390.226554 -312.024214) (xy 390.227058 -312.049922) (xy 390.544062 -312.049922)
			(xy 390.548022 -312.000868) (xy 390.559799 -311.953084) (xy 390.57909 -311.907808) (xy 390.605393 -311.866212)
			(xy 390.638028 -311.829375) (xy 390.676149 -311.79825) (xy 390.71877 -311.773643) (xy 390.764786 -311.756191)
			(xy 390.813005 -311.746347) (xy 390.86218 -311.744366) (xy 390.911035 -311.750298) (xy 390.958306 -311.76399)
			(xy 391.002768 -311.785088) (xy 391.043271 -311.813044) (xy 391.078764 -311.847136) (xy 391.108329 -311.88648)
			(xy 391.1312 -311.930057) (xy 391.146784 -311.976738) (xy 391.154679 -312.025315) (xy 391.155174 -312.049922)
			(xy 391.154679 -312.074529) (xy 391.1545 -312.07563) (xy 391.473178 -312.07563) (xy 391.473178 -312.024214)
			(xy 391.481221 -311.973432) (xy 391.497109 -311.924533) (xy 391.520452 -311.878721) (xy 391.550673 -311.837125)
			(xy 391.587029 -311.800769) (xy 391.628625 -311.770548) (xy 391.674437 -311.747205) (xy 391.723336 -311.731317)
			(xy 391.774118 -311.723274) (xy 391.825534 -311.723274) (xy 391.876316 -311.731317) (xy 391.925215 -311.747205)
			(xy 391.971027 -311.770548) (xy 392.012623 -311.800769) (xy 392.048979 -311.837125) (xy 392.0792 -311.878721)
			(xy 392.102543 -311.924533) (xy 392.118431 -311.973432) (xy 392.126474 -312.024214) (xy 392.126978 -312.049922)
			(xy 392.443982 -312.049922) (xy 392.447942 -312.000868) (xy 392.459719 -311.953084) (xy 392.47901 -311.907808)
			(xy 392.505313 -311.866212) (xy 392.537948 -311.829375) (xy 392.576069 -311.79825) (xy 392.61869 -311.773643)
			(xy 392.664706 -311.756191) (xy 392.712925 -311.746347) (xy 392.7621 -311.744366) (xy 392.810955 -311.750298)
			(xy 392.858226 -311.76399) (xy 392.902688 -311.785088) (xy 392.943191 -311.813044) (xy 392.978684 -311.847136)
			(xy 393.008249 -311.88648) (xy 393.03112 -311.930057) (xy 393.046704 -311.976738) (xy 393.054599 -312.025315)
			(xy 393.055094 -312.049922) (xy 393.054599 -312.074529) (xy 393.05442 -312.07563) (xy 393.373352 -312.07563)
			(xy 393.373352 -312.024214) (xy 393.381395 -311.973432) (xy 393.397283 -311.924533) (xy 393.420626 -311.878721)
			(xy 393.450847 -311.837125) (xy 393.487203 -311.800769) (xy 393.528799 -311.770548) (xy 393.574611 -311.747205)
			(xy 393.62351 -311.731317) (xy 393.674292 -311.723274) (xy 393.725708 -311.723274) (xy 393.77649 -311.731317)
			(xy 393.825389 -311.747205) (xy 393.871201 -311.770548) (xy 393.912797 -311.800769) (xy 393.949153 -311.837125)
			(xy 393.979374 -311.878721) (xy 394.002717 -311.924533) (xy 394.018605 -311.973432) (xy 394.026648 -312.024214)
			(xy 394.027152 -312.049922) (xy 394.344156 -312.049922) (xy 394.348116 -312.000868) (xy 394.359893 -311.953084)
			(xy 394.379184 -311.907808) (xy 394.405487 -311.866212) (xy 394.438122 -311.829375) (xy 394.476243 -311.79825)
			(xy 394.518864 -311.773643) (xy 394.56488 -311.756191) (xy 394.613099 -311.746347) (xy 394.662274 -311.744366)
			(xy 394.711129 -311.750298) (xy 394.7584 -311.76399) (xy 394.802862 -311.785088) (xy 394.843365 -311.813044)
			(xy 394.878858 -311.847136) (xy 394.908423 -311.88648) (xy 394.931294 -311.930057) (xy 394.946878 -311.976738)
			(xy 394.954773 -312.025315) (xy 394.955268 -312.049922) (xy 394.954773 -312.074529) (xy 394.954594 -312.07563)
			(xy 395.273272 -312.07563) (xy 395.273272 -312.024214) (xy 395.281315 -311.973432) (xy 395.297203 -311.924533)
			(xy 395.320546 -311.878721) (xy 395.350767 -311.837125) (xy 395.387123 -311.800769) (xy 395.428719 -311.770548)
			(xy 395.474531 -311.747205) (xy 395.52343 -311.731317) (xy 395.574212 -311.723274) (xy 395.625628 -311.723274)
			(xy 395.67641 -311.731317) (xy 395.725309 -311.747205) (xy 395.771121 -311.770548) (xy 395.812717 -311.800769)
			(xy 395.849073 -311.837125) (xy 395.879294 -311.878721) (xy 395.902637 -311.924533) (xy 395.918525 -311.973432)
			(xy 395.926568 -312.024214) (xy 395.927072 -312.049922) (xy 396.244076 -312.049922) (xy 396.248036 -312.000868)
			(xy 396.259813 -311.953084) (xy 396.279104 -311.907808) (xy 396.305407 -311.866212) (xy 396.338042 -311.829375)
			(xy 396.376163 -311.79825) (xy 396.418784 -311.773643) (xy 396.4648 -311.756191) (xy 396.513019 -311.746347)
			(xy 396.562194 -311.744366) (xy 396.611049 -311.750298) (xy 396.65832 -311.76399) (xy 396.702782 -311.785088)
			(xy 396.743285 -311.813044) (xy 396.778778 -311.847136) (xy 396.808343 -311.88648) (xy 396.831214 -311.930057)
			(xy 396.846798 -311.976738) (xy 396.854693 -312.025315) (xy 396.855188 -312.049922) (xy 396.854693 -312.074529)
			(xy 396.854514 -312.07563) (xy 397.173192 -312.07563) (xy 397.173192 -312.024214) (xy 397.181235 -311.973432)
			(xy 397.197123 -311.924533) (xy 397.220466 -311.878721) (xy 397.250687 -311.837125) (xy 397.287043 -311.800769)
			(xy 397.328639 -311.770548) (xy 397.374451 -311.747205) (xy 397.42335 -311.731317) (xy 397.474132 -311.723274)
			(xy 397.525548 -311.723274) (xy 397.57633 -311.731317) (xy 397.625229 -311.747205) (xy 397.671041 -311.770548)
			(xy 397.712637 -311.800769) (xy 397.748993 -311.837125) (xy 397.779214 -311.878721) (xy 397.802557 -311.924533)
			(xy 397.818445 -311.973432) (xy 397.826488 -312.024214) (xy 397.826992 -312.049922) (xy 398.143996 -312.049922)
			(xy 398.147956 -312.000868) (xy 398.159733 -311.953084) (xy 398.179024 -311.907808) (xy 398.205327 -311.866212)
			(xy 398.237962 -311.829375) (xy 398.276083 -311.79825) (xy 398.318704 -311.773643) (xy 398.36472 -311.756191)
			(xy 398.412939 -311.746347) (xy 398.462114 -311.744366) (xy 398.510969 -311.750298) (xy 398.55824 -311.76399)
			(xy 398.602702 -311.785088) (xy 398.643205 -311.813044) (xy 398.678698 -311.847136) (xy 398.708263 -311.88648)
			(xy 398.731134 -311.930057) (xy 398.746718 -311.976738) (xy 398.754613 -312.025315) (xy 398.755108 -312.049922)
			(xy 398.754613 -312.074529) (xy 398.754434 -312.07563) (xy 399.073366 -312.07563) (xy 399.073366 -312.024214)
			(xy 399.081409 -311.973432) (xy 399.097297 -311.924533) (xy 399.12064 -311.878721) (xy 399.150861 -311.837125)
			(xy 399.187217 -311.800769) (xy 399.228813 -311.770548) (xy 399.274625 -311.747205) (xy 399.323524 -311.731317)
			(xy 399.374306 -311.723274) (xy 399.425722 -311.723274) (xy 399.476504 -311.731317) (xy 399.525403 -311.747205)
			(xy 399.571215 -311.770548) (xy 399.612811 -311.800769) (xy 399.649167 -311.837125) (xy 399.679388 -311.878721)
			(xy 399.702731 -311.924533) (xy 399.718619 -311.973432) (xy 399.726662 -312.024214) (xy 399.727166 -312.049922)
			(xy 400.04417 -312.049922) (xy 400.04813 -312.000868) (xy 400.059907 -311.953084) (xy 400.079198 -311.907808)
			(xy 400.105501 -311.866212) (xy 400.138136 -311.829375) (xy 400.176257 -311.79825) (xy 400.218878 -311.773643)
			(xy 400.264894 -311.756191) (xy 400.313113 -311.746347) (xy 400.362288 -311.744366) (xy 400.411143 -311.750298)
			(xy 400.458414 -311.76399) (xy 400.502876 -311.785088) (xy 400.543379 -311.813044) (xy 400.578872 -311.847136)
			(xy 400.608437 -311.88648) (xy 400.631308 -311.930057) (xy 400.646892 -311.976738) (xy 400.654787 -312.025315)
			(xy 400.655282 -312.049922) (xy 400.654787 -312.074529) (xy 400.654608 -312.07563) (xy 400.973286 -312.07563)
			(xy 400.973286 -312.024214) (xy 400.981329 -311.973432) (xy 400.997217 -311.924533) (xy 401.02056 -311.878721)
			(xy 401.050781 -311.837125) (xy 401.087137 -311.800769) (xy 401.128733 -311.770548) (xy 401.174545 -311.747205)
			(xy 401.223444 -311.731317) (xy 401.274226 -311.723274) (xy 401.325642 -311.723274) (xy 401.376424 -311.731317)
			(xy 401.425323 -311.747205) (xy 401.471135 -311.770548) (xy 401.512731 -311.800769) (xy 401.549087 -311.837125)
			(xy 401.579308 -311.878721) (xy 401.602651 -311.924533) (xy 401.618539 -311.973432) (xy 401.626582 -312.024214)
			(xy 401.627086 -312.049922) (xy 401.94409 -312.049922) (xy 401.94805 -312.000868) (xy 401.959827 -311.953084)
			(xy 401.979118 -311.907808) (xy 402.005421 -311.866212) (xy 402.038056 -311.829375) (xy 402.076177 -311.79825)
			(xy 402.118798 -311.773643) (xy 402.164814 -311.756191) (xy 402.213033 -311.746347) (xy 402.262208 -311.744366)
			(xy 402.311063 -311.750298) (xy 402.358334 -311.76399) (xy 402.402796 -311.785088) (xy 402.443299 -311.813044)
			(xy 402.478792 -311.847136) (xy 402.508357 -311.88648) (xy 402.531228 -311.930057) (xy 402.546812 -311.976738)
			(xy 402.554707 -312.025315) (xy 402.555202 -312.049922) (xy 402.554707 -312.074529) (xy 402.554528 -312.07563)
			(xy 402.873206 -312.07563) (xy 402.873206 -312.024214) (xy 402.881249 -311.973432) (xy 402.897137 -311.924533)
			(xy 402.92048 -311.878721) (xy 402.950701 -311.837125) (xy 402.987057 -311.800769) (xy 403.028653 -311.770548)
			(xy 403.074465 -311.747205) (xy 403.123364 -311.731317) (xy 403.174146 -311.723274) (xy 403.225562 -311.723274)
			(xy 403.276344 -311.731317) (xy 403.325243 -311.747205) (xy 403.371055 -311.770548) (xy 403.412651 -311.800769)
			(xy 403.449007 -311.837125) (xy 403.479228 -311.878721) (xy 403.502571 -311.924533) (xy 403.518459 -311.973432)
			(xy 403.526502 -312.024214) (xy 403.527006 -312.049922) (xy 403.84401 -312.049922) (xy 403.84797 -312.000868)
			(xy 403.859747 -311.953084) (xy 403.879038 -311.907808) (xy 403.905341 -311.866212) (xy 403.937976 -311.829375)
			(xy 403.976097 -311.79825) (xy 404.018718 -311.773643) (xy 404.064734 -311.756191) (xy 404.112953 -311.746347)
			(xy 404.162128 -311.744366) (xy 404.210983 -311.750298) (xy 404.258254 -311.76399) (xy 404.302716 -311.785088)
			(xy 404.343219 -311.813044) (xy 404.378712 -311.847136) (xy 404.408277 -311.88648) (xy 404.431148 -311.930057)
			(xy 404.446732 -311.976738) (xy 404.454627 -312.025315) (xy 404.455122 -312.049922) (xy 404.454627 -312.074529)
			(xy 404.454448 -312.07563) (xy 404.77338 -312.07563) (xy 404.77338 -312.024214) (xy 404.781423 -311.973432)
			(xy 404.797311 -311.924533) (xy 404.820654 -311.878721) (xy 404.850875 -311.837125) (xy 404.887231 -311.800769)
			(xy 404.928827 -311.770548) (xy 404.974639 -311.747205) (xy 405.023538 -311.731317) (xy 405.07432 -311.723274)
			(xy 405.125736 -311.723274) (xy 405.176518 -311.731317) (xy 405.225417 -311.747205) (xy 405.271229 -311.770548)
			(xy 405.312825 -311.800769) (xy 405.349181 -311.837125) (xy 405.379402 -311.878721) (xy 405.402745 -311.924533)
			(xy 405.418633 -311.973432) (xy 405.426676 -312.024214) (xy 405.42718 -312.049922) (xy 405.744184 -312.049922)
			(xy 405.748144 -312.000868) (xy 405.759921 -311.953084) (xy 405.779212 -311.907808) (xy 405.805515 -311.866212)
			(xy 405.83815 -311.829375) (xy 405.876271 -311.79825) (xy 405.918892 -311.773643) (xy 405.964908 -311.756191)
			(xy 406.013127 -311.746347) (xy 406.062302 -311.744366) (xy 406.111157 -311.750298) (xy 406.158428 -311.76399)
			(xy 406.20289 -311.785088) (xy 406.243393 -311.813044) (xy 406.278886 -311.847136) (xy 406.308451 -311.88648)
			(xy 406.331322 -311.930057) (xy 406.346906 -311.976738) (xy 406.354801 -312.025315) (xy 406.355296 -312.049922)
			(xy 406.354801 -312.074529) (xy 406.354622 -312.07563) (xy 406.6733 -312.07563) (xy 406.6733 -312.024214)
			(xy 406.681343 -311.973432) (xy 406.697231 -311.924533) (xy 406.720574 -311.878721) (xy 406.750795 -311.837125)
			(xy 406.787151 -311.800769) (xy 406.828747 -311.770548) (xy 406.874559 -311.747205) (xy 406.923458 -311.731317)
			(xy 406.97424 -311.723274) (xy 407.025656 -311.723274) (xy 407.076438 -311.731317) (xy 407.125337 -311.747205)
			(xy 407.171149 -311.770548) (xy 407.212745 -311.800769) (xy 407.249101 -311.837125) (xy 407.279322 -311.878721)
			(xy 407.302665 -311.924533) (xy 407.318553 -311.973432) (xy 407.326596 -312.024214) (xy 407.3271 -312.049922)
			(xy 407.644104 -312.049922) (xy 407.648064 -312.000868) (xy 407.659841 -311.953084) (xy 407.679132 -311.907808)
			(xy 407.705435 -311.866212) (xy 407.73807 -311.829375) (xy 407.776191 -311.79825) (xy 407.818812 -311.773643)
			(xy 407.864828 -311.756191) (xy 407.913047 -311.746347) (xy 407.962222 -311.744366) (xy 408.011077 -311.750298)
			(xy 408.058348 -311.76399) (xy 408.10281 -311.785088) (xy 408.143313 -311.813044) (xy 408.178806 -311.847136)
			(xy 408.208371 -311.88648) (xy 408.231242 -311.930057) (xy 408.246826 -311.976738) (xy 408.254721 -312.025315)
			(xy 408.255216 -312.049922) (xy 408.254721 -312.074529) (xy 408.254542 -312.07563) (xy 408.57322 -312.07563)
			(xy 408.57322 -312.024214) (xy 408.581263 -311.973432) (xy 408.597151 -311.924533) (xy 408.620494 -311.878721)
			(xy 408.650715 -311.837125) (xy 408.687071 -311.800769) (xy 408.728667 -311.770548) (xy 408.774479 -311.747205)
			(xy 408.823378 -311.731317) (xy 408.87416 -311.723274) (xy 408.925576 -311.723274) (xy 408.976358 -311.731317)
			(xy 409.025257 -311.747205) (xy 409.071069 -311.770548) (xy 409.112665 -311.800769) (xy 409.149021 -311.837125)
			(xy 409.179242 -311.878721) (xy 409.202585 -311.924533) (xy 409.218473 -311.973432) (xy 409.226516 -312.024214)
			(xy 409.22702 -312.049922) (xy 409.544024 -312.049922) (xy 409.547984 -312.000868) (xy 409.559761 -311.953084)
			(xy 409.579052 -311.907808) (xy 409.605355 -311.866212) (xy 409.63799 -311.829375) (xy 409.676111 -311.79825)
			(xy 409.718732 -311.773643) (xy 409.764748 -311.756191) (xy 409.812967 -311.746347) (xy 409.862142 -311.744366)
			(xy 409.910997 -311.750298) (xy 409.958268 -311.76399) (xy 410.00273 -311.785088) (xy 410.043233 -311.813044)
			(xy 410.078726 -311.847136) (xy 410.108291 -311.88648) (xy 410.131162 -311.930057) (xy 410.146746 -311.976738)
			(xy 410.154641 -312.025315) (xy 410.155136 -312.049922) (xy 410.154641 -312.074529) (xy 410.154462 -312.07563)
			(xy 410.47314 -312.07563) (xy 410.47314 -312.024214) (xy 410.481183 -311.973432) (xy 410.497071 -311.924533)
			(xy 410.520414 -311.878721) (xy 410.550635 -311.837125) (xy 410.586991 -311.800769) (xy 410.628587 -311.770548)
			(xy 410.674399 -311.747205) (xy 410.723298 -311.731317) (xy 410.77408 -311.723274) (xy 410.825496 -311.723274)
			(xy 410.876278 -311.731317) (xy 410.925177 -311.747205) (xy 410.970989 -311.770548) (xy 411.012585 -311.800769)
			(xy 411.048941 -311.837125) (xy 411.079162 -311.878721) (xy 411.102505 -311.924533) (xy 411.118393 -311.973432)
			(xy 411.126436 -312.024214) (xy 411.12694 -312.049922) (xy 411.444198 -312.049922) (xy 411.448158 -312.000868)
			(xy 411.459935 -311.953084) (xy 411.479226 -311.907808) (xy 411.505529 -311.866212) (xy 411.538164 -311.829375)
			(xy 411.576285 -311.79825) (xy 411.618906 -311.773643) (xy 411.664922 -311.756191) (xy 411.713141 -311.746347)
			(xy 411.762316 -311.744366) (xy 411.811171 -311.750298) (xy 411.858442 -311.76399) (xy 411.902904 -311.785088)
			(xy 411.943407 -311.813044) (xy 411.9789 -311.847136) (xy 412.008465 -311.88648) (xy 412.031336 -311.930057)
			(xy 412.04692 -311.976738) (xy 412.054815 -312.025315) (xy 412.05531 -312.049922) (xy 412.054815 -312.074529)
			(xy 412.054636 -312.07563) (xy 412.373314 -312.07563) (xy 412.373314 -312.024214) (xy 412.381357 -311.973432)
			(xy 412.397245 -311.924533) (xy 412.420588 -311.878721) (xy 412.450809 -311.837125) (xy 412.487165 -311.800769)
			(xy 412.528761 -311.770548) (xy 412.574573 -311.747205) (xy 412.623472 -311.731317) (xy 412.674254 -311.723274)
			(xy 412.72567 -311.723274) (xy 412.776452 -311.731317) (xy 412.825351 -311.747205) (xy 412.871163 -311.770548)
			(xy 412.912759 -311.800769) (xy 412.949115 -311.837125) (xy 412.979336 -311.878721) (xy 413.002679 -311.924533)
			(xy 413.018567 -311.973432) (xy 413.02661 -312.024214) (xy 413.027114 -312.049922) (xy 413.344118 -312.049922)
			(xy 413.348078 -312.000868) (xy 413.359855 -311.953084) (xy 413.379146 -311.907808) (xy 413.405449 -311.866212)
			(xy 413.438084 -311.829375) (xy 413.476205 -311.79825) (xy 413.518826 -311.773643) (xy 413.564842 -311.756191)
			(xy 413.613061 -311.746347) (xy 413.662236 -311.744366) (xy 413.711091 -311.750298) (xy 413.758362 -311.76399)
			(xy 413.802824 -311.785088) (xy 413.843327 -311.813044) (xy 413.87882 -311.847136) (xy 413.908385 -311.88648)
			(xy 413.931256 -311.930057) (xy 413.94684 -311.976738) (xy 413.954735 -312.025315) (xy 413.95523 -312.049922)
			(xy 413.954735 -312.074529) (xy 413.954556 -312.07563) (xy 414.273234 -312.07563) (xy 414.273234 -312.024214)
			(xy 414.281277 -311.973432) (xy 414.297165 -311.924533) (xy 414.320508 -311.878721) (xy 414.350729 -311.837125)
			(xy 414.387085 -311.800769) (xy 414.428681 -311.770548) (xy 414.474493 -311.747205) (xy 414.523392 -311.731317)
			(xy 414.574174 -311.723274) (xy 414.62559 -311.723274) (xy 414.676372 -311.731317) (xy 414.725271 -311.747205)
			(xy 414.771083 -311.770548) (xy 414.812679 -311.800769) (xy 414.849035 -311.837125) (xy 414.879256 -311.878721)
			(xy 414.902599 -311.924533) (xy 414.918487 -311.973432) (xy 414.92653 -312.024214) (xy 414.927034 -312.049922)
			(xy 415.244038 -312.049922) (xy 415.247998 -312.000868) (xy 415.259775 -311.953084) (xy 415.279066 -311.907808)
			(xy 415.305369 -311.866212) (xy 415.338004 -311.829375) (xy 415.376125 -311.79825) (xy 415.418746 -311.773643)
			(xy 415.464762 -311.756191) (xy 415.512981 -311.746347) (xy 415.562156 -311.744366) (xy 415.611011 -311.750298)
			(xy 415.658282 -311.76399) (xy 415.702744 -311.785088) (xy 415.743247 -311.813044) (xy 415.77874 -311.847136)
			(xy 415.808305 -311.88648) (xy 415.831176 -311.930057) (xy 415.84676 -311.976738) (xy 415.854655 -312.025315)
			(xy 415.85515 -312.049922) (xy 415.854655 -312.074529) (xy 415.854476 -312.07563) (xy 416.173154 -312.07563)
			(xy 416.173154 -312.024214) (xy 416.181197 -311.973432) (xy 416.197085 -311.924533) (xy 416.220428 -311.878721)
			(xy 416.250649 -311.837125) (xy 416.287005 -311.800769) (xy 416.328601 -311.770548) (xy 416.374413 -311.747205)
			(xy 416.423312 -311.731317) (xy 416.474094 -311.723274) (xy 416.52551 -311.723274) (xy 416.576292 -311.731317)
			(xy 416.625191 -311.747205) (xy 416.671003 -311.770548) (xy 416.712599 -311.800769) (xy 416.748955 -311.837125)
			(xy 416.779176 -311.878721) (xy 416.802519 -311.924533) (xy 416.818407 -311.973432) (xy 416.82645 -312.024214)
			(xy 416.826954 -312.049922) (xy 416.82645 -312.07563) (xy 416.818407 -312.126412) (xy 416.802519 -312.175311)
			(xy 416.779176 -312.221123) (xy 416.748955 -312.262719) (xy 416.712599 -312.299075) (xy 416.671003 -312.329296)
			(xy 416.625191 -312.352639) (xy 416.576292 -312.368527) (xy 416.52551 -312.37657) (xy 416.474094 -312.37657)
			(xy 416.423312 -312.368527) (xy 416.374413 -312.352639) (xy 416.328601 -312.329296) (xy 416.287005 -312.299075)
			(xy 416.250649 -312.262719) (xy 416.220428 -312.221123) (xy 416.197085 -312.175311) (xy 416.181197 -312.126412)
			(xy 416.173154 -312.07563) (xy 415.854476 -312.07563) (xy 415.84676 -312.123106) (xy 415.831176 -312.169787)
			(xy 415.808305 -312.213364) (xy 415.77874 -312.252708) (xy 415.743247 -312.2868) (xy 415.702744 -312.314756)
			(xy 415.658282 -312.335854) (xy 415.611011 -312.349546) (xy 415.562156 -312.355478) (xy 415.512981 -312.353497)
			(xy 415.464762 -312.343653) (xy 415.418746 -312.326201) (xy 415.376125 -312.301594) (xy 415.338004 -312.270469)
			(xy 415.305369 -312.233632) (xy 415.279066 -312.192036) (xy 415.259775 -312.14676) (xy 415.247998 -312.098976)
			(xy 415.244038 -312.049922) (xy 414.927034 -312.049922) (xy 414.92653 -312.07563) (xy 414.918487 -312.126412)
			(xy 414.902599 -312.175311) (xy 414.879256 -312.221123) (xy 414.849035 -312.262719) (xy 414.812679 -312.299075)
			(xy 414.771083 -312.329296) (xy 414.725271 -312.352639) (xy 414.676372 -312.368527) (xy 414.62559 -312.37657)
			(xy 414.574174 -312.37657) (xy 414.523392 -312.368527) (xy 414.474493 -312.352639) (xy 414.428681 -312.329296)
			(xy 414.387085 -312.299075) (xy 414.350729 -312.262719) (xy 414.320508 -312.221123) (xy 414.297165 -312.175311)
			(xy 414.281277 -312.126412) (xy 414.273234 -312.07563) (xy 413.954556 -312.07563) (xy 413.94684 -312.123106)
			(xy 413.931256 -312.169787) (xy 413.908385 -312.213364) (xy 413.87882 -312.252708) (xy 413.843327 -312.2868)
			(xy 413.802824 -312.314756) (xy 413.758362 -312.335854) (xy 413.711091 -312.349546) (xy 413.662236 -312.355478)
			(xy 413.613061 -312.353497) (xy 413.564842 -312.343653) (xy 413.518826 -312.326201) (xy 413.476205 -312.301594)
			(xy 413.438084 -312.270469) (xy 413.405449 -312.233632) (xy 413.379146 -312.192036) (xy 413.359855 -312.14676)
			(xy 413.348078 -312.098976) (xy 413.344118 -312.049922) (xy 413.027114 -312.049922) (xy 413.02661 -312.07563)
			(xy 413.018567 -312.126412) (xy 413.002679 -312.175311) (xy 412.979336 -312.221123) (xy 412.949115 -312.262719)
			(xy 412.912759 -312.299075) (xy 412.871163 -312.329296) (xy 412.825351 -312.352639) (xy 412.776452 -312.368527)
			(xy 412.72567 -312.37657) (xy 412.674254 -312.37657) (xy 412.623472 -312.368527) (xy 412.574573 -312.352639)
			(xy 412.528761 -312.329296) (xy 412.487165 -312.299075) (xy 412.450809 -312.262719) (xy 412.420588 -312.221123)
			(xy 412.397245 -312.175311) (xy 412.381357 -312.126412) (xy 412.373314 -312.07563) (xy 412.054636 -312.07563)
			(xy 412.04692 -312.123106) (xy 412.031336 -312.169787) (xy 412.008465 -312.213364) (xy 411.9789 -312.252708)
			(xy 411.943407 -312.2868) (xy 411.902904 -312.314756) (xy 411.858442 -312.335854) (xy 411.811171 -312.349546)
			(xy 411.762316 -312.355478) (xy 411.713141 -312.353497) (xy 411.664922 -312.343653) (xy 411.618906 -312.326201)
			(xy 411.576285 -312.301594) (xy 411.538164 -312.270469) (xy 411.505529 -312.233632) (xy 411.479226 -312.192036)
			(xy 411.459935 -312.14676) (xy 411.448158 -312.098976) (xy 411.444198 -312.049922) (xy 411.12694 -312.049922)
			(xy 411.126436 -312.07563) (xy 411.118393 -312.126412) (xy 411.102505 -312.175311) (xy 411.079162 -312.221123)
			(xy 411.048941 -312.262719) (xy 411.012585 -312.299075) (xy 410.970989 -312.329296) (xy 410.925177 -312.352639)
			(xy 410.876278 -312.368527) (xy 410.825496 -312.37657) (xy 410.77408 -312.37657) (xy 410.723298 -312.368527)
			(xy 410.674399 -312.352639) (xy 410.628587 -312.329296) (xy 410.586991 -312.299075) (xy 410.550635 -312.262719)
			(xy 410.520414 -312.221123) (xy 410.497071 -312.175311) (xy 410.481183 -312.126412) (xy 410.47314 -312.07563)
			(xy 410.154462 -312.07563) (xy 410.146746 -312.123106) (xy 410.131162 -312.169787) (xy 410.108291 -312.213364)
			(xy 410.078726 -312.252708) (xy 410.043233 -312.2868) (xy 410.00273 -312.314756) (xy 409.958268 -312.335854)
			(xy 409.910997 -312.349546) (xy 409.862142 -312.355478) (xy 409.812967 -312.353497) (xy 409.764748 -312.343653)
			(xy 409.718732 -312.326201) (xy 409.676111 -312.301594) (xy 409.63799 -312.270469) (xy 409.605355 -312.233632)
			(xy 409.579052 -312.192036) (xy 409.559761 -312.14676) (xy 409.547984 -312.098976) (xy 409.544024 -312.049922)
			(xy 409.22702 -312.049922) (xy 409.226516 -312.07563) (xy 409.218473 -312.126412) (xy 409.202585 -312.175311)
			(xy 409.179242 -312.221123) (xy 409.149021 -312.262719) (xy 409.112665 -312.299075) (xy 409.071069 -312.329296)
			(xy 409.025257 -312.352639) (xy 408.976358 -312.368527) (xy 408.925576 -312.37657) (xy 408.87416 -312.37657)
			(xy 408.823378 -312.368527) (xy 408.774479 -312.352639) (xy 408.728667 -312.329296) (xy 408.687071 -312.299075)
			(xy 408.650715 -312.262719) (xy 408.620494 -312.221123) (xy 408.597151 -312.175311) (xy 408.581263 -312.126412)
			(xy 408.57322 -312.07563) (xy 408.254542 -312.07563) (xy 408.246826 -312.123106) (xy 408.231242 -312.169787)
			(xy 408.208371 -312.213364) (xy 408.178806 -312.252708) (xy 408.143313 -312.2868) (xy 408.10281 -312.314756)
			(xy 408.058348 -312.335854) (xy 408.011077 -312.349546) (xy 407.962222 -312.355478) (xy 407.913047 -312.353497)
			(xy 407.864828 -312.343653) (xy 407.818812 -312.326201) (xy 407.776191 -312.301594) (xy 407.73807 -312.270469)
			(xy 407.705435 -312.233632) (xy 407.679132 -312.192036) (xy 407.659841 -312.14676) (xy 407.648064 -312.098976)
			(xy 407.644104 -312.049922) (xy 407.3271 -312.049922) (xy 407.326596 -312.07563) (xy 407.318553 -312.126412)
			(xy 407.302665 -312.175311) (xy 407.279322 -312.221123) (xy 407.249101 -312.262719) (xy 407.212745 -312.299075)
			(xy 407.171149 -312.329296) (xy 407.125337 -312.352639) (xy 407.076438 -312.368527) (xy 407.025656 -312.37657)
			(xy 406.97424 -312.37657) (xy 406.923458 -312.368527) (xy 406.874559 -312.352639) (xy 406.828747 -312.329296)
			(xy 406.787151 -312.299075) (xy 406.750795 -312.262719) (xy 406.720574 -312.221123) (xy 406.697231 -312.175311)
			(xy 406.681343 -312.126412) (xy 406.6733 -312.07563) (xy 406.354622 -312.07563) (xy 406.346906 -312.123106)
			(xy 406.331322 -312.169787) (xy 406.308451 -312.213364) (xy 406.278886 -312.252708) (xy 406.243393 -312.2868)
			(xy 406.20289 -312.314756) (xy 406.158428 -312.335854) (xy 406.111157 -312.349546) (xy 406.062302 -312.355478)
			(xy 406.013127 -312.353497) (xy 405.964908 -312.343653) (xy 405.918892 -312.326201) (xy 405.876271 -312.301594)
			(xy 405.83815 -312.270469) (xy 405.805515 -312.233632) (xy 405.779212 -312.192036) (xy 405.759921 -312.14676)
			(xy 405.748144 -312.098976) (xy 405.744184 -312.049922) (xy 405.42718 -312.049922) (xy 405.426676 -312.07563)
			(xy 405.418633 -312.126412) (xy 405.402745 -312.175311) (xy 405.379402 -312.221123) (xy 405.349181 -312.262719)
			(xy 405.312825 -312.299075) (xy 405.271229 -312.329296) (xy 405.225417 -312.352639) (xy 405.176518 -312.368527)
			(xy 405.125736 -312.37657) (xy 405.07432 -312.37657) (xy 405.023538 -312.368527) (xy 404.974639 -312.352639)
			(xy 404.928827 -312.329296) (xy 404.887231 -312.299075) (xy 404.850875 -312.262719) (xy 404.820654 -312.221123)
			(xy 404.797311 -312.175311) (xy 404.781423 -312.126412) (xy 404.77338 -312.07563) (xy 404.454448 -312.07563)
			(xy 404.446732 -312.123106) (xy 404.431148 -312.169787) (xy 404.408277 -312.213364) (xy 404.378712 -312.252708)
			(xy 404.343219 -312.2868) (xy 404.302716 -312.314756) (xy 404.258254 -312.335854) (xy 404.210983 -312.349546)
			(xy 404.162128 -312.355478) (xy 404.112953 -312.353497) (xy 404.064734 -312.343653) (xy 404.018718 -312.326201)
			(xy 403.976097 -312.301594) (xy 403.937976 -312.270469) (xy 403.905341 -312.233632) (xy 403.879038 -312.192036)
			(xy 403.859747 -312.14676) (xy 403.84797 -312.098976) (xy 403.84401 -312.049922) (xy 403.527006 -312.049922)
			(xy 403.526502 -312.07563) (xy 403.518459 -312.126412) (xy 403.502571 -312.175311) (xy 403.479228 -312.221123)
			(xy 403.449007 -312.262719) (xy 403.412651 -312.299075) (xy 403.371055 -312.329296) (xy 403.325243 -312.352639)
			(xy 403.276344 -312.368527) (xy 403.225562 -312.37657) (xy 403.174146 -312.37657) (xy 403.123364 -312.368527)
			(xy 403.074465 -312.352639) (xy 403.028653 -312.329296) (xy 402.987057 -312.299075) (xy 402.950701 -312.262719)
			(xy 402.92048 -312.221123) (xy 402.897137 -312.175311) (xy 402.881249 -312.126412) (xy 402.873206 -312.07563)
			(xy 402.554528 -312.07563) (xy 402.546812 -312.123106) (xy 402.531228 -312.169787) (xy 402.508357 -312.213364)
			(xy 402.478792 -312.252708) (xy 402.443299 -312.2868) (xy 402.402796 -312.314756) (xy 402.358334 -312.335854)
			(xy 402.311063 -312.349546) (xy 402.262208 -312.355478) (xy 402.213033 -312.353497) (xy 402.164814 -312.343653)
			(xy 402.118798 -312.326201) (xy 402.076177 -312.301594) (xy 402.038056 -312.270469) (xy 402.005421 -312.233632)
			(xy 401.979118 -312.192036) (xy 401.959827 -312.14676) (xy 401.94805 -312.098976) (xy 401.94409 -312.049922)
			(xy 401.627086 -312.049922) (xy 401.626582 -312.07563) (xy 401.618539 -312.126412) (xy 401.602651 -312.175311)
			(xy 401.579308 -312.221123) (xy 401.549087 -312.262719) (xy 401.512731 -312.299075) (xy 401.471135 -312.329296)
			(xy 401.425323 -312.352639) (xy 401.376424 -312.368527) (xy 401.325642 -312.37657) (xy 401.274226 -312.37657)
			(xy 401.223444 -312.368527) (xy 401.174545 -312.352639) (xy 401.128733 -312.329296) (xy 401.087137 -312.299075)
			(xy 401.050781 -312.262719) (xy 401.02056 -312.221123) (xy 400.997217 -312.175311) (xy 400.981329 -312.126412)
			(xy 400.973286 -312.07563) (xy 400.654608 -312.07563) (xy 400.646892 -312.123106) (xy 400.631308 -312.169787)
			(xy 400.608437 -312.213364) (xy 400.578872 -312.252708) (xy 400.543379 -312.2868) (xy 400.502876 -312.314756)
			(xy 400.458414 -312.335854) (xy 400.411143 -312.349546) (xy 400.362288 -312.355478) (xy 400.313113 -312.353497)
			(xy 400.264894 -312.343653) (xy 400.218878 -312.326201) (xy 400.176257 -312.301594) (xy 400.138136 -312.270469)
			(xy 400.105501 -312.233632) (xy 400.079198 -312.192036) (xy 400.059907 -312.14676) (xy 400.04813 -312.098976)
			(xy 400.04417 -312.049922) (xy 399.727166 -312.049922) (xy 399.726662 -312.07563) (xy 399.718619 -312.126412)
			(xy 399.702731 -312.175311) (xy 399.679388 -312.221123) (xy 399.649167 -312.262719) (xy 399.612811 -312.299075)
			(xy 399.571215 -312.329296) (xy 399.525403 -312.352639) (xy 399.476504 -312.368527) (xy 399.425722 -312.37657)
			(xy 399.374306 -312.37657) (xy 399.323524 -312.368527) (xy 399.274625 -312.352639) (xy 399.228813 -312.329296)
			(xy 399.187217 -312.299075) (xy 399.150861 -312.262719) (xy 399.12064 -312.221123) (xy 399.097297 -312.175311)
			(xy 399.081409 -312.126412) (xy 399.073366 -312.07563) (xy 398.754434 -312.07563) (xy 398.746718 -312.123106)
			(xy 398.731134 -312.169787) (xy 398.708263 -312.213364) (xy 398.678698 -312.252708) (xy 398.643205 -312.2868)
			(xy 398.602702 -312.314756) (xy 398.55824 -312.335854) (xy 398.510969 -312.349546) (xy 398.462114 -312.355478)
			(xy 398.412939 -312.353497) (xy 398.36472 -312.343653) (xy 398.318704 -312.326201) (xy 398.276083 -312.301594)
			(xy 398.237962 -312.270469) (xy 398.205327 -312.233632) (xy 398.179024 -312.192036) (xy 398.159733 -312.14676)
			(xy 398.147956 -312.098976) (xy 398.143996 -312.049922) (xy 397.826992 -312.049922) (xy 397.826488 -312.07563)
			(xy 397.818445 -312.126412) (xy 397.802557 -312.175311) (xy 397.779214 -312.221123) (xy 397.748993 -312.262719)
			(xy 397.712637 -312.299075) (xy 397.671041 -312.329296) (xy 397.625229 -312.352639) (xy 397.57633 -312.368527)
			(xy 397.525548 -312.37657) (xy 397.474132 -312.37657) (xy 397.42335 -312.368527) (xy 397.374451 -312.352639)
			(xy 397.328639 -312.329296) (xy 397.287043 -312.299075) (xy 397.250687 -312.262719) (xy 397.220466 -312.221123)
			(xy 397.197123 -312.175311) (xy 397.181235 -312.126412) (xy 397.173192 -312.07563) (xy 396.854514 -312.07563)
			(xy 396.846798 -312.123106) (xy 396.831214 -312.169787) (xy 396.808343 -312.213364) (xy 396.778778 -312.252708)
			(xy 396.743285 -312.2868) (xy 396.702782 -312.314756) (xy 396.65832 -312.335854) (xy 396.611049 -312.349546)
			(xy 396.562194 -312.355478) (xy 396.513019 -312.353497) (xy 396.4648 -312.343653) (xy 396.418784 -312.326201)
			(xy 396.376163 -312.301594) (xy 396.338042 -312.270469) (xy 396.305407 -312.233632) (xy 396.279104 -312.192036)
			(xy 396.259813 -312.14676) (xy 396.248036 -312.098976) (xy 396.244076 -312.049922) (xy 395.927072 -312.049922)
			(xy 395.926568 -312.07563) (xy 395.918525 -312.126412) (xy 395.902637 -312.175311) (xy 395.879294 -312.221123)
			(xy 395.849073 -312.262719) (xy 395.812717 -312.299075) (xy 395.771121 -312.329296) (xy 395.725309 -312.352639)
			(xy 395.67641 -312.368527) (xy 395.625628 -312.37657) (xy 395.574212 -312.37657) (xy 395.52343 -312.368527)
			(xy 395.474531 -312.352639) (xy 395.428719 -312.329296) (xy 395.387123 -312.299075) (xy 395.350767 -312.262719)
			(xy 395.320546 -312.221123) (xy 395.297203 -312.175311) (xy 395.281315 -312.126412) (xy 395.273272 -312.07563)
			(xy 394.954594 -312.07563) (xy 394.946878 -312.123106) (xy 394.931294 -312.169787) (xy 394.908423 -312.213364)
			(xy 394.878858 -312.252708) (xy 394.843365 -312.2868) (xy 394.802862 -312.314756) (xy 394.7584 -312.335854)
			(xy 394.711129 -312.349546) (xy 394.662274 -312.355478) (xy 394.613099 -312.353497) (xy 394.56488 -312.343653)
			(xy 394.518864 -312.326201) (xy 394.476243 -312.301594) (xy 394.438122 -312.270469) (xy 394.405487 -312.233632)
			(xy 394.379184 -312.192036) (xy 394.359893 -312.14676) (xy 394.348116 -312.098976) (xy 394.344156 -312.049922)
			(xy 394.027152 -312.049922) (xy 394.026648 -312.07563) (xy 394.018605 -312.126412) (xy 394.002717 -312.175311)
			(xy 393.979374 -312.221123) (xy 393.949153 -312.262719) (xy 393.912797 -312.299075) (xy 393.871201 -312.329296)
			(xy 393.825389 -312.352639) (xy 393.77649 -312.368527) (xy 393.725708 -312.37657) (xy 393.674292 -312.37657)
			(xy 393.62351 -312.368527) (xy 393.574611 -312.352639) (xy 393.528799 -312.329296) (xy 393.487203 -312.299075)
			(xy 393.450847 -312.262719) (xy 393.420626 -312.221123) (xy 393.397283 -312.175311) (xy 393.381395 -312.126412)
			(xy 393.373352 -312.07563) (xy 393.05442 -312.07563) (xy 393.046704 -312.123106) (xy 393.03112 -312.169787)
			(xy 393.008249 -312.213364) (xy 392.978684 -312.252708) (xy 392.943191 -312.2868) (xy 392.902688 -312.314756)
			(xy 392.858226 -312.335854) (xy 392.810955 -312.349546) (xy 392.7621 -312.355478) (xy 392.712925 -312.353497)
			(xy 392.664706 -312.343653) (xy 392.61869 -312.326201) (xy 392.576069 -312.301594) (xy 392.537948 -312.270469)
			(xy 392.505313 -312.233632) (xy 392.47901 -312.192036) (xy 392.459719 -312.14676) (xy 392.447942 -312.098976)
			(xy 392.443982 -312.049922) (xy 392.126978 -312.049922) (xy 392.126474 -312.07563) (xy 392.118431 -312.126412)
			(xy 392.102543 -312.175311) (xy 392.0792 -312.221123) (xy 392.048979 -312.262719) (xy 392.012623 -312.299075)
			(xy 391.971027 -312.329296) (xy 391.925215 -312.352639) (xy 391.876316 -312.368527) (xy 391.825534 -312.37657)
			(xy 391.774118 -312.37657) (xy 391.723336 -312.368527) (xy 391.674437 -312.352639) (xy 391.628625 -312.329296)
			(xy 391.587029 -312.299075) (xy 391.550673 -312.262719) (xy 391.520452 -312.221123) (xy 391.497109 -312.175311)
			(xy 391.481221 -312.126412) (xy 391.473178 -312.07563) (xy 391.1545 -312.07563) (xy 391.146784 -312.123106)
			(xy 391.1312 -312.169787) (xy 391.108329 -312.213364) (xy 391.078764 -312.252708) (xy 391.043271 -312.2868)
			(xy 391.002768 -312.314756) (xy 390.958306 -312.335854) (xy 390.911035 -312.349546) (xy 390.86218 -312.355478)
			(xy 390.813005 -312.353497) (xy 390.764786 -312.343653) (xy 390.71877 -312.326201) (xy 390.676149 -312.301594)
			(xy 390.638028 -312.270469) (xy 390.605393 -312.233632) (xy 390.57909 -312.192036) (xy 390.559799 -312.14676)
			(xy 390.548022 -312.098976) (xy 390.544062 -312.049922) (xy 390.227058 -312.049922) (xy 390.226554 -312.07563)
			(xy 390.218511 -312.126412) (xy 390.202623 -312.175311) (xy 390.17928 -312.221123) (xy 390.149059 -312.262719)
			(xy 390.112703 -312.299075) (xy 390.071107 -312.329296) (xy 390.025295 -312.352639) (xy 389.976396 -312.368527)
			(xy 389.925614 -312.37657) (xy 389.874198 -312.37657) (xy 389.823416 -312.368527) (xy 389.774517 -312.352639)
			(xy 389.728705 -312.329296) (xy 389.687109 -312.299075) (xy 389.650753 -312.262719) (xy 389.620532 -312.221123)
			(xy 389.597189 -312.175311) (xy 389.581301 -312.126412) (xy 389.573258 -312.07563) (xy 389.25458 -312.07563)
			(xy 389.246864 -312.123106) (xy 389.23128 -312.169787) (xy 389.208409 -312.213364) (xy 389.178844 -312.252708)
			(xy 389.143351 -312.2868) (xy 389.102848 -312.314756) (xy 389.058386 -312.335854) (xy 389.011115 -312.349546)
			(xy 388.96226 -312.355478) (xy 388.913085 -312.353497) (xy 388.864866 -312.343653) (xy 388.81885 -312.326201)
			(xy 388.776229 -312.301594) (xy 388.738108 -312.270469) (xy 388.705473 -312.233632) (xy 388.67917 -312.192036)
			(xy 388.659879 -312.14676) (xy 388.648102 -312.098976) (xy 388.644142 -312.049922) (xy 388.327138 -312.049922)
			(xy 388.326634 -312.07563) (xy 388.318591 -312.126412) (xy 388.302703 -312.175311) (xy 388.27936 -312.221123)
			(xy 388.249139 -312.262719) (xy 388.212783 -312.299075) (xy 388.171187 -312.329296) (xy 388.125375 -312.352639)
			(xy 388.076476 -312.368527) (xy 388.025694 -312.37657) (xy 387.974278 -312.37657) (xy 387.923496 -312.368527)
			(xy 387.874597 -312.352639) (xy 387.828785 -312.329296) (xy 387.787189 -312.299075) (xy 387.750833 -312.262719)
			(xy 387.720612 -312.221123) (xy 387.697269 -312.175311) (xy 387.681381 -312.126412) (xy 387.673338 -312.07563)
			(xy 387.35466 -312.07563) (xy 387.346944 -312.123106) (xy 387.33136 -312.169787) (xy 387.308489 -312.213364)
			(xy 387.278924 -312.252708) (xy 387.243431 -312.2868) (xy 387.202928 -312.314756) (xy 387.158466 -312.335854)
			(xy 387.111195 -312.349546) (xy 387.06234 -312.355478) (xy 387.013165 -312.353497) (xy 386.964946 -312.343653)
			(xy 386.91893 -312.326201) (xy 386.876309 -312.301594) (xy 386.838188 -312.270469) (xy 386.805553 -312.233632)
			(xy 386.77925 -312.192036) (xy 386.759959 -312.14676) (xy 386.748182 -312.098976) (xy 386.744222 -312.049922)
			(xy 386.426964 -312.049922) (xy 386.42646 -312.07563) (xy 386.418417 -312.126412) (xy 386.402529 -312.175311)
			(xy 386.379186 -312.221123) (xy 386.348965 -312.262719) (xy 386.312609 -312.299075) (xy 386.271013 -312.329296)
			(xy 386.225201 -312.352639) (xy 386.176302 -312.368527) (xy 386.12552 -312.37657) (xy 386.074104 -312.37657)
			(xy 386.023322 -312.368527) (xy 385.974423 -312.352639) (xy 385.928611 -312.329296) (xy 385.887015 -312.299075)
			(xy 385.850659 -312.262719) (xy 385.820438 -312.221123) (xy 385.797095 -312.175311) (xy 385.781207 -312.126412)
			(xy 385.773164 -312.07563) (xy 385.4765 -312.07563) (xy 385.468457 -312.126412) (xy 385.452569 -312.175311)
			(xy 385.429226 -312.221123) (xy 385.399005 -312.262719) (xy 385.362649 -312.299075) (xy 385.321053 -312.329296)
			(xy 385.275241 -312.352639) (xy 385.226342 -312.368527) (xy 385.17556 -312.37657) (xy 385.124144 -312.37657)
			(xy 385.073362 -312.368527) (xy 385.024463 -312.352639) (xy 384.978651 -312.329296) (xy 384.937055 -312.299075)
			(xy 384.900699 -312.262719) (xy 384.870478 -312.221123) (xy 384.847135 -312.175311) (xy 384.831247 -312.126412)
			(xy 384.823204 -312.07563) (xy 384.504231 -312.07563) (xy 384.496556 -312.122852) (xy 384.480972 -312.169533)
			(xy 384.458101 -312.21311) (xy 384.428536 -312.252454) (xy 384.393043 -312.286546) (xy 384.35254 -312.314502)
			(xy 384.308078 -312.3356) (xy 384.260807 -312.349292) (xy 384.211952 -312.355224) (xy 384.162777 -312.353243)
			(xy 384.114558 -312.343399) (xy 384.068542 -312.325947) (xy 384.025921 -312.30134) (xy 383.9878 -312.270215)
			(xy 383.955165 -312.233378) (xy 383.928862 -312.191782) (xy 383.909571 -312.146506) (xy 383.897794 -312.098722)
			(xy 383.893834 -312.049668) (xy 383.105048 -312.049668) (xy 383.125871 -312.081142) (xy 383.149543 -312.131639)
			(xy 383.165611 -312.185046) (xy 383.173731 -312.240222) (xy 383.17424 -312.268108) (xy 383.173731 -312.295994)
			(xy 383.165611 -312.35117) (xy 383.149543 -312.404577) (xy 383.125871 -312.455074) (xy 383.095098 -312.501587)
			(xy 383.057881 -312.543124) (xy 383.015013 -312.578799) (xy 382.967407 -312.607853) (xy 382.916078 -312.629665)
			(xy 382.862121 -312.643771) (xy 382.806684 -312.649871) (xy 382.75095 -312.647834) (xy 382.696107 -312.637704)
			(xy 382.643323 -312.619697) (xy 382.593723 -312.594196) (xy 382.548365 -312.561745) (xy 382.508216 -312.523036)
			(xy 382.47413 -312.478893) (xy 382.446834 -312.430258) (xy 382.426911 -312.378167) (xy 382.414785 -312.32373)
			(xy 382.410714 -312.268108) (xy 380.696863 -312.268108) (xy 380.716388 -312.289899) (xy 380.747161 -312.336412)
			(xy 380.770833 -312.386909) (xy 380.786901 -312.440316) (xy 380.795021 -312.495492) (xy 380.79553 -312.523378)
			(xy 380.795021 -312.551264) (xy 380.786901 -312.60644) (xy 380.770833 -312.659847) (xy 380.747161 -312.710344)
			(xy 380.716388 -312.756857) (xy 380.679171 -312.798394) (xy 380.636303 -312.834069) (xy 380.588697 -312.863123)
			(xy 380.537368 -312.884935) (xy 380.483411 -312.899041) (xy 380.427974 -312.905141) (xy 380.37224 -312.903104)
			(xy 380.317397 -312.892974) (xy 380.264613 -312.874967) (xy 380.215013 -312.849466) (xy 380.169655 -312.817015)
			(xy 380.129506 -312.778306) (xy 380.09542 -312.734163) (xy 380.068124 -312.685528) (xy 380.048201 -312.633437)
			(xy 380.036075 -312.579) (xy 380.032004 -312.523378) (xy 351.03308 -312.523378) (xy 351.03308 -312.999882)
			(xy 384.844048 -312.999882) (xy 384.848008 -312.950828) (xy 384.859785 -312.903044) (xy 384.879076 -312.857768)
			(xy 384.905379 -312.816172) (xy 384.938014 -312.779335) (xy 384.976135 -312.74821) (xy 385.018756 -312.723603)
			(xy 385.064772 -312.706151) (xy 385.112991 -312.696307) (xy 385.162166 -312.694326) (xy 385.211021 -312.700258)
			(xy 385.258292 -312.71395) (xy 385.302754 -312.735048) (xy 385.343257 -312.763004) (xy 385.37875 -312.797096)
			(xy 385.408315 -312.83644) (xy 385.431186 -312.880017) (xy 385.44677 -312.926698) (xy 385.454665 -312.975275)
			(xy 385.45516 -312.999882) (xy 385.794008 -312.999882) (xy 385.797968 -312.950828) (xy 385.809745 -312.903044)
			(xy 385.829036 -312.857768) (xy 385.855339 -312.816172) (xy 385.887974 -312.779335) (xy 385.926095 -312.74821)
			(xy 385.968716 -312.723603) (xy 386.014732 -312.706151) (xy 386.062951 -312.696307) (xy 386.112126 -312.694326)
			(xy 386.160981 -312.700258) (xy 386.208252 -312.71395) (xy 386.252714 -312.735048) (xy 386.293217 -312.763004)
			(xy 386.32871 -312.797096) (xy 386.358275 -312.83644) (xy 386.381146 -312.880017) (xy 386.39673 -312.926698)
			(xy 386.404625 -312.975275) (xy 386.40512 -312.999882) (xy 386.404625 -313.024489) (xy 386.404446 -313.02559)
			(xy 386.723378 -313.02559) (xy 386.723378 -312.974174) (xy 386.731421 -312.923392) (xy 386.747309 -312.874493)
			(xy 386.770652 -312.828681) (xy 386.800873 -312.787085) (xy 386.837229 -312.750729) (xy 386.878825 -312.720508)
			(xy 386.924637 -312.697165) (xy 386.973536 -312.681277) (xy 387.024318 -312.673234) (xy 387.075734 -312.673234)
			(xy 387.126516 -312.681277) (xy 387.175415 -312.697165) (xy 387.221227 -312.720508) (xy 387.262823 -312.750729)
			(xy 387.299179 -312.787085) (xy 387.3294 -312.828681) (xy 387.352743 -312.874493) (xy 387.368631 -312.923392)
			(xy 387.376674 -312.974174) (xy 387.377178 -312.999882) (xy 387.694182 -312.999882) (xy 387.698142 -312.950828)
			(xy 387.709919 -312.903044) (xy 387.72921 -312.857768) (xy 387.755513 -312.816172) (xy 387.788148 -312.779335)
			(xy 387.826269 -312.74821) (xy 387.86889 -312.723603) (xy 387.914906 -312.706151) (xy 387.963125 -312.696307)
			(xy 388.0123 -312.694326) (xy 388.061155 -312.700258) (xy 388.108426 -312.71395) (xy 388.152888 -312.735048)
			(xy 388.193391 -312.763004) (xy 388.228884 -312.797096) (xy 388.258449 -312.83644) (xy 388.28132 -312.880017)
			(xy 388.296904 -312.926698) (xy 388.304799 -312.975275) (xy 388.305294 -312.999882) (xy 388.304799 -313.024489)
			(xy 388.30462 -313.02559) (xy 388.623298 -313.02559) (xy 388.623298 -312.974174) (xy 388.631341 -312.923392)
			(xy 388.647229 -312.874493) (xy 388.670572 -312.828681) (xy 388.700793 -312.787085) (xy 388.737149 -312.750729)
			(xy 388.778745 -312.720508) (xy 388.824557 -312.697165) (xy 388.873456 -312.681277) (xy 388.924238 -312.673234)
			(xy 388.975654 -312.673234) (xy 389.026436 -312.681277) (xy 389.075335 -312.697165) (xy 389.121147 -312.720508)
			(xy 389.162743 -312.750729) (xy 389.199099 -312.787085) (xy 389.22932 -312.828681) (xy 389.252663 -312.874493)
			(xy 389.268551 -312.923392) (xy 389.276594 -312.974174) (xy 389.277098 -312.999882) (xy 389.276594 -313.02559)
			(xy 389.268551 -313.076372) (xy 389.252663 -313.125271) (xy 389.22932 -313.171083) (xy 389.199099 -313.212679)
			(xy 389.162743 -313.249035) (xy 389.121147 -313.279256) (xy 389.075335 -313.302599) (xy 389.026436 -313.318487)
			(xy 388.975654 -313.32653) (xy 388.924238 -313.32653) (xy 388.873456 -313.318487) (xy 388.824557 -313.302599)
			(xy 388.778745 -313.279256) (xy 388.737149 -313.249035) (xy 388.700793 -313.212679) (xy 388.670572 -313.171083)
			(xy 388.647229 -313.125271) (xy 388.631341 -313.076372) (xy 388.623298 -313.02559) (xy 388.30462 -313.02559)
			(xy 388.296904 -313.073066) (xy 388.28132 -313.119747) (xy 388.258449 -313.163324) (xy 388.228884 -313.202668)
			(xy 388.193391 -313.23676) (xy 388.152888 -313.264716) (xy 388.108426 -313.285814) (xy 388.061155 -313.299506)
			(xy 388.0123 -313.305438) (xy 387.963125 -313.303457) (xy 387.914906 -313.293613) (xy 387.86889 -313.276161)
			(xy 387.826269 -313.251554) (xy 387.788148 -313.220429) (xy 387.755513 -313.183592) (xy 387.72921 -313.141996)
			(xy 387.709919 -313.09672) (xy 387.698142 -313.048936) (xy 387.694182 -312.999882) (xy 387.377178 -312.999882)
			(xy 387.376674 -313.02559) (xy 387.368631 -313.076372) (xy 387.352743 -313.125271) (xy 387.3294 -313.171083)
			(xy 387.299179 -313.212679) (xy 387.262823 -313.249035) (xy 387.221227 -313.279256) (xy 387.175415 -313.302599)
			(xy 387.126516 -313.318487) (xy 387.075734 -313.32653) (xy 387.024318 -313.32653) (xy 386.973536 -313.318487)
			(xy 386.924637 -313.302599) (xy 386.878825 -313.279256) (xy 386.837229 -313.249035) (xy 386.800873 -313.212679)
			(xy 386.770652 -313.171083) (xy 386.747309 -313.125271) (xy 386.731421 -313.076372) (xy 386.723378 -313.02559)
			(xy 386.404446 -313.02559) (xy 386.39673 -313.073066) (xy 386.381146 -313.119747) (xy 386.358275 -313.163324)
			(xy 386.32871 -313.202668) (xy 386.293217 -313.23676) (xy 386.252714 -313.264716) (xy 386.208252 -313.285814)
			(xy 386.160981 -313.299506) (xy 386.112126 -313.305438) (xy 386.062951 -313.303457) (xy 386.014732 -313.293613)
			(xy 385.968716 -313.276161) (xy 385.926095 -313.251554) (xy 385.887974 -313.220429) (xy 385.855339 -313.183592)
			(xy 385.829036 -313.141996) (xy 385.809745 -313.09672) (xy 385.797968 -313.048936) (xy 385.794008 -312.999882)
			(xy 385.45516 -312.999882) (xy 385.454665 -313.024489) (xy 385.44677 -313.073066) (xy 385.431186 -313.119747)
			(xy 385.408315 -313.163324) (xy 385.37875 -313.202668) (xy 385.343257 -313.23676) (xy 385.302754 -313.264716)
			(xy 385.258292 -313.285814) (xy 385.211021 -313.299506) (xy 385.162166 -313.305438) (xy 385.112991 -313.303457)
			(xy 385.064772 -313.293613) (xy 385.018756 -313.276161) (xy 384.976135 -313.251554) (xy 384.938014 -313.220429)
			(xy 384.905379 -313.183592) (xy 384.879076 -313.141996) (xy 384.859785 -313.09672) (xy 384.848008 -313.048936)
			(xy 384.844048 -312.999882) (xy 351.03308 -312.999882) (xy 351.03308 -313.669934) (xy 382.34696 -313.669934)
			(xy 382.351031 -313.614312) (xy 382.363157 -313.559875) (xy 382.38308 -313.507784) (xy 382.410376 -313.459149)
			(xy 382.444462 -313.415006) (xy 382.484611 -313.376297) (xy 382.529969 -313.343846) (xy 382.579569 -313.318345)
			(xy 382.632353 -313.300338) (xy 382.687196 -313.290208) (xy 382.74293 -313.288171) (xy 382.798367 -313.294271)
			(xy 382.852324 -313.308377) (xy 382.903653 -313.330189) (xy 382.951259 -313.359243) (xy 382.994127 -313.394918)
			(xy 383.031344 -313.436455) (xy 383.062117 -313.482968) (xy 383.085789 -313.533465) (xy 383.101857 -313.586872)
			(xy 383.109977 -313.642048) (xy 383.110486 -313.669934) (xy 383.109977 -313.69782) (xy 383.101857 -313.752996)
			(xy 383.085789 -313.806403) (xy 383.062117 -313.8569) (xy 383.031344 -313.903413) (xy 382.994127 -313.94495)
			(xy 382.988249 -313.949842) (xy 384.844048 -313.949842) (xy 384.848008 -313.900788) (xy 384.859785 -313.853004)
			(xy 384.879076 -313.807728) (xy 384.905379 -313.766132) (xy 384.938014 -313.729295) (xy 384.976135 -313.69817)
			(xy 385.018756 -313.673563) (xy 385.064772 -313.656111) (xy 385.112991 -313.646267) (xy 385.162166 -313.644286)
			(xy 385.211021 -313.650218) (xy 385.258292 -313.66391) (xy 385.302754 -313.685008) (xy 385.343257 -313.712964)
			(xy 385.37875 -313.747056) (xy 385.408315 -313.7864) (xy 385.431186 -313.829977) (xy 385.44677 -313.876658)
			(xy 385.454665 -313.925235) (xy 385.45516 -313.949842) (xy 385.794008 -313.949842) (xy 385.797968 -313.900788)
			(xy 385.809745 -313.853004) (xy 385.829036 -313.807728) (xy 385.855339 -313.766132) (xy 385.887974 -313.729295)
			(xy 385.926095 -313.69817) (xy 385.968716 -313.673563) (xy 386.014732 -313.656111) (xy 386.062951 -313.646267)
			(xy 386.112126 -313.644286) (xy 386.160981 -313.650218) (xy 386.208252 -313.66391) (xy 386.252714 -313.685008)
			(xy 386.293217 -313.712964) (xy 386.32871 -313.747056) (xy 386.358275 -313.7864) (xy 386.381146 -313.829977)
			(xy 386.39673 -313.876658) (xy 386.404625 -313.925235) (xy 386.40512 -313.949842) (xy 386.404625 -313.974449)
			(xy 386.404446 -313.97555) (xy 386.723378 -313.97555) (xy 386.723378 -313.924134) (xy 386.731421 -313.873352)
			(xy 386.747309 -313.824453) (xy 386.770652 -313.778641) (xy 386.800873 -313.737045) (xy 386.837229 -313.700689)
			(xy 386.878825 -313.670468) (xy 386.924637 -313.647125) (xy 386.973536 -313.631237) (xy 387.024318 -313.623194)
			(xy 387.075734 -313.623194) (xy 387.126516 -313.631237) (xy 387.175415 -313.647125) (xy 387.221227 -313.670468)
			(xy 387.262823 -313.700689) (xy 387.299179 -313.737045) (xy 387.3294 -313.778641) (xy 387.352743 -313.824453)
			(xy 387.368631 -313.873352) (xy 387.376674 -313.924134) (xy 387.377178 -313.949842) (xy 387.694182 -313.949842)
			(xy 387.698142 -313.900788) (xy 387.709919 -313.853004) (xy 387.72921 -313.807728) (xy 387.755513 -313.766132)
			(xy 387.788148 -313.729295) (xy 387.826269 -313.69817) (xy 387.86889 -313.673563) (xy 387.914906 -313.656111)
			(xy 387.963125 -313.646267) (xy 388.0123 -313.644286) (xy 388.061155 -313.650218) (xy 388.108426 -313.66391)
			(xy 388.152888 -313.685008) (xy 388.193391 -313.712964) (xy 388.228884 -313.747056) (xy 388.258449 -313.7864)
			(xy 388.28132 -313.829977) (xy 388.296904 -313.876658) (xy 388.304799 -313.925235) (xy 388.305294 -313.949842)
			(xy 388.304799 -313.974449) (xy 388.30462 -313.97555) (xy 388.623298 -313.97555) (xy 388.623298 -313.924134)
			(xy 388.631341 -313.873352) (xy 388.647229 -313.824453) (xy 388.670572 -313.778641) (xy 388.700793 -313.737045)
			(xy 388.737149 -313.700689) (xy 388.778745 -313.670468) (xy 388.824557 -313.647125) (xy 388.873456 -313.631237)
			(xy 388.924238 -313.623194) (xy 388.975654 -313.623194) (xy 389.026436 -313.631237) (xy 389.075335 -313.647125)
			(xy 389.121147 -313.670468) (xy 389.162743 -313.700689) (xy 389.199099 -313.737045) (xy 389.22932 -313.778641)
			(xy 389.252663 -313.824453) (xy 389.268551 -313.873352) (xy 389.276594 -313.924134) (xy 389.277098 -313.949842)
			(xy 389.276594 -313.97555) (xy 389.268551 -314.026332) (xy 389.252663 -314.075231) (xy 389.22932 -314.121043)
			(xy 389.199099 -314.162639) (xy 389.162743 -314.198995) (xy 389.121147 -314.229216) (xy 389.075335 -314.252559)
			(xy 389.026436 -314.268447) (xy 388.975654 -314.27649) (xy 388.924238 -314.27649) (xy 388.873456 -314.268447)
			(xy 388.824557 -314.252559) (xy 388.778745 -314.229216) (xy 388.737149 -314.198995) (xy 388.700793 -314.162639)
			(xy 388.670572 -314.121043) (xy 388.647229 -314.075231) (xy 388.631341 -314.026332) (xy 388.623298 -313.97555)
			(xy 388.30462 -313.97555) (xy 388.296904 -314.023026) (xy 388.28132 -314.069707) (xy 388.258449 -314.113284)
			(xy 388.228884 -314.152628) (xy 388.193391 -314.18672) (xy 388.152888 -314.214676) (xy 388.108426 -314.235774)
			(xy 388.061155 -314.249466) (xy 388.0123 -314.255398) (xy 387.963125 -314.253417) (xy 387.914906 -314.243573)
			(xy 387.86889 -314.226121) (xy 387.826269 -314.201514) (xy 387.788148 -314.170389) (xy 387.755513 -314.133552)
			(xy 387.72921 -314.091956) (xy 387.709919 -314.04668) (xy 387.698142 -313.998896) (xy 387.694182 -313.949842)
			(xy 387.377178 -313.949842) (xy 387.376674 -313.97555) (xy 387.368631 -314.026332) (xy 387.352743 -314.075231)
			(xy 387.3294 -314.121043) (xy 387.299179 -314.162639) (xy 387.262823 -314.198995) (xy 387.221227 -314.229216)
			(xy 387.175415 -314.252559) (xy 387.126516 -314.268447) (xy 387.075734 -314.27649) (xy 387.024318 -314.27649)
			(xy 386.973536 -314.268447) (xy 386.924637 -314.252559) (xy 386.878825 -314.229216) (xy 386.837229 -314.198995)
			(xy 386.800873 -314.162639) (xy 386.770652 -314.121043) (xy 386.747309 -314.075231) (xy 386.731421 -314.026332)
			(xy 386.723378 -313.97555) (xy 386.404446 -313.97555) (xy 386.39673 -314.023026) (xy 386.381146 -314.069707)
			(xy 386.358275 -314.113284) (xy 386.32871 -314.152628) (xy 386.293217 -314.18672) (xy 386.252714 -314.214676)
			(xy 386.208252 -314.235774) (xy 386.160981 -314.249466) (xy 386.112126 -314.255398) (xy 386.062951 -314.253417)
			(xy 386.014732 -314.243573) (xy 385.968716 -314.226121) (xy 385.926095 -314.201514) (xy 385.887974 -314.170389)
			(xy 385.855339 -314.133552) (xy 385.829036 -314.091956) (xy 385.809745 -314.04668) (xy 385.797968 -313.998896)
			(xy 385.794008 -313.949842) (xy 385.45516 -313.949842) (xy 385.454665 -313.974449) (xy 385.44677 -314.023026)
			(xy 385.431186 -314.069707) (xy 385.408315 -314.113284) (xy 385.37875 -314.152628) (xy 385.343257 -314.18672)
			(xy 385.302754 -314.214676) (xy 385.258292 -314.235774) (xy 385.211021 -314.249466) (xy 385.162166 -314.255398)
			(xy 385.112991 -314.253417) (xy 385.064772 -314.243573) (xy 385.018756 -314.226121) (xy 384.976135 -314.201514)
			(xy 384.938014 -314.170389) (xy 384.905379 -314.133552) (xy 384.879076 -314.091956) (xy 384.859785 -314.04668)
			(xy 384.848008 -313.998896) (xy 384.844048 -313.949842) (xy 382.988249 -313.949842) (xy 382.951259 -313.980625)
			(xy 382.903653 -314.009679) (xy 382.852324 -314.031491) (xy 382.798367 -314.045597) (xy 382.74293 -314.051697)
			(xy 382.687196 -314.04966) (xy 382.632353 -314.03953) (xy 382.579569 -314.021523) (xy 382.529969 -313.996022)
			(xy 382.484611 -313.963571) (xy 382.444462 -313.924862) (xy 382.410376 -313.880719) (xy 382.38308 -313.832084)
			(xy 382.363157 -313.779993) (xy 382.351031 -313.725556) (xy 382.34696 -313.669934) (xy 351.03308 -313.669934)
			(xy 351.03308 -314.547504) (xy 351.039684 -314.554108) (xy 351.039684 -314.899548) (xy 383.89358 -314.899548)
			(xy 383.89754 -314.850494) (xy 383.909317 -314.80271) (xy 383.928608 -314.757434) (xy 383.954911 -314.715838)
			(xy 383.987546 -314.679001) (xy 384.025667 -314.647876) (xy 384.068288 -314.623269) (xy 384.114304 -314.605817)
			(xy 384.162523 -314.595973) (xy 384.211698 -314.593992) (xy 384.260553 -314.599924) (xy 384.307824 -314.613616)
			(xy 384.352286 -314.634714) (xy 384.392789 -314.66267) (xy 384.428282 -314.696762) (xy 384.457847 -314.736106)
			(xy 384.480718 -314.779683) (xy 384.496302 -314.826364) (xy 384.504197 -314.874941) (xy 384.504692 -314.899548)
			(xy 384.504197 -314.924155) (xy 384.503977 -314.92551) (xy 384.823204 -314.92551) (xy 384.823204 -314.874094)
			(xy 384.831247 -314.823312) (xy 384.847135 -314.774413) (xy 384.870478 -314.728601) (xy 384.900699 -314.687005)
			(xy 384.937055 -314.650649) (xy 384.978651 -314.620428) (xy 385.024463 -314.597085) (xy 385.073362 -314.581197)
			(xy 385.124144 -314.573154) (xy 385.17556 -314.573154) (xy 385.226342 -314.581197) (xy 385.275241 -314.597085)
			(xy 385.321053 -314.620428) (xy 385.362649 -314.650649) (xy 385.399005 -314.687005) (xy 385.429226 -314.728601)
			(xy 385.452569 -314.774413) (xy 385.468457 -314.823312) (xy 385.4765 -314.874094) (xy 385.477004 -314.899802)
			(xy 385.4765 -314.92551) (xy 385.773164 -314.92551) (xy 385.773164 -314.874094) (xy 385.781207 -314.823312)
			(xy 385.797095 -314.774413) (xy 385.820438 -314.728601) (xy 385.850659 -314.687005) (xy 385.887015 -314.650649)
			(xy 385.928611 -314.620428) (xy 385.974423 -314.597085) (xy 386.023322 -314.581197) (xy 386.074104 -314.573154)
			(xy 386.12552 -314.573154) (xy 386.176302 -314.581197) (xy 386.225201 -314.597085) (xy 386.271013 -314.620428)
			(xy 386.312609 -314.650649) (xy 386.348965 -314.687005) (xy 386.379186 -314.728601) (xy 386.402529 -314.774413)
			(xy 386.418417 -314.823312) (xy 386.42646 -314.874094) (xy 386.426964 -314.899802) (xy 386.744222 -314.899802)
			(xy 386.748182 -314.850748) (xy 386.759959 -314.802964) (xy 386.77925 -314.757688) (xy 386.805553 -314.716092)
			(xy 386.838188 -314.679255) (xy 386.876309 -314.64813) (xy 386.91893 -314.623523) (xy 386.964946 -314.606071)
			(xy 387.013165 -314.596227) (xy 387.06234 -314.594246) (xy 387.111195 -314.600178) (xy 387.158466 -314.61387)
			(xy 387.202928 -314.634968) (xy 387.243431 -314.662924) (xy 387.278924 -314.697016) (xy 387.308489 -314.73636)
			(xy 387.33136 -314.779937) (xy 387.346944 -314.826618) (xy 387.354839 -314.875195) (xy 387.355334 -314.899802)
			(xy 387.694182 -314.899802) (xy 387.698142 -314.850748) (xy 387.709919 -314.802964) (xy 387.72921 -314.757688)
			(xy 387.755513 -314.716092) (xy 387.788148 -314.679255) (xy 387.826269 -314.64813) (xy 387.86889 -314.623523)
			(xy 387.914906 -314.606071) (xy 387.963125 -314.596227) (xy 388.0123 -314.594246) (xy 388.061155 -314.600178)
			(xy 388.108426 -314.61387) (xy 388.152888 -314.634968) (xy 388.193391 -314.662924) (xy 388.228884 -314.697016)
			(xy 388.258449 -314.73636) (xy 388.28132 -314.779937) (xy 388.296904 -314.826618) (xy 388.304799 -314.875195)
			(xy 388.305294 -314.899802) (xy 388.644142 -314.899802) (xy 388.648102 -314.850748) (xy 388.659879 -314.802964)
			(xy 388.67917 -314.757688) (xy 388.705473 -314.716092) (xy 388.738108 -314.679255) (xy 388.776229 -314.64813)
			(xy 388.81885 -314.623523) (xy 388.864866 -314.606071) (xy 388.913085 -314.596227) (xy 388.96226 -314.594246)
			(xy 389.011115 -314.600178) (xy 389.058386 -314.61387) (xy 389.102848 -314.634968) (xy 389.143351 -314.662924)
			(xy 389.178844 -314.697016) (xy 389.208409 -314.73636) (xy 389.23128 -314.779937) (xy 389.246864 -314.826618)
			(xy 389.254759 -314.875195) (xy 389.255254 -314.899802) (xy 389.254759 -314.924409) (xy 389.246864 -314.972986)
			(xy 389.23128 -315.019667) (xy 389.208409 -315.063244) (xy 389.178844 -315.102588) (xy 389.143351 -315.13668)
			(xy 389.102848 -315.164636) (xy 389.058386 -315.185734) (xy 389.011115 -315.199426) (xy 388.96226 -315.205358)
			(xy 388.913085 -315.203377) (xy 388.864866 -315.193533) (xy 388.81885 -315.176081) (xy 388.776229 -315.151474)
			(xy 388.738108 -315.120349) (xy 388.705473 -315.083512) (xy 388.67917 -315.041916) (xy 388.659879 -314.99664)
			(xy 388.648102 -314.948856) (xy 388.644142 -314.899802) (xy 388.305294 -314.899802) (xy 388.304799 -314.924409)
			(xy 388.296904 -314.972986) (xy 388.28132 -315.019667) (xy 388.258449 -315.063244) (xy 388.228884 -315.102588)
			(xy 388.193391 -315.13668) (xy 388.152888 -315.164636) (xy 388.108426 -315.185734) (xy 388.061155 -315.199426)
			(xy 388.0123 -315.205358) (xy 387.963125 -315.203377) (xy 387.914906 -315.193533) (xy 387.86889 -315.176081)
			(xy 387.826269 -315.151474) (xy 387.788148 -315.120349) (xy 387.755513 -315.083512) (xy 387.72921 -315.041916)
			(xy 387.709919 -314.99664) (xy 387.698142 -314.948856) (xy 387.694182 -314.899802) (xy 387.355334 -314.899802)
			(xy 387.354839 -314.924409) (xy 387.346944 -314.972986) (xy 387.33136 -315.019667) (xy 387.308489 -315.063244)
			(xy 387.278924 -315.102588) (xy 387.243431 -315.13668) (xy 387.202928 -315.164636) (xy 387.158466 -315.185734)
			(xy 387.111195 -315.199426) (xy 387.06234 -315.205358) (xy 387.013165 -315.203377) (xy 386.964946 -315.193533)
			(xy 386.91893 -315.176081) (xy 386.876309 -315.151474) (xy 386.838188 -315.120349) (xy 386.805553 -315.083512)
			(xy 386.77925 -315.041916) (xy 386.759959 -314.99664) (xy 386.748182 -314.948856) (xy 386.744222 -314.899802)
			(xy 386.426964 -314.899802) (xy 386.42646 -314.92551) (xy 386.418417 -314.976292) (xy 386.402529 -315.025191)
			(xy 386.379186 -315.071003) (xy 386.348965 -315.112599) (xy 386.312609 -315.148955) (xy 386.271013 -315.179176)
			(xy 386.225201 -315.202519) (xy 386.176302 -315.218407) (xy 386.12552 -315.22645) (xy 386.074104 -315.22645)
			(xy 386.023322 -315.218407) (xy 385.974423 -315.202519) (xy 385.928611 -315.179176) (xy 385.887015 -315.148955)
			(xy 385.850659 -315.112599) (xy 385.820438 -315.071003) (xy 385.797095 -315.025191) (xy 385.781207 -314.976292)
			(xy 385.773164 -314.92551) (xy 385.4765 -314.92551) (xy 385.468457 -314.976292) (xy 385.452569 -315.025191)
			(xy 385.429226 -315.071003) (xy 385.399005 -315.112599) (xy 385.362649 -315.148955) (xy 385.321053 -315.179176)
			(xy 385.275241 -315.202519) (xy 385.226342 -315.218407) (xy 385.17556 -315.22645) (xy 385.124144 -315.22645)
			(xy 385.073362 -315.218407) (xy 385.024463 -315.202519) (xy 384.978651 -315.179176) (xy 384.937055 -315.148955)
			(xy 384.900699 -315.112599) (xy 384.870478 -315.071003) (xy 384.847135 -315.025191) (xy 384.831247 -314.976292)
			(xy 384.823204 -314.92551) (xy 384.503977 -314.92551) (xy 384.496302 -314.972732) (xy 384.480718 -315.019413)
			(xy 384.457847 -315.06299) (xy 384.428282 -315.102334) (xy 384.392789 -315.136426) (xy 384.352286 -315.164382)
			(xy 384.307824 -315.18548) (xy 384.260553 -315.199172) (xy 384.211698 -315.205104) (xy 384.162523 -315.203123)
			(xy 384.114304 -315.193279) (xy 384.068288 -315.175827) (xy 384.025667 -315.15122) (xy 383.987546 -315.120095)
			(xy 383.954911 -315.083258) (xy 383.928608 -315.041662) (xy 383.909317 -314.996386) (xy 383.89754 -314.948602)
			(xy 383.89358 -314.899548) (xy 351.039684 -314.899548) (xy 351.039684 -315.849762) (xy 384.844048 -315.849762)
			(xy 384.848008 -315.800708) (xy 384.859785 -315.752924) (xy 384.879076 -315.707648) (xy 384.905379 -315.666052)
			(xy 384.938014 -315.629215) (xy 384.976135 -315.59809) (xy 385.018756 -315.573483) (xy 385.064772 -315.556031)
			(xy 385.112991 -315.546187) (xy 385.162166 -315.544206) (xy 385.211021 -315.550138) (xy 385.258292 -315.56383)
			(xy 385.302754 -315.584928) (xy 385.343257 -315.612884) (xy 385.37875 -315.646976) (xy 385.408315 -315.68632)
			(xy 385.431186 -315.729897) (xy 385.44677 -315.776578) (xy 385.454665 -315.825155) (xy 385.45516 -315.849762)
			(xy 385.794008 -315.849762) (xy 385.797968 -315.800708) (xy 385.809745 -315.752924) (xy 385.829036 -315.707648)
			(xy 385.855339 -315.666052) (xy 385.887974 -315.629215) (xy 385.926095 -315.59809) (xy 385.968716 -315.573483)
			(xy 386.014732 -315.556031) (xy 386.062951 -315.546187) (xy 386.112126 -315.544206) (xy 386.160981 -315.550138)
			(xy 386.208252 -315.56383) (xy 386.252714 -315.584928) (xy 386.293217 -315.612884) (xy 386.32871 -315.646976)
			(xy 386.358275 -315.68632) (xy 386.381146 -315.729897) (xy 386.39673 -315.776578) (xy 386.404625 -315.825155)
			(xy 386.40512 -315.849762) (xy 386.404625 -315.874369) (xy 386.39673 -315.922946) (xy 386.381146 -315.969627)
			(xy 386.358275 -316.013204) (xy 386.32871 -316.052548) (xy 386.293217 -316.08664) (xy 386.252714 -316.114596)
			(xy 386.208252 -316.135694) (xy 386.160981 -316.149386) (xy 386.112126 -316.155318) (xy 386.062951 -316.153337)
			(xy 386.014732 -316.143493) (xy 385.968716 -316.126041) (xy 385.926095 -316.101434) (xy 385.887974 -316.070309)
			(xy 385.855339 -316.033472) (xy 385.829036 -315.991876) (xy 385.809745 -315.9466) (xy 385.797968 -315.898816)
			(xy 385.794008 -315.849762) (xy 385.45516 -315.849762) (xy 385.454665 -315.874369) (xy 385.44677 -315.922946)
			(xy 385.431186 -315.969627) (xy 385.408315 -316.013204) (xy 385.37875 -316.052548) (xy 385.343257 -316.08664)
			(xy 385.302754 -316.114596) (xy 385.258292 -316.135694) (xy 385.211021 -316.149386) (xy 385.162166 -316.155318)
			(xy 385.112991 -316.153337) (xy 385.064772 -316.143493) (xy 385.018756 -316.126041) (xy 384.976135 -316.101434)
			(xy 384.938014 -316.070309) (xy 384.905379 -316.033472) (xy 384.879076 -315.991876) (xy 384.859785 -315.9466)
			(xy 384.848008 -315.898816) (xy 384.844048 -315.849762) (xy 351.039684 -315.849762) (xy 351.039684 -316.941962)
			(xy 351.040152 -316.951836) (xy 351.047604 -316.970125) (xy 351.054162 -316.977522) (xy 351.054416 -316.977776)
			(xy 351.800414 -317.723774) (xy 351.800922 -317.724282) (xy 351.808303 -317.730866) (xy 351.826601 -317.738323)
			(xy 351.836482 -317.73876)
		)
		(stroke
			(width 0)
			(type solid)
		)
		(fill yes)
		(layer "In15.Cu")
		(net "P0V8_PEX3")
	)
	(gr_poly
		(pts
			(xy 24.976836 -319.677288) (xy 24.985115 -319.676965) (xy 25.000794 -319.671643) (xy 25.00757 -319.666874)
			(xy 25.02916 -319.650364) (xy 25.035576 -319.645163) (xy 25.044912 -319.631554) (xy 25.047448 -319.623694)
			(xy 25.047448 -319.62344) (xy 25.073855 -319.530069) (xy 25.133281 -319.345328) (xy 25.200161 -319.163154)
			(xy 25.274387 -318.983846) (xy 25.355835 -318.807702) (xy 25.444371 -318.635011) (xy 25.539848 -318.46606)
			(xy 25.64211 -318.301126) (xy 25.750986 -318.140482) (xy 25.866299 -317.984393) (xy 25.987856 -317.833117)
			(xy 26.115458 -317.686904) (xy 26.248894 -317.545995) (xy 26.387944 -317.410622) (xy 26.532378 -317.281009)
			(xy 26.681958 -317.15737) (xy 26.836436 -317.039909) (xy 26.995558 -316.92882) (xy 27.159061 -316.824287)
			(xy 27.326676 -316.726481) (xy 27.498125 -316.635564) (xy 27.673126 -316.551687) (xy 27.851389 -316.474988)
			(xy 28.032621 -316.405593) (xy 28.216522 -316.343617) (xy 28.402789 -316.289163) (xy 28.591114 -316.242319)
			(xy 28.781186 -316.203164) (xy 28.972692 -316.171763) (xy 29.165316 -316.148166) (xy 29.358739 -316.132413)
			(xy 29.552642 -316.12453) (xy 29.746706 -316.12453) (xy 29.940609 -316.132413) (xy 30.134032 -316.148166)
			(xy 30.326656 -316.171763) (xy 30.518162 -316.203164) (xy 30.708234 -316.242319) (xy 30.896559 -316.289163)
			(xy 31.082826 -316.343617) (xy 31.266727 -316.405593) (xy 31.447959 -316.474988) (xy 31.626222 -316.551687)
			(xy 31.801223 -316.635564) (xy 31.972672 -316.726481) (xy 32.097753 -316.799468) (xy 35.59354 -316.799468)
			(xy 35.5975 -316.750414) (xy 35.609277 -316.70263) (xy 35.628568 -316.657354) (xy 35.654871 -316.615758)
			(xy 35.687506 -316.578921) (xy 35.725627 -316.547796) (xy 35.768248 -316.523189) (xy 35.814264 -316.505737)
			(xy 35.862483 -316.495893) (xy 35.911658 -316.493912) (xy 35.960513 -316.499844) (xy 36.007784 -316.513536)
			(xy 36.052246 -316.534634) (xy 36.092749 -316.56259) (xy 36.128242 -316.596682) (xy 36.157807 -316.636026)
			(xy 36.180678 -316.679603) (xy 36.196262 -316.726284) (xy 36.204157 -316.774861) (xy 36.204652 -316.799468)
			(xy 36.204157 -316.824075) (xy 36.203937 -316.82543) (xy 36.523164 -316.82543) (xy 36.523164 -316.774014)
			(xy 36.531207 -316.723232) (xy 36.547095 -316.674333) (xy 36.570438 -316.628521) (xy 36.600659 -316.586925)
			(xy 36.637015 -316.550569) (xy 36.678611 -316.520348) (xy 36.724423 -316.497005) (xy 36.773322 -316.481117)
			(xy 36.824104 -316.473074) (xy 36.87552 -316.473074) (xy 36.926302 -316.481117) (xy 36.975201 -316.497005)
			(xy 37.021013 -316.520348) (xy 37.062609 -316.550569) (xy 37.098965 -316.586925) (xy 37.129186 -316.628521)
			(xy 37.152529 -316.674333) (xy 37.168417 -316.723232) (xy 37.17646 -316.774014) (xy 37.176964 -316.799722)
			(xy 37.17646 -316.82543) (xy 37.473124 -316.82543) (xy 37.473124 -316.774014) (xy 37.481167 -316.723232)
			(xy 37.497055 -316.674333) (xy 37.520398 -316.628521) (xy 37.550619 -316.586925) (xy 37.586975 -316.550569)
			(xy 37.628571 -316.520348) (xy 37.674383 -316.497005) (xy 37.723282 -316.481117) (xy 37.774064 -316.473074)
			(xy 37.82548 -316.473074) (xy 37.876262 -316.481117) (xy 37.925161 -316.497005) (xy 37.970973 -316.520348)
			(xy 38.012569 -316.550569) (xy 38.048925 -316.586925) (xy 38.079146 -316.628521) (xy 38.102489 -316.674333)
			(xy 38.118377 -316.723232) (xy 38.12642 -316.774014) (xy 38.126924 -316.799722) (xy 38.444182 -316.799722)
			(xy 38.448142 -316.750668) (xy 38.459919 -316.702884) (xy 38.47921 -316.657608) (xy 38.505513 -316.616012)
			(xy 38.538148 -316.579175) (xy 38.576269 -316.54805) (xy 38.61889 -316.523443) (xy 38.664906 -316.505991)
			(xy 38.713125 -316.496147) (xy 38.7623 -316.494166) (xy 38.811155 -316.500098) (xy 38.858426 -316.51379)
			(xy 38.902888 -316.534888) (xy 38.943391 -316.562844) (xy 38.978884 -316.596936) (xy 39.008449 -316.63628)
			(xy 39.03132 -316.679857) (xy 39.046904 -316.726538) (xy 39.054799 -316.775115) (xy 39.055294 -316.799722)
			(xy 39.054799 -316.824329) (xy 39.05462 -316.82543) (xy 39.373298 -316.82543) (xy 39.373298 -316.774014)
			(xy 39.381341 -316.723232) (xy 39.397229 -316.674333) (xy 39.420572 -316.628521) (xy 39.450793 -316.586925)
			(xy 39.487149 -316.550569) (xy 39.528745 -316.520348) (xy 39.574557 -316.497005) (xy 39.623456 -316.481117)
			(xy 39.674238 -316.473074) (xy 39.725654 -316.473074) (xy 39.776436 -316.481117) (xy 39.825335 -316.497005)
			(xy 39.871147 -316.520348) (xy 39.912743 -316.550569) (xy 39.949099 -316.586925) (xy 39.97932 -316.628521)
			(xy 40.002663 -316.674333) (xy 40.018551 -316.723232) (xy 40.026594 -316.774014) (xy 40.027098 -316.799722)
			(xy 40.344102 -316.799722) (xy 40.348062 -316.750668) (xy 40.359839 -316.702884) (xy 40.37913 -316.657608)
			(xy 40.405433 -316.616012) (xy 40.438068 -316.579175) (xy 40.476189 -316.54805) (xy 40.51881 -316.523443)
			(xy 40.564826 -316.505991) (xy 40.613045 -316.496147) (xy 40.66222 -316.494166) (xy 40.711075 -316.500098)
			(xy 40.758346 -316.51379) (xy 40.802808 -316.534888) (xy 40.843311 -316.562844) (xy 40.878804 -316.596936)
			(xy 40.908369 -316.63628) (xy 40.93124 -316.679857) (xy 40.946824 -316.726538) (xy 40.954719 -316.775115)
			(xy 40.955214 -316.799722) (xy 40.954719 -316.824329) (xy 40.95454 -316.82543) (xy 41.273218 -316.82543)
			(xy 41.273218 -316.774014) (xy 41.281261 -316.723232) (xy 41.297149 -316.674333) (xy 41.320492 -316.628521)
			(xy 41.350713 -316.586925) (xy 41.387069 -316.550569) (xy 41.428665 -316.520348) (xy 41.474477 -316.497005)
			(xy 41.523376 -316.481117) (xy 41.574158 -316.473074) (xy 41.625574 -316.473074) (xy 41.676356 -316.481117)
			(xy 41.725255 -316.497005) (xy 41.771067 -316.520348) (xy 41.812663 -316.550569) (xy 41.849019 -316.586925)
			(xy 41.87924 -316.628521) (xy 41.902583 -316.674333) (xy 41.918471 -316.723232) (xy 41.926514 -316.774014)
			(xy 41.927018 -316.799722) (xy 42.244022 -316.799722) (xy 42.247982 -316.750668) (xy 42.259759 -316.702884)
			(xy 42.27905 -316.657608) (xy 42.305353 -316.616012) (xy 42.337988 -316.579175) (xy 42.376109 -316.54805)
			(xy 42.41873 -316.523443) (xy 42.464746 -316.505991) (xy 42.512965 -316.496147) (xy 42.56214 -316.494166)
			(xy 42.610995 -316.500098) (xy 42.658266 -316.51379) (xy 42.702728 -316.534888) (xy 42.743231 -316.562844)
			(xy 42.778724 -316.596936) (xy 42.808289 -316.63628) (xy 42.83116 -316.679857) (xy 42.846744 -316.726538)
			(xy 42.854639 -316.775115) (xy 42.855134 -316.799722) (xy 42.854639 -316.824329) (xy 42.85446 -316.82543)
			(xy 43.173138 -316.82543) (xy 43.173138 -316.774014) (xy 43.181181 -316.723232) (xy 43.197069 -316.674333)
			(xy 43.220412 -316.628521) (xy 43.250633 -316.586925) (xy 43.286989 -316.550569) (xy 43.328585 -316.520348)
			(xy 43.374397 -316.497005) (xy 43.423296 -316.481117) (xy 43.474078 -316.473074) (xy 43.525494 -316.473074)
			(xy 43.576276 -316.481117) (xy 43.625175 -316.497005) (xy 43.670987 -316.520348) (xy 43.712583 -316.550569)
			(xy 43.748939 -316.586925) (xy 43.77916 -316.628521) (xy 43.802503 -316.674333) (xy 43.818391 -316.723232)
			(xy 43.826434 -316.774014) (xy 43.826938 -316.799722) (xy 44.143942 -316.799722) (xy 44.147902 -316.750668)
			(xy 44.159679 -316.702884) (xy 44.17897 -316.657608) (xy 44.205273 -316.616012) (xy 44.237908 -316.579175)
			(xy 44.276029 -316.54805) (xy 44.31865 -316.523443) (xy 44.364666 -316.505991) (xy 44.412885 -316.496147)
			(xy 44.46206 -316.494166) (xy 44.510915 -316.500098) (xy 44.558186 -316.51379) (xy 44.602648 -316.534888)
			(xy 44.643151 -316.562844) (xy 44.678644 -316.596936) (xy 44.708209 -316.63628) (xy 44.73108 -316.679857)
			(xy 44.746664 -316.726538) (xy 44.754559 -316.775115) (xy 44.755054 -316.799722) (xy 44.754559 -316.824329)
			(xy 44.75438 -316.82543) (xy 45.073312 -316.82543) (xy 45.073312 -316.774014) (xy 45.081355 -316.723232)
			(xy 45.097243 -316.674333) (xy 45.120586 -316.628521) (xy 45.150807 -316.586925) (xy 45.187163 -316.550569)
			(xy 45.228759 -316.520348) (xy 45.274571 -316.497005) (xy 45.32347 -316.481117) (xy 45.374252 -316.473074)
			(xy 45.425668 -316.473074) (xy 45.47645 -316.481117) (xy 45.525349 -316.497005) (xy 45.571161 -316.520348)
			(xy 45.612757 -316.550569) (xy 45.649113 -316.586925) (xy 45.679334 -316.628521) (xy 45.702677 -316.674333)
			(xy 45.718565 -316.723232) (xy 45.726608 -316.774014) (xy 45.727112 -316.799722) (xy 46.044116 -316.799722)
			(xy 46.048076 -316.750668) (xy 46.059853 -316.702884) (xy 46.079144 -316.657608) (xy 46.105447 -316.616012)
			(xy 46.138082 -316.579175) (xy 46.176203 -316.54805) (xy 46.218824 -316.523443) (xy 46.26484 -316.505991)
			(xy 46.313059 -316.496147) (xy 46.362234 -316.494166) (xy 46.411089 -316.500098) (xy 46.45836 -316.51379)
			(xy 46.502822 -316.534888) (xy 46.543325 -316.562844) (xy 46.578818 -316.596936) (xy 46.608383 -316.63628)
			(xy 46.631254 -316.679857) (xy 46.646838 -316.726538) (xy 46.654733 -316.775115) (xy 46.655228 -316.799722)
			(xy 46.654733 -316.824329) (xy 46.654554 -316.82543) (xy 46.973232 -316.82543) (xy 46.973232 -316.774014)
			(xy 46.981275 -316.723232) (xy 46.997163 -316.674333) (xy 47.020506 -316.628521) (xy 47.050727 -316.586925)
			(xy 47.087083 -316.550569) (xy 47.128679 -316.520348) (xy 47.174491 -316.497005) (xy 47.22339 -316.481117)
			(xy 47.274172 -316.473074) (xy 47.325588 -316.473074) (xy 47.37637 -316.481117) (xy 47.425269 -316.497005)
			(xy 47.471081 -316.520348) (xy 47.512677 -316.550569) (xy 47.549033 -316.586925) (xy 47.579254 -316.628521)
			(xy 47.602597 -316.674333) (xy 47.618485 -316.723232) (xy 47.626528 -316.774014) (xy 47.627032 -316.799722)
			(xy 47.944036 -316.799722) (xy 47.947996 -316.750668) (xy 47.959773 -316.702884) (xy 47.979064 -316.657608)
			(xy 48.005367 -316.616012) (xy 48.038002 -316.579175) (xy 48.076123 -316.54805) (xy 48.118744 -316.523443)
			(xy 48.16476 -316.505991) (xy 48.212979 -316.496147) (xy 48.262154 -316.494166) (xy 48.311009 -316.500098)
			(xy 48.35828 -316.51379) (xy 48.402742 -316.534888) (xy 48.443245 -316.562844) (xy 48.478738 -316.596936)
			(xy 48.508303 -316.63628) (xy 48.531174 -316.679857) (xy 48.546758 -316.726538) (xy 48.554653 -316.775115)
			(xy 48.555148 -316.799722) (xy 48.554653 -316.824329) (xy 48.554474 -316.82543) (xy 48.873152 -316.82543)
			(xy 48.873152 -316.774014) (xy 48.881195 -316.723232) (xy 48.897083 -316.674333) (xy 48.920426 -316.628521)
			(xy 48.950647 -316.586925) (xy 48.987003 -316.550569) (xy 49.028599 -316.520348) (xy 49.074411 -316.497005)
			(xy 49.12331 -316.481117) (xy 49.174092 -316.473074) (xy 49.225508 -316.473074) (xy 49.27629 -316.481117)
			(xy 49.325189 -316.497005) (xy 49.371001 -316.520348) (xy 49.412597 -316.550569) (xy 49.448953 -316.586925)
			(xy 49.479174 -316.628521) (xy 49.502517 -316.674333) (xy 49.518405 -316.723232) (xy 49.526448 -316.774014)
			(xy 49.526952 -316.799722) (xy 49.843956 -316.799722) (xy 49.847916 -316.750668) (xy 49.859693 -316.702884)
			(xy 49.878984 -316.657608) (xy 49.905287 -316.616012) (xy 49.937922 -316.579175) (xy 49.976043 -316.54805)
			(xy 50.018664 -316.523443) (xy 50.06468 -316.505991) (xy 50.112899 -316.496147) (xy 50.162074 -316.494166)
			(xy 50.210929 -316.500098) (xy 50.2582 -316.51379) (xy 50.302662 -316.534888) (xy 50.343165 -316.562844)
			(xy 50.378658 -316.596936) (xy 50.408223 -316.63628) (xy 50.431094 -316.679857) (xy 50.446678 -316.726538)
			(xy 50.454573 -316.775115) (xy 50.455068 -316.799722) (xy 50.454573 -316.824329) (xy 50.454394 -316.82543)
			(xy 50.773326 -316.82543) (xy 50.773326 -316.774014) (xy 50.781369 -316.723232) (xy 50.797257 -316.674333)
			(xy 50.8206 -316.628521) (xy 50.850821 -316.586925) (xy 50.887177 -316.550569) (xy 50.928773 -316.520348)
			(xy 50.974585 -316.497005) (xy 51.023484 -316.481117) (xy 51.074266 -316.473074) (xy 51.125682 -316.473074)
			(xy 51.176464 -316.481117) (xy 51.225363 -316.497005) (xy 51.271175 -316.520348) (xy 51.312771 -316.550569)
			(xy 51.349127 -316.586925) (xy 51.379348 -316.628521) (xy 51.402691 -316.674333) (xy 51.418579 -316.723232)
			(xy 51.426622 -316.774014) (xy 51.427126 -316.799722) (xy 51.74413 -316.799722) (xy 51.74809 -316.750668)
			(xy 51.759867 -316.702884) (xy 51.779158 -316.657608) (xy 51.805461 -316.616012) (xy 51.838096 -316.579175)
			(xy 51.876217 -316.54805) (xy 51.918838 -316.523443) (xy 51.964854 -316.505991) (xy 52.013073 -316.496147)
			(xy 52.062248 -316.494166) (xy 52.111103 -316.500098) (xy 52.158374 -316.51379) (xy 52.202836 -316.534888)
			(xy 52.243339 -316.562844) (xy 52.278832 -316.596936) (xy 52.308397 -316.63628) (xy 52.331268 -316.679857)
			(xy 52.346852 -316.726538) (xy 52.354747 -316.775115) (xy 52.355242 -316.799722) (xy 52.354747 -316.824329)
			(xy 52.354568 -316.82543) (xy 52.673246 -316.82543) (xy 52.673246 -316.774014) (xy 52.681289 -316.723232)
			(xy 52.697177 -316.674333) (xy 52.72052 -316.628521) (xy 52.750741 -316.586925) (xy 52.787097 -316.550569)
			(xy 52.828693 -316.520348) (xy 52.874505 -316.497005) (xy 52.923404 -316.481117) (xy 52.974186 -316.473074)
			(xy 53.025602 -316.473074) (xy 53.076384 -316.481117) (xy 53.125283 -316.497005) (xy 53.171095 -316.520348)
			(xy 53.212691 -316.550569) (xy 53.249047 -316.586925) (xy 53.279268 -316.628521) (xy 53.302611 -316.674333)
			(xy 53.318499 -316.723232) (xy 53.326542 -316.774014) (xy 53.327046 -316.799722) (xy 53.64405 -316.799722)
			(xy 53.64801 -316.750668) (xy 53.659787 -316.702884) (xy 53.679078 -316.657608) (xy 53.705381 -316.616012)
			(xy 53.738016 -316.579175) (xy 53.776137 -316.54805) (xy 53.818758 -316.523443) (xy 53.864774 -316.505991)
			(xy 53.912993 -316.496147) (xy 53.962168 -316.494166) (xy 54.011023 -316.500098) (xy 54.058294 -316.51379)
			(xy 54.102756 -316.534888) (xy 54.143259 -316.562844) (xy 54.178752 -316.596936) (xy 54.208317 -316.63628)
			(xy 54.231188 -316.679857) (xy 54.246772 -316.726538) (xy 54.254667 -316.775115) (xy 54.255162 -316.799722)
			(xy 54.254667 -316.824329) (xy 54.254488 -316.82543) (xy 54.573166 -316.82543) (xy 54.573166 -316.774014)
			(xy 54.581209 -316.723232) (xy 54.597097 -316.674333) (xy 54.62044 -316.628521) (xy 54.650661 -316.586925)
			(xy 54.687017 -316.550569) (xy 54.728613 -316.520348) (xy 54.774425 -316.497005) (xy 54.823324 -316.481117)
			(xy 54.874106 -316.473074) (xy 54.925522 -316.473074) (xy 54.976304 -316.481117) (xy 55.025203 -316.497005)
			(xy 55.071015 -316.520348) (xy 55.112611 -316.550569) (xy 55.148967 -316.586925) (xy 55.179188 -316.628521)
			(xy 55.202531 -316.674333) (xy 55.218419 -316.723232) (xy 55.226462 -316.774014) (xy 55.226966 -316.799722)
			(xy 55.54397 -316.799722) (xy 55.54793 -316.750668) (xy 55.559707 -316.702884) (xy 55.578998 -316.657608)
			(xy 55.605301 -316.616012) (xy 55.637936 -316.579175) (xy 55.676057 -316.54805) (xy 55.718678 -316.523443)
			(xy 55.764694 -316.505991) (xy 55.812913 -316.496147) (xy 55.862088 -316.494166) (xy 55.910943 -316.500098)
			(xy 55.958214 -316.51379) (xy 56.002676 -316.534888) (xy 56.043179 -316.562844) (xy 56.078672 -316.596936)
			(xy 56.108237 -316.63628) (xy 56.131108 -316.679857) (xy 56.146692 -316.726538) (xy 56.154587 -316.775115)
			(xy 56.155082 -316.799722) (xy 56.154587 -316.824329) (xy 56.154408 -316.82543) (xy 56.47334 -316.82543)
			(xy 56.47334 -316.774014) (xy 56.481383 -316.723232) (xy 56.497271 -316.674333) (xy 56.520614 -316.628521)
			(xy 56.550835 -316.586925) (xy 56.587191 -316.550569) (xy 56.628787 -316.520348) (xy 56.674599 -316.497005)
			(xy 56.723498 -316.481117) (xy 56.77428 -316.473074) (xy 56.825696 -316.473074) (xy 56.876478 -316.481117)
			(xy 56.925377 -316.497005) (xy 56.971189 -316.520348) (xy 57.012785 -316.550569) (xy 57.049141 -316.586925)
			(xy 57.079362 -316.628521) (xy 57.102705 -316.674333) (xy 57.118593 -316.723232) (xy 57.126636 -316.774014)
			(xy 57.12714 -316.799722) (xy 57.444144 -316.799722) (xy 57.448104 -316.750668) (xy 57.459881 -316.702884)
			(xy 57.479172 -316.657608) (xy 57.505475 -316.616012) (xy 57.53811 -316.579175) (xy 57.576231 -316.54805)
			(xy 57.618852 -316.523443) (xy 57.664868 -316.505991) (xy 57.713087 -316.496147) (xy 57.762262 -316.494166)
			(xy 57.811117 -316.500098) (xy 57.858388 -316.51379) (xy 57.90285 -316.534888) (xy 57.943353 -316.562844)
			(xy 57.978846 -316.596936) (xy 58.008411 -316.63628) (xy 58.031282 -316.679857) (xy 58.046866 -316.726538)
			(xy 58.054761 -316.775115) (xy 58.055256 -316.799722) (xy 58.054761 -316.824329) (xy 58.054582 -316.82543)
			(xy 58.37326 -316.82543) (xy 58.37326 -316.774014) (xy 58.381303 -316.723232) (xy 58.397191 -316.674333)
			(xy 58.420534 -316.628521) (xy 58.450755 -316.586925) (xy 58.487111 -316.550569) (xy 58.528707 -316.520348)
			(xy 58.574519 -316.497005) (xy 58.623418 -316.481117) (xy 58.6742 -316.473074) (xy 58.725616 -316.473074)
			(xy 58.776398 -316.481117) (xy 58.825297 -316.497005) (xy 58.871109 -316.520348) (xy 58.912705 -316.550569)
			(xy 58.949061 -316.586925) (xy 58.979282 -316.628521) (xy 59.002625 -316.674333) (xy 59.018513 -316.723232)
			(xy 59.026556 -316.774014) (xy 59.02706 -316.799722) (xy 59.344064 -316.799722) (xy 59.348024 -316.750668)
			(xy 59.359801 -316.702884) (xy 59.379092 -316.657608) (xy 59.405395 -316.616012) (xy 59.43803 -316.579175)
			(xy 59.476151 -316.54805) (xy 59.518772 -316.523443) (xy 59.564788 -316.505991) (xy 59.613007 -316.496147)
			(xy 59.662182 -316.494166) (xy 59.711037 -316.500098) (xy 59.758308 -316.51379) (xy 59.80277 -316.534888)
			(xy 59.843273 -316.562844) (xy 59.878766 -316.596936) (xy 59.908331 -316.63628) (xy 59.931202 -316.679857)
			(xy 59.946786 -316.726538) (xy 59.954681 -316.775115) (xy 59.955176 -316.799722) (xy 59.954681 -316.824329)
			(xy 59.954502 -316.82543) (xy 60.27318 -316.82543) (xy 60.27318 -316.774014) (xy 60.281223 -316.723232)
			(xy 60.297111 -316.674333) (xy 60.320454 -316.628521) (xy 60.350675 -316.586925) (xy 60.387031 -316.550569)
			(xy 60.428627 -316.520348) (xy 60.474439 -316.497005) (xy 60.523338 -316.481117) (xy 60.57412 -316.473074)
			(xy 60.625536 -316.473074) (xy 60.676318 -316.481117) (xy 60.725217 -316.497005) (xy 60.771029 -316.520348)
			(xy 60.812625 -316.550569) (xy 60.848981 -316.586925) (xy 60.879202 -316.628521) (xy 60.902545 -316.674333)
			(xy 60.918433 -316.723232) (xy 60.926476 -316.774014) (xy 60.92698 -316.799722) (xy 61.243984 -316.799722)
			(xy 61.247944 -316.750668) (xy 61.259721 -316.702884) (xy 61.279012 -316.657608) (xy 61.305315 -316.616012)
			(xy 61.33795 -316.579175) (xy 61.376071 -316.54805) (xy 61.418692 -316.523443) (xy 61.464708 -316.505991)
			(xy 61.512927 -316.496147) (xy 61.562102 -316.494166) (xy 61.610957 -316.500098) (xy 61.658228 -316.51379)
			(xy 61.70269 -316.534888) (xy 61.743193 -316.562844) (xy 61.778686 -316.596936) (xy 61.808251 -316.63628)
			(xy 61.831122 -316.679857) (xy 61.846706 -316.726538) (xy 61.854601 -316.775115) (xy 61.855096 -316.799722)
			(xy 61.854601 -316.824329) (xy 61.854422 -316.82543) (xy 62.1731 -316.82543) (xy 62.1731 -316.774014)
			(xy 62.181143 -316.723232) (xy 62.197031 -316.674333) (xy 62.220374 -316.628521) (xy 62.250595 -316.586925)
			(xy 62.286951 -316.550569) (xy 62.328547 -316.520348) (xy 62.374359 -316.497005) (xy 62.423258 -316.481117)
			(xy 62.47404 -316.473074) (xy 62.525456 -316.473074) (xy 62.576238 -316.481117) (xy 62.625137 -316.497005)
			(xy 62.670949 -316.520348) (xy 62.712545 -316.550569) (xy 62.748901 -316.586925) (xy 62.779122 -316.628521)
			(xy 62.802465 -316.674333) (xy 62.818353 -316.723232) (xy 62.826396 -316.774014) (xy 62.8269 -316.799722)
			(xy 63.144158 -316.799722) (xy 63.148118 -316.750668) (xy 63.159895 -316.702884) (xy 63.179186 -316.657608)
			(xy 63.205489 -316.616012) (xy 63.238124 -316.579175) (xy 63.276245 -316.54805) (xy 63.318866 -316.523443)
			(xy 63.364882 -316.505991) (xy 63.413101 -316.496147) (xy 63.462276 -316.494166) (xy 63.511131 -316.500098)
			(xy 63.558402 -316.51379) (xy 63.602864 -316.534888) (xy 63.643367 -316.562844) (xy 63.67886 -316.596936)
			(xy 63.708425 -316.63628) (xy 63.731296 -316.679857) (xy 63.74688 -316.726538) (xy 63.754775 -316.775115)
			(xy 63.75527 -316.799722) (xy 63.754775 -316.824329) (xy 63.754596 -316.82543) (xy 64.073274 -316.82543)
			(xy 64.073274 -316.774014) (xy 64.081317 -316.723232) (xy 64.097205 -316.674333) (xy 64.120548 -316.628521)
			(xy 64.150769 -316.586925) (xy 64.187125 -316.550569) (xy 64.228721 -316.520348) (xy 64.274533 -316.497005)
			(xy 64.323432 -316.481117) (xy 64.374214 -316.473074) (xy 64.42563 -316.473074) (xy 64.476412 -316.481117)
			(xy 64.525311 -316.497005) (xy 64.571123 -316.520348) (xy 64.612719 -316.550569) (xy 64.649075 -316.586925)
			(xy 64.679296 -316.628521) (xy 64.702639 -316.674333) (xy 64.718527 -316.723232) (xy 64.72657 -316.774014)
			(xy 64.727074 -316.799722) (xy 65.044078 -316.799722) (xy 65.048038 -316.750668) (xy 65.059815 -316.702884)
			(xy 65.079106 -316.657608) (xy 65.105409 -316.616012) (xy 65.138044 -316.579175) (xy 65.176165 -316.54805)
			(xy 65.218786 -316.523443) (xy 65.264802 -316.505991) (xy 65.313021 -316.496147) (xy 65.362196 -316.494166)
			(xy 65.411051 -316.500098) (xy 65.458322 -316.51379) (xy 65.502784 -316.534888) (xy 65.543287 -316.562844)
			(xy 65.57878 -316.596936) (xy 65.608345 -316.63628) (xy 65.631216 -316.679857) (xy 65.6468 -316.726538)
			(xy 65.654695 -316.775115) (xy 65.65519 -316.799722) (xy 65.654695 -316.824329) (xy 65.654516 -316.82543)
			(xy 65.973194 -316.82543) (xy 65.973194 -316.774014) (xy 65.981237 -316.723232) (xy 65.997125 -316.674333)
			(xy 66.020468 -316.628521) (xy 66.050689 -316.586925) (xy 66.087045 -316.550569) (xy 66.128641 -316.520348)
			(xy 66.174453 -316.497005) (xy 66.223352 -316.481117) (xy 66.274134 -316.473074) (xy 66.32555 -316.473074)
			(xy 66.376332 -316.481117) (xy 66.425231 -316.497005) (xy 66.471043 -316.520348) (xy 66.512639 -316.550569)
			(xy 66.548995 -316.586925) (xy 66.579216 -316.628521) (xy 66.602559 -316.674333) (xy 66.618447 -316.723232)
			(xy 66.62649 -316.774014) (xy 66.626994 -316.799722) (xy 66.943998 -316.799722) (xy 66.947958 -316.750668)
			(xy 66.959735 -316.702884) (xy 66.979026 -316.657608) (xy 67.005329 -316.616012) (xy 67.037964 -316.579175)
			(xy 67.076085 -316.54805) (xy 67.118706 -316.523443) (xy 67.164722 -316.505991) (xy 67.212941 -316.496147)
			(xy 67.262116 -316.494166) (xy 67.310971 -316.500098) (xy 67.358242 -316.51379) (xy 67.402704 -316.534888)
			(xy 67.443207 -316.562844) (xy 67.4787 -316.596936) (xy 67.508265 -316.63628) (xy 67.531136 -316.679857)
			(xy 67.54672 -316.726538) (xy 67.554615 -316.775115) (xy 67.55511 -316.799722) (xy 67.554615 -316.824329)
			(xy 67.554436 -316.82543) (xy 67.873114 -316.82543) (xy 67.873114 -316.774014) (xy 67.881157 -316.723232)
			(xy 67.897045 -316.674333) (xy 67.920388 -316.628521) (xy 67.950609 -316.586925) (xy 67.986965 -316.550569)
			(xy 68.028561 -316.520348) (xy 68.074373 -316.497005) (xy 68.123272 -316.481117) (xy 68.174054 -316.473074)
			(xy 68.22547 -316.473074) (xy 68.276252 -316.481117) (xy 68.325151 -316.497005) (xy 68.370963 -316.520348)
			(xy 68.412559 -316.550569) (xy 68.448915 -316.586925) (xy 68.479136 -316.628521) (xy 68.502479 -316.674333)
			(xy 68.518367 -316.723232) (xy 68.52641 -316.774014) (xy 68.526914 -316.799722) (xy 68.844172 -316.799722)
			(xy 68.848132 -316.750668) (xy 68.859909 -316.702884) (xy 68.8792 -316.657608) (xy 68.905503 -316.616012)
			(xy 68.938138 -316.579175) (xy 68.976259 -316.54805) (xy 69.01888 -316.523443) (xy 69.064896 -316.505991)
			(xy 69.113115 -316.496147) (xy 69.16229 -316.494166) (xy 69.211145 -316.500098) (xy 69.258416 -316.51379)
			(xy 69.302878 -316.534888) (xy 69.343381 -316.562844) (xy 69.378874 -316.596936) (xy 69.408439 -316.63628)
			(xy 69.43131 -316.679857) (xy 69.446894 -316.726538) (xy 69.454789 -316.775115) (xy 69.455284 -316.799722)
			(xy 69.454789 -316.824329) (xy 69.45461 -316.82543) (xy 69.773288 -316.82543) (xy 69.773288 -316.774014)
			(xy 69.781331 -316.723232) (xy 69.797219 -316.674333) (xy 69.820562 -316.628521) (xy 69.850783 -316.586925)
			(xy 69.887139 -316.550569) (xy 69.928735 -316.520348) (xy 69.974547 -316.497005) (xy 70.023446 -316.481117)
			(xy 70.074228 -316.473074) (xy 70.125644 -316.473074) (xy 70.176426 -316.481117) (xy 70.225325 -316.497005)
			(xy 70.271137 -316.520348) (xy 70.312733 -316.550569) (xy 70.349089 -316.586925) (xy 70.37931 -316.628521)
			(xy 70.402653 -316.674333) (xy 70.418541 -316.723232) (xy 70.426584 -316.774014) (xy 70.427088 -316.799722)
			(xy 70.744092 -316.799722) (xy 70.748052 -316.750668) (xy 70.759829 -316.702884) (xy 70.77912 -316.657608)
			(xy 70.805423 -316.616012) (xy 70.838058 -316.579175) (xy 70.876179 -316.54805) (xy 70.9188 -316.523443)
			(xy 70.964816 -316.505991) (xy 71.013035 -316.496147) (xy 71.06221 -316.494166) (xy 71.111065 -316.500098)
			(xy 71.158336 -316.51379) (xy 71.202798 -316.534888) (xy 71.243301 -316.562844) (xy 71.278794 -316.596936)
			(xy 71.308359 -316.63628) (xy 71.33123 -316.679857) (xy 71.346814 -316.726538) (xy 71.354709 -316.775115)
			(xy 71.355204 -316.799722) (xy 71.354709 -316.824329) (xy 71.346814 -316.872906) (xy 71.33123 -316.919587)
			(xy 71.308359 -316.963164) (xy 71.278794 -317.002508) (xy 71.243301 -317.0366) (xy 71.202798 -317.064556)
			(xy 71.158336 -317.085654) (xy 71.111065 -317.099346) (xy 71.06221 -317.105278) (xy 71.013035 -317.103297)
			(xy 70.964816 -317.093453) (xy 70.9188 -317.076001) (xy 70.876179 -317.051394) (xy 70.838058 -317.020269)
			(xy 70.805423 -316.983432) (xy 70.77912 -316.941836) (xy 70.759829 -316.89656) (xy 70.748052 -316.848776)
			(xy 70.744092 -316.799722) (xy 70.427088 -316.799722) (xy 70.426584 -316.82543) (xy 70.418541 -316.876212)
			(xy 70.402653 -316.925111) (xy 70.37931 -316.970923) (xy 70.349089 -317.012519) (xy 70.312733 -317.048875)
			(xy 70.271137 -317.079096) (xy 70.225325 -317.102439) (xy 70.176426 -317.118327) (xy 70.125644 -317.12637)
			(xy 70.074228 -317.12637) (xy 70.023446 -317.118327) (xy 69.974547 -317.102439) (xy 69.928735 -317.079096)
			(xy 69.887139 -317.048875) (xy 69.850783 -317.012519) (xy 69.820562 -316.970923) (xy 69.797219 -316.925111)
			(xy 69.781331 -316.876212) (xy 69.773288 -316.82543) (xy 69.45461 -316.82543) (xy 69.446894 -316.872906)
			(xy 69.43131 -316.919587) (xy 69.408439 -316.963164) (xy 69.378874 -317.002508) (xy 69.343381 -317.0366)
			(xy 69.302878 -317.064556) (xy 69.258416 -317.085654) (xy 69.211145 -317.099346) (xy 69.16229 -317.105278)
			(xy 69.113115 -317.103297) (xy 69.064896 -317.093453) (xy 69.01888 -317.076001) (xy 68.976259 -317.051394)
			(xy 68.938138 -317.020269) (xy 68.905503 -316.983432) (xy 68.8792 -316.941836) (xy 68.859909 -316.89656)
			(xy 68.848132 -316.848776) (xy 68.844172 -316.799722) (xy 68.526914 -316.799722) (xy 68.52641 -316.82543)
			(xy 68.518367 -316.876212) (xy 68.502479 -316.925111) (xy 68.479136 -316.970923) (xy 68.448915 -317.012519)
			(xy 68.412559 -317.048875) (xy 68.370963 -317.079096) (xy 68.325151 -317.102439) (xy 68.276252 -317.118327)
			(xy 68.22547 -317.12637) (xy 68.174054 -317.12637) (xy 68.123272 -317.118327) (xy 68.074373 -317.102439)
			(xy 68.028561 -317.079096) (xy 67.986965 -317.048875) (xy 67.950609 -317.012519) (xy 67.920388 -316.970923)
			(xy 67.897045 -316.925111) (xy 67.881157 -316.876212) (xy 67.873114 -316.82543) (xy 67.554436 -316.82543)
			(xy 67.54672 -316.872906) (xy 67.531136 -316.919587) (xy 67.508265 -316.963164) (xy 67.4787 -317.002508)
			(xy 67.443207 -317.0366) (xy 67.402704 -317.064556) (xy 67.358242 -317.085654) (xy 67.310971 -317.099346)
			(xy 67.262116 -317.105278) (xy 67.212941 -317.103297) (xy 67.164722 -317.093453) (xy 67.118706 -317.076001)
			(xy 67.076085 -317.051394) (xy 67.037964 -317.020269) (xy 67.005329 -316.983432) (xy 66.979026 -316.941836)
			(xy 66.959735 -316.89656) (xy 66.947958 -316.848776) (xy 66.943998 -316.799722) (xy 66.626994 -316.799722)
			(xy 66.62649 -316.82543) (xy 66.618447 -316.876212) (xy 66.602559 -316.925111) (xy 66.579216 -316.970923)
			(xy 66.548995 -317.012519) (xy 66.512639 -317.048875) (xy 66.471043 -317.079096) (xy 66.425231 -317.102439)
			(xy 66.376332 -317.118327) (xy 66.32555 -317.12637) (xy 66.274134 -317.12637) (xy 66.223352 -317.118327)
			(xy 66.174453 -317.102439) (xy 66.128641 -317.079096) (xy 66.087045 -317.048875) (xy 66.050689 -317.012519)
			(xy 66.020468 -316.970923) (xy 65.997125 -316.925111) (xy 65.981237 -316.876212) (xy 65.973194 -316.82543)
			(xy 65.654516 -316.82543) (xy 65.6468 -316.872906) (xy 65.631216 -316.919587) (xy 65.608345 -316.963164)
			(xy 65.57878 -317.002508) (xy 65.543287 -317.0366) (xy 65.502784 -317.064556) (xy 65.458322 -317.085654)
			(xy 65.411051 -317.099346) (xy 65.362196 -317.105278) (xy 65.313021 -317.103297) (xy 65.264802 -317.093453)
			(xy 65.218786 -317.076001) (xy 65.176165 -317.051394) (xy 65.138044 -317.020269) (xy 65.105409 -316.983432)
			(xy 65.079106 -316.941836) (xy 65.059815 -316.89656) (xy 65.048038 -316.848776) (xy 65.044078 -316.799722)
			(xy 64.727074 -316.799722) (xy 64.72657 -316.82543) (xy 64.718527 -316.876212) (xy 64.702639 -316.925111)
			(xy 64.679296 -316.970923) (xy 64.649075 -317.012519) (xy 64.612719 -317.048875) (xy 64.571123 -317.079096)
			(xy 64.525311 -317.102439) (xy 64.476412 -317.118327) (xy 64.42563 -317.12637) (xy 64.374214 -317.12637)
			(xy 64.323432 -317.118327) (xy 64.274533 -317.102439) (xy 64.228721 -317.079096) (xy 64.187125 -317.048875)
			(xy 64.150769 -317.012519) (xy 64.120548 -316.970923) (xy 64.097205 -316.925111) (xy 64.081317 -316.876212)
			(xy 64.073274 -316.82543) (xy 63.754596 -316.82543) (xy 63.74688 -316.872906) (xy 63.731296 -316.919587)
			(xy 63.708425 -316.963164) (xy 63.67886 -317.002508) (xy 63.643367 -317.0366) (xy 63.602864 -317.064556)
			(xy 63.558402 -317.085654) (xy 63.511131 -317.099346) (xy 63.462276 -317.105278) (xy 63.413101 -317.103297)
			(xy 63.364882 -317.093453) (xy 63.318866 -317.076001) (xy 63.276245 -317.051394) (xy 63.238124 -317.020269)
			(xy 63.205489 -316.983432) (xy 63.179186 -316.941836) (xy 63.159895 -316.89656) (xy 63.148118 -316.848776)
			(xy 63.144158 -316.799722) (xy 62.8269 -316.799722) (xy 62.826396 -316.82543) (xy 62.818353 -316.876212)
			(xy 62.802465 -316.925111) (xy 62.779122 -316.970923) (xy 62.748901 -317.012519) (xy 62.712545 -317.048875)
			(xy 62.670949 -317.079096) (xy 62.625137 -317.102439) (xy 62.576238 -317.118327) (xy 62.525456 -317.12637)
			(xy 62.47404 -317.12637) (xy 62.423258 -317.118327) (xy 62.374359 -317.102439) (xy 62.328547 -317.079096)
			(xy 62.286951 -317.048875) (xy 62.250595 -317.012519) (xy 62.220374 -316.970923) (xy 62.197031 -316.925111)
			(xy 62.181143 -316.876212) (xy 62.1731 -316.82543) (xy 61.854422 -316.82543) (xy 61.846706 -316.872906)
			(xy 61.831122 -316.919587) (xy 61.808251 -316.963164) (xy 61.778686 -317.002508) (xy 61.743193 -317.0366)
			(xy 61.70269 -317.064556) (xy 61.658228 -317.085654) (xy 61.610957 -317.099346) (xy 61.562102 -317.105278)
			(xy 61.512927 -317.103297) (xy 61.464708 -317.093453) (xy 61.418692 -317.076001) (xy 61.376071 -317.051394)
			(xy 61.33795 -317.020269) (xy 61.305315 -316.983432) (xy 61.279012 -316.941836) (xy 61.259721 -316.89656)
			(xy 61.247944 -316.848776) (xy 61.243984 -316.799722) (xy 60.92698 -316.799722) (xy 60.926476 -316.82543)
			(xy 60.918433 -316.876212) (xy 60.902545 -316.925111) (xy 60.879202 -316.970923) (xy 60.848981 -317.012519)
			(xy 60.812625 -317.048875) (xy 60.771029 -317.079096) (xy 60.725217 -317.102439) (xy 60.676318 -317.118327)
			(xy 60.625536 -317.12637) (xy 60.57412 -317.12637) (xy 60.523338 -317.118327) (xy 60.474439 -317.102439)
			(xy 60.428627 -317.079096) (xy 60.387031 -317.048875) (xy 60.350675 -317.012519) (xy 60.320454 -316.970923)
			(xy 60.297111 -316.925111) (xy 60.281223 -316.876212) (xy 60.27318 -316.82543) (xy 59.954502 -316.82543)
			(xy 59.946786 -316.872906) (xy 59.931202 -316.919587) (xy 59.908331 -316.963164) (xy 59.878766 -317.002508)
			(xy 59.843273 -317.0366) (xy 59.80277 -317.064556) (xy 59.758308 -317.085654) (xy 59.711037 -317.099346)
			(xy 59.662182 -317.105278) (xy 59.613007 -317.103297) (xy 59.564788 -317.093453) (xy 59.518772 -317.076001)
			(xy 59.476151 -317.051394) (xy 59.43803 -317.020269) (xy 59.405395 -316.983432) (xy 59.379092 -316.941836)
			(xy 59.359801 -316.89656) (xy 59.348024 -316.848776) (xy 59.344064 -316.799722) (xy 59.02706 -316.799722)
			(xy 59.026556 -316.82543) (xy 59.018513 -316.876212) (xy 59.002625 -316.925111) (xy 58.979282 -316.970923)
			(xy 58.949061 -317.012519) (xy 58.912705 -317.048875) (xy 58.871109 -317.079096) (xy 58.825297 -317.102439)
			(xy 58.776398 -317.118327) (xy 58.725616 -317.12637) (xy 58.6742 -317.12637) (xy 58.623418 -317.118327)
			(xy 58.574519 -317.102439) (xy 58.528707 -317.079096) (xy 58.487111 -317.048875) (xy 58.450755 -317.012519)
			(xy 58.420534 -316.970923) (xy 58.397191 -316.925111) (xy 58.381303 -316.876212) (xy 58.37326 -316.82543)
			(xy 58.054582 -316.82543) (xy 58.046866 -316.872906) (xy 58.031282 -316.919587) (xy 58.008411 -316.963164)
			(xy 57.978846 -317.002508) (xy 57.943353 -317.0366) (xy 57.90285 -317.064556) (xy 57.858388 -317.085654)
			(xy 57.811117 -317.099346) (xy 57.762262 -317.105278) (xy 57.713087 -317.103297) (xy 57.664868 -317.093453)
			(xy 57.618852 -317.076001) (xy 57.576231 -317.051394) (xy 57.53811 -317.020269) (xy 57.505475 -316.983432)
			(xy 57.479172 -316.941836) (xy 57.459881 -316.89656) (xy 57.448104 -316.848776) (xy 57.444144 -316.799722)
			(xy 57.12714 -316.799722) (xy 57.126636 -316.82543) (xy 57.118593 -316.876212) (xy 57.102705 -316.925111)
			(xy 57.079362 -316.970923) (xy 57.049141 -317.012519) (xy 57.012785 -317.048875) (xy 56.971189 -317.079096)
			(xy 56.925377 -317.102439) (xy 56.876478 -317.118327) (xy 56.825696 -317.12637) (xy 56.77428 -317.12637)
			(xy 56.723498 -317.118327) (xy 56.674599 -317.102439) (xy 56.628787 -317.079096) (xy 56.587191 -317.048875)
			(xy 56.550835 -317.012519) (xy 56.520614 -316.970923) (xy 56.497271 -316.925111) (xy 56.481383 -316.876212)
			(xy 56.47334 -316.82543) (xy 56.154408 -316.82543) (xy 56.146692 -316.872906) (xy 56.131108 -316.919587)
			(xy 56.108237 -316.963164) (xy 56.078672 -317.002508) (xy 56.043179 -317.0366) (xy 56.002676 -317.064556)
			(xy 55.958214 -317.085654) (xy 55.910943 -317.099346) (xy 55.862088 -317.105278) (xy 55.812913 -317.103297)
			(xy 55.764694 -317.093453) (xy 55.718678 -317.076001) (xy 55.676057 -317.051394) (xy 55.637936 -317.020269)
			(xy 55.605301 -316.983432) (xy 55.578998 -316.941836) (xy 55.559707 -316.89656) (xy 55.54793 -316.848776)
			(xy 55.54397 -316.799722) (xy 55.226966 -316.799722) (xy 55.226462 -316.82543) (xy 55.218419 -316.876212)
			(xy 55.202531 -316.925111) (xy 55.179188 -316.970923) (xy 55.148967 -317.012519) (xy 55.112611 -317.048875)
			(xy 55.071015 -317.079096) (xy 55.025203 -317.102439) (xy 54.976304 -317.118327) (xy 54.925522 -317.12637)
			(xy 54.874106 -317.12637) (xy 54.823324 -317.118327) (xy 54.774425 -317.102439) (xy 54.728613 -317.079096)
			(xy 54.687017 -317.048875) (xy 54.650661 -317.012519) (xy 54.62044 -316.970923) (xy 54.597097 -316.925111)
			(xy 54.581209 -316.876212) (xy 54.573166 -316.82543) (xy 54.254488 -316.82543) (xy 54.246772 -316.872906)
			(xy 54.231188 -316.919587) (xy 54.208317 -316.963164) (xy 54.178752 -317.002508) (xy 54.143259 -317.0366)
			(xy 54.102756 -317.064556) (xy 54.058294 -317.085654) (xy 54.011023 -317.099346) (xy 53.962168 -317.105278)
			(xy 53.912993 -317.103297) (xy 53.864774 -317.093453) (xy 53.818758 -317.076001) (xy 53.776137 -317.051394)
			(xy 53.738016 -317.020269) (xy 53.705381 -316.983432) (xy 53.679078 -316.941836) (xy 53.659787 -316.89656)
			(xy 53.64801 -316.848776) (xy 53.64405 -316.799722) (xy 53.327046 -316.799722) (xy 53.326542 -316.82543)
			(xy 53.318499 -316.876212) (xy 53.302611 -316.925111) (xy 53.279268 -316.970923) (xy 53.249047 -317.012519)
			(xy 53.212691 -317.048875) (xy 53.171095 -317.079096) (xy 53.125283 -317.102439) (xy 53.076384 -317.118327)
			(xy 53.025602 -317.12637) (xy 52.974186 -317.12637) (xy 52.923404 -317.118327) (xy 52.874505 -317.102439)
			(xy 52.828693 -317.079096) (xy 52.787097 -317.048875) (xy 52.750741 -317.012519) (xy 52.72052 -316.970923)
			(xy 52.697177 -316.925111) (xy 52.681289 -316.876212) (xy 52.673246 -316.82543) (xy 52.354568 -316.82543)
			(xy 52.346852 -316.872906) (xy 52.331268 -316.919587) (xy 52.308397 -316.963164) (xy 52.278832 -317.002508)
			(xy 52.243339 -317.0366) (xy 52.202836 -317.064556) (xy 52.158374 -317.085654) (xy 52.111103 -317.099346)
			(xy 52.062248 -317.105278) (xy 52.013073 -317.103297) (xy 51.964854 -317.093453) (xy 51.918838 -317.076001)
			(xy 51.876217 -317.051394) (xy 51.838096 -317.020269) (xy 51.805461 -316.983432) (xy 51.779158 -316.941836)
			(xy 51.759867 -316.89656) (xy 51.74809 -316.848776) (xy 51.74413 -316.799722) (xy 51.427126 -316.799722)
			(xy 51.426622 -316.82543) (xy 51.418579 -316.876212) (xy 51.402691 -316.925111) (xy 51.379348 -316.970923)
			(xy 51.349127 -317.012519) (xy 51.312771 -317.048875) (xy 51.271175 -317.079096) (xy 51.225363 -317.102439)
			(xy 51.176464 -317.118327) (xy 51.125682 -317.12637) (xy 51.074266 -317.12637) (xy 51.023484 -317.118327)
			(xy 50.974585 -317.102439) (xy 50.928773 -317.079096) (xy 50.887177 -317.048875) (xy 50.850821 -317.012519)
			(xy 50.8206 -316.970923) (xy 50.797257 -316.925111) (xy 50.781369 -316.876212) (xy 50.773326 -316.82543)
			(xy 50.454394 -316.82543) (xy 50.446678 -316.872906) (xy 50.431094 -316.919587) (xy 50.408223 -316.963164)
			(xy 50.378658 -317.002508) (xy 50.343165 -317.0366) (xy 50.302662 -317.064556) (xy 50.2582 -317.085654)
			(xy 50.210929 -317.099346) (xy 50.162074 -317.105278) (xy 50.112899 -317.103297) (xy 50.06468 -317.093453)
			(xy 50.018664 -317.076001) (xy 49.976043 -317.051394) (xy 49.937922 -317.020269) (xy 49.905287 -316.983432)
			(xy 49.878984 -316.941836) (xy 49.859693 -316.89656) (xy 49.847916 -316.848776) (xy 49.843956 -316.799722)
			(xy 49.526952 -316.799722) (xy 49.526448 -316.82543) (xy 49.518405 -316.876212) (xy 49.502517 -316.925111)
			(xy 49.479174 -316.970923) (xy 49.448953 -317.012519) (xy 49.412597 -317.048875) (xy 49.371001 -317.079096)
			(xy 49.325189 -317.102439) (xy 49.27629 -317.118327) (xy 49.225508 -317.12637) (xy 49.174092 -317.12637)
			(xy 49.12331 -317.118327) (xy 49.074411 -317.102439) (xy 49.028599 -317.079096) (xy 48.987003 -317.048875)
			(xy 48.950647 -317.012519) (xy 48.920426 -316.970923) (xy 48.897083 -316.925111) (xy 48.881195 -316.876212)
			(xy 48.873152 -316.82543) (xy 48.554474 -316.82543) (xy 48.546758 -316.872906) (xy 48.531174 -316.919587)
			(xy 48.508303 -316.963164) (xy 48.478738 -317.002508) (xy 48.443245 -317.0366) (xy 48.402742 -317.064556)
			(xy 48.35828 -317.085654) (xy 48.311009 -317.099346) (xy 48.262154 -317.105278) (xy 48.212979 -317.103297)
			(xy 48.16476 -317.093453) (xy 48.118744 -317.076001) (xy 48.076123 -317.051394) (xy 48.038002 -317.020269)
			(xy 48.005367 -316.983432) (xy 47.979064 -316.941836) (xy 47.959773 -316.89656) (xy 47.947996 -316.848776)
			(xy 47.944036 -316.799722) (xy 47.627032 -316.799722) (xy 47.626528 -316.82543) (xy 47.618485 -316.876212)
			(xy 47.602597 -316.925111) (xy 47.579254 -316.970923) (xy 47.549033 -317.012519) (xy 47.512677 -317.048875)
			(xy 47.471081 -317.079096) (xy 47.425269 -317.102439) (xy 47.37637 -317.118327) (xy 47.325588 -317.12637)
			(xy 47.274172 -317.12637) (xy 47.22339 -317.118327) (xy 47.174491 -317.102439) (xy 47.128679 -317.079096)
			(xy 47.087083 -317.048875) (xy 47.050727 -317.012519) (xy 47.020506 -316.970923) (xy 46.997163 -316.925111)
			(xy 46.981275 -316.876212) (xy 46.973232 -316.82543) (xy 46.654554 -316.82543) (xy 46.646838 -316.872906)
			(xy 46.631254 -316.919587) (xy 46.608383 -316.963164) (xy 46.578818 -317.002508) (xy 46.543325 -317.0366)
			(xy 46.502822 -317.064556) (xy 46.45836 -317.085654) (xy 46.411089 -317.099346) (xy 46.362234 -317.105278)
			(xy 46.313059 -317.103297) (xy 46.26484 -317.093453) (xy 46.218824 -317.076001) (xy 46.176203 -317.051394)
			(xy 46.138082 -317.020269) (xy 46.105447 -316.983432) (xy 46.079144 -316.941836) (xy 46.059853 -316.89656)
			(xy 46.048076 -316.848776) (xy 46.044116 -316.799722) (xy 45.727112 -316.799722) (xy 45.726608 -316.82543)
			(xy 45.718565 -316.876212) (xy 45.702677 -316.925111) (xy 45.679334 -316.970923) (xy 45.649113 -317.012519)
			(xy 45.612757 -317.048875) (xy 45.571161 -317.079096) (xy 45.525349 -317.102439) (xy 45.47645 -317.118327)
			(xy 45.425668 -317.12637) (xy 45.374252 -317.12637) (xy 45.32347 -317.118327) (xy 45.274571 -317.102439)
			(xy 45.228759 -317.079096) (xy 45.187163 -317.048875) (xy 45.150807 -317.012519) (xy 45.120586 -316.970923)
			(xy 45.097243 -316.925111) (xy 45.081355 -316.876212) (xy 45.073312 -316.82543) (xy 44.75438 -316.82543)
			(xy 44.746664 -316.872906) (xy 44.73108 -316.919587) (xy 44.708209 -316.963164) (xy 44.678644 -317.002508)
			(xy 44.643151 -317.0366) (xy 44.602648 -317.064556) (xy 44.558186 -317.085654) (xy 44.510915 -317.099346)
			(xy 44.46206 -317.105278) (xy 44.412885 -317.103297) (xy 44.364666 -317.093453) (xy 44.31865 -317.076001)
			(xy 44.276029 -317.051394) (xy 44.237908 -317.020269) (xy 44.205273 -316.983432) (xy 44.17897 -316.941836)
			(xy 44.159679 -316.89656) (xy 44.147902 -316.848776) (xy 44.143942 -316.799722) (xy 43.826938 -316.799722)
			(xy 43.826434 -316.82543) (xy 43.818391 -316.876212) (xy 43.802503 -316.925111) (xy 43.77916 -316.970923)
			(xy 43.748939 -317.012519) (xy 43.712583 -317.048875) (xy 43.670987 -317.079096) (xy 43.625175 -317.102439)
			(xy 43.576276 -317.118327) (xy 43.525494 -317.12637) (xy 43.474078 -317.12637) (xy 43.423296 -317.118327)
			(xy 43.374397 -317.102439) (xy 43.328585 -317.079096) (xy 43.286989 -317.048875) (xy 43.250633 -317.012519)
			(xy 43.220412 -316.970923) (xy 43.197069 -316.925111) (xy 43.181181 -316.876212) (xy 43.173138 -316.82543)
			(xy 42.85446 -316.82543) (xy 42.846744 -316.872906) (xy 42.83116 -316.919587) (xy 42.808289 -316.963164)
			(xy 42.778724 -317.002508) (xy 42.743231 -317.0366) (xy 42.702728 -317.064556) (xy 42.658266 -317.085654)
			(xy 42.610995 -317.099346) (xy 42.56214 -317.105278) (xy 42.512965 -317.103297) (xy 42.464746 -317.093453)
			(xy 42.41873 -317.076001) (xy 42.376109 -317.051394) (xy 42.337988 -317.020269) (xy 42.305353 -316.983432)
			(xy 42.27905 -316.941836) (xy 42.259759 -316.89656) (xy 42.247982 -316.848776) (xy 42.244022 -316.799722)
			(xy 41.927018 -316.799722) (xy 41.926514 -316.82543) (xy 41.918471 -316.876212) (xy 41.902583 -316.925111)
			(xy 41.87924 -316.970923) (xy 41.849019 -317.012519) (xy 41.812663 -317.048875) (xy 41.771067 -317.079096)
			(xy 41.725255 -317.102439) (xy 41.676356 -317.118327) (xy 41.625574 -317.12637) (xy 41.574158 -317.12637)
			(xy 41.523376 -317.118327) (xy 41.474477 -317.102439) (xy 41.428665 -317.079096) (xy 41.387069 -317.048875)
			(xy 41.350713 -317.012519) (xy 41.320492 -316.970923) (xy 41.297149 -316.925111) (xy 41.281261 -316.876212)
			(xy 41.273218 -316.82543) (xy 40.95454 -316.82543) (xy 40.946824 -316.872906) (xy 40.93124 -316.919587)
			(xy 40.908369 -316.963164) (xy 40.878804 -317.002508) (xy 40.843311 -317.0366) (xy 40.802808 -317.064556)
			(xy 40.758346 -317.085654) (xy 40.711075 -317.099346) (xy 40.66222 -317.105278) (xy 40.613045 -317.103297)
			(xy 40.564826 -317.093453) (xy 40.51881 -317.076001) (xy 40.476189 -317.051394) (xy 40.438068 -317.020269)
			(xy 40.405433 -316.983432) (xy 40.37913 -316.941836) (xy 40.359839 -316.89656) (xy 40.348062 -316.848776)
			(xy 40.344102 -316.799722) (xy 40.027098 -316.799722) (xy 40.026594 -316.82543) (xy 40.018551 -316.876212)
			(xy 40.002663 -316.925111) (xy 39.97932 -316.970923) (xy 39.949099 -317.012519) (xy 39.912743 -317.048875)
			(xy 39.871147 -317.079096) (xy 39.825335 -317.102439) (xy 39.776436 -317.118327) (xy 39.725654 -317.12637)
			(xy 39.674238 -317.12637) (xy 39.623456 -317.118327) (xy 39.574557 -317.102439) (xy 39.528745 -317.079096)
			(xy 39.487149 -317.048875) (xy 39.450793 -317.012519) (xy 39.420572 -316.970923) (xy 39.397229 -316.925111)
			(xy 39.381341 -316.876212) (xy 39.373298 -316.82543) (xy 39.05462 -316.82543) (xy 39.046904 -316.872906)
			(xy 39.03132 -316.919587) (xy 39.008449 -316.963164) (xy 38.978884 -317.002508) (xy 38.943391 -317.0366)
			(xy 38.902888 -317.064556) (xy 38.858426 -317.085654) (xy 38.811155 -317.099346) (xy 38.7623 -317.105278)
			(xy 38.713125 -317.103297) (xy 38.664906 -317.093453) (xy 38.61889 -317.076001) (xy 38.576269 -317.051394)
			(xy 38.538148 -317.020269) (xy 38.505513 -316.983432) (xy 38.47921 -316.941836) (xy 38.459919 -316.89656)
			(xy 38.448142 -316.848776) (xy 38.444182 -316.799722) (xy 38.126924 -316.799722) (xy 38.12642 -316.82543)
			(xy 38.118377 -316.876212) (xy 38.102489 -316.925111) (xy 38.079146 -316.970923) (xy 38.048925 -317.012519)
			(xy 38.012569 -317.048875) (xy 37.970973 -317.079096) (xy 37.925161 -317.102439) (xy 37.876262 -317.118327)
			(xy 37.82548 -317.12637) (xy 37.774064 -317.12637) (xy 37.723282 -317.118327) (xy 37.674383 -317.102439)
			(xy 37.628571 -317.079096) (xy 37.586975 -317.048875) (xy 37.550619 -317.012519) (xy 37.520398 -316.970923)
			(xy 37.497055 -316.925111) (xy 37.481167 -316.876212) (xy 37.473124 -316.82543) (xy 37.17646 -316.82543)
			(xy 37.168417 -316.876212) (xy 37.152529 -316.925111) (xy 37.129186 -316.970923) (xy 37.098965 -317.012519)
			(xy 37.062609 -317.048875) (xy 37.021013 -317.079096) (xy 36.975201 -317.102439) (xy 36.926302 -317.118327)
			(xy 36.87552 -317.12637) (xy 36.824104 -317.12637) (xy 36.773322 -317.118327) (xy 36.724423 -317.102439)
			(xy 36.678611 -317.079096) (xy 36.637015 -317.048875) (xy 36.600659 -317.012519) (xy 36.570438 -316.970923)
			(xy 36.547095 -316.925111) (xy 36.531207 -316.876212) (xy 36.523164 -316.82543) (xy 36.203937 -316.82543)
			(xy 36.196262 -316.872652) (xy 36.180678 -316.919333) (xy 36.157807 -316.96291) (xy 36.128242 -317.002254)
			(xy 36.092749 -317.036346) (xy 36.052246 -317.064302) (xy 36.007784 -317.0854) (xy 35.960513 -317.099092)
			(xy 35.911658 -317.105024) (xy 35.862483 -317.103043) (xy 35.814264 -317.093199) (xy 35.768248 -317.075747)
			(xy 35.725627 -317.05114) (xy 35.687506 -317.020015) (xy 35.654871 -316.983178) (xy 35.628568 -316.941582)
			(xy 35.609277 -316.896306) (xy 35.5975 -316.848522) (xy 35.59354 -316.799468) (xy 32.097753 -316.799468)
			(xy 32.140287 -316.824287) (xy 32.30379 -316.92882) (xy 32.462912 -317.039909) (xy 32.61739 -317.15737)
			(xy 32.76697 -317.281009) (xy 32.911404 -317.410622) (xy 33.050454 -317.545995) (xy 33.18389 -317.686904)
			(xy 33.238899 -317.749936) (xy 36.544008 -317.749936) (xy 36.547968 -317.700882) (xy 36.559745 -317.653098)
			(xy 36.579036 -317.607822) (xy 36.605339 -317.566226) (xy 36.637974 -317.529389) (xy 36.676095 -317.498264)
			(xy 36.718716 -317.473657) (xy 36.764732 -317.456205) (xy 36.812951 -317.446361) (xy 36.862126 -317.44438)
			(xy 36.910981 -317.450312) (xy 36.958252 -317.464004) (xy 37.002714 -317.485102) (xy 37.043217 -317.513058)
			(xy 37.07871 -317.54715) (xy 37.108275 -317.586494) (xy 37.131146 -317.630071) (xy 37.14673 -317.676752)
			(xy 37.154625 -317.725329) (xy 37.15512 -317.749936) (xy 37.154625 -317.774543) (xy 37.14673 -317.82312)
			(xy 37.131146 -317.869801) (xy 37.108275 -317.913378) (xy 37.07871 -317.952722) (xy 37.043217 -317.986814)
			(xy 37.002714 -318.01477) (xy 36.958252 -318.035868) (xy 36.910981 -318.04956) (xy 36.862126 -318.055492)
			(xy 36.812951 -318.053511) (xy 36.764732 -318.043667) (xy 36.718716 -318.026215) (xy 36.676095 -318.001608)
			(xy 36.637974 -317.970483) (xy 36.605339 -317.933646) (xy 36.579036 -317.89205) (xy 36.559745 -317.846774)
			(xy 36.547968 -317.79899) (xy 36.544008 -317.749936) (xy 33.238899 -317.749936) (xy 33.311492 -317.833117)
			(xy 33.433049 -317.984393) (xy 33.548362 -318.140482) (xy 33.657238 -318.301126) (xy 33.7595 -318.46606)
			(xy 33.854977 -318.635011) (xy 33.943513 -318.807702) (xy 34.024961 -318.983846) (xy 34.099187 -319.163154)
			(xy 34.166067 -319.345328) (xy 34.225493 -319.530069) (xy 34.2519 -319.62344) (xy 34.2519 -319.623694)
			(xy 34.254485 -319.631529) (xy 34.263815 -319.645124) (xy 34.270188 -319.650364) (xy 34.291778 -319.666874)
			(xy 34.298562 -319.671623) (xy 34.314238 -319.676928) (xy 34.322512 -319.677288) (xy 37.969698 -319.677288)
			(xy 37.975286 -319.677034) (xy 37.986871 -319.675106) (xy 38.006596 -319.662407) (xy 38.013132 -319.65265)
			(xy 38.027334 -319.630073) (xy 38.062332 -319.589828) (xy 38.082728 -319.57264) (xy 38.087554 -319.56883)
			(xy 38.094666 -319.559432) (xy 38.101524 -319.543684) (xy 38.101524 -319.532762) (xy 38.10127 -319.471294)
			(xy 38.090094 -319.449704) (xy 38.080188 -319.442592) (xy 38.059495 -319.426919) (xy 38.022798 -319.390208)
			(xy 37.992289 -319.348212) (xy 37.968719 -319.301965) (xy 37.952666 -319.252602) (xy 37.944525 -319.201337)
			(xy 37.944044 -319.175384) (xy 37.944044 -319.104518) (xy 37.943487 -319.093824) (xy 37.934832 -319.074263)
			(xy 37.92728 -319.066672) (xy 37.863018 -319.009014) (xy 37.842698 -319.00241) (xy 37.831776 -319.003426)
			(xy 37.799772 -319.005204) (xy 37.774519 -319.00468) (xy 37.724701 -318.996363) (xy 37.676932 -318.97996)
			(xy 37.632514 -318.955918) (xy 37.592658 -318.924894) (xy 37.558452 -318.887734) (xy 37.530829 -318.84545)
			(xy 37.510542 -318.799196) (xy 37.498144 -318.750235) (xy 37.493973 -318.6999) (xy 37.498144 -318.649565)
			(xy 37.510542 -318.600604) (xy 37.530829 -318.55435) (xy 37.558452 -318.512066) (xy 37.592658 -318.474906)
			(xy 37.632514 -318.443882) (xy 37.676932 -318.41984) (xy 37.724701 -318.403437) (xy 37.774519 -318.39512)
			(xy 37.799772 -318.394588) (xy 37.831776 -318.396366) (xy 37.842698 -318.397382) (xy 37.863018 -318.390778)
			(xy 37.92728 -318.33312) (xy 37.934941 -318.325603) (xy 37.943629 -318.305999) (xy 37.944044 -318.295274)
			(xy 37.944044 -318.224916) (xy 37.944207 -318.211262) (xy 37.946498 -318.18405) (xy 37.948616 -318.17056)
			(xy 37.950648 -318.158622) (xy 37.943536 -318.136016) (xy 37.870638 -318.059562) (xy 37.848286 -318.051688)
			(xy 37.836094 -318.052958) (xy 37.82705 -318.054005) (xy 37.808876 -318.055147) (xy 37.799772 -318.055244)
			(xy 37.774948 -318.054756) (xy 37.725955 -318.046719) (xy 37.678908 -318.030862) (xy 37.635045 -318.007602)
			(xy 37.595524 -317.977553) (xy 37.561385 -317.941506) (xy 37.533527 -317.90041) (xy 37.512685 -317.855349)
			(xy 37.499407 -317.807509) (xy 37.494044 -317.758152) (xy 37.496737 -317.708577) (xy 37.507415 -317.660091)
			(xy 37.525796 -317.613971) (xy 37.551397 -317.571433) (xy 37.583542 -317.533597) (xy 37.621385 -317.501459)
			(xy 37.663929 -317.475868) (xy 37.710053 -317.457496) (xy 37.758541 -317.446829) (xy 37.808116 -317.444146)
			(xy 37.857472 -317.449519) (xy 37.905309 -317.462807) (xy 37.950366 -317.483658) (xy 37.991456 -317.511525)
			(xy 38.027496 -317.545672) (xy 38.057537 -317.585199) (xy 38.080787 -317.629067) (xy 38.096635 -317.676117)
			(xy 38.104661 -317.725112) (xy 38.10508 -317.749936) (xy 38.104982 -317.75904) (xy 38.103839 -317.777213)
			(xy 38.102794 -317.786258) (xy 38.101524 -317.79845) (xy 38.109398 -317.820802) (xy 38.185852 -317.8937)
			(xy 38.208458 -317.900812) (xy 38.220396 -317.89878) (xy 38.233884 -317.896647) (xy 38.261097 -317.894355)
			(xy 38.274752 -317.894208) (xy 38.28417 -317.894244) (xy 38.302977 -317.895262) (xy 38.312344 -317.89624)
			(xy 38.323774 -317.897764) (xy 38.345618 -317.890144) (xy 38.418262 -317.817754) (xy 38.426136 -317.796164)
			(xy 38.424866 -317.784734) (xy 38.423088 -317.749936) (xy 38.423564 -317.724225) (xy 38.431603 -317.673436)
			(xy 38.447491 -317.62453) (xy 38.470834 -317.578712) (xy 38.501059 -317.537111) (xy 38.53742 -317.500751)
			(xy 38.579022 -317.470528) (xy 38.624841 -317.447186) (xy 38.673747 -317.431301) (xy 38.724536 -317.423263)
			(xy 38.775958 -317.42327) (xy 38.826745 -317.431323) (xy 38.875647 -317.447223) (xy 38.921459 -317.470578)
			(xy 38.963052 -317.500813) (xy 38.999403 -317.537183) (xy 39.029616 -317.578793) (xy 39.052946 -317.624618)
			(xy 39.068819 -317.673528) (xy 39.076844 -317.72432) (xy 39.076823 -317.775741) (xy 39.068758 -317.826526)
			(xy 39.052845 -317.875424) (xy 39.029479 -317.92123) (xy 38.999233 -317.962816) (xy 38.962853 -317.999157)
			(xy 38.921236 -318.029359) (xy 38.875405 -318.052678) (xy 38.826491 -318.068538) (xy 38.775697 -318.07655)
			(xy 38.749986 -318.077088) (xy 38.715188 -318.075056) (xy 38.703504 -318.073786) (xy 38.681914 -318.081406)
			(xy 38.609524 -318.154304) (xy 38.601904 -318.175894) (xy 38.603428 -318.187578) (xy 38.604398 -318.196882)
			(xy 38.605416 -318.215562) (xy 38.60546 -318.224916) (xy 38.60546 -318.27343) (xy 38.605927 -318.284085)
			(xy 38.614625 -318.303537) (xy 38.622224 -318.311022) (xy 38.686232 -318.368934) (xy 38.706298 -318.375538)
			(xy 38.71722 -318.374522) (xy 38.749986 -318.372744) (xy 38.775697 -318.373221) (xy 38.826486 -318.381263)
			(xy 38.875391 -318.397152) (xy 38.921209 -318.420495) (xy 38.96281 -318.450719) (xy 38.999172 -318.487079)
			(xy 39.029397 -318.528679) (xy 39.052743 -318.574496) (xy 39.068633 -318.623401) (xy 39.076678 -318.674189)
			(xy 39.076678 -318.725611) (xy 39.068633 -318.776399) (xy 39.052743 -318.825304) (xy 39.029397 -318.871121)
			(xy 38.999172 -318.912721) (xy 38.96281 -318.949081) (xy 38.921209 -318.979305) (xy 38.875391 -319.002648)
			(xy 38.826486 -319.018537) (xy 38.775697 -319.026579) (xy 38.749986 -319.027048) (xy 38.71722 -319.02527)
			(xy 38.706298 -319.024254) (xy 38.686232 -319.030858) (xy 38.622224 -319.08877) (xy 38.614712 -319.096314)
			(xy 38.606044 -319.115733) (xy 38.60546 -319.126362) (xy 38.60546 -319.17513) (xy 38.605299 -319.188784)
			(xy 38.603013 -319.215997) (xy 38.600888 -319.229486) (xy 38.598856 -319.241424) (xy 38.605968 -319.26403)
			(xy 38.678866 -319.340484) (xy 38.701218 -319.348358) (xy 38.71341 -319.347088) (xy 38.722518 -319.346034)
			(xy 38.740818 -319.344891) (xy 38.749986 -319.344802) (xy 38.775513 -319.345317) (xy 38.825856 -319.35381)
			(xy 38.874084 -319.370561) (xy 38.918852 -319.395104) (xy 38.958912 -319.426754) (xy 38.993147 -319.464629)
			(xy 39.020602 -319.507672) (xy 39.040513 -319.554684) (xy 39.052323 -319.604353) (xy 39.054532 -319.62979)
			(xy 39.056056 -319.649856) (xy 39.085266 -319.677288) (xy 39.869618 -319.677288) (xy 39.875206 -319.677034)
			(xy 39.886788 -319.675102) (xy 39.906507 -319.662399) (xy 39.913052 -319.65265) (xy 39.927255 -319.630074)
			(xy 39.962254 -319.589831) (xy 39.982648 -319.57264) (xy 39.987474 -319.56883) (xy 39.994586 -319.559432)
			(xy 40.001444 -319.543684) (xy 40.001444 -319.532762) (xy 40.00119 -319.471294) (xy 39.990014 -319.449704)
			(xy 39.980108 -319.442592) (xy 39.959414 -319.42692) (xy 39.922715 -319.390209) (xy 39.892204 -319.348214)
			(xy 39.868632 -319.301967) (xy 39.852578 -319.252604) (xy 39.844437 -319.201338) (xy 39.843964 -319.175384)
			(xy 39.843964 -319.104518) (xy 39.843507 -319.093858) (xy 39.834825 -319.074389) (xy 39.8272 -319.066926)
			(xy 39.762938 -319.009014) (xy 39.742618 -319.00241) (xy 39.731696 -319.003426) (xy 39.699946 -319.005204)
			(xy 39.674686 -319.004715) (xy 39.624854 -318.996406) (xy 39.57707 -318.980008) (xy 39.532637 -318.955968)
			(xy 39.492767 -318.924942) (xy 39.458549 -318.887776) (xy 39.430915 -318.845484) (xy 39.410619 -318.79922)
			(xy 39.398216 -318.750247) (xy 39.394044 -318.6999) (xy 39.398216 -318.649553) (xy 39.410619 -318.60058)
			(xy 39.430915 -318.554316) (xy 39.458549 -318.512024) (xy 39.492767 -318.474858) (xy 39.532637 -318.443832)
			(xy 39.57707 -318.419792) (xy 39.624854 -318.403394) (xy 39.674686 -318.395085) (xy 39.699946 -318.394588)
			(xy 39.731696 -318.396366) (xy 39.742618 -318.397382) (xy 39.762938 -318.390778) (xy 39.8272 -318.332866)
			(xy 39.834699 -318.325317) (xy 39.843338 -318.305898) (xy 39.843964 -318.295274) (xy 39.843964 -318.224916)
			(xy 39.844127 -318.211262) (xy 39.846418 -318.18405) (xy 39.848536 -318.17056) (xy 39.850568 -318.158622)
			(xy 39.843456 -318.136016) (xy 39.770558 -318.059562) (xy 39.748206 -318.051688) (xy 39.736268 -318.053212)
			(xy 39.727221 -318.054202) (xy 39.709047 -318.055219) (xy 39.699946 -318.055244) (xy 39.675121 -318.054762)
			(xy 39.626123 -318.046736) (xy 39.57907 -318.030889) (xy 39.5352 -318.007638) (xy 39.495671 -317.977595)
			(xy 39.461522 -317.941553) (xy 39.433655 -317.90046) (xy 39.412804 -317.8554) (xy 39.399517 -317.807561)
			(xy 39.394146 -317.758202) (xy 39.396831 -317.708624) (xy 39.407502 -317.660134) (xy 39.425877 -317.614009)
			(xy 39.451474 -317.571465) (xy 39.483616 -317.533623) (xy 39.521457 -317.501479) (xy 39.564 -317.475882)
			(xy 39.610124 -317.457505) (xy 39.658614 -317.446832) (xy 39.708192 -317.444145) (xy 39.757551 -317.449515)
			(xy 39.805391 -317.4628) (xy 39.850451 -317.48365) (xy 39.891545 -317.511516) (xy 39.927588 -317.545663)
			(xy 39.957632 -317.585192) (xy 39.980885 -317.629061) (xy 39.996734 -317.676114) (xy 40.004761 -317.725111)
			(xy 40.005254 -317.749936) (xy 40.005156 -317.75904) (xy 40.004013 -317.777213) (xy 40.002968 -317.786258)
			(xy 40.001698 -317.79845) (xy 40.009572 -317.820802) (xy 40.086026 -317.8937) (xy 40.108632 -317.900558)
			(xy 40.12057 -317.89878) (xy 40.133995 -317.896659) (xy 40.161081 -317.894366) (xy 40.174672 -317.894208)
			(xy 40.18409 -317.894245) (xy 40.202897 -317.895263) (xy 40.212264 -317.89624) (xy 40.223694 -317.897764)
			(xy 40.245538 -317.890144) (xy 40.318182 -317.817754) (xy 40.326056 -317.796164) (xy 40.324786 -317.784734)
			(xy 40.323008 -317.749936) (xy 40.323484 -317.724218) (xy 40.331526 -317.673413) (xy 40.347419 -317.624493)
			(xy 40.370771 -317.578663) (xy 40.401005 -317.53705) (xy 40.437379 -317.500681) (xy 40.478995 -317.470451)
			(xy 40.524828 -317.447105) (xy 40.57375 -317.431218) (xy 40.624555 -317.423181) (xy 40.675992 -317.423193)
			(xy 40.726794 -317.431252) (xy 40.775708 -317.447161) (xy 40.821531 -317.470528) (xy 40.863134 -317.500777)
			(xy 40.899491 -317.537163) (xy 40.929707 -317.578789) (xy 40.953037 -317.62463) (xy 40.968908 -317.673558)
			(xy 40.976928 -317.724365) (xy 40.976899 -317.775802) (xy 40.968822 -317.826601) (xy 40.952896 -317.87551)
			(xy 40.929514 -317.921325) (xy 40.899251 -317.962918) (xy 40.862853 -317.999262) (xy 40.821217 -318.029464)
			(xy 40.775368 -318.05278) (xy 40.726435 -318.068634) (xy 40.675625 -318.076636) (xy 40.649906 -318.077088)
			(xy 40.615108 -318.075056) (xy 40.603424 -318.073786) (xy 40.581834 -318.081406) (xy 40.509444 -318.154304)
			(xy 40.501824 -318.175894) (xy 40.503348 -318.187578) (xy 40.504318 -318.196882) (xy 40.505336 -318.215562)
			(xy 40.50538 -318.224916) (xy 40.50538 -318.27343) (xy 40.505845 -318.284087) (xy 40.514532 -318.303548)
			(xy 40.522144 -318.311022) (xy 40.586152 -318.368934) (xy 40.606218 -318.375538) (xy 40.61714 -318.374522)
			(xy 40.649906 -318.372744) (xy 40.675614 -318.373249) (xy 40.726396 -318.381293) (xy 40.775295 -318.397182)
			(xy 40.821106 -318.420524) (xy 40.862702 -318.450746) (xy 40.899058 -318.487103) (xy 40.929279 -318.528699)
			(xy 40.952621 -318.574511) (xy 40.968509 -318.62341) (xy 40.976552 -318.674192) (xy 40.976552 -318.725608)
			(xy 40.968509 -318.77639) (xy 40.952621 -318.825289) (xy 40.929279 -318.871101) (xy 40.899058 -318.912697)
			(xy 40.862702 -318.949054) (xy 40.821106 -318.979276) (xy 40.775295 -319.002618) (xy 40.726396 -319.018507)
			(xy 40.675614 -319.026551) (xy 40.649906 -319.027048) (xy 40.61714 -319.02527) (xy 40.606218 -319.024254)
			(xy 40.586152 -319.030858) (xy 40.522144 -319.08877) (xy 40.51463 -319.096313) (xy 40.505958 -319.115732)
			(xy 40.50538 -319.126362) (xy 40.50538 -319.17513) (xy 40.505219 -319.188784) (xy 40.502933 -319.215997)
			(xy 40.500808 -319.229486) (xy 40.498776 -319.241424) (xy 40.505888 -319.26403) (xy 40.578786 -319.340484)
			(xy 40.601138 -319.348358) (xy 40.61333 -319.347088) (xy 40.622438 -319.346035) (xy 40.640738 -319.344893)
			(xy 40.649906 -319.344802) (xy 40.675437 -319.34531) (xy 40.72579 -319.353793) (xy 40.774029 -319.370537)
			(xy 40.818809 -319.395076) (xy 40.858881 -319.426725) (xy 40.893126 -319.464602) (xy 40.92059 -319.507649)
			(xy 40.940507 -319.554667) (xy 40.952322 -319.604344) (xy 40.954452 -319.62979) (xy 40.955976 -319.649856)
			(xy 40.985186 -319.677288) (xy 41.769538 -319.677288) (xy 41.775126 -319.677034) (xy 41.785369 -319.675354)
			(xy 41.803322 -319.66498) (xy 41.809924 -319.656968) (xy 41.812972 -319.65265) (xy 41.81906 -319.642687)
			(xy 41.832539 -319.623617) (xy 41.839896 -319.61455) (xy 41.849582 -319.603181) (xy 41.870831 -319.58219)
			(xy 41.882314 -319.57264) (xy 41.882568 -319.572386) (xy 41.882822 -319.572132) (xy 41.886964 -319.568552)
			(xy 41.893755 -319.559969) (xy 41.896284 -319.555114) (xy 41.896284 -319.55486) (xy 41.898631 -319.549638)
			(xy 41.901202 -319.538485) (xy 41.901364 -319.532762) (xy 41.90111 -319.483486) (xy 41.900488 -319.471641)
			(xy 41.889891 -319.450453) (xy 41.88079 -319.442846) (xy 41.880282 -319.442592) (xy 41.880028 -319.442338)
			(xy 41.859325 -319.426648) (xy 41.822615 -319.389898) (xy 41.792105 -319.347858) (xy 41.768545 -319.301565)
			(xy 41.752515 -319.252156) (xy 41.744411 -319.200848) (xy 41.743884 -319.174876) (xy 41.743884 -319.104518)
			(xy 41.743428 -319.093858) (xy 41.734748 -319.074387) (xy 41.72712 -319.066926) (xy 41.662858 -319.009014)
			(xy 41.642538 -319.00241) (xy 41.631616 -319.003426) (xy 41.599866 -319.005204) (xy 41.574613 -319.00468)
			(xy 41.524796 -318.996362) (xy 41.477028 -318.979958) (xy 41.43261 -318.955916) (xy 41.392756 -318.924892)
			(xy 41.358551 -318.887732) (xy 41.330928 -318.845448) (xy 41.310641 -318.799195) (xy 41.298243 -318.750234)
			(xy 41.294073 -318.6999) (xy 41.298243 -318.649566) (xy 41.310641 -318.600605) (xy 41.330928 -318.554352)
			(xy 41.358551 -318.512068) (xy 41.392756 -318.474908) (xy 41.43261 -318.443884) (xy 41.477028 -318.419842)
			(xy 41.524796 -318.403438) (xy 41.574613 -318.39512) (xy 41.599866 -318.394588) (xy 41.631616 -318.396366)
			(xy 41.642538 -318.397382) (xy 41.662858 -318.390778) (xy 41.72712 -318.332866) (xy 41.734617 -318.325316)
			(xy 41.743253 -318.305897) (xy 41.743884 -318.295274) (xy 41.743884 -318.224916) (xy 41.744047 -318.211262)
			(xy 41.746337 -318.18405) (xy 41.748456 -318.17056) (xy 41.750488 -318.158622) (xy 41.743376 -318.136016)
			(xy 41.670478 -318.059562) (xy 41.648126 -318.051688) (xy 41.636188 -318.053212) (xy 41.627141 -318.054202)
			(xy 41.608967 -318.055221) (xy 41.599866 -318.055244) (xy 41.575042 -318.054755) (xy 41.52605 -318.046718)
			(xy 41.479003 -318.03086) (xy 41.435141 -318.0076) (xy 41.39562 -317.97755) (xy 41.361482 -317.941502)
			(xy 41.333625 -317.900406) (xy 41.312783 -317.855345) (xy 41.299506 -317.807505) (xy 41.294144 -317.758148)
			(xy 41.296838 -317.708573) (xy 41.307516 -317.660088) (xy 41.325898 -317.613968) (xy 41.351499 -317.57143)
			(xy 41.383644 -317.533595) (xy 41.421487 -317.501458) (xy 41.464031 -317.475867) (xy 41.510155 -317.457495)
			(xy 41.558643 -317.446828) (xy 41.608218 -317.444146) (xy 41.657574 -317.44952) (xy 41.70541 -317.462807)
			(xy 41.750467 -317.483659) (xy 41.791557 -317.511526) (xy 41.827597 -317.545672) (xy 41.857637 -317.5852)
			(xy 41.880888 -317.629067) (xy 41.896735 -317.676118) (xy 41.904761 -317.725112) (xy 41.905174 -317.749936)
			(xy 41.905076 -317.75904) (xy 41.903933 -317.777213) (xy 41.902888 -317.786258) (xy 41.901618 -317.79845)
			(xy 41.909492 -317.820802) (xy 41.985946 -317.8937) (xy 42.008552 -317.900558) (xy 42.02049 -317.89878)
			(xy 42.033915 -317.896659) (xy 42.061001 -317.894369) (xy 42.074592 -317.894208) (xy 42.08401 -317.894243)
			(xy 42.102818 -317.895257) (xy 42.112184 -317.89624) (xy 42.123614 -317.897764) (xy 42.145458 -317.890144)
			(xy 42.218102 -317.817754) (xy 42.225976 -317.796164) (xy 42.224706 -317.784734) (xy 42.222928 -317.749936)
			(xy 42.223404 -317.724219) (xy 42.231446 -317.673419) (xy 42.247337 -317.624503) (xy 42.270686 -317.578675)
			(xy 42.300919 -317.537065) (xy 42.337289 -317.500698) (xy 42.378902 -317.47047) (xy 42.424732 -317.447125)
			(xy 42.47365 -317.431238) (xy 42.524451 -317.423201) (xy 42.575884 -317.423212) (xy 42.626682 -317.43127)
			(xy 42.675593 -317.447177) (xy 42.721413 -317.470541) (xy 42.763013 -317.500786) (xy 42.799369 -317.537168)
			(xy 42.829584 -317.57879) (xy 42.852915 -317.624627) (xy 42.868786 -317.67355) (xy 42.876807 -317.724354)
			(xy 42.87678 -317.775787) (xy 42.868706 -317.826582) (xy 42.852784 -317.875489) (xy 42.829405 -317.921301)
			(xy 42.799147 -317.962892) (xy 42.762753 -317.999236) (xy 42.721122 -318.029438) (xy 42.675277 -318.052754)
			(xy 42.626349 -318.06861) (xy 42.575543 -318.076615) (xy 42.549826 -318.077088) (xy 42.515028 -318.075056)
			(xy 42.503344 -318.073786) (xy 42.481754 -318.081406) (xy 42.409364 -318.154304) (xy 42.401744 -318.175894)
			(xy 42.403268 -318.187578) (xy 42.404238 -318.196882) (xy 42.405257 -318.215562) (xy 42.4053 -318.224916)
			(xy 42.4053 -318.27343) (xy 42.405765 -318.284086) (xy 42.414455 -318.303545) (xy 42.422064 -318.311022)
			(xy 42.486072 -318.368934) (xy 42.506138 -318.375538) (xy 42.51706 -318.374522) (xy 42.549826 -318.372744)
			(xy 42.575533 -318.37325) (xy 42.626313 -318.381296) (xy 42.675209 -318.397187) (xy 42.721017 -318.420531)
			(xy 42.76261 -318.450753) (xy 42.798964 -318.487109) (xy 42.829183 -318.528705) (xy 42.852523 -318.574515)
			(xy 42.86841 -318.623413) (xy 42.876452 -318.674193) (xy 42.876452 -318.725607) (xy 42.86841 -318.776387)
			(xy 42.852523 -318.825285) (xy 42.829183 -318.871095) (xy 42.798964 -318.912691) (xy 42.76261 -318.949047)
			(xy 42.721017 -318.979269) (xy 42.675209 -319.002613) (xy 42.626313 -319.018504) (xy 42.575533 -319.02655)
			(xy 42.549826 -319.027048) (xy 42.51706 -319.02527) (xy 42.506138 -319.024254) (xy 42.486072 -319.030858)
			(xy 42.422064 -319.08877) (xy 42.414547 -319.096311) (xy 42.405872 -319.115731) (xy 42.4053 -319.126362)
			(xy 42.4053 -319.17513) (xy 42.40514 -319.188784) (xy 42.402853 -319.215997) (xy 42.400728 -319.229486)
			(xy 42.398696 -319.241424) (xy 42.405808 -319.26403) (xy 42.478706 -319.340484) (xy 42.501058 -319.348358)
			(xy 42.51325 -319.347088) (xy 42.522357 -319.346032) (xy 42.540658 -319.344886) (xy 42.549826 -319.344802)
			(xy 42.575356 -319.345312) (xy 42.625707 -319.353797) (xy 42.673943 -319.370543) (xy 42.71872 -319.395083)
			(xy 42.758788 -319.426732) (xy 42.793031 -319.464608) (xy 42.820493 -319.507655) (xy 42.840409 -319.554671)
			(xy 42.852222 -319.604346) (xy 42.854372 -319.62979) (xy 42.855896 -319.649856) (xy 42.885106 -319.677288)
			(xy 43.669712 -319.677288) (xy 43.6753 -319.677034) (xy 43.686883 -319.675103) (xy 43.706604 -319.662401)
			(xy 43.713146 -319.65265) (xy 43.727349 -319.630073) (xy 43.762348 -319.58983) (xy 43.782742 -319.57264)
			(xy 43.787568 -319.56883) (xy 43.79468 -319.559432) (xy 43.801538 -319.543684) (xy 43.801538 -319.532762)
			(xy 43.801284 -319.471294) (xy 43.790108 -319.449704) (xy 43.780202 -319.442592) (xy 43.759465 -319.426893)
			(xy 43.722692 -319.390117) (xy 43.692122 -319.348043) (xy 43.668507 -319.301706) (xy 43.65243 -319.252245)
			(xy 43.644285 -319.20088) (xy 43.643804 -319.174876) (xy 43.643804 -319.104518) (xy 43.643348 -319.093857)
			(xy 43.634671 -319.074384) (xy 43.62704 -319.066926) (xy 43.562778 -319.009014) (xy 43.542458 -319.00241)
			(xy 43.531536 -319.003426) (xy 43.499786 -319.005204) (xy 43.474532 -319.004681) (xy 43.424712 -318.996366)
			(xy 43.376941 -318.979964) (xy 43.332521 -318.955923) (xy 43.292664 -318.924899) (xy 43.258456 -318.887738)
			(xy 43.230831 -318.845454) (xy 43.210543 -318.799199) (xy 43.198144 -318.750236) (xy 43.193973 -318.6999)
			(xy 43.198144 -318.649564) (xy 43.210543 -318.600601) (xy 43.230831 -318.554346) (xy 43.258456 -318.512062)
			(xy 43.292664 -318.474901) (xy 43.332521 -318.443877) (xy 43.376941 -318.419836) (xy 43.424712 -318.403434)
			(xy 43.474532 -318.395119) (xy 43.499786 -318.394588) (xy 43.531536 -318.396366) (xy 43.542458 -318.397382)
			(xy 43.562778 -318.390778) (xy 43.62704 -318.332866) (xy 43.634546 -318.325321) (xy 43.643197 -318.305901)
			(xy 43.643804 -318.295274) (xy 43.643804 -318.224916) (xy 43.643967 -318.211262) (xy 43.646257 -318.18405)
			(xy 43.648376 -318.17056) (xy 43.650408 -318.158622) (xy 43.643296 -318.136016) (xy 43.570398 -318.059562)
			(xy 43.548046 -318.051688) (xy 43.536108 -318.053212) (xy 43.527061 -318.0542) (xy 43.508887 -318.055214)
			(xy 43.499786 -318.055244) (xy 43.474962 -318.054757) (xy 43.425968 -318.046722) (xy 43.378919 -318.030867)
			(xy 43.335056 -318.007609) (xy 43.295533 -317.977561) (xy 43.261392 -317.941515) (xy 43.233532 -317.900419)
			(xy 43.212688 -317.855359) (xy 43.199409 -317.807519) (xy 43.194045 -317.758161) (xy 43.196736 -317.708586)
			(xy 43.207412 -317.660099) (xy 43.225793 -317.613979) (xy 43.251392 -317.571439) (xy 43.283537 -317.533602)
			(xy 43.32138 -317.501463) (xy 43.363924 -317.47587) (xy 43.410047 -317.457498) (xy 43.458536 -317.446829)
			(xy 43.508112 -317.444146) (xy 43.557468 -317.449519) (xy 43.605306 -317.462806) (xy 43.650363 -317.483657)
			(xy 43.691454 -317.511523) (xy 43.727494 -317.54567) (xy 43.757536 -317.585198) (xy 43.780787 -317.629065)
			(xy 43.796634 -317.676117) (xy 43.804661 -317.725112) (xy 43.805094 -317.749936) (xy 43.805054 -317.759037)
			(xy 43.804035 -317.777209) (xy 43.803062 -317.786258) (xy 43.801538 -317.798196) (xy 43.809412 -317.820548)
			(xy 43.885866 -317.893446) (xy 43.908472 -317.900558) (xy 43.92041 -317.898526) (xy 43.933898 -317.896395)
			(xy 43.961111 -317.894102) (xy 43.974766 -317.893954) (xy 43.98412 -317.893996) (xy 44.002801 -317.895012)
			(xy 44.012104 -317.895986) (xy 44.023788 -317.897256) (xy 44.045378 -317.88989) (xy 44.118022 -317.8175)
			(xy 44.125896 -317.79591) (xy 44.124626 -317.78448) (xy 44.122848 -317.749936) (xy 44.123324 -317.724221)
			(xy 44.131365 -317.673425) (xy 44.147255 -317.624512) (xy 44.170602 -317.578687) (xy 44.200832 -317.537081)
			(xy 44.237199 -317.500716) (xy 44.278808 -317.470489) (xy 44.324635 -317.447145) (xy 44.373549 -317.431259)
			(xy 44.424346 -317.423222) (xy 44.475775 -317.423231) (xy 44.52657 -317.431288) (xy 44.575478 -317.447192)
			(xy 44.621295 -317.470553) (xy 44.662893 -317.500795) (xy 44.699247 -317.537173) (xy 44.729461 -317.578791)
			(xy 44.752792 -317.624624) (xy 44.768663 -317.673543) (xy 44.776686 -317.724342) (xy 44.776661 -317.775772)
			(xy 44.76859 -317.826564) (xy 44.752671 -317.875467) (xy 44.729296 -317.921278) (xy 44.699042 -317.962867)
			(xy 44.662653 -317.99921) (xy 44.621026 -318.029412) (xy 44.575187 -318.052729) (xy 44.526263 -318.068586)
			(xy 44.475461 -318.076593) (xy 44.449746 -318.077088) (xy 44.415202 -318.075056) (xy 44.403772 -318.073786)
			(xy 44.382182 -318.08166) (xy 44.309792 -318.154304) (xy 44.302426 -318.175894) (xy 44.303696 -318.187578)
			(xy 44.304664 -318.196882) (xy 44.305681 -318.215562) (xy 44.305728 -318.224916) (xy 44.305728 -318.27343)
			(xy 44.306194 -318.284085) (xy 44.314888 -318.303541) (xy 44.322492 -318.311022) (xy 44.386246 -318.368934)
			(xy 44.406566 -318.375538) (xy 44.417488 -318.374522) (xy 44.449746 -318.372744) (xy 44.475452 -318.373252)
			(xy 44.526229 -318.3813) (xy 44.575123 -318.397193) (xy 44.620928 -318.420538) (xy 44.662519 -318.45076)
			(xy 44.69887 -318.487116) (xy 44.729086 -318.528711) (xy 44.752425 -318.57452) (xy 44.76831 -318.623416)
			(xy 44.776352 -318.674194) (xy 44.776352 -318.725606) (xy 44.76831 -318.776384) (xy 44.752425 -318.82528)
			(xy 44.729086 -318.871089) (xy 44.69887 -318.912684) (xy 44.662519 -318.94904) (xy 44.620928 -318.979262)
			(xy 44.575123 -319.002607) (xy 44.526229 -319.0185) (xy 44.475452 -319.026548) (xy 44.449746 -319.027048)
			(xy 44.417488 -319.02527) (xy 44.406566 -319.024254) (xy 44.386246 -319.030858) (xy 44.322492 -319.08877)
			(xy 44.314984 -319.096316) (xy 44.306321 -319.115734) (xy 44.305728 -319.126362) (xy 44.305728 -319.174876)
			(xy 44.305575 -319.188594) (xy 44.30329 -319.215934) (xy 44.301156 -319.229486) (xy 44.299124 -319.241424)
			(xy 44.306236 -319.26403) (xy 44.379134 -319.340484) (xy 44.401486 -319.348358) (xy 44.413424 -319.347088)
			(xy 44.422532 -319.346034) (xy 44.440832 -319.344892) (xy 44.45 -319.344802) (xy 44.475532 -319.34531)
			(xy 44.525885 -319.353792) (xy 44.574125 -319.370535) (xy 44.618906 -319.395074) (xy 44.658978 -319.426723)
			(xy 44.693224 -319.4646) (xy 44.720689 -319.507647) (xy 44.740607 -319.554666) (xy 44.752421 -319.604343)
			(xy 44.754546 -319.62979) (xy 44.75607 -319.649856) (xy 44.78528 -319.677288) (xy 45.569632 -319.677288)
			(xy 45.57522 -319.677034) (xy 45.585464 -319.675356) (xy 45.603418 -319.664982) (xy 45.610018 -319.656968)
			(xy 45.613066 -319.65265) (xy 45.619154 -319.642686) (xy 45.632633 -319.623617) (xy 45.63999 -319.61455)
			(xy 45.649779 -319.603031) (xy 45.671279 -319.58178) (xy 45.682916 -319.572132) (xy 45.691339 -319.564458)
			(xy 45.70107 -319.543887) (xy 45.701712 -319.532508) (xy 45.701458 -319.471294) (xy 45.690536 -319.449958)
			(xy 45.680376 -319.442846) (xy 45.659583 -319.427168) (xy 45.622736 -319.390373) (xy 45.592108 -319.34826)
			(xy 45.568455 -319.301869) (xy 45.55236 -319.252346) (xy 45.544223 -319.200913) (xy 45.543724 -319.174876)
			(xy 45.543724 -319.104518) (xy 45.543269 -319.093857) (xy 45.534594 -319.074381) (xy 45.52696 -319.066926)
			(xy 45.462698 -319.009014) (xy 45.442378 -319.00241) (xy 45.43171 -319.00368) (xy 45.39996 -319.005204)
			(xy 45.374707 -319.004679) (xy 45.324891 -318.99636) (xy 45.277124 -318.979956) (xy 45.232707 -318.955914)
			(xy 45.192853 -318.92489) (xy 45.158649 -318.88773) (xy 45.131027 -318.845446) (xy 45.110741 -318.799194)
			(xy 45.098343 -318.750233) (xy 45.094173 -318.6999) (xy 45.098343 -318.649567) (xy 45.110741 -318.600606)
			(xy 45.131027 -318.554354) (xy 45.158649 -318.51207) (xy 45.192853 -318.47491) (xy 45.232707 -318.443886)
			(xy 45.277124 -318.419844) (xy 45.324891 -318.40344) (xy 45.374707 -318.395121) (xy 45.39996 -318.394588)
			(xy 45.43171 -318.396112) (xy 45.442378 -318.397382) (xy 45.462698 -318.390778) (xy 45.52696 -318.332866)
			(xy 45.534464 -318.32532) (xy 45.54311 -318.3059) (xy 45.543724 -318.295274) (xy 45.543724 -318.224916)
			(xy 45.543887 -318.211262) (xy 45.546177 -318.18405) (xy 45.548296 -318.17056) (xy 45.550074 -318.158622)
			(xy 45.543216 -318.136016) (xy 45.470318 -318.059562) (xy 45.447966 -318.051688) (xy 45.436028 -318.053212)
			(xy 45.427044 -318.054195) (xy 45.408998 -318.055212) (xy 45.39996 -318.055244) (xy 45.375136 -318.054755)
			(xy 45.326144 -318.046716) (xy 45.279098 -318.030858) (xy 45.235236 -318.007597) (xy 45.195716 -317.977546)
			(xy 45.161579 -317.941498) (xy 45.133722 -317.900402) (xy 45.112882 -317.85534) (xy 45.099606 -317.807501)
			(xy 45.094244 -317.758144) (xy 45.096938 -317.70857) (xy 45.107617 -317.660084) (xy 45.125999 -317.613965)
			(xy 45.151601 -317.571428) (xy 45.183746 -317.533592) (xy 45.22159 -317.501456) (xy 45.264134 -317.475865)
			(xy 45.310257 -317.457495) (xy 45.358745 -317.446828) (xy 45.40832 -317.444146) (xy 45.457676 -317.44952)
			(xy 45.505512 -317.462808) (xy 45.550568 -317.48366) (xy 45.591657 -317.511526) (xy 45.627697 -317.545673)
			(xy 45.657738 -317.585201) (xy 45.680988 -317.629067) (xy 45.696835 -317.676118) (xy 45.704861 -317.725112)
			(xy 45.705268 -317.749936) (xy 45.705228 -317.759037) (xy 45.704209 -317.777209) (xy 45.703236 -317.786258)
			(xy 45.701712 -317.798196) (xy 45.709586 -317.820548) (xy 45.78604 -317.893446) (xy 45.808646 -317.900304)
			(xy 45.820584 -317.898526) (xy 45.83401 -317.89641) (xy 45.861095 -317.894125) (xy 45.874686 -317.893954)
			(xy 45.884104 -317.893991) (xy 45.902911 -317.895011) (xy 45.912278 -317.895986) (xy 45.923708 -317.89751)
			(xy 45.945298 -317.88989) (xy 46.018196 -317.8175) (xy 46.02607 -317.796164) (xy 46.0248 -317.78448)
			(xy 46.022768 -317.749936) (xy 46.023243 -317.724227) (xy 46.031281 -317.673443) (xy 46.047165 -317.62454)
			(xy 46.070503 -317.578725) (xy 46.10072 -317.537125) (xy 46.137074 -317.500764) (xy 46.178668 -317.470538)
			(xy 46.224479 -317.44719) (xy 46.273378 -317.431297) (xy 46.324161 -317.423249) (xy 46.375578 -317.423244)
			(xy 46.426363 -317.431282) (xy 46.475264 -317.447167) (xy 46.521079 -317.470505) (xy 46.562679 -317.500724)
			(xy 46.59904 -317.537078) (xy 46.629265 -317.578673) (xy 46.652612 -317.624484) (xy 46.668505 -317.673383)
			(xy 46.676552 -317.724166) (xy 46.676556 -317.775583) (xy 46.668516 -317.826368) (xy 46.652631 -317.875269)
			(xy 46.629292 -317.921084) (xy 46.599073 -317.962683) (xy 46.562718 -317.999043) (xy 46.521123 -318.029268)
			(xy 46.475311 -318.052614) (xy 46.426412 -318.068506) (xy 46.375628 -318.076552) (xy 46.34992 -318.077088)
			(xy 46.315376 -318.075056) (xy 46.303692 -318.073786) (xy 46.282102 -318.08166) (xy 46.209712 -318.154304)
			(xy 46.202346 -318.175894) (xy 46.203616 -318.187578) (xy 46.204584 -318.196882) (xy 46.205601 -318.215562)
			(xy 46.205648 -318.224916) (xy 46.205648 -318.27343) (xy 46.206115 -318.284085) (xy 46.214811 -318.303538)
			(xy 46.222412 -318.311022) (xy 46.286166 -318.368934) (xy 46.306486 -318.375538) (xy 46.317408 -318.374522)
			(xy 46.34992 -318.372744) (xy 46.375627 -318.37325) (xy 46.426408 -318.381295) (xy 46.475305 -318.397186)
			(xy 46.521114 -318.420529) (xy 46.562708 -318.450751) (xy 46.599062 -318.487107) (xy 46.629281 -318.528703)
			(xy 46.652622 -318.574514) (xy 46.668509 -318.623412) (xy 46.676552 -318.674193) (xy 46.676552 -318.725607)
			(xy 46.668509 -318.776388) (xy 46.652622 -318.825286) (xy 46.629281 -318.871097) (xy 46.599062 -318.912693)
			(xy 46.562708 -318.949049) (xy 46.521114 -318.979271) (xy 46.475305 -319.002614) (xy 46.426408 -319.018505)
			(xy 46.375627 -319.02655) (xy 46.34992 -319.027048) (xy 46.317408 -319.02527) (xy 46.306486 -319.024254)
			(xy 46.286166 -319.030858) (xy 46.222412 -319.08877) (xy 46.214902 -319.096315) (xy 46.206236 -319.115733)
			(xy 46.205648 -319.126362) (xy 46.205648 -319.174876) (xy 46.205495 -319.188594) (xy 46.20321 -319.215934)
			(xy 46.201076 -319.229486) (xy 46.199044 -319.241424) (xy 46.206156 -319.26403) (xy 46.279054 -319.340484)
			(xy 46.301406 -319.348358) (xy 46.313344 -319.347088) (xy 46.322452 -319.346035) (xy 46.340752 -319.344894)
			(xy 46.34992 -319.344802) (xy 46.375451 -319.345312) (xy 46.425802 -319.353796) (xy 46.474039 -319.370541)
			(xy 46.518817 -319.395081) (xy 46.558886 -319.42673) (xy 46.59313 -319.464606) (xy 46.620592 -319.507653)
			(xy 46.640508 -319.55467) (xy 46.652322 -319.604346) (xy 46.654466 -319.62979) (xy 46.65599 -319.649856)
			(xy 46.6852 -319.677288) (xy 47.469552 -319.677288) (xy 47.47514 -319.677034) (xy 47.485392 -319.67537)
			(xy 47.50337 -319.665013) (xy 47.509938 -319.656968) (xy 47.512986 -319.65265) (xy 47.519075 -319.642687)
			(xy 47.532554 -319.623618) (xy 47.53991 -319.61455) (xy 47.549699 -319.603031) (xy 47.571201 -319.581782)
			(xy 47.582836 -319.572132) (xy 47.59127 -319.564464) (xy 47.601016 -319.543891) (xy 47.601632 -319.532508)
			(xy 47.601378 -319.471294) (xy 47.590456 -319.449958) (xy 47.580296 -319.442846) (xy 47.559507 -319.427165)
			(xy 47.522669 -319.390367) (xy 47.492048 -319.348252) (xy 47.4684 -319.301862) (xy 47.45231 -319.252341)
			(xy 47.444175 -319.200911) (xy 47.443644 -319.174876) (xy 47.443644 -319.104518) (xy 47.443186 -319.093859)
			(xy 47.434502 -319.074392) (xy 47.42688 -319.066926) (xy 47.362618 -319.009014) (xy 47.342298 -319.00241)
			(xy 47.33163 -319.00368) (xy 47.29988 -319.005204) (xy 47.274626 -319.004681) (xy 47.224808 -318.996365)
			(xy 47.177037 -318.979962) (xy 47.132618 -318.955921) (xy 47.092761 -318.924897) (xy 47.058554 -318.887736)
			(xy 47.03093 -318.845452) (xy 47.010642 -318.799198) (xy 46.998244 -318.750235) (xy 46.994073 -318.6999)
			(xy 46.998244 -318.649565) (xy 47.010642 -318.600602) (xy 47.03093 -318.554348) (xy 47.058554 -318.512064)
			(xy 47.092761 -318.474903) (xy 47.132618 -318.443879) (xy 47.177037 -318.419838) (xy 47.224808 -318.403435)
			(xy 47.274626 -318.395119) (xy 47.29988 -318.394588) (xy 47.33163 -318.396112) (xy 47.342298 -318.397382)
			(xy 47.362618 -318.390778) (xy 47.42688 -318.332866) (xy 47.434381 -318.325318) (xy 47.443024 -318.305899)
			(xy 47.443644 -318.295274) (xy 47.443644 -318.224916) (xy 47.443807 -318.211262) (xy 47.446098 -318.18405)
			(xy 47.448216 -318.17056) (xy 47.449994 -318.158622) (xy 47.443136 -318.136016) (xy 47.370238 -318.059562)
			(xy 47.347886 -318.051688) (xy 47.335948 -318.053212) (xy 47.326964 -318.054195) (xy 47.308918 -318.055214)
			(xy 47.29988 -318.055244) (xy 47.275056 -318.054756) (xy 47.226062 -318.046721) (xy 47.179014 -318.030865)
			(xy 47.135151 -318.007606) (xy 47.095629 -317.977558) (xy 47.061489 -317.941511) (xy 47.03363 -317.900415)
			(xy 47.012787 -317.855354) (xy 46.999508 -317.807515) (xy 46.994144 -317.758157) (xy 46.996837 -317.708582)
			(xy 47.007514 -317.660096) (xy 47.025894 -317.613976) (xy 47.051494 -317.571437) (xy 47.083639 -317.5336)
			(xy 47.121482 -317.501462) (xy 47.164026 -317.475869) (xy 47.21015 -317.457497) (xy 47.258638 -317.446829)
			(xy 47.308213 -317.444146) (xy 47.35757 -317.449519) (xy 47.405407 -317.462806) (xy 47.450464 -317.483658)
			(xy 47.491554 -317.511524) (xy 47.527595 -317.545671) (xy 47.557636 -317.585199) (xy 47.580887 -317.629066)
			(xy 47.596734 -317.676117) (xy 47.604761 -317.725112) (xy 47.605188 -317.749936) (xy 47.605148 -317.759037)
			(xy 47.604129 -317.777209) (xy 47.603156 -317.786258) (xy 47.601632 -317.798196) (xy 47.609506 -317.820548)
			(xy 47.68596 -317.893446) (xy 47.708566 -317.900304) (xy 47.720504 -317.898526) (xy 47.73393 -317.896407)
			(xy 47.761015 -317.894115) (xy 47.774606 -317.893954) (xy 47.784024 -317.893989) (xy 47.802832 -317.895004)
			(xy 47.812198 -317.895986) (xy 47.823628 -317.89751) (xy 47.845218 -317.88989) (xy 47.918116 -317.8175)
			(xy 47.92599 -317.796164) (xy 47.92472 -317.78448) (xy 47.922688 -317.749936) (xy 47.92319 -317.724231)
			(xy 47.931226 -317.673454) (xy 47.947107 -317.62456) (xy 47.970441 -317.578751) (xy 48.000654 -317.537157)
			(xy 48.037001 -317.500802) (xy 48.078589 -317.470579) (xy 48.124392 -317.447235) (xy 48.173283 -317.431343)
			(xy 48.224058 -317.423295) (xy 48.275467 -317.423289) (xy 48.326244 -317.431326) (xy 48.375139 -317.447206)
			(xy 48.420947 -317.47054) (xy 48.462542 -317.500753) (xy 48.498898 -317.5371) (xy 48.52912 -317.578688)
			(xy 48.552464 -317.624491) (xy 48.568356 -317.673382) (xy 48.576405 -317.724157) (xy 48.576411 -317.775566)
			(xy 48.568374 -317.826343) (xy 48.552494 -317.875238) (xy 48.52916 -317.921046) (xy 48.498948 -317.962641)
			(xy 48.462601 -317.998997) (xy 48.421013 -318.029219) (xy 48.37521 -318.052564) (xy 48.32632 -318.068456)
			(xy 48.275544 -318.076504) (xy 48.24984 -318.077088) (xy 48.215296 -318.075056) (xy 48.203612 -318.073786)
			(xy 48.182022 -318.08166) (xy 48.109632 -318.154304) (xy 48.102266 -318.175894) (xy 48.103536 -318.187578)
			(xy 48.104504 -318.196882) (xy 48.105521 -318.215562) (xy 48.105568 -318.224916) (xy 48.105568 -318.27343)
			(xy 48.106032 -318.284087) (xy 48.114719 -318.303549) (xy 48.122332 -318.311022) (xy 48.186086 -318.368934)
			(xy 48.206406 -318.375538) (xy 48.217328 -318.374522) (xy 48.24984 -318.372744) (xy 48.275546 -318.373251)
			(xy 48.326324 -318.381299) (xy 48.375219 -318.397191) (xy 48.421025 -318.420536) (xy 48.462616 -318.450758)
			(xy 48.498968 -318.487114) (xy 48.529185 -318.528709) (xy 48.552524 -318.574518) (xy 48.56841 -318.623415)
			(xy 48.576452 -318.674194) (xy 48.576452 -318.725606) (xy 48.56841 -318.776385) (xy 48.552524 -318.825282)
			(xy 48.529185 -318.871091) (xy 48.498968 -318.912686) (xy 48.462616 -318.949042) (xy 48.421025 -318.979264)
			(xy 48.375219 -319.002609) (xy 48.326324 -319.018501) (xy 48.275546 -319.026549) (xy 48.24984 -319.027048)
			(xy 48.217328 -319.02527) (xy 48.206406 -319.024254) (xy 48.186086 -319.030858) (xy 48.122332 -319.08877)
			(xy 48.114819 -319.096313) (xy 48.10615 -319.115732) (xy 48.105568 -319.126362) (xy 48.105568 -319.174876)
			(xy 48.105415 -319.188594) (xy 48.103129 -319.215934) (xy 48.100996 -319.229486) (xy 48.098964 -319.241424)
			(xy 48.106076 -319.26403) (xy 48.178974 -319.340484) (xy 48.201326 -319.348358) (xy 48.213264 -319.347088)
			(xy 48.222371 -319.346033) (xy 48.240672 -319.344887) (xy 48.24984 -319.344802) (xy 48.27537 -319.345313)
			(xy 48.325718 -319.3538) (xy 48.373952 -319.370547) (xy 48.418727 -319.395088) (xy 48.458794 -319.426737)
			(xy 48.493035 -319.464613) (xy 48.520495 -319.507659) (xy 48.540409 -319.554674) (xy 48.552222 -319.604348)
			(xy 48.554386 -319.62979) (xy 48.55591 -319.649856) (xy 48.58512 -319.677288) (xy 49.369726 -319.677288)
			(xy 49.375314 -319.677034) (xy 49.385558 -319.675357) (xy 49.403515 -319.664985) (xy 49.410112 -319.656968)
			(xy 49.41316 -319.65265) (xy 49.419248 -319.642686) (xy 49.432726 -319.623617) (xy 49.440084 -319.61455)
			(xy 49.449872 -319.603031) (xy 49.471373 -319.58178) (xy 49.48301 -319.572132) (xy 49.491434 -319.564458)
			(xy 49.501166 -319.543888) (xy 49.501806 -319.532508) (xy 49.501552 -319.471294) (xy 49.49063 -319.449958)
			(xy 49.480724 -319.442846) (xy 49.459929 -319.42717) (xy 49.423077 -319.390377) (xy 49.392444 -319.348265)
			(xy 49.368787 -319.301873) (xy 49.35269 -319.252349) (xy 49.344551 -319.200914) (xy 49.344072 -319.174876)
			(xy 49.344072 -319.104518) (xy 49.343516 -319.093823) (xy 49.334864 -319.074259) (xy 49.327308 -319.066672)
			(xy 49.263046 -319.009014) (xy 49.242726 -319.00241) (xy 49.231804 -319.003426) (xy 49.1998 -319.005204)
			(xy 49.174545 -319.004682) (xy 49.124724 -318.996369) (xy 49.076951 -318.979968) (xy 49.032528 -318.955928)
			(xy 48.992669 -318.924904) (xy 48.95846 -318.887743) (xy 48.930833 -318.845458) (xy 48.910544 -318.799202)
			(xy 48.898144 -318.750237) (xy 48.893973 -318.6999) (xy 48.898144 -318.649563) (xy 48.910544 -318.600598)
			(xy 48.930833 -318.554342) (xy 48.95846 -318.512057) (xy 48.992669 -318.474896) (xy 49.032528 -318.443872)
			(xy 49.076951 -318.419832) (xy 49.124724 -318.403431) (xy 49.174545 -318.395118) (xy 49.1998 -318.394588)
			(xy 49.231804 -318.396366) (xy 49.242726 -318.397382) (xy 49.263046 -318.390778) (xy 49.327308 -318.33312)
			(xy 49.334965 -318.325601) (xy 49.343648 -318.305997) (xy 49.344072 -318.295274) (xy 49.344072 -318.224916)
			(xy 49.344235 -318.211262) (xy 49.346526 -318.18405) (xy 49.348644 -318.17056) (xy 49.350676 -318.158622)
			(xy 49.343564 -318.136016) (xy 49.270666 -318.059562) (xy 49.248314 -318.051688) (xy 49.236122 -318.052958)
			(xy 49.227078 -318.054006) (xy 49.208904 -318.05515) (xy 49.1998 -318.055244) (xy 49.174976 -318.054758)
			(xy 49.125981 -318.046725) (xy 49.078931 -318.030872) (xy 49.035066 -318.007616) (xy 48.995542 -317.977569)
			(xy 48.961399 -317.941523) (xy 48.933538 -317.900429) (xy 48.912692 -317.855368) (xy 48.899411 -317.807529)
			(xy 48.894045 -317.758171) (xy 48.896735 -317.708595) (xy 48.90741 -317.660107) (xy 48.925789 -317.613986)
			(xy 48.951388 -317.571445) (xy 48.983532 -317.533607) (xy 49.021375 -317.501467) (xy 49.063918 -317.475873)
			(xy 49.110042 -317.457499) (xy 49.158531 -317.44683) (xy 49.208107 -317.444146) (xy 49.257464 -317.449518)
			(xy 49.305302 -317.462804) (xy 49.35036 -317.483655) (xy 49.391452 -317.511521) (xy 49.427493 -317.545668)
			(xy 49.457535 -317.585197) (xy 49.480786 -317.629064) (xy 49.496634 -317.676116) (xy 49.504661 -317.725112)
			(xy 49.505108 -317.749936) (xy 49.50501 -317.75904) (xy 49.503867 -317.777213) (xy 49.502822 -317.786258)
			(xy 49.501552 -317.79845) (xy 49.509426 -317.820802) (xy 49.58588 -317.8937) (xy 49.608486 -317.900812)
			(xy 49.620424 -317.89878) (xy 49.633912 -317.896648) (xy 49.661125 -317.894358) (xy 49.67478 -317.894208)
			(xy 49.684134 -317.89425) (xy 49.702815 -317.895265) (xy 49.712118 -317.89624) (xy 49.723802 -317.897764)
			(xy 49.745392 -317.890144) (xy 49.818036 -317.817754) (xy 49.82591 -317.796164) (xy 49.82464 -317.78448)
			(xy 49.822608 -317.749936) (xy 49.823084 -317.724222) (xy 49.831124 -317.673426) (xy 49.847011 -317.624513)
			(xy 49.870355 -317.578688) (xy 49.900581 -317.537079) (xy 49.936943 -317.500711) (xy 49.978548 -317.47048)
			(xy 50.02437 -317.447129) (xy 50.07328 -317.431234) (xy 50.124075 -317.423187) (xy 50.175504 -317.423186)
			(xy 50.226299 -317.431229) (xy 50.275211 -317.447121) (xy 50.321034 -317.470468) (xy 50.36264 -317.500697)
			(xy 50.399005 -317.537063) (xy 50.429234 -317.57867) (xy 50.452581 -317.624493) (xy 50.468472 -317.673405)
			(xy 50.476515 -317.7242) (xy 50.476512 -317.775629) (xy 50.468465 -317.826424) (xy 50.452569 -317.875334)
			(xy 50.429218 -317.921155) (xy 50.398986 -317.96276) (xy 50.362618 -317.999122) (xy 50.321009 -318.029347)
			(xy 50.275183 -318.05269) (xy 50.22627 -318.068577) (xy 50.175474 -318.076617) (xy 50.14976 -318.077088)
			(xy 50.115216 -318.075056) (xy 50.103532 -318.073786) (xy 50.081942 -318.08166) (xy 50.009552 -318.154304)
			(xy 50.001932 -318.175894) (xy 50.003456 -318.187578) (xy 50.004426 -318.196882) (xy 50.005444 -318.215562)
			(xy 50.005488 -318.224916) (xy 50.005488 -318.27343) (xy 50.005953 -318.284087) (xy 50.014642 -318.303547)
			(xy 50.022252 -318.311022) (xy 50.086006 -318.368934) (xy 50.106326 -318.375538) (xy 50.117248 -318.374522)
			(xy 50.14976 -318.372744) (xy 50.175472 -318.373219) (xy 50.226264 -318.381258) (xy 50.275173 -318.397144)
			(xy 50.320994 -318.420486) (xy 50.3626 -318.45071) (xy 50.398964 -318.48707) (xy 50.429193 -318.528672)
			(xy 50.45254 -318.57449) (xy 50.468433 -318.623397) (xy 50.476478 -318.674188) (xy 50.476478 -318.725612)
			(xy 50.468433 -318.776403) (xy 50.45254 -318.82531) (xy 50.429193 -318.871128) (xy 50.398964 -318.91273)
			(xy 50.3626 -318.94909) (xy 50.320994 -318.979314) (xy 50.275173 -319.002656) (xy 50.226264 -319.018542)
			(xy 50.175472 -319.026581) (xy 50.14976 -319.027048) (xy 50.117248 -319.02527) (xy 50.106326 -319.024254)
			(xy 50.086006 -319.030858) (xy 50.022252 -319.08877) (xy 50.014737 -319.096312) (xy 50.006064 -319.115732)
			(xy 50.005488 -319.126362) (xy 50.005488 -319.17513) (xy 50.005327 -319.188784) (xy 50.003041 -319.215997)
			(xy 50.000916 -319.229486) (xy 49.998884 -319.241424) (xy 50.005996 -319.26403) (xy 50.078894 -319.340484)
			(xy 50.101246 -319.348358) (xy 50.113438 -319.347088) (xy 50.122546 -319.346035) (xy 50.140846 -319.344894)
			(xy 50.150014 -319.344802) (xy 50.175545 -319.345311) (xy 50.225897 -319.353795) (xy 50.274135 -319.37054)
			(xy 50.318913 -319.395079) (xy 50.358984 -319.426728) (xy 50.393228 -319.464604) (xy 50.420691 -319.507651)
			(xy 50.440608 -319.554669) (xy 50.452422 -319.604345) (xy 50.45456 -319.62979) (xy 50.456084 -319.649856)
			(xy 50.485294 -319.677288) (xy 51.269646 -319.677288) (xy 51.275234 -319.677034) (xy 51.285487 -319.675371)
			(xy 51.303467 -319.665015) (xy 51.310032 -319.656968) (xy 51.31308 -319.65265) (xy 51.319169 -319.642687)
			(xy 51.332647 -319.623618) (xy 51.340004 -319.61455) (xy 51.349793 -319.603031) (xy 51.371294 -319.581781)
			(xy 51.38293 -319.572132) (xy 51.391364 -319.564464) (xy 51.401112 -319.543892) (xy 51.401726 -319.532508)
			(xy 51.401472 -319.471294) (xy 51.39055 -319.449958) (xy 51.380644 -319.442846) (xy 51.359848 -319.42717)
			(xy 51.322994 -319.390378) (xy 51.292359 -319.348266) (xy 51.2687 -319.301875) (xy 51.252602 -319.25235)
			(xy 51.244463 -319.200914) (xy 51.243992 -319.174876) (xy 51.243992 -319.104518) (xy 51.243536 -319.093858)
			(xy 51.234857 -319.074386) (xy 51.227228 -319.066926) (xy 51.162966 -319.009014) (xy 51.142646 -319.00241)
			(xy 51.131724 -319.003426) (xy 51.099974 -319.005204) (xy 51.07472 -319.00468) (xy 51.024903 -318.996363)
			(xy 50.977133 -318.979961) (xy 50.932715 -318.955919) (xy 50.892859 -318.924895) (xy 50.858653 -318.887734)
			(xy 50.831029 -318.84545) (xy 50.810742 -318.799197) (xy 50.798344 -318.750235) (xy 50.794173 -318.6999)
			(xy 50.798344 -318.649565) (xy 50.810742 -318.600603) (xy 50.831029 -318.55435) (xy 50.858653 -318.512066)
			(xy 50.892859 -318.474905) (xy 50.932715 -318.443881) (xy 50.977133 -318.419839) (xy 51.024903 -318.403437)
			(xy 51.07472 -318.39512) (xy 51.099974 -318.394588) (xy 51.131724 -318.396366) (xy 51.142646 -318.397382)
			(xy 51.162966 -318.390778) (xy 51.227228 -318.332866) (xy 51.234735 -318.325321) (xy 51.243388 -318.305901)
			(xy 51.243992 -318.295274) (xy 51.243992 -318.224916) (xy 51.244155 -318.211262) (xy 51.246445 -318.18405)
			(xy 51.248564 -318.17056) (xy 51.250596 -318.158622) (xy 51.243484 -318.136016) (xy 51.170586 -318.059562)
			(xy 51.148234 -318.051688) (xy 51.136296 -318.053212) (xy 51.127249 -318.054203) (xy 51.109075 -318.055222)
			(xy 51.099974 -318.055244) (xy 51.07515 -318.054756) (xy 51.026157 -318.04672) (xy 50.979109 -318.030863)
			(xy 50.935247 -318.007603) (xy 50.895725 -317.977554) (xy 50.861586 -317.941507) (xy 50.833728 -317.900411)
			(xy 50.812885 -317.85535) (xy 50.799608 -317.807511) (xy 50.794244 -317.758153) (xy 50.796937 -317.708579)
			(xy 50.807615 -317.660092) (xy 50.825996 -317.613973) (xy 50.851596 -317.571434) (xy 50.883741 -317.533597)
			(xy 50.921584 -317.50146) (xy 50.964128 -317.475868) (xy 51.010252 -317.457496) (xy 51.05874 -317.446829)
			(xy 51.108315 -317.444146) (xy 51.157672 -317.449519) (xy 51.205509 -317.462807) (xy 51.250565 -317.483658)
			(xy 51.291655 -317.511525) (xy 51.327696 -317.545671) (xy 51.357737 -317.585199) (xy 51.380987 -317.629066)
			(xy 51.396835 -317.676117) (xy 51.404861 -317.725112) (xy 51.405282 -317.749936) (xy 51.405184 -317.75904)
			(xy 51.404041 -317.777213) (xy 51.402996 -317.786258) (xy 51.401726 -317.79845) (xy 51.4096 -317.820802)
			(xy 51.486054 -317.8937) (xy 51.50866 -317.900558) (xy 51.520598 -317.89878) (xy 51.534023 -317.89666)
			(xy 51.561109 -317.894369) (xy 51.5747 -317.894208) (xy 51.584118 -317.894243) (xy 51.602926 -317.895257)
			(xy 51.612292 -317.89624) (xy 51.623722 -317.897764) (xy 51.645566 -317.890144) (xy 51.71821 -317.817754)
			(xy 51.726084 -317.796164) (xy 51.724814 -317.784734) (xy 51.723036 -317.749936) (xy 51.723512 -317.72422)
			(xy 51.731553 -317.673421) (xy 51.747444 -317.624506) (xy 51.770793 -317.57868) (xy 51.801024 -317.537071)
			(xy 51.837393 -317.500705) (xy 51.879004 -317.470478) (xy 51.924833 -317.447133) (xy 51.973749 -317.431247)
			(xy 52.024549 -317.423209) (xy 52.07598 -317.42322) (xy 52.126777 -317.431277) (xy 52.175687 -317.447183)
			(xy 52.221506 -317.470546) (xy 52.263105 -317.50079) (xy 52.29946 -317.53717) (xy 52.329675 -317.57879)
			(xy 52.353005 -317.624626) (xy 52.368877 -317.673547) (xy 52.376898 -317.724349) (xy 52.376872 -317.775781)
			(xy 52.3688 -317.826575) (xy 52.352879 -317.87548) (xy 52.329502 -317.921292) (xy 52.299245 -317.962882)
			(xy 52.262853 -317.999225) (xy 52.221224 -318.029427) (xy 52.175381 -318.052744) (xy 52.126455 -318.0686)
			(xy 52.07565 -318.076606) (xy 52.049934 -318.077088) (xy 52.015136 -318.075056) (xy 52.003452 -318.073786)
			(xy 51.981862 -318.081406) (xy 51.909472 -318.154304) (xy 51.901852 -318.175894) (xy 51.903376 -318.187578)
			(xy 51.904346 -318.196882) (xy 51.905365 -318.215562) (xy 51.905408 -318.224916) (xy 51.905408 -318.27343)
			(xy 51.905874 -318.284086) (xy 51.914565 -318.303544) (xy 51.922172 -318.311022) (xy 51.98618 -318.368934)
			(xy 52.006246 -318.375538) (xy 52.017168 -318.374522) (xy 52.049934 -318.372744) (xy 52.07564 -318.373251)
			(xy 52.126419 -318.381298) (xy 52.175314 -318.39719) (xy 52.221122 -318.420534) (xy 52.262714 -318.450756)
			(xy 52.299066 -318.487112) (xy 52.329284 -318.528707) (xy 52.352623 -318.574517) (xy 52.36851 -318.623414)
			(xy 52.376552 -318.674194) (xy 52.376552 -318.725606) (xy 52.36851 -318.776386) (xy 52.352623 -318.825283)
			(xy 52.329284 -318.871093) (xy 52.299066 -318.912688) (xy 52.262714 -318.949044) (xy 52.221122 -318.979266)
			(xy 52.175314 -319.00261) (xy 52.126419 -319.018502) (xy 52.07564 -319.026549) (xy 52.049934 -319.027048)
			(xy 52.017168 -319.02527) (xy 52.006246 -319.024254) (xy 51.98618 -319.030858) (xy 51.922172 -319.08877)
			(xy 51.914655 -319.096311) (xy 51.905978 -319.115731) (xy 51.905408 -319.126362) (xy 51.905408 -319.17513)
			(xy 51.905248 -319.188784) (xy 51.902961 -319.215997) (xy 51.900836 -319.229486) (xy 51.898804 -319.241424)
			(xy 51.905916 -319.26403) (xy 51.978814 -319.340484) (xy 52.001166 -319.348358) (xy 52.013358 -319.347088)
			(xy 52.022465 -319.346032) (xy 52.040766 -319.344886) (xy 52.049934 -319.344802) (xy 52.075464 -319.345313)
			(xy 52.125813 -319.353799) (xy 52.174048 -319.370546) (xy 52.218824 -319.395086) (xy 52.258891 -319.426735)
			(xy 52.293133 -319.464611) (xy 52.320594 -319.507657) (xy 52.340509 -319.554673) (xy 52.352322 -319.604347)
			(xy 52.35448 -319.62979) (xy 52.356004 -319.649856) (xy 52.385214 -319.677288) (xy 53.169566 -319.677288)
			(xy 53.175154 -319.677034) (xy 53.185405 -319.675367) (xy 53.203379 -319.665008) (xy 53.209952 -319.656968)
			(xy 53.213 -319.65265) (xy 53.219089 -319.642687) (xy 53.232568 -319.623618) (xy 53.239924 -319.61455)
			(xy 53.249713 -319.603032) (xy 53.271216 -319.581783) (xy 53.28285 -319.572132) (xy 53.291282 -319.564462)
			(xy 53.301025 -319.543891) (xy 53.301646 -319.532508) (xy 53.301392 -319.471294) (xy 53.29047 -319.449958)
			(xy 53.280564 -319.442846) (xy 53.259767 -319.427171) (xy 53.22291 -319.39038) (xy 53.192274 -319.348268)
			(xy 53.168614 -319.301877) (xy 53.152515 -319.252351) (xy 53.144374 -319.200915) (xy 53.143912 -319.174876)
			(xy 53.143912 -319.104518) (xy 53.143457 -319.093857) (xy 53.13478 -319.074383) (xy 53.127148 -319.066926)
			(xy 53.062886 -319.009014) (xy 53.042566 -319.00241) (xy 53.031644 -319.003426) (xy 52.999894 -319.005204)
			(xy 52.974639 -319.004682) (xy 52.924819 -318.996368) (xy 52.877047 -318.979966) (xy 52.832625 -318.955926)
			(xy 52.792767 -318.924902) (xy 52.758558 -318.887741) (xy 52.730932 -318.845456) (xy 52.710643 -318.799201)
			(xy 52.698244 -318.750237) (xy 52.694073 -318.6999) (xy 52.698244 -318.649563) (xy 52.710643 -318.600599)
			(xy 52.730932 -318.554344) (xy 52.758558 -318.512059) (xy 52.792767 -318.474898) (xy 52.832625 -318.443874)
			(xy 52.877047 -318.419834) (xy 52.924819 -318.403432) (xy 52.974639 -318.395118) (xy 52.999894 -318.394588)
			(xy 53.031644 -318.396366) (xy 53.042566 -318.397382) (xy 53.062886 -318.390778) (xy 53.127148 -318.332866)
			(xy 53.134653 -318.32532) (xy 53.143302 -318.3059) (xy 53.143912 -318.295274) (xy 53.143912 -318.224916)
			(xy 53.144075 -318.211262) (xy 53.146365 -318.18405) (xy 53.148484 -318.17056) (xy 53.150516 -318.158622)
			(xy 53.143404 -318.136016) (xy 53.070506 -318.059562) (xy 53.048154 -318.051688) (xy 53.036216 -318.053212)
			(xy 53.027169 -318.0542) (xy 53.008995 -318.055215) (xy 52.999894 -318.055244) (xy 52.97507 -318.054757)
			(xy 52.926075 -318.046724) (xy 52.879026 -318.03087) (xy 52.835162 -318.007613) (xy 52.795638 -317.977566)
			(xy 52.761496 -317.94152) (xy 52.733635 -317.900425) (xy 52.71279 -317.855364) (xy 52.69951 -317.807525)
			(xy 52.694145 -317.758167) (xy 52.696835 -317.708591) (xy 52.707511 -317.660104) (xy 52.725891 -317.613983)
			(xy 52.75149 -317.571443) (xy 52.783634 -317.533604) (xy 52.821477 -317.501465) (xy 52.86402 -317.475872)
			(xy 52.910144 -317.457499) (xy 52.958633 -317.44683) (xy 53.008209 -317.444146) (xy 53.057566 -317.449518)
			(xy 53.105404 -317.462805) (xy 53.150462 -317.483656) (xy 53.191552 -317.511522) (xy 53.227594 -317.545669)
			(xy 53.257636 -317.585197) (xy 53.280887 -317.629065) (xy 53.296734 -317.676116) (xy 53.304761 -317.725112)
			(xy 53.305202 -317.749936) (xy 53.305104 -317.75904) (xy 53.303961 -317.777213) (xy 53.302916 -317.786258)
			(xy 53.301646 -317.79845) (xy 53.30952 -317.820802) (xy 53.385974 -317.8937) (xy 53.40858 -317.900558)
			(xy 53.420518 -317.89878) (xy 53.433944 -317.896661) (xy 53.461029 -317.894372) (xy 53.47462 -317.894208)
			(xy 53.484038 -317.894243) (xy 53.502845 -317.895259) (xy 53.512212 -317.89624) (xy 53.523642 -317.897764)
			(xy 53.545486 -317.890144) (xy 53.61813 -317.817754) (xy 53.626004 -317.796164) (xy 53.624734 -317.784734)
			(xy 53.622956 -317.749936) (xy 53.623432 -317.724222) (xy 53.631473 -317.673427) (xy 53.647362 -317.624515)
			(xy 53.670709 -317.578692) (xy 53.700937 -317.537087) (xy 53.737303 -317.500723) (xy 53.778911 -317.470497)
			(xy 53.824736 -317.447154) (xy 53.873648 -317.431267) (xy 53.924444 -317.42323) (xy 53.975872 -317.423239)
			(xy 54.026665 -317.431295) (xy 54.075572 -317.447198) (xy 54.121388 -317.470558) (xy 54.162985 -317.500798)
			(xy 54.199338 -317.537175) (xy 54.229552 -317.578791) (xy 54.252882 -317.624623) (xy 54.268754 -317.67354)
			(xy 54.276777 -317.724338) (xy 54.276754 -317.775766) (xy 54.268683 -317.826556) (xy 54.252766 -317.875459)
			(xy 54.229393 -317.921268) (xy 54.19914 -317.962856) (xy 54.162753 -317.999199) (xy 54.121128 -318.029401)
			(xy 54.07529 -318.052718) (xy 54.026369 -318.068576) (xy 53.975568 -318.076585) (xy 53.949854 -318.077088)
			(xy 53.915056 -318.075056) (xy 53.903372 -318.073786) (xy 53.881782 -318.081406) (xy 53.809392 -318.154304)
			(xy 53.801772 -318.175894) (xy 53.803296 -318.187578) (xy 53.804266 -318.196882) (xy 53.805284 -318.215562)
			(xy 53.805328 -318.224916) (xy 53.805328 -318.27343) (xy 53.805794 -318.284085) (xy 53.814488 -318.303541)
			(xy 53.822092 -318.311022) (xy 53.8861 -318.368934) (xy 53.906166 -318.375538) (xy 53.917088 -318.374522)
			(xy 53.949854 -318.372744) (xy 53.975566 -318.373219) (xy 54.026359 -318.381257) (xy 54.075269 -318.397143)
			(xy 54.121091 -318.420484) (xy 54.162697 -318.450708) (xy 54.199062 -318.487068) (xy 54.229292 -318.52867)
			(xy 54.25264 -318.574489) (xy 54.268532 -318.623396) (xy 54.276578 -318.674188) (xy 54.276578 -318.725612)
			(xy 54.268532 -318.776404) (xy 54.25264 -318.825311) (xy 54.229292 -318.87113) (xy 54.199062 -318.912732)
			(xy 54.162697 -318.949092) (xy 54.121091 -318.979316) (xy 54.075269 -319.002657) (xy 54.026359 -319.018543)
			(xy 53.975566 -319.026581) (xy 53.949854 -319.027048) (xy 53.917088 -319.02527) (xy 53.906166 -319.024254)
			(xy 53.8861 -319.030858) (xy 53.822092 -319.08877) (xy 53.814584 -319.096316) (xy 53.805921 -319.115734)
			(xy 53.805328 -319.126362) (xy 53.805328 -319.17513) (xy 53.805167 -319.188784) (xy 53.802881 -319.215997)
			(xy 53.800756 -319.229486) (xy 53.798724 -319.241424) (xy 53.805836 -319.26403) (xy 53.878734 -319.340484)
			(xy 53.901086 -319.348358) (xy 53.913278 -319.347088) (xy 53.922386 -319.346033) (xy 53.940686 -319.344888)
			(xy 53.949854 -319.344802) (xy 53.975383 -319.345314) (xy 54.02573 -319.353803) (xy 54.073962 -319.370552)
			(xy 54.118735 -319.395093) (xy 54.158799 -319.426743) (xy 54.193038 -319.464618) (xy 54.220497 -319.507663)
			(xy 54.24041 -319.554677) (xy 54.252222 -319.60435) (xy 54.2544 -319.62979) (xy 54.255924 -319.649856)
			(xy 54.285134 -319.677288) (xy 55.06974 -319.677288) (xy 55.075328 -319.677034) (xy 55.085571 -319.675354)
			(xy 55.103523 -319.664979) (xy 55.110126 -319.656968) (xy 55.113174 -319.65265) (xy 55.119262 -319.642687)
			(xy 55.132741 -319.623617) (xy 55.140098 -319.61455) (xy 55.149784 -319.603181) (xy 55.171033 -319.58219)
			(xy 55.182516 -319.57264) (xy 55.18277 -319.572386) (xy 55.183024 -319.572132) (xy 55.187166 -319.568552)
			(xy 55.193957 -319.559969) (xy 55.196486 -319.555114) (xy 55.196486 -319.55486) (xy 55.198833 -319.549638)
			(xy 55.201404 -319.538485) (xy 55.201566 -319.532762) (xy 55.201312 -319.483486) (xy 55.200691 -319.471641)
			(xy 55.190093 -319.450453) (xy 55.180992 -319.442846) (xy 55.180484 -319.442592) (xy 55.18023 -319.442338)
			(xy 55.159511 -319.426653) (xy 55.122766 -319.389911) (xy 55.092214 -319.347878) (xy 55.068607 -319.301587)
			(xy 55.052524 -319.252175) (xy 55.04436 -319.200857) (xy 55.043832 -319.174876) (xy 55.043832 -319.104518)
			(xy 55.043377 -319.093857) (xy 55.034703 -319.07438) (xy 55.027068 -319.066926) (xy 54.962806 -319.009014)
			(xy 54.942486 -319.00241) (xy 54.931564 -319.003426) (xy 54.899814 -319.005204) (xy 54.874556 -319.004712)
			(xy 54.824728 -318.9964) (xy 54.776949 -318.979999) (xy 54.73252 -318.955957) (xy 54.692655 -318.924931)
			(xy 54.65844 -318.887765) (xy 54.63081 -318.845475) (xy 54.610517 -318.799214) (xy 54.598116 -318.750244)
			(xy 54.593944 -318.6999) (xy 54.598116 -318.649556) (xy 54.610517 -318.600586) (xy 54.63081 -318.554325)
			(xy 54.65844 -318.512035) (xy 54.692655 -318.474869) (xy 54.73252 -318.443843) (xy 54.776949 -318.419801)
			(xy 54.824728 -318.4034) (xy 54.874556 -318.395088) (xy 54.899814 -318.394588) (xy 54.931564 -318.396366)
			(xy 54.942486 -318.397382) (xy 54.962806 -318.390778) (xy 55.027068 -318.332866) (xy 55.034571 -318.325319)
			(xy 55.043216 -318.305899) (xy 55.043832 -318.295274) (xy 55.043832 -318.224916) (xy 55.043995 -318.211262)
			(xy 55.046286 -318.18405) (xy 55.048404 -318.17056) (xy 55.050436 -318.158622) (xy 55.043324 -318.136016)
			(xy 54.970426 -318.059562) (xy 54.948074 -318.051688) (xy 54.936136 -318.053212) (xy 54.927089 -318.054201)
			(xy 54.908915 -318.055217) (xy 54.899814 -318.055244) (xy 54.874989 -318.054759) (xy 54.825994 -318.046729)
			(xy 54.778943 -318.030877) (xy 54.735077 -318.007622) (xy 54.69555 -317.977577) (xy 54.661406 -317.941532)
			(xy 54.633543 -317.900438) (xy 54.612696 -317.855378) (xy 54.599413 -317.807539) (xy 54.594045 -317.75818)
			(xy 54.596734 -317.708604) (xy 54.607407 -317.660116) (xy 54.625786 -317.613993) (xy 54.651384 -317.571451)
			(xy 54.683527 -317.533612) (xy 54.721369 -317.501471) (xy 54.763913 -317.475876) (xy 54.810037 -317.457501)
			(xy 54.858526 -317.446831) (xy 54.908102 -317.444146) (xy 54.95746 -317.449517) (xy 55.005299 -317.462803)
			(xy 55.050358 -317.483654) (xy 55.091449 -317.51152) (xy 55.127492 -317.545667) (xy 55.157534 -317.585195)
			(xy 55.180786 -317.629063) (xy 55.196634 -317.676115) (xy 55.204661 -317.725111) (xy 55.205122 -317.749936)
			(xy 55.205082 -317.759037) (xy 55.204063 -317.777209) (xy 55.20309 -317.786258) (xy 55.201566 -317.798196)
			(xy 55.20944 -317.820548) (xy 55.285894 -317.893446) (xy 55.3085 -317.900558) (xy 55.320438 -317.898526)
			(xy 55.333926 -317.896396) (xy 55.361139 -317.894106) (xy 55.374794 -317.893954) (xy 55.384148 -317.893997)
			(xy 55.402828 -317.895015) (xy 55.412132 -317.895986) (xy 55.423816 -317.897256) (xy 55.445406 -317.88989)
			(xy 55.51805 -317.8175) (xy 55.525924 -317.79591) (xy 55.524654 -317.78448) (xy 55.522876 -317.749936)
			(xy 55.523352 -317.724224) (xy 55.531392 -317.673433) (xy 55.54728 -317.624525) (xy 55.570624 -317.578705)
			(xy 55.600851 -317.537102) (xy 55.637214 -317.500741) (xy 55.678818 -317.470516) (xy 55.724639 -317.447174)
			(xy 55.773547 -317.431288) (xy 55.824339 -317.42325) (xy 55.875763 -317.423258) (xy 55.926553 -317.431312)
			(xy 55.975456 -317.447213) (xy 56.02127 -317.47057) (xy 56.062865 -317.500807) (xy 56.099216 -317.53718)
			(xy 56.129429 -317.578793) (xy 56.152759 -317.62462) (xy 56.168632 -317.673533) (xy 56.176656 -317.724326)
			(xy 56.176635 -317.77575) (xy 56.168567 -317.826538) (xy 56.152653 -317.875437) (xy 56.129284 -317.921244)
			(xy 56.099036 -317.962831) (xy 56.062653 -317.999173) (xy 56.021033 -318.029375) (xy 55.9752 -318.052693)
			(xy 55.926282 -318.068553) (xy 55.875486 -318.076563) (xy 55.849774 -318.077088) (xy 55.81523 -318.075056)
			(xy 55.8038 -318.073786) (xy 55.78221 -318.08166) (xy 55.70982 -318.154304) (xy 55.702454 -318.175894)
			(xy 55.703724 -318.187578) (xy 55.704692 -318.196882) (xy 55.705709 -318.215562) (xy 55.705756 -318.224916)
			(xy 55.705756 -318.27343) (xy 55.706223 -318.284085) (xy 55.71492 -318.303537) (xy 55.72252 -318.311022)
			(xy 55.786274 -318.368934) (xy 55.806594 -318.375538) (xy 55.817516 -318.374522) (xy 55.849774 -318.372744)
			(xy 55.875485 -318.37322) (xy 55.926276 -318.381261) (xy 55.975183 -318.397148) (xy 56.021002 -318.420491)
			(xy 56.062605 -318.450715) (xy 56.098968 -318.487075) (xy 56.129195 -318.528676) (xy 56.152542 -318.574493)
			(xy 56.168433 -318.623399) (xy 56.176478 -318.674189) (xy 56.176478 -318.725611) (xy 56.168433 -318.776401)
			(xy 56.152542 -318.825307) (xy 56.129195 -318.871124) (xy 56.098968 -318.912725) (xy 56.062605 -318.949085)
			(xy 56.021002 -318.979309) (xy 55.975183 -319.002652) (xy 55.926276 -319.018539) (xy 55.875485 -319.02658)
			(xy 55.849774 -319.027048) (xy 55.817516 -319.02527) (xy 55.806594 -319.024254) (xy 55.786274 -319.030858)
			(xy 55.72252 -319.08877) (xy 55.715009 -319.096314) (xy 55.706341 -319.115733) (xy 55.705756 -319.126362)
			(xy 55.705756 -319.174876) (xy 55.705603 -319.188594) (xy 55.703318 -319.215934) (xy 55.701184 -319.229486)
			(xy 55.699152 -319.241424) (xy 55.706264 -319.26403) (xy 55.779162 -319.340484) (xy 55.801514 -319.348358)
			(xy 55.813452 -319.347088) (xy 55.822559 -319.346032) (xy 55.84086 -319.344886) (xy 55.850028 -319.344802)
			(xy 55.875558 -319.345312) (xy 55.925908 -319.353798) (xy 55.974144 -319.370544) (xy 56.018921 -319.395084)
			(xy 56.058989 -319.426733) (xy 56.093232 -319.464609) (xy 56.120693 -319.507655) (xy 56.140609 -319.554672)
			(xy 56.152422 -319.604347) (xy 56.154574 -319.62979) (xy 56.156098 -319.649856) (xy 56.185308 -319.677288)
			(xy 56.969914 -319.677288) (xy 56.975502 -319.677034) (xy 56.987085 -319.675103) (xy 57.006805 -319.662401)
			(xy 57.013348 -319.65265) (xy 57.027551 -319.630074) (xy 57.06255 -319.58983) (xy 57.082944 -319.57264)
			(xy 57.08777 -319.56883) (xy 57.094882 -319.559432) (xy 57.10174 -319.543684) (xy 57.10174 -319.532762)
			(xy 57.101486 -319.471294) (xy 57.09031 -319.449704) (xy 57.080404 -319.442592) (xy 57.05971 -319.426919)
			(xy 57.023011 -319.390209) (xy 56.992501 -319.348214) (xy 56.96893 -319.301967) (xy 56.952876 -319.252603)
			(xy 56.944735 -319.201338) (xy 56.94426 -319.175384) (xy 56.94426 -319.104518) (xy 56.943703 -319.093823)
			(xy 56.93505 -319.074261) (xy 56.927496 -319.066672) (xy 56.863234 -319.009014) (xy 56.842914 -319.00241)
			(xy 56.831992 -319.003426) (xy 56.799988 -319.005204) (xy 56.774734 -319.004682) (xy 56.724914 -318.996366)
			(xy 56.677143 -318.979965) (xy 56.632722 -318.955924) (xy 56.592864 -318.9249) (xy 56.558656 -318.887739)
			(xy 56.531031 -318.845454) (xy 56.510743 -318.799199) (xy 56.498344 -318.750236) (xy 56.494173 -318.6999)
			(xy 56.498344 -318.649564) (xy 56.510743 -318.600601) (xy 56.531031 -318.554346) (xy 56.558656 -318.512061)
			(xy 56.592864 -318.4749) (xy 56.632722 -318.443876) (xy 56.677143 -318.419835) (xy 56.724914 -318.403434)
			(xy 56.774734 -318.395118) (xy 56.799988 -318.394588) (xy 56.831992 -318.396366) (xy 56.842914 -318.397382)
			(xy 56.863234 -318.390778) (xy 56.927496 -318.33312) (xy 56.935155 -318.325602) (xy 56.94384 -318.305998)
			(xy 56.94426 -318.295274) (xy 56.94426 -318.224916) (xy 56.944423 -318.211262) (xy 56.946714 -318.18405)
			(xy 56.948832 -318.17056) (xy 56.950864 -318.158622) (xy 56.943752 -318.136016) (xy 56.870854 -318.059562)
			(xy 56.848502 -318.051688) (xy 56.83631 -318.052958) (xy 56.827266 -318.054006) (xy 56.809092 -318.055149)
			(xy 56.799988 -318.055244) (xy 56.775164 -318.054757) (xy 56.72617 -318.046723) (xy 56.679121 -318.030868)
			(xy 56.635257 -318.00761) (xy 56.595734 -317.977562) (xy 56.561593 -317.941516) (xy 56.533733 -317.900421)
			(xy 56.512889 -317.85536) (xy 56.499609 -317.80752) (xy 56.494245 -317.758163) (xy 56.496936 -317.708587)
			(xy 56.507612 -317.660101) (xy 56.525992 -317.61398) (xy 56.551592 -317.57144) (xy 56.583736 -317.533602)
			(xy 56.621579 -317.501464) (xy 56.664123 -317.475871) (xy 56.710246 -317.457498) (xy 56.758735 -317.446829)
			(xy 56.808311 -317.444146) (xy 56.857668 -317.449518) (xy 56.905505 -317.462805) (xy 56.950563 -317.483657)
			(xy 56.991653 -317.511523) (xy 57.027694 -317.54567) (xy 57.057736 -317.585198) (xy 57.080987 -317.629065)
			(xy 57.096834 -317.676116) (xy 57.104861 -317.725112) (xy 57.105296 -317.749936) (xy 57.105198 -317.75904)
			(xy 57.104055 -317.777213) (xy 57.10301 -317.786258) (xy 57.10174 -317.79845) (xy 57.109614 -317.820802)
			(xy 57.186068 -317.8937) (xy 57.208674 -317.900812) (xy 57.220612 -317.89878) (xy 57.2341 -317.896648)
			(xy 57.261313 -317.894357) (xy 57.274968 -317.894208) (xy 57.284322 -317.89425) (xy 57.303003 -317.895264)
			(xy 57.312306 -317.89624) (xy 57.32399 -317.897764) (xy 57.34558 -317.890144) (xy 57.418224 -317.817754)
			(xy 57.426098 -317.796164) (xy 57.424828 -317.78448) (xy 57.422796 -317.749936) (xy 57.423298 -317.724232)
			(xy 57.431334 -317.673457) (xy 57.447214 -317.624564) (xy 57.470547 -317.578756) (xy 57.500759 -317.537163)
			(xy 57.537106 -317.500809) (xy 57.578692 -317.470587) (xy 57.624493 -317.447243) (xy 57.673383 -317.431352)
			(xy 57.724156 -317.423304) (xy 57.775564 -317.423297) (xy 57.826339 -317.431333) (xy 57.875233 -317.447213)
			(xy 57.92104 -317.470545) (xy 57.962634 -317.500757) (xy 57.998989 -317.537103) (xy 58.029211 -317.578688)
			(xy 58.052555 -317.624489) (xy 58.068447 -317.673379) (xy 58.076496 -317.724152) (xy 58.0765 -317.749936)
			(xy 58.394104 -317.749936) (xy 58.398064 -317.700882) (xy 58.409841 -317.653098) (xy 58.429132 -317.607822)
			(xy 58.455435 -317.566226) (xy 58.48807 -317.529389) (xy 58.526191 -317.498264) (xy 58.568812 -317.473657)
			(xy 58.614828 -317.456205) (xy 58.663047 -317.446361) (xy 58.712222 -317.44438) (xy 58.761077 -317.450312)
			(xy 58.808348 -317.464004) (xy 58.85281 -317.485102) (xy 58.893313 -317.513058) (xy 58.928806 -317.54715)
			(xy 58.958371 -317.586494) (xy 58.981242 -317.630071) (xy 58.996826 -317.676752) (xy 59.004721 -317.725329)
			(xy 59.005216 -317.749936) (xy 59.004721 -317.774543) (xy 58.996826 -317.82312) (xy 58.981242 -317.869801)
			(xy 58.958371 -317.913378) (xy 58.928806 -317.952722) (xy 58.893313 -317.986814) (xy 58.85281 -318.01477)
			(xy 58.808348 -318.035868) (xy 58.761077 -318.04956) (xy 58.712222 -318.055492) (xy 58.663047 -318.053511)
			(xy 58.614828 -318.043667) (xy 58.568812 -318.026215) (xy 58.526191 -318.001608) (xy 58.48807 -317.970483)
			(xy 58.455435 -317.933646) (xy 58.429132 -317.89205) (xy 58.409841 -317.846774) (xy 58.398064 -317.79899)
			(xy 58.394104 -317.749936) (xy 58.0765 -317.749936) (xy 58.076503 -317.77556) (xy 58.068468 -317.826335)
			(xy 58.052589 -317.875229) (xy 58.029257 -317.921037) (xy 57.999046 -317.96263) (xy 57.962701 -317.998986)
			(xy 57.921115 -318.029209) (xy 57.875314 -318.052554) (xy 57.826425 -318.068447) (xy 57.775652 -318.076496)
			(xy 57.749948 -318.077088) (xy 57.715404 -318.075056) (xy 57.70372 -318.073786) (xy 57.68213 -318.08166)
			(xy 57.60974 -318.154304) (xy 57.60212 -318.175894) (xy 57.603644 -318.187578) (xy 57.604614 -318.196882)
			(xy 57.605632 -318.215562) (xy 57.605676 -318.224916) (xy 57.605676 -318.27343) (xy 57.606141 -318.284087)
			(xy 57.614828 -318.303548) (xy 57.62244 -318.311022) (xy 57.686194 -318.368934) (xy 57.706514 -318.375538)
			(xy 57.717436 -318.374522) (xy 57.749948 -318.372744) (xy 57.775654 -318.373252) (xy 57.826431 -318.381301)
			(xy 57.875324 -318.397194) (xy 57.92113 -318.420539) (xy 57.96272 -318.450761) (xy 57.99907 -318.487117)
			(xy 58.029287 -318.528711) (xy 58.052625 -318.57452) (xy 58.06851 -318.623416) (xy 58.076552 -318.674194)
			(xy 58.076552 -318.699896) (xy 58.394104 -318.699896) (xy 58.398064 -318.650842) (xy 58.409841 -318.603058)
			(xy 58.429132 -318.557782) (xy 58.455435 -318.516186) (xy 58.48807 -318.479349) (xy 58.526191 -318.448224)
			(xy 58.568812 -318.423617) (xy 58.614828 -318.406165) (xy 58.663047 -318.396321) (xy 58.712222 -318.39434)
			(xy 58.761077 -318.400272) (xy 58.808348 -318.413964) (xy 58.85281 -318.435062) (xy 58.893313 -318.463018)
			(xy 58.928806 -318.49711) (xy 58.958371 -318.536454) (xy 58.981242 -318.580031) (xy 58.996826 -318.626712)
			(xy 59.004721 -318.675289) (xy 59.005216 -318.699896) (xy 59.004721 -318.724503) (xy 58.996826 -318.77308)
			(xy 58.981242 -318.819761) (xy 58.958371 -318.863338) (xy 58.928806 -318.902682) (xy 58.893313 -318.936774)
			(xy 58.85281 -318.96473) (xy 58.808348 -318.985828) (xy 58.761077 -318.99952) (xy 58.712222 -319.005452)
			(xy 58.663047 -319.003471) (xy 58.614828 -318.993627) (xy 58.568812 -318.976175) (xy 58.526191 -318.951568)
			(xy 58.48807 -318.920443) (xy 58.455435 -318.883606) (xy 58.429132 -318.84201) (xy 58.409841 -318.796734)
			(xy 58.398064 -318.74895) (xy 58.394104 -318.699896) (xy 58.076552 -318.699896) (xy 58.076552 -318.725606)
			(xy 58.06851 -318.776384) (xy 58.052625 -318.82528) (xy 58.029287 -318.871089) (xy 57.99907 -318.912683)
			(xy 57.96272 -318.949039) (xy 57.92113 -318.979261) (xy 57.875324 -319.002606) (xy 57.826431 -319.018499)
			(xy 57.775654 -319.026548) (xy 57.749948 -319.027048) (xy 57.717436 -319.02527) (xy 57.706514 -319.024254)
			(xy 57.686194 -319.030858) (xy 57.62244 -319.08877) (xy 57.614926 -319.096313) (xy 57.606255 -319.115732)
			(xy 57.605676 -319.126362) (xy 57.605676 -319.17513) (xy 57.605515 -319.188784) (xy 57.603229 -319.215997)
			(xy 57.601104 -319.229486) (xy 57.599072 -319.241424) (xy 57.606184 -319.26403) (xy 57.679082 -319.340484)
			(xy 57.701434 -319.348358) (xy 57.713626 -319.347088) (xy 57.722734 -319.346034) (xy 57.741034 -319.344892)
			(xy 57.750202 -319.344802) (xy 57.775734 -319.34531) (xy 57.826087 -319.353792) (xy 57.874327 -319.370536)
			(xy 57.919107 -319.395075) (xy 57.959179 -319.426724) (xy 57.993425 -319.4646) (xy 58.020889 -319.507648)
			(xy 58.040807 -319.554666) (xy 58.052621 -319.604344) (xy 58.054748 -319.62979) (xy 58.056272 -319.649856)
			(xy 58.085482 -319.677288) (xy 59.314588 -319.677288) (xy 59.343798 -319.649856) (xy 59.345322 -319.62979)
			(xy 59.347541 -319.604359) (xy 59.359374 -319.554706) (xy 59.379298 -319.507711) (xy 59.406759 -319.464683)
			(xy 59.440993 -319.42682) (xy 59.481045 -319.395177) (xy 59.525802 -319.370633) (xy 59.574016 -319.353874)
			(xy 59.624346 -319.345365) (xy 59.649868 -319.344802) (xy 59.658972 -319.344901) (xy 59.677145 -319.346046)
			(xy 59.68619 -319.347088) (xy 59.698382 -319.348358) (xy 59.720734 -319.340484) (xy 59.793632 -319.26403)
			(xy 59.800744 -319.241424) (xy 59.798712 -319.229486) (xy 59.79658 -319.215998) (xy 59.79429 -319.188785)
			(xy 59.79414 -319.17513) (xy 59.79414 -319.126362) (xy 59.793671 -319.115708) (xy 59.784972 -319.096259)
			(xy 59.777376 -319.08877) (xy 59.713622 -319.030858) (xy 59.693302 -319.024254) (xy 59.68238 -319.02527)
			(xy 59.649868 -319.027048) (xy 59.624162 -319.026542) (xy 59.573384 -319.018495) (xy 59.52449 -319.002604)
			(xy 59.478683 -318.97926) (xy 59.437092 -318.949039) (xy 59.400741 -318.912683) (xy 59.370523 -318.871089)
			(xy 59.347184 -318.82528) (xy 59.331298 -318.776385) (xy 59.323256 -318.725606) (xy 59.323256 -318.674194)
			(xy 59.331298 -318.623415) (xy 59.347184 -318.57452) (xy 59.370523 -318.528711) (xy 59.400741 -318.487117)
			(xy 59.437092 -318.450761) (xy 59.478683 -318.42054) (xy 59.52449 -318.397196) (xy 59.573384 -318.381305)
			(xy 59.624162 -318.373258) (xy 59.649868 -318.372744) (xy 59.68238 -318.374522) (xy 59.693302 -318.375538)
			(xy 59.713622 -318.368934) (xy 59.777376 -318.311022) (xy 59.784887 -318.303478) (xy 59.793552 -318.284059)
			(xy 59.79414 -318.27343) (xy 59.79414 -318.224916) (xy 59.794183 -318.215562) (xy 59.795198 -318.196881)
			(xy 59.796172 -318.187578) (xy 59.797696 -318.175894) (xy 59.790076 -318.154304) (xy 59.717686 -318.08166)
			(xy 59.696096 -318.073786) (xy 59.684412 -318.075056) (xy 59.649868 -318.077088) (xy 59.624155 -318.076607)
			(xy 59.573364 -318.068558) (xy 59.524457 -318.052661) (xy 59.478639 -318.02931) (xy 59.437038 -317.999079)
			(xy 59.400678 -317.962712) (xy 59.370456 -317.921105) (xy 59.347114 -317.875282) (xy 59.331227 -317.826372)
			(xy 59.323188 -317.775579) (xy 59.323193 -317.724154) (xy 59.331243 -317.673363) (xy 59.347139 -317.624456)
			(xy 59.37049 -317.578638) (xy 59.400722 -317.537037) (xy 59.437089 -317.500678) (xy 59.478696 -317.470455)
			(xy 59.524519 -317.447113) (xy 59.573429 -317.431227) (xy 59.624222 -317.423188) (xy 59.675647 -317.423193)
			(xy 59.726439 -317.431243) (xy 59.775345 -317.44714) (xy 59.821163 -317.470491) (xy 59.862764 -317.500723)
			(xy 59.899123 -317.53709) (xy 59.929346 -317.578697) (xy 59.952687 -317.62452) (xy 59.968573 -317.67343)
			(xy 59.976613 -317.724223) (xy 59.97702 -317.749936) (xy 59.974988 -317.78448) (xy 59.973718 -317.796164)
			(xy 59.981592 -317.817754) (xy 60.054236 -317.890144) (xy 60.075826 -317.897764) (xy 60.08751 -317.89624)
			(xy 60.096814 -317.895271) (xy 60.115494 -317.894255) (xy 60.124848 -317.894208) (xy 60.138502 -317.894369)
			(xy 60.165715 -317.896657) (xy 60.179204 -317.89878) (xy 60.191142 -317.900812) (xy 60.213748 -317.8937)
			(xy 60.290202 -317.820802) (xy 60.298076 -317.79845) (xy 60.296806 -317.786258) (xy 60.295756 -317.777214)
			(xy 60.29461 -317.75904) (xy 60.29452 -317.749936) (xy 60.295003 -317.725117) (xy 60.303028 -317.676133)
			(xy 60.318871 -317.629092) (xy 60.342117 -317.585234) (xy 60.372152 -317.545714) (xy 60.408184 -317.511575)
			(xy 60.449266 -317.483714) (xy 60.494313 -317.462867) (xy 60.54214 -317.449582) (xy 60.591486 -317.44421)
			(xy 60.641051 -317.446892) (xy 60.689529 -317.457557) (xy 60.735643 -317.475925) (xy 60.778178 -317.501511)
			(xy 60.816013 -317.533642) (xy 60.848151 -317.57147) (xy 60.873746 -317.614) (xy 60.892124 -317.66011)
			(xy 60.902799 -317.708586) (xy 60.905492 -317.75815) (xy 60.90013 -317.807497) (xy 60.886855 -317.855327)
			(xy 60.866017 -317.900379) (xy 60.838165 -317.941466) (xy 60.804033 -317.977505) (xy 60.76452 -318.007549)
			(xy 60.720667 -318.030803) (xy 60.673629 -318.046657) (xy 60.624647 -318.054692) (xy 60.599828 -318.055244)
			(xy 60.590724 -318.055145) (xy 60.572551 -318.054) (xy 60.563506 -318.052958) (xy 60.551314 -318.051688)
			(xy 60.528962 -318.059562) (xy 60.456064 -318.136016) (xy 60.448952 -318.158622) (xy 60.450984 -318.17056)
			(xy 60.453114 -318.184048) (xy 60.4554 -318.211262) (xy 60.455556 -318.224916) (xy 60.455556 -318.295274)
			(xy 60.456112 -318.305969) (xy 60.464764 -318.325532) (xy 60.47232 -318.33312) (xy 60.536582 -318.390778)
			(xy 60.556902 -318.397382) (xy 60.567824 -318.396366) (xy 60.599828 -318.394588) (xy 60.625082 -318.395112)
			(xy 60.674901 -318.403429) (xy 60.722671 -318.419833) (xy 60.767091 -318.443875) (xy 60.806947 -318.4749)
			(xy 60.841154 -318.512062) (xy 60.868778 -318.554346) (xy 60.889066 -318.600601) (xy 60.901464 -318.649564)
			(xy 60.905635 -318.6999) (xy 60.901464 -318.750236) (xy 60.889066 -318.799199) (xy 60.868778 -318.845454)
			(xy 60.841154 -318.887738) (xy 60.806947 -318.9249) (xy 60.767091 -318.955925) (xy 60.722671 -318.979967)
			(xy 60.674901 -318.996371) (xy 60.625082 -319.004688) (xy 60.599828 -319.005204) (xy 60.567824 -319.003426)
			(xy 60.556902 -319.00241) (xy 60.536582 -319.009014) (xy 60.47232 -319.066672) (xy 60.464658 -319.074189)
			(xy 60.455967 -319.093793) (xy 60.455556 -319.104518) (xy 60.455556 -319.174876) (xy 60.455065 -319.200892)
			(xy 60.446903 -319.252281) (xy 60.430794 -319.301758) (xy 60.407135 -319.3481) (xy 60.376509 -319.390166)
			(xy 60.339673 -319.426915) (xy 60.318904 -319.442592) (xy 60.318396 -319.4431) (xy 60.318142 -319.4431)
			(xy 60.30904 -319.450704) (xy 60.298456 -319.471896) (xy 60.297822 -319.48374) (xy 60.297568 -319.532254)
			(xy 60.298024 -319.543673) (xy 60.30781 -319.5643) (xy 60.316364 -319.571878) (xy 60.336922 -319.58923)
			(xy 60.372182 -319.629855) (xy 60.386468 -319.65265) (xy 60.389008 -319.656206) (xy 60.395644 -319.664467)
			(xy 60.413873 -319.675227) (xy 60.424314 -319.677034) (xy 60.429902 -319.677288) (xy 61.214508 -319.677288)
			(xy 61.243718 -319.649856) (xy 61.245242 -319.62979) (xy 61.247461 -319.60436) (xy 61.259294 -319.554708)
			(xy 61.279219 -319.507714) (xy 61.30668 -319.464688) (xy 61.340914 -319.426827) (xy 61.380967 -319.395186)
			(xy 61.425723 -319.370646) (xy 61.473938 -319.353889) (xy 61.524267 -319.345383) (xy 61.549788 -319.344802)
			(xy 61.558892 -319.344901) (xy 61.577065 -319.346047) (xy 61.58611 -319.347088) (xy 61.598302 -319.348358)
			(xy 61.620654 -319.340484) (xy 61.693552 -319.26403) (xy 61.700664 -319.241424) (xy 61.698632 -319.229486)
			(xy 61.6965 -319.215998) (xy 61.69421 -319.188785) (xy 61.69406 -319.17513) (xy 61.69406 -319.126362)
			(xy 61.693592 -319.115708) (xy 61.684895 -319.096256) (xy 61.677296 -319.08877) (xy 61.613542 -319.030858)
			(xy 61.593222 -319.024254) (xy 61.5823 -319.02527) (xy 61.549788 -319.027048) (xy 61.524081 -319.026543)
			(xy 61.473301 -319.018499) (xy 61.424404 -319.002609) (xy 61.378595 -318.979267) (xy 61.337001 -318.949046)
			(xy 61.300646 -318.91269) (xy 61.270427 -318.871095) (xy 61.247086 -318.825285) (xy 61.231199 -318.776388)
			(xy 61.223156 -318.725607) (xy 61.223156 -318.674193) (xy 61.231199 -318.623412) (xy 61.247086 -318.574515)
			(xy 61.270427 -318.528705) (xy 61.300646 -318.48711) (xy 61.337001 -318.450754) (xy 61.378595 -318.420533)
			(xy 61.424404 -318.397191) (xy 61.473301 -318.381301) (xy 61.524081 -318.373257) (xy 61.549788 -318.372744)
			(xy 61.5823 -318.374522) (xy 61.593222 -318.375538) (xy 61.613542 -318.368934) (xy 61.677296 -318.311022)
			(xy 61.684804 -318.303476) (xy 61.693466 -318.284058) (xy 61.69406 -318.27343) (xy 61.69406 -318.224916)
			(xy 61.694103 -318.215562) (xy 61.695118 -318.196881) (xy 61.696092 -318.187578) (xy 61.697616 -318.175894)
			(xy 61.689996 -318.154304) (xy 61.617606 -318.08166) (xy 61.596016 -318.073786) (xy 61.584332 -318.075056)
			(xy 61.549788 -318.077088) (xy 61.524075 -318.076609) (xy 61.473282 -318.068562) (xy 61.424374 -318.052668)
			(xy 61.378554 -318.029319) (xy 61.336951 -317.99909) (xy 61.300589 -317.962725) (xy 61.270364 -317.921119)
			(xy 61.247019 -317.875296) (xy 61.231131 -317.826386) (xy 61.223089 -317.775593) (xy 61.223092 -317.724167)
			(xy 61.23114 -317.673375) (xy 61.247035 -317.624467) (xy 61.270385 -317.578647) (xy 61.300615 -317.537045)
			(xy 61.336981 -317.500684) (xy 61.378588 -317.47046) (xy 61.424411 -317.447116) (xy 61.473321 -317.431229)
			(xy 61.524115 -317.423188) (xy 61.575541 -317.423192) (xy 61.626333 -317.431242) (xy 61.675241 -317.447138)
			(xy 61.72106 -317.470489) (xy 61.762661 -317.50072) (xy 61.799021 -317.537088) (xy 61.829245 -317.578695)
			(xy 61.852587 -317.624518) (xy 61.868473 -317.673429) (xy 61.876513 -317.724223) (xy 61.87694 -317.749936)
			(xy 61.874908 -317.78448) (xy 61.873638 -317.796164) (xy 61.881512 -317.817754) (xy 61.954156 -317.890144)
			(xy 61.975746 -317.897764) (xy 61.98743 -317.89624) (xy 61.996734 -317.895272) (xy 62.015414 -317.894256)
			(xy 62.024768 -317.894208) (xy 62.038422 -317.89437) (xy 62.065635 -317.896659) (xy 62.079124 -317.89878)
			(xy 62.091062 -317.900812) (xy 62.113668 -317.8937) (xy 62.190122 -317.820802) (xy 62.197996 -317.79845)
			(xy 62.196726 -317.786258) (xy 62.195677 -317.777214) (xy 62.194531 -317.75904) (xy 62.19444 -317.749936)
			(xy 62.194923 -317.725119) (xy 62.202947 -317.676139) (xy 62.218789 -317.629101) (xy 62.242033 -317.585247)
			(xy 62.272065 -317.54573) (xy 62.308094 -317.511593) (xy 62.349172 -317.483734) (xy 62.394215 -317.462887)
			(xy 62.442038 -317.449603) (xy 62.49138 -317.44423) (xy 62.540941 -317.446911) (xy 62.589415 -317.457574)
			(xy 62.635526 -317.475939) (xy 62.678058 -317.501522) (xy 62.715891 -317.533649) (xy 62.748029 -317.571473)
			(xy 62.773623 -317.613999) (xy 62.792001 -317.660104) (xy 62.802678 -317.708576) (xy 62.805372 -317.758136)
			(xy 62.800013 -317.80748) (xy 62.786742 -317.855306) (xy 62.765908 -317.900355) (xy 62.73806 -317.94144)
			(xy 62.703933 -317.977479) (xy 62.664424 -318.007522) (xy 62.620576 -318.030778) (xy 62.573543 -318.046633)
			(xy 62.524565 -318.05467) (xy 62.499748 -318.055244) (xy 62.490644 -318.055146) (xy 62.472471 -318.054001)
			(xy 62.463426 -318.052958) (xy 62.451234 -318.051688) (xy 62.428882 -318.059562) (xy 62.355984 -318.136016)
			(xy 62.348872 -318.158622) (xy 62.350904 -318.17056) (xy 62.353034 -318.184048) (xy 62.35532 -318.211262)
			(xy 62.355476 -318.224916) (xy 62.355476 -318.295274) (xy 62.356029 -318.305971) (xy 62.364673 -318.325543)
			(xy 62.37224 -318.33312) (xy 62.436502 -318.390778) (xy 62.456822 -318.397382) (xy 62.467744 -318.396366)
			(xy 62.499748 -318.394588) (xy 62.525001 -318.395113) (xy 62.574817 -318.403433) (xy 62.622585 -318.419839)
			(xy 62.667001 -318.443882) (xy 62.706855 -318.474907) (xy 62.741059 -318.512068) (xy 62.768681 -318.554352)
			(xy 62.788967 -318.600605) (xy 62.801365 -318.649566) (xy 62.805535 -318.6999) (xy 62.801365 -318.750234)
			(xy 62.788967 -318.799195) (xy 62.768681 -318.845448) (xy 62.741059 -318.887732) (xy 62.706855 -318.924893)
			(xy 62.667001 -318.955918) (xy 62.622585 -318.979961) (xy 62.574817 -318.996367) (xy 62.525001 -319.004687)
			(xy 62.499748 -319.005204) (xy 62.467744 -319.003426) (xy 62.456822 -319.00241) (xy 62.436502 -319.009014)
			(xy 62.37224 -319.066672) (xy 62.364575 -319.074187) (xy 62.355881 -319.093792) (xy 62.355476 -319.104518)
			(xy 62.355476 -319.174876) (xy 62.354985 -319.200893) (xy 62.346824 -319.252282) (xy 62.330715 -319.301759)
			(xy 62.307057 -319.348103) (xy 62.276432 -319.390169) (xy 62.239597 -319.426921) (xy 62.218824 -319.442592)
			(xy 62.218316 -319.4431) (xy 62.218062 -319.4431) (xy 62.208957 -319.450702) (xy 62.198369 -319.471894)
			(xy 62.197742 -319.48374) (xy 62.197488 -319.532254) (xy 62.197941 -319.543675) (xy 62.207716 -319.564314)
			(xy 62.216284 -319.571878) (xy 62.236846 -319.589226) (xy 62.272114 -319.629846) (xy 62.286388 -319.65265)
			(xy 62.288928 -319.656206) (xy 62.295565 -319.664464) (xy 62.313796 -319.675218) (xy 62.324234 -319.677034)
			(xy 62.329822 -319.677288) (xy 63.114682 -319.677288) (xy 63.143892 -319.649856) (xy 63.145416 -319.62979)
			(xy 63.147635 -319.604359) (xy 63.159468 -319.554705) (xy 63.179392 -319.50771) (xy 63.206853 -319.464681)
			(xy 63.241086 -319.426818) (xy 63.281139 -319.395174) (xy 63.325895 -319.37063) (xy 63.37411 -319.353869)
			(xy 63.42444 -319.345359) (xy 63.449962 -319.344802) (xy 63.459066 -319.3449) (xy 63.477239 -319.346045)
			(xy 63.486284 -319.347088) (xy 63.498222 -319.348358) (xy 63.520574 -319.340484) (xy 63.593472 -319.26403)
			(xy 63.600584 -319.241424) (xy 63.598552 -319.229232) (xy 63.596422 -319.215744) (xy 63.594136 -319.18853)
			(xy 63.59398 -319.174876) (xy 63.59398 -319.126362) (xy 63.593513 -319.115707) (xy 63.584818 -319.096253)
			(xy 63.577216 -319.08877) (xy 63.513462 -319.030858) (xy 63.493142 -319.024254) (xy 63.48222 -319.02527)
			(xy 63.449962 -319.027048) (xy 63.424257 -319.026541) (xy 63.373479 -319.018493) (xy 63.324586 -319.002602)
			(xy 63.27878 -318.979258) (xy 63.23719 -318.949036) (xy 63.200839 -318.912681) (xy 63.170622 -318.871087)
			(xy 63.147284 -318.825279) (xy 63.131398 -318.776384) (xy 63.123356 -318.725606) (xy 63.123356 -318.674194)
			(xy 63.131398 -318.623416) (xy 63.147284 -318.574521) (xy 63.170622 -318.528713) (xy 63.200839 -318.487119)
			(xy 63.23719 -318.450764) (xy 63.27878 -318.420542) (xy 63.324586 -318.397198) (xy 63.373479 -318.381307)
			(xy 63.424257 -318.373259) (xy 63.449962 -318.372744) (xy 63.48222 -318.374522) (xy 63.493142 -318.375538)
			(xy 63.513462 -318.368934) (xy 63.577216 -318.311022) (xy 63.584722 -318.303476) (xy 63.59338 -318.284057)
			(xy 63.59398 -318.27343) (xy 63.59398 -318.224916) (xy 63.594023 -318.215562) (xy 63.59504 -318.196882)
			(xy 63.596012 -318.187578) (xy 63.597282 -318.175894) (xy 63.589916 -318.154304) (xy 63.517526 -318.08166)
			(xy 63.495936 -318.073786) (xy 63.484506 -318.075056) (xy 63.449962 -318.077088) (xy 63.42428 -318.076582)
			(xy 63.373549 -318.068542) (xy 63.3247 -318.052667) (xy 63.278935 -318.029347) (xy 63.23738 -317.999157)
			(xy 63.201059 -317.962838) (xy 63.170866 -317.921286) (xy 63.147542 -317.875523) (xy 63.131664 -317.826675)
			(xy 63.12362 -317.775945) (xy 63.12361 -317.724581) (xy 63.131634 -317.673847) (xy 63.147494 -317.624993)
			(xy 63.1708 -317.579221) (xy 63.200978 -317.537657) (xy 63.237285 -317.501325) (xy 63.278828 -317.471118)
			(xy 63.324584 -317.447781) (xy 63.373427 -317.431887) (xy 63.424155 -317.423828) (xy 63.475519 -317.423803)
			(xy 63.526255 -317.431811) (xy 63.575114 -317.447656) (xy 63.620893 -317.470947) (xy 63.662466 -317.501112)
			(xy 63.69881 -317.537408) (xy 63.729029 -317.578942) (xy 63.752381 -317.624691) (xy 63.768289 -317.673529)
			(xy 63.776364 -317.724254) (xy 63.77686 -317.749936) (xy 63.775082 -317.78448) (xy 63.773812 -317.79591)
			(xy 63.781686 -317.8175) (xy 63.85433 -317.88989) (xy 63.87592 -317.897256) (xy 63.887604 -317.895986)
			(xy 63.896908 -317.895019) (xy 63.915588 -317.894003) (xy 63.924942 -317.893954) (xy 63.938596 -317.894115)
			(xy 63.965809 -317.896403) (xy 63.979298 -317.898526) (xy 63.991236 -317.900558) (xy 64.013842 -317.893446)
			(xy 64.090296 -317.820548) (xy 64.09817 -317.798196) (xy 64.096646 -317.786258) (xy 64.095657 -317.777211)
			(xy 64.09464 -317.759037) (xy 64.094614 -317.749936) (xy 64.095097 -317.725117) (xy 64.103122 -317.676131)
			(xy 64.118966 -317.629089) (xy 64.142212 -317.58523) (xy 64.172248 -317.54571) (xy 64.208282 -317.511569)
			(xy 64.249364 -317.483708) (xy 64.294412 -317.462861) (xy 64.34224 -317.449576) (xy 64.391587 -317.444204)
			(xy 64.441154 -317.446886) (xy 64.489633 -317.457552) (xy 64.535748 -317.475921) (xy 64.578283 -317.501508)
			(xy 64.616119 -317.53364) (xy 64.648258 -317.571469) (xy 64.673853 -317.614) (xy 64.692231 -317.660112)
			(xy 64.702906 -317.708589) (xy 64.705598 -317.758155) (xy 64.700235 -317.807503) (xy 64.686959 -317.855333)
			(xy 64.66612 -317.900386) (xy 64.638267 -317.941473) (xy 64.604134 -317.977513) (xy 64.564619 -318.007556)
			(xy 64.520764 -318.030811) (xy 64.473725 -318.046664) (xy 64.424741 -318.054698) (xy 64.399922 -318.055244)
			(xy 64.390821 -318.055205) (xy 64.372648 -318.05419) (xy 64.3636 -318.053212) (xy 64.351662 -318.051688)
			(xy 64.32931 -318.059562) (xy 64.256412 -318.136016) (xy 64.2493 -318.158622) (xy 64.251332 -318.17056)
			(xy 64.253461 -318.184048) (xy 64.25575 -318.211262) (xy 64.255904 -318.224916) (xy 64.255904 -318.295274)
			(xy 64.256359 -318.305935) (xy 64.265035 -318.32541) (xy 64.272668 -318.332866) (xy 64.33693 -318.390778)
			(xy 64.35725 -318.397382) (xy 64.368172 -318.396366) (xy 64.399922 -318.394588) (xy 64.425176 -318.395111)
			(xy 64.474996 -318.403428) (xy 64.522767 -318.419831) (xy 64.567188 -318.443873) (xy 64.607045 -318.474898)
			(xy 64.641252 -318.51206) (xy 64.668877 -318.554345) (xy 64.689166 -318.6006) (xy 64.701564 -318.649564)
			(xy 64.705735 -318.6999) (xy 64.701564 -318.750236) (xy 64.689166 -318.7992) (xy 64.668877 -318.845455)
			(xy 64.641252 -318.88774) (xy 64.607045 -318.924902) (xy 64.567188 -318.955927) (xy 64.522767 -318.979969)
			(xy 64.474996 -318.996372) (xy 64.425176 -319.004689) (xy 64.399922 -319.005204) (xy 64.368172 -319.003426)
			(xy 64.35725 -319.00241) (xy 64.33693 -319.009014) (xy 64.272668 -319.066926) (xy 64.26516 -319.07447)
			(xy 64.256505 -319.09389) (xy 64.255904 -319.104518) (xy 64.255904 -319.174876) (xy 64.255416 -319.200955)
			(xy 64.247232 -319.252468) (xy 64.231063 -319.302058) (xy 64.20731 -319.348494) (xy 64.176563 -319.390627)
			(xy 64.139583 -319.42741) (xy 64.118744 -319.4431) (xy 64.109354 -319.450708) (xy 64.09834 -319.472183)
			(xy 64.097662 -319.484248) (xy 64.097408 -319.532254) (xy 64.097896 -319.543759) (xy 64.107821 -319.564513)
			(xy 64.116458 -319.572132) (xy 64.137017 -319.58941) (xy 64.172281 -319.629907) (xy 64.186562 -319.65265)
			(xy 64.193095 -319.66241) (xy 64.212821 -319.67511) (xy 64.224408 -319.677034) (xy 64.229996 -319.677288)
			(xy 65.014602 -319.677288) (xy 65.043812 -319.649856) (xy 65.045336 -319.62979) (xy 65.047555 -319.60436)
			(xy 65.059388 -319.554707) (xy 65.079313 -319.507713) (xy 65.106774 -319.464686) (xy 65.141008 -319.426825)
			(xy 65.18106 -319.395183) (xy 65.225817 -319.370642) (xy 65.274031 -319.353885) (xy 65.324361 -319.345378)
			(xy 65.349882 -319.344802) (xy 65.358986 -319.344901) (xy 65.377159 -319.346047) (xy 65.386204 -319.347088)
			(xy 65.398142 -319.348358) (xy 65.420494 -319.340484) (xy 65.493392 -319.26403) (xy 65.500504 -319.241424)
			(xy 65.498472 -319.229232) (xy 65.496342 -319.215744) (xy 65.494056 -319.18853) (xy 65.4939 -319.174876)
			(xy 65.4939 -319.126362) (xy 65.493433 -319.115706) (xy 65.484741 -319.09625) (xy 65.477136 -319.08877)
			(xy 65.413382 -319.030858) (xy 65.393062 -319.024254) (xy 65.38214 -319.02527) (xy 65.349882 -319.027048)
			(xy 65.324175 -319.026543) (xy 65.273396 -319.018497) (xy 65.2245 -319.002608) (xy 65.178691 -318.979265)
			(xy 65.137098 -318.949044) (xy 65.100745 -318.912688) (xy 65.070526 -318.871093) (xy 65.047185 -318.825284)
			(xy 65.031298 -318.776387) (xy 65.023256 -318.725607) (xy 65.023256 -318.674193) (xy 65.031298 -318.623413)
			(xy 65.047185 -318.574516) (xy 65.070526 -318.528707) (xy 65.100745 -318.487112) (xy 65.137098 -318.450756)
			(xy 65.178691 -318.420535) (xy 65.2245 -318.397192) (xy 65.273396 -318.381303) (xy 65.324175 -318.373257)
			(xy 65.349882 -318.372744) (xy 65.38214 -318.374522) (xy 65.393062 -318.375538) (xy 65.413382 -318.368934)
			(xy 65.477136 -318.311022) (xy 65.484651 -318.30348) (xy 65.493323 -318.28406) (xy 65.4939 -318.27343)
			(xy 65.4939 -318.224916) (xy 65.493943 -318.215562) (xy 65.49496 -318.196882) (xy 65.495932 -318.187578)
			(xy 65.497202 -318.175894) (xy 65.489836 -318.154304) (xy 65.417446 -318.08166) (xy 65.395856 -318.073786)
			(xy 65.384426 -318.075056) (xy 65.349882 -318.077088) (xy 65.3242 -318.076583) (xy 65.273468 -318.068547)
			(xy 65.224617 -318.052674) (xy 65.17885 -318.029357) (xy 65.137293 -317.999168) (xy 65.10097 -317.962851)
			(xy 65.070774 -317.921299) (xy 65.047448 -317.875537) (xy 65.031567 -317.826689) (xy 65.023521 -317.775958)
			(xy 65.023509 -317.724594) (xy 65.031531 -317.673859) (xy 65.04739 -317.625004) (xy 65.070694 -317.57923)
			(xy 65.100871 -317.537665) (xy 65.137178 -317.501331) (xy 65.17872 -317.471123) (xy 65.224476 -317.447784)
			(xy 65.27332 -317.431889) (xy 65.324048 -317.423829) (xy 65.375413 -317.423802) (xy 65.426149 -317.431809)
			(xy 65.475009 -317.447654) (xy 65.520789 -317.470945) (xy 65.562363 -317.50111) (xy 65.598708 -317.537406)
			(xy 65.628928 -317.57894) (xy 65.65228 -317.624689) (xy 65.668189 -317.673528) (xy 65.676264 -317.724254)
			(xy 65.67678 -317.749936) (xy 65.675002 -317.78448) (xy 65.673732 -317.79591) (xy 65.681606 -317.8175)
			(xy 65.75425 -317.88989) (xy 65.77584 -317.897256) (xy 65.787524 -317.895986) (xy 65.796828 -317.895019)
			(xy 65.815508 -317.894005) (xy 65.824862 -317.893954) (xy 65.838516 -317.894116) (xy 65.865729 -317.896405)
			(xy 65.879218 -317.898526) (xy 65.891156 -317.900558) (xy 65.913762 -317.893446) (xy 65.990216 -317.820548)
			(xy 65.99809 -317.798196) (xy 65.996566 -317.786258) (xy 65.995577 -317.777211) (xy 65.99456 -317.759037)
			(xy 65.994534 -317.749936) (xy 65.995017 -317.725119) (xy 66.003041 -317.676137) (xy 66.018884 -317.629098)
			(xy 66.042128 -317.585243) (xy 66.072161 -317.545725) (xy 66.108191 -317.511587) (xy 66.14927 -317.483728)
			(xy 66.194314 -317.462881) (xy 66.242138 -317.449597) (xy 66.291481 -317.444224) (xy 66.341044 -317.446905)
			(xy 66.389519 -317.457569) (xy 66.435631 -317.475935) (xy 66.478164 -317.501519) (xy 66.515998 -317.533647)
			(xy 66.548136 -317.571472) (xy 66.57373 -317.613999) (xy 66.592108 -317.660106) (xy 66.602784 -317.708579)
			(xy 66.605478 -317.75814) (xy 66.600118 -317.807485) (xy 66.586846 -317.855312) (xy 66.566011 -317.900362)
			(xy 66.538162 -317.941448) (xy 66.504033 -317.977487) (xy 66.464523 -318.00753) (xy 66.420673 -318.030785)
			(xy 66.373639 -318.04664) (xy 66.324659 -318.054677) (xy 66.299842 -318.055244) (xy 66.290741 -318.055206)
			(xy 66.272568 -318.054192) (xy 66.26352 -318.053212) (xy 66.251582 -318.051688) (xy 66.22923 -318.059562)
			(xy 66.156332 -318.136016) (xy 66.14922 -318.158622) (xy 66.151252 -318.17056) (xy 66.153381 -318.184048)
			(xy 66.15567 -318.211262) (xy 66.155824 -318.224916) (xy 66.155824 -318.295274) (xy 66.156279 -318.305935)
			(xy 66.164958 -318.325407) (xy 66.172588 -318.332866) (xy 66.23685 -318.390778) (xy 66.25717 -318.397382)
			(xy 66.268092 -318.396366) (xy 66.299842 -318.394588) (xy 66.325095 -318.395113) (xy 66.374912 -318.403432)
			(xy 66.422681 -318.419837) (xy 66.467098 -318.44388) (xy 66.506953 -318.474905) (xy 66.541158 -318.512066)
			(xy 66.56878 -318.55435) (xy 66.589067 -318.600604) (xy 66.601465 -318.649566) (xy 66.605635 -318.6999)
			(xy 66.601465 -318.750234) (xy 66.589067 -318.799196) (xy 66.56878 -318.84545) (xy 66.541158 -318.887734)
			(xy 66.506953 -318.924895) (xy 66.467098 -318.95592) (xy 66.422681 -318.979963) (xy 66.374912 -318.996368)
			(xy 66.325095 -319.004687) (xy 66.299842 -319.005204) (xy 66.268092 -319.003426) (xy 66.25717 -319.00241)
			(xy 66.23685 -319.009014) (xy 66.172588 -319.066926) (xy 66.165089 -319.074475) (xy 66.156449 -319.093894)
			(xy 66.155824 -319.104518) (xy 66.155824 -319.174876) (xy 66.155316 -319.200903) (xy 66.147119 -319.252308)
			(xy 66.130969 -319.301795) (xy 66.107267 -319.34814) (xy 66.076597 -319.390201) (xy 66.039717 -319.426937)
			(xy 66.018918 -319.442592) (xy 66.01841 -319.4431) (xy 66.018156 -319.4431) (xy 66.009052 -319.450703)
			(xy 65.998465 -319.471895) (xy 65.997836 -319.48374) (xy 65.997582 -319.532254) (xy 65.998035 -319.543676)
			(xy 66.007809 -319.564315) (xy 66.016378 -319.571878) (xy 66.03694 -319.589226) (xy 66.072209 -319.629846)
			(xy 66.086482 -319.65265) (xy 66.089022 -319.656206) (xy 66.095659 -319.664465) (xy 66.113889 -319.675221)
			(xy 66.124328 -319.677034) (xy 66.129916 -319.677288) (xy 66.914522 -319.677288) (xy 66.943732 -319.649856)
			(xy 66.945256 -319.62979) (xy 66.947475 -319.604357) (xy 66.959307 -319.554699) (xy 66.97923 -319.507699)
			(xy 67.00669 -319.464665) (xy 67.040922 -319.426796) (xy 67.080974 -319.395145) (xy 67.12573 -319.370593)
			(xy 67.173946 -319.353824) (xy 67.224278 -319.345304) (xy 67.249802 -319.344802) (xy 67.258906 -319.344899)
			(xy 67.27708 -319.34604) (xy 67.286124 -319.347088) (xy 67.298062 -319.348358) (xy 67.320414 -319.340484)
			(xy 67.393312 -319.26403) (xy 67.400424 -319.241424) (xy 67.398392 -319.229232) (xy 67.396263 -319.215744)
			(xy 67.393977 -319.18853) (xy 67.39382 -319.174876) (xy 67.39382 -319.126362) (xy 67.393354 -319.115706)
			(xy 67.384664 -319.096247) (xy 67.377056 -319.08877) (xy 67.313302 -319.030858) (xy 67.292982 -319.024254)
			(xy 67.28206 -319.02527) (xy 67.249802 -319.027048) (xy 67.224092 -319.02657) (xy 67.173306 -319.018527)
			(xy 67.124404 -319.002637) (xy 67.078589 -318.979294) (xy 67.03699 -318.949071) (xy 67.000631 -318.912712)
			(xy 66.970407 -318.871113) (xy 66.947063 -318.825298) (xy 66.931174 -318.776396) (xy 66.92313 -318.72561)
			(xy 66.92313 -318.67419) (xy 66.931174 -318.623404) (xy 66.947063 -318.574502) (xy 66.970407 -318.528687)
			(xy 67.000631 -318.487088) (xy 67.03699 -318.450729) (xy 67.078589 -318.420506) (xy 67.124404 -318.397163)
			(xy 67.173306 -318.381273) (xy 67.224092 -318.37323) (xy 67.249802 -318.372744) (xy 67.28206 -318.374522)
			(xy 67.292982 -318.375538) (xy 67.313302 -318.368934) (xy 67.377056 -318.311022) (xy 67.384569 -318.303479)
			(xy 67.393238 -318.28406) (xy 67.39382 -318.27343) (xy 67.39382 -318.224916) (xy 67.393863 -318.215562)
			(xy 67.39488 -318.196882) (xy 67.395852 -318.187578) (xy 67.397122 -318.175894) (xy 67.389756 -318.154304)
			(xy 67.317366 -318.08166) (xy 67.295776 -318.073786) (xy 67.284346 -318.075056) (xy 67.249802 -318.077088)
			(xy 67.224119 -318.076585) (xy 67.173386 -318.068551) (xy 67.124534 -318.052681) (xy 67.078765 -318.029366)
			(xy 67.037206 -317.999179) (xy 67.000881 -317.962863) (xy 66.970682 -317.921313) (xy 66.947354 -317.875551)
			(xy 66.93147 -317.826703) (xy 66.923422 -317.775972) (xy 66.923408 -317.724607) (xy 66.931428 -317.673871)
			(xy 66.947285 -317.625015) (xy 66.970588 -317.57924) (xy 67.000764 -317.537673) (xy 67.03707 -317.501337)
			(xy 67.078613 -317.471128) (xy 67.124369 -317.447787) (xy 67.173212 -317.431891) (xy 67.223941 -317.423829)
			(xy 67.275306 -317.423802) (xy 67.326044 -317.431808) (xy 67.374904 -317.447652) (xy 67.420686 -317.470943)
			(xy 67.462261 -317.501108) (xy 67.498606 -317.537404) (xy 67.528827 -317.578938) (xy 67.552179 -317.624688)
			(xy 67.568089 -317.673527) (xy 67.576164 -317.724254) (xy 67.5767 -317.749936) (xy 67.574922 -317.78448)
			(xy 67.573652 -317.79591) (xy 67.581526 -317.8175) (xy 67.65417 -317.88989) (xy 67.67576 -317.897256)
			(xy 67.687444 -317.895986) (xy 67.696748 -317.895017) (xy 67.715428 -317.893998) (xy 67.724782 -317.893954)
			(xy 67.738436 -317.894117) (xy 67.765648 -317.896407) (xy 67.779138 -317.898526) (xy 67.791076 -317.900558)
			(xy 67.813682 -317.893446) (xy 67.890136 -317.820548) (xy 67.89801 -317.798196) (xy 67.896486 -317.786258)
			(xy 67.895497 -317.777211) (xy 67.89448 -317.759037) (xy 67.894454 -317.749936) (xy 67.894937 -317.725111)
			(xy 67.902964 -317.676113) (xy 67.918813 -317.629061) (xy 67.942066 -317.585192) (xy 67.972109 -317.545663)
			(xy 68.008153 -317.511515) (xy 68.049246 -317.483649) (xy 68.094306 -317.462799) (xy 68.142146 -317.449514)
			(xy 68.191505 -317.444143) (xy 68.241083 -317.44683) (xy 68.289573 -317.457502) (xy 68.335697 -317.475879)
			(xy 68.378241 -317.501476) (xy 68.416083 -317.533619) (xy 68.448225 -317.571461) (xy 68.473822 -317.614004)
			(xy 68.492199 -317.660129) (xy 68.50287 -317.708619) (xy 68.505556 -317.758197) (xy 68.500186 -317.807556)
			(xy 68.4869 -317.855396) (xy 68.46605 -317.900456) (xy 68.438183 -317.941549) (xy 68.404036 -317.977592)
			(xy 68.364507 -318.007635) (xy 68.320638 -318.030888) (xy 68.273585 -318.046736) (xy 68.224587 -318.054763)
			(xy 68.199762 -318.055244) (xy 68.190661 -318.055204) (xy 68.172489 -318.054185) (xy 68.16344 -318.053212)
			(xy 68.151502 -318.051688) (xy 68.12915 -318.059562) (xy 68.056252 -318.136016) (xy 68.04914 -318.158622)
			(xy 68.051172 -318.17056) (xy 68.053301 -318.184048) (xy 68.05559 -318.211262) (xy 68.055744 -318.224916)
			(xy 68.055744 -318.295274) (xy 68.0562 -318.305934) (xy 68.064881 -318.325404) (xy 68.072508 -318.332866)
			(xy 68.13677 -318.390778) (xy 68.15709 -318.397382) (xy 68.168012 -318.396366) (xy 68.199762 -318.394588)
			(xy 68.225022 -318.395078) (xy 68.274854 -318.403387) (xy 68.322638 -318.419787) (xy 68.367072 -318.443828)
			(xy 68.406941 -318.474855) (xy 68.44116 -318.512022) (xy 68.468794 -318.554314) (xy 68.489089 -318.600579)
			(xy 68.501492 -318.649552) (xy 68.505664 -318.6999) (xy 68.501492 -318.750248) (xy 68.489089 -318.799221)
			(xy 68.468794 -318.845486) (xy 68.44116 -318.887778) (xy 68.406941 -318.924945) (xy 68.367072 -318.955972)
			(xy 68.322638 -318.980013) (xy 68.274854 -318.996413) (xy 68.225022 -319.004722) (xy 68.199762 -319.005204)
			(xy 68.168012 -319.003426) (xy 68.15709 -319.00241) (xy 68.13677 -319.009014) (xy 68.072508 -319.066926)
			(xy 68.065007 -319.074474) (xy 68.056363 -319.093893) (xy 68.055744 -319.104518) (xy 68.055744 -319.174876)
			(xy 68.055236 -319.200903) (xy 68.047039 -319.252309) (xy 68.03089 -319.301796) (xy 68.007189 -319.348143)
			(xy 67.97652 -319.390205) (xy 67.939641 -319.426943) (xy 67.918838 -319.442592) (xy 67.91833 -319.4431)
			(xy 67.918076 -319.4431) (xy 67.908984 -319.450709) (xy 67.898414 -319.471899) (xy 67.897756 -319.48374)
			(xy 67.897502 -319.532254) (xy 67.897956 -319.543675) (xy 67.907733 -319.564311) (xy 67.916298 -319.571878)
			(xy 67.936859 -319.589227) (xy 67.972126 -319.629848) (xy 67.986402 -319.65265) (xy 67.988942 -319.656206)
			(xy 67.99558 -319.664463) (xy 68.013811 -319.675211) (xy 68.024248 -319.677034) (xy 68.029836 -319.677288)
			(xy 68.814696 -319.677288) (xy 68.843906 -319.649856) (xy 68.84543 -319.62979) (xy 68.847649 -319.60436)
			(xy 68.859482 -319.554706) (xy 68.879407 -319.507712) (xy 68.906868 -319.464685) (xy 68.941101 -319.426823)
			(xy 68.981154 -319.39518) (xy 69.02591 -319.370638) (xy 69.074125 -319.35388) (xy 69.124454 -319.345372)
			(xy 69.149976 -319.344802) (xy 69.15908 -319.344901) (xy 69.177253 -319.346046) (xy 69.186298 -319.347088)
			(xy 69.19849 -319.348358) (xy 69.220842 -319.340484) (xy 69.29374 -319.26403) (xy 69.300852 -319.241424)
			(xy 69.29882 -319.229486) (xy 69.296688 -319.215998) (xy 69.294398 -319.188785) (xy 69.294248 -319.17513)
			(xy 69.294248 -319.126362) (xy 69.29378 -319.115708) (xy 69.285081 -319.096257) (xy 69.277484 -319.08877)
			(xy 69.21373 -319.030858) (xy 69.19341 -319.024254) (xy 69.182488 -319.02527) (xy 69.149976 -319.027048)
			(xy 69.12427 -319.026542) (xy 69.073491 -319.018496) (xy 69.024596 -319.002606) (xy 68.978788 -318.979263)
			(xy 68.937196 -318.949041) (xy 68.900843 -318.912686) (xy 68.870625 -318.871092) (xy 68.847285 -318.825282)
			(xy 68.831398 -318.776386) (xy 68.823356 -318.725606) (xy 68.823356 -318.674194) (xy 68.831398 -318.623414)
			(xy 68.847285 -318.574518) (xy 68.870625 -318.528708) (xy 68.900843 -318.487114) (xy 68.937196 -318.450759)
			(xy 68.978788 -318.420537) (xy 69.024596 -318.397194) (xy 69.073491 -318.381304) (xy 69.12427 -318.373258)
			(xy 69.149976 -318.372744) (xy 69.182488 -318.374522) (xy 69.19341 -318.375538) (xy 69.21373 -318.368934)
			(xy 69.277484 -318.311022) (xy 69.284994 -318.303477) (xy 69.293657 -318.284058) (xy 69.294248 -318.27343)
			(xy 69.294248 -318.224916) (xy 69.294291 -318.215562) (xy 69.295306 -318.196881) (xy 69.29628 -318.187578)
			(xy 69.297804 -318.175894) (xy 69.290184 -318.154304) (xy 69.217794 -318.08166) (xy 69.196204 -318.073786)
			(xy 69.18452 -318.075056) (xy 69.149976 -318.077088) (xy 69.124263 -318.076608) (xy 69.073471 -318.068559)
			(xy 69.024564 -318.052664) (xy 68.978745 -318.029314) (xy 68.937143 -317.999083) (xy 68.900783 -317.962717)
			(xy 68.870559 -317.921111) (xy 68.847216 -317.875288) (xy 68.831329 -317.826378) (xy 68.823288 -317.775585)
			(xy 68.823292 -317.724159) (xy 68.831342 -317.673367) (xy 68.847237 -317.62446) (xy 68.870588 -317.578642)
			(xy 68.900819 -317.53704) (xy 68.937186 -317.50068) (xy 68.978793 -317.470457) (xy 69.024616 -317.447114)
			(xy 69.073526 -317.431228) (xy 69.124319 -317.423188) (xy 69.175745 -317.423193) (xy 69.226536 -317.431243)
			(xy 69.275444 -317.447139) (xy 69.321262 -317.47049) (xy 69.362863 -317.500722) (xy 69.399222 -317.537089)
			(xy 69.429445 -317.578696) (xy 69.452787 -317.624519) (xy 69.468673 -317.67343) (xy 69.476713 -317.724223)
			(xy 69.477128 -317.749936) (xy 69.475096 -317.78448) (xy 69.473826 -317.796164) (xy 69.4817 -317.817754)
			(xy 69.554344 -317.890144) (xy 69.575934 -317.897764) (xy 69.587618 -317.89624) (xy 69.596922 -317.895272)
			(xy 69.615602 -317.894255) (xy 69.624956 -317.894208) (xy 69.63861 -317.89437) (xy 69.665823 -317.896658)
			(xy 69.679312 -317.89878) (xy 69.69125 -317.900812) (xy 69.713856 -317.8937) (xy 69.79031 -317.820802)
			(xy 69.798184 -317.79845) (xy 69.796914 -317.786258) (xy 69.795865 -317.777214) (xy 69.794719 -317.75904)
			(xy 69.794628 -317.749936) (xy 69.795111 -317.725118) (xy 69.803135 -317.676135) (xy 69.818979 -317.629096)
			(xy 69.842223 -317.585239) (xy 69.872257 -317.545721) (xy 69.908288 -317.511582) (xy 69.949368 -317.483722)
			(xy 69.994414 -317.462875) (xy 70.042239 -317.449591) (xy 70.091583 -317.444218) (xy 70.141147 -317.4469)
			(xy 70.189623 -317.457564) (xy 70.235736 -317.475931) (xy 70.27827 -317.501516) (xy 70.316104 -317.533645)
			(xy 70.348242 -317.571472) (xy 70.373837 -317.613999) (xy 70.392215 -317.660108) (xy 70.402891 -317.708582)
			(xy 70.405584 -317.758145) (xy 70.400223 -317.80749) (xy 70.38695 -317.855318) (xy 70.366113 -317.900369)
			(xy 70.338263 -317.941456) (xy 70.304133 -317.977495) (xy 70.264622 -318.007538) (xy 70.220771 -318.030793)
			(xy 70.173735 -318.046647) (xy 70.124754 -318.054683) (xy 70.099936 -318.055244) (xy 70.090832 -318.055146)
			(xy 70.072659 -318.054) (xy 70.063614 -318.052958) (xy 70.051422 -318.051688) (xy 70.02907 -318.059562)
			(xy 69.956172 -318.136016) (xy 69.94906 -318.158622) (xy 69.951092 -318.17056) (xy 69.953222 -318.184048)
			(xy 69.955508 -318.211262) (xy 69.955664 -318.224916) (xy 69.955664 -318.295274) (xy 69.95622 -318.305969)
			(xy 69.964874 -318.325531) (xy 69.972428 -318.33312) (xy 70.03669 -318.390778) (xy 70.05701 -318.397382)
			(xy 70.067932 -318.396366) (xy 70.099936 -318.394588) (xy 70.12519 -318.395112) (xy 70.175007 -318.403431)
			(xy 70.222777 -318.419835) (xy 70.267195 -318.443878) (xy 70.30705 -318.474903) (xy 70.341256 -318.512064)
			(xy 70.368879 -318.554349) (xy 70.389166 -318.600603) (xy 70.401564 -318.649565) (xy 70.405735 -318.6999)
			(xy 70.401564 -318.750235) (xy 70.389166 -318.799197) (xy 70.368879 -318.845451) (xy 70.341256 -318.887736)
			(xy 70.30705 -318.924897) (xy 70.267195 -318.955922) (xy 70.222777 -318.979965) (xy 70.175007 -318.996369)
			(xy 70.12519 -319.004688) (xy 70.099936 -319.005204) (xy 70.067932 -319.003426) (xy 70.05701 -319.00241)
			(xy 70.03669 -319.009014) (xy 69.972428 -319.066672) (xy 69.964765 -319.074188) (xy 69.956073 -319.093793)
			(xy 69.955664 -319.104518) (xy 69.955664 -319.175384) (xy 69.955155 -319.20141) (xy 69.946956 -319.252813)
			(xy 69.930804 -319.302297) (xy 69.907098 -319.348638) (xy 69.876424 -319.390694) (xy 69.83954 -319.427424)
			(xy 69.818758 -319.4431) (xy 69.808852 -319.450212) (xy 69.797676 -319.471802) (xy 69.797422 -319.532254)
			(xy 69.79791 -319.543759) (xy 69.807838 -319.564511) (xy 69.816472 -319.572132) (xy 69.837031 -319.589411)
			(xy 69.872293 -319.629908) (xy 69.886576 -319.65265) (xy 69.89311 -319.662409) (xy 69.912836 -319.675102)
			(xy 69.924422 -319.677034) (xy 69.93001 -319.677288) (xy 70.714616 -319.677288) (xy 70.743826 -319.649856)
			(xy 70.74535 -319.62979) (xy 70.747569 -319.60436) (xy 70.759402 -319.554708) (xy 70.779327 -319.507715)
			(xy 70.806789 -319.46469) (xy 70.841023 -319.42683) (xy 70.881076 -319.39519) (xy 70.925832 -319.370651)
			(xy 70.974046 -319.353895) (xy 71.024375 -319.34539) (xy 71.049896 -319.344802) (xy 71.069482 -319.345099)
			(xy 71.108337 -319.350064) (xy 71.127366 -319.354708) (xy 71.140574 -319.358264) (xy 71.166482 -319.351152)
			(xy 71.195692 -319.321942) (xy 71.201845 -319.315221) (xy 71.209372 -319.29864) (xy 71.210651 -319.280476)
			(xy 71.208392 -319.27165) (xy 71.208392 -319.271142) (xy 71.20174 -319.247634) (xy 71.194595 -319.199304)
			(xy 71.194168 -319.174876) (xy 71.194168 -319.126362) (xy 71.1937 -319.115707) (xy 71.185004 -319.096255)
			(xy 71.177404 -319.08877) (xy 71.11365 -319.030858) (xy 71.09333 -319.024254) (xy 71.082408 -319.02527)
			(xy 71.049896 -319.027048) (xy 71.024189 -319.026544) (xy 70.973407 -319.0185) (xy 70.924509 -319.002612)
			(xy 70.878699 -318.97927) (xy 70.837104 -318.949049) (xy 70.800749 -318.912693) (xy 70.770528 -318.871098)
			(xy 70.747187 -318.825287) (xy 70.731299 -318.776389) (xy 70.723256 -318.725607) (xy 70.723256 -318.674193)
			(xy 70.731299 -318.623411) (xy 70.747187 -318.574513) (xy 70.770528 -318.528702) (xy 70.800749 -318.487107)
			(xy 70.837104 -318.450751) (xy 70.878699 -318.42053) (xy 70.924509 -318.397188) (xy 70.973407 -318.3813)
			(xy 71.024189 -318.373256) (xy 71.049896 -318.372744) (xy 71.082408 -318.374522) (xy 71.09333 -318.375538)
			(xy 71.11365 -318.368934) (xy 71.177404 -318.311022) (xy 71.184911 -318.303476) (xy 71.193571 -318.284057)
			(xy 71.194168 -318.27343) (xy 71.194168 -318.224916) (xy 71.194211 -318.215562) (xy 71.195226 -318.196881)
			(xy 71.1962 -318.187578) (xy 71.197724 -318.175894) (xy 71.190104 -318.154304) (xy 71.117714 -318.08166)
			(xy 71.096124 -318.073786) (xy 71.08444 -318.075056) (xy 71.049896 -318.077088) (xy 71.024183 -318.076609)
			(xy 70.97339 -318.068564) (xy 70.924481 -318.052671) (xy 70.87866 -318.029323) (xy 70.837056 -317.999095)
			(xy 70.800693 -317.96273) (xy 70.770467 -317.921124) (xy 70.747122 -317.875302) (xy 70.731232 -317.826392)
			(xy 70.723189 -317.775599) (xy 70.723191 -317.724172) (xy 70.731239 -317.673379) (xy 70.747133 -317.624471)
			(xy 70.770482 -317.578651) (xy 70.800712 -317.537048) (xy 70.837079 -317.500686) (xy 70.878685 -317.470461)
			(xy 70.924508 -317.447118) (xy 70.973418 -317.431229) (xy 71.024212 -317.423188) (xy 71.075638 -317.423192)
			(xy 71.126431 -317.431241) (xy 71.175339 -317.447137) (xy 71.221158 -317.470488) (xy 71.26276 -317.500719)
			(xy 71.299121 -317.537087) (xy 71.329344 -317.578694) (xy 71.352687 -317.624518) (xy 71.368573 -317.673429)
			(xy 71.376613 -317.724223) (xy 71.377048 -317.749936) (xy 71.375016 -317.78448) (xy 71.373746 -317.796164)
			(xy 71.38162 -317.817754) (xy 71.454264 -317.890144) (xy 71.475854 -317.897764) (xy 71.487538 -317.89624)
			(xy 71.496842 -317.895272) (xy 71.515522 -317.894257) (xy 71.524876 -317.894208) (xy 71.53853 -317.89437)
			(xy 71.565742 -317.89666) (xy 71.579232 -317.89878) (xy 71.59117 -317.900812) (xy 71.613776 -317.8937)
			(xy 71.69023 -317.820802) (xy 71.698104 -317.79845) (xy 71.696834 -317.786258) (xy 71.695785 -317.777214)
			(xy 71.694639 -317.75904) (xy 71.694548 -317.749936) (xy 71.695016 -317.725942) (xy 71.702517 -317.678543)
			(xy 71.717341 -317.632901) (xy 71.739122 -317.590141) (xy 71.767324 -317.551313) (xy 71.801252 -317.517376)
			(xy 71.840072 -317.489164) (xy 71.882827 -317.467372) (xy 71.928465 -317.452536) (xy 71.975862 -317.445022)
			(xy 71.999856 -317.444628) (xy 72.00896 -317.444726) (xy 72.027133 -317.445871) (xy 72.036178 -317.446914)
			(xy 72.04837 -317.448184) (xy 72.070722 -317.44031) (xy 72.14362 -317.363856) (xy 72.150732 -317.34125)
			(xy 72.1487 -317.329312) (xy 72.146579 -317.315887) (xy 72.144288 -317.288801) (xy 72.144128 -317.27521)
			(xy 72.144128 -317.226188) (xy 72.143667 -317.215529) (xy 72.134985 -317.196062) (xy 72.127364 -317.188596)
			(xy 72.06361 -317.130684) (xy 72.04329 -317.12408) (xy 72.032368 -317.125096) (xy 71.999856 -317.12662)
			(xy 71.974169 -317.126113) (xy 71.923428 -317.11807) (xy 71.874569 -317.102189) (xy 71.828796 -317.078861)
			(xy 71.787236 -317.048661) (xy 71.750911 -317.012331) (xy 71.720716 -316.970766) (xy 71.697394 -316.92499)
			(xy 71.68152 -316.87613) (xy 71.673484 -316.825387) (xy 71.673484 -316.774013) (xy 71.68152 -316.72327)
			(xy 71.697394 -316.67441) (xy 71.720716 -316.628634) (xy 71.750911 -316.587069) (xy 71.787236 -316.550739)
			(xy 71.828796 -316.520539) (xy 71.874569 -316.497211) (xy 71.923428 -316.48133) (xy 71.974169 -316.473287)
			(xy 71.999856 -316.472824) (xy 72.032368 -316.474348) (xy 72.04329 -316.475364) (xy 72.06361 -316.46876)
			(xy 72.127364 -316.410848) (xy 72.13488 -316.403306) (xy 72.143557 -316.383887) (xy 72.144128 -316.373256)
			(xy 72.144128 -316.324234) (xy 72.144185 -316.315007) (xy 72.145204 -316.296581) (xy 72.14616 -316.287404)
			(xy 72.14743 -316.27572) (xy 72.140064 -316.25413) (xy 72.067674 -316.181486) (xy 72.046084 -316.173612)
			(xy 72.0344 -316.174882) (xy 71.999856 -316.17666) (xy 71.974173 -316.176153) (xy 71.923442 -316.168112)
			(xy 71.874592 -316.152234) (xy 71.828828 -316.12891) (xy 71.787275 -316.098715) (xy 71.750956 -316.062392)
			(xy 71.720767 -316.020835) (xy 71.697449 -315.975067) (xy 71.681578 -315.926216) (xy 71.673543 -315.875483)
			(xy 71.673543 -315.824117) (xy 71.681578 -315.773384) (xy 71.697449 -315.724533) (xy 71.720767 -315.678765)
			(xy 71.750956 -315.637208) (xy 71.787275 -315.600885) (xy 71.828828 -315.57069) (xy 71.874592 -315.547366)
			(xy 71.923442 -315.531488) (xy 71.974173 -315.523447) (xy 71.999856 -315.522864) (xy 72.013575 -315.522994)
			(xy 72.040916 -315.525286) (xy 72.054466 -315.527436) (xy 72.066404 -315.529214) (xy 72.089264 -315.522356)
			(xy 72.165718 -315.448696) (xy 72.173592 -315.42609) (xy 72.172068 -315.414152) (xy 72.170869 -315.404354)
			(xy 72.169595 -315.384653) (xy 72.169528 -315.374782) (xy 72.169715 -315.3606) (xy 72.172391 -315.332361)
			(xy 72.174862 -315.318394) (xy 72.177148 -315.305948) (xy 72.169782 -315.282326) (xy 72.092312 -315.204856)
			(xy 72.06869 -315.19749) (xy 72.056244 -315.199776) (xy 72.042279 -315.202259) (xy 72.014039 -315.204927)
			(xy 71.999856 -315.20511) (xy 71.975036 -315.204621) (xy 71.92605 -315.196583) (xy 71.87901 -315.180726)
			(xy 71.835155 -315.157468) (xy 71.795641 -315.127422) (xy 71.761507 -315.091379) (xy 71.733654 -315.050289)
			(xy 71.712816 -315.005234) (xy 71.69954 -314.957402) (xy 71.694178 -314.908051) (xy 71.696871 -314.858484)
			(xy 71.707546 -314.810005) (xy 71.725924 -314.763892) (xy 71.75152 -314.721359) (xy 71.78366 -314.683527)
			(xy 71.821496 -314.651393) (xy 71.864033 -314.625804) (xy 71.910149 -314.607433) (xy 71.95863 -314.596764)
			(xy 72.008198 -314.59408) (xy 72.057547 -314.599449) (xy 72.105377 -314.612731) (xy 72.150429 -314.633577)
			(xy 72.191515 -314.661436) (xy 72.227553 -314.695575) (xy 72.257593 -314.735094) (xy 72.280844 -314.778953)
			(xy 72.296694 -314.825995) (xy 72.304724 -314.874982) (xy 72.305164 -314.899802) (xy 72.30475 -314.922534)
			(xy 72.298004 -314.967494) (xy 72.284647 -315.010952) (xy 72.275192 -315.031628) (xy 72.271095 -315.041303)
			(xy 72.270296 -315.062275) (xy 72.277959 -315.081813) (xy 72.292802 -315.096651) (xy 72.312343 -315.104307)
			(xy 72.333315 -315.103501) (xy 72.34301 -315.099446) (xy 72.353513 -315.094537) (xy 72.375127 -315.086147)
			(xy 72.38619 -315.082682) (xy 72.395588 -315.079888) (xy 72.417746 -315.074191) (xy 72.463169 -315.068725)
			(xy 72.5089 -315.070095) (xy 72.531478 -315.073792) (xy 72.543924 -315.076078) (xy 72.567546 -315.068712)
			(xy 72.644508 -314.991496) (xy 72.651874 -314.967874) (xy 72.649588 -314.955428) (xy 72.647212 -314.941644)
			(xy 72.644668 -314.913788) (xy 72.644508 -314.899802) (xy 72.64503 -314.874547) (xy 72.653343 -314.824725)
			(xy 72.669744 -314.776951) (xy 72.693785 -314.732528) (xy 72.724809 -314.692668) (xy 72.761971 -314.658458)
			(xy 72.804257 -314.630832) (xy 72.850513 -314.610542) (xy 72.899478 -314.598142) (xy 72.949816 -314.593971)
			(xy 73.000154 -314.598142) (xy 73.049119 -314.610542) (xy 73.095375 -314.630832) (xy 73.137661 -314.658458)
			(xy 73.174823 -314.692668) (xy 73.205847 -314.732528) (xy 73.229888 -314.776951) (xy 73.246289 -314.824725)
			(xy 73.254602 -314.874547) (xy 73.255124 -314.899802) (xy 73.254616 -314.91809) (xy 73.2536 -314.932314)
			(xy 73.266554 -314.956952) (xy 73.367392 -315.018674) (xy 73.395078 -315.018928) (xy 73.407524 -315.011816)
			(xy 73.444542 -314.990595) (xy 73.521617 -314.953968) (xy 73.561448 -314.938664) (xy 73.570781 -314.934692)
			(xy 73.585544 -314.920805) (xy 73.593819 -314.902303) (xy 73.594468 -314.892182) (xy 73.595577 -314.867339)
			(xy 73.604854 -314.818487) (xy 73.621923 -314.771783) (xy 73.646333 -314.728461) (xy 73.677439 -314.689666)
			(xy 73.714419 -314.656422) (xy 73.756296 -314.629609) (xy 73.801963 -314.609934) (xy 73.850215 -314.597917)
			(xy 73.899776 -314.593875) (xy 73.949337 -314.597917) (xy 73.997589 -314.609934) (xy 74.043256 -314.629609)
			(xy 74.085133 -314.656422) (xy 74.122113 -314.689666) (xy 74.153219 -314.728461) (xy 74.177629 -314.771783)
			(xy 74.194698 -314.818487) (xy 74.203975 -314.867339) (xy 74.205084 -314.892182) (xy 74.205714 -314.902318)
			(xy 74.213938 -314.920868) (xy 74.228733 -314.934753) (xy 74.238104 -314.938664) (xy 74.278005 -314.953947)
			(xy 74.355208 -314.990575) (xy 74.392282 -315.011816) (xy 74.404728 -315.019182) (xy 74.432414 -315.018928)
			(xy 74.533252 -314.957206) (xy 74.546206 -314.932314) (xy 74.54519 -314.91809) (xy 74.544682 -314.899802)
			(xy 74.545204 -314.874547) (xy 74.553517 -314.824725) (xy 74.569918 -314.776951) (xy 74.593959 -314.732528)
			(xy 74.624983 -314.692668) (xy 74.662145 -314.658458) (xy 74.704431 -314.630832) (xy 74.750687 -314.610542)
			(xy 74.799652 -314.598142) (xy 74.84999 -314.593971) (xy 74.900328 -314.598142) (xy 74.949293 -314.610542)
			(xy 74.995549 -314.630832) (xy 75.037835 -314.658458) (xy 75.074997 -314.692668) (xy 75.106021 -314.732528)
			(xy 75.130062 -314.776951) (xy 75.146463 -314.824725) (xy 75.154776 -314.874547) (xy 75.155298 -314.899802)
			(xy 75.15479 -314.91809) (xy 75.153774 -314.932314) (xy 75.166728 -314.956952) (xy 75.267566 -315.018674)
			(xy 75.295252 -315.018928) (xy 75.307698 -315.011816) (xy 75.344716 -314.990594) (xy 75.42179 -314.953965)
			(xy 75.461622 -314.938664) (xy 75.470959 -314.934695) (xy 75.485729 -314.92081) (xy 75.494009 -314.902305)
			(xy 75.494642 -314.892182) (xy 75.495751 -314.867339) (xy 75.505028 -314.818487) (xy 75.522097 -314.771783)
			(xy 75.546507 -314.728461) (xy 75.577613 -314.689666) (xy 75.614593 -314.656422) (xy 75.65647 -314.629609)
			(xy 75.702137 -314.609934) (xy 75.750389 -314.597917) (xy 75.79995 -314.593875) (xy 75.849511 -314.597917)
			(xy 75.897763 -314.609934) (xy 75.94343 -314.629609) (xy 75.985307 -314.656422) (xy 76.022287 -314.689666)
			(xy 76.053393 -314.728461) (xy 76.077803 -314.771783) (xy 76.094872 -314.818487) (xy 76.104149 -314.867339)
			(xy 76.105258 -314.892182) (xy 76.105888 -314.902319) (xy 76.114109 -314.920872) (xy 76.128902 -314.934764)
			(xy 76.138278 -314.938664) (xy 76.178114 -314.953957) (xy 76.255189 -314.990584) (xy 76.292202 -315.011816)
			(xy 76.304648 -315.018928) (xy 76.332334 -315.018674) (xy 76.433172 -314.956952) (xy 76.446126 -314.932314)
			(xy 76.44511 -314.91809) (xy 76.444602 -314.899802) (xy 76.445124 -314.874547) (xy 76.453437 -314.824725)
			(xy 76.469838 -314.776951) (xy 76.493879 -314.732528) (xy 76.524903 -314.692668) (xy 76.562065 -314.658458)
			(xy 76.604351 -314.630832) (xy 76.650607 -314.610542) (xy 76.699572 -314.598142) (xy 76.74991 -314.593971)
			(xy 76.800248 -314.598142) (xy 76.849213 -314.610542) (xy 76.895469 -314.630832) (xy 76.937755 -314.658458)
			(xy 76.974917 -314.692668) (xy 77.005941 -314.732528) (xy 77.029982 -314.776951) (xy 77.046383 -314.824725)
			(xy 77.054696 -314.874547) (xy 77.055218 -314.899802) (xy 77.05471 -314.91809) (xy 77.053694 -314.932314)
			(xy 77.066648 -314.956952) (xy 77.167486 -315.018674) (xy 77.195172 -315.018928) (xy 77.207618 -315.011816)
			(xy 77.244636 -314.990594) (xy 77.321711 -314.953968) (xy 77.361542 -314.938664) (xy 77.370876 -314.934693)
			(xy 77.385641 -314.920806) (xy 77.393917 -314.902304) (xy 77.394562 -314.892182) (xy 77.395671 -314.867339)
			(xy 77.404948 -314.818487) (xy 77.422017 -314.771783) (xy 77.446427 -314.728461) (xy 77.477533 -314.689666)
			(xy 77.514513 -314.656422) (xy 77.55639 -314.629609) (xy 77.602057 -314.609934) (xy 77.650309 -314.597917)
			(xy 77.69987 -314.593875) (xy 77.749431 -314.597917) (xy 77.797683 -314.609934) (xy 77.84335 -314.629609)
			(xy 77.885227 -314.656422) (xy 77.922207 -314.689666) (xy 77.953313 -314.728461) (xy 77.977723 -314.771783)
			(xy 77.994792 -314.818487) (xy 78.004069 -314.867339) (xy 78.005178 -314.892182) (xy 78.005808 -314.902318)
			(xy 78.014031 -314.920869) (xy 78.028826 -314.934756) (xy 78.038198 -314.938664) (xy 78.078033 -314.953958)
			(xy 78.155108 -314.990586) (xy 78.192122 -315.011816) (xy 78.204568 -315.018928) (xy 78.232254 -315.018674)
			(xy 78.333092 -314.956952) (xy 78.346046 -314.932314) (xy 78.34503 -314.91809) (xy 78.344522 -314.899802)
			(xy 78.345069 -314.873997) (xy 78.353764 -314.823123) (xy 78.37089 -314.774436) (xy 78.395959 -314.729322)
			(xy 78.428258 -314.689066) (xy 78.466865 -314.654815) (xy 78.510683 -314.627543) (xy 78.558462 -314.608028)
			(xy 78.608843 -314.596825) (xy 78.63459 -314.595002) (xy 78.643827 -314.594094) (xy 78.660764 -314.586538)
			(xy 78.66761 -314.58027) (xy 78.689708 -314.55868) (xy 78.69655 -314.55128) (xy 78.704276 -314.532682)
			(xy 78.704694 -314.522612) (xy 78.704694 -314.348876) (xy 78.704266 -314.338808) (xy 78.696545 -314.32021)
			(xy 78.689708 -314.312808) (xy 78.667864 -314.291218) (xy 78.660896 -314.284908) (xy 78.643696 -314.277363)
			(xy 78.634336 -314.276486) (xy 78.608151 -314.274725) (xy 78.556801 -314.263906) (xy 78.507838 -314.245025)
			(xy 78.462518 -314.218568) (xy 78.422004 -314.185214) (xy 78.387335 -314.145819) (xy 78.359403 -314.101393)
			(xy 78.338922 -314.053077) (xy 78.32642 -314.002111) (xy 78.322216 -313.949802) (xy 78.326419 -313.897493)
			(xy 78.338921 -313.846527) (xy 78.359401 -313.79821) (xy 78.387333 -313.753784) (xy 78.422001 -313.714388)
			(xy 78.462514 -313.681034) (xy 78.507834 -313.654577) (xy 78.556797 -313.635695) (xy 78.608147 -313.624875)
			(xy 78.634336 -313.623198) (xy 78.643715 -313.622407) (xy 78.660936 -313.614839) (xy 78.667864 -313.608466)
			(xy 78.689708 -313.586876) (xy 78.69655 -313.579476) (xy 78.704274 -313.560878) (xy 78.704694 -313.550808)
			(xy 78.704694 -313.398916) (xy 78.704255 -313.388853) (xy 78.696519 -313.370271) (xy 78.689708 -313.362848)
			(xy 78.667864 -313.341258) (xy 78.660893 -313.334954) (xy 78.643694 -313.327418) (xy 78.634336 -313.326526)
			(xy 78.608156 -313.324766) (xy 78.556816 -313.313947) (xy 78.507861 -313.29507) (xy 78.46255 -313.268618)
			(xy 78.422043 -313.235269) (xy 78.387382 -313.195881) (xy 78.359454 -313.151463) (xy 78.338978 -313.103156)
			(xy 78.326479 -313.052198) (xy 78.322276 -312.999899) (xy 78.326479 -312.9476) (xy 78.338979 -312.896643)
			(xy 78.359455 -312.848335) (xy 78.387383 -312.803918) (xy 78.422044 -312.764529) (xy 78.462551 -312.731181)
			(xy 78.507863 -312.704729) (xy 78.556817 -312.685852) (xy 78.608158 -312.675034) (xy 78.634336 -312.673238)
			(xy 78.643716 -312.672448) (xy 78.660941 -312.664884) (xy 78.667864 -312.658506) (xy 78.689708 -312.636916)
			(xy 78.69654 -312.629512) (xy 78.704243 -312.610914) (xy 78.704694 -312.600848) (xy 78.704694 -312.427112)
			(xy 78.704273 -312.417041) (xy 78.696561 -312.398434) (xy 78.689708 -312.391044) (xy 78.66761 -312.369454)
			(xy 78.660747 -312.363212) (xy 78.643819 -312.35566) (xy 78.63459 -312.354722) (xy 78.610189 -312.353037)
			(xy 78.562348 -312.342871) (xy 78.516741 -312.325206) (xy 78.474534 -312.300494) (xy 78.43681 -312.269366)
			(xy 78.404532 -312.23262) (xy 78.378528 -312.191197) (xy 78.359463 -312.146157) (xy 78.347825 -312.098653)
			(xy 78.343912 -312.049901) (xy 78.347825 -312.001149) (xy 78.359462 -311.953645) (xy 78.378527 -311.908605)
			(xy 78.404531 -311.867181) (xy 78.436808 -311.830435) (xy 78.474533 -311.799308) (xy 78.516739 -311.774595)
			(xy 78.562346 -311.756929) (xy 78.610187 -311.746764) (xy 78.63459 -311.745122) (xy 78.643828 -311.744215)
			(xy 78.660766 -311.736661) (xy 78.66761 -311.73039) (xy 78.689708 -311.7088) (xy 78.696554 -311.701401)
			(xy 78.704287 -311.682803) (xy 78.704694 -311.672732) (xy 78.704694 -311.477152) (xy 78.704262 -311.467086)
			(xy 78.696535 -311.448495) (xy 78.689708 -311.441084) (xy 78.66761 -311.419494) (xy 78.660745 -311.413258)
			(xy 78.643816 -311.405715) (xy 78.63459 -311.404762) (xy 78.610194 -311.403077) (xy 78.562362 -311.392913)
			(xy 78.516764 -311.375251) (xy 78.474566 -311.350543) (xy 78.436849 -311.319421) (xy 78.404578 -311.282682)
			(xy 78.37858 -311.241267) (xy 78.359519 -311.196236) (xy 78.347884 -311.148741) (xy 78.343972 -311.099998)
			(xy 78.347884 -311.051256) (xy 78.35952 -311.003761) (xy 78.378581 -310.95873) (xy 78.404581 -310.917315)
			(xy 78.436852 -310.880576) (xy 78.474569 -310.849455) (xy 78.516767 -310.824747) (xy 78.562366 -310.807086)
			(xy 78.610197 -310.796923) (xy 78.63459 -310.795162) (xy 78.643829 -310.794256) (xy 78.660771 -310.786706)
			(xy 78.66761 -310.78043) (xy 78.689708 -310.75884) (xy 78.696544 -310.751438) (xy 78.704256 -310.73284)
			(xy 78.704694 -310.722772) (xy 78.704694 -310.526938) (xy 78.704259 -310.516873) (xy 78.696528 -310.498285)
			(xy 78.689708 -310.49087) (xy 78.66761 -310.46928) (xy 78.660744 -310.463046) (xy 78.643816 -310.455505)
			(xy 78.63459 -310.454548) (xy 78.610187 -310.452863) (xy 78.562342 -310.442696) (xy 78.516731 -310.42503)
			(xy 78.474521 -310.400316) (xy 78.436793 -310.369186) (xy 78.404512 -310.332437) (xy 78.378505 -310.291011)
			(xy 78.359439 -310.245967) (xy 78.3478 -310.198459) (xy 78.343886 -310.149702) (xy 78.347799 -310.100946)
			(xy 78.359437 -310.053438) (xy 78.378503 -310.008394) (xy 78.404509 -309.966967) (xy 78.436789 -309.930218)
			(xy 78.474517 -309.899087) (xy 78.516726 -309.874372) (xy 78.562337 -309.856705) (xy 78.610182 -309.846538)
			(xy 78.63459 -309.844948) (xy 78.643829 -309.844041) (xy 78.660769 -309.83649) (xy 78.66761 -309.830216)
			(xy 78.689708 -309.808626) (xy 78.696542 -309.801223) (xy 78.704248 -309.782625) (xy 78.704694 -309.772558)
			(xy 78.704694 -309.578756) (xy 78.700884 -309.569358) (xy 78.688692 -309.538116) (xy 78.684712 -309.528795)
			(xy 78.670819 -309.514062) (xy 78.652321 -309.505819) (xy 78.64221 -309.505096) (xy 78.617366 -309.50399)
			(xy 78.568512 -309.494716) (xy 78.521806 -309.47765) (xy 78.478481 -309.453243) (xy 78.439684 -309.422138)
			(xy 78.406438 -309.385159) (xy 78.379622 -309.343282) (xy 78.359946 -309.297614) (xy 78.347928 -309.249362)
			(xy 78.343886 -309.1998) (xy 78.347928 -309.150238) (xy 78.359946 -309.101985) (xy 78.379622 -309.056317)
			(xy 78.406438 -309.01444) (xy 78.439684 -308.977461) (xy 78.478482 -308.946357) (xy 78.521806 -308.92195)
			(xy 78.568513 -308.904884) (xy 78.617367 -308.89561) (xy 78.64221 -308.89448) (xy 78.652346 -308.893846)
			(xy 78.670896 -308.885622) (xy 78.684788 -308.870833) (xy 78.688692 -308.86146) (xy 78.700884 -308.830218)
			(xy 78.704694 -308.82082) (xy 78.704694 -308.627018) (xy 78.704256 -308.616955) (xy 78.69652 -308.598372)
			(xy 78.689708 -308.59095) (xy 78.66761 -308.56936) (xy 78.660748 -308.563118) (xy 78.643819 -308.555565)
			(xy 78.63459 -308.554628) (xy 78.610188 -308.552943) (xy 78.562347 -308.542777) (xy 78.516738 -308.525112)
			(xy 78.474531 -308.500399) (xy 78.436806 -308.469271) (xy 78.404527 -308.432524) (xy 78.378523 -308.3911)
			(xy 78.359457 -308.34606) (xy 78.347819 -308.298554) (xy 78.343906 -308.249801) (xy 78.347819 -308.201048)
			(xy 78.359456 -308.153543) (xy 78.378521 -308.108502) (xy 78.404526 -308.067078) (xy 78.436804 -308.030331)
			(xy 78.474529 -307.999203) (xy 78.516736 -307.97449) (xy 78.562344 -307.956824) (xy 78.610186 -307.946658)
			(xy 78.63459 -307.945028) (xy 78.643828 -307.944121) (xy 78.660767 -307.936568) (xy 78.66761 -307.930296)
			(xy 78.689708 -307.908706) (xy 78.696555 -307.901307) (xy 78.70429 -307.88271) (xy 78.704694 -307.872638)
			(xy 78.704694 -307.678836) (xy 78.700884 -307.669438) (xy 78.688692 -307.638196) (xy 78.68471 -307.628878)
			(xy 78.670815 -307.614151) (xy 78.652319 -307.605912) (xy 78.64221 -307.605176) (xy 78.617368 -307.60407)
			(xy 78.568517 -307.594797) (xy 78.521814 -307.577732) (xy 78.478492 -307.553326) (xy 78.439697 -307.522223)
			(xy 78.406453 -307.485247) (xy 78.37964 -307.443373) (xy 78.359964 -307.397708) (xy 78.347947 -307.349458)
			(xy 78.343906 -307.299899) (xy 78.347948 -307.25034) (xy 78.359965 -307.202091) (xy 78.37964 -307.156426)
			(xy 78.406454 -307.114552) (xy 78.439698 -307.077575) (xy 78.478493 -307.046473) (xy 78.521815 -307.022067)
			(xy 78.568519 -307.005003) (xy 78.61737 -306.99573) (xy 78.64221 -306.99456) (xy 78.652345 -306.993926)
			(xy 78.670892 -306.9857) (xy 78.68478 -306.970909) (xy 78.688692 -306.96154) (xy 78.700884 -306.930298)
			(xy 78.704694 -306.9209) (xy 78.704694 -306.727098) (xy 78.70427 -306.717028) (xy 78.696555 -306.698425)
			(xy 78.689708 -306.69103) (xy 78.66761 -306.66944) (xy 78.660747 -306.6632) (xy 78.643818 -306.65565)
			(xy 78.63459 -306.654708) (xy 78.61019 -306.653023) (xy 78.562351 -306.642858) (xy 78.516746 -306.625193)
			(xy 78.474542 -306.600482) (xy 78.436819 -306.569355) (xy 78.404543 -306.532612) (xy 78.37854 -306.49119)
			(xy 78.359476 -306.446152) (xy 78.347839 -306.39865) (xy 78.343926 -306.3499) (xy 78.347839 -306.30115)
			(xy 78.359476 -306.253648) (xy 78.37854 -306.20861) (xy 78.404542 -306.167189) (xy 78.436818 -306.130445)
			(xy 78.474541 -306.099319) (xy 78.516745 -306.074607) (xy 78.562351 -306.056943) (xy 78.610189 -306.046777)
			(xy 78.63459 -306.045108) (xy 78.643828 -306.0442) (xy 78.660765 -306.036645) (xy 78.66761 -306.030376)
			(xy 78.689708 -306.008786) (xy 78.696552 -306.001386) (xy 78.70428 -305.982789) (xy 78.704694 -305.972718)
			(xy 78.704694 -305.778916) (xy 78.700884 -305.769518) (xy 78.688692 -305.738276) (xy 78.684719 -305.728947)
			(xy 78.67083 -305.714197) (xy 78.652327 -305.705943) (xy 78.64221 -305.705256) (xy 78.617362 -305.704149)
			(xy 78.568498 -305.694874) (xy 78.521782 -305.677805) (xy 78.478449 -305.653393) (xy 78.439643 -305.622283)
			(xy 78.406391 -305.585297) (xy 78.37957 -305.543412) (xy 78.359889 -305.497735) (xy 78.347869 -305.449473)
			(xy 78.343826 -305.399901) (xy 78.347868 -305.350329) (xy 78.359888 -305.302067) (xy 78.379569 -305.25639)
			(xy 78.406389 -305.214505) (xy 78.439642 -305.177519) (xy 78.478447 -305.146408) (xy 78.52178 -305.121996)
			(xy 78.568495 -305.104926) (xy 78.617359 -305.095651) (xy 78.64221 -305.09464) (xy 78.652344 -305.094005)
			(xy 78.670888 -305.085778) (xy 78.684771 -305.070985) (xy 78.688692 -305.06162) (xy 78.700884 -305.030378)
			(xy 78.704694 -305.02098) (xy 78.704694 -304.826924) (xy 78.704257 -304.81686) (xy 78.696522 -304.798276)
			(xy 78.689708 -304.790856) (xy 78.66761 -304.769266) (xy 78.660748 -304.763023) (xy 78.64382 -304.755469)
			(xy 78.63459 -304.754534) (xy 78.610188 -304.752849) (xy 78.562345 -304.742683) (xy 78.516736 -304.725017)
			(xy 78.474528 -304.700304) (xy 78.436802 -304.669175) (xy 78.404523 -304.632428) (xy 78.378518 -304.591003)
			(xy 78.359452 -304.545962) (xy 78.347813 -304.498456) (xy 78.3439 -304.449702) (xy 78.347813 -304.400948)
			(xy 78.359451 -304.353441) (xy 78.378516 -304.308399) (xy 78.404521 -304.266975) (xy 78.436799 -304.230227)
			(xy 78.474525 -304.199098) (xy 78.516733 -304.174384) (xy 78.562342 -304.156718) (xy 78.610185 -304.146552)
			(xy 78.63459 -304.144934) (xy 78.643828 -304.144027) (xy 78.660768 -304.136475) (xy 78.66761 -304.130202)
			(xy 78.689708 -304.108612) (xy 78.696555 -304.101214) (xy 78.704293 -304.082616) (xy 78.704694 -304.072544)
			(xy 78.704694 -288.677096) (xy 78.70427 -288.667026) (xy 78.696554 -288.648423) (xy 78.689708 -288.641028)
			(xy 78.66761 -288.619438) (xy 78.660747 -288.613198) (xy 78.643818 -288.605649) (xy 78.63459 -288.604706)
			(xy 78.61019 -288.603021) (xy 78.562352 -288.592856) (xy 78.516747 -288.575191) (xy 78.474543 -288.55048)
			(xy 78.43682 -288.519354) (xy 78.404544 -288.48261) (xy 78.378542 -288.441189) (xy 78.359478 -288.396152)
			(xy 78.347841 -288.34865) (xy 78.343928 -288.2999) (xy 78.347841 -288.251151) (xy 78.359478 -288.203649)
			(xy 78.378541 -288.158611) (xy 78.404544 -288.11719) (xy 78.43682 -288.080446) (xy 78.474542 -288.04932)
			(xy 78.516746 -288.024609) (xy 78.562351 -288.006944) (xy 78.61019 -287.996779) (xy 78.63459 -287.995106)
			(xy 78.643828 -287.994198) (xy 78.660764 -287.986642) (xy 78.66761 -287.980374) (xy 78.689708 -287.958784)
			(xy 78.696551 -287.951384) (xy 78.704279 -287.932786) (xy 78.704694 -287.922716) (xy 78.704694 -287.727136)
			(xy 78.704259 -287.717071) (xy 78.696528 -287.698484) (xy 78.689708 -287.691068) (xy 78.66761 -287.669478)
			(xy 78.660744 -287.663244) (xy 78.643816 -287.655704) (xy 78.63459 -287.654746) (xy 78.610187 -287.653061)
			(xy 78.562342 -287.642895) (xy 78.516731 -287.625228) (xy 78.474522 -287.600514) (xy 78.436794 -287.569384)
			(xy 78.404514 -287.532636) (xy 78.378507 -287.49121) (xy 78.35944 -287.446166) (xy 78.347801 -287.398658)
			(xy 78.343888 -287.349902) (xy 78.347801 -287.301146) (xy 78.359439 -287.253638) (xy 78.378505 -287.208594)
			(xy 78.404511 -287.167168) (xy 78.436791 -287.130419) (xy 78.474518 -287.099289) (xy 78.516727 -287.074574)
			(xy 78.562338 -287.056907) (xy 78.610182 -287.04674) (xy 78.63459 -287.045146) (xy 78.643829 -287.044239)
			(xy 78.660769 -287.036688) (xy 78.66761 -287.030414) (xy 78.689708 -287.008824) (xy 78.696542 -287.001421)
			(xy 78.704247 -286.982823) (xy 78.704694 -286.972756) (xy 78.704694 -286.823404) (xy 78.704271 -286.813334)
			(xy 78.696557 -286.794729) (xy 78.689708 -286.787336) (xy 78.609698 -286.707326) (xy 78.596998 -286.700468)
			(xy 78.589378 -286.698944) (xy 78.565978 -286.69376) (xy 78.521049 -286.677083) (xy 78.479281 -286.653584)
			(xy 78.441702 -286.623842) (xy 78.409237 -286.588588) (xy 78.395576 -286.568896) (xy 78.388062 -286.558832)
			(xy 78.365953 -286.546976) (xy 78.353412 -286.54629) (xy 78.022196 -286.54629) (xy 78.013496 -286.546641)
			(xy 77.997096 -286.552459) (xy 77.983584 -286.563424) (xy 77.978762 -286.570674) (xy 77.964901 -286.592324)
			(xy 77.931513 -286.631409) (xy 77.892423 -286.664791) (xy 77.848592 -286.691647) (xy 77.8011 -286.711317)
			(xy 77.751116 -286.723316) (xy 77.69987 -286.727348) (xy 77.648624 -286.723316) (xy 77.59864 -286.711317)
			(xy 77.551148 -286.691647) (xy 77.507317 -286.664791) (xy 77.468227 -286.631409) (xy 77.434839 -286.592324)
			(xy 77.420978 -286.570674) (xy 77.416158 -286.563417) (xy 77.402656 -286.552427) (xy 77.386249 -286.546604)
			(xy 77.377544 -286.54629) (xy 77.072236 -286.54629) (xy 77.063541 -286.546651) (xy 77.047156 -286.552482)
			(xy 77.033661 -286.563452) (xy 77.028802 -286.570674) (xy 77.014941 -286.592324) (xy 76.981553 -286.631409)
			(xy 76.942463 -286.664791) (xy 76.898632 -286.691647) (xy 76.85114 -286.711317) (xy 76.801156 -286.723316)
			(xy 76.74991 -286.727348) (xy 76.698664 -286.723316) (xy 76.64868 -286.711317) (xy 76.601188 -286.691647)
			(xy 76.557357 -286.664791) (xy 76.518267 -286.631409) (xy 76.484879 -286.592324) (xy 76.471018 -286.570674)
			(xy 76.466196 -286.563423) (xy 76.452691 -286.552449) (xy 76.436286 -286.546645) (xy 76.427584 -286.54629)
			(xy 76.096368 -286.54629) (xy 76.083815 -286.546938) (xy 76.061689 -286.558798) (xy 76.054204 -286.568896)
			(xy 76.039899 -286.589458) (xy 76.005699 -286.62605) (xy 75.965988 -286.656575) (xy 75.921831 -286.680214)
			(xy 75.874409 -286.696334) (xy 75.824993 -286.704503) (xy 75.774907 -286.704503) (xy 75.725491 -286.696334)
			(xy 75.678069 -286.680214) (xy 75.633912 -286.656575) (xy 75.594201 -286.62605) (xy 75.560001 -286.589458)
			(xy 75.545696 -286.568896) (xy 75.538183 -286.558829) (xy 75.516075 -286.546964) (xy 75.503532 -286.54629)
			(xy 75.146408 -286.54629) (xy 75.13385 -286.546929) (xy 75.111709 -286.55878) (xy 75.104244 -286.568896)
			(xy 75.089939 -286.589458) (xy 75.055739 -286.62605) (xy 75.016028 -286.656575) (xy 74.971871 -286.680214)
			(xy 74.924449 -286.696334) (xy 74.875033 -286.704503) (xy 74.824947 -286.704503) (xy 74.775531 -286.696334)
			(xy 74.728109 -286.680214) (xy 74.683952 -286.656575) (xy 74.644241 -286.62605) (xy 74.610041 -286.589458)
			(xy 74.595736 -286.568896) (xy 74.588226 -286.558822) (xy 74.566118 -286.54694) (xy 74.553572 -286.54629)
			(xy 74.196194 -286.54629) (xy 74.183638 -286.546933) (xy 74.161502 -286.558786) (xy 74.15403 -286.568896)
			(xy 74.139725 -286.589458) (xy 74.105525 -286.62605) (xy 74.065814 -286.656575) (xy 74.021657 -286.680214)
			(xy 73.974235 -286.696334) (xy 73.924819 -286.704503) (xy 73.874733 -286.704503) (xy 73.825317 -286.696334)
			(xy 73.777895 -286.680214) (xy 73.733738 -286.656575) (xy 73.694027 -286.62605) (xy 73.659827 -286.589458)
			(xy 73.645522 -286.568896) (xy 73.638011 -286.558824) (xy 73.615903 -286.546949) (xy 73.603358 -286.54629)
			(xy 70.912482 -286.54629) (xy 70.903312 -286.546672) (xy 70.886156 -286.55315) (xy 70.872414 -286.565292)
			(xy 70.867778 -286.573214) (xy 70.818756 -286.664908) (xy 70.82028 -286.692848) (xy 70.828154 -286.704532)
			(xy 70.840446 -286.72352) (xy 70.859896 -286.764356) (xy 70.873106 -286.807615) (xy 70.879786 -286.85235)
			(xy 70.880224 -286.874966) (xy 70.879702 -286.900221) (xy 70.871389 -286.950043) (xy 70.854988 -286.997817)
			(xy 70.830947 -287.04224) (xy 70.799923 -287.0821) (xy 70.762761 -287.11631) (xy 70.720475 -287.143936)
			(xy 70.674219 -287.164226) (xy 70.625254 -287.176626) (xy 70.574916 -287.180797) (xy 70.524578 -287.176626)
			(xy 70.475613 -287.164226) (xy 70.429357 -287.143936) (xy 70.387071 -287.11631) (xy 70.349909 -287.0821)
			(xy 70.318885 -287.04224) (xy 70.294844 -286.997817) (xy 70.278443 -286.950043) (xy 70.27013 -286.900221)
			(xy 70.269608 -286.874966) (xy 70.270015 -286.852348) (xy 70.276689 -286.807606) (xy 70.2899 -286.764342)
			(xy 70.309359 -286.723505) (xy 70.321678 -286.704532) (xy 70.329552 -286.692848) (xy 70.331076 -286.664908)
			(xy 70.282054 -286.573214) (xy 70.277389 -286.565321) (xy 70.263628 -286.553227) (xy 70.246508 -286.546706)
			(xy 70.23735 -286.54629) (xy 69.962522 -286.54629) (xy 69.953348 -286.546666) (xy 69.936181 -286.553134)
			(xy 69.922427 -286.565274) (xy 69.917818 -286.573214) (xy 69.868796 -286.664908) (xy 69.87032 -286.692848)
			(xy 69.878194 -286.704532) (xy 69.890488 -286.723519) (xy 69.909942 -286.764354) (xy 69.923154 -286.807614)
			(xy 69.929836 -286.85235) (xy 69.930264 -286.874966) (xy 69.929742 -286.900221) (xy 69.921429 -286.950043)
			(xy 69.905028 -286.997817) (xy 69.880987 -287.04224) (xy 69.849963 -287.0821) (xy 69.812801 -287.11631)
			(xy 69.770515 -287.143936) (xy 69.724259 -287.164226) (xy 69.675294 -287.176626) (xy 69.624956 -287.180797)
			(xy 69.574618 -287.176626) (xy 69.525653 -287.164226) (xy 69.479397 -287.143936) (xy 69.437111 -287.11631)
			(xy 69.399949 -287.0821) (xy 69.368925 -287.04224) (xy 69.344884 -286.997817) (xy 69.328483 -286.950043)
			(xy 69.32017 -286.900221) (xy 69.319648 -286.874966) (xy 69.320055 -286.852348) (xy 69.32673 -286.807607)
			(xy 69.339943 -286.764344) (xy 69.359404 -286.723508) (xy 69.371718 -286.704532) (xy 69.379592 -286.692848)
			(xy 69.381116 -286.664908) (xy 69.332094 -286.573214) (xy 69.327426 -286.565328) (xy 69.313663 -286.55325)
			(xy 69.296544 -286.546748) (xy 69.28739 -286.54629) (xy 69.012308 -286.54629) (xy 69.003136 -286.546668)
			(xy 68.985972 -286.55314) (xy 68.972222 -286.565281) (xy 68.967604 -286.573214) (xy 68.918582 -286.664908)
			(xy 68.920106 -286.692848) (xy 68.92798 -286.704532) (xy 68.940271 -286.72352) (xy 68.959719 -286.764357)
			(xy 68.972928 -286.807616) (xy 68.979608 -286.852351) (xy 68.98005 -286.874966) (xy 68.979528 -286.900221)
			(xy 68.971215 -286.950043) (xy 68.954814 -286.997817) (xy 68.930773 -287.04224) (xy 68.899749 -287.0821)
			(xy 68.862587 -287.11631) (xy 68.820301 -287.143936) (xy 68.774045 -287.164226) (xy 68.72508 -287.176626)
			(xy 68.674742 -287.180797) (xy 68.624404 -287.176626) (xy 68.575439 -287.164226) (xy 68.529183 -287.143936)
			(xy 68.486897 -287.11631) (xy 68.449735 -287.0821) (xy 68.418711 -287.04224) (xy 68.39467 -286.997817)
			(xy 68.378269 -286.950043) (xy 68.369956 -286.900221) (xy 68.369434 -286.874966) (xy 68.369841 -286.852348)
			(xy 68.376515 -286.807607) (xy 68.389728 -286.764343) (xy 68.409188 -286.723507) (xy 68.421504 -286.704532)
			(xy 68.429378 -286.692848) (xy 68.430902 -286.664908) (xy 68.38188 -286.573214) (xy 68.377212 -286.56533)
			(xy 68.363447 -286.553255) (xy 68.346329 -286.546758) (xy 68.337176 -286.54629) (xy 68.062348 -286.54629)
			(xy 68.053172 -286.546661) (xy 68.035998 -286.553124) (xy 68.022236 -286.565263) (xy 68.017644 -286.573214)
			(xy 67.968622 -286.664908) (xy 67.970146 -286.692848) (xy 67.97802 -286.704532) (xy 67.990313 -286.72352)
			(xy 68.009765 -286.764355) (xy 68.022977 -286.807614) (xy 68.029658 -286.85235) (xy 68.03009 -286.874966)
			(xy 68.029568 -286.900221) (xy 68.021255 -286.950043) (xy 68.004854 -286.997817) (xy 67.980813 -287.04224)
			(xy 67.949789 -287.0821) (xy 67.912627 -287.11631) (xy 67.870341 -287.143936) (xy 67.824085 -287.164226)
			(xy 67.77512 -287.176626) (xy 67.724782 -287.180797) (xy 67.674444 -287.176626) (xy 67.625479 -287.164226)
			(xy 67.579223 -287.143936) (xy 67.536937 -287.11631) (xy 67.499775 -287.0821) (xy 67.468751 -287.04224)
			(xy 67.44471 -286.997817) (xy 67.428309 -286.950043) (xy 67.419996 -286.900221) (xy 67.419474 -286.874966)
			(xy 67.419881 -286.852348) (xy 67.426556 -286.807607) (xy 67.43977 -286.764345) (xy 67.459233 -286.72351)
			(xy 67.471544 -286.704532) (xy 67.479418 -286.692848) (xy 67.480942 -286.664908) (xy 67.43192 -286.573214)
			(xy 67.427253 -286.565325) (xy 67.413491 -286.55324) (xy 67.396371 -286.54673) (xy 67.387216 -286.54629)
			(xy 67.112388 -286.54629) (xy 67.103218 -286.546671) (xy 67.08606 -286.553147) (xy 67.072316 -286.56529)
			(xy 67.067684 -286.573214) (xy 67.018662 -286.664908) (xy 67.020186 -286.692848) (xy 67.02806 -286.704532)
			(xy 67.040352 -286.72352) (xy 67.059801 -286.764356) (xy 67.073011 -286.807615) (xy 67.079691 -286.85235)
			(xy 67.08013 -286.874966) (xy 67.079608 -286.900221) (xy 67.071295 -286.950043) (xy 67.054894 -286.997817)
			(xy 67.030853 -287.04224) (xy 66.999829 -287.0821) (xy 66.962667 -287.11631) (xy 66.920381 -287.143936)
			(xy 66.874125 -287.164226) (xy 66.82516 -287.176626) (xy 66.774822 -287.180797) (xy 66.724484 -287.176626)
			(xy 66.675519 -287.164226) (xy 66.629263 -287.143936) (xy 66.586977 -287.11631) (xy 66.549815 -287.0821)
			(xy 66.518791 -287.04224) (xy 66.49475 -286.997817) (xy 66.478349 -286.950043) (xy 66.470036 -286.900221)
			(xy 66.469514 -286.874966) (xy 66.469921 -286.852348) (xy 66.476595 -286.807607) (xy 66.489807 -286.764343)
			(xy 66.509266 -286.723506) (xy 66.521584 -286.704532) (xy 66.529458 -286.692848) (xy 66.530982 -286.664908)
			(xy 66.48196 -286.573214) (xy 66.477296 -286.565321) (xy 66.463535 -286.553225) (xy 66.446414 -286.546701)
			(xy 66.437256 -286.54629) (xy 66.162428 -286.54629) (xy 66.153254 -286.546665) (xy 66.136085 -286.553132)
			(xy 66.122329 -286.565272) (xy 66.117724 -286.573214) (xy 66.068702 -286.664908) (xy 66.070226 -286.692848)
			(xy 66.0781 -286.704532) (xy 66.090394 -286.723519) (xy 66.109847 -286.764355) (xy 66.12306 -286.807614)
			(xy 66.129741 -286.85235) (xy 66.13017 -286.874966) (xy 66.129648 -286.900221) (xy 66.121335 -286.950043)
			(xy 66.104934 -286.997817) (xy 66.080893 -287.04224) (xy 66.049869 -287.0821) (xy 66.012707 -287.11631)
			(xy 65.970421 -287.143936) (xy 65.924165 -287.164226) (xy 65.8752 -287.176626) (xy 65.824862 -287.180797)
			(xy 65.774524 -287.176626) (xy 65.725559 -287.164226) (xy 65.679303 -287.143936) (xy 65.637017 -287.11631)
			(xy 65.599855 -287.0821) (xy 65.568831 -287.04224) (xy 65.54479 -286.997817) (xy 65.528389 -286.950043)
			(xy 65.520076 -286.900221) (xy 65.519554 -286.874966) (xy 65.519961 -286.852348) (xy 65.526636 -286.807607)
			(xy 65.539849 -286.764344) (xy 65.55931 -286.723508) (xy 65.571624 -286.704532) (xy 65.579498 -286.692848)
			(xy 65.581022 -286.664908) (xy 65.532 -286.573214) (xy 65.527333 -286.565327) (xy 65.513569 -286.553247)
			(xy 65.49645 -286.546744) (xy 65.487296 -286.54629) (xy 65.212468 -286.54629) (xy 65.2033 -286.546674)
			(xy 65.186147 -286.553155) (xy 65.172409 -286.565298) (xy 65.167764 -286.573214) (xy 65.118742 -286.664908)
			(xy 65.120266 -286.692848) (xy 65.12814 -286.704532) (xy 65.140432 -286.72352) (xy 65.159883 -286.764356)
			(xy 65.173094 -286.807615) (xy 65.179775 -286.85235) (xy 65.18021 -286.874966) (xy 65.179688 -286.900221)
			(xy 65.171375 -286.950043) (xy 65.154974 -286.997817) (xy 65.130933 -287.04224) (xy 65.099909 -287.0821)
			(xy 65.062747 -287.11631) (xy 65.020461 -287.143936) (xy 64.974205 -287.164226) (xy 64.92524 -287.176626)
			(xy 64.874902 -287.180797) (xy 64.824564 -287.176626) (xy 64.775599 -287.164226) (xy 64.729343 -287.143936)
			(xy 64.687057 -287.11631) (xy 64.649895 -287.0821) (xy 64.618871 -287.04224) (xy 64.59483 -286.997817)
			(xy 64.578429 -286.950043) (xy 64.570116 -286.900221) (xy 64.569594 -286.874966) (xy 64.570001 -286.852348)
			(xy 64.576674 -286.807606) (xy 64.589885 -286.764342) (xy 64.609344 -286.723504) (xy 64.621664 -286.704532)
			(xy 64.629538 -286.692848) (xy 64.631062 -286.664908) (xy 64.58204 -286.573214) (xy 64.577375 -286.565323)
			(xy 64.563613 -286.553232) (xy 64.546493 -286.546715) (xy 64.537336 -286.54629) (xy 64.262508 -286.54629)
			(xy 64.253336 -286.546668) (xy 64.236172 -286.55314) (xy 64.222422 -286.565281) (xy 64.217804 -286.573214)
			(xy 64.168782 -286.664908) (xy 64.170306 -286.692848) (xy 64.17818 -286.704532) (xy 64.190471 -286.72352)
			(xy 64.209919 -286.764357) (xy 64.223128 -286.807616) (xy 64.229808 -286.852351) (xy 64.23025 -286.874966)
			(xy 64.229728 -286.900221) (xy 64.221415 -286.950043) (xy 64.205014 -286.997817) (xy 64.180973 -287.04224)
			(xy 64.149949 -287.0821) (xy 64.112787 -287.11631) (xy 64.070501 -287.143936) (xy 64.024245 -287.164226)
			(xy 63.97528 -287.176626) (xy 63.924942 -287.180797) (xy 63.874604 -287.176626) (xy 63.825639 -287.164226)
			(xy 63.779383 -287.143936) (xy 63.737097 -287.11631) (xy 63.699935 -287.0821) (xy 63.668911 -287.04224)
			(xy 63.64487 -286.997817) (xy 63.628469 -286.950043) (xy 63.620156 -286.900221) (xy 63.619634 -286.874966)
			(xy 63.620041 -286.852348) (xy 63.626715 -286.807607) (xy 63.639928 -286.764343) (xy 63.659388 -286.723507)
			(xy 63.671704 -286.704532) (xy 63.679578 -286.692848) (xy 63.681102 -286.664908) (xy 63.63208 -286.573214)
			(xy 63.627412 -286.56533) (xy 63.613647 -286.553255) (xy 63.596529 -286.546758) (xy 63.587376 -286.54629)
			(xy 63.312548 -286.54629) (xy 63.303372 -286.546661) (xy 63.286198 -286.553124) (xy 63.272436 -286.565263)
			(xy 63.267844 -286.573214) (xy 63.218822 -286.664908) (xy 63.220346 -286.692848) (xy 63.22822 -286.704532)
			(xy 63.240513 -286.72352) (xy 63.259965 -286.764355) (xy 63.273177 -286.807614) (xy 63.279858 -286.85235)
			(xy 63.28029 -286.874966) (xy 63.279768 -286.900221) (xy 63.271455 -286.950043) (xy 63.255054 -286.997817)
			(xy 63.231013 -287.04224) (xy 63.199989 -287.0821) (xy 63.162827 -287.11631) (xy 63.120541 -287.143936)
			(xy 63.074285 -287.164226) (xy 63.02532 -287.176626) (xy 62.974982 -287.180797) (xy 62.924644 -287.176626)
			(xy 62.875679 -287.164226) (xy 62.829423 -287.143936) (xy 62.787137 -287.11631) (xy 62.749975 -287.0821)
			(xy 62.718951 -287.04224) (xy 62.69491 -286.997817) (xy 62.678509 -286.950043) (xy 62.670196 -286.900221)
			(xy 62.669674 -286.874966) (xy 62.670081 -286.852348) (xy 62.676756 -286.807607) (xy 62.68997 -286.764345)
			(xy 62.709433 -286.72351) (xy 62.721744 -286.704532) (xy 62.729618 -286.692848) (xy 62.731142 -286.664908)
			(xy 62.68212 -286.573214) (xy 62.677453 -286.565325) (xy 62.663691 -286.55324) (xy 62.646571 -286.54673)
			(xy 62.637416 -286.54629) (xy 62.362334 -286.54629) (xy 62.353159 -286.546664) (xy 62.335989 -286.55313)
			(xy 62.322231 -286.565269) (xy 62.31763 -286.573214) (xy 62.268608 -286.664908) (xy 62.270132 -286.692848)
			(xy 62.278006 -286.704532) (xy 62.2903 -286.723519) (xy 62.309753 -286.764355) (xy 62.322965 -286.807614)
			(xy 62.329646 -286.85235) (xy 62.330076 -286.874966) (xy 62.329554 -286.900221) (xy 62.321241 -286.950043)
			(xy 62.30484 -286.997817) (xy 62.280799 -287.04224) (xy 62.249775 -287.0821) (xy 62.212613 -287.11631)
			(xy 62.170327 -287.143936) (xy 62.124071 -287.164226) (xy 62.075106 -287.176626) (xy 62.024768 -287.180797)
			(xy 61.97443 -287.176626) (xy 61.925465 -287.164226) (xy 61.879209 -287.143936) (xy 61.836923 -287.11631)
			(xy 61.799761 -287.0821) (xy 61.768737 -287.04224) (xy 61.744696 -286.997817) (xy 61.728295 -286.950043)
			(xy 61.719982 -286.900221) (xy 61.71946 -286.874966) (xy 61.719867 -286.852348) (xy 61.726542 -286.807607)
			(xy 61.739755 -286.764344) (xy 61.759217 -286.723509) (xy 61.77153 -286.704532) (xy 61.779404 -286.692848)
			(xy 61.780928 -286.664908) (xy 61.731906 -286.573214) (xy 61.727239 -286.565327) (xy 61.713476 -286.553245)
			(xy 61.696356 -286.546739) (xy 61.687202 -286.54629) (xy 61.412374 -286.54629) (xy 61.403205 -286.546673)
			(xy 61.386051 -286.553153) (xy 61.372311 -286.565296) (xy 61.36767 -286.573214) (xy 61.318648 -286.664908)
			(xy 61.320172 -286.692848) (xy 61.328046 -286.704532) (xy 61.340338 -286.72352) (xy 61.359789 -286.764356)
			(xy 61.372999 -286.807615) (xy 61.37968 -286.85235) (xy 61.380116 -286.874966) (xy 61.379594 -286.900221)
			(xy 61.371281 -286.950043) (xy 61.35488 -286.997817) (xy 61.330839 -287.04224) (xy 61.299815 -287.0821)
			(xy 61.262653 -287.11631) (xy 61.220367 -287.143936) (xy 61.174111 -287.164226) (xy 61.125146 -287.176626)
			(xy 61.074808 -287.180797) (xy 61.02447 -287.176626) (xy 60.975505 -287.164226) (xy 60.929249 -287.143936)
			(xy 60.886963 -287.11631) (xy 60.849801 -287.0821) (xy 60.818777 -287.04224) (xy 60.794736 -286.997817)
			(xy 60.778335 -286.950043) (xy 60.770022 -286.900221) (xy 60.7695 -286.874966) (xy 60.769907 -286.852348)
			(xy 60.776581 -286.807606) (xy 60.789792 -286.764342) (xy 60.80925 -286.723505) (xy 60.82157 -286.704532)
			(xy 60.829444 -286.692848) (xy 60.830968 -286.664908) (xy 60.781946 -286.573214) (xy 60.777281 -286.565322)
			(xy 60.76352 -286.55323) (xy 60.746399 -286.546711) (xy 60.737242 -286.54629) (xy 60.462414 -286.54629)
			(xy 60.453241 -286.546667) (xy 60.436076 -286.553137) (xy 60.422325 -286.565278) (xy 60.41771 -286.573214)
			(xy 60.368688 -286.664908) (xy 60.370212 -286.692848) (xy 60.378086 -286.704532) (xy 60.390377 -286.72352)
			(xy 60.409825 -286.764357) (xy 60.423033 -286.807616) (xy 60.429713 -286.852351) (xy 60.430156 -286.874966)
			(xy 60.429634 -286.900221) (xy 60.421321 -286.950043) (xy 60.40492 -286.997817) (xy 60.380879 -287.04224)
			(xy 60.349855 -287.0821) (xy 60.312693 -287.11631) (xy 60.270407 -287.143936) (xy 60.224151 -287.164226)
			(xy 60.175186 -287.176626) (xy 60.124848 -287.180797) (xy 60.07451 -287.176626) (xy 60.025545 -287.164226)
			(xy 59.979289 -287.143936) (xy 59.937003 -287.11631) (xy 59.899841 -287.0821) (xy 59.868817 -287.04224)
			(xy 59.844776 -286.997817) (xy 59.828375 -286.950043) (xy 59.820062 -286.900221) (xy 59.81954 -286.874966)
			(xy 59.819947 -286.852348) (xy 59.826621 -286.807607) (xy 59.839834 -286.764343) (xy 59.859295 -286.723507)
			(xy 59.87161 -286.704532) (xy 59.879484 -286.692848) (xy 59.881008 -286.664908) (xy 59.831986 -286.573214)
			(xy 59.827318 -286.565329) (xy 59.813554 -286.553253) (xy 59.796435 -286.546753) (xy 59.787282 -286.54629)
			(xy 58.562494 -286.54629) (xy 58.553323 -286.54667) (xy 58.536164 -286.553145) (xy 58.522418 -286.565287)
			(xy 58.51779 -286.573214) (xy 58.468768 -286.664908) (xy 58.470292 -286.692848) (xy 58.478166 -286.704532)
			(xy 58.490457 -286.72352) (xy 58.509907 -286.764356) (xy 58.523116 -286.807615) (xy 58.529796 -286.852351)
			(xy 58.530236 -286.874966) (xy 58.529714 -286.900221) (xy 58.521401 -286.950043) (xy 58.505 -286.997817)
			(xy 58.480959 -287.04224) (xy 58.449935 -287.0821) (xy 58.412773 -287.11631) (xy 58.370487 -287.143936)
			(xy 58.324231 -287.164226) (xy 58.275266 -287.176626) (xy 58.224928 -287.180797) (xy 58.17459 -287.176626)
			(xy 58.125625 -287.164226) (xy 58.079369 -287.143936) (xy 58.037083 -287.11631) (xy 57.999921 -287.0821)
			(xy 57.968897 -287.04224) (xy 57.944856 -286.997817) (xy 57.928455 -286.950043) (xy 57.920142 -286.900221)
			(xy 57.91962 -286.874966) (xy 57.920027 -286.852348) (xy 57.926701 -286.807607) (xy 57.939913 -286.764343)
			(xy 57.959373 -286.723506) (xy 57.97169 -286.704532) (xy 57.979564 -286.692848) (xy 57.981088 -286.664908)
			(xy 57.932066 -286.573214) (xy 57.927402 -286.56532) (xy 57.913641 -286.553222) (xy 57.89652 -286.546697)
			(xy 57.887362 -286.54629) (xy 57.612534 -286.54629) (xy 57.603359 -286.546664) (xy 57.586189 -286.55313)
			(xy 57.572431 -286.565269) (xy 57.56783 -286.573214) (xy 57.518808 -286.664908) (xy 57.520332 -286.692848)
			(xy 57.528206 -286.704532) (xy 57.5405 -286.723519) (xy 57.559953 -286.764355) (xy 57.573165 -286.807614)
			(xy 57.579846 -286.85235) (xy 57.580276 -286.874966) (xy 57.579754 -286.900221) (xy 57.571441 -286.950043)
			(xy 57.55504 -286.997817) (xy 57.530999 -287.04224) (xy 57.499975 -287.0821) (xy 57.462813 -287.11631)
			(xy 57.420527 -287.143936) (xy 57.374271 -287.164226) (xy 57.325306 -287.176626) (xy 57.274968 -287.180797)
			(xy 57.22463 -287.176626) (xy 57.175665 -287.164226) (xy 57.129409 -287.143936) (xy 57.087123 -287.11631)
			(xy 57.049961 -287.0821) (xy 57.018937 -287.04224) (xy 56.994896 -286.997817) (xy 56.978495 -286.950043)
			(xy 56.970182 -286.900221) (xy 56.96966 -286.874966) (xy 56.970067 -286.852348) (xy 56.976742 -286.807607)
			(xy 56.989955 -286.764344) (xy 57.009417 -286.723509) (xy 57.02173 -286.704532) (xy 57.029604 -286.692848)
			(xy 57.031128 -286.664908) (xy 56.982106 -286.573214) (xy 56.977439 -286.565327) (xy 56.963676 -286.553245)
			(xy 56.946556 -286.546739) (xy 56.937402 -286.54629) (xy 56.66232 -286.54629) (xy 56.653147 -286.546666)
			(xy 56.63598 -286.553135) (xy 56.622227 -286.565275) (xy 56.617616 -286.573214) (xy 56.568594 -286.664908)
			(xy 56.570118 -286.692848) (xy 56.577992 -286.704532) (xy 56.590283 -286.723521) (xy 56.60973 -286.764357)
			(xy 56.622938 -286.807616) (xy 56.629618 -286.852351) (xy 56.630062 -286.874966) (xy 56.62954 -286.900221)
			(xy 56.621227 -286.950043) (xy 56.604826 -286.997817) (xy 56.580785 -287.04224) (xy 56.549761 -287.0821)
			(xy 56.512599 -287.11631) (xy 56.470313 -287.143936) (xy 56.424057 -287.164226) (xy 56.375092 -287.176626)
			(xy 56.324754 -287.180797) (xy 56.274416 -287.176626) (xy 56.225451 -287.164226) (xy 56.179195 -287.143936)
			(xy 56.136909 -287.11631) (xy 56.099747 -287.0821) (xy 56.068723 -287.04224) (xy 56.044682 -286.997817)
			(xy 56.028281 -286.950043) (xy 56.019968 -286.900221) (xy 56.019446 -286.874966) (xy 56.019853 -286.852348)
			(xy 56.026528 -286.807607) (xy 56.039741 -286.764344) (xy 56.059202 -286.723508) (xy 56.071516 -286.704532)
			(xy 56.07939 -286.692848) (xy 56.080914 -286.664908) (xy 56.031892 -286.573214) (xy 56.027224 -286.565328)
			(xy 56.01346 -286.55325) (xy 55.996341 -286.546749) (xy 55.987188 -286.54629) (xy 55.71236 -286.54629)
			(xy 55.703183 -286.546659) (xy 55.686005 -286.55312) (xy 55.67224 -286.565258) (xy 55.667656 -286.573214)
			(xy 55.618634 -286.664908) (xy 55.620158 -286.692848) (xy 55.628032 -286.704532) (xy 55.640325 -286.72352)
			(xy 55.659776 -286.764355) (xy 55.672987 -286.807615) (xy 55.679668 -286.85235) (xy 55.680102 -286.874966)
			(xy 55.67958 -286.900221) (xy 55.671267 -286.950043) (xy 55.654866 -286.997817) (xy 55.630825 -287.04224)
			(xy 55.599801 -287.0821) (xy 55.562639 -287.11631) (xy 55.520353 -287.143936) (xy 55.474097 -287.164226)
			(xy 55.425132 -287.176626) (xy 55.374794 -287.180797) (xy 55.324456 -287.176626) (xy 55.275491 -287.164226)
			(xy 55.229235 -287.143936) (xy 55.186949 -287.11631) (xy 55.149787 -287.0821) (xy 55.118763 -287.04224)
			(xy 55.094722 -286.997817) (xy 55.078321 -286.950043) (xy 55.070008 -286.900221) (xy 55.069486 -286.874966)
			(xy 55.069892 -286.852348) (xy 55.076566 -286.807606) (xy 55.089777 -286.764342) (xy 55.109235 -286.723504)
			(xy 55.121556 -286.704532) (xy 55.12943 -286.692848) (xy 55.130954 -286.664908) (xy 55.081932 -286.573214)
			(xy 55.077266 -286.565324) (xy 55.063504 -286.553235) (xy 55.046384 -286.546721) (xy 55.037228 -286.54629)
			(xy 54.7624 -286.54629) (xy 54.753228 -286.546669) (xy 54.736067 -286.553143) (xy 54.72232 -286.565284)
			(xy 54.717696 -286.573214) (xy 54.668674 -286.664908) (xy 54.670198 -286.692848) (xy 54.678072 -286.704532)
			(xy 54.690363 -286.72352) (xy 54.709812 -286.764356) (xy 54.723021 -286.807616) (xy 54.729701 -286.852351)
			(xy 54.730142 -286.874966) (xy 54.72962 -286.900221) (xy 54.721307 -286.950043) (xy 54.704906 -286.997817)
			(xy 54.680865 -287.04224) (xy 54.649841 -287.0821) (xy 54.612679 -287.11631) (xy 54.570393 -287.143936)
			(xy 54.524137 -287.164226) (xy 54.475172 -287.176626) (xy 54.424834 -287.180797) (xy 54.374496 -287.176626)
			(xy 54.325531 -287.164226) (xy 54.279275 -287.143936) (xy 54.236989 -287.11631) (xy 54.199827 -287.0821)
			(xy 54.168803 -287.04224) (xy 54.144762 -286.997817) (xy 54.128361 -286.950043) (xy 54.120048 -286.900221)
			(xy 54.119526 -286.874966) (xy 54.119933 -286.852348) (xy 54.126607 -286.807607) (xy 54.139819 -286.764343)
			(xy 54.159279 -286.723506) (xy 54.171596 -286.704532) (xy 54.17947 -286.692848) (xy 54.180994 -286.664908)
			(xy 54.131972 -286.573214) (xy 54.127303 -286.56533) (xy 54.113539 -286.553258) (xy 54.09642 -286.546763)
			(xy 54.087268 -286.54629) (xy 53.81244 -286.54629) (xy 53.803265 -286.546663) (xy 53.786093 -286.553128)
			(xy 53.772333 -286.565267) (xy 53.767736 -286.573214) (xy 53.718714 -286.664908) (xy 53.720238 -286.692848)
			(xy 53.728112 -286.704532) (xy 53.740405 -286.723519) (xy 53.759858 -286.764355) (xy 53.77307 -286.807614)
			(xy 53.779751 -286.85235) (xy 53.780182 -286.874966) (xy 53.77966 -286.900221) (xy 53.771347 -286.950043)
			(xy 53.754946 -286.997817) (xy 53.730905 -287.04224) (xy 53.699881 -287.0821) (xy 53.662719 -287.11631)
			(xy 53.620433 -287.143936) (xy 53.574177 -287.164226) (xy 53.525212 -287.176626) (xy 53.474874 -287.180797)
			(xy 53.424536 -287.176626) (xy 53.375571 -287.164226) (xy 53.329315 -287.143936) (xy 53.287029 -287.11631)
			(xy 53.249867 -287.0821) (xy 53.218843 -287.04224) (xy 53.194802 -286.997817) (xy 53.178401 -286.950043)
			(xy 53.170088 -286.900221) (xy 53.169566 -286.874966) (xy 53.169973 -286.852348) (xy 53.176648 -286.807607)
			(xy 53.189862 -286.764344) (xy 53.209324 -286.723509) (xy 53.221636 -286.704532) (xy 53.22951 -286.692848)
			(xy 53.231034 -286.664908) (xy 53.182012 -286.573214) (xy 53.177345 -286.565326) (xy 53.163582 -286.553243)
			(xy 53.146463 -286.546735) (xy 53.137308 -286.54629) (xy 52.86248 -286.54629) (xy 52.85331 -286.546672)
			(xy 52.836155 -286.553151) (xy 52.822413 -286.565293) (xy 52.817776 -286.573214) (xy 52.768754 -286.664908)
			(xy 52.770278 -286.692848) (xy 52.778152 -286.704532) (xy 52.790444 -286.72352) (xy 52.809894 -286.764356)
			(xy 52.823104 -286.807615) (xy 52.829785 -286.85235) (xy 52.830222 -286.874966) (xy 52.8297 -286.900221)
			(xy 52.821387 -286.950043) (xy 52.804986 -286.997817) (xy 52.780945 -287.04224) (xy 52.749921 -287.0821)
			(xy 52.712759 -287.11631) (xy 52.670473 -287.143936) (xy 52.624217 -287.164226) (xy 52.575252 -287.176626)
			(xy 52.524914 -287.180797) (xy 52.474576 -287.176626) (xy 52.425611 -287.164226) (xy 52.379355 -287.143936)
			(xy 52.337069 -287.11631) (xy 52.299907 -287.0821) (xy 52.268883 -287.04224) (xy 52.244842 -286.997817)
			(xy 52.228441 -286.950043) (xy 52.220128 -286.900221) (xy 52.219606 -286.874966) (xy 52.220013 -286.852348)
			(xy 52.226687 -286.807606) (xy 52.239898 -286.764342) (xy 52.259357 -286.723505) (xy 52.271676 -286.704532)
			(xy 52.27955 -286.692848) (xy 52.281074 -286.664908) (xy 52.232052 -286.573214) (xy 52.227387 -286.565322)
			(xy 52.213626 -286.553228) (xy 52.196506 -286.546707) (xy 52.187348 -286.54629) (xy 51.91252 -286.54629)
			(xy 51.903347 -286.546666) (xy 51.88618 -286.553135) (xy 51.872427 -286.565275) (xy 51.867816 -286.573214)
			(xy 51.818794 -286.664908) (xy 51.820318 -286.692848) (xy 51.828192 -286.704532) (xy 51.840483 -286.723521)
			(xy 51.85993 -286.764357) (xy 51.873138 -286.807616) (xy 51.879818 -286.852351) (xy 51.880262 -286.874966)
			(xy 51.87974 -286.900221) (xy 51.871427 -286.950043) (xy 51.855026 -286.997817) (xy 51.830985 -287.04224)
			(xy 51.799961 -287.0821) (xy 51.762799 -287.11631) (xy 51.720513 -287.143936) (xy 51.674257 -287.164226)
			(xy 51.625292 -287.176626) (xy 51.574954 -287.180797) (xy 51.524616 -287.176626) (xy 51.475651 -287.164226)
			(xy 51.429395 -287.143936) (xy 51.387109 -287.11631) (xy 51.349947 -287.0821) (xy 51.318923 -287.04224)
			(xy 51.294882 -286.997817) (xy 51.278481 -286.950043) (xy 51.270168 -286.900221) (xy 51.269646 -286.874966)
			(xy 51.270053 -286.852348) (xy 51.276728 -286.807607) (xy 51.289941 -286.764344) (xy 51.309402 -286.723508)
			(xy 51.321716 -286.704532) (xy 51.32959 -286.692848) (xy 51.331114 -286.664908) (xy 51.282092 -286.573214)
			(xy 51.277424 -286.565328) (xy 51.26366 -286.55325) (xy 51.246541 -286.546749) (xy 51.237388 -286.54629)
			(xy 50.96256 -286.54629) (xy 50.953383 -286.546659) (xy 50.936205 -286.55312) (xy 50.92244 -286.565258)
			(xy 50.917856 -286.573214) (xy 50.868834 -286.664908) (xy 50.870358 -286.692848) (xy 50.878232 -286.704532)
			(xy 50.890525 -286.72352) (xy 50.909976 -286.764355) (xy 50.923187 -286.807615) (xy 50.929868 -286.85235)
			(xy 50.930302 -286.874966) (xy 50.92978 -286.900221) (xy 50.921467 -286.950043) (xy 50.905066 -286.997817)
			(xy 50.881025 -287.04224) (xy 50.850001 -287.0821) (xy 50.812839 -287.11631) (xy 50.770553 -287.143936)
			(xy 50.724297 -287.164226) (xy 50.675332 -287.176626) (xy 50.624994 -287.180797) (xy 50.574656 -287.176626)
			(xy 50.525691 -287.164226) (xy 50.479435 -287.143936) (xy 50.437149 -287.11631) (xy 50.399987 -287.0821)
			(xy 50.368963 -287.04224) (xy 50.344922 -286.997817) (xy 50.328521 -286.950043) (xy 50.320208 -286.900221)
			(xy 50.319686 -286.874966) (xy 50.320092 -286.852348) (xy 50.326766 -286.807606) (xy 50.339977 -286.764342)
			(xy 50.359435 -286.723504) (xy 50.371756 -286.704532) (xy 50.37963 -286.692848) (xy 50.381154 -286.664908)
			(xy 50.332132 -286.573214) (xy 50.327466 -286.565324) (xy 50.313704 -286.553235) (xy 50.296584 -286.546721)
			(xy 50.287428 -286.54629) (xy 50.012346 -286.54629) (xy 50.00317 -286.546662) (xy 49.985996 -286.553125)
			(xy 49.972236 -286.565264) (xy 49.967642 -286.573214) (xy 49.91862 -286.664908) (xy 49.920144 -286.692848)
			(xy 49.928018 -286.704532) (xy 49.940311 -286.723519) (xy 49.959763 -286.764355) (xy 49.972975 -286.807614)
			(xy 49.979656 -286.85235) (xy 49.980088 -286.874966) (xy 49.979566 -286.900221) (xy 49.971253 -286.950043)
			(xy 49.954852 -286.997817) (xy 49.930811 -287.04224) (xy 49.899787 -287.0821) (xy 49.862625 -287.11631)
			(xy 49.820339 -287.143936) (xy 49.774083 -287.164226) (xy 49.725118 -287.176626) (xy 49.67478 -287.180797)
			(xy 49.624442 -287.176626) (xy 49.575477 -287.164226) (xy 49.529221 -287.143936) (xy 49.486935 -287.11631)
			(xy 49.449773 -287.0821) (xy 49.418749 -287.04224) (xy 49.394708 -286.997817) (xy 49.378307 -286.950043)
			(xy 49.369994 -286.900221) (xy 49.369472 -286.874966) (xy 49.369879 -286.852348) (xy 49.376554 -286.807607)
			(xy 49.389768 -286.764345) (xy 49.40923 -286.72351) (xy 49.421542 -286.704532) (xy 49.429416 -286.692848)
			(xy 49.43094 -286.664908) (xy 49.381918 -286.573214) (xy 49.377251 -286.565326) (xy 49.363489 -286.553241)
			(xy 49.346369 -286.546731) (xy 49.337214 -286.54629) (xy 49.062386 -286.54629) (xy 49.053216 -286.546671)
			(xy 49.036059 -286.553148) (xy 49.022315 -286.56529) (xy 49.017682 -286.573214) (xy 48.96866 -286.664908)
			(xy 48.970184 -286.692848) (xy 48.978058 -286.704532) (xy 48.99035 -286.72352) (xy 49.009799 -286.764356)
			(xy 49.023009 -286.807615) (xy 49.02969 -286.85235) (xy 49.030128 -286.874966) (xy 49.029606 -286.900221)
			(xy 49.021293 -286.950043) (xy 49.004892 -286.997817) (xy 48.980851 -287.04224) (xy 48.949827 -287.0821)
			(xy 48.912665 -287.11631) (xy 48.870379 -287.143936) (xy 48.824123 -287.164226) (xy 48.775158 -287.176626)
			(xy 48.72482 -287.180797) (xy 48.674482 -287.176626) (xy 48.625517 -287.164226) (xy 48.579261 -287.143936)
			(xy 48.536975 -287.11631) (xy 48.499813 -287.0821) (xy 48.468789 -287.04224) (xy 48.444748 -286.997817)
			(xy 48.428347 -286.950043) (xy 48.420034 -286.900221) (xy 48.419512 -286.874966) (xy 48.419919 -286.852348)
			(xy 48.426593 -286.807606) (xy 48.439805 -286.764342) (xy 48.459264 -286.723505) (xy 48.471582 -286.704532)
			(xy 48.479456 -286.692848) (xy 48.48098 -286.664908) (xy 48.431958 -286.573214) (xy 48.427293 -286.565321)
			(xy 48.413533 -286.553225) (xy 48.396412 -286.546703) (xy 48.387254 -286.54629) (xy 48.112426 -286.54629)
			(xy 48.103252 -286.546665) (xy 48.086084 -286.553133) (xy 48.072329 -286.565273) (xy 48.067722 -286.573214)
			(xy 48.0187 -286.664908) (xy 48.020224 -286.692848) (xy 48.028098 -286.704532) (xy 48.040392 -286.723519)
			(xy 48.059845 -286.764354) (xy 48.073058 -286.807614) (xy 48.07974 -286.85235) (xy 48.080168 -286.874966)
			(xy 48.079646 -286.900221) (xy 48.071333 -286.950043) (xy 48.054932 -286.997817) (xy 48.030891 -287.04224)
			(xy 47.999867 -287.0821) (xy 47.962705 -287.11631) (xy 47.920419 -287.143936) (xy 47.874163 -287.164226)
			(xy 47.825198 -287.176626) (xy 47.77486 -287.180797) (xy 47.724522 -287.176626) (xy 47.675557 -287.164226)
			(xy 47.629301 -287.143936) (xy 47.587015 -287.11631) (xy 47.549853 -287.0821) (xy 47.518829 -287.04224)
			(xy 47.494788 -286.997817) (xy 47.478387 -286.950043) (xy 47.470074 -286.900221) (xy 47.469552 -286.874966)
			(xy 47.469959 -286.852348) (xy 47.476634 -286.807607) (xy 47.489847 -286.764344) (xy 47.509308 -286.723508)
			(xy 47.521622 -286.704532) (xy 47.529496 -286.692848) (xy 47.53102 -286.664908) (xy 47.481998 -286.573214)
			(xy 47.477331 -286.565328) (xy 47.463567 -286.553248) (xy 47.446448 -286.546745) (xy 47.437294 -286.54629)
			(xy 47.162466 -286.54629) (xy 47.153298 -286.546675) (xy 47.136146 -286.553156) (xy 47.122408 -286.565299)
			(xy 47.117762 -286.573214) (xy 47.06874 -286.664908) (xy 47.070264 -286.692848) (xy 47.078138 -286.704532)
			(xy 47.090431 -286.72352) (xy 47.109881 -286.764356) (xy 47.123092 -286.807615) (xy 47.129773 -286.85235)
			(xy 47.130208 -286.874966) (xy 47.129686 -286.900221) (xy 47.121373 -286.950043) (xy 47.104972 -286.997817)
			(xy 47.080931 -287.04224) (xy 47.049907 -287.0821) (xy 47.012745 -287.11631) (xy 46.970459 -287.143936)
			(xy 46.924203 -287.164226) (xy 46.875238 -287.176626) (xy 46.8249 -287.180797) (xy 46.774562 -287.176626)
			(xy 46.725597 -287.164226) (xy 46.679341 -287.143936) (xy 46.637055 -287.11631) (xy 46.599893 -287.0821)
			(xy 46.568869 -287.04224) (xy 46.544828 -286.997817) (xy 46.528427 -286.950043) (xy 46.520114 -286.900221)
			(xy 46.519592 -286.874966) (xy 46.520009 -286.852181) (xy 46.52677 -286.807115) (xy 46.540153 -286.763554)
			(xy 46.55986 -286.722465) (xy 46.585453 -286.684761) (xy 46.616365 -286.651278) (xy 46.633892 -286.636714)
			(xy 46.643036 -286.629348) (xy 46.652942 -286.608774) (xy 46.652942 -286.59709) (xy 46.652453 -286.587081)
			(xy 46.644793 -286.568585) (xy 46.630642 -286.554425) (xy 46.612151 -286.546753) (xy 46.602142 -286.54629)
			(xy 46.571662 -286.54629) (xy 46.525688 -286.517334) (xy 46.176438 -286.517334) (xy 46.1518 -286.532828)
			(xy 46.14545 -286.54629) (xy 46.105826 -286.62884) (xy 46.102811 -286.63566) (xy 46.100475 -286.650381)
			(xy 46.101254 -286.657796) (xy 46.101508 -286.65805) (xy 46.102664 -286.664818) (xy 46.10808 -286.67743)
			(xy 46.112176 -286.682942) (xy 46.128131 -286.703456) (xy 46.153539 -286.748786) (xy 46.170894 -286.797768)
			(xy 46.179693 -286.848983) (xy 46.180248 -286.874966) (xy 46.179726 -286.900221) (xy 46.171413 -286.950043)
			(xy 46.155012 -286.997817) (xy 46.130971 -287.04224) (xy 46.099947 -287.0821) (xy 46.062785 -287.11631)
			(xy 46.020499 -287.143936) (xy 45.974243 -287.164226) (xy 45.925278 -287.176626) (xy 45.87494 -287.180797)
			(xy 45.824602 -287.176626) (xy 45.775637 -287.164226) (xy 45.729381 -287.143936) (xy 45.687095 -287.11631)
			(xy 45.649933 -287.0821) (xy 45.618909 -287.04224) (xy 45.594868 -286.997817) (xy 45.578467 -286.950043)
			(xy 45.570154 -286.900221) (xy 45.569632 -286.874966) (xy 45.570211 -286.848988) (xy 45.579045 -286.797787)
			(xy 45.596403 -286.748815) (xy 45.621785 -286.703479) (xy 45.637704 -286.682942) (xy 45.641825 -286.677445)
			(xy 45.647239 -286.664825) (xy 45.648372 -286.65805) (xy 45.648626 -286.657796) (xy 45.64938 -286.650379)
			(xy 45.647065 -286.635659) (xy 45.644054 -286.62884) (xy 45.60443 -286.54629) (xy 45.59808 -286.532828)
			(xy 45.573442 -286.517334) (xy 45.226478 -286.517334) (xy 45.20184 -286.532828) (xy 45.19549 -286.54629)
			(xy 45.155866 -286.62884) (xy 45.152849 -286.63566) (xy 45.150511 -286.650381) (xy 45.151294 -286.657796)
			(xy 45.151548 -286.65805) (xy 45.152702 -286.664819) (xy 45.158113 -286.677435) (xy 45.162216 -286.682942)
			(xy 45.178174 -286.703455) (xy 45.203587 -286.748784) (xy 45.220945 -286.797766) (xy 45.229746 -286.848982)
			(xy 45.230288 -286.874966) (xy 45.229766 -286.900221) (xy 45.221453 -286.950043) (xy 45.205052 -286.997817)
			(xy 45.181011 -287.04224) (xy 45.149987 -287.0821) (xy 45.112825 -287.11631) (xy 45.070539 -287.143936)
			(xy 45.024283 -287.164226) (xy 44.975318 -287.176626) (xy 44.92498 -287.180797) (xy 44.874642 -287.176626)
			(xy 44.825677 -287.164226) (xy 44.779421 -287.143936) (xy 44.737135 -287.11631) (xy 44.699973 -287.0821)
			(xy 44.668949 -287.04224) (xy 44.644908 -286.997817) (xy 44.628507 -286.950043) (xy 44.620194 -286.900221)
			(xy 44.619672 -286.874966) (xy 44.620251 -286.848988) (xy 44.629086 -286.797788) (xy 44.646446 -286.748817)
			(xy 44.67183 -286.703483) (xy 44.687744 -286.682942) (xy 44.691862 -286.677444) (xy 44.697272 -286.664824)
			(xy 44.698412 -286.65805) (xy 44.698666 -286.657796) (xy 44.699419 -286.650379) (xy 44.697107 -286.635658)
			(xy 44.694094 -286.62884) (xy 44.65447 -286.54629) (xy 44.64812 -286.532828) (xy 44.623482 -286.517334)
			(xy 44.29125 -286.517334) (xy 44.27728 -286.519366) (xy 44.277026 -286.519366) (xy 44.26679 -286.522803)
			(xy 44.250337 -286.536753) (xy 44.245276 -286.54629) (xy 44.205906 -286.62884) (xy 44.203033 -286.635498)
			(xy 44.200726 -286.649807) (xy 44.201334 -286.657034) (xy 44.20244 -286.663935) (xy 44.207843 -286.676818)
			(xy 44.212002 -286.682434) (xy 44.212256 -286.682942) (xy 44.21251 -286.682942) (xy 44.228341 -286.703478)
			(xy 44.253573 -286.748773) (xy 44.270795 -286.797677) (xy 44.279513 -286.848787) (xy 44.280074 -286.874712)
			(xy 44.280074 -286.882332) (xy 44.278965 -286.907175) (xy 44.269688 -286.956027) (xy 44.252619 -287.002731)
			(xy 44.228209 -287.046053) (xy 44.197103 -287.084848) (xy 44.160123 -287.118092) (xy 44.118246 -287.144905)
			(xy 44.072579 -287.16458) (xy 44.024327 -287.176597) (xy 43.974766 -287.180639) (xy 43.925205 -287.176597)
			(xy 43.876953 -287.16458) (xy 43.831286 -287.144905) (xy 43.789409 -287.118092) (xy 43.752429 -287.084848)
			(xy 43.721323 -287.046053) (xy 43.696913 -287.002731) (xy 43.679844 -286.956027) (xy 43.670567 -286.907175)
			(xy 43.669458 -286.882332) (xy 43.669458 -286.874712) (xy 43.66995 -286.848781) (xy 43.678663 -286.797659)
			(xy 43.695892 -286.748744) (xy 43.72114 -286.703445) (xy 43.737022 -286.682942) (xy 43.737276 -286.682942)
			(xy 43.73753 -286.682434) (xy 43.741714 -286.676832) (xy 43.747125 -286.663944) (xy 43.748198 -286.657034)
			(xy 43.748874 -286.649807) (xy 43.746545 -286.635486) (xy 43.743626 -286.62884) (xy 43.704256 -286.54629)
			(xy 43.699782 -286.537787) (xy 43.685756 -286.524678) (xy 43.667883 -286.517671) (xy 43.658282 -286.517334)
			(xy 43.34129 -286.517334) (xy 43.32732 -286.519366) (xy 43.327066 -286.519366) (xy 43.316838 -286.522812)
			(xy 43.300403 -286.53677) (xy 43.295316 -286.54629) (xy 43.255946 -286.62884) (xy 43.253076 -286.635499)
			(xy 43.250772 -286.649807) (xy 43.251374 -286.657034) (xy 43.252481 -286.663934) (xy 43.257887 -286.676815)
			(xy 43.262042 -286.682434) (xy 43.262296 -286.682942) (xy 43.26255 -286.682942) (xy 43.278379 -286.703479)
			(xy 43.303608 -286.748774) (xy 43.320827 -286.797679) (xy 43.329544 -286.848788) (xy 43.330114 -286.874712)
			(xy 43.330114 -286.882332) (xy 43.329005 -286.907175) (xy 43.319728 -286.956027) (xy 43.302659 -287.002731)
			(xy 43.278249 -287.046053) (xy 43.247143 -287.084848) (xy 43.210163 -287.118092) (xy 43.168286 -287.144905)
			(xy 43.122619 -287.16458) (xy 43.074367 -287.176597) (xy 43.024806 -287.180639) (xy 42.975245 -287.176597)
			(xy 42.926993 -287.16458) (xy 42.881326 -287.144905) (xy 42.839449 -287.118092) (xy 42.802469 -287.084848)
			(xy 42.771363 -287.046053) (xy 42.746953 -287.002731) (xy 42.729884 -286.956027) (xy 42.720607 -286.907175)
			(xy 42.719498 -286.882332) (xy 42.719498 -286.874712) (xy 42.719991 -286.848782) (xy 42.728705 -286.79766)
			(xy 42.745935 -286.748746) (xy 42.771185 -286.703449) (xy 42.787062 -286.682942) (xy 42.787316 -286.682942)
			(xy 42.78757 -286.682434) (xy 42.791758 -286.676834) (xy 42.797176 -286.663946) (xy 42.798238 -286.657034)
			(xy 42.798914 -286.649807) (xy 42.796587 -286.635485) (xy 42.793666 -286.62884) (xy 42.754296 -286.54629)
			(xy 42.749819 -286.537794) (xy 42.73579 -286.524702) (xy 42.717919 -286.517715) (xy 42.708322 -286.517334)
			(xy 42.376344 -286.517334) (xy 42.351706 -286.532828) (xy 42.345356 -286.54629) (xy 42.305732 -286.62884)
			(xy 42.302716 -286.63566) (xy 42.30038 -286.650381) (xy 42.30116 -286.657796) (xy 42.301414 -286.65805)
			(xy 42.30257 -286.664818) (xy 42.307987 -286.67743) (xy 42.312082 -286.682942) (xy 42.328036 -286.703456)
			(xy 42.353444 -286.748787) (xy 42.370799 -286.797768) (xy 42.379598 -286.848983) (xy 42.380154 -286.874966)
			(xy 42.379632 -286.900221) (xy 42.371319 -286.950043) (xy 42.354918 -286.997817) (xy 42.330877 -287.04224)
			(xy 42.299853 -287.0821) (xy 42.262691 -287.11631) (xy 42.220405 -287.143936) (xy 42.174149 -287.164226)
			(xy 42.125184 -287.176626) (xy 42.074846 -287.180797) (xy 42.024508 -287.176626) (xy 41.975543 -287.164226)
			(xy 41.929287 -287.143936) (xy 41.887001 -287.11631) (xy 41.849839 -287.0821) (xy 41.818815 -287.04224)
			(xy 41.794774 -286.997817) (xy 41.778373 -286.950043) (xy 41.77006 -286.900221) (xy 41.769538 -286.874966)
			(xy 41.770172 -286.846919) (xy 41.780429 -286.79177) (xy 41.800609 -286.739431) (xy 41.81475 -286.7152)
			(xy 41.823894 -286.69996) (xy 41.81983 -286.665162) (xy 41.334436 -286.179768) (xy 41.299638 -286.175704)
			(xy 41.284652 -286.185102) (xy 41.260416 -286.199206) (xy 41.208061 -286.219272) (xy 41.152921 -286.229438)
			(xy 41.124886 -286.23006) (xy 41.100895 -286.229613) (xy 41.053504 -286.222104) (xy 41.007871 -286.207274)
			(xy 40.965121 -286.185487) (xy 40.926305 -286.15728) (xy 40.89238 -286.123348) (xy 40.864181 -286.084527)
			(xy 40.842403 -286.041771) (xy 40.827582 -285.996136) (xy 40.820082 -285.948743) (xy 40.819578 -285.924752)
			(xy 40.820186 -285.896716) (xy 40.830363 -285.841577) (xy 40.850421 -285.789216) (xy 40.864536 -285.764986)
			(xy 40.873934 -285.75) (xy 40.86987 -285.715202) (xy 40.384476 -285.229808) (xy 40.349678 -285.225744)
			(xy 40.334692 -285.235142) (xy 40.310457 -285.249252) (xy 40.258103 -285.269328) (xy 40.202963 -285.279504)
			(xy 40.174926 -285.2801) (xy 40.149668 -285.279609) (xy 40.099839 -285.271298) (xy 40.052058 -285.254899)
			(xy 40.007629 -285.230858) (xy 39.967762 -285.199832) (xy 39.933547 -285.162667) (xy 39.905915 -285.120377)
			(xy 39.885622 -285.074115) (xy 39.87322 -285.025144) (xy 39.869048 -284.9748) (xy 39.87322 -284.924456)
			(xy 39.885622 -284.875485) (xy 39.905915 -284.829223) (xy 39.933547 -284.786933) (xy 39.967762 -284.749768)
			(xy 40.007629 -284.718742) (xy 40.052058 -284.694701) (xy 40.099839 -284.678302) (xy 40.149668 -284.669991)
			(xy 40.174926 -284.669484) (xy 40.18915 -284.669738) (xy 40.199564 -284.670246) (xy 40.218868 -284.663134)
			(xy 40.279574 -284.604968) (xy 40.28669 -284.597542) (xy 40.294808 -284.578665) (xy 40.295322 -284.568392)
			(xy 40.295322 -284.431232) (xy 40.294805 -284.420961) (xy 40.286686 -284.402084) (xy 40.279574 -284.394656)
			(xy 40.218868 -284.33649) (xy 40.199564 -284.329378) (xy 40.18915 -284.329886) (xy 40.174926 -284.33014)
			(xy 40.149664 -284.329649) (xy 40.099829 -284.321337) (xy 40.052042 -284.304935) (xy 40.007607 -284.280892)
			(xy 39.967735 -284.249861) (xy 39.933515 -284.212691) (xy 39.90588 -284.170396) (xy 39.885584 -284.124128)
			(xy 39.87318 -284.075151) (xy 39.869008 -284.0248) (xy 39.87318 -283.974449) (xy 39.885584 -283.925472)
			(xy 39.90588 -283.879204) (xy 39.933515 -283.836909) (xy 39.967735 -283.799739) (xy 40.007607 -283.768708)
			(xy 40.052042 -283.744665) (xy 40.099829 -283.728263) (xy 40.149664 -283.719951) (xy 40.174926 -283.719524)
			(xy 40.18915 -283.719778) (xy 40.199564 -283.720286) (xy 40.218868 -283.713174) (xy 40.279574 -283.655008)
			(xy 40.286696 -283.647584) (xy 40.294829 -283.628708) (xy 40.295322 -283.618432) (xy 40.295322 -283.481272)
			(xy 40.294794 -283.471006) (xy 40.286659 -283.452146) (xy 40.279574 -283.444696) (xy 40.218868 -283.38653)
			(xy 40.199564 -283.379418) (xy 40.18915 -283.379926) (xy 40.174926 -283.38018) (xy 40.149669 -283.379689)
			(xy 40.099844 -283.371379) (xy 40.052066 -283.35498) (xy 40.00764 -283.330941) (xy 39.967776 -283.299917)
			(xy 39.933562 -283.262755) (xy 39.905933 -283.220467) (xy 39.885641 -283.174209) (xy 39.87324 -283.125241)
			(xy 39.869068 -283.0749) (xy 39.87324 -283.024559) (xy 39.885641 -282.975591) (xy 39.905933 -282.929333)
			(xy 39.933562 -282.887045) (xy 39.967776 -282.849883) (xy 40.00764 -282.818859) (xy 40.052066 -282.79482)
			(xy 40.099844 -282.778421) (xy 40.149669 -282.770111) (xy 40.174926 -282.769564) (xy 40.18915 -282.769818)
			(xy 40.199564 -282.770326) (xy 40.218868 -282.763214) (xy 40.279574 -282.705048) (xy 40.286687 -282.697621)
			(xy 40.294797 -282.678744) (xy 40.295322 -282.668472) (xy 40.295322 -282.531312) (xy 40.294801 -282.521042)
			(xy 40.286677 -282.502172) (xy 40.279574 -282.494736) (xy 40.218868 -282.43657) (xy 40.199564 -282.429458)
			(xy 40.18915 -282.429966) (xy 40.174926 -282.43022) (xy 40.149666 -282.429729) (xy 40.099834 -282.421418)
			(xy 40.05205 -282.405017) (xy 40.007618 -282.380975) (xy 39.967749 -282.349947) (xy 39.933531 -282.312779)
			(xy 39.905898 -282.270486) (xy 39.885603 -282.224222) (xy 39.8732 -282.175248) (xy 39.869028 -282.1249)
			(xy 39.8732 -282.074552) (xy 39.885603 -282.025578) (xy 39.905898 -281.979314) (xy 39.933531 -281.937021)
			(xy 39.967749 -281.899853) (xy 40.007618 -281.868825) (xy 40.05205 -281.844783) (xy 40.099834 -281.828382)
			(xy 40.149666 -281.820071) (xy 40.174926 -281.819604) (xy 40.18915 -281.819858) (xy 40.199564 -281.820366)
			(xy 40.218868 -281.813254) (xy 40.279574 -281.755088) (xy 40.286693 -281.747663) (xy 40.294819 -281.728786)
			(xy 40.295322 -281.718512) (xy 40.295322 -281.581352) (xy 40.29479 -281.571087) (xy 40.28665 -281.552233)
			(xy 40.279574 -281.544776) (xy 40.218868 -281.48661) (xy 40.199564 -281.479498) (xy 40.18915 -281.480006)
			(xy 40.174926 -281.48026) (xy 40.149671 -281.47977) (xy 40.099849 -281.47146) (xy 40.052074 -281.455062)
			(xy 40.00765 -281.431025) (xy 39.967789 -281.400002) (xy 39.933578 -281.362842) (xy 39.90595 -281.320558)
			(xy 39.88566 -281.274302) (xy 39.873259 -281.225338) (xy 39.869088 -281.175) (xy 39.873259 -281.124662)
			(xy 39.88566 -281.075698) (xy 39.90595 -281.029442) (xy 39.933578 -280.987158) (xy 39.967789 -280.949998)
			(xy 40.00765 -280.918975) (xy 40.052074 -280.894938) (xy 40.099849 -280.87854) (xy 40.149671 -280.87023)
			(xy 40.174926 -280.869644) (xy 40.18915 -280.869898) (xy 40.199564 -280.870406) (xy 40.218868 -280.863294)
			(xy 40.279574 -280.805128) (xy 40.286684 -280.7977) (xy 40.294787 -280.778823) (xy 40.295322 -280.768552)
			(xy 40.295322 -280.631138) (xy 40.294806 -280.620866) (xy 40.286688 -280.601988) (xy 40.279574 -280.594562)
			(xy 40.218868 -280.536396) (xy 40.199564 -280.529284) (xy 40.18915 -280.529792) (xy 40.174926 -280.530046)
			(xy 40.149664 -280.529555) (xy 40.099828 -280.521243) (xy 40.05204 -280.504841) (xy 40.007603 -280.480797)
			(xy 39.967731 -280.449766) (xy 39.93351 -280.412595) (xy 39.905875 -280.370299) (xy 39.885578 -280.32403)
			(xy 39.873174 -280.275052) (xy 39.869002 -280.2247) (xy 39.873175 -280.174348) (xy 39.885578 -280.12537)
			(xy 39.905875 -280.079101) (xy 39.93351 -280.036805) (xy 39.967731 -279.999634) (xy 40.007603 -279.968603)
			(xy 40.05204 -279.944559) (xy 40.099828 -279.928157) (xy 40.149664 -279.919845) (xy 40.174926 -279.91943)
			(xy 40.18915 -279.919684) (xy 40.199564 -279.920192) (xy 40.218868 -279.91308) (xy 40.279574 -279.854914)
			(xy 40.286697 -279.84749) (xy 40.294832 -279.828614) (xy 40.295322 -279.818338) (xy 40.295322 -279.681178)
			(xy 40.294795 -279.670911) (xy 40.286662 -279.65205) (xy 40.279574 -279.644602) (xy 40.218868 -279.586436)
			(xy 40.199564 -279.579324) (xy 40.18915 -279.579832) (xy 40.174926 -279.580086) (xy 40.149669 -279.579595)
			(xy 40.099842 -279.571285) (xy 40.052064 -279.554886) (xy 40.007636 -279.530846) (xy 39.967772 -279.499822)
			(xy 39.933558 -279.462658) (xy 39.905927 -279.42037) (xy 39.885635 -279.374111) (xy 39.873234 -279.325142)
			(xy 39.869062 -279.2748) (xy 39.873234 -279.224458) (xy 39.885635 -279.175489) (xy 39.905927 -279.12923)
			(xy 39.933558 -279.086942) (xy 39.967772 -279.049778) (xy 40.007636 -279.018754) (xy 40.052064 -278.994714)
			(xy 40.099842 -278.978315) (xy 40.149669 -278.970005) (xy 40.174926 -278.96947) (xy 40.18915 -278.969724)
			(xy 40.199564 -278.970232) (xy 40.218868 -278.96312) (xy 40.279574 -278.904954) (xy 40.286688 -278.897527)
			(xy 40.294801 -278.87865) (xy 40.295322 -278.868378) (xy 40.295322 -278.731218) (xy 40.294802 -278.720948)
			(xy 40.286679 -278.702076) (xy 40.279574 -278.694642) (xy 40.218868 -278.636476) (xy 40.199564 -278.629364)
			(xy 40.18915 -278.629872) (xy 40.174926 -278.630126) (xy 40.149665 -278.629635) (xy 40.099833 -278.621324)
			(xy 40.052048 -278.604923) (xy 40.007614 -278.58088) (xy 39.967745 -278.549851) (xy 39.933526 -278.512683)
			(xy 39.905892 -278.470389) (xy 39.885597 -278.424124) (xy 39.873194 -278.375149) (xy 39.869022 -278.3248)
			(xy 39.873194 -278.274451) (xy 39.885597 -278.225476) (xy 39.905892 -278.179211) (xy 39.933526 -278.136917)
			(xy 39.967745 -278.099749) (xy 40.007614 -278.06872) (xy 40.052048 -278.044677) (xy 40.099833 -278.028276)
			(xy 40.149665 -278.019965) (xy 40.174926 -278.01951) (xy 40.18915 -278.019764) (xy 40.199564 -278.020272)
			(xy 40.218868 -278.01316) (xy 40.279574 -277.954994) (xy 40.286694 -277.947569) (xy 40.294822 -277.928693)
			(xy 40.295322 -277.918418) (xy 40.295322 -277.781258) (xy 40.294791 -277.770993) (xy 40.286653 -277.752137)
			(xy 40.279574 -277.744682) (xy 40.218868 -277.686516) (xy 40.199564 -277.679404) (xy 40.18915 -277.679912)
			(xy 40.174926 -277.680166) (xy 40.14967 -277.679676) (xy 40.099847 -277.671365) (xy 40.052072 -277.654968)
			(xy 40.007647 -277.63093) (xy 39.967785 -277.599907) (xy 39.933573 -277.562746) (xy 39.905945 -277.520461)
			(xy 39.885654 -277.474204) (xy 39.873253 -277.425239) (xy 39.869082 -277.3749) (xy 39.873253 -277.324561)
			(xy 39.885654 -277.275596) (xy 39.905945 -277.229339) (xy 39.933573 -277.187054) (xy 39.967785 -277.149893)
			(xy 40.007647 -277.11887) (xy 40.052072 -277.094832) (xy 40.099847 -277.078435) (xy 40.14967 -277.070124)
			(xy 40.174926 -277.06955) (xy 40.18915 -277.069804) (xy 40.199564 -277.070312) (xy 40.218868 -277.0632)
			(xy 40.279574 -277.005034) (xy 40.286685 -276.997606) (xy 40.29479 -276.978729) (xy 40.295322 -276.968458)
			(xy 40.295322 -276.831298) (xy 40.294798 -276.821029) (xy 40.286671 -276.802163) (xy 40.279574 -276.794722)
			(xy 40.218868 -276.736556) (xy 40.199564 -276.729444) (xy 40.18915 -276.729952) (xy 40.174926 -276.730206)
			(xy 40.149667 -276.729715) (xy 40.099838 -276.721404) (xy 40.052056 -276.705004) (xy 40.007625 -276.680963)
			(xy 39.967758 -276.649936) (xy 39.933542 -276.612771) (xy 39.90591 -276.57048) (xy 39.885616 -276.524217)
			(xy 39.873214 -276.475245) (xy 39.869042 -276.4249) (xy 39.873214 -276.374555) (xy 39.885616 -276.325583)
			(xy 39.90591 -276.27932) (xy 39.933542 -276.237029) (xy 39.967758 -276.199864) (xy 40.007625 -276.168837)
			(xy 40.052056 -276.144796) (xy 40.099838 -276.128396) (xy 40.149667 -276.120085) (xy 40.174926 -276.11959)
			(xy 40.18915 -276.119844) (xy 40.199564 -276.120352) (xy 40.218868 -276.11324) (xy 40.279574 -276.055074)
			(xy 40.286691 -276.047648) (xy 40.294812 -276.028772) (xy 40.295322 -276.018498) (xy 40.295322 -275.881338)
			(xy 40.294806 -275.871066) (xy 40.286688 -275.852188) (xy 40.279574 -275.844762) (xy 40.218868 -275.786596)
			(xy 40.199564 -275.779484) (xy 40.18915 -275.779992) (xy 40.174926 -275.780246) (xy 40.149664 -275.779755)
			(xy 40.099828 -275.771443) (xy 40.05204 -275.755041) (xy 40.007603 -275.730997) (xy 39.967731 -275.699966)
			(xy 39.93351 -275.662795) (xy 39.905875 -275.620499) (xy 39.885578 -275.57423) (xy 39.873174 -275.525252)
			(xy 39.869002 -275.4749) (xy 39.873175 -275.424548) (xy 39.885578 -275.37557) (xy 39.905875 -275.329301)
			(xy 39.93351 -275.287005) (xy 39.967731 -275.249834) (xy 40.007603 -275.218803) (xy 40.05204 -275.194759)
			(xy 40.099828 -275.178357) (xy 40.149664 -275.170045) (xy 40.174926 -275.16963) (xy 40.18915 -275.169884)
			(xy 40.199564 -275.170392) (xy 40.218868 -275.16328) (xy 40.279574 -275.105114) (xy 40.286697 -275.09769)
			(xy 40.294832 -275.078814) (xy 40.295322 -275.068538) (xy 40.295322 -274.931378) (xy 40.294795 -274.921111)
			(xy 40.286662 -274.90225) (xy 40.279574 -274.894802) (xy 40.218868 -274.836636) (xy 40.199564 -274.829524)
			(xy 40.18915 -274.830032) (xy 40.174926 -274.830286) (xy 40.149669 -274.829795) (xy 40.099842 -274.821485)
			(xy 40.052064 -274.805086) (xy 40.007636 -274.781046) (xy 39.967772 -274.750022) (xy 39.933558 -274.712858)
			(xy 39.905927 -274.67057) (xy 39.885635 -274.624311) (xy 39.873234 -274.575342) (xy 39.869062 -274.525)
			(xy 39.873234 -274.474658) (xy 39.885635 -274.425689) (xy 39.905927 -274.37943) (xy 39.933558 -274.337142)
			(xy 39.967772 -274.299978) (xy 40.007636 -274.268954) (xy 40.052064 -274.244914) (xy 40.099842 -274.228515)
			(xy 40.149669 -274.220205) (xy 40.174926 -274.21967) (xy 40.18915 -274.219924) (xy 40.199564 -274.220432)
			(xy 40.218868 -274.21332) (xy 40.279574 -274.155154) (xy 40.286688 -274.147727) (xy 40.294801 -274.12885)
			(xy 40.295322 -274.118578) (xy 40.295322 -273.981164) (xy 40.294792 -273.970898) (xy 40.286656 -273.952041)
			(xy 40.279574 -273.944588) (xy 40.218868 -273.886422) (xy 40.199564 -273.87931) (xy 40.18915 -273.879818)
			(xy 40.174926 -273.880072) (xy 40.14967 -273.879581) (xy 40.099846 -273.871271) (xy 40.052069 -273.854873)
			(xy 40.007644 -273.830835) (xy 39.967781 -273.799811) (xy 39.933569 -273.76265) (xy 39.90594 -273.720363)
			(xy 39.885648 -273.674106) (xy 39.873247 -273.62514) (xy 39.869076 -273.5748) (xy 39.873247 -273.52446)
			(xy 39.885648 -273.475494) (xy 39.90594 -273.429237) (xy 39.933569 -273.38695) (xy 39.967781 -273.349789)
			(xy 40.007644 -273.318765) (xy 40.052069 -273.294727) (xy 40.099846 -273.278329) (xy 40.14967 -273.270019)
			(xy 40.174926 -273.269456) (xy 40.18915 -273.26971) (xy 40.199564 -273.270218) (xy 40.218868 -273.263106)
			(xy 40.279574 -273.20494) (xy 40.286686 -273.197512) (xy 40.294793 -273.178636) (xy 40.295322 -273.168364)
			(xy 40.295322 -273.031204) (xy 40.2948 -273.020935) (xy 40.286673 -273.002067) (xy 40.279574 -272.994628)
			(xy 40.218868 -272.936462) (xy 40.199564 -272.92935) (xy 40.18915 -272.929858) (xy 40.174926 -272.930112)
			(xy 40.149667 -272.929621) (xy 40.099836 -272.92131) (xy 40.052053 -272.90491) (xy 40.007622 -272.880868)
			(xy 39.967754 -272.849841) (xy 39.933537 -272.812674) (xy 39.905905 -272.770382) (xy 39.88561 -272.724119)
			(xy 39.873208 -272.675146) (xy 39.869036 -272.6248) (xy 39.873208 -272.574454) (xy 39.88561 -272.525481)
			(xy 39.905905 -272.479218) (xy 39.933537 -272.436926) (xy 39.967754 -272.399759) (xy 40.007622 -272.368732)
			(xy 40.052053 -272.34469) (xy 40.099836 -272.32829) (xy 40.149667 -272.319979) (xy 40.174926 -272.319496)
			(xy 40.18915 -272.31975) (xy 40.199564 -272.320258) (xy 40.218868 -272.313146) (xy 40.279574 -272.25498)
			(xy 40.286692 -272.247555) (xy 40.294815 -272.228678) (xy 40.295322 -272.218404) (xy 40.295322 -271.035018)
			(xy 40.28059 -271.010888) (xy 40.26789 -271.004284) (xy 40.24349 -270.991015) (xy 40.198466 -270.958495)
			(xy 40.158629 -270.919794) (xy 40.124822 -270.875728) (xy 40.097757 -270.827228) (xy 40.078006 -270.775319)
			(xy 40.065986 -270.721094) (xy 40.061951 -270.665701) (xy 40.065986 -270.610307) (xy 40.078005 -270.556083)
			(xy 40.097756 -270.504173) (xy 40.124821 -270.455673) (xy 40.158628 -270.411608) (xy 40.198464 -270.372906)
			(xy 40.243488 -270.340386) (xy 40.26789 -270.32712) (xy 40.28059 -270.320516) (xy 40.295322 -270.296386)
			(xy 40.295322 -253.704852) (xy 40.295034 -253.697066) (xy 40.290375 -253.682206) (xy 40.286178 -253.675642)
			(xy 40.269854 -253.651418) (xy 40.243965 -253.599058) (xy 40.226346 -253.543368) (xy 40.217406 -253.485645)
			(xy 40.216836 -253.45644) (xy 40.217357 -253.427229) (xy 40.22626 -253.369489) (xy 40.243877 -253.313787)
			(xy 40.269797 -253.261429) (xy 40.286178 -253.237238) (xy 40.29043 -253.230699) (xy 40.295088 -253.215824)
			(xy 40.295322 -253.208028) (xy 40.295322 -251.406914) (xy 40.295043 -251.399125) (xy 40.290399 -251.384255)
			(xy 40.286178 -251.377704) (xy 40.269856 -251.35348) (xy 40.243973 -251.301118) (xy 40.226359 -251.245428)
			(xy 40.217425 -251.187706) (xy 40.216836 -251.158502) (xy 40.217291 -251.131701) (xy 40.224801 -251.078627)
			(xy 40.239672 -251.027129) (xy 40.261611 -250.978222) (xy 40.27551 -250.955302) (xy 40.284908 -250.940062)
			(xy 40.281098 -250.90501) (xy 39.656512 -250.280424) (xy 39.649115 -250.273573) (xy 39.630517 -250.265831)
			(xy 39.620444 -250.265438) (xy 35.641026 -250.265438) (xy 35.636136 -250.265299) (xy 35.626544 -250.263379)
			(xy 35.621976 -250.261628) (xy 35.612324 -250.257818) (xy 2.430526 -250.257818) (xy 2.420462 -250.258255)
			(xy 2.401879 -250.26599) (xy 2.394458 -250.272804) (xy 1.675384 -250.991878) (xy 1.668541 -250.999277)
			(xy 1.660821 -251.017876) (xy 1.660398 -251.027946) (xy 1.660398 -251.158502) (xy 23.960326 -251.158502)
			(xy 23.964397 -251.10288) (xy 23.976523 -251.048443) (xy 23.996446 -250.996352) (xy 24.023742 -250.947717)
			(xy 24.057828 -250.903574) (xy 24.097977 -250.864865) (xy 24.143335 -250.832414) (xy 24.192935 -250.806913)
			(xy 24.245719 -250.788906) (xy 24.300562 -250.778776) (xy 24.356296 -250.776739) (xy 24.411733 -250.782839)
			(xy 24.46569 -250.796945) (xy 24.517019 -250.818757) (xy 24.564625 -250.847811) (xy 24.607493 -250.883486)
			(xy 24.64471 -250.925023) (xy 24.675483 -250.971536) (xy 24.699155 -251.022033) (xy 24.715223 -251.07544)
			(xy 24.723343 -251.130616) (xy 24.723792 -251.1552) (xy 25.068782 -251.1552) (xy 25.072853 -251.099578)
			(xy 25.084979 -251.045141) (xy 25.104902 -250.99305) (xy 25.132198 -250.944415) (xy 25.166284 -250.900272)
			(xy 25.206433 -250.861563) (xy 25.251791 -250.829112) (xy 25.301391 -250.803611) (xy 25.354175 -250.785604)
			(xy 25.409018 -250.775474) (xy 25.464752 -250.773437) (xy 25.520189 -250.779537) (xy 25.574146 -250.793643)
			(xy 25.625475 -250.815455) (xy 25.673081 -250.844509) (xy 25.715949 -250.880184) (xy 25.753166 -250.921721)
			(xy 25.783939 -250.968234) (xy 25.807611 -251.018731) (xy 25.823679 -251.072138) (xy 25.831799 -251.127314)
			(xy 25.832308 -251.1552) (xy 25.832248 -251.158502) (xy 25.992326 -251.158502) (xy 25.996397 -251.10288)
			(xy 26.008523 -251.048443) (xy 26.028446 -250.996352) (xy 26.055742 -250.947717) (xy 26.089828 -250.903574)
			(xy 26.129977 -250.864865) (xy 26.175335 -250.832414) (xy 26.224935 -250.806913) (xy 26.277719 -250.788906)
			(xy 26.332562 -250.778776) (xy 26.388296 -250.776739) (xy 26.443733 -250.782839) (xy 26.49769 -250.796945)
			(xy 26.549019 -250.818757) (xy 26.596625 -250.847811) (xy 26.639493 -250.883486) (xy 26.67671 -250.925023)
			(xy 26.707483 -250.971536) (xy 26.731155 -251.022033) (xy 26.747223 -251.07544) (xy 26.755343 -251.130616)
			(xy 26.755852 -251.158502) (xy 27.008326 -251.158502) (xy 27.012397 -251.10288) (xy 27.024523 -251.048443)
			(xy 27.044446 -250.996352) (xy 27.071742 -250.947717) (xy 27.105828 -250.903574) (xy 27.145977 -250.864865)
			(xy 27.191335 -250.832414) (xy 27.240935 -250.806913) (xy 27.293719 -250.788906) (xy 27.348562 -250.778776)
			(xy 27.404296 -250.776739) (xy 27.459733 -250.782839) (xy 27.51369 -250.796945) (xy 27.565019 -250.818757)
			(xy 27.612625 -250.847811) (xy 27.655493 -250.883486) (xy 27.69271 -250.925023) (xy 27.723483 -250.971536)
			(xy 27.747155 -251.022033) (xy 27.763223 -251.07544) (xy 27.771343 -251.130616) (xy 27.771852 -251.158502)
			(xy 28.024326 -251.158502) (xy 28.028397 -251.10288) (xy 28.040523 -251.048443) (xy 28.060446 -250.996352)
			(xy 28.087742 -250.947717) (xy 28.121828 -250.903574) (xy 28.161977 -250.864865) (xy 28.207335 -250.832414)
			(xy 28.256935 -250.806913) (xy 28.309719 -250.788906) (xy 28.364562 -250.778776) (xy 28.420296 -250.776739)
			(xy 28.475733 -250.782839) (xy 28.52969 -250.796945) (xy 28.581019 -250.818757) (xy 28.628625 -250.847811)
			(xy 28.671493 -250.883486) (xy 28.70871 -250.925023) (xy 28.739483 -250.971536) (xy 28.763155 -251.022033)
			(xy 28.779223 -251.07544) (xy 28.787343 -251.130616) (xy 28.787852 -251.158502) (xy 29.040326 -251.158502)
			(xy 29.044397 -251.10288) (xy 29.056523 -251.048443) (xy 29.076446 -250.996352) (xy 29.103742 -250.947717)
			(xy 29.137828 -250.903574) (xy 29.177977 -250.864865) (xy 29.223335 -250.832414) (xy 29.272935 -250.806913)
			(xy 29.325719 -250.788906) (xy 29.380562 -250.778776) (xy 29.436296 -250.776739) (xy 29.491733 -250.782839)
			(xy 29.54569 -250.796945) (xy 29.597019 -250.818757) (xy 29.644625 -250.847811) (xy 29.687493 -250.883486)
			(xy 29.72471 -250.925023) (xy 29.755483 -250.971536) (xy 29.779155 -251.022033) (xy 29.795223 -251.07544)
			(xy 29.803343 -251.130616) (xy 29.803852 -251.158502) (xy 30.056326 -251.158502) (xy 30.060397 -251.10288)
			(xy 30.072523 -251.048443) (xy 30.092446 -250.996352) (xy 30.119742 -250.947717) (xy 30.153828 -250.903574)
			(xy 30.193977 -250.864865) (xy 30.239335 -250.832414) (xy 30.288935 -250.806913) (xy 30.341719 -250.788906)
			(xy 30.396562 -250.778776) (xy 30.452296 -250.776739) (xy 30.507733 -250.782839) (xy 30.56169 -250.796945)
			(xy 30.613019 -250.818757) (xy 30.660625 -250.847811) (xy 30.703493 -250.883486) (xy 30.74071 -250.925023)
			(xy 30.771483 -250.971536) (xy 30.795155 -251.022033) (xy 30.811223 -251.07544) (xy 30.819343 -251.130616)
			(xy 30.819852 -251.158502) (xy 31.072326 -251.158502) (xy 31.076397 -251.10288) (xy 31.088523 -251.048443)
			(xy 31.108446 -250.996352) (xy 31.135742 -250.947717) (xy 31.169828 -250.903574) (xy 31.209977 -250.864865)
			(xy 31.255335 -250.832414) (xy 31.304935 -250.806913) (xy 31.357719 -250.788906) (xy 31.412562 -250.778776)
			(xy 31.468296 -250.776739) (xy 31.523733 -250.782839) (xy 31.57769 -250.796945) (xy 31.629019 -250.818757)
			(xy 31.676625 -250.847811) (xy 31.719493 -250.883486) (xy 31.75671 -250.925023) (xy 31.787483 -250.971536)
			(xy 31.811155 -251.022033) (xy 31.827223 -251.07544) (xy 31.835343 -251.130616) (xy 31.835852 -251.158502)
			(xy 32.088326 -251.158502) (xy 32.092397 -251.10288) (xy 32.104523 -251.048443) (xy 32.124446 -250.996352)
			(xy 32.151742 -250.947717) (xy 32.185828 -250.903574) (xy 32.225977 -250.864865) (xy 32.271335 -250.832414)
			(xy 32.320935 -250.806913) (xy 32.373719 -250.788906) (xy 32.428562 -250.778776) (xy 32.484296 -250.776739)
			(xy 32.539733 -250.782839) (xy 32.59369 -250.796945) (xy 32.645019 -250.818757) (xy 32.692625 -250.847811)
			(xy 32.735493 -250.883486) (xy 32.77271 -250.925023) (xy 32.803483 -250.971536) (xy 32.827155 -251.022033)
			(xy 32.843223 -251.07544) (xy 32.851343 -251.130616) (xy 32.851852 -251.158502) (xy 33.104326 -251.158502)
			(xy 33.108397 -251.10288) (xy 33.120523 -251.048443) (xy 33.140446 -250.996352) (xy 33.167742 -250.947717)
			(xy 33.201828 -250.903574) (xy 33.241977 -250.864865) (xy 33.287335 -250.832414) (xy 33.336935 -250.806913)
			(xy 33.389719 -250.788906) (xy 33.444562 -250.778776) (xy 33.500296 -250.776739) (xy 33.555733 -250.782839)
			(xy 33.60969 -250.796945) (xy 33.661019 -250.818757) (xy 33.708625 -250.847811) (xy 33.751493 -250.883486)
			(xy 33.78871 -250.925023) (xy 33.819483 -250.971536) (xy 33.843155 -251.022033) (xy 33.859223 -251.07544)
			(xy 33.867343 -251.130616) (xy 33.867852 -251.158502) (xy 34.120326 -251.158502) (xy 34.124397 -251.10288)
			(xy 34.136523 -251.048443) (xy 34.156446 -250.996352) (xy 34.183742 -250.947717) (xy 34.217828 -250.903574)
			(xy 34.257977 -250.864865) (xy 34.303335 -250.832414) (xy 34.352935 -250.806913) (xy 34.405719 -250.788906)
			(xy 34.460562 -250.778776) (xy 34.516296 -250.776739) (xy 34.571733 -250.782839) (xy 34.62569 -250.796945)
			(xy 34.677019 -250.818757) (xy 34.724625 -250.847811) (xy 34.767493 -250.883486) (xy 34.80471 -250.925023)
			(xy 34.835483 -250.971536) (xy 34.859155 -251.022033) (xy 34.875223 -251.07544) (xy 34.883343 -251.130616)
			(xy 34.883852 -251.158502) (xy 35.136326 -251.158502) (xy 35.140397 -251.10288) (xy 35.152523 -251.048443)
			(xy 35.172446 -250.996352) (xy 35.199742 -250.947717) (xy 35.233828 -250.903574) (xy 35.273977 -250.864865)
			(xy 35.319335 -250.832414) (xy 35.368935 -250.806913) (xy 35.421719 -250.788906) (xy 35.476562 -250.778776)
			(xy 35.532296 -250.776739) (xy 35.587733 -250.782839) (xy 35.64169 -250.796945) (xy 35.693019 -250.818757)
			(xy 35.740625 -250.847811) (xy 35.783493 -250.883486) (xy 35.82071 -250.925023) (xy 35.851483 -250.971536)
			(xy 35.875155 -251.022033) (xy 35.891223 -251.07544) (xy 35.899343 -251.130616) (xy 35.899852 -251.158502)
			(xy 36.152326 -251.158502) (xy 36.156397 -251.10288) (xy 36.168523 -251.048443) (xy 36.188446 -250.996352)
			(xy 36.215742 -250.947717) (xy 36.249828 -250.903574) (xy 36.289977 -250.864865) (xy 36.335335 -250.832414)
			(xy 36.384935 -250.806913) (xy 36.437719 -250.788906) (xy 36.492562 -250.778776) (xy 36.548296 -250.776739)
			(xy 36.603733 -250.782839) (xy 36.65769 -250.796945) (xy 36.709019 -250.818757) (xy 36.756625 -250.847811)
			(xy 36.799493 -250.883486) (xy 36.83671 -250.925023) (xy 36.867483 -250.971536) (xy 36.891155 -251.022033)
			(xy 36.907223 -251.07544) (xy 36.915343 -251.130616) (xy 36.915852 -251.158502) (xy 37.168326 -251.158502)
			(xy 37.172397 -251.10288) (xy 37.184523 -251.048443) (xy 37.204446 -250.996352) (xy 37.231742 -250.947717)
			(xy 37.265828 -250.903574) (xy 37.305977 -250.864865) (xy 37.351335 -250.832414) (xy 37.400935 -250.806913)
			(xy 37.453719 -250.788906) (xy 37.508562 -250.778776) (xy 37.564296 -250.776739) (xy 37.619733 -250.782839)
			(xy 37.67369 -250.796945) (xy 37.725019 -250.818757) (xy 37.772625 -250.847811) (xy 37.815493 -250.883486)
			(xy 37.85271 -250.925023) (xy 37.883483 -250.971536) (xy 37.907155 -251.022033) (xy 37.923223 -251.07544)
			(xy 37.931343 -251.130616) (xy 37.931852 -251.158502) (xy 38.184326 -251.158502) (xy 38.188397 -251.10288)
			(xy 38.200523 -251.048443) (xy 38.220446 -250.996352) (xy 38.247742 -250.947717) (xy 38.281828 -250.903574)
			(xy 38.321977 -250.864865) (xy 38.367335 -250.832414) (xy 38.416935 -250.806913) (xy 38.469719 -250.788906)
			(xy 38.524562 -250.778776) (xy 38.580296 -250.776739) (xy 38.635733 -250.782839) (xy 38.68969 -250.796945)
			(xy 38.741019 -250.818757) (xy 38.788625 -250.847811) (xy 38.831493 -250.883486) (xy 38.86871 -250.925023)
			(xy 38.899483 -250.971536) (xy 38.923155 -251.022033) (xy 38.939223 -251.07544) (xy 38.947343 -251.130616)
			(xy 38.947852 -251.158502) (xy 38.947343 -251.186388) (xy 38.939223 -251.241564) (xy 38.923155 -251.294971)
			(xy 38.899483 -251.345468) (xy 38.86871 -251.391981) (xy 38.831493 -251.433518) (xy 38.788625 -251.469193)
			(xy 38.741019 -251.498247) (xy 38.68969 -251.520059) (xy 38.635733 -251.534165) (xy 38.580296 -251.540265)
			(xy 38.524562 -251.538228) (xy 38.469719 -251.528098) (xy 38.416935 -251.510091) (xy 38.367335 -251.48459)
			(xy 38.321977 -251.452139) (xy 38.281828 -251.41343) (xy 38.247742 -251.369287) (xy 38.220446 -251.320652)
			(xy 38.200523 -251.268561) (xy 38.188397 -251.214124) (xy 38.184326 -251.158502) (xy 37.931852 -251.158502)
			(xy 37.931343 -251.186388) (xy 37.923223 -251.241564) (xy 37.907155 -251.294971) (xy 37.883483 -251.345468)
			(xy 37.85271 -251.391981) (xy 37.815493 -251.433518) (xy 37.772625 -251.469193) (xy 37.725019 -251.498247)
			(xy 37.67369 -251.520059) (xy 37.619733 -251.534165) (xy 37.564296 -251.540265) (xy 37.508562 -251.538228)
			(xy 37.453719 -251.528098) (xy 37.400935 -251.510091) (xy 37.351335 -251.48459) (xy 37.305977 -251.452139)
			(xy 37.265828 -251.41343) (xy 37.231742 -251.369287) (xy 37.204446 -251.320652) (xy 37.184523 -251.268561)
			(xy 37.172397 -251.214124) (xy 37.168326 -251.158502) (xy 36.915852 -251.158502) (xy 36.915343 -251.186388)
			(xy 36.907223 -251.241564) (xy 36.891155 -251.294971) (xy 36.867483 -251.345468) (xy 36.83671 -251.391981)
			(xy 36.799493 -251.433518) (xy 36.756625 -251.469193) (xy 36.709019 -251.498247) (xy 36.65769 -251.520059)
			(xy 36.603733 -251.534165) (xy 36.548296 -251.540265) (xy 36.492562 -251.538228) (xy 36.437719 -251.528098)
			(xy 36.384935 -251.510091) (xy 36.335335 -251.48459) (xy 36.289977 -251.452139) (xy 36.249828 -251.41343)
			(xy 36.215742 -251.369287) (xy 36.188446 -251.320652) (xy 36.168523 -251.268561) (xy 36.156397 -251.214124)
			(xy 36.152326 -251.158502) (xy 35.899852 -251.158502) (xy 35.899343 -251.186388) (xy 35.891223 -251.241564)
			(xy 35.875155 -251.294971) (xy 35.851483 -251.345468) (xy 35.82071 -251.391981) (xy 35.783493 -251.433518)
			(xy 35.740625 -251.469193) (xy 35.693019 -251.498247) (xy 35.64169 -251.520059) (xy 35.587733 -251.534165)
			(xy 35.532296 -251.540265) (xy 35.476562 -251.538228) (xy 35.421719 -251.528098) (xy 35.368935 -251.510091)
			(xy 35.319335 -251.48459) (xy 35.273977 -251.452139) (xy 35.233828 -251.41343) (xy 35.199742 -251.369287)
			(xy 35.172446 -251.320652) (xy 35.152523 -251.268561) (xy 35.140397 -251.214124) (xy 35.136326 -251.158502)
			(xy 34.883852 -251.158502) (xy 34.883343 -251.186388) (xy 34.875223 -251.241564) (xy 34.859155 -251.294971)
			(xy 34.835483 -251.345468) (xy 34.80471 -251.391981) (xy 34.767493 -251.433518) (xy 34.724625 -251.469193)
			(xy 34.677019 -251.498247) (xy 34.62569 -251.520059) (xy 34.571733 -251.534165) (xy 34.516296 -251.540265)
			(xy 34.460562 -251.538228) (xy 34.405719 -251.528098) (xy 34.352935 -251.510091) (xy 34.303335 -251.48459)
			(xy 34.257977 -251.452139) (xy 34.217828 -251.41343) (xy 34.183742 -251.369287) (xy 34.156446 -251.320652)
			(xy 34.136523 -251.268561) (xy 34.124397 -251.214124) (xy 34.120326 -251.158502) (xy 33.867852 -251.158502)
			(xy 33.867343 -251.186388) (xy 33.859223 -251.241564) (xy 33.843155 -251.294971) (xy 33.819483 -251.345468)
			(xy 33.78871 -251.391981) (xy 33.751493 -251.433518) (xy 33.708625 -251.469193) (xy 33.661019 -251.498247)
			(xy 33.60969 -251.520059) (xy 33.555733 -251.534165) (xy 33.500296 -251.540265) (xy 33.444562 -251.538228)
			(xy 33.389719 -251.528098) (xy 33.336935 -251.510091) (xy 33.287335 -251.48459) (xy 33.241977 -251.452139)
			(xy 33.201828 -251.41343) (xy 33.167742 -251.369287) (xy 33.140446 -251.320652) (xy 33.120523 -251.268561)
			(xy 33.108397 -251.214124) (xy 33.104326 -251.158502) (xy 32.851852 -251.158502) (xy 32.851343 -251.186388)
			(xy 32.843223 -251.241564) (xy 32.827155 -251.294971) (xy 32.803483 -251.345468) (xy 32.77271 -251.391981)
			(xy 32.735493 -251.433518) (xy 32.692625 -251.469193) (xy 32.645019 -251.498247) (xy 32.59369 -251.520059)
			(xy 32.539733 -251.534165) (xy 32.484296 -251.540265) (xy 32.428562 -251.538228) (xy 32.373719 -251.528098)
			(xy 32.320935 -251.510091) (xy 32.271335 -251.48459) (xy 32.225977 -251.452139) (xy 32.185828 -251.41343)
			(xy 32.151742 -251.369287) (xy 32.124446 -251.320652) (xy 32.104523 -251.268561) (xy 32.092397 -251.214124)
			(xy 32.088326 -251.158502) (xy 31.835852 -251.158502) (xy 31.835343 -251.186388) (xy 31.827223 -251.241564)
			(xy 31.811155 -251.294971) (xy 31.787483 -251.345468) (xy 31.75671 -251.391981) (xy 31.719493 -251.433518)
			(xy 31.676625 -251.469193) (xy 31.629019 -251.498247) (xy 31.57769 -251.520059) (xy 31.523733 -251.534165)
			(xy 31.468296 -251.540265) (xy 31.412562 -251.538228) (xy 31.357719 -251.528098) (xy 31.304935 -251.510091)
			(xy 31.255335 -251.48459) (xy 31.209977 -251.452139) (xy 31.169828 -251.41343) (xy 31.135742 -251.369287)
			(xy 31.108446 -251.320652) (xy 31.088523 -251.268561) (xy 31.076397 -251.214124) (xy 31.072326 -251.158502)
			(xy 30.819852 -251.158502) (xy 30.819343 -251.186388) (xy 30.811223 -251.241564) (xy 30.795155 -251.294971)
			(xy 30.771483 -251.345468) (xy 30.74071 -251.391981) (xy 30.703493 -251.433518) (xy 30.660625 -251.469193)
			(xy 30.613019 -251.498247) (xy 30.56169 -251.520059) (xy 30.507733 -251.534165) (xy 30.452296 -251.540265)
			(xy 30.396562 -251.538228) (xy 30.341719 -251.528098) (xy 30.288935 -251.510091) (xy 30.239335 -251.48459)
			(xy 30.193977 -251.452139) (xy 30.153828 -251.41343) (xy 30.119742 -251.369287) (xy 30.092446 -251.320652)
			(xy 30.072523 -251.268561) (xy 30.060397 -251.214124) (xy 30.056326 -251.158502) (xy 29.803852 -251.158502)
			(xy 29.803343 -251.186388) (xy 29.795223 -251.241564) (xy 29.779155 -251.294971) (xy 29.755483 -251.345468)
			(xy 29.72471 -251.391981) (xy 29.687493 -251.433518) (xy 29.644625 -251.469193) (xy 29.597019 -251.498247)
			(xy 29.54569 -251.520059) (xy 29.491733 -251.534165) (xy 29.436296 -251.540265) (xy 29.380562 -251.538228)
			(xy 29.325719 -251.528098) (xy 29.272935 -251.510091) (xy 29.223335 -251.48459) (xy 29.177977 -251.452139)
			(xy 29.137828 -251.41343) (xy 29.103742 -251.369287) (xy 29.076446 -251.320652) (xy 29.056523 -251.268561)
			(xy 29.044397 -251.214124) (xy 29.040326 -251.158502) (xy 28.787852 -251.158502) (xy 28.787343 -251.186388)
			(xy 28.779223 -251.241564) (xy 28.763155 -251.294971) (xy 28.739483 -251.345468) (xy 28.70871 -251.391981)
			(xy 28.671493 -251.433518) (xy 28.628625 -251.469193) (xy 28.581019 -251.498247) (xy 28.52969 -251.520059)
			(xy 28.475733 -251.534165) (xy 28.420296 -251.540265) (xy 28.364562 -251.538228) (xy 28.309719 -251.528098)
			(xy 28.256935 -251.510091) (xy 28.207335 -251.48459) (xy 28.161977 -251.452139) (xy 28.121828 -251.41343)
			(xy 28.087742 -251.369287) (xy 28.060446 -251.320652) (xy 28.040523 -251.268561) (xy 28.028397 -251.214124)
			(xy 28.024326 -251.158502) (xy 27.771852 -251.158502) (xy 27.771343 -251.186388) (xy 27.763223 -251.241564)
			(xy 27.747155 -251.294971) (xy 27.723483 -251.345468) (xy 27.69271 -251.391981) (xy 27.655493 -251.433518)
			(xy 27.612625 -251.469193) (xy 27.565019 -251.498247) (xy 27.51369 -251.520059) (xy 27.459733 -251.534165)
			(xy 27.404296 -251.540265) (xy 27.348562 -251.538228) (xy 27.293719 -251.528098) (xy 27.240935 -251.510091)
			(xy 27.191335 -251.48459) (xy 27.145977 -251.452139) (xy 27.105828 -251.41343) (xy 27.071742 -251.369287)
			(xy 27.044446 -251.320652) (xy 27.024523 -251.268561) (xy 27.012397 -251.214124) (xy 27.008326 -251.158502)
			(xy 26.755852 -251.158502) (xy 26.755343 -251.186388) (xy 26.747223 -251.241564) (xy 26.731155 -251.294971)
			(xy 26.707483 -251.345468) (xy 26.67671 -251.391981) (xy 26.639493 -251.433518) (xy 26.596625 -251.469193)
			(xy 26.549019 -251.498247) (xy 26.49769 -251.520059) (xy 26.443733 -251.534165) (xy 26.388296 -251.540265)
			(xy 26.332562 -251.538228) (xy 26.277719 -251.528098) (xy 26.224935 -251.510091) (xy 26.175335 -251.48459)
			(xy 26.129977 -251.452139) (xy 26.089828 -251.41343) (xy 26.055742 -251.369287) (xy 26.028446 -251.320652)
			(xy 26.008523 -251.268561) (xy 25.996397 -251.214124) (xy 25.992326 -251.158502) (xy 25.832248 -251.158502)
			(xy 25.831799 -251.183086) (xy 25.823679 -251.238262) (xy 25.807611 -251.291669) (xy 25.783939 -251.342166)
			(xy 25.753166 -251.388679) (xy 25.715949 -251.430216) (xy 25.673081 -251.465891) (xy 25.625475 -251.494945)
			(xy 25.574146 -251.516757) (xy 25.520189 -251.530863) (xy 25.464752 -251.536963) (xy 25.409018 -251.534926)
			(xy 25.354175 -251.524796) (xy 25.301391 -251.506789) (xy 25.251791 -251.481288) (xy 25.206433 -251.448837)
			(xy 25.166284 -251.410128) (xy 25.132198 -251.365985) (xy 25.104902 -251.31735) (xy 25.084979 -251.265259)
			(xy 25.072853 -251.210822) (xy 25.068782 -251.1552) (xy 24.723792 -251.1552) (xy 24.723852 -251.158502)
			(xy 24.723343 -251.186388) (xy 24.715223 -251.241564) (xy 24.699155 -251.294971) (xy 24.675483 -251.345468)
			(xy 24.64471 -251.391981) (xy 24.607493 -251.433518) (xy 24.564625 -251.469193) (xy 24.517019 -251.498247)
			(xy 24.46569 -251.520059) (xy 24.411733 -251.534165) (xy 24.356296 -251.540265) (xy 24.300562 -251.538228)
			(xy 24.245719 -251.528098) (xy 24.192935 -251.510091) (xy 24.143335 -251.48459) (xy 24.097977 -251.452139)
			(xy 24.057828 -251.41343) (xy 24.023742 -251.369287) (xy 23.996446 -251.320652) (xy 23.976523 -251.268561)
			(xy 23.964397 -251.214124) (xy 23.960326 -251.158502) (xy 1.660398 -251.158502) (xy 1.660398 -253.620778)
			(xy 21.387306 -253.620778) (xy 21.391377 -253.565156) (xy 21.403503 -253.510719) (xy 21.423426 -253.458628)
			(xy 21.450722 -253.409993) (xy 21.484808 -253.36585) (xy 21.524957 -253.327141) (xy 21.570315 -253.29469)
			(xy 21.619915 -253.269189) (xy 21.672699 -253.251182) (xy 21.727542 -253.241052) (xy 21.783276 -253.239015)
			(xy 21.838713 -253.245115) (xy 21.89267 -253.259221) (xy 21.943999 -253.281033) (xy 21.991605 -253.310087)
			(xy 22.034473 -253.345762) (xy 22.07169 -253.387299) (xy 22.102463 -253.433812) (xy 22.113071 -253.45644)
			(xy 23.960326 -253.45644) (xy 23.964397 -253.400818) (xy 23.976523 -253.346381) (xy 23.996446 -253.29429)
			(xy 24.023742 -253.245655) (xy 24.057828 -253.201512) (xy 24.097977 -253.162803) (xy 24.143335 -253.130352)
			(xy 24.192935 -253.104851) (xy 24.245719 -253.086844) (xy 24.300562 -253.076714) (xy 24.356296 -253.074677)
			(xy 24.411733 -253.080777) (xy 24.46569 -253.094883) (xy 24.517019 -253.116695) (xy 24.564625 -253.145749)
			(xy 24.607493 -253.181424) (xy 24.64471 -253.222961) (xy 24.675483 -253.269474) (xy 24.699155 -253.319971)
			(xy 24.715223 -253.373378) (xy 24.723343 -253.428554) (xy 24.723852 -253.45644) (xy 24.976326 -253.45644)
			(xy 24.980397 -253.400818) (xy 24.992523 -253.346381) (xy 25.012446 -253.29429) (xy 25.039742 -253.245655)
			(xy 25.073828 -253.201512) (xy 25.113977 -253.162803) (xy 25.159335 -253.130352) (xy 25.208935 -253.104851)
			(xy 25.261719 -253.086844) (xy 25.316562 -253.076714) (xy 25.372296 -253.074677) (xy 25.427733 -253.080777)
			(xy 25.48169 -253.094883) (xy 25.533019 -253.116695) (xy 25.580625 -253.145749) (xy 25.623493 -253.181424)
			(xy 25.66071 -253.222961) (xy 25.691483 -253.269474) (xy 25.715155 -253.319971) (xy 25.731223 -253.373378)
			(xy 25.739343 -253.428554) (xy 25.739852 -253.45644) (xy 25.992326 -253.45644) (xy 25.996397 -253.400818)
			(xy 26.008523 -253.346381) (xy 26.028446 -253.29429) (xy 26.055742 -253.245655) (xy 26.089828 -253.201512)
			(xy 26.129977 -253.162803) (xy 26.175335 -253.130352) (xy 26.224935 -253.104851) (xy 26.277719 -253.086844)
			(xy 26.332562 -253.076714) (xy 26.388296 -253.074677) (xy 26.443733 -253.080777) (xy 26.49769 -253.094883)
			(xy 26.549019 -253.116695) (xy 26.596625 -253.145749) (xy 26.639493 -253.181424) (xy 26.67671 -253.222961)
			(xy 26.707483 -253.269474) (xy 26.731155 -253.319971) (xy 26.747223 -253.373378) (xy 26.755343 -253.428554)
			(xy 26.755852 -253.45644) (xy 27.008326 -253.45644) (xy 27.012397 -253.400818) (xy 27.024523 -253.346381)
			(xy 27.044446 -253.29429) (xy 27.071742 -253.245655) (xy 27.105828 -253.201512) (xy 27.145977 -253.162803)
			(xy 27.191335 -253.130352) (xy 27.240935 -253.104851) (xy 27.293719 -253.086844) (xy 27.348562 -253.076714)
			(xy 27.404296 -253.074677) (xy 27.459733 -253.080777) (xy 27.51369 -253.094883) (xy 27.565019 -253.116695)
			(xy 27.612625 -253.145749) (xy 27.655493 -253.181424) (xy 27.69271 -253.222961) (xy 27.723483 -253.269474)
			(xy 27.747155 -253.319971) (xy 27.763223 -253.373378) (xy 27.771343 -253.428554) (xy 27.771852 -253.45644)
			(xy 28.024326 -253.45644) (xy 28.028397 -253.400818) (xy 28.040523 -253.346381) (xy 28.060446 -253.29429)
			(xy 28.087742 -253.245655) (xy 28.121828 -253.201512) (xy 28.161977 -253.162803) (xy 28.207335 -253.130352)
			(xy 28.256935 -253.104851) (xy 28.309719 -253.086844) (xy 28.364562 -253.076714) (xy 28.420296 -253.074677)
			(xy 28.475733 -253.080777) (xy 28.52969 -253.094883) (xy 28.581019 -253.116695) (xy 28.628625 -253.145749)
			(xy 28.671493 -253.181424) (xy 28.70871 -253.222961) (xy 28.739483 -253.269474) (xy 28.763155 -253.319971)
			(xy 28.779223 -253.373378) (xy 28.787343 -253.428554) (xy 28.787852 -253.45644) (xy 29.040326 -253.45644)
			(xy 29.044397 -253.400818) (xy 29.056523 -253.346381) (xy 29.076446 -253.29429) (xy 29.103742 -253.245655)
			(xy 29.137828 -253.201512) (xy 29.177977 -253.162803) (xy 29.223335 -253.130352) (xy 29.272935 -253.104851)
			(xy 29.325719 -253.086844) (xy 29.380562 -253.076714) (xy 29.436296 -253.074677) (xy 29.491733 -253.080777)
			(xy 29.54569 -253.094883) (xy 29.597019 -253.116695) (xy 29.644625 -253.145749) (xy 29.687493 -253.181424)
			(xy 29.72471 -253.222961) (xy 29.755483 -253.269474) (xy 29.779155 -253.319971) (xy 29.795223 -253.373378)
			(xy 29.803343 -253.428554) (xy 29.803852 -253.45644) (xy 30.056326 -253.45644) (xy 30.060397 -253.400818)
			(xy 30.072523 -253.346381) (xy 30.092446 -253.29429) (xy 30.119742 -253.245655) (xy 30.153828 -253.201512)
			(xy 30.193977 -253.162803) (xy 30.239335 -253.130352) (xy 30.288935 -253.104851) (xy 30.341719 -253.086844)
			(xy 30.396562 -253.076714) (xy 30.452296 -253.074677) (xy 30.507733 -253.080777) (xy 30.56169 -253.094883)
			(xy 30.613019 -253.116695) (xy 30.660625 -253.145749) (xy 30.703493 -253.181424) (xy 30.74071 -253.222961)
			(xy 30.771483 -253.269474) (xy 30.795155 -253.319971) (xy 30.811223 -253.373378) (xy 30.819343 -253.428554)
			(xy 30.819852 -253.45644) (xy 31.072326 -253.45644) (xy 31.076397 -253.400818) (xy 31.088523 -253.346381)
			(xy 31.108446 -253.29429) (xy 31.135742 -253.245655) (xy 31.169828 -253.201512) (xy 31.209977 -253.162803)
			(xy 31.255335 -253.130352) (xy 31.304935 -253.104851) (xy 31.357719 -253.086844) (xy 31.412562 -253.076714)
			(xy 31.468296 -253.074677) (xy 31.523733 -253.080777) (xy 31.57769 -253.094883) (xy 31.629019 -253.116695)
			(xy 31.676625 -253.145749) (xy 31.719493 -253.181424) (xy 31.75671 -253.222961) (xy 31.787483 -253.269474)
			(xy 31.811155 -253.319971) (xy 31.827223 -253.373378) (xy 31.835343 -253.428554) (xy 31.835852 -253.45644)
			(xy 32.088326 -253.45644) (xy 32.092397 -253.400818) (xy 32.104523 -253.346381) (xy 32.124446 -253.29429)
			(xy 32.151742 -253.245655) (xy 32.185828 -253.201512) (xy 32.225977 -253.162803) (xy 32.271335 -253.130352)
			(xy 32.320935 -253.104851) (xy 32.373719 -253.086844) (xy 32.428562 -253.076714) (xy 32.484296 -253.074677)
			(xy 32.539733 -253.080777) (xy 32.59369 -253.094883) (xy 32.645019 -253.116695) (xy 32.692625 -253.145749)
			(xy 32.735493 -253.181424) (xy 32.77271 -253.222961) (xy 32.803483 -253.269474) (xy 32.827155 -253.319971)
			(xy 32.843223 -253.373378) (xy 32.851343 -253.428554) (xy 32.851852 -253.45644) (xy 33.104326 -253.45644)
			(xy 33.108397 -253.400818) (xy 33.120523 -253.346381) (xy 33.140446 -253.29429) (xy 33.167742 -253.245655)
			(xy 33.201828 -253.201512) (xy 33.241977 -253.162803) (xy 33.287335 -253.130352) (xy 33.336935 -253.104851)
			(xy 33.389719 -253.086844) (xy 33.444562 -253.076714) (xy 33.500296 -253.074677) (xy 33.555733 -253.080777)
			(xy 33.60969 -253.094883) (xy 33.661019 -253.116695) (xy 33.708625 -253.145749) (xy 33.751493 -253.181424)
			(xy 33.78871 -253.222961) (xy 33.819483 -253.269474) (xy 33.843155 -253.319971) (xy 33.859223 -253.373378)
			(xy 33.867343 -253.428554) (xy 33.867852 -253.45644) (xy 34.120326 -253.45644) (xy 34.124397 -253.400818)
			(xy 34.136523 -253.346381) (xy 34.156446 -253.29429) (xy 34.183742 -253.245655) (xy 34.217828 -253.201512)
			(xy 34.257977 -253.162803) (xy 34.303335 -253.130352) (xy 34.352935 -253.104851) (xy 34.405719 -253.086844)
			(xy 34.460562 -253.076714) (xy 34.516296 -253.074677) (xy 34.571733 -253.080777) (xy 34.62569 -253.094883)
			(xy 34.677019 -253.116695) (xy 34.724625 -253.145749) (xy 34.767493 -253.181424) (xy 34.80471 -253.222961)
			(xy 34.835483 -253.269474) (xy 34.859155 -253.319971) (xy 34.875223 -253.373378) (xy 34.883343 -253.428554)
			(xy 34.883852 -253.45644) (xy 35.136326 -253.45644) (xy 35.140397 -253.400818) (xy 35.152523 -253.346381)
			(xy 35.172446 -253.29429) (xy 35.199742 -253.245655) (xy 35.233828 -253.201512) (xy 35.273977 -253.162803)
			(xy 35.319335 -253.130352) (xy 35.368935 -253.104851) (xy 35.421719 -253.086844) (xy 35.476562 -253.076714)
			(xy 35.532296 -253.074677) (xy 35.587733 -253.080777) (xy 35.64169 -253.094883) (xy 35.693019 -253.116695)
			(xy 35.740625 -253.145749) (xy 35.783493 -253.181424) (xy 35.82071 -253.222961) (xy 35.851483 -253.269474)
			(xy 35.875155 -253.319971) (xy 35.891223 -253.373378) (xy 35.899343 -253.428554) (xy 35.899852 -253.45644)
			(xy 36.152326 -253.45644) (xy 36.156397 -253.400818) (xy 36.168523 -253.346381) (xy 36.188446 -253.29429)
			(xy 36.215742 -253.245655) (xy 36.249828 -253.201512) (xy 36.289977 -253.162803) (xy 36.335335 -253.130352)
			(xy 36.384935 -253.104851) (xy 36.437719 -253.086844) (xy 36.492562 -253.076714) (xy 36.548296 -253.074677)
			(xy 36.603733 -253.080777) (xy 36.65769 -253.094883) (xy 36.709019 -253.116695) (xy 36.756625 -253.145749)
			(xy 36.799493 -253.181424) (xy 36.83671 -253.222961) (xy 36.867483 -253.269474) (xy 36.891155 -253.319971)
			(xy 36.907223 -253.373378) (xy 36.915343 -253.428554) (xy 36.915852 -253.45644) (xy 37.168326 -253.45644)
			(xy 37.172397 -253.400818) (xy 37.184523 -253.346381) (xy 37.204446 -253.29429) (xy 37.231742 -253.245655)
			(xy 37.265828 -253.201512) (xy 37.305977 -253.162803) (xy 37.351335 -253.130352) (xy 37.400935 -253.104851)
			(xy 37.453719 -253.086844) (xy 37.508562 -253.076714) (xy 37.564296 -253.074677) (xy 37.619733 -253.080777)
			(xy 37.67369 -253.094883) (xy 37.725019 -253.116695) (xy 37.772625 -253.145749) (xy 37.815493 -253.181424)
			(xy 37.85271 -253.222961) (xy 37.883483 -253.269474) (xy 37.907155 -253.319971) (xy 37.923223 -253.373378)
			(xy 37.931343 -253.428554) (xy 37.931852 -253.45644) (xy 38.184326 -253.45644) (xy 38.188397 -253.400818)
			(xy 38.200523 -253.346381) (xy 38.220446 -253.29429) (xy 38.247742 -253.245655) (xy 38.281828 -253.201512)
			(xy 38.321977 -253.162803) (xy 38.367335 -253.130352) (xy 38.416935 -253.104851) (xy 38.469719 -253.086844)
			(xy 38.524562 -253.076714) (xy 38.580296 -253.074677) (xy 38.635733 -253.080777) (xy 38.68969 -253.094883)
			(xy 38.741019 -253.116695) (xy 38.788625 -253.145749) (xy 38.831493 -253.181424) (xy 38.86871 -253.222961)
			(xy 38.899483 -253.269474) (xy 38.923155 -253.319971) (xy 38.939223 -253.373378) (xy 38.947343 -253.428554)
			(xy 38.947852 -253.45644) (xy 39.200326 -253.45644) (xy 39.204397 -253.400818) (xy 39.216523 -253.346381)
			(xy 39.236446 -253.29429) (xy 39.263742 -253.245655) (xy 39.297828 -253.201512) (xy 39.337977 -253.162803)
			(xy 39.383335 -253.130352) (xy 39.432935 -253.104851) (xy 39.485719 -253.086844) (xy 39.540562 -253.076714)
			(xy 39.596296 -253.074677) (xy 39.651733 -253.080777) (xy 39.70569 -253.094883) (xy 39.757019 -253.116695)
			(xy 39.804625 -253.145749) (xy 39.847493 -253.181424) (xy 39.88471 -253.222961) (xy 39.915483 -253.269474)
			(xy 39.939155 -253.319971) (xy 39.955223 -253.373378) (xy 39.963343 -253.428554) (xy 39.963852 -253.45644)
			(xy 39.963343 -253.484326) (xy 39.955223 -253.539502) (xy 39.939155 -253.592909) (xy 39.915483 -253.643406)
			(xy 39.88471 -253.689919) (xy 39.847493 -253.731456) (xy 39.804625 -253.767131) (xy 39.757019 -253.796185)
			(xy 39.70569 -253.817997) (xy 39.651733 -253.832103) (xy 39.596296 -253.838203) (xy 39.540562 -253.836166)
			(xy 39.485719 -253.826036) (xy 39.432935 -253.808029) (xy 39.383335 -253.782528) (xy 39.337977 -253.750077)
			(xy 39.297828 -253.711368) (xy 39.263742 -253.667225) (xy 39.236446 -253.61859) (xy 39.216523 -253.566499)
			(xy 39.204397 -253.512062) (xy 39.200326 -253.45644) (xy 38.947852 -253.45644) (xy 38.947343 -253.484326)
			(xy 38.939223 -253.539502) (xy 38.923155 -253.592909) (xy 38.899483 -253.643406) (xy 38.86871 -253.689919)
			(xy 38.831493 -253.731456) (xy 38.788625 -253.767131) (xy 38.741019 -253.796185) (xy 38.68969 -253.817997)
			(xy 38.635733 -253.832103) (xy 38.580296 -253.838203) (xy 38.524562 -253.836166) (xy 38.469719 -253.826036)
			(xy 38.416935 -253.808029) (xy 38.367335 -253.782528) (xy 38.321977 -253.750077) (xy 38.281828 -253.711368)
			(xy 38.247742 -253.667225) (xy 38.220446 -253.61859) (xy 38.200523 -253.566499) (xy 38.188397 -253.512062)
			(xy 38.184326 -253.45644) (xy 37.931852 -253.45644) (xy 37.931343 -253.484326) (xy 37.923223 -253.539502)
			(xy 37.907155 -253.592909) (xy 37.883483 -253.643406) (xy 37.85271 -253.689919) (xy 37.815493 -253.731456)
			(xy 37.772625 -253.767131) (xy 37.725019 -253.796185) (xy 37.67369 -253.817997) (xy 37.619733 -253.832103)
			(xy 37.564296 -253.838203) (xy 37.508562 -253.836166) (xy 37.453719 -253.826036) (xy 37.400935 -253.808029)
			(xy 37.351335 -253.782528) (xy 37.305977 -253.750077) (xy 37.265828 -253.711368) (xy 37.231742 -253.667225)
			(xy 37.204446 -253.61859) (xy 37.184523 -253.566499) (xy 37.172397 -253.512062) (xy 37.168326 -253.45644)
			(xy 36.915852 -253.45644) (xy 36.915343 -253.484326) (xy 36.907223 -253.539502) (xy 36.891155 -253.592909)
			(xy 36.867483 -253.643406) (xy 36.83671 -253.689919) (xy 36.799493 -253.731456) (xy 36.756625 -253.767131)
			(xy 36.709019 -253.796185) (xy 36.65769 -253.817997) (xy 36.603733 -253.832103) (xy 36.548296 -253.838203)
			(xy 36.492562 -253.836166) (xy 36.437719 -253.826036) (xy 36.384935 -253.808029) (xy 36.335335 -253.782528)
			(xy 36.289977 -253.750077) (xy 36.249828 -253.711368) (xy 36.215742 -253.667225) (xy 36.188446 -253.61859)
			(xy 36.168523 -253.566499) (xy 36.156397 -253.512062) (xy 36.152326 -253.45644) (xy 35.899852 -253.45644)
			(xy 35.899343 -253.484326) (xy 35.891223 -253.539502) (xy 35.875155 -253.592909) (xy 35.851483 -253.643406)
			(xy 35.82071 -253.689919) (xy 35.783493 -253.731456) (xy 35.740625 -253.767131) (xy 35.693019 -253.796185)
			(xy 35.64169 -253.817997) (xy 35.587733 -253.832103) (xy 35.532296 -253.838203) (xy 35.476562 -253.836166)
			(xy 35.421719 -253.826036) (xy 35.368935 -253.808029) (xy 35.319335 -253.782528) (xy 35.273977 -253.750077)
			(xy 35.233828 -253.711368) (xy 35.199742 -253.667225) (xy 35.172446 -253.61859) (xy 35.152523 -253.566499)
			(xy 35.140397 -253.512062) (xy 35.136326 -253.45644) (xy 34.883852 -253.45644) (xy 34.883343 -253.484326)
			(xy 34.875223 -253.539502) (xy 34.859155 -253.592909) (xy 34.835483 -253.643406) (xy 34.80471 -253.689919)
			(xy 34.767493 -253.731456) (xy 34.724625 -253.767131) (xy 34.677019 -253.796185) (xy 34.62569 -253.817997)
			(xy 34.571733 -253.832103) (xy 34.516296 -253.838203) (xy 34.460562 -253.836166) (xy 34.405719 -253.826036)
			(xy 34.352935 -253.808029) (xy 34.303335 -253.782528) (xy 34.257977 -253.750077) (xy 34.217828 -253.711368)
			(xy 34.183742 -253.667225) (xy 34.156446 -253.61859) (xy 34.136523 -253.566499) (xy 34.124397 -253.512062)
			(xy 34.120326 -253.45644) (xy 33.867852 -253.45644) (xy 33.867343 -253.484326) (xy 33.859223 -253.539502)
			(xy 33.843155 -253.592909) (xy 33.819483 -253.643406) (xy 33.78871 -253.689919) (xy 33.751493 -253.731456)
			(xy 33.708625 -253.767131) (xy 33.661019 -253.796185) (xy 33.60969 -253.817997) (xy 33.555733 -253.832103)
			(xy 33.500296 -253.838203) (xy 33.444562 -253.836166) (xy 33.389719 -253.826036) (xy 33.336935 -253.808029)
			(xy 33.287335 -253.782528) (xy 33.241977 -253.750077) (xy 33.201828 -253.711368) (xy 33.167742 -253.667225)
			(xy 33.140446 -253.61859) (xy 33.120523 -253.566499) (xy 33.108397 -253.512062) (xy 33.104326 -253.45644)
			(xy 32.851852 -253.45644) (xy 32.851343 -253.484326) (xy 32.843223 -253.539502) (xy 32.827155 -253.592909)
			(xy 32.803483 -253.643406) (xy 32.77271 -253.689919) (xy 32.735493 -253.731456) (xy 32.692625 -253.767131)
			(xy 32.645019 -253.796185) (xy 32.59369 -253.817997) (xy 32.539733 -253.832103) (xy 32.484296 -253.838203)
			(xy 32.428562 -253.836166) (xy 32.373719 -253.826036) (xy 32.320935 -253.808029) (xy 32.271335 -253.782528)
			(xy 32.225977 -253.750077) (xy 32.185828 -253.711368) (xy 32.151742 -253.667225) (xy 32.124446 -253.61859)
			(xy 32.104523 -253.566499) (xy 32.092397 -253.512062) (xy 32.088326 -253.45644) (xy 31.835852 -253.45644)
			(xy 31.835343 -253.484326) (xy 31.827223 -253.539502) (xy 31.811155 -253.592909) (xy 31.787483 -253.643406)
			(xy 31.75671 -253.689919) (xy 31.719493 -253.731456) (xy 31.676625 -253.767131) (xy 31.629019 -253.796185)
			(xy 31.57769 -253.817997) (xy 31.523733 -253.832103) (xy 31.468296 -253.838203) (xy 31.412562 -253.836166)
			(xy 31.357719 -253.826036) (xy 31.304935 -253.808029) (xy 31.255335 -253.782528) (xy 31.209977 -253.750077)
			(xy 31.169828 -253.711368) (xy 31.135742 -253.667225) (xy 31.108446 -253.61859) (xy 31.088523 -253.566499)
			(xy 31.076397 -253.512062) (xy 31.072326 -253.45644) (xy 30.819852 -253.45644) (xy 30.819343 -253.484326)
			(xy 30.811223 -253.539502) (xy 30.795155 -253.592909) (xy 30.771483 -253.643406) (xy 30.74071 -253.689919)
			(xy 30.703493 -253.731456) (xy 30.660625 -253.767131) (xy 30.613019 -253.796185) (xy 30.56169 -253.817997)
			(xy 30.507733 -253.832103) (xy 30.452296 -253.838203) (xy 30.396562 -253.836166) (xy 30.341719 -253.826036)
			(xy 30.288935 -253.808029) (xy 30.239335 -253.782528) (xy 30.193977 -253.750077) (xy 30.153828 -253.711368)
			(xy 30.119742 -253.667225) (xy 30.092446 -253.61859) (xy 30.072523 -253.566499) (xy 30.060397 -253.512062)
			(xy 30.056326 -253.45644) (xy 29.803852 -253.45644) (xy 29.803343 -253.484326) (xy 29.795223 -253.539502)
			(xy 29.779155 -253.592909) (xy 29.755483 -253.643406) (xy 29.72471 -253.689919) (xy 29.687493 -253.731456)
			(xy 29.644625 -253.767131) (xy 29.597019 -253.796185) (xy 29.54569 -253.817997) (xy 29.491733 -253.832103)
			(xy 29.436296 -253.838203) (xy 29.380562 -253.836166) (xy 29.325719 -253.826036) (xy 29.272935 -253.808029)
			(xy 29.223335 -253.782528) (xy 29.177977 -253.750077) (xy 29.137828 -253.711368) (xy 29.103742 -253.667225)
			(xy 29.076446 -253.61859) (xy 29.056523 -253.566499) (xy 29.044397 -253.512062) (xy 29.040326 -253.45644)
			(xy 28.787852 -253.45644) (xy 28.787343 -253.484326) (xy 28.779223 -253.539502) (xy 28.763155 -253.592909)
			(xy 28.739483 -253.643406) (xy 28.70871 -253.689919) (xy 28.671493 -253.731456) (xy 28.628625 -253.767131)
			(xy 28.581019 -253.796185) (xy 28.52969 -253.817997) (xy 28.475733 -253.832103) (xy 28.420296 -253.838203)
			(xy 28.364562 -253.836166) (xy 28.309719 -253.826036) (xy 28.256935 -253.808029) (xy 28.207335 -253.782528)
			(xy 28.161977 -253.750077) (xy 28.121828 -253.711368) (xy 28.087742 -253.667225) (xy 28.060446 -253.61859)
			(xy 28.040523 -253.566499) (xy 28.028397 -253.512062) (xy 28.024326 -253.45644) (xy 27.771852 -253.45644)
			(xy 27.771343 -253.484326) (xy 27.763223 -253.539502) (xy 27.747155 -253.592909) (xy 27.723483 -253.643406)
			(xy 27.69271 -253.689919) (xy 27.655493 -253.731456) (xy 27.612625 -253.767131) (xy 27.565019 -253.796185)
			(xy 27.51369 -253.817997) (xy 27.459733 -253.832103) (xy 27.404296 -253.838203) (xy 27.348562 -253.836166)
			(xy 27.293719 -253.826036) (xy 27.240935 -253.808029) (xy 27.191335 -253.782528) (xy 27.145977 -253.750077)
			(xy 27.105828 -253.711368) (xy 27.071742 -253.667225) (xy 27.044446 -253.61859) (xy 27.024523 -253.566499)
			(xy 27.012397 -253.512062) (xy 27.008326 -253.45644) (xy 26.755852 -253.45644) (xy 26.755343 -253.484326)
			(xy 26.747223 -253.539502) (xy 26.731155 -253.592909) (xy 26.707483 -253.643406) (xy 26.67671 -253.689919)
			(xy 26.639493 -253.731456) (xy 26.596625 -253.767131) (xy 26.549019 -253.796185) (xy 26.49769 -253.817997)
			(xy 26.443733 -253.832103) (xy 26.388296 -253.838203) (xy 26.332562 -253.836166) (xy 26.277719 -253.826036)
			(xy 26.224935 -253.808029) (xy 26.175335 -253.782528) (xy 26.129977 -253.750077) (xy 26.089828 -253.711368)
			(xy 26.055742 -253.667225) (xy 26.028446 -253.61859) (xy 26.008523 -253.566499) (xy 25.996397 -253.512062)
			(xy 25.992326 -253.45644) (xy 25.739852 -253.45644) (xy 25.739343 -253.484326) (xy 25.731223 -253.539502)
			(xy 25.715155 -253.592909) (xy 25.691483 -253.643406) (xy 25.66071 -253.689919) (xy 25.623493 -253.731456)
			(xy 25.580625 -253.767131) (xy 25.533019 -253.796185) (xy 25.48169 -253.817997) (xy 25.427733 -253.832103)
			(xy 25.372296 -253.838203) (xy 25.316562 -253.836166) (xy 25.261719 -253.826036) (xy 25.208935 -253.808029)
			(xy 25.159335 -253.782528) (xy 25.113977 -253.750077) (xy 25.073828 -253.711368) (xy 25.039742 -253.667225)
			(xy 25.012446 -253.61859) (xy 24.992523 -253.566499) (xy 24.980397 -253.512062) (xy 24.976326 -253.45644)
			(xy 24.723852 -253.45644) (xy 24.723343 -253.484326) (xy 24.715223 -253.539502) (xy 24.699155 -253.592909)
			(xy 24.675483 -253.643406) (xy 24.64471 -253.689919) (xy 24.607493 -253.731456) (xy 24.564625 -253.767131)
			(xy 24.517019 -253.796185) (xy 24.46569 -253.817997) (xy 24.411733 -253.832103) (xy 24.356296 -253.838203)
			(xy 24.300562 -253.836166) (xy 24.245719 -253.826036) (xy 24.192935 -253.808029) (xy 24.143335 -253.782528)
			(xy 24.097977 -253.750077) (xy 24.057828 -253.711368) (xy 24.023742 -253.667225) (xy 23.996446 -253.61859)
			(xy 23.976523 -253.566499) (xy 23.964397 -253.512062) (xy 23.960326 -253.45644) (xy 22.113071 -253.45644)
			(xy 22.126135 -253.484309) (xy 22.142203 -253.537716) (xy 22.150323 -253.592892) (xy 22.150832 -253.620778)
			(xy 22.150323 -253.648664) (xy 22.142203 -253.70384) (xy 22.126135 -253.757247) (xy 22.102463 -253.807744)
			(xy 22.07169 -253.854257) (xy 22.034473 -253.895794) (xy 21.991605 -253.931469) (xy 21.943999 -253.960523)
			(xy 21.89267 -253.982335) (xy 21.838713 -253.996441) (xy 21.783276 -254.002541) (xy 21.727542 -254.000504)
			(xy 21.672699 -253.990374) (xy 21.619915 -253.972367) (xy 21.570315 -253.946866) (xy 21.524957 -253.914415)
			(xy 21.484808 -253.875706) (xy 21.450722 -253.831563) (xy 21.423426 -253.782928) (xy 21.403503 -253.730837)
			(xy 21.391377 -253.6764) (xy 21.387306 -253.620778) (xy 1.660398 -253.620778) (xy 1.660398 -255.732026)
			(xy 3.944364 -255.732026) (xy 3.948435 -255.676404) (xy 3.960561 -255.621967) (xy 3.980484 -255.569876)
			(xy 4.00778 -255.521241) (xy 4.041866 -255.477098) (xy 4.082015 -255.438389) (xy 4.127373 -255.405938)
			(xy 4.176973 -255.380437) (xy 4.229757 -255.36243) (xy 4.2846 -255.3523) (xy 4.340334 -255.350263)
			(xy 4.395771 -255.356363) (xy 4.449728 -255.370469) (xy 4.501057 -255.392281) (xy 4.548663 -255.421335)
			(xy 4.591531 -255.45701) (xy 4.628748 -255.498547) (xy 4.659521 -255.54506) (xy 4.683193 -255.595557)
			(xy 4.692308 -255.625854) (xy 5.829806 -255.625854) (xy 5.833877 -255.570232) (xy 5.846003 -255.515795)
			(xy 5.865926 -255.463704) (xy 5.893222 -255.415069) (xy 5.927308 -255.370926) (xy 5.967457 -255.332217)
			(xy 6.012815 -255.299766) (xy 6.062415 -255.274265) (xy 6.115199 -255.256258) (xy 6.170042 -255.246128)
			(xy 6.225776 -255.244091) (xy 6.281213 -255.250191) (xy 6.33517 -255.264297) (xy 6.386499 -255.286109)
			(xy 6.434105 -255.315163) (xy 6.476973 -255.350838) (xy 6.51419 -255.392375) (xy 6.544963 -255.438888)
			(xy 6.568635 -255.489385) (xy 6.584703 -255.542792) (xy 6.592823 -255.597968) (xy 6.593332 -255.625854)
			(xy 6.592831 -255.653286) (xy 7.359648 -255.653286) (xy 7.363719 -255.597664) (xy 7.375845 -255.543227)
			(xy 7.395768 -255.491136) (xy 7.423064 -255.442501) (xy 7.45715 -255.398358) (xy 7.497299 -255.359649)
			(xy 7.542657 -255.327198) (xy 7.592257 -255.301697) (xy 7.645041 -255.28369) (xy 7.699884 -255.27356)
			(xy 7.755618 -255.271523) (xy 7.811055 -255.277623) (xy 7.865012 -255.291729) (xy 7.916341 -255.313541)
			(xy 7.963947 -255.342595) (xy 8.006815 -255.37827) (xy 8.044032 -255.419807) (xy 8.074805 -255.46632)
			(xy 8.098477 -255.516817) (xy 8.114545 -255.570224) (xy 8.119741 -255.605534) (xy 8.896348 -255.605534)
			(xy 8.900419 -255.549912) (xy 8.912545 -255.495475) (xy 8.932468 -255.443384) (xy 8.959764 -255.394749)
			(xy 8.99385 -255.350606) (xy 9.033999 -255.311897) (xy 9.079357 -255.279446) (xy 9.128957 -255.253945)
			(xy 9.181741 -255.235938) (xy 9.236584 -255.225808) (xy 9.292318 -255.223771) (xy 9.347755 -255.229871)
			(xy 9.401712 -255.243977) (xy 9.453041 -255.265789) (xy 9.500647 -255.294843) (xy 9.543515 -255.330518)
			(xy 9.580732 -255.372055) (xy 9.611505 -255.418568) (xy 9.635177 -255.469065) (xy 9.651245 -255.522472)
			(xy 9.659365 -255.577648) (xy 9.659874 -255.605534) (xy 9.659365 -255.63342) (xy 9.651245 -255.688596)
			(xy 9.644369 -255.711452) (xy 10.405362 -255.711452) (xy 10.409433 -255.65583) (xy 10.421559 -255.601393)
			(xy 10.441482 -255.549302) (xy 10.468778 -255.500667) (xy 10.502864 -255.456524) (xy 10.543013 -255.417815)
			(xy 10.588371 -255.385364) (xy 10.637971 -255.359863) (xy 10.690755 -255.341856) (xy 10.745598 -255.331726)
			(xy 10.801332 -255.329689) (xy 10.856769 -255.335789) (xy 10.910726 -255.349895) (xy 10.962055 -255.371707)
			(xy 11.009661 -255.400761) (xy 11.052529 -255.436436) (xy 11.089746 -255.477973) (xy 11.120519 -255.524486)
			(xy 11.144191 -255.574983) (xy 11.160259 -255.62839) (xy 11.16396 -255.65354) (xy 11.983464 -255.65354)
			(xy 11.987535 -255.597918) (xy 11.999661 -255.543481) (xy 12.019584 -255.49139) (xy 12.04688 -255.442755)
			(xy 12.080966 -255.398612) (xy 12.121115 -255.359903) (xy 12.166473 -255.327452) (xy 12.216073 -255.301951)
			(xy 12.268857 -255.283944) (xy 12.3237 -255.273814) (xy 12.379434 -255.271777) (xy 12.434871 -255.277877)
			(xy 12.488828 -255.291983) (xy 12.540157 -255.313795) (xy 12.587763 -255.342849) (xy 12.630631 -255.378524)
			(xy 12.667848 -255.420061) (xy 12.698621 -255.466574) (xy 12.722293 -255.517071) (xy 12.738361 -255.570478)
			(xy 12.746481 -255.625654) (xy 12.74699 -255.65354) (xy 12.746481 -255.681426) (xy 12.738361 -255.736602)
			(xy 12.722293 -255.790009) (xy 12.698621 -255.840506) (xy 12.667848 -255.887019) (xy 12.64673 -255.910588)
			(xy 21.87651 -255.910588) (xy 21.880581 -255.854966) (xy 21.892707 -255.800529) (xy 21.91263 -255.748438)
			(xy 21.939926 -255.699803) (xy 21.974012 -255.65566) (xy 22.014161 -255.616951) (xy 22.059519 -255.5845)
			(xy 22.109119 -255.558999) (xy 22.161903 -255.540992) (xy 22.216746 -255.530862) (xy 22.27248 -255.528825)
			(xy 22.327917 -255.534925) (xy 22.381874 -255.549031) (xy 22.433203 -255.570843) (xy 22.480809 -255.599897)
			(xy 22.523677 -255.635572) (xy 22.558963 -255.674954) (xy 22.765453 -255.674954) (xy 22.765453 -255.620446)
			(xy 22.773211 -255.566494) (xy 22.788567 -255.514195) (xy 22.811211 -255.464614) (xy 22.84068 -255.41876)
			(xy 22.876375 -255.377567) (xy 22.91757 -255.341873) (xy 22.963424 -255.312405) (xy 23.013006 -255.289763)
			(xy 23.065306 -255.274408) (xy 23.119258 -255.266653) (xy 23.146512 -255.26619) (xy 23.176121 -255.266801)
			(xy 23.23463 -255.275939) (xy 23.291025 -255.29401) (xy 23.343949 -255.320578) (xy 23.392131 -255.355006)
			(xy 23.434414 -255.396466) (xy 23.469782 -255.443963) (xy 23.484078 -255.469898) (xy 23.491605 -255.482931)
			(xy 23.512833 -255.504246) (xy 23.539345 -255.518463) (xy 23.568845 -255.524353) (xy 23.598783 -255.521405)
			(xy 23.626568 -255.509874) (xy 23.649797 -255.490759) (xy 23.658576 -255.478534) (xy 23.673758 -255.456285)
			(xy 23.709456 -255.415951) (xy 23.750471 -255.381036) (xy 23.795986 -255.352233) (xy 23.845098 -255.330115)
			(xy 23.896832 -255.31512) (xy 23.95016 -255.307547) (xy 23.977092 -255.307084) (xy 24.004345 -255.307563)
			(xy 24.058295 -255.315319) (xy 24.110593 -255.330674) (xy 24.160173 -255.353315) (xy 24.206026 -255.382782)
			(xy 24.247219 -255.418475) (xy 24.282913 -255.459667) (xy 24.312381 -255.50552) (xy 24.335024 -255.555099)
			(xy 24.35038 -255.607397) (xy 24.358137 -255.661347) (xy 24.358137 -255.715853) (xy 24.35038 -255.769803)
			(xy 24.335024 -255.822101) (xy 24.312381 -255.87168) (xy 24.282913 -255.917533) (xy 24.247219 -255.958725)
			(xy 24.206026 -255.994418) (xy 24.160173 -256.023885) (xy 24.110593 -256.046526) (xy 24.058295 -256.061881)
			(xy 24.004345 -256.069637) (xy 23.977092 -256.0701) (xy 23.947483 -256.06949) (xy 23.888973 -256.060353)
			(xy 23.832579 -256.042282) (xy 23.779655 -256.015714) (xy 23.731472 -255.981286) (xy 23.68919 -255.939825)
			(xy 23.653822 -255.892327) (xy 23.639526 -255.866392) (xy 23.631993 -255.853363) (xy 23.610765 -255.83205)
			(xy 23.584256 -255.817834) (xy 23.554757 -255.811945) (xy 23.524821 -255.814892) (xy 23.497037 -255.82642)
			(xy 23.473808 -255.845532) (xy 23.465028 -255.857756) (xy 23.44984 -255.88) (xy 23.414143 -255.920335)
			(xy 23.37313 -255.955251) (xy 23.327616 -255.984055) (xy 23.278504 -256.006174) (xy 23.226771 -256.021169)
			(xy 23.173443 -256.028743) (xy 23.146512 -256.029206) (xy 23.119258 -256.028747) (xy 23.065306 -256.020992)
			(xy 23.013006 -256.005637) (xy 22.963424 -255.982995) (xy 22.91757 -255.953527) (xy 22.876375 -255.917833)
			(xy 22.84068 -255.87664) (xy 22.811211 -255.830786) (xy 22.788567 -255.781205) (xy 22.773211 -255.728906)
			(xy 22.765453 -255.674954) (xy 22.558963 -255.674954) (xy 22.560894 -255.677109) (xy 22.591667 -255.723622)
			(xy 22.615339 -255.774119) (xy 22.631407 -255.827526) (xy 22.639527 -255.882702) (xy 22.640036 -255.910588)
			(xy 22.639527 -255.938474) (xy 22.631407 -255.99365) (xy 22.615339 -256.047057) (xy 22.591667 -256.097554)
			(xy 22.560894 -256.144067) (xy 22.523677 -256.185604) (xy 22.480809 -256.221279) (xy 22.433203 -256.250333)
			(xy 22.381874 -256.272145) (xy 22.327917 -256.286251) (xy 22.27248 -256.292351) (xy 22.216746 -256.290314)
			(xy 22.161903 -256.280184) (xy 22.109119 -256.262177) (xy 22.059519 -256.236676) (xy 22.014161 -256.204225)
			(xy 21.974012 -256.165516) (xy 21.939926 -256.121373) (xy 21.91263 -256.072738) (xy 21.892707 -256.020647)
			(xy 21.880581 -255.96621) (xy 21.87651 -255.910588) (xy 12.64673 -255.910588) (xy 12.630631 -255.928556)
			(xy 12.587763 -255.964231) (xy 12.540157 -255.993285) (xy 12.488828 -256.015097) (xy 12.434871 -256.029203)
			(xy 12.379434 -256.035303) (xy 12.3237 -256.033266) (xy 12.268857 -256.023136) (xy 12.216073 -256.005129)
			(xy 12.166473 -255.979628) (xy 12.121115 -255.947177) (xy 12.080966 -255.908468) (xy 12.04688 -255.864325)
			(xy 12.019584 -255.81569) (xy 11.999661 -255.763599) (xy 11.987535 -255.709162) (xy 11.983464 -255.65354)
			(xy 11.16396 -255.65354) (xy 11.168379 -255.683566) (xy 11.168888 -255.711452) (xy 11.168379 -255.739338)
			(xy 11.160259 -255.794514) (xy 11.144191 -255.847921) (xy 11.120519 -255.898418) (xy 11.089746 -255.944931)
			(xy 11.052529 -255.986468) (xy 11.009661 -256.022143) (xy 10.962055 -256.051197) (xy 10.910726 -256.073009)
			(xy 10.856769 -256.087115) (xy 10.801332 -256.093215) (xy 10.745598 -256.091178) (xy 10.690755 -256.081048)
			(xy 10.637971 -256.063041) (xy 10.588371 -256.03754) (xy 10.543013 -256.005089) (xy 10.502864 -255.96638)
			(xy 10.468778 -255.922237) (xy 10.441482 -255.873602) (xy 10.421559 -255.821511) (xy 10.409433 -255.767074)
			(xy 10.405362 -255.711452) (xy 9.644369 -255.711452) (xy 9.635177 -255.742003) (xy 9.611505 -255.7925)
			(xy 9.580732 -255.839013) (xy 9.543515 -255.88055) (xy 9.500647 -255.916225) (xy 9.453041 -255.945279)
			(xy 9.401712 -255.967091) (xy 9.347755 -255.981197) (xy 9.292318 -255.987297) (xy 9.236584 -255.98526)
			(xy 9.181741 -255.97513) (xy 9.128957 -255.957123) (xy 9.079357 -255.931622) (xy 9.033999 -255.899171)
			(xy 8.99385 -255.860462) (xy 8.959764 -255.816319) (xy 8.932468 -255.767684) (xy 8.912545 -255.715593)
			(xy 8.900419 -255.661156) (xy 8.896348 -255.605534) (xy 8.119741 -255.605534) (xy 8.122665 -255.6254)
			(xy 8.123174 -255.653286) (xy 8.122665 -255.681172) (xy 8.114545 -255.736348) (xy 8.098477 -255.789755)
			(xy 8.074805 -255.840252) (xy 8.044032 -255.886765) (xy 8.006815 -255.928302) (xy 7.963947 -255.963977)
			(xy 7.916341 -255.993031) (xy 7.865012 -256.014843) (xy 7.811055 -256.028949) (xy 7.755618 -256.035049)
			(xy 7.699884 -256.033012) (xy 7.645041 -256.022882) (xy 7.592257 -256.004875) (xy 7.542657 -255.979374)
			(xy 7.497299 -255.946923) (xy 7.45715 -255.908214) (xy 7.423064 -255.864071) (xy 7.395768 -255.815436)
			(xy 7.375845 -255.763345) (xy 7.363719 -255.708908) (xy 7.359648 -255.653286) (xy 6.592831 -255.653286)
			(xy 6.592823 -255.65374) (xy 6.584703 -255.708916) (xy 6.568635 -255.762323) (xy 6.544963 -255.81282)
			(xy 6.51419 -255.859333) (xy 6.476973 -255.90087) (xy 6.434105 -255.936545) (xy 6.386499 -255.965599)
			(xy 6.33517 -255.987411) (xy 6.281213 -256.001517) (xy 6.225776 -256.007617) (xy 6.170042 -256.00558)
			(xy 6.115199 -255.99545) (xy 6.062415 -255.977443) (xy 6.012815 -255.951942) (xy 5.967457 -255.919491)
			(xy 5.927308 -255.880782) (xy 5.893222 -255.836639) (xy 5.865926 -255.788004) (xy 5.846003 -255.735913)
			(xy 5.833877 -255.681476) (xy 5.829806 -255.625854) (xy 4.692308 -255.625854) (xy 4.699261 -255.648964)
			(xy 4.707381 -255.70414) (xy 4.70789 -255.732026) (xy 4.707381 -255.759912) (xy 4.699261 -255.815088)
			(xy 4.683193 -255.868495) (xy 4.659521 -255.918992) (xy 4.628748 -255.965505) (xy 4.591531 -256.007042)
			(xy 4.548663 -256.042717) (xy 4.501057 -256.071771) (xy 4.449728 -256.093583) (xy 4.395771 -256.107689)
			(xy 4.340334 -256.113789) (xy 4.2846 -256.111752) (xy 4.229757 -256.101622) (xy 4.176973 -256.083615)
			(xy 4.127373 -256.058114) (xy 4.082015 -256.025663) (xy 4.041866 -255.986954) (xy 4.00778 -255.942811)
			(xy 3.980484 -255.894176) (xy 3.960561 -255.842085) (xy 3.948435 -255.787648) (xy 3.944364 -255.732026)
			(xy 1.660398 -255.732026) (xy 1.660398 -256.516124) (xy 3.26466 -256.516124) (xy 3.268731 -256.460502)
			(xy 3.280857 -256.406065) (xy 3.30078 -256.353974) (xy 3.328076 -256.305339) (xy 3.362162 -256.261196)
			(xy 3.402311 -256.222487) (xy 3.447669 -256.190036) (xy 3.497269 -256.164535) (xy 3.550053 -256.146528)
			(xy 3.604896 -256.136398) (xy 3.66063 -256.134361) (xy 3.716067 -256.140461) (xy 3.770024 -256.154567)
			(xy 3.821353 -256.176379) (xy 3.868959 -256.205433) (xy 3.911827 -256.241108) (xy 3.949044 -256.282645)
			(xy 3.979817 -256.329158) (xy 4.003489 -256.379655) (xy 4.019557 -256.433062) (xy 4.025875 -256.475992)
			(xy 4.752846 -256.475992) (xy 4.756917 -256.42037) (xy 4.769043 -256.365933) (xy 4.788966 -256.313842)
			(xy 4.816262 -256.265207) (xy 4.850348 -256.221064) (xy 4.890497 -256.182355) (xy 4.935855 -256.149904)
			(xy 4.985455 -256.124403) (xy 5.038239 -256.106396) (xy 5.093082 -256.096266) (xy 5.148816 -256.094229)
			(xy 5.204253 -256.100329) (xy 5.25821 -256.114435) (xy 5.309539 -256.136247) (xy 5.357145 -256.165301)
			(xy 5.400013 -256.200976) (xy 5.43723 -256.242513) (xy 5.468003 -256.289026) (xy 5.491675 -256.339523)
			(xy 5.507743 -256.39293) (xy 5.515863 -256.448106) (xy 5.516372 -256.475992) (xy 5.515863 -256.503878)
			(xy 5.511108 -256.53619) (xy 6.261352 -256.53619) (xy 6.265423 -256.480568) (xy 6.277549 -256.426131)
			(xy 6.297472 -256.37404) (xy 6.324768 -256.325405) (xy 6.358854 -256.281262) (xy 6.399003 -256.242553)
			(xy 6.444361 -256.210102) (xy 6.493961 -256.184601) (xy 6.546745 -256.166594) (xy 6.601588 -256.156464)
			(xy 6.657322 -256.154427) (xy 6.712759 -256.160527) (xy 6.766716 -256.174633) (xy 6.818045 -256.196445)
			(xy 6.865651 -256.225499) (xy 6.908519 -256.261174) (xy 6.945736 -256.302711) (xy 6.976509 -256.349224)
			(xy 7.000181 -256.399721) (xy 7.016249 -256.453128) (xy 7.019614 -256.475992) (xy 7.769604 -256.475992)
			(xy 7.773675 -256.42037) (xy 7.785801 -256.365933) (xy 7.805724 -256.313842) (xy 7.83302 -256.265207)
			(xy 7.867106 -256.221064) (xy 7.907255 -256.182355) (xy 7.952613 -256.149904) (xy 8.002213 -256.124403)
			(xy 8.054997 -256.106396) (xy 8.10984 -256.096266) (xy 8.165574 -256.094229) (xy 8.221011 -256.100329)
			(xy 8.274968 -256.114435) (xy 8.326297 -256.136247) (xy 8.373903 -256.165301) (xy 8.416771 -256.200976)
			(xy 8.453988 -256.242513) (xy 8.484761 -256.289026) (xy 8.508433 -256.339523) (xy 8.513192 -256.355342)
			(xy 9.479024 -256.355342) (xy 9.483095 -256.29972) (xy 9.495221 -256.245283) (xy 9.515144 -256.193192)
			(xy 9.54244 -256.144557) (xy 9.576526 -256.100414) (xy 9.616675 -256.061705) (xy 9.662033 -256.029254)
			(xy 9.711633 -256.003753) (xy 9.764417 -255.985746) (xy 9.81926 -255.975616) (xy 9.874994 -255.973579)
			(xy 9.930431 -255.979679) (xy 9.984388 -255.993785) (xy 10.035717 -256.015597) (xy 10.083323 -256.044651)
			(xy 10.126191 -256.080326) (xy 10.163408 -256.121863) (xy 10.194181 -256.168376) (xy 10.217853 -256.218873)
			(xy 10.233921 -256.27228) (xy 10.242041 -256.327456) (xy 10.24255 -256.355342) (xy 10.242041 -256.383228)
			(xy 10.237286 -256.41554) (xy 11.047728 -256.41554) (xy 11.051799 -256.359918) (xy 11.063925 -256.305481)
			(xy 11.083848 -256.25339) (xy 11.111144 -256.204755) (xy 11.14523 -256.160612) (xy 11.185379 -256.121903)
			(xy 11.230737 -256.089452) (xy 11.280337 -256.063951) (xy 11.333121 -256.045944) (xy 11.387964 -256.035814)
			(xy 11.443698 -256.033777) (xy 11.499135 -256.039877) (xy 11.553092 -256.053983) (xy 11.604421 -256.075795)
			(xy 11.652027 -256.104849) (xy 11.694895 -256.140524) (xy 11.732112 -256.182061) (xy 11.762885 -256.228574)
			(xy 11.786557 -256.279071) (xy 11.802625 -256.332478) (xy 11.810745 -256.387654) (xy 11.811254 -256.41554)
			(xy 11.810888 -256.435606) (xy 12.455396 -256.435606) (xy 12.459467 -256.379984) (xy 12.471593 -256.325547)
			(xy 12.491516 -256.273456) (xy 12.518812 -256.224821) (xy 12.552898 -256.180678) (xy 12.593047 -256.141969)
			(xy 12.638405 -256.109518) (xy 12.688005 -256.084017) (xy 12.740789 -256.06601) (xy 12.795632 -256.05588)
			(xy 12.851366 -256.053843) (xy 12.906803 -256.059943) (xy 12.96076 -256.074049) (xy 13.012089 -256.095861)
			(xy 13.059695 -256.124915) (xy 13.102563 -256.16059) (xy 13.13978 -256.202127) (xy 13.170553 -256.24864)
			(xy 13.194225 -256.299137) (xy 13.210293 -256.352544) (xy 13.218413 -256.40772) (xy 13.218922 -256.435606)
			(xy 13.218413 -256.463492) (xy 13.216039 -256.479621) (xy 25.279328 -256.479621) (xy 25.279328 -256.425119)
			(xy 25.287084 -256.371171) (xy 25.302439 -256.318876) (xy 25.325081 -256.269299) (xy 25.354547 -256.223449)
			(xy 25.390238 -256.182258) (xy 25.431429 -256.146567) (xy 25.477279 -256.117101) (xy 25.526856 -256.094459)
			(xy 25.579151 -256.079104) (xy 25.633099 -256.071348) (xy 25.66035 -256.070862) (xy 25.686666 -256.071314)
			(xy 25.7388 -256.078536) (xy 25.789447 -256.09285) (xy 25.837649 -256.113985) (xy 25.882491 -256.14154)
			(xy 25.923123 -256.174992) (xy 25.941274 -256.194052) (xy 25.94881 -256.201437) (xy 25.968079 -256.209972)
			(xy 25.978612 -256.210562) (xy 26.053288 -256.210562) (xy 26.06384 -256.210051) (xy 26.083136 -256.201504)
			(xy 26.090626 -256.194052) (xy 26.108758 -256.17497) (xy 26.149378 -256.14149) (xy 26.194219 -256.113919)
			(xy 26.242427 -256.09278) (xy 26.293085 -256.078477) (xy 26.34523 -256.071281) (xy 26.37155 -256.070862)
			(xy 26.398801 -256.071348) (xy 26.452749 -256.079104) (xy 26.505044 -256.094459) (xy 26.513997 -256.098548)
			(xy 27.881832 -256.098548) (xy 27.885903 -256.042926) (xy 27.898029 -255.988489) (xy 27.917952 -255.936398)
			(xy 27.945248 -255.887763) (xy 27.979334 -255.84362) (xy 28.019483 -255.804911) (xy 28.064841 -255.77246)
			(xy 28.114441 -255.746959) (xy 28.167225 -255.728952) (xy 28.222068 -255.718822) (xy 28.277802 -255.716785)
			(xy 28.333239 -255.722885) (xy 28.387196 -255.736991) (xy 28.438525 -255.758803) (xy 28.486131 -255.787857)
			(xy 28.528999 -255.823532) (xy 28.566216 -255.865069) (xy 28.596989 -255.911582) (xy 28.620661 -255.962079)
			(xy 28.636729 -256.015486) (xy 28.644849 -256.070662) (xy 28.645358 -256.098548) (xy 28.644849 -256.126434)
			(xy 28.636729 -256.18161) (xy 28.620661 -256.235017) (xy 28.596989 -256.285514) (xy 28.566216 -256.332027)
			(xy 28.528999 -256.373564) (xy 28.526173 -256.375916) (xy 28.769562 -256.375916) (xy 28.773633 -256.320294)
			(xy 28.785759 -256.265857) (xy 28.805682 -256.213766) (xy 28.832978 -256.165131) (xy 28.867064 -256.120988)
			(xy 28.907213 -256.082279) (xy 28.952571 -256.049828) (xy 29.002171 -256.024327) (xy 29.054955 -256.00632)
			(xy 29.109798 -255.99619) (xy 29.165532 -255.994153) (xy 29.220969 -256.000253) (xy 29.274926 -256.014359)
			(xy 29.326255 -256.036171) (xy 29.373861 -256.065225) (xy 29.416729 -256.1009) (xy 29.453946 -256.142437)
			(xy 29.484719 -256.18895) (xy 29.508391 -256.239447) (xy 29.524459 -256.292854) (xy 29.532579 -256.34803)
			(xy 29.533088 -256.375916) (xy 30.245048 -256.375916) (xy 30.249119 -256.320294) (xy 30.261245 -256.265857)
			(xy 30.281168 -256.213766) (xy 30.308464 -256.165131) (xy 30.34255 -256.120988) (xy 30.382699 -256.082279)
			(xy 30.428057 -256.049828) (xy 30.477657 -256.024327) (xy 30.530441 -256.00632) (xy 30.585284 -255.99619)
			(xy 30.641018 -255.994153) (xy 30.696455 -256.000253) (xy 30.750412 -256.014359) (xy 30.801741 -256.036171)
			(xy 30.849347 -256.065225) (xy 30.892215 -256.1009) (xy 30.929432 -256.142437) (xy 30.960205 -256.18895)
			(xy 30.983877 -256.239447) (xy 30.999945 -256.292854) (xy 31.008065 -256.34803) (xy 31.008574 -256.375916)
			(xy 31.134048 -256.375916) (xy 31.138119 -256.320294) (xy 31.150245 -256.265857) (xy 31.170168 -256.213766)
			(xy 31.197464 -256.165131) (xy 31.23155 -256.120988) (xy 31.271699 -256.082279) (xy 31.317057 -256.049828)
			(xy 31.366657 -256.024327) (xy 31.419441 -256.00632) (xy 31.474284 -255.99619) (xy 31.530018 -255.994153)
			(xy 31.585455 -256.000253) (xy 31.639412 -256.014359) (xy 31.690741 -256.036171) (xy 31.738347 -256.065225)
			(xy 31.781215 -256.1009) (xy 31.818432 -256.142437) (xy 31.849205 -256.18895) (xy 31.872877 -256.239447)
			(xy 31.888945 -256.292854) (xy 31.897065 -256.34803) (xy 31.897574 -256.375916) (xy 31.897065 -256.403802)
			(xy 31.888945 -256.458978) (xy 31.872877 -256.512385) (xy 31.849205 -256.562882) (xy 31.818432 -256.609395)
			(xy 31.781215 -256.650932) (xy 31.738347 -256.686607) (xy 31.690741 -256.715661) (xy 31.639412 -256.737473)
			(xy 31.585455 -256.751579) (xy 31.530018 -256.757679) (xy 31.474284 -256.755642) (xy 31.419441 -256.745512)
			(xy 31.366657 -256.727505) (xy 31.317057 -256.702004) (xy 31.271699 -256.669553) (xy 31.23155 -256.630844)
			(xy 31.197464 -256.586701) (xy 31.170168 -256.538066) (xy 31.150245 -256.485975) (xy 31.138119 -256.431538)
			(xy 31.134048 -256.375916) (xy 31.008574 -256.375916) (xy 31.008065 -256.403802) (xy 30.999945 -256.458978)
			(xy 30.983877 -256.512385) (xy 30.960205 -256.562882) (xy 30.929432 -256.609395) (xy 30.892215 -256.650932)
			(xy 30.849347 -256.686607) (xy 30.801741 -256.715661) (xy 30.750412 -256.737473) (xy 30.696455 -256.751579)
			(xy 30.641018 -256.757679) (xy 30.585284 -256.755642) (xy 30.530441 -256.745512) (xy 30.477657 -256.727505)
			(xy 30.428057 -256.702004) (xy 30.382699 -256.669553) (xy 30.34255 -256.630844) (xy 30.308464 -256.586701)
			(xy 30.281168 -256.538066) (xy 30.261245 -256.485975) (xy 30.249119 -256.431538) (xy 30.245048 -256.375916)
			(xy 29.533088 -256.375916) (xy 29.532579 -256.403802) (xy 29.524459 -256.458978) (xy 29.508391 -256.512385)
			(xy 29.484719 -256.562882) (xy 29.453946 -256.609395) (xy 29.416729 -256.650932) (xy 29.373861 -256.686607)
			(xy 29.326255 -256.715661) (xy 29.274926 -256.737473) (xy 29.220969 -256.751579) (xy 29.165532 -256.757679)
			(xy 29.109798 -256.755642) (xy 29.054955 -256.745512) (xy 29.002171 -256.727505) (xy 28.952571 -256.702004)
			(xy 28.907213 -256.669553) (xy 28.867064 -256.630844) (xy 28.832978 -256.586701) (xy 28.805682 -256.538066)
			(xy 28.785759 -256.485975) (xy 28.773633 -256.431538) (xy 28.769562 -256.375916) (xy 28.526173 -256.375916)
			(xy 28.486131 -256.409239) (xy 28.438525 -256.438293) (xy 28.387196 -256.460105) (xy 28.333239 -256.474211)
			(xy 28.277802 -256.480311) (xy 28.222068 -256.478274) (xy 28.167225 -256.468144) (xy 28.114441 -256.450137)
			(xy 28.064841 -256.424636) (xy 28.019483 -256.392185) (xy 27.979334 -256.353476) (xy 27.945248 -256.309333)
			(xy 27.917952 -256.260698) (xy 27.898029 -256.208607) (xy 27.885903 -256.15417) (xy 27.881832 -256.098548)
			(xy 26.513997 -256.098548) (xy 26.554621 -256.117101) (xy 26.600471 -256.146567) (xy 26.641662 -256.182258)
			(xy 26.677353 -256.223449) (xy 26.706819 -256.269299) (xy 26.729461 -256.318876) (xy 26.744816 -256.371171)
			(xy 26.752572 -256.425119) (xy 26.752572 -256.479621) (xy 26.744816 -256.533569) (xy 26.729461 -256.585864)
			(xy 26.706819 -256.635441) (xy 26.677353 -256.681291) (xy 26.641662 -256.722482) (xy 26.600471 -256.758173)
			(xy 26.554621 -256.787639) (xy 26.505044 -256.810281) (xy 26.452749 -256.825636) (xy 26.398801 -256.833392)
			(xy 26.37155 -256.833878) (xy 26.345233 -256.833445) (xy 26.293098 -256.826222) (xy 26.242449 -256.811905)
			(xy 26.194247 -256.790767) (xy 26.149406 -256.763208) (xy 26.108775 -256.72975) (xy 26.090626 -256.710688)
			(xy 26.083098 -256.703294) (xy 26.063823 -256.694766) (xy 26.053288 -256.694178) (xy 25.978612 -256.694178)
			(xy 25.968062 -256.694706) (xy 25.948767 -256.703243) (xy 25.941274 -256.710688) (xy 25.92315 -256.729778)
			(xy 25.882527 -256.763255) (xy 25.837685 -256.790825) (xy 25.789475 -256.811962) (xy 25.738816 -256.826264)
			(xy 25.68667 -256.833459) (xy 25.66035 -256.833878) (xy 25.633099 -256.833392) (xy 25.579151 -256.825636)
			(xy 25.526856 -256.810281) (xy 25.477279 -256.787639) (xy 25.431429 -256.758173) (xy 25.390238 -256.722482)
			(xy 25.354547 -256.681291) (xy 25.325081 -256.635441) (xy 25.302439 -256.585864) (xy 25.287084 -256.533569)
			(xy 25.279328 -256.479621) (xy 13.216039 -256.479621) (xy 13.210293 -256.518668) (xy 13.194225 -256.572075)
			(xy 13.170553 -256.622572) (xy 13.13978 -256.669085) (xy 13.102563 -256.710622) (xy 13.059695 -256.746297)
			(xy 13.012089 -256.775351) (xy 12.96076 -256.797163) (xy 12.906803 -256.811269) (xy 12.851366 -256.817369)
			(xy 12.795632 -256.815332) (xy 12.740789 -256.805202) (xy 12.688005 -256.787195) (xy 12.638405 -256.761694)
			(xy 12.593047 -256.729243) (xy 12.552898 -256.690534) (xy 12.518812 -256.646391) (xy 12.491516 -256.597756)
			(xy 12.471593 -256.545665) (xy 12.459467 -256.491228) (xy 12.455396 -256.435606) (xy 11.810888 -256.435606)
			(xy 11.810745 -256.443426) (xy 11.802625 -256.498602) (xy 11.786557 -256.552009) (xy 11.762885 -256.602506)
			(xy 11.732112 -256.649019) (xy 11.694895 -256.690556) (xy 11.652027 -256.726231) (xy 11.604421 -256.755285)
			(xy 11.553092 -256.777097) (xy 11.499135 -256.791203) (xy 11.443698 -256.797303) (xy 11.387964 -256.795266)
			(xy 11.333121 -256.785136) (xy 11.280337 -256.767129) (xy 11.230737 -256.741628) (xy 11.185379 -256.709177)
			(xy 11.14523 -256.670468) (xy 11.111144 -256.626325) (xy 11.083848 -256.57769) (xy 11.063925 -256.525599)
			(xy 11.051799 -256.471162) (xy 11.047728 -256.41554) (xy 10.237286 -256.41554) (xy 10.233921 -256.438404)
			(xy 10.217853 -256.491811) (xy 10.194181 -256.542308) (xy 10.163408 -256.588821) (xy 10.126191 -256.630358)
			(xy 10.083323 -256.666033) (xy 10.035717 -256.695087) (xy 9.984388 -256.716899) (xy 9.930431 -256.731005)
			(xy 9.874994 -256.737105) (xy 9.81926 -256.735068) (xy 9.764417 -256.724938) (xy 9.711633 -256.706931)
			(xy 9.662033 -256.68143) (xy 9.616675 -256.648979) (xy 9.576526 -256.61027) (xy 9.54244 -256.566127)
			(xy 9.515144 -256.517492) (xy 9.495221 -256.465401) (xy 9.483095 -256.410964) (xy 9.479024 -256.355342)
			(xy 8.513192 -256.355342) (xy 8.524501 -256.39293) (xy 8.532621 -256.448106) (xy 8.53313 -256.475992)
			(xy 8.532621 -256.503878) (xy 8.524501 -256.559054) (xy 8.508433 -256.612461) (xy 8.484761 -256.662958)
			(xy 8.453988 -256.709471) (xy 8.416771 -256.751008) (xy 8.373903 -256.786683) (xy 8.326297 -256.815737)
			(xy 8.274968 -256.837549) (xy 8.221011 -256.851655) (xy 8.165574 -256.857755) (xy 8.10984 -256.855718)
			(xy 8.054997 -256.845588) (xy 8.002213 -256.827581) (xy 7.952613 -256.80208) (xy 7.907255 -256.769629)
			(xy 7.867106 -256.73092) (xy 7.83302 -256.686777) (xy 7.805724 -256.638142) (xy 7.785801 -256.586051)
			(xy 7.773675 -256.531614) (xy 7.769604 -256.475992) (xy 7.019614 -256.475992) (xy 7.024369 -256.508304)
			(xy 7.024878 -256.53619) (xy 7.024369 -256.564076) (xy 7.016249 -256.619252) (xy 7.000181 -256.672659)
			(xy 6.976509 -256.723156) (xy 6.945736 -256.769669) (xy 6.908519 -256.811206) (xy 6.865651 -256.846881)
			(xy 6.818045 -256.875935) (xy 6.766716 -256.897747) (xy 6.712759 -256.911853) (xy 6.657322 -256.917953)
			(xy 6.601588 -256.915916) (xy 6.546745 -256.905786) (xy 6.493961 -256.887779) (xy 6.444361 -256.862278)
			(xy 6.399003 -256.829827) (xy 6.358854 -256.791118) (xy 6.324768 -256.746975) (xy 6.297472 -256.69834)
			(xy 6.277549 -256.646249) (xy 6.265423 -256.591812) (xy 6.261352 -256.53619) (xy 5.511108 -256.53619)
			(xy 5.507743 -256.559054) (xy 5.491675 -256.612461) (xy 5.468003 -256.662958) (xy 5.43723 -256.709471)
			(xy 5.400013 -256.751008) (xy 5.357145 -256.786683) (xy 5.309539 -256.815737) (xy 5.25821 -256.837549)
			(xy 5.204253 -256.851655) (xy 5.148816 -256.857755) (xy 5.093082 -256.855718) (xy 5.038239 -256.845588)
			(xy 4.985455 -256.827581) (xy 4.935855 -256.80208) (xy 4.890497 -256.769629) (xy 4.850348 -256.73092)
			(xy 4.816262 -256.686777) (xy 4.788966 -256.638142) (xy 4.769043 -256.586051) (xy 4.756917 -256.531614)
			(xy 4.752846 -256.475992) (xy 4.025875 -256.475992) (xy 4.027677 -256.488238) (xy 4.028186 -256.516124)
			(xy 4.027677 -256.54401) (xy 4.019557 -256.599186) (xy 4.003489 -256.652593) (xy 3.979817 -256.70309)
			(xy 3.949044 -256.749603) (xy 3.911827 -256.79114) (xy 3.868959 -256.826815) (xy 3.821353 -256.855869)
			(xy 3.770024 -256.877681) (xy 3.716067 -256.891787) (xy 3.66063 -256.897887) (xy 3.604896 -256.89585)
			(xy 3.550053 -256.88572) (xy 3.497269 -256.867713) (xy 3.447669 -256.842212) (xy 3.402311 -256.809761)
			(xy 3.362162 -256.771052) (xy 3.328076 -256.726909) (xy 3.30078 -256.678274) (xy 3.280857 -256.626183)
			(xy 3.268731 -256.571746) (xy 3.26466 -256.516124) (xy 1.660398 -256.516124) (xy 1.660398 -256.987548)
			(xy 27.881832 -256.987548) (xy 27.885903 -256.931926) (xy 27.898029 -256.877489) (xy 27.917952 -256.825398)
			(xy 27.945248 -256.776763) (xy 27.979334 -256.73262) (xy 28.019483 -256.693911) (xy 28.064841 -256.66146)
			(xy 28.114441 -256.635959) (xy 28.167225 -256.617952) (xy 28.222068 -256.607822) (xy 28.277802 -256.605785)
			(xy 28.333239 -256.611885) (xy 28.387196 -256.625991) (xy 28.438525 -256.647803) (xy 28.486131 -256.676857)
			(xy 28.528999 -256.712532) (xy 28.566216 -256.754069) (xy 28.596989 -256.800582) (xy 28.620661 -256.851079)
			(xy 28.636729 -256.904486) (xy 28.644849 -256.959662) (xy 28.645358 -256.987548) (xy 28.644849 -257.015434)
			(xy 28.636729 -257.07061) (xy 28.620661 -257.124017) (xy 28.614145 -257.137916) (xy 34.296096 -257.137916)
			(xy 34.296647 -257.108534) (xy 34.305675 -257.050468) (xy 34.323505 -256.994474) (xy 34.349715 -256.941879)
			(xy 34.383683 -256.893927) (xy 34.424606 -256.851754) (xy 34.447734 -256.833624) (xy 34.457132 -256.826258)
			(xy 34.467546 -256.805684) (xy 34.46907 -256.701798) (xy 34.459164 -256.680716) (xy 34.45002 -256.67335)
			(xy 34.42817 -256.655146) (xy 34.389629 -256.613328) (xy 34.357722 -256.566252) (xy 34.333155 -256.514962)
			(xy 34.316472 -256.460593) (xy 34.308044 -256.404351) (xy 34.307526 -256.375916) (xy 34.308012 -256.348665)
			(xy 34.315768 -256.294717) (xy 34.331123 -256.242422) (xy 34.353765 -256.192845) (xy 34.383231 -256.146995)
			(xy 34.418922 -256.105804) (xy 34.460113 -256.070113) (xy 34.505963 -256.040647) (xy 34.55554 -256.018005)
			(xy 34.607835 -256.00265) (xy 34.661783 -255.994894) (xy 34.716285 -255.994894) (xy 34.770233 -256.00265)
			(xy 34.822528 -256.018005) (xy 34.872105 -256.040647) (xy 34.917955 -256.070113) (xy 34.959146 -256.105804)
			(xy 34.994837 -256.146995) (xy 35.024303 -256.192845) (xy 35.046945 -256.242422) (xy 35.0623 -256.294717)
			(xy 35.070056 -256.348665) (xy 35.070542 -256.375916) (xy 35.069999 -256.405298) (xy 35.060967 -256.463364)
			(xy 35.043134 -256.519357) (xy 35.016923 -256.571952) (xy 34.982954 -256.619904) (xy 34.942031 -256.662077)
			(xy 34.918904 -256.680208) (xy 34.909506 -256.687574) (xy 34.899092 -256.708148) (xy 34.897568 -256.812034)
			(xy 34.907474 -256.833116) (xy 34.916618 -256.840482) (xy 34.938443 -256.858714) (xy 34.976984 -256.900528)
			(xy 35.008893 -256.947598) (xy 35.033464 -256.998883) (xy 35.050153 -257.053245) (xy 35.058589 -257.109483)
			(xy 35.059112 -257.137916) (xy 35.692586 -257.137916) (xy 35.696657 -257.082294) (xy 35.708783 -257.027857)
			(xy 35.728706 -256.975766) (xy 35.756002 -256.927131) (xy 35.790088 -256.882988) (xy 35.830237 -256.844279)
			(xy 35.875595 -256.811828) (xy 35.925195 -256.786327) (xy 35.977979 -256.76832) (xy 36.032822 -256.75819)
			(xy 36.088556 -256.756153) (xy 36.143993 -256.762253) (xy 36.19795 -256.776359) (xy 36.249279 -256.798171)
			(xy 36.296885 -256.827225) (xy 36.339753 -256.8629) (xy 36.37697 -256.904437) (xy 36.407743 -256.95095)
			(xy 36.431415 -257.001447) (xy 36.447483 -257.054854) (xy 36.455603 -257.11003) (xy 36.456112 -257.137916)
			(xy 36.579046 -257.137916) (xy 36.583117 -257.082294) (xy 36.595243 -257.027857) (xy 36.615166 -256.975766)
			(xy 36.642462 -256.927131) (xy 36.676548 -256.882988) (xy 36.716697 -256.844279) (xy 36.762055 -256.811828)
			(xy 36.811655 -256.786327) (xy 36.864439 -256.76832) (xy 36.919282 -256.75819) (xy 36.975016 -256.756153)
			(xy 37.030453 -256.762253) (xy 37.08441 -256.776359) (xy 37.135739 -256.798171) (xy 37.183345 -256.827225)
			(xy 37.226213 -256.8629) (xy 37.26343 -256.904437) (xy 37.294203 -256.95095) (xy 37.317875 -257.001447)
			(xy 37.333943 -257.054854) (xy 37.342063 -257.11003) (xy 37.342572 -257.137916) (xy 37.342063 -257.165802)
			(xy 37.333943 -257.220978) (xy 37.317875 -257.274385) (xy 37.294203 -257.324882) (xy 37.26343 -257.371395)
			(xy 37.226213 -257.412932) (xy 37.183345 -257.448607) (xy 37.135739 -257.477661) (xy 37.08441 -257.499473)
			(xy 37.030453 -257.513579) (xy 36.975016 -257.519679) (xy 36.919282 -257.517642) (xy 36.864439 -257.507512)
			(xy 36.811655 -257.489505) (xy 36.762055 -257.464004) (xy 36.716697 -257.431553) (xy 36.676548 -257.392844)
			(xy 36.642462 -257.348701) (xy 36.615166 -257.300066) (xy 36.595243 -257.247975) (xy 36.583117 -257.193538)
			(xy 36.579046 -257.137916) (xy 36.456112 -257.137916) (xy 36.455603 -257.165802) (xy 36.447483 -257.220978)
			(xy 36.431415 -257.274385) (xy 36.407743 -257.324882) (xy 36.37697 -257.371395) (xy 36.339753 -257.412932)
			(xy 36.296885 -257.448607) (xy 36.249279 -257.477661) (xy 36.19795 -257.499473) (xy 36.143993 -257.513579)
			(xy 36.088556 -257.519679) (xy 36.032822 -257.517642) (xy 35.977979 -257.507512) (xy 35.925195 -257.489505)
			(xy 35.875595 -257.464004) (xy 35.830237 -257.431553) (xy 35.790088 -257.392844) (xy 35.756002 -257.348701)
			(xy 35.728706 -257.300066) (xy 35.708783 -257.247975) (xy 35.696657 -257.193538) (xy 35.692586 -257.137916)
			(xy 35.059112 -257.137916) (xy 35.058626 -257.165167) (xy 35.05087 -257.219115) (xy 35.035515 -257.27141)
			(xy 35.012873 -257.320987) (xy 34.983407 -257.366837) (xy 34.947716 -257.408028) (xy 34.906525 -257.443719)
			(xy 34.860675 -257.473185) (xy 34.811098 -257.495827) (xy 34.758803 -257.511182) (xy 34.704855 -257.518938)
			(xy 34.650353 -257.518938) (xy 34.596405 -257.511182) (xy 34.54411 -257.495827) (xy 34.494533 -257.473185)
			(xy 34.448683 -257.443719) (xy 34.407492 -257.408028) (xy 34.371801 -257.366837) (xy 34.342335 -257.320987)
			(xy 34.319693 -257.27141) (xy 34.304338 -257.219115) (xy 34.296582 -257.165167) (xy 34.296096 -257.137916)
			(xy 28.614145 -257.137916) (xy 28.596989 -257.174514) (xy 28.566216 -257.221027) (xy 28.528999 -257.262564)
			(xy 28.486131 -257.298239) (xy 28.438525 -257.327293) (xy 28.387196 -257.349105) (xy 28.333239 -257.363211)
			(xy 28.277802 -257.369311) (xy 28.222068 -257.367274) (xy 28.167225 -257.357144) (xy 28.114441 -257.339137)
			(xy 28.064841 -257.313636) (xy 28.019483 -257.281185) (xy 27.979334 -257.242476) (xy 27.945248 -257.198333)
			(xy 27.917952 -257.149698) (xy 27.898029 -257.097607) (xy 27.885903 -257.04317) (xy 27.881832 -256.987548)
			(xy 1.660398 -256.987548) (xy 1.660398 -257.60807) (xy 3.22402 -257.60807) (xy 3.228091 -257.552448)
			(xy 3.240217 -257.498011) (xy 3.26014 -257.44592) (xy 3.287436 -257.397285) (xy 3.321522 -257.353142)
			(xy 3.361671 -257.314433) (xy 3.407029 -257.281982) (xy 3.456629 -257.256481) (xy 3.509413 -257.238474)
			(xy 3.564256 -257.228344) (xy 3.61999 -257.226307) (xy 3.675427 -257.232407) (xy 3.729384 -257.246513)
			(xy 3.780713 -257.268325) (xy 3.828319 -257.297379) (xy 3.871187 -257.333054) (xy 3.908404 -257.374591)
			(xy 3.939177 -257.421104) (xy 3.962849 -257.471601) (xy 3.978917 -257.525008) (xy 3.987037 -257.580184)
			(xy 3.987546 -257.60807) (xy 4.74802 -257.60807) (xy 4.752091 -257.552448) (xy 4.764217 -257.498011)
			(xy 4.78414 -257.44592) (xy 4.811436 -257.397285) (xy 4.845522 -257.353142) (xy 4.885671 -257.314433)
			(xy 4.931029 -257.281982) (xy 4.980629 -257.256481) (xy 5.033413 -257.238474) (xy 5.088256 -257.228344)
			(xy 5.14399 -257.226307) (xy 5.199427 -257.232407) (xy 5.253384 -257.246513) (xy 5.304713 -257.268325)
			(xy 5.352319 -257.297379) (xy 5.395187 -257.333054) (xy 5.432404 -257.374591) (xy 5.463177 -257.421104)
			(xy 5.486849 -257.471601) (xy 5.502917 -257.525008) (xy 5.511037 -257.580184) (xy 5.511546 -257.60807)
			(xy 7.03402 -257.60807) (xy 7.038091 -257.552448) (xy 7.050217 -257.498011) (xy 7.07014 -257.44592)
			(xy 7.097436 -257.397285) (xy 7.131522 -257.353142) (xy 7.171671 -257.314433) (xy 7.217029 -257.281982)
			(xy 7.266629 -257.256481) (xy 7.319413 -257.238474) (xy 7.374256 -257.228344) (xy 7.42999 -257.226307)
			(xy 7.485427 -257.232407) (xy 7.539384 -257.246513) (xy 7.590713 -257.268325) (xy 7.638319 -257.297379)
			(xy 7.681187 -257.333054) (xy 7.718404 -257.374591) (xy 7.749177 -257.421104) (xy 7.772849 -257.471601)
			(xy 7.788917 -257.525008) (xy 7.797037 -257.580184) (xy 7.797546 -257.60807) (xy 8.55802 -257.60807)
			(xy 8.562091 -257.552448) (xy 8.574217 -257.498011) (xy 8.59414 -257.44592) (xy 8.621436 -257.397285)
			(xy 8.655522 -257.353142) (xy 8.695671 -257.314433) (xy 8.741029 -257.281982) (xy 8.790629 -257.256481)
			(xy 8.843413 -257.238474) (xy 8.898256 -257.228344) (xy 8.95399 -257.226307) (xy 9.009427 -257.232407)
			(xy 9.063384 -257.246513) (xy 9.114713 -257.268325) (xy 9.162319 -257.297379) (xy 9.205187 -257.333054)
			(xy 9.242404 -257.374591) (xy 9.273177 -257.421104) (xy 9.296849 -257.471601) (xy 9.312917 -257.525008)
			(xy 9.321037 -257.580184) (xy 9.321546 -257.60807) (xy 10.08202 -257.60807) (xy 10.086091 -257.552448)
			(xy 10.098217 -257.498011) (xy 10.11814 -257.44592) (xy 10.145436 -257.397285) (xy 10.179522 -257.353142)
			(xy 10.219671 -257.314433) (xy 10.265029 -257.281982) (xy 10.314629 -257.256481) (xy 10.367413 -257.238474)
			(xy 10.422256 -257.228344) (xy 10.47799 -257.226307) (xy 10.533427 -257.232407) (xy 10.587384 -257.246513)
			(xy 10.638713 -257.268325) (xy 10.686319 -257.297379) (xy 10.729187 -257.333054) (xy 10.766404 -257.374591)
			(xy 10.797177 -257.421104) (xy 10.820849 -257.471601) (xy 10.836917 -257.525008) (xy 10.845037 -257.580184)
			(xy 10.845546 -257.60807) (xy 11.60602 -257.60807) (xy 11.610091 -257.552448) (xy 11.622217 -257.498011)
			(xy 11.64214 -257.44592) (xy 11.669436 -257.397285) (xy 11.703522 -257.353142) (xy 11.743671 -257.314433)
			(xy 11.789029 -257.281982) (xy 11.838629 -257.256481) (xy 11.891413 -257.238474) (xy 11.946256 -257.228344)
			(xy 12.00199 -257.226307) (xy 12.057427 -257.232407) (xy 12.111384 -257.246513) (xy 12.162713 -257.268325)
			(xy 12.210319 -257.297379) (xy 12.253187 -257.333054) (xy 12.290404 -257.374591) (xy 12.321177 -257.421104)
			(xy 12.344849 -257.471601) (xy 12.360917 -257.525008) (xy 12.369037 -257.580184) (xy 12.369546 -257.60807)
			(xy 13.13002 -257.60807) (xy 13.134091 -257.552448) (xy 13.146217 -257.498011) (xy 13.16614 -257.44592)
			(xy 13.193436 -257.397285) (xy 13.227522 -257.353142) (xy 13.267671 -257.314433) (xy 13.313029 -257.281982)
			(xy 13.362629 -257.256481) (xy 13.415413 -257.238474) (xy 13.470256 -257.228344) (xy 13.52599 -257.226307)
			(xy 13.581427 -257.232407) (xy 13.635384 -257.246513) (xy 13.686713 -257.268325) (xy 13.734319 -257.297379)
			(xy 13.777187 -257.333054) (xy 13.814404 -257.374591) (xy 13.845177 -257.421104) (xy 13.868849 -257.471601)
			(xy 13.869635 -257.474212) (xy 21.97176 -257.474212) (xy 21.975831 -257.41859) (xy 21.987957 -257.364153)
			(xy 22.00788 -257.312062) (xy 22.035176 -257.263427) (xy 22.069262 -257.219284) (xy 22.109411 -257.180575)
			(xy 22.154769 -257.148124) (xy 22.204369 -257.122623) (xy 22.257153 -257.104616) (xy 22.311996 -257.094486)
			(xy 22.36773 -257.092449) (xy 22.423167 -257.098549) (xy 22.477124 -257.112655) (xy 22.528453 -257.134467)
			(xy 22.576059 -257.163521) (xy 22.618927 -257.199196) (xy 22.656144 -257.240733) (xy 22.686917 -257.287246)
			(xy 22.710589 -257.337743) (xy 22.726657 -257.39115) (xy 22.734777 -257.446326) (xy 22.735286 -257.474212)
			(xy 22.734777 -257.502098) (xy 22.726657 -257.557274) (xy 22.710589 -257.610681) (xy 22.686917 -257.661178)
			(xy 22.656144 -257.707691) (xy 22.618927 -257.749228) (xy 22.576059 -257.784903) (xy 22.528453 -257.813957)
			(xy 22.477124 -257.835769) (xy 22.423167 -257.849875) (xy 22.36773 -257.855975) (xy 22.311996 -257.853938)
			(xy 22.257153 -257.843808) (xy 22.204369 -257.825801) (xy 22.154769 -257.8003) (xy 22.109411 -257.767849)
			(xy 22.069262 -257.72914) (xy 22.035176 -257.684997) (xy 22.00788 -257.636362) (xy 21.987957 -257.584271)
			(xy 21.975831 -257.529834) (xy 21.97176 -257.474212) (xy 13.869635 -257.474212) (xy 13.884917 -257.525008)
			(xy 13.893037 -257.580184) (xy 13.893546 -257.60807) (xy 13.893037 -257.635956) (xy 13.884917 -257.691132)
			(xy 13.868849 -257.744539) (xy 13.845177 -257.795036) (xy 13.814404 -257.841549) (xy 13.777187 -257.883086)
			(xy 13.734319 -257.918761) (xy 13.686713 -257.947815) (xy 13.635384 -257.969627) (xy 13.581427 -257.983733)
			(xy 13.52599 -257.989833) (xy 13.470256 -257.987796) (xy 13.415413 -257.977666) (xy 13.362629 -257.959659)
			(xy 13.313029 -257.934158) (xy 13.267671 -257.901707) (xy 13.227522 -257.862998) (xy 13.193436 -257.818855)
			(xy 13.16614 -257.77022) (xy 13.146217 -257.718129) (xy 13.134091 -257.663692) (xy 13.13002 -257.60807)
			(xy 12.369546 -257.60807) (xy 12.369037 -257.635956) (xy 12.360917 -257.691132) (xy 12.344849 -257.744539)
			(xy 12.321177 -257.795036) (xy 12.290404 -257.841549) (xy 12.253187 -257.883086) (xy 12.210319 -257.918761)
			(xy 12.162713 -257.947815) (xy 12.111384 -257.969627) (xy 12.057427 -257.983733) (xy 12.00199 -257.989833)
			(xy 11.946256 -257.987796) (xy 11.891413 -257.977666) (xy 11.838629 -257.959659) (xy 11.789029 -257.934158)
			(xy 11.743671 -257.901707) (xy 11.703522 -257.862998) (xy 11.669436 -257.818855) (xy 11.64214 -257.77022)
			(xy 11.622217 -257.718129) (xy 11.610091 -257.663692) (xy 11.60602 -257.60807) (xy 10.845546 -257.60807)
			(xy 10.845037 -257.635956) (xy 10.836917 -257.691132) (xy 10.820849 -257.744539) (xy 10.797177 -257.795036)
			(xy 10.766404 -257.841549) (xy 10.729187 -257.883086) (xy 10.686319 -257.918761) (xy 10.638713 -257.947815)
			(xy 10.587384 -257.969627) (xy 10.533427 -257.983733) (xy 10.47799 -257.989833) (xy 10.422256 -257.987796)
			(xy 10.367413 -257.977666) (xy 10.314629 -257.959659) (xy 10.265029 -257.934158) (xy 10.219671 -257.901707)
			(xy 10.179522 -257.862998) (xy 10.145436 -257.818855) (xy 10.11814 -257.77022) (xy 10.098217 -257.718129)
			(xy 10.086091 -257.663692) (xy 10.08202 -257.60807) (xy 9.321546 -257.60807) (xy 9.321037 -257.635956)
			(xy 9.312917 -257.691132) (xy 9.296849 -257.744539) (xy 9.273177 -257.795036) (xy 9.242404 -257.841549)
			(xy 9.205187 -257.883086) (xy 9.162319 -257.918761) (xy 9.114713 -257.947815) (xy 9.063384 -257.969627)
			(xy 9.009427 -257.983733) (xy 8.95399 -257.989833) (xy 8.898256 -257.987796) (xy 8.843413 -257.977666)
			(xy 8.790629 -257.959659) (xy 8.741029 -257.934158) (xy 8.695671 -257.901707) (xy 8.655522 -257.862998)
			(xy 8.621436 -257.818855) (xy 8.59414 -257.77022) (xy 8.574217 -257.718129) (xy 8.562091 -257.663692)
			(xy 8.55802 -257.60807) (xy 7.797546 -257.60807) (xy 7.797037 -257.635956) (xy 7.788917 -257.691132)
			(xy 7.772849 -257.744539) (xy 7.749177 -257.795036) (xy 7.718404 -257.841549) (xy 7.681187 -257.883086)
			(xy 7.638319 -257.918761) (xy 7.590713 -257.947815) (xy 7.539384 -257.969627) (xy 7.485427 -257.983733)
			(xy 7.42999 -257.989833) (xy 7.374256 -257.987796) (xy 7.319413 -257.977666) (xy 7.266629 -257.959659)
			(xy 7.217029 -257.934158) (xy 7.171671 -257.901707) (xy 7.131522 -257.862998) (xy 7.097436 -257.818855)
			(xy 7.07014 -257.77022) (xy 7.050217 -257.718129) (xy 7.038091 -257.663692) (xy 7.03402 -257.60807)
			(xy 5.511546 -257.60807) (xy 5.511037 -257.635956) (xy 5.502917 -257.691132) (xy 5.486849 -257.744539)
			(xy 5.463177 -257.795036) (xy 5.432404 -257.841549) (xy 5.395187 -257.883086) (xy 5.352319 -257.918761)
			(xy 5.304713 -257.947815) (xy 5.253384 -257.969627) (xy 5.199427 -257.983733) (xy 5.14399 -257.989833)
			(xy 5.088256 -257.987796) (xy 5.033413 -257.977666) (xy 4.980629 -257.959659) (xy 4.931029 -257.934158)
			(xy 4.885671 -257.901707) (xy 4.845522 -257.862998) (xy 4.811436 -257.818855) (xy 4.78414 -257.77022)
			(xy 4.764217 -257.718129) (xy 4.752091 -257.663692) (xy 4.74802 -257.60807) (xy 3.987546 -257.60807)
			(xy 3.987037 -257.635956) (xy 3.978917 -257.691132) (xy 3.962849 -257.744539) (xy 3.939177 -257.795036)
			(xy 3.908404 -257.841549) (xy 3.871187 -257.883086) (xy 3.828319 -257.918761) (xy 3.780713 -257.947815)
			(xy 3.729384 -257.969627) (xy 3.675427 -257.983733) (xy 3.61999 -257.989833) (xy 3.564256 -257.987796)
			(xy 3.509413 -257.977666) (xy 3.456629 -257.959659) (xy 3.407029 -257.934158) (xy 3.361671 -257.901707)
			(xy 3.321522 -257.862998) (xy 3.287436 -257.818855) (xy 3.26014 -257.77022) (xy 3.240217 -257.718129)
			(xy 3.228091 -257.663692) (xy 3.22402 -257.60807) (xy 1.660398 -257.60807) (xy 1.660398 -258.510786)
			(xy 3.22402 -258.510786) (xy 3.228091 -258.455164) (xy 3.240217 -258.400727) (xy 3.26014 -258.348636)
			(xy 3.287436 -258.300001) (xy 3.321522 -258.255858) (xy 3.361671 -258.217149) (xy 3.407029 -258.184698)
			(xy 3.456629 -258.159197) (xy 3.509413 -258.14119) (xy 3.564256 -258.13106) (xy 3.61999 -258.129023)
			(xy 3.675427 -258.135123) (xy 3.729384 -258.149229) (xy 3.780713 -258.171041) (xy 3.828319 -258.200095)
			(xy 3.871187 -258.23577) (xy 3.908404 -258.277307) (xy 3.939177 -258.32382) (xy 3.962849 -258.374317)
			(xy 3.978917 -258.427724) (xy 3.987037 -258.4829) (xy 3.987546 -258.510786) (xy 4.74802 -258.510786)
			(xy 4.752091 -258.455164) (xy 4.764217 -258.400727) (xy 4.78414 -258.348636) (xy 4.811436 -258.300001)
			(xy 4.845522 -258.255858) (xy 4.885671 -258.217149) (xy 4.931029 -258.184698) (xy 4.980629 -258.159197)
			(xy 5.033413 -258.14119) (xy 5.088256 -258.13106) (xy 5.14399 -258.129023) (xy 5.199427 -258.135123)
			(xy 5.253384 -258.149229) (xy 5.304713 -258.171041) (xy 5.352319 -258.200095) (xy 5.395187 -258.23577)
			(xy 5.432404 -258.277307) (xy 5.463177 -258.32382) (xy 5.486849 -258.374317) (xy 5.502917 -258.427724)
			(xy 5.511037 -258.4829) (xy 5.511546 -258.510786) (xy 6.27202 -258.510786) (xy 6.276091 -258.455164)
			(xy 6.288217 -258.400727) (xy 6.30814 -258.348636) (xy 6.335436 -258.300001) (xy 6.369522 -258.255858)
			(xy 6.409671 -258.217149) (xy 6.455029 -258.184698) (xy 6.504629 -258.159197) (xy 6.557413 -258.14119)
			(xy 6.612256 -258.13106) (xy 6.66799 -258.129023) (xy 6.723427 -258.135123) (xy 6.777384 -258.149229)
			(xy 6.828713 -258.171041) (xy 6.876319 -258.200095) (xy 6.919187 -258.23577) (xy 6.956404 -258.277307)
			(xy 6.987177 -258.32382) (xy 7.010849 -258.374317) (xy 7.026917 -258.427724) (xy 7.035037 -258.4829)
			(xy 7.035546 -258.510786) (xy 7.79602 -258.510786) (xy 7.800091 -258.455164) (xy 7.812217 -258.400727)
			(xy 7.83214 -258.348636) (xy 7.859436 -258.300001) (xy 7.893522 -258.255858) (xy 7.933671 -258.217149)
			(xy 7.979029 -258.184698) (xy 8.028629 -258.159197) (xy 8.081413 -258.14119) (xy 8.136256 -258.13106)
			(xy 8.19199 -258.129023) (xy 8.247427 -258.135123) (xy 8.301384 -258.149229) (xy 8.352713 -258.171041)
			(xy 8.400319 -258.200095) (xy 8.443187 -258.23577) (xy 8.480404 -258.277307) (xy 8.511177 -258.32382)
			(xy 8.534849 -258.374317) (xy 8.550917 -258.427724) (xy 8.559037 -258.4829) (xy 8.559546 -258.510786)
			(xy 9.32002 -258.510786) (xy 9.324091 -258.455164) (xy 9.336217 -258.400727) (xy 9.35614 -258.348636)
			(xy 9.383436 -258.300001) (xy 9.417522 -258.255858) (xy 9.457671 -258.217149) (xy 9.503029 -258.184698)
			(xy 9.552629 -258.159197) (xy 9.605413 -258.14119) (xy 9.660256 -258.13106) (xy 9.71599 -258.129023)
			(xy 9.771427 -258.135123) (xy 9.825384 -258.149229) (xy 9.876713 -258.171041) (xy 9.924319 -258.200095)
			(xy 9.967187 -258.23577) (xy 10.004404 -258.277307) (xy 10.035177 -258.32382) (xy 10.058849 -258.374317)
			(xy 10.074917 -258.427724) (xy 10.083037 -258.4829) (xy 10.083546 -258.510786) (xy 10.84402 -258.510786)
			(xy 10.848091 -258.455164) (xy 10.860217 -258.400727) (xy 10.88014 -258.348636) (xy 10.907436 -258.300001)
			(xy 10.941522 -258.255858) (xy 10.981671 -258.217149) (xy 11.027029 -258.184698) (xy 11.076629 -258.159197)
			(xy 11.129413 -258.14119) (xy 11.184256 -258.13106) (xy 11.23999 -258.129023) (xy 11.295427 -258.135123)
			(xy 11.349384 -258.149229) (xy 11.400713 -258.171041) (xy 11.448319 -258.200095) (xy 11.491187 -258.23577)
			(xy 11.528404 -258.277307) (xy 11.559177 -258.32382) (xy 11.582849 -258.374317) (xy 11.598917 -258.427724)
			(xy 11.607037 -258.4829) (xy 11.607546 -258.510786) (xy 11.607037 -258.538672) (xy 11.602805 -258.567428)
			(xy 11.988798 -258.567428) (xy 11.992869 -258.511806) (xy 12.004995 -258.457369) (xy 12.024918 -258.405278)
			(xy 12.052214 -258.356643) (xy 12.0863 -258.3125) (xy 12.126449 -258.273791) (xy 12.171807 -258.24134)
			(xy 12.221407 -258.215839) (xy 12.274191 -258.197832) (xy 12.329034 -258.187702) (xy 12.384768 -258.185665)
			(xy 12.440205 -258.191765) (xy 12.494162 -258.205871) (xy 12.545491 -258.227683) (xy 12.593097 -258.256737)
			(xy 12.635965 -258.292412) (xy 12.673182 -258.333949) (xy 12.703955 -258.380462) (xy 12.727627 -258.430959)
			(xy 12.743695 -258.484366) (xy 12.747583 -258.510786) (xy 13.13002 -258.510786) (xy 13.134091 -258.455164)
			(xy 13.146217 -258.400727) (xy 13.16614 -258.348636) (xy 13.193436 -258.300001) (xy 13.227522 -258.255858)
			(xy 13.267671 -258.217149) (xy 13.313029 -258.184698) (xy 13.362629 -258.159197) (xy 13.415413 -258.14119)
			(xy 13.470256 -258.13106) (xy 13.52599 -258.129023) (xy 13.581427 -258.135123) (xy 13.635384 -258.149229)
			(xy 13.686713 -258.171041) (xy 13.734319 -258.200095) (xy 13.777187 -258.23577) (xy 13.814404 -258.277307)
			(xy 13.845177 -258.32382) (xy 13.868849 -258.374317) (xy 13.884917 -258.427724) (xy 13.893037 -258.4829)
			(xy 13.893546 -258.510786) (xy 13.893037 -258.538672) (xy 13.884917 -258.593848) (xy 13.868849 -258.647255)
			(xy 13.860309 -258.665472) (xy 21.126448 -258.665472) (xy 21.130519 -258.60985) (xy 21.142645 -258.555413)
			(xy 21.162568 -258.503322) (xy 21.189864 -258.454687) (xy 21.22395 -258.410544) (xy 21.264099 -258.371835)
			(xy 21.309457 -258.339384) (xy 21.359057 -258.313883) (xy 21.411841 -258.295876) (xy 21.466684 -258.285746)
			(xy 21.522418 -258.283709) (xy 21.577855 -258.289809) (xy 21.631812 -258.303915) (xy 21.683141 -258.325727)
			(xy 21.730747 -258.354781) (xy 21.773615 -258.390456) (xy 21.810832 -258.431993) (xy 21.841605 -258.478506)
			(xy 21.865277 -258.529003) (xy 21.881345 -258.58241) (xy 21.889465 -258.637586) (xy 21.889691 -258.649978)
			(xy 22.926292 -258.649978) (xy 22.930363 -258.594356) (xy 22.942489 -258.539919) (xy 22.962412 -258.487828)
			(xy 22.989708 -258.439193) (xy 23.023794 -258.39505) (xy 23.063943 -258.356341) (xy 23.109301 -258.32389)
			(xy 23.158901 -258.298389) (xy 23.211685 -258.280382) (xy 23.266528 -258.270252) (xy 23.322262 -258.268215)
			(xy 23.375363 -258.274058) (xy 28.769562 -258.274058) (xy 28.773633 -258.218436) (xy 28.785759 -258.163999)
			(xy 28.805682 -258.111908) (xy 28.832978 -258.063273) (xy 28.867064 -258.01913) (xy 28.907213 -257.980421)
			(xy 28.952571 -257.94797) (xy 29.002171 -257.922469) (xy 29.054955 -257.904462) (xy 29.109798 -257.894332)
			(xy 29.165532 -257.892295) (xy 29.220969 -257.898395) (xy 29.274926 -257.912501) (xy 29.326255 -257.934313)
			(xy 29.373861 -257.963367) (xy 29.416729 -257.999042) (xy 29.453946 -258.040579) (xy 29.484719 -258.087092)
			(xy 29.508391 -258.137589) (xy 29.524459 -258.190996) (xy 29.532579 -258.246172) (xy 29.533088 -258.274058)
			(xy 30.2547 -258.274058) (xy 30.258771 -258.218436) (xy 30.270897 -258.163999) (xy 30.29082 -258.111908)
			(xy 30.318116 -258.063273) (xy 30.352202 -258.01913) (xy 30.392351 -257.980421) (xy 30.437709 -257.94797)
			(xy 30.487309 -257.922469) (xy 30.540093 -257.904462) (xy 30.594936 -257.894332) (xy 30.65067 -257.892295)
			(xy 30.706107 -257.898395) (xy 30.760064 -257.912501) (xy 30.811393 -257.934313) (xy 30.858999 -257.963367)
			(xy 30.901867 -257.999042) (xy 30.939084 -258.040579) (xy 30.969857 -258.087092) (xy 30.993529 -258.137589)
			(xy 31.009597 -258.190996) (xy 31.017717 -258.246172) (xy 31.018226 -258.274058) (xy 31.017717 -258.301944)
			(xy 31.009597 -258.35712) (xy 30.993529 -258.410527) (xy 30.969857 -258.461024) (xy 30.939084 -258.507537)
			(xy 30.901867 -258.549074) (xy 30.858999 -258.584749) (xy 30.811393 -258.613803) (xy 30.760064 -258.635615)
			(xy 30.706107 -258.649721) (xy 30.65067 -258.655821) (xy 30.594936 -258.653784) (xy 30.540093 -258.643654)
			(xy 30.487309 -258.625647) (xy 30.437709 -258.600146) (xy 30.392351 -258.567695) (xy 30.352202 -258.528986)
			(xy 30.318116 -258.484843) (xy 30.29082 -258.436208) (xy 30.270897 -258.384117) (xy 30.258771 -258.32968)
			(xy 30.2547 -258.274058) (xy 29.533088 -258.274058) (xy 29.532579 -258.301944) (xy 29.524459 -258.35712)
			(xy 29.508391 -258.410527) (xy 29.484719 -258.461024) (xy 29.453946 -258.507537) (xy 29.416729 -258.549074)
			(xy 29.373861 -258.584749) (xy 29.326255 -258.613803) (xy 29.274926 -258.635615) (xy 29.220969 -258.649721)
			(xy 29.165532 -258.655821) (xy 29.109798 -258.653784) (xy 29.054955 -258.643654) (xy 29.002171 -258.625647)
			(xy 28.952571 -258.600146) (xy 28.907213 -258.567695) (xy 28.867064 -258.528986) (xy 28.832978 -258.484843)
			(xy 28.805682 -258.436208) (xy 28.785759 -258.384117) (xy 28.773633 -258.32968) (xy 28.769562 -258.274058)
			(xy 23.375363 -258.274058) (xy 23.377699 -258.274315) (xy 23.431656 -258.288421) (xy 23.482985 -258.310233)
			(xy 23.530591 -258.339287) (xy 23.573459 -258.374962) (xy 23.610676 -258.416499) (xy 23.641449 -258.463012)
			(xy 23.665121 -258.513509) (xy 23.681189 -258.566916) (xy 23.689309 -258.622092) (xy 23.689818 -258.649978)
			(xy 23.689309 -258.677864) (xy 23.687357 -258.691126) (xy 24.410668 -258.691126) (xy 24.414739 -258.635504)
			(xy 24.426865 -258.581067) (xy 24.446788 -258.528976) (xy 24.474084 -258.480341) (xy 24.50817 -258.436198)
			(xy 24.548319 -258.397489) (xy 24.593677 -258.365038) (xy 24.643277 -258.339537) (xy 24.696061 -258.32153)
			(xy 24.750904 -258.3114) (xy 24.806638 -258.309363) (xy 24.862075 -258.315463) (xy 24.916032 -258.329569)
			(xy 24.967361 -258.351381) (xy 25.014967 -258.380435) (xy 25.057835 -258.41611) (xy 25.095052 -258.457647)
			(xy 25.125825 -258.50416) (xy 25.149497 -258.554657) (xy 25.165565 -258.608064) (xy 25.173685 -258.66324)
			(xy 25.174194 -258.691126) (xy 25.173685 -258.719012) (xy 25.165565 -258.774188) (xy 25.149497 -258.827595)
			(xy 25.125825 -258.878092) (xy 25.095052 -258.924605) (xy 25.057835 -258.966142) (xy 25.014967 -259.001817)
			(xy 24.967361 -259.030871) (xy 24.916032 -259.052683) (xy 24.862075 -259.066789) (xy 24.806638 -259.072889)
			(xy 24.750904 -259.070852) (xy 24.696061 -259.060722) (xy 24.643277 -259.042715) (xy 24.593677 -259.017214)
			(xy 24.548319 -258.984763) (xy 24.50817 -258.946054) (xy 24.474084 -258.901911) (xy 24.446788 -258.853276)
			(xy 24.426865 -258.801185) (xy 24.414739 -258.746748) (xy 24.410668 -258.691126) (xy 23.687357 -258.691126)
			(xy 23.681189 -258.73304) (xy 23.665121 -258.786447) (xy 23.641449 -258.836944) (xy 23.610676 -258.883457)
			(xy 23.573459 -258.924994) (xy 23.530591 -258.960669) (xy 23.482985 -258.989723) (xy 23.431656 -259.011535)
			(xy 23.377699 -259.025641) (xy 23.322262 -259.031741) (xy 23.266528 -259.029704) (xy 23.211685 -259.019574)
			(xy 23.158901 -259.001567) (xy 23.109301 -258.976066) (xy 23.063943 -258.943615) (xy 23.023794 -258.904906)
			(xy 22.989708 -258.860763) (xy 22.962412 -258.812128) (xy 22.942489 -258.760037) (xy 22.930363 -258.7056)
			(xy 22.926292 -258.649978) (xy 21.889691 -258.649978) (xy 21.889974 -258.665472) (xy 21.889465 -258.693358)
			(xy 21.881345 -258.748534) (xy 21.865277 -258.801941) (xy 21.841605 -258.852438) (xy 21.810832 -258.898951)
			(xy 21.773615 -258.940488) (xy 21.730747 -258.976163) (xy 21.683141 -259.005217) (xy 21.631812 -259.027029)
			(xy 21.577855 -259.041135) (xy 21.522418 -259.047235) (xy 21.466684 -259.045198) (xy 21.411841 -259.035068)
			(xy 21.359057 -259.017061) (xy 21.309457 -258.99156) (xy 21.264099 -258.959109) (xy 21.22395 -258.9204)
			(xy 21.189864 -258.876257) (xy 21.162568 -258.827622) (xy 21.142645 -258.775531) (xy 21.130519 -258.721094)
			(xy 21.126448 -258.665472) (xy 13.860309 -258.665472) (xy 13.845177 -258.697752) (xy 13.814404 -258.744265)
			(xy 13.777187 -258.785802) (xy 13.734319 -258.821477) (xy 13.686713 -258.850531) (xy 13.635384 -258.872343)
			(xy 13.581427 -258.886449) (xy 13.52599 -258.892549) (xy 13.470256 -258.890512) (xy 13.415413 -258.880382)
			(xy 13.362629 -258.862375) (xy 13.313029 -258.836874) (xy 13.267671 -258.804423) (xy 13.227522 -258.765714)
			(xy 13.193436 -258.721571) (xy 13.16614 -258.672936) (xy 13.146217 -258.620845) (xy 13.134091 -258.566408)
			(xy 13.13002 -258.510786) (xy 12.747583 -258.510786) (xy 12.751815 -258.539542) (xy 12.752324 -258.567428)
			(xy 12.751815 -258.595314) (xy 12.743695 -258.65049) (xy 12.727627 -258.703897) (xy 12.703955 -258.754394)
			(xy 12.673182 -258.800907) (xy 12.635965 -258.842444) (xy 12.593097 -258.878119) (xy 12.545491 -258.907173)
			(xy 12.494162 -258.928985) (xy 12.440205 -258.943091) (xy 12.384768 -258.949191) (xy 12.329034 -258.947154)
			(xy 12.274191 -258.937024) (xy 12.221407 -258.919017) (xy 12.171807 -258.893516) (xy 12.126449 -258.861065)
			(xy 12.0863 -258.822356) (xy 12.052214 -258.778213) (xy 12.024918 -258.729578) (xy 12.004995 -258.677487)
			(xy 11.992869 -258.62305) (xy 11.988798 -258.567428) (xy 11.602805 -258.567428) (xy 11.598917 -258.593848)
			(xy 11.582849 -258.647255) (xy 11.559177 -258.697752) (xy 11.528404 -258.744265) (xy 11.491187 -258.785802)
			(xy 11.448319 -258.821477) (xy 11.400713 -258.850531) (xy 11.349384 -258.872343) (xy 11.295427 -258.886449)
			(xy 11.23999 -258.892549) (xy 11.184256 -258.890512) (xy 11.129413 -258.880382) (xy 11.076629 -258.862375)
			(xy 11.027029 -258.836874) (xy 10.981671 -258.804423) (xy 10.941522 -258.765714) (xy 10.907436 -258.721571)
			(xy 10.88014 -258.672936) (xy 10.860217 -258.620845) (xy 10.848091 -258.566408) (xy 10.84402 -258.510786)
			(xy 10.083546 -258.510786) (xy 10.083037 -258.538672) (xy 10.074917 -258.593848) (xy 10.058849 -258.647255)
			(xy 10.035177 -258.697752) (xy 10.004404 -258.744265) (xy 9.967187 -258.785802) (xy 9.924319 -258.821477)
			(xy 9.876713 -258.850531) (xy 9.825384 -258.872343) (xy 9.771427 -258.886449) (xy 9.71599 -258.892549)
			(xy 9.660256 -258.890512) (xy 9.605413 -258.880382) (xy 9.552629 -258.862375) (xy 9.503029 -258.836874)
			(xy 9.457671 -258.804423) (xy 9.417522 -258.765714) (xy 9.383436 -258.721571) (xy 9.35614 -258.672936)
			(xy 9.336217 -258.620845) (xy 9.324091 -258.566408) (xy 9.32002 -258.510786) (xy 8.559546 -258.510786)
			(xy 8.559037 -258.538672) (xy 8.550917 -258.593848) (xy 8.534849 -258.647255) (xy 8.511177 -258.697752)
			(xy 8.480404 -258.744265) (xy 8.443187 -258.785802) (xy 8.400319 -258.821477) (xy 8.352713 -258.850531)
			(xy 8.301384 -258.872343) (xy 8.247427 -258.886449) (xy 8.19199 -258.892549) (xy 8.136256 -258.890512)
			(xy 8.081413 -258.880382) (xy 8.028629 -258.862375) (xy 7.979029 -258.836874) (xy 7.933671 -258.804423)
			(xy 7.893522 -258.765714) (xy 7.859436 -258.721571) (xy 7.83214 -258.672936) (xy 7.812217 -258.620845)
			(xy 7.800091 -258.566408) (xy 7.79602 -258.510786) (xy 7.035546 -258.510786) (xy 7.035037 -258.538672)
			(xy 7.026917 -258.593848) (xy 7.010849 -258.647255) (xy 6.987177 -258.697752) (xy 6.956404 -258.744265)
			(xy 6.919187 -258.785802) (xy 6.876319 -258.821477) (xy 6.828713 -258.850531) (xy 6.777384 -258.872343)
			(xy 6.723427 -258.886449) (xy 6.66799 -258.892549) (xy 6.612256 -258.890512) (xy 6.557413 -258.880382)
			(xy 6.504629 -258.862375) (xy 6.455029 -258.836874) (xy 6.409671 -258.804423) (xy 6.369522 -258.765714)
			(xy 6.335436 -258.721571) (xy 6.30814 -258.672936) (xy 6.288217 -258.620845) (xy 6.276091 -258.566408)
			(xy 6.27202 -258.510786) (xy 5.511546 -258.510786) (xy 5.511037 -258.538672) (xy 5.502917 -258.593848)
			(xy 5.486849 -258.647255) (xy 5.463177 -258.697752) (xy 5.432404 -258.744265) (xy 5.395187 -258.785802)
			(xy 5.352319 -258.821477) (xy 5.304713 -258.850531) (xy 5.253384 -258.872343) (xy 5.199427 -258.886449)
			(xy 5.14399 -258.892549) (xy 5.088256 -258.890512) (xy 5.033413 -258.880382) (xy 4.980629 -258.862375)
			(xy 4.931029 -258.836874) (xy 4.885671 -258.804423) (xy 4.845522 -258.765714) (xy 4.811436 -258.721571)
			(xy 4.78414 -258.672936) (xy 4.764217 -258.620845) (xy 4.752091 -258.566408) (xy 4.74802 -258.510786)
			(xy 3.987546 -258.510786) (xy 3.987037 -258.538672) (xy 3.978917 -258.593848) (xy 3.962849 -258.647255)
			(xy 3.939177 -258.697752) (xy 3.908404 -258.744265) (xy 3.871187 -258.785802) (xy 3.828319 -258.821477)
			(xy 3.780713 -258.850531) (xy 3.729384 -258.872343) (xy 3.675427 -258.886449) (xy 3.61999 -258.892549)
			(xy 3.564256 -258.890512) (xy 3.509413 -258.880382) (xy 3.456629 -258.862375) (xy 3.407029 -258.836874)
			(xy 3.361671 -258.804423) (xy 3.321522 -258.765714) (xy 3.287436 -258.721571) (xy 3.26014 -258.672936)
			(xy 3.240217 -258.620845) (xy 3.228091 -258.566408) (xy 3.22402 -258.510786) (xy 1.660398 -258.510786)
			(xy 1.660398 -259.576316) (xy 30.245048 -259.576316) (xy 30.249119 -259.520694) (xy 30.261245 -259.466257)
			(xy 30.281168 -259.414166) (xy 30.308464 -259.365531) (xy 30.34255 -259.321388) (xy 30.382699 -259.282679)
			(xy 30.428057 -259.250228) (xy 30.477657 -259.224727) (xy 30.530441 -259.20672) (xy 30.585284 -259.19659)
			(xy 30.641018 -259.194553) (xy 30.696455 -259.200653) (xy 30.750412 -259.214759) (xy 30.801741 -259.236571)
			(xy 30.849347 -259.265625) (xy 30.892215 -259.3013) (xy 30.929432 -259.342837) (xy 30.960205 -259.38935)
			(xy 30.983877 -259.439847) (xy 30.999945 -259.493254) (xy 31.008065 -259.54843) (xy 31.008574 -259.576316)
			(xy 31.134048 -259.576316) (xy 31.138119 -259.520694) (xy 31.150245 -259.466257) (xy 31.170168 -259.414166)
			(xy 31.197464 -259.365531) (xy 31.23155 -259.321388) (xy 31.271699 -259.282679) (xy 31.317057 -259.250228)
			(xy 31.366657 -259.224727) (xy 31.419441 -259.20672) (xy 31.474284 -259.19659) (xy 31.530018 -259.194553)
			(xy 31.585455 -259.200653) (xy 31.639412 -259.214759) (xy 31.690741 -259.236571) (xy 31.738347 -259.265625)
			(xy 31.781215 -259.3013) (xy 31.818432 -259.342837) (xy 31.849205 -259.38935) (xy 31.872877 -259.439847)
			(xy 31.888945 -259.493254) (xy 31.897065 -259.54843) (xy 31.897574 -259.576316) (xy 31.897065 -259.604202)
			(xy 31.888945 -259.659378) (xy 31.872877 -259.712785) (xy 31.849205 -259.763282) (xy 31.818432 -259.809795)
			(xy 31.781215 -259.851332) (xy 31.738347 -259.887007) (xy 31.690741 -259.916061) (xy 31.639412 -259.937873)
			(xy 31.585455 -259.951979) (xy 31.530018 -259.958079) (xy 31.474284 -259.956042) (xy 31.419441 -259.945912)
			(xy 31.366657 -259.927905) (xy 31.317057 -259.902404) (xy 31.271699 -259.869953) (xy 31.23155 -259.831244)
			(xy 31.197464 -259.787101) (xy 31.170168 -259.738466) (xy 31.150245 -259.686375) (xy 31.138119 -259.631938)
			(xy 31.134048 -259.576316) (xy 31.008574 -259.576316) (xy 31.008065 -259.604202) (xy 30.999945 -259.659378)
			(xy 30.983877 -259.712785) (xy 30.960205 -259.763282) (xy 30.929432 -259.809795) (xy 30.892215 -259.851332)
			(xy 30.849347 -259.887007) (xy 30.801741 -259.916061) (xy 30.750412 -259.937873) (xy 30.696455 -259.951979)
			(xy 30.641018 -259.958079) (xy 30.585284 -259.956042) (xy 30.530441 -259.945912) (xy 30.477657 -259.927905)
			(xy 30.428057 -259.902404) (xy 30.382699 -259.869953) (xy 30.34255 -259.831244) (xy 30.308464 -259.787101)
			(xy 30.281168 -259.738466) (xy 30.261245 -259.686375) (xy 30.249119 -259.631938) (xy 30.245048 -259.576316)
			(xy 1.660398 -259.576316) (xy 1.660398 -260.740398) (xy 22.04339 -260.740398) (xy 22.043956 -260.711756)
			(xy 22.05252 -260.655116) (xy 22.069455 -260.600392) (xy 22.09438 -260.548815) (xy 22.126735 -260.501543)
			(xy 22.165793 -260.459639) (xy 22.187916 -260.44144) (xy 22.196298 -260.434836) (xy 22.206204 -260.415786)
			(xy 22.212808 -260.31952) (xy 22.205696 -260.299454) (xy 22.198076 -260.29158) (xy 22.178306 -260.270146)
			(xy 22.144874 -260.222374) (xy 22.119096 -260.170073) (xy 22.101571 -260.11446) (xy 22.092708 -260.056828)
			(xy 22.092158 -260.027674) (xy 22.092644 -260.000423) (xy 22.1004 -259.946475) (xy 22.115755 -259.89418)
			(xy 22.138397 -259.844603) (xy 22.167863 -259.798753) (xy 22.203554 -259.757562) (xy 22.244745 -259.721871)
			(xy 22.290595 -259.692405) (xy 22.340172 -259.669763) (xy 22.392467 -259.654408) (xy 22.446415 -259.646652)
			(xy 22.500917 -259.646652) (xy 22.554865 -259.654408) (xy 22.60716 -259.669763) (xy 22.656737 -259.692405)
			(xy 22.702587 -259.721871) (xy 22.743778 -259.757562) (xy 22.779469 -259.798753) (xy 22.808935 -259.844603)
			(xy 22.831577 -259.89418) (xy 22.846932 -259.946475) (xy 22.854688 -260.000423) (xy 22.855174 -260.027674)
			(xy 22.854672 -260.056319) (xy 22.85251 -260.0706) (xy 23.642826 -260.0706) (xy 23.646897 -260.014978)
			(xy 23.659023 -259.960541) (xy 23.678946 -259.90845) (xy 23.706242 -259.859815) (xy 23.740328 -259.815672)
			(xy 23.780477 -259.776963) (xy 23.825835 -259.744512) (xy 23.875435 -259.719011) (xy 23.928219 -259.701004)
			(xy 23.983062 -259.690874) (xy 24.038796 -259.688837) (xy 24.094233 -259.694937) (xy 24.14819 -259.709043)
			(xy 24.199519 -259.730855) (xy 24.247125 -259.759909) (xy 24.289993 -259.795584) (xy 24.32721 -259.837121)
			(xy 24.357983 -259.883634) (xy 24.381655 -259.934131) (xy 24.397723 -259.987538) (xy 24.405843 -260.042714)
			(xy 24.406352 -260.0706) (xy 24.405843 -260.098486) (xy 24.402695 -260.119876) (xy 27.661868 -260.119876)
			(xy 27.665939 -260.064254) (xy 27.678065 -260.009817) (xy 27.697988 -259.957726) (xy 27.725284 -259.909091)
			(xy 27.75937 -259.864948) (xy 27.799519 -259.826239) (xy 27.844877 -259.793788) (xy 27.894477 -259.768287)
			(xy 27.947261 -259.75028) (xy 28.002104 -259.74015) (xy 28.057838 -259.738113) (xy 28.113275 -259.744213)
			(xy 28.167232 -259.758319) (xy 28.218561 -259.780131) (xy 28.266167 -259.809185) (xy 28.309035 -259.84486)
			(xy 28.346252 -259.886397) (xy 28.377025 -259.93291) (xy 28.400697 -259.983407) (xy 28.416765 -260.036814)
			(xy 28.424885 -260.09199) (xy 28.425394 -260.119876) (xy 28.424885 -260.147762) (xy 28.416765 -260.202938)
			(xy 28.400697 -260.256345) (xy 28.377025 -260.306842) (xy 28.356202 -260.338316) (xy 34.296096 -260.338316)
			(xy 34.296647 -260.308934) (xy 34.305675 -260.250868) (xy 34.323505 -260.194874) (xy 34.349715 -260.142279)
			(xy 34.383683 -260.094327) (xy 34.424606 -260.052154) (xy 34.447734 -260.034024) (xy 34.457132 -260.026658)
			(xy 34.467546 -260.006084) (xy 34.46907 -259.902198) (xy 34.459164 -259.881116) (xy 34.45002 -259.87375)
			(xy 34.42817 -259.855546) (xy 34.389629 -259.813728) (xy 34.357722 -259.766652) (xy 34.333155 -259.715362)
			(xy 34.316472 -259.660993) (xy 34.308044 -259.604751) (xy 34.307526 -259.576316) (xy 34.308012 -259.549065)
			(xy 34.315768 -259.495117) (xy 34.331123 -259.442822) (xy 34.353765 -259.393245) (xy 34.383231 -259.347395)
			(xy 34.418922 -259.306204) (xy 34.460113 -259.270513) (xy 34.505963 -259.241047) (xy 34.55554 -259.218405)
			(xy 34.607835 -259.20305) (xy 34.661783 -259.195294) (xy 34.716285 -259.195294) (xy 34.770233 -259.20305)
			(xy 34.822528 -259.218405) (xy 34.872105 -259.241047) (xy 34.917955 -259.270513) (xy 34.959146 -259.306204)
			(xy 34.994837 -259.347395) (xy 35.024303 -259.393245) (xy 35.046945 -259.442822) (xy 35.0623 -259.495117)
			(xy 35.070056 -259.549065) (xy 35.070542 -259.576316) (xy 35.069999 -259.605698) (xy 35.060967 -259.663764)
			(xy 35.043134 -259.719757) (xy 35.016923 -259.772352) (xy 34.982954 -259.820304) (xy 34.942031 -259.862477)
			(xy 34.918904 -259.880608) (xy 34.909506 -259.887974) (xy 34.899092 -259.908548) (xy 34.897568 -260.012434)
			(xy 34.907474 -260.033516) (xy 34.916618 -260.040882) (xy 34.938443 -260.059114) (xy 34.976984 -260.100928)
			(xy 35.008893 -260.147998) (xy 35.033464 -260.199283) (xy 35.050153 -260.253645) (xy 35.058589 -260.309883)
			(xy 35.059112 -260.338316) (xy 35.692586 -260.338316) (xy 35.696657 -260.282694) (xy 35.708783 -260.228257)
			(xy 35.728706 -260.176166) (xy 35.756002 -260.127531) (xy 35.790088 -260.083388) (xy 35.830237 -260.044679)
			(xy 35.875595 -260.012228) (xy 35.925195 -259.986727) (xy 35.977979 -259.96872) (xy 36.032822 -259.95859)
			(xy 36.088556 -259.956553) (xy 36.143993 -259.962653) (xy 36.19795 -259.976759) (xy 36.249279 -259.998571)
			(xy 36.296885 -260.027625) (xy 36.339753 -260.0633) (xy 36.37697 -260.104837) (xy 36.407743 -260.15135)
			(xy 36.431415 -260.201847) (xy 36.447483 -260.255254) (xy 36.455603 -260.31043) (xy 36.456112 -260.338316)
			(xy 36.579046 -260.338316) (xy 36.583117 -260.282694) (xy 36.595243 -260.228257) (xy 36.615166 -260.176166)
			(xy 36.642462 -260.127531) (xy 36.676548 -260.083388) (xy 36.716697 -260.044679) (xy 36.762055 -260.012228)
			(xy 36.811655 -259.986727) (xy 36.864439 -259.96872) (xy 36.919282 -259.95859) (xy 36.975016 -259.956553)
			(xy 37.030453 -259.962653) (xy 37.08441 -259.976759) (xy 37.135739 -259.998571) (xy 37.183345 -260.027625)
			(xy 37.226213 -260.0633) (xy 37.26343 -260.104837) (xy 37.294203 -260.15135) (xy 37.317875 -260.201847)
			(xy 37.333943 -260.255254) (xy 37.342063 -260.31043) (xy 37.342572 -260.338316) (xy 37.342063 -260.366202)
			(xy 37.333943 -260.421378) (xy 37.317875 -260.474785) (xy 37.294203 -260.525282) (xy 37.26343 -260.571795)
			(xy 37.226213 -260.613332) (xy 37.183345 -260.649007) (xy 37.135739 -260.678061) (xy 37.08441 -260.699873)
			(xy 37.030453 -260.713979) (xy 36.975016 -260.720079) (xy 36.919282 -260.718042) (xy 36.864439 -260.707912)
			(xy 36.811655 -260.689905) (xy 36.762055 -260.664404) (xy 36.716697 -260.631953) (xy 36.676548 -260.593244)
			(xy 36.642462 -260.549101) (xy 36.615166 -260.500466) (xy 36.595243 -260.448375) (xy 36.583117 -260.393938)
			(xy 36.579046 -260.338316) (xy 36.456112 -260.338316) (xy 36.455603 -260.366202) (xy 36.447483 -260.421378)
			(xy 36.431415 -260.474785) (xy 36.407743 -260.525282) (xy 36.37697 -260.571795) (xy 36.339753 -260.613332)
			(xy 36.296885 -260.649007) (xy 36.249279 -260.678061) (xy 36.19795 -260.699873) (xy 36.143993 -260.713979)
			(xy 36.088556 -260.720079) (xy 36.032822 -260.718042) (xy 35.977979 -260.707912) (xy 35.925195 -260.689905)
			(xy 35.875595 -260.664404) (xy 35.830237 -260.631953) (xy 35.790088 -260.593244) (xy 35.756002 -260.549101)
			(xy 35.728706 -260.500466) (xy 35.708783 -260.448375) (xy 35.696657 -260.393938) (xy 35.692586 -260.338316)
			(xy 35.059112 -260.338316) (xy 35.058626 -260.365567) (xy 35.05087 -260.419515) (xy 35.035515 -260.47181)
			(xy 35.012873 -260.521387) (xy 34.983407 -260.567237) (xy 34.947716 -260.608428) (xy 34.906525 -260.644119)
			(xy 34.860675 -260.673585) (xy 34.811098 -260.696227) (xy 34.758803 -260.711582) (xy 34.704855 -260.719338)
			(xy 34.650353 -260.719338) (xy 34.596405 -260.711582) (xy 34.54411 -260.696227) (xy 34.494533 -260.673585)
			(xy 34.448683 -260.644119) (xy 34.407492 -260.608428) (xy 34.371801 -260.567237) (xy 34.342335 -260.521387)
			(xy 34.319693 -260.47181) (xy 34.304338 -260.419515) (xy 34.296582 -260.365567) (xy 34.296096 -260.338316)
			(xy 28.356202 -260.338316) (xy 28.346252 -260.353355) (xy 28.309035 -260.394892) (xy 28.266167 -260.430567)
			(xy 28.218561 -260.459621) (xy 28.167232 -260.481433) (xy 28.113275 -260.495539) (xy 28.057838 -260.501639)
			(xy 28.002104 -260.499602) (xy 27.947261 -260.489472) (xy 27.894477 -260.471465) (xy 27.844877 -260.445964)
			(xy 27.799519 -260.413513) (xy 27.75937 -260.374804) (xy 27.725284 -260.330661) (xy 27.697988 -260.282026)
			(xy 27.678065 -260.229935) (xy 27.665939 -260.175498) (xy 27.661868 -260.119876) (xy 24.402695 -260.119876)
			(xy 24.397723 -260.153662) (xy 24.381655 -260.207069) (xy 24.357983 -260.257566) (xy 24.32721 -260.304079)
			(xy 24.289993 -260.345616) (xy 24.247125 -260.381291) (xy 24.199519 -260.410345) (xy 24.14819 -260.432157)
			(xy 24.094233 -260.446263) (xy 24.038796 -260.452363) (xy 23.983062 -260.450326) (xy 23.928219 -260.440196)
			(xy 23.875435 -260.422189) (xy 23.825835 -260.396688) (xy 23.780477 -260.364237) (xy 23.740328 -260.325528)
			(xy 23.706242 -260.281385) (xy 23.678946 -260.23275) (xy 23.659023 -260.180659) (xy 23.646897 -260.126222)
			(xy 23.642826 -260.0706) (xy 22.85251 -260.0706) (xy 22.846097 -260.112963) (xy 22.82915 -260.167688)
			(xy 22.804213 -260.219265) (xy 22.771846 -260.266535) (xy 22.732776 -260.308435) (xy 22.710648 -260.326632)
			(xy 22.702266 -260.333236) (xy 22.69236 -260.352286) (xy 22.685756 -260.448552) (xy 22.692868 -260.468618)
			(xy 22.700488 -260.476492) (xy 22.720239 -260.497943) (xy 22.749139 -260.53923) (xy 26.534616 -260.53923)
			(xy 26.538687 -260.483608) (xy 26.550813 -260.429171) (xy 26.570736 -260.37708) (xy 26.598032 -260.328445)
			(xy 26.632118 -260.284302) (xy 26.672267 -260.245593) (xy 26.717625 -260.213142) (xy 26.767225 -260.187641)
			(xy 26.820009 -260.169634) (xy 26.874852 -260.159504) (xy 26.930586 -260.157467) (xy 26.986023 -260.163567)
			(xy 27.03998 -260.177673) (xy 27.091309 -260.199485) (xy 27.138915 -260.228539) (xy 27.181783 -260.264214)
			(xy 27.219 -260.305751) (xy 27.249773 -260.352264) (xy 27.273445 -260.402761) (xy 27.289513 -260.456168)
			(xy 27.297633 -260.511344) (xy 27.298142 -260.53923) (xy 27.297633 -260.567116) (xy 27.289513 -260.622292)
			(xy 27.273445 -260.675699) (xy 27.249773 -260.726196) (xy 27.219 -260.772709) (xy 27.181783 -260.814246)
			(xy 27.138915 -260.849921) (xy 27.091309 -260.878975) (xy 27.03998 -260.900787) (xy 26.986023 -260.914893)
			(xy 26.930586 -260.920993) (xy 26.874852 -260.918956) (xy 26.820009 -260.908826) (xy 26.767225 -260.890819)
			(xy 26.717625 -260.865318) (xy 26.672267 -260.832867) (xy 26.632118 -260.794158) (xy 26.598032 -260.750015)
			(xy 26.570736 -260.70138) (xy 26.550813 -260.649289) (xy 26.538687 -260.594852) (xy 26.534616 -260.53923)
			(xy 22.749139 -260.53923) (xy 22.753675 -260.54571) (xy 22.779457 -260.598007) (xy 22.796986 -260.653616)
			(xy 22.805854 -260.711245) (xy 22.806406 -260.740398) (xy 22.80592 -260.767649) (xy 22.798164 -260.821597)
			(xy 22.782809 -260.873892) (xy 22.760167 -260.923469) (xy 22.730701 -260.969319) (xy 22.69501 -261.01051)
			(xy 22.653819 -261.046201) (xy 22.607969 -261.075667) (xy 22.558392 -261.098309) (xy 22.506097 -261.113664)
			(xy 22.452149 -261.12142) (xy 22.397647 -261.12142) (xy 22.343699 -261.113664) (xy 22.291404 -261.098309)
			(xy 22.241827 -261.075667) (xy 22.195977 -261.046201) (xy 22.154786 -261.01051) (xy 22.119095 -260.969319)
			(xy 22.089629 -260.923469) (xy 22.066987 -260.873892) (xy 22.051632 -260.821597) (xy 22.043876 -260.767649)
			(xy 22.04339 -260.740398) (xy 1.660398 -260.740398) (xy 1.660398 -261.764272) (xy 24.31872 -261.764272)
			(xy 24.322791 -261.70865) (xy 24.334917 -261.654213) (xy 24.35484 -261.602122) (xy 24.382136 -261.553487)
			(xy 24.416222 -261.509344) (xy 24.456371 -261.470635) (xy 24.501729 -261.438184) (xy 24.551329 -261.412683)
			(xy 24.604113 -261.394676) (xy 24.658956 -261.384546) (xy 24.71469 -261.382509) (xy 24.770127 -261.388609)
			(xy 24.824084 -261.402715) (xy 24.875413 -261.424527) (xy 24.923019 -261.453581) (xy 24.965887 -261.489256)
			(xy 25.003104 -261.530793) (xy 25.033877 -261.577306) (xy 25.057549 -261.627803) (xy 25.073617 -261.68121)
			(xy 25.081737 -261.736386) (xy 25.082246 -261.764272) (xy 25.081737 -261.792158) (xy 25.077941 -261.817951)
			(xy 25.519366 -261.817951) (xy 25.519366 -261.763449) (xy 25.527122 -261.709501) (xy 25.542477 -261.657206)
			(xy 25.565117 -261.607629) (xy 25.594582 -261.561778) (xy 25.630273 -261.520587) (xy 25.671462 -261.484894)
			(xy 25.717311 -261.455427) (xy 25.766888 -261.432784) (xy 25.819182 -261.417426) (xy 25.873129 -261.409667)
			(xy 25.90038 -261.40918) (xy 25.929298 -261.409682) (xy 25.986471 -261.41841) (xy 26.041672 -261.435669)
			(xy 26.093634 -261.461064) (xy 26.141167 -261.494012) (xy 26.183182 -261.533758) (xy 26.20137 -261.556246)
			(xy 26.208941 -261.564997) (xy 26.229693 -261.575185) (xy 26.241248 -261.575804) (xy 26.321512 -261.575804)
			(xy 26.33308 -261.575239) (xy 26.353851 -261.56504) (xy 26.36139 -261.556246) (xy 26.378143 -261.535463)
			(xy 26.416497 -261.498333) (xy 26.459651 -261.466911) (xy 26.506765 -261.441812) (xy 26.556917 -261.423526)
			(xy 26.609128 -261.412409) (xy 26.66238 -261.408679) (xy 26.715632 -261.412409) (xy 26.767843 -261.423526)
			(xy 26.817995 -261.441812) (xy 26.865109 -261.466911) (xy 26.908263 -261.498333) (xy 26.946617 -261.535463)
			(xy 26.96337 -261.556246) (xy 26.970941 -261.564997) (xy 26.991693 -261.575185) (xy 27.003248 -261.575804)
			(xy 27.083512 -261.575804) (xy 27.09508 -261.575239) (xy 27.115851 -261.56504) (xy 27.12339 -261.556246)
			(xy 27.140143 -261.535463) (xy 27.178497 -261.498333) (xy 27.221651 -261.466911) (xy 27.268765 -261.441812)
			(xy 27.318917 -261.423526) (xy 27.371128 -261.412409) (xy 27.42438 -261.408679) (xy 27.477632 -261.412409)
			(xy 27.529843 -261.423526) (xy 27.579995 -261.441812) (xy 27.627109 -261.466911) (xy 27.670263 -261.498333)
			(xy 27.708617 -261.535463) (xy 27.72537 -261.556246) (xy 27.732941 -261.564997) (xy 27.753693 -261.575185)
			(xy 27.765248 -261.575804) (xy 27.845512 -261.575804) (xy 27.85708 -261.575239) (xy 27.877851 -261.56504)
			(xy 27.88539 -261.556246) (xy 27.903573 -261.533756) (xy 27.945596 -261.494024) (xy 27.993133 -261.461087)
			(xy 28.045096 -261.4357) (xy 28.100294 -261.418445) (xy 28.157464 -261.409716) (xy 28.18638 -261.40918)
			(xy 28.213633 -261.409666) (xy 28.267584 -261.41742) (xy 28.319883 -261.432774) (xy 28.369464 -261.455415)
			(xy 28.399098 -261.474458) (xy 28.769562 -261.474458) (xy 28.773633 -261.418836) (xy 28.785759 -261.364399)
			(xy 28.805682 -261.312308) (xy 28.832978 -261.263673) (xy 28.867064 -261.21953) (xy 28.907213 -261.180821)
			(xy 28.952571 -261.14837) (xy 29.002171 -261.122869) (xy 29.054955 -261.104862) (xy 29.109798 -261.094732)
			(xy 29.165532 -261.092695) (xy 29.220969 -261.098795) (xy 29.274926 -261.112901) (xy 29.326255 -261.134713)
			(xy 29.373861 -261.163767) (xy 29.416729 -261.199442) (xy 29.453946 -261.240979) (xy 29.484719 -261.287492)
			(xy 29.508391 -261.337989) (xy 29.524459 -261.391396) (xy 29.532579 -261.446572) (xy 29.533088 -261.474458)
			(xy 30.2547 -261.474458) (xy 30.258771 -261.418836) (xy 30.270897 -261.364399) (xy 30.29082 -261.312308)
			(xy 30.318116 -261.263673) (xy 30.352202 -261.21953) (xy 30.392351 -261.180821) (xy 30.437709 -261.14837)
			(xy 30.487309 -261.122869) (xy 30.540093 -261.104862) (xy 30.594936 -261.094732) (xy 30.65067 -261.092695)
			(xy 30.706107 -261.098795) (xy 30.760064 -261.112901) (xy 30.811393 -261.134713) (xy 30.858999 -261.163767)
			(xy 30.901867 -261.199442) (xy 30.939084 -261.240979) (xy 30.969857 -261.287492) (xy 30.993529 -261.337989)
			(xy 31.009597 -261.391396) (xy 31.017717 -261.446572) (xy 31.018226 -261.474458) (xy 31.017717 -261.502344)
			(xy 31.009597 -261.55752) (xy 30.993529 -261.610927) (xy 30.969857 -261.661424) (xy 30.939084 -261.707937)
			(xy 30.901867 -261.749474) (xy 30.858999 -261.785149) (xy 30.811393 -261.814203) (xy 30.760064 -261.836015)
			(xy 30.706107 -261.850121) (xy 30.65067 -261.856221) (xy 30.594936 -261.854184) (xy 30.540093 -261.844054)
			(xy 30.487309 -261.826047) (xy 30.437709 -261.800546) (xy 30.392351 -261.768095) (xy 30.352202 -261.729386)
			(xy 30.318116 -261.685243) (xy 30.29082 -261.636608) (xy 30.270897 -261.584517) (xy 30.258771 -261.53008)
			(xy 30.2547 -261.474458) (xy 29.533088 -261.474458) (xy 29.532579 -261.502344) (xy 29.524459 -261.55752)
			(xy 29.508391 -261.610927) (xy 29.484719 -261.661424) (xy 29.453946 -261.707937) (xy 29.416729 -261.749474)
			(xy 29.373861 -261.785149) (xy 29.326255 -261.814203) (xy 29.274926 -261.836015) (xy 29.220969 -261.850121)
			(xy 29.165532 -261.856221) (xy 29.109798 -261.854184) (xy 29.054955 -261.844054) (xy 29.002171 -261.826047)
			(xy 28.952571 -261.800546) (xy 28.907213 -261.768095) (xy 28.867064 -261.729386) (xy 28.832978 -261.685243)
			(xy 28.805682 -261.636608) (xy 28.785759 -261.584517) (xy 28.773633 -261.53008) (xy 28.769562 -261.474458)
			(xy 28.399098 -261.474458) (xy 28.415318 -261.484881) (xy 28.456512 -261.520574) (xy 28.492207 -261.561766)
			(xy 28.521676 -261.607618) (xy 28.544319 -261.657198) (xy 28.559675 -261.709496) (xy 28.567433 -261.763447)
			(xy 28.567433 -261.817953) (xy 28.559675 -261.871904) (xy 28.544319 -261.924202) (xy 28.521676 -261.973782)
			(xy 28.492207 -262.019634) (xy 28.456512 -262.060826) (xy 28.415318 -262.096519) (xy 28.369464 -262.125985)
			(xy 28.319883 -262.148626) (xy 28.267584 -262.16398) (xy 28.213633 -262.171734) (xy 28.18638 -262.172196)
			(xy 28.157465 -262.171622) (xy 28.100296 -262.162905) (xy 28.045099 -262.145658) (xy 27.993137 -262.120277)
			(xy 27.945601 -262.087343) (xy 27.903582 -262.047611) (xy 27.88539 -262.02513) (xy 27.87784 -262.016356)
			(xy 27.857072 -262.006182) (xy 27.845512 -262.005572) (xy 27.765248 -262.005572) (xy 27.75368 -262.006145)
			(xy 27.732907 -262.016335) (xy 27.72537 -262.02513) (xy 27.708617 -262.045913) (xy 27.670263 -262.083043)
			(xy 27.627109 -262.114465) (xy 27.579995 -262.139564) (xy 27.529843 -262.15785) (xy 27.477632 -262.168967)
			(xy 27.42438 -262.172697) (xy 27.371128 -262.168967) (xy 27.318917 -262.15785) (xy 27.268765 -262.139564)
			(xy 27.221651 -262.114465) (xy 27.178497 -262.083043) (xy 27.140143 -262.045913) (xy 27.12339 -262.02513)
			(xy 27.11584 -262.016356) (xy 27.095072 -262.006182) (xy 27.083512 -262.005572) (xy 27.003248 -262.005572)
			(xy 26.99168 -262.006145) (xy 26.970907 -262.016335) (xy 26.96337 -262.02513) (xy 26.946617 -262.045913)
			(xy 26.908263 -262.083043) (xy 26.865109 -262.114465) (xy 26.817995 -262.139564) (xy 26.767843 -262.15785)
			(xy 26.715632 -262.168967) (xy 26.66238 -262.172697) (xy 26.609128 -262.168967) (xy 26.556917 -262.15785)
			(xy 26.506765 -262.139564) (xy 26.459651 -262.114465) (xy 26.416497 -262.083043) (xy 26.378143 -262.045913)
			(xy 26.36139 -262.02513) (xy 26.35384 -262.016356) (xy 26.333072 -262.006182) (xy 26.321512 -262.005572)
			(xy 26.241248 -262.005572) (xy 26.22968 -262.006145) (xy 26.208907 -262.016335) (xy 26.20137 -262.02513)
			(xy 26.183204 -262.047634) (xy 26.141178 -262.087367) (xy 26.093637 -262.120302) (xy 26.041672 -262.145687)
			(xy 25.98647 -262.162939) (xy 25.929297 -262.171663) (xy 25.90038 -262.172196) (xy 25.873129 -262.171733)
			(xy 25.819182 -262.163974) (xy 25.766888 -262.148616) (xy 25.717311 -262.125973) (xy 25.671462 -262.096506)
			(xy 25.630273 -262.060813) (xy 25.594582 -262.019622) (xy 25.565117 -261.973771) (xy 25.542477 -261.924194)
			(xy 25.527122 -261.871899) (xy 25.519366 -261.817951) (xy 25.077941 -261.817951) (xy 25.073617 -261.847334)
			(xy 25.057549 -261.900741) (xy 25.033877 -261.951238) (xy 25.003104 -261.997751) (xy 24.965887 -262.039288)
			(xy 24.923019 -262.074963) (xy 24.875413 -262.104017) (xy 24.824084 -262.125829) (xy 24.770127 -262.139935)
			(xy 24.71469 -262.146035) (xy 24.658956 -262.143998) (xy 24.604113 -262.133868) (xy 24.551329 -262.115861)
			(xy 24.501729 -262.09036) (xy 24.456371 -262.057909) (xy 24.416222 -262.0192) (xy 24.382136 -261.975057)
			(xy 24.35484 -261.926422) (xy 24.334917 -261.874331) (xy 24.322791 -261.819894) (xy 24.31872 -261.764272)
			(xy 1.660398 -261.764272) (xy 1.660398 -262.519668) (xy 22.592282 -262.519668) (xy 22.596353 -262.464046)
			(xy 22.608479 -262.409609) (xy 22.628402 -262.357518) (xy 22.655698 -262.308883) (xy 22.689784 -262.26474)
			(xy 22.729933 -262.226031) (xy 22.775291 -262.19358) (xy 22.824891 -262.168079) (xy 22.877675 -262.150072)
			(xy 22.932518 -262.139942) (xy 22.988252 -262.137905) (xy 23.043689 -262.144005) (xy 23.097646 -262.158111)
			(xy 23.148975 -262.179923) (xy 23.196581 -262.208977) (xy 23.239449 -262.244652) (xy 23.276666 -262.286189)
			(xy 23.307439 -262.332702) (xy 23.331111 -262.383199) (xy 23.347179 -262.436606) (xy 23.355299 -262.491782)
			(xy 23.355808 -262.519668) (xy 23.355299 -262.547554) (xy 23.347179 -262.60273) (xy 23.331111 -262.656137)
			(xy 23.307439 -262.706634) (xy 23.276666 -262.753147) (xy 23.239449 -262.794684) (xy 23.196581 -262.830359)
			(xy 23.148975 -262.859413) (xy 23.097646 -262.881225) (xy 23.043689 -262.895331) (xy 22.988252 -262.901431)
			(xy 22.932518 -262.899394) (xy 22.877675 -262.889264) (xy 22.824891 -262.871257) (xy 22.775291 -262.845756)
			(xy 22.729933 -262.813305) (xy 22.689784 -262.774596) (xy 22.655698 -262.730453) (xy 22.628402 -262.681818)
			(xy 22.608479 -262.629727) (xy 22.596353 -262.57529) (xy 22.592282 -262.519668) (xy 1.660398 -262.519668)
			(xy 1.660398 -262.912352) (xy 25.168858 -262.912352) (xy 25.172929 -262.85673) (xy 25.185055 -262.802293)
			(xy 25.204978 -262.750202) (xy 25.232274 -262.701567) (xy 25.26636 -262.657424) (xy 25.306509 -262.618715)
			(xy 25.351867 -262.586264) (xy 25.401467 -262.560763) (xy 25.454251 -262.542756) (xy 25.509094 -262.532626)
			(xy 25.564828 -262.530589) (xy 25.620265 -262.536689) (xy 25.674222 -262.550795) (xy 25.725551 -262.572607)
			(xy 25.773157 -262.601661) (xy 25.816025 -262.637336) (xy 25.853242 -262.678873) (xy 25.884015 -262.725386)
			(xy 25.907687 -262.775883) (xy 25.923755 -262.82929) (xy 25.931875 -262.884466) (xy 25.932384 -262.912352)
			(xy 25.931875 -262.940238) (xy 25.923755 -262.995414) (xy 25.907687 -263.048821) (xy 25.884015 -263.099318)
			(xy 25.853242 -263.145831) (xy 25.816025 -263.187368) (xy 25.773157 -263.223043) (xy 25.725551 -263.252097)
			(xy 25.674222 -263.273909) (xy 25.620265 -263.288015) (xy 25.564828 -263.294115) (xy 25.509094 -263.292078)
			(xy 25.454251 -263.281948) (xy 25.401467 -263.263941) (xy 25.351867 -263.23844) (xy 25.306509 -263.205989)
			(xy 25.26636 -263.16728) (xy 25.232274 -263.123137) (xy 25.204978 -263.074502) (xy 25.185055 -263.022411)
			(xy 25.172929 -262.967974) (xy 25.168858 -262.912352) (xy 1.660398 -262.912352) (xy 1.660398 -264.017506)
			(xy 36.356542 -264.017506) (xy 36.360613 -263.961884) (xy 36.372739 -263.907447) (xy 36.392662 -263.855356)
			(xy 36.419958 -263.806721) (xy 36.454044 -263.762578) (xy 36.494193 -263.723869) (xy 36.539551 -263.691418)
			(xy 36.589151 -263.665917) (xy 36.641935 -263.64791) (xy 36.696778 -263.63778) (xy 36.752512 -263.635743)
			(xy 36.807949 -263.641843) (xy 36.861906 -263.655949) (xy 36.913235 -263.677761) (xy 36.960841 -263.706815)
			(xy 37.003709 -263.74249) (xy 37.040926 -263.784027) (xy 37.071699 -263.83054) (xy 37.095371 -263.881037)
			(xy 37.111439 -263.934444) (xy 37.119559 -263.98962) (xy 37.120068 -264.017506) (xy 37.119559 -264.045392)
			(xy 37.111439 -264.100568) (xy 37.095371 -264.153975) (xy 37.078854 -264.18921) (xy 37.95979 -264.18921)
			(xy 37.963861 -264.133588) (xy 37.975987 -264.079151) (xy 37.99591 -264.02706) (xy 38.023206 -263.978425)
			(xy 38.057292 -263.934282) (xy 38.097441 -263.895573) (xy 38.142799 -263.863122) (xy 38.192399 -263.837621)
			(xy 38.245183 -263.819614) (xy 38.300026 -263.809484) (xy 38.35576 -263.807447) (xy 38.411197 -263.813547)
			(xy 38.465154 -263.827653) (xy 38.516483 -263.849465) (xy 38.564089 -263.878519) (xy 38.606957 -263.914194)
			(xy 38.644174 -263.955731) (xy 38.674947 -264.002244) (xy 38.698619 -264.052741) (xy 38.714687 -264.106148)
			(xy 38.722807 -264.161324) (xy 38.723316 -264.18921) (xy 38.722807 -264.217096) (xy 38.714687 -264.272272)
			(xy 38.698619 -264.325679) (xy 38.674947 -264.376176) (xy 38.644174 -264.422689) (xy 38.606957 -264.464226)
			(xy 38.564089 -264.499901) (xy 38.516483 -264.528955) (xy 38.465154 -264.550767) (xy 38.411197 -264.564873)
			(xy 38.35576 -264.570973) (xy 38.300026 -264.568936) (xy 38.245183 -264.558806) (xy 38.192399 -264.540799)
			(xy 38.142799 -264.515298) (xy 38.097441 -264.482847) (xy 38.057292 -264.444138) (xy 38.023206 -264.399995)
			(xy 37.99591 -264.35136) (xy 37.975987 -264.299269) (xy 37.963861 -264.244832) (xy 37.95979 -264.18921)
			(xy 37.078854 -264.18921) (xy 37.071699 -264.204472) (xy 37.040926 -264.250985) (xy 37.003709 -264.292522)
			(xy 36.960841 -264.328197) (xy 36.913235 -264.357251) (xy 36.861906 -264.379063) (xy 36.807949 -264.393169)
			(xy 36.752512 -264.399269) (xy 36.696778 -264.397232) (xy 36.641935 -264.387102) (xy 36.589151 -264.369095)
			(xy 36.539551 -264.343594) (xy 36.494193 -264.311143) (xy 36.454044 -264.272434) (xy 36.419958 -264.228291)
			(xy 36.392662 -264.179656) (xy 36.372739 -264.127565) (xy 36.360613 -264.073128) (xy 36.356542 -264.017506)
			(xy 1.660398 -264.017506) (xy 1.660398 -265.804904) (xy 37.345618 -265.804904) (xy 37.349689 -265.749282)
			(xy 37.361815 -265.694845) (xy 37.381738 -265.642754) (xy 37.409034 -265.594119) (xy 37.44312 -265.549976)
			(xy 37.483269 -265.511267) (xy 37.528627 -265.478816) (xy 37.578227 -265.453315) (xy 37.631011 -265.435308)
			(xy 37.685854 -265.425178) (xy 37.741588 -265.423141) (xy 37.797025 -265.429241) (xy 37.850982 -265.443347)
			(xy 37.902311 -265.465159) (xy 37.949917 -265.494213) (xy 37.992785 -265.529888) (xy 38.030002 -265.571425)
			(xy 38.060775 -265.617938) (xy 38.084447 -265.668435) (xy 38.100515 -265.721842) (xy 38.108635 -265.777018)
			(xy 38.109144 -265.804904) (xy 38.108635 -265.83279) (xy 38.100515 -265.887966) (xy 38.084447 -265.941373)
			(xy 38.060775 -265.99187) (xy 38.030002 -266.038383) (xy 37.992785 -266.07992) (xy 37.949917 -266.115595)
			(xy 37.902311 -266.144649) (xy 37.850982 -266.166461) (xy 37.797025 -266.180567) (xy 37.741588 -266.186667)
			(xy 37.685854 -266.18463) (xy 37.631011 -266.1745) (xy 37.578227 -266.156493) (xy 37.528627 -266.130992)
			(xy 37.483269 -266.098541) (xy 37.44312 -266.059832) (xy 37.409034 -266.015689) (xy 37.381738 -265.967054)
			(xy 37.361815 -265.914963) (xy 37.349689 -265.860526) (xy 37.345618 -265.804904) (xy 1.660398 -265.804904)
			(xy 1.660398 -267.500608) (xy 17.210784 -267.500608) (xy 17.214855 -267.444986) (xy 17.226981 -267.390549)
			(xy 17.246904 -267.338458) (xy 17.2742 -267.289823) (xy 17.308286 -267.24568) (xy 17.348435 -267.206971)
			(xy 17.393793 -267.17452) (xy 17.443393 -267.149019) (xy 17.496177 -267.131012) (xy 17.55102 -267.120882)
			(xy 17.606754 -267.118845) (xy 17.662191 -267.124945) (xy 17.716148 -267.139051) (xy 17.767477 -267.160863)
			(xy 17.815083 -267.189917) (xy 17.857951 -267.225592) (xy 17.895168 -267.267129) (xy 17.925941 -267.313642)
			(xy 17.949613 -267.364139) (xy 17.965681 -267.417546) (xy 17.973801 -267.472722) (xy 17.97431 -267.500608)
			(xy 17.973801 -267.528494) (xy 17.965681 -267.58367) (xy 17.949613 -267.637077) (xy 17.925941 -267.687574)
			(xy 17.895168 -267.734087) (xy 17.857951 -267.775624) (xy 17.815083 -267.811299) (xy 17.767477 -267.840353)
			(xy 17.716148 -267.862165) (xy 17.662191 -267.876271) (xy 17.606754 -267.882371) (xy 17.55102 -267.880334)
			(xy 17.496177 -267.870204) (xy 17.443393 -267.852197) (xy 17.393793 -267.826696) (xy 17.348435 -267.794245)
			(xy 17.308286 -267.755536) (xy 17.2742 -267.711393) (xy 17.246904 -267.662758) (xy 17.226981 -267.610667)
			(xy 17.214855 -267.55623) (xy 17.210784 -267.500608) (xy 1.660398 -267.500608) (xy 1.660398 -270.100806)
			(xy 17.238724 -270.100806) (xy 17.242795 -270.045184) (xy 17.254921 -269.990747) (xy 17.274844 -269.938656)
			(xy 17.30214 -269.890021) (xy 17.336226 -269.845878) (xy 17.376375 -269.807169) (xy 17.421733 -269.774718)
			(xy 17.471333 -269.749217) (xy 17.524117 -269.73121) (xy 17.57896 -269.72108) (xy 17.634694 -269.719043)
			(xy 17.690131 -269.725143) (xy 17.744088 -269.739249) (xy 17.795417 -269.761061) (xy 17.843023 -269.790115)
			(xy 17.885891 -269.82579) (xy 17.923108 -269.867327) (xy 17.953881 -269.91384) (xy 17.977553 -269.964337)
			(xy 17.993621 -270.017744) (xy 18.001741 -270.07292) (xy 18.00225 -270.100806) (xy 18.001741 -270.128692)
			(xy 17.993621 -270.183868) (xy 17.977553 -270.237275) (xy 17.953881 -270.287772) (xy 17.923108 -270.334285)
			(xy 17.885891 -270.375822) (xy 17.843023 -270.411497) (xy 17.795417 -270.440551) (xy 17.744088 -270.462363)
			(xy 17.690131 -270.476469) (xy 17.634694 -270.482569) (xy 17.57896 -270.480532) (xy 17.524117 -270.470402)
			(xy 17.471333 -270.452395) (xy 17.421733 -270.426894) (xy 17.376375 -270.394443) (xy 17.336226 -270.355734)
			(xy 17.30214 -270.311591) (xy 17.274844 -270.262956) (xy 17.254921 -270.210865) (xy 17.242795 -270.156428)
			(xy 17.238724 -270.100806) (xy 1.660398 -270.100806) (xy 1.660398 -270.204692) (xy 1.677924 -270.2306)
			(xy 1.692402 -270.236188) (xy 1.718645 -270.247187) (xy 1.767812 -270.275828) (xy 1.812181 -270.311452)
			(xy 1.850768 -270.353269) (xy 1.882718 -270.400353) (xy 1.907321 -270.45166) (xy 1.924033 -270.506051)
			(xy 1.932482 -270.56232) (xy 1.932482 -270.619221) (xy 1.924032 -270.675491) (xy 1.90732 -270.729882)
			(xy 1.882717 -270.781188) (xy 1.850767 -270.828272) (xy 1.81218 -270.870089) (xy 1.767811 -270.905713)
			(xy 1.718644 -270.934353) (xy 1.692402 -270.945356) (xy 1.677924 -270.950944) (xy 1.660398 -270.976852)
			(xy 1.660398 -271.184624) (xy 17.47469 -271.184624) (xy 17.478761 -271.129002) (xy 17.490887 -271.074565)
			(xy 17.51081 -271.022474) (xy 17.538106 -270.973839) (xy 17.572192 -270.929696) (xy 17.612341 -270.890987)
			(xy 17.657699 -270.858536) (xy 17.707299 -270.833035) (xy 17.760083 -270.815028) (xy 17.814926 -270.804898)
			(xy 17.87066 -270.802861) (xy 17.926097 -270.808961) (xy 17.980054 -270.823067) (xy 18.031383 -270.844879)
			(xy 18.078989 -270.873933) (xy 18.11018 -270.89989) (xy 24.898611 -270.89989) (xy 24.902617 -270.704835)
			(xy 24.914627 -270.510109) (xy 24.934622 -270.31604) (xy 24.962567 -270.122956) (xy 24.998416 -269.931181)
			(xy 25.042108 -269.741041) (xy 25.093569 -269.552854) (xy 25.152713 -269.366939) (xy 25.21944 -269.183608)
			(xy 25.293637 -269.003172) (xy 25.375179 -268.825934) (xy 25.46393 -268.652193) (xy 25.559738 -268.482242)
			(xy 25.662443 -268.316368) (xy 25.771871 -268.15485) (xy 25.887838 -267.997961) (xy 26.010149 -267.845966)
			(xy 26.138596 -267.69912) (xy 26.272964 -267.557671) (xy 26.413026 -267.421858) (xy 26.558545 -267.291909)
			(xy 26.709277 -267.168045) (xy 26.864967 -267.050473) (xy 27.025353 -266.939393) (xy 27.190164 -266.83499)
			(xy 27.359122 -266.737442) (xy 27.531943 -266.646913) (xy 27.708335 -266.563555) (xy 27.888 -266.487509)
			(xy 28.070635 -266.418904) (xy 28.255934 -266.357854) (xy 28.443582 -266.304464) (xy 28.633264 -266.258822)
			(xy 28.824661 -266.221006) (xy 29.017448 -266.19108) (xy 29.211301 -266.169094) (xy 29.405894 -266.155085)
			(xy 29.600897 -266.149077) (xy 29.795983 -266.15108) (xy 29.990822 -266.161091) (xy 30.185086 -266.179092)
			(xy 30.378447 -266.205054) (xy 30.57058 -266.238932) (xy 30.761159 -266.280669) (xy 30.949864 -266.330196)
			(xy 31.136377 -266.387428) (xy 31.320383 -266.452269) (xy 31.501571 -266.52461) (xy 31.679637 -266.604328)
			(xy 31.85428 -266.69129) (xy 32.025206 -266.785349) (xy 32.192125 -266.886345) (xy 32.308409 -266.963398)
			(xy 38.656004 -266.963398) (xy 38.660075 -266.907776) (xy 38.672201 -266.853339) (xy 38.692124 -266.801248)
			(xy 38.71942 -266.752613) (xy 38.753506 -266.70847) (xy 38.793655 -266.669761) (xy 38.839013 -266.63731)
			(xy 38.888613 -266.611809) (xy 38.941397 -266.593802) (xy 38.99624 -266.583672) (xy 39.051974 -266.581635)
			(xy 39.107411 -266.587735) (xy 39.161368 -266.601841) (xy 39.212697 -266.623653) (xy 39.260303 -266.652707)
			(xy 39.303171 -266.688382) (xy 39.340388 -266.729919) (xy 39.371161 -266.776432) (xy 39.394833 -266.826929)
			(xy 39.410901 -266.880336) (xy 39.419021 -266.935512) (xy 39.41953 -266.963398) (xy 39.419021 -266.991284)
			(xy 39.410901 -267.04646) (xy 39.394833 -267.099867) (xy 39.371161 -267.150364) (xy 39.340388 -267.196877)
			(xy 39.303171 -267.238414) (xy 39.260303 -267.274089) (xy 39.212697 -267.303143) (xy 39.161368 -267.324955)
			(xy 39.107411 -267.339061) (xy 39.051974 -267.345161) (xy 38.99624 -267.343124) (xy 38.941397 -267.332994)
			(xy 38.888613 -267.314987) (xy 38.839013 -267.289486) (xy 38.793655 -267.257035) (xy 38.753506 -267.218326)
			(xy 38.71942 -267.174183) (xy 38.692124 -267.125548) (xy 38.672201 -267.073457) (xy 38.660075 -267.01902)
			(xy 38.656004 -266.963398) (xy 32.308409 -266.963398) (xy 32.354758 -266.99411) (xy 32.512829 -267.10846)
			(xy 32.666072 -267.229203) (xy 32.814229 -267.356137) (xy 32.95705 -267.489045) (xy 33.045174 -267.578078)
			(xy 36.853112 -267.578078) (xy 36.857183 -267.522456) (xy 36.869309 -267.468019) (xy 36.889232 -267.415928)
			(xy 36.916528 -267.367293) (xy 36.950614 -267.32315) (xy 36.990763 -267.284441) (xy 37.036121 -267.25199)
			(xy 37.085721 -267.226489) (xy 37.138505 -267.208482) (xy 37.193348 -267.198352) (xy 37.249082 -267.196315)
			(xy 37.304519 -267.202415) (xy 37.358476 -267.216521) (xy 37.409805 -267.238333) (xy 37.457411 -267.267387)
			(xy 37.500279 -267.303062) (xy 37.537496 -267.344599) (xy 37.568269 -267.391112) (xy 37.591941 -267.441609)
			(xy 37.608009 -267.495016) (xy 37.616129 -267.550192) (xy 37.616638 -267.578078) (xy 37.616129 -267.605964)
			(xy 37.608009 -267.66114) (xy 37.591941 -267.714547) (xy 37.568269 -267.765044) (xy 37.537496 -267.811557)
			(xy 37.500279 -267.853094) (xy 37.457411 -267.888769) (xy 37.409805 -267.917823) (xy 37.358476 -267.939635)
			(xy 37.304519 -267.953741) (xy 37.249082 -267.959841) (xy 37.193348 -267.957804) (xy 37.138505 -267.947674)
			(xy 37.085721 -267.929667) (xy 37.036121 -267.904166) (xy 36.990763 -267.871715) (xy 36.950614 -267.833006)
			(xy 36.916528 -267.788863) (xy 36.889232 -267.740228) (xy 36.869309 -267.688137) (xy 36.857183 -267.6337)
			(xy 36.853112 -267.578078) (xy 33.045174 -267.578078) (xy 33.094294 -267.627705) (xy 33.22573 -267.771883)
			(xy 33.351135 -267.921336) (xy 33.470299 -268.07581) (xy 33.58302 -268.235047) (xy 33.689109 -268.398778)
			(xy 33.788387 -268.566725) (xy 33.880685 -268.738608) (xy 33.96585 -268.914134) (xy 34.043736 -269.093009)
			(xy 34.114213 -269.274931) (xy 34.177161 -269.459593) (xy 34.232476 -269.646683) (xy 34.280062 -269.835887)
			(xy 34.319841 -270.026884) (xy 34.351745 -270.219354) (xy 34.37572 -270.412972) (xy 34.386802 -270.547592)
			(xy 39.118284 -270.547592) (xy 39.122355 -270.49197) (xy 39.134481 -270.437533) (xy 39.154404 -270.385442)
			(xy 39.1817 -270.336807) (xy 39.215786 -270.292664) (xy 39.255935 -270.253955) (xy 39.301293 -270.221504)
			(xy 39.350893 -270.196003) (xy 39.403677 -270.177996) (xy 39.45852 -270.167866) (xy 39.514254 -270.165829)
			(xy 39.569691 -270.171929) (xy 39.623648 -270.186035) (xy 39.674977 -270.207847) (xy 39.722583 -270.236901)
			(xy 39.765451 -270.272576) (xy 39.802668 -270.314113) (xy 39.833441 -270.360626) (xy 39.857113 -270.411123)
			(xy 39.873181 -270.46453) (xy 39.881301 -270.519706) (xy 39.88181 -270.547592) (xy 39.881301 -270.575478)
			(xy 39.873181 -270.630654) (xy 39.857113 -270.684061) (xy 39.833441 -270.734558) (xy 39.802668 -270.781071)
			(xy 39.765451 -270.822608) (xy 39.722583 -270.858283) (xy 39.674977 -270.887337) (xy 39.623648 -270.909149)
			(xy 39.569691 -270.923255) (xy 39.514254 -270.929355) (xy 39.45852 -270.927318) (xy 39.403677 -270.917188)
			(xy 39.350893 -270.899181) (xy 39.301293 -270.87368) (xy 39.255935 -270.841229) (xy 39.215786 -270.80252)
			(xy 39.1817 -270.758377) (xy 39.154404 -270.709742) (xy 39.134481 -270.657651) (xy 39.122355 -270.603214)
			(xy 39.118284 -270.547592) (xy 34.386802 -270.547592) (xy 34.391726 -270.60741) (xy 34.399735 -270.802342)
			(xy 34.400236 -270.89989) (xy 34.399735 -270.997438) (xy 34.391726 -271.19237) (xy 34.37572 -271.386808)
			(xy 34.351745 -271.580426) (xy 34.319841 -271.772896) (xy 34.280062 -271.963893) (xy 34.232476 -272.153097)
			(xy 34.177161 -272.340187) (xy 34.114213 -272.524849) (xy 34.07549 -272.624804) (xy 37.969202 -272.624804)
			(xy 37.973162 -272.57575) (xy 37.984939 -272.527966) (xy 38.00423 -272.48269) (xy 38.030533 -272.441094)
			(xy 38.063168 -272.404257) (xy 38.101289 -272.373132) (xy 38.14391 -272.348525) (xy 38.189926 -272.331073)
			(xy 38.238145 -272.321229) (xy 38.28732 -272.319248) (xy 38.336175 -272.32518) (xy 38.383446 -272.338872)
			(xy 38.427908 -272.35997) (xy 38.468411 -272.387926) (xy 38.503904 -272.422018) (xy 38.533469 -272.461362)
			(xy 38.55634 -272.504939) (xy 38.571924 -272.55162) (xy 38.579819 -272.600197) (xy 38.580314 -272.624804)
			(xy 38.919162 -272.624804) (xy 38.923122 -272.57575) (xy 38.934899 -272.527966) (xy 38.95419 -272.48269)
			(xy 38.980493 -272.441094) (xy 39.013128 -272.404257) (xy 39.051249 -272.373132) (xy 39.09387 -272.348525)
			(xy 39.139886 -272.331073) (xy 39.188105 -272.321229) (xy 39.23728 -272.319248) (xy 39.286135 -272.32518)
			(xy 39.333406 -272.338872) (xy 39.377868 -272.35997) (xy 39.418371 -272.387926) (xy 39.453864 -272.422018)
			(xy 39.483429 -272.461362) (xy 39.5063 -272.504939) (xy 39.521884 -272.55162) (xy 39.529779 -272.600197)
			(xy 39.530274 -272.624804) (xy 39.529779 -272.649411) (xy 39.521884 -272.697988) (xy 39.5063 -272.744669)
			(xy 39.483429 -272.788246) (xy 39.453864 -272.82759) (xy 39.418371 -272.861682) (xy 39.377868 -272.889638)
			(xy 39.333406 -272.910736) (xy 39.286135 -272.924428) (xy 39.23728 -272.93036) (xy 39.188105 -272.928379)
			(xy 39.139886 -272.918535) (xy 39.09387 -272.901083) (xy 39.051249 -272.876476) (xy 39.013128 -272.845351)
			(xy 38.980493 -272.808514) (xy 38.95419 -272.766918) (xy 38.934899 -272.721642) (xy 38.923122 -272.673858)
			(xy 38.919162 -272.624804) (xy 38.580314 -272.624804) (xy 38.579819 -272.649411) (xy 38.571924 -272.697988)
			(xy 38.55634 -272.744669) (xy 38.533469 -272.788246) (xy 38.503904 -272.82759) (xy 38.468411 -272.861682)
			(xy 38.427908 -272.889638) (xy 38.383446 -272.910736) (xy 38.336175 -272.924428) (xy 38.28732 -272.93036)
			(xy 38.238145 -272.928379) (xy 38.189926 -272.918535) (xy 38.14391 -272.901083) (xy 38.101289 -272.876476)
			(xy 38.063168 -272.845351) (xy 38.030533 -272.808514) (xy 38.00423 -272.766918) (xy 37.984939 -272.721642)
			(xy 37.973162 -272.673858) (xy 37.969202 -272.624804) (xy 34.07549 -272.624804) (xy 34.043736 -272.706771)
			(xy 33.96585 -272.885646) (xy 33.880685 -273.061172) (xy 33.788387 -273.233055) (xy 33.689109 -273.401002)
			(xy 33.58302 -273.564733) (xy 33.575919 -273.574764) (xy 37.018988 -273.574764) (xy 37.022948 -273.52571)
			(xy 37.034725 -273.477926) (xy 37.054016 -273.43265) (xy 37.080319 -273.391054) (xy 37.112954 -273.354217)
			(xy 37.151075 -273.323092) (xy 37.193696 -273.298485) (xy 37.239712 -273.281033) (xy 37.287931 -273.271189)
			(xy 37.337106 -273.269208) (xy 37.385961 -273.27514) (xy 37.433232 -273.288832) (xy 37.477694 -273.30993)
			(xy 37.518197 -273.337886) (xy 37.55369 -273.371978) (xy 37.583255 -273.411322) (xy 37.606126 -273.454899)
			(xy 37.62171 -273.50158) (xy 37.629605 -273.550157) (xy 37.6301 -273.574764) (xy 37.968948 -273.574764)
			(xy 37.972908 -273.52571) (xy 37.984685 -273.477926) (xy 38.003976 -273.43265) (xy 38.030279 -273.391054)
			(xy 38.062914 -273.354217) (xy 38.101035 -273.323092) (xy 38.143656 -273.298485) (xy 38.189672 -273.281033)
			(xy 38.237891 -273.271189) (xy 38.287066 -273.269208) (xy 38.335921 -273.27514) (xy 38.383192 -273.288832)
			(xy 38.427654 -273.30993) (xy 38.468157 -273.337886) (xy 38.50365 -273.371978) (xy 38.533215 -273.411322)
			(xy 38.556086 -273.454899) (xy 38.57167 -273.50158) (xy 38.579565 -273.550157) (xy 38.58006 -273.574764)
			(xy 38.919162 -273.574764) (xy 38.923122 -273.52571) (xy 38.934899 -273.477926) (xy 38.95419 -273.43265)
			(xy 38.980493 -273.391054) (xy 39.013128 -273.354217) (xy 39.051249 -273.323092) (xy 39.09387 -273.298485)
			(xy 39.139886 -273.281033) (xy 39.188105 -273.271189) (xy 39.23728 -273.269208) (xy 39.286135 -273.27514)
			(xy 39.333406 -273.288832) (xy 39.377868 -273.30993) (xy 39.418371 -273.337886) (xy 39.453864 -273.371978)
			(xy 39.483429 -273.411322) (xy 39.5063 -273.454899) (xy 39.521884 -273.50158) (xy 39.529779 -273.550157)
			(xy 39.530274 -273.574764) (xy 39.529779 -273.599371) (xy 39.521884 -273.647948) (xy 39.5063 -273.694629)
			(xy 39.483429 -273.738206) (xy 39.453864 -273.77755) (xy 39.418371 -273.811642) (xy 39.377868 -273.839598)
			(xy 39.333406 -273.860696) (xy 39.286135 -273.874388) (xy 39.23728 -273.88032) (xy 39.188105 -273.878339)
			(xy 39.139886 -273.868495) (xy 39.09387 -273.851043) (xy 39.051249 -273.826436) (xy 39.013128 -273.795311)
			(xy 38.980493 -273.758474) (xy 38.95419 -273.716878) (xy 38.934899 -273.671602) (xy 38.923122 -273.623818)
			(xy 38.919162 -273.574764) (xy 38.58006 -273.574764) (xy 38.579565 -273.599371) (xy 38.57167 -273.647948)
			(xy 38.556086 -273.694629) (xy 38.533215 -273.738206) (xy 38.50365 -273.77755) (xy 38.468157 -273.811642)
			(xy 38.427654 -273.839598) (xy 38.383192 -273.860696) (xy 38.335921 -273.874388) (xy 38.287066 -273.88032)
			(xy 38.237891 -273.878339) (xy 38.189672 -273.868495) (xy 38.143656 -273.851043) (xy 38.101035 -273.826436)
			(xy 38.062914 -273.795311) (xy 38.030279 -273.758474) (xy 38.003976 -273.716878) (xy 37.984685 -273.671602)
			(xy 37.972908 -273.623818) (xy 37.968948 -273.574764) (xy 37.6301 -273.574764) (xy 37.629605 -273.599371)
			(xy 37.62171 -273.647948) (xy 37.606126 -273.694629) (xy 37.583255 -273.738206) (xy 37.55369 -273.77755)
			(xy 37.518197 -273.811642) (xy 37.477694 -273.839598) (xy 37.433232 -273.860696) (xy 37.385961 -273.874388)
			(xy 37.337106 -273.88032) (xy 37.287931 -273.878339) (xy 37.239712 -273.868495) (xy 37.193696 -273.851043)
			(xy 37.151075 -273.826436) (xy 37.112954 -273.795311) (xy 37.080319 -273.758474) (xy 37.054016 -273.716878)
			(xy 37.034725 -273.671602) (xy 37.022948 -273.623818) (xy 37.018988 -273.574764) (xy 33.575919 -273.574764)
			(xy 33.470299 -273.72397) (xy 33.351135 -273.878444) (xy 33.22573 -274.027897) (xy 33.094294 -274.172075)
			(xy 32.95705 -274.310735) (xy 32.814229 -274.443643) (xy 32.719591 -274.524724) (xy 37.018988 -274.524724)
			(xy 37.022948 -274.47567) (xy 37.034725 -274.427886) (xy 37.054016 -274.38261) (xy 37.080319 -274.341014)
			(xy 37.112954 -274.304177) (xy 37.151075 -274.273052) (xy 37.193696 -274.248445) (xy 37.239712 -274.230993)
			(xy 37.287931 -274.221149) (xy 37.337106 -274.219168) (xy 37.385961 -274.2251) (xy 37.433232 -274.238792)
			(xy 37.477694 -274.25989) (xy 37.518197 -274.287846) (xy 37.55369 -274.321938) (xy 37.583255 -274.361282)
			(xy 37.606126 -274.404859) (xy 37.62171 -274.45154) (xy 37.629605 -274.500117) (xy 37.6301 -274.524724)
			(xy 37.630095 -274.524978) (xy 37.969202 -274.524978) (xy 37.973162 -274.475924) (xy 37.984939 -274.42814)
			(xy 38.00423 -274.382864) (xy 38.030533 -274.341268) (xy 38.063168 -274.304431) (xy 38.101289 -274.273306)
			(xy 38.14391 -274.248699) (xy 38.189926 -274.231247) (xy 38.238145 -274.221403) (xy 38.28732 -274.219422)
			(xy 38.336175 -274.225354) (xy 38.383446 -274.239046) (xy 38.427908 -274.260144) (xy 38.468411 -274.2881)
			(xy 38.503904 -274.322192) (xy 38.533469 -274.361536) (xy 38.55634 -274.405113) (xy 38.571924 -274.451794)
			(xy 38.579819 -274.500371) (xy 38.580314 -274.524978) (xy 38.919162 -274.524978) (xy 38.923122 -274.475924)
			(xy 38.934899 -274.42814) (xy 38.95419 -274.382864) (xy 38.980493 -274.341268) (xy 39.013128 -274.304431)
			(xy 39.051249 -274.273306) (xy 39.09387 -274.248699) (xy 39.139886 -274.231247) (xy 39.188105 -274.221403)
			(xy 39.23728 -274.219422) (xy 39.286135 -274.225354) (xy 39.333406 -274.239046) (xy 39.377868 -274.260144)
			(xy 39.418371 -274.2881) (xy 39.453864 -274.322192) (xy 39.483429 -274.361536) (xy 39.5063 -274.405113)
			(xy 39.521884 -274.451794) (xy 39.529779 -274.500371) (xy 39.530274 -274.524978) (xy 39.529779 -274.549585)
			(xy 39.521884 -274.598162) (xy 39.5063 -274.644843) (xy 39.483429 -274.68842) (xy 39.453864 -274.727764)
			(xy 39.418371 -274.761856) (xy 39.377868 -274.789812) (xy 39.333406 -274.81091) (xy 39.286135 -274.824602)
			(xy 39.23728 -274.830534) (xy 39.188105 -274.828553) (xy 39.139886 -274.818709) (xy 39.09387 -274.801257)
			(xy 39.051249 -274.77665) (xy 39.013128 -274.745525) (xy 38.980493 -274.708688) (xy 38.95419 -274.667092)
			(xy 38.934899 -274.621816) (xy 38.923122 -274.574032) (xy 38.919162 -274.524978) (xy 38.580314 -274.524978)
			(xy 38.579819 -274.549585) (xy 38.571924 -274.598162) (xy 38.55634 -274.644843) (xy 38.533469 -274.68842)
			(xy 38.503904 -274.727764) (xy 38.468411 -274.761856) (xy 38.427908 -274.789812) (xy 38.383446 -274.81091)
			(xy 38.336175 -274.824602) (xy 38.28732 -274.830534) (xy 38.238145 -274.828553) (xy 38.189926 -274.818709)
			(xy 38.14391 -274.801257) (xy 38.101289 -274.77665) (xy 38.063168 -274.745525) (xy 38.030533 -274.708688)
			(xy 38.00423 -274.667092) (xy 37.984939 -274.621816) (xy 37.973162 -274.574032) (xy 37.969202 -274.524978)
			(xy 37.630095 -274.524978) (xy 37.629605 -274.549331) (xy 37.62171 -274.597908) (xy 37.606126 -274.644589)
			(xy 37.583255 -274.688166) (xy 37.55369 -274.72751) (xy 37.518197 -274.761602) (xy 37.477694 -274.789558)
			(xy 37.433232 -274.810656) (xy 37.385961 -274.824348) (xy 37.337106 -274.83028) (xy 37.287931 -274.828299)
			(xy 37.239712 -274.818455) (xy 37.193696 -274.801003) (xy 37.151075 -274.776396) (xy 37.112954 -274.745271)
			(xy 37.080319 -274.708434) (xy 37.054016 -274.666838) (xy 37.034725 -274.621562) (xy 37.022948 -274.573778)
			(xy 37.018988 -274.524724) (xy 32.719591 -274.524724) (xy 32.666072 -274.570577) (xy 32.512829 -274.69132)
			(xy 32.354758 -274.80567) (xy 32.192125 -274.913435) (xy 32.025206 -275.014431) (xy 31.85428 -275.10849)
			(xy 31.679637 -275.195452) (xy 31.501571 -275.27517) (xy 31.320383 -275.347511) (xy 31.136377 -275.412352)
			(xy 30.949864 -275.469584) (xy 30.929464 -275.474938) (xy 36.069028 -275.474938) (xy 36.072988 -275.425884)
			(xy 36.084765 -275.3781) (xy 36.104056 -275.332824) (xy 36.130359 -275.291228) (xy 36.162994 -275.254391)
			(xy 36.201115 -275.223266) (xy 36.243736 -275.198659) (xy 36.289752 -275.181207) (xy 36.337971 -275.171363)
			(xy 36.387146 -275.169382) (xy 36.436001 -275.175314) (xy 36.483272 -275.189006) (xy 36.527734 -275.210104)
			(xy 36.568237 -275.23806) (xy 36.60373 -275.272152) (xy 36.633295 -275.311496) (xy 36.656166 -275.355073)
			(xy 36.67175 -275.401754) (xy 36.679645 -275.450331) (xy 36.68014 -275.474938) (xy 37.018988 -275.474938)
			(xy 37.022948 -275.425884) (xy 37.034725 -275.3781) (xy 37.054016 -275.332824) (xy 37.080319 -275.291228)
			(xy 37.112954 -275.254391) (xy 37.151075 -275.223266) (xy 37.193696 -275.198659) (xy 37.239712 -275.181207)
			(xy 37.287931 -275.171363) (xy 37.337106 -275.169382) (xy 37.385961 -275.175314) (xy 37.433232 -275.189006)
			(xy 37.477694 -275.210104) (xy 37.518197 -275.23806) (xy 37.55369 -275.272152) (xy 37.583255 -275.311496)
			(xy 37.606126 -275.355073) (xy 37.62171 -275.401754) (xy 37.629605 -275.450331) (xy 37.6301 -275.474938)
			(xy 37.969202 -275.474938) (xy 37.973162 -275.425884) (xy 37.984939 -275.3781) (xy 38.00423 -275.332824)
			(xy 38.030533 -275.291228) (xy 38.063168 -275.254391) (xy 38.101289 -275.223266) (xy 38.14391 -275.198659)
			(xy 38.189926 -275.181207) (xy 38.238145 -275.171363) (xy 38.28732 -275.169382) (xy 38.336175 -275.175314)
			(xy 38.383446 -275.189006) (xy 38.427908 -275.210104) (xy 38.468411 -275.23806) (xy 38.503904 -275.272152)
			(xy 38.533469 -275.311496) (xy 38.55634 -275.355073) (xy 38.571924 -275.401754) (xy 38.579819 -275.450331)
			(xy 38.580314 -275.474938) (xy 38.919162 -275.474938) (xy 38.923122 -275.425884) (xy 38.934899 -275.3781)
			(xy 38.95419 -275.332824) (xy 38.980493 -275.291228) (xy 39.013128 -275.254391) (xy 39.051249 -275.223266)
			(xy 39.09387 -275.198659) (xy 39.139886 -275.181207) (xy 39.188105 -275.171363) (xy 39.23728 -275.169382)
			(xy 39.286135 -275.175314) (xy 39.333406 -275.189006) (xy 39.377868 -275.210104) (xy 39.418371 -275.23806)
			(xy 39.453864 -275.272152) (xy 39.483429 -275.311496) (xy 39.5063 -275.355073) (xy 39.521884 -275.401754)
			(xy 39.529779 -275.450331) (xy 39.530274 -275.474938) (xy 39.529779 -275.499545) (xy 39.521884 -275.548122)
			(xy 39.5063 -275.594803) (xy 39.483429 -275.63838) (xy 39.453864 -275.677724) (xy 39.418371 -275.711816)
			(xy 39.377868 -275.739772) (xy 39.333406 -275.76087) (xy 39.286135 -275.774562) (xy 39.23728 -275.780494)
			(xy 39.188105 -275.778513) (xy 39.139886 -275.768669) (xy 39.09387 -275.751217) (xy 39.051249 -275.72661)
			(xy 39.013128 -275.695485) (xy 38.980493 -275.658648) (xy 38.95419 -275.617052) (xy 38.934899 -275.571776)
			(xy 38.923122 -275.523992) (xy 38.919162 -275.474938) (xy 38.580314 -275.474938) (xy 38.579819 -275.499545)
			(xy 38.571924 -275.548122) (xy 38.55634 -275.594803) (xy 38.533469 -275.63838) (xy 38.503904 -275.677724)
			(xy 38.468411 -275.711816) (xy 38.427908 -275.739772) (xy 38.383446 -275.76087) (xy 38.336175 -275.774562)
			(xy 38.28732 -275.780494) (xy 38.238145 -275.778513) (xy 38.189926 -275.768669) (xy 38.14391 -275.751217)
			(xy 38.101289 -275.72661) (xy 38.063168 -275.695485) (xy 38.030533 -275.658648) (xy 38.00423 -275.617052)
			(xy 37.984939 -275.571776) (xy 37.973162 -275.523992) (xy 37.969202 -275.474938) (xy 37.6301 -275.474938)
			(xy 37.629605 -275.499545) (xy 37.62171 -275.548122) (xy 37.606126 -275.594803) (xy 37.583255 -275.63838)
			(xy 37.55369 -275.677724) (xy 37.518197 -275.711816) (xy 37.477694 -275.739772) (xy 37.433232 -275.76087)
			(xy 37.385961 -275.774562) (xy 37.337106 -275.780494) (xy 37.287931 -275.778513) (xy 37.239712 -275.768669)
			(xy 37.193696 -275.751217) (xy 37.151075 -275.72661) (xy 37.112954 -275.695485) (xy 37.080319 -275.658648)
			(xy 37.054016 -275.617052) (xy 37.034725 -275.571776) (xy 37.022948 -275.523992) (xy 37.018988 -275.474938)
			(xy 36.68014 -275.474938) (xy 36.679645 -275.499545) (xy 36.67175 -275.548122) (xy 36.656166 -275.594803)
			(xy 36.633295 -275.63838) (xy 36.60373 -275.677724) (xy 36.568237 -275.711816) (xy 36.527734 -275.739772)
			(xy 36.483272 -275.76087) (xy 36.436001 -275.774562) (xy 36.387146 -275.780494) (xy 36.337971 -275.778513)
			(xy 36.289752 -275.768669) (xy 36.243736 -275.751217) (xy 36.201115 -275.72661) (xy 36.162994 -275.695485)
			(xy 36.130359 -275.658648) (xy 36.104056 -275.617052) (xy 36.084765 -275.571776) (xy 36.072988 -275.523992)
			(xy 36.069028 -275.474938) (xy 30.929464 -275.474938) (xy 30.761159 -275.519111) (xy 30.57058 -275.560848)
			(xy 30.378447 -275.594726) (xy 30.185086 -275.620688) (xy 29.990822 -275.638689) (xy 29.795983 -275.6487)
			(xy 29.600897 -275.650703) (xy 29.405894 -275.644695) (xy 29.211301 -275.630686) (xy 29.017448 -275.6087)
			(xy 28.824661 -275.578774) (xy 28.633264 -275.540958) (xy 28.443582 -275.495316) (xy 28.255934 -275.441926)
			(xy 28.070635 -275.380876) (xy 27.888 -275.312271) (xy 27.708335 -275.236225) (xy 27.531943 -275.152867)
			(xy 27.359122 -275.062338) (xy 27.190164 -274.96479) (xy 27.025353 -274.860387) (xy 26.864967 -274.749307)
			(xy 26.709277 -274.631735) (xy 26.558545 -274.507871) (xy 26.413026 -274.377922) (xy 26.272964 -274.242109)
			(xy 26.138596 -274.10066) (xy 26.010149 -273.953814) (xy 25.887838 -273.801819) (xy 25.771871 -273.64493)
			(xy 25.662443 -273.483412) (xy 25.559738 -273.317538) (xy 25.46393 -273.147587) (xy 25.375179 -272.973846)
			(xy 25.293637 -272.796608) (xy 25.21944 -272.616172) (xy 25.152713 -272.432841) (xy 25.093569 -272.246926)
			(xy 25.042108 -272.058739) (xy 24.998416 -271.868599) (xy 24.962567 -271.676824) (xy 24.934622 -271.48374)
			(xy 24.914627 -271.289671) (xy 24.902617 -271.094945) (xy 24.898611 -270.89989) (xy 18.11018 -270.89989)
			(xy 18.121857 -270.909608) (xy 18.159074 -270.951145) (xy 18.189847 -270.997658) (xy 18.213519 -271.048155)
			(xy 18.229587 -271.101562) (xy 18.237707 -271.156738) (xy 18.238216 -271.184624) (xy 18.237707 -271.21251)
			(xy 18.229587 -271.267686) (xy 18.213519 -271.321093) (xy 18.189847 -271.37159) (xy 18.159074 -271.418103)
			(xy 18.121857 -271.45964) (xy 18.078989 -271.495315) (xy 18.031383 -271.524369) (xy 17.980054 -271.546181)
			(xy 17.926097 -271.560287) (xy 17.87066 -271.566387) (xy 17.814926 -271.56435) (xy 17.760083 -271.55422)
			(xy 17.707299 -271.536213) (xy 17.657699 -271.510712) (xy 17.612341 -271.478261) (xy 17.572192 -271.439552)
			(xy 17.538106 -271.395409) (xy 17.51081 -271.346774) (xy 17.490887 -271.294683) (xy 17.478761 -271.240246)
			(xy 17.47469 -271.184624) (xy 1.660398 -271.184624) (xy 1.660398 -271.549114) (xy 1.677924 -271.575022)
			(xy 1.692402 -271.58061) (xy 1.718646 -271.591609) (xy 1.767813 -271.620249) (xy 1.812183 -271.655873)
			(xy 1.85077 -271.697691) (xy 1.88272 -271.744775) (xy 1.907324 -271.796082) (xy 1.924035 -271.850473)
			(xy 1.932485 -271.906744) (xy 1.932485 -271.963644) (xy 1.924035 -272.019915) (xy 1.907324 -272.074306)
			(xy 1.88272 -272.125613) (xy 1.85077 -272.172697) (xy 1.812183 -272.214515) (xy 1.767813 -272.250139)
			(xy 1.718646 -272.278779) (xy 1.692402 -272.289778) (xy 1.677924 -272.295366) (xy 1.660398 -272.321274)
			(xy 1.660398 -272.345912) (xy 11.635738 -272.345912) (xy 11.639809 -272.29029) (xy 11.651935 -272.235853)
			(xy 11.671858 -272.183762) (xy 11.699154 -272.135127) (xy 11.73324 -272.090984) (xy 11.773389 -272.052275)
			(xy 11.818747 -272.019824) (xy 11.868347 -271.994323) (xy 11.921131 -271.976316) (xy 11.975974 -271.966186)
			(xy 12.031708 -271.964149) (xy 12.087145 -271.970249) (xy 12.141102 -271.984355) (xy 12.192431 -272.006167)
			(xy 12.240037 -272.035221) (xy 12.282905 -272.070896) (xy 12.320122 -272.112433) (xy 12.350895 -272.158946)
			(xy 12.374567 -272.209443) (xy 12.390635 -272.26285) (xy 12.398755 -272.318026) (xy 12.399264 -272.345912)
			(xy 12.398755 -272.373798) (xy 12.390635 -272.428974) (xy 12.374894 -272.481294) (xy 13.765528 -272.481294)
			(xy 13.769599 -272.425672) (xy 13.781725 -272.371235) (xy 13.801648 -272.319144) (xy 13.828944 -272.270509)
			(xy 13.86303 -272.226366) (xy 13.903179 -272.187657) (xy 13.948537 -272.155206) (xy 13.998137 -272.129705)
			(xy 14.050921 -272.111698) (xy 14.105764 -272.101568) (xy 14.161498 -272.099531) (xy 14.216935 -272.105631)
			(xy 14.270892 -272.119737) (xy 14.322221 -272.141549) (xy 14.369827 -272.170603) (xy 14.405901 -272.200624)
			(xy 17.412968 -272.200624) (xy 17.417039 -272.145002) (xy 17.429165 -272.090565) (xy 17.449088 -272.038474)
			(xy 17.476384 -271.989839) (xy 17.51047 -271.945696) (xy 17.550619 -271.906987) (xy 17.595977 -271.874536)
			(xy 17.645577 -271.849035) (xy 17.698361 -271.831028) (xy 17.753204 -271.820898) (xy 17.808938 -271.818861)
			(xy 17.864375 -271.824961) (xy 17.918332 -271.839067) (xy 17.969661 -271.860879) (xy 18.017267 -271.889933)
			(xy 18.060135 -271.925608) (xy 18.097352 -271.967145) (xy 18.128125 -272.013658) (xy 18.151797 -272.064155)
			(xy 18.167865 -272.117562) (xy 18.175985 -272.172738) (xy 18.176494 -272.200624) (xy 18.175985 -272.22851)
			(xy 18.167865 -272.283686) (xy 18.151797 -272.337093) (xy 18.128125 -272.38759) (xy 18.097352 -272.434103)
			(xy 18.060135 -272.47564) (xy 18.017267 -272.511315) (xy 17.969661 -272.540369) (xy 17.918332 -272.562181)
			(xy 17.864375 -272.576287) (xy 17.808938 -272.582387) (xy 17.753204 -272.58035) (xy 17.698361 -272.57022)
			(xy 17.645577 -272.552213) (xy 17.595977 -272.526712) (xy 17.550619 -272.494261) (xy 17.51047 -272.455552)
			(xy 17.476384 -272.411409) (xy 17.449088 -272.362774) (xy 17.429165 -272.310683) (xy 17.417039 -272.256246)
			(xy 17.412968 -272.200624) (xy 14.405901 -272.200624) (xy 14.412695 -272.206278) (xy 14.449912 -272.247815)
			(xy 14.480685 -272.294328) (xy 14.504357 -272.344825) (xy 14.520425 -272.398232) (xy 14.528545 -272.453408)
			(xy 14.529054 -272.481294) (xy 14.528545 -272.50918) (xy 14.520425 -272.564356) (xy 14.504357 -272.617763)
			(xy 14.480685 -272.66826) (xy 14.449912 -272.714773) (xy 14.412695 -272.75631) (xy 14.369827 -272.791985)
			(xy 14.322221 -272.821039) (xy 14.270892 -272.842851) (xy 14.216935 -272.856957) (xy 14.161498 -272.863057)
			(xy 14.105764 -272.86102) (xy 14.050921 -272.85089) (xy 13.998137 -272.832883) (xy 13.948537 -272.807382)
			(xy 13.903179 -272.774931) (xy 13.86303 -272.736222) (xy 13.828944 -272.692079) (xy 13.801648 -272.643444)
			(xy 13.781725 -272.591353) (xy 13.769599 -272.536916) (xy 13.765528 -272.481294) (xy 12.374894 -272.481294)
			(xy 12.374567 -272.482381) (xy 12.350895 -272.532878) (xy 12.320122 -272.579391) (xy 12.282905 -272.620928)
			(xy 12.240037 -272.656603) (xy 12.192431 -272.685657) (xy 12.141102 -272.707469) (xy 12.087145 -272.721575)
			(xy 12.031708 -272.727675) (xy 11.975974 -272.725638) (xy 11.921131 -272.715508) (xy 11.868347 -272.697501)
			(xy 11.818747 -272.672) (xy 11.773389 -272.639549) (xy 11.73324 -272.60084) (xy 11.699154 -272.556697)
			(xy 11.671858 -272.508062) (xy 11.651935 -272.455971) (xy 11.639809 -272.401534) (xy 11.635738 -272.345912)
			(xy 1.660398 -272.345912) (xy 1.660398 -272.911062) (xy 1.665369 -272.918174) (xy 15.261334 -272.918174)
			(xy 15.265405 -272.862552) (xy 15.277531 -272.808115) (xy 15.297454 -272.756024) (xy 15.32475 -272.707389)
			(xy 15.358836 -272.663246) (xy 15.398985 -272.624537) (xy 15.444343 -272.592086) (xy 15.493943 -272.566585)
			(xy 15.546727 -272.548578) (xy 15.60157 -272.538448) (xy 15.657304 -272.536411) (xy 15.712741 -272.542511)
			(xy 15.766698 -272.556617) (xy 15.818027 -272.578429) (xy 15.865633 -272.607483) (xy 15.908501 -272.643158)
			(xy 15.945718 -272.684695) (xy 15.976491 -272.731208) (xy 16.000163 -272.781705) (xy 16.016231 -272.835112)
			(xy 16.024351 -272.890288) (xy 16.02486 -272.918174) (xy 16.024351 -272.94606) (xy 16.016231 -273.001236)
			(xy 16.000163 -273.054643) (xy 15.976491 -273.10514) (xy 15.945718 -273.151653) (xy 15.908501 -273.19319)
			(xy 15.880342 -273.216624) (xy 17.412968 -273.216624) (xy 17.417039 -273.161002) (xy 17.429165 -273.106565)
			(xy 17.449088 -273.054474) (xy 17.476384 -273.005839) (xy 17.51047 -272.961696) (xy 17.550619 -272.922987)
			(xy 17.595977 -272.890536) (xy 17.645577 -272.865035) (xy 17.698361 -272.847028) (xy 17.753204 -272.836898)
			(xy 17.808938 -272.834861) (xy 17.864375 -272.840961) (xy 17.918332 -272.855067) (xy 17.969661 -272.876879)
			(xy 18.017267 -272.905933) (xy 18.060135 -272.941608) (xy 18.097352 -272.983145) (xy 18.128125 -273.029658)
			(xy 18.151797 -273.080155) (xy 18.167865 -273.133562) (xy 18.175985 -273.188738) (xy 18.176494 -273.216624)
			(xy 18.175985 -273.24451) (xy 18.167865 -273.299686) (xy 18.151797 -273.353093) (xy 18.128125 -273.40359)
			(xy 18.097352 -273.450103) (xy 18.060135 -273.49164) (xy 18.017267 -273.527315) (xy 17.969661 -273.556369)
			(xy 17.918332 -273.578181) (xy 17.864375 -273.592287) (xy 17.808938 -273.598387) (xy 17.753204 -273.59635)
			(xy 17.698361 -273.58622) (xy 17.645577 -273.568213) (xy 17.595977 -273.542712) (xy 17.550619 -273.510261)
			(xy 17.51047 -273.471552) (xy 17.476384 -273.427409) (xy 17.449088 -273.378774) (xy 17.429165 -273.326683)
			(xy 17.417039 -273.272246) (xy 17.412968 -273.216624) (xy 15.880342 -273.216624) (xy 15.865633 -273.228865)
			(xy 15.818027 -273.257919) (xy 15.766698 -273.279731) (xy 15.712741 -273.293837) (xy 15.657304 -273.299937)
			(xy 15.60157 -273.2979) (xy 15.546727 -273.28777) (xy 15.493943 -273.269763) (xy 15.444343 -273.244262)
			(xy 15.398985 -273.211811) (xy 15.358836 -273.173102) (xy 15.32475 -273.128959) (xy 15.297454 -273.080324)
			(xy 15.277531 -273.028233) (xy 15.265405 -272.973796) (xy 15.261334 -272.918174) (xy 1.665369 -272.918174)
			(xy 1.678686 -272.937224) (xy 1.693926 -272.942812) (xy 1.719664 -272.95256) (xy 1.768257 -272.978402)
			(xy 1.812629 -273.010962) (xy 1.85186 -273.049563) (xy 1.885133 -273.093403) (xy 1.911757 -273.141572)
			(xy 1.93118 -273.193067) (xy 1.942998 -273.24682) (xy 1.946964 -273.301714) (xy 1.942998 -273.356608)
			(xy 1.93118 -273.410361) (xy 1.911757 -273.461856) (xy 1.885133 -273.510025) (xy 1.85186 -273.553865)
			(xy 1.812629 -273.592466) (xy 1.768257 -273.625026) (xy 1.719664 -273.650868) (xy 1.693926 -273.660616)
			(xy 1.678686 -273.666204) (xy 1.660398 -273.692366) (xy 1.660398 -274.082256) (xy 10.07567 -274.082256)
			(xy 10.079741 -274.026634) (xy 10.091867 -273.972197) (xy 10.11179 -273.920106) (xy 10.139086 -273.871471)
			(xy 10.173172 -273.827328) (xy 10.213321 -273.788619) (xy 10.258679 -273.756168) (xy 10.308279 -273.730667)
			(xy 10.361063 -273.71266) (xy 10.415906 -273.70253) (xy 10.47164 -273.700493) (xy 10.527077 -273.706593)
			(xy 10.581034 -273.720699) (xy 10.632363 -273.742511) (xy 10.679969 -273.771565) (xy 10.722837 -273.80724)
			(xy 10.760054 -273.848777) (xy 10.790827 -273.89529) (xy 10.814499 -273.945787) (xy 10.830567 -273.999194)
			(xy 10.838687 -274.05437) (xy 10.839196 -274.082256) (xy 10.838687 -274.110142) (xy 10.830567 -274.165318)
			(xy 10.814499 -274.218725) (xy 10.807983 -274.232624) (xy 15.393668 -274.232624) (xy 15.397739 -274.177002)
			(xy 15.409865 -274.122565) (xy 15.429788 -274.070474) (xy 15.457084 -274.021839) (xy 15.49117 -273.977696)
			(xy 15.531319 -273.938987) (xy 15.576677 -273.906536) (xy 15.626277 -273.881035) (xy 15.679061 -273.863028)
			(xy 15.733904 -273.852898) (xy 15.789638 -273.850861) (xy 15.845075 -273.856961) (xy 15.899032 -273.871067)
			(xy 15.950361 -273.892879) (xy 15.997967 -273.921933) (xy 16.040835 -273.957608) (xy 16.078052 -273.999145)
			(xy 16.108825 -274.045658) (xy 16.132497 -274.096155) (xy 16.148565 -274.149562) (xy 16.156685 -274.204738)
			(xy 16.157194 -274.232624) (xy 17.412968 -274.232624) (xy 17.417039 -274.177002) (xy 17.429165 -274.122565)
			(xy 17.449088 -274.070474) (xy 17.476384 -274.021839) (xy 17.51047 -273.977696) (xy 17.550619 -273.938987)
			(xy 17.595977 -273.906536) (xy 17.645577 -273.881035) (xy 17.698361 -273.863028) (xy 17.753204 -273.852898)
			(xy 17.808938 -273.850861) (xy 17.864375 -273.856961) (xy 17.918332 -273.871067) (xy 17.969661 -273.892879)
			(xy 18.017267 -273.921933) (xy 18.060135 -273.957608) (xy 18.097352 -273.999145) (xy 18.128125 -274.045658)
			(xy 18.151797 -274.096155) (xy 18.167865 -274.149562) (xy 18.175985 -274.204738) (xy 18.176494 -274.232624)
			(xy 18.175985 -274.26051) (xy 18.167865 -274.315686) (xy 18.151797 -274.369093) (xy 18.128125 -274.41959)
			(xy 18.097352 -274.466103) (xy 18.060135 -274.50764) (xy 18.017267 -274.543315) (xy 17.969661 -274.572369)
			(xy 17.918332 -274.594181) (xy 17.864375 -274.608287) (xy 17.808938 -274.614387) (xy 17.753204 -274.61235)
			(xy 17.698361 -274.60222) (xy 17.645577 -274.584213) (xy 17.595977 -274.558712) (xy 17.550619 -274.526261)
			(xy 17.51047 -274.487552) (xy 17.476384 -274.443409) (xy 17.449088 -274.394774) (xy 17.429165 -274.342683)
			(xy 17.417039 -274.288246) (xy 17.412968 -274.232624) (xy 16.157194 -274.232624) (xy 16.156685 -274.26051)
			(xy 16.148565 -274.315686) (xy 16.132497 -274.369093) (xy 16.108825 -274.41959) (xy 16.078052 -274.466103)
			(xy 16.040835 -274.50764) (xy 15.997967 -274.543315) (xy 15.950361 -274.572369) (xy 15.899032 -274.594181)
			(xy 15.845075 -274.608287) (xy 15.789638 -274.614387) (xy 15.733904 -274.61235) (xy 15.679061 -274.60222)
			(xy 15.626277 -274.584213) (xy 15.576677 -274.558712) (xy 15.531319 -274.526261) (xy 15.49117 -274.487552)
			(xy 15.457084 -274.443409) (xy 15.429788 -274.394774) (xy 15.409865 -274.342683) (xy 15.397739 -274.288246)
			(xy 15.393668 -274.232624) (xy 10.807983 -274.232624) (xy 10.790827 -274.269222) (xy 10.760054 -274.315735)
			(xy 10.722837 -274.357272) (xy 10.679969 -274.392947) (xy 10.632363 -274.422001) (xy 10.581034 -274.443813)
			(xy 10.527077 -274.457919) (xy 10.47164 -274.464019) (xy 10.415906 -274.461982) (xy 10.361063 -274.451852)
			(xy 10.308279 -274.433845) (xy 10.258679 -274.408344) (xy 10.213321 -274.375893) (xy 10.173172 -274.337184)
			(xy 10.139086 -274.293041) (xy 10.11179 -274.244406) (xy 10.091867 -274.192315) (xy 10.079741 -274.137878)
			(xy 10.07567 -274.082256) (xy 1.660398 -274.082256) (xy 1.660398 -274.270724) (xy 1.676908 -274.296124)
			(xy 1.690878 -274.30222) (xy 1.715946 -274.313765) (xy 1.762749 -274.343011) (xy 1.804849 -274.378697)
			(xy 1.841367 -274.420077) (xy 1.87154 -274.466288) (xy 1.894739 -274.516365) (xy 1.91048 -274.569262)
			(xy 1.918433 -274.623875) (xy 1.918433 -274.679065) (xy 1.91048 -274.733678) (xy 1.894739 -274.786575)
			(xy 1.87154 -274.836652) (xy 1.841367 -274.882863) (xy 1.804849 -274.924243) (xy 1.802125 -274.926552)
			(xy 12.410946 -274.926552) (xy 12.415017 -274.87093) (xy 12.427143 -274.816493) (xy 12.447066 -274.764402)
			(xy 12.474362 -274.715767) (xy 12.508448 -274.671624) (xy 12.548597 -274.632915) (xy 12.593955 -274.600464)
			(xy 12.643555 -274.574963) (xy 12.696339 -274.556956) (xy 12.751182 -274.546826) (xy 12.806916 -274.544789)
			(xy 12.862353 -274.550889) (xy 12.91631 -274.564995) (xy 12.967639 -274.586807) (xy 13.015245 -274.615861)
			(xy 13.058113 -274.651536) (xy 13.09533 -274.693073) (xy 13.126103 -274.739586) (xy 13.149775 -274.790083)
			(xy 13.165843 -274.84349) (xy 13.173963 -274.898666) (xy 13.174263 -274.915122) (xy 13.600428 -274.915122)
			(xy 13.604499 -274.8595) (xy 13.616625 -274.805063) (xy 13.636548 -274.752972) (xy 13.663844 -274.704337)
			(xy 13.69793 -274.660194) (xy 13.738079 -274.621485) (xy 13.783437 -274.589034) (xy 13.833037 -274.563533)
			(xy 13.885821 -274.545526) (xy 13.940664 -274.535396) (xy 13.996398 -274.533359) (xy 14.051835 -274.539459)
			(xy 14.105792 -274.553565) (xy 14.157121 -274.575377) (xy 14.204727 -274.604431) (xy 14.247595 -274.640106)
			(xy 14.284812 -274.681643) (xy 14.315585 -274.728156) (xy 14.339257 -274.778653) (xy 14.355325 -274.83206)
			(xy 14.363445 -274.887236) (xy 14.363954 -274.915122) (xy 14.363445 -274.943008) (xy 14.355325 -274.998184)
			(xy 14.339257 -275.051591) (xy 14.315585 -275.102088) (xy 14.284812 -275.148601) (xy 14.247595 -275.190138)
			(xy 14.204727 -275.225813) (xy 14.157121 -275.254867) (xy 14.105792 -275.276679) (xy 14.051835 -275.290785)
			(xy 13.996398 -275.296885) (xy 13.940664 -275.294848) (xy 13.885821 -275.284718) (xy 13.833037 -275.266711)
			(xy 13.783437 -275.24121) (xy 13.738079 -275.208759) (xy 13.69793 -275.17005) (xy 13.663844 -275.125907)
			(xy 13.636548 -275.077272) (xy 13.616625 -275.025181) (xy 13.604499 -274.970744) (xy 13.600428 -274.915122)
			(xy 13.174263 -274.915122) (xy 13.174472 -274.926552) (xy 13.173963 -274.954438) (xy 13.165843 -275.009614)
			(xy 13.149775 -275.063021) (xy 13.126103 -275.113518) (xy 13.09533 -275.160031) (xy 13.058113 -275.201568)
			(xy 13.015245 -275.237243) (xy 12.967639 -275.266297) (xy 12.91631 -275.288109) (xy 12.862353 -275.302215)
			(xy 12.806916 -275.308315) (xy 12.751182 -275.306278) (xy 12.696339 -275.296148) (xy 12.643555 -275.278141)
			(xy 12.593955 -275.25264) (xy 12.548597 -275.220189) (xy 12.508448 -275.18148) (xy 12.474362 -275.137337)
			(xy 12.447066 -275.088702) (xy 12.427143 -275.036611) (xy 12.415017 -274.982174) (xy 12.410946 -274.926552)
			(xy 1.802125 -274.926552) (xy 1.762749 -274.959929) (xy 1.715946 -274.989175) (xy 1.690878 -275.00072)
			(xy 1.676908 -275.006816) (xy 1.660398 -275.032216) (xy 1.660398 -275.601684) (xy 1.676908 -275.627084)
			(xy 1.690878 -275.63318) (xy 1.715997 -275.644705) (xy 1.762902 -275.67393) (xy 1.805099 -275.709617)
			(xy 1.841705 -275.75102) (xy 1.871954 -275.797271) (xy 1.895212 -275.847402) (xy 1.910994 -275.900366)
			(xy 1.917738 -275.946616) (xy 10.886692 -275.946616) (xy 10.890763 -275.890994) (xy 10.902889 -275.836557)
			(xy 10.922812 -275.784466) (xy 10.950108 -275.735831) (xy 10.984194 -275.691688) (xy 11.024343 -275.652979)
			(xy 11.069701 -275.620528) (xy 11.119301 -275.595027) (xy 11.172085 -275.57702) (xy 11.226928 -275.56689)
			(xy 11.282662 -275.564853) (xy 11.338099 -275.570953) (xy 11.392056 -275.585059) (xy 11.443385 -275.606871)
			(xy 11.490991 -275.635925) (xy 11.533859 -275.6716) (xy 11.571076 -275.713137) (xy 11.601849 -275.75965)
			(xy 11.625521 -275.810147) (xy 11.641589 -275.863554) (xy 11.649709 -275.91873) (xy 11.650218 -275.946616)
			(xy 11.649709 -275.974502) (xy 11.641589 -276.029678) (xy 11.625521 -276.083085) (xy 11.620791 -276.093174)
			(xy 12.410946 -276.093174) (xy 12.415017 -276.037552) (xy 12.427143 -275.983115) (xy 12.447066 -275.931024)
			(xy 12.474362 -275.882389) (xy 12.508448 -275.838246) (xy 12.548597 -275.799537) (xy 12.593955 -275.767086)
			(xy 12.643555 -275.741585) (xy 12.696339 -275.723578) (xy 12.751182 -275.713448) (xy 12.806916 -275.711411)
			(xy 12.862353 -275.717511) (xy 12.91631 -275.731617) (xy 12.967639 -275.753429) (xy 13.015245 -275.782483)
			(xy 13.058113 -275.818158) (xy 13.09533 -275.859695) (xy 13.126103 -275.906208) (xy 13.149775 -275.956705)
			(xy 13.165843 -276.010112) (xy 13.173963 -276.065288) (xy 13.174268 -276.081998) (xy 13.588998 -276.081998)
			(xy 13.593069 -276.026376) (xy 13.605195 -275.971939) (xy 13.625118 -275.919848) (xy 13.652414 -275.871213)
			(xy 13.6865 -275.82707) (xy 13.726649 -275.788361) (xy 13.772007 -275.75591) (xy 13.821607 -275.730409)
			(xy 13.874391 -275.712402) (xy 13.929234 -275.702272) (xy 13.984968 -275.700235) (xy 14.040405 -275.706335)
			(xy 14.094362 -275.720441) (xy 14.145691 -275.742253) (xy 14.193297 -275.771307) (xy 14.236165 -275.806982)
			(xy 14.273382 -275.848519) (xy 14.304155 -275.895032) (xy 14.327827 -275.945529) (xy 14.343895 -275.998936)
			(xy 14.352015 -276.054112) (xy 14.352524 -276.081998) (xy 14.352015 -276.109884) (xy 14.343895 -276.16506)
			(xy 14.327827 -276.218467) (xy 14.30619 -276.264624) (xy 15.394178 -276.264624) (xy 15.394684 -276.235706)
			(xy 15.403411 -276.178533) (xy 15.42067 -276.123333) (xy 15.446064 -276.07137) (xy 15.479011 -276.023837)
			(xy 15.518756 -275.981822) (xy 15.541244 -275.963634) (xy 15.549993 -275.95606) (xy 15.560182 -275.93531)
			(xy 15.560802 -275.923756) (xy 15.560802 -275.843492) (xy 15.560235 -275.831924) (xy 15.550038 -275.811153)
			(xy 15.541244 -275.803614) (xy 15.518776 -275.785404) (xy 15.479038 -275.743389) (xy 15.446096 -275.695859)
			(xy 15.420705 -275.643901) (xy 15.403445 -275.588706) (xy 15.394714 -275.531539) (xy 15.394178 -275.502624)
			(xy 15.394664 -275.475373) (xy 15.40242 -275.421425) (xy 15.417775 -275.36913) (xy 15.440417 -275.319553)
			(xy 15.469883 -275.273703) (xy 15.505574 -275.232512) (xy 15.546765 -275.196821) (xy 15.592615 -275.167355)
			(xy 15.642192 -275.144713) (xy 15.694487 -275.129358) (xy 15.748435 -275.121602) (xy 15.802937 -275.121602)
			(xy 15.856885 -275.129358) (xy 15.90918 -275.144713) (xy 15.958757 -275.167355) (xy 16.004607 -275.196821)
			(xy 16.045798 -275.232512) (xy 16.081489 -275.273703) (xy 16.110955 -275.319553) (xy 16.133597 -275.36913)
			(xy 16.148952 -275.421425) (xy 16.156708 -275.475373) (xy 16.157194 -275.502624) (xy 16.156624 -275.531539)
			(xy 16.147906 -275.588708) (xy 16.130658 -275.643906) (xy 16.105276 -275.695868) (xy 16.072342 -275.743403)
			(xy 16.03261 -275.785422) (xy 16.010128 -275.803614) (xy 16.001352 -275.811162) (xy 15.991179 -275.831932)
			(xy 15.99057 -275.843492) (xy 15.99057 -275.923756) (xy 15.991142 -275.935324) (xy 16.001333 -275.956097)
			(xy 16.010128 -275.963634) (xy 16.032634 -275.981799) (xy 16.072366 -276.023825) (xy 16.105302 -276.071365)
			(xy 16.130686 -276.123332) (xy 16.147938 -276.178534) (xy 16.156662 -276.235707) (xy 16.157194 -276.264624)
			(xy 16.156708 -276.291875) (xy 16.148952 -276.345823) (xy 16.133597 -276.398118) (xy 16.121366 -276.424898)
			(xy 36.069028 -276.424898) (xy 36.072988 -276.375844) (xy 36.084765 -276.32806) (xy 36.104056 -276.282784)
			(xy 36.130359 -276.241188) (xy 36.162994 -276.204351) (xy 36.201115 -276.173226) (xy 36.243736 -276.148619)
			(xy 36.289752 -276.131167) (xy 36.337971 -276.121323) (xy 36.387146 -276.119342) (xy 36.436001 -276.125274)
			(xy 36.483272 -276.138966) (xy 36.527734 -276.160064) (xy 36.568237 -276.18802) (xy 36.60373 -276.222112)
			(xy 36.633295 -276.261456) (xy 36.656166 -276.305033) (xy 36.67175 -276.351714) (xy 36.679645 -276.400291)
			(xy 36.68014 -276.424898) (xy 37.018988 -276.424898) (xy 37.022948 -276.375844) (xy 37.034725 -276.32806)
			(xy 37.054016 -276.282784) (xy 37.080319 -276.241188) (xy 37.112954 -276.204351) (xy 37.151075 -276.173226)
			(xy 37.193696 -276.148619) (xy 37.239712 -276.131167) (xy 37.287931 -276.121323) (xy 37.337106 -276.119342)
			(xy 37.385961 -276.125274) (xy 37.433232 -276.138966) (xy 37.477694 -276.160064) (xy 37.518197 -276.18802)
			(xy 37.55369 -276.222112) (xy 37.583255 -276.261456) (xy 37.606126 -276.305033) (xy 37.62171 -276.351714)
			(xy 37.629605 -276.400291) (xy 37.6301 -276.424898) (xy 37.969202 -276.424898) (xy 37.973162 -276.375844)
			(xy 37.984939 -276.32806) (xy 38.00423 -276.282784) (xy 38.030533 -276.241188) (xy 38.063168 -276.204351)
			(xy 38.101289 -276.173226) (xy 38.14391 -276.148619) (xy 38.189926 -276.131167) (xy 38.238145 -276.121323)
			(xy 38.28732 -276.119342) (xy 38.336175 -276.125274) (xy 38.383446 -276.138966) (xy 38.427908 -276.160064)
			(xy 38.468411 -276.18802) (xy 38.503904 -276.222112) (xy 38.533469 -276.261456) (xy 38.55634 -276.305033)
			(xy 38.571924 -276.351714) (xy 38.579819 -276.400291) (xy 38.580314 -276.424898) (xy 38.919162 -276.424898)
			(xy 38.923122 -276.375844) (xy 38.934899 -276.32806) (xy 38.95419 -276.282784) (xy 38.980493 -276.241188)
			(xy 39.013128 -276.204351) (xy 39.051249 -276.173226) (xy 39.09387 -276.148619) (xy 39.139886 -276.131167)
			(xy 39.188105 -276.121323) (xy 39.23728 -276.119342) (xy 39.286135 -276.125274) (xy 39.333406 -276.138966)
			(xy 39.377868 -276.160064) (xy 39.418371 -276.18802) (xy 39.453864 -276.222112) (xy 39.483429 -276.261456)
			(xy 39.5063 -276.305033) (xy 39.521884 -276.351714) (xy 39.529779 -276.400291) (xy 39.530274 -276.424898)
			(xy 39.529779 -276.449505) (xy 39.521884 -276.498082) (xy 39.5063 -276.544763) (xy 39.483429 -276.58834)
			(xy 39.453864 -276.627684) (xy 39.418371 -276.661776) (xy 39.377868 -276.689732) (xy 39.333406 -276.71083)
			(xy 39.286135 -276.724522) (xy 39.23728 -276.730454) (xy 39.188105 -276.728473) (xy 39.139886 -276.718629)
			(xy 39.09387 -276.701177) (xy 39.051249 -276.67657) (xy 39.013128 -276.645445) (xy 38.980493 -276.608608)
			(xy 38.95419 -276.567012) (xy 38.934899 -276.521736) (xy 38.923122 -276.473952) (xy 38.919162 -276.424898)
			(xy 38.580314 -276.424898) (xy 38.579819 -276.449505) (xy 38.571924 -276.498082) (xy 38.55634 -276.544763)
			(xy 38.533469 -276.58834) (xy 38.503904 -276.627684) (xy 38.468411 -276.661776) (xy 38.427908 -276.689732)
			(xy 38.383446 -276.71083) (xy 38.336175 -276.724522) (xy 38.28732 -276.730454) (xy 38.238145 -276.728473)
			(xy 38.189926 -276.718629) (xy 38.14391 -276.701177) (xy 38.101289 -276.67657) (xy 38.063168 -276.645445)
			(xy 38.030533 -276.608608) (xy 38.00423 -276.567012) (xy 37.984939 -276.521736) (xy 37.973162 -276.473952)
			(xy 37.969202 -276.424898) (xy 37.6301 -276.424898) (xy 37.629605 -276.449505) (xy 37.62171 -276.498082)
			(xy 37.606126 -276.544763) (xy 37.583255 -276.58834) (xy 37.55369 -276.627684) (xy 37.518197 -276.661776)
			(xy 37.477694 -276.689732) (xy 37.433232 -276.71083) (xy 37.385961 -276.724522) (xy 37.337106 -276.730454)
			(xy 37.287931 -276.728473) (xy 37.239712 -276.718629) (xy 37.193696 -276.701177) (xy 37.151075 -276.67657)
			(xy 37.112954 -276.645445) (xy 37.080319 -276.608608) (xy 37.054016 -276.567012) (xy 37.034725 -276.521736)
			(xy 37.022948 -276.473952) (xy 37.018988 -276.424898) (xy 36.68014 -276.424898) (xy 36.679645 -276.449505)
			(xy 36.67175 -276.498082) (xy 36.656166 -276.544763) (xy 36.633295 -276.58834) (xy 36.60373 -276.627684)
			(xy 36.568237 -276.661776) (xy 36.527734 -276.689732) (xy 36.483272 -276.71083) (xy 36.436001 -276.724522)
			(xy 36.387146 -276.730454) (xy 36.337971 -276.728473) (xy 36.289752 -276.718629) (xy 36.243736 -276.701177)
			(xy 36.201115 -276.67657) (xy 36.162994 -276.645445) (xy 36.130359 -276.608608) (xy 36.104056 -276.567012)
			(xy 36.084765 -276.521736) (xy 36.072988 -276.473952) (xy 36.069028 -276.424898) (xy 16.121366 -276.424898)
			(xy 16.110955 -276.447695) (xy 16.081489 -276.493545) (xy 16.045798 -276.534736) (xy 16.004607 -276.570427)
			(xy 15.958757 -276.599893) (xy 15.90918 -276.622535) (xy 15.856885 -276.63789) (xy 15.802937 -276.645646)
			(xy 15.748435 -276.645646) (xy 15.694487 -276.63789) (xy 15.642192 -276.622535) (xy 15.592615 -276.599893)
			(xy 15.546765 -276.570427) (xy 15.505574 -276.534736) (xy 15.469883 -276.493545) (xy 15.440417 -276.447695)
			(xy 15.417775 -276.398118) (xy 15.40242 -276.345823) (xy 15.394664 -276.291875) (xy 15.394178 -276.264624)
			(xy 14.30619 -276.264624) (xy 14.304155 -276.268964) (xy 14.273382 -276.315477) (xy 14.236165 -276.357014)
			(xy 14.193297 -276.392689) (xy 14.145691 -276.421743) (xy 14.094362 -276.443555) (xy 14.040405 -276.457661)
			(xy 13.984968 -276.463761) (xy 13.929234 -276.461724) (xy 13.874391 -276.451594) (xy 13.821607 -276.433587)
			(xy 13.772007 -276.408086) (xy 13.726649 -276.375635) (xy 13.6865 -276.336926) (xy 13.652414 -276.292783)
			(xy 13.625118 -276.244148) (xy 13.605195 -276.192057) (xy 13.593069 -276.13762) (xy 13.588998 -276.081998)
			(xy 13.174268 -276.081998) (xy 13.174472 -276.093174) (xy 13.173963 -276.12106) (xy 13.165843 -276.176236)
			(xy 13.149775 -276.229643) (xy 13.126103 -276.28014) (xy 13.09533 -276.326653) (xy 13.058113 -276.36819)
			(xy 13.015245 -276.403865) (xy 12.967639 -276.432919) (xy 12.91631 -276.454731) (xy 12.862353 -276.468837)
			(xy 12.806916 -276.474937) (xy 12.751182 -276.4729) (xy 12.696339 -276.46277) (xy 12.643555 -276.444763)
			(xy 12.593955 -276.419262) (xy 12.548597 -276.386811) (xy 12.508448 -276.348102) (xy 12.474362 -276.303959)
			(xy 12.447066 -276.255324) (xy 12.427143 -276.203233) (xy 12.415017 -276.148796) (xy 12.410946 -276.093174)
			(xy 11.620791 -276.093174) (xy 11.601849 -276.133582) (xy 11.571076 -276.180095) (xy 11.533859 -276.221632)
			(xy 11.490991 -276.257307) (xy 11.443385 -276.286361) (xy 11.392056 -276.308173) (xy 11.338099 -276.322279)
			(xy 11.282662 -276.328379) (xy 11.226928 -276.326342) (xy 11.172085 -276.316212) (xy 11.119301 -276.298205)
			(xy 11.069701 -276.272704) (xy 11.024343 -276.240253) (xy 10.984194 -276.201544) (xy 10.950108 -276.157401)
			(xy 10.922812 -276.108766) (xy 10.902889 -276.056675) (xy 10.890763 -276.002238) (xy 10.886692 -275.946616)
			(xy 1.917738 -275.946616) (xy 1.918968 -275.955052) (xy 1.918968 -276.010316) (xy 1.910994 -276.065002)
			(xy 1.895212 -276.117966) (xy 1.871954 -276.168097) (xy 1.841705 -276.214348) (xy 1.805099 -276.255751)
			(xy 1.762902 -276.291438) (xy 1.715997 -276.320663) (xy 1.690878 -276.332188) (xy 1.676908 -276.338284)
			(xy 1.660398 -276.363684) (xy 1.660398 -276.789134) (xy 9.320782 -276.789134) (xy 9.324853 -276.733512)
			(xy 9.336979 -276.679075) (xy 9.356902 -276.626984) (xy 9.384198 -276.578349) (xy 9.418284 -276.534206)
			(xy 9.458433 -276.495497) (xy 9.503791 -276.463046) (xy 9.553391 -276.437545) (xy 9.606175 -276.419538)
			(xy 9.661018 -276.409408) (xy 9.716752 -276.407371) (xy 9.772189 -276.413471) (xy 9.826146 -276.427577)
			(xy 9.877475 -276.449389) (xy 9.925081 -276.478443) (xy 9.967949 -276.514118) (xy 10.005166 -276.555655)
			(xy 10.035939 -276.602168) (xy 10.059611 -276.652665) (xy 10.075679 -276.706072) (xy 10.083799 -276.761248)
			(xy 10.084308 -276.789134) (xy 10.083799 -276.81702) (xy 10.075679 -276.872196) (xy 10.059611 -276.925603)
			(xy 10.035939 -276.9761) (xy 10.005166 -277.022613) (xy 9.967949 -277.06415) (xy 9.925081 -277.099825)
			(xy 9.877475 -277.128879) (xy 9.826146 -277.150691) (xy 9.772189 -277.164797) (xy 9.716752 -277.170897)
			(xy 9.661018 -277.16886) (xy 9.606175 -277.15873) (xy 9.553391 -277.140723) (xy 9.503791 -277.115222)
			(xy 9.458433 -277.082771) (xy 9.418284 -277.044062) (xy 9.384198 -276.999919) (xy 9.356902 -276.951284)
			(xy 9.336979 -276.899193) (xy 9.324853 -276.844756) (xy 9.320782 -276.789134) (xy 1.660398 -276.789134)
			(xy 1.660398 -276.977602) (xy 1.676908 -277.002748) (xy 1.690878 -277.008844) (xy 1.716098 -277.020329)
			(xy 1.763207 -277.049511) (xy 1.805598 -277.0852) (xy 1.842381 -277.126647) (xy 1.872781 -277.172979)
			(xy 1.896159 -277.223221) (xy 1.912023 -277.276317) (xy 1.912653 -277.280624) (xy 15.393668 -277.280624)
			(xy 15.397739 -277.225002) (xy 15.409865 -277.170565) (xy 15.429788 -277.118474) (xy 15.457084 -277.069839)
			(xy 15.49117 -277.025696) (xy 15.531319 -276.986987) (xy 15.576677 -276.954536) (xy 15.626277 -276.929035)
			(xy 15.679061 -276.911028) (xy 15.733904 -276.900898) (xy 15.789638 -276.898861) (xy 15.845075 -276.904961)
			(xy 15.899032 -276.919067) (xy 15.950361 -276.940879) (xy 15.997967 -276.969933) (xy 16.040835 -277.005608)
			(xy 16.078052 -277.047145) (xy 16.108825 -277.093658) (xy 16.132497 -277.144155) (xy 16.148565 -277.197562)
			(xy 16.156685 -277.252738) (xy 16.157194 -277.280624) (xy 16.156685 -277.30851) (xy 16.148565 -277.363686)
			(xy 16.145204 -277.374858) (xy 36.069028 -277.374858) (xy 36.072988 -277.325804) (xy 36.084765 -277.27802)
			(xy 36.104056 -277.232744) (xy 36.130359 -277.191148) (xy 36.162994 -277.154311) (xy 36.201115 -277.123186)
			(xy 36.243736 -277.098579) (xy 36.289752 -277.081127) (xy 36.337971 -277.071283) (xy 36.387146 -277.069302)
			(xy 36.436001 -277.075234) (xy 36.483272 -277.088926) (xy 36.527734 -277.110024) (xy 36.568237 -277.13798)
			(xy 36.60373 -277.172072) (xy 36.633295 -277.211416) (xy 36.656166 -277.254993) (xy 36.67175 -277.301674)
			(xy 36.679645 -277.350251) (xy 36.68014 -277.374858) (xy 37.018988 -277.374858) (xy 37.022948 -277.325804)
			(xy 37.034725 -277.27802) (xy 37.054016 -277.232744) (xy 37.080319 -277.191148) (xy 37.112954 -277.154311)
			(xy 37.151075 -277.123186) (xy 37.193696 -277.098579) (xy 37.239712 -277.081127) (xy 37.287931 -277.071283)
			(xy 37.337106 -277.069302) (xy 37.385961 -277.075234) (xy 37.433232 -277.088926) (xy 37.477694 -277.110024)
			(xy 37.518197 -277.13798) (xy 37.55369 -277.172072) (xy 37.583255 -277.211416) (xy 37.606126 -277.254993)
			(xy 37.62171 -277.301674) (xy 37.629605 -277.350251) (xy 37.6301 -277.374858) (xy 37.969202 -277.374858)
			(xy 37.973162 -277.325804) (xy 37.984939 -277.27802) (xy 38.00423 -277.232744) (xy 38.030533 -277.191148)
			(xy 38.063168 -277.154311) (xy 38.101289 -277.123186) (xy 38.14391 -277.098579) (xy 38.189926 -277.081127)
			(xy 38.238145 -277.071283) (xy 38.28732 -277.069302) (xy 38.336175 -277.075234) (xy 38.383446 -277.088926)
			(xy 38.427908 -277.110024) (xy 38.468411 -277.13798) (xy 38.503904 -277.172072) (xy 38.533469 -277.211416)
			(xy 38.55634 -277.254993) (xy 38.571924 -277.301674) (xy 38.579819 -277.350251) (xy 38.580314 -277.374858)
			(xy 38.919162 -277.374858) (xy 38.923122 -277.325804) (xy 38.934899 -277.27802) (xy 38.95419 -277.232744)
			(xy 38.980493 -277.191148) (xy 39.013128 -277.154311) (xy 39.051249 -277.123186) (xy 39.09387 -277.098579)
			(xy 39.139886 -277.081127) (xy 39.188105 -277.071283) (xy 39.23728 -277.069302) (xy 39.286135 -277.075234)
			(xy 39.333406 -277.088926) (xy 39.377868 -277.110024) (xy 39.418371 -277.13798) (xy 39.453864 -277.172072)
			(xy 39.483429 -277.211416) (xy 39.5063 -277.254993) (xy 39.521884 -277.301674) (xy 39.529779 -277.350251)
			(xy 39.530274 -277.374858) (xy 39.529779 -277.399465) (xy 39.521884 -277.448042) (xy 39.5063 -277.494723)
			(xy 39.483429 -277.5383) (xy 39.453864 -277.577644) (xy 39.418371 -277.611736) (xy 39.377868 -277.639692)
			(xy 39.333406 -277.66079) (xy 39.286135 -277.674482) (xy 39.23728 -277.680414) (xy 39.188105 -277.678433)
			(xy 39.139886 -277.668589) (xy 39.09387 -277.651137) (xy 39.051249 -277.62653) (xy 39.013128 -277.595405)
			(xy 38.980493 -277.558568) (xy 38.95419 -277.516972) (xy 38.934899 -277.471696) (xy 38.923122 -277.423912)
			(xy 38.919162 -277.374858) (xy 38.580314 -277.374858) (xy 38.579819 -277.399465) (xy 38.571924 -277.448042)
			(xy 38.55634 -277.494723) (xy 38.533469 -277.5383) (xy 38.503904 -277.577644) (xy 38.468411 -277.611736)
			(xy 38.427908 -277.639692) (xy 38.383446 -277.66079) (xy 38.336175 -277.674482) (xy 38.28732 -277.680414)
			(xy 38.238145 -277.678433) (xy 38.189926 -277.668589) (xy 38.14391 -277.651137) (xy 38.101289 -277.62653)
			(xy 38.063168 -277.595405) (xy 38.030533 -277.558568) (xy 38.00423 -277.516972) (xy 37.984939 -277.471696)
			(xy 37.973162 -277.423912) (xy 37.969202 -277.374858) (xy 37.6301 -277.374858) (xy 37.629605 -277.399465)
			(xy 37.62171 -277.448042) (xy 37.606126 -277.494723) (xy 37.583255 -277.5383) (xy 37.55369 -277.577644)
			(xy 37.518197 -277.611736) (xy 37.477694 -277.639692) (xy 37.433232 -277.66079) (xy 37.385961 -277.674482)
			(xy 37.337106 -277.680414) (xy 37.287931 -277.678433) (xy 37.239712 -277.668589) (xy 37.193696 -277.651137)
			(xy 37.151075 -277.62653) (xy 37.112954 -277.595405) (xy 37.080319 -277.558568) (xy 37.054016 -277.516972)
			(xy 37.034725 -277.471696) (xy 37.022948 -277.423912) (xy 37.018988 -277.374858) (xy 36.68014 -277.374858)
			(xy 36.679645 -277.399465) (xy 36.67175 -277.448042) (xy 36.656166 -277.494723) (xy 36.633295 -277.5383)
			(xy 36.60373 -277.577644) (xy 36.568237 -277.611736) (xy 36.527734 -277.639692) (xy 36.483272 -277.66079)
			(xy 36.436001 -277.674482) (xy 36.387146 -277.680414) (xy 36.337971 -277.678433) (xy 36.289752 -277.668589)
			(xy 36.243736 -277.651137) (xy 36.201115 -277.62653) (xy 36.162994 -277.595405) (xy 36.130359 -277.558568)
			(xy 36.104056 -277.516972) (xy 36.084765 -277.471696) (xy 36.072988 -277.423912) (xy 36.069028 -277.374858)
			(xy 16.145204 -277.374858) (xy 16.132497 -277.417093) (xy 16.108825 -277.46759) (xy 16.078052 -277.514103)
			(xy 16.040835 -277.55564) (xy 15.997967 -277.591315) (xy 15.950361 -277.620369) (xy 15.899032 -277.642181)
			(xy 15.845075 -277.656287) (xy 15.789638 -277.662387) (xy 15.733904 -277.66035) (xy 15.679061 -277.65022)
			(xy 15.626277 -277.632213) (xy 15.576677 -277.606712) (xy 15.531319 -277.574261) (xy 15.49117 -277.535552)
			(xy 15.457084 -277.491409) (xy 15.429788 -277.442774) (xy 15.409865 -277.390683) (xy 15.397739 -277.336246)
			(xy 15.393668 -277.280624) (xy 1.912653 -277.280624) (xy 1.920039 -277.331149) (xy 1.920039 -277.386563)
			(xy 1.912023 -277.441395) (xy 1.896159 -277.494491) (xy 1.872781 -277.544733) (xy 1.842381 -277.591065)
			(xy 1.805598 -277.632512) (xy 1.763207 -277.668201) (xy 1.716098 -277.697383) (xy 1.690878 -277.708868)
			(xy 1.676908 -277.714964) (xy 1.660398 -277.74011) (xy 1.660398 -277.814278) (xy 9.324846 -277.814278)
			(xy 9.328917 -277.758656) (xy 9.341043 -277.704219) (xy 9.360966 -277.652128) (xy 9.388262 -277.603493)
			(xy 9.422348 -277.55935) (xy 9.462497 -277.520641) (xy 9.507855 -277.48819) (xy 9.557455 -277.462689)
			(xy 9.610239 -277.444682) (xy 9.665082 -277.434552) (xy 9.720816 -277.432515) (xy 9.776253 -277.438615)
			(xy 9.83021 -277.452721) (xy 9.881539 -277.474533) (xy 9.929145 -277.503587) (xy 9.972013 -277.539262)
			(xy 10.00923 -277.580799) (xy 10.040003 -277.627312) (xy 10.063675 -277.677809) (xy 10.079743 -277.731216)
			(xy 10.087863 -277.786392) (xy 10.088372 -277.814278) (xy 11.344146 -277.814278) (xy 11.348217 -277.758656)
			(xy 11.360343 -277.704219) (xy 11.380266 -277.652128) (xy 11.407562 -277.603493) (xy 11.441648 -277.55935)
			(xy 11.481797 -277.520641) (xy 11.527155 -277.48819) (xy 11.576755 -277.462689) (xy 11.629539 -277.444682)
			(xy 11.684382 -277.434552) (xy 11.740116 -277.432515) (xy 11.795553 -277.438615) (xy 11.84951 -277.452721)
			(xy 11.900839 -277.474533) (xy 11.948445 -277.503587) (xy 11.991313 -277.539262) (xy 12.02853 -277.580799)
			(xy 12.059303 -277.627312) (xy 12.082975 -277.677809) (xy 12.099043 -277.731216) (xy 12.107163 -277.786392)
			(xy 12.107672 -277.814278) (xy 12.107163 -277.842164) (xy 12.099043 -277.89734) (xy 12.082975 -277.950747)
			(xy 12.059303 -278.001244) (xy 12.02853 -278.047757) (xy 11.991313 -278.089294) (xy 11.948445 -278.124969)
			(xy 11.900839 -278.154023) (xy 11.84951 -278.175835) (xy 11.795553 -278.189941) (xy 11.740116 -278.196041)
			(xy 11.684382 -278.194004) (xy 11.629539 -278.183874) (xy 11.576755 -278.165867) (xy 11.527155 -278.140366)
			(xy 11.481797 -278.107915) (xy 11.441648 -278.069206) (xy 11.407562 -278.025063) (xy 11.380266 -277.976428)
			(xy 11.360343 -277.924337) (xy 11.348217 -277.8699) (xy 11.344146 -277.814278) (xy 10.088372 -277.814278)
			(xy 10.087863 -277.842164) (xy 10.079743 -277.89734) (xy 10.063675 -277.950747) (xy 10.040003 -278.001244)
			(xy 10.00923 -278.047757) (xy 9.972013 -278.089294) (xy 9.929145 -278.124969) (xy 9.881539 -278.154023)
			(xy 9.83021 -278.175835) (xy 9.776253 -278.189941) (xy 9.720816 -278.196041) (xy 9.665082 -278.194004)
			(xy 9.610239 -278.183874) (xy 9.557455 -278.165867) (xy 9.507855 -278.140366) (xy 9.462497 -278.107915)
			(xy 9.422348 -278.069206) (xy 9.388262 -278.025063) (xy 9.360966 -277.976428) (xy 9.341043 -277.924337)
			(xy 9.328917 -277.8699) (xy 9.324846 -277.814278) (xy 1.660398 -277.814278) (xy 1.660398 -278.301704)
			(xy 19.362418 -278.301704) (xy 19.366489 -278.246082) (xy 19.378615 -278.191645) (xy 19.398538 -278.139554)
			(xy 19.425834 -278.090919) (xy 19.45992 -278.046776) (xy 19.500069 -278.008067) (xy 19.545427 -277.975616)
			(xy 19.595027 -277.950115) (xy 19.647811 -277.932108) (xy 19.702654 -277.921978) (xy 19.758388 -277.919941)
			(xy 19.813825 -277.926041) (xy 19.867782 -277.940147) (xy 19.919111 -277.961959) (xy 19.966717 -277.991013)
			(xy 20.009585 -278.026688) (xy 20.046802 -278.068225) (xy 20.077575 -278.114738) (xy 20.101247 -278.165235)
			(xy 20.117315 -278.218642) (xy 20.125435 -278.273818) (xy 20.125944 -278.301704) (xy 20.125435 -278.32959)
			(xy 20.117315 -278.384766) (xy 20.101247 -278.438173) (xy 20.098899 -278.443182) (xy 25.719276 -278.443182)
			(xy 25.723347 -278.38756) (xy 25.735473 -278.333123) (xy 25.755396 -278.281032) (xy 25.782692 -278.232397)
			(xy 25.816778 -278.188254) (xy 25.856927 -278.149545) (xy 25.902285 -278.117094) (xy 25.951885 -278.091593)
			(xy 26.004669 -278.073586) (xy 26.059512 -278.063456) (xy 26.115246 -278.061419) (xy 26.170683 -278.067519)
			(xy 26.22464 -278.081625) (xy 26.275969 -278.103437) (xy 26.323575 -278.132491) (xy 26.366443 -278.168166)
			(xy 26.40366 -278.209703) (xy 26.434433 -278.256216) (xy 26.458105 -278.306713) (xy 26.463552 -278.324818)
			(xy 36.069028 -278.324818) (xy 36.072988 -278.275764) (xy 36.084765 -278.22798) (xy 36.104056 -278.182704)
			(xy 36.130359 -278.141108) (xy 36.162994 -278.104271) (xy 36.201115 -278.073146) (xy 36.243736 -278.048539)
			(xy 36.289752 -278.031087) (xy 36.337971 -278.021243) (xy 36.387146 -278.019262) (xy 36.436001 -278.025194)
			(xy 36.483272 -278.038886) (xy 36.527734 -278.059984) (xy 36.568237 -278.08794) (xy 36.60373 -278.122032)
			(xy 36.633295 -278.161376) (xy 36.656166 -278.204953) (xy 36.67175 -278.251634) (xy 36.679645 -278.300211)
			(xy 36.68014 -278.324818) (xy 37.018988 -278.324818) (xy 37.022948 -278.275764) (xy 37.034725 -278.22798)
			(xy 37.054016 -278.182704) (xy 37.080319 -278.141108) (xy 37.112954 -278.104271) (xy 37.151075 -278.073146)
			(xy 37.193696 -278.048539) (xy 37.239712 -278.031087) (xy 37.287931 -278.021243) (xy 37.337106 -278.019262)
			(xy 37.385961 -278.025194) (xy 37.433232 -278.038886) (xy 37.477694 -278.059984) (xy 37.518197 -278.08794)
			(xy 37.55369 -278.122032) (xy 37.583255 -278.161376) (xy 37.606126 -278.204953) (xy 37.62171 -278.251634)
			(xy 37.629605 -278.300211) (xy 37.6301 -278.324818) (xy 37.969202 -278.324818) (xy 37.973162 -278.275764)
			(xy 37.984939 -278.22798) (xy 38.00423 -278.182704) (xy 38.030533 -278.141108) (xy 38.063168 -278.104271)
			(xy 38.101289 -278.073146) (xy 38.14391 -278.048539) (xy 38.189926 -278.031087) (xy 38.238145 -278.021243)
			(xy 38.28732 -278.019262) (xy 38.336175 -278.025194) (xy 38.383446 -278.038886) (xy 38.427908 -278.059984)
			(xy 38.468411 -278.08794) (xy 38.503904 -278.122032) (xy 38.533469 -278.161376) (xy 38.55634 -278.204953)
			(xy 38.571924 -278.251634) (xy 38.579819 -278.300211) (xy 38.580314 -278.324818) (xy 38.919162 -278.324818)
			(xy 38.923122 -278.275764) (xy 38.934899 -278.22798) (xy 38.95419 -278.182704) (xy 38.980493 -278.141108)
			(xy 39.013128 -278.104271) (xy 39.051249 -278.073146) (xy 39.09387 -278.048539) (xy 39.139886 -278.031087)
			(xy 39.188105 -278.021243) (xy 39.23728 -278.019262) (xy 39.286135 -278.025194) (xy 39.333406 -278.038886)
			(xy 39.377868 -278.059984) (xy 39.418371 -278.08794) (xy 39.453864 -278.122032) (xy 39.483429 -278.161376)
			(xy 39.5063 -278.204953) (xy 39.521884 -278.251634) (xy 39.529779 -278.300211) (xy 39.530274 -278.324818)
			(xy 39.529779 -278.349425) (xy 39.521884 -278.398002) (xy 39.5063 -278.444683) (xy 39.483429 -278.48826)
			(xy 39.453864 -278.527604) (xy 39.418371 -278.561696) (xy 39.377868 -278.589652) (xy 39.333406 -278.61075)
			(xy 39.286135 -278.624442) (xy 39.23728 -278.630374) (xy 39.188105 -278.628393) (xy 39.139886 -278.618549)
			(xy 39.09387 -278.601097) (xy 39.051249 -278.57649) (xy 39.013128 -278.545365) (xy 38.980493 -278.508528)
			(xy 38.95419 -278.466932) (xy 38.934899 -278.421656) (xy 38.923122 -278.373872) (xy 38.919162 -278.324818)
			(xy 38.580314 -278.324818) (xy 38.579819 -278.349425) (xy 38.571924 -278.398002) (xy 38.55634 -278.444683)
			(xy 38.533469 -278.48826) (xy 38.503904 -278.527604) (xy 38.468411 -278.561696) (xy 38.427908 -278.589652)
			(xy 38.383446 -278.61075) (xy 38.336175 -278.624442) (xy 38.28732 -278.630374) (xy 38.238145 -278.628393)
			(xy 38.189926 -278.618549) (xy 38.14391 -278.601097) (xy 38.101289 -278.57649) (xy 38.063168 -278.545365)
			(xy 38.030533 -278.508528) (xy 38.00423 -278.466932) (xy 37.984939 -278.421656) (xy 37.973162 -278.373872)
			(xy 37.969202 -278.324818) (xy 37.6301 -278.324818) (xy 37.629605 -278.349425) (xy 37.62171 -278.398002)
			(xy 37.606126 -278.444683) (xy 37.583255 -278.48826) (xy 37.55369 -278.527604) (xy 37.518197 -278.561696)
			(xy 37.477694 -278.589652) (xy 37.433232 -278.61075) (xy 37.385961 -278.624442) (xy 37.337106 -278.630374)
			(xy 37.287931 -278.628393) (xy 37.239712 -278.618549) (xy 37.193696 -278.601097) (xy 37.151075 -278.57649)
			(xy 37.112954 -278.545365) (xy 37.080319 -278.508528) (xy 37.054016 -278.466932) (xy 37.034725 -278.421656)
			(xy 37.022948 -278.373872) (xy 37.018988 -278.324818) (xy 36.68014 -278.324818) (xy 36.679645 -278.349425)
			(xy 36.67175 -278.398002) (xy 36.656166 -278.444683) (xy 36.633295 -278.48826) (xy 36.60373 -278.527604)
			(xy 36.568237 -278.561696) (xy 36.527734 -278.589652) (xy 36.483272 -278.61075) (xy 36.436001 -278.624442)
			(xy 36.387146 -278.630374) (xy 36.337971 -278.628393) (xy 36.289752 -278.618549) (xy 36.243736 -278.601097)
			(xy 36.201115 -278.57649) (xy 36.162994 -278.545365) (xy 36.130359 -278.508528) (xy 36.104056 -278.466932)
			(xy 36.084765 -278.421656) (xy 36.072988 -278.373872) (xy 36.069028 -278.324818) (xy 26.463552 -278.324818)
			(xy 26.474173 -278.36012) (xy 26.482293 -278.415296) (xy 26.482802 -278.443182) (xy 26.482293 -278.471068)
			(xy 26.474173 -278.526244) (xy 26.458105 -278.579651) (xy 26.434433 -278.630148) (xy 26.40366 -278.676661)
			(xy 26.366443 -278.718198) (xy 26.323575 -278.753873) (xy 26.318245 -278.757126) (xy 33.547048 -278.757126)
			(xy 33.551119 -278.701504) (xy 33.563245 -278.647067) (xy 33.583168 -278.594976) (xy 33.610464 -278.546341)
			(xy 33.64455 -278.502198) (xy 33.684699 -278.463489) (xy 33.730057 -278.431038) (xy 33.779657 -278.405537)
			(xy 33.832441 -278.38753) (xy 33.887284 -278.3774) (xy 33.943018 -278.375363) (xy 33.998455 -278.381463)
			(xy 34.052412 -278.395569) (xy 34.103741 -278.417381) (xy 34.151347 -278.446435) (xy 34.194215 -278.48211)
			(xy 34.231432 -278.523647) (xy 34.262205 -278.57016) (xy 34.285877 -278.620657) (xy 34.301945 -278.674064)
			(xy 34.310065 -278.72924) (xy 34.310574 -278.757126) (xy 34.310065 -278.785012) (xy 34.301945 -278.840188)
			(xy 34.285877 -278.893595) (xy 34.262205 -278.944092) (xy 34.231432 -278.990605) (xy 34.194215 -279.032142)
			(xy 34.151347 -279.067817) (xy 34.103741 -279.096871) (xy 34.052412 -279.118683) (xy 33.998455 -279.132789)
			(xy 33.943018 -279.138889) (xy 33.887284 -279.136852) (xy 33.832441 -279.126722) (xy 33.779657 -279.108715)
			(xy 33.730057 -279.083214) (xy 33.684699 -279.050763) (xy 33.64455 -279.012054) (xy 33.610464 -278.967911)
			(xy 33.583168 -278.919276) (xy 33.563245 -278.867185) (xy 33.551119 -278.812748) (xy 33.547048 -278.757126)
			(xy 26.318245 -278.757126) (xy 26.275969 -278.782927) (xy 26.22464 -278.804739) (xy 26.170683 -278.818845)
			(xy 26.115246 -278.824945) (xy 26.059512 -278.822908) (xy 26.004669 -278.812778) (xy 25.951885 -278.794771)
			(xy 25.902285 -278.76927) (xy 25.856927 -278.736819) (xy 25.816778 -278.69811) (xy 25.782692 -278.653967)
			(xy 25.755396 -278.605332) (xy 25.735473 -278.553241) (xy 25.723347 -278.498804) (xy 25.719276 -278.443182)
			(xy 20.098899 -278.443182) (xy 20.077575 -278.48867) (xy 20.046802 -278.535183) (xy 20.009585 -278.57672)
			(xy 19.966717 -278.612395) (xy 19.919111 -278.641449) (xy 19.867782 -278.663261) (xy 19.813825 -278.677367)
			(xy 19.758388 -278.683467) (xy 19.702654 -278.68143) (xy 19.647811 -278.6713) (xy 19.595027 -278.653293)
			(xy 19.545427 -278.627792) (xy 19.500069 -278.595341) (xy 19.45992 -278.556632) (xy 19.425834 -278.512489)
			(xy 19.398538 -278.463854) (xy 19.378615 -278.411763) (xy 19.366489 -278.357326) (xy 19.362418 -278.301704)
			(xy 1.660398 -278.301704) (xy 1.660398 -279.73909) (xy 5.034026 -279.73909) (xy 5.034518 -279.710836)
			(xy 5.042855 -279.654948) (xy 5.059345 -279.6009) (xy 5.083626 -279.549876) (xy 5.115169 -279.502992)
			(xy 5.133848 -279.481788) (xy 5.140452 -279.474676) (xy 5.14731 -279.45715) (xy 5.14731 -279.369266)
			(xy 5.140452 -279.35174) (xy 5.133848 -279.344628) (xy 5.115176 -279.32342) (xy 5.083639 -279.276534)
			(xy 5.059362 -279.22551) (xy 5.042875 -279.171465) (xy 5.034539 -279.115578) (xy 5.034026 -279.087326)
			(xy 5.03448 -279.060072) (xy 5.042234 -279.006119) (xy 5.057588 -278.953819) (xy 5.08023 -278.904237)
			(xy 5.109699 -278.858382) (xy 5.145394 -278.817188) (xy 5.186588 -278.781494) (xy 5.232444 -278.752026)
			(xy 5.282027 -278.729386) (xy 5.334327 -278.714032) (xy 5.38828 -278.706279) (xy 5.415534 -278.705818)
			(xy 5.444273 -278.706343) (xy 5.501099 -278.714969) (xy 5.555989 -278.73202) (xy 5.6077 -278.75711)
			(xy 5.655064 -278.789673) (xy 5.676392 -278.808942) (xy 5.683504 -278.815546) (xy 5.70103 -278.822658)
			(xy 5.790438 -278.822658) (xy 5.807964 -278.815546) (xy 5.815076 -278.808942) (xy 5.836403 -278.789672)
			(xy 5.883766 -278.757107) (xy 5.935477 -278.732016) (xy 5.990368 -278.714966) (xy 6.047195 -278.706344)
			(xy 6.104673 -278.706344) (xy 6.1615 -278.714966) (xy 6.216391 -278.732016) (xy 6.268102 -278.757107)
			(xy 6.315465 -278.789672) (xy 6.336792 -278.808942) (xy 6.343904 -278.815546) (xy 6.36143 -278.822658)
			(xy 6.450838 -278.822658) (xy 6.468364 -278.815546) (xy 6.475476 -278.808942) (xy 6.496803 -278.789672)
			(xy 6.544166 -278.757107) (xy 6.595877 -278.732016) (xy 6.650768 -278.714966) (xy 6.707595 -278.706344)
			(xy 6.765073 -278.706344) (xy 6.8219 -278.714966) (xy 6.876791 -278.732016) (xy 6.928502 -278.757107)
			(xy 6.975865 -278.789672) (xy 6.997192 -278.808942) (xy 7.004304 -278.815546) (xy 7.02183 -278.822658)
			(xy 7.111238 -278.822658) (xy 7.128764 -278.815546) (xy 7.135876 -278.808942) (xy 7.15719 -278.789656)
			(xy 7.204555 -278.757092) (xy 7.25627 -278.732002) (xy 7.311164 -278.714955) (xy 7.367994 -278.706336)
			(xy 7.396734 -278.705818) (xy 7.423987 -278.706246) (xy 7.477938 -278.714008) (xy 7.530236 -278.729369)
			(xy 7.579815 -278.752016) (xy 7.625666 -278.781488) (xy 7.666857 -278.817186) (xy 7.702548 -278.858382)
			(xy 7.732013 -278.904238) (xy 7.754652 -278.95382) (xy 7.770005 -279.00612) (xy 7.777758 -279.060073)
			(xy 7.778242 -279.087326) (xy 7.777767 -279.11558) (xy 7.769428 -279.17147) (xy 7.752934 -279.225518)
			(xy 7.729489 -279.274778) (xy 36.069028 -279.274778) (xy 36.072988 -279.225724) (xy 36.084765 -279.17794)
			(xy 36.104056 -279.132664) (xy 36.130359 -279.091068) (xy 36.162994 -279.054231) (xy 36.201115 -279.023106)
			(xy 36.243736 -278.998499) (xy 36.289752 -278.981047) (xy 36.337971 -278.971203) (xy 36.387146 -278.969222)
			(xy 36.436001 -278.975154) (xy 36.483272 -278.988846) (xy 36.527734 -279.009944) (xy 36.568237 -279.0379)
			(xy 36.60373 -279.071992) (xy 36.633295 -279.111336) (xy 36.656166 -279.154913) (xy 36.67175 -279.201594)
			(xy 36.679645 -279.250171) (xy 36.68014 -279.274778) (xy 37.018988 -279.274778) (xy 37.022948 -279.225724)
			(xy 37.034725 -279.17794) (xy 37.054016 -279.132664) (xy 37.080319 -279.091068) (xy 37.112954 -279.054231)
			(xy 37.151075 -279.023106) (xy 37.193696 -278.998499) (xy 37.239712 -278.981047) (xy 37.287931 -278.971203)
			(xy 37.337106 -278.969222) (xy 37.385961 -278.975154) (xy 37.433232 -278.988846) (xy 37.477694 -279.009944)
			(xy 37.518197 -279.0379) (xy 37.55369 -279.071992) (xy 37.583255 -279.111336) (xy 37.606126 -279.154913)
			(xy 37.62171 -279.201594) (xy 37.629605 -279.250171) (xy 37.6301 -279.274778) (xy 37.969202 -279.274778)
			(xy 37.973162 -279.225724) (xy 37.984939 -279.17794) (xy 38.00423 -279.132664) (xy 38.030533 -279.091068)
			(xy 38.063168 -279.054231) (xy 38.101289 -279.023106) (xy 38.14391 -278.998499) (xy 38.189926 -278.981047)
			(xy 38.238145 -278.971203) (xy 38.28732 -278.969222) (xy 38.336175 -278.975154) (xy 38.383446 -278.988846)
			(xy 38.427908 -279.009944) (xy 38.468411 -279.0379) (xy 38.503904 -279.071992) (xy 38.533469 -279.111336)
			(xy 38.55634 -279.154913) (xy 38.571924 -279.201594) (xy 38.579819 -279.250171) (xy 38.580314 -279.274778)
			(xy 38.919162 -279.274778) (xy 38.923122 -279.225724) (xy 38.934899 -279.17794) (xy 38.95419 -279.132664)
			(xy 38.980493 -279.091068) (xy 39.013128 -279.054231) (xy 39.051249 -279.023106) (xy 39.09387 -278.998499)
			(xy 39.139886 -278.981047) (xy 39.188105 -278.971203) (xy 39.23728 -278.969222) (xy 39.286135 -278.975154)
			(xy 39.333406 -278.988846) (xy 39.377868 -279.009944) (xy 39.418371 -279.0379) (xy 39.453864 -279.071992)
			(xy 39.483429 -279.111336) (xy 39.5063 -279.154913) (xy 39.521884 -279.201594) (xy 39.529779 -279.250171)
			(xy 39.530274 -279.274778) (xy 39.529779 -279.299385) (xy 39.521884 -279.347962) (xy 39.5063 -279.394643)
			(xy 39.483429 -279.43822) (xy 39.453864 -279.477564) (xy 39.418371 -279.511656) (xy 39.377868 -279.539612)
			(xy 39.333406 -279.56071) (xy 39.286135 -279.574402) (xy 39.23728 -279.580334) (xy 39.188105 -279.578353)
			(xy 39.139886 -279.568509) (xy 39.09387 -279.551057) (xy 39.051249 -279.52645) (xy 39.013128 -279.495325)
			(xy 38.980493 -279.458488) (xy 38.95419 -279.416892) (xy 38.934899 -279.371616) (xy 38.923122 -279.323832)
			(xy 38.919162 -279.274778) (xy 38.580314 -279.274778) (xy 38.579819 -279.299385) (xy 38.571924 -279.347962)
			(xy 38.55634 -279.394643) (xy 38.533469 -279.43822) (xy 38.503904 -279.477564) (xy 38.468411 -279.511656)
			(xy 38.427908 -279.539612) (xy 38.383446 -279.56071) (xy 38.336175 -279.574402) (xy 38.28732 -279.580334)
			(xy 38.238145 -279.578353) (xy 38.189926 -279.568509) (xy 38.14391 -279.551057) (xy 38.101289 -279.52645)
			(xy 38.063168 -279.495325) (xy 38.030533 -279.458488) (xy 38.00423 -279.416892) (xy 37.984939 -279.371616)
			(xy 37.973162 -279.323832) (xy 37.969202 -279.274778) (xy 37.6301 -279.274778) (xy 37.629605 -279.299385)
			(xy 37.62171 -279.347962) (xy 37.606126 -279.394643) (xy 37.583255 -279.43822) (xy 37.55369 -279.477564)
			(xy 37.518197 -279.511656) (xy 37.477694 -279.539612) (xy 37.433232 -279.56071) (xy 37.385961 -279.574402)
			(xy 37.337106 -279.580334) (xy 37.287931 -279.578353) (xy 37.239712 -279.568509) (xy 37.193696 -279.551057)
			(xy 37.151075 -279.52645) (xy 37.112954 -279.495325) (xy 37.080319 -279.458488) (xy 37.054016 -279.416892)
			(xy 37.034725 -279.371616) (xy 37.022948 -279.323832) (xy 37.018988 -279.274778) (xy 36.68014 -279.274778)
			(xy 36.679645 -279.299385) (xy 36.67175 -279.347962) (xy 36.656166 -279.394643) (xy 36.633295 -279.43822)
			(xy 36.60373 -279.477564) (xy 36.568237 -279.511656) (xy 36.527734 -279.539612) (xy 36.483272 -279.56071)
			(xy 36.436001 -279.574402) (xy 36.387146 -279.580334) (xy 36.337971 -279.578353) (xy 36.289752 -279.568509)
			(xy 36.243736 -279.551057) (xy 36.201115 -279.52645) (xy 36.162994 -279.495325) (xy 36.130359 -279.458488)
			(xy 36.104056 -279.416892) (xy 36.084765 -279.371616) (xy 36.072988 -279.323832) (xy 36.069028 -279.274778)
			(xy 7.729489 -279.274778) (xy 7.728649 -279.276542) (xy 7.697102 -279.323425) (xy 7.67842 -279.344628)
			(xy 7.671816 -279.35174) (xy 7.664958 -279.369266) (xy 7.664958 -279.45715) (xy 7.671816 -279.474676)
			(xy 7.67842 -279.481788) (xy 7.697095 -279.502995) (xy 7.728632 -279.54988) (xy 7.752909 -279.600904)
			(xy 7.769395 -279.654951) (xy 7.77773 -279.710837) (xy 7.778242 -279.73909) (xy 7.777713 -279.766339)
			(xy 7.769958 -279.820284) (xy 7.754606 -279.872576) (xy 7.731969 -279.92215) (xy 7.726209 -279.931114)
			(xy 25.811478 -279.931114) (xy 25.815549 -279.875492) (xy 25.827675 -279.821055) (xy 25.847598 -279.768964)
			(xy 25.874894 -279.720329) (xy 25.90898 -279.676186) (xy 25.949129 -279.637477) (xy 25.994487 -279.605026)
			(xy 26.044087 -279.579525) (xy 26.096871 -279.561518) (xy 26.151714 -279.551388) (xy 26.207448 -279.549351)
			(xy 26.262885 -279.555451) (xy 26.316842 -279.569557) (xy 26.368171 -279.591369) (xy 26.415777 -279.620423)
			(xy 26.458645 -279.656098) (xy 26.495862 -279.697635) (xy 26.526635 -279.744148) (xy 26.550307 -279.794645)
			(xy 26.566375 -279.848052) (xy 26.574495 -279.903228) (xy 26.575004 -279.931114) (xy 27.286964 -279.931114)
			(xy 27.291035 -279.875492) (xy 27.303161 -279.821055) (xy 27.323084 -279.768964) (xy 27.35038 -279.720329)
			(xy 27.384466 -279.676186) (xy 27.424615 -279.637477) (xy 27.469973 -279.605026) (xy 27.519573 -279.579525)
			(xy 27.572357 -279.561518) (xy 27.6272 -279.551388) (xy 27.682934 -279.549351) (xy 27.738371 -279.555451)
			(xy 27.792328 -279.569557) (xy 27.843657 -279.591369) (xy 27.891263 -279.620423) (xy 27.934131 -279.656098)
			(xy 27.971348 -279.697635) (xy 28.002121 -279.744148) (xy 28.025793 -279.794645) (xy 28.041861 -279.848052)
			(xy 28.049981 -279.903228) (xy 28.05049 -279.931114) (xy 28.175964 -279.931114) (xy 28.180035 -279.875492)
			(xy 28.192161 -279.821055) (xy 28.212084 -279.768964) (xy 28.23938 -279.720329) (xy 28.273466 -279.676186)
			(xy 28.313615 -279.637477) (xy 28.358973 -279.605026) (xy 28.408573 -279.579525) (xy 28.461357 -279.561518)
			(xy 28.5162 -279.551388) (xy 28.571934 -279.549351) (xy 28.627371 -279.555451) (xy 28.681328 -279.569557)
			(xy 28.732657 -279.591369) (xy 28.780263 -279.620423) (xy 28.823131 -279.656098) (xy 28.860348 -279.697635)
			(xy 28.891121 -279.744148) (xy 28.914793 -279.794645) (xy 28.930861 -279.848052) (xy 28.938981 -279.903228)
			(xy 28.93949 -279.931114) (xy 28.938981 -279.959) (xy 28.930861 -280.014176) (xy 28.914793 -280.067583)
			(xy 28.891121 -280.11808) (xy 28.860348 -280.164593) (xy 28.823131 -280.20613) (xy 28.780263 -280.241805)
			(xy 28.732657 -280.270859) (xy 28.681328 -280.292671) (xy 28.627371 -280.306777) (xy 28.571934 -280.312877)
			(xy 28.5162 -280.31084) (xy 28.461357 -280.30071) (xy 28.408573 -280.282703) (xy 28.358973 -280.257202)
			(xy 28.313615 -280.224751) (xy 28.273466 -280.186042) (xy 28.23938 -280.141899) (xy 28.212084 -280.093264)
			(xy 28.192161 -280.041173) (xy 28.180035 -279.986736) (xy 28.175964 -279.931114) (xy 28.05049 -279.931114)
			(xy 28.049981 -279.959) (xy 28.041861 -280.014176) (xy 28.025793 -280.067583) (xy 28.002121 -280.11808)
			(xy 27.971348 -280.164593) (xy 27.934131 -280.20613) (xy 27.891263 -280.241805) (xy 27.843657 -280.270859)
			(xy 27.792328 -280.292671) (xy 27.738371 -280.306777) (xy 27.682934 -280.312877) (xy 27.6272 -280.31084)
			(xy 27.572357 -280.30071) (xy 27.519573 -280.282703) (xy 27.469973 -280.257202) (xy 27.424615 -280.224751)
			(xy 27.384466 -280.186042) (xy 27.35038 -280.141899) (xy 27.323084 -280.093264) (xy 27.303161 -280.041173)
			(xy 27.291035 -279.986736) (xy 27.286964 -279.931114) (xy 26.575004 -279.931114) (xy 26.574495 -279.959)
			(xy 26.566375 -280.014176) (xy 26.550307 -280.067583) (xy 26.526635 -280.11808) (xy 26.495862 -280.164593)
			(xy 26.458645 -280.20613) (xy 26.415777 -280.241805) (xy 26.368171 -280.270859) (xy 26.316842 -280.292671)
			(xy 26.262885 -280.306777) (xy 26.207448 -280.312877) (xy 26.151714 -280.31084) (xy 26.096871 -280.30071)
			(xy 26.044087 -280.282703) (xy 25.994487 -280.257202) (xy 25.949129 -280.224751) (xy 25.90898 -280.186042)
			(xy 25.874894 -280.141899) (xy 25.847598 -280.093264) (xy 25.827675 -280.041173) (xy 25.815549 -279.986736)
			(xy 25.811478 -279.931114) (xy 7.726209 -279.931114) (xy 7.702507 -279.967999) (xy 7.66682 -280.009189)
			(xy 7.625634 -280.04488) (xy 7.579789 -280.074348) (xy 7.530217 -280.096991) (xy 7.477927 -280.112349)
			(xy 7.423983 -280.120109) (xy 7.396734 -280.120598) (xy 7.367994 -280.120115) (xy 7.311164 -280.111483)
			(xy 7.256273 -280.094423) (xy 7.204562 -280.069322) (xy 7.157201 -280.036749) (xy 7.135876 -280.017474)
			(xy 7.128764 -280.01087) (xy 7.111238 -280.003758) (xy 7.02183 -280.003758) (xy 7.004304 -280.01087)
			(xy 6.997192 -280.017474) (xy 6.975865 -280.036744) (xy 6.928502 -280.069309) (xy 6.876791 -280.0944)
			(xy 6.8219 -280.11145) (xy 6.765073 -280.120072) (xy 6.707595 -280.120072) (xy 6.650768 -280.11145)
			(xy 6.595877 -280.0944) (xy 6.544166 -280.069309) (xy 6.496803 -280.036744) (xy 6.475476 -280.017474)
			(xy 6.468364 -280.01087) (xy 6.450838 -280.003758) (xy 6.36143 -280.003758) (xy 6.343904 -280.01087)
			(xy 6.336792 -280.017474) (xy 6.315465 -280.036744) (xy 6.268102 -280.069309) (xy 6.216391 -280.0944)
			(xy 6.1615 -280.11145) (xy 6.104673 -280.120072) (xy 6.047195 -280.120072) (xy 5.990368 -280.11145)
			(xy 5.935477 -280.0944) (xy 5.883766 -280.069309) (xy 5.836403 -280.036744) (xy 5.815076 -280.017474)
			(xy 5.807964 -280.01087) (xy 5.790438 -280.003758) (xy 5.70103 -280.003758) (xy 5.683504 -280.01087)
			(xy 5.676392 -280.017474) (xy 5.655053 -280.036731) (xy 5.607694 -280.069298) (xy 5.555985 -280.094393)
			(xy 5.501097 -280.111447) (xy 5.444272 -280.120075) (xy 5.415534 -280.120598) (xy 5.388282 -280.120113)
			(xy 5.334331 -280.11236) (xy 5.282033 -280.097008) (xy 5.232452 -280.074369) (xy 5.186598 -280.044904)
			(xy 5.145405 -280.009212) (xy 5.109711 -279.968021) (xy 5.080243 -279.922169) (xy 5.0576 -279.87259)
			(xy 5.042245 -279.820293) (xy 5.034489 -279.766342) (xy 5.034026 -279.73909) (xy 1.660398 -279.73909)
			(xy 1.660398 -280.722651) (xy 9.692378 -280.722651) (xy 9.692378 -280.668149) (xy 9.700134 -280.614203)
			(xy 9.715488 -280.561909) (xy 9.738128 -280.512333) (xy 9.767593 -280.466483) (xy 9.803283 -280.425293)
			(xy 9.844472 -280.389602) (xy 9.890321 -280.360135) (xy 9.939896 -280.337493) (xy 9.992189 -280.322137)
			(xy 10.046135 -280.314379) (xy 10.073386 -280.313892) (xy 10.102124 -280.314426) (xy 10.158951 -280.323047)
			(xy 10.213842 -280.340094) (xy 10.265554 -280.365184) (xy 10.312917 -280.397746) (xy 10.334244 -280.417016)
			(xy 10.341356 -280.42362) (xy 10.358882 -280.430732) (xy 10.44829 -280.430732) (xy 10.465816 -280.42362)
			(xy 10.472928 -280.417016) (xy 10.494255 -280.397746) (xy 10.541618 -280.365181) (xy 10.593329 -280.34009)
			(xy 10.64822 -280.32304) (xy 10.705047 -280.314418) (xy 10.762525 -280.314418) (xy 10.819352 -280.32304)
			(xy 10.874243 -280.34009) (xy 10.925954 -280.365181) (xy 10.973317 -280.397746) (xy 10.994644 -280.417016)
			(xy 11.001756 -280.42362) (xy 11.019282 -280.430732) (xy 11.10869 -280.430732) (xy 11.126216 -280.42362)
			(xy 11.133328 -280.417016) (xy 11.154658 -280.397748) (xy 11.202019 -280.365182) (xy 11.25373 -280.34009)
			(xy 11.30862 -280.323038) (xy 11.365447 -280.314414) (xy 11.394186 -280.313892) (xy 11.42431 -280.31446)
			(xy 11.483807 -280.32394) (xy 11.541075 -280.342651) (xy 11.594692 -280.370128) (xy 11.643326 -280.405688)
			(xy 11.66495 -280.426668) (xy 11.672062 -280.434034) (xy 11.690858 -280.441654) (xy 11.783314 -280.441654)
			(xy 11.80211 -280.434034) (xy 11.809222 -280.426668) (xy 11.83087 -280.405712) (xy 11.879491 -280.370138)
			(xy 11.933102 -280.342652) (xy 11.990367 -280.323939) (xy 12.049863 -280.314463) (xy 12.079986 -280.313892)
			(xy 12.10724 -280.314354) (xy 12.161192 -280.32211) (xy 12.213491 -280.337465) (xy 12.263073 -280.360106)
			(xy 12.308928 -280.389574) (xy 12.350123 -280.425268) (xy 12.385818 -280.466461) (xy 12.415287 -280.512314)
			(xy 12.437931 -280.561895) (xy 12.453287 -280.614194) (xy 12.461045 -280.668147) (xy 12.461045 -280.72265)
			(xy 13.939778 -280.72265) (xy 13.939778 -280.66815) (xy 13.947534 -280.614204) (xy 13.962887 -280.561912)
			(xy 13.985527 -280.512336) (xy 14.01499 -280.466487) (xy 14.050679 -280.425298) (xy 14.091866 -280.389606)
			(xy 14.137713 -280.360139) (xy 14.187287 -280.337496) (xy 14.239579 -280.322139) (xy 14.293524 -280.31438)
			(xy 14.320774 -280.313892) (xy 14.349512 -280.314434) (xy 14.406339 -280.323052) (xy 14.461229 -280.340098)
			(xy 14.512941 -280.365186) (xy 14.560305 -280.397747) (xy 14.581632 -280.417016) (xy 14.588744 -280.42362)
			(xy 14.60627 -280.430732) (xy 14.695678 -280.430732) (xy 14.713204 -280.42362) (xy 14.720316 -280.417016)
			(xy 14.741643 -280.397746) (xy 14.789006 -280.365181) (xy 14.840717 -280.34009) (xy 14.895608 -280.32304)
			(xy 14.952435 -280.314418) (xy 15.009913 -280.314418) (xy 15.06674 -280.32304) (xy 15.121631 -280.34009)
			(xy 15.173342 -280.365181) (xy 15.220705 -280.397746) (xy 15.242032 -280.417016) (xy 15.249144 -280.42362)
			(xy 15.26667 -280.430732) (xy 15.356078 -280.430732) (xy 15.373604 -280.42362) (xy 15.380716 -280.417016)
			(xy 15.40205 -280.397754) (xy 15.449411 -280.365187) (xy 15.501121 -280.340094) (xy 15.55601 -280.323041)
			(xy 15.612836 -280.314415) (xy 15.641574 -280.313892) (xy 15.671697 -280.314467) (xy 15.731194 -280.323945)
			(xy 15.788462 -280.342655) (xy 15.84208 -280.37013) (xy 15.890713 -280.405689) (xy 15.912338 -280.426668)
			(xy 15.91945 -280.434034) (xy 15.938246 -280.441654) (xy 16.030702 -280.441654) (xy 16.049498 -280.434034)
			(xy 16.05661 -280.426668) (xy 16.078219 -280.40567) (xy 16.126851 -280.370101) (xy 16.180471 -280.342623)
			(xy 16.237745 -280.32392) (xy 16.297248 -280.314456) (xy 16.327374 -280.313892) (xy 16.354628 -280.314354)
			(xy 16.408582 -280.322108) (xy 16.460883 -280.337461) (xy 16.510466 -280.360102) (xy 16.556323 -280.38957)
			(xy 16.597518 -280.425263) (xy 16.633215 -280.466457) (xy 16.662685 -280.512311) (xy 16.68533 -280.561893)
			(xy 16.700687 -280.614193) (xy 16.708445 -280.668146) (xy 16.708445 -280.693114) (xy 31.338012 -280.693114)
			(xy 31.338555 -280.663732) (xy 31.347584 -280.605665) (xy 31.365415 -280.54967) (xy 31.391626 -280.497075)
			(xy 31.425597 -280.449124) (xy 31.466521 -280.406952) (xy 31.48965 -280.388822) (xy 31.499048 -280.381456)
			(xy 31.509462 -280.360882) (xy 31.510986 -280.256996) (xy 31.50108 -280.235914) (xy 31.491936 -280.228548)
			(xy 31.470088 -280.210342) (xy 31.431546 -280.168524) (xy 31.399638 -280.121449) (xy 31.375071 -280.070159)
			(xy 31.358388 -280.015791) (xy 31.34996 -279.959549) (xy 31.349442 -279.931114) (xy 31.349928 -279.903863)
			(xy 31.357684 -279.849915) (xy 31.373039 -279.79762) (xy 31.395681 -279.748043) (xy 31.425147 -279.702193)
			(xy 31.460838 -279.661002) (xy 31.502029 -279.625311) (xy 31.547879 -279.595845) (xy 31.597456 -279.573203)
			(xy 31.649751 -279.557848) (xy 31.703699 -279.550092) (xy 31.758201 -279.550092) (xy 31.812149 -279.557848)
			(xy 31.864444 -279.573203) (xy 31.914021 -279.595845) (xy 31.959871 -279.625311) (xy 32.001062 -279.661002)
			(xy 32.036753 -279.702193) (xy 32.066219 -279.748043) (xy 32.088861 -279.79762) (xy 32.104216 -279.849915)
			(xy 32.111972 -279.903863) (xy 32.112458 -279.931114) (xy 32.111907 -279.960496) (xy 32.102876 -280.018561)
			(xy 32.085044 -280.074554) (xy 32.058835 -280.127149) (xy 32.024867 -280.1751) (xy 31.983946 -280.217274)
			(xy 31.974426 -280.224738) (xy 36.069028 -280.224738) (xy 36.072988 -280.175684) (xy 36.084765 -280.1279)
			(xy 36.104056 -280.082624) (xy 36.130359 -280.041028) (xy 36.162994 -280.004191) (xy 36.201115 -279.973066)
			(xy 36.243736 -279.948459) (xy 36.289752 -279.931007) (xy 36.337971 -279.921163) (xy 36.387146 -279.919182)
			(xy 36.436001 -279.925114) (xy 36.483272 -279.938806) (xy 36.527734 -279.959904) (xy 36.568237 -279.98786)
			(xy 36.60373 -280.021952) (xy 36.633295 -280.061296) (xy 36.656166 -280.104873) (xy 36.67175 -280.151554)
			(xy 36.679645 -280.200131) (xy 36.68014 -280.224738) (xy 37.018988 -280.224738) (xy 37.022948 -280.175684)
			(xy 37.034725 -280.1279) (xy 37.054016 -280.082624) (xy 37.080319 -280.041028) (xy 37.112954 -280.004191)
			(xy 37.151075 -279.973066) (xy 37.193696 -279.948459) (xy 37.239712 -279.931007) (xy 37.287931 -279.921163)
			(xy 37.337106 -279.919182) (xy 37.385961 -279.925114) (xy 37.433232 -279.938806) (xy 37.477694 -279.959904)
			(xy 37.518197 -279.98786) (xy 37.55369 -280.021952) (xy 37.583255 -280.061296) (xy 37.606126 -280.104873)
			(xy 37.62171 -280.151554) (xy 37.629605 -280.200131) (xy 37.6301 -280.224738) (xy 37.969202 -280.224738)
			(xy 37.973162 -280.175684) (xy 37.984939 -280.1279) (xy 38.00423 -280.082624) (xy 38.030533 -280.041028)
			(xy 38.063168 -280.004191) (xy 38.101289 -279.973066) (xy 38.14391 -279.948459) (xy 38.189926 -279.931007)
			(xy 38.238145 -279.921163) (xy 38.28732 -279.919182) (xy 38.336175 -279.925114) (xy 38.383446 -279.938806)
			(xy 38.427908 -279.959904) (xy 38.468411 -279.98786) (xy 38.503904 -280.021952) (xy 38.533469 -280.061296)
			(xy 38.55634 -280.104873) (xy 38.571924 -280.151554) (xy 38.579819 -280.200131) (xy 38.580314 -280.224738)
			(xy 38.919162 -280.224738) (xy 38.923122 -280.175684) (xy 38.934899 -280.1279) (xy 38.95419 -280.082624)
			(xy 38.980493 -280.041028) (xy 39.013128 -280.004191) (xy 39.051249 -279.973066) (xy 39.09387 -279.948459)
			(xy 39.139886 -279.931007) (xy 39.188105 -279.921163) (xy 39.23728 -279.919182) (xy 39.286135 -279.925114)
			(xy 39.333406 -279.938806) (xy 39.377868 -279.959904) (xy 39.418371 -279.98786) (xy 39.453864 -280.021952)
			(xy 39.483429 -280.061296) (xy 39.5063 -280.104873) (xy 39.521884 -280.151554) (xy 39.529779 -280.200131)
			(xy 39.530274 -280.224738) (xy 39.529779 -280.249345) (xy 39.521884 -280.297922) (xy 39.5063 -280.344603)
			(xy 39.483429 -280.38818) (xy 39.453864 -280.427524) (xy 39.418371 -280.461616) (xy 39.377868 -280.489572)
			(xy 39.333406 -280.51067) (xy 39.286135 -280.524362) (xy 39.23728 -280.530294) (xy 39.188105 -280.528313)
			(xy 39.139886 -280.518469) (xy 39.09387 -280.501017) (xy 39.051249 -280.47641) (xy 39.013128 -280.445285)
			(xy 38.980493 -280.408448) (xy 38.95419 -280.366852) (xy 38.934899 -280.321576) (xy 38.923122 -280.273792)
			(xy 38.919162 -280.224738) (xy 38.580314 -280.224738) (xy 38.579819 -280.249345) (xy 38.571924 -280.297922)
			(xy 38.55634 -280.344603) (xy 38.533469 -280.38818) (xy 38.503904 -280.427524) (xy 38.468411 -280.461616)
			(xy 38.427908 -280.489572) (xy 38.383446 -280.51067) (xy 38.336175 -280.524362) (xy 38.28732 -280.530294)
			(xy 38.238145 -280.528313) (xy 38.189926 -280.518469) (xy 38.14391 -280.501017) (xy 38.101289 -280.47641)
			(xy 38.063168 -280.445285) (xy 38.030533 -280.408448) (xy 38.00423 -280.366852) (xy 37.984939 -280.321576)
			(xy 37.973162 -280.273792) (xy 37.969202 -280.224738) (xy 37.6301 -280.224738) (xy 37.629605 -280.249345)
			(xy 37.62171 -280.297922) (xy 37.606126 -280.344603) (xy 37.583255 -280.38818) (xy 37.55369 -280.427524)
			(xy 37.518197 -280.461616) (xy 37.477694 -280.489572) (xy 37.433232 -280.51067) (xy 37.385961 -280.524362)
			(xy 37.337106 -280.530294) (xy 37.287931 -280.528313) (xy 37.239712 -280.518469) (xy 37.193696 -280.501017)
			(xy 37.151075 -280.47641) (xy 37.112954 -280.445285) (xy 37.080319 -280.408448) (xy 37.054016 -280.366852)
			(xy 37.034725 -280.321576) (xy 37.022948 -280.273792) (xy 37.018988 -280.224738) (xy 36.68014 -280.224738)
			(xy 36.679645 -280.249345) (xy 36.67175 -280.297922) (xy 36.656166 -280.344603) (xy 36.633295 -280.38818)
			(xy 36.60373 -280.427524) (xy 36.568237 -280.461616) (xy 36.527734 -280.489572) (xy 36.483272 -280.51067)
			(xy 36.436001 -280.524362) (xy 36.387146 -280.530294) (xy 36.337971 -280.528313) (xy 36.289752 -280.518469)
			(xy 36.243736 -280.501017) (xy 36.201115 -280.47641) (xy 36.162994 -280.445285) (xy 36.130359 -280.408448)
			(xy 36.104056 -280.366852) (xy 36.084765 -280.321576) (xy 36.072988 -280.273792) (xy 36.069028 -280.224738)
			(xy 31.974426 -280.224738) (xy 31.96082 -280.235406) (xy 31.951422 -280.242772) (xy 31.941008 -280.263346)
			(xy 31.939484 -280.367232) (xy 31.94939 -280.388314) (xy 31.958534 -280.39568) (xy 31.980362 -280.413909)
			(xy 32.018902 -280.455724) (xy 32.05081 -280.502795) (xy 32.07538 -280.55408) (xy 32.092068 -280.608443)
			(xy 32.100505 -280.664681) (xy 32.101028 -280.693114) (xy 32.734502 -280.693114) (xy 32.738573 -280.637492)
			(xy 32.750699 -280.583055) (xy 32.770622 -280.530964) (xy 32.797918 -280.482329) (xy 32.832004 -280.438186)
			(xy 32.872153 -280.399477) (xy 32.917511 -280.367026) (xy 32.967111 -280.341525) (xy 33.019895 -280.323518)
			(xy 33.074738 -280.313388) (xy 33.130472 -280.311351) (xy 33.185909 -280.317451) (xy 33.239866 -280.331557)
			(xy 33.291195 -280.353369) (xy 33.338801 -280.382423) (xy 33.381669 -280.418098) (xy 33.418886 -280.459635)
			(xy 33.449659 -280.506148) (xy 33.473331 -280.556645) (xy 33.489399 -280.610052) (xy 33.497519 -280.665228)
			(xy 33.498028 -280.693114) (xy 33.620962 -280.693114) (xy 33.625033 -280.637492) (xy 33.637159 -280.583055)
			(xy 33.657082 -280.530964) (xy 33.684378 -280.482329) (xy 33.718464 -280.438186) (xy 33.758613 -280.399477)
			(xy 33.803971 -280.367026) (xy 33.853571 -280.341525) (xy 33.906355 -280.323518) (xy 33.961198 -280.313388)
			(xy 34.016932 -280.311351) (xy 34.072369 -280.317451) (xy 34.126326 -280.331557) (xy 34.177655 -280.353369)
			(xy 34.225261 -280.382423) (xy 34.268129 -280.418098) (xy 34.305346 -280.459635) (xy 34.336119 -280.506148)
			(xy 34.359791 -280.556645) (xy 34.375859 -280.610052) (xy 34.383979 -280.665228) (xy 34.384488 -280.693114)
			(xy 34.383979 -280.721) (xy 34.375859 -280.776176) (xy 34.359791 -280.829583) (xy 34.336119 -280.88008)
			(xy 34.305346 -280.926593) (xy 34.268129 -280.96813) (xy 34.225261 -281.003805) (xy 34.177655 -281.032859)
			(xy 34.126326 -281.054671) (xy 34.072369 -281.068777) (xy 34.016932 -281.074877) (xy 33.961198 -281.07284)
			(xy 33.906355 -281.06271) (xy 33.853571 -281.044703) (xy 33.803971 -281.019202) (xy 33.758613 -280.986751)
			(xy 33.718464 -280.948042) (xy 33.684378 -280.903899) (xy 33.657082 -280.855264) (xy 33.637159 -280.803173)
			(xy 33.625033 -280.748736) (xy 33.620962 -280.693114) (xy 33.498028 -280.693114) (xy 33.497519 -280.721)
			(xy 33.489399 -280.776176) (xy 33.473331 -280.829583) (xy 33.449659 -280.88008) (xy 33.418886 -280.926593)
			(xy 33.381669 -280.96813) (xy 33.338801 -281.003805) (xy 33.291195 -281.032859) (xy 33.239866 -281.054671)
			(xy 33.185909 -281.068777) (xy 33.130472 -281.074877) (xy 33.074738 -281.07284) (xy 33.019895 -281.06271)
			(xy 32.967111 -281.044703) (xy 32.917511 -281.019202) (xy 32.872153 -280.986751) (xy 32.832004 -280.948042)
			(xy 32.797918 -280.903899) (xy 32.770622 -280.855264) (xy 32.750699 -280.803173) (xy 32.738573 -280.748736)
			(xy 32.734502 -280.693114) (xy 32.101028 -280.693114) (xy 32.100542 -280.720365) (xy 32.092786 -280.774313)
			(xy 32.077431 -280.826608) (xy 32.054789 -280.876185) (xy 32.025323 -280.922035) (xy 31.989632 -280.963226)
			(xy 31.948441 -280.998917) (xy 31.902591 -281.028383) (xy 31.853014 -281.051025) (xy 31.800719 -281.06638)
			(xy 31.746771 -281.074136) (xy 31.692269 -281.074136) (xy 31.638321 -281.06638) (xy 31.586026 -281.051025)
			(xy 31.536449 -281.028383) (xy 31.490599 -280.998917) (xy 31.449408 -280.963226) (xy 31.413717 -280.922035)
			(xy 31.384251 -280.876185) (xy 31.361609 -280.826608) (xy 31.346254 -280.774313) (xy 31.338498 -280.720365)
			(xy 31.338012 -280.693114) (xy 16.708445 -280.693114) (xy 16.708445 -280.722654) (xy 16.700687 -280.776607)
			(xy 16.68533 -280.828907) (xy 16.662685 -280.878489) (xy 16.633215 -280.924343) (xy 16.597518 -280.965537)
			(xy 16.556323 -281.00123) (xy 16.510466 -281.030698) (xy 16.460883 -281.053339) (xy 16.408582 -281.068692)
			(xy 16.354628 -281.076446) (xy 16.327374 -281.076908) (xy 16.297249 -281.076366) (xy 16.237751 -281.06688)
			(xy 16.180482 -281.048163) (xy 16.126866 -281.02068) (xy 16.078233 -280.985115) (xy 16.05661 -280.964132)
			(xy 16.049498 -280.956766) (xy 16.030702 -280.949146) (xy 15.938246 -280.949146) (xy 15.91945 -280.956766)
			(xy 15.912338 -280.964132) (xy 15.890708 -280.985107) (xy 15.842082 -281.020678) (xy 15.788467 -281.048161)
			(xy 15.731197 -281.06687) (xy 15.671698 -281.07634) (xy 15.641574 -281.076908) (xy 15.612835 -281.076398)
			(xy 15.556007 -281.067772) (xy 15.501116 -281.050718) (xy 15.449404 -281.025624) (xy 15.402042 -280.993056)
			(xy 15.380716 -280.973784) (xy 15.373604 -280.96718) (xy 15.356078 -280.960068) (xy 15.26667 -280.960068)
			(xy 15.249144 -280.96718) (xy 15.242032 -280.973784) (xy 15.220705 -280.993054) (xy 15.173342 -281.025619)
			(xy 15.121631 -281.05071) (xy 15.06674 -281.06776) (xy 15.009913 -281.076382) (xy 14.952435 -281.076382)
			(xy 14.895608 -281.06776) (xy 14.840717 -281.05071) (xy 14.789006 -281.025619) (xy 14.741643 -280.993054)
			(xy 14.720316 -280.973784) (xy 14.713204 -280.96718) (xy 14.695678 -280.960068) (xy 14.60627 -280.960068)
			(xy 14.588744 -280.96718) (xy 14.581632 -280.973784) (xy 14.560319 -280.993071) (xy 14.512953 -281.025634)
			(xy 14.461237 -281.050723) (xy 14.406344 -281.06777) (xy 14.349514 -281.076389) (xy 14.320774 -281.076908)
			(xy 14.293524 -281.07642) (xy 14.239579 -281.068661) (xy 14.187287 -281.053304) (xy 14.137713 -281.030661)
			(xy 14.091866 -281.001194) (xy 14.050679 -280.965502) (xy 14.01499 -280.924313) (xy 13.985527 -280.878464)
			(xy 13.962887 -280.828888) (xy 13.947534 -280.776596) (xy 13.939778 -280.72265) (xy 12.461045 -280.72265)
			(xy 12.461045 -280.722653) (xy 12.453287 -280.776606) (xy 12.437931 -280.828905) (xy 12.415287 -280.878486)
			(xy 12.385818 -280.924339) (xy 12.350123 -280.965532) (xy 12.308928 -281.001226) (xy 12.263073 -281.030694)
			(xy 12.213491 -281.053335) (xy 12.161192 -281.06869) (xy 12.10724 -281.076446) (xy 12.079986 -281.076908)
			(xy 12.049862 -281.076358) (xy 11.990364 -281.066874) (xy 11.933095 -281.048159) (xy 11.879478 -281.020678)
			(xy 11.830845 -280.985114) (xy 11.809222 -280.964132) (xy 11.80211 -280.956766) (xy 11.783314 -280.949146)
			(xy 11.690858 -280.949146) (xy 11.672062 -280.956766) (xy 11.66495 -280.964132) (xy 11.643315 -280.985101)
			(xy 11.59469 -281.020673) (xy 11.541076 -281.048157) (xy 11.483808 -281.066867) (xy 11.42431 -281.076339)
			(xy 11.394186 -281.076908) (xy 11.365447 -281.076391) (xy 11.308619 -281.067766) (xy 11.253729 -281.050715)
			(xy 11.202017 -281.025622) (xy 11.154655 -280.993055) (xy 11.133328 -280.973784) (xy 11.126216 -280.96718)
			(xy 11.10869 -280.960068) (xy 11.019282 -280.960068) (xy 11.001756 -280.96718) (xy 10.994644 -280.973784)
			(xy 10.973317 -280.993054) (xy 10.925954 -281.025619) (xy 10.874243 -281.05071) (xy 10.819352 -281.06776)
			(xy 10.762525 -281.076382) (xy 10.705047 -281.076382) (xy 10.64822 -281.06776) (xy 10.593329 -281.05071)
			(xy 10.541618 -281.025619) (xy 10.494255 -280.993054) (xy 10.472928 -280.973784) (xy 10.465816 -280.96718)
			(xy 10.44829 -280.960068) (xy 10.358882 -280.960068) (xy 10.341356 -280.96718) (xy 10.334244 -280.973784)
			(xy 10.312926 -280.993065) (xy 10.265561 -281.025629) (xy 10.213847 -281.050719) (xy 10.158955 -281.067767)
			(xy 10.102126 -281.076388) (xy 10.073386 -281.076908) (xy 10.046135 -281.076421) (xy 9.992189 -281.068663)
			(xy 9.939896 -281.053307) (xy 9.890321 -281.030665) (xy 9.844472 -281.001198) (xy 9.803283 -280.965507)
			(xy 9.767593 -280.924317) (xy 9.738128 -280.878467) (xy 9.715488 -280.828891) (xy 9.700134 -280.776597)
			(xy 9.692378 -280.722651) (xy 1.660398 -280.722651) (xy 1.660398 -281.174952) (xy 36.069028 -281.174952)
			(xy 36.072988 -281.125898) (xy 36.084765 -281.078114) (xy 36.104056 -281.032838) (xy 36.130359 -280.991242)
			(xy 36.162994 -280.954405) (xy 36.201115 -280.92328) (xy 36.243736 -280.898673) (xy 36.289752 -280.881221)
			(xy 36.337971 -280.871377) (xy 36.387146 -280.869396) (xy 36.436001 -280.875328) (xy 36.483272 -280.88902)
			(xy 36.527734 -280.910118) (xy 36.568237 -280.938074) (xy 36.60373 -280.972166) (xy 36.633295 -281.01151)
			(xy 36.656166 -281.055087) (xy 36.67175 -281.101768) (xy 36.679645 -281.150345) (xy 36.68014 -281.174952)
			(xy 37.018988 -281.174952) (xy 37.022948 -281.125898) (xy 37.034725 -281.078114) (xy 37.054016 -281.032838)
			(xy 37.080319 -280.991242) (xy 37.112954 -280.954405) (xy 37.151075 -280.92328) (xy 37.193696 -280.898673)
			(xy 37.239712 -280.881221) (xy 37.287931 -280.871377) (xy 37.337106 -280.869396) (xy 37.385961 -280.875328)
			(xy 37.433232 -280.88902) (xy 37.477694 -280.910118) (xy 37.518197 -280.938074) (xy 37.55369 -280.972166)
			(xy 37.583255 -281.01151) (xy 37.606126 -281.055087) (xy 37.62171 -281.101768) (xy 37.629605 -281.150345)
			(xy 37.6301 -281.174952) (xy 37.969202 -281.174952) (xy 37.973162 -281.125898) (xy 37.984939 -281.078114)
			(xy 38.00423 -281.032838) (xy 38.030533 -280.991242) (xy 38.063168 -280.954405) (xy 38.101289 -280.92328)
			(xy 38.14391 -280.898673) (xy 38.189926 -280.881221) (xy 38.238145 -280.871377) (xy 38.28732 -280.869396)
			(xy 38.336175 -280.875328) (xy 38.383446 -280.88902) (xy 38.427908 -280.910118) (xy 38.468411 -280.938074)
			(xy 38.503904 -280.972166) (xy 38.533469 -281.01151) (xy 38.55634 -281.055087) (xy 38.571924 -281.101768)
			(xy 38.579819 -281.150345) (xy 38.580314 -281.174952) (xy 38.919162 -281.174952) (xy 38.923122 -281.125898)
			(xy 38.934899 -281.078114) (xy 38.95419 -281.032838) (xy 38.980493 -280.991242) (xy 39.013128 -280.954405)
			(xy 39.051249 -280.92328) (xy 39.09387 -280.898673) (xy 39.139886 -280.881221) (xy 39.188105 -280.871377)
			(xy 39.23728 -280.869396) (xy 39.286135 -280.875328) (xy 39.333406 -280.88902) (xy 39.377868 -280.910118)
			(xy 39.418371 -280.938074) (xy 39.453864 -280.972166) (xy 39.483429 -281.01151) (xy 39.5063 -281.055087)
			(xy 39.521884 -281.101768) (xy 39.529779 -281.150345) (xy 39.530274 -281.174952) (xy 39.529779 -281.199559)
			(xy 39.521884 -281.248136) (xy 39.5063 -281.294817) (xy 39.483429 -281.338394) (xy 39.453864 -281.377738)
			(xy 39.418371 -281.41183) (xy 39.377868 -281.439786) (xy 39.333406 -281.460884) (xy 39.286135 -281.474576)
			(xy 39.23728 -281.480508) (xy 39.188105 -281.478527) (xy 39.139886 -281.468683) (xy 39.09387 -281.451231)
			(xy 39.051249 -281.426624) (xy 39.013128 -281.395499) (xy 38.980493 -281.358662) (xy 38.95419 -281.317066)
			(xy 38.934899 -281.27179) (xy 38.923122 -281.224006) (xy 38.919162 -281.174952) (xy 38.580314 -281.174952)
			(xy 38.579819 -281.199559) (xy 38.571924 -281.248136) (xy 38.55634 -281.294817) (xy 38.533469 -281.338394)
			(xy 38.503904 -281.377738) (xy 38.468411 -281.41183) (xy 38.427908 -281.439786) (xy 38.383446 -281.460884)
			(xy 38.336175 -281.474576) (xy 38.28732 -281.480508) (xy 38.238145 -281.478527) (xy 38.189926 -281.468683)
			(xy 38.14391 -281.451231) (xy 38.101289 -281.426624) (xy 38.063168 -281.395499) (xy 38.030533 -281.358662)
			(xy 38.00423 -281.317066) (xy 37.984939 -281.27179) (xy 37.973162 -281.224006) (xy 37.969202 -281.174952)
			(xy 37.6301 -281.174952) (xy 37.629605 -281.199559) (xy 37.62171 -281.248136) (xy 37.606126 -281.294817)
			(xy 37.583255 -281.338394) (xy 37.55369 -281.377738) (xy 37.518197 -281.41183) (xy 37.477694 -281.439786)
			(xy 37.433232 -281.460884) (xy 37.385961 -281.474576) (xy 37.337106 -281.480508) (xy 37.287931 -281.478527)
			(xy 37.239712 -281.468683) (xy 37.193696 -281.451231) (xy 37.151075 -281.426624) (xy 37.112954 -281.395499)
			(xy 37.080319 -281.358662) (xy 37.054016 -281.317066) (xy 37.034725 -281.27179) (xy 37.022948 -281.224006)
			(xy 37.018988 -281.174952) (xy 36.68014 -281.174952) (xy 36.679645 -281.199559) (xy 36.67175 -281.248136)
			(xy 36.656166 -281.294817) (xy 36.633295 -281.338394) (xy 36.60373 -281.377738) (xy 36.568237 -281.41183)
			(xy 36.527734 -281.439786) (xy 36.483272 -281.460884) (xy 36.436001 -281.474576) (xy 36.387146 -281.480508)
			(xy 36.337971 -281.478527) (xy 36.289752 -281.468683) (xy 36.243736 -281.451231) (xy 36.201115 -281.426624)
			(xy 36.162994 -281.395499) (xy 36.130359 -281.358662) (xy 36.104056 -281.317066) (xy 36.084765 -281.27179)
			(xy 36.072988 -281.224006) (xy 36.069028 -281.174952) (xy 1.660398 -281.174952) (xy 1.660398 -281.829256)
			(xy 25.811478 -281.829256) (xy 25.815549 -281.773634) (xy 25.827675 -281.719197) (xy 25.847598 -281.667106)
			(xy 25.874894 -281.618471) (xy 25.90898 -281.574328) (xy 25.949129 -281.535619) (xy 25.994487 -281.503168)
			(xy 26.044087 -281.477667) (xy 26.096871 -281.45966) (xy 26.151714 -281.44953) (xy 26.207448 -281.447493)
			(xy 26.262885 -281.453593) (xy 26.316842 -281.467699) (xy 26.368171 -281.489511) (xy 26.415777 -281.518565)
			(xy 26.458645 -281.55424) (xy 26.495862 -281.595777) (xy 26.526635 -281.64229) (xy 26.550307 -281.692787)
			(xy 26.566375 -281.746194) (xy 26.574495 -281.80137) (xy 26.575004 -281.829256) (xy 27.296616 -281.829256)
			(xy 27.300687 -281.773634) (xy 27.312813 -281.719197) (xy 27.332736 -281.667106) (xy 27.360032 -281.618471)
			(xy 27.394118 -281.574328) (xy 27.434267 -281.535619) (xy 27.479625 -281.503168) (xy 27.529225 -281.477667)
			(xy 27.582009 -281.45966) (xy 27.636852 -281.44953) (xy 27.692586 -281.447493) (xy 27.748023 -281.453593)
			(xy 27.80198 -281.467699) (xy 27.853309 -281.489511) (xy 27.900915 -281.518565) (xy 27.943783 -281.55424)
			(xy 27.981 -281.595777) (xy 28.011773 -281.64229) (xy 28.035445 -281.692787) (xy 28.051513 -281.746194)
			(xy 28.059633 -281.80137) (xy 28.060142 -281.829256) (xy 28.059633 -281.857142) (xy 28.051513 -281.912318)
			(xy 28.035445 -281.965725) (xy 28.011773 -282.016222) (xy 27.981 -282.062735) (xy 27.943783 -282.104272)
			(xy 27.918981 -282.124912) (xy 36.069028 -282.124912) (xy 36.072988 -282.075858) (xy 36.084765 -282.028074)
			(xy 36.104056 -281.982798) (xy 36.130359 -281.941202) (xy 36.162994 -281.904365) (xy 36.201115 -281.87324)
			(xy 36.243736 -281.848633) (xy 36.289752 -281.831181) (xy 36.337971 -281.821337) (xy 36.387146 -281.819356)
			(xy 36.436001 -281.825288) (xy 36.483272 -281.83898) (xy 36.527734 -281.860078) (xy 36.568237 -281.888034)
			(xy 36.60373 -281.922126) (xy 36.633295 -281.96147) (xy 36.656166 -282.005047) (xy 36.67175 -282.051728)
			(xy 36.679645 -282.100305) (xy 36.68014 -282.124912) (xy 37.018988 -282.124912) (xy 37.022948 -282.075858)
			(xy 37.034725 -282.028074) (xy 37.054016 -281.982798) (xy 37.080319 -281.941202) (xy 37.112954 -281.904365)
			(xy 37.151075 -281.87324) (xy 37.193696 -281.848633) (xy 37.239712 -281.831181) (xy 37.287931 -281.821337)
			(xy 37.337106 -281.819356) (xy 37.385961 -281.825288) (xy 37.433232 -281.83898) (xy 37.477694 -281.860078)
			(xy 37.518197 -281.888034) (xy 37.55369 -281.922126) (xy 37.583255 -281.96147) (xy 37.606126 -282.005047)
			(xy 37.62171 -282.051728) (xy 37.629605 -282.100305) (xy 37.6301 -282.124912) (xy 37.969202 -282.124912)
			(xy 37.973162 -282.075858) (xy 37.984939 -282.028074) (xy 38.00423 -281.982798) (xy 38.030533 -281.941202)
			(xy 38.063168 -281.904365) (xy 38.101289 -281.87324) (xy 38.14391 -281.848633) (xy 38.189926 -281.831181)
			(xy 38.238145 -281.821337) (xy 38.28732 -281.819356) (xy 38.336175 -281.825288) (xy 38.383446 -281.83898)
			(xy 38.427908 -281.860078) (xy 38.468411 -281.888034) (xy 38.503904 -281.922126) (xy 38.533469 -281.96147)
			(xy 38.55634 -282.005047) (xy 38.571924 -282.051728) (xy 38.579819 -282.100305) (xy 38.580314 -282.124912)
			(xy 38.919162 -282.124912) (xy 38.923122 -282.075858) (xy 38.934899 -282.028074) (xy 38.95419 -281.982798)
			(xy 38.980493 -281.941202) (xy 39.013128 -281.904365) (xy 39.051249 -281.87324) (xy 39.09387 -281.848633)
			(xy 39.139886 -281.831181) (xy 39.188105 -281.821337) (xy 39.23728 -281.819356) (xy 39.286135 -281.825288)
			(xy 39.333406 -281.83898) (xy 39.377868 -281.860078) (xy 39.418371 -281.888034) (xy 39.453864 -281.922126)
			(xy 39.483429 -281.96147) (xy 39.5063 -282.005047) (xy 39.521884 -282.051728) (xy 39.529779 -282.100305)
			(xy 39.530274 -282.124912) (xy 39.529779 -282.149519) (xy 39.521884 -282.198096) (xy 39.5063 -282.244777)
			(xy 39.483429 -282.288354) (xy 39.453864 -282.327698) (xy 39.418371 -282.36179) (xy 39.377868 -282.389746)
			(xy 39.333406 -282.410844) (xy 39.286135 -282.424536) (xy 39.23728 -282.430468) (xy 39.188105 -282.428487)
			(xy 39.139886 -282.418643) (xy 39.09387 -282.401191) (xy 39.051249 -282.376584) (xy 39.013128 -282.345459)
			(xy 38.980493 -282.308622) (xy 38.95419 -282.267026) (xy 38.934899 -282.22175) (xy 38.923122 -282.173966)
			(xy 38.919162 -282.124912) (xy 38.580314 -282.124912) (xy 38.579819 -282.149519) (xy 38.571924 -282.198096)
			(xy 38.55634 -282.244777) (xy 38.533469 -282.288354) (xy 38.503904 -282.327698) (xy 38.468411 -282.36179)
			(xy 38.427908 -282.389746) (xy 38.383446 -282.410844) (xy 38.336175 -282.424536) (xy 38.28732 -282.430468)
			(xy 38.238145 -282.428487) (xy 38.189926 -282.418643) (xy 38.14391 -282.401191) (xy 38.101289 -282.376584)
			(xy 38.063168 -282.345459) (xy 38.030533 -282.308622) (xy 38.00423 -282.267026) (xy 37.984939 -282.22175)
			(xy 37.973162 -282.173966) (xy 37.969202 -282.124912) (xy 37.6301 -282.124912) (xy 37.629605 -282.149519)
			(xy 37.62171 -282.198096) (xy 37.606126 -282.244777) (xy 37.583255 -282.288354) (xy 37.55369 -282.327698)
			(xy 37.518197 -282.36179) (xy 37.477694 -282.389746) (xy 37.433232 -282.410844) (xy 37.385961 -282.424536)
			(xy 37.337106 -282.430468) (xy 37.287931 -282.428487) (xy 37.239712 -282.418643) (xy 37.193696 -282.401191)
			(xy 37.151075 -282.376584) (xy 37.112954 -282.345459) (xy 37.080319 -282.308622) (xy 37.054016 -282.267026)
			(xy 37.034725 -282.22175) (xy 37.022948 -282.173966) (xy 37.018988 -282.124912) (xy 36.68014 -282.124912)
			(xy 36.679645 -282.149519) (xy 36.67175 -282.198096) (xy 36.656166 -282.244777) (xy 36.633295 -282.288354)
			(xy 36.60373 -282.327698) (xy 36.568237 -282.36179) (xy 36.527734 -282.389746) (xy 36.483272 -282.410844)
			(xy 36.436001 -282.424536) (xy 36.387146 -282.430468) (xy 36.337971 -282.428487) (xy 36.289752 -282.418643)
			(xy 36.243736 -282.401191) (xy 36.201115 -282.376584) (xy 36.162994 -282.345459) (xy 36.130359 -282.308622)
			(xy 36.104056 -282.267026) (xy 36.084765 -282.22175) (xy 36.072988 -282.173966) (xy 36.069028 -282.124912)
			(xy 27.918981 -282.124912) (xy 27.900915 -282.139947) (xy 27.853309 -282.169001) (xy 27.80198 -282.190813)
			(xy 27.748023 -282.204919) (xy 27.692586 -282.211019) (xy 27.636852 -282.208982) (xy 27.582009 -282.198852)
			(xy 27.529225 -282.180845) (xy 27.479625 -282.155344) (xy 27.434267 -282.122893) (xy 27.394118 -282.084184)
			(xy 27.360032 -282.040041) (xy 27.332736 -281.991406) (xy 27.312813 -281.939315) (xy 27.300687 -281.884878)
			(xy 27.296616 -281.829256) (xy 26.575004 -281.829256) (xy 26.574495 -281.857142) (xy 26.566375 -281.912318)
			(xy 26.550307 -281.965725) (xy 26.526635 -282.016222) (xy 26.495862 -282.062735) (xy 26.458645 -282.104272)
			(xy 26.415777 -282.139947) (xy 26.368171 -282.169001) (xy 26.316842 -282.190813) (xy 26.262885 -282.204919)
			(xy 26.207448 -282.211019) (xy 26.151714 -282.208982) (xy 26.096871 -282.198852) (xy 26.044087 -282.180845)
			(xy 25.994487 -282.155344) (xy 25.949129 -282.122893) (xy 25.90898 -282.084184) (xy 25.874894 -282.040041)
			(xy 25.847598 -281.991406) (xy 25.827675 -281.939315) (xy 25.815549 -281.884878) (xy 25.811478 -281.829256)
			(xy 1.660398 -281.829256) (xy 1.660398 -282.382031) (xy 1.86739 -282.382031) (xy 1.86739 -282.327529)
			(xy 1.875146 -282.273582) (xy 1.890501 -282.221287) (xy 1.913142 -282.171711) (xy 1.942608 -282.12586)
			(xy 1.978299 -282.084671) (xy 2.019489 -282.048979) (xy 2.065339 -282.019513) (xy 2.114916 -281.996872)
			(xy 2.16721 -281.981517) (xy 2.221157 -281.97376) (xy 2.248408 -281.973274) (xy 2.277147 -281.9738)
			(xy 2.333974 -281.982423) (xy 2.388864 -281.999473) (xy 2.440576 -282.024564) (xy 2.487939 -282.057128)
			(xy 2.509266 -282.076398) (xy 2.516378 -282.083002) (xy 2.533904 -282.090114) (xy 2.623312 -282.090114)
			(xy 2.640838 -282.083002) (xy 2.64795 -282.076398) (xy 2.669283 -282.057134) (xy 2.716642 -282.024564)
			(xy 2.768352 -281.99947) (xy 2.823242 -281.982418) (xy 2.880069 -281.973795) (xy 2.908808 -281.973274)
			(xy 2.938932 -281.973833) (xy 2.998429 -281.983316) (xy 3.055698 -282.002029) (xy 3.109314 -282.029508)
			(xy 3.157948 -282.065069) (xy 3.179572 -282.08605) (xy 3.186684 -282.093416) (xy 3.20548 -282.101036)
			(xy 3.297936 -282.101036) (xy 3.316732 -282.093416) (xy 3.323844 -282.08605) (xy 3.345479 -282.06508)
			(xy 3.394104 -282.029509) (xy 3.447718 -282.002026) (xy 3.504986 -281.983315) (xy 3.564484 -281.973843)
			(xy 3.594608 -281.973274) (xy 3.621979 -281.973717) (xy 3.67616 -281.981538) (xy 3.728664 -281.997031)
			(xy 3.778411 -282.019879) (xy 3.824376 -282.049609) (xy 3.845306 -282.067254) (xy 3.852418 -282.07335)
			(xy 3.869436 -282.0797) (xy 3.95478 -282.0797) (xy 3.971798 -282.07335) (xy 3.97891 -282.067254)
			(xy 3.999834 -282.049605) (xy 4.045808 -282.019893) (xy 4.095558 -281.997058) (xy 4.148061 -281.981569)
			(xy 4.202238 -281.973745) (xy 4.229608 -281.973274) (xy 4.256861 -281.973733) (xy 4.310813 -281.98149)
			(xy 4.363111 -281.996846) (xy 4.412691 -282.019488) (xy 4.458545 -282.048957) (xy 4.499738 -282.08465)
			(xy 4.535432 -282.125843) (xy 4.564901 -282.171697) (xy 4.587543 -282.221277) (xy 4.6029 -282.273576)
			(xy 4.610657 -282.327527) (xy 4.610657 -282.382031) (xy 5.88618 -282.382031) (xy 5.88618 -282.327529)
			(xy 5.893936 -282.273582) (xy 5.909291 -282.221288) (xy 5.931932 -282.171711) (xy 5.961397 -282.125861)
			(xy 5.997088 -282.084671) (xy 6.038278 -282.04898) (xy 6.084128 -282.019514) (xy 6.133704 -281.996872)
			(xy 6.185998 -281.981517) (xy 6.239945 -281.97376) (xy 6.267196 -281.973274) (xy 6.295934 -281.973807)
			(xy 6.352761 -281.982428) (xy 6.407651 -281.999477) (xy 6.459363 -282.024566) (xy 6.506727 -282.057129)
			(xy 6.528054 -282.076398) (xy 6.535166 -282.083002) (xy 6.552692 -282.090114) (xy 6.6421 -282.090114)
			(xy 6.659626 -282.083002) (xy 6.666738 -282.076398) (xy 6.688065 -282.057128) (xy 6.735428 -282.024563)
			(xy 6.787139 -281.999472) (xy 6.84203 -281.982422) (xy 6.898857 -281.9738) (xy 6.956335 -281.9738)
			(xy 7.013162 -281.982422) (xy 7.068053 -281.999472) (xy 7.119764 -282.024563) (xy 7.167127 -282.057128)
			(xy 7.188454 -282.076398) (xy 7.195566 -282.083002) (xy 7.213092 -282.090114) (xy 7.3025 -282.090114)
			(xy 7.320026 -282.083002) (xy 7.327138 -282.076398) (xy 7.348476 -282.05714) (xy 7.395834 -282.024569)
			(xy 7.447543 -281.999474) (xy 7.502431 -281.98242) (xy 7.559258 -281.973796) (xy 7.587996 -281.973274)
			(xy 7.61812 -281.97384) (xy 7.677617 -281.983321) (xy 7.734885 -282.002033) (xy 7.788502 -282.02951)
			(xy 7.837136 -282.06507) (xy 7.85876 -282.08605) (xy 7.865872 -282.093416) (xy 7.884668 -282.101036)
			(xy 7.977124 -282.101036) (xy 7.99592 -282.093416) (xy 8.003032 -282.08605) (xy 8.024672 -282.065086)
			(xy 8.073296 -282.029514) (xy 8.126908 -282.00203) (xy 8.184175 -281.983318) (xy 8.243673 -281.973844)
			(xy 8.273796 -281.973274) (xy 8.301049 -281.973733) (xy 8.355001 -281.98149) (xy 8.407299 -281.996845)
			(xy 8.45688 -282.019488) (xy 8.502734 -282.048956) (xy 8.543928 -282.08465) (xy 8.579622 -282.125843)
			(xy 8.60909 -282.171696) (xy 8.631733 -282.221277) (xy 8.64709 -282.273575) (xy 8.654847 -282.327527)
			(xy 8.654847 -282.382033) (xy 8.64709 -282.435985) (xy 8.631733 -282.488283) (xy 8.60909 -282.537864)
			(xy 8.579622 -282.583717) (xy 8.543928 -282.62491) (xy 8.502734 -282.660604) (xy 8.45688 -282.690072)
			(xy 8.407299 -282.712715) (xy 8.355001 -282.72807) (xy 8.301049 -282.735827) (xy 8.273796 -282.73629)
			(xy 8.243672 -282.735739) (xy 8.184174 -282.726256) (xy 8.126905 -282.707541) (xy 8.073288 -282.68006)
			(xy 8.024656 -282.644496) (xy 8.003032 -282.623514) (xy 7.99592 -282.616148) (xy 7.977124 -282.608528)
			(xy 7.884668 -282.608528) (xy 7.865872 -282.616148) (xy 7.85876 -282.623514) (xy 7.837134 -282.644493)
			(xy 7.788505 -282.680061) (xy 7.734889 -282.707541) (xy 7.677619 -282.726249) (xy 7.61812 -282.735721)
			(xy 7.587996 -282.73629) (xy 7.559257 -282.735771) (xy 7.502429 -282.727148) (xy 7.447538 -282.710097)
			(xy 7.395827 -282.685004) (xy 7.348464 -282.652437) (xy 7.327138 -282.633166) (xy 7.320026 -282.626562)
			(xy 7.3025 -282.61945) (xy 7.213092 -282.61945) (xy 7.195566 -282.626562) (xy 7.188454 -282.633166)
			(xy 7.167127 -282.652436) (xy 7.119764 -282.685001) (xy 7.068053 -282.710092) (xy 7.013162 -282.727142)
			(xy 6.956335 -282.735764) (xy 6.898857 -282.735764) (xy 6.84203 -282.727142) (xy 6.787139 -282.710092)
			(xy 6.735428 -282.685001) (xy 6.688065 -282.652436) (xy 6.666738 -282.633166) (xy 6.659626 -282.626562)
			(xy 6.6421 -282.61945) (xy 6.552692 -282.61945) (xy 6.535166 -282.626562) (xy 6.528054 -282.633166)
			(xy 6.506729 -282.652439) (xy 6.459366 -282.685005) (xy 6.407654 -282.710097) (xy 6.352763 -282.727147)
			(xy 6.295935 -282.735769) (xy 6.267196 -282.73629) (xy 6.239945 -282.7358) (xy 6.185998 -282.728043)
			(xy 6.133704 -282.712688) (xy 6.084128 -282.690046) (xy 6.038278 -282.66058) (xy 5.997088 -282.624889)
			(xy 5.961397 -282.583699) (xy 5.931932 -282.537849) (xy 5.909291 -282.488272) (xy 5.893936 -282.435978)
			(xy 5.88618 -282.382031) (xy 4.610657 -282.382031) (xy 4.610657 -282.382033) (xy 4.6029 -282.435984)
			(xy 4.587543 -282.488283) (xy 4.564901 -282.537863) (xy 4.535432 -282.583717) (xy 4.499738 -282.62491)
			(xy 4.458545 -282.660603) (xy 4.412691 -282.690072) (xy 4.363111 -282.712714) (xy 4.310813 -282.72807)
			(xy 4.256861 -282.735827) (xy 4.229608 -282.73629) (xy 4.202238 -282.735822) (xy 4.148059 -282.728005)
			(xy 4.095556 -282.712516) (xy 4.045809 -282.689675) (xy 3.999842 -282.659951) (xy 3.97891 -282.64231)
			(xy 3.971798 -282.636214) (xy 3.95478 -282.629864) (xy 3.869436 -282.629864) (xy 3.852418 -282.636214)
			(xy 3.845306 -282.64231) (xy 3.824384 -282.659961) (xy 3.778408 -282.689671) (xy 3.728658 -282.712504)
			(xy 3.676155 -282.727993) (xy 3.621978 -282.735818) (xy 3.594608 -282.73629) (xy 3.564484 -282.735731)
			(xy 3.504986 -282.72625) (xy 3.447717 -282.707537) (xy 3.394101 -282.680058) (xy 3.345468 -282.644495)
			(xy 3.323844 -282.623514) (xy 3.316732 -282.616148) (xy 3.297936 -282.608528) (xy 3.20548 -282.608528)
			(xy 3.186684 -282.616148) (xy 3.179572 -282.623514) (xy 3.157941 -282.644487) (xy 3.109313 -282.680056)
			(xy 3.055699 -282.707537) (xy 2.99843 -282.726247) (xy 2.938932 -282.73572) (xy 2.908808 -282.73629)
			(xy 2.880069 -282.735764) (xy 2.823242 -282.727142) (xy 2.768351 -282.710093) (xy 2.716639 -282.685002)
			(xy 2.669277 -282.652437) (xy 2.64795 -282.633166) (xy 2.640838 -282.626562) (xy 2.623312 -282.61945)
			(xy 2.533904 -282.61945) (xy 2.516378 -282.626562) (xy 2.509266 -282.633166) (xy 2.487936 -282.652434)
			(xy 2.440575 -282.685) (xy 2.388864 -282.710093) (xy 2.333974 -282.727145) (xy 2.277147 -282.735768)
			(xy 2.248408 -282.73629) (xy 2.221157 -282.7358) (xy 2.16721 -282.728043) (xy 2.114916 -282.712688)
			(xy 2.065339 -282.690047) (xy 2.019489 -282.660581) (xy 1.978299 -282.624889) (xy 1.942608 -282.5837)
			(xy 1.913142 -282.537849) (xy 1.890501 -282.488273) (xy 1.875146 -282.435978) (xy 1.86739 -282.382031)
			(xy 1.660398 -282.382031) (xy 1.660398 -283.186451) (xy 9.692378 -283.186451) (xy 9.692378 -283.131949)
			(xy 9.700134 -283.078003) (xy 9.715488 -283.025709) (xy 9.738128 -282.976133) (xy 9.767593 -282.930283)
			(xy 9.803283 -282.889093) (xy 9.844472 -282.853402) (xy 9.890321 -282.823935) (xy 9.939896 -282.801293)
			(xy 9.992189 -282.785937) (xy 10.046135 -282.778179) (xy 10.073386 -282.777692) (xy 10.102124 -282.778226)
			(xy 10.158951 -282.786847) (xy 10.213842 -282.803894) (xy 10.265554 -282.828984) (xy 10.312917 -282.861546)
			(xy 10.334244 -282.880816) (xy 10.341356 -282.88742) (xy 10.358882 -282.894532) (xy 10.44829 -282.894532)
			(xy 10.465816 -282.88742) (xy 10.472928 -282.880816) (xy 10.494255 -282.861546) (xy 10.541618 -282.828981)
			(xy 10.593329 -282.80389) (xy 10.64822 -282.78684) (xy 10.705047 -282.778218) (xy 10.762525 -282.778218)
			(xy 10.819352 -282.78684) (xy 10.874243 -282.80389) (xy 10.925954 -282.828981) (xy 10.973317 -282.861546)
			(xy 10.994644 -282.880816) (xy 11.001756 -282.88742) (xy 11.019282 -282.894532) (xy 11.10869 -282.894532)
			(xy 11.126216 -282.88742) (xy 11.133328 -282.880816) (xy 11.154658 -282.861548) (xy 11.202019 -282.828982)
			(xy 11.25373 -282.80389) (xy 11.30862 -282.786838) (xy 11.365447 -282.778214) (xy 11.394186 -282.777692)
			(xy 11.42431 -282.77826) (xy 11.483807 -282.78774) (xy 11.541075 -282.806451) (xy 11.594692 -282.833928)
			(xy 11.643326 -282.869488) (xy 11.66495 -282.890468) (xy 11.672062 -282.897834) (xy 11.690858 -282.905454)
			(xy 11.783314 -282.905454) (xy 11.80211 -282.897834) (xy 11.809222 -282.890468) (xy 11.83087 -282.869512)
			(xy 11.879491 -282.833938) (xy 11.933102 -282.806452) (xy 11.990367 -282.787739) (xy 12.049863 -282.778263)
			(xy 12.079986 -282.777692) (xy 12.10724 -282.778154) (xy 12.161192 -282.78591) (xy 12.213491 -282.801265)
			(xy 12.263073 -282.823906) (xy 12.308928 -282.853374) (xy 12.350123 -282.889068) (xy 12.385818 -282.930261)
			(xy 12.415287 -282.976114) (xy 12.437931 -283.025695) (xy 12.453287 -283.077994) (xy 12.461045 -283.131947)
			(xy 12.461045 -283.18645) (xy 13.965178 -283.18645) (xy 13.965178 -283.13195) (xy 13.972934 -283.078004)
			(xy 13.988287 -283.025712) (xy 14.010927 -282.976136) (xy 14.04039 -282.930287) (xy 14.076079 -282.889098)
			(xy 14.117266 -282.853406) (xy 14.163113 -282.823939) (xy 14.212687 -282.801296) (xy 14.264979 -282.785939)
			(xy 14.318924 -282.77818) (xy 14.346174 -282.777692) (xy 14.374912 -282.778234) (xy 14.431739 -282.786852)
			(xy 14.486629 -282.803898) (xy 14.538341 -282.828986) (xy 14.585705 -282.861547) (xy 14.607032 -282.880816)
			(xy 14.614144 -282.88742) (xy 14.63167 -282.894532) (xy 14.721078 -282.894532) (xy 14.738604 -282.88742)
			(xy 14.745716 -282.880816) (xy 14.767043 -282.861546) (xy 14.814406 -282.828981) (xy 14.866117 -282.80389)
			(xy 14.921008 -282.78684) (xy 14.977835 -282.778218) (xy 15.035313 -282.778218) (xy 15.09214 -282.78684)
			(xy 15.147031 -282.80389) (xy 15.198742 -282.828981) (xy 15.246105 -282.861546) (xy 15.267432 -282.880816)
			(xy 15.274544 -282.88742) (xy 15.29207 -282.894532) (xy 15.381478 -282.894532) (xy 15.399004 -282.88742)
			(xy 15.406116 -282.880816) (xy 15.42745 -282.861554) (xy 15.474811 -282.828987) (xy 15.526521 -282.803894)
			(xy 15.58141 -282.786841) (xy 15.638236 -282.778215) (xy 15.666974 -282.777692) (xy 15.697097 -282.778267)
			(xy 15.756594 -282.787745) (xy 15.813862 -282.806455) (xy 15.86748 -282.83393) (xy 15.916113 -282.869489)
			(xy 15.937738 -282.890468) (xy 15.94485 -282.897834) (xy 15.963646 -282.905454) (xy 16.056102 -282.905454)
			(xy 16.074898 -282.897834) (xy 16.08201 -282.890468) (xy 16.103619 -282.86947) (xy 16.152251 -282.833901)
			(xy 16.205871 -282.806423) (xy 16.263145 -282.78772) (xy 16.322648 -282.778256) (xy 16.352774 -282.777692)
			(xy 16.380028 -282.778154) (xy 16.433982 -282.785908) (xy 16.486283 -282.801261) (xy 16.535866 -282.823902)
			(xy 16.581723 -282.85337) (xy 16.622918 -282.889063) (xy 16.658615 -282.930257) (xy 16.688085 -282.976111)
			(xy 16.71073 -283.025693) (xy 16.726087 -283.077993) (xy 16.733783 -283.131514) (xy 25.811478 -283.131514)
			(xy 25.815549 -283.075892) (xy 25.827675 -283.021455) (xy 25.847598 -282.969364) (xy 25.874894 -282.920729)
			(xy 25.90898 -282.876586) (xy 25.949129 -282.837877) (xy 25.994487 -282.805426) (xy 26.044087 -282.779925)
			(xy 26.096871 -282.761918) (xy 26.151714 -282.751788) (xy 26.207448 -282.749751) (xy 26.262885 -282.755851)
			(xy 26.316842 -282.769957) (xy 26.368171 -282.791769) (xy 26.415777 -282.820823) (xy 26.458645 -282.856498)
			(xy 26.495862 -282.898035) (xy 26.526635 -282.944548) (xy 26.550307 -282.995045) (xy 26.566375 -283.048452)
			(xy 26.574495 -283.103628) (xy 26.575004 -283.131514) (xy 27.286964 -283.131514) (xy 27.291035 -283.075892)
			(xy 27.303161 -283.021455) (xy 27.323084 -282.969364) (xy 27.35038 -282.920729) (xy 27.384466 -282.876586)
			(xy 27.424615 -282.837877) (xy 27.469973 -282.805426) (xy 27.519573 -282.779925) (xy 27.572357 -282.761918)
			(xy 27.6272 -282.751788) (xy 27.682934 -282.749751) (xy 27.738371 -282.755851) (xy 27.792328 -282.769957)
			(xy 27.843657 -282.791769) (xy 27.891263 -282.820823) (xy 27.934131 -282.856498) (xy 27.971348 -282.898035)
			(xy 28.002121 -282.944548) (xy 28.025793 -282.995045) (xy 28.041861 -283.048452) (xy 28.049981 -283.103628)
			(xy 28.05049 -283.131514) (xy 28.175964 -283.131514) (xy 28.180035 -283.075892) (xy 28.192161 -283.021455)
			(xy 28.212084 -282.969364) (xy 28.23938 -282.920729) (xy 28.273466 -282.876586) (xy 28.313615 -282.837877)
			(xy 28.358973 -282.805426) (xy 28.408573 -282.779925) (xy 28.461357 -282.761918) (xy 28.5162 -282.751788)
			(xy 28.571934 -282.749751) (xy 28.627371 -282.755851) (xy 28.681328 -282.769957) (xy 28.732657 -282.791769)
			(xy 28.780263 -282.820823) (xy 28.823131 -282.856498) (xy 28.860348 -282.898035) (xy 28.891121 -282.944548)
			(xy 28.914793 -282.995045) (xy 28.930861 -283.048452) (xy 28.938981 -283.103628) (xy 28.93949 -283.131514)
			(xy 28.938981 -283.1594) (xy 28.930861 -283.214576) (xy 28.914793 -283.267983) (xy 28.891121 -283.31848)
			(xy 28.860348 -283.364993) (xy 28.823131 -283.40653) (xy 28.780263 -283.442205) (xy 28.732657 -283.471259)
			(xy 28.681328 -283.493071) (xy 28.627371 -283.507177) (xy 28.571934 -283.513277) (xy 28.5162 -283.51124)
			(xy 28.461357 -283.50111) (xy 28.408573 -283.483103) (xy 28.358973 -283.457602) (xy 28.313615 -283.425151)
			(xy 28.273466 -283.386442) (xy 28.23938 -283.342299) (xy 28.212084 -283.293664) (xy 28.192161 -283.241573)
			(xy 28.180035 -283.187136) (xy 28.175964 -283.131514) (xy 28.05049 -283.131514) (xy 28.049981 -283.1594)
			(xy 28.041861 -283.214576) (xy 28.025793 -283.267983) (xy 28.002121 -283.31848) (xy 27.971348 -283.364993)
			(xy 27.934131 -283.40653) (xy 27.891263 -283.442205) (xy 27.843657 -283.471259) (xy 27.792328 -283.493071)
			(xy 27.738371 -283.507177) (xy 27.682934 -283.513277) (xy 27.6272 -283.51124) (xy 27.572357 -283.50111)
			(xy 27.519573 -283.483103) (xy 27.469973 -283.457602) (xy 27.424615 -283.425151) (xy 27.384466 -283.386442)
			(xy 27.35038 -283.342299) (xy 27.323084 -283.293664) (xy 27.303161 -283.241573) (xy 27.291035 -283.187136)
			(xy 27.286964 -283.131514) (xy 26.575004 -283.131514) (xy 26.574495 -283.1594) (xy 26.566375 -283.214576)
			(xy 26.550307 -283.267983) (xy 26.526635 -283.31848) (xy 26.495862 -283.364993) (xy 26.458645 -283.40653)
			(xy 26.415777 -283.442205) (xy 26.368171 -283.471259) (xy 26.316842 -283.493071) (xy 26.262885 -283.507177)
			(xy 26.207448 -283.513277) (xy 26.151714 -283.51124) (xy 26.096871 -283.50111) (xy 26.044087 -283.483103)
			(xy 25.994487 -283.457602) (xy 25.949129 -283.425151) (xy 25.90898 -283.386442) (xy 25.874894 -283.342299)
			(xy 25.847598 -283.293664) (xy 25.827675 -283.241573) (xy 25.815549 -283.187136) (xy 25.811478 -283.131514)
			(xy 16.733783 -283.131514) (xy 16.733845 -283.131946) (xy 16.733845 -283.186454) (xy 16.726087 -283.240407)
			(xy 16.71073 -283.292707) (xy 16.688085 -283.342289) (xy 16.658615 -283.388143) (xy 16.622918 -283.429337)
			(xy 16.581723 -283.46503) (xy 16.535866 -283.494498) (xy 16.486283 -283.517139) (xy 16.433982 -283.532492)
			(xy 16.380028 -283.540246) (xy 16.352774 -283.540708) (xy 16.322649 -283.540166) (xy 16.263151 -283.53068)
			(xy 16.205882 -283.511963) (xy 16.152266 -283.48448) (xy 16.103633 -283.448915) (xy 16.08201 -283.427932)
			(xy 16.074898 -283.420566) (xy 16.056102 -283.412946) (xy 15.963646 -283.412946) (xy 15.94485 -283.420566)
			(xy 15.937738 -283.427932) (xy 15.916108 -283.448907) (xy 15.867482 -283.484478) (xy 15.813867 -283.511961)
			(xy 15.756597 -283.53067) (xy 15.697098 -283.54014) (xy 15.666974 -283.540708) (xy 15.638235 -283.540198)
			(xy 15.581407 -283.531572) (xy 15.526516 -283.514518) (xy 15.474804 -283.489424) (xy 15.427442 -283.456856)
			(xy 15.406116 -283.437584) (xy 15.399004 -283.43098) (xy 15.381478 -283.423868) (xy 15.29207 -283.423868)
			(xy 15.274544 -283.43098) (xy 15.267432 -283.437584) (xy 15.246105 -283.456854) (xy 15.198742 -283.489419)
			(xy 15.147031 -283.51451) (xy 15.09214 -283.53156) (xy 15.035313 -283.540182) (xy 14.977835 -283.540182)
			(xy 14.921008 -283.53156) (xy 14.866117 -283.51451) (xy 14.814406 -283.489419) (xy 14.767043 -283.456854)
			(xy 14.745716 -283.437584) (xy 14.738604 -283.43098) (xy 14.721078 -283.423868) (xy 14.63167 -283.423868)
			(xy 14.614144 -283.43098) (xy 14.607032 -283.437584) (xy 14.585719 -283.456871) (xy 14.538353 -283.489434)
			(xy 14.486637 -283.514523) (xy 14.431744 -283.53157) (xy 14.374914 -283.540189) (xy 14.346174 -283.540708)
			(xy 14.318924 -283.54022) (xy 14.264979 -283.532461) (xy 14.212687 -283.517104) (xy 14.163113 -283.494461)
			(xy 14.117266 -283.464994) (xy 14.076079 -283.429302) (xy 14.04039 -283.388113) (xy 14.010927 -283.342264)
			(xy 13.988287 -283.292688) (xy 13.972934 -283.240396) (xy 13.965178 -283.18645) (xy 12.461045 -283.18645)
			(xy 12.461045 -283.186453) (xy 12.453287 -283.240406) (xy 12.437931 -283.292705) (xy 12.415287 -283.342286)
			(xy 12.385818 -283.388139) (xy 12.350123 -283.429332) (xy 12.308928 -283.465026) (xy 12.263073 -283.494494)
			(xy 12.213491 -283.517135) (xy 12.161192 -283.53249) (xy 12.10724 -283.540246) (xy 12.079986 -283.540708)
			(xy 12.049862 -283.540158) (xy 11.990364 -283.530674) (xy 11.933095 -283.511959) (xy 11.879478 -283.484478)
			(xy 11.830845 -283.448914) (xy 11.809222 -283.427932) (xy 11.80211 -283.420566) (xy 11.783314 -283.412946)
			(xy 11.690858 -283.412946) (xy 11.672062 -283.420566) (xy 11.66495 -283.427932) (xy 11.643315 -283.448901)
			(xy 11.59469 -283.484473) (xy 11.541076 -283.511957) (xy 11.483808 -283.530667) (xy 11.42431 -283.540139)
			(xy 11.394186 -283.540708) (xy 11.365447 -283.540191) (xy 11.308619 -283.531566) (xy 11.253729 -283.514515)
			(xy 11.202017 -283.489422) (xy 11.154655 -283.456855) (xy 11.133328 -283.437584) (xy 11.126216 -283.43098)
			(xy 11.10869 -283.423868) (xy 11.019282 -283.423868) (xy 11.001756 -283.43098) (xy 10.994644 -283.437584)
			(xy 10.973317 -283.456854) (xy 10.925954 -283.489419) (xy 10.874243 -283.51451) (xy 10.819352 -283.53156)
			(xy 10.762525 -283.540182) (xy 10.705047 -283.540182) (xy 10.64822 -283.53156) (xy 10.593329 -283.51451)
			(xy 10.541618 -283.489419) (xy 10.494255 -283.456854) (xy 10.472928 -283.437584) (xy 10.465816 -283.43098)
			(xy 10.44829 -283.423868) (xy 10.358882 -283.423868) (xy 10.341356 -283.43098) (xy 10.334244 -283.437584)
			(xy 10.312926 -283.456865) (xy 10.265561 -283.489429) (xy 10.213847 -283.514519) (xy 10.158955 -283.531567)
			(xy 10.102126 -283.540188) (xy 10.073386 -283.540708) (xy 10.046135 -283.540221) (xy 9.992189 -283.532463)
			(xy 9.939896 -283.517107) (xy 9.890321 -283.494465) (xy 9.844472 -283.464998) (xy 9.803283 -283.429307)
			(xy 9.767593 -283.388117) (xy 9.738128 -283.342267) (xy 9.715488 -283.292691) (xy 9.700134 -283.240397)
			(xy 9.692378 -283.186451) (xy 1.660398 -283.186451) (xy 1.660398 -283.893514) (xy 31.338012 -283.893514)
			(xy 31.338555 -283.864132) (xy 31.347584 -283.806065) (xy 31.365415 -283.75007) (xy 31.391626 -283.697475)
			(xy 31.425597 -283.649524) (xy 31.466521 -283.607352) (xy 31.48965 -283.589222) (xy 31.499048 -283.581856)
			(xy 31.509462 -283.561282) (xy 31.510986 -283.457396) (xy 31.50108 -283.436314) (xy 31.491936 -283.428948)
			(xy 31.470088 -283.410742) (xy 31.431546 -283.368924) (xy 31.399638 -283.321849) (xy 31.375071 -283.270559)
			(xy 31.358388 -283.216191) (xy 31.34996 -283.159949) (xy 31.349442 -283.131514) (xy 31.349928 -283.104263)
			(xy 31.357684 -283.050315) (xy 31.373039 -282.99802) (xy 31.395681 -282.948443) (xy 31.425147 -282.902593)
			(xy 31.460838 -282.861402) (xy 31.502029 -282.825711) (xy 31.547879 -282.796245) (xy 31.597456 -282.773603)
			(xy 31.649751 -282.758248) (xy 31.703699 -282.750492) (xy 31.758201 -282.750492) (xy 31.812149 -282.758248)
			(xy 31.864444 -282.773603) (xy 31.914021 -282.796245) (xy 31.959871 -282.825711) (xy 32.001062 -282.861402)
			(xy 32.036753 -282.902593) (xy 32.066219 -282.948443) (xy 32.088861 -282.99802) (xy 32.104216 -283.050315)
			(xy 32.107747 -283.074872) (xy 36.069028 -283.074872) (xy 36.072988 -283.025818) (xy 36.084765 -282.978034)
			(xy 36.104056 -282.932758) (xy 36.130359 -282.891162) (xy 36.162994 -282.854325) (xy 36.201115 -282.8232)
			(xy 36.243736 -282.798593) (xy 36.289752 -282.781141) (xy 36.337971 -282.771297) (xy 36.387146 -282.769316)
			(xy 36.436001 -282.775248) (xy 36.483272 -282.78894) (xy 36.527734 -282.810038) (xy 36.568237 -282.837994)
			(xy 36.60373 -282.872086) (xy 36.633295 -282.91143) (xy 36.656166 -282.955007) (xy 36.67175 -283.001688)
			(xy 36.679645 -283.050265) (xy 36.68014 -283.074872) (xy 37.018988 -283.074872) (xy 37.022948 -283.025818)
			(xy 37.034725 -282.978034) (xy 37.054016 -282.932758) (xy 37.080319 -282.891162) (xy 37.112954 -282.854325)
			(xy 37.151075 -282.8232) (xy 37.193696 -282.798593) (xy 37.239712 -282.781141) (xy 37.287931 -282.771297)
			(xy 37.337106 -282.769316) (xy 37.385961 -282.775248) (xy 37.433232 -282.78894) (xy 37.477694 -282.810038)
			(xy 37.518197 -282.837994) (xy 37.55369 -282.872086) (xy 37.583255 -282.91143) (xy 37.606126 -282.955007)
			(xy 37.62171 -283.001688) (xy 37.629605 -283.050265) (xy 37.6301 -283.074872) (xy 37.969202 -283.074872)
			(xy 37.973162 -283.025818) (xy 37.984939 -282.978034) (xy 38.00423 -282.932758) (xy 38.030533 -282.891162)
			(xy 38.063168 -282.854325) (xy 38.101289 -282.8232) (xy 38.14391 -282.798593) (xy 38.189926 -282.781141)
			(xy 38.238145 -282.771297) (xy 38.28732 -282.769316) (xy 38.336175 -282.775248) (xy 38.383446 -282.78894)
			(xy 38.427908 -282.810038) (xy 38.468411 -282.837994) (xy 38.503904 -282.872086) (xy 38.533469 -282.91143)
			(xy 38.55634 -282.955007) (xy 38.571924 -283.001688) (xy 38.579819 -283.050265) (xy 38.580314 -283.074872)
			(xy 38.919162 -283.074872) (xy 38.923122 -283.025818) (xy 38.934899 -282.978034) (xy 38.95419 -282.932758)
			(xy 38.980493 -282.891162) (xy 39.013128 -282.854325) (xy 39.051249 -282.8232) (xy 39.09387 -282.798593)
			(xy 39.139886 -282.781141) (xy 39.188105 -282.771297) (xy 39.23728 -282.769316) (xy 39.286135 -282.775248)
			(xy 39.333406 -282.78894) (xy 39.377868 -282.810038) (xy 39.418371 -282.837994) (xy 39.453864 -282.872086)
			(xy 39.483429 -282.91143) (xy 39.5063 -282.955007) (xy 39.521884 -283.001688) (xy 39.529779 -283.050265)
			(xy 39.530274 -283.074872) (xy 39.529779 -283.099479) (xy 39.521884 -283.148056) (xy 39.5063 -283.194737)
			(xy 39.483429 -283.238314) (xy 39.453864 -283.277658) (xy 39.418371 -283.31175) (xy 39.377868 -283.339706)
			(xy 39.333406 -283.360804) (xy 39.286135 -283.374496) (xy 39.23728 -283.380428) (xy 39.188105 -283.378447)
			(xy 39.139886 -283.368603) (xy 39.09387 -283.351151) (xy 39.051249 -283.326544) (xy 39.013128 -283.295419)
			(xy 38.980493 -283.258582) (xy 38.95419 -283.216986) (xy 38.934899 -283.17171) (xy 38.923122 -283.123926)
			(xy 38.919162 -283.074872) (xy 38.580314 -283.074872) (xy 38.579819 -283.099479) (xy 38.571924 -283.148056)
			(xy 38.55634 -283.194737) (xy 38.533469 -283.238314) (xy 38.503904 -283.277658) (xy 38.468411 -283.31175)
			(xy 38.427908 -283.339706) (xy 38.383446 -283.360804) (xy 38.336175 -283.374496) (xy 38.28732 -283.380428)
			(xy 38.238145 -283.378447) (xy 38.189926 -283.368603) (xy 38.14391 -283.351151) (xy 38.101289 -283.326544)
			(xy 38.063168 -283.295419) (xy 38.030533 -283.258582) (xy 38.00423 -283.216986) (xy 37.984939 -283.17171)
			(xy 37.973162 -283.123926) (xy 37.969202 -283.074872) (xy 37.6301 -283.074872) (xy 37.629605 -283.099479)
			(xy 37.62171 -283.148056) (xy 37.606126 -283.194737) (xy 37.583255 -283.238314) (xy 37.55369 -283.277658)
			(xy 37.518197 -283.31175) (xy 37.477694 -283.339706) (xy 37.433232 -283.360804) (xy 37.385961 -283.374496)
			(xy 37.337106 -283.380428) (xy 37.287931 -283.378447) (xy 37.239712 -283.368603) (xy 37.193696 -283.351151)
			(xy 37.151075 -283.326544) (xy 37.112954 -283.295419) (xy 37.080319 -283.258582) (xy 37.054016 -283.216986)
			(xy 37.034725 -283.17171) (xy 37.022948 -283.123926) (xy 37.018988 -283.074872) (xy 36.68014 -283.074872)
			(xy 36.679645 -283.099479) (xy 36.67175 -283.148056) (xy 36.656166 -283.194737) (xy 36.633295 -283.238314)
			(xy 36.60373 -283.277658) (xy 36.568237 -283.31175) (xy 36.527734 -283.339706) (xy 36.483272 -283.360804)
			(xy 36.436001 -283.374496) (xy 36.387146 -283.380428) (xy 36.337971 -283.378447) (xy 36.289752 -283.368603)
			(xy 36.243736 -283.351151) (xy 36.201115 -283.326544) (xy 36.162994 -283.295419) (xy 36.130359 -283.258582)
			(xy 36.104056 -283.216986) (xy 36.084765 -283.17171) (xy 36.072988 -283.123926) (xy 36.069028 -283.074872)
			(xy 32.107747 -283.074872) (xy 32.111972 -283.104263) (xy 32.112458 -283.131514) (xy 32.111907 -283.160896)
			(xy 32.102876 -283.218961) (xy 32.085044 -283.274954) (xy 32.058835 -283.327549) (xy 32.024867 -283.3755)
			(xy 31.983946 -283.417674) (xy 31.96082 -283.435806) (xy 31.951422 -283.443172) (xy 31.941008 -283.463746)
			(xy 31.939484 -283.567632) (xy 31.94939 -283.588714) (xy 31.958534 -283.59608) (xy 31.980362 -283.614309)
			(xy 32.018902 -283.656124) (xy 32.05081 -283.703195) (xy 32.07538 -283.75448) (xy 32.092068 -283.808843)
			(xy 32.100505 -283.865081) (xy 32.101028 -283.893514) (xy 32.734502 -283.893514) (xy 32.738573 -283.837892)
			(xy 32.750699 -283.783455) (xy 32.770622 -283.731364) (xy 32.797918 -283.682729) (xy 32.832004 -283.638586)
			(xy 32.872153 -283.599877) (xy 32.917511 -283.567426) (xy 32.967111 -283.541925) (xy 33.019895 -283.523918)
			(xy 33.074738 -283.513788) (xy 33.130472 -283.511751) (xy 33.185909 -283.517851) (xy 33.239866 -283.531957)
			(xy 33.291195 -283.553769) (xy 33.338801 -283.582823) (xy 33.381669 -283.618498) (xy 33.418886 -283.660035)
			(xy 33.449659 -283.706548) (xy 33.473331 -283.757045) (xy 33.489399 -283.810452) (xy 33.497519 -283.865628)
			(xy 33.498028 -283.893514) (xy 33.620962 -283.893514) (xy 33.625033 -283.837892) (xy 33.637159 -283.783455)
			(xy 33.657082 -283.731364) (xy 33.684378 -283.682729) (xy 33.718464 -283.638586) (xy 33.758613 -283.599877)
			(xy 33.803971 -283.567426) (xy 33.853571 -283.541925) (xy 33.906355 -283.523918) (xy 33.961198 -283.513788)
			(xy 34.016932 -283.511751) (xy 34.072369 -283.517851) (xy 34.126326 -283.531957) (xy 34.177655 -283.553769)
			(xy 34.225261 -283.582823) (xy 34.268129 -283.618498) (xy 34.305346 -283.660035) (xy 34.336119 -283.706548)
			(xy 34.359791 -283.757045) (xy 34.375859 -283.810452) (xy 34.383979 -283.865628) (xy 34.384488 -283.893514)
			(xy 34.383979 -283.9214) (xy 34.375859 -283.976576) (xy 34.361341 -284.024832) (xy 36.069028 -284.024832)
			(xy 36.072988 -283.975778) (xy 36.084765 -283.927994) (xy 36.104056 -283.882718) (xy 36.130359 -283.841122)
			(xy 36.162994 -283.804285) (xy 36.201115 -283.77316) (xy 36.243736 -283.748553) (xy 36.289752 -283.731101)
			(xy 36.337971 -283.721257) (xy 36.387146 -283.719276) (xy 36.436001 -283.725208) (xy 36.483272 -283.7389)
			(xy 36.527734 -283.759998) (xy 36.568237 -283.787954) (xy 36.60373 -283.822046) (xy 36.633295 -283.86139)
			(xy 36.656166 -283.904967) (xy 36.67175 -283.951648) (xy 36.679645 -284.000225) (xy 36.68014 -284.024832)
			(xy 37.018988 -284.024832) (xy 37.022948 -283.975778) (xy 37.034725 -283.927994) (xy 37.054016 -283.882718)
			(xy 37.080319 -283.841122) (xy 37.112954 -283.804285) (xy 37.151075 -283.77316) (xy 37.193696 -283.748553)
			(xy 37.239712 -283.731101) (xy 37.287931 -283.721257) (xy 37.337106 -283.719276) (xy 37.385961 -283.725208)
			(xy 37.433232 -283.7389) (xy 37.477694 -283.759998) (xy 37.518197 -283.787954) (xy 37.55369 -283.822046)
			(xy 37.583255 -283.86139) (xy 37.606126 -283.904967) (xy 37.62171 -283.951648) (xy 37.629605 -284.000225)
			(xy 37.6301 -284.024832) (xy 37.969202 -284.024832) (xy 37.973162 -283.975778) (xy 37.984939 -283.927994)
			(xy 38.00423 -283.882718) (xy 38.030533 -283.841122) (xy 38.063168 -283.804285) (xy 38.101289 -283.77316)
			(xy 38.14391 -283.748553) (xy 38.189926 -283.731101) (xy 38.238145 -283.721257) (xy 38.28732 -283.719276)
			(xy 38.336175 -283.725208) (xy 38.383446 -283.7389) (xy 38.427908 -283.759998) (xy 38.468411 -283.787954)
			(xy 38.503904 -283.822046) (xy 38.533469 -283.86139) (xy 38.55634 -283.904967) (xy 38.571924 -283.951648)
			(xy 38.579819 -284.000225) (xy 38.580314 -284.024832) (xy 38.919162 -284.024832) (xy 38.923122 -283.975778)
			(xy 38.934899 -283.927994) (xy 38.95419 -283.882718) (xy 38.980493 -283.841122) (xy 39.013128 -283.804285)
			(xy 39.051249 -283.77316) (xy 39.09387 -283.748553) (xy 39.139886 -283.731101) (xy 39.188105 -283.721257)
			(xy 39.23728 -283.719276) (xy 39.286135 -283.725208) (xy 39.333406 -283.7389) (xy 39.377868 -283.759998)
			(xy 39.418371 -283.787954) (xy 39.453864 -283.822046) (xy 39.483429 -283.86139) (xy 39.5063 -283.904967)
			(xy 39.521884 -283.951648) (xy 39.529779 -284.000225) (xy 39.530274 -284.024832) (xy 39.529779 -284.049439)
			(xy 39.521884 -284.098016) (xy 39.5063 -284.144697) (xy 39.483429 -284.188274) (xy 39.453864 -284.227618)
			(xy 39.418371 -284.26171) (xy 39.377868 -284.289666) (xy 39.333406 -284.310764) (xy 39.286135 -284.324456)
			(xy 39.23728 -284.330388) (xy 39.188105 -284.328407) (xy 39.139886 -284.318563) (xy 39.09387 -284.301111)
			(xy 39.051249 -284.276504) (xy 39.013128 -284.245379) (xy 38.980493 -284.208542) (xy 38.95419 -284.166946)
			(xy 38.934899 -284.12167) (xy 38.923122 -284.073886) (xy 38.919162 -284.024832) (xy 38.580314 -284.024832)
			(xy 38.579819 -284.049439) (xy 38.571924 -284.098016) (xy 38.55634 -284.144697) (xy 38.533469 -284.188274)
			(xy 38.503904 -284.227618) (xy 38.468411 -284.26171) (xy 38.427908 -284.289666) (xy 38.383446 -284.310764)
			(xy 38.336175 -284.324456) (xy 38.28732 -284.330388) (xy 38.238145 -284.328407) (xy 38.189926 -284.318563)
			(xy 38.14391 -284.301111) (xy 38.101289 -284.276504) (xy 38.063168 -284.245379) (xy 38.030533 -284.208542)
			(xy 38.00423 -284.166946) (xy 37.984939 -284.12167) (xy 37.973162 -284.073886) (xy 37.969202 -284.024832)
			(xy 37.6301 -284.024832) (xy 37.629605 -284.049439) (xy 37.62171 -284.098016) (xy 37.606126 -284.144697)
			(xy 37.583255 -284.188274) (xy 37.55369 -284.227618) (xy 37.518197 -284.26171) (xy 37.477694 -284.289666)
			(xy 37.433232 -284.310764) (xy 37.385961 -284.324456) (xy 37.337106 -284.330388) (xy 37.287931 -284.328407)
			(xy 37.239712 -284.318563) (xy 37.193696 -284.301111) (xy 37.151075 -284.276504) (xy 37.112954 -284.245379)
			(xy 37.080319 -284.208542) (xy 37.054016 -284.166946) (xy 37.034725 -284.12167) (xy 37.022948 -284.073886)
			(xy 37.018988 -284.024832) (xy 36.68014 -284.024832) (xy 36.679645 -284.049439) (xy 36.67175 -284.098016)
			(xy 36.656166 -284.144697) (xy 36.633295 -284.188274) (xy 36.60373 -284.227618) (xy 36.568237 -284.26171)
			(xy 36.527734 -284.289666) (xy 36.483272 -284.310764) (xy 36.436001 -284.324456) (xy 36.387146 -284.330388)
			(xy 36.337971 -284.328407) (xy 36.289752 -284.318563) (xy 36.243736 -284.301111) (xy 36.201115 -284.276504)
			(xy 36.162994 -284.245379) (xy 36.130359 -284.208542) (xy 36.104056 -284.166946) (xy 36.084765 -284.12167)
			(xy 36.072988 -284.073886) (xy 36.069028 -284.024832) (xy 34.361341 -284.024832) (xy 34.359791 -284.029983)
			(xy 34.336119 -284.08048) (xy 34.305346 -284.126993) (xy 34.268129 -284.16853) (xy 34.225261 -284.204205)
			(xy 34.177655 -284.233259) (xy 34.126326 -284.255071) (xy 34.072369 -284.269177) (xy 34.016932 -284.275277)
			(xy 33.961198 -284.27324) (xy 33.906355 -284.26311) (xy 33.853571 -284.245103) (xy 33.803971 -284.219602)
			(xy 33.758613 -284.187151) (xy 33.718464 -284.148442) (xy 33.684378 -284.104299) (xy 33.657082 -284.055664)
			(xy 33.637159 -284.003573) (xy 33.625033 -283.949136) (xy 33.620962 -283.893514) (xy 33.498028 -283.893514)
			(xy 33.497519 -283.9214) (xy 33.489399 -283.976576) (xy 33.473331 -284.029983) (xy 33.449659 -284.08048)
			(xy 33.418886 -284.126993) (xy 33.381669 -284.16853) (xy 33.338801 -284.204205) (xy 33.291195 -284.233259)
			(xy 33.239866 -284.255071) (xy 33.185909 -284.269177) (xy 33.130472 -284.275277) (xy 33.074738 -284.27324)
			(xy 33.019895 -284.26311) (xy 32.967111 -284.245103) (xy 32.917511 -284.219602) (xy 32.872153 -284.187151)
			(xy 32.832004 -284.148442) (xy 32.797918 -284.104299) (xy 32.770622 -284.055664) (xy 32.750699 -284.003573)
			(xy 32.738573 -283.949136) (xy 32.734502 -283.893514) (xy 32.101028 -283.893514) (xy 32.100542 -283.920765)
			(xy 32.092786 -283.974713) (xy 32.077431 -284.027008) (xy 32.054789 -284.076585) (xy 32.025323 -284.122435)
			(xy 31.989632 -284.163626) (xy 31.948441 -284.199317) (xy 31.902591 -284.228783) (xy 31.853014 -284.251425)
			(xy 31.800719 -284.26678) (xy 31.746771 -284.274536) (xy 31.692269 -284.274536) (xy 31.638321 -284.26678)
			(xy 31.586026 -284.251425) (xy 31.536449 -284.228783) (xy 31.490599 -284.199317) (xy 31.449408 -284.163626)
			(xy 31.413717 -284.122435) (xy 31.384251 -284.076585) (xy 31.361609 -284.027008) (xy 31.346254 -283.974713)
			(xy 31.338498 -283.920765) (xy 31.338012 -283.893514) (xy 1.660398 -283.893514) (xy 1.660398 -284.845831)
			(xy 1.89279 -284.845831) (xy 1.89279 -284.791329) (xy 1.900546 -284.737382) (xy 1.915901 -284.685087)
			(xy 1.938542 -284.635511) (xy 1.968008 -284.58966) (xy 2.003699 -284.548471) (xy 2.044889 -284.512779)
			(xy 2.090739 -284.483313) (xy 2.140316 -284.460672) (xy 2.19261 -284.445317) (xy 2.246557 -284.43756)
			(xy 2.273808 -284.437074) (xy 2.302547 -284.4376) (xy 2.359374 -284.446223) (xy 2.414264 -284.463273)
			(xy 2.465976 -284.488364) (xy 2.513339 -284.520928) (xy 2.534666 -284.540198) (xy 2.541778 -284.546802)
			(xy 2.559304 -284.553914) (xy 2.648712 -284.553914) (xy 2.666238 -284.546802) (xy 2.67335 -284.540198)
			(xy 2.694683 -284.520934) (xy 2.742042 -284.488364) (xy 2.793752 -284.46327) (xy 2.848642 -284.446218)
			(xy 2.905469 -284.437595) (xy 2.934208 -284.437074) (xy 2.964332 -284.437633) (xy 3.023829 -284.447116)
			(xy 3.081098 -284.465829) (xy 3.134714 -284.493308) (xy 3.183348 -284.528869) (xy 3.204972 -284.54985)
			(xy 3.212084 -284.557216) (xy 3.23088 -284.564836) (xy 3.323336 -284.564836) (xy 3.342132 -284.557216)
			(xy 3.349244 -284.54985) (xy 3.370879 -284.52888) (xy 3.419504 -284.493309) (xy 3.473118 -284.465826)
			(xy 3.530386 -284.447115) (xy 3.589884 -284.437643) (xy 3.620008 -284.437074) (xy 3.647379 -284.437517)
			(xy 3.70156 -284.445338) (xy 3.754064 -284.460831) (xy 3.803811 -284.483679) (xy 3.849776 -284.513409)
			(xy 3.870706 -284.531054) (xy 3.877818 -284.53715) (xy 3.894836 -284.5435) (xy 3.98018 -284.5435)
			(xy 3.997198 -284.53715) (xy 4.00431 -284.531054) (xy 4.025234 -284.513405) (xy 4.071208 -284.483693)
			(xy 4.120958 -284.460858) (xy 4.173461 -284.445369) (xy 4.227638 -284.437545) (xy 4.255008 -284.437074)
			(xy 4.282261 -284.437533) (xy 4.336213 -284.44529) (xy 4.388511 -284.460646) (xy 4.438091 -284.483288)
			(xy 4.483945 -284.512757) (xy 4.525138 -284.54845) (xy 4.560832 -284.589643) (xy 4.590301 -284.635497)
			(xy 4.612943 -284.685077) (xy 4.6283 -284.737376) (xy 4.636057 -284.791327) (xy 4.636057 -284.845831)
			(xy 5.88618 -284.845831) (xy 5.88618 -284.791329) (xy 5.893936 -284.737382) (xy 5.909291 -284.685088)
			(xy 5.931932 -284.635511) (xy 5.961397 -284.589661) (xy 5.997088 -284.548471) (xy 6.038278 -284.51278)
			(xy 6.084128 -284.483314) (xy 6.133704 -284.460672) (xy 6.185998 -284.445317) (xy 6.239945 -284.43756)
			(xy 6.267196 -284.437074) (xy 6.295934 -284.437607) (xy 6.352761 -284.446228) (xy 6.407651 -284.463277)
			(xy 6.459363 -284.488366) (xy 6.506727 -284.520929) (xy 6.528054 -284.540198) (xy 6.535166 -284.546802)
			(xy 6.552692 -284.553914) (xy 6.6421 -284.553914) (xy 6.659626 -284.546802) (xy 6.666738 -284.540198)
			(xy 6.688065 -284.520928) (xy 6.735428 -284.488363) (xy 6.787139 -284.463272) (xy 6.84203 -284.446222)
			(xy 6.898857 -284.4376) (xy 6.956335 -284.4376) (xy 7.013162 -284.446222) (xy 7.068053 -284.463272)
			(xy 7.119764 -284.488363) (xy 7.167127 -284.520928) (xy 7.188454 -284.540198) (xy 7.195566 -284.546802)
			(xy 7.213092 -284.553914) (xy 7.3025 -284.553914) (xy 7.320026 -284.546802) (xy 7.327138 -284.540198)
			(xy 7.348476 -284.52094) (xy 7.395834 -284.488369) (xy 7.447543 -284.463274) (xy 7.502431 -284.44622)
			(xy 7.559258 -284.437596) (xy 7.587996 -284.437074) (xy 7.61812 -284.43764) (xy 7.677617 -284.447121)
			(xy 7.734885 -284.465833) (xy 7.788502 -284.49331) (xy 7.837136 -284.52887) (xy 7.85876 -284.54985)
			(xy 7.865872 -284.557216) (xy 7.884668 -284.564836) (xy 7.977124 -284.564836) (xy 7.99592 -284.557216)
			(xy 8.003032 -284.54985) (xy 8.024672 -284.528886) (xy 8.073296 -284.493314) (xy 8.126908 -284.46583)
			(xy 8.184175 -284.447118) (xy 8.243673 -284.437644) (xy 8.273796 -284.437074) (xy 8.301049 -284.437533)
			(xy 8.355001 -284.44529) (xy 8.407299 -284.460645) (xy 8.45688 -284.483288) (xy 8.502734 -284.512756)
			(xy 8.543928 -284.54845) (xy 8.579622 -284.589643) (xy 8.60909 -284.635496) (xy 8.631733 -284.685077)
			(xy 8.64709 -284.737375) (xy 8.654847 -284.791327) (xy 8.654847 -284.845833) (xy 8.64709 -284.899785)
			(xy 8.631733 -284.952083) (xy 8.60909 -285.001664) (xy 8.591101 -285.029656) (xy 25.811478 -285.029656)
			(xy 25.815549 -284.974034) (xy 25.827675 -284.919597) (xy 25.847598 -284.867506) (xy 25.874894 -284.818871)
			(xy 25.90898 -284.774728) (xy 25.949129 -284.736019) (xy 25.994487 -284.703568) (xy 26.044087 -284.678067)
			(xy 26.096871 -284.66006) (xy 26.151714 -284.64993) (xy 26.207448 -284.647893) (xy 26.262885 -284.653993)
			(xy 26.316842 -284.668099) (xy 26.368171 -284.689911) (xy 26.415777 -284.718965) (xy 26.458645 -284.75464)
			(xy 26.495862 -284.796177) (xy 26.526635 -284.84269) (xy 26.550307 -284.893187) (xy 26.566375 -284.946594)
			(xy 26.574495 -285.00177) (xy 26.575004 -285.029656) (xy 27.296616 -285.029656) (xy 27.300687 -284.974034)
			(xy 27.312813 -284.919597) (xy 27.332736 -284.867506) (xy 27.360032 -284.818871) (xy 27.394118 -284.774728)
			(xy 27.434267 -284.736019) (xy 27.479625 -284.703568) (xy 27.529225 -284.678067) (xy 27.582009 -284.66006)
			(xy 27.636852 -284.64993) (xy 27.692586 -284.647893) (xy 27.748023 -284.653993) (xy 27.80198 -284.668099)
			(xy 27.853309 -284.689911) (xy 27.900915 -284.718965) (xy 27.943783 -284.75464) (xy 27.981 -284.796177)
			(xy 28.011773 -284.84269) (xy 28.035445 -284.893187) (xy 28.051513 -284.946594) (xy 28.055663 -284.974792)
			(xy 36.069028 -284.974792) (xy 36.072988 -284.925738) (xy 36.084765 -284.877954) (xy 36.104056 -284.832678)
			(xy 36.130359 -284.791082) (xy 36.162994 -284.754245) (xy 36.201115 -284.72312) (xy 36.243736 -284.698513)
			(xy 36.289752 -284.681061) (xy 36.337971 -284.671217) (xy 36.387146 -284.669236) (xy 36.436001 -284.675168)
			(xy 36.483272 -284.68886) (xy 36.527734 -284.709958) (xy 36.568237 -284.737914) (xy 36.60373 -284.772006)
			(xy 36.633295 -284.81135) (xy 36.656166 -284.854927) (xy 36.67175 -284.901608) (xy 36.679645 -284.950185)
			(xy 36.68014 -284.974792) (xy 37.018988 -284.974792) (xy 37.022948 -284.925738) (xy 37.034725 -284.877954)
			(xy 37.054016 -284.832678) (xy 37.080319 -284.791082) (xy 37.112954 -284.754245) (xy 37.151075 -284.72312)
			(xy 37.193696 -284.698513) (xy 37.239712 -284.681061) (xy 37.287931 -284.671217) (xy 37.337106 -284.669236)
			(xy 37.385961 -284.675168) (xy 37.433232 -284.68886) (xy 37.477694 -284.709958) (xy 37.518197 -284.737914)
			(xy 37.55369 -284.772006) (xy 37.583255 -284.81135) (xy 37.606126 -284.854927) (xy 37.62171 -284.901608)
			(xy 37.629605 -284.950185) (xy 37.6301 -284.974792) (xy 37.969202 -284.974792) (xy 37.973162 -284.925738)
			(xy 37.984939 -284.877954) (xy 38.00423 -284.832678) (xy 38.030533 -284.791082) (xy 38.063168 -284.754245)
			(xy 38.101289 -284.72312) (xy 38.14391 -284.698513) (xy 38.189926 -284.681061) (xy 38.238145 -284.671217)
			(xy 38.28732 -284.669236) (xy 38.336175 -284.675168) (xy 38.383446 -284.68886) (xy 38.427908 -284.709958)
			(xy 38.468411 -284.737914) (xy 38.503904 -284.772006) (xy 38.533469 -284.81135) (xy 38.55634 -284.854927)
			(xy 38.571924 -284.901608) (xy 38.579819 -284.950185) (xy 38.580314 -284.974792) (xy 38.919162 -284.974792)
			(xy 38.923122 -284.925738) (xy 38.934899 -284.877954) (xy 38.95419 -284.832678) (xy 38.980493 -284.791082)
			(xy 39.013128 -284.754245) (xy 39.051249 -284.72312) (xy 39.09387 -284.698513) (xy 39.139886 -284.681061)
			(xy 39.188105 -284.671217) (xy 39.23728 -284.669236) (xy 39.286135 -284.675168) (xy 39.333406 -284.68886)
			(xy 39.377868 -284.709958) (xy 39.418371 -284.737914) (xy 39.453864 -284.772006) (xy 39.483429 -284.81135)
			(xy 39.5063 -284.854927) (xy 39.521884 -284.901608) (xy 39.529779 -284.950185) (xy 39.530274 -284.974792)
			(xy 39.529779 -284.999399) (xy 39.521884 -285.047976) (xy 39.5063 -285.094657) (xy 39.483429 -285.138234)
			(xy 39.453864 -285.177578) (xy 39.418371 -285.21167) (xy 39.377868 -285.239626) (xy 39.333406 -285.260724)
			(xy 39.286135 -285.274416) (xy 39.23728 -285.280348) (xy 39.188105 -285.278367) (xy 39.139886 -285.268523)
			(xy 39.09387 -285.251071) (xy 39.051249 -285.226464) (xy 39.013128 -285.195339) (xy 38.980493 -285.158502)
			(xy 38.95419 -285.116906) (xy 38.934899 -285.07163) (xy 38.923122 -285.023846) (xy 38.919162 -284.974792)
			(xy 38.580314 -284.974792) (xy 38.579819 -284.999399) (xy 38.571924 -285.047976) (xy 38.55634 -285.094657)
			(xy 38.533469 -285.138234) (xy 38.503904 -285.177578) (xy 38.468411 -285.21167) (xy 38.427908 -285.239626)
			(xy 38.383446 -285.260724) (xy 38.336175 -285.274416) (xy 38.28732 -285.280348) (xy 38.238145 -285.278367)
			(xy 38.189926 -285.268523) (xy 38.14391 -285.251071) (xy 38.101289 -285.226464) (xy 38.063168 -285.195339)
			(xy 38.030533 -285.158502) (xy 38.00423 -285.116906) (xy 37.984939 -285.07163) (xy 37.973162 -285.023846)
			(xy 37.969202 -284.974792) (xy 37.6301 -284.974792) (xy 37.629605 -284.999399) (xy 37.62171 -285.047976)
			(xy 37.606126 -285.094657) (xy 37.583255 -285.138234) (xy 37.55369 -285.177578) (xy 37.518197 -285.21167)
			(xy 37.477694 -285.239626) (xy 37.433232 -285.260724) (xy 37.385961 -285.274416) (xy 37.337106 -285.280348)
			(xy 37.287931 -285.278367) (xy 37.239712 -285.268523) (xy 37.193696 -285.251071) (xy 37.151075 -285.226464)
			(xy 37.112954 -285.195339) (xy 37.080319 -285.158502) (xy 37.054016 -285.116906) (xy 37.034725 -285.07163)
			(xy 37.022948 -285.023846) (xy 37.018988 -284.974792) (xy 36.68014 -284.974792) (xy 36.679645 -284.999399)
			(xy 36.67175 -285.047976) (xy 36.656166 -285.094657) (xy 36.633295 -285.138234) (xy 36.60373 -285.177578)
			(xy 36.568237 -285.21167) (xy 36.527734 -285.239626) (xy 36.483272 -285.260724) (xy 36.436001 -285.274416)
			(xy 36.387146 -285.280348) (xy 36.337971 -285.278367) (xy 36.289752 -285.268523) (xy 36.243736 -285.251071)
			(xy 36.201115 -285.226464) (xy 36.162994 -285.195339) (xy 36.130359 -285.158502) (xy 36.104056 -285.116906)
			(xy 36.084765 -285.07163) (xy 36.072988 -285.023846) (xy 36.069028 -284.974792) (xy 28.055663 -284.974792)
			(xy 28.059633 -285.00177) (xy 28.060142 -285.029656) (xy 28.059633 -285.057542) (xy 28.051513 -285.112718)
			(xy 28.035445 -285.166125) (xy 28.011773 -285.216622) (xy 27.981 -285.263135) (xy 27.943783 -285.304672)
			(xy 27.900915 -285.340347) (xy 27.853309 -285.369401) (xy 27.80198 -285.391213) (xy 27.748023 -285.405319)
			(xy 27.692586 -285.411419) (xy 27.636852 -285.409382) (xy 27.582009 -285.399252) (xy 27.529225 -285.381245)
			(xy 27.479625 -285.355744) (xy 27.434267 -285.323293) (xy 27.394118 -285.284584) (xy 27.360032 -285.240441)
			(xy 27.332736 -285.191806) (xy 27.312813 -285.139715) (xy 27.300687 -285.085278) (xy 27.296616 -285.029656)
			(xy 26.575004 -285.029656) (xy 26.574495 -285.057542) (xy 26.566375 -285.112718) (xy 26.550307 -285.166125)
			(xy 26.526635 -285.216622) (xy 26.495862 -285.263135) (xy 26.458645 -285.304672) (xy 26.415777 -285.340347)
			(xy 26.368171 -285.369401) (xy 26.316842 -285.391213) (xy 26.262885 -285.405319) (xy 26.207448 -285.411419)
			(xy 26.151714 -285.409382) (xy 26.096871 -285.399252) (xy 26.044087 -285.381245) (xy 25.994487 -285.355744)
			(xy 25.949129 -285.323293) (xy 25.90898 -285.284584) (xy 25.874894 -285.240441) (xy 25.847598 -285.191806)
			(xy 25.827675 -285.139715) (xy 25.815549 -285.085278) (xy 25.811478 -285.029656) (xy 8.591101 -285.029656)
			(xy 8.579622 -285.047517) (xy 8.543928 -285.08871) (xy 8.502734 -285.124404) (xy 8.45688 -285.153872)
			(xy 8.407299 -285.176515) (xy 8.355001 -285.19187) (xy 8.301049 -285.199627) (xy 8.273796 -285.20009)
			(xy 8.243672 -285.199539) (xy 8.184174 -285.190056) (xy 8.126905 -285.171341) (xy 8.073288 -285.14386)
			(xy 8.024656 -285.108296) (xy 8.003032 -285.087314) (xy 7.99592 -285.079948) (xy 7.977124 -285.072328)
			(xy 7.884668 -285.072328) (xy 7.865872 -285.079948) (xy 7.85876 -285.087314) (xy 7.837134 -285.108293)
			(xy 7.788505 -285.143861) (xy 7.734889 -285.171341) (xy 7.677619 -285.190049) (xy 7.61812 -285.199521)
			(xy 7.587996 -285.20009) (xy 7.559257 -285.199571) (xy 7.502429 -285.190948) (xy 7.447538 -285.173897)
			(xy 7.395827 -285.148804) (xy 7.348464 -285.116237) (xy 7.327138 -285.096966) (xy 7.320026 -285.090362)
			(xy 7.3025 -285.08325) (xy 7.213092 -285.08325) (xy 7.195566 -285.090362) (xy 7.188454 -285.096966)
			(xy 7.167127 -285.116236) (xy 7.119764 -285.148801) (xy 7.068053 -285.173892) (xy 7.013162 -285.190942)
			(xy 6.956335 -285.199564) (xy 6.898857 -285.199564) (xy 6.84203 -285.190942) (xy 6.787139 -285.173892)
			(xy 6.735428 -285.148801) (xy 6.688065 -285.116236) (xy 6.666738 -285.096966) (xy 6.659626 -285.090362)
			(xy 6.6421 -285.08325) (xy 6.552692 -285.08325) (xy 6.535166 -285.090362) (xy 6.528054 -285.096966)
			(xy 6.506729 -285.116239) (xy 6.459366 -285.148805) (xy 6.407654 -285.173897) (xy 6.352763 -285.190947)
			(xy 6.295935 -285.199569) (xy 6.267196 -285.20009) (xy 6.239945 -285.1996) (xy 6.185998 -285.191843)
			(xy 6.133704 -285.176488) (xy 6.084128 -285.153846) (xy 6.038278 -285.12438) (xy 5.997088 -285.088689)
			(xy 5.961397 -285.047499) (xy 5.931932 -285.001649) (xy 5.909291 -284.952072) (xy 5.893936 -284.899778)
			(xy 5.88618 -284.845831) (xy 4.636057 -284.845831) (xy 4.636057 -284.845833) (xy 4.6283 -284.899784)
			(xy 4.612943 -284.952083) (xy 4.590301 -285.001663) (xy 4.560832 -285.047517) (xy 4.525138 -285.08871)
			(xy 4.483945 -285.124403) (xy 4.438091 -285.153872) (xy 4.388511 -285.176514) (xy 4.336213 -285.19187)
			(xy 4.282261 -285.199627) (xy 4.255008 -285.20009) (xy 4.227638 -285.199622) (xy 4.173459 -285.191805)
			(xy 4.120956 -285.176316) (xy 4.071209 -285.153475) (xy 4.025242 -285.123751) (xy 4.00431 -285.10611)
			(xy 3.997198 -285.100014) (xy 3.98018 -285.093664) (xy 3.894836 -285.093664) (xy 3.877818 -285.100014)
			(xy 3.870706 -285.10611) (xy 3.849784 -285.123761) (xy 3.803808 -285.153471) (xy 3.754058 -285.176304)
			(xy 3.701555 -285.191793) (xy 3.647378 -285.199618) (xy 3.620008 -285.20009) (xy 3.589884 -285.199531)
			(xy 3.530386 -285.19005) (xy 3.473117 -285.171337) (xy 3.419501 -285.143858) (xy 3.370868 -285.108295)
			(xy 3.349244 -285.087314) (xy 3.342132 -285.079948) (xy 3.323336 -285.072328) (xy 3.23088 -285.072328)
			(xy 3.212084 -285.079948) (xy 3.204972 -285.087314) (xy 3.183341 -285.108287) (xy 3.134713 -285.143856)
			(xy 3.081099 -285.171337) (xy 3.02383 -285.190047) (xy 2.964332 -285.19952) (xy 2.934208 -285.20009)
			(xy 2.905469 -285.199564) (xy 2.848642 -285.190942) (xy 2.793751 -285.173893) (xy 2.742039 -285.148802)
			(xy 2.694677 -285.116237) (xy 2.67335 -285.096966) (xy 2.666238 -285.090362) (xy 2.648712 -285.08325)
			(xy 2.559304 -285.08325) (xy 2.541778 -285.090362) (xy 2.534666 -285.096966) (xy 2.513336 -285.116234)
			(xy 2.465975 -285.1488) (xy 2.414264 -285.173893) (xy 2.359374 -285.190945) (xy 2.302547 -285.199568)
			(xy 2.273808 -285.20009) (xy 2.246557 -285.1996) (xy 2.19261 -285.191843) (xy 2.140316 -285.176488)
			(xy 2.090739 -285.153847) (xy 2.044889 -285.124381) (xy 2.003699 -285.088689) (xy 1.968008 -285.0475)
			(xy 1.938542 -285.001649) (xy 1.915901 -284.952073) (xy 1.900546 -284.899778) (xy 1.89279 -284.845831)
			(xy 1.660398 -284.845831) (xy 1.660398 -285.462218) (xy 11.958572 -285.462218) (xy 11.962643 -285.406596)
			(xy 11.974769 -285.352159) (xy 11.994692 -285.300068) (xy 12.021988 -285.251433) (xy 12.056074 -285.20729)
			(xy 12.096223 -285.168581) (xy 12.141581 -285.13613) (xy 12.191181 -285.110629) (xy 12.243965 -285.092622)
			(xy 12.298808 -285.082492) (xy 12.354542 -285.080455) (xy 12.409979 -285.086555) (xy 12.463936 -285.100661)
			(xy 12.515265 -285.122473) (xy 12.562871 -285.151527) (xy 12.605739 -285.187202) (xy 12.642956 -285.228739)
			(xy 12.673729 -285.275252) (xy 12.697401 -285.325749) (xy 12.713469 -285.379156) (xy 12.721589 -285.434332)
			(xy 12.722098 -285.462218) (xy 14.151354 -285.462218) (xy 14.155425 -285.406596) (xy 14.167551 -285.352159)
			(xy 14.187474 -285.300068) (xy 14.21477 -285.251433) (xy 14.248856 -285.20729) (xy 14.289005 -285.168581)
			(xy 14.334363 -285.13613) (xy 14.383963 -285.110629) (xy 14.436747 -285.092622) (xy 14.49159 -285.082492)
			(xy 14.547324 -285.080455) (xy 14.602761 -285.086555) (xy 14.656718 -285.100661) (xy 14.708047 -285.122473)
			(xy 14.755653 -285.151527) (xy 14.798521 -285.187202) (xy 14.835738 -285.228739) (xy 14.866511 -285.275252)
			(xy 14.890183 -285.325749) (xy 14.906251 -285.379156) (xy 14.914371 -285.434332) (xy 14.91488 -285.462218)
			(xy 14.914371 -285.490104) (xy 14.906251 -285.54528) (xy 14.890183 -285.598687) (xy 14.866511 -285.649184)
			(xy 14.835738 -285.695697) (xy 14.798521 -285.737234) (xy 14.755653 -285.772909) (xy 14.708047 -285.801963)
			(xy 14.656718 -285.823775) (xy 14.602761 -285.837881) (xy 14.547324 -285.843981) (xy 14.49159 -285.841944)
			(xy 14.436747 -285.831814) (xy 14.383963 -285.813807) (xy 14.334363 -285.788306) (xy 14.289005 -285.755855)
			(xy 14.248856 -285.717146) (xy 14.21477 -285.673003) (xy 14.187474 -285.624368) (xy 14.167551 -285.572277)
			(xy 14.155425 -285.51784) (xy 14.151354 -285.462218) (xy 12.722098 -285.462218) (xy 12.721589 -285.490104)
			(xy 12.713469 -285.54528) (xy 12.697401 -285.598687) (xy 12.673729 -285.649184) (xy 12.642956 -285.695697)
			(xy 12.605739 -285.737234) (xy 12.562871 -285.772909) (xy 12.515265 -285.801963) (xy 12.463936 -285.823775)
			(xy 12.409979 -285.837881) (xy 12.354542 -285.843981) (xy 12.298808 -285.841944) (xy 12.243965 -285.831814)
			(xy 12.191181 -285.813807) (xy 12.141581 -285.788306) (xy 12.096223 -285.755855) (xy 12.056074 -285.717146)
			(xy 12.021988 -285.673003) (xy 11.994692 -285.624368) (xy 11.974769 -285.572277) (xy 11.962643 -285.51784)
			(xy 11.958572 -285.462218) (xy 1.660398 -285.462218) (xy 1.660398 -285.924752) (xy 36.069028 -285.924752)
			(xy 36.072988 -285.875698) (xy 36.084765 -285.827914) (xy 36.104056 -285.782638) (xy 36.130359 -285.741042)
			(xy 36.162994 -285.704205) (xy 36.201115 -285.67308) (xy 36.243736 -285.648473) (xy 36.289752 -285.631021)
			(xy 36.337971 -285.621177) (xy 36.387146 -285.619196) (xy 36.436001 -285.625128) (xy 36.483272 -285.63882)
			(xy 36.527734 -285.659918) (xy 36.568237 -285.687874) (xy 36.60373 -285.721966) (xy 36.633295 -285.76131)
			(xy 36.656166 -285.804887) (xy 36.67175 -285.851568) (xy 36.679645 -285.900145) (xy 36.68014 -285.924752)
			(xy 37.018988 -285.924752) (xy 37.022948 -285.875698) (xy 37.034725 -285.827914) (xy 37.054016 -285.782638)
			(xy 37.080319 -285.741042) (xy 37.112954 -285.704205) (xy 37.151075 -285.67308) (xy 37.193696 -285.648473)
			(xy 37.239712 -285.631021) (xy 37.287931 -285.621177) (xy 37.337106 -285.619196) (xy 37.385961 -285.625128)
			(xy 37.433232 -285.63882) (xy 37.477694 -285.659918) (xy 37.518197 -285.687874) (xy 37.55369 -285.721966)
			(xy 37.583255 -285.76131) (xy 37.606126 -285.804887) (xy 37.62171 -285.851568) (xy 37.629605 -285.900145)
			(xy 37.6301 -285.924752) (xy 37.969202 -285.924752) (xy 37.973162 -285.875698) (xy 37.984939 -285.827914)
			(xy 38.00423 -285.782638) (xy 38.030533 -285.741042) (xy 38.063168 -285.704205) (xy 38.101289 -285.67308)
			(xy 38.14391 -285.648473) (xy 38.189926 -285.631021) (xy 38.238145 -285.621177) (xy 38.28732 -285.619196)
			(xy 38.336175 -285.625128) (xy 38.383446 -285.63882) (xy 38.427908 -285.659918) (xy 38.468411 -285.687874)
			(xy 38.503904 -285.721966) (xy 38.533469 -285.76131) (xy 38.55634 -285.804887) (xy 38.571924 -285.851568)
			(xy 38.579819 -285.900145) (xy 38.580314 -285.924752) (xy 38.919162 -285.924752) (xy 38.923122 -285.875698)
			(xy 38.934899 -285.827914) (xy 38.95419 -285.782638) (xy 38.980493 -285.741042) (xy 39.013128 -285.704205)
			(xy 39.051249 -285.67308) (xy 39.09387 -285.648473) (xy 39.139886 -285.631021) (xy 39.188105 -285.621177)
			(xy 39.23728 -285.619196) (xy 39.286135 -285.625128) (xy 39.333406 -285.63882) (xy 39.377868 -285.659918)
			(xy 39.418371 -285.687874) (xy 39.453864 -285.721966) (xy 39.483429 -285.76131) (xy 39.5063 -285.804887)
			(xy 39.521884 -285.851568) (xy 39.529779 -285.900145) (xy 39.530274 -285.924752) (xy 39.869122 -285.924752)
			(xy 39.873082 -285.875698) (xy 39.884859 -285.827914) (xy 39.90415 -285.782638) (xy 39.930453 -285.741042)
			(xy 39.963088 -285.704205) (xy 40.001209 -285.67308) (xy 40.04383 -285.648473) (xy 40.089846 -285.631021)
			(xy 40.138065 -285.621177) (xy 40.18724 -285.619196) (xy 40.236095 -285.625128) (xy 40.283366 -285.63882)
			(xy 40.327828 -285.659918) (xy 40.368331 -285.687874) (xy 40.403824 -285.721966) (xy 40.433389 -285.76131)
			(xy 40.45626 -285.804887) (xy 40.471844 -285.851568) (xy 40.479739 -285.900145) (xy 40.480234 -285.924752)
			(xy 40.479739 -285.949359) (xy 40.471844 -285.997936) (xy 40.45626 -286.044617) (xy 40.433389 -286.088194)
			(xy 40.403824 -286.127538) (xy 40.368331 -286.16163) (xy 40.327828 -286.189586) (xy 40.283366 -286.210684)
			(xy 40.236095 -286.224376) (xy 40.18724 -286.230308) (xy 40.138065 -286.228327) (xy 40.089846 -286.218483)
			(xy 40.04383 -286.201031) (xy 40.001209 -286.176424) (xy 39.963088 -286.145299) (xy 39.930453 -286.108462)
			(xy 39.90415 -286.066866) (xy 39.884859 -286.02159) (xy 39.873082 -285.973806) (xy 39.869122 -285.924752)
			(xy 39.530274 -285.924752) (xy 39.529779 -285.949359) (xy 39.521884 -285.997936) (xy 39.5063 -286.044617)
			(xy 39.483429 -286.088194) (xy 39.453864 -286.127538) (xy 39.418371 -286.16163) (xy 39.377868 -286.189586)
			(xy 39.333406 -286.210684) (xy 39.286135 -286.224376) (xy 39.23728 -286.230308) (xy 39.188105 -286.228327)
			(xy 39.139886 -286.218483) (xy 39.09387 -286.201031) (xy 39.051249 -286.176424) (xy 39.013128 -286.145299)
			(xy 38.980493 -286.108462) (xy 38.95419 -286.066866) (xy 38.934899 -286.02159) (xy 38.923122 -285.973806)
			(xy 38.919162 -285.924752) (xy 38.580314 -285.924752) (xy 38.579819 -285.949359) (xy 38.571924 -285.997936)
			(xy 38.55634 -286.044617) (xy 38.533469 -286.088194) (xy 38.503904 -286.127538) (xy 38.468411 -286.16163)
			(xy 38.427908 -286.189586) (xy 38.383446 -286.210684) (xy 38.336175 -286.224376) (xy 38.28732 -286.230308)
			(xy 38.238145 -286.228327) (xy 38.189926 -286.218483) (xy 38.14391 -286.201031) (xy 38.101289 -286.176424)
			(xy 38.063168 -286.145299) (xy 38.030533 -286.108462) (xy 38.00423 -286.066866) (xy 37.984939 -286.02159)
			(xy 37.973162 -285.973806) (xy 37.969202 -285.924752) (xy 37.6301 -285.924752) (xy 37.629605 -285.949359)
			(xy 37.62171 -285.997936) (xy 37.606126 -286.044617) (xy 37.583255 -286.088194) (xy 37.55369 -286.127538)
			(xy 37.518197 -286.16163) (xy 37.477694 -286.189586) (xy 37.433232 -286.210684) (xy 37.385961 -286.224376)
			(xy 37.337106 -286.230308) (xy 37.287931 -286.228327) (xy 37.239712 -286.218483) (xy 37.193696 -286.201031)
			(xy 37.151075 -286.176424) (xy 37.112954 -286.145299) (xy 37.080319 -286.108462) (xy 37.054016 -286.066866)
			(xy 37.034725 -286.02159) (xy 37.022948 -285.973806) (xy 37.018988 -285.924752) (xy 36.68014 -285.924752)
			(xy 36.679645 -285.949359) (xy 36.67175 -285.997936) (xy 36.656166 -286.044617) (xy 36.633295 -286.088194)
			(xy 36.60373 -286.127538) (xy 36.568237 -286.16163) (xy 36.527734 -286.189586) (xy 36.483272 -286.210684)
			(xy 36.436001 -286.224376) (xy 36.387146 -286.230308) (xy 36.337971 -286.228327) (xy 36.289752 -286.218483)
			(xy 36.243736 -286.201031) (xy 36.201115 -286.176424) (xy 36.162994 -286.145299) (xy 36.130359 -286.108462)
			(xy 36.104056 -286.066866) (xy 36.084765 -286.02159) (xy 36.072988 -285.973806) (xy 36.069028 -285.924752)
			(xy 1.660398 -285.924752) (xy 1.660398 -286.331914) (xy 25.811478 -286.331914) (xy 25.815549 -286.276292)
			(xy 25.827675 -286.221855) (xy 25.847598 -286.169764) (xy 25.874894 -286.121129) (xy 25.90898 -286.076986)
			(xy 25.949129 -286.038277) (xy 25.994487 -286.005826) (xy 26.044087 -285.980325) (xy 26.096871 -285.962318)
			(xy 26.151714 -285.952188) (xy 26.207448 -285.950151) (xy 26.262885 -285.956251) (xy 26.316842 -285.970357)
			(xy 26.368171 -285.992169) (xy 26.415777 -286.021223) (xy 26.458645 -286.056898) (xy 26.495862 -286.098435)
			(xy 26.526635 -286.144948) (xy 26.550307 -286.195445) (xy 26.566375 -286.248852) (xy 26.574495 -286.304028)
			(xy 26.575004 -286.331914) (xy 27.286964 -286.331914) (xy 27.291035 -286.276292) (xy 27.303161 -286.221855)
			(xy 27.323084 -286.169764) (xy 27.35038 -286.121129) (xy 27.384466 -286.076986) (xy 27.424615 -286.038277)
			(xy 27.469973 -286.005826) (xy 27.519573 -285.980325) (xy 27.572357 -285.962318) (xy 27.6272 -285.952188)
			(xy 27.682934 -285.950151) (xy 27.738371 -285.956251) (xy 27.792328 -285.970357) (xy 27.843657 -285.992169)
			(xy 27.891263 -286.021223) (xy 27.934131 -286.056898) (xy 27.971348 -286.098435) (xy 28.002121 -286.144948)
			(xy 28.025793 -286.195445) (xy 28.041861 -286.248852) (xy 28.049981 -286.304028) (xy 28.05049 -286.331914)
			(xy 28.175964 -286.331914) (xy 28.180035 -286.276292) (xy 28.192161 -286.221855) (xy 28.212084 -286.169764)
			(xy 28.23938 -286.121129) (xy 28.273466 -286.076986) (xy 28.313615 -286.038277) (xy 28.358973 -286.005826)
			(xy 28.408573 -285.980325) (xy 28.461357 -285.962318) (xy 28.5162 -285.952188) (xy 28.571934 -285.950151)
			(xy 28.627371 -285.956251) (xy 28.681328 -285.970357) (xy 28.732657 -285.992169) (xy 28.780263 -286.021223)
			(xy 28.823131 -286.056898) (xy 28.860348 -286.098435) (xy 28.891121 -286.144948) (xy 28.914793 -286.195445)
			(xy 28.930861 -286.248852) (xy 28.938981 -286.304028) (xy 28.93949 -286.331914) (xy 28.938981 -286.3598)
			(xy 28.930861 -286.414976) (xy 28.914793 -286.468383) (xy 28.891121 -286.51888) (xy 28.860348 -286.565393)
			(xy 28.823131 -286.60693) (xy 28.780263 -286.642605) (xy 28.732657 -286.671659) (xy 28.681328 -286.693471)
			(xy 28.627371 -286.707577) (xy 28.571934 -286.713677) (xy 28.5162 -286.71164) (xy 28.461357 -286.70151)
			(xy 28.408573 -286.683503) (xy 28.358973 -286.658002) (xy 28.313615 -286.625551) (xy 28.273466 -286.586842)
			(xy 28.23938 -286.542699) (xy 28.212084 -286.494064) (xy 28.192161 -286.441973) (xy 28.180035 -286.387536)
			(xy 28.175964 -286.331914) (xy 28.05049 -286.331914) (xy 28.049981 -286.3598) (xy 28.041861 -286.414976)
			(xy 28.025793 -286.468383) (xy 28.002121 -286.51888) (xy 27.971348 -286.565393) (xy 27.934131 -286.60693)
			(xy 27.891263 -286.642605) (xy 27.843657 -286.671659) (xy 27.792328 -286.693471) (xy 27.738371 -286.707577)
			(xy 27.682934 -286.713677) (xy 27.6272 -286.71164) (xy 27.572357 -286.70151) (xy 27.519573 -286.683503)
			(xy 27.469973 -286.658002) (xy 27.424615 -286.625551) (xy 27.384466 -286.586842) (xy 27.35038 -286.542699)
			(xy 27.323084 -286.494064) (xy 27.303161 -286.441973) (xy 27.291035 -286.387536) (xy 27.286964 -286.331914)
			(xy 26.575004 -286.331914) (xy 26.574495 -286.3598) (xy 26.566375 -286.414976) (xy 26.550307 -286.468383)
			(xy 26.526635 -286.51888) (xy 26.495862 -286.565393) (xy 26.458645 -286.60693) (xy 26.415777 -286.642605)
			(xy 26.368171 -286.671659) (xy 26.316842 -286.693471) (xy 26.262885 -286.707577) (xy 26.207448 -286.713677)
			(xy 26.151714 -286.71164) (xy 26.096871 -286.70151) (xy 26.044087 -286.683503) (xy 25.994487 -286.658002)
			(xy 25.949129 -286.625551) (xy 25.90898 -286.586842) (xy 25.874894 -286.542699) (xy 25.847598 -286.494064)
			(xy 25.827675 -286.441973) (xy 25.815549 -286.387536) (xy 25.811478 -286.331914) (xy 1.660398 -286.331914)
			(xy 1.660398 -287.131831) (xy 3.23899 -287.131831) (xy 3.23899 -287.077329) (xy 3.246746 -287.023382)
			(xy 3.262101 -286.971087) (xy 3.284742 -286.921511) (xy 3.314208 -286.87566) (xy 3.349899 -286.834471)
			(xy 3.391089 -286.798779) (xy 3.436939 -286.769313) (xy 3.486516 -286.746672) (xy 3.53881 -286.731317)
			(xy 3.592757 -286.72356) (xy 3.620008 -286.723074) (xy 3.647379 -286.723517) (xy 3.70156 -286.731338)
			(xy 3.754064 -286.746831) (xy 3.803811 -286.769679) (xy 3.849776 -286.799409) (xy 3.870706 -286.817054)
			(xy 3.877818 -286.82315) (xy 3.894836 -286.8295) (xy 3.98018 -286.8295) (xy 3.997198 -286.82315)
			(xy 4.00431 -286.817054) (xy 4.025234 -286.799405) (xy 4.071208 -286.769693) (xy 4.120958 -286.746858)
			(xy 4.173461 -286.731369) (xy 4.227638 -286.723545) (xy 4.255008 -286.723074) (xy 4.282261 -286.723533)
			(xy 4.336213 -286.73129) (xy 4.388511 -286.746646) (xy 4.438091 -286.769288) (xy 4.483945 -286.798757)
			(xy 4.525138 -286.83445) (xy 4.560832 -286.875643) (xy 4.590301 -286.921497) (xy 4.612943 -286.971077)
			(xy 4.6283 -287.023376) (xy 4.636057 -287.077327) (xy 4.636057 -287.131831) (xy 5.20038 -287.131831)
			(xy 5.20038 -287.077329) (xy 5.208136 -287.023382) (xy 5.223491 -286.971088) (xy 5.246132 -286.921511)
			(xy 5.275597 -286.875661) (xy 5.311288 -286.834471) (xy 5.352478 -286.79878) (xy 5.398328 -286.769314)
			(xy 5.447904 -286.746672) (xy 5.500198 -286.731317) (xy 5.554145 -286.72356) (xy 5.581396 -286.723074)
			(xy 5.61152 -286.72364) (xy 5.671017 -286.733121) (xy 5.728285 -286.751833) (xy 5.781902 -286.77931)
			(xy 5.830536 -286.81487) (xy 5.85216 -286.83585) (xy 5.859272 -286.843216) (xy 5.878068 -286.850836)
			(xy 5.970524 -286.850836) (xy 5.98932 -286.843216) (xy 5.996432 -286.83585) (xy 6.018072 -286.814886)
			(xy 6.066696 -286.779314) (xy 6.120308 -286.75183) (xy 6.177575 -286.733118) (xy 6.237073 -286.723644)
			(xy 6.267196 -286.723074) (xy 6.294449 -286.723533) (xy 6.348401 -286.73129) (xy 6.400699 -286.746645)
			(xy 6.45028 -286.769288) (xy 6.496134 -286.798756) (xy 6.537328 -286.83445) (xy 6.573022 -286.875643)
			(xy 6.60249 -286.921496) (xy 6.625133 -286.971077) (xy 6.64049 -287.023375) (xy 6.648247 -287.077327)
			(xy 6.648247 -287.093914) (xy 31.338012 -287.093914) (xy 31.338555 -287.064532) (xy 31.347584 -287.006465)
			(xy 31.365415 -286.95047) (xy 31.391626 -286.897875) (xy 31.425597 -286.849924) (xy 31.466521 -286.807752)
			(xy 31.48965 -286.789622) (xy 31.499048 -286.782256) (xy 31.509462 -286.761682) (xy 31.510986 -286.657796)
			(xy 31.50108 -286.636714) (xy 31.491936 -286.629348) (xy 31.470088 -286.611142) (xy 31.431546 -286.569324)
			(xy 31.399638 -286.522249) (xy 31.375071 -286.470959) (xy 31.358388 -286.416591) (xy 31.34996 -286.360349)
			(xy 31.349442 -286.331914) (xy 31.349928 -286.304663) (xy 31.357684 -286.250715) (xy 31.373039 -286.19842)
			(xy 31.395681 -286.148843) (xy 31.425147 -286.102993) (xy 31.460838 -286.061802) (xy 31.502029 -286.026111)
			(xy 31.547879 -285.996645) (xy 31.597456 -285.974003) (xy 31.649751 -285.958648) (xy 31.703699 -285.950892)
			(xy 31.758201 -285.950892) (xy 31.812149 -285.958648) (xy 31.864444 -285.974003) (xy 31.914021 -285.996645)
			(xy 31.959871 -286.026111) (xy 32.001062 -286.061802) (xy 32.036753 -286.102993) (xy 32.066219 -286.148843)
			(xy 32.088861 -286.19842) (xy 32.104216 -286.250715) (xy 32.111972 -286.304663) (xy 32.112458 -286.331914)
			(xy 32.111907 -286.361296) (xy 32.102876 -286.419361) (xy 32.085044 -286.475354) (xy 32.058835 -286.527949)
			(xy 32.024867 -286.5759) (xy 31.983946 -286.618074) (xy 31.96082 -286.636206) (xy 31.951422 -286.643572)
			(xy 31.941008 -286.664146) (xy 31.939484 -286.768032) (xy 31.94939 -286.789114) (xy 31.958534 -286.79648)
			(xy 31.980362 -286.814709) (xy 32.018902 -286.856524) (xy 32.05081 -286.903595) (xy 32.07538 -286.95488)
			(xy 32.092068 -287.009243) (xy 32.100505 -287.065481) (xy 32.101028 -287.093914) (xy 32.734502 -287.093914)
			(xy 32.738573 -287.038292) (xy 32.750699 -286.983855) (xy 32.770622 -286.931764) (xy 32.797918 -286.883129)
			(xy 32.832004 -286.838986) (xy 32.872153 -286.800277) (xy 32.917511 -286.767826) (xy 32.967111 -286.742325)
			(xy 33.019895 -286.724318) (xy 33.074738 -286.714188) (xy 33.130472 -286.712151) (xy 33.185909 -286.718251)
			(xy 33.239866 -286.732357) (xy 33.291195 -286.754169) (xy 33.338801 -286.783223) (xy 33.381669 -286.818898)
			(xy 33.418886 -286.860435) (xy 33.449659 -286.906948) (xy 33.473331 -286.957445) (xy 33.489399 -287.010852)
			(xy 33.497519 -287.066028) (xy 33.498028 -287.093914) (xy 33.620962 -287.093914) (xy 33.625033 -287.038292)
			(xy 33.637159 -286.983855) (xy 33.657082 -286.931764) (xy 33.684378 -286.883129) (xy 33.718464 -286.838986)
			(xy 33.758613 -286.800277) (xy 33.803971 -286.767826) (xy 33.853571 -286.742325) (xy 33.906355 -286.724318)
			(xy 33.961198 -286.714188) (xy 34.016932 -286.712151) (xy 34.072369 -286.718251) (xy 34.126326 -286.732357)
			(xy 34.177655 -286.754169) (xy 34.225261 -286.783223) (xy 34.268129 -286.818898) (xy 34.305346 -286.860435)
			(xy 34.31496 -286.874966) (xy 36.069028 -286.874966) (xy 36.072988 -286.825912) (xy 36.084765 -286.778128)
			(xy 36.104056 -286.732852) (xy 36.130359 -286.691256) (xy 36.162994 -286.654419) (xy 36.201115 -286.623294)
			(xy 36.243736 -286.598687) (xy 36.289752 -286.581235) (xy 36.337971 -286.571391) (xy 36.387146 -286.56941)
			(xy 36.436001 -286.575342) (xy 36.483272 -286.589034) (xy 36.527734 -286.610132) (xy 36.568237 -286.638088)
			(xy 36.60373 -286.67218) (xy 36.633295 -286.711524) (xy 36.656166 -286.755101) (xy 36.67175 -286.801782)
			(xy 36.679645 -286.850359) (xy 36.68014 -286.874966) (xy 37.018988 -286.874966) (xy 37.022948 -286.825912)
			(xy 37.034725 -286.778128) (xy 37.054016 -286.732852) (xy 37.080319 -286.691256) (xy 37.112954 -286.654419)
			(xy 37.151075 -286.623294) (xy 37.193696 -286.598687) (xy 37.239712 -286.581235) (xy 37.287931 -286.571391)
			(xy 37.337106 -286.56941) (xy 37.385961 -286.575342) (xy 37.433232 -286.589034) (xy 37.477694 -286.610132)
			(xy 37.518197 -286.638088) (xy 37.55369 -286.67218) (xy 37.583255 -286.711524) (xy 37.606126 -286.755101)
			(xy 37.62171 -286.801782) (xy 37.629605 -286.850359) (xy 37.6301 -286.874966) (xy 37.969202 -286.874966)
			(xy 37.973162 -286.825912) (xy 37.984939 -286.778128) (xy 38.00423 -286.732852) (xy 38.030533 -286.691256)
			(xy 38.063168 -286.654419) (xy 38.101289 -286.623294) (xy 38.14391 -286.598687) (xy 38.189926 -286.581235)
			(xy 38.238145 -286.571391) (xy 38.28732 -286.56941) (xy 38.336175 -286.575342) (xy 38.383446 -286.589034)
			(xy 38.427908 -286.610132) (xy 38.468411 -286.638088) (xy 38.503904 -286.67218) (xy 38.533469 -286.711524)
			(xy 38.55634 -286.755101) (xy 38.571924 -286.801782) (xy 38.579819 -286.850359) (xy 38.580314 -286.874966)
			(xy 38.919162 -286.874966) (xy 38.923122 -286.825912) (xy 38.934899 -286.778128) (xy 38.95419 -286.732852)
			(xy 38.980493 -286.691256) (xy 39.013128 -286.654419) (xy 39.051249 -286.623294) (xy 39.09387 -286.598687)
			(xy 39.139886 -286.581235) (xy 39.188105 -286.571391) (xy 39.23728 -286.56941) (xy 39.286135 -286.575342)
			(xy 39.333406 -286.589034) (xy 39.377868 -286.610132) (xy 39.418371 -286.638088) (xy 39.453864 -286.67218)
			(xy 39.483429 -286.711524) (xy 39.5063 -286.755101) (xy 39.521884 -286.801782) (xy 39.529779 -286.850359)
			(xy 39.530274 -286.874966) (xy 39.869122 -286.874966) (xy 39.873082 -286.825912) (xy 39.884859 -286.778128)
			(xy 39.90415 -286.732852) (xy 39.930453 -286.691256) (xy 39.963088 -286.654419) (xy 40.001209 -286.623294)
			(xy 40.04383 -286.598687) (xy 40.089846 -286.581235) (xy 40.138065 -286.571391) (xy 40.18724 -286.56941)
			(xy 40.236095 -286.575342) (xy 40.283366 -286.589034) (xy 40.327828 -286.610132) (xy 40.368331 -286.638088)
			(xy 40.403824 -286.67218) (xy 40.433389 -286.711524) (xy 40.45626 -286.755101) (xy 40.471844 -286.801782)
			(xy 40.479739 -286.850359) (xy 40.480234 -286.874966) (xy 40.819082 -286.874966) (xy 40.823042 -286.825912)
			(xy 40.834819 -286.778128) (xy 40.85411 -286.732852) (xy 40.880413 -286.691256) (xy 40.913048 -286.654419)
			(xy 40.951169 -286.623294) (xy 40.99379 -286.598687) (xy 41.039806 -286.581235) (xy 41.088025 -286.571391)
			(xy 41.1372 -286.56941) (xy 41.186055 -286.575342) (xy 41.233326 -286.589034) (xy 41.277788 -286.610132)
			(xy 41.318291 -286.638088) (xy 41.353784 -286.67218) (xy 41.383349 -286.711524) (xy 41.40622 -286.755101)
			(xy 41.421804 -286.801782) (xy 41.429699 -286.850359) (xy 41.430194 -286.874966) (xy 41.429699 -286.899573)
			(xy 41.421804 -286.94815) (xy 41.40622 -286.994831) (xy 41.383349 -287.038408) (xy 41.353784 -287.077752)
			(xy 41.318291 -287.111844) (xy 41.277788 -287.1398) (xy 41.233326 -287.160898) (xy 41.186055 -287.17459)
			(xy 41.1372 -287.180522) (xy 41.088025 -287.178541) (xy 41.039806 -287.168697) (xy 40.99379 -287.151245)
			(xy 40.951169 -287.126638) (xy 40.913048 -287.095513) (xy 40.880413 -287.058676) (xy 40.85411 -287.01708)
			(xy 40.834819 -286.971804) (xy 40.823042 -286.92402) (xy 40.819082 -286.874966) (xy 40.480234 -286.874966)
			(xy 40.479739 -286.899573) (xy 40.471844 -286.94815) (xy 40.45626 -286.994831) (xy 40.433389 -287.038408)
			(xy 40.403824 -287.077752) (xy 40.368331 -287.111844) (xy 40.327828 -287.1398) (xy 40.283366 -287.160898)
			(xy 40.236095 -287.17459) (xy 40.18724 -287.180522) (xy 40.138065 -287.178541) (xy 40.089846 -287.168697)
			(xy 40.04383 -287.151245) (xy 40.001209 -287.126638) (xy 39.963088 -287.095513) (xy 39.930453 -287.058676)
			(xy 39.90415 -287.01708) (xy 39.884859 -286.971804) (xy 39.873082 -286.92402) (xy 39.869122 -286.874966)
			(xy 39.530274 -286.874966) (xy 39.529779 -286.899573) (xy 39.521884 -286.94815) (xy 39.5063 -286.994831)
			(xy 39.483429 -287.038408) (xy 39.453864 -287.077752) (xy 39.418371 -287.111844) (xy 39.377868 -287.1398)
			(xy 39.333406 -287.160898) (xy 39.286135 -287.17459) (xy 39.23728 -287.180522) (xy 39.188105 -287.178541)
			(xy 39.139886 -287.168697) (xy 39.09387 -287.151245) (xy 39.051249 -287.126638) (xy 39.013128 -287.095513)
			(xy 38.980493 -287.058676) (xy 38.95419 -287.01708) (xy 38.934899 -286.971804) (xy 38.923122 -286.92402)
			(xy 38.919162 -286.874966) (xy 38.580314 -286.874966) (xy 38.579819 -286.899573) (xy 38.571924 -286.94815)
			(xy 38.55634 -286.994831) (xy 38.533469 -287.038408) (xy 38.503904 -287.077752) (xy 38.468411 -287.111844)
			(xy 38.427908 -287.1398) (xy 38.383446 -287.160898) (xy 38.336175 -287.17459) (xy 38.28732 -287.180522)
			(xy 38.238145 -287.178541) (xy 38.189926 -287.168697) (xy 38.14391 -287.151245) (xy 38.101289 -287.126638)
			(xy 38.063168 -287.095513) (xy 38.030533 -287.058676) (xy 38.00423 -287.01708) (xy 37.984939 -286.971804)
			(xy 37.973162 -286.92402) (xy 37.969202 -286.874966) (xy 37.6301 -286.874966) (xy 37.629605 -286.899573)
			(xy 37.62171 -286.94815) (xy 37.606126 -286.994831) (xy 37.583255 -287.038408) (xy 37.55369 -287.077752)
			(xy 37.518197 -287.111844) (xy 37.477694 -287.1398) (xy 37.433232 -287.160898) (xy 37.385961 -287.17459)
			(xy 37.337106 -287.180522) (xy 37.287931 -287.178541) (xy 37.239712 -287.168697) (xy 37.193696 -287.151245)
			(xy 37.151075 -287.126638) (xy 37.112954 -287.095513) (xy 37.080319 -287.058676) (xy 37.054016 -287.01708)
			(xy 37.034725 -286.971804) (xy 37.022948 -286.92402) (xy 37.018988 -286.874966) (xy 36.68014 -286.874966)
			(xy 36.679645 -286.899573) (xy 36.67175 -286.94815) (xy 36.656166 -286.994831) (xy 36.633295 -287.038408)
			(xy 36.60373 -287.077752) (xy 36.568237 -287.111844) (xy 36.527734 -287.1398) (xy 36.483272 -287.160898)
			(xy 36.436001 -287.17459) (xy 36.387146 -287.180522) (xy 36.337971 -287.178541) (xy 36.289752 -287.168697)
			(xy 36.243736 -287.151245) (xy 36.201115 -287.126638) (xy 36.162994 -287.095513) (xy 36.130359 -287.058676)
			(xy 36.104056 -287.01708) (xy 36.084765 -286.971804) (xy 36.072988 -286.92402) (xy 36.069028 -286.874966)
			(xy 34.31496 -286.874966) (xy 34.336119 -286.906948) (xy 34.359791 -286.957445) (xy 34.375859 -287.010852)
			(xy 34.383979 -287.066028) (xy 34.384488 -287.093914) (xy 34.383979 -287.1218) (xy 34.375859 -287.176976)
			(xy 34.359791 -287.230383) (xy 34.336119 -287.28088) (xy 34.305346 -287.327393) (xy 34.285139 -287.349946)
			(xy 73.593972 -287.349946) (xy 73.597932 -287.300892) (xy 73.609709 -287.253108) (xy 73.629 -287.207832)
			(xy 73.655303 -287.166236) (xy 73.687938 -287.129399) (xy 73.726059 -287.098274) (xy 73.76868 -287.073667)
			(xy 73.814696 -287.056215) (xy 73.862915 -287.046371) (xy 73.91209 -287.04439) (xy 73.960945 -287.050322)
			(xy 74.008216 -287.064014) (xy 74.052678 -287.085112) (xy 74.093181 -287.113068) (xy 74.128674 -287.14716)
			(xy 74.158239 -287.186504) (xy 74.18111 -287.230081) (xy 74.196694 -287.276762) (xy 74.204589 -287.325339)
			(xy 74.205084 -287.349946) (xy 74.204589 -287.374553) (xy 74.20441 -287.375654) (xy 74.523088 -287.375654)
			(xy 74.523088 -287.324238) (xy 74.531131 -287.273456) (xy 74.547019 -287.224557) (xy 74.570362 -287.178745)
			(xy 74.600583 -287.137149) (xy 74.636939 -287.100793) (xy 74.678535 -287.070572) (xy 74.724347 -287.047229)
			(xy 74.773246 -287.031341) (xy 74.824028 -287.023298) (xy 74.875444 -287.023298) (xy 74.926226 -287.031341)
			(xy 74.975125 -287.047229) (xy 75.020937 -287.070572) (xy 75.062533 -287.100793) (xy 75.098889 -287.137149)
			(xy 75.12911 -287.178745) (xy 75.152453 -287.224557) (xy 75.168341 -287.273456) (xy 75.176384 -287.324238)
			(xy 75.176888 -287.349946) (xy 75.176384 -287.375654) (xy 75.473302 -287.375654) (xy 75.473302 -287.324238)
			(xy 75.481345 -287.273456) (xy 75.497233 -287.224557) (xy 75.520576 -287.178745) (xy 75.550797 -287.137149)
			(xy 75.587153 -287.100793) (xy 75.628749 -287.070572) (xy 75.674561 -287.047229) (xy 75.72346 -287.031341)
			(xy 75.774242 -287.023298) (xy 75.825658 -287.023298) (xy 75.87644 -287.031341) (xy 75.925339 -287.047229)
			(xy 75.971151 -287.070572) (xy 76.012747 -287.100793) (xy 76.049103 -287.137149) (xy 76.079324 -287.178745)
			(xy 76.102667 -287.224557) (xy 76.118555 -287.273456) (xy 76.126598 -287.324238) (xy 76.127102 -287.349946)
			(xy 76.444106 -287.349946) (xy 76.448066 -287.300892) (xy 76.459843 -287.253108) (xy 76.479134 -287.207832)
			(xy 76.505437 -287.166236) (xy 76.538072 -287.129399) (xy 76.576193 -287.098274) (xy 76.618814 -287.073667)
			(xy 76.66483 -287.056215) (xy 76.713049 -287.046371) (xy 76.762224 -287.04439) (xy 76.811079 -287.050322)
			(xy 76.85835 -287.064014) (xy 76.902812 -287.085112) (xy 76.943315 -287.113068) (xy 76.978808 -287.14716)
			(xy 77.008373 -287.186504) (xy 77.031244 -287.230081) (xy 77.046828 -287.276762) (xy 77.054723 -287.325339)
			(xy 77.055218 -287.349946) (xy 77.394066 -287.349946) (xy 77.398026 -287.300892) (xy 77.409803 -287.253108)
			(xy 77.429094 -287.207832) (xy 77.455397 -287.166236) (xy 77.488032 -287.129399) (xy 77.526153 -287.098274)
			(xy 77.568774 -287.073667) (xy 77.61479 -287.056215) (xy 77.663009 -287.046371) (xy 77.712184 -287.04439)
			(xy 77.761039 -287.050322) (xy 77.80831 -287.064014) (xy 77.852772 -287.085112) (xy 77.893275 -287.113068)
			(xy 77.928768 -287.14716) (xy 77.958333 -287.186504) (xy 77.981204 -287.230081) (xy 77.996788 -287.276762)
			(xy 78.004683 -287.325339) (xy 78.005178 -287.349946) (xy 78.004683 -287.374553) (xy 77.996788 -287.42313)
			(xy 77.981204 -287.469811) (xy 77.958333 -287.513388) (xy 77.928768 -287.552732) (xy 77.893275 -287.586824)
			(xy 77.852772 -287.61478) (xy 77.80831 -287.635878) (xy 77.761039 -287.64957) (xy 77.712184 -287.655502)
			(xy 77.663009 -287.653521) (xy 77.61479 -287.643677) (xy 77.568774 -287.626225) (xy 77.526153 -287.601618)
			(xy 77.488032 -287.570493) (xy 77.455397 -287.533656) (xy 77.429094 -287.49206) (xy 77.409803 -287.446784)
			(xy 77.398026 -287.399) (xy 77.394066 -287.349946) (xy 77.055218 -287.349946) (xy 77.054723 -287.374553)
			(xy 77.046828 -287.42313) (xy 77.031244 -287.469811) (xy 77.008373 -287.513388) (xy 76.978808 -287.552732)
			(xy 76.943315 -287.586824) (xy 76.902812 -287.61478) (xy 76.85835 -287.635878) (xy 76.811079 -287.64957)
			(xy 76.762224 -287.655502) (xy 76.713049 -287.653521) (xy 76.66483 -287.643677) (xy 76.618814 -287.626225)
			(xy 76.576193 -287.601618) (xy 76.538072 -287.570493) (xy 76.505437 -287.533656) (xy 76.479134 -287.49206)
			(xy 76.459843 -287.446784) (xy 76.448066 -287.399) (xy 76.444106 -287.349946) (xy 76.127102 -287.349946)
			(xy 76.126598 -287.375654) (xy 76.118555 -287.426436) (xy 76.102667 -287.475335) (xy 76.079324 -287.521147)
			(xy 76.049103 -287.562743) (xy 76.012747 -287.599099) (xy 75.971151 -287.62932) (xy 75.925339 -287.652663)
			(xy 75.87644 -287.668551) (xy 75.825658 -287.676594) (xy 75.774242 -287.676594) (xy 75.72346 -287.668551)
			(xy 75.674561 -287.652663) (xy 75.628749 -287.62932) (xy 75.587153 -287.599099) (xy 75.550797 -287.562743)
			(xy 75.520576 -287.521147) (xy 75.497233 -287.475335) (xy 75.481345 -287.426436) (xy 75.473302 -287.375654)
			(xy 75.176384 -287.375654) (xy 75.168341 -287.426436) (xy 75.152453 -287.475335) (xy 75.12911 -287.521147)
			(xy 75.098889 -287.562743) (xy 75.062533 -287.599099) (xy 75.020937 -287.62932) (xy 74.975125 -287.652663)
			(xy 74.926226 -287.668551) (xy 74.875444 -287.676594) (xy 74.824028 -287.676594) (xy 74.773246 -287.668551)
			(xy 74.724347 -287.652663) (xy 74.678535 -287.62932) (xy 74.636939 -287.599099) (xy 74.600583 -287.562743)
			(xy 74.570362 -287.521147) (xy 74.547019 -287.475335) (xy 74.531131 -287.426436) (xy 74.523088 -287.375654)
			(xy 74.20441 -287.375654) (xy 74.196694 -287.42313) (xy 74.18111 -287.469811) (xy 74.158239 -287.513388)
			(xy 74.128674 -287.552732) (xy 74.093181 -287.586824) (xy 74.052678 -287.61478) (xy 74.008216 -287.635878)
			(xy 73.960945 -287.64957) (xy 73.91209 -287.655502) (xy 73.862915 -287.653521) (xy 73.814696 -287.643677)
			(xy 73.76868 -287.626225) (xy 73.726059 -287.601618) (xy 73.687938 -287.570493) (xy 73.655303 -287.533656)
			(xy 73.629 -287.49206) (xy 73.609709 -287.446784) (xy 73.597932 -287.399) (xy 73.593972 -287.349946)
			(xy 34.285139 -287.349946) (xy 34.268129 -287.36893) (xy 34.225261 -287.404605) (xy 34.177655 -287.433659)
			(xy 34.126326 -287.455471) (xy 34.072369 -287.469577) (xy 34.016932 -287.475677) (xy 33.961198 -287.47364)
			(xy 33.906355 -287.46351) (xy 33.853571 -287.445503) (xy 33.803971 -287.420002) (xy 33.758613 -287.387551)
			(xy 33.718464 -287.348842) (xy 33.684378 -287.304699) (xy 33.657082 -287.256064) (xy 33.637159 -287.203973)
			(xy 33.625033 -287.149536) (xy 33.620962 -287.093914) (xy 33.498028 -287.093914) (xy 33.497519 -287.1218)
			(xy 33.489399 -287.176976) (xy 33.473331 -287.230383) (xy 33.449659 -287.28088) (xy 33.418886 -287.327393)
			(xy 33.381669 -287.36893) (xy 33.338801 -287.404605) (xy 33.291195 -287.433659) (xy 33.239866 -287.455471)
			(xy 33.185909 -287.469577) (xy 33.130472 -287.475677) (xy 33.074738 -287.47364) (xy 33.019895 -287.46351)
			(xy 32.967111 -287.445503) (xy 32.917511 -287.420002) (xy 32.872153 -287.387551) (xy 32.832004 -287.348842)
			(xy 32.797918 -287.304699) (xy 32.770622 -287.256064) (xy 32.750699 -287.203973) (xy 32.738573 -287.149536)
			(xy 32.734502 -287.093914) (xy 32.101028 -287.093914) (xy 32.100542 -287.121165) (xy 32.092786 -287.175113)
			(xy 32.077431 -287.227408) (xy 32.054789 -287.276985) (xy 32.025323 -287.322835) (xy 31.989632 -287.364026)
			(xy 31.948441 -287.399717) (xy 31.902591 -287.429183) (xy 31.853014 -287.451825) (xy 31.800719 -287.46718)
			(xy 31.746771 -287.474936) (xy 31.692269 -287.474936) (xy 31.638321 -287.46718) (xy 31.586026 -287.451825)
			(xy 31.536449 -287.429183) (xy 31.490599 -287.399717) (xy 31.449408 -287.364026) (xy 31.413717 -287.322835)
			(xy 31.384251 -287.276985) (xy 31.361609 -287.227408) (xy 31.346254 -287.175113) (xy 31.338498 -287.121165)
			(xy 31.338012 -287.093914) (xy 6.648247 -287.093914) (xy 6.648247 -287.131833) (xy 6.64049 -287.185785)
			(xy 6.625133 -287.238083) (xy 6.60249 -287.287664) (xy 6.573022 -287.333517) (xy 6.537328 -287.37471)
			(xy 6.496134 -287.410404) (xy 6.45028 -287.439872) (xy 6.400699 -287.462515) (xy 6.348401 -287.47787)
			(xy 6.294449 -287.485627) (xy 6.267196 -287.48609) (xy 6.237072 -287.485539) (xy 6.177574 -287.476056)
			(xy 6.120305 -287.457341) (xy 6.066688 -287.42986) (xy 6.018056 -287.394296) (xy 5.996432 -287.373314)
			(xy 5.98932 -287.365948) (xy 5.970524 -287.358328) (xy 5.878068 -287.358328) (xy 5.859272 -287.365948)
			(xy 5.85216 -287.373314) (xy 5.830534 -287.394293) (xy 5.781905 -287.429861) (xy 5.728289 -287.457341)
			(xy 5.671019 -287.476049) (xy 5.61152 -287.485521) (xy 5.581396 -287.48609) (xy 5.554145 -287.4856)
			(xy 5.500198 -287.477843) (xy 5.447904 -287.462488) (xy 5.398328 -287.439846) (xy 5.352478 -287.41038)
			(xy 5.311288 -287.374689) (xy 5.275597 -287.333499) (xy 5.246132 -287.287649) (xy 5.223491 -287.238072)
			(xy 5.208136 -287.185778) (xy 5.20038 -287.131831) (xy 4.636057 -287.131831) (xy 4.636057 -287.131833)
			(xy 4.6283 -287.185784) (xy 4.612943 -287.238083) (xy 4.590301 -287.287663) (xy 4.560832 -287.333517)
			(xy 4.525138 -287.37471) (xy 4.483945 -287.410403) (xy 4.438091 -287.439872) (xy 4.388511 -287.462514)
			(xy 4.336213 -287.47787) (xy 4.282261 -287.485627) (xy 4.255008 -287.48609) (xy 4.227638 -287.485622)
			(xy 4.173459 -287.477805) (xy 4.120956 -287.462316) (xy 4.071209 -287.439475) (xy 4.025242 -287.409751)
			(xy 4.00431 -287.39211) (xy 3.997198 -287.386014) (xy 3.98018 -287.379664) (xy 3.894836 -287.379664)
			(xy 3.877818 -287.386014) (xy 3.870706 -287.39211) (xy 3.849784 -287.409761) (xy 3.803808 -287.439471)
			(xy 3.754058 -287.462304) (xy 3.701555 -287.477793) (xy 3.647378 -287.485618) (xy 3.620008 -287.48609)
			(xy 3.592757 -287.4856) (xy 3.53881 -287.477843) (xy 3.486516 -287.462488) (xy 3.436939 -287.439847)
			(xy 3.391089 -287.410381) (xy 3.349899 -287.374689) (xy 3.314208 -287.3335) (xy 3.284742 -287.287649)
			(xy 3.262101 -287.238073) (xy 3.246746 -287.185778) (xy 3.23899 -287.131831) (xy 1.660398 -287.131831)
			(xy 1.660398 -287.984001) (xy 11.94992 -287.984001) (xy 11.94992 -287.929499) (xy 11.957676 -287.875552)
			(xy 11.973031 -287.823257) (xy 11.995672 -287.773681) (xy 12.025138 -287.72783) (xy 12.060829 -287.686641)
			(xy 12.102019 -287.650949) (xy 12.147869 -287.621483) (xy 12.197446 -287.598842) (xy 12.24974 -287.583487)
			(xy 12.303687 -287.57573) (xy 12.330938 -287.575244) (xy 12.358307 -287.575736) (xy 12.412486 -287.583546)
			(xy 12.464989 -287.599028) (xy 12.514736 -287.621865) (xy 12.560704 -287.651585) (xy 12.581636 -287.669224)
			(xy 12.588748 -287.67532) (xy 12.605766 -287.68167) (xy 12.69111 -287.68167) (xy 12.708128 -287.67532)
			(xy 12.71524 -287.669224) (xy 12.736187 -287.651603) (xy 12.782155 -287.621888) (xy 12.831899 -287.599048)
			(xy 12.884396 -287.583553) (xy 12.93857 -287.57572) (xy 12.965938 -287.575244) (xy 12.993191 -287.575703)
			(xy 13.047143 -287.58346) (xy 13.099441 -287.598816) (xy 13.149021 -287.621458) (xy 13.194875 -287.650927)
			(xy 13.236068 -287.68662) (xy 13.271762 -287.727813) (xy 13.301231 -287.773667) (xy 13.323873 -287.823247)
			(xy 13.33923 -287.875546) (xy 13.346987 -287.929497) (xy 13.346987 -287.984001) (xy 13.68982 -287.984001)
			(xy 13.68982 -287.929499) (xy 13.697576 -287.875552) (xy 13.712931 -287.823257) (xy 13.735572 -287.773681)
			(xy 13.765038 -287.72783) (xy 13.800729 -287.686641) (xy 13.841919 -287.650949) (xy 13.887769 -287.621483)
			(xy 13.937346 -287.598842) (xy 13.98964 -287.583487) (xy 14.043587 -287.57573) (xy 14.070838 -287.575244)
			(xy 14.098207 -287.575736) (xy 14.152386 -287.583546) (xy 14.204889 -287.599028) (xy 14.254636 -287.621865)
			(xy 14.300604 -287.651585) (xy 14.321536 -287.669224) (xy 14.328648 -287.67532) (xy 14.345666 -287.68167)
			(xy 14.43101 -287.68167) (xy 14.448028 -287.67532) (xy 14.45514 -287.669224) (xy 14.476087 -287.651603)
			(xy 14.522055 -287.621888) (xy 14.571799 -287.599048) (xy 14.624296 -287.583553) (xy 14.67847 -287.57572)
			(xy 14.705838 -287.575244) (xy 14.733091 -287.575703) (xy 14.787043 -287.58346) (xy 14.839341 -287.598816)
			(xy 14.888921 -287.621458) (xy 14.934775 -287.650927) (xy 14.975968 -287.68662) (xy 15.011662 -287.727813)
			(xy 15.041131 -287.773667) (xy 15.063773 -287.823247) (xy 15.064266 -287.824926) (xy 36.069028 -287.824926)
			(xy 36.072988 -287.775872) (xy 36.084765 -287.728088) (xy 36.104056 -287.682812) (xy 36.130359 -287.641216)
			(xy 36.162994 -287.604379) (xy 36.201115 -287.573254) (xy 36.243736 -287.548647) (xy 36.289752 -287.531195)
			(xy 36.337971 -287.521351) (xy 36.387146 -287.51937) (xy 36.436001 -287.525302) (xy 36.483272 -287.538994)
			(xy 36.527734 -287.560092) (xy 36.568237 -287.588048) (xy 36.60373 -287.62214) (xy 36.633295 -287.661484)
			(xy 36.656166 -287.705061) (xy 36.67175 -287.751742) (xy 36.679645 -287.800319) (xy 36.68014 -287.824926)
			(xy 37.018988 -287.824926) (xy 37.022948 -287.775872) (xy 37.034725 -287.728088) (xy 37.054016 -287.682812)
			(xy 37.080319 -287.641216) (xy 37.112954 -287.604379) (xy 37.151075 -287.573254) (xy 37.193696 -287.548647)
			(xy 37.239712 -287.531195) (xy 37.287931 -287.521351) (xy 37.337106 -287.51937) (xy 37.385961 -287.525302)
			(xy 37.433232 -287.538994) (xy 37.477694 -287.560092) (xy 37.518197 -287.588048) (xy 37.55369 -287.62214)
			(xy 37.583255 -287.661484) (xy 37.606126 -287.705061) (xy 37.62171 -287.751742) (xy 37.629605 -287.800319)
			(xy 37.6301 -287.824926) (xy 37.629605 -287.849533) (xy 37.629463 -287.850408) (xy 37.944539 -287.850408)
			(xy 37.944539 -287.798392) (xy 37.952677 -287.747016) (xy 37.968751 -287.697546) (xy 37.992366 -287.651199)
			(xy 38.02294 -287.609117) (xy 38.059722 -287.572337) (xy 38.101804 -287.541763) (xy 38.148151 -287.518148)
			(xy 38.197622 -287.502075) (xy 38.248998 -287.493939) (xy 38.275006 -287.493456) (xy 39.224966 -287.493456)
			(xy 39.250978 -287.493901) (xy 39.302363 -287.502035) (xy 39.351843 -287.518107) (xy 39.398199 -287.541722)
			(xy 39.44029 -287.572299) (xy 39.477079 -287.609084) (xy 39.50766 -287.651172) (xy 39.53128 -287.697525)
			(xy 39.547357 -287.747004) (xy 39.555496 -287.798388) (xy 39.555496 -287.824926) (xy 39.869122 -287.824926)
			(xy 39.873082 -287.775872) (xy 39.884859 -287.728088) (xy 39.90415 -287.682812) (xy 39.930453 -287.641216)
			(xy 39.963088 -287.604379) (xy 40.001209 -287.573254) (xy 40.04383 -287.548647) (xy 40.089846 -287.531195)
			(xy 40.138065 -287.521351) (xy 40.18724 -287.51937) (xy 40.236095 -287.525302) (xy 40.283366 -287.538994)
			(xy 40.327828 -287.560092) (xy 40.368331 -287.588048) (xy 40.403824 -287.62214) (xy 40.433389 -287.661484)
			(xy 40.45626 -287.705061) (xy 40.471844 -287.751742) (xy 40.479739 -287.800319) (xy 40.480234 -287.824926)
			(xy 40.479739 -287.849533) (xy 40.479597 -287.850405) (xy 40.794466 -287.850405) (xy 40.794466 -287.798395)
			(xy 40.802602 -287.747025) (xy 40.818674 -287.697561) (xy 40.842285 -287.651219) (xy 40.872855 -287.609142)
			(xy 40.909631 -287.572364) (xy 40.951707 -287.541792) (xy 40.998048 -287.518179) (xy 41.047512 -287.502105)
			(xy 41.098881 -287.493967) (xy 41.124886 -287.493456) (xy 42.074846 -287.493456) (xy 42.100852 -287.493934)
			(xy 42.152223 -287.502077) (xy 42.201688 -287.518155) (xy 42.248029 -287.541773) (xy 42.290106 -287.572348)
			(xy 42.326882 -287.609129) (xy 42.357451 -287.65121) (xy 42.381063 -287.697554) (xy 42.397134 -287.747022)
			(xy 42.40527 -287.798394) (xy 42.40527 -287.824926) (xy 42.719002 -287.824926) (xy 42.722962 -287.775872)
			(xy 42.734739 -287.728088) (xy 42.75403 -287.682812) (xy 42.780333 -287.641216) (xy 42.812968 -287.604379)
			(xy 42.851089 -287.573254) (xy 42.89371 -287.548647) (xy 42.939726 -287.531195) (xy 42.987945 -287.521351)
			(xy 43.03712 -287.51937) (xy 43.085975 -287.525302) (xy 43.133246 -287.538994) (xy 43.177708 -287.560092)
			(xy 43.218211 -287.588048) (xy 43.253704 -287.62214) (xy 43.283269 -287.661484) (xy 43.30614 -287.705061)
			(xy 43.321724 -287.751742) (xy 43.329619 -287.800319) (xy 43.330114 -287.824926) (xy 43.668962 -287.824926)
			(xy 43.672922 -287.775872) (xy 43.684699 -287.728088) (xy 43.70399 -287.682812) (xy 43.730293 -287.641216)
			(xy 43.762928 -287.604379) (xy 43.801049 -287.573254) (xy 43.84367 -287.548647) (xy 43.889686 -287.531195)
			(xy 43.937905 -287.521351) (xy 43.98708 -287.51937) (xy 44.035935 -287.525302) (xy 44.083206 -287.538994)
			(xy 44.127668 -287.560092) (xy 44.168171 -287.588048) (xy 44.203664 -287.62214) (xy 44.233229 -287.661484)
			(xy 44.2561 -287.705061) (xy 44.271684 -287.751742) (xy 44.279579 -287.800319) (xy 44.280074 -287.824926)
			(xy 44.619176 -287.824926) (xy 44.623136 -287.775872) (xy 44.634913 -287.728088) (xy 44.654204 -287.682812)
			(xy 44.680507 -287.641216) (xy 44.713142 -287.604379) (xy 44.751263 -287.573254) (xy 44.793884 -287.548647)
			(xy 44.8399 -287.531195) (xy 44.888119 -287.521351) (xy 44.937294 -287.51937) (xy 44.986149 -287.525302)
			(xy 45.03342 -287.538994) (xy 45.077882 -287.560092) (xy 45.118385 -287.588048) (xy 45.153878 -287.62214)
			(xy 45.183443 -287.661484) (xy 45.206314 -287.705061) (xy 45.221898 -287.751742) (xy 45.229793 -287.800319)
			(xy 45.230288 -287.824926) (xy 45.569136 -287.824926) (xy 45.573096 -287.775872) (xy 45.584873 -287.728088)
			(xy 45.604164 -287.682812) (xy 45.630467 -287.641216) (xy 45.663102 -287.604379) (xy 45.701223 -287.573254)
			(xy 45.743844 -287.548647) (xy 45.78986 -287.531195) (xy 45.838079 -287.521351) (xy 45.887254 -287.51937)
			(xy 45.936109 -287.525302) (xy 45.98338 -287.538994) (xy 46.027842 -287.560092) (xy 46.068345 -287.588048)
			(xy 46.103838 -287.62214) (xy 46.133403 -287.661484) (xy 46.156274 -287.705061) (xy 46.171858 -287.751742)
			(xy 46.179753 -287.800319) (xy 46.180248 -287.824926) (xy 46.519096 -287.824926) (xy 46.523056 -287.775872)
			(xy 46.534833 -287.728088) (xy 46.554124 -287.682812) (xy 46.580427 -287.641216) (xy 46.613062 -287.604379)
			(xy 46.651183 -287.573254) (xy 46.693804 -287.548647) (xy 46.73982 -287.531195) (xy 46.788039 -287.521351)
			(xy 46.837214 -287.51937) (xy 46.886069 -287.525302) (xy 46.93334 -287.538994) (xy 46.977802 -287.560092)
			(xy 47.018305 -287.588048) (xy 47.053798 -287.62214) (xy 47.083363 -287.661484) (xy 47.106234 -287.705061)
			(xy 47.121818 -287.751742) (xy 47.129713 -287.800319) (xy 47.130208 -287.824926) (xy 47.469056 -287.824926)
			(xy 47.473016 -287.775872) (xy 47.484793 -287.728088) (xy 47.504084 -287.682812) (xy 47.530387 -287.641216)
			(xy 47.563022 -287.604379) (xy 47.601143 -287.573254) (xy 47.643764 -287.548647) (xy 47.68978 -287.531195)
			(xy 47.737999 -287.521351) (xy 47.787174 -287.51937) (xy 47.836029 -287.525302) (xy 47.8833 -287.538994)
			(xy 47.927762 -287.560092) (xy 47.968265 -287.588048) (xy 48.003758 -287.62214) (xy 48.033323 -287.661484)
			(xy 48.056194 -287.705061) (xy 48.071778 -287.751742) (xy 48.079673 -287.800319) (xy 48.080168 -287.824926)
			(xy 48.419016 -287.824926) (xy 48.422976 -287.775872) (xy 48.434753 -287.728088) (xy 48.454044 -287.682812)
			(xy 48.480347 -287.641216) (xy 48.512982 -287.604379) (xy 48.551103 -287.573254) (xy 48.593724 -287.548647)
			(xy 48.63974 -287.531195) (xy 48.687959 -287.521351) (xy 48.737134 -287.51937) (xy 48.785989 -287.525302)
			(xy 48.83326 -287.538994) (xy 48.877722 -287.560092) (xy 48.918225 -287.588048) (xy 48.953718 -287.62214)
			(xy 48.983283 -287.661484) (xy 49.006154 -287.705061) (xy 49.021738 -287.751742) (xy 49.029633 -287.800319)
			(xy 49.030128 -287.824926) (xy 49.368976 -287.824926) (xy 49.372936 -287.775872) (xy 49.384713 -287.728088)
			(xy 49.404004 -287.682812) (xy 49.430307 -287.641216) (xy 49.462942 -287.604379) (xy 49.501063 -287.573254)
			(xy 49.543684 -287.548647) (xy 49.5897 -287.531195) (xy 49.637919 -287.521351) (xy 49.687094 -287.51937)
			(xy 49.735949 -287.525302) (xy 49.78322 -287.538994) (xy 49.827682 -287.560092) (xy 49.868185 -287.588048)
			(xy 49.903678 -287.62214) (xy 49.933243 -287.661484) (xy 49.956114 -287.705061) (xy 49.971698 -287.751742)
			(xy 49.979593 -287.800319) (xy 49.980088 -287.824926) (xy 50.31919 -287.824926) (xy 50.32315 -287.775872)
			(xy 50.334927 -287.728088) (xy 50.354218 -287.682812) (xy 50.380521 -287.641216) (xy 50.413156 -287.604379)
			(xy 50.451277 -287.573254) (xy 50.493898 -287.548647) (xy 50.539914 -287.531195) (xy 50.588133 -287.521351)
			(xy 50.637308 -287.51937) (xy 50.686163 -287.525302) (xy 50.733434 -287.538994) (xy 50.777896 -287.560092)
			(xy 50.818399 -287.588048) (xy 50.853892 -287.62214) (xy 50.883457 -287.661484) (xy 50.906328 -287.705061)
			(xy 50.921912 -287.751742) (xy 50.929807 -287.800319) (xy 50.930302 -287.824926) (xy 51.26915 -287.824926)
			(xy 51.27311 -287.775872) (xy 51.284887 -287.728088) (xy 51.304178 -287.682812) (xy 51.330481 -287.641216)
			(xy 51.363116 -287.604379) (xy 51.401237 -287.573254) (xy 51.443858 -287.548647) (xy 51.489874 -287.531195)
			(xy 51.538093 -287.521351) (xy 51.587268 -287.51937) (xy 51.636123 -287.525302) (xy 51.683394 -287.538994)
			(xy 51.727856 -287.560092) (xy 51.768359 -287.588048) (xy 51.803852 -287.62214) (xy 51.833417 -287.661484)
			(xy 51.856288 -287.705061) (xy 51.871872 -287.751742) (xy 51.879767 -287.800319) (xy 51.880262 -287.824926)
			(xy 52.21911 -287.824926) (xy 52.22307 -287.775872) (xy 52.234847 -287.728088) (xy 52.254138 -287.682812)
			(xy 52.280441 -287.641216) (xy 52.313076 -287.604379) (xy 52.351197 -287.573254) (xy 52.393818 -287.548647)
			(xy 52.439834 -287.531195) (xy 52.488053 -287.521351) (xy 52.537228 -287.51937) (xy 52.586083 -287.525302)
			(xy 52.633354 -287.538994) (xy 52.677816 -287.560092) (xy 52.718319 -287.588048) (xy 52.753812 -287.62214)
			(xy 52.783377 -287.661484) (xy 52.806248 -287.705061) (xy 52.821832 -287.751742) (xy 52.829727 -287.800319)
			(xy 52.830222 -287.824926) (xy 53.16907 -287.824926) (xy 53.17303 -287.775872) (xy 53.184807 -287.728088)
			(xy 53.204098 -287.682812) (xy 53.230401 -287.641216) (xy 53.263036 -287.604379) (xy 53.301157 -287.573254)
			(xy 53.343778 -287.548647) (xy 53.389794 -287.531195) (xy 53.438013 -287.521351) (xy 53.487188 -287.51937)
			(xy 53.536043 -287.525302) (xy 53.583314 -287.538994) (xy 53.627776 -287.560092) (xy 53.668279 -287.588048)
			(xy 53.703772 -287.62214) (xy 53.733337 -287.661484) (xy 53.756208 -287.705061) (xy 53.771792 -287.751742)
			(xy 53.779687 -287.800319) (xy 53.780182 -287.824926) (xy 54.11903 -287.824926) (xy 54.12299 -287.775872)
			(xy 54.134767 -287.728088) (xy 54.154058 -287.682812) (xy 54.180361 -287.641216) (xy 54.212996 -287.604379)
			(xy 54.251117 -287.573254) (xy 54.293738 -287.548647) (xy 54.339754 -287.531195) (xy 54.387973 -287.521351)
			(xy 54.437148 -287.51937) (xy 54.486003 -287.525302) (xy 54.533274 -287.538994) (xy 54.577736 -287.560092)
			(xy 54.618239 -287.588048) (xy 54.653732 -287.62214) (xy 54.683297 -287.661484) (xy 54.706168 -287.705061)
			(xy 54.721752 -287.751742) (xy 54.729647 -287.800319) (xy 54.730142 -287.824926) (xy 55.06899 -287.824926)
			(xy 55.07295 -287.775872) (xy 55.084727 -287.728088) (xy 55.104018 -287.682812) (xy 55.130321 -287.641216)
			(xy 55.162956 -287.604379) (xy 55.201077 -287.573254) (xy 55.243698 -287.548647) (xy 55.289714 -287.531195)
			(xy 55.337933 -287.521351) (xy 55.387108 -287.51937) (xy 55.435963 -287.525302) (xy 55.483234 -287.538994)
			(xy 55.527696 -287.560092) (xy 55.568199 -287.588048) (xy 55.603692 -287.62214) (xy 55.633257 -287.661484)
			(xy 55.656128 -287.705061) (xy 55.671712 -287.751742) (xy 55.679607 -287.800319) (xy 55.680102 -287.824926)
			(xy 56.01895 -287.824926) (xy 56.02291 -287.775872) (xy 56.034687 -287.728088) (xy 56.053978 -287.682812)
			(xy 56.080281 -287.641216) (xy 56.112916 -287.604379) (xy 56.151037 -287.573254) (xy 56.193658 -287.548647)
			(xy 56.239674 -287.531195) (xy 56.287893 -287.521351) (xy 56.337068 -287.51937) (xy 56.385923 -287.525302)
			(xy 56.433194 -287.538994) (xy 56.477656 -287.560092) (xy 56.518159 -287.588048) (xy 56.553652 -287.62214)
			(xy 56.583217 -287.661484) (xy 56.606088 -287.705061) (xy 56.621672 -287.751742) (xy 56.629567 -287.800319)
			(xy 56.630062 -287.824926) (xy 56.969164 -287.824926) (xy 56.973124 -287.775872) (xy 56.984901 -287.728088)
			(xy 57.004192 -287.682812) (xy 57.030495 -287.641216) (xy 57.06313 -287.604379) (xy 57.101251 -287.573254)
			(xy 57.143872 -287.548647) (xy 57.189888 -287.531195) (xy 57.238107 -287.521351) (xy 57.287282 -287.51937)
			(xy 57.336137 -287.525302) (xy 57.383408 -287.538994) (xy 57.42787 -287.560092) (xy 57.468373 -287.588048)
			(xy 57.503866 -287.62214) (xy 57.533431 -287.661484) (xy 57.553624 -287.699958) (xy 57.944016 -287.699958)
			(xy 57.947976 -287.650904) (xy 57.959753 -287.60312) (xy 57.979044 -287.557844) (xy 58.005347 -287.516248)
			(xy 58.037982 -287.479411) (xy 58.076103 -287.448286) (xy 58.118724 -287.423679) (xy 58.16474 -287.406227)
			(xy 58.212959 -287.396383) (xy 58.262134 -287.394402) (xy 58.310989 -287.400334) (xy 58.35826 -287.414026)
			(xy 58.402722 -287.435124) (xy 58.443225 -287.46308) (xy 58.478718 -287.497172) (xy 58.508283 -287.536516)
			(xy 58.531154 -287.580093) (xy 58.546738 -287.626774) (xy 58.554633 -287.675351) (xy 58.555128 -287.699958)
			(xy 58.554633 -287.724565) (xy 58.546738 -287.773142) (xy 58.531154 -287.819823) (xy 58.508283 -287.8634)
			(xy 58.480888 -287.899856) (xy 59.819044 -287.899856) (xy 59.823004 -287.850802) (xy 59.834781 -287.803018)
			(xy 59.854072 -287.757742) (xy 59.880375 -287.716146) (xy 59.91301 -287.679309) (xy 59.951131 -287.648184)
			(xy 59.993752 -287.623577) (xy 60.039768 -287.606125) (xy 60.087987 -287.596281) (xy 60.137162 -287.5943)
			(xy 60.186017 -287.600232) (xy 60.233288 -287.613924) (xy 60.27775 -287.635022) (xy 60.318253 -287.662978)
			(xy 60.353746 -287.69707) (xy 60.383311 -287.736414) (xy 60.406182 -287.779991) (xy 60.421183 -287.824926)
			(xy 60.769004 -287.824926) (xy 60.772964 -287.775872) (xy 60.784741 -287.728088) (xy 60.804032 -287.682812)
			(xy 60.830335 -287.641216) (xy 60.86297 -287.604379) (xy 60.901091 -287.573254) (xy 60.943712 -287.548647)
			(xy 60.989728 -287.531195) (xy 61.037947 -287.521351) (xy 61.087122 -287.51937) (xy 61.135977 -287.525302)
			(xy 61.183248 -287.538994) (xy 61.22771 -287.560092) (xy 61.268213 -287.588048) (xy 61.303706 -287.62214)
			(xy 61.333271 -287.661484) (xy 61.356142 -287.705061) (xy 61.371726 -287.751742) (xy 61.379621 -287.800319)
			(xy 61.380116 -287.824926) (xy 61.718964 -287.824926) (xy 61.722924 -287.775872) (xy 61.734701 -287.728088)
			(xy 61.753992 -287.682812) (xy 61.780295 -287.641216) (xy 61.81293 -287.604379) (xy 61.851051 -287.573254)
			(xy 61.893672 -287.548647) (xy 61.939688 -287.531195) (xy 61.987907 -287.521351) (xy 62.037082 -287.51937)
			(xy 62.085937 -287.525302) (xy 62.133208 -287.538994) (xy 62.17767 -287.560092) (xy 62.218173 -287.588048)
			(xy 62.253666 -287.62214) (xy 62.283231 -287.661484) (xy 62.306102 -287.705061) (xy 62.321686 -287.751742)
			(xy 62.329581 -287.800319) (xy 62.330076 -287.824926) (xy 62.669178 -287.824926) (xy 62.673138 -287.775872)
			(xy 62.684915 -287.728088) (xy 62.704206 -287.682812) (xy 62.730509 -287.641216) (xy 62.763144 -287.604379)
			(xy 62.801265 -287.573254) (xy 62.843886 -287.548647) (xy 62.889902 -287.531195) (xy 62.938121 -287.521351)
			(xy 62.987296 -287.51937) (xy 63.036151 -287.525302) (xy 63.083422 -287.538994) (xy 63.127884 -287.560092)
			(xy 63.168387 -287.588048) (xy 63.20388 -287.62214) (xy 63.233445 -287.661484) (xy 63.256316 -287.705061)
			(xy 63.2719 -287.751742) (xy 63.279795 -287.800319) (xy 63.28029 -287.824926) (xy 63.619138 -287.824926)
			(xy 63.623098 -287.775872) (xy 63.634875 -287.728088) (xy 63.654166 -287.682812) (xy 63.680469 -287.641216)
			(xy 63.713104 -287.604379) (xy 63.751225 -287.573254) (xy 63.793846 -287.548647) (xy 63.839862 -287.531195)
			(xy 63.888081 -287.521351) (xy 63.937256 -287.51937) (xy 63.986111 -287.525302) (xy 64.033382 -287.538994)
			(xy 64.077844 -287.560092) (xy 64.118347 -287.588048) (xy 64.15384 -287.62214) (xy 64.183405 -287.661484)
			(xy 64.206276 -287.705061) (xy 64.22186 -287.751742) (xy 64.229755 -287.800319) (xy 64.23025 -287.824926)
			(xy 64.569098 -287.824926) (xy 64.573058 -287.775872) (xy 64.584835 -287.728088) (xy 64.604126 -287.682812)
			(xy 64.630429 -287.641216) (xy 64.663064 -287.604379) (xy 64.701185 -287.573254) (xy 64.743806 -287.548647)
			(xy 64.789822 -287.531195) (xy 64.838041 -287.521351) (xy 64.887216 -287.51937) (xy 64.936071 -287.525302)
			(xy 64.983342 -287.538994) (xy 65.027804 -287.560092) (xy 65.068307 -287.588048) (xy 65.1038 -287.62214)
			(xy 65.133365 -287.661484) (xy 65.156236 -287.705061) (xy 65.17182 -287.751742) (xy 65.179715 -287.800319)
			(xy 65.18021 -287.824926) (xy 65.519058 -287.824926) (xy 65.523018 -287.775872) (xy 65.534795 -287.728088)
			(xy 65.554086 -287.682812) (xy 65.580389 -287.641216) (xy 65.613024 -287.604379) (xy 65.651145 -287.573254)
			(xy 65.693766 -287.548647) (xy 65.739782 -287.531195) (xy 65.788001 -287.521351) (xy 65.837176 -287.51937)
			(xy 65.886031 -287.525302) (xy 65.933302 -287.538994) (xy 65.977764 -287.560092) (xy 66.018267 -287.588048)
			(xy 66.05376 -287.62214) (xy 66.083325 -287.661484) (xy 66.106196 -287.705061) (xy 66.12178 -287.751742)
			(xy 66.129675 -287.800319) (xy 66.13017 -287.824926) (xy 66.469018 -287.824926) (xy 66.472978 -287.775872)
			(xy 66.484755 -287.728088) (xy 66.504046 -287.682812) (xy 66.530349 -287.641216) (xy 66.562984 -287.604379)
			(xy 66.601105 -287.573254) (xy 66.643726 -287.548647) (xy 66.689742 -287.531195) (xy 66.737961 -287.521351)
			(xy 66.787136 -287.51937) (xy 66.835991 -287.525302) (xy 66.883262 -287.538994) (xy 66.927724 -287.560092)
			(xy 66.968227 -287.588048) (xy 67.00372 -287.62214) (xy 67.033285 -287.661484) (xy 67.056156 -287.705061)
			(xy 67.07174 -287.751742) (xy 67.079635 -287.800319) (xy 67.08013 -287.824926) (xy 67.418978 -287.824926)
			(xy 67.422938 -287.775872) (xy 67.434715 -287.728088) (xy 67.454006 -287.682812) (xy 67.480309 -287.641216)
			(xy 67.512944 -287.604379) (xy 67.551065 -287.573254) (xy 67.593686 -287.548647) (xy 67.639702 -287.531195)
			(xy 67.687921 -287.521351) (xy 67.737096 -287.51937) (xy 67.785951 -287.525302) (xy 67.833222 -287.538994)
			(xy 67.877684 -287.560092) (xy 67.918187 -287.588048) (xy 67.95368 -287.62214) (xy 67.983245 -287.661484)
			(xy 68.006116 -287.705061) (xy 68.0217 -287.751742) (xy 68.029595 -287.800319) (xy 68.03009 -287.824926)
			(xy 68.368938 -287.824926) (xy 68.372898 -287.775872) (xy 68.384675 -287.728088) (xy 68.403966 -287.682812)
			(xy 68.430269 -287.641216) (xy 68.462904 -287.604379) (xy 68.501025 -287.573254) (xy 68.543646 -287.548647)
			(xy 68.589662 -287.531195) (xy 68.637881 -287.521351) (xy 68.687056 -287.51937) (xy 68.735911 -287.525302)
			(xy 68.783182 -287.538994) (xy 68.827644 -287.560092) (xy 68.868147 -287.588048) (xy 68.90364 -287.62214)
			(xy 68.933205 -287.661484) (xy 68.956076 -287.705061) (xy 68.97166 -287.751742) (xy 68.979555 -287.800319)
			(xy 68.98005 -287.824926) (xy 70.269112 -287.824926) (xy 70.273072 -287.775872) (xy 70.284849 -287.728088)
			(xy 70.30414 -287.682812) (xy 70.330443 -287.641216) (xy 70.363078 -287.604379) (xy 70.401199 -287.573254)
			(xy 70.44382 -287.548647) (xy 70.489836 -287.531195) (xy 70.538055 -287.521351) (xy 70.58723 -287.51937)
			(xy 70.636085 -287.525302) (xy 70.683356 -287.538994) (xy 70.727818 -287.560092) (xy 70.768321 -287.588048)
			(xy 70.803814 -287.62214) (xy 70.833379 -287.661484) (xy 70.85625 -287.705061) (xy 70.871834 -287.751742)
			(xy 70.879729 -287.800319) (xy 70.880224 -287.824926) (xy 70.879729 -287.849533) (xy 70.871834 -287.89811)
			(xy 70.85625 -287.944791) (xy 70.833379 -287.988368) (xy 70.803814 -288.027712) (xy 70.768321 -288.061804)
			(xy 70.727818 -288.08976) (xy 70.683356 -288.110858) (xy 70.636085 -288.12455) (xy 70.58723 -288.130482)
			(xy 70.538055 -288.128501) (xy 70.489836 -288.118657) (xy 70.44382 -288.101205) (xy 70.401199 -288.076598)
			(xy 70.363078 -288.045473) (xy 70.330443 -288.008636) (xy 70.30414 -287.96704) (xy 70.284849 -287.921764)
			(xy 70.273072 -287.87398) (xy 70.269112 -287.824926) (xy 68.98005 -287.824926) (xy 68.979555 -287.849533)
			(xy 68.97166 -287.89811) (xy 68.956076 -287.944791) (xy 68.933205 -287.988368) (xy 68.90364 -288.027712)
			(xy 68.868147 -288.061804) (xy 68.827644 -288.08976) (xy 68.783182 -288.110858) (xy 68.735911 -288.12455)
			(xy 68.687056 -288.130482) (xy 68.637881 -288.128501) (xy 68.589662 -288.118657) (xy 68.543646 -288.101205)
			(xy 68.501025 -288.076598) (xy 68.462904 -288.045473) (xy 68.430269 -288.008636) (xy 68.403966 -287.96704)
			(xy 68.384675 -287.921764) (xy 68.372898 -287.87398) (xy 68.368938 -287.824926) (xy 68.03009 -287.824926)
			(xy 68.029595 -287.849533) (xy 68.0217 -287.89811) (xy 68.006116 -287.944791) (xy 67.983245 -287.988368)
			(xy 67.95368 -288.027712) (xy 67.918187 -288.061804) (xy 67.877684 -288.08976) (xy 67.833222 -288.110858)
			(xy 67.785951 -288.12455) (xy 67.737096 -288.130482) (xy 67.687921 -288.128501) (xy 67.639702 -288.118657)
			(xy 67.593686 -288.101205) (xy 67.551065 -288.076598) (xy 67.512944 -288.045473) (xy 67.480309 -288.008636)
			(xy 67.454006 -287.96704) (xy 67.434715 -287.921764) (xy 67.422938 -287.87398) (xy 67.418978 -287.824926)
			(xy 67.08013 -287.824926) (xy 67.079635 -287.849533) (xy 67.07174 -287.89811) (xy 67.056156 -287.944791)
			(xy 67.033285 -287.988368) (xy 67.00372 -288.027712) (xy 66.968227 -288.061804) (xy 66.927724 -288.08976)
			(xy 66.883262 -288.110858) (xy 66.835991 -288.12455) (xy 66.787136 -288.130482) (xy 66.737961 -288.128501)
			(xy 66.689742 -288.118657) (xy 66.643726 -288.101205) (xy 66.601105 -288.076598) (xy 66.562984 -288.045473)
			(xy 66.530349 -288.008636) (xy 66.504046 -287.96704) (xy 66.484755 -287.921764) (xy 66.472978 -287.87398)
			(xy 66.469018 -287.824926) (xy 66.13017 -287.824926) (xy 66.129675 -287.849533) (xy 66.12178 -287.89811)
			(xy 66.106196 -287.944791) (xy 66.083325 -287.988368) (xy 66.05376 -288.027712) (xy 66.018267 -288.061804)
			(xy 65.977764 -288.08976) (xy 65.933302 -288.110858) (xy 65.886031 -288.12455) (xy 65.837176 -288.130482)
			(xy 65.788001 -288.128501) (xy 65.739782 -288.118657) (xy 65.693766 -288.101205) (xy 65.651145 -288.076598)
			(xy 65.613024 -288.045473) (xy 65.580389 -288.008636) (xy 65.554086 -287.96704) (xy 65.534795 -287.921764)
			(xy 65.523018 -287.87398) (xy 65.519058 -287.824926) (xy 65.18021 -287.824926) (xy 65.179715 -287.849533)
			(xy 65.17182 -287.89811) (xy 65.156236 -287.944791) (xy 65.133365 -287.988368) (xy 65.1038 -288.027712)
			(xy 65.068307 -288.061804) (xy 65.027804 -288.08976) (xy 64.983342 -288.110858) (xy 64.936071 -288.12455)
			(xy 64.887216 -288.130482) (xy 64.838041 -288.128501) (xy 64.789822 -288.118657) (xy 64.743806 -288.101205)
			(xy 64.701185 -288.076598) (xy 64.663064 -288.045473) (xy 64.630429 -288.008636) (xy 64.604126 -287.96704)
			(xy 64.584835 -287.921764) (xy 64.573058 -287.87398) (xy 64.569098 -287.824926) (xy 64.23025 -287.824926)
			(xy 64.229755 -287.849533) (xy 64.22186 -287.89811) (xy 64.206276 -287.944791) (xy 64.183405 -287.988368)
			(xy 64.15384 -288.027712) (xy 64.118347 -288.061804) (xy 64.077844 -288.08976) (xy 64.033382 -288.110858)
			(xy 63.986111 -288.12455) (xy 63.937256 -288.130482) (xy 63.888081 -288.128501) (xy 63.839862 -288.118657)
			(xy 63.793846 -288.101205) (xy 63.751225 -288.076598) (xy 63.713104 -288.045473) (xy 63.680469 -288.008636)
			(xy 63.654166 -287.96704) (xy 63.634875 -287.921764) (xy 63.623098 -287.87398) (xy 63.619138 -287.824926)
			(xy 63.28029 -287.824926) (xy 63.279795 -287.849533) (xy 63.2719 -287.89811) (xy 63.256316 -287.944791)
			(xy 63.233445 -287.988368) (xy 63.20388 -288.027712) (xy 63.168387 -288.061804) (xy 63.127884 -288.08976)
			(xy 63.083422 -288.110858) (xy 63.036151 -288.12455) (xy 62.987296 -288.130482) (xy 62.938121 -288.128501)
			(xy 62.889902 -288.118657) (xy 62.843886 -288.101205) (xy 62.801265 -288.076598) (xy 62.763144 -288.045473)
			(xy 62.730509 -288.008636) (xy 62.704206 -287.96704) (xy 62.684915 -287.921764) (xy 62.673138 -287.87398)
			(xy 62.669178 -287.824926) (xy 62.330076 -287.824926) (xy 62.329581 -287.849533) (xy 62.321686 -287.89811)
			(xy 62.306102 -287.944791) (xy 62.283231 -287.988368) (xy 62.253666 -288.027712) (xy 62.218173 -288.061804)
			(xy 62.17767 -288.08976) (xy 62.133208 -288.110858) (xy 62.085937 -288.12455) (xy 62.037082 -288.130482)
			(xy 61.987907 -288.128501) (xy 61.939688 -288.118657) (xy 61.893672 -288.101205) (xy 61.851051 -288.076598)
			(xy 61.81293 -288.045473) (xy 61.780295 -288.008636) (xy 61.753992 -287.96704) (xy 61.734701 -287.921764)
			(xy 61.722924 -287.87398) (xy 61.718964 -287.824926) (xy 61.380116 -287.824926) (xy 61.379621 -287.849533)
			(xy 61.371726 -287.89811) (xy 61.356142 -287.944791) (xy 61.333271 -287.988368) (xy 61.303706 -288.027712)
			(xy 61.268213 -288.061804) (xy 61.22771 -288.08976) (xy 61.183248 -288.110858) (xy 61.135977 -288.12455)
			(xy 61.087122 -288.130482) (xy 61.037947 -288.128501) (xy 60.989728 -288.118657) (xy 60.943712 -288.101205)
			(xy 60.901091 -288.076598) (xy 60.86297 -288.045473) (xy 60.830335 -288.008636) (xy 60.804032 -287.96704)
			(xy 60.784741 -287.921764) (xy 60.772964 -287.87398) (xy 60.769004 -287.824926) (xy 60.421183 -287.824926)
			(xy 60.421766 -287.826672) (xy 60.429661 -287.875249) (xy 60.430156 -287.899856) (xy 60.429661 -287.924463)
			(xy 60.421766 -287.97304) (xy 60.406182 -288.019721) (xy 60.383311 -288.063298) (xy 60.353746 -288.102642)
			(xy 60.318253 -288.136734) (xy 60.27775 -288.16469) (xy 60.233288 -288.185788) (xy 60.186017 -288.19948)
			(xy 60.137162 -288.205412) (xy 60.087987 -288.203431) (xy 60.039768 -288.193587) (xy 59.993752 -288.176135)
			(xy 59.951131 -288.151528) (xy 59.91301 -288.120403) (xy 59.880375 -288.083566) (xy 59.854072 -288.04197)
			(xy 59.834781 -287.996694) (xy 59.823004 -287.94891) (xy 59.819044 -287.899856) (xy 58.480888 -287.899856)
			(xy 58.478718 -287.902744) (xy 58.443225 -287.936836) (xy 58.402722 -287.964792) (xy 58.35826 -287.98589)
			(xy 58.310989 -287.999582) (xy 58.262134 -288.005514) (xy 58.212959 -288.003533) (xy 58.16474 -287.993689)
			(xy 58.118724 -287.976237) (xy 58.076103 -287.95163) (xy 58.037982 -287.920505) (xy 58.005347 -287.883668)
			(xy 57.979044 -287.842072) (xy 57.959753 -287.796796) (xy 57.947976 -287.749012) (xy 57.944016 -287.699958)
			(xy 57.553624 -287.699958) (xy 57.556302 -287.705061) (xy 57.571886 -287.751742) (xy 57.579781 -287.800319)
			(xy 57.580276 -287.824926) (xy 57.579781 -287.849533) (xy 57.571886 -287.89811) (xy 57.556302 -287.944791)
			(xy 57.533431 -287.988368) (xy 57.503866 -288.027712) (xy 57.468373 -288.061804) (xy 57.42787 -288.08976)
			(xy 57.383408 -288.110858) (xy 57.336137 -288.12455) (xy 57.287282 -288.130482) (xy 57.238107 -288.128501)
			(xy 57.189888 -288.118657) (xy 57.143872 -288.101205) (xy 57.101251 -288.076598) (xy 57.06313 -288.045473)
			(xy 57.030495 -288.008636) (xy 57.004192 -287.96704) (xy 56.984901 -287.921764) (xy 56.973124 -287.87398)
			(xy 56.969164 -287.824926) (xy 56.630062 -287.824926) (xy 56.629567 -287.849533) (xy 56.621672 -287.89811)
			(xy 56.606088 -287.944791) (xy 56.583217 -287.988368) (xy 56.553652 -288.027712) (xy 56.518159 -288.061804)
			(xy 56.477656 -288.08976) (xy 56.433194 -288.110858) (xy 56.385923 -288.12455) (xy 56.337068 -288.130482)
			(xy 56.287893 -288.128501) (xy 56.239674 -288.118657) (xy 56.193658 -288.101205) (xy 56.151037 -288.076598)
			(xy 56.112916 -288.045473) (xy 56.080281 -288.008636) (xy 56.053978 -287.96704) (xy 56.034687 -287.921764)
			(xy 56.02291 -287.87398) (xy 56.01895 -287.824926) (xy 55.680102 -287.824926) (xy 55.679607 -287.849533)
			(xy 55.671712 -287.89811) (xy 55.656128 -287.944791) (xy 55.633257 -287.988368) (xy 55.603692 -288.027712)
			(xy 55.568199 -288.061804) (xy 55.527696 -288.08976) (xy 55.483234 -288.110858) (xy 55.435963 -288.12455)
			(xy 55.387108 -288.130482) (xy 55.337933 -288.128501) (xy 55.289714 -288.118657) (xy 55.243698 -288.101205)
			(xy 55.201077 -288.076598) (xy 55.162956 -288.045473) (xy 55.130321 -288.008636) (xy 55.104018 -287.96704)
			(xy 55.084727 -287.921764) (xy 55.07295 -287.87398) (xy 55.06899 -287.824926) (xy 54.730142 -287.824926)
			(xy 54.729647 -287.849533) (xy 54.721752 -287.89811) (xy 54.706168 -287.944791) (xy 54.683297 -287.988368)
			(xy 54.653732 -288.027712) (xy 54.618239 -288.061804) (xy 54.577736 -288.08976) (xy 54.533274 -288.110858)
			(xy 54.486003 -288.12455) (xy 54.437148 -288.130482) (xy 54.387973 -288.128501) (xy 54.339754 -288.118657)
			(xy 54.293738 -288.101205) (xy 54.251117 -288.076598) (xy 54.212996 -288.045473) (xy 54.180361 -288.008636)
			(xy 54.154058 -287.96704) (xy 54.134767 -287.921764) (xy 54.12299 -287.87398) (xy 54.11903 -287.824926)
			(xy 53.780182 -287.824926) (xy 53.779687 -287.849533) (xy 53.771792 -287.89811) (xy 53.756208 -287.944791)
			(xy 53.733337 -287.988368) (xy 53.703772 -288.027712) (xy 53.668279 -288.061804) (xy 53.627776 -288.08976)
			(xy 53.583314 -288.110858) (xy 53.536043 -288.12455) (xy 53.487188 -288.130482) (xy 53.438013 -288.128501)
			(xy 53.389794 -288.118657) (xy 53.343778 -288.101205) (xy 53.301157 -288.076598) (xy 53.263036 -288.045473)
			(xy 53.230401 -288.008636) (xy 53.204098 -287.96704) (xy 53.184807 -287.921764) (xy 53.17303 -287.87398)
			(xy 53.16907 -287.824926) (xy 52.830222 -287.824926) (xy 52.829727 -287.849533) (xy 52.821832 -287.89811)
			(xy 52.806248 -287.944791) (xy 52.783377 -287.988368) (xy 52.753812 -288.027712) (xy 52.718319 -288.061804)
			(xy 52.677816 -288.08976) (xy 52.633354 -288.110858) (xy 52.586083 -288.12455) (xy 52.537228 -288.130482)
			(xy 52.488053 -288.128501) (xy 52.439834 -288.118657) (xy 52.393818 -288.101205) (xy 52.351197 -288.076598)
			(xy 52.313076 -288.045473) (xy 52.280441 -288.008636) (xy 52.254138 -287.96704) (xy 52.234847 -287.921764)
			(xy 52.22307 -287.87398) (xy 52.21911 -287.824926) (xy 51.880262 -287.824926) (xy 51.879767 -287.849533)
			(xy 51.871872 -287.89811) (xy 51.856288 -287.944791) (xy 51.833417 -287.988368) (xy 51.803852 -288.027712)
			(xy 51.768359 -288.061804) (xy 51.727856 -288.08976) (xy 51.683394 -288.110858) (xy 51.636123 -288.12455)
			(xy 51.587268 -288.130482) (xy 51.538093 -288.128501) (xy 51.489874 -288.118657) (xy 51.443858 -288.101205)
			(xy 51.401237 -288.076598) (xy 51.363116 -288.045473) (xy 51.330481 -288.008636) (xy 51.304178 -287.96704)
			(xy 51.284887 -287.921764) (xy 51.27311 -287.87398) (xy 51.26915 -287.824926) (xy 50.930302 -287.824926)
			(xy 50.929807 -287.849533) (xy 50.921912 -287.89811) (xy 50.906328 -287.944791) (xy 50.883457 -287.988368)
			(xy 50.853892 -288.027712) (xy 50.818399 -288.061804) (xy 50.777896 -288.08976) (xy 50.733434 -288.110858)
			(xy 50.686163 -288.12455) (xy 50.637308 -288.130482) (xy 50.588133 -288.128501) (xy 50.539914 -288.118657)
			(xy 50.493898 -288.101205) (xy 50.451277 -288.076598) (xy 50.413156 -288.045473) (xy 50.380521 -288.008636)
			(xy 50.354218 -287.96704) (xy 50.334927 -287.921764) (xy 50.32315 -287.87398) (xy 50.31919 -287.824926)
			(xy 49.980088 -287.824926) (xy 49.979593 -287.849533) (xy 49.971698 -287.89811) (xy 49.956114 -287.944791)
			(xy 49.933243 -287.988368) (xy 49.903678 -288.027712) (xy 49.868185 -288.061804) (xy 49.827682 -288.08976)
			(xy 49.78322 -288.110858) (xy 49.735949 -288.12455) (xy 49.687094 -288.130482) (xy 49.637919 -288.128501)
			(xy 49.5897 -288.118657) (xy 49.543684 -288.101205) (xy 49.501063 -288.076598) (xy 49.462942 -288.045473)
			(xy 49.430307 -288.008636) (xy 49.404004 -287.96704) (xy 49.384713 -287.921764) (xy 49.372936 -287.87398)
			(xy 49.368976 -287.824926) (xy 49.030128 -287.824926) (xy 49.029633 -287.849533) (xy 49.021738 -287.89811)
			(xy 49.006154 -287.944791) (xy 48.983283 -287.988368) (xy 48.953718 -288.027712) (xy 48.918225 -288.061804)
			(xy 48.877722 -288.08976) (xy 48.83326 -288.110858) (xy 48.785989 -288.12455) (xy 48.737134 -288.130482)
			(xy 48.687959 -288.128501) (xy 48.63974 -288.118657) (xy 48.593724 -288.101205) (xy 48.551103 -288.076598)
			(xy 48.512982 -288.045473) (xy 48.480347 -288.008636) (xy 48.454044 -287.96704) (xy 48.434753 -287.921764)
			(xy 48.422976 -287.87398) (xy 48.419016 -287.824926) (xy 48.080168 -287.824926) (xy 48.079673 -287.849533)
			(xy 48.071778 -287.89811) (xy 48.056194 -287.944791) (xy 48.033323 -287.988368) (xy 48.003758 -288.027712)
			(xy 47.968265 -288.061804) (xy 47.927762 -288.08976) (xy 47.8833 -288.110858) (xy 47.836029 -288.12455)
			(xy 47.787174 -288.130482) (xy 47.737999 -288.128501) (xy 47.68978 -288.118657) (xy 47.643764 -288.101205)
			(xy 47.601143 -288.076598) (xy 47.563022 -288.045473) (xy 47.530387 -288.008636) (xy 47.504084 -287.96704)
			(xy 47.484793 -287.921764) (xy 47.473016 -287.87398) (xy 47.469056 -287.824926) (xy 47.130208 -287.824926)
			(xy 47.129713 -287.849533) (xy 47.121818 -287.89811) (xy 47.106234 -287.944791) (xy 47.083363 -287.988368)
			(xy 47.053798 -288.027712) (xy 47.018305 -288.061804) (xy 46.977802 -288.08976) (xy 46.93334 -288.110858)
			(xy 46.886069 -288.12455) (xy 46.837214 -288.130482) (xy 46.788039 -288.128501) (xy 46.73982 -288.118657)
			(xy 46.693804 -288.101205) (xy 46.651183 -288.076598) (xy 46.613062 -288.045473) (xy 46.580427 -288.008636)
			(xy 46.554124 -287.96704) (xy 46.534833 -287.921764) (xy 46.523056 -287.87398) (xy 46.519096 -287.824926)
			(xy 46.180248 -287.824926) (xy 46.179753 -287.849533) (xy 46.171858 -287.89811) (xy 46.156274 -287.944791)
			(xy 46.133403 -287.988368) (xy 46.103838 -288.027712) (xy 46.068345 -288.061804) (xy 46.027842 -288.08976)
			(xy 45.98338 -288.110858) (xy 45.936109 -288.12455) (xy 45.887254 -288.130482) (xy 45.838079 -288.128501)
			(xy 45.78986 -288.118657) (xy 45.743844 -288.101205) (xy 45.701223 -288.076598) (xy 45.663102 -288.045473)
			(xy 45.630467 -288.008636) (xy 45.604164 -287.96704) (xy 45.584873 -287.921764) (xy 45.573096 -287.87398)
			(xy 45.569136 -287.824926) (xy 45.230288 -287.824926) (xy 45.229793 -287.849533) (xy 45.221898 -287.89811)
			(xy 45.206314 -287.944791) (xy 45.183443 -287.988368) (xy 45.153878 -288.027712) (xy 45.118385 -288.061804)
			(xy 45.077882 -288.08976) (xy 45.03342 -288.110858) (xy 44.986149 -288.12455) (xy 44.937294 -288.130482)
			(xy 44.888119 -288.128501) (xy 44.8399 -288.118657) (xy 44.793884 -288.101205) (xy 44.751263 -288.076598)
			(xy 44.713142 -288.045473) (xy 44.680507 -288.008636) (xy 44.654204 -287.96704) (xy 44.634913 -287.921764)
			(xy 44.623136 -287.87398) (xy 44.619176 -287.824926) (xy 44.280074 -287.824926) (xy 44.279579 -287.849533)
			(xy 44.271684 -287.89811) (xy 44.2561 -287.944791) (xy 44.233229 -287.988368) (xy 44.203664 -288.027712)
			(xy 44.168171 -288.061804) (xy 44.127668 -288.08976) (xy 44.083206 -288.110858) (xy 44.035935 -288.12455)
			(xy 43.98708 -288.130482) (xy 43.937905 -288.128501) (xy 43.889686 -288.118657) (xy 43.84367 -288.101205)
			(xy 43.801049 -288.076598) (xy 43.762928 -288.045473) (xy 43.730293 -288.008636) (xy 43.70399 -287.96704)
			(xy 43.684699 -287.921764) (xy 43.672922 -287.87398) (xy 43.668962 -287.824926) (xy 43.330114 -287.824926)
			(xy 43.329619 -287.849533) (xy 43.321724 -287.89811) (xy 43.30614 -287.944791) (xy 43.283269 -287.988368)
			(xy 43.253704 -288.027712) (xy 43.218211 -288.061804) (xy 43.177708 -288.08976) (xy 43.133246 -288.110858)
			(xy 43.085975 -288.12455) (xy 43.03712 -288.130482) (xy 42.987945 -288.128501) (xy 42.939726 -288.118657)
			(xy 42.89371 -288.101205) (xy 42.851089 -288.076598) (xy 42.812968 -288.045473) (xy 42.780333 -288.008636)
			(xy 42.75403 -287.96704) (xy 42.734739 -287.921764) (xy 42.722962 -287.87398) (xy 42.719002 -287.824926)
			(xy 42.40527 -287.824926) (xy 42.40527 -287.850406) (xy 42.397134 -287.901778) (xy 42.381063 -287.951246)
			(xy 42.357451 -287.99759) (xy 42.326882 -288.039671) (xy 42.290106 -288.076452) (xy 42.248029 -288.107027)
			(xy 42.201688 -288.130645) (xy 42.152223 -288.146723) (xy 42.100852 -288.154866) (xy 42.074846 -288.15538)
			(xy 41.124886 -288.15538) (xy 41.098881 -288.154833) (xy 41.047512 -288.146695) (xy 40.998048 -288.130621)
			(xy 40.951707 -288.107008) (xy 40.909631 -288.076436) (xy 40.872855 -288.039658) (xy 40.842285 -287.997581)
			(xy 40.818674 -287.951239) (xy 40.802602 -287.901775) (xy 40.794466 -287.850405) (xy 40.479597 -287.850405)
			(xy 40.471844 -287.89811) (xy 40.45626 -287.944791) (xy 40.433389 -287.988368) (xy 40.403824 -288.027712)
			(xy 40.368331 -288.061804) (xy 40.327828 -288.08976) (xy 40.283366 -288.110858) (xy 40.236095 -288.12455)
			(xy 40.18724 -288.130482) (xy 40.138065 -288.128501) (xy 40.089846 -288.118657) (xy 40.04383 -288.101205)
			(xy 40.001209 -288.076598) (xy 39.963088 -288.045473) (xy 39.930453 -288.008636) (xy 39.90415 -287.96704)
			(xy 39.884859 -287.921764) (xy 39.873082 -287.87398) (xy 39.869122 -287.824926) (xy 39.555496 -287.824926)
			(xy 39.555496 -287.850412) (xy 39.547357 -287.901796) (xy 39.53128 -287.951275) (xy 39.50766 -287.997628)
			(xy 39.477079 -288.039716) (xy 39.44029 -288.076501) (xy 39.398199 -288.107078) (xy 39.351843 -288.130693)
			(xy 39.302363 -288.146765) (xy 39.250978 -288.154899) (xy 39.224966 -288.15538) (xy 38.275006 -288.15538)
			(xy 38.248998 -288.154861) (xy 38.197622 -288.146725) (xy 38.148151 -288.130652) (xy 38.101804 -288.107037)
			(xy 38.059722 -288.076463) (xy 38.02294 -288.039683) (xy 37.992366 -287.997601) (xy 37.968751 -287.951254)
			(xy 37.952677 -287.901784) (xy 37.944539 -287.850408) (xy 37.629463 -287.850408) (xy 37.62171 -287.89811)
			(xy 37.606126 -287.944791) (xy 37.583255 -287.988368) (xy 37.55369 -288.027712) (xy 37.518197 -288.061804)
			(xy 37.477694 -288.08976) (xy 37.433232 -288.110858) (xy 37.385961 -288.12455) (xy 37.337106 -288.130482)
			(xy 37.287931 -288.128501) (xy 37.239712 -288.118657) (xy 37.193696 -288.101205) (xy 37.151075 -288.076598)
			(xy 37.112954 -288.045473) (xy 37.080319 -288.008636) (xy 37.054016 -287.96704) (xy 37.034725 -287.921764)
			(xy 37.022948 -287.87398) (xy 37.018988 -287.824926) (xy 36.68014 -287.824926) (xy 36.679645 -287.849533)
			(xy 36.67175 -287.89811) (xy 36.656166 -287.944791) (xy 36.633295 -287.988368) (xy 36.60373 -288.027712)
			(xy 36.568237 -288.061804) (xy 36.527734 -288.08976) (xy 36.483272 -288.110858) (xy 36.436001 -288.12455)
			(xy 36.387146 -288.130482) (xy 36.337971 -288.128501) (xy 36.289752 -288.118657) (xy 36.243736 -288.101205)
			(xy 36.201115 -288.076598) (xy 36.162994 -288.045473) (xy 36.130359 -288.008636) (xy 36.104056 -287.96704)
			(xy 36.084765 -287.921764) (xy 36.072988 -287.87398) (xy 36.069028 -287.824926) (xy 15.064266 -287.824926)
			(xy 15.07913 -287.875546) (xy 15.086887 -287.929497) (xy 15.086887 -287.984003) (xy 15.07913 -288.037954)
			(xy 15.063773 -288.090253) (xy 15.041131 -288.139833) (xy 15.011662 -288.185687) (xy 14.975968 -288.22688)
			(xy 14.972303 -288.230056) (xy 25.811478 -288.230056) (xy 25.815549 -288.174434) (xy 25.827675 -288.119997)
			(xy 25.847598 -288.067906) (xy 25.874894 -288.019271) (xy 25.90898 -287.975128) (xy 25.949129 -287.936419)
			(xy 25.994487 -287.903968) (xy 26.044087 -287.878467) (xy 26.096871 -287.86046) (xy 26.151714 -287.85033)
			(xy 26.207448 -287.848293) (xy 26.262885 -287.854393) (xy 26.316842 -287.868499) (xy 26.368171 -287.890311)
			(xy 26.415777 -287.919365) (xy 26.458645 -287.95504) (xy 26.495862 -287.996577) (xy 26.526635 -288.04309)
			(xy 26.550307 -288.093587) (xy 26.566375 -288.146994) (xy 26.574495 -288.20217) (xy 26.575004 -288.230056)
			(xy 27.296616 -288.230056) (xy 27.300687 -288.174434) (xy 27.312813 -288.119997) (xy 27.332736 -288.067906)
			(xy 27.360032 -288.019271) (xy 27.394118 -287.975128) (xy 27.434267 -287.936419) (xy 27.479625 -287.903968)
			(xy 27.529225 -287.878467) (xy 27.582009 -287.86046) (xy 27.636852 -287.85033) (xy 27.692586 -287.848293)
			(xy 27.748023 -287.854393) (xy 27.80198 -287.868499) (xy 27.853309 -287.890311) (xy 27.900915 -287.919365)
			(xy 27.943783 -287.95504) (xy 27.981 -287.996577) (xy 28.011773 -288.04309) (xy 28.035445 -288.093587)
			(xy 28.051513 -288.146994) (xy 28.059633 -288.20217) (xy 28.060142 -288.230056) (xy 28.059633 -288.257942)
			(xy 28.053457 -288.299906) (xy 73.593972 -288.299906) (xy 73.597932 -288.250852) (xy 73.609709 -288.203068)
			(xy 73.629 -288.157792) (xy 73.655303 -288.116196) (xy 73.687938 -288.079359) (xy 73.726059 -288.048234)
			(xy 73.76868 -288.023627) (xy 73.814696 -288.006175) (xy 73.862915 -287.996331) (xy 73.91209 -287.99435)
			(xy 73.960945 -288.000282) (xy 74.008216 -288.013974) (xy 74.052678 -288.035072) (xy 74.093181 -288.063028)
			(xy 74.128674 -288.09712) (xy 74.158239 -288.136464) (xy 74.18111 -288.180041) (xy 74.196694 -288.226722)
			(xy 74.204589 -288.275299) (xy 74.205084 -288.299906) (xy 74.544186 -288.299906) (xy 74.548146 -288.250852)
			(xy 74.559923 -288.203068) (xy 74.579214 -288.157792) (xy 74.605517 -288.116196) (xy 74.638152 -288.079359)
			(xy 74.676273 -288.048234) (xy 74.718894 -288.023627) (xy 74.76491 -288.006175) (xy 74.813129 -287.996331)
			(xy 74.862304 -287.99435) (xy 74.911159 -288.000282) (xy 74.95843 -288.013974) (xy 75.002892 -288.035072)
			(xy 75.043395 -288.063028) (xy 75.078888 -288.09712) (xy 75.108453 -288.136464) (xy 75.131324 -288.180041)
			(xy 75.146908 -288.226722) (xy 75.154803 -288.275299) (xy 75.155298 -288.299906) (xy 75.494146 -288.299906)
			(xy 75.498106 -288.250852) (xy 75.509883 -288.203068) (xy 75.529174 -288.157792) (xy 75.555477 -288.116196)
			(xy 75.588112 -288.079359) (xy 75.626233 -288.048234) (xy 75.668854 -288.023627) (xy 75.71487 -288.006175)
			(xy 75.763089 -287.996331) (xy 75.812264 -287.99435) (xy 75.861119 -288.000282) (xy 75.90839 -288.013974)
			(xy 75.952852 -288.035072) (xy 75.993355 -288.063028) (xy 76.028848 -288.09712) (xy 76.058413 -288.136464)
			(xy 76.081284 -288.180041) (xy 76.096868 -288.226722) (xy 76.104763 -288.275299) (xy 76.105258 -288.299906)
			(xy 76.104763 -288.324513) (xy 76.104584 -288.325614) (xy 76.423262 -288.325614) (xy 76.423262 -288.274198)
			(xy 76.431305 -288.223416) (xy 76.447193 -288.174517) (xy 76.470536 -288.128705) (xy 76.500757 -288.087109)
			(xy 76.537113 -288.050753) (xy 76.578709 -288.020532) (xy 76.624521 -287.997189) (xy 76.67342 -287.981301)
			(xy 76.724202 -287.973258) (xy 76.775618 -287.973258) (xy 76.8264 -287.981301) (xy 76.875299 -287.997189)
			(xy 76.921111 -288.020532) (xy 76.962707 -288.050753) (xy 76.999063 -288.087109) (xy 77.029284 -288.128705)
			(xy 77.052627 -288.174517) (xy 77.068515 -288.223416) (xy 77.076558 -288.274198) (xy 77.077062 -288.299906)
			(xy 77.076558 -288.325614) (xy 77.373222 -288.325614) (xy 77.373222 -288.274198) (xy 77.381265 -288.223416)
			(xy 77.397153 -288.174517) (xy 77.420496 -288.128705) (xy 77.450717 -288.087109) (xy 77.487073 -288.050753)
			(xy 77.528669 -288.020532) (xy 77.574481 -287.997189) (xy 77.62338 -287.981301) (xy 77.674162 -287.973258)
			(xy 77.725578 -287.973258) (xy 77.77636 -287.981301) (xy 77.825259 -287.997189) (xy 77.871071 -288.020532)
			(xy 77.912667 -288.050753) (xy 77.949023 -288.087109) (xy 77.979244 -288.128705) (xy 78.002587 -288.174517)
			(xy 78.018475 -288.223416) (xy 78.026518 -288.274198) (xy 78.027022 -288.299906) (xy 78.026518 -288.325614)
			(xy 78.018475 -288.376396) (xy 78.002587 -288.425295) (xy 77.979244 -288.471107) (xy 77.949023 -288.512703)
			(xy 77.912667 -288.549059) (xy 77.871071 -288.57928) (xy 77.825259 -288.602623) (xy 77.77636 -288.618511)
			(xy 77.725578 -288.626554) (xy 77.674162 -288.626554) (xy 77.62338 -288.618511) (xy 77.574481 -288.602623)
			(xy 77.528669 -288.57928) (xy 77.487073 -288.549059) (xy 77.450717 -288.512703) (xy 77.420496 -288.471107)
			(xy 77.397153 -288.425295) (xy 77.381265 -288.376396) (xy 77.373222 -288.325614) (xy 77.076558 -288.325614)
			(xy 77.068515 -288.376396) (xy 77.052627 -288.425295) (xy 77.029284 -288.471107) (xy 76.999063 -288.512703)
			(xy 76.962707 -288.549059) (xy 76.921111 -288.57928) (xy 76.875299 -288.602623) (xy 76.8264 -288.618511)
			(xy 76.775618 -288.626554) (xy 76.724202 -288.626554) (xy 76.67342 -288.618511) (xy 76.624521 -288.602623)
			(xy 76.578709 -288.57928) (xy 76.537113 -288.549059) (xy 76.500757 -288.512703) (xy 76.470536 -288.471107)
			(xy 76.447193 -288.425295) (xy 76.431305 -288.376396) (xy 76.423262 -288.325614) (xy 76.104584 -288.325614)
			(xy 76.096868 -288.37309) (xy 76.081284 -288.419771) (xy 76.058413 -288.463348) (xy 76.028848 -288.502692)
			(xy 75.993355 -288.536784) (xy 75.952852 -288.56474) (xy 75.90839 -288.585838) (xy 75.861119 -288.59953)
			(xy 75.812264 -288.605462) (xy 75.763089 -288.603481) (xy 75.71487 -288.593637) (xy 75.668854 -288.576185)
			(xy 75.626233 -288.551578) (xy 75.588112 -288.520453) (xy 75.555477 -288.483616) (xy 75.529174 -288.44202)
			(xy 75.509883 -288.396744) (xy 75.498106 -288.34896) (xy 75.494146 -288.299906) (xy 75.155298 -288.299906)
			(xy 75.154803 -288.324513) (xy 75.146908 -288.37309) (xy 75.131324 -288.419771) (xy 75.108453 -288.463348)
			(xy 75.078888 -288.502692) (xy 75.043395 -288.536784) (xy 75.002892 -288.56474) (xy 74.95843 -288.585838)
			(xy 74.911159 -288.59953) (xy 74.862304 -288.605462) (xy 74.813129 -288.603481) (xy 74.76491 -288.593637)
			(xy 74.718894 -288.576185) (xy 74.676273 -288.551578) (xy 74.638152 -288.520453) (xy 74.605517 -288.483616)
			(xy 74.579214 -288.44202) (xy 74.559923 -288.396744) (xy 74.548146 -288.34896) (xy 74.544186 -288.299906)
			(xy 74.205084 -288.299906) (xy 74.204589 -288.324513) (xy 74.196694 -288.37309) (xy 74.18111 -288.419771)
			(xy 74.158239 -288.463348) (xy 74.128674 -288.502692) (xy 74.093181 -288.536784) (xy 74.052678 -288.56474)
			(xy 74.008216 -288.585838) (xy 73.960945 -288.59953) (xy 73.91209 -288.605462) (xy 73.862915 -288.603481)
			(xy 73.814696 -288.593637) (xy 73.76868 -288.576185) (xy 73.726059 -288.551578) (xy 73.687938 -288.520453)
			(xy 73.655303 -288.483616) (xy 73.629 -288.44202) (xy 73.609709 -288.396744) (xy 73.597932 -288.34896)
			(xy 73.593972 -288.299906) (xy 28.053457 -288.299906) (xy 28.051513 -288.313118) (xy 28.035445 -288.366525)
			(xy 28.011773 -288.417022) (xy 27.981 -288.463535) (xy 27.943783 -288.505072) (xy 27.900915 -288.540747)
			(xy 27.853309 -288.569801) (xy 27.80198 -288.591613) (xy 27.748023 -288.605719) (xy 27.692586 -288.611819)
			(xy 27.636852 -288.609782) (xy 27.582009 -288.599652) (xy 27.529225 -288.581645) (xy 27.479625 -288.556144)
			(xy 27.434267 -288.523693) (xy 27.394118 -288.484984) (xy 27.360032 -288.440841) (xy 27.332736 -288.392206)
			(xy 27.312813 -288.340115) (xy 27.300687 -288.285678) (xy 27.296616 -288.230056) (xy 26.575004 -288.230056)
			(xy 26.574495 -288.257942) (xy 26.566375 -288.313118) (xy 26.550307 -288.366525) (xy 26.526635 -288.417022)
			(xy 26.495862 -288.463535) (xy 26.458645 -288.505072) (xy 26.415777 -288.540747) (xy 26.368171 -288.569801)
			(xy 26.316842 -288.591613) (xy 26.262885 -288.605719) (xy 26.207448 -288.611819) (xy 26.151714 -288.609782)
			(xy 26.096871 -288.599652) (xy 26.044087 -288.581645) (xy 25.994487 -288.556144) (xy 25.949129 -288.523693)
			(xy 25.90898 -288.484984) (xy 25.874894 -288.440841) (xy 25.847598 -288.392206) (xy 25.827675 -288.340115)
			(xy 25.815549 -288.285678) (xy 25.811478 -288.230056) (xy 14.972303 -288.230056) (xy 14.934775 -288.262573)
			(xy 14.888921 -288.292042) (xy 14.839341 -288.314684) (xy 14.787043 -288.33004) (xy 14.733091 -288.337797)
			(xy 14.705838 -288.33826) (xy 14.678468 -288.337781) (xy 14.624289 -288.329968) (xy 14.571786 -288.314482)
			(xy 14.522039 -288.291643) (xy 14.476072 -288.261921) (xy 14.45514 -288.24428) (xy 14.448028 -288.238184)
			(xy 14.43101 -288.231834) (xy 14.345666 -288.231834) (xy 14.328648 -288.238184) (xy 14.321536 -288.24428)
			(xy 14.300599 -288.261913) (xy 14.254628 -288.291626) (xy 14.204881 -288.314464) (xy 14.152382 -288.329956)
			(xy 14.098207 -288.337785) (xy 14.070838 -288.33826) (xy 14.043587 -288.33777) (xy 13.98964 -288.330013)
			(xy 13.937346 -288.314658) (xy 13.887769 -288.292017) (xy 13.841919 -288.262551) (xy 13.800729 -288.226859)
			(xy 13.765038 -288.18567) (xy 13.735572 -288.139819) (xy 13.712931 -288.090243) (xy 13.697576 -288.037948)
			(xy 13.68982 -287.984001) (xy 13.346987 -287.984001) (xy 13.346987 -287.984003) (xy 13.33923 -288.037954)
			(xy 13.323873 -288.090253) (xy 13.301231 -288.139833) (xy 13.271762 -288.185687) (xy 13.236068 -288.22688)
			(xy 13.194875 -288.262573) (xy 13.149021 -288.292042) (xy 13.099441 -288.314684) (xy 13.047143 -288.33004)
			(xy 12.993191 -288.337797) (xy 12.965938 -288.33826) (xy 12.938568 -288.337781) (xy 12.884389 -288.329968)
			(xy 12.831886 -288.314482) (xy 12.782139 -288.291643) (xy 12.736172 -288.261921) (xy 12.71524 -288.24428)
			(xy 12.708128 -288.238184) (xy 12.69111 -288.231834) (xy 12.605766 -288.231834) (xy 12.588748 -288.238184)
			(xy 12.581636 -288.24428) (xy 12.560699 -288.261913) (xy 12.514728 -288.291626) (xy 12.464981 -288.314464)
			(xy 12.412482 -288.329956) (xy 12.358307 -288.337785) (xy 12.330938 -288.33826) (xy 12.303687 -288.33777)
			(xy 12.24974 -288.330013) (xy 12.197446 -288.314658) (xy 12.147869 -288.292017) (xy 12.102019 -288.262551)
			(xy 12.060829 -288.226859) (xy 12.025138 -288.18567) (xy 11.995672 -288.139819) (xy 11.973031 -288.090243)
			(xy 11.957676 -288.037948) (xy 11.94992 -287.984001) (xy 1.660398 -287.984001) (xy 1.660398 -288.774886)
			(xy 35.119068 -288.774886) (xy 35.123028 -288.725832) (xy 35.134805 -288.678048) (xy 35.154096 -288.632772)
			(xy 35.180399 -288.591176) (xy 35.213034 -288.554339) (xy 35.251155 -288.523214) (xy 35.293776 -288.498607)
			(xy 35.339792 -288.481155) (xy 35.388011 -288.471311) (xy 35.437186 -288.46933) (xy 35.486041 -288.475262)
			(xy 35.533312 -288.488954) (xy 35.577774 -288.510052) (xy 35.618277 -288.538008) (xy 35.65377 -288.5721)
			(xy 35.683335 -288.611444) (xy 35.706206 -288.655021) (xy 35.72179 -288.701702) (xy 35.729685 -288.750279)
			(xy 35.73018 -288.774886) (xy 35.729685 -288.799493) (xy 35.729535 -288.800413) (xy 36.0443 -288.800413)
			(xy 36.0443 -288.748387) (xy 36.052439 -288.697003) (xy 36.068516 -288.647524) (xy 36.092136 -288.60117)
			(xy 36.122718 -288.559082) (xy 36.159507 -288.522297) (xy 36.201598 -288.49172) (xy 36.247954 -288.468104)
			(xy 36.297434 -288.452031) (xy 36.348819 -288.443897) (xy 36.374832 -288.443416) (xy 37.324792 -288.443416)
			(xy 37.3508 -288.443943) (xy 37.402175 -288.452079) (xy 37.451646 -288.468151) (xy 37.497993 -288.491765)
			(xy 37.540075 -288.522339) (xy 37.576856 -288.559119) (xy 37.60743 -288.601201) (xy 37.631045 -288.647547)
			(xy 37.647119 -288.697017) (xy 37.655257 -288.748392) (xy 37.655257 -288.774886) (xy 37.969202 -288.774886)
			(xy 37.973162 -288.725832) (xy 37.984939 -288.678048) (xy 38.00423 -288.632772) (xy 38.030533 -288.591176)
			(xy 38.063168 -288.554339) (xy 38.101289 -288.523214) (xy 38.14391 -288.498607) (xy 38.189926 -288.481155)
			(xy 38.238145 -288.471311) (xy 38.28732 -288.46933) (xy 38.336175 -288.475262) (xy 38.383446 -288.488954)
			(xy 38.427908 -288.510052) (xy 38.468411 -288.538008) (xy 38.503904 -288.5721) (xy 38.533469 -288.611444)
			(xy 38.55634 -288.655021) (xy 38.571924 -288.701702) (xy 38.579819 -288.750279) (xy 38.580314 -288.774886)
			(xy 41.769042 -288.774886) (xy 41.773002 -288.725832) (xy 41.784779 -288.678048) (xy 41.80407 -288.632772)
			(xy 41.830373 -288.591176) (xy 41.863008 -288.554339) (xy 41.901129 -288.523214) (xy 41.94375 -288.498607)
			(xy 41.989766 -288.481155) (xy 42.037985 -288.471311) (xy 42.08716 -288.46933) (xy 42.136015 -288.475262)
			(xy 42.183286 -288.488954) (xy 42.227748 -288.510052) (xy 42.268251 -288.538008) (xy 42.303744 -288.5721)
			(xy 42.333309 -288.611444) (xy 42.35618 -288.655021) (xy 42.371764 -288.701702) (xy 42.379659 -288.750279)
			(xy 42.380154 -288.774886) (xy 42.379659 -288.799493) (xy 42.37951 -288.800411) (xy 42.694299 -288.800411)
			(xy 42.694299 -288.748389) (xy 42.702438 -288.697007) (xy 42.718514 -288.64753) (xy 42.742132 -288.601178)
			(xy 42.77271 -288.559091) (xy 42.809496 -288.522306) (xy 42.851583 -288.491729) (xy 42.897936 -288.468111)
			(xy 42.947413 -288.452036) (xy 42.998795 -288.443899) (xy 43.024806 -288.443416) (xy 43.974766 -288.443416)
			(xy 44.000775 -288.443941) (xy 44.052154 -288.452074) (xy 44.101628 -288.468144) (xy 44.147978 -288.491757)
			(xy 44.190064 -288.52233) (xy 44.226848 -288.55911) (xy 44.257426 -288.601193) (xy 44.281043 -288.647541)
			(xy 44.297119 -288.697013) (xy 44.305257 -288.748391) (xy 44.305257 -288.774886) (xy 44.619176 -288.774886)
			(xy 44.623136 -288.725832) (xy 44.634913 -288.678048) (xy 44.654204 -288.632772) (xy 44.680507 -288.591176)
			(xy 44.713142 -288.554339) (xy 44.751263 -288.523214) (xy 44.793884 -288.498607) (xy 44.8399 -288.481155)
			(xy 44.888119 -288.471311) (xy 44.937294 -288.46933) (xy 44.986149 -288.475262) (xy 45.03342 -288.488954)
			(xy 45.077882 -288.510052) (xy 45.118385 -288.538008) (xy 45.153878 -288.5721) (xy 45.183443 -288.611444)
			(xy 45.206314 -288.655021) (xy 45.221898 -288.701702) (xy 45.229793 -288.750279) (xy 45.230288 -288.774886)
			(xy 45.569136 -288.774886) (xy 45.573096 -288.725832) (xy 45.584873 -288.678048) (xy 45.604164 -288.632772)
			(xy 45.630467 -288.591176) (xy 45.663102 -288.554339) (xy 45.701223 -288.523214) (xy 45.743844 -288.498607)
			(xy 45.78986 -288.481155) (xy 45.838079 -288.471311) (xy 45.887254 -288.46933) (xy 45.936109 -288.475262)
			(xy 45.98338 -288.488954) (xy 46.027842 -288.510052) (xy 46.068345 -288.538008) (xy 46.103838 -288.5721)
			(xy 46.133403 -288.611444) (xy 46.156274 -288.655021) (xy 46.171858 -288.701702) (xy 46.179753 -288.750279)
			(xy 46.180248 -288.774886) (xy 46.519096 -288.774886) (xy 46.523056 -288.725832) (xy 46.534833 -288.678048)
			(xy 46.554124 -288.632772) (xy 46.580427 -288.591176) (xy 46.613062 -288.554339) (xy 46.651183 -288.523214)
			(xy 46.693804 -288.498607) (xy 46.73982 -288.481155) (xy 46.788039 -288.471311) (xy 46.837214 -288.46933)
			(xy 46.886069 -288.475262) (xy 46.93334 -288.488954) (xy 46.977802 -288.510052) (xy 47.018305 -288.538008)
			(xy 47.053798 -288.5721) (xy 47.083363 -288.611444) (xy 47.106234 -288.655021) (xy 47.121818 -288.701702)
			(xy 47.129713 -288.750279) (xy 47.130208 -288.774886) (xy 47.469056 -288.774886) (xy 47.473016 -288.725832)
			(xy 47.484793 -288.678048) (xy 47.504084 -288.632772) (xy 47.530387 -288.591176) (xy 47.563022 -288.554339)
			(xy 47.601143 -288.523214) (xy 47.643764 -288.498607) (xy 47.68978 -288.481155) (xy 47.737999 -288.471311)
			(xy 47.787174 -288.46933) (xy 47.836029 -288.475262) (xy 47.8833 -288.488954) (xy 47.927762 -288.510052)
			(xy 47.968265 -288.538008) (xy 48.003758 -288.5721) (xy 48.033323 -288.611444) (xy 48.056194 -288.655021)
			(xy 48.071778 -288.701702) (xy 48.079673 -288.750279) (xy 48.080168 -288.774886) (xy 48.419016 -288.774886)
			(xy 48.422976 -288.725832) (xy 48.434753 -288.678048) (xy 48.454044 -288.632772) (xy 48.480347 -288.591176)
			(xy 48.512982 -288.554339) (xy 48.551103 -288.523214) (xy 48.593724 -288.498607) (xy 48.63974 -288.481155)
			(xy 48.687959 -288.471311) (xy 48.737134 -288.46933) (xy 48.785989 -288.475262) (xy 48.83326 -288.488954)
			(xy 48.877722 -288.510052) (xy 48.918225 -288.538008) (xy 48.953718 -288.5721) (xy 48.983283 -288.611444)
			(xy 49.006154 -288.655021) (xy 49.021738 -288.701702) (xy 49.029633 -288.750279) (xy 49.030128 -288.774886)
			(xy 49.368976 -288.774886) (xy 49.372936 -288.725832) (xy 49.384713 -288.678048) (xy 49.404004 -288.632772)
			(xy 49.430307 -288.591176) (xy 49.462942 -288.554339) (xy 49.501063 -288.523214) (xy 49.543684 -288.498607)
			(xy 49.5897 -288.481155) (xy 49.637919 -288.471311) (xy 49.687094 -288.46933) (xy 49.735949 -288.475262)
			(xy 49.78322 -288.488954) (xy 49.827682 -288.510052) (xy 49.868185 -288.538008) (xy 49.903678 -288.5721)
			(xy 49.933243 -288.611444) (xy 49.956114 -288.655021) (xy 49.971698 -288.701702) (xy 49.979593 -288.750279)
			(xy 49.980088 -288.774886) (xy 68.368938 -288.774886) (xy 68.372898 -288.725832) (xy 68.384675 -288.678048)
			(xy 68.403966 -288.632772) (xy 68.430269 -288.591176) (xy 68.462904 -288.554339) (xy 68.501025 -288.523214)
			(xy 68.543646 -288.498607) (xy 68.589662 -288.481155) (xy 68.637881 -288.471311) (xy 68.687056 -288.46933)
			(xy 68.735911 -288.475262) (xy 68.783182 -288.488954) (xy 68.827644 -288.510052) (xy 68.868147 -288.538008)
			(xy 68.90364 -288.5721) (xy 68.933205 -288.611444) (xy 68.956076 -288.655021) (xy 68.97166 -288.701702)
			(xy 68.979555 -288.750279) (xy 68.98005 -288.774886) (xy 69.319152 -288.774886) (xy 69.323112 -288.725832)
			(xy 69.334889 -288.678048) (xy 69.35418 -288.632772) (xy 69.380483 -288.591176) (xy 69.413118 -288.554339)
			(xy 69.451239 -288.523214) (xy 69.49386 -288.498607) (xy 69.539876 -288.481155) (xy 69.588095 -288.471311)
			(xy 69.63727 -288.46933) (xy 69.686125 -288.475262) (xy 69.733396 -288.488954) (xy 69.777858 -288.510052)
			(xy 69.818361 -288.538008) (xy 69.853854 -288.5721) (xy 69.883419 -288.611444) (xy 69.90629 -288.655021)
			(xy 69.921874 -288.701702) (xy 69.929769 -288.750279) (xy 69.930264 -288.774886) (xy 70.269112 -288.774886)
			(xy 70.273072 -288.725832) (xy 70.284849 -288.678048) (xy 70.30414 -288.632772) (xy 70.330443 -288.591176)
			(xy 70.363078 -288.554339) (xy 70.401199 -288.523214) (xy 70.44382 -288.498607) (xy 70.489836 -288.481155)
			(xy 70.538055 -288.471311) (xy 70.58723 -288.46933) (xy 70.636085 -288.475262) (xy 70.683356 -288.488954)
			(xy 70.727818 -288.510052) (xy 70.768321 -288.538008) (xy 70.803814 -288.5721) (xy 70.833379 -288.611444)
			(xy 70.85625 -288.655021) (xy 70.871834 -288.701702) (xy 70.879729 -288.750279) (xy 70.880224 -288.774886)
			(xy 71.219072 -288.774886) (xy 71.223032 -288.725832) (xy 71.234809 -288.678048) (xy 71.2541 -288.632772)
			(xy 71.280403 -288.591176) (xy 71.313038 -288.554339) (xy 71.351159 -288.523214) (xy 71.39378 -288.498607)
			(xy 71.439796 -288.481155) (xy 71.488015 -288.471311) (xy 71.53719 -288.46933) (xy 71.586045 -288.475262)
			(xy 71.633316 -288.488954) (xy 71.677778 -288.510052) (xy 71.718281 -288.538008) (xy 71.753774 -288.5721)
			(xy 71.783339 -288.611444) (xy 71.80621 -288.655021) (xy 71.821794 -288.701702) (xy 71.829689 -288.750279)
			(xy 71.830184 -288.774886) (xy 72.169032 -288.774886) (xy 72.172992 -288.725832) (xy 72.184769 -288.678048)
			(xy 72.20406 -288.632772) (xy 72.230363 -288.591176) (xy 72.262998 -288.554339) (xy 72.301119 -288.523214)
			(xy 72.34374 -288.498607) (xy 72.389756 -288.481155) (xy 72.437975 -288.471311) (xy 72.48715 -288.46933)
			(xy 72.536005 -288.475262) (xy 72.583276 -288.488954) (xy 72.627738 -288.510052) (xy 72.668241 -288.538008)
			(xy 72.703734 -288.5721) (xy 72.733299 -288.611444) (xy 72.75617 -288.655021) (xy 72.771754 -288.701702)
			(xy 72.779649 -288.750279) (xy 72.780144 -288.774886) (xy 72.779649 -288.799493) (xy 72.771754 -288.84807)
			(xy 72.75617 -288.894751) (xy 72.733299 -288.938328) (xy 72.703734 -288.977672) (xy 72.668241 -289.011764)
			(xy 72.627738 -289.03972) (xy 72.583276 -289.060818) (xy 72.536005 -289.07451) (xy 72.48715 -289.080442)
			(xy 72.437975 -289.078461) (xy 72.389756 -289.068617) (xy 72.34374 -289.051165) (xy 72.301119 -289.026558)
			(xy 72.262998 -288.995433) (xy 72.230363 -288.958596) (xy 72.20406 -288.917) (xy 72.184769 -288.871724)
			(xy 72.172992 -288.82394) (xy 72.169032 -288.774886) (xy 71.830184 -288.774886) (xy 71.829689 -288.799493)
			(xy 71.821794 -288.84807) (xy 71.80621 -288.894751) (xy 71.783339 -288.938328) (xy 71.753774 -288.977672)
			(xy 71.718281 -289.011764) (xy 71.677778 -289.03972) (xy 71.633316 -289.060818) (xy 71.586045 -289.07451)
			(xy 71.53719 -289.080442) (xy 71.488015 -289.078461) (xy 71.439796 -289.068617) (xy 71.39378 -289.051165)
			(xy 71.351159 -289.026558) (xy 71.313038 -288.995433) (xy 71.280403 -288.958596) (xy 71.2541 -288.917)
			(xy 71.234809 -288.871724) (xy 71.223032 -288.82394) (xy 71.219072 -288.774886) (xy 70.880224 -288.774886)
			(xy 70.879729 -288.799493) (xy 70.871834 -288.84807) (xy 70.85625 -288.894751) (xy 70.833379 -288.938328)
			(xy 70.803814 -288.977672) (xy 70.768321 -289.011764) (xy 70.727818 -289.03972) (xy 70.683356 -289.060818)
			(xy 70.636085 -289.07451) (xy 70.58723 -289.080442) (xy 70.538055 -289.078461) (xy 70.489836 -289.068617)
			(xy 70.44382 -289.051165) (xy 70.401199 -289.026558) (xy 70.363078 -288.995433) (xy 70.330443 -288.958596)
			(xy 70.30414 -288.917) (xy 70.284849 -288.871724) (xy 70.273072 -288.82394) (xy 70.269112 -288.774886)
			(xy 69.930264 -288.774886) (xy 69.929769 -288.799493) (xy 69.921874 -288.84807) (xy 69.90629 -288.894751)
			(xy 69.883419 -288.938328) (xy 69.853854 -288.977672) (xy 69.818361 -289.011764) (xy 69.777858 -289.03972)
			(xy 69.733396 -289.060818) (xy 69.686125 -289.07451) (xy 69.63727 -289.080442) (xy 69.588095 -289.078461)
			(xy 69.539876 -289.068617) (xy 69.49386 -289.051165) (xy 69.451239 -289.026558) (xy 69.413118 -288.995433)
			(xy 69.380483 -288.958596) (xy 69.35418 -288.917) (xy 69.334889 -288.871724) (xy 69.323112 -288.82394)
			(xy 69.319152 -288.774886) (xy 68.98005 -288.774886) (xy 68.979555 -288.799493) (xy 68.97166 -288.84807)
			(xy 68.956076 -288.894751) (xy 68.933205 -288.938328) (xy 68.90364 -288.977672) (xy 68.868147 -289.011764)
			(xy 68.827644 -289.03972) (xy 68.783182 -289.060818) (xy 68.735911 -289.07451) (xy 68.687056 -289.080442)
			(xy 68.637881 -289.078461) (xy 68.589662 -289.068617) (xy 68.543646 -289.051165) (xy 68.501025 -289.026558)
			(xy 68.462904 -288.995433) (xy 68.430269 -288.958596) (xy 68.403966 -288.917) (xy 68.384675 -288.871724)
			(xy 68.372898 -288.82394) (xy 68.368938 -288.774886) (xy 49.980088 -288.774886) (xy 49.979593 -288.799493)
			(xy 49.971698 -288.84807) (xy 49.956114 -288.894751) (xy 49.933243 -288.938328) (xy 49.903678 -288.977672)
			(xy 49.868185 -289.011764) (xy 49.827682 -289.03972) (xy 49.78322 -289.060818) (xy 49.735949 -289.07451)
			(xy 49.687094 -289.080442) (xy 49.637919 -289.078461) (xy 49.5897 -289.068617) (xy 49.543684 -289.051165)
			(xy 49.501063 -289.026558) (xy 49.462942 -288.995433) (xy 49.430307 -288.958596) (xy 49.404004 -288.917)
			(xy 49.384713 -288.871724) (xy 49.372936 -288.82394) (xy 49.368976 -288.774886) (xy 49.030128 -288.774886)
			(xy 49.029633 -288.799493) (xy 49.021738 -288.84807) (xy 49.006154 -288.894751) (xy 48.983283 -288.938328)
			(xy 48.953718 -288.977672) (xy 48.918225 -289.011764) (xy 48.877722 -289.03972) (xy 48.83326 -289.060818)
			(xy 48.785989 -289.07451) (xy 48.737134 -289.080442) (xy 48.687959 -289.078461) (xy 48.63974 -289.068617)
			(xy 48.593724 -289.051165) (xy 48.551103 -289.026558) (xy 48.512982 -288.995433) (xy 48.480347 -288.958596)
			(xy 48.454044 -288.917) (xy 48.434753 -288.871724) (xy 48.422976 -288.82394) (xy 48.419016 -288.774886)
			(xy 48.080168 -288.774886) (xy 48.079673 -288.799493) (xy 48.071778 -288.84807) (xy 48.056194 -288.894751)
			(xy 48.033323 -288.938328) (xy 48.003758 -288.977672) (xy 47.968265 -289.011764) (xy 47.927762 -289.03972)
			(xy 47.8833 -289.060818) (xy 47.836029 -289.07451) (xy 47.787174 -289.080442) (xy 47.737999 -289.078461)
			(xy 47.68978 -289.068617) (xy 47.643764 -289.051165) (xy 47.601143 -289.026558) (xy 47.563022 -288.995433)
			(xy 47.530387 -288.958596) (xy 47.504084 -288.917) (xy 47.484793 -288.871724) (xy 47.473016 -288.82394)
			(xy 47.469056 -288.774886) (xy 47.130208 -288.774886) (xy 47.129713 -288.799493) (xy 47.121818 -288.84807)
			(xy 47.106234 -288.894751) (xy 47.083363 -288.938328) (xy 47.053798 -288.977672) (xy 47.018305 -289.011764)
			(xy 46.977802 -289.03972) (xy 46.93334 -289.060818) (xy 46.886069 -289.07451) (xy 46.837214 -289.080442)
			(xy 46.788039 -289.078461) (xy 46.73982 -289.068617) (xy 46.693804 -289.051165) (xy 46.651183 -289.026558)
			(xy 46.613062 -288.995433) (xy 46.580427 -288.958596) (xy 46.554124 -288.917) (xy 46.534833 -288.871724)
			(xy 46.523056 -288.82394) (xy 46.519096 -288.774886) (xy 46.180248 -288.774886) (xy 46.179753 -288.799493)
			(xy 46.171858 -288.84807) (xy 46.156274 -288.894751) (xy 46.133403 -288.938328) (xy 46.103838 -288.977672)
			(xy 46.068345 -289.011764) (xy 46.027842 -289.03972) (xy 45.98338 -289.060818) (xy 45.936109 -289.07451)
			(xy 45.887254 -289.080442) (xy 45.838079 -289.078461) (xy 45.78986 -289.068617) (xy 45.743844 -289.051165)
			(xy 45.701223 -289.026558) (xy 45.663102 -288.995433) (xy 45.630467 -288.958596) (xy 45.604164 -288.917)
			(xy 45.584873 -288.871724) (xy 45.573096 -288.82394) (xy 45.569136 -288.774886) (xy 45.230288 -288.774886)
			(xy 45.229793 -288.799493) (xy 45.221898 -288.84807) (xy 45.206314 -288.894751) (xy 45.183443 -288.938328)
			(xy 45.153878 -288.977672) (xy 45.118385 -289.011764) (xy 45.077882 -289.03972) (xy 45.03342 -289.060818)
			(xy 44.986149 -289.07451) (xy 44.937294 -289.080442) (xy 44.888119 -289.078461) (xy 44.8399 -289.068617)
			(xy 44.793884 -289.051165) (xy 44.751263 -289.026558) (xy 44.713142 -288.995433) (xy 44.680507 -288.958596)
			(xy 44.654204 -288.917) (xy 44.634913 -288.871724) (xy 44.623136 -288.82394) (xy 44.619176 -288.774886)
			(xy 44.305257 -288.774886) (xy 44.305257 -288.800409) (xy 44.297119 -288.851787) (xy 44.281043 -288.901259)
			(xy 44.257426 -288.947607) (xy 44.226848 -288.98969) (xy 44.190064 -289.02647) (xy 44.147978 -289.057043)
			(xy 44.101628 -289.080656) (xy 44.052154 -289.096726) (xy 44.000775 -289.104859) (xy 43.974766 -289.10534)
			(xy 43.024806 -289.10534) (xy 42.998795 -289.104901) (xy 42.947413 -289.096764) (xy 42.897936 -289.080689)
			(xy 42.851583 -289.057071) (xy 42.809496 -289.026494) (xy 42.77271 -288.989709) (xy 42.742132 -288.947622)
			(xy 42.718514 -288.90127) (xy 42.702438 -288.851793) (xy 42.694299 -288.800411) (xy 42.37951 -288.800411)
			(xy 42.371764 -288.84807) (xy 42.35618 -288.894751) (xy 42.333309 -288.938328) (xy 42.303744 -288.977672)
			(xy 42.268251 -289.011764) (xy 42.227748 -289.03972) (xy 42.183286 -289.060818) (xy 42.136015 -289.07451)
			(xy 42.08716 -289.080442) (xy 42.037985 -289.078461) (xy 41.989766 -289.068617) (xy 41.94375 -289.051165)
			(xy 41.901129 -289.026558) (xy 41.863008 -288.995433) (xy 41.830373 -288.958596) (xy 41.80407 -288.917)
			(xy 41.784779 -288.871724) (xy 41.773002 -288.82394) (xy 41.769042 -288.774886) (xy 38.580314 -288.774886)
			(xy 38.579819 -288.799493) (xy 38.571924 -288.84807) (xy 38.55634 -288.894751) (xy 38.533469 -288.938328)
			(xy 38.503904 -288.977672) (xy 38.468411 -289.011764) (xy 38.427908 -289.03972) (xy 38.383446 -289.060818)
			(xy 38.336175 -289.07451) (xy 38.28732 -289.080442) (xy 38.238145 -289.078461) (xy 38.189926 -289.068617)
			(xy 38.14391 -289.051165) (xy 38.101289 -289.026558) (xy 38.063168 -288.995433) (xy 38.030533 -288.958596)
			(xy 38.00423 -288.917) (xy 37.984939 -288.871724) (xy 37.973162 -288.82394) (xy 37.969202 -288.774886)
			(xy 37.655257 -288.774886) (xy 37.655257 -288.800408) (xy 37.647119 -288.851783) (xy 37.631045 -288.901253)
			(xy 37.60743 -288.947599) (xy 37.576856 -288.989681) (xy 37.540075 -289.026461) (xy 37.497993 -289.057035)
			(xy 37.451646 -289.080649) (xy 37.402175 -289.096721) (xy 37.3508 -289.104857) (xy 37.324792 -289.10534)
			(xy 36.374832 -289.10534) (xy 36.348819 -289.104903) (xy 36.297434 -289.096769) (xy 36.247954 -289.080696)
			(xy 36.201598 -289.05708) (xy 36.159507 -289.026503) (xy 36.122718 -288.989718) (xy 36.092136 -288.94763)
			(xy 36.068516 -288.901276) (xy 36.052439 -288.851797) (xy 36.0443 -288.800413) (xy 35.729535 -288.800413)
			(xy 35.72179 -288.84807) (xy 35.706206 -288.894751) (xy 35.683335 -288.938328) (xy 35.65377 -288.977672)
			(xy 35.618277 -289.011764) (xy 35.577774 -289.03972) (xy 35.533312 -289.060818) (xy 35.486041 -289.07451)
			(xy 35.437186 -289.080442) (xy 35.388011 -289.078461) (xy 35.339792 -289.068617) (xy 35.293776 -289.051165)
			(xy 35.251155 -289.026558) (xy 35.213034 -288.995433) (xy 35.180399 -288.958596) (xy 35.154096 -288.917)
			(xy 35.134805 -288.871724) (xy 35.123028 -288.82394) (xy 35.119068 -288.774886) (xy 1.660398 -288.774886)
			(xy 1.660398 -289.258323) (xy 3.252675 -289.258323) (xy 3.252675 -289.203817) (xy 3.260432 -289.149866)
			(xy 3.275789 -289.097568) (xy 3.298431 -289.047987) (xy 3.3279 -289.002134) (xy 3.363594 -288.960941)
			(xy 3.404787 -288.925247) (xy 3.450641 -288.89578) (xy 3.500221 -288.873137) (xy 3.55252 -288.857782)
			(xy 3.606471 -288.850025) (xy 3.633724 -288.849562) (xy 3.661095 -288.849999) (xy 3.715276 -288.857821)
			(xy 3.76778 -288.873316) (xy 3.817527 -288.896165) (xy 3.863492 -288.925897) (xy 3.884422 -288.943542)
			(xy 3.891534 -288.949638) (xy 3.908552 -288.955988) (xy 3.993896 -288.955988) (xy 4.010914 -288.949638)
			(xy 4.018026 -288.943542) (xy 4.038981 -288.925931) (xy 4.084947 -288.896213) (xy 4.134688 -288.873371)
			(xy 4.187184 -288.857874) (xy 4.241356 -288.850039) (xy 4.268724 -288.849562) (xy 4.295975 -288.850048)
			(xy 4.349922 -288.857805) (xy 4.402217 -288.873161) (xy 4.451793 -288.895802) (xy 4.497643 -288.925268)
			(xy 4.538833 -288.96096) (xy 4.574524 -289.00215) (xy 4.60399 -289.048) (xy 4.626631 -289.097577)
			(xy 4.641986 -289.149872) (xy 4.649742 -289.203819) (xy 4.649742 -289.258321) (xy 5.006068 -289.258321)
			(xy 5.006068 -289.203819) (xy 5.013824 -289.149872) (xy 5.029179 -289.097577) (xy 5.05182 -289.048)
			(xy 5.081286 -289.00215) (xy 5.116977 -288.96096) (xy 5.158167 -288.925268) (xy 5.204017 -288.895802)
			(xy 5.253593 -288.873161) (xy 5.305888 -288.857805) (xy 5.359835 -288.850048) (xy 5.387086 -288.849562)
			(xy 5.414457 -288.850021) (xy 5.468637 -288.857838) (xy 5.52114 -288.873328) (xy 5.570887 -288.896172)
			(xy 5.616853 -288.925899) (xy 5.637784 -288.943542) (xy 5.644896 -288.949638) (xy 5.661914 -288.955988)
			(xy 5.747258 -288.955988) (xy 5.764276 -288.949638) (xy 5.771388 -288.943542) (xy 5.792319 -288.925902)
			(xy 5.838292 -288.896189) (xy 5.888039 -288.873352) (xy 5.94054 -288.857862) (xy 5.994717 -288.850035)
			(xy 6.022086 -288.849562) (xy 6.049339 -288.850025) (xy 6.10329 -288.857782) (xy 6.155589 -288.873137)
			(xy 6.205169 -288.89578) (xy 6.251023 -288.925247) (xy 6.292216 -288.960941) (xy 6.32791 -289.002134)
			(xy 6.357379 -289.047987) (xy 6.380021 -289.097568) (xy 6.395378 -289.149866) (xy 6.403135 -289.203817)
			(xy 6.403135 -289.258323) (xy 6.395378 -289.312274) (xy 6.380021 -289.364572) (xy 6.357379 -289.414153)
			(xy 6.32791 -289.460006) (xy 6.292216 -289.501199) (xy 6.256307 -289.532314) (xy 28.175964 -289.532314)
			(xy 28.180035 -289.476692) (xy 28.192161 -289.422255) (xy 28.212084 -289.370164) (xy 28.23938 -289.321529)
			(xy 28.273466 -289.277386) (xy 28.313615 -289.238677) (xy 28.358973 -289.206226) (xy 28.408573 -289.180725)
			(xy 28.461357 -289.162718) (xy 28.5162 -289.152588) (xy 28.571934 -289.150551) (xy 28.627371 -289.156651)
			(xy 28.681328 -289.170757) (xy 28.732657 -289.192569) (xy 28.780263 -289.221623) (xy 28.823131 -289.257298)
			(xy 28.860348 -289.298835) (xy 28.891121 -289.345348) (xy 28.914793 -289.395845) (xy 28.930861 -289.449252)
			(xy 28.938981 -289.504428) (xy 28.93949 -289.532314) (xy 28.938981 -289.5602) (xy 28.930861 -289.615376)
			(xy 28.914793 -289.668783) (xy 28.891121 -289.71928) (xy 28.860348 -289.765793) (xy 28.823131 -289.80733)
			(xy 28.780263 -289.843005) (xy 28.732657 -289.872059) (xy 28.681328 -289.893871) (xy 28.627371 -289.907977)
			(xy 28.571934 -289.914077) (xy 28.5162 -289.91204) (xy 28.461357 -289.90191) (xy 28.408573 -289.883903)
			(xy 28.358973 -289.858402) (xy 28.313615 -289.825951) (xy 28.273466 -289.787242) (xy 28.23938 -289.743099)
			(xy 28.212084 -289.694464) (xy 28.192161 -289.642373) (xy 28.180035 -289.587936) (xy 28.175964 -289.532314)
			(xy 6.256307 -289.532314) (xy 6.251023 -289.536893) (xy 6.205169 -289.56636) (xy 6.155589 -289.589003)
			(xy 6.10329 -289.604358) (xy 6.049339 -289.612115) (xy 6.022086 -289.612578) (xy 5.994715 -289.612125)
			(xy 5.940535 -289.604305) (xy 5.888032 -289.588813) (xy 5.838285 -289.565968) (xy 5.792319 -289.536241)
			(xy 5.771388 -289.518598) (xy 5.764276 -289.512502) (xy 5.747258 -289.506152) (xy 5.661914 -289.506152)
			(xy 5.644896 -289.512502) (xy 5.637784 -289.518598) (xy 5.616831 -289.536211) (xy 5.570864 -289.565927)
			(xy 5.521122 -289.588768) (xy 5.468626 -289.604265) (xy 5.414454 -289.6121) (xy 5.387086 -289.612578)
			(xy 5.359835 -289.612092) (xy 5.305888 -289.604335) (xy 5.253593 -289.588979) (xy 5.204017 -289.566338)
			(xy 5.158167 -289.536872) (xy 5.116977 -289.50118) (xy 5.081286 -289.45999) (xy 5.05182 -289.41414)
			(xy 5.029179 -289.364563) (xy 5.013824 -289.312268) (xy 5.006068 -289.258321) (xy 4.649742 -289.258321)
			(xy 4.641986 -289.312268) (xy 4.626631 -289.364563) (xy 4.60399 -289.41414) (xy 4.574524 -289.45999)
			(xy 4.538833 -289.50118) (xy 4.497643 -289.536872) (xy 4.451793 -289.566338) (xy 4.402217 -289.588979)
			(xy 4.349922 -289.604335) (xy 4.295975 -289.612092) (xy 4.268724 -289.612578) (xy 4.241354 -289.612103)
			(xy 4.187175 -289.604288) (xy 4.134672 -289.588802) (xy 4.084925 -289.565962) (xy 4.038958 -289.536239)
			(xy 4.018026 -289.518598) (xy 4.010914 -289.512502) (xy 3.993896 -289.506152) (xy 3.908552 -289.506152)
			(xy 3.891534 -289.512502) (xy 3.884422 -289.518598) (xy 3.863492 -289.53624) (xy 3.817519 -289.565951)
			(xy 3.767771 -289.588787) (xy 3.71527 -289.604277) (xy 3.661093 -289.612105) (xy 3.633724 -289.612578)
			(xy 3.606471 -289.612115) (xy 3.55252 -289.604358) (xy 3.500221 -289.589003) (xy 3.450641 -289.56636)
			(xy 3.404787 -289.536893) (xy 3.363594 -289.501199) (xy 3.3279 -289.460006) (xy 3.298431 -289.414153)
			(xy 3.275789 -289.364572) (xy 3.260432 -289.312274) (xy 3.252675 -289.258323) (xy 1.660398 -289.258323)
			(xy 1.660398 -290.321238) (xy 31.234888 -290.321238) (xy 31.235327 -290.29466) (xy 31.242726 -290.24202)
			(xy 31.257359 -290.190917) (xy 31.278942 -290.142339) (xy 31.307058 -290.097226) (xy 31.341163 -290.056452)
			(xy 31.380596 -290.020805) (xy 31.424594 -289.990976) (xy 31.448248 -289.978846) (xy 31.460777 -289.972266)
			(xy 31.481831 -289.953371) (xy 31.49689 -289.929422) (xy 31.504794 -289.902259) (xy 31.504938 -289.873969)
			(xy 31.49731 -289.846727) (xy 31.482496 -289.822626) (xy 31.472378 -289.81273) (xy 31.45335 -289.794617)
			(xy 31.419969 -289.754051) (xy 31.392474 -289.709287) (xy 31.371382 -289.661172) (xy 31.357095 -289.610618)
			(xy 31.349882 -289.558581) (xy 31.349442 -289.532314) (xy 31.349928 -289.505063) (xy 31.357684 -289.451115)
			(xy 31.373039 -289.39882) (xy 31.395681 -289.349243) (xy 31.425147 -289.303393) (xy 31.460838 -289.262202)
			(xy 31.502029 -289.226511) (xy 31.547879 -289.197045) (xy 31.597456 -289.174403) (xy 31.649751 -289.159048)
			(xy 31.703699 -289.151292) (xy 31.758201 -289.151292) (xy 31.812149 -289.159048) (xy 31.864444 -289.174403)
			(xy 31.914021 -289.197045) (xy 31.959871 -289.226511) (xy 32.001062 -289.262202) (xy 32.036753 -289.303393)
			(xy 32.066219 -289.349243) (xy 32.088861 -289.39882) (xy 32.104216 -289.451115) (xy 32.111972 -289.505063)
			(xy 32.112458 -289.532314) (xy 32.111954 -289.55889) (xy 32.104562 -289.611525) (xy 32.089937 -289.662626)
			(xy 32.068363 -289.711202) (xy 32.059862 -289.724846) (xy 36.069028 -289.724846) (xy 36.072988 -289.675792)
			(xy 36.084765 -289.628008) (xy 36.104056 -289.582732) (xy 36.130359 -289.541136) (xy 36.162994 -289.504299)
			(xy 36.201115 -289.473174) (xy 36.243736 -289.448567) (xy 36.289752 -289.431115) (xy 36.337971 -289.421271)
			(xy 36.387146 -289.41929) (xy 36.436001 -289.425222) (xy 36.483272 -289.438914) (xy 36.527734 -289.460012)
			(xy 36.568237 -289.487968) (xy 36.60373 -289.52206) (xy 36.633295 -289.561404) (xy 36.656166 -289.604981)
			(xy 36.67175 -289.651662) (xy 36.679645 -289.700239) (xy 36.68014 -289.724846) (xy 37.018988 -289.724846)
			(xy 37.022948 -289.675792) (xy 37.034725 -289.628008) (xy 37.054016 -289.582732) (xy 37.080319 -289.541136)
			(xy 37.112954 -289.504299) (xy 37.151075 -289.473174) (xy 37.193696 -289.448567) (xy 37.239712 -289.431115)
			(xy 37.287931 -289.421271) (xy 37.337106 -289.41929) (xy 37.385961 -289.425222) (xy 37.433232 -289.438914)
			(xy 37.477694 -289.460012) (xy 37.518197 -289.487968) (xy 37.55369 -289.52206) (xy 37.583255 -289.561404)
			(xy 37.606126 -289.604981) (xy 37.62171 -289.651662) (xy 37.629605 -289.700239) (xy 37.6301 -289.724846)
			(xy 37.969202 -289.724846) (xy 37.973162 -289.675792) (xy 37.984939 -289.628008) (xy 38.00423 -289.582732)
			(xy 38.030533 -289.541136) (xy 38.063168 -289.504299) (xy 38.101289 -289.473174) (xy 38.14391 -289.448567)
			(xy 38.189926 -289.431115) (xy 38.238145 -289.421271) (xy 38.28732 -289.41929) (xy 38.336175 -289.425222)
			(xy 38.383446 -289.438914) (xy 38.427908 -289.460012) (xy 38.468411 -289.487968) (xy 38.503904 -289.52206)
			(xy 38.533469 -289.561404) (xy 38.55634 -289.604981) (xy 38.571924 -289.651662) (xy 38.579819 -289.700239)
			(xy 38.580314 -289.724846) (xy 38.919162 -289.724846) (xy 38.923122 -289.675792) (xy 38.934899 -289.628008)
			(xy 38.95419 -289.582732) (xy 38.980493 -289.541136) (xy 39.013128 -289.504299) (xy 39.051249 -289.473174)
			(xy 39.09387 -289.448567) (xy 39.139886 -289.431115) (xy 39.188105 -289.421271) (xy 39.23728 -289.41929)
			(xy 39.286135 -289.425222) (xy 39.333406 -289.438914) (xy 39.377868 -289.460012) (xy 39.418371 -289.487968)
			(xy 39.453864 -289.52206) (xy 39.483429 -289.561404) (xy 39.5063 -289.604981) (xy 39.521884 -289.651662)
			(xy 39.529779 -289.700239) (xy 39.530274 -289.724846) (xy 39.869122 -289.724846) (xy 39.873082 -289.675792)
			(xy 39.884859 -289.628008) (xy 39.90415 -289.582732) (xy 39.930453 -289.541136) (xy 39.963088 -289.504299)
			(xy 40.001209 -289.473174) (xy 40.04383 -289.448567) (xy 40.089846 -289.431115) (xy 40.138065 -289.421271)
			(xy 40.18724 -289.41929) (xy 40.236095 -289.425222) (xy 40.283366 -289.438914) (xy 40.327828 -289.460012)
			(xy 40.368331 -289.487968) (xy 40.403824 -289.52206) (xy 40.433389 -289.561404) (xy 40.45626 -289.604981)
			(xy 40.471844 -289.651662) (xy 40.479739 -289.700239) (xy 40.480234 -289.724846) (xy 40.819082 -289.724846)
			(xy 40.823042 -289.675792) (xy 40.834819 -289.628008) (xy 40.85411 -289.582732) (xy 40.880413 -289.541136)
			(xy 40.913048 -289.504299) (xy 40.951169 -289.473174) (xy 40.99379 -289.448567) (xy 41.039806 -289.431115)
			(xy 41.088025 -289.421271) (xy 41.1372 -289.41929) (xy 41.186055 -289.425222) (xy 41.233326 -289.438914)
			(xy 41.277788 -289.460012) (xy 41.318291 -289.487968) (xy 41.353784 -289.52206) (xy 41.383349 -289.561404)
			(xy 41.40622 -289.604981) (xy 41.421804 -289.651662) (xy 41.429699 -289.700239) (xy 41.430194 -289.724846)
			(xy 41.769042 -289.724846) (xy 41.773002 -289.675792) (xy 41.784779 -289.628008) (xy 41.80407 -289.582732)
			(xy 41.830373 -289.541136) (xy 41.863008 -289.504299) (xy 41.901129 -289.473174) (xy 41.94375 -289.448567)
			(xy 41.989766 -289.431115) (xy 42.037985 -289.421271) (xy 42.08716 -289.41929) (xy 42.136015 -289.425222)
			(xy 42.183286 -289.438914) (xy 42.227748 -289.460012) (xy 42.268251 -289.487968) (xy 42.303744 -289.52206)
			(xy 42.333309 -289.561404) (xy 42.35618 -289.604981) (xy 42.371764 -289.651662) (xy 42.379659 -289.700239)
			(xy 42.380154 -289.724846) (xy 42.719002 -289.724846) (xy 42.722962 -289.675792) (xy 42.734739 -289.628008)
			(xy 42.75403 -289.582732) (xy 42.780333 -289.541136) (xy 42.812968 -289.504299) (xy 42.851089 -289.473174)
			(xy 42.89371 -289.448567) (xy 42.939726 -289.431115) (xy 42.987945 -289.421271) (xy 43.03712 -289.41929)
			(xy 43.085975 -289.425222) (xy 43.133246 -289.438914) (xy 43.177708 -289.460012) (xy 43.218211 -289.487968)
			(xy 43.253704 -289.52206) (xy 43.283269 -289.561404) (xy 43.30614 -289.604981) (xy 43.321724 -289.651662)
			(xy 43.329619 -289.700239) (xy 43.330114 -289.724846) (xy 43.668962 -289.724846) (xy 43.672922 -289.675792)
			(xy 43.684699 -289.628008) (xy 43.70399 -289.582732) (xy 43.730293 -289.541136) (xy 43.762928 -289.504299)
			(xy 43.801049 -289.473174) (xy 43.84367 -289.448567) (xy 43.889686 -289.431115) (xy 43.937905 -289.421271)
			(xy 43.98708 -289.41929) (xy 44.035935 -289.425222) (xy 44.083206 -289.438914) (xy 44.127668 -289.460012)
			(xy 44.168171 -289.487968) (xy 44.203664 -289.52206) (xy 44.233229 -289.561404) (xy 44.2561 -289.604981)
			(xy 44.271684 -289.651662) (xy 44.279579 -289.700239) (xy 44.280074 -289.724846) (xy 44.619176 -289.724846)
			(xy 44.623136 -289.675792) (xy 44.634913 -289.628008) (xy 44.654204 -289.582732) (xy 44.680507 -289.541136)
			(xy 44.713142 -289.504299) (xy 44.751263 -289.473174) (xy 44.793884 -289.448567) (xy 44.8399 -289.431115)
			(xy 44.888119 -289.421271) (xy 44.937294 -289.41929) (xy 44.986149 -289.425222) (xy 45.03342 -289.438914)
			(xy 45.077882 -289.460012) (xy 45.118385 -289.487968) (xy 45.153878 -289.52206) (xy 45.183443 -289.561404)
			(xy 45.206314 -289.604981) (xy 45.221898 -289.651662) (xy 45.229793 -289.700239) (xy 45.230288 -289.724846)
			(xy 45.569136 -289.724846) (xy 45.573096 -289.675792) (xy 45.584873 -289.628008) (xy 45.604164 -289.582732)
			(xy 45.630467 -289.541136) (xy 45.663102 -289.504299) (xy 45.701223 -289.473174) (xy 45.743844 -289.448567)
			(xy 45.78986 -289.431115) (xy 45.838079 -289.421271) (xy 45.887254 -289.41929) (xy 45.936109 -289.425222)
			(xy 45.98338 -289.438914) (xy 46.027842 -289.460012) (xy 46.068345 -289.487968) (xy 46.103838 -289.52206)
			(xy 46.133403 -289.561404) (xy 46.156274 -289.604981) (xy 46.171858 -289.651662) (xy 46.179753 -289.700239)
			(xy 46.180248 -289.724846) (xy 46.519096 -289.724846) (xy 46.523056 -289.675792) (xy 46.534833 -289.628008)
			(xy 46.554124 -289.582732) (xy 46.580427 -289.541136) (xy 46.613062 -289.504299) (xy 46.651183 -289.473174)
			(xy 46.693804 -289.448567) (xy 46.73982 -289.431115) (xy 46.788039 -289.421271) (xy 46.837214 -289.41929)
			(xy 46.886069 -289.425222) (xy 46.93334 -289.438914) (xy 46.977802 -289.460012) (xy 47.018305 -289.487968)
			(xy 47.053798 -289.52206) (xy 47.083363 -289.561404) (xy 47.106234 -289.604981) (xy 47.121818 -289.651662)
			(xy 47.129713 -289.700239) (xy 47.130208 -289.724846) (xy 47.469056 -289.724846) (xy 47.473016 -289.675792)
			(xy 47.484793 -289.628008) (xy 47.504084 -289.582732) (xy 47.530387 -289.541136) (xy 47.563022 -289.504299)
			(xy 47.601143 -289.473174) (xy 47.643764 -289.448567) (xy 47.68978 -289.431115) (xy 47.737999 -289.421271)
			(xy 47.787174 -289.41929) (xy 47.836029 -289.425222) (xy 47.8833 -289.438914) (xy 47.927762 -289.460012)
			(xy 47.968265 -289.487968) (xy 48.003758 -289.52206) (xy 48.033323 -289.561404) (xy 48.056194 -289.604981)
			(xy 48.071778 -289.651662) (xy 48.079673 -289.700239) (xy 48.080168 -289.724846) (xy 48.419016 -289.724846)
			(xy 48.422976 -289.675792) (xy 48.434753 -289.628008) (xy 48.454044 -289.582732) (xy 48.480347 -289.541136)
			(xy 48.512982 -289.504299) (xy 48.551103 -289.473174) (xy 48.593724 -289.448567) (xy 48.63974 -289.431115)
			(xy 48.687959 -289.421271) (xy 48.737134 -289.41929) (xy 48.785989 -289.425222) (xy 48.83326 -289.438914)
			(xy 48.877722 -289.460012) (xy 48.918225 -289.487968) (xy 48.953718 -289.52206) (xy 48.983283 -289.561404)
			(xy 49.006154 -289.604981) (xy 49.021738 -289.651662) (xy 49.029633 -289.700239) (xy 49.030128 -289.724846)
			(xy 49.368976 -289.724846) (xy 49.372936 -289.675792) (xy 49.384713 -289.628008) (xy 49.404004 -289.582732)
			(xy 49.430307 -289.541136) (xy 49.462942 -289.504299) (xy 49.501063 -289.473174) (xy 49.543684 -289.448567)
			(xy 49.5897 -289.431115) (xy 49.637919 -289.421271) (xy 49.687094 -289.41929) (xy 49.735949 -289.425222)
			(xy 49.78322 -289.438914) (xy 49.827682 -289.460012) (xy 49.868185 -289.487968) (xy 49.903678 -289.52206)
			(xy 49.933243 -289.561404) (xy 49.956114 -289.604981) (xy 49.971698 -289.651662) (xy 49.979593 -289.700239)
			(xy 49.980088 -289.724846) (xy 50.31919 -289.724846) (xy 50.32315 -289.675792) (xy 50.334927 -289.628008)
			(xy 50.354218 -289.582732) (xy 50.380521 -289.541136) (xy 50.413156 -289.504299) (xy 50.451277 -289.473174)
			(xy 50.493898 -289.448567) (xy 50.539914 -289.431115) (xy 50.588133 -289.421271) (xy 50.637308 -289.41929)
			(xy 50.686163 -289.425222) (xy 50.733434 -289.438914) (xy 50.777896 -289.460012) (xy 50.818399 -289.487968)
			(xy 50.853892 -289.52206) (xy 50.883457 -289.561404) (xy 50.906328 -289.604981) (xy 50.921912 -289.651662)
			(xy 50.929807 -289.700239) (xy 50.930302 -289.724846) (xy 51.26915 -289.724846) (xy 51.27311 -289.675792)
			(xy 51.284887 -289.628008) (xy 51.304178 -289.582732) (xy 51.330481 -289.541136) (xy 51.363116 -289.504299)
			(xy 51.401237 -289.473174) (xy 51.443858 -289.448567) (xy 51.489874 -289.431115) (xy 51.538093 -289.421271)
			(xy 51.587268 -289.41929) (xy 51.636123 -289.425222) (xy 51.683394 -289.438914) (xy 51.727856 -289.460012)
			(xy 51.768359 -289.487968) (xy 51.803852 -289.52206) (xy 51.833417 -289.561404) (xy 51.856288 -289.604981)
			(xy 51.871872 -289.651662) (xy 51.879767 -289.700239) (xy 51.880262 -289.724846) (xy 52.21911 -289.724846)
			(xy 52.22307 -289.675792) (xy 52.234847 -289.628008) (xy 52.254138 -289.582732) (xy 52.280441 -289.541136)
			(xy 52.313076 -289.504299) (xy 52.351197 -289.473174) (xy 52.393818 -289.448567) (xy 52.439834 -289.431115)
			(xy 52.488053 -289.421271) (xy 52.537228 -289.41929) (xy 52.586083 -289.425222) (xy 52.633354 -289.438914)
			(xy 52.677816 -289.460012) (xy 52.718319 -289.487968) (xy 52.753812 -289.52206) (xy 52.783377 -289.561404)
			(xy 52.806248 -289.604981) (xy 52.821832 -289.651662) (xy 52.829727 -289.700239) (xy 52.830222 -289.724846)
			(xy 53.16907 -289.724846) (xy 53.17303 -289.675792) (xy 53.184807 -289.628008) (xy 53.204098 -289.582732)
			(xy 53.230401 -289.541136) (xy 53.263036 -289.504299) (xy 53.301157 -289.473174) (xy 53.343778 -289.448567)
			(xy 53.389794 -289.431115) (xy 53.438013 -289.421271) (xy 53.487188 -289.41929) (xy 53.536043 -289.425222)
			(xy 53.583314 -289.438914) (xy 53.627776 -289.460012) (xy 53.668279 -289.487968) (xy 53.703772 -289.52206)
			(xy 53.733337 -289.561404) (xy 53.756208 -289.604981) (xy 53.771792 -289.651662) (xy 53.779687 -289.700239)
			(xy 53.780182 -289.724846) (xy 54.11903 -289.724846) (xy 54.12299 -289.675792) (xy 54.134767 -289.628008)
			(xy 54.154058 -289.582732) (xy 54.180361 -289.541136) (xy 54.212996 -289.504299) (xy 54.251117 -289.473174)
			(xy 54.293738 -289.448567) (xy 54.339754 -289.431115) (xy 54.387973 -289.421271) (xy 54.437148 -289.41929)
			(xy 54.486003 -289.425222) (xy 54.533274 -289.438914) (xy 54.577736 -289.460012) (xy 54.618239 -289.487968)
			(xy 54.653732 -289.52206) (xy 54.683297 -289.561404) (xy 54.706168 -289.604981) (xy 54.721752 -289.651662)
			(xy 54.729647 -289.700239) (xy 54.730142 -289.724846) (xy 55.06899 -289.724846) (xy 55.07295 -289.675792)
			(xy 55.084727 -289.628008) (xy 55.104018 -289.582732) (xy 55.130321 -289.541136) (xy 55.162956 -289.504299)
			(xy 55.201077 -289.473174) (xy 55.243698 -289.448567) (xy 55.289714 -289.431115) (xy 55.337933 -289.421271)
			(xy 55.387108 -289.41929) (xy 55.435963 -289.425222) (xy 55.483234 -289.438914) (xy 55.527696 -289.460012)
			(xy 55.568199 -289.487968) (xy 55.603692 -289.52206) (xy 55.633257 -289.561404) (xy 55.656128 -289.604981)
			(xy 55.671712 -289.651662) (xy 55.679607 -289.700239) (xy 55.680102 -289.724846) (xy 56.01895 -289.724846)
			(xy 56.02291 -289.675792) (xy 56.034687 -289.628008) (xy 56.053978 -289.582732) (xy 56.080281 -289.541136)
			(xy 56.112916 -289.504299) (xy 56.151037 -289.473174) (xy 56.193658 -289.448567) (xy 56.239674 -289.431115)
			(xy 56.287893 -289.421271) (xy 56.337068 -289.41929) (xy 56.385923 -289.425222) (xy 56.433194 -289.438914)
			(xy 56.477656 -289.460012) (xy 56.518159 -289.487968) (xy 56.553652 -289.52206) (xy 56.583217 -289.561404)
			(xy 56.606088 -289.604981) (xy 56.621672 -289.651662) (xy 56.629567 -289.700239) (xy 56.630062 -289.724846)
			(xy 56.969164 -289.724846) (xy 56.973124 -289.675792) (xy 56.984901 -289.628008) (xy 57.004192 -289.582732)
			(xy 57.030495 -289.541136) (xy 57.06313 -289.504299) (xy 57.101251 -289.473174) (xy 57.143872 -289.448567)
			(xy 57.189888 -289.431115) (xy 57.238107 -289.421271) (xy 57.287282 -289.41929) (xy 57.336137 -289.425222)
			(xy 57.383408 -289.438914) (xy 57.42787 -289.460012) (xy 57.468373 -289.487968) (xy 57.503866 -289.52206)
			(xy 57.533431 -289.561404) (xy 57.556302 -289.604981) (xy 57.571886 -289.651662) (xy 57.579781 -289.700239)
			(xy 57.580276 -289.724846) (xy 57.919124 -289.724846) (xy 57.923084 -289.675792) (xy 57.934861 -289.628008)
			(xy 57.954152 -289.582732) (xy 57.980455 -289.541136) (xy 58.01309 -289.504299) (xy 58.051211 -289.473174)
			(xy 58.093832 -289.448567) (xy 58.139848 -289.431115) (xy 58.188067 -289.421271) (xy 58.237242 -289.41929)
			(xy 58.286097 -289.425222) (xy 58.333368 -289.438914) (xy 58.37783 -289.460012) (xy 58.418333 -289.487968)
			(xy 58.453826 -289.52206) (xy 58.483391 -289.561404) (xy 58.506262 -289.604981) (xy 58.521846 -289.651662)
			(xy 58.529741 -289.700239) (xy 58.530236 -289.724846) (xy 59.819044 -289.724846) (xy 59.823004 -289.675792)
			(xy 59.834781 -289.628008) (xy 59.854072 -289.582732) (xy 59.880375 -289.541136) (xy 59.91301 -289.504299)
			(xy 59.951131 -289.473174) (xy 59.993752 -289.448567) (xy 60.039768 -289.431115) (xy 60.087987 -289.421271)
			(xy 60.137162 -289.41929) (xy 60.186017 -289.425222) (xy 60.233288 -289.438914) (xy 60.27775 -289.460012)
			(xy 60.318253 -289.487968) (xy 60.353746 -289.52206) (xy 60.383311 -289.561404) (xy 60.406182 -289.604981)
			(xy 60.421766 -289.651662) (xy 60.429661 -289.700239) (xy 60.430156 -289.724846) (xy 60.769004 -289.724846)
			(xy 60.772964 -289.675792) (xy 60.784741 -289.628008) (xy 60.804032 -289.582732) (xy 60.830335 -289.541136)
			(xy 60.86297 -289.504299) (xy 60.901091 -289.473174) (xy 60.943712 -289.448567) (xy 60.989728 -289.431115)
			(xy 61.037947 -289.421271) (xy 61.087122 -289.41929) (xy 61.135977 -289.425222) (xy 61.183248 -289.438914)
			(xy 61.22771 -289.460012) (xy 61.268213 -289.487968) (xy 61.303706 -289.52206) (xy 61.333271 -289.561404)
			(xy 61.356142 -289.604981) (xy 61.371726 -289.651662) (xy 61.379621 -289.700239) (xy 61.380116 -289.724846)
			(xy 61.718964 -289.724846) (xy 61.722924 -289.675792) (xy 61.734701 -289.628008) (xy 61.753992 -289.582732)
			(xy 61.780295 -289.541136) (xy 61.81293 -289.504299) (xy 61.851051 -289.473174) (xy 61.893672 -289.448567)
			(xy 61.939688 -289.431115) (xy 61.987907 -289.421271) (xy 62.037082 -289.41929) (xy 62.085937 -289.425222)
			(xy 62.133208 -289.438914) (xy 62.17767 -289.460012) (xy 62.218173 -289.487968) (xy 62.253666 -289.52206)
			(xy 62.283231 -289.561404) (xy 62.306102 -289.604981) (xy 62.321686 -289.651662) (xy 62.329581 -289.700239)
			(xy 62.330076 -289.724846) (xy 62.669178 -289.724846) (xy 62.673138 -289.675792) (xy 62.684915 -289.628008)
			(xy 62.704206 -289.582732) (xy 62.730509 -289.541136) (xy 62.763144 -289.504299) (xy 62.801265 -289.473174)
			(xy 62.843886 -289.448567) (xy 62.889902 -289.431115) (xy 62.938121 -289.421271) (xy 62.987296 -289.41929)
			(xy 63.036151 -289.425222) (xy 63.083422 -289.438914) (xy 63.127884 -289.460012) (xy 63.168387 -289.487968)
			(xy 63.20388 -289.52206) (xy 63.233445 -289.561404) (xy 63.256316 -289.604981) (xy 63.2719 -289.651662)
			(xy 63.279795 -289.700239) (xy 63.28029 -289.724846) (xy 63.619138 -289.724846) (xy 63.623098 -289.675792)
			(xy 63.634875 -289.628008) (xy 63.654166 -289.582732) (xy 63.680469 -289.541136) (xy 63.713104 -289.504299)
			(xy 63.751225 -289.473174) (xy 63.793846 -289.448567) (xy 63.839862 -289.431115) (xy 63.888081 -289.421271)
			(xy 63.937256 -289.41929) (xy 63.986111 -289.425222) (xy 64.033382 -289.438914) (xy 64.077844 -289.460012)
			(xy 64.118347 -289.487968) (xy 64.15384 -289.52206) (xy 64.183405 -289.561404) (xy 64.206276 -289.604981)
			(xy 64.22186 -289.651662) (xy 64.229755 -289.700239) (xy 64.23025 -289.724846) (xy 64.569098 -289.724846)
			(xy 64.573058 -289.675792) (xy 64.584835 -289.628008) (xy 64.604126 -289.582732) (xy 64.630429 -289.541136)
			(xy 64.663064 -289.504299) (xy 64.701185 -289.473174) (xy 64.743806 -289.448567) (xy 64.789822 -289.431115)
			(xy 64.838041 -289.421271) (xy 64.887216 -289.41929) (xy 64.936071 -289.425222) (xy 64.983342 -289.438914)
			(xy 65.027804 -289.460012) (xy 65.068307 -289.487968) (xy 65.1038 -289.52206) (xy 65.133365 -289.561404)
			(xy 65.156236 -289.604981) (xy 65.17182 -289.651662) (xy 65.179715 -289.700239) (xy 65.18021 -289.724846)
			(xy 65.519058 -289.724846) (xy 65.523018 -289.675792) (xy 65.534795 -289.628008) (xy 65.554086 -289.582732)
			(xy 65.580389 -289.541136) (xy 65.613024 -289.504299) (xy 65.651145 -289.473174) (xy 65.693766 -289.448567)
			(xy 65.739782 -289.431115) (xy 65.788001 -289.421271) (xy 65.837176 -289.41929) (xy 65.886031 -289.425222)
			(xy 65.933302 -289.438914) (xy 65.977764 -289.460012) (xy 66.018267 -289.487968) (xy 66.05376 -289.52206)
			(xy 66.083325 -289.561404) (xy 66.106196 -289.604981) (xy 66.12178 -289.651662) (xy 66.129675 -289.700239)
			(xy 66.13017 -289.724846) (xy 66.469018 -289.724846) (xy 66.472978 -289.675792) (xy 66.484755 -289.628008)
			(xy 66.504046 -289.582732) (xy 66.530349 -289.541136) (xy 66.562984 -289.504299) (xy 66.601105 -289.473174)
			(xy 66.643726 -289.448567) (xy 66.689742 -289.431115) (xy 66.737961 -289.421271) (xy 66.787136 -289.41929)
			(xy 66.835991 -289.425222) (xy 66.883262 -289.438914) (xy 66.927724 -289.460012) (xy 66.968227 -289.487968)
			(xy 67.00372 -289.52206) (xy 67.033285 -289.561404) (xy 67.056156 -289.604981) (xy 67.07174 -289.651662)
			(xy 67.079635 -289.700239) (xy 67.08013 -289.724846) (xy 67.418978 -289.724846) (xy 67.422938 -289.675792)
			(xy 67.434715 -289.628008) (xy 67.454006 -289.582732) (xy 67.480309 -289.541136) (xy 67.512944 -289.504299)
			(xy 67.551065 -289.473174) (xy 67.593686 -289.448567) (xy 67.639702 -289.431115) (xy 67.687921 -289.421271)
			(xy 67.737096 -289.41929) (xy 67.785951 -289.425222) (xy 67.833222 -289.438914) (xy 67.877684 -289.460012)
			(xy 67.918187 -289.487968) (xy 67.95368 -289.52206) (xy 67.983245 -289.561404) (xy 68.006116 -289.604981)
			(xy 68.0217 -289.651662) (xy 68.029595 -289.700239) (xy 68.03009 -289.724846) (xy 68.368938 -289.724846)
			(xy 68.372898 -289.675792) (xy 68.384675 -289.628008) (xy 68.403966 -289.582732) (xy 68.430269 -289.541136)
			(xy 68.462904 -289.504299) (xy 68.501025 -289.473174) (xy 68.543646 -289.448567) (xy 68.589662 -289.431115)
			(xy 68.637881 -289.421271) (xy 68.687056 -289.41929) (xy 68.735911 -289.425222) (xy 68.783182 -289.438914)
			(xy 68.827644 -289.460012) (xy 68.868147 -289.487968) (xy 68.90364 -289.52206) (xy 68.933205 -289.561404)
			(xy 68.956076 -289.604981) (xy 68.97166 -289.651662) (xy 68.979555 -289.700239) (xy 68.98005 -289.724846)
			(xy 69.319152 -289.724846) (xy 69.323112 -289.675792) (xy 69.334889 -289.628008) (xy 69.35418 -289.582732)
			(xy 69.380483 -289.541136) (xy 69.413118 -289.504299) (xy 69.451239 -289.473174) (xy 69.49386 -289.448567)
			(xy 69.539876 -289.431115) (xy 69.588095 -289.421271) (xy 69.63727 -289.41929) (xy 69.686125 -289.425222)
			(xy 69.733396 -289.438914) (xy 69.777858 -289.460012) (xy 69.818361 -289.487968) (xy 69.853854 -289.52206)
			(xy 69.883419 -289.561404) (xy 69.90629 -289.604981) (xy 69.921874 -289.651662) (xy 69.929769 -289.700239)
			(xy 69.930264 -289.724846) (xy 70.269112 -289.724846) (xy 70.273072 -289.675792) (xy 70.284849 -289.628008)
			(xy 70.30414 -289.582732) (xy 70.330443 -289.541136) (xy 70.363078 -289.504299) (xy 70.401199 -289.473174)
			(xy 70.44382 -289.448567) (xy 70.489836 -289.431115) (xy 70.538055 -289.421271) (xy 70.58723 -289.41929)
			(xy 70.636085 -289.425222) (xy 70.683356 -289.438914) (xy 70.727818 -289.460012) (xy 70.768321 -289.487968)
			(xy 70.803814 -289.52206) (xy 70.833379 -289.561404) (xy 70.85625 -289.604981) (xy 70.871834 -289.651662)
			(xy 70.879729 -289.700239) (xy 70.880224 -289.724846) (xy 71.219072 -289.724846) (xy 71.223032 -289.675792)
			(xy 71.234809 -289.628008) (xy 71.2541 -289.582732) (xy 71.280403 -289.541136) (xy 71.313038 -289.504299)
			(xy 71.351159 -289.473174) (xy 71.39378 -289.448567) (xy 71.439796 -289.431115) (xy 71.488015 -289.421271)
			(xy 71.53719 -289.41929) (xy 71.586045 -289.425222) (xy 71.633316 -289.438914) (xy 71.677778 -289.460012)
			(xy 71.718281 -289.487968) (xy 71.753774 -289.52206) (xy 71.783339 -289.561404) (xy 71.80621 -289.604981)
			(xy 71.821794 -289.651662) (xy 71.829689 -289.700239) (xy 71.830184 -289.724846) (xy 72.169032 -289.724846)
			(xy 72.172992 -289.675792) (xy 72.184769 -289.628008) (xy 72.20406 -289.582732) (xy 72.230363 -289.541136)
			(xy 72.262998 -289.504299) (xy 72.301119 -289.473174) (xy 72.34374 -289.448567) (xy 72.389756 -289.431115)
			(xy 72.437975 -289.421271) (xy 72.48715 -289.41929) (xy 72.536005 -289.425222) (xy 72.583276 -289.438914)
			(xy 72.627738 -289.460012) (xy 72.668241 -289.487968) (xy 72.703734 -289.52206) (xy 72.733299 -289.561404)
			(xy 72.75617 -289.604981) (xy 72.771754 -289.651662) (xy 72.779649 -289.700239) (xy 72.779976 -289.716507)
			(xy 73.119127 -289.716507) (xy 73.124496 -289.667166) (xy 73.137775 -289.619343) (xy 73.158617 -289.574298)
			(xy 73.186471 -289.533218) (xy 73.220603 -289.497186) (xy 73.260116 -289.46715) (xy 73.303967 -289.443902)
			(xy 73.351001 -289.428054) (xy 73.39998 -289.420024) (xy 73.424796 -289.419538) (xy 73.438979 -289.419714)
			(xy 73.467219 -289.422387) (xy 73.481184 -289.424872) (xy 73.49363 -289.427158) (xy 73.517252 -289.419792)
			(xy 73.594722 -289.342322) (xy 73.602088 -289.3187) (xy 73.599802 -289.306254) (xy 73.597323 -289.292289)
			(xy 73.594653 -289.264049) (xy 73.594468 -289.249866) (xy 73.59499 -289.224611) (xy 73.603303 -289.174789)
			(xy 73.619704 -289.127015) (xy 73.643745 -289.082592) (xy 73.674769 -289.042732) (xy 73.711931 -289.008522)
			(xy 73.754217 -288.980896) (xy 73.800473 -288.960606) (xy 73.849438 -288.948206) (xy 73.899776 -288.944035)
			(xy 73.950114 -288.948206) (xy 73.999079 -288.960606) (xy 74.045335 -288.980896) (xy 74.087621 -289.008522)
			(xy 74.124783 -289.042732) (xy 74.155807 -289.082592) (xy 74.179848 -289.127015) (xy 74.196249 -289.174789)
			(xy 74.204562 -289.224611) (xy 74.205084 -289.249866) (xy 74.204903 -289.264049) (xy 74.202234 -289.292289)
			(xy 74.19975 -289.306254) (xy 74.197464 -289.3187) (xy 74.20483 -289.342576) (xy 74.282046 -289.419792)
			(xy 74.306176 -289.427158) (xy 74.318368 -289.424872) (xy 74.332396 -289.42238) (xy 74.360764 -289.419713)
			(xy 74.37501 -289.419538) (xy 74.399829 -289.419989) (xy 74.448813 -289.42802) (xy 74.495853 -289.443871)
			(xy 74.539708 -289.467122) (xy 74.579225 -289.497162) (xy 74.613361 -289.5332) (xy 74.641217 -289.574284)
			(xy 74.66206 -289.619335) (xy 74.675341 -289.667163) (xy 74.680709 -289.71651) (xy 74.680257 -289.724846)
			(xy 75.969126 -289.724846) (xy 75.973086 -289.675792) (xy 75.984863 -289.628008) (xy 76.004154 -289.582732)
			(xy 76.030457 -289.541136) (xy 76.063092 -289.504299) (xy 76.101213 -289.473174) (xy 76.143834 -289.448567)
			(xy 76.18985 -289.431115) (xy 76.238069 -289.421271) (xy 76.287244 -289.41929) (xy 76.336099 -289.425222)
			(xy 76.38337 -289.438914) (xy 76.427832 -289.460012) (xy 76.468335 -289.487968) (xy 76.503828 -289.52206)
			(xy 76.533393 -289.561404) (xy 76.556264 -289.604981) (xy 76.571848 -289.651662) (xy 76.579743 -289.700239)
			(xy 76.580238 -289.724846) (xy 76.919086 -289.724846) (xy 76.923046 -289.675792) (xy 76.934823 -289.628008)
			(xy 76.954114 -289.582732) (xy 76.980417 -289.541136) (xy 77.013052 -289.504299) (xy 77.051173 -289.473174)
			(xy 77.093794 -289.448567) (xy 77.13981 -289.431115) (xy 77.188029 -289.421271) (xy 77.237204 -289.41929)
			(xy 77.286059 -289.425222) (xy 77.33333 -289.438914) (xy 77.377792 -289.460012) (xy 77.418295 -289.487968)
			(xy 77.453788 -289.52206) (xy 77.483353 -289.561404) (xy 77.506224 -289.604981) (xy 77.521808 -289.651662)
			(xy 77.529703 -289.700239) (xy 77.530198 -289.724846) (xy 77.869046 -289.724846) (xy 77.873006 -289.675792)
			(xy 77.884783 -289.628008) (xy 77.904074 -289.582732) (xy 77.930377 -289.541136) (xy 77.963012 -289.504299)
			(xy 78.001133 -289.473174) (xy 78.043754 -289.448567) (xy 78.08977 -289.431115) (xy 78.137989 -289.421271)
			(xy 78.187164 -289.41929) (xy 78.236019 -289.425222) (xy 78.28329 -289.438914) (xy 78.327752 -289.460012)
			(xy 78.368255 -289.487968) (xy 78.403748 -289.52206) (xy 78.433313 -289.561404) (xy 78.456184 -289.604981)
			(xy 78.471768 -289.651662) (xy 78.479663 -289.700239) (xy 78.480158 -289.724846) (xy 78.479663 -289.749453)
			(xy 78.471768 -289.79803) (xy 78.456184 -289.844711) (xy 78.433313 -289.888288) (xy 78.403748 -289.927632)
			(xy 78.368255 -289.961724) (xy 78.327752 -289.98968) (xy 78.28329 -290.010778) (xy 78.236019 -290.02447)
			(xy 78.187164 -290.030402) (xy 78.137989 -290.028421) (xy 78.08977 -290.018577) (xy 78.043754 -290.001125)
			(xy 78.001133 -289.976518) (xy 77.963012 -289.945393) (xy 77.930377 -289.908556) (xy 77.904074 -289.86696)
			(xy 77.884783 -289.821684) (xy 77.873006 -289.7739) (xy 77.869046 -289.724846) (xy 77.530198 -289.724846)
			(xy 77.529703 -289.749453) (xy 77.521808 -289.79803) (xy 77.506224 -289.844711) (xy 77.483353 -289.888288)
			(xy 77.453788 -289.927632) (xy 77.418295 -289.961724) (xy 77.377792 -289.98968) (xy 77.33333 -290.010778)
			(xy 77.286059 -290.02447) (xy 77.237204 -290.030402) (xy 77.188029 -290.028421) (xy 77.13981 -290.018577)
			(xy 77.093794 -290.001125) (xy 77.051173 -289.976518) (xy 77.013052 -289.945393) (xy 76.980417 -289.908556)
			(xy 76.954114 -289.86696) (xy 76.934823 -289.821684) (xy 76.923046 -289.7739) (xy 76.919086 -289.724846)
			(xy 76.580238 -289.724846) (xy 76.579743 -289.749453) (xy 76.571848 -289.79803) (xy 76.556264 -289.844711)
			(xy 76.533393 -289.888288) (xy 76.503828 -289.927632) (xy 76.468335 -289.961724) (xy 76.427832 -289.98968)
			(xy 76.38337 -290.010778) (xy 76.336099 -290.02447) (xy 76.287244 -290.030402) (xy 76.238069 -290.028421)
			(xy 76.18985 -290.018577) (xy 76.143834 -290.001125) (xy 76.101213 -289.976518) (xy 76.063092 -289.945393)
			(xy 76.030457 -289.908556) (xy 76.004154 -289.86696) (xy 75.984863 -289.821684) (xy 75.973086 -289.7739)
			(xy 75.969126 -289.724846) (xy 74.680257 -289.724846) (xy 74.678023 -289.766076) (xy 74.667354 -289.814554)
			(xy 74.648983 -289.860667) (xy 74.623394 -289.903201) (xy 74.591261 -289.941035) (xy 74.553431 -289.973173)
			(xy 74.510899 -289.998767) (xy 74.464788 -290.017143) (xy 74.416311 -290.027818) (xy 74.366746 -290.03051)
			(xy 74.317399 -290.025147) (xy 74.269568 -290.011873) (xy 74.224516 -289.991035) (xy 74.183428 -289.963183)
			(xy 74.147387 -289.929051) (xy 74.117342 -289.889539) (xy 74.094085 -289.845686) (xy 74.078229 -289.798648)
			(xy 74.070192 -289.749665) (xy 74.069702 -289.724846) (xy 74.069885 -289.710663) (xy 74.072553 -289.682423)
			(xy 74.075036 -289.668458) (xy 74.077322 -289.656012) (xy 74.069956 -289.632136) (xy 73.99274 -289.55492)
			(xy 73.96861 -289.547554) (xy 73.956418 -289.54984) (xy 73.942388 -289.55232) (xy 73.914022 -289.554995)
			(xy 73.899776 -289.555174) (xy 73.885593 -289.555001) (xy 73.857353 -289.552327) (xy 73.843388 -289.54984)
			(xy 73.830942 -289.547554) (xy 73.80732 -289.55492) (xy 73.72985 -289.63239) (xy 73.722484 -289.656012)
			(xy 73.72477 -289.668458) (xy 73.72725 -289.682423) (xy 73.72992 -289.710663) (xy 73.730104 -289.724846)
			(xy 73.729573 -289.749662) (xy 73.721536 -289.79864) (xy 73.705682 -289.845672) (xy 73.682427 -289.88952)
			(xy 73.652386 -289.929028) (xy 73.616349 -289.963156) (xy 73.575265 -289.991004) (xy 73.530218 -290.011839)
			(xy 73.482393 -290.025112) (xy 73.433051 -290.030474) (xy 73.383491 -290.027782) (xy 73.33502 -290.017108)
			(xy 73.288914 -289.998733) (xy 73.246388 -289.973142) (xy 73.208562 -289.941008) (xy 73.176434 -289.903178)
			(xy 73.150848 -289.860648) (xy 73.13248 -289.81454) (xy 73.121812 -289.766067) (xy 73.119127 -289.716507)
			(xy 72.779976 -289.716507) (xy 72.780144 -289.724846) (xy 72.779649 -289.749453) (xy 72.771754 -289.79803)
			(xy 72.75617 -289.844711) (xy 72.733299 -289.888288) (xy 72.703734 -289.927632) (xy 72.668241 -289.961724)
			(xy 72.627738 -289.98968) (xy 72.583276 -290.010778) (xy 72.536005 -290.02447) (xy 72.48715 -290.030402)
			(xy 72.437975 -290.028421) (xy 72.389756 -290.018577) (xy 72.34374 -290.001125) (xy 72.301119 -289.976518)
			(xy 72.262998 -289.945393) (xy 72.230363 -289.908556) (xy 72.20406 -289.86696) (xy 72.184769 -289.821684)
			(xy 72.172992 -289.7739) (xy 72.169032 -289.724846) (xy 71.830184 -289.724846) (xy 71.829689 -289.749453)
			(xy 71.821794 -289.79803) (xy 71.80621 -289.844711) (xy 71.783339 -289.888288) (xy 71.753774 -289.927632)
			(xy 71.718281 -289.961724) (xy 71.677778 -289.98968) (xy 71.633316 -290.010778) (xy 71.586045 -290.02447)
			(xy 71.53719 -290.030402) (xy 71.488015 -290.028421) (xy 71.439796 -290.018577) (xy 71.39378 -290.001125)
			(xy 71.351159 -289.976518) (xy 71.313038 -289.945393) (xy 71.280403 -289.908556) (xy 71.2541 -289.86696)
			(xy 71.234809 -289.821684) (xy 71.223032 -289.7739) (xy 71.219072 -289.724846) (xy 70.880224 -289.724846)
			(xy 70.879729 -289.749453) (xy 70.871834 -289.79803) (xy 70.85625 -289.844711) (xy 70.833379 -289.888288)
			(xy 70.803814 -289.927632) (xy 70.768321 -289.961724) (xy 70.727818 -289.98968) (xy 70.683356 -290.010778)
			(xy 70.636085 -290.02447) (xy 70.58723 -290.030402) (xy 70.538055 -290.028421) (xy 70.489836 -290.018577)
			(xy 70.44382 -290.001125) (xy 70.401199 -289.976518) (xy 70.363078 -289.945393) (xy 70.330443 -289.908556)
			(xy 70.30414 -289.86696) (xy 70.284849 -289.821684) (xy 70.273072 -289.7739) (xy 70.269112 -289.724846)
			(xy 69.930264 -289.724846) (xy 69.929769 -289.749453) (xy 69.921874 -289.79803) (xy 69.90629 -289.844711)
			(xy 69.883419 -289.888288) (xy 69.853854 -289.927632) (xy 69.818361 -289.961724) (xy 69.777858 -289.98968)
			(xy 69.733396 -290.010778) (xy 69.686125 -290.02447) (xy 69.63727 -290.030402) (xy 69.588095 -290.028421)
			(xy 69.539876 -290.018577) (xy 69.49386 -290.001125) (xy 69.451239 -289.976518) (xy 69.413118 -289.945393)
			(xy 69.380483 -289.908556) (xy 69.35418 -289.86696) (xy 69.334889 -289.821684) (xy 69.323112 -289.7739)
			(xy 69.319152 -289.724846) (xy 68.98005 -289.724846) (xy 68.979555 -289.749453) (xy 68.97166 -289.79803)
			(xy 68.956076 -289.844711) (xy 68.933205 -289.888288) (xy 68.90364 -289.927632) (xy 68.868147 -289.961724)
			(xy 68.827644 -289.98968) (xy 68.783182 -290.010778) (xy 68.735911 -290.02447) (xy 68.687056 -290.030402)
			(xy 68.637881 -290.028421) (xy 68.589662 -290.018577) (xy 68.543646 -290.001125) (xy 68.501025 -289.976518)
			(xy 68.462904 -289.945393) (xy 68.430269 -289.908556) (xy 68.403966 -289.86696) (xy 68.384675 -289.821684)
			(xy 68.372898 -289.7739) (xy 68.368938 -289.724846) (xy 68.03009 -289.724846) (xy 68.029595 -289.749453)
			(xy 68.0217 -289.79803) (xy 68.006116 -289.844711) (xy 67.983245 -289.888288) (xy 67.95368 -289.927632)
			(xy 67.918187 -289.961724) (xy 67.877684 -289.98968) (xy 67.833222 -290.010778) (xy 67.785951 -290.02447)
			(xy 67.737096 -290.030402) (xy 67.687921 -290.028421) (xy 67.639702 -290.018577) (xy 67.593686 -290.001125)
			(xy 67.551065 -289.976518) (xy 67.512944 -289.945393) (xy 67.480309 -289.908556) (xy 67.454006 -289.86696)
			(xy 67.434715 -289.821684) (xy 67.422938 -289.7739) (xy 67.418978 -289.724846) (xy 67.08013 -289.724846)
			(xy 67.079635 -289.749453) (xy 67.07174 -289.79803) (xy 67.056156 -289.844711) (xy 67.033285 -289.888288)
			(xy 67.00372 -289.927632) (xy 66.968227 -289.961724) (xy 66.927724 -289.98968) (xy 66.883262 -290.010778)
			(xy 66.835991 -290.02447) (xy 66.787136 -290.030402) (xy 66.737961 -290.028421) (xy 66.689742 -290.018577)
			(xy 66.643726 -290.001125) (xy 66.601105 -289.976518) (xy 66.562984 -289.945393) (xy 66.530349 -289.908556)
			(xy 66.504046 -289.86696) (xy 66.484755 -289.821684) (xy 66.472978 -289.7739) (xy 66.469018 -289.724846)
			(xy 66.13017 -289.724846) (xy 66.129675 -289.749453) (xy 66.12178 -289.79803) (xy 66.106196 -289.844711)
			(xy 66.083325 -289.888288) (xy 66.05376 -289.927632) (xy 66.018267 -289.961724) (xy 65.977764 -289.98968)
			(xy 65.933302 -290.010778) (xy 65.886031 -290.02447) (xy 65.837176 -290.030402) (xy 65.788001 -290.028421)
			(xy 65.739782 -290.018577) (xy 65.693766 -290.001125) (xy 65.651145 -289.976518) (xy 65.613024 -289.945393)
			(xy 65.580389 -289.908556) (xy 65.554086 -289.86696) (xy 65.534795 -289.821684) (xy 65.523018 -289.7739)
			(xy 65.519058 -289.724846) (xy 65.18021 -289.724846) (xy 65.179715 -289.749453) (xy 65.17182 -289.79803)
			(xy 65.156236 -289.844711) (xy 65.133365 -289.888288) (xy 65.1038 -289.927632) (xy 65.068307 -289.961724)
			(xy 65.027804 -289.98968) (xy 64.983342 -290.010778) (xy 64.936071 -290.02447) (xy 64.887216 -290.030402)
			(xy 64.838041 -290.028421) (xy 64.789822 -290.018577) (xy 64.743806 -290.001125) (xy 64.701185 -289.976518)
			(xy 64.663064 -289.945393) (xy 64.630429 -289.908556) (xy 64.604126 -289.86696) (xy 64.584835 -289.821684)
			(xy 64.573058 -289.7739) (xy 64.569098 -289.724846) (xy 64.23025 -289.724846) (xy 64.229755 -289.749453)
			(xy 64.22186 -289.79803) (xy 64.206276 -289.844711) (xy 64.183405 -289.888288) (xy 64.15384 -289.927632)
			(xy 64.118347 -289.961724) (xy 64.077844 -289.98968) (xy 64.033382 -290.010778) (xy 63.986111 -290.02447)
			(xy 63.937256 -290.030402) (xy 63.888081 -290.028421) (xy 63.839862 -290.018577) (xy 63.793846 -290.001125)
			(xy 63.751225 -289.976518) (xy 63.713104 -289.945393) (xy 63.680469 -289.908556) (xy 63.654166 -289.86696)
			(xy 63.634875 -289.821684) (xy 63.623098 -289.7739) (xy 63.619138 -289.724846) (xy 63.28029 -289.724846)
			(xy 63.279795 -289.749453) (xy 63.2719 -289.79803) (xy 63.256316 -289.844711) (xy 63.233445 -289.888288)
			(xy 63.20388 -289.927632) (xy 63.168387 -289.961724) (xy 63.127884 -289.98968) (xy 63.083422 -290.010778)
			(xy 63.036151 -290.02447) (xy 62.987296 -290.030402) (xy 62.938121 -290.028421) (xy 62.889902 -290.018577)
			(xy 62.843886 -290.001125) (xy 62.801265 -289.976518) (xy 62.763144 -289.945393) (xy 62.730509 -289.908556)
			(xy 62.704206 -289.86696) (xy 62.684915 -289.821684) (xy 62.673138 -289.7739) (xy 62.669178 -289.724846)
			(xy 62.330076 -289.724846) (xy 62.329581 -289.749453) (xy 62.321686 -289.79803) (xy 62.306102 -289.844711)
			(xy 62.283231 -289.888288) (xy 62.253666 -289.927632) (xy 62.218173 -289.961724) (xy 62.17767 -289.98968)
			(xy 62.133208 -290.010778) (xy 62.085937 -290.02447) (xy 62.037082 -290.030402) (xy 61.987907 -290.028421)
			(xy 61.939688 -290.018577) (xy 61.893672 -290.001125) (xy 61.851051 -289.976518) (xy 61.81293 -289.945393)
			(xy 61.780295 -289.908556) (xy 61.753992 -289.86696) (xy 61.734701 -289.821684) (xy 61.722924 -289.7739)
			(xy 61.718964 -289.724846) (xy 61.380116 -289.724846) (xy 61.379621 -289.749453) (xy 61.371726 -289.79803)
			(xy 61.356142 -289.844711) (xy 61.333271 -289.888288) (xy 61.303706 -289.927632) (xy 61.268213 -289.961724)
			(xy 61.22771 -289.98968) (xy 61.183248 -290.010778) (xy 61.135977 -290.02447) (xy 61.087122 -290.030402)
			(xy 61.037947 -290.028421) (xy 60.989728 -290.018577) (xy 60.943712 -290.001125) (xy 60.901091 -289.976518)
			(xy 60.86297 -289.945393) (xy 60.830335 -289.908556) (xy 60.804032 -289.86696) (xy 60.784741 -289.821684)
			(xy 60.772964 -289.7739) (xy 60.769004 -289.724846) (xy 60.430156 -289.724846) (xy 60.429661 -289.749453)
			(xy 60.421766 -289.79803) (xy 60.406182 -289.844711) (xy 60.383311 -289.888288) (xy 60.353746 -289.927632)
			(xy 60.318253 -289.961724) (xy 60.27775 -289.98968) (xy 60.233288 -290.010778) (xy 60.186017 -290.02447)
			(xy 60.137162 -290.030402) (xy 60.087987 -290.028421) (xy 60.039768 -290.018577) (xy 59.993752 -290.001125)
			(xy 59.951131 -289.976518) (xy 59.91301 -289.945393) (xy 59.880375 -289.908556) (xy 59.854072 -289.86696)
			(xy 59.834781 -289.821684) (xy 59.823004 -289.7739) (xy 59.819044 -289.724846) (xy 58.530236 -289.724846)
			(xy 58.529741 -289.749453) (xy 58.521846 -289.79803) (xy 58.506262 -289.844711) (xy 58.483391 -289.888288)
			(xy 58.453826 -289.927632) (xy 58.418333 -289.961724) (xy 58.37783 -289.98968) (xy 58.333368 -290.010778)
			(xy 58.286097 -290.02447) (xy 58.237242 -290.030402) (xy 58.188067 -290.028421) (xy 58.139848 -290.018577)
			(xy 58.093832 -290.001125) (xy 58.051211 -289.976518) (xy 58.01309 -289.945393) (xy 57.980455 -289.908556)
			(xy 57.954152 -289.86696) (xy 57.934861 -289.821684) (xy 57.923084 -289.7739) (xy 57.919124 -289.724846)
			(xy 57.580276 -289.724846) (xy 57.579781 -289.749453) (xy 57.571886 -289.79803) (xy 57.556302 -289.844711)
			(xy 57.533431 -289.888288) (xy 57.503866 -289.927632) (xy 57.468373 -289.961724) (xy 57.42787 -289.98968)
			(xy 57.383408 -290.010778) (xy 57.336137 -290.02447) (xy 57.287282 -290.030402) (xy 57.238107 -290.028421)
			(xy 57.189888 -290.018577) (xy 57.143872 -290.001125) (xy 57.101251 -289.976518) (xy 57.06313 -289.945393)
			(xy 57.030495 -289.908556) (xy 57.004192 -289.86696) (xy 56.984901 -289.821684) (xy 56.973124 -289.7739)
			(xy 56.969164 -289.724846) (xy 56.630062 -289.724846) (xy 56.629567 -289.749453) (xy 56.621672 -289.79803)
			(xy 56.606088 -289.844711) (xy 56.583217 -289.888288) (xy 56.553652 -289.927632) (xy 56.518159 -289.961724)
			(xy 56.477656 -289.98968) (xy 56.433194 -290.010778) (xy 56.385923 -290.02447) (xy 56.337068 -290.030402)
			(xy 56.287893 -290.028421) (xy 56.239674 -290.018577) (xy 56.193658 -290.001125) (xy 56.151037 -289.976518)
			(xy 56.112916 -289.945393) (xy 56.080281 -289.908556) (xy 56.053978 -289.86696) (xy 56.034687 -289.821684)
			(xy 56.02291 -289.7739) (xy 56.01895 -289.724846) (xy 55.680102 -289.724846) (xy 55.679607 -289.749453)
			(xy 55.671712 -289.79803) (xy 55.656128 -289.844711) (xy 55.633257 -289.888288) (xy 55.603692 -289.927632)
			(xy 55.568199 -289.961724) (xy 55.527696 -289.98968) (xy 55.483234 -290.010778) (xy 55.435963 -290.02447)
			(xy 55.387108 -290.030402) (xy 55.337933 -290.028421) (xy 55.289714 -290.018577) (xy 55.243698 -290.001125)
			(xy 55.201077 -289.976518) (xy 55.162956 -289.945393) (xy 55.130321 -289.908556) (xy 55.104018 -289.86696)
			(xy 55.084727 -289.821684) (xy 55.07295 -289.7739) (xy 55.06899 -289.724846) (xy 54.730142 -289.724846)
			(xy 54.729647 -289.749453) (xy 54.721752 -289.79803) (xy 54.706168 -289.844711) (xy 54.683297 -289.888288)
			(xy 54.653732 -289.927632) (xy 54.618239 -289.961724) (xy 54.577736 -289.98968) (xy 54.533274 -290.010778)
			(xy 54.486003 -290.02447) (xy 54.437148 -290.030402) (xy 54.387973 -290.028421) (xy 54.339754 -290.018577)
			(xy 54.293738 -290.001125) (xy 54.251117 -289.976518) (xy 54.212996 -289.945393) (xy 54.180361 -289.908556)
			(xy 54.154058 -289.86696) (xy 54.134767 -289.821684) (xy 54.12299 -289.7739) (xy 54.11903 -289.724846)
			(xy 53.780182 -289.724846) (xy 53.779687 -289.749453) (xy 53.771792 -289.79803) (xy 53.756208 -289.844711)
			(xy 53.733337 -289.888288) (xy 53.703772 -289.927632) (xy 53.668279 -289.961724) (xy 53.627776 -289.98968)
			(xy 53.583314 -290.010778) (xy 53.536043 -290.02447) (xy 53.487188 -290.030402) (xy 53.438013 -290.028421)
			(xy 53.389794 -290.018577) (xy 53.343778 -290.001125) (xy 53.301157 -289.976518) (xy 53.263036 -289.945393)
			(xy 53.230401 -289.908556) (xy 53.204098 -289.86696) (xy 53.184807 -289.821684) (xy 53.17303 -289.7739)
			(xy 53.16907 -289.724846) (xy 52.830222 -289.724846) (xy 52.829727 -289.749453) (xy 52.821832 -289.79803)
			(xy 52.806248 -289.844711) (xy 52.783377 -289.888288) (xy 52.753812 -289.927632) (xy 52.718319 -289.961724)
			(xy 52.677816 -289.98968) (xy 52.633354 -290.010778) (xy 52.586083 -290.02447) (xy 52.537228 -290.030402)
			(xy 52.488053 -290.028421) (xy 52.439834 -290.018577) (xy 52.393818 -290.001125) (xy 52.351197 -289.976518)
			(xy 52.313076 -289.945393) (xy 52.280441 -289.908556) (xy 52.254138 -289.86696) (xy 52.234847 -289.821684)
			(xy 52.22307 -289.7739) (xy 52.21911 -289.724846) (xy 51.880262 -289.724846) (xy 51.879767 -289.749453)
			(xy 51.871872 -289.79803) (xy 51.856288 -289.844711) (xy 51.833417 -289.888288) (xy 51.803852 -289.927632)
			(xy 51.768359 -289.961724) (xy 51.727856 -289.98968) (xy 51.683394 -290.010778) (xy 51.636123 -290.02447)
			(xy 51.587268 -290.030402) (xy 51.538093 -290.028421) (xy 51.489874 -290.018577) (xy 51.443858 -290.001125)
			(xy 51.401237 -289.976518) (xy 51.363116 -289.945393) (xy 51.330481 -289.908556) (xy 51.304178 -289.86696)
			(xy 51.284887 -289.821684) (xy 51.27311 -289.7739) (xy 51.26915 -289.724846) (xy 50.930302 -289.724846)
			(xy 50.929807 -289.749453) (xy 50.921912 -289.79803) (xy 50.906328 -289.844711) (xy 50.883457 -289.888288)
			(xy 50.853892 -289.927632) (xy 50.818399 -289.961724) (xy 50.777896 -289.98968) (xy 50.733434 -290.010778)
			(xy 50.686163 -290.02447) (xy 50.637308 -290.030402) (xy 50.588133 -290.028421) (xy 50.539914 -290.018577)
			(xy 50.493898 -290.001125) (xy 50.451277 -289.976518) (xy 50.413156 -289.945393) (xy 50.380521 -289.908556)
			(xy 50.354218 -289.86696) (xy 50.334927 -289.821684) (xy 50.32315 -289.7739) (xy 50.31919 -289.724846)
			(xy 49.980088 -289.724846) (xy 49.979593 -289.749453) (xy 49.971698 -289.79803) (xy 49.956114 -289.844711)
			(xy 49.933243 -289.888288) (xy 49.903678 -289.927632) (xy 49.868185 -289.961724) (xy 49.827682 -289.98968)
			(xy 49.78322 -290.010778) (xy 49.735949 -290.02447) (xy 49.687094 -290.030402) (xy 49.637919 -290.028421)
			(xy 49.5897 -290.018577) (xy 49.543684 -290.001125) (xy 49.501063 -289.976518) (xy 49.462942 -289.945393)
			(xy 49.430307 -289.908556) (xy 49.404004 -289.86696) (xy 49.384713 -289.821684) (xy 49.372936 -289.7739)
			(xy 49.368976 -289.724846) (xy 49.030128 -289.724846) (xy 49.029633 -289.749453) (xy 49.021738 -289.79803)
			(xy 49.006154 -289.844711) (xy 48.983283 -289.888288) (xy 48.953718 -289.927632) (xy 48.918225 -289.961724)
			(xy 48.877722 -289.98968) (xy 48.83326 -290.010778) (xy 48.785989 -290.02447) (xy 48.737134 -290.030402)
			(xy 48.687959 -290.028421) (xy 48.63974 -290.018577) (xy 48.593724 -290.001125) (xy 48.551103 -289.976518)
			(xy 48.512982 -289.945393) (xy 48.480347 -289.908556) (xy 48.454044 -289.86696) (xy 48.434753 -289.821684)
			(xy 48.422976 -289.7739) (xy 48.419016 -289.724846) (xy 48.080168 -289.724846) (xy 48.079673 -289.749453)
			(xy 48.071778 -289.79803) (xy 48.056194 -289.844711) (xy 48.033323 -289.888288) (xy 48.003758 -289.927632)
			(xy 47.968265 -289.961724) (xy 47.927762 -289.98968) (xy 47.8833 -290.010778) (xy 47.836029 -290.02447)
			(xy 47.787174 -290.030402) (xy 47.737999 -290.028421) (xy 47.68978 -290.018577) (xy 47.643764 -290.001125)
			(xy 47.601143 -289.976518) (xy 47.563022 -289.945393) (xy 47.530387 -289.908556) (xy 47.504084 -289.86696)
			(xy 47.484793 -289.821684) (xy 47.473016 -289.7739) (xy 47.469056 -289.724846) (xy 47.130208 -289.724846)
			(xy 47.129713 -289.749453) (xy 47.121818 -289.79803) (xy 47.106234 -289.844711) (xy 47.083363 -289.888288)
			(xy 47.053798 -289.927632) (xy 47.018305 -289.961724) (xy 46.977802 -289.98968) (xy 46.93334 -290.010778)
			(xy 46.886069 -290.02447) (xy 46.837214 -290.030402) (xy 46.788039 -290.028421) (xy 46.73982 -290.018577)
			(xy 46.693804 -290.001125) (xy 46.651183 -289.976518) (xy 46.613062 -289.945393) (xy 46.580427 -289.908556)
			(xy 46.554124 -289.86696) (xy 46.534833 -289.821684) (xy 46.523056 -289.7739) (xy 46.519096 -289.724846)
			(xy 46.180248 -289.724846) (xy 46.179753 -289.749453) (xy 46.171858 -289.79803) (xy 46.156274 -289.844711)
			(xy 46.133403 -289.888288) (xy 46.103838 -289.927632) (xy 46.068345 -289.961724) (xy 46.027842 -289.98968)
			(xy 45.98338 -290.010778) (xy 45.936109 -290.02447) (xy 45.887254 -290.030402) (xy 45.838079 -290.028421)
			(xy 45.78986 -290.018577) (xy 45.743844 -290.001125) (xy 45.701223 -289.976518) (xy 45.663102 -289.945393)
			(xy 45.630467 -289.908556) (xy 45.604164 -289.86696) (xy 45.584873 -289.821684) (xy 45.573096 -289.7739)
			(xy 45.569136 -289.724846) (xy 45.230288 -289.724846) (xy 45.229793 -289.749453) (xy 45.221898 -289.79803)
			(xy 45.206314 -289.844711) (xy 45.183443 -289.888288) (xy 45.153878 -289.927632) (xy 45.118385 -289.961724)
			(xy 45.077882 -289.98968) (xy 45.03342 -290.010778) (xy 44.986149 -290.02447) (xy 44.937294 -290.030402)
			(xy 44.888119 -290.028421) (xy 44.8399 -290.018577) (xy 44.793884 -290.001125) (xy 44.751263 -289.976518)
			(xy 44.713142 -289.945393) (xy 44.680507 -289.908556) (xy 44.654204 -289.86696) (xy 44.634913 -289.821684)
			(xy 44.623136 -289.7739) (xy 44.619176 -289.724846) (xy 44.280074 -289.724846) (xy 44.279579 -289.749453)
			(xy 44.271684 -289.79803) (xy 44.2561 -289.844711) (xy 44.233229 -289.888288) (xy 44.203664 -289.927632)
			(xy 44.168171 -289.961724) (xy 44.127668 -289.98968) (xy 44.083206 -290.010778) (xy 44.035935 -290.02447)
			(xy 43.98708 -290.030402) (xy 43.937905 -290.028421) (xy 43.889686 -290.018577) (xy 43.84367 -290.001125)
			(xy 43.801049 -289.976518) (xy 43.762928 -289.945393) (xy 43.730293 -289.908556) (xy 43.70399 -289.86696)
			(xy 43.684699 -289.821684) (xy 43.672922 -289.7739) (xy 43.668962 -289.724846) (xy 43.330114 -289.724846)
			(xy 43.329619 -289.749453) (xy 43.321724 -289.79803) (xy 43.30614 -289.844711) (xy 43.283269 -289.888288)
			(xy 43.253704 -289.927632) (xy 43.218211 -289.961724) (xy 43.177708 -289.98968) (xy 43.133246 -290.010778)
			(xy 43.085975 -290.02447) (xy 43.03712 -290.030402) (xy 42.987945 -290.028421) (xy 42.939726 -290.018577)
			(xy 42.89371 -290.001125) (xy 42.851089 -289.976518) (xy 42.812968 -289.945393) (xy 42.780333 -289.908556)
			(xy 42.75403 -289.86696) (xy 42.734739 -289.821684) (xy 42.722962 -289.7739) (xy 42.719002 -289.724846)
			(xy 42.380154 -289.724846) (xy 42.379659 -289.749453) (xy 42.371764 -289.79803) (xy 42.35618 -289.844711)
			(xy 42.333309 -289.888288) (xy 42.303744 -289.927632) (xy 42.268251 -289.961724) (xy 42.227748 -289.98968)
			(xy 42.183286 -290.010778) (xy 42.136015 -290.02447) (xy 42.08716 -290.030402) (xy 42.037985 -290.028421)
			(xy 41.989766 -290.018577) (xy 41.94375 -290.001125) (xy 41.901129 -289.976518) (xy 41.863008 -289.945393)
			(xy 41.830373 -289.908556) (xy 41.80407 -289.86696) (xy 41.784779 -289.821684) (xy 41.773002 -289.7739)
			(xy 41.769042 -289.724846) (xy 41.430194 -289.724846) (xy 41.429699 -289.749453) (xy 41.421804 -289.79803)
			(xy 41.40622 -289.844711) (xy 41.383349 -289.888288) (xy 41.353784 -289.927632) (xy 41.318291 -289.961724)
			(xy 41.277788 -289.98968) (xy 41.233326 -290.010778) (xy 41.186055 -290.02447) (xy 41.1372 -290.030402)
			(xy 41.088025 -290.028421) (xy 41.039806 -290.018577) (xy 40.99379 -290.001125) (xy 40.951169 -289.976518)
			(xy 40.913048 -289.945393) (xy 40.880413 -289.908556) (xy 40.85411 -289.86696) (xy 40.834819 -289.821684)
			(xy 40.823042 -289.7739) (xy 40.819082 -289.724846) (xy 40.480234 -289.724846) (xy 40.479739 -289.749453)
			(xy 40.471844 -289.79803) (xy 40.45626 -289.844711) (xy 40.433389 -289.888288) (xy 40.403824 -289.927632)
			(xy 40.368331 -289.961724) (xy 40.327828 -289.98968) (xy 40.283366 -290.010778) (xy 40.236095 -290.02447)
			(xy 40.18724 -290.030402) (xy 40.138065 -290.028421) (xy 40.089846 -290.018577) (xy 40.04383 -290.001125)
			(xy 40.001209 -289.976518) (xy 39.963088 -289.945393) (xy 39.930453 -289.908556) (xy 39.90415 -289.86696)
			(xy 39.884859 -289.821684) (xy 39.873082 -289.7739) (xy 39.869122 -289.724846) (xy 39.530274 -289.724846)
			(xy 39.529779 -289.749453) (xy 39.521884 -289.79803) (xy 39.5063 -289.844711) (xy 39.483429 -289.888288)
			(xy 39.453864 -289.927632) (xy 39.418371 -289.961724) (xy 39.377868 -289.98968) (xy 39.333406 -290.010778)
			(xy 39.286135 -290.02447) (xy 39.23728 -290.030402) (xy 39.188105 -290.028421) (xy 39.139886 -290.018577)
			(xy 39.09387 -290.001125) (xy 39.051249 -289.976518) (xy 39.013128 -289.945393) (xy 38.980493 -289.908556)
			(xy 38.95419 -289.86696) (xy 38.934899 -289.821684) (xy 38.923122 -289.7739) (xy 38.919162 -289.724846)
			(xy 38.580314 -289.724846) (xy 38.579819 -289.749453) (xy 38.571924 -289.79803) (xy 38.55634 -289.844711)
			(xy 38.533469 -289.888288) (xy 38.503904 -289.927632) (xy 38.468411 -289.961724) (xy 38.427908 -289.98968)
			(xy 38.383446 -290.010778) (xy 38.336175 -290.02447) (xy 38.28732 -290.030402) (xy 38.238145 -290.028421)
			(xy 38.189926 -290.018577) (xy 38.14391 -290.001125) (xy 38.101289 -289.976518) (xy 38.063168 -289.945393)
			(xy 38.030533 -289.908556) (xy 38.00423 -289.86696) (xy 37.984939 -289.821684) (xy 37.973162 -289.7739)
			(xy 37.969202 -289.724846) (xy 37.6301 -289.724846) (xy 37.629605 -289.749453) (xy 37.62171 -289.79803)
			(xy 37.606126 -289.844711) (xy 37.583255 -289.888288) (xy 37.55369 -289.927632) (xy 37.518197 -289.961724)
			(xy 37.477694 -289.98968) (xy 37.433232 -290.010778) (xy 37.385961 -290.02447) (xy 37.337106 -290.030402)
			(xy 37.287931 -290.028421) (xy 37.239712 -290.018577) (xy 37.193696 -290.001125) (xy 37.151075 -289.976518)
			(xy 37.112954 -289.945393) (xy 37.080319 -289.908556) (xy 37.054016 -289.86696) (xy 37.034725 -289.821684)
			(xy 37.022948 -289.7739) (xy 37.018988 -289.724846) (xy 36.68014 -289.724846) (xy 36.679645 -289.749453)
			(xy 36.67175 -289.79803) (xy 36.656166 -289.844711) (xy 36.633295 -289.888288) (xy 36.60373 -289.927632)
			(xy 36.568237 -289.961724) (xy 36.527734 -289.98968) (xy 36.483272 -290.010778) (xy 36.436001 -290.02447)
			(xy 36.387146 -290.030402) (xy 36.337971 -290.028421) (xy 36.289752 -290.018577) (xy 36.243736 -290.001125)
			(xy 36.201115 -289.976518) (xy 36.162994 -289.945393) (xy 36.130359 -289.908556) (xy 36.104056 -289.86696)
			(xy 36.084765 -289.821684) (xy 36.072988 -289.7739) (xy 36.069028 -289.724846) (xy 32.059862 -289.724846)
			(xy 32.040256 -289.756315) (xy 32.006161 -289.79709) (xy 31.966737 -289.83274) (xy 31.922747 -289.862573)
			(xy 31.899098 -289.874706) (xy 31.886606 -289.881344) (xy 31.865564 -289.900233) (xy 31.850513 -289.92417)
			(xy 31.842608 -289.951319) (xy 31.842456 -289.979595) (xy 31.850069 -290.006827) (xy 31.864862 -290.030925)
			(xy 31.874968 -290.040822) (xy 31.893963 -290.058969) (xy 31.927348 -290.099526) (xy 31.95485 -290.144283)
			(xy 31.975947 -290.192391) (xy 31.990241 -290.24294) (xy 31.99737 -290.294314) (xy 33.620962 -290.294314)
			(xy 33.625033 -290.238692) (xy 33.637159 -290.184255) (xy 33.657082 -290.132164) (xy 33.684378 -290.083529)
			(xy 33.718464 -290.039386) (xy 33.758613 -290.000677) (xy 33.803971 -289.968226) (xy 33.853571 -289.942725)
			(xy 33.906355 -289.924718) (xy 33.961198 -289.914588) (xy 34.016932 -289.912551) (xy 34.072369 -289.918651)
			(xy 34.126326 -289.932757) (xy 34.177655 -289.954569) (xy 34.225261 -289.983623) (xy 34.268129 -290.019298)
			(xy 34.305346 -290.060835) (xy 34.336119 -290.107348) (xy 34.359791 -290.157845) (xy 34.375859 -290.211252)
			(xy 34.383979 -290.266428) (xy 34.384488 -290.294314) (xy 34.383979 -290.3222) (xy 34.375859 -290.377376)
			(xy 34.359791 -290.430783) (xy 34.336119 -290.48128) (xy 34.305346 -290.527793) (xy 34.268129 -290.56933)
			(xy 34.225261 -290.605005) (xy 34.177655 -290.634059) (xy 34.126326 -290.655871) (xy 34.072369 -290.669977)
			(xy 34.028483 -290.674806) (xy 36.069028 -290.674806) (xy 36.072988 -290.625752) (xy 36.084765 -290.577968)
			(xy 36.104056 -290.532692) (xy 36.130359 -290.491096) (xy 36.162994 -290.454259) (xy 36.201115 -290.423134)
			(xy 36.243736 -290.398527) (xy 36.289752 -290.381075) (xy 36.337971 -290.371231) (xy 36.387146 -290.36925)
			(xy 36.436001 -290.375182) (xy 36.483272 -290.388874) (xy 36.527734 -290.409972) (xy 36.568237 -290.437928)
			(xy 36.60373 -290.47202) (xy 36.633295 -290.511364) (xy 36.656166 -290.554941) (xy 36.67175 -290.601622)
			(xy 36.679645 -290.650199) (xy 36.68014 -290.674806) (xy 37.018988 -290.674806) (xy 37.022948 -290.625752)
			(xy 37.034725 -290.577968) (xy 37.054016 -290.532692) (xy 37.080319 -290.491096) (xy 37.112954 -290.454259)
			(xy 37.151075 -290.423134) (xy 37.193696 -290.398527) (xy 37.239712 -290.381075) (xy 37.287931 -290.371231)
			(xy 37.337106 -290.36925) (xy 37.385961 -290.375182) (xy 37.433232 -290.388874) (xy 37.477694 -290.409972)
			(xy 37.518197 -290.437928) (xy 37.55369 -290.47202) (xy 37.583255 -290.511364) (xy 37.606126 -290.554941)
			(xy 37.62171 -290.601622) (xy 37.629605 -290.650199) (xy 37.6301 -290.674806) (xy 37.969202 -290.674806)
			(xy 37.973162 -290.625752) (xy 37.984939 -290.577968) (xy 38.00423 -290.532692) (xy 38.030533 -290.491096)
			(xy 38.063168 -290.454259) (xy 38.101289 -290.423134) (xy 38.14391 -290.398527) (xy 38.189926 -290.381075)
			(xy 38.238145 -290.371231) (xy 38.28732 -290.36925) (xy 38.336175 -290.375182) (xy 38.383446 -290.388874)
			(xy 38.427908 -290.409972) (xy 38.468411 -290.437928) (xy 38.503904 -290.47202) (xy 38.533469 -290.511364)
			(xy 38.55634 -290.554941) (xy 38.571924 -290.601622) (xy 38.579819 -290.650199) (xy 38.580314 -290.674806)
			(xy 40.819082 -290.674806) (xy 40.823042 -290.625752) (xy 40.834819 -290.577968) (xy 40.85411 -290.532692)
			(xy 40.880413 -290.491096) (xy 40.913048 -290.454259) (xy 40.951169 -290.423134) (xy 40.99379 -290.398527)
			(xy 41.039806 -290.381075) (xy 41.088025 -290.371231) (xy 41.1372 -290.36925) (xy 41.186055 -290.375182)
			(xy 41.233326 -290.388874) (xy 41.277788 -290.409972) (xy 41.318291 -290.437928) (xy 41.353784 -290.47202)
			(xy 41.383349 -290.511364) (xy 41.40622 -290.554941) (xy 41.421804 -290.601622) (xy 41.429699 -290.650199)
			(xy 41.430194 -290.674806) (xy 41.769042 -290.674806) (xy 41.773002 -290.625752) (xy 41.784779 -290.577968)
			(xy 41.80407 -290.532692) (xy 41.830373 -290.491096) (xy 41.863008 -290.454259) (xy 41.901129 -290.423134)
			(xy 41.94375 -290.398527) (xy 41.989766 -290.381075) (xy 42.037985 -290.371231) (xy 42.08716 -290.36925)
			(xy 42.136015 -290.375182) (xy 42.183286 -290.388874) (xy 42.227748 -290.409972) (xy 42.268251 -290.437928)
			(xy 42.303744 -290.47202) (xy 42.333309 -290.511364) (xy 42.35618 -290.554941) (xy 42.371764 -290.601622)
			(xy 42.379659 -290.650199) (xy 42.380154 -290.674806) (xy 42.719002 -290.674806) (xy 42.722962 -290.625752)
			(xy 42.734739 -290.577968) (xy 42.75403 -290.532692) (xy 42.780333 -290.491096) (xy 42.812968 -290.454259)
			(xy 42.851089 -290.423134) (xy 42.89371 -290.398527) (xy 42.939726 -290.381075) (xy 42.987945 -290.371231)
			(xy 43.03712 -290.36925) (xy 43.085975 -290.375182) (xy 43.133246 -290.388874) (xy 43.177708 -290.409972)
			(xy 43.218211 -290.437928) (xy 43.253704 -290.47202) (xy 43.283269 -290.511364) (xy 43.30614 -290.554941)
			(xy 43.321724 -290.601622) (xy 43.329619 -290.650199) (xy 43.330114 -290.674806) (xy 43.668962 -290.674806)
			(xy 43.672922 -290.625752) (xy 43.684699 -290.577968) (xy 43.70399 -290.532692) (xy 43.730293 -290.491096)
			(xy 43.762928 -290.454259) (xy 43.801049 -290.423134) (xy 43.84367 -290.398527) (xy 43.889686 -290.381075)
			(xy 43.937905 -290.371231) (xy 43.98708 -290.36925) (xy 44.035935 -290.375182) (xy 44.083206 -290.388874)
			(xy 44.127668 -290.409972) (xy 44.168171 -290.437928) (xy 44.203664 -290.47202) (xy 44.233229 -290.511364)
			(xy 44.2561 -290.554941) (xy 44.271684 -290.601622) (xy 44.279579 -290.650199) (xy 44.280074 -290.674806)
			(xy 44.619176 -290.674806) (xy 44.623136 -290.625752) (xy 44.634913 -290.577968) (xy 44.654204 -290.532692)
			(xy 44.680507 -290.491096) (xy 44.713142 -290.454259) (xy 44.751263 -290.423134) (xy 44.793884 -290.398527)
			(xy 44.8399 -290.381075) (xy 44.888119 -290.371231) (xy 44.937294 -290.36925) (xy 44.986149 -290.375182)
			(xy 45.03342 -290.388874) (xy 45.077882 -290.409972) (xy 45.118385 -290.437928) (xy 45.153878 -290.47202)
			(xy 45.183443 -290.511364) (xy 45.206314 -290.554941) (xy 45.221898 -290.601622) (xy 45.229793 -290.650199)
			(xy 45.230288 -290.674806) (xy 45.569136 -290.674806) (xy 45.573096 -290.625752) (xy 45.584873 -290.577968)
			(xy 45.604164 -290.532692) (xy 45.630467 -290.491096) (xy 45.663102 -290.454259) (xy 45.701223 -290.423134)
			(xy 45.743844 -290.398527) (xy 45.78986 -290.381075) (xy 45.838079 -290.371231) (xy 45.887254 -290.36925)
			(xy 45.936109 -290.375182) (xy 45.98338 -290.388874) (xy 46.027842 -290.409972) (xy 46.068345 -290.437928)
			(xy 46.103838 -290.47202) (xy 46.133403 -290.511364) (xy 46.156274 -290.554941) (xy 46.171858 -290.601622)
			(xy 46.179753 -290.650199) (xy 46.180248 -290.674806) (xy 46.519096 -290.674806) (xy 46.523056 -290.625752)
			(xy 46.534833 -290.577968) (xy 46.554124 -290.532692) (xy 46.580427 -290.491096) (xy 46.613062 -290.454259)
			(xy 46.651183 -290.423134) (xy 46.693804 -290.398527) (xy 46.73982 -290.381075) (xy 46.788039 -290.371231)
			(xy 46.837214 -290.36925) (xy 46.886069 -290.375182) (xy 46.93334 -290.388874) (xy 46.977802 -290.409972)
			(xy 47.018305 -290.437928) (xy 47.053798 -290.47202) (xy 47.083363 -290.511364) (xy 47.106234 -290.554941)
			(xy 47.121818 -290.601622) (xy 47.129713 -290.650199) (xy 47.130208 -290.674806) (xy 47.469056 -290.674806)
			(xy 47.473016 -290.625752) (xy 47.484793 -290.577968) (xy 47.504084 -290.532692) (xy 47.530387 -290.491096)
			(xy 47.563022 -290.454259) (xy 47.601143 -290.423134) (xy 47.643764 -290.398527) (xy 47.68978 -290.381075)
			(xy 47.737999 -290.371231) (xy 47.787174 -290.36925) (xy 47.836029 -290.375182) (xy 47.8833 -290.388874)
			(xy 47.927762 -290.409972) (xy 47.968265 -290.437928) (xy 48.003758 -290.47202) (xy 48.033323 -290.511364)
			(xy 48.056194 -290.554941) (xy 48.071778 -290.601622) (xy 48.079673 -290.650199) (xy 48.080168 -290.674806)
			(xy 48.419016 -290.674806) (xy 48.422976 -290.625752) (xy 48.434753 -290.577968) (xy 48.454044 -290.532692)
			(xy 48.480347 -290.491096) (xy 48.512982 -290.454259) (xy 48.551103 -290.423134) (xy 48.593724 -290.398527)
			(xy 48.63974 -290.381075) (xy 48.687959 -290.371231) (xy 48.737134 -290.36925) (xy 48.785989 -290.375182)
			(xy 48.83326 -290.388874) (xy 48.877722 -290.409972) (xy 48.918225 -290.437928) (xy 48.953718 -290.47202)
			(xy 48.983283 -290.511364) (xy 49.006154 -290.554941) (xy 49.021738 -290.601622) (xy 49.029633 -290.650199)
			(xy 49.030128 -290.674806) (xy 49.368976 -290.674806) (xy 49.372936 -290.625752) (xy 49.384713 -290.577968)
			(xy 49.404004 -290.532692) (xy 49.430307 -290.491096) (xy 49.462942 -290.454259) (xy 49.501063 -290.423134)
			(xy 49.543684 -290.398527) (xy 49.5897 -290.381075) (xy 49.637919 -290.371231) (xy 49.687094 -290.36925)
			(xy 49.735949 -290.375182) (xy 49.78322 -290.388874) (xy 49.827682 -290.409972) (xy 49.868185 -290.437928)
			(xy 49.903678 -290.47202) (xy 49.933243 -290.511364) (xy 49.956114 -290.554941) (xy 49.971698 -290.601622)
			(xy 49.979593 -290.650199) (xy 49.980088 -290.674806) (xy 50.31919 -290.674806) (xy 50.32315 -290.625752)
			(xy 50.334927 -290.577968) (xy 50.354218 -290.532692) (xy 50.380521 -290.491096) (xy 50.413156 -290.454259)
			(xy 50.451277 -290.423134) (xy 50.493898 -290.398527) (xy 50.539914 -290.381075) (xy 50.588133 -290.371231)
			(xy 50.637308 -290.36925) (xy 50.686163 -290.375182) (xy 50.733434 -290.388874) (xy 50.777896 -290.409972)
			(xy 50.818399 -290.437928) (xy 50.853892 -290.47202) (xy 50.883457 -290.511364) (xy 50.906328 -290.554941)
			(xy 50.921912 -290.601622) (xy 50.929807 -290.650199) (xy 50.930302 -290.674806) (xy 51.26915 -290.674806)
			(xy 51.27311 -290.625752) (xy 51.284887 -290.577968) (xy 51.304178 -290.532692) (xy 51.330481 -290.491096)
			(xy 51.363116 -290.454259) (xy 51.401237 -290.423134) (xy 51.443858 -290.398527) (xy 51.489874 -290.381075)
			(xy 51.538093 -290.371231) (xy 51.587268 -290.36925) (xy 51.636123 -290.375182) (xy 51.683394 -290.388874)
			(xy 51.727856 -290.409972) (xy 51.768359 -290.437928) (xy 51.803852 -290.47202) (xy 51.833417 -290.511364)
			(xy 51.856288 -290.554941) (xy 51.871872 -290.601622) (xy 51.879767 -290.650199) (xy 51.880262 -290.674806)
			(xy 52.21911 -290.674806) (xy 52.22307 -290.625752) (xy 52.234847 -290.577968) (xy 52.254138 -290.532692)
			(xy 52.280441 -290.491096) (xy 52.313076 -290.454259) (xy 52.351197 -290.423134) (xy 52.393818 -290.398527)
			(xy 52.439834 -290.381075) (xy 52.488053 -290.371231) (xy 52.537228 -290.36925) (xy 52.586083 -290.375182)
			(xy 52.633354 -290.388874) (xy 52.677816 -290.409972) (xy 52.718319 -290.437928) (xy 52.753812 -290.47202)
			(xy 52.783377 -290.511364) (xy 52.806248 -290.554941) (xy 52.821832 -290.601622) (xy 52.829727 -290.650199)
			(xy 52.830222 -290.674806) (xy 53.16907 -290.674806) (xy 53.17303 -290.625752) (xy 53.184807 -290.577968)
			(xy 53.204098 -290.532692) (xy 53.230401 -290.491096) (xy 53.263036 -290.454259) (xy 53.301157 -290.423134)
			(xy 53.343778 -290.398527) (xy 53.389794 -290.381075) (xy 53.438013 -290.371231) (xy 53.487188 -290.36925)
			(xy 53.536043 -290.375182) (xy 53.583314 -290.388874) (xy 53.627776 -290.409972) (xy 53.668279 -290.437928)
			(xy 53.703772 -290.47202) (xy 53.733337 -290.511364) (xy 53.756208 -290.554941) (xy 53.771792 -290.601622)
			(xy 53.779687 -290.650199) (xy 53.780182 -290.674806) (xy 54.11903 -290.674806) (xy 54.12299 -290.625752)
			(xy 54.134767 -290.577968) (xy 54.154058 -290.532692) (xy 54.180361 -290.491096) (xy 54.212996 -290.454259)
			(xy 54.251117 -290.423134) (xy 54.293738 -290.398527) (xy 54.339754 -290.381075) (xy 54.387973 -290.371231)
			(xy 54.437148 -290.36925) (xy 54.486003 -290.375182) (xy 54.533274 -290.388874) (xy 54.577736 -290.409972)
			(xy 54.618239 -290.437928) (xy 54.653732 -290.47202) (xy 54.683297 -290.511364) (xy 54.706168 -290.554941)
			(xy 54.721752 -290.601622) (xy 54.729647 -290.650199) (xy 54.730142 -290.674806) (xy 55.06899 -290.674806)
			(xy 55.07295 -290.625752) (xy 55.084727 -290.577968) (xy 55.104018 -290.532692) (xy 55.130321 -290.491096)
			(xy 55.162956 -290.454259) (xy 55.201077 -290.423134) (xy 55.243698 -290.398527) (xy 55.289714 -290.381075)
			(xy 55.337933 -290.371231) (xy 55.387108 -290.36925) (xy 55.435963 -290.375182) (xy 55.483234 -290.388874)
			(xy 55.527696 -290.409972) (xy 55.568199 -290.437928) (xy 55.603692 -290.47202) (xy 55.633257 -290.511364)
			(xy 55.656128 -290.554941) (xy 55.671712 -290.601622) (xy 55.679607 -290.650199) (xy 55.680102 -290.674806)
			(xy 56.01895 -290.674806) (xy 56.02291 -290.625752) (xy 56.034687 -290.577968) (xy 56.053978 -290.532692)
			(xy 56.080281 -290.491096) (xy 56.112916 -290.454259) (xy 56.151037 -290.423134) (xy 56.193658 -290.398527)
			(xy 56.239674 -290.381075) (xy 56.287893 -290.371231) (xy 56.337068 -290.36925) (xy 56.385923 -290.375182)
			(xy 56.433194 -290.388874) (xy 56.477656 -290.409972) (xy 56.518159 -290.437928) (xy 56.553652 -290.47202)
			(xy 56.583217 -290.511364) (xy 56.606088 -290.554941) (xy 56.621672 -290.601622) (xy 56.629567 -290.650199)
			(xy 56.630062 -290.674806) (xy 56.969164 -290.674806) (xy 56.973124 -290.625752) (xy 56.984901 -290.577968)
			(xy 57.004192 -290.532692) (xy 57.030495 -290.491096) (xy 57.06313 -290.454259) (xy 57.101251 -290.423134)
			(xy 57.143872 -290.398527) (xy 57.189888 -290.381075) (xy 57.238107 -290.371231) (xy 57.287282 -290.36925)
			(xy 57.336137 -290.375182) (xy 57.383408 -290.388874) (xy 57.42787 -290.409972) (xy 57.468373 -290.437928)
			(xy 57.503866 -290.47202) (xy 57.533431 -290.511364) (xy 57.556302 -290.554941) (xy 57.571886 -290.601622)
			(xy 57.579781 -290.650199) (xy 57.580276 -290.674806) (xy 57.919124 -290.674806) (xy 57.923084 -290.625752)
			(xy 57.934861 -290.577968) (xy 57.954152 -290.532692) (xy 57.980455 -290.491096) (xy 58.01309 -290.454259)
			(xy 58.051211 -290.423134) (xy 58.093832 -290.398527) (xy 58.139848 -290.381075) (xy 58.188067 -290.371231)
			(xy 58.237242 -290.36925) (xy 58.286097 -290.375182) (xy 58.333368 -290.388874) (xy 58.37783 -290.409972)
			(xy 58.418333 -290.437928) (xy 58.453826 -290.47202) (xy 58.483391 -290.511364) (xy 58.506262 -290.554941)
			(xy 58.521846 -290.601622) (xy 58.529741 -290.650199) (xy 58.530236 -290.674806) (xy 59.819044 -290.674806)
			(xy 59.823004 -290.625752) (xy 59.834781 -290.577968) (xy 59.854072 -290.532692) (xy 59.880375 -290.491096)
			(xy 59.91301 -290.454259) (xy 59.951131 -290.423134) (xy 59.993752 -290.398527) (xy 60.039768 -290.381075)
			(xy 60.087987 -290.371231) (xy 60.137162 -290.36925) (xy 60.186017 -290.375182) (xy 60.233288 -290.388874)
			(xy 60.27775 -290.409972) (xy 60.318253 -290.437928) (xy 60.353746 -290.47202) (xy 60.383311 -290.511364)
			(xy 60.406182 -290.554941) (xy 60.421766 -290.601622) (xy 60.429661 -290.650199) (xy 60.430156 -290.674806)
			(xy 60.769004 -290.674806) (xy 60.772964 -290.625752) (xy 60.784741 -290.577968) (xy 60.804032 -290.532692)
			(xy 60.830335 -290.491096) (xy 60.86297 -290.454259) (xy 60.901091 -290.423134) (xy 60.943712 -290.398527)
			(xy 60.989728 -290.381075) (xy 61.037947 -290.371231) (xy 61.087122 -290.36925) (xy 61.135977 -290.375182)
			(xy 61.183248 -290.388874) (xy 61.22771 -290.409972) (xy 61.268213 -290.437928) (xy 61.303706 -290.47202)
			(xy 61.333271 -290.511364) (xy 61.356142 -290.554941) (xy 61.371726 -290.601622) (xy 61.379621 -290.650199)
			(xy 61.380116 -290.674806) (xy 61.718964 -290.674806) (xy 61.722924 -290.625752) (xy 61.734701 -290.577968)
			(xy 61.753992 -290.532692) (xy 61.780295 -290.491096) (xy 61.81293 -290.454259) (xy 61.851051 -290.423134)
			(xy 61.893672 -290.398527) (xy 61.939688 -290.381075) (xy 61.987907 -290.371231) (xy 62.037082 -290.36925)
			(xy 62.085937 -290.375182) (xy 62.133208 -290.388874) (xy 62.17767 -290.409972) (xy 62.218173 -290.437928)
			(xy 62.253666 -290.47202) (xy 62.283231 -290.511364) (xy 62.306102 -290.554941) (xy 62.321686 -290.601622)
			(xy 62.329581 -290.650199) (xy 62.330076 -290.674806) (xy 62.669178 -290.674806) (xy 62.673138 -290.625752)
			(xy 62.684915 -290.577968) (xy 62.704206 -290.532692) (xy 62.730509 -290.491096) (xy 62.763144 -290.454259)
			(xy 62.801265 -290.423134) (xy 62.843886 -290.398527) (xy 62.889902 -290.381075) (xy 62.938121 -290.371231)
			(xy 62.987296 -290.36925) (xy 63.036151 -290.375182) (xy 63.083422 -290.388874) (xy 63.127884 -290.409972)
			(xy 63.168387 -290.437928) (xy 63.20388 -290.47202) (xy 63.233445 -290.511364) (xy 63.256316 -290.554941)
			(xy 63.2719 -290.601622) (xy 63.279795 -290.650199) (xy 63.28029 -290.674806) (xy 63.619138 -290.674806)
			(xy 63.623098 -290.625752) (xy 63.634875 -290.577968) (xy 63.654166 -290.532692) (xy 63.680469 -290.491096)
			(xy 63.713104 -290.454259) (xy 63.751225 -290.423134) (xy 63.793846 -290.398527) (xy 63.839862 -290.381075)
			(xy 63.888081 -290.371231) (xy 63.937256 -290.36925) (xy 63.986111 -290.375182) (xy 64.033382 -290.388874)
			(xy 64.077844 -290.409972) (xy 64.118347 -290.437928) (xy 64.15384 -290.47202) (xy 64.183405 -290.511364)
			(xy 64.206276 -290.554941) (xy 64.22186 -290.601622) (xy 64.229755 -290.650199) (xy 64.23025 -290.674806)
			(xy 64.569098 -290.674806) (xy 64.573058 -290.625752) (xy 64.584835 -290.577968) (xy 64.604126 -290.532692)
			(xy 64.630429 -290.491096) (xy 64.663064 -290.454259) (xy 64.701185 -290.423134) (xy 64.743806 -290.398527)
			(xy 64.789822 -290.381075) (xy 64.838041 -290.371231) (xy 64.887216 -290.36925) (xy 64.936071 -290.375182)
			(xy 64.983342 -290.388874) (xy 65.027804 -290.409972) (xy 65.068307 -290.437928) (xy 65.1038 -290.47202)
			(xy 65.133365 -290.511364) (xy 65.156236 -290.554941) (xy 65.17182 -290.601622) (xy 65.179715 -290.650199)
			(xy 65.18021 -290.674806) (xy 65.519058 -290.674806) (xy 65.523018 -290.625752) (xy 65.534795 -290.577968)
			(xy 65.554086 -290.532692) (xy 65.580389 -290.491096) (xy 65.613024 -290.454259) (xy 65.651145 -290.423134)
			(xy 65.693766 -290.398527) (xy 65.739782 -290.381075) (xy 65.788001 -290.371231) (xy 65.837176 -290.36925)
			(xy 65.886031 -290.375182) (xy 65.933302 -290.388874) (xy 65.977764 -290.409972) (xy 66.018267 -290.437928)
			(xy 66.05376 -290.47202) (xy 66.083325 -290.511364) (xy 66.106196 -290.554941) (xy 66.12178 -290.601622)
			(xy 66.129675 -290.650199) (xy 66.13017 -290.674806) (xy 66.469018 -290.674806) (xy 66.472978 -290.625752)
			(xy 66.484755 -290.577968) (xy 66.504046 -290.532692) (xy 66.530349 -290.491096) (xy 66.562984 -290.454259)
			(xy 66.601105 -290.423134) (xy 66.643726 -290.398527) (xy 66.689742 -290.381075) (xy 66.737961 -290.371231)
			(xy 66.787136 -290.36925) (xy 66.835991 -290.375182) (xy 66.883262 -290.388874) (xy 66.927724 -290.409972)
			(xy 66.968227 -290.437928) (xy 67.00372 -290.47202) (xy 67.033285 -290.511364) (xy 67.056156 -290.554941)
			(xy 67.07174 -290.601622) (xy 67.079635 -290.650199) (xy 67.08013 -290.674806) (xy 67.418978 -290.674806)
			(xy 67.422938 -290.625752) (xy 67.434715 -290.577968) (xy 67.454006 -290.532692) (xy 67.480309 -290.491096)
			(xy 67.512944 -290.454259) (xy 67.551065 -290.423134) (xy 67.593686 -290.398527) (xy 67.639702 -290.381075)
			(xy 67.687921 -290.371231) (xy 67.737096 -290.36925) (xy 67.785951 -290.375182) (xy 67.833222 -290.388874)
			(xy 67.877684 -290.409972) (xy 67.918187 -290.437928) (xy 67.95368 -290.47202) (xy 67.983245 -290.511364)
			(xy 68.006116 -290.554941) (xy 68.0217 -290.601622) (xy 68.029595 -290.650199) (xy 68.03009 -290.674806)
			(xy 68.368938 -290.674806) (xy 68.372898 -290.625752) (xy 68.384675 -290.577968) (xy 68.403966 -290.532692)
			(xy 68.430269 -290.491096) (xy 68.462904 -290.454259) (xy 68.501025 -290.423134) (xy 68.543646 -290.398527)
			(xy 68.589662 -290.381075) (xy 68.637881 -290.371231) (xy 68.687056 -290.36925) (xy 68.735911 -290.375182)
			(xy 68.783182 -290.388874) (xy 68.827644 -290.409972) (xy 68.868147 -290.437928) (xy 68.90364 -290.47202)
			(xy 68.933205 -290.511364) (xy 68.956076 -290.554941) (xy 68.97166 -290.601622) (xy 68.979555 -290.650199)
			(xy 68.98005 -290.674806) (xy 69.319152 -290.674806) (xy 69.323112 -290.625752) (xy 69.334889 -290.577968)
			(xy 69.35418 -290.532692) (xy 69.380483 -290.491096) (xy 69.413118 -290.454259) (xy 69.451239 -290.423134)
			(xy 69.49386 -290.398527) (xy 69.539876 -290.381075) (xy 69.588095 -290.371231) (xy 69.63727 -290.36925)
			(xy 69.686125 -290.375182) (xy 69.733396 -290.388874) (xy 69.777858 -290.409972) (xy 69.818361 -290.437928)
			(xy 69.853854 -290.47202) (xy 69.883419 -290.511364) (xy 69.90629 -290.554941) (xy 69.921874 -290.601622)
			(xy 69.929769 -290.650199) (xy 69.930264 -290.674806) (xy 70.269112 -290.674806) (xy 70.273072 -290.625752)
			(xy 70.284849 -290.577968) (xy 70.30414 -290.532692) (xy 70.330443 -290.491096) (xy 70.363078 -290.454259)
			(xy 70.401199 -290.423134) (xy 70.44382 -290.398527) (xy 70.489836 -290.381075) (xy 70.538055 -290.371231)
			(xy 70.58723 -290.36925) (xy 70.636085 -290.375182) (xy 70.683356 -290.388874) (xy 70.727818 -290.409972)
			(xy 70.768321 -290.437928) (xy 70.803814 -290.47202) (xy 70.833379 -290.511364) (xy 70.85625 -290.554941)
			(xy 70.871834 -290.601622) (xy 70.879729 -290.650199) (xy 70.880224 -290.674806) (xy 71.219072 -290.674806)
			(xy 71.223032 -290.625752) (xy 71.234809 -290.577968) (xy 71.2541 -290.532692) (xy 71.280403 -290.491096)
			(xy 71.313038 -290.454259) (xy 71.351159 -290.423134) (xy 71.39378 -290.398527) (xy 71.439796 -290.381075)
			(xy 71.488015 -290.371231) (xy 71.53719 -290.36925) (xy 71.586045 -290.375182) (xy 71.633316 -290.388874)
			(xy 71.677778 -290.409972) (xy 71.718281 -290.437928) (xy 71.753774 -290.47202) (xy 71.783339 -290.511364)
			(xy 71.80621 -290.554941) (xy 71.821794 -290.601622) (xy 71.829689 -290.650199) (xy 71.830184 -290.674806)
			(xy 72.169032 -290.674806) (xy 72.172992 -290.625752) (xy 72.184769 -290.577968) (xy 72.20406 -290.532692)
			(xy 72.230363 -290.491096) (xy 72.262998 -290.454259) (xy 72.301119 -290.423134) (xy 72.34374 -290.398527)
			(xy 72.389756 -290.381075) (xy 72.437975 -290.371231) (xy 72.48715 -290.36925) (xy 72.536005 -290.375182)
			(xy 72.583276 -290.388874) (xy 72.627738 -290.409972) (xy 72.668241 -290.437928) (xy 72.703734 -290.47202)
			(xy 72.733299 -290.511364) (xy 72.75617 -290.554941) (xy 72.771754 -290.601622) (xy 72.779649 -290.650199)
			(xy 72.780144 -290.674806) (xy 73.118992 -290.674806) (xy 73.122952 -290.625752) (xy 73.134729 -290.577968)
			(xy 73.15402 -290.532692) (xy 73.180323 -290.491096) (xy 73.212958 -290.454259) (xy 73.251079 -290.423134)
			(xy 73.2937 -290.398527) (xy 73.339716 -290.381075) (xy 73.387935 -290.371231) (xy 73.43711 -290.36925)
			(xy 73.485965 -290.375182) (xy 73.533236 -290.388874) (xy 73.577698 -290.409972) (xy 73.618201 -290.437928)
			(xy 73.653694 -290.47202) (xy 73.683259 -290.511364) (xy 73.70613 -290.554941) (xy 73.721714 -290.601622)
			(xy 73.729609 -290.650199) (xy 73.730104 -290.674806) (xy 74.068952 -290.674806) (xy 74.072912 -290.625752)
			(xy 74.084689 -290.577968) (xy 74.10398 -290.532692) (xy 74.130283 -290.491096) (xy 74.162918 -290.454259)
			(xy 74.201039 -290.423134) (xy 74.24366 -290.398527) (xy 74.289676 -290.381075) (xy 74.337895 -290.371231)
			(xy 74.38707 -290.36925) (xy 74.435925 -290.375182) (xy 74.483196 -290.388874) (xy 74.527658 -290.409972)
			(xy 74.568161 -290.437928) (xy 74.603654 -290.47202) (xy 74.633219 -290.511364) (xy 74.65609 -290.554941)
			(xy 74.671674 -290.601622) (xy 74.679569 -290.650199) (xy 74.680064 -290.674806) (xy 75.019166 -290.674806)
			(xy 75.023126 -290.625752) (xy 75.034903 -290.577968) (xy 75.054194 -290.532692) (xy 75.080497 -290.491096)
			(xy 75.113132 -290.454259) (xy 75.151253 -290.423134) (xy 75.193874 -290.398527) (xy 75.23989 -290.381075)
			(xy 75.288109 -290.371231) (xy 75.337284 -290.36925) (xy 75.386139 -290.375182) (xy 75.43341 -290.388874)
			(xy 75.477872 -290.409972) (xy 75.518375 -290.437928) (xy 75.553868 -290.47202) (xy 75.583433 -290.511364)
			(xy 75.606304 -290.554941) (xy 75.621888 -290.601622) (xy 75.629783 -290.650199) (xy 75.630278 -290.674806)
			(xy 75.969126 -290.674806) (xy 75.973086 -290.625752) (xy 75.984863 -290.577968) (xy 76.004154 -290.532692)
			(xy 76.030457 -290.491096) (xy 76.063092 -290.454259) (xy 76.101213 -290.423134) (xy 76.143834 -290.398527)
			(xy 76.18985 -290.381075) (xy 76.238069 -290.371231) (xy 76.287244 -290.36925) (xy 76.336099 -290.375182)
			(xy 76.38337 -290.388874) (xy 76.427832 -290.409972) (xy 76.468335 -290.437928) (xy 76.503828 -290.47202)
			(xy 76.533393 -290.511364) (xy 76.556264 -290.554941) (xy 76.571848 -290.601622) (xy 76.579743 -290.650199)
			(xy 76.580238 -290.674806) (xy 76.919086 -290.674806) (xy 76.923046 -290.625752) (xy 76.934823 -290.577968)
			(xy 76.954114 -290.532692) (xy 76.980417 -290.491096) (xy 77.013052 -290.454259) (xy 77.051173 -290.423134)
			(xy 77.093794 -290.398527) (xy 77.13981 -290.381075) (xy 77.188029 -290.371231) (xy 77.237204 -290.36925)
			(xy 77.286059 -290.375182) (xy 77.33333 -290.388874) (xy 77.377792 -290.409972) (xy 77.418295 -290.437928)
			(xy 77.453788 -290.47202) (xy 77.483353 -290.511364) (xy 77.506224 -290.554941) (xy 77.521808 -290.601622)
			(xy 77.529703 -290.650199) (xy 77.530198 -290.674806) (xy 77.869046 -290.674806) (xy 77.873006 -290.625752)
			(xy 77.884783 -290.577968) (xy 77.904074 -290.532692) (xy 77.930377 -290.491096) (xy 77.963012 -290.454259)
			(xy 78.001133 -290.423134) (xy 78.043754 -290.398527) (xy 78.08977 -290.381075) (xy 78.137989 -290.371231)
			(xy 78.187164 -290.36925) (xy 78.236019 -290.375182) (xy 78.28329 -290.388874) (xy 78.327752 -290.409972)
			(xy 78.368255 -290.437928) (xy 78.403748 -290.47202) (xy 78.433313 -290.511364) (xy 78.456184 -290.554941)
			(xy 78.471768 -290.601622) (xy 78.479663 -290.650199) (xy 78.480158 -290.674806) (xy 78.479663 -290.699413)
			(xy 78.471768 -290.74799) (xy 78.456184 -290.794671) (xy 78.433313 -290.838248) (xy 78.403748 -290.877592)
			(xy 78.368255 -290.911684) (xy 78.327752 -290.93964) (xy 78.28329 -290.960738) (xy 78.236019 -290.97443)
			(xy 78.187164 -290.980362) (xy 78.137989 -290.978381) (xy 78.08977 -290.968537) (xy 78.043754 -290.951085)
			(xy 78.001133 -290.926478) (xy 77.963012 -290.895353) (xy 77.930377 -290.858516) (xy 77.904074 -290.81692)
			(xy 77.884783 -290.771644) (xy 77.873006 -290.72386) (xy 77.869046 -290.674806) (xy 77.530198 -290.674806)
			(xy 77.529703 -290.699413) (xy 77.521808 -290.74799) (xy 77.506224 -290.794671) (xy 77.483353 -290.838248)
			(xy 77.453788 -290.877592) (xy 77.418295 -290.911684) (xy 77.377792 -290.93964) (xy 77.33333 -290.960738)
			(xy 77.286059 -290.97443) (xy 77.237204 -290.980362) (xy 77.188029 -290.978381) (xy 77.13981 -290.968537)
			(xy 77.093794 -290.951085) (xy 77.051173 -290.926478) (xy 77.013052 -290.895353) (xy 76.980417 -290.858516)
			(xy 76.954114 -290.81692) (xy 76.934823 -290.771644) (xy 76.923046 -290.72386) (xy 76.919086 -290.674806)
			(xy 76.580238 -290.674806) (xy 76.579743 -290.699413) (xy 76.571848 -290.74799) (xy 76.556264 -290.794671)
			(xy 76.533393 -290.838248) (xy 76.503828 -290.877592) (xy 76.468335 -290.911684) (xy 76.427832 -290.93964)
			(xy 76.38337 -290.960738) (xy 76.336099 -290.97443) (xy 76.287244 -290.980362) (xy 76.238069 -290.978381)
			(xy 76.18985 -290.968537) (xy 76.143834 -290.951085) (xy 76.101213 -290.926478) (xy 76.063092 -290.895353)
			(xy 76.030457 -290.858516) (xy 76.004154 -290.81692) (xy 75.984863 -290.771644) (xy 75.973086 -290.72386)
			(xy 75.969126 -290.674806) (xy 75.630278 -290.674806) (xy 75.629783 -290.699413) (xy 75.621888 -290.74799)
			(xy 75.606304 -290.794671) (xy 75.583433 -290.838248) (xy 75.553868 -290.877592) (xy 75.518375 -290.911684)
			(xy 75.477872 -290.93964) (xy 75.43341 -290.960738) (xy 75.386139 -290.97443) (xy 75.337284 -290.980362)
			(xy 75.288109 -290.978381) (xy 75.23989 -290.968537) (xy 75.193874 -290.951085) (xy 75.151253 -290.926478)
			(xy 75.113132 -290.895353) (xy 75.080497 -290.858516) (xy 75.054194 -290.81692) (xy 75.034903 -290.771644)
			(xy 75.023126 -290.72386) (xy 75.019166 -290.674806) (xy 74.680064 -290.674806) (xy 74.679569 -290.699413)
			(xy 74.671674 -290.74799) (xy 74.65609 -290.794671) (xy 74.633219 -290.838248) (xy 74.603654 -290.877592)
			(xy 74.568161 -290.911684) (xy 74.527658 -290.93964) (xy 74.483196 -290.960738) (xy 74.435925 -290.97443)
			(xy 74.38707 -290.980362) (xy 74.337895 -290.978381) (xy 74.289676 -290.968537) (xy 74.24366 -290.951085)
			(xy 74.201039 -290.926478) (xy 74.162918 -290.895353) (xy 74.130283 -290.858516) (xy 74.10398 -290.81692)
			(xy 74.084689 -290.771644) (xy 74.072912 -290.72386) (xy 74.068952 -290.674806) (xy 73.730104 -290.674806)
			(xy 73.729609 -290.699413) (xy 73.721714 -290.74799) (xy 73.70613 -290.794671) (xy 73.683259 -290.838248)
			(xy 73.653694 -290.877592) (xy 73.618201 -290.911684) (xy 73.577698 -290.93964) (xy 73.533236 -290.960738)
			(xy 73.485965 -290.97443) (xy 73.43711 -290.980362) (xy 73.387935 -290.978381) (xy 73.339716 -290.968537)
			(xy 73.2937 -290.951085) (xy 73.251079 -290.926478) (xy 73.212958 -290.895353) (xy 73.180323 -290.858516)
			(xy 73.15402 -290.81692) (xy 73.134729 -290.771644) (xy 73.122952 -290.72386) (xy 73.118992 -290.674806)
			(xy 72.780144 -290.674806) (xy 72.779649 -290.699413) (xy 72.771754 -290.74799) (xy 72.75617 -290.794671)
			(xy 72.733299 -290.838248) (xy 72.703734 -290.877592) (xy 72.668241 -290.911684) (xy 72.627738 -290.93964)
			(xy 72.583276 -290.960738) (xy 72.536005 -290.97443) (xy 72.48715 -290.980362) (xy 72.437975 -290.978381)
			(xy 72.389756 -290.968537) (xy 72.34374 -290.951085) (xy 72.301119 -290.926478) (xy 72.262998 -290.895353)
			(xy 72.230363 -290.858516) (xy 72.20406 -290.81692) (xy 72.184769 -290.771644) (xy 72.172992 -290.72386)
			(xy 72.169032 -290.674806) (xy 71.830184 -290.674806) (xy 71.829689 -290.699413) (xy 71.821794 -290.74799)
			(xy 71.80621 -290.794671) (xy 71.783339 -290.838248) (xy 71.753774 -290.877592) (xy 71.718281 -290.911684)
			(xy 71.677778 -290.93964) (xy 71.633316 -290.960738) (xy 71.586045 -290.97443) (xy 71.53719 -290.980362)
			(xy 71.488015 -290.978381) (xy 71.439796 -290.968537) (xy 71.39378 -290.951085) (xy 71.351159 -290.926478)
			(xy 71.313038 -290.895353) (xy 71.280403 -290.858516) (xy 71.2541 -290.81692) (xy 71.234809 -290.771644)
			(xy 71.223032 -290.72386) (xy 71.219072 -290.674806) (xy 70.880224 -290.674806) (xy 70.879729 -290.699413)
			(xy 70.871834 -290.74799) (xy 70.85625 -290.794671) (xy 70.833379 -290.838248) (xy 70.803814 -290.877592)
			(xy 70.768321 -290.911684) (xy 70.727818 -290.93964) (xy 70.683356 -290.960738) (xy 70.636085 -290.97443)
			(xy 70.58723 -290.980362) (xy 70.538055 -290.978381) (xy 70.489836 -290.968537) (xy 70.44382 -290.951085)
			(xy 70.401199 -290.926478) (xy 70.363078 -290.895353) (xy 70.330443 -290.858516) (xy 70.30414 -290.81692)
			(xy 70.284849 -290.771644) (xy 70.273072 -290.72386) (xy 70.269112 -290.674806) (xy 69.930264 -290.674806)
			(xy 69.929769 -290.699413) (xy 69.921874 -290.74799) (xy 69.90629 -290.794671) (xy 69.883419 -290.838248)
			(xy 69.853854 -290.877592) (xy 69.818361 -290.911684) (xy 69.777858 -290.93964) (xy 69.733396 -290.960738)
			(xy 69.686125 -290.97443) (xy 69.63727 -290.980362) (xy 69.588095 -290.978381) (xy 69.539876 -290.968537)
			(xy 69.49386 -290.951085) (xy 69.451239 -290.926478) (xy 69.413118 -290.895353) (xy 69.380483 -290.858516)
			(xy 69.35418 -290.81692) (xy 69.334889 -290.771644) (xy 69.323112 -290.72386) (xy 69.319152 -290.674806)
			(xy 68.98005 -290.674806) (xy 68.979555 -290.699413) (xy 68.97166 -290.74799) (xy 68.956076 -290.794671)
			(xy 68.933205 -290.838248) (xy 68.90364 -290.877592) (xy 68.868147 -290.911684) (xy 68.827644 -290.93964)
			(xy 68.783182 -290.960738) (xy 68.735911 -290.97443) (xy 68.687056 -290.980362) (xy 68.637881 -290.978381)
			(xy 68.589662 -290.968537) (xy 68.543646 -290.951085) (xy 68.501025 -290.926478) (xy 68.462904 -290.895353)
			(xy 68.430269 -290.858516) (xy 68.403966 -290.81692) (xy 68.384675 -290.771644) (xy 68.372898 -290.72386)
			(xy 68.368938 -290.674806) (xy 68.03009 -290.674806) (xy 68.029595 -290.699413) (xy 68.0217 -290.74799)
			(xy 68.006116 -290.794671) (xy 67.983245 -290.838248) (xy 67.95368 -290.877592) (xy 67.918187 -290.911684)
			(xy 67.877684 -290.93964) (xy 67.833222 -290.960738) (xy 67.785951 -290.97443) (xy 67.737096 -290.980362)
			(xy 67.687921 -290.978381) (xy 67.639702 -290.968537) (xy 67.593686 -290.951085) (xy 67.551065 -290.926478)
			(xy 67.512944 -290.895353) (xy 67.480309 -290.858516) (xy 67.454006 -290.81692) (xy 67.434715 -290.771644)
			(xy 67.422938 -290.72386) (xy 67.418978 -290.674806) (xy 67.08013 -290.674806) (xy 67.079635 -290.699413)
			(xy 67.07174 -290.74799) (xy 67.056156 -290.794671) (xy 67.033285 -290.838248) (xy 67.00372 -290.877592)
			(xy 66.968227 -290.911684) (xy 66.927724 -290.93964) (xy 66.883262 -290.960738) (xy 66.835991 -290.97443)
			(xy 66.787136 -290.980362) (xy 66.737961 -290.978381) (xy 66.689742 -290.968537) (xy 66.643726 -290.951085)
			(xy 66.601105 -290.926478) (xy 66.562984 -290.895353) (xy 66.530349 -290.858516) (xy 66.504046 -290.81692)
			(xy 66.484755 -290.771644) (xy 66.472978 -290.72386) (xy 66.469018 -290.674806) (xy 66.13017 -290.674806)
			(xy 66.129675 -290.699413) (xy 66.12178 -290.74799) (xy 66.106196 -290.794671) (xy 66.083325 -290.838248)
			(xy 66.05376 -290.877592) (xy 66.018267 -290.911684) (xy 65.977764 -290.93964) (xy 65.933302 -290.960738)
			(xy 65.886031 -290.97443) (xy 65.837176 -290.980362) (xy 65.788001 -290.978381) (xy 65.739782 -290.968537)
			(xy 65.693766 -290.951085) (xy 65.651145 -290.926478) (xy 65.613024 -290.895353) (xy 65.580389 -290.858516)
			(xy 65.554086 -290.81692) (xy 65.534795 -290.771644) (xy 65.523018 -290.72386) (xy 65.519058 -290.674806)
			(xy 65.18021 -290.674806) (xy 65.179715 -290.699413) (xy 65.17182 -290.74799) (xy 65.156236 -290.794671)
			(xy 65.133365 -290.838248) (xy 65.1038 -290.877592) (xy 65.068307 -290.911684) (xy 65.027804 -290.93964)
			(xy 64.983342 -290.960738) (xy 64.936071 -290.97443) (xy 64.887216 -290.980362) (xy 64.838041 -290.978381)
			(xy 64.789822 -290.968537) (xy 64.743806 -290.951085) (xy 64.701185 -290.926478) (xy 64.663064 -290.895353)
			(xy 64.630429 -290.858516) (xy 64.604126 -290.81692) (xy 64.584835 -290.771644) (xy 64.573058 -290.72386)
			(xy 64.569098 -290.674806) (xy 64.23025 -290.674806) (xy 64.229755 -290.699413) (xy 64.22186 -290.74799)
			(xy 64.206276 -290.794671) (xy 64.183405 -290.838248) (xy 64.15384 -290.877592) (xy 64.118347 -290.911684)
			(xy 64.077844 -290.93964) (xy 64.033382 -290.960738) (xy 63.986111 -290.97443) (xy 63.937256 -290.980362)
			(xy 63.888081 -290.978381) (xy 63.839862 -290.968537) (xy 63.793846 -290.951085) (xy 63.751225 -290.926478)
			(xy 63.713104 -290.895353) (xy 63.680469 -290.858516) (xy 63.654166 -290.81692) (xy 63.634875 -290.771644)
			(xy 63.623098 -290.72386) (xy 63.619138 -290.674806) (xy 63.28029 -290.674806) (xy 63.279795 -290.699413)
			(xy 63.2719 -290.74799) (xy 63.256316 -290.794671) (xy 63.233445 -290.838248) (xy 63.20388 -290.877592)
			(xy 63.168387 -290.911684) (xy 63.127884 -290.93964) (xy 63.083422 -290.960738) (xy 63.036151 -290.97443)
			(xy 62.987296 -290.980362) (xy 62.938121 -290.978381) (xy 62.889902 -290.968537) (xy 62.843886 -290.951085)
			(xy 62.801265 -290.926478) (xy 62.763144 -290.895353) (xy 62.730509 -290.858516) (xy 62.704206 -290.81692)
			(xy 62.684915 -290.771644) (xy 62.673138 -290.72386) (xy 62.669178 -290.674806) (xy 62.330076 -290.674806)
			(xy 62.329581 -290.699413) (xy 62.321686 -290.74799) (xy 62.306102 -290.794671) (xy 62.283231 -290.838248)
			(xy 62.253666 -290.877592) (xy 62.218173 -290.911684) (xy 62.17767 -290.93964) (xy 62.133208 -290.960738)
			(xy 62.085937 -290.97443) (xy 62.037082 -290.980362) (xy 61.987907 -290.978381) (xy 61.939688 -290.968537)
			(xy 61.893672 -290.951085) (xy 61.851051 -290.926478) (xy 61.81293 -290.895353) (xy 61.780295 -290.858516)
			(xy 61.753992 -290.81692) (xy 61.734701 -290.771644) (xy 61.722924 -290.72386) (xy 61.718964 -290.674806)
			(xy 61.380116 -290.674806) (xy 61.379621 -290.699413) (xy 61.371726 -290.74799) (xy 61.356142 -290.794671)
			(xy 61.333271 -290.838248) (xy 61.303706 -290.877592) (xy 61.268213 -290.911684) (xy 61.22771 -290.93964)
			(xy 61.183248 -290.960738) (xy 61.135977 -290.97443) (xy 61.087122 -290.980362) (xy 61.037947 -290.978381)
			(xy 60.989728 -290.968537) (xy 60.943712 -290.951085) (xy 60.901091 -290.926478) (xy 60.86297 -290.895353)
			(xy 60.830335 -290.858516) (xy 60.804032 -290.81692) (xy 60.784741 -290.771644) (xy 60.772964 -290.72386)
			(xy 60.769004 -290.674806) (xy 60.430156 -290.674806) (xy 60.429661 -290.699413) (xy 60.421766 -290.74799)
			(xy 60.406182 -290.794671) (xy 60.383311 -290.838248) (xy 60.353746 -290.877592) (xy 60.318253 -290.911684)
			(xy 60.27775 -290.93964) (xy 60.233288 -290.960738) (xy 60.186017 -290.97443) (xy 60.137162 -290.980362)
			(xy 60.087987 -290.978381) (xy 60.039768 -290.968537) (xy 59.993752 -290.951085) (xy 59.951131 -290.926478)
			(xy 59.91301 -290.895353) (xy 59.880375 -290.858516) (xy 59.854072 -290.81692) (xy 59.834781 -290.771644)
			(xy 59.823004 -290.72386) (xy 59.819044 -290.674806) (xy 58.530236 -290.674806) (xy 58.529741 -290.699413)
			(xy 58.521846 -290.74799) (xy 58.506262 -290.794671) (xy 58.483391 -290.838248) (xy 58.453826 -290.877592)
			(xy 58.418333 -290.911684) (xy 58.37783 -290.93964) (xy 58.333368 -290.960738) (xy 58.286097 -290.97443)
			(xy 58.237242 -290.980362) (xy 58.188067 -290.978381) (xy 58.139848 -290.968537) (xy 58.093832 -290.951085)
			(xy 58.051211 -290.926478) (xy 58.01309 -290.895353) (xy 57.980455 -290.858516) (xy 57.954152 -290.81692)
			(xy 57.934861 -290.771644) (xy 57.923084 -290.72386) (xy 57.919124 -290.674806) (xy 57.580276 -290.674806)
			(xy 57.579781 -290.699413) (xy 57.571886 -290.74799) (xy 57.556302 -290.794671) (xy 57.533431 -290.838248)
			(xy 57.503866 -290.877592) (xy 57.468373 -290.911684) (xy 57.42787 -290.93964) (xy 57.383408 -290.960738)
			(xy 57.336137 -290.97443) (xy 57.287282 -290.980362) (xy 57.238107 -290.978381) (xy 57.189888 -290.968537)
			(xy 57.143872 -290.951085) (xy 57.101251 -290.926478) (xy 57.06313 -290.895353) (xy 57.030495 -290.858516)
			(xy 57.004192 -290.81692) (xy 56.984901 -290.771644) (xy 56.973124 -290.72386) (xy 56.969164 -290.674806)
			(xy 56.630062 -290.674806) (xy 56.629567 -290.699413) (xy 56.621672 -290.74799) (xy 56.606088 -290.794671)
			(xy 56.583217 -290.838248) (xy 56.553652 -290.877592) (xy 56.518159 -290.911684) (xy 56.477656 -290.93964)
			(xy 56.433194 -290.960738) (xy 56.385923 -290.97443) (xy 56.337068 -290.980362) (xy 56.287893 -290.978381)
			(xy 56.239674 -290.968537) (xy 56.193658 -290.951085) (xy 56.151037 -290.926478) (xy 56.112916 -290.895353)
			(xy 56.080281 -290.858516) (xy 56.053978 -290.81692) (xy 56.034687 -290.771644) (xy 56.02291 -290.72386)
			(xy 56.01895 -290.674806) (xy 55.680102 -290.674806) (xy 55.679607 -290.699413) (xy 55.671712 -290.74799)
			(xy 55.656128 -290.794671) (xy 55.633257 -290.838248) (xy 55.603692 -290.877592) (xy 55.568199 -290.911684)
			(xy 55.527696 -290.93964) (xy 55.483234 -290.960738) (xy 55.435963 -290.97443) (xy 55.387108 -290.980362)
			(xy 55.337933 -290.978381) (xy 55.289714 -290.968537) (xy 55.243698 -290.951085) (xy 55.201077 -290.926478)
			(xy 55.162956 -290.895353) (xy 55.130321 -290.858516) (xy 55.104018 -290.81692) (xy 55.084727 -290.771644)
			(xy 55.07295 -290.72386) (xy 55.06899 -290.674806) (xy 54.730142 -290.674806) (xy 54.729647 -290.699413)
			(xy 54.721752 -290.74799) (xy 54.706168 -290.794671) (xy 54.683297 -290.838248) (xy 54.653732 -290.877592)
			(xy 54.618239 -290.911684) (xy 54.577736 -290.93964) (xy 54.533274 -290.960738) (xy 54.486003 -290.97443)
			(xy 54.437148 -290.980362) (xy 54.387973 -290.978381) (xy 54.339754 -290.968537) (xy 54.293738 -290.951085)
			(xy 54.251117 -290.926478) (xy 54.212996 -290.895353) (xy 54.180361 -290.858516) (xy 54.154058 -290.81692)
			(xy 54.134767 -290.771644) (xy 54.12299 -290.72386) (xy 54.11903 -290.674806) (xy 53.780182 -290.674806)
			(xy 53.779687 -290.699413) (xy 53.771792 -290.74799) (xy 53.756208 -290.794671) (xy 53.733337 -290.838248)
			(xy 53.703772 -290.877592) (xy 53.668279 -290.911684) (xy 53.627776 -290.93964) (xy 53.583314 -290.960738)
			(xy 53.536043 -290.97443) (xy 53.487188 -290.980362) (xy 53.438013 -290.978381) (xy 53.389794 -290.968537)
			(xy 53.343778 -290.951085) (xy 53.301157 -290.926478) (xy 53.263036 -290.895353) (xy 53.230401 -290.858516)
			(xy 53.204098 -290.81692) (xy 53.184807 -290.771644) (xy 53.17303 -290.72386) (xy 53.16907 -290.674806)
			(xy 52.830222 -290.674806) (xy 52.829727 -290.699413) (xy 52.821832 -290.74799) (xy 52.806248 -290.794671)
			(xy 52.783377 -290.838248) (xy 52.753812 -290.877592) (xy 52.718319 -290.911684) (xy 52.677816 -290.93964)
			(xy 52.633354 -290.960738) (xy 52.586083 -290.97443) (xy 52.537228 -290.980362) (xy 52.488053 -290.978381)
			(xy 52.439834 -290.968537) (xy 52.393818 -290.951085) (xy 52.351197 -290.926478) (xy 52.313076 -290.895353)
			(xy 52.280441 -290.858516) (xy 52.254138 -290.81692) (xy 52.234847 -290.771644) (xy 52.22307 -290.72386)
			(xy 52.21911 -290.674806) (xy 51.880262 -290.674806) (xy 51.879767 -290.699413) (xy 51.871872 -290.74799)
			(xy 51.856288 -290.794671) (xy 51.833417 -290.838248) (xy 51.803852 -290.877592) (xy 51.768359 -290.911684)
			(xy 51.727856 -290.93964) (xy 51.683394 -290.960738) (xy 51.636123 -290.97443) (xy 51.587268 -290.980362)
			(xy 51.538093 -290.978381) (xy 51.489874 -290.968537) (xy 51.443858 -290.951085) (xy 51.401237 -290.926478)
			(xy 51.363116 -290.895353) (xy 51.330481 -290.858516) (xy 51.304178 -290.81692) (xy 51.284887 -290.771644)
			(xy 51.27311 -290.72386) (xy 51.26915 -290.674806) (xy 50.930302 -290.674806) (xy 50.929807 -290.699413)
			(xy 50.921912 -290.74799) (xy 50.906328 -290.794671) (xy 50.883457 -290.838248) (xy 50.853892 -290.877592)
			(xy 50.818399 -290.911684) (xy 50.777896 -290.93964) (xy 50.733434 -290.960738) (xy 50.686163 -290.97443)
			(xy 50.637308 -290.980362) (xy 50.588133 -290.978381) (xy 50.539914 -290.968537) (xy 50.493898 -290.951085)
			(xy 50.451277 -290.926478) (xy 50.413156 -290.895353) (xy 50.380521 -290.858516) (xy 50.354218 -290.81692)
			(xy 50.334927 -290.771644) (xy 50.32315 -290.72386) (xy 50.31919 -290.674806) (xy 49.980088 -290.674806)
			(xy 49.979593 -290.699413) (xy 49.971698 -290.74799) (xy 49.956114 -290.794671) (xy 49.933243 -290.838248)
			(xy 49.903678 -290.877592) (xy 49.868185 -290.911684) (xy 49.827682 -290.93964) (xy 49.78322 -290.960738)
			(xy 49.735949 -290.97443) (xy 49.687094 -290.980362) (xy 49.637919 -290.978381) (xy 49.5897 -290.968537)
			(xy 49.543684 -290.951085) (xy 49.501063 -290.926478) (xy 49.462942 -290.895353) (xy 49.430307 -290.858516)
			(xy 49.404004 -290.81692) (xy 49.384713 -290.771644) (xy 49.372936 -290.72386) (xy 49.368976 -290.674806)
			(xy 49.030128 -290.674806) (xy 49.029633 -290.699413) (xy 49.021738 -290.74799) (xy 49.006154 -290.794671)
			(xy 48.983283 -290.838248) (xy 48.953718 -290.877592) (xy 48.918225 -290.911684) (xy 48.877722 -290.93964)
			(xy 48.83326 -290.960738) (xy 48.785989 -290.97443) (xy 48.737134 -290.980362) (xy 48.687959 -290.978381)
			(xy 48.63974 -290.968537) (xy 48.593724 -290.951085) (xy 48.551103 -290.926478) (xy 48.512982 -290.895353)
			(xy 48.480347 -290.858516) (xy 48.454044 -290.81692) (xy 48.434753 -290.771644) (xy 48.422976 -290.72386)
			(xy 48.419016 -290.674806) (xy 48.080168 -290.674806) (xy 48.079673 -290.699413) (xy 48.071778 -290.74799)
			(xy 48.056194 -290.794671) (xy 48.033323 -290.838248) (xy 48.003758 -290.877592) (xy 47.968265 -290.911684)
			(xy 47.927762 -290.93964) (xy 47.8833 -290.960738) (xy 47.836029 -290.97443) (xy 47.787174 -290.980362)
			(xy 47.737999 -290.978381) (xy 47.68978 -290.968537) (xy 47.643764 -290.951085) (xy 47.601143 -290.926478)
			(xy 47.563022 -290.895353) (xy 47.530387 -290.858516) (xy 47.504084 -290.81692) (xy 47.484793 -290.771644)
			(xy 47.473016 -290.72386) (xy 47.469056 -290.674806) (xy 47.130208 -290.674806) (xy 47.129713 -290.699413)
			(xy 47.121818 -290.74799) (xy 47.106234 -290.794671) (xy 47.083363 -290.838248) (xy 47.053798 -290.877592)
			(xy 47.018305 -290.911684) (xy 46.977802 -290.93964) (xy 46.93334 -290.960738) (xy 46.886069 -290.97443)
			(xy 46.837214 -290.980362) (xy 46.788039 -290.978381) (xy 46.73982 -290.968537) (xy 46.693804 -290.951085)
			(xy 46.651183 -290.926478) (xy 46.613062 -290.895353) (xy 46.580427 -290.858516) (xy 46.554124 -290.81692)
			(xy 46.534833 -290.771644) (xy 46.523056 -290.72386) (xy 46.519096 -290.674806) (xy 46.180248 -290.674806)
			(xy 46.179753 -290.699413) (xy 46.171858 -290.74799) (xy 46.156274 -290.794671) (xy 46.133403 -290.838248)
			(xy 46.103838 -290.877592) (xy 46.068345 -290.911684) (xy 46.027842 -290.93964) (xy 45.98338 -290.960738)
			(xy 45.936109 -290.97443) (xy 45.887254 -290.980362) (xy 45.838079 -290.978381) (xy 45.78986 -290.968537)
			(xy 45.743844 -290.951085) (xy 45.701223 -290.926478) (xy 45.663102 -290.895353) (xy 45.630467 -290.858516)
			(xy 45.604164 -290.81692) (xy 45.584873 -290.771644) (xy 45.573096 -290.72386) (xy 45.569136 -290.674806)
			(xy 45.230288 -290.674806) (xy 45.229793 -290.699413) (xy 45.221898 -290.74799) (xy 45.206314 -290.794671)
			(xy 45.183443 -290.838248) (xy 45.153878 -290.877592) (xy 45.118385 -290.911684) (xy 45.077882 -290.93964)
			(xy 45.03342 -290.960738) (xy 44.986149 -290.97443) (xy 44.937294 -290.980362) (xy 44.888119 -290.978381)
			(xy 44.8399 -290.968537) (xy 44.793884 -290.951085) (xy 44.751263 -290.926478) (xy 44.713142 -290.895353)
			(xy 44.680507 -290.858516) (xy 44.654204 -290.81692) (xy 44.634913 -290.771644) (xy 44.623136 -290.72386)
			(xy 44.619176 -290.674806) (xy 44.280074 -290.674806) (xy 44.279579 -290.699413) (xy 44.271684 -290.74799)
			(xy 44.2561 -290.794671) (xy 44.233229 -290.838248) (xy 44.203664 -290.877592) (xy 44.168171 -290.911684)
			(xy 44.127668 -290.93964) (xy 44.083206 -290.960738) (xy 44.035935 -290.97443) (xy 43.98708 -290.980362)
			(xy 43.937905 -290.978381) (xy 43.889686 -290.968537) (xy 43.84367 -290.951085) (xy 43.801049 -290.926478)
			(xy 43.762928 -290.895353) (xy 43.730293 -290.858516) (xy 43.70399 -290.81692) (xy 43.684699 -290.771644)
			(xy 43.672922 -290.72386) (xy 43.668962 -290.674806) (xy 43.330114 -290.674806) (xy 43.329619 -290.699413)
			(xy 43.321724 -290.74799) (xy 43.30614 -290.794671) (xy 43.283269 -290.838248) (xy 43.253704 -290.877592)
			(xy 43.218211 -290.911684) (xy 43.177708 -290.93964) (xy 43.133246 -290.960738) (xy 43.085975 -290.97443)
			(xy 43.03712 -290.980362) (xy 42.987945 -290.978381) (xy 42.939726 -290.968537) (xy 42.89371 -290.951085)
			(xy 42.851089 -290.926478) (xy 42.812968 -290.895353) (xy 42.780333 -290.858516) (xy 42.75403 -290.81692)
			(xy 42.734739 -290.771644) (xy 42.722962 -290.72386) (xy 42.719002 -290.674806) (xy 42.380154 -290.674806)
			(xy 42.379659 -290.699413) (xy 42.371764 -290.74799) (xy 42.35618 -290.794671) (xy 42.333309 -290.838248)
			(xy 42.303744 -290.877592) (xy 42.268251 -290.911684) (xy 42.227748 -290.93964) (xy 42.183286 -290.960738)
			(xy 42.136015 -290.97443) (xy 42.08716 -290.980362) (xy 42.037985 -290.978381) (xy 41.989766 -290.968537)
			(xy 41.94375 -290.951085) (xy 41.901129 -290.926478) (xy 41.863008 -290.895353) (xy 41.830373 -290.858516)
			(xy 41.80407 -290.81692) (xy 41.784779 -290.771644) (xy 41.773002 -290.72386) (xy 41.769042 -290.674806)
			(xy 41.430194 -290.674806) (xy 41.429699 -290.699413) (xy 41.421804 -290.74799) (xy 41.40622 -290.794671)
			(xy 41.383349 -290.838248) (xy 41.353784 -290.877592) (xy 41.318291 -290.911684) (xy 41.277788 -290.93964)
			(xy 41.233326 -290.960738) (xy 41.186055 -290.97443) (xy 41.1372 -290.980362) (xy 41.088025 -290.978381)
			(xy 41.039806 -290.968537) (xy 40.99379 -290.951085) (xy 40.951169 -290.926478) (xy 40.913048 -290.895353)
			(xy 40.880413 -290.858516) (xy 40.85411 -290.81692) (xy 40.834819 -290.771644) (xy 40.823042 -290.72386)
			(xy 40.819082 -290.674806) (xy 38.580314 -290.674806) (xy 38.579819 -290.699413) (xy 38.571924 -290.74799)
			(xy 38.55634 -290.794671) (xy 38.533469 -290.838248) (xy 38.503904 -290.877592) (xy 38.468411 -290.911684)
			(xy 38.427908 -290.93964) (xy 38.383446 -290.960738) (xy 38.336175 -290.97443) (xy 38.28732 -290.980362)
			(xy 38.238145 -290.978381) (xy 38.189926 -290.968537) (xy 38.14391 -290.951085) (xy 38.101289 -290.926478)
			(xy 38.063168 -290.895353) (xy 38.030533 -290.858516) (xy 38.00423 -290.81692) (xy 37.984939 -290.771644)
			(xy 37.973162 -290.72386) (xy 37.969202 -290.674806) (xy 37.6301 -290.674806) (xy 37.629605 -290.699413)
			(xy 37.62171 -290.74799) (xy 37.606126 -290.794671) (xy 37.583255 -290.838248) (xy 37.55369 -290.877592)
			(xy 37.518197 -290.911684) (xy 37.477694 -290.93964) (xy 37.433232 -290.960738) (xy 37.385961 -290.97443)
			(xy 37.337106 -290.980362) (xy 37.287931 -290.978381) (xy 37.239712 -290.968537) (xy 37.193696 -290.951085)
			(xy 37.151075 -290.926478) (xy 37.112954 -290.895353) (xy 37.080319 -290.858516) (xy 37.054016 -290.81692)
			(xy 37.034725 -290.771644) (xy 37.022948 -290.72386) (xy 37.018988 -290.674806) (xy 36.68014 -290.674806)
			(xy 36.679645 -290.699413) (xy 36.67175 -290.74799) (xy 36.656166 -290.794671) (xy 36.633295 -290.838248)
			(xy 36.60373 -290.877592) (xy 36.568237 -290.911684) (xy 36.527734 -290.93964) (xy 36.483272 -290.960738)
			(xy 36.436001 -290.97443) (xy 36.387146 -290.980362) (xy 36.337971 -290.978381) (xy 36.289752 -290.968537)
			(xy 36.243736 -290.951085) (xy 36.201115 -290.926478) (xy 36.162994 -290.895353) (xy 36.130359 -290.858516)
			(xy 36.104056 -290.81692) (xy 36.084765 -290.771644) (xy 36.072988 -290.72386) (xy 36.069028 -290.674806)
			(xy 34.028483 -290.674806) (xy 34.016932 -290.676077) (xy 33.961198 -290.67404) (xy 33.906355 -290.66391)
			(xy 33.853571 -290.645903) (xy 33.803971 -290.620402) (xy 33.758613 -290.587951) (xy 33.718464 -290.549242)
			(xy 33.684378 -290.505099) (xy 33.657082 -290.456464) (xy 33.637159 -290.404373) (xy 33.625033 -290.349936)
			(xy 33.620962 -290.294314) (xy 31.99737 -290.294314) (xy 31.997461 -290.294973) (xy 31.997904 -290.321238)
			(xy 31.997418 -290.348489) (xy 31.989662 -290.402437) (xy 31.974307 -290.454732) (xy 31.951665 -290.504309)
			(xy 31.922199 -290.550159) (xy 31.886508 -290.59135) (xy 31.845317 -290.627041) (xy 31.799467 -290.656507)
			(xy 31.74989 -290.679149) (xy 31.697595 -290.694504) (xy 31.643647 -290.70226) (xy 31.589145 -290.70226)
			(xy 31.535197 -290.694504) (xy 31.482902 -290.679149) (xy 31.433325 -290.656507) (xy 31.387475 -290.627041)
			(xy 31.346284 -290.59135) (xy 31.310593 -290.550159) (xy 31.281127 -290.504309) (xy 31.258485 -290.454732)
			(xy 31.24313 -290.402437) (xy 31.235374 -290.348489) (xy 31.234888 -290.321238) (xy 1.660398 -290.321238)
			(xy 1.660398 -290.820856) (xy 32.748218 -290.820856) (xy 32.752289 -290.765234) (xy 32.764415 -290.710797)
			(xy 32.784338 -290.658706) (xy 32.811634 -290.610071) (xy 32.84572 -290.565928) (xy 32.885869 -290.527219)
			(xy 32.931227 -290.494768) (xy 32.980827 -290.469267) (xy 33.033611 -290.45126) (xy 33.088454 -290.44113)
			(xy 33.144188 -290.439093) (xy 33.199625 -290.445193) (xy 33.253582 -290.459299) (xy 33.304911 -290.481111)
			(xy 33.352517 -290.510165) (xy 33.395385 -290.54584) (xy 33.432602 -290.587377) (xy 33.463375 -290.63389)
			(xy 33.487047 -290.684387) (xy 33.503115 -290.737794) (xy 33.511235 -290.79297) (xy 33.511744 -290.820856)
			(xy 33.511235 -290.848742) (xy 33.503115 -290.903918) (xy 33.487047 -290.957325) (xy 33.463375 -291.007822)
			(xy 33.432602 -291.054335) (xy 33.395385 -291.095872) (xy 33.352517 -291.131547) (xy 33.304911 -291.160601)
			(xy 33.253582 -291.182413) (xy 33.199625 -291.196519) (xy 33.144188 -291.202619) (xy 33.088454 -291.200582)
			(xy 33.033611 -291.190452) (xy 32.980827 -291.172445) (xy 32.931227 -291.146944) (xy 32.885869 -291.114493)
			(xy 32.84572 -291.075784) (xy 32.811634 -291.031641) (xy 32.784338 -290.983006) (xy 32.764415 -290.930915)
			(xy 32.752289 -290.876478) (xy 32.748218 -290.820856) (xy 1.660398 -290.820856) (xy 1.660398 -291.430456)
			(xy 25.811478 -291.430456) (xy 25.815549 -291.374834) (xy 25.827675 -291.320397) (xy 25.847598 -291.268306)
			(xy 25.874894 -291.219671) (xy 25.90898 -291.175528) (xy 25.949129 -291.136819) (xy 25.994487 -291.104368)
			(xy 26.044087 -291.078867) (xy 26.096871 -291.06086) (xy 26.151714 -291.05073) (xy 26.207448 -291.048693)
			(xy 26.262885 -291.054793) (xy 26.316842 -291.068899) (xy 26.368171 -291.090711) (xy 26.415777 -291.119765)
			(xy 26.458645 -291.15544) (xy 26.495862 -291.196977) (xy 26.526635 -291.24349) (xy 26.550307 -291.293987)
			(xy 26.566375 -291.347394) (xy 26.574495 -291.40257) (xy 26.575004 -291.430456) (xy 27.296616 -291.430456)
			(xy 27.300687 -291.374834) (xy 27.312813 -291.320397) (xy 27.332736 -291.268306) (xy 27.360032 -291.219671)
			(xy 27.394118 -291.175528) (xy 27.434267 -291.136819) (xy 27.479625 -291.104368) (xy 27.529225 -291.078867)
			(xy 27.582009 -291.06086) (xy 27.636852 -291.05073) (xy 27.692586 -291.048693) (xy 27.748023 -291.054793)
			(xy 27.80198 -291.068899) (xy 27.853309 -291.090711) (xy 27.900915 -291.119765) (xy 27.943783 -291.15544)
			(xy 27.981 -291.196977) (xy 28.011773 -291.24349) (xy 28.035445 -291.293987) (xy 28.051513 -291.347394)
			(xy 28.059633 -291.40257) (xy 28.060142 -291.430456) (xy 28.059633 -291.458342) (xy 28.051513 -291.513518)
			(xy 28.035445 -291.566925) (xy 28.011773 -291.617422) (xy 28.006914 -291.624766) (xy 36.069028 -291.624766)
			(xy 36.072988 -291.575712) (xy 36.084765 -291.527928) (xy 36.104056 -291.482652) (xy 36.130359 -291.441056)
			(xy 36.162994 -291.404219) (xy 36.201115 -291.373094) (xy 36.243736 -291.348487) (xy 36.289752 -291.331035)
			(xy 36.337971 -291.321191) (xy 36.387146 -291.31921) (xy 36.436001 -291.325142) (xy 36.483272 -291.338834)
			(xy 36.527734 -291.359932) (xy 36.568237 -291.387888) (xy 36.60373 -291.42198) (xy 36.633295 -291.461324)
			(xy 36.656166 -291.504901) (xy 36.67175 -291.551582) (xy 36.679645 -291.600159) (xy 36.68014 -291.624766)
			(xy 37.018988 -291.624766) (xy 37.022948 -291.575712) (xy 37.034725 -291.527928) (xy 37.054016 -291.482652)
			(xy 37.080319 -291.441056) (xy 37.112954 -291.404219) (xy 37.151075 -291.373094) (xy 37.193696 -291.348487)
			(xy 37.239712 -291.331035) (xy 37.287931 -291.321191) (xy 37.337106 -291.31921) (xy 37.385961 -291.325142)
			(xy 37.433232 -291.338834) (xy 37.477694 -291.359932) (xy 37.518197 -291.387888) (xy 37.55369 -291.42198)
			(xy 37.583255 -291.461324) (xy 37.606126 -291.504901) (xy 37.62171 -291.551582) (xy 37.629605 -291.600159)
			(xy 37.6301 -291.624766) (xy 37.969202 -291.624766) (xy 37.973162 -291.575712) (xy 37.984939 -291.527928)
			(xy 38.00423 -291.482652) (xy 38.030533 -291.441056) (xy 38.063168 -291.404219) (xy 38.101289 -291.373094)
			(xy 38.14391 -291.348487) (xy 38.189926 -291.331035) (xy 38.238145 -291.321191) (xy 38.28732 -291.31921)
			(xy 38.336175 -291.325142) (xy 38.383446 -291.338834) (xy 38.427908 -291.359932) (xy 38.468411 -291.387888)
			(xy 38.503904 -291.42198) (xy 38.533469 -291.461324) (xy 38.55634 -291.504901) (xy 38.571924 -291.551582)
			(xy 38.579819 -291.600159) (xy 38.580314 -291.624766) (xy 40.819082 -291.624766) (xy 40.823042 -291.575712)
			(xy 40.834819 -291.527928) (xy 40.85411 -291.482652) (xy 40.880413 -291.441056) (xy 40.913048 -291.404219)
			(xy 40.951169 -291.373094) (xy 40.99379 -291.348487) (xy 41.039806 -291.331035) (xy 41.088025 -291.321191)
			(xy 41.1372 -291.31921) (xy 41.186055 -291.325142) (xy 41.233326 -291.338834) (xy 41.277788 -291.359932)
			(xy 41.318291 -291.387888) (xy 41.353784 -291.42198) (xy 41.383349 -291.461324) (xy 41.40622 -291.504901)
			(xy 41.421804 -291.551582) (xy 41.429699 -291.600159) (xy 41.430194 -291.624766) (xy 41.769042 -291.624766)
			(xy 41.773002 -291.575712) (xy 41.784779 -291.527928) (xy 41.80407 -291.482652) (xy 41.830373 -291.441056)
			(xy 41.863008 -291.404219) (xy 41.901129 -291.373094) (xy 41.94375 -291.348487) (xy 41.989766 -291.331035)
			(xy 42.037985 -291.321191) (xy 42.08716 -291.31921) (xy 42.136015 -291.325142) (xy 42.183286 -291.338834)
			(xy 42.227748 -291.359932) (xy 42.268251 -291.387888) (xy 42.303744 -291.42198) (xy 42.333309 -291.461324)
			(xy 42.35618 -291.504901) (xy 42.371764 -291.551582) (xy 42.379659 -291.600159) (xy 42.380154 -291.624766)
			(xy 42.719002 -291.624766) (xy 42.722962 -291.575712) (xy 42.734739 -291.527928) (xy 42.75403 -291.482652)
			(xy 42.780333 -291.441056) (xy 42.812968 -291.404219) (xy 42.851089 -291.373094) (xy 42.89371 -291.348487)
			(xy 42.939726 -291.331035) (xy 42.987945 -291.321191) (xy 43.03712 -291.31921) (xy 43.085975 -291.325142)
			(xy 43.133246 -291.338834) (xy 43.177708 -291.359932) (xy 43.218211 -291.387888) (xy 43.253704 -291.42198)
			(xy 43.283269 -291.461324) (xy 43.30614 -291.504901) (xy 43.321724 -291.551582) (xy 43.329619 -291.600159)
			(xy 43.330114 -291.624766) (xy 43.668962 -291.624766) (xy 43.672922 -291.575712) (xy 43.684699 -291.527928)
			(xy 43.70399 -291.482652) (xy 43.730293 -291.441056) (xy 43.762928 -291.404219) (xy 43.801049 -291.373094)
			(xy 43.84367 -291.348487) (xy 43.889686 -291.331035) (xy 43.937905 -291.321191) (xy 43.98708 -291.31921)
			(xy 44.035935 -291.325142) (xy 44.083206 -291.338834) (xy 44.127668 -291.359932) (xy 44.168171 -291.387888)
			(xy 44.203664 -291.42198) (xy 44.233229 -291.461324) (xy 44.2561 -291.504901) (xy 44.271684 -291.551582)
			(xy 44.279579 -291.600159) (xy 44.280074 -291.624766) (xy 44.619176 -291.624766) (xy 44.623136 -291.575712)
			(xy 44.634913 -291.527928) (xy 44.654204 -291.482652) (xy 44.680507 -291.441056) (xy 44.713142 -291.404219)
			(xy 44.751263 -291.373094) (xy 44.793884 -291.348487) (xy 44.8399 -291.331035) (xy 44.888119 -291.321191)
			(xy 44.937294 -291.31921) (xy 44.986149 -291.325142) (xy 45.03342 -291.338834) (xy 45.077882 -291.359932)
			(xy 45.118385 -291.387888) (xy 45.153878 -291.42198) (xy 45.183443 -291.461324) (xy 45.206314 -291.504901)
			(xy 45.221898 -291.551582) (xy 45.229793 -291.600159) (xy 45.230288 -291.624766) (xy 45.569136 -291.624766)
			(xy 45.573096 -291.575712) (xy 45.584873 -291.527928) (xy 45.604164 -291.482652) (xy 45.630467 -291.441056)
			(xy 45.663102 -291.404219) (xy 45.701223 -291.373094) (xy 45.743844 -291.348487) (xy 45.78986 -291.331035)
			(xy 45.838079 -291.321191) (xy 45.887254 -291.31921) (xy 45.936109 -291.325142) (xy 45.98338 -291.338834)
			(xy 46.027842 -291.359932) (xy 46.068345 -291.387888) (xy 46.103838 -291.42198) (xy 46.133403 -291.461324)
			(xy 46.156274 -291.504901) (xy 46.171858 -291.551582) (xy 46.179753 -291.600159) (xy 46.180248 -291.624766)
			(xy 47.469056 -291.624766) (xy 47.473016 -291.575712) (xy 47.484793 -291.527928) (xy 47.504084 -291.482652)
			(xy 47.530387 -291.441056) (xy 47.563022 -291.404219) (xy 47.601143 -291.373094) (xy 47.643764 -291.348487)
			(xy 47.68978 -291.331035) (xy 47.737999 -291.321191) (xy 47.787174 -291.31921) (xy 47.836029 -291.325142)
			(xy 47.8833 -291.338834) (xy 47.927762 -291.359932) (xy 47.968265 -291.387888) (xy 48.003758 -291.42198)
			(xy 48.033323 -291.461324) (xy 48.056194 -291.504901) (xy 48.071778 -291.551582) (xy 48.079673 -291.600159)
			(xy 48.080168 -291.624766) (xy 48.419016 -291.624766) (xy 48.422976 -291.575712) (xy 48.434753 -291.527928)
			(xy 48.454044 -291.482652) (xy 48.480347 -291.441056) (xy 48.512982 -291.404219) (xy 48.551103 -291.373094)
			(xy 48.593724 -291.348487) (xy 48.63974 -291.331035) (xy 48.687959 -291.321191) (xy 48.737134 -291.31921)
			(xy 48.785989 -291.325142) (xy 48.83326 -291.338834) (xy 48.877722 -291.359932) (xy 48.918225 -291.387888)
			(xy 48.953718 -291.42198) (xy 48.983283 -291.461324) (xy 49.006154 -291.504901) (xy 49.021738 -291.551582)
			(xy 49.029633 -291.600159) (xy 49.030128 -291.624766) (xy 49.368976 -291.624766) (xy 49.372936 -291.575712)
			(xy 49.384713 -291.527928) (xy 49.404004 -291.482652) (xy 49.430307 -291.441056) (xy 49.462942 -291.404219)
			(xy 49.501063 -291.373094) (xy 49.543684 -291.348487) (xy 49.5897 -291.331035) (xy 49.637919 -291.321191)
			(xy 49.687094 -291.31921) (xy 49.735949 -291.325142) (xy 49.78322 -291.338834) (xy 49.827682 -291.359932)
			(xy 49.868185 -291.387888) (xy 49.903678 -291.42198) (xy 49.933243 -291.461324) (xy 49.956114 -291.504901)
			(xy 49.971698 -291.551582) (xy 49.979593 -291.600159) (xy 49.980088 -291.624766) (xy 50.31919 -291.624766)
			(xy 50.32315 -291.575712) (xy 50.334927 -291.527928) (xy 50.354218 -291.482652) (xy 50.380521 -291.441056)
			(xy 50.413156 -291.404219) (xy 50.451277 -291.373094) (xy 50.493898 -291.348487) (xy 50.539914 -291.331035)
			(xy 50.588133 -291.321191) (xy 50.637308 -291.31921) (xy 50.686163 -291.325142) (xy 50.733434 -291.338834)
			(xy 50.777896 -291.359932) (xy 50.818399 -291.387888) (xy 50.853892 -291.42198) (xy 50.883457 -291.461324)
			(xy 50.906328 -291.504901) (xy 50.921912 -291.551582) (xy 50.929807 -291.600159) (xy 50.930302 -291.624766)
			(xy 51.26915 -291.624766) (xy 51.27311 -291.575712) (xy 51.284887 -291.527928) (xy 51.304178 -291.482652)
			(xy 51.330481 -291.441056) (xy 51.363116 -291.404219) (xy 51.401237 -291.373094) (xy 51.443858 -291.348487)
			(xy 51.489874 -291.331035) (xy 51.538093 -291.321191) (xy 51.587268 -291.31921) (xy 51.636123 -291.325142)
			(xy 51.683394 -291.338834) (xy 51.727856 -291.359932) (xy 51.768359 -291.387888) (xy 51.803852 -291.42198)
			(xy 51.833417 -291.461324) (xy 51.856288 -291.504901) (xy 51.871872 -291.551582) (xy 51.879767 -291.600159)
			(xy 51.880262 -291.624766) (xy 52.21911 -291.624766) (xy 52.22307 -291.575712) (xy 52.234847 -291.527928)
			(xy 52.254138 -291.482652) (xy 52.280441 -291.441056) (xy 52.313076 -291.404219) (xy 52.351197 -291.373094)
			(xy 52.393818 -291.348487) (xy 52.439834 -291.331035) (xy 52.488053 -291.321191) (xy 52.537228 -291.31921)
			(xy 52.586083 -291.325142) (xy 52.633354 -291.338834) (xy 52.677816 -291.359932) (xy 52.718319 -291.387888)
			(xy 52.753812 -291.42198) (xy 52.783377 -291.461324) (xy 52.806248 -291.504901) (xy 52.821832 -291.551582)
			(xy 52.829727 -291.600159) (xy 52.830222 -291.624766) (xy 53.16907 -291.624766) (xy 53.17303 -291.575712)
			(xy 53.184807 -291.527928) (xy 53.204098 -291.482652) (xy 53.230401 -291.441056) (xy 53.263036 -291.404219)
			(xy 53.301157 -291.373094) (xy 53.343778 -291.348487) (xy 53.389794 -291.331035) (xy 53.438013 -291.321191)
			(xy 53.487188 -291.31921) (xy 53.536043 -291.325142) (xy 53.583314 -291.338834) (xy 53.627776 -291.359932)
			(xy 53.668279 -291.387888) (xy 53.703772 -291.42198) (xy 53.733337 -291.461324) (xy 53.756208 -291.504901)
			(xy 53.771792 -291.551582) (xy 53.779687 -291.600159) (xy 53.780182 -291.624766) (xy 54.11903 -291.624766)
			(xy 54.12299 -291.575712) (xy 54.134767 -291.527928) (xy 54.154058 -291.482652) (xy 54.180361 -291.441056)
			(xy 54.212996 -291.404219) (xy 54.251117 -291.373094) (xy 54.293738 -291.348487) (xy 54.339754 -291.331035)
			(xy 54.387973 -291.321191) (xy 54.437148 -291.31921) (xy 54.486003 -291.325142) (xy 54.533274 -291.338834)
			(xy 54.577736 -291.359932) (xy 54.618239 -291.387888) (xy 54.653732 -291.42198) (xy 54.683297 -291.461324)
			(xy 54.706168 -291.504901) (xy 54.721752 -291.551582) (xy 54.729647 -291.600159) (xy 54.730142 -291.624766)
			(xy 55.06899 -291.624766) (xy 55.07295 -291.575712) (xy 55.084727 -291.527928) (xy 55.104018 -291.482652)
			(xy 55.130321 -291.441056) (xy 55.162956 -291.404219) (xy 55.201077 -291.373094) (xy 55.243698 -291.348487)
			(xy 55.289714 -291.331035) (xy 55.337933 -291.321191) (xy 55.387108 -291.31921) (xy 55.435963 -291.325142)
			(xy 55.483234 -291.338834) (xy 55.527696 -291.359932) (xy 55.568199 -291.387888) (xy 55.603692 -291.42198)
			(xy 55.633257 -291.461324) (xy 55.656128 -291.504901) (xy 55.671712 -291.551582) (xy 55.679607 -291.600159)
			(xy 55.680102 -291.624766) (xy 56.01895 -291.624766) (xy 56.02291 -291.575712) (xy 56.034687 -291.527928)
			(xy 56.053978 -291.482652) (xy 56.080281 -291.441056) (xy 56.112916 -291.404219) (xy 56.151037 -291.373094)
			(xy 56.193658 -291.348487) (xy 56.239674 -291.331035) (xy 56.287893 -291.321191) (xy 56.337068 -291.31921)
			(xy 56.385923 -291.325142) (xy 56.433194 -291.338834) (xy 56.477656 -291.359932) (xy 56.518159 -291.387888)
			(xy 56.553652 -291.42198) (xy 56.583217 -291.461324) (xy 56.606088 -291.504901) (xy 56.621672 -291.551582)
			(xy 56.629567 -291.600159) (xy 56.630062 -291.624766) (xy 56.969164 -291.624766) (xy 56.973124 -291.575712)
			(xy 56.984901 -291.527928) (xy 57.004192 -291.482652) (xy 57.030495 -291.441056) (xy 57.06313 -291.404219)
			(xy 57.101251 -291.373094) (xy 57.143872 -291.348487) (xy 57.189888 -291.331035) (xy 57.238107 -291.321191)
			(xy 57.287282 -291.31921) (xy 57.336137 -291.325142) (xy 57.383408 -291.338834) (xy 57.42787 -291.359932)
			(xy 57.468373 -291.387888) (xy 57.503866 -291.42198) (xy 57.533431 -291.461324) (xy 57.556302 -291.504901)
			(xy 57.571886 -291.551582) (xy 57.579781 -291.600159) (xy 57.580276 -291.624766) (xy 57.919124 -291.624766)
			(xy 57.923084 -291.575712) (xy 57.934861 -291.527928) (xy 57.954152 -291.482652) (xy 57.980455 -291.441056)
			(xy 58.01309 -291.404219) (xy 58.051211 -291.373094) (xy 58.093832 -291.348487) (xy 58.139848 -291.331035)
			(xy 58.188067 -291.321191) (xy 58.237242 -291.31921) (xy 58.286097 -291.325142) (xy 58.333368 -291.338834)
			(xy 58.37783 -291.359932) (xy 58.418333 -291.387888) (xy 58.453826 -291.42198) (xy 58.483391 -291.461324)
			(xy 58.506262 -291.504901) (xy 58.521846 -291.551582) (xy 58.529741 -291.600159) (xy 58.530236 -291.624766)
			(xy 59.819044 -291.624766) (xy 59.823004 -291.575712) (xy 59.834781 -291.527928) (xy 59.854072 -291.482652)
			(xy 59.880375 -291.441056) (xy 59.91301 -291.404219) (xy 59.951131 -291.373094) (xy 59.993752 -291.348487)
			(xy 60.039768 -291.331035) (xy 60.087987 -291.321191) (xy 60.137162 -291.31921) (xy 60.186017 -291.325142)
			(xy 60.233288 -291.338834) (xy 60.27775 -291.359932) (xy 60.318253 -291.387888) (xy 60.353746 -291.42198)
			(xy 60.383311 -291.461324) (xy 60.406182 -291.504901) (xy 60.421766 -291.551582) (xy 60.429661 -291.600159)
			(xy 60.430156 -291.624766) (xy 60.769004 -291.624766) (xy 60.772964 -291.575712) (xy 60.784741 -291.527928)
			(xy 60.804032 -291.482652) (xy 60.830335 -291.441056) (xy 60.86297 -291.404219) (xy 60.901091 -291.373094)
			(xy 60.943712 -291.348487) (xy 60.989728 -291.331035) (xy 61.037947 -291.321191) (xy 61.087122 -291.31921)
			(xy 61.135977 -291.325142) (xy 61.183248 -291.338834) (xy 61.22771 -291.359932) (xy 61.268213 -291.387888)
			(xy 61.303706 -291.42198) (xy 61.333271 -291.461324) (xy 61.356142 -291.504901) (xy 61.371726 -291.551582)
			(xy 61.379621 -291.600159) (xy 61.380116 -291.624766) (xy 61.718964 -291.624766) (xy 61.722924 -291.575712)
			(xy 61.734701 -291.527928) (xy 61.753992 -291.482652) (xy 61.780295 -291.441056) (xy 61.81293 -291.404219)
			(xy 61.851051 -291.373094) (xy 61.893672 -291.348487) (xy 61.939688 -291.331035) (xy 61.987907 -291.321191)
			(xy 62.037082 -291.31921) (xy 62.085937 -291.325142) (xy 62.133208 -291.338834) (xy 62.17767 -291.359932)
			(xy 62.218173 -291.387888) (xy 62.253666 -291.42198) (xy 62.283231 -291.461324) (xy 62.306102 -291.504901)
			(xy 62.321686 -291.551582) (xy 62.329581 -291.600159) (xy 62.330076 -291.624766) (xy 62.669178 -291.624766)
			(xy 62.673138 -291.575712) (xy 62.684915 -291.527928) (xy 62.704206 -291.482652) (xy 62.730509 -291.441056)
			(xy 62.763144 -291.404219) (xy 62.801265 -291.373094) (xy 62.843886 -291.348487) (xy 62.889902 -291.331035)
			(xy 62.938121 -291.321191) (xy 62.987296 -291.31921) (xy 63.036151 -291.325142) (xy 63.083422 -291.338834)
			(xy 63.127884 -291.359932) (xy 63.168387 -291.387888) (xy 63.20388 -291.42198) (xy 63.233445 -291.461324)
			(xy 63.256316 -291.504901) (xy 63.2719 -291.551582) (xy 63.279795 -291.600159) (xy 63.28029 -291.624766)
			(xy 63.619138 -291.624766) (xy 63.623098 -291.575712) (xy 63.634875 -291.527928) (xy 63.654166 -291.482652)
			(xy 63.680469 -291.441056) (xy 63.713104 -291.404219) (xy 63.751225 -291.373094) (xy 63.793846 -291.348487)
			(xy 63.839862 -291.331035) (xy 63.888081 -291.321191) (xy 63.937256 -291.31921) (xy 63.986111 -291.325142)
			(xy 64.033382 -291.338834) (xy 64.077844 -291.359932) (xy 64.118347 -291.387888) (xy 64.15384 -291.42198)
			(xy 64.183405 -291.461324) (xy 64.206276 -291.504901) (xy 64.22186 -291.551582) (xy 64.229755 -291.600159)
			(xy 64.23025 -291.624766) (xy 64.569098 -291.624766) (xy 64.573058 -291.575712) (xy 64.584835 -291.527928)
			(xy 64.604126 -291.482652) (xy 64.630429 -291.441056) (xy 64.663064 -291.404219) (xy 64.701185 -291.373094)
			(xy 64.743806 -291.348487) (xy 64.789822 -291.331035) (xy 64.838041 -291.321191) (xy 64.887216 -291.31921)
			(xy 64.936071 -291.325142) (xy 64.983342 -291.338834) (xy 65.027804 -291.359932) (xy 65.068307 -291.387888)
			(xy 65.1038 -291.42198) (xy 65.133365 -291.461324) (xy 65.156236 -291.504901) (xy 65.17182 -291.551582)
			(xy 65.179715 -291.600159) (xy 65.18021 -291.624766) (xy 65.519058 -291.624766) (xy 65.523018 -291.575712)
			(xy 65.534795 -291.527928) (xy 65.554086 -291.482652) (xy 65.580389 -291.441056) (xy 65.613024 -291.404219)
			(xy 65.651145 -291.373094) (xy 65.693766 -291.348487) (xy 65.739782 -291.331035) (xy 65.788001 -291.321191)
			(xy 65.837176 -291.31921) (xy 65.886031 -291.325142) (xy 65.933302 -291.338834) (xy 65.977764 -291.359932)
			(xy 66.018267 -291.387888) (xy 66.05376 -291.42198) (xy 66.083325 -291.461324) (xy 66.106196 -291.504901)
			(xy 66.12178 -291.551582) (xy 66.129675 -291.600159) (xy 66.13017 -291.624766) (xy 66.469018 -291.624766)
			(xy 66.472978 -291.575712) (xy 66.484755 -291.527928) (xy 66.504046 -291.482652) (xy 66.530349 -291.441056)
			(xy 66.562984 -291.404219) (xy 66.601105 -291.373094) (xy 66.643726 -291.348487) (xy 66.689742 -291.331035)
			(xy 66.737961 -291.321191) (xy 66.787136 -291.31921) (xy 66.835991 -291.325142) (xy 66.883262 -291.338834)
			(xy 66.927724 -291.359932) (xy 66.968227 -291.387888) (xy 67.00372 -291.42198) (xy 67.033285 -291.461324)
			(xy 67.056156 -291.504901) (xy 67.07174 -291.551582) (xy 67.079635 -291.600159) (xy 67.08013 -291.624766)
			(xy 67.418978 -291.624766) (xy 67.422938 -291.575712) (xy 67.434715 -291.527928) (xy 67.454006 -291.482652)
			(xy 67.480309 -291.441056) (xy 67.512944 -291.404219) (xy 67.551065 -291.373094) (xy 67.593686 -291.348487)
			(xy 67.639702 -291.331035) (xy 67.687921 -291.321191) (xy 67.737096 -291.31921) (xy 67.785951 -291.325142)
			(xy 67.833222 -291.338834) (xy 67.877684 -291.359932) (xy 67.918187 -291.387888) (xy 67.95368 -291.42198)
			(xy 67.983245 -291.461324) (xy 68.006116 -291.504901) (xy 68.0217 -291.551582) (xy 68.029595 -291.600159)
			(xy 68.03009 -291.624766) (xy 68.368938 -291.624766) (xy 68.372898 -291.575712) (xy 68.384675 -291.527928)
			(xy 68.403966 -291.482652) (xy 68.430269 -291.441056) (xy 68.462904 -291.404219) (xy 68.501025 -291.373094)
			(xy 68.543646 -291.348487) (xy 68.589662 -291.331035) (xy 68.637881 -291.321191) (xy 68.687056 -291.31921)
			(xy 68.735911 -291.325142) (xy 68.783182 -291.338834) (xy 68.827644 -291.359932) (xy 68.868147 -291.387888)
			(xy 68.90364 -291.42198) (xy 68.933205 -291.461324) (xy 68.956076 -291.504901) (xy 68.97166 -291.551582)
			(xy 68.979555 -291.600159) (xy 68.98005 -291.624766) (xy 69.319152 -291.624766) (xy 69.323112 -291.575712)
			(xy 69.334889 -291.527928) (xy 69.35418 -291.482652) (xy 69.380483 -291.441056) (xy 69.413118 -291.404219)
			(xy 69.451239 -291.373094) (xy 69.49386 -291.348487) (xy 69.539876 -291.331035) (xy 69.588095 -291.321191)
			(xy 69.63727 -291.31921) (xy 69.686125 -291.325142) (xy 69.733396 -291.338834) (xy 69.777858 -291.359932)
			(xy 69.818361 -291.387888) (xy 69.853854 -291.42198) (xy 69.883419 -291.461324) (xy 69.90629 -291.504901)
			(xy 69.921874 -291.551582) (xy 69.929769 -291.600159) (xy 69.930264 -291.624766) (xy 70.269112 -291.624766)
			(xy 70.273072 -291.575712) (xy 70.284849 -291.527928) (xy 70.30414 -291.482652) (xy 70.330443 -291.441056)
			(xy 70.363078 -291.404219) (xy 70.401199 -291.373094) (xy 70.44382 -291.348487) (xy 70.489836 -291.331035)
			(xy 70.538055 -291.321191) (xy 70.58723 -291.31921) (xy 70.636085 -291.325142) (xy 70.683356 -291.338834)
			(xy 70.727818 -291.359932) (xy 70.768321 -291.387888) (xy 70.803814 -291.42198) (xy 70.833379 -291.461324)
			(xy 70.85625 -291.504901) (xy 70.871834 -291.551582) (xy 70.879729 -291.600159) (xy 70.880224 -291.624766)
			(xy 71.219072 -291.624766) (xy 71.223032 -291.575712) (xy 71.234809 -291.527928) (xy 71.2541 -291.482652)
			(xy 71.280403 -291.441056) (xy 71.313038 -291.404219) (xy 71.351159 -291.373094) (xy 71.39378 -291.348487)
			(xy 71.439796 -291.331035) (xy 71.488015 -291.321191) (xy 71.53719 -291.31921) (xy 71.586045 -291.325142)
			(xy 71.633316 -291.338834) (xy 71.677778 -291.359932) (xy 71.718281 -291.387888) (xy 71.753774 -291.42198)
			(xy 71.783339 -291.461324) (xy 71.80621 -291.504901) (xy 71.821794 -291.551582) (xy 71.829689 -291.600159)
			(xy 71.830184 -291.624766) (xy 72.169032 -291.624766) (xy 72.172992 -291.575712) (xy 72.184769 -291.527928)
			(xy 72.20406 -291.482652) (xy 72.230363 -291.441056) (xy 72.262998 -291.404219) (xy 72.301119 -291.373094)
			(xy 72.34374 -291.348487) (xy 72.389756 -291.331035) (xy 72.437975 -291.321191) (xy 72.48715 -291.31921)
			(xy 72.536005 -291.325142) (xy 72.583276 -291.338834) (xy 72.627738 -291.359932) (xy 72.668241 -291.387888)
			(xy 72.703734 -291.42198) (xy 72.733299 -291.461324) (xy 72.75617 -291.504901) (xy 72.771754 -291.551582)
			(xy 72.779649 -291.600159) (xy 72.780144 -291.624766) (xy 73.118992 -291.624766) (xy 73.122952 -291.575712)
			(xy 73.134729 -291.527928) (xy 73.15402 -291.482652) (xy 73.180323 -291.441056) (xy 73.212958 -291.404219)
			(xy 73.251079 -291.373094) (xy 73.2937 -291.348487) (xy 73.339716 -291.331035) (xy 73.387935 -291.321191)
			(xy 73.43711 -291.31921) (xy 73.485965 -291.325142) (xy 73.533236 -291.338834) (xy 73.577698 -291.359932)
			(xy 73.618201 -291.387888) (xy 73.653694 -291.42198) (xy 73.683259 -291.461324) (xy 73.70613 -291.504901)
			(xy 73.721714 -291.551582) (xy 73.729609 -291.600159) (xy 73.730104 -291.624766) (xy 74.069206 -291.624766)
			(xy 74.073166 -291.575712) (xy 74.084943 -291.527928) (xy 74.104234 -291.482652) (xy 74.130537 -291.441056)
			(xy 74.163172 -291.404219) (xy 74.201293 -291.373094) (xy 74.243914 -291.348487) (xy 74.28993 -291.331035)
			(xy 74.338149 -291.321191) (xy 74.387324 -291.31921) (xy 74.436179 -291.325142) (xy 74.48345 -291.338834)
			(xy 74.527912 -291.359932) (xy 74.568415 -291.387888) (xy 74.603908 -291.42198) (xy 74.633473 -291.461324)
			(xy 74.656344 -291.504901) (xy 74.671928 -291.551582) (xy 74.679823 -291.600159) (xy 74.680318 -291.624766)
			(xy 75.969126 -291.624766) (xy 75.973086 -291.575712) (xy 75.984863 -291.527928) (xy 76.004154 -291.482652)
			(xy 76.030457 -291.441056) (xy 76.063092 -291.404219) (xy 76.101213 -291.373094) (xy 76.143834 -291.348487)
			(xy 76.18985 -291.331035) (xy 76.238069 -291.321191) (xy 76.287244 -291.31921) (xy 76.336099 -291.325142)
			(xy 76.38337 -291.338834) (xy 76.427832 -291.359932) (xy 76.468335 -291.387888) (xy 76.503828 -291.42198)
			(xy 76.533393 -291.461324) (xy 76.556264 -291.504901) (xy 76.571848 -291.551582) (xy 76.579743 -291.600159)
			(xy 76.580238 -291.624766) (xy 76.919086 -291.624766) (xy 76.923046 -291.575712) (xy 76.934823 -291.527928)
			(xy 76.954114 -291.482652) (xy 76.980417 -291.441056) (xy 77.013052 -291.404219) (xy 77.051173 -291.373094)
			(xy 77.093794 -291.348487) (xy 77.13981 -291.331035) (xy 77.188029 -291.321191) (xy 77.237204 -291.31921)
			(xy 77.286059 -291.325142) (xy 77.33333 -291.338834) (xy 77.377792 -291.359932) (xy 77.418295 -291.387888)
			(xy 77.453788 -291.42198) (xy 77.483353 -291.461324) (xy 77.506224 -291.504901) (xy 77.521808 -291.551582)
			(xy 77.529703 -291.600159) (xy 77.530198 -291.624766) (xy 77.869046 -291.624766) (xy 77.873006 -291.575712)
			(xy 77.884783 -291.527928) (xy 77.904074 -291.482652) (xy 77.930377 -291.441056) (xy 77.963012 -291.404219)
			(xy 78.001133 -291.373094) (xy 78.043754 -291.348487) (xy 78.08977 -291.331035) (xy 78.137989 -291.321191)
			(xy 78.187164 -291.31921) (xy 78.236019 -291.325142) (xy 78.28329 -291.338834) (xy 78.327752 -291.359932)
			(xy 78.368255 -291.387888) (xy 78.403748 -291.42198) (xy 78.433313 -291.461324) (xy 78.456184 -291.504901)
			(xy 78.471768 -291.551582) (xy 78.479663 -291.600159) (xy 78.480158 -291.624766) (xy 78.479663 -291.649373)
			(xy 78.471768 -291.69795) (xy 78.456184 -291.744631) (xy 78.433313 -291.788208) (xy 78.403748 -291.827552)
			(xy 78.368255 -291.861644) (xy 78.327752 -291.8896) (xy 78.28329 -291.910698) (xy 78.236019 -291.92439)
			(xy 78.187164 -291.930322) (xy 78.137989 -291.928341) (xy 78.08977 -291.918497) (xy 78.043754 -291.901045)
			(xy 78.001133 -291.876438) (xy 77.963012 -291.845313) (xy 77.930377 -291.808476) (xy 77.904074 -291.76688)
			(xy 77.884783 -291.721604) (xy 77.873006 -291.67382) (xy 77.869046 -291.624766) (xy 77.530198 -291.624766)
			(xy 77.529703 -291.649373) (xy 77.521808 -291.69795) (xy 77.506224 -291.744631) (xy 77.483353 -291.788208)
			(xy 77.453788 -291.827552) (xy 77.418295 -291.861644) (xy 77.377792 -291.8896) (xy 77.33333 -291.910698)
			(xy 77.286059 -291.92439) (xy 77.237204 -291.930322) (xy 77.188029 -291.928341) (xy 77.13981 -291.918497)
			(xy 77.093794 -291.901045) (xy 77.051173 -291.876438) (xy 77.013052 -291.845313) (xy 76.980417 -291.808476)
			(xy 76.954114 -291.76688) (xy 76.934823 -291.721604) (xy 76.923046 -291.67382) (xy 76.919086 -291.624766)
			(xy 76.580238 -291.624766) (xy 76.579743 -291.649373) (xy 76.571848 -291.69795) (xy 76.556264 -291.744631)
			(xy 76.533393 -291.788208) (xy 76.503828 -291.827552) (xy 76.468335 -291.861644) (xy 76.427832 -291.8896)
			(xy 76.38337 -291.910698) (xy 76.336099 -291.92439) (xy 76.287244 -291.930322) (xy 76.238069 -291.928341)
			(xy 76.18985 -291.918497) (xy 76.143834 -291.901045) (xy 76.101213 -291.876438) (xy 76.063092 -291.845313)
			(xy 76.030457 -291.808476) (xy 76.004154 -291.76688) (xy 75.984863 -291.721604) (xy 75.973086 -291.67382)
			(xy 75.969126 -291.624766) (xy 74.680318 -291.624766) (xy 74.679823 -291.649373) (xy 74.671928 -291.69795)
			(xy 74.656344 -291.744631) (xy 74.633473 -291.788208) (xy 74.603908 -291.827552) (xy 74.568415 -291.861644)
			(xy 74.527912 -291.8896) (xy 74.48345 -291.910698) (xy 74.436179 -291.92439) (xy 74.387324 -291.930322)
			(xy 74.338149 -291.928341) (xy 74.28993 -291.918497) (xy 74.243914 -291.901045) (xy 74.201293 -291.876438)
			(xy 74.163172 -291.845313) (xy 74.130537 -291.808476) (xy 74.104234 -291.76688) (xy 74.084943 -291.721604)
			(xy 74.073166 -291.67382) (xy 74.069206 -291.624766) (xy 73.730104 -291.624766) (xy 73.729609 -291.649373)
			(xy 73.721714 -291.69795) (xy 73.70613 -291.744631) (xy 73.683259 -291.788208) (xy 73.653694 -291.827552)
			(xy 73.618201 -291.861644) (xy 73.577698 -291.8896) (xy 73.533236 -291.910698) (xy 73.485965 -291.92439)
			(xy 73.43711 -291.930322) (xy 73.387935 -291.928341) (xy 73.339716 -291.918497) (xy 73.2937 -291.901045)
			(xy 73.251079 -291.876438) (xy 73.212958 -291.845313) (xy 73.180323 -291.808476) (xy 73.15402 -291.76688)
			(xy 73.134729 -291.721604) (xy 73.122952 -291.67382) (xy 73.118992 -291.624766) (xy 72.780144 -291.624766)
			(xy 72.779649 -291.649373) (xy 72.771754 -291.69795) (xy 72.75617 -291.744631) (xy 72.733299 -291.788208)
			(xy 72.703734 -291.827552) (xy 72.668241 -291.861644) (xy 72.627738 -291.8896) (xy 72.583276 -291.910698)
			(xy 72.536005 -291.92439) (xy 72.48715 -291.930322) (xy 72.437975 -291.928341) (xy 72.389756 -291.918497)
			(xy 72.34374 -291.901045) (xy 72.301119 -291.876438) (xy 72.262998 -291.845313) (xy 72.230363 -291.808476)
			(xy 72.20406 -291.76688) (xy 72.184769 -291.721604) (xy 72.172992 -291.67382) (xy 72.169032 -291.624766)
			(xy 71.830184 -291.624766) (xy 71.829689 -291.649373) (xy 71.821794 -291.69795) (xy 71.80621 -291.744631)
			(xy 71.783339 -291.788208) (xy 71.753774 -291.827552) (xy 71.718281 -291.861644) (xy 71.677778 -291.8896)
			(xy 71.633316 -291.910698) (xy 71.586045 -291.92439) (xy 71.53719 -291.930322) (xy 71.488015 -291.928341)
			(xy 71.439796 -291.918497) (xy 71.39378 -291.901045) (xy 71.351159 -291.876438) (xy 71.313038 -291.845313)
			(xy 71.280403 -291.808476) (xy 71.2541 -291.76688) (xy 71.234809 -291.721604) (xy 71.223032 -291.67382)
			(xy 71.219072 -291.624766) (xy 70.880224 -291.624766) (xy 70.879729 -291.649373) (xy 70.871834 -291.69795)
			(xy 70.85625 -291.744631) (xy 70.833379 -291.788208) (xy 70.803814 -291.827552) (xy 70.768321 -291.861644)
			(xy 70.727818 -291.8896) (xy 70.683356 -291.910698) (xy 70.636085 -291.92439) (xy 70.58723 -291.930322)
			(xy 70.538055 -291.928341) (xy 70.489836 -291.918497) (xy 70.44382 -291.901045) (xy 70.401199 -291.876438)
			(xy 70.363078 -291.845313) (xy 70.330443 -291.808476) (xy 70.30414 -291.76688) (xy 70.284849 -291.721604)
			(xy 70.273072 -291.67382) (xy 70.269112 -291.624766) (xy 69.930264 -291.624766) (xy 69.929769 -291.649373)
			(xy 69.921874 -291.69795) (xy 69.90629 -291.744631) (xy 69.883419 -291.788208) (xy 69.853854 -291.827552)
			(xy 69.818361 -291.861644) (xy 69.777858 -291.8896) (xy 69.733396 -291.910698) (xy 69.686125 -291.92439)
			(xy 69.63727 -291.930322) (xy 69.588095 -291.928341) (xy 69.539876 -291.918497) (xy 69.49386 -291.901045)
			(xy 69.451239 -291.876438) (xy 69.413118 -291.845313) (xy 69.380483 -291.808476) (xy 69.35418 -291.76688)
			(xy 69.334889 -291.721604) (xy 69.323112 -291.67382) (xy 69.319152 -291.624766) (xy 68.98005 -291.624766)
			(xy 68.979555 -291.649373) (xy 68.97166 -291.69795) (xy 68.956076 -291.744631) (xy 68.933205 -291.788208)
			(xy 68.90364 -291.827552) (xy 68.868147 -291.861644) (xy 68.827644 -291.8896) (xy 68.783182 -291.910698)
			(xy 68.735911 -291.92439) (xy 68.687056 -291.930322) (xy 68.637881 -291.928341) (xy 68.589662 -291.918497)
			(xy 68.543646 -291.901045) (xy 68.501025 -291.876438) (xy 68.462904 -291.845313) (xy 68.430269 -291.808476)
			(xy 68.403966 -291.76688) (xy 68.384675 -291.721604) (xy 68.372898 -291.67382) (xy 68.368938 -291.624766)
			(xy 68.03009 -291.624766) (xy 68.029595 -291.649373) (xy 68.0217 -291.69795) (xy 68.006116 -291.744631)
			(xy 67.983245 -291.788208) (xy 67.95368 -291.827552) (xy 67.918187 -291.861644) (xy 67.877684 -291.8896)
			(xy 67.833222 -291.910698) (xy 67.785951 -291.92439) (xy 67.737096 -291.930322) (xy 67.687921 -291.928341)
			(xy 67.639702 -291.918497) (xy 67.593686 -291.901045) (xy 67.551065 -291.876438) (xy 67.512944 -291.845313)
			(xy 67.480309 -291.808476) (xy 67.454006 -291.76688) (xy 67.434715 -291.721604) (xy 67.422938 -291.67382)
			(xy 67.418978 -291.624766) (xy 67.08013 -291.624766) (xy 67.079635 -291.649373) (xy 67.07174 -291.69795)
			(xy 67.056156 -291.744631) (xy 67.033285 -291.788208) (xy 67.00372 -291.827552) (xy 66.968227 -291.861644)
			(xy 66.927724 -291.8896) (xy 66.883262 -291.910698) (xy 66.835991 -291.92439) (xy 66.787136 -291.930322)
			(xy 66.737961 -291.928341) (xy 66.689742 -291.918497) (xy 66.643726 -291.901045) (xy 66.601105 -291.876438)
			(xy 66.562984 -291.845313) (xy 66.530349 -291.808476) (xy 66.504046 -291.76688) (xy 66.484755 -291.721604)
			(xy 66.472978 -291.67382) (xy 66.469018 -291.624766) (xy 66.13017 -291.624766) (xy 66.129675 -291.649373)
			(xy 66.12178 -291.69795) (xy 66.106196 -291.744631) (xy 66.083325 -291.788208) (xy 66.05376 -291.827552)
			(xy 66.018267 -291.861644) (xy 65.977764 -291.8896) (xy 65.933302 -291.910698) (xy 65.886031 -291.92439)
			(xy 65.837176 -291.930322) (xy 65.788001 -291.928341) (xy 65.739782 -291.918497) (xy 65.693766 -291.901045)
			(xy 65.651145 -291.876438) (xy 65.613024 -291.845313) (xy 65.580389 -291.808476) (xy 65.554086 -291.76688)
			(xy 65.534795 -291.721604) (xy 65.523018 -291.67382) (xy 65.519058 -291.624766) (xy 65.18021 -291.624766)
			(xy 65.179715 -291.649373) (xy 65.17182 -291.69795) (xy 65.156236 -291.744631) (xy 65.133365 -291.788208)
			(xy 65.1038 -291.827552) (xy 65.068307 -291.861644) (xy 65.027804 -291.8896) (xy 64.983342 -291.910698)
			(xy 64.936071 -291.92439) (xy 64.887216 -291.930322) (xy 64.838041 -291.928341) (xy 64.789822 -291.918497)
			(xy 64.743806 -291.901045) (xy 64.701185 -291.876438) (xy 64.663064 -291.845313) (xy 64.630429 -291.808476)
			(xy 64.604126 -291.76688) (xy 64.584835 -291.721604) (xy 64.573058 -291.67382) (xy 64.569098 -291.624766)
			(xy 64.23025 -291.624766) (xy 64.229755 -291.649373) (xy 64.22186 -291.69795) (xy 64.206276 -291.744631)
			(xy 64.183405 -291.788208) (xy 64.15384 -291.827552) (xy 64.118347 -291.861644) (xy 64.077844 -291.8896)
			(xy 64.033382 -291.910698) (xy 63.986111 -291.92439) (xy 63.937256 -291.930322) (xy 63.888081 -291.928341)
			(xy 63.839862 -291.918497) (xy 63.793846 -291.901045) (xy 63.751225 -291.876438) (xy 63.713104 -291.845313)
			(xy 63.680469 -291.808476) (xy 63.654166 -291.76688) (xy 63.634875 -291.721604) (xy 63.623098 -291.67382)
			(xy 63.619138 -291.624766) (xy 63.28029 -291.624766) (xy 63.279795 -291.649373) (xy 63.2719 -291.69795)
			(xy 63.256316 -291.744631) (xy 63.233445 -291.788208) (xy 63.20388 -291.827552) (xy 63.168387 -291.861644)
			(xy 63.127884 -291.8896) (xy 63.083422 -291.910698) (xy 63.036151 -291.92439) (xy 62.987296 -291.930322)
			(xy 62.938121 -291.928341) (xy 62.889902 -291.918497) (xy 62.843886 -291.901045) (xy 62.801265 -291.876438)
			(xy 62.763144 -291.845313) (xy 62.730509 -291.808476) (xy 62.704206 -291.76688) (xy 62.684915 -291.721604)
			(xy 62.673138 -291.67382) (xy 62.669178 -291.624766) (xy 62.330076 -291.624766) (xy 62.329581 -291.649373)
			(xy 62.321686 -291.69795) (xy 62.306102 -291.744631) (xy 62.283231 -291.788208) (xy 62.253666 -291.827552)
			(xy 62.218173 -291.861644) (xy 62.17767 -291.8896) (xy 62.133208 -291.910698) (xy 62.085937 -291.92439)
			(xy 62.037082 -291.930322) (xy 61.987907 -291.928341) (xy 61.939688 -291.918497) (xy 61.893672 -291.901045)
			(xy 61.851051 -291.876438) (xy 61.81293 -291.845313) (xy 61.780295 -291.808476) (xy 61.753992 -291.76688)
			(xy 61.734701 -291.721604) (xy 61.722924 -291.67382) (xy 61.718964 -291.624766) (xy 61.380116 -291.624766)
			(xy 61.379621 -291.649373) (xy 61.371726 -291.69795) (xy 61.356142 -291.744631) (xy 61.333271 -291.788208)
			(xy 61.303706 -291.827552) (xy 61.268213 -291.861644) (xy 61.22771 -291.8896) (xy 61.183248 -291.910698)
			(xy 61.135977 -291.92439) (xy 61.087122 -291.930322) (xy 61.037947 -291.928341) (xy 60.989728 -291.918497)
			(xy 60.943712 -291.901045) (xy 60.901091 -291.876438) (xy 60.86297 -291.845313) (xy 60.830335 -291.808476)
			(xy 60.804032 -291.76688) (xy 60.784741 -291.721604) (xy 60.772964 -291.67382) (xy 60.769004 -291.624766)
			(xy 60.430156 -291.624766) (xy 60.429661 -291.649373) (xy 60.421766 -291.69795) (xy 60.406182 -291.744631)
			(xy 60.383311 -291.788208) (xy 60.353746 -291.827552) (xy 60.318253 -291.861644) (xy 60.27775 -291.8896)
			(xy 60.233288 -291.910698) (xy 60.186017 -291.92439) (xy 60.137162 -291.930322) (xy 60.087987 -291.928341)
			(xy 60.039768 -291.918497) (xy 59.993752 -291.901045) (xy 59.951131 -291.876438) (xy 59.91301 -291.845313)
			(xy 59.880375 -291.808476) (xy 59.854072 -291.76688) (xy 59.834781 -291.721604) (xy 59.823004 -291.67382)
			(xy 59.819044 -291.624766) (xy 58.530236 -291.624766) (xy 58.529741 -291.649373) (xy 58.521846 -291.69795)
			(xy 58.506262 -291.744631) (xy 58.483391 -291.788208) (xy 58.453826 -291.827552) (xy 58.418333 -291.861644)
			(xy 58.37783 -291.8896) (xy 58.333368 -291.910698) (xy 58.286097 -291.92439) (xy 58.237242 -291.930322)
			(xy 58.188067 -291.928341) (xy 58.139848 -291.918497) (xy 58.093832 -291.901045) (xy 58.051211 -291.876438)
			(xy 58.01309 -291.845313) (xy 57.980455 -291.808476) (xy 57.954152 -291.76688) (xy 57.934861 -291.721604)
			(xy 57.923084 -291.67382) (xy 57.919124 -291.624766) (xy 57.580276 -291.624766) (xy 57.579781 -291.649373)
			(xy 57.571886 -291.69795) (xy 57.556302 -291.744631) (xy 57.533431 -291.788208) (xy 57.503866 -291.827552)
			(xy 57.468373 -291.861644) (xy 57.42787 -291.8896) (xy 57.383408 -291.910698) (xy 57.336137 -291.92439)
			(xy 57.287282 -291.930322) (xy 57.238107 -291.928341) (xy 57.189888 -291.918497) (xy 57.143872 -291.901045)
			(xy 57.101251 -291.876438) (xy 57.06313 -291.845313) (xy 57.030495 -291.808476) (xy 57.004192 -291.76688)
			(xy 56.984901 -291.721604) (xy 56.973124 -291.67382) (xy 56.969164 -291.624766) (xy 56.630062 -291.624766)
			(xy 56.629567 -291.649373) (xy 56.621672 -291.69795) (xy 56.606088 -291.744631) (xy 56.583217 -291.788208)
			(xy 56.553652 -291.827552) (xy 56.518159 -291.861644) (xy 56.477656 -291.8896) (xy 56.433194 -291.910698)
			(xy 56.385923 -291.92439) (xy 56.337068 -291.930322) (xy 56.287893 -291.928341) (xy 56.239674 -291.918497)
			(xy 56.193658 -291.901045) (xy 56.151037 -291.876438) (xy 56.112916 -291.845313) (xy 56.080281 -291.808476)
			(xy 56.053978 -291.76688) (xy 56.034687 -291.721604) (xy 56.02291 -291.67382) (xy 56.01895 -291.624766)
			(xy 55.680102 -291.624766) (xy 55.679607 -291.649373) (xy 55.671712 -291.69795) (xy 55.656128 -291.744631)
			(xy 55.633257 -291.788208) (xy 55.603692 -291.827552) (xy 55.568199 -291.861644) (xy 55.527696 -291.8896)
			(xy 55.483234 -291.910698) (xy 55.435963 -291.92439) (xy 55.387108 -291.930322) (xy 55.337933 -291.928341)
			(xy 55.289714 -291.918497) (xy 55.243698 -291.901045) (xy 55.201077 -291.876438) (xy 55.162956 -291.845313)
			(xy 55.130321 -291.808476) (xy 55.104018 -291.76688) (xy 55.084727 -291.721604) (xy 55.07295 -291.67382)
			(xy 55.06899 -291.624766) (xy 54.730142 -291.624766) (xy 54.729647 -291.649373) (xy 54.721752 -291.69795)
			(xy 54.706168 -291.744631) (xy 54.683297 -291.788208) (xy 54.653732 -291.827552) (xy 54.618239 -291.861644)
			(xy 54.577736 -291.8896) (xy 54.533274 -291.910698) (xy 54.486003 -291.92439) (xy 54.437148 -291.930322)
			(xy 54.387973 -291.928341) (xy 54.339754 -291.918497) (xy 54.293738 -291.901045) (xy 54.251117 -291.876438)
			(xy 54.212996 -291.845313) (xy 54.180361 -291.808476) (xy 54.154058 -291.76688) (xy 54.134767 -291.721604)
			(xy 54.12299 -291.67382) (xy 54.11903 -291.624766) (xy 53.780182 -291.624766) (xy 53.779687 -291.649373)
			(xy 53.771792 -291.69795) (xy 53.756208 -291.744631) (xy 53.733337 -291.788208) (xy 53.703772 -291.827552)
			(xy 53.668279 -291.861644) (xy 53.627776 -291.8896) (xy 53.583314 -291.910698) (xy 53.536043 -291.92439)
			(xy 53.487188 -291.930322) (xy 53.438013 -291.928341) (xy 53.389794 -291.918497) (xy 53.343778 -291.901045)
			(xy 53.301157 -291.876438) (xy 53.263036 -291.845313) (xy 53.230401 -291.808476) (xy 53.204098 -291.76688)
			(xy 53.184807 -291.721604) (xy 53.17303 -291.67382) (xy 53.16907 -291.624766) (xy 52.830222 -291.624766)
			(xy 52.829727 -291.649373) (xy 52.821832 -291.69795) (xy 52.806248 -291.744631) (xy 52.783377 -291.788208)
			(xy 52.753812 -291.827552) (xy 52.718319 -291.861644) (xy 52.677816 -291.8896) (xy 52.633354 -291.910698)
			(xy 52.586083 -291.92439) (xy 52.537228 -291.930322) (xy 52.488053 -291.928341) (xy 52.439834 -291.918497)
			(xy 52.393818 -291.901045) (xy 52.351197 -291.876438) (xy 52.313076 -291.845313) (xy 52.280441 -291.808476)
			(xy 52.254138 -291.76688) (xy 52.234847 -291.721604) (xy 52.22307 -291.67382) (xy 52.21911 -291.624766)
			(xy 51.880262 -291.624766) (xy 51.879767 -291.649373) (xy 51.871872 -291.69795) (xy 51.856288 -291.744631)
			(xy 51.833417 -291.788208) (xy 51.803852 -291.827552) (xy 51.768359 -291.861644) (xy 51.727856 -291.8896)
			(xy 51.683394 -291.910698) (xy 51.636123 -291.92439) (xy 51.587268 -291.930322) (xy 51.538093 -291.928341)
			(xy 51.489874 -291.918497) (xy 51.443858 -291.901045) (xy 51.401237 -291.876438) (xy 51.363116 -291.845313)
			(xy 51.330481 -291.808476) (xy 51.304178 -291.76688) (xy 51.284887 -291.721604) (xy 51.27311 -291.67382)
			(xy 51.26915 -291.624766) (xy 50.930302 -291.624766) (xy 50.929807 -291.649373) (xy 50.921912 -291.69795)
			(xy 50.906328 -291.744631) (xy 50.883457 -291.788208) (xy 50.853892 -291.827552) (xy 50.818399 -291.861644)
			(xy 50.777896 -291.8896) (xy 50.733434 -291.910698) (xy 50.686163 -291.92439) (xy 50.637308 -291.930322)
			(xy 50.588133 -291.928341) (xy 50.539914 -291.918497) (xy 50.493898 -291.901045) (xy 50.451277 -291.876438)
			(xy 50.413156 -291.845313) (xy 50.380521 -291.808476) (xy 50.354218 -291.76688) (xy 50.334927 -291.721604)
			(xy 50.32315 -291.67382) (xy 50.31919 -291.624766) (xy 49.980088 -291.624766) (xy 49.979593 -291.649373)
			(xy 49.971698 -291.69795) (xy 49.956114 -291.744631) (xy 49.933243 -291.788208) (xy 49.903678 -291.827552)
			(xy 49.868185 -291.861644) (xy 49.827682 -291.8896) (xy 49.78322 -291.910698) (xy 49.735949 -291.92439)
			(xy 49.687094 -291.930322) (xy 49.637919 -291.928341) (xy 49.5897 -291.918497) (xy 49.543684 -291.901045)
			(xy 49.501063 -291.876438) (xy 49.462942 -291.845313) (xy 49.430307 -291.808476) (xy 49.404004 -291.76688)
			(xy 49.384713 -291.721604) (xy 49.372936 -291.67382) (xy 49.368976 -291.624766) (xy 49.030128 -291.624766)
			(xy 49.029633 -291.649373) (xy 49.021738 -291.69795) (xy 49.006154 -291.744631) (xy 48.983283 -291.788208)
			(xy 48.953718 -291.827552) (xy 48.918225 -291.861644) (xy 48.877722 -291.8896) (xy 48.83326 -291.910698)
			(xy 48.785989 -291.92439) (xy 48.737134 -291.930322) (xy 48.687959 -291.928341) (xy 48.63974 -291.918497)
			(xy 48.593724 -291.901045) (xy 48.551103 -291.876438) (xy 48.512982 -291.845313) (xy 48.480347 -291.808476)
			(xy 48.454044 -291.76688) (xy 48.434753 -291.721604) (xy 48.422976 -291.67382) (xy 48.419016 -291.624766)
			(xy 48.080168 -291.624766) (xy 48.079673 -291.649373) (xy 48.071778 -291.69795) (xy 48.056194 -291.744631)
			(xy 48.033323 -291.788208) (xy 48.003758 -291.827552) (xy 47.968265 -291.861644) (xy 47.927762 -291.8896)
			(xy 47.8833 -291.910698) (xy 47.836029 -291.92439) (xy 47.787174 -291.930322) (xy 47.737999 -291.928341)
			(xy 47.68978 -291.918497) (xy 47.643764 -291.901045) (xy 47.601143 -291.876438) (xy 47.563022 -291.845313)
			(xy 47.530387 -291.808476) (xy 47.504084 -291.76688) (xy 47.484793 -291.721604) (xy 47.473016 -291.67382)
			(xy 47.469056 -291.624766) (xy 46.180248 -291.624766) (xy 46.179753 -291.649373) (xy 46.171858 -291.69795)
			(xy 46.156274 -291.744631) (xy 46.133403 -291.788208) (xy 46.103838 -291.827552) (xy 46.068345 -291.861644)
			(xy 46.027842 -291.8896) (xy 45.98338 -291.910698) (xy 45.936109 -291.92439) (xy 45.887254 -291.930322)
			(xy 45.838079 -291.928341) (xy 45.78986 -291.918497) (xy 45.743844 -291.901045) (xy 45.701223 -291.876438)
			(xy 45.663102 -291.845313) (xy 45.630467 -291.808476) (xy 45.604164 -291.76688) (xy 45.584873 -291.721604)
			(xy 45.573096 -291.67382) (xy 45.569136 -291.624766) (xy 45.230288 -291.624766) (xy 45.229793 -291.649373)
			(xy 45.221898 -291.69795) (xy 45.206314 -291.744631) (xy 45.183443 -291.788208) (xy 45.153878 -291.827552)
			(xy 45.118385 -291.861644) (xy 45.077882 -291.8896) (xy 45.03342 -291.910698) (xy 44.986149 -291.92439)
			(xy 44.937294 -291.930322) (xy 44.888119 -291.928341) (xy 44.8399 -291.918497) (xy 44.793884 -291.901045)
			(xy 44.751263 -291.876438) (xy 44.713142 -291.845313) (xy 44.680507 -291.808476) (xy 44.654204 -291.76688)
			(xy 44.634913 -291.721604) (xy 44.623136 -291.67382) (xy 44.619176 -291.624766) (xy 44.280074 -291.624766)
			(xy 44.279579 -291.649373) (xy 44.271684 -291.69795) (xy 44.2561 -291.744631) (xy 44.233229 -291.788208)
			(xy 44.203664 -291.827552) (xy 44.168171 -291.861644) (xy 44.127668 -291.8896) (xy 44.083206 -291.910698)
			(xy 44.035935 -291.92439) (xy 43.98708 -291.930322) (xy 43.937905 -291.928341) (xy 43.889686 -291.918497)
			(xy 43.84367 -291.901045) (xy 43.801049 -291.876438) (xy 43.762928 -291.845313) (xy 43.730293 -291.808476)
			(xy 43.70399 -291.76688) (xy 43.684699 -291.721604) (xy 43.672922 -291.67382) (xy 43.668962 -291.624766)
			(xy 43.330114 -291.624766) (xy 43.329619 -291.649373) (xy 43.321724 -291.69795) (xy 43.30614 -291.744631)
			(xy 43.283269 -291.788208) (xy 43.253704 -291.827552) (xy 43.218211 -291.861644) (xy 43.177708 -291.8896)
			(xy 43.133246 -291.910698) (xy 43.085975 -291.92439) (xy 43.03712 -291.930322) (xy 42.987945 -291.928341)
			(xy 42.939726 -291.918497) (xy 42.89371 -291.901045) (xy 42.851089 -291.876438) (xy 42.812968 -291.845313)
			(xy 42.780333 -291.808476) (xy 42.75403 -291.76688) (xy 42.734739 -291.721604) (xy 42.722962 -291.67382)
			(xy 42.719002 -291.624766) (xy 42.380154 -291.624766) (xy 42.379659 -291.649373) (xy 42.371764 -291.69795)
			(xy 42.35618 -291.744631) (xy 42.333309 -291.788208) (xy 42.303744 -291.827552) (xy 42.268251 -291.861644)
			(xy 42.227748 -291.8896) (xy 42.183286 -291.910698) (xy 42.136015 -291.92439) (xy 42.08716 -291.930322)
			(xy 42.037985 -291.928341) (xy 41.989766 -291.918497) (xy 41.94375 -291.901045) (xy 41.901129 -291.876438)
			(xy 41.863008 -291.845313) (xy 41.830373 -291.808476) (xy 41.80407 -291.76688) (xy 41.784779 -291.721604)
			(xy 41.773002 -291.67382) (xy 41.769042 -291.624766) (xy 41.430194 -291.624766) (xy 41.429699 -291.649373)
			(xy 41.421804 -291.69795) (xy 41.40622 -291.744631) (xy 41.383349 -291.788208) (xy 41.353784 -291.827552)
			(xy 41.318291 -291.861644) (xy 41.277788 -291.8896) (xy 41.233326 -291.910698) (xy 41.186055 -291.92439)
			(xy 41.1372 -291.930322) (xy 41.088025 -291.928341) (xy 41.039806 -291.918497) (xy 40.99379 -291.901045)
			(xy 40.951169 -291.876438) (xy 40.913048 -291.845313) (xy 40.880413 -291.808476) (xy 40.85411 -291.76688)
			(xy 40.834819 -291.721604) (xy 40.823042 -291.67382) (xy 40.819082 -291.624766) (xy 38.580314 -291.624766)
			(xy 38.579819 -291.649373) (xy 38.571924 -291.69795) (xy 38.55634 -291.744631) (xy 38.533469 -291.788208)
			(xy 38.503904 -291.827552) (xy 38.468411 -291.861644) (xy 38.427908 -291.8896) (xy 38.383446 -291.910698)
			(xy 38.336175 -291.92439) (xy 38.28732 -291.930322) (xy 38.238145 -291.928341) (xy 38.189926 -291.918497)
			(xy 38.14391 -291.901045) (xy 38.101289 -291.876438) (xy 38.063168 -291.845313) (xy 38.030533 -291.808476)
			(xy 38.00423 -291.76688) (xy 37.984939 -291.721604) (xy 37.973162 -291.67382) (xy 37.969202 -291.624766)
			(xy 37.6301 -291.624766) (xy 37.629605 -291.649373) (xy 37.62171 -291.69795) (xy 37.606126 -291.744631)
			(xy 37.583255 -291.788208) (xy 37.55369 -291.827552) (xy 37.518197 -291.861644) (xy 37.477694 -291.8896)
			(xy 37.433232 -291.910698) (xy 37.385961 -291.92439) (xy 37.337106 -291.930322) (xy 37.287931 -291.928341)
			(xy 37.239712 -291.918497) (xy 37.193696 -291.901045) (xy 37.151075 -291.876438) (xy 37.112954 -291.845313)
			(xy 37.080319 -291.808476) (xy 37.054016 -291.76688) (xy 37.034725 -291.721604) (xy 37.022948 -291.67382)
			(xy 37.018988 -291.624766) (xy 36.68014 -291.624766) (xy 36.679645 -291.649373) (xy 36.67175 -291.69795)
			(xy 36.656166 -291.744631) (xy 36.633295 -291.788208) (xy 36.60373 -291.827552) (xy 36.568237 -291.861644)
			(xy 36.527734 -291.8896) (xy 36.483272 -291.910698) (xy 36.436001 -291.92439) (xy 36.387146 -291.930322)
			(xy 36.337971 -291.928341) (xy 36.289752 -291.918497) (xy 36.243736 -291.901045) (xy 36.201115 -291.876438)
			(xy 36.162994 -291.845313) (xy 36.130359 -291.808476) (xy 36.104056 -291.76688) (xy 36.084765 -291.721604)
			(xy 36.072988 -291.67382) (xy 36.069028 -291.624766) (xy 28.006914 -291.624766) (xy 27.981 -291.663935)
			(xy 27.943783 -291.705472) (xy 27.900915 -291.741147) (xy 27.853309 -291.770201) (xy 27.80198 -291.792013)
			(xy 27.748023 -291.806119) (xy 27.692586 -291.812219) (xy 27.636852 -291.810182) (xy 27.582009 -291.800052)
			(xy 27.529225 -291.782045) (xy 27.479625 -291.756544) (xy 27.434267 -291.724093) (xy 27.394118 -291.685384)
			(xy 27.360032 -291.641241) (xy 27.332736 -291.592606) (xy 27.312813 -291.540515) (xy 27.300687 -291.486078)
			(xy 27.296616 -291.430456) (xy 26.575004 -291.430456) (xy 26.574495 -291.458342) (xy 26.566375 -291.513518)
			(xy 26.550307 -291.566925) (xy 26.526635 -291.617422) (xy 26.495862 -291.663935) (xy 26.458645 -291.705472)
			(xy 26.415777 -291.741147) (xy 26.368171 -291.770201) (xy 26.316842 -291.792013) (xy 26.262885 -291.806119)
			(xy 26.207448 -291.812219) (xy 26.151714 -291.810182) (xy 26.096871 -291.800052) (xy 26.044087 -291.782045)
			(xy 25.994487 -291.756544) (xy 25.949129 -291.724093) (xy 25.90898 -291.685384) (xy 25.874894 -291.641241)
			(xy 25.847598 -291.592606) (xy 25.827675 -291.540515) (xy 25.815549 -291.486078) (xy 25.811478 -291.430456)
			(xy 1.660398 -291.430456) (xy 1.660398 -292.732714) (xy 25.811478 -292.732714) (xy 25.815549 -292.677092)
			(xy 25.827675 -292.622655) (xy 25.847598 -292.570564) (xy 25.874894 -292.521929) (xy 25.90898 -292.477786)
			(xy 25.949129 -292.439077) (xy 25.994487 -292.406626) (xy 26.044087 -292.381125) (xy 26.096871 -292.363118)
			(xy 26.151714 -292.352988) (xy 26.207448 -292.350951) (xy 26.262885 -292.357051) (xy 26.316842 -292.371157)
			(xy 26.368171 -292.392969) (xy 26.415777 -292.422023) (xy 26.458645 -292.457698) (xy 26.495862 -292.499235)
			(xy 26.526635 -292.545748) (xy 26.550307 -292.596245) (xy 26.566375 -292.649652) (xy 26.574495 -292.704828)
			(xy 26.575004 -292.732714) (xy 27.286964 -292.732714) (xy 27.291035 -292.677092) (xy 27.303161 -292.622655)
			(xy 27.323084 -292.570564) (xy 27.35038 -292.521929) (xy 27.384466 -292.477786) (xy 27.424615 -292.439077)
			(xy 27.469973 -292.406626) (xy 27.519573 -292.381125) (xy 27.572357 -292.363118) (xy 27.6272 -292.352988)
			(xy 27.682934 -292.350951) (xy 27.738371 -292.357051) (xy 27.792328 -292.371157) (xy 27.843657 -292.392969)
			(xy 27.891263 -292.422023) (xy 27.934131 -292.457698) (xy 27.971348 -292.499235) (xy 28.002121 -292.545748)
			(xy 28.025793 -292.596245) (xy 28.041861 -292.649652) (xy 28.049981 -292.704828) (xy 28.05049 -292.732714)
			(xy 28.175964 -292.732714) (xy 28.180035 -292.677092) (xy 28.192161 -292.622655) (xy 28.212084 -292.570564)
			(xy 28.23938 -292.521929) (xy 28.273466 -292.477786) (xy 28.313615 -292.439077) (xy 28.358973 -292.406626)
			(xy 28.408573 -292.381125) (xy 28.461357 -292.363118) (xy 28.5162 -292.352988) (xy 28.571934 -292.350951)
			(xy 28.627371 -292.357051) (xy 28.681328 -292.371157) (xy 28.732657 -292.392969) (xy 28.780263 -292.422023)
			(xy 28.823131 -292.457698) (xy 28.860348 -292.499235) (xy 28.891121 -292.545748) (xy 28.914793 -292.596245)
			(xy 28.930861 -292.649652) (xy 28.938981 -292.704828) (xy 28.93949 -292.732714) (xy 28.938981 -292.7606)
			(xy 28.930861 -292.815776) (xy 28.914793 -292.869183) (xy 28.891121 -292.91968) (xy 28.860348 -292.966193)
			(xy 28.823131 -293.00773) (xy 28.780263 -293.043405) (xy 28.732657 -293.072459) (xy 28.681328 -293.094271)
			(xy 28.627371 -293.108377) (xy 28.571934 -293.114477) (xy 28.5162 -293.11244) (xy 28.461357 -293.10231)
			(xy 28.408573 -293.084303) (xy 28.358973 -293.058802) (xy 28.313615 -293.026351) (xy 28.273466 -292.987642)
			(xy 28.23938 -292.943499) (xy 28.212084 -292.894864) (xy 28.192161 -292.842773) (xy 28.180035 -292.788336)
			(xy 28.175964 -292.732714) (xy 28.05049 -292.732714) (xy 28.049981 -292.7606) (xy 28.041861 -292.815776)
			(xy 28.025793 -292.869183) (xy 28.002121 -292.91968) (xy 27.971348 -292.966193) (xy 27.934131 -293.00773)
			(xy 27.891263 -293.043405) (xy 27.843657 -293.072459) (xy 27.792328 -293.094271) (xy 27.738371 -293.108377)
			(xy 27.682934 -293.114477) (xy 27.6272 -293.11244) (xy 27.572357 -293.10231) (xy 27.519573 -293.084303)
			(xy 27.469973 -293.058802) (xy 27.424615 -293.026351) (xy 27.384466 -292.987642) (xy 27.35038 -292.943499)
			(xy 27.323084 -292.894864) (xy 27.303161 -292.842773) (xy 27.291035 -292.788336) (xy 27.286964 -292.732714)
			(xy 26.575004 -292.732714) (xy 26.574495 -292.7606) (xy 26.566375 -292.815776) (xy 26.550307 -292.869183)
			(xy 26.526635 -292.91968) (xy 26.495862 -292.966193) (xy 26.458645 -293.00773) (xy 26.415777 -293.043405)
			(xy 26.368171 -293.072459) (xy 26.316842 -293.094271) (xy 26.262885 -293.108377) (xy 26.207448 -293.114477)
			(xy 26.151714 -293.11244) (xy 26.096871 -293.10231) (xy 26.044087 -293.084303) (xy 25.994487 -293.058802)
			(xy 25.949129 -293.026351) (xy 25.90898 -292.987642) (xy 25.874894 -292.943499) (xy 25.847598 -292.894864)
			(xy 25.827675 -292.842773) (xy 25.815549 -292.788336) (xy 25.811478 -292.732714) (xy 1.660398 -292.732714)
			(xy 1.660398 -293.494714) (xy 31.338012 -293.494714) (xy 31.338555 -293.465332) (xy 31.347584 -293.407265)
			(xy 31.365415 -293.35127) (xy 31.391626 -293.298675) (xy 31.425597 -293.250724) (xy 31.466521 -293.208552)
			(xy 31.48965 -293.190422) (xy 31.499048 -293.183056) (xy 31.509462 -293.162482) (xy 31.510986 -293.058596)
			(xy 31.50108 -293.037514) (xy 31.491936 -293.030148) (xy 31.470088 -293.011942) (xy 31.431546 -292.970124)
			(xy 31.399638 -292.923049) (xy 31.375071 -292.871759) (xy 31.358388 -292.817391) (xy 31.34996 -292.761149)
			(xy 31.349442 -292.732714) (xy 31.349928 -292.705463) (xy 31.357684 -292.651515) (xy 31.373039 -292.59922)
			(xy 31.395681 -292.549643) (xy 31.425147 -292.503793) (xy 31.460838 -292.462602) (xy 31.502029 -292.426911)
			(xy 31.547879 -292.397445) (xy 31.597456 -292.374803) (xy 31.649751 -292.359448) (xy 31.703699 -292.351692)
			(xy 31.758201 -292.351692) (xy 31.812149 -292.359448) (xy 31.864444 -292.374803) (xy 31.914021 -292.397445)
			(xy 31.959871 -292.426911) (xy 32.001062 -292.462602) (xy 32.036753 -292.503793) (xy 32.066219 -292.549643)
			(xy 32.077791 -292.57498) (xy 36.069028 -292.57498) (xy 36.072988 -292.525926) (xy 36.084765 -292.478142)
			(xy 36.104056 -292.432866) (xy 36.130359 -292.39127) (xy 36.162994 -292.354433) (xy 36.201115 -292.323308)
			(xy 36.243736 -292.298701) (xy 36.289752 -292.281249) (xy 36.337971 -292.271405) (xy 36.387146 -292.269424)
			(xy 36.436001 -292.275356) (xy 36.483272 -292.289048) (xy 36.527734 -292.310146) (xy 36.568237 -292.338102)
			(xy 36.60373 -292.372194) (xy 36.633295 -292.411538) (xy 36.656166 -292.455115) (xy 36.67175 -292.501796)
			(xy 36.679645 -292.550373) (xy 36.68014 -292.57498) (xy 37.018988 -292.57498) (xy 37.022948 -292.525926)
			(xy 37.034725 -292.478142) (xy 37.054016 -292.432866) (xy 37.080319 -292.39127) (xy 37.112954 -292.354433)
			(xy 37.151075 -292.323308) (xy 37.193696 -292.298701) (xy 37.239712 -292.281249) (xy 37.287931 -292.271405)
			(xy 37.337106 -292.269424) (xy 37.385961 -292.275356) (xy 37.433232 -292.289048) (xy 37.477694 -292.310146)
			(xy 37.518197 -292.338102) (xy 37.55369 -292.372194) (xy 37.583255 -292.411538) (xy 37.606126 -292.455115)
			(xy 37.62171 -292.501796) (xy 37.629605 -292.550373) (xy 37.6301 -292.57498) (xy 37.969202 -292.57498)
			(xy 37.973162 -292.525926) (xy 37.984939 -292.478142) (xy 38.00423 -292.432866) (xy 38.030533 -292.39127)
			(xy 38.063168 -292.354433) (xy 38.101289 -292.323308) (xy 38.14391 -292.298701) (xy 38.189926 -292.281249)
			(xy 38.238145 -292.271405) (xy 38.28732 -292.269424) (xy 38.336175 -292.275356) (xy 38.383446 -292.289048)
			(xy 38.427908 -292.310146) (xy 38.468411 -292.338102) (xy 38.503904 -292.372194) (xy 38.533469 -292.411538)
			(xy 38.55634 -292.455115) (xy 38.571924 -292.501796) (xy 38.579819 -292.550373) (xy 38.580309 -292.574726)
			(xy 38.919162 -292.574726) (xy 38.923122 -292.525672) (xy 38.934899 -292.477888) (xy 38.95419 -292.432612)
			(xy 38.980493 -292.391016) (xy 39.013128 -292.354179) (xy 39.051249 -292.323054) (xy 39.09387 -292.298447)
			(xy 39.139886 -292.280995) (xy 39.188105 -292.271151) (xy 39.23728 -292.26917) (xy 39.286135 -292.275102)
			(xy 39.333406 -292.288794) (xy 39.377868 -292.309892) (xy 39.418371 -292.337848) (xy 39.453864 -292.37194)
			(xy 39.483429 -292.411284) (xy 39.5063 -292.454861) (xy 39.521884 -292.501542) (xy 39.529779 -292.550119)
			(xy 39.530274 -292.574726) (xy 39.869122 -292.574726) (xy 39.873082 -292.525672) (xy 39.884859 -292.477888)
			(xy 39.90415 -292.432612) (xy 39.930453 -292.391016) (xy 39.963088 -292.354179) (xy 40.001209 -292.323054)
			(xy 40.04383 -292.298447) (xy 40.089846 -292.280995) (xy 40.138065 -292.271151) (xy 40.18724 -292.26917)
			(xy 40.236095 -292.275102) (xy 40.283366 -292.288794) (xy 40.327828 -292.309892) (xy 40.368331 -292.337848)
			(xy 40.403824 -292.37194) (xy 40.433389 -292.411284) (xy 40.45626 -292.454861) (xy 40.471844 -292.501542)
			(xy 40.479739 -292.550119) (xy 40.480234 -292.574726) (xy 40.480229 -292.57498) (xy 40.819082 -292.57498)
			(xy 40.823042 -292.525926) (xy 40.834819 -292.478142) (xy 40.85411 -292.432866) (xy 40.880413 -292.39127)
			(xy 40.913048 -292.354433) (xy 40.951169 -292.323308) (xy 40.99379 -292.298701) (xy 41.039806 -292.281249)
			(xy 41.088025 -292.271405) (xy 41.1372 -292.269424) (xy 41.186055 -292.275356) (xy 41.233326 -292.289048)
			(xy 41.277788 -292.310146) (xy 41.318291 -292.338102) (xy 41.353784 -292.372194) (xy 41.383349 -292.411538)
			(xy 41.40622 -292.455115) (xy 41.421804 -292.501796) (xy 41.429699 -292.550373) (xy 41.430194 -292.57498)
			(xy 41.429699 -292.599587) (xy 41.429367 -292.601629) (xy 41.719236 -292.601629) (xy 41.719236 -292.548331)
			(xy 41.727179 -292.495627) (xy 41.742889 -292.444697) (xy 41.766015 -292.396676) (xy 41.796039 -292.352639)
			(xy 41.832291 -292.313568) (xy 41.873962 -292.280337) (xy 41.92012 -292.253688) (xy 41.969734 -292.234216)
			(xy 42.021696 -292.222356) (xy 42.074846 -292.218373) (xy 42.127996 -292.222356) (xy 42.179958 -292.234216)
			(xy 42.229572 -292.253688) (xy 42.27573 -292.280337) (xy 42.317401 -292.313568) (xy 42.353653 -292.352639)
			(xy 42.383677 -292.396676) (xy 42.406803 -292.444697) (xy 42.422513 -292.495627) (xy 42.430456 -292.548331)
			(xy 42.430954 -292.57498) (xy 42.719002 -292.57498) (xy 42.722962 -292.525926) (xy 42.734739 -292.478142)
			(xy 42.75403 -292.432866) (xy 42.780333 -292.39127) (xy 42.812968 -292.354433) (xy 42.851089 -292.323308)
			(xy 42.89371 -292.298701) (xy 42.939726 -292.281249) (xy 42.987945 -292.271405) (xy 43.03712 -292.269424)
			(xy 43.085975 -292.275356) (xy 43.133246 -292.289048) (xy 43.177708 -292.310146) (xy 43.218211 -292.338102)
			(xy 43.253704 -292.372194) (xy 43.283269 -292.411538) (xy 43.30614 -292.455115) (xy 43.321724 -292.501796)
			(xy 43.329619 -292.550373) (xy 43.330114 -292.57498) (xy 43.668962 -292.57498) (xy 43.672922 -292.525926)
			(xy 43.684699 -292.478142) (xy 43.70399 -292.432866) (xy 43.730293 -292.39127) (xy 43.762928 -292.354433)
			(xy 43.801049 -292.323308) (xy 43.84367 -292.298701) (xy 43.889686 -292.281249) (xy 43.937905 -292.271405)
			(xy 43.98708 -292.269424) (xy 44.035935 -292.275356) (xy 44.083206 -292.289048) (xy 44.127668 -292.310146)
			(xy 44.168171 -292.338102) (xy 44.203664 -292.372194) (xy 44.233229 -292.411538) (xy 44.2561 -292.455115)
			(xy 44.271684 -292.501796) (xy 44.279579 -292.550373) (xy 44.280074 -292.57498) (xy 44.619176 -292.57498)
			(xy 44.623136 -292.525926) (xy 44.634913 -292.478142) (xy 44.654204 -292.432866) (xy 44.680507 -292.39127)
			(xy 44.713142 -292.354433) (xy 44.751263 -292.323308) (xy 44.793884 -292.298701) (xy 44.8399 -292.281249)
			(xy 44.888119 -292.271405) (xy 44.937294 -292.269424) (xy 44.986149 -292.275356) (xy 45.03342 -292.289048)
			(xy 45.077882 -292.310146) (xy 45.118385 -292.338102) (xy 45.153878 -292.372194) (xy 45.183443 -292.411538)
			(xy 45.206314 -292.455115) (xy 45.221898 -292.501796) (xy 45.229793 -292.550373) (xy 45.230288 -292.57498)
			(xy 45.569136 -292.57498) (xy 45.573096 -292.525926) (xy 45.584873 -292.478142) (xy 45.604164 -292.432866)
			(xy 45.630467 -292.39127) (xy 45.663102 -292.354433) (xy 45.701223 -292.323308) (xy 45.743844 -292.298701)
			(xy 45.78986 -292.281249) (xy 45.838079 -292.271405) (xy 45.887254 -292.269424) (xy 45.936109 -292.275356)
			(xy 45.98338 -292.289048) (xy 46.027842 -292.310146) (xy 46.068345 -292.338102) (xy 46.103838 -292.372194)
			(xy 46.133403 -292.411538) (xy 46.156274 -292.455115) (xy 46.171858 -292.501796) (xy 46.179753 -292.550373)
			(xy 46.180248 -292.57498) (xy 46.519096 -292.57498) (xy 46.523056 -292.525926) (xy 46.534833 -292.478142)
			(xy 46.554124 -292.432866) (xy 46.580427 -292.39127) (xy 46.613062 -292.354433) (xy 46.651183 -292.323308)
			(xy 46.693804 -292.298701) (xy 46.73982 -292.281249) (xy 46.788039 -292.271405) (xy 46.837214 -292.269424)
			(xy 46.886069 -292.275356) (xy 46.93334 -292.289048) (xy 46.977802 -292.310146) (xy 47.018305 -292.338102)
			(xy 47.053798 -292.372194) (xy 47.083363 -292.411538) (xy 47.106234 -292.455115) (xy 47.121818 -292.501796)
			(xy 47.129713 -292.550373) (xy 47.130208 -292.57498) (xy 47.469056 -292.57498) (xy 47.473016 -292.525926)
			(xy 47.484793 -292.478142) (xy 47.504084 -292.432866) (xy 47.530387 -292.39127) (xy 47.563022 -292.354433)
			(xy 47.601143 -292.323308) (xy 47.643764 -292.298701) (xy 47.68978 -292.281249) (xy 47.737999 -292.271405)
			(xy 47.787174 -292.269424) (xy 47.836029 -292.275356) (xy 47.8833 -292.289048) (xy 47.927762 -292.310146)
			(xy 47.968265 -292.338102) (xy 48.003758 -292.372194) (xy 48.033323 -292.411538) (xy 48.056194 -292.455115)
			(xy 48.071778 -292.501796) (xy 48.079673 -292.550373) (xy 48.080163 -292.574726) (xy 48.419016 -292.574726)
			(xy 48.422976 -292.525672) (xy 48.434753 -292.477888) (xy 48.454044 -292.432612) (xy 48.480347 -292.391016)
			(xy 48.512982 -292.354179) (xy 48.551103 -292.323054) (xy 48.593724 -292.298447) (xy 48.63974 -292.280995)
			(xy 48.687959 -292.271151) (xy 48.737134 -292.26917) (xy 48.785989 -292.275102) (xy 48.83326 -292.288794)
			(xy 48.877722 -292.309892) (xy 48.918225 -292.337848) (xy 48.953718 -292.37194) (xy 48.983283 -292.411284)
			(xy 49.006154 -292.454861) (xy 49.021738 -292.501542) (xy 49.029633 -292.550119) (xy 49.030128 -292.574726)
			(xy 49.368976 -292.574726) (xy 49.372936 -292.525672) (xy 49.384713 -292.477888) (xy 49.404004 -292.432612)
			(xy 49.430307 -292.391016) (xy 49.462942 -292.354179) (xy 49.501063 -292.323054) (xy 49.543684 -292.298447)
			(xy 49.5897 -292.280995) (xy 49.637919 -292.271151) (xy 49.687094 -292.26917) (xy 49.735949 -292.275102)
			(xy 49.78322 -292.288794) (xy 49.827682 -292.309892) (xy 49.868185 -292.337848) (xy 49.903678 -292.37194)
			(xy 49.933243 -292.411284) (xy 49.956114 -292.454861) (xy 49.971698 -292.501542) (xy 49.979593 -292.550119)
			(xy 49.980088 -292.574726) (xy 49.980083 -292.57498) (xy 50.31919 -292.57498) (xy 50.32315 -292.525926)
			(xy 50.334927 -292.478142) (xy 50.354218 -292.432866) (xy 50.380521 -292.39127) (xy 50.413156 -292.354433)
			(xy 50.451277 -292.323308) (xy 50.493898 -292.298701) (xy 50.539914 -292.281249) (xy 50.588133 -292.271405)
			(xy 50.637308 -292.269424) (xy 50.686163 -292.275356) (xy 50.733434 -292.289048) (xy 50.777896 -292.310146)
			(xy 50.818399 -292.338102) (xy 50.853892 -292.372194) (xy 50.883457 -292.411538) (xy 50.906328 -292.455115)
			(xy 50.921912 -292.501796) (xy 50.929807 -292.550373) (xy 50.930302 -292.57498) (xy 51.26915 -292.57498)
			(xy 51.27311 -292.525926) (xy 51.284887 -292.478142) (xy 51.304178 -292.432866) (xy 51.330481 -292.39127)
			(xy 51.363116 -292.354433) (xy 51.401237 -292.323308) (xy 51.443858 -292.298701) (xy 51.489874 -292.281249)
			(xy 51.538093 -292.271405) (xy 51.587268 -292.269424) (xy 51.636123 -292.275356) (xy 51.683394 -292.289048)
			(xy 51.727856 -292.310146) (xy 51.768359 -292.338102) (xy 51.803852 -292.372194) (xy 51.833417 -292.411538)
			(xy 51.856288 -292.455115) (xy 51.871872 -292.501796) (xy 51.879767 -292.550373) (xy 51.880262 -292.57498)
			(xy 52.21911 -292.57498) (xy 52.22307 -292.525926) (xy 52.234847 -292.478142) (xy 52.254138 -292.432866)
			(xy 52.280441 -292.39127) (xy 52.313076 -292.354433) (xy 52.351197 -292.323308) (xy 52.393818 -292.298701)
			(xy 52.439834 -292.281249) (xy 52.488053 -292.271405) (xy 52.537228 -292.269424) (xy 52.586083 -292.275356)
			(xy 52.633354 -292.289048) (xy 52.677816 -292.310146) (xy 52.718319 -292.338102) (xy 52.753812 -292.372194)
			(xy 52.783377 -292.411538) (xy 52.806248 -292.455115) (xy 52.821832 -292.501796) (xy 52.829727 -292.550373)
			(xy 52.830222 -292.57498) (xy 53.16907 -292.57498) (xy 53.17303 -292.525926) (xy 53.184807 -292.478142)
			(xy 53.204098 -292.432866) (xy 53.230401 -292.39127) (xy 53.263036 -292.354433) (xy 53.301157 -292.323308)
			(xy 53.343778 -292.298701) (xy 53.389794 -292.281249) (xy 53.438013 -292.271405) (xy 53.487188 -292.269424)
			(xy 53.536043 -292.275356) (xy 53.583314 -292.289048) (xy 53.627776 -292.310146) (xy 53.668279 -292.338102)
			(xy 53.703772 -292.372194) (xy 53.733337 -292.411538) (xy 53.756208 -292.455115) (xy 53.771792 -292.501796)
			(xy 53.779687 -292.550373) (xy 53.780182 -292.57498) (xy 54.11903 -292.57498) (xy 54.12299 -292.525926)
			(xy 54.134767 -292.478142) (xy 54.154058 -292.432866) (xy 54.180361 -292.39127) (xy 54.212996 -292.354433)
			(xy 54.251117 -292.323308) (xy 54.293738 -292.298701) (xy 54.339754 -292.281249) (xy 54.387973 -292.271405)
			(xy 54.437148 -292.269424) (xy 54.486003 -292.275356) (xy 54.533274 -292.289048) (xy 54.577736 -292.310146)
			(xy 54.618239 -292.338102) (xy 54.653732 -292.372194) (xy 54.683297 -292.411538) (xy 54.706168 -292.455115)
			(xy 54.721752 -292.501796) (xy 54.729647 -292.550373) (xy 54.730142 -292.57498) (xy 55.06899 -292.57498)
			(xy 55.07295 -292.525926) (xy 55.084727 -292.478142) (xy 55.104018 -292.432866) (xy 55.130321 -292.39127)
			(xy 55.162956 -292.354433) (xy 55.201077 -292.323308) (xy 55.243698 -292.298701) (xy 55.289714 -292.281249)
			(xy 55.337933 -292.271405) (xy 55.387108 -292.269424) (xy 55.435963 -292.275356) (xy 55.483234 -292.289048)
			(xy 55.527696 -292.310146) (xy 55.568199 -292.338102) (xy 55.603692 -292.372194) (xy 55.633257 -292.411538)
			(xy 55.656128 -292.455115) (xy 55.671712 -292.501796) (xy 55.679607 -292.550373) (xy 55.680102 -292.57498)
			(xy 56.019204 -292.57498) (xy 56.023164 -292.525926) (xy 56.034941 -292.478142) (xy 56.054232 -292.432866)
			(xy 56.080535 -292.39127) (xy 56.11317 -292.354433) (xy 56.151291 -292.323308) (xy 56.193912 -292.298701)
			(xy 56.239928 -292.281249) (xy 56.288147 -292.271405) (xy 56.337322 -292.269424) (xy 56.386177 -292.275356)
			(xy 56.433448 -292.289048) (xy 56.47791 -292.310146) (xy 56.518413 -292.338102) (xy 56.553906 -292.372194)
			(xy 56.583471 -292.411538) (xy 56.606342 -292.455115) (xy 56.621926 -292.501796) (xy 56.629821 -292.550373)
			(xy 56.630316 -292.57498) (xy 56.969164 -292.57498) (xy 56.973124 -292.525926) (xy 56.984901 -292.478142)
			(xy 57.004192 -292.432866) (xy 57.030495 -292.39127) (xy 57.06313 -292.354433) (xy 57.101251 -292.323308)
			(xy 57.143872 -292.298701) (xy 57.189888 -292.281249) (xy 57.238107 -292.271405) (xy 57.287282 -292.269424)
			(xy 57.336137 -292.275356) (xy 57.383408 -292.289048) (xy 57.42787 -292.310146) (xy 57.468373 -292.338102)
			(xy 57.503866 -292.372194) (xy 57.533431 -292.411538) (xy 57.556302 -292.455115) (xy 57.571886 -292.501796)
			(xy 57.579781 -292.550373) (xy 57.580276 -292.57498) (xy 57.919124 -292.57498) (xy 57.923084 -292.525926)
			(xy 57.934861 -292.478142) (xy 57.954152 -292.432866) (xy 57.980455 -292.39127) (xy 58.01309 -292.354433)
			(xy 58.051211 -292.323308) (xy 58.093832 -292.298701) (xy 58.139848 -292.281249) (xy 58.188067 -292.271405)
			(xy 58.237242 -292.269424) (xy 58.286097 -292.275356) (xy 58.333368 -292.289048) (xy 58.37783 -292.310146)
			(xy 58.418333 -292.338102) (xy 58.453826 -292.372194) (xy 58.483391 -292.411538) (xy 58.506262 -292.455115)
			(xy 58.521846 -292.501796) (xy 58.529741 -292.550373) (xy 58.530231 -292.574726) (xy 59.819044 -292.574726)
			(xy 59.823004 -292.525672) (xy 59.834781 -292.477888) (xy 59.854072 -292.432612) (xy 59.880375 -292.391016)
			(xy 59.91301 -292.354179) (xy 59.951131 -292.323054) (xy 59.993752 -292.298447) (xy 60.039768 -292.280995)
			(xy 60.087987 -292.271151) (xy 60.137162 -292.26917) (xy 60.186017 -292.275102) (xy 60.233288 -292.288794)
			(xy 60.27775 -292.309892) (xy 60.318253 -292.337848) (xy 60.353746 -292.37194) (xy 60.383311 -292.411284)
			(xy 60.406182 -292.454861) (xy 60.421766 -292.501542) (xy 60.429661 -292.550119) (xy 60.430156 -292.574726)
			(xy 60.769004 -292.574726) (xy 60.772964 -292.525672) (xy 60.784741 -292.477888) (xy 60.804032 -292.432612)
			(xy 60.830335 -292.391016) (xy 60.86297 -292.354179) (xy 60.901091 -292.323054) (xy 60.943712 -292.298447)
			(xy 60.989728 -292.280995) (xy 61.037947 -292.271151) (xy 61.087122 -292.26917) (xy 61.135977 -292.275102)
			(xy 61.183248 -292.288794) (xy 61.22771 -292.309892) (xy 61.268213 -292.337848) (xy 61.303706 -292.37194)
			(xy 61.333271 -292.411284) (xy 61.356142 -292.454861) (xy 61.371726 -292.501542) (xy 61.379621 -292.550119)
			(xy 61.380116 -292.574726) (xy 61.718964 -292.574726) (xy 61.722924 -292.525672) (xy 61.734701 -292.477888)
			(xy 61.753992 -292.432612) (xy 61.780295 -292.391016) (xy 61.81293 -292.354179) (xy 61.851051 -292.323054)
			(xy 61.893672 -292.298447) (xy 61.939688 -292.280995) (xy 61.987907 -292.271151) (xy 62.037082 -292.26917)
			(xy 62.085937 -292.275102) (xy 62.133208 -292.288794) (xy 62.17767 -292.309892) (xy 62.218173 -292.337848)
			(xy 62.253666 -292.37194) (xy 62.283231 -292.411284) (xy 62.306102 -292.454861) (xy 62.321686 -292.501542)
			(xy 62.329581 -292.550119) (xy 62.330076 -292.574726) (xy 62.669178 -292.574726) (xy 62.673138 -292.525672)
			(xy 62.684915 -292.477888) (xy 62.704206 -292.432612) (xy 62.730509 -292.391016) (xy 62.763144 -292.354179)
			(xy 62.801265 -292.323054) (xy 62.843886 -292.298447) (xy 62.889902 -292.280995) (xy 62.938121 -292.271151)
			(xy 62.987296 -292.26917) (xy 63.036151 -292.275102) (xy 63.083422 -292.288794) (xy 63.127884 -292.309892)
			(xy 63.168387 -292.337848) (xy 63.20388 -292.37194) (xy 63.233445 -292.411284) (xy 63.256316 -292.454861)
			(xy 63.2719 -292.501542) (xy 63.279795 -292.550119) (xy 63.28029 -292.574726) (xy 63.619138 -292.574726)
			(xy 63.623098 -292.525672) (xy 63.634875 -292.477888) (xy 63.654166 -292.432612) (xy 63.680469 -292.391016)
			(xy 63.713104 -292.354179) (xy 63.751225 -292.323054) (xy 63.793846 -292.298447) (xy 63.839862 -292.280995)
			(xy 63.888081 -292.271151) (xy 63.937256 -292.26917) (xy 63.986111 -292.275102) (xy 64.033382 -292.288794)
			(xy 64.077844 -292.309892) (xy 64.118347 -292.337848) (xy 64.15384 -292.37194) (xy 64.183405 -292.411284)
			(xy 64.206276 -292.454861) (xy 64.22186 -292.501542) (xy 64.229755 -292.550119) (xy 64.23025 -292.574726)
			(xy 64.569098 -292.574726) (xy 64.573058 -292.525672) (xy 64.584835 -292.477888) (xy 64.604126 -292.432612)
			(xy 64.630429 -292.391016) (xy 64.663064 -292.354179) (xy 64.701185 -292.323054) (xy 64.743806 -292.298447)
			(xy 64.789822 -292.280995) (xy 64.838041 -292.271151) (xy 64.887216 -292.26917) (xy 64.936071 -292.275102)
			(xy 64.983342 -292.288794) (xy 65.027804 -292.309892) (xy 65.068307 -292.337848) (xy 65.1038 -292.37194)
			(xy 65.133365 -292.411284) (xy 65.156236 -292.454861) (xy 65.17182 -292.501542) (xy 65.179715 -292.550119)
			(xy 65.18021 -292.574726) (xy 65.519058 -292.574726) (xy 65.523018 -292.525672) (xy 65.534795 -292.477888)
			(xy 65.554086 -292.432612) (xy 65.580389 -292.391016) (xy 65.613024 -292.354179) (xy 65.651145 -292.323054)
			(xy 65.693766 -292.298447) (xy 65.739782 -292.280995) (xy 65.788001 -292.271151) (xy 65.837176 -292.26917)
			(xy 65.886031 -292.275102) (xy 65.933302 -292.288794) (xy 65.977764 -292.309892) (xy 66.018267 -292.337848)
			(xy 66.05376 -292.37194) (xy 66.083325 -292.411284) (xy 66.106196 -292.454861) (xy 66.12178 -292.501542)
			(xy 66.129675 -292.550119) (xy 66.13017 -292.574726) (xy 66.469018 -292.574726) (xy 66.472978 -292.525672)
			(xy 66.484755 -292.477888) (xy 66.504046 -292.432612) (xy 66.530349 -292.391016) (xy 66.562984 -292.354179)
			(xy 66.601105 -292.323054) (xy 66.643726 -292.298447) (xy 66.689742 -292.280995) (xy 66.737961 -292.271151)
			(xy 66.787136 -292.26917) (xy 66.835991 -292.275102) (xy 66.883262 -292.288794) (xy 66.927724 -292.309892)
			(xy 66.968227 -292.337848) (xy 67.00372 -292.37194) (xy 67.033285 -292.411284) (xy 67.056156 -292.454861)
			(xy 67.07174 -292.501542) (xy 67.079635 -292.550119) (xy 67.08013 -292.574726) (xy 67.418978 -292.574726)
			(xy 67.422938 -292.525672) (xy 67.434715 -292.477888) (xy 67.454006 -292.432612) (xy 67.480309 -292.391016)
			(xy 67.512944 -292.354179) (xy 67.551065 -292.323054) (xy 67.593686 -292.298447) (xy 67.639702 -292.280995)
			(xy 67.687921 -292.271151) (xy 67.737096 -292.26917) (xy 67.785951 -292.275102) (xy 67.833222 -292.288794)
			(xy 67.877684 -292.309892) (xy 67.918187 -292.337848) (xy 67.95368 -292.37194) (xy 67.983245 -292.411284)
			(xy 68.006116 -292.454861) (xy 68.0217 -292.501542) (xy 68.029595 -292.550119) (xy 68.03009 -292.574726)
			(xy 68.368938 -292.574726) (xy 68.372898 -292.525672) (xy 68.384675 -292.477888) (xy 68.403966 -292.432612)
			(xy 68.430269 -292.391016) (xy 68.462904 -292.354179) (xy 68.501025 -292.323054) (xy 68.543646 -292.298447)
			(xy 68.589662 -292.280995) (xy 68.637881 -292.271151) (xy 68.687056 -292.26917) (xy 68.735911 -292.275102)
			(xy 68.783182 -292.288794) (xy 68.827644 -292.309892) (xy 68.868147 -292.337848) (xy 68.90364 -292.37194)
			(xy 68.933205 -292.411284) (xy 68.956076 -292.454861) (xy 68.97166 -292.501542) (xy 68.979555 -292.550119)
			(xy 68.98005 -292.574726) (xy 69.319152 -292.574726) (xy 69.323112 -292.525672) (xy 69.334889 -292.477888)
			(xy 69.35418 -292.432612) (xy 69.380483 -292.391016) (xy 69.413118 -292.354179) (xy 69.451239 -292.323054)
			(xy 69.49386 -292.298447) (xy 69.539876 -292.280995) (xy 69.588095 -292.271151) (xy 69.63727 -292.26917)
			(xy 69.686125 -292.275102) (xy 69.733396 -292.288794) (xy 69.777858 -292.309892) (xy 69.818361 -292.337848)
			(xy 69.853854 -292.37194) (xy 69.883419 -292.411284) (xy 69.90629 -292.454861) (xy 69.921874 -292.501542)
			(xy 69.929769 -292.550119) (xy 69.930264 -292.574726) (xy 69.930259 -292.57498) (xy 70.269112 -292.57498)
			(xy 70.273072 -292.525926) (xy 70.284849 -292.478142) (xy 70.30414 -292.432866) (xy 70.330443 -292.39127)
			(xy 70.363078 -292.354433) (xy 70.401199 -292.323308) (xy 70.44382 -292.298701) (xy 70.489836 -292.281249)
			(xy 70.538055 -292.271405) (xy 70.58723 -292.269424) (xy 70.636085 -292.275356) (xy 70.683356 -292.289048)
			(xy 70.727818 -292.310146) (xy 70.768321 -292.338102) (xy 70.803814 -292.372194) (xy 70.833379 -292.411538)
			(xy 70.85625 -292.455115) (xy 70.871834 -292.501796) (xy 70.879729 -292.550373) (xy 70.880219 -292.574726)
			(xy 71.219072 -292.574726) (xy 71.223032 -292.525672) (xy 71.234809 -292.477888) (xy 71.2541 -292.432612)
			(xy 71.280403 -292.391016) (xy 71.313038 -292.354179) (xy 71.351159 -292.323054) (xy 71.39378 -292.298447)
			(xy 71.439796 -292.280995) (xy 71.488015 -292.271151) (xy 71.53719 -292.26917) (xy 71.586045 -292.275102)
			(xy 71.633316 -292.288794) (xy 71.677778 -292.309892) (xy 71.718281 -292.337848) (xy 71.753774 -292.37194)
			(xy 71.783339 -292.411284) (xy 71.80621 -292.454861) (xy 71.821794 -292.501542) (xy 71.829689 -292.550119)
			(xy 71.830184 -292.574726) (xy 72.169032 -292.574726) (xy 72.172992 -292.525672) (xy 72.184769 -292.477888)
			(xy 72.20406 -292.432612) (xy 72.230363 -292.391016) (xy 72.262998 -292.354179) (xy 72.301119 -292.323054)
			(xy 72.34374 -292.298447) (xy 72.389756 -292.280995) (xy 72.437975 -292.271151) (xy 72.48715 -292.26917)
			(xy 72.536005 -292.275102) (xy 72.583276 -292.288794) (xy 72.627738 -292.309892) (xy 72.668241 -292.337848)
			(xy 72.703734 -292.37194) (xy 72.733299 -292.411284) (xy 72.75617 -292.454861) (xy 72.771754 -292.501542)
			(xy 72.779649 -292.550119) (xy 72.780144 -292.574726) (xy 73.118992 -292.574726) (xy 73.122952 -292.525672)
			(xy 73.134729 -292.477888) (xy 73.15402 -292.432612) (xy 73.180323 -292.391016) (xy 73.212958 -292.354179)
			(xy 73.251079 -292.323054) (xy 73.2937 -292.298447) (xy 73.339716 -292.280995) (xy 73.387935 -292.271151)
			(xy 73.43711 -292.26917) (xy 73.485965 -292.275102) (xy 73.533236 -292.288794) (xy 73.577698 -292.309892)
			(xy 73.618201 -292.337848) (xy 73.653694 -292.37194) (xy 73.683259 -292.411284) (xy 73.70613 -292.454861)
			(xy 73.721714 -292.501542) (xy 73.729609 -292.550119) (xy 73.730104 -292.574726) (xy 74.068952 -292.574726)
			(xy 74.072912 -292.525672) (xy 74.084689 -292.477888) (xy 74.10398 -292.432612) (xy 74.130283 -292.391016)
			(xy 74.162918 -292.354179) (xy 74.201039 -292.323054) (xy 74.24366 -292.298447) (xy 74.289676 -292.280995)
			(xy 74.337895 -292.271151) (xy 74.38707 -292.26917) (xy 74.435925 -292.275102) (xy 74.483196 -292.288794)
			(xy 74.527658 -292.309892) (xy 74.568161 -292.337848) (xy 74.603654 -292.37194) (xy 74.633219 -292.411284)
			(xy 74.65609 -292.454861) (xy 74.671674 -292.501542) (xy 74.679569 -292.550119) (xy 74.680064 -292.574726)
			(xy 75.019166 -292.574726) (xy 75.023126 -292.525672) (xy 75.034903 -292.477888) (xy 75.054194 -292.432612)
			(xy 75.080497 -292.391016) (xy 75.113132 -292.354179) (xy 75.151253 -292.323054) (xy 75.193874 -292.298447)
			(xy 75.23989 -292.280995) (xy 75.288109 -292.271151) (xy 75.337284 -292.26917) (xy 75.386139 -292.275102)
			(xy 75.43341 -292.288794) (xy 75.477872 -292.309892) (xy 75.518375 -292.337848) (xy 75.553868 -292.37194)
			(xy 75.583433 -292.411284) (xy 75.606304 -292.454861) (xy 75.621888 -292.501542) (xy 75.629783 -292.550119)
			(xy 75.630278 -292.574726) (xy 75.969126 -292.574726) (xy 75.973086 -292.525672) (xy 75.984863 -292.477888)
			(xy 76.004154 -292.432612) (xy 76.030457 -292.391016) (xy 76.063092 -292.354179) (xy 76.101213 -292.323054)
			(xy 76.143834 -292.298447) (xy 76.18985 -292.280995) (xy 76.238069 -292.271151) (xy 76.287244 -292.26917)
			(xy 76.336099 -292.275102) (xy 76.38337 -292.288794) (xy 76.427832 -292.309892) (xy 76.468335 -292.337848)
			(xy 76.503828 -292.37194) (xy 76.533393 -292.411284) (xy 76.556264 -292.454861) (xy 76.571848 -292.501542)
			(xy 76.579743 -292.550119) (xy 76.580238 -292.574726) (xy 76.919086 -292.574726) (xy 76.923046 -292.525672)
			(xy 76.934823 -292.477888) (xy 76.954114 -292.432612) (xy 76.980417 -292.391016) (xy 77.013052 -292.354179)
			(xy 77.051173 -292.323054) (xy 77.093794 -292.298447) (xy 77.13981 -292.280995) (xy 77.188029 -292.271151)
			(xy 77.237204 -292.26917) (xy 77.286059 -292.275102) (xy 77.33333 -292.288794) (xy 77.377792 -292.309892)
			(xy 77.418295 -292.337848) (xy 77.453788 -292.37194) (xy 77.483353 -292.411284) (xy 77.506224 -292.454861)
			(xy 77.521808 -292.501542) (xy 77.529703 -292.550119) (xy 77.530198 -292.574726) (xy 77.869046 -292.574726)
			(xy 77.873006 -292.525672) (xy 77.884783 -292.477888) (xy 77.904074 -292.432612) (xy 77.930377 -292.391016)
			(xy 77.963012 -292.354179) (xy 78.001133 -292.323054) (xy 78.043754 -292.298447) (xy 78.08977 -292.280995)
			(xy 78.137989 -292.271151) (xy 78.187164 -292.26917) (xy 78.236019 -292.275102) (xy 78.28329 -292.288794)
			(xy 78.327752 -292.309892) (xy 78.368255 -292.337848) (xy 78.403748 -292.37194) (xy 78.433313 -292.411284)
			(xy 78.456184 -292.454861) (xy 78.471768 -292.501542) (xy 78.479663 -292.550119) (xy 78.480158 -292.574726)
			(xy 78.479663 -292.599333) (xy 78.471768 -292.64791) (xy 78.456184 -292.694591) (xy 78.433313 -292.738168)
			(xy 78.403748 -292.777512) (xy 78.368255 -292.811604) (xy 78.327752 -292.83956) (xy 78.28329 -292.860658)
			(xy 78.236019 -292.87435) (xy 78.187164 -292.880282) (xy 78.137989 -292.878301) (xy 78.08977 -292.868457)
			(xy 78.043754 -292.851005) (xy 78.001133 -292.826398) (xy 77.963012 -292.795273) (xy 77.930377 -292.758436)
			(xy 77.904074 -292.71684) (xy 77.884783 -292.671564) (xy 77.873006 -292.62378) (xy 77.869046 -292.574726)
			(xy 77.530198 -292.574726) (xy 77.529703 -292.599333) (xy 77.521808 -292.64791) (xy 77.506224 -292.694591)
			(xy 77.483353 -292.738168) (xy 77.453788 -292.777512) (xy 77.418295 -292.811604) (xy 77.377792 -292.83956)
			(xy 77.33333 -292.860658) (xy 77.286059 -292.87435) (xy 77.237204 -292.880282) (xy 77.188029 -292.878301)
			(xy 77.13981 -292.868457) (xy 77.093794 -292.851005) (xy 77.051173 -292.826398) (xy 77.013052 -292.795273)
			(xy 76.980417 -292.758436) (xy 76.954114 -292.71684) (xy 76.934823 -292.671564) (xy 76.923046 -292.62378)
			(xy 76.919086 -292.574726) (xy 76.580238 -292.574726) (xy 76.579743 -292.599333) (xy 76.571848 -292.64791)
			(xy 76.556264 -292.694591) (xy 76.533393 -292.738168) (xy 76.503828 -292.777512) (xy 76.468335 -292.811604)
			(xy 76.427832 -292.83956) (xy 76.38337 -292.860658) (xy 76.336099 -292.87435) (xy 76.287244 -292.880282)
			(xy 76.238069 -292.878301) (xy 76.18985 -292.868457) (xy 76.143834 -292.851005) (xy 76.101213 -292.826398)
			(xy 76.063092 -292.795273) (xy 76.030457 -292.758436) (xy 76.004154 -292.71684) (xy 75.984863 -292.671564)
			(xy 75.973086 -292.62378) (xy 75.969126 -292.574726) (xy 75.630278 -292.574726) (xy 75.629783 -292.599333)
			(xy 75.621888 -292.64791) (xy 75.606304 -292.694591) (xy 75.583433 -292.738168) (xy 75.553868 -292.777512)
			(xy 75.518375 -292.811604) (xy 75.477872 -292.83956) (xy 75.43341 -292.860658) (xy 75.386139 -292.87435)
			(xy 75.337284 -292.880282) (xy 75.288109 -292.878301) (xy 75.23989 -292.868457) (xy 75.193874 -292.851005)
			(xy 75.151253 -292.826398) (xy 75.113132 -292.795273) (xy 75.080497 -292.758436) (xy 75.054194 -292.71684)
			(xy 75.034903 -292.671564) (xy 75.023126 -292.62378) (xy 75.019166 -292.574726) (xy 74.680064 -292.574726)
			(xy 74.679569 -292.599333) (xy 74.671674 -292.64791) (xy 74.65609 -292.694591) (xy 74.633219 -292.738168)
			(xy 74.603654 -292.777512) (xy 74.568161 -292.811604) (xy 74.527658 -292.83956) (xy 74.483196 -292.860658)
			(xy 74.435925 -292.87435) (xy 74.38707 -292.880282) (xy 74.337895 -292.878301) (xy 74.289676 -292.868457)
			(xy 74.24366 -292.851005) (xy 74.201039 -292.826398) (xy 74.162918 -292.795273) (xy 74.130283 -292.758436)
			(xy 74.10398 -292.71684) (xy 74.084689 -292.671564) (xy 74.072912 -292.62378) (xy 74.068952 -292.574726)
			(xy 73.730104 -292.574726) (xy 73.729609 -292.599333) (xy 73.721714 -292.64791) (xy 73.70613 -292.694591)
			(xy 73.683259 -292.738168) (xy 73.653694 -292.777512) (xy 73.618201 -292.811604) (xy 73.577698 -292.83956)
			(xy 73.533236 -292.860658) (xy 73.485965 -292.87435) (xy 73.43711 -292.880282) (xy 73.387935 -292.878301)
			(xy 73.339716 -292.868457) (xy 73.2937 -292.851005) (xy 73.251079 -292.826398) (xy 73.212958 -292.795273)
			(xy 73.180323 -292.758436) (xy 73.15402 -292.71684) (xy 73.134729 -292.671564) (xy 73.122952 -292.62378)
			(xy 73.118992 -292.574726) (xy 72.780144 -292.574726) (xy 72.779649 -292.599333) (xy 72.771754 -292.64791)
			(xy 72.75617 -292.694591) (xy 72.733299 -292.738168) (xy 72.703734 -292.777512) (xy 72.668241 -292.811604)
			(xy 72.627738 -292.83956) (xy 72.583276 -292.860658) (xy 72.536005 -292.87435) (xy 72.48715 -292.880282)
			(xy 72.437975 -292.878301) (xy 72.389756 -292.868457) (xy 72.34374 -292.851005) (xy 72.301119 -292.826398)
			(xy 72.262998 -292.795273) (xy 72.230363 -292.758436) (xy 72.20406 -292.71684) (xy 72.184769 -292.671564)
			(xy 72.172992 -292.62378) (xy 72.169032 -292.574726) (xy 71.830184 -292.574726) (xy 71.829689 -292.599333)
			(xy 71.821794 -292.64791) (xy 71.80621 -292.694591) (xy 71.783339 -292.738168) (xy 71.753774 -292.777512)
			(xy 71.718281 -292.811604) (xy 71.677778 -292.83956) (xy 71.633316 -292.860658) (xy 71.586045 -292.87435)
			(xy 71.53719 -292.880282) (xy 71.488015 -292.878301) (xy 71.439796 -292.868457) (xy 71.39378 -292.851005)
			(xy 71.351159 -292.826398) (xy 71.313038 -292.795273) (xy 71.280403 -292.758436) (xy 71.2541 -292.71684)
			(xy 71.234809 -292.671564) (xy 71.223032 -292.62378) (xy 71.219072 -292.574726) (xy 70.880219 -292.574726)
			(xy 70.880224 -292.57498) (xy 70.879729 -292.599587) (xy 70.871834 -292.648164) (xy 70.85625 -292.694845)
			(xy 70.833379 -292.738422) (xy 70.803814 -292.777766) (xy 70.768321 -292.811858) (xy 70.727818 -292.839814)
			(xy 70.683356 -292.860912) (xy 70.636085 -292.874604) (xy 70.58723 -292.880536) (xy 70.538055 -292.878555)
			(xy 70.489836 -292.868711) (xy 70.44382 -292.851259) (xy 70.401199 -292.826652) (xy 70.363078 -292.795527)
			(xy 70.330443 -292.75869) (xy 70.30414 -292.717094) (xy 70.284849 -292.671818) (xy 70.273072 -292.624034)
			(xy 70.269112 -292.57498) (xy 69.930259 -292.57498) (xy 69.929769 -292.599333) (xy 69.921874 -292.64791)
			(xy 69.90629 -292.694591) (xy 69.883419 -292.738168) (xy 69.853854 -292.777512) (xy 69.818361 -292.811604)
			(xy 69.777858 -292.83956) (xy 69.733396 -292.860658) (xy 69.686125 -292.87435) (xy 69.63727 -292.880282)
			(xy 69.588095 -292.878301) (xy 69.539876 -292.868457) (xy 69.49386 -292.851005) (xy 69.451239 -292.826398)
			(xy 69.413118 -292.795273) (xy 69.380483 -292.758436) (xy 69.35418 -292.71684) (xy 69.334889 -292.671564)
			(xy 69.323112 -292.62378) (xy 69.319152 -292.574726) (xy 68.98005 -292.574726) (xy 68.979555 -292.599333)
			(xy 68.97166 -292.64791) (xy 68.956076 -292.694591) (xy 68.933205 -292.738168) (xy 68.90364 -292.777512)
			(xy 68.868147 -292.811604) (xy 68.827644 -292.83956) (xy 68.783182 -292.860658) (xy 68.735911 -292.87435)
			(xy 68.687056 -292.880282) (xy 68.637881 -292.878301) (xy 68.589662 -292.868457) (xy 68.543646 -292.851005)
			(xy 68.501025 -292.826398) (xy 68.462904 -292.795273) (xy 68.430269 -292.758436) (xy 68.403966 -292.71684)
			(xy 68.384675 -292.671564) (xy 68.372898 -292.62378) (xy 68.368938 -292.574726) (xy 68.03009 -292.574726)
			(xy 68.029595 -292.599333) (xy 68.0217 -292.64791) (xy 68.006116 -292.694591) (xy 67.983245 -292.738168)
			(xy 67.95368 -292.777512) (xy 67.918187 -292.811604) (xy 67.877684 -292.83956) (xy 67.833222 -292.860658)
			(xy 67.785951 -292.87435) (xy 67.737096 -292.880282) (xy 67.687921 -292.878301) (xy 67.639702 -292.868457)
			(xy 67.593686 -292.851005) (xy 67.551065 -292.826398) (xy 67.512944 -292.795273) (xy 67.480309 -292.758436)
			(xy 67.454006 -292.71684) (xy 67.434715 -292.671564) (xy 67.422938 -292.62378) (xy 67.418978 -292.574726)
			(xy 67.08013 -292.574726) (xy 67.079635 -292.599333) (xy 67.07174 -292.64791) (xy 67.056156 -292.694591)
			(xy 67.033285 -292.738168) (xy 67.00372 -292.777512) (xy 66.968227 -292.811604) (xy 66.927724 -292.83956)
			(xy 66.883262 -292.860658) (xy 66.835991 -292.87435) (xy 66.787136 -292.880282) (xy 66.737961 -292.878301)
			(xy 66.689742 -292.868457) (xy 66.643726 -292.851005) (xy 66.601105 -292.826398) (xy 66.562984 -292.795273)
			(xy 66.530349 -292.758436) (xy 66.504046 -292.71684) (xy 66.484755 -292.671564) (xy 66.472978 -292.62378)
			(xy 66.469018 -292.574726) (xy 66.13017 -292.574726) (xy 66.129675 -292.599333) (xy 66.12178 -292.64791)
			(xy 66.106196 -292.694591) (xy 66.083325 -292.738168) (xy 66.05376 -292.777512) (xy 66.018267 -292.811604)
			(xy 65.977764 -292.83956) (xy 65.933302 -292.860658) (xy 65.886031 -292.87435) (xy 65.837176 -292.880282)
			(xy 65.788001 -292.878301) (xy 65.739782 -292.868457) (xy 65.693766 -292.851005) (xy 65.651145 -292.826398)
			(xy 65.613024 -292.795273) (xy 65.580389 -292.758436) (xy 65.554086 -292.71684) (xy 65.534795 -292.671564)
			(xy 65.523018 -292.62378) (xy 65.519058 -292.574726) (xy 65.18021 -292.574726) (xy 65.179715 -292.599333)
			(xy 65.17182 -292.64791) (xy 65.156236 -292.694591) (xy 65.133365 -292.738168) (xy 65.1038 -292.777512)
			(xy 65.068307 -292.811604) (xy 65.027804 -292.83956) (xy 64.983342 -292.860658) (xy 64.936071 -292.87435)
			(xy 64.887216 -292.880282) (xy 64.838041 -292.878301) (xy 64.789822 -292.868457) (xy 64.743806 -292.851005)
			(xy 64.701185 -292.826398) (xy 64.663064 -292.795273) (xy 64.630429 -292.758436) (xy 64.604126 -292.71684)
			(xy 64.584835 -292.671564) (xy 64.573058 -292.62378) (xy 64.569098 -292.574726) (xy 64.23025 -292.574726)
			(xy 64.229755 -292.599333) (xy 64.22186 -292.64791) (xy 64.206276 -292.694591) (xy 64.183405 -292.738168)
			(xy 64.15384 -292.777512) (xy 64.118347 -292.811604) (xy 64.077844 -292.83956) (xy 64.033382 -292.860658)
			(xy 63.986111 -292.87435) (xy 63.937256 -292.880282) (xy 63.888081 -292.878301) (xy 63.839862 -292.868457)
			(xy 63.793846 -292.851005) (xy 63.751225 -292.826398) (xy 63.713104 -292.795273) (xy 63.680469 -292.758436)
			(xy 63.654166 -292.71684) (xy 63.634875 -292.671564) (xy 63.623098 -292.62378) (xy 63.619138 -292.574726)
			(xy 63.28029 -292.574726) (xy 63.279795 -292.599333) (xy 63.2719 -292.64791) (xy 63.256316 -292.694591)
			(xy 63.233445 -292.738168) (xy 63.20388 -292.777512) (xy 63.168387 -292.811604) (xy 63.127884 -292.83956)
			(xy 63.083422 -292.860658) (xy 63.036151 -292.87435) (xy 62.987296 -292.880282) (xy 62.938121 -292.878301)
			(xy 62.889902 -292.868457) (xy 62.843886 -292.851005) (xy 62.801265 -292.826398) (xy 62.763144 -292.795273)
			(xy 62.730509 -292.758436) (xy 62.704206 -292.71684) (xy 62.684915 -292.671564) (xy 62.673138 -292.62378)
			(xy 62.669178 -292.574726) (xy 62.330076 -292.574726) (xy 62.329581 -292.599333) (xy 62.321686 -292.64791)
			(xy 62.306102 -292.694591) (xy 62.283231 -292.738168) (xy 62.253666 -292.777512) (xy 62.218173 -292.811604)
			(xy 62.17767 -292.83956) (xy 62.133208 -292.860658) (xy 62.085937 -292.87435) (xy 62.037082 -292.880282)
			(xy 61.987907 -292.878301) (xy 61.939688 -292.868457) (xy 61.893672 -292.851005) (xy 61.851051 -292.826398)
			(xy 61.81293 -292.795273) (xy 61.780295 -292.758436) (xy 61.753992 -292.71684) (xy 61.734701 -292.671564)
			(xy 61.722924 -292.62378) (xy 61.718964 -292.574726) (xy 61.380116 -292.574726) (xy 61.379621 -292.599333)
			(xy 61.371726 -292.64791) (xy 61.356142 -292.694591) (xy 61.333271 -292.738168) (xy 61.303706 -292.777512)
			(xy 61.268213 -292.811604) (xy 61.22771 -292.83956) (xy 61.183248 -292.860658) (xy 61.135977 -292.87435)
			(xy 61.087122 -292.880282) (xy 61.037947 -292.878301) (xy 60.989728 -292.868457) (xy 60.943712 -292.851005)
			(xy 60.901091 -292.826398) (xy 60.86297 -292.795273) (xy 60.830335 -292.758436) (xy 60.804032 -292.71684)
			(xy 60.784741 -292.671564) (xy 60.772964 -292.62378) (xy 60.769004 -292.574726) (xy 60.430156 -292.574726)
			(xy 60.429661 -292.599333) (xy 60.421766 -292.64791) (xy 60.406182 -292.694591) (xy 60.383311 -292.738168)
			(xy 60.353746 -292.777512) (xy 60.318253 -292.811604) (xy 60.27775 -292.83956) (xy 60.233288 -292.860658)
			(xy 60.186017 -292.87435) (xy 60.137162 -292.880282) (xy 60.087987 -292.878301) (xy 60.039768 -292.868457)
			(xy 59.993752 -292.851005) (xy 59.951131 -292.826398) (xy 59.91301 -292.795273) (xy 59.880375 -292.758436)
			(xy 59.854072 -292.71684) (xy 59.834781 -292.671564) (xy 59.823004 -292.62378) (xy 59.819044 -292.574726)
			(xy 58.530231 -292.574726) (xy 58.530236 -292.57498) (xy 58.529741 -292.599587) (xy 58.521846 -292.648164)
			(xy 58.506262 -292.694845) (xy 58.483391 -292.738422) (xy 58.453826 -292.777766) (xy 58.418333 -292.811858)
			(xy 58.37783 -292.839814) (xy 58.333368 -292.860912) (xy 58.286097 -292.874604) (xy 58.237242 -292.880536)
			(xy 58.188067 -292.878555) (xy 58.139848 -292.868711) (xy 58.093832 -292.851259) (xy 58.051211 -292.826652)
			(xy 58.01309 -292.795527) (xy 57.980455 -292.75869) (xy 57.954152 -292.717094) (xy 57.934861 -292.671818)
			(xy 57.923084 -292.624034) (xy 57.919124 -292.57498) (xy 57.580276 -292.57498) (xy 57.579781 -292.599587)
			(xy 57.571886 -292.648164) (xy 57.556302 -292.694845) (xy 57.533431 -292.738422) (xy 57.503866 -292.777766)
			(xy 57.468373 -292.811858) (xy 57.42787 -292.839814) (xy 57.383408 -292.860912) (xy 57.336137 -292.874604)
			(xy 57.287282 -292.880536) (xy 57.238107 -292.878555) (xy 57.189888 -292.868711) (xy 57.143872 -292.851259)
			(xy 57.101251 -292.826652) (xy 57.06313 -292.795527) (xy 57.030495 -292.75869) (xy 57.004192 -292.717094)
			(xy 56.984901 -292.671818) (xy 56.973124 -292.624034) (xy 56.969164 -292.57498) (xy 56.630316 -292.57498)
			(xy 56.629821 -292.599587) (xy 56.621926 -292.648164) (xy 56.606342 -292.694845) (xy 56.583471 -292.738422)
			(xy 56.553906 -292.777766) (xy 56.518413 -292.811858) (xy 56.47791 -292.839814) (xy 56.433448 -292.860912)
			(xy 56.386177 -292.874604) (xy 56.337322 -292.880536) (xy 56.288147 -292.878555) (xy 56.239928 -292.868711)
			(xy 56.193912 -292.851259) (xy 56.151291 -292.826652) (xy 56.11317 -292.795527) (xy 56.080535 -292.75869)
			(xy 56.054232 -292.717094) (xy 56.034941 -292.671818) (xy 56.023164 -292.624034) (xy 56.019204 -292.57498)
			(xy 55.680102 -292.57498) (xy 55.679607 -292.599587) (xy 55.671712 -292.648164) (xy 55.656128 -292.694845)
			(xy 55.633257 -292.738422) (xy 55.603692 -292.777766) (xy 55.568199 -292.811858) (xy 55.527696 -292.839814)
			(xy 55.483234 -292.860912) (xy 55.435963 -292.874604) (xy 55.387108 -292.880536) (xy 55.337933 -292.878555)
			(xy 55.289714 -292.868711) (xy 55.243698 -292.851259) (xy 55.201077 -292.826652) (xy 55.162956 -292.795527)
			(xy 55.130321 -292.75869) (xy 55.104018 -292.717094) (xy 55.084727 -292.671818) (xy 55.07295 -292.624034)
			(xy 55.06899 -292.57498) (xy 54.730142 -292.57498) (xy 54.729647 -292.599587) (xy 54.721752 -292.648164)
			(xy 54.706168 -292.694845) (xy 54.683297 -292.738422) (xy 54.653732 -292.777766) (xy 54.618239 -292.811858)
			(xy 54.577736 -292.839814) (xy 54.533274 -292.860912) (xy 54.486003 -292.874604) (xy 54.437148 -292.880536)
			(xy 54.387973 -292.878555) (xy 54.339754 -292.868711) (xy 54.293738 -292.851259) (xy 54.251117 -292.826652)
			(xy 54.212996 -292.795527) (xy 54.180361 -292.75869) (xy 54.154058 -292.717094) (xy 54.134767 -292.671818)
			(xy 54.12299 -292.624034) (xy 54.11903 -292.57498) (xy 53.780182 -292.57498) (xy 53.779687 -292.599587)
			(xy 53.771792 -292.648164) (xy 53.756208 -292.694845) (xy 53.733337 -292.738422) (xy 53.703772 -292.777766)
			(xy 53.668279 -292.811858) (xy 53.627776 -292.839814) (xy 53.583314 -292.860912) (xy 53.536043 -292.874604)
			(xy 53.487188 -292.880536) (xy 53.438013 -292.878555) (xy 53.389794 -292.868711) (xy 53.343778 -292.851259)
			(xy 53.301157 -292.826652) (xy 53.263036 -292.795527) (xy 53.230401 -292.75869) (xy 53.204098 -292.717094)
			(xy 53.184807 -292.671818) (xy 53.17303 -292.624034) (xy 53.16907 -292.57498) (xy 52.830222 -292.57498)
			(xy 52.829727 -292.599587) (xy 52.821832 -292.648164) (xy 52.806248 -292.694845) (xy 52.783377 -292.738422)
			(xy 52.753812 -292.777766) (xy 52.718319 -292.811858) (xy 52.677816 -292.839814) (xy 52.633354 -292.860912)
			(xy 52.586083 -292.874604) (xy 52.537228 -292.880536) (xy 52.488053 -292.878555) (xy 52.439834 -292.868711)
			(xy 52.393818 -292.851259) (xy 52.351197 -292.826652) (xy 52.313076 -292.795527) (xy 52.280441 -292.75869)
			(xy 52.254138 -292.717094) (xy 52.234847 -292.671818) (xy 52.22307 -292.624034) (xy 52.21911 -292.57498)
			(xy 51.880262 -292.57498) (xy 51.879767 -292.599587) (xy 51.871872 -292.648164) (xy 51.856288 -292.694845)
			(xy 51.833417 -292.738422) (xy 51.803852 -292.777766) (xy 51.768359 -292.811858) (xy 51.727856 -292.839814)
			(xy 51.683394 -292.860912) (xy 51.636123 -292.874604) (xy 51.587268 -292.880536) (xy 51.538093 -292.878555)
			(xy 51.489874 -292.868711) (xy 51.443858 -292.851259) (xy 51.401237 -292.826652) (xy 51.363116 -292.795527)
			(xy 51.330481 -292.75869) (xy 51.304178 -292.717094) (xy 51.284887 -292.671818) (xy 51.27311 -292.624034)
			(xy 51.26915 -292.57498) (xy 50.930302 -292.57498) (xy 50.929807 -292.599587) (xy 50.921912 -292.648164)
			(xy 50.906328 -292.694845) (xy 50.883457 -292.738422) (xy 50.853892 -292.777766) (xy 50.818399 -292.811858)
			(xy 50.777896 -292.839814) (xy 50.733434 -292.860912) (xy 50.686163 -292.874604) (xy 50.637308 -292.880536)
			(xy 50.588133 -292.878555) (xy 50.539914 -292.868711) (xy 50.493898 -292.851259) (xy 50.451277 -292.826652)
			(xy 50.413156 -292.795527) (xy 50.380521 -292.75869) (xy 50.354218 -292.717094) (xy 50.334927 -292.671818)
			(xy 50.32315 -292.624034) (xy 50.31919 -292.57498) (xy 49.980083 -292.57498) (xy 49.979593 -292.599333)
			(xy 49.971698 -292.64791) (xy 49.956114 -292.694591) (xy 49.933243 -292.738168) (xy 49.903678 -292.777512)
			(xy 49.868185 -292.811604) (xy 49.827682 -292.83956) (xy 49.78322 -292.860658) (xy 49.735949 -292.87435)
			(xy 49.687094 -292.880282) (xy 49.637919 -292.878301) (xy 49.5897 -292.868457) (xy 49.543684 -292.851005)
			(xy 49.501063 -292.826398) (xy 49.462942 -292.795273) (xy 49.430307 -292.758436) (xy 49.404004 -292.71684)
			(xy 49.384713 -292.671564) (xy 49.372936 -292.62378) (xy 49.368976 -292.574726) (xy 49.030128 -292.574726)
			(xy 49.029633 -292.599333) (xy 49.021738 -292.64791) (xy 49.006154 -292.694591) (xy 48.983283 -292.738168)
			(xy 48.953718 -292.777512) (xy 48.918225 -292.811604) (xy 48.877722 -292.83956) (xy 48.83326 -292.860658)
			(xy 48.785989 -292.87435) (xy 48.737134 -292.880282) (xy 48.687959 -292.878301) (xy 48.63974 -292.868457)
			(xy 48.593724 -292.851005) (xy 48.551103 -292.826398) (xy 48.512982 -292.795273) (xy 48.480347 -292.758436)
			(xy 48.454044 -292.71684) (xy 48.434753 -292.671564) (xy 48.422976 -292.62378) (xy 48.419016 -292.574726)
			(xy 48.080163 -292.574726) (xy 48.080168 -292.57498) (xy 48.079673 -292.599587) (xy 48.071778 -292.648164)
			(xy 48.056194 -292.694845) (xy 48.033323 -292.738422) (xy 48.003758 -292.777766) (xy 47.968265 -292.811858)
			(xy 47.927762 -292.839814) (xy 47.8833 -292.860912) (xy 47.836029 -292.874604) (xy 47.787174 -292.880536)
			(xy 47.737999 -292.878555) (xy 47.68978 -292.868711) (xy 47.643764 -292.851259) (xy 47.601143 -292.826652)
			(xy 47.563022 -292.795527) (xy 47.530387 -292.75869) (xy 47.504084 -292.717094) (xy 47.484793 -292.671818)
			(xy 47.473016 -292.624034) (xy 47.469056 -292.57498) (xy 47.130208 -292.57498) (xy 47.129713 -292.599587)
			(xy 47.121818 -292.648164) (xy 47.106234 -292.694845) (xy 47.083363 -292.738422) (xy 47.053798 -292.777766)
			(xy 47.018305 -292.811858) (xy 46.977802 -292.839814) (xy 46.93334 -292.860912) (xy 46.886069 -292.874604)
			(xy 46.837214 -292.880536) (xy 46.788039 -292.878555) (xy 46.73982 -292.868711) (xy 46.693804 -292.851259)
			(xy 46.651183 -292.826652) (xy 46.613062 -292.795527) (xy 46.580427 -292.75869) (xy 46.554124 -292.717094)
			(xy 46.534833 -292.671818) (xy 46.523056 -292.624034) (xy 46.519096 -292.57498) (xy 46.180248 -292.57498)
			(xy 46.179753 -292.599587) (xy 46.171858 -292.648164) (xy 46.156274 -292.694845) (xy 46.133403 -292.738422)
			(xy 46.103838 -292.777766) (xy 46.068345 -292.811858) (xy 46.027842 -292.839814) (xy 45.98338 -292.860912)
			(xy 45.936109 -292.874604) (xy 45.887254 -292.880536) (xy 45.838079 -292.878555) (xy 45.78986 -292.868711)
			(xy 45.743844 -292.851259) (xy 45.701223 -292.826652) (xy 45.663102 -292.795527) (xy 45.630467 -292.75869)
			(xy 45.604164 -292.717094) (xy 45.584873 -292.671818) (xy 45.573096 -292.624034) (xy 45.569136 -292.57498)
			(xy 45.230288 -292.57498) (xy 45.229793 -292.599587) (xy 45.221898 -292.648164) (xy 45.206314 -292.694845)
			(xy 45.183443 -292.738422) (xy 45.153878 -292.777766) (xy 45.118385 -292.811858) (xy 45.077882 -292.839814)
			(xy 45.03342 -292.860912) (xy 44.986149 -292.874604) (xy 44.937294 -292.880536) (xy 44.888119 -292.878555)
			(xy 44.8399 -292.868711) (xy 44.793884 -292.851259) (xy 44.751263 -292.826652) (xy 44.713142 -292.795527)
			(xy 44.680507 -292.75869) (xy 44.654204 -292.717094) (xy 44.634913 -292.671818) (xy 44.623136 -292.624034)
			(xy 44.619176 -292.57498) (xy 44.280074 -292.57498) (xy 44.279579 -292.599587) (xy 44.271684 -292.648164)
			(xy 44.2561 -292.694845) (xy 44.233229 -292.738422) (xy 44.203664 -292.777766) (xy 44.168171 -292.811858)
			(xy 44.127668 -292.839814) (xy 44.083206 -292.860912) (xy 44.035935 -292.874604) (xy 43.98708 -292.880536)
			(xy 43.937905 -292.878555) (xy 43.889686 -292.868711) (xy 43.84367 -292.851259) (xy 43.801049 -292.826652)
			(xy 43.762928 -292.795527) (xy 43.730293 -292.75869) (xy 43.70399 -292.717094) (xy 43.684699 -292.671818)
			(xy 43.672922 -292.624034) (xy 43.668962 -292.57498) (xy 43.330114 -292.57498) (xy 43.329619 -292.599587)
			(xy 43.321724 -292.648164) (xy 43.30614 -292.694845) (xy 43.283269 -292.738422) (xy 43.253704 -292.777766)
			(xy 43.218211 -292.811858) (xy 43.177708 -292.839814) (xy 43.133246 -292.860912) (xy 43.085975 -292.874604)
			(xy 43.03712 -292.880536) (xy 42.987945 -292.878555) (xy 42.939726 -292.868711) (xy 42.89371 -292.851259)
			(xy 42.851089 -292.826652) (xy 42.812968 -292.795527) (xy 42.780333 -292.75869) (xy 42.75403 -292.717094)
			(xy 42.734739 -292.671818) (xy 42.722962 -292.624034) (xy 42.719002 -292.57498) (xy 42.430954 -292.57498)
			(xy 42.430456 -292.601629) (xy 42.422513 -292.654333) (xy 42.406803 -292.705263) (xy 42.383677 -292.753284)
			(xy 42.353653 -292.797321) (xy 42.317401 -292.836392) (xy 42.27573 -292.869623) (xy 42.229572 -292.896272)
			(xy 42.179958 -292.915744) (xy 42.127996 -292.927604) (xy 42.074846 -292.931588) (xy 42.021696 -292.927604)
			(xy 41.969734 -292.915744) (xy 41.92012 -292.896272) (xy 41.873962 -292.869623) (xy 41.832291 -292.836392)
			(xy 41.796039 -292.797321) (xy 41.766015 -292.753284) (xy 41.742889 -292.705263) (xy 41.727179 -292.654333)
			(xy 41.719236 -292.601629) (xy 41.429367 -292.601629) (xy 41.421804 -292.648164) (xy 41.40622 -292.694845)
			(xy 41.383349 -292.738422) (xy 41.353784 -292.777766) (xy 41.318291 -292.811858) (xy 41.277788 -292.839814)
			(xy 41.233326 -292.860912) (xy 41.186055 -292.874604) (xy 41.1372 -292.880536) (xy 41.088025 -292.878555)
			(xy 41.039806 -292.868711) (xy 40.99379 -292.851259) (xy 40.951169 -292.826652) (xy 40.913048 -292.795527)
			(xy 40.880413 -292.75869) (xy 40.85411 -292.717094) (xy 40.834819 -292.671818) (xy 40.823042 -292.624034)
			(xy 40.819082 -292.57498) (xy 40.480229 -292.57498) (xy 40.479739 -292.599333) (xy 40.471844 -292.64791)
			(xy 40.45626 -292.694591) (xy 40.433389 -292.738168) (xy 40.403824 -292.777512) (xy 40.368331 -292.811604)
			(xy 40.327828 -292.83956) (xy 40.283366 -292.860658) (xy 40.236095 -292.87435) (xy 40.18724 -292.880282)
			(xy 40.138065 -292.878301) (xy 40.089846 -292.868457) (xy 40.04383 -292.851005) (xy 40.001209 -292.826398)
			(xy 39.963088 -292.795273) (xy 39.930453 -292.758436) (xy 39.90415 -292.71684) (xy 39.884859 -292.671564)
			(xy 39.873082 -292.62378) (xy 39.869122 -292.574726) (xy 39.530274 -292.574726) (xy 39.529779 -292.599333)
			(xy 39.521884 -292.64791) (xy 39.5063 -292.694591) (xy 39.483429 -292.738168) (xy 39.453864 -292.777512)
			(xy 39.418371 -292.811604) (xy 39.377868 -292.83956) (xy 39.333406 -292.860658) (xy 39.286135 -292.87435)
			(xy 39.23728 -292.880282) (xy 39.188105 -292.878301) (xy 39.139886 -292.868457) (xy 39.09387 -292.851005)
			(xy 39.051249 -292.826398) (xy 39.013128 -292.795273) (xy 38.980493 -292.758436) (xy 38.95419 -292.71684)
			(xy 38.934899 -292.671564) (xy 38.923122 -292.62378) (xy 38.919162 -292.574726) (xy 38.580309 -292.574726)
			(xy 38.580314 -292.57498) (xy 38.579819 -292.599587) (xy 38.571924 -292.648164) (xy 38.55634 -292.694845)
			(xy 38.533469 -292.738422) (xy 38.503904 -292.777766) (xy 38.468411 -292.811858) (xy 38.427908 -292.839814)
			(xy 38.383446 -292.860912) (xy 38.336175 -292.874604) (xy 38.28732 -292.880536) (xy 38.238145 -292.878555)
			(xy 38.189926 -292.868711) (xy 38.14391 -292.851259) (xy 38.101289 -292.826652) (xy 38.063168 -292.795527)
			(xy 38.030533 -292.75869) (xy 38.00423 -292.717094) (xy 37.984939 -292.671818) (xy 37.973162 -292.624034)
			(xy 37.969202 -292.57498) (xy 37.6301 -292.57498) (xy 37.629605 -292.599587) (xy 37.62171 -292.648164)
			(xy 37.606126 -292.694845) (xy 37.583255 -292.738422) (xy 37.55369 -292.777766) (xy 37.518197 -292.811858)
			(xy 37.477694 -292.839814) (xy 37.433232 -292.860912) (xy 37.385961 -292.874604) (xy 37.337106 -292.880536)
			(xy 37.287931 -292.878555) (xy 37.239712 -292.868711) (xy 37.193696 -292.851259) (xy 37.151075 -292.826652)
			(xy 37.112954 -292.795527) (xy 37.080319 -292.75869) (xy 37.054016 -292.717094) (xy 37.034725 -292.671818)
			(xy 37.022948 -292.624034) (xy 37.018988 -292.57498) (xy 36.68014 -292.57498) (xy 36.679645 -292.599587)
			(xy 36.67175 -292.648164) (xy 36.656166 -292.694845) (xy 36.633295 -292.738422) (xy 36.60373 -292.777766)
			(xy 36.568237 -292.811858) (xy 36.527734 -292.839814) (xy 36.483272 -292.860912) (xy 36.436001 -292.874604)
			(xy 36.387146 -292.880536) (xy 36.337971 -292.878555) (xy 36.289752 -292.868711) (xy 36.243736 -292.851259)
			(xy 36.201115 -292.826652) (xy 36.162994 -292.795527) (xy 36.130359 -292.75869) (xy 36.104056 -292.717094)
			(xy 36.084765 -292.671818) (xy 36.072988 -292.624034) (xy 36.069028 -292.57498) (xy 32.077791 -292.57498)
			(xy 32.088861 -292.59922) (xy 32.104216 -292.651515) (xy 32.111972 -292.705463) (xy 32.112458 -292.732714)
			(xy 32.111907 -292.762096) (xy 32.102876 -292.820161) (xy 32.085044 -292.876154) (xy 32.058835 -292.928749)
			(xy 32.024867 -292.9767) (xy 31.983946 -293.018874) (xy 31.96082 -293.037006) (xy 31.951422 -293.044372)
			(xy 31.941008 -293.064946) (xy 31.939484 -293.168832) (xy 31.94939 -293.189914) (xy 31.958534 -293.19728)
			(xy 31.980362 -293.215509) (xy 32.018902 -293.257324) (xy 32.05081 -293.304395) (xy 32.07538 -293.35568)
			(xy 32.092068 -293.410043) (xy 32.100505 -293.466281) (xy 32.101028 -293.494714) (xy 32.734502 -293.494714)
			(xy 32.738573 -293.439092) (xy 32.750699 -293.384655) (xy 32.770622 -293.332564) (xy 32.797918 -293.283929)
			(xy 32.832004 -293.239786) (xy 32.872153 -293.201077) (xy 32.917511 -293.168626) (xy 32.967111 -293.143125)
			(xy 33.019895 -293.125118) (xy 33.074738 -293.114988) (xy 33.130472 -293.112951) (xy 33.185909 -293.119051)
			(xy 33.239866 -293.133157) (xy 33.291195 -293.154969) (xy 33.338801 -293.184023) (xy 33.381669 -293.219698)
			(xy 33.418886 -293.261235) (xy 33.449659 -293.307748) (xy 33.473331 -293.358245) (xy 33.489399 -293.411652)
			(xy 33.497519 -293.466828) (xy 33.498028 -293.494714) (xy 33.620962 -293.494714) (xy 33.625033 -293.439092)
			(xy 33.637159 -293.384655) (xy 33.657082 -293.332564) (xy 33.684378 -293.283929) (xy 33.718464 -293.239786)
			(xy 33.758613 -293.201077) (xy 33.803971 -293.168626) (xy 33.853571 -293.143125) (xy 33.906355 -293.125118)
			(xy 33.961198 -293.114988) (xy 34.016932 -293.112951) (xy 34.072369 -293.119051) (xy 34.126326 -293.133157)
			(xy 34.177655 -293.154969) (xy 34.225261 -293.184023) (xy 34.268129 -293.219698) (xy 34.305346 -293.261235)
			(xy 34.336119 -293.307748) (xy 34.359791 -293.358245) (xy 34.375859 -293.411652) (xy 34.383979 -293.466828)
			(xy 34.384488 -293.494714) (xy 34.383979 -293.5226) (xy 34.383635 -293.52494) (xy 37.969202 -293.52494)
			(xy 37.973162 -293.475886) (xy 37.984939 -293.428102) (xy 38.00423 -293.382826) (xy 38.030533 -293.34123)
			(xy 38.063168 -293.304393) (xy 38.101289 -293.273268) (xy 38.14391 -293.248661) (xy 38.189926 -293.231209)
			(xy 38.238145 -293.221365) (xy 38.28732 -293.219384) (xy 38.336175 -293.225316) (xy 38.383446 -293.239008)
			(xy 38.427908 -293.260106) (xy 38.468411 -293.288062) (xy 38.503904 -293.322154) (xy 38.533469 -293.361498)
			(xy 38.55634 -293.405075) (xy 38.571924 -293.451756) (xy 38.579819 -293.500333) (xy 38.580314 -293.52494)
			(xy 38.919162 -293.52494) (xy 38.923122 -293.475886) (xy 38.934899 -293.428102) (xy 38.95419 -293.382826)
			(xy 38.980493 -293.34123) (xy 39.013128 -293.304393) (xy 39.051249 -293.273268) (xy 39.09387 -293.248661)
			(xy 39.139886 -293.231209) (xy 39.188105 -293.221365) (xy 39.23728 -293.219384) (xy 39.286135 -293.225316)
			(xy 39.333406 -293.239008) (xy 39.377868 -293.260106) (xy 39.418371 -293.288062) (xy 39.453864 -293.322154)
			(xy 39.483429 -293.361498) (xy 39.5063 -293.405075) (xy 39.521884 -293.451756) (xy 39.529779 -293.500333)
			(xy 39.530274 -293.52494) (xy 39.869122 -293.52494) (xy 39.873082 -293.475886) (xy 39.884859 -293.428102)
			(xy 39.90415 -293.382826) (xy 39.930453 -293.34123) (xy 39.963088 -293.304393) (xy 40.001209 -293.273268)
			(xy 40.04383 -293.248661) (xy 40.089846 -293.231209) (xy 40.138065 -293.221365) (xy 40.18724 -293.219384)
			(xy 40.236095 -293.225316) (xy 40.283366 -293.239008) (xy 40.327828 -293.260106) (xy 40.368331 -293.288062)
			(xy 40.403824 -293.322154) (xy 40.433389 -293.361498) (xy 40.45626 -293.405075) (xy 40.471844 -293.451756)
			(xy 40.479739 -293.500333) (xy 40.480234 -293.52494) (xy 40.819082 -293.52494) (xy 40.823042 -293.475886)
			(xy 40.834819 -293.428102) (xy 40.85411 -293.382826) (xy 40.880413 -293.34123) (xy 40.913048 -293.304393)
			(xy 40.951169 -293.273268) (xy 40.99379 -293.248661) (xy 41.039806 -293.231209) (xy 41.088025 -293.221365)
			(xy 41.1372 -293.219384) (xy 41.186055 -293.225316) (xy 41.233326 -293.239008) (xy 41.277788 -293.260106)
			(xy 41.318291 -293.288062) (xy 41.353784 -293.322154) (xy 41.383349 -293.361498) (xy 41.40622 -293.405075)
			(xy 41.421804 -293.451756) (xy 41.429699 -293.500333) (xy 41.430194 -293.52494) (xy 41.769042 -293.52494)
			(xy 41.773002 -293.475886) (xy 41.784779 -293.428102) (xy 41.80407 -293.382826) (xy 41.830373 -293.34123)
			(xy 41.863008 -293.304393) (xy 41.901129 -293.273268) (xy 41.94375 -293.248661) (xy 41.989766 -293.231209)
			(xy 42.037985 -293.221365) (xy 42.08716 -293.219384) (xy 42.136015 -293.225316) (xy 42.183286 -293.239008)
			(xy 42.227748 -293.260106) (xy 42.268251 -293.288062) (xy 42.303744 -293.322154) (xy 42.333309 -293.361498)
			(xy 42.35618 -293.405075) (xy 42.371764 -293.451756) (xy 42.379659 -293.500333) (xy 42.380154 -293.52494)
			(xy 42.379659 -293.549547) (xy 42.379327 -293.551589) (xy 42.669196 -293.551589) (xy 42.669196 -293.498291)
			(xy 42.677139 -293.445587) (xy 42.692849 -293.394657) (xy 42.715975 -293.346636) (xy 42.745999 -293.302599)
			(xy 42.782251 -293.263528) (xy 42.823922 -293.230297) (xy 42.87008 -293.203648) (xy 42.919694 -293.184176)
			(xy 42.971656 -293.172316) (xy 43.024806 -293.168333) (xy 43.077956 -293.172316) (xy 43.129918 -293.184176)
			(xy 43.179532 -293.203648) (xy 43.22569 -293.230297) (xy 43.267361 -293.263528) (xy 43.303613 -293.302599)
			(xy 43.333637 -293.346636) (xy 43.356763 -293.394657) (xy 43.372473 -293.445587) (xy 43.380416 -293.498291)
			(xy 43.380914 -293.52494) (xy 43.668962 -293.52494) (xy 43.672922 -293.475886) (xy 43.684699 -293.428102)
			(xy 43.70399 -293.382826) (xy 43.730293 -293.34123) (xy 43.762928 -293.304393) (xy 43.801049 -293.273268)
			(xy 43.84367 -293.248661) (xy 43.889686 -293.231209) (xy 43.937905 -293.221365) (xy 43.98708 -293.219384)
			(xy 44.035935 -293.225316) (xy 44.083206 -293.239008) (xy 44.127668 -293.260106) (xy 44.168171 -293.288062)
			(xy 44.203664 -293.322154) (xy 44.233229 -293.361498) (xy 44.2561 -293.405075) (xy 44.271684 -293.451756)
			(xy 44.279579 -293.500333) (xy 44.280074 -293.52494) (xy 45.569136 -293.52494) (xy 45.573096 -293.475886)
			(xy 45.584873 -293.428102) (xy 45.604164 -293.382826) (xy 45.630467 -293.34123) (xy 45.663102 -293.304393)
			(xy 45.701223 -293.273268) (xy 45.743844 -293.248661) (xy 45.78986 -293.231209) (xy 45.838079 -293.221365)
			(xy 45.887254 -293.219384) (xy 45.936109 -293.225316) (xy 45.98338 -293.239008) (xy 46.027842 -293.260106)
			(xy 46.068345 -293.288062) (xy 46.103838 -293.322154) (xy 46.133403 -293.361498) (xy 46.156274 -293.405075)
			(xy 46.171858 -293.451756) (xy 46.179753 -293.500333) (xy 46.180248 -293.52494) (xy 47.469056 -293.52494)
			(xy 47.473016 -293.475886) (xy 47.484793 -293.428102) (xy 47.504084 -293.382826) (xy 47.530387 -293.34123)
			(xy 47.563022 -293.304393) (xy 47.601143 -293.273268) (xy 47.643764 -293.248661) (xy 47.68978 -293.231209)
			(xy 47.737999 -293.221365) (xy 47.787174 -293.219384) (xy 47.836029 -293.225316) (xy 47.8833 -293.239008)
			(xy 47.927762 -293.260106) (xy 47.968265 -293.288062) (xy 48.003758 -293.322154) (xy 48.033323 -293.361498)
			(xy 48.056194 -293.405075) (xy 48.071778 -293.451756) (xy 48.079673 -293.500333) (xy 48.080168 -293.52494)
			(xy 48.419016 -293.52494) (xy 48.422976 -293.475886) (xy 48.434753 -293.428102) (xy 48.454044 -293.382826)
			(xy 48.480347 -293.34123) (xy 48.512982 -293.304393) (xy 48.551103 -293.273268) (xy 48.593724 -293.248661)
			(xy 48.63974 -293.231209) (xy 48.687959 -293.221365) (xy 48.737134 -293.219384) (xy 48.785989 -293.225316)
			(xy 48.83326 -293.239008) (xy 48.877722 -293.260106) (xy 48.918225 -293.288062) (xy 48.953718 -293.322154)
			(xy 48.983283 -293.361498) (xy 49.006154 -293.405075) (xy 49.021738 -293.451756) (xy 49.029633 -293.500333)
			(xy 49.030128 -293.52494) (xy 49.368976 -293.52494) (xy 49.372936 -293.475886) (xy 49.384713 -293.428102)
			(xy 49.404004 -293.382826) (xy 49.430307 -293.34123) (xy 49.462942 -293.304393) (xy 49.501063 -293.273268)
			(xy 49.543684 -293.248661) (xy 49.5897 -293.231209) (xy 49.637919 -293.221365) (xy 49.687094 -293.219384)
			(xy 49.735949 -293.225316) (xy 49.78322 -293.239008) (xy 49.827682 -293.260106) (xy 49.868185 -293.288062)
			(xy 49.903678 -293.322154) (xy 49.933243 -293.361498) (xy 49.956114 -293.405075) (xy 49.971698 -293.451756)
			(xy 49.979593 -293.500333) (xy 49.980088 -293.52494) (xy 50.31919 -293.52494) (xy 50.32315 -293.475886)
			(xy 50.334927 -293.428102) (xy 50.354218 -293.382826) (xy 50.380521 -293.34123) (xy 50.413156 -293.304393)
			(xy 50.451277 -293.273268) (xy 50.493898 -293.248661) (xy 50.539914 -293.231209) (xy 50.588133 -293.221365)
			(xy 50.637308 -293.219384) (xy 50.686163 -293.225316) (xy 50.733434 -293.239008) (xy 50.777896 -293.260106)
			(xy 50.818399 -293.288062) (xy 50.853892 -293.322154) (xy 50.883457 -293.361498) (xy 50.906328 -293.405075)
			(xy 50.921912 -293.451756) (xy 50.929807 -293.500333) (xy 50.930302 -293.52494) (xy 51.26915 -293.52494)
			(xy 51.27311 -293.475886) (xy 51.284887 -293.428102) (xy 51.304178 -293.382826) (xy 51.330481 -293.34123)
			(xy 51.363116 -293.304393) (xy 51.401237 -293.273268) (xy 51.443858 -293.248661) (xy 51.489874 -293.231209)
			(xy 51.538093 -293.221365) (xy 51.587268 -293.219384) (xy 51.636123 -293.225316) (xy 51.683394 -293.239008)
			(xy 51.727856 -293.260106) (xy 51.768359 -293.288062) (xy 51.803852 -293.322154) (xy 51.833417 -293.361498)
			(xy 51.856288 -293.405075) (xy 51.871872 -293.451756) (xy 51.879767 -293.500333) (xy 51.880262 -293.52494)
			(xy 52.21911 -293.52494) (xy 52.22307 -293.475886) (xy 52.234847 -293.428102) (xy 52.254138 -293.382826)
			(xy 52.280441 -293.34123) (xy 52.313076 -293.304393) (xy 52.351197 -293.273268) (xy 52.393818 -293.248661)
			(xy 52.439834 -293.231209) (xy 52.488053 -293.221365) (xy 52.537228 -293.219384) (xy 52.586083 -293.225316)
			(xy 52.633354 -293.239008) (xy 52.677816 -293.260106) (xy 52.718319 -293.288062) (xy 52.753812 -293.322154)
			(xy 52.783377 -293.361498) (xy 52.806248 -293.405075) (xy 52.821832 -293.451756) (xy 52.829727 -293.500333)
			(xy 52.830222 -293.52494) (xy 53.16907 -293.52494) (xy 53.17303 -293.475886) (xy 53.184807 -293.428102)
			(xy 53.204098 -293.382826) (xy 53.230401 -293.34123) (xy 53.263036 -293.304393) (xy 53.301157 -293.273268)
			(xy 53.343778 -293.248661) (xy 53.389794 -293.231209) (xy 53.438013 -293.221365) (xy 53.487188 -293.219384)
			(xy 53.536043 -293.225316) (xy 53.583314 -293.239008) (xy 53.627776 -293.260106) (xy 53.668279 -293.288062)
			(xy 53.703772 -293.322154) (xy 53.733337 -293.361498) (xy 53.756208 -293.405075) (xy 53.771792 -293.451756)
			(xy 53.779687 -293.500333) (xy 53.780182 -293.52494) (xy 54.11903 -293.52494) (xy 54.12299 -293.475886)
			(xy 54.134767 -293.428102) (xy 54.154058 -293.382826) (xy 54.180361 -293.34123) (xy 54.212996 -293.304393)
			(xy 54.251117 -293.273268) (xy 54.293738 -293.248661) (xy 54.339754 -293.231209) (xy 54.387973 -293.221365)
			(xy 54.437148 -293.219384) (xy 54.486003 -293.225316) (xy 54.533274 -293.239008) (xy 54.577736 -293.260106)
			(xy 54.618239 -293.288062) (xy 54.653732 -293.322154) (xy 54.683297 -293.361498) (xy 54.706168 -293.405075)
			(xy 54.721752 -293.451756) (xy 54.729647 -293.500333) (xy 54.730142 -293.52494) (xy 55.06899 -293.52494)
			(xy 55.07295 -293.475886) (xy 55.084727 -293.428102) (xy 55.104018 -293.382826) (xy 55.130321 -293.34123)
			(xy 55.162956 -293.304393) (xy 55.201077 -293.273268) (xy 55.243698 -293.248661) (xy 55.289714 -293.231209)
			(xy 55.337933 -293.221365) (xy 55.387108 -293.219384) (xy 55.435963 -293.225316) (xy 55.483234 -293.239008)
			(xy 55.527696 -293.260106) (xy 55.568199 -293.288062) (xy 55.603692 -293.322154) (xy 55.633257 -293.361498)
			(xy 55.656128 -293.405075) (xy 55.671712 -293.451756) (xy 55.679607 -293.500333) (xy 55.680102 -293.52494)
			(xy 56.01895 -293.52494) (xy 56.02291 -293.475886) (xy 56.034687 -293.428102) (xy 56.053978 -293.382826)
			(xy 56.080281 -293.34123) (xy 56.112916 -293.304393) (xy 56.151037 -293.273268) (xy 56.193658 -293.248661)
			(xy 56.239674 -293.231209) (xy 56.287893 -293.221365) (xy 56.337068 -293.219384) (xy 56.385923 -293.225316)
			(xy 56.433194 -293.239008) (xy 56.477656 -293.260106) (xy 56.518159 -293.288062) (xy 56.553652 -293.322154)
			(xy 56.583217 -293.361498) (xy 56.606088 -293.405075) (xy 56.621672 -293.451756) (xy 56.629567 -293.500333)
			(xy 56.630062 -293.52494) (xy 56.969164 -293.52494) (xy 56.973124 -293.475886) (xy 56.984901 -293.428102)
			(xy 57.004192 -293.382826) (xy 57.030495 -293.34123) (xy 57.06313 -293.304393) (xy 57.101251 -293.273268)
			(xy 57.143872 -293.248661) (xy 57.189888 -293.231209) (xy 57.238107 -293.221365) (xy 57.287282 -293.219384)
			(xy 57.336137 -293.225316) (xy 57.383408 -293.239008) (xy 57.42787 -293.260106) (xy 57.468373 -293.288062)
			(xy 57.503866 -293.322154) (xy 57.533431 -293.361498) (xy 57.556302 -293.405075) (xy 57.571886 -293.451756)
			(xy 57.579781 -293.500333) (xy 57.580276 -293.52494) (xy 57.919124 -293.52494) (xy 57.923084 -293.475886)
			(xy 57.934861 -293.428102) (xy 57.954152 -293.382826) (xy 57.980455 -293.34123) (xy 58.01309 -293.304393)
			(xy 58.051211 -293.273268) (xy 58.093832 -293.248661) (xy 58.139848 -293.231209) (xy 58.188067 -293.221365)
			(xy 58.237242 -293.219384) (xy 58.286097 -293.225316) (xy 58.333368 -293.239008) (xy 58.37783 -293.260106)
			(xy 58.418333 -293.288062) (xy 58.453826 -293.322154) (xy 58.483391 -293.361498) (xy 58.506262 -293.405075)
			(xy 58.521846 -293.451756) (xy 58.529741 -293.500333) (xy 58.530236 -293.52494) (xy 59.819044 -293.52494)
			(xy 59.823004 -293.475886) (xy 59.834781 -293.428102) (xy 59.854072 -293.382826) (xy 59.880375 -293.34123)
			(xy 59.91301 -293.304393) (xy 59.951131 -293.273268) (xy 59.993752 -293.248661) (xy 60.039768 -293.231209)
			(xy 60.087987 -293.221365) (xy 60.137162 -293.219384) (xy 60.186017 -293.225316) (xy 60.233288 -293.239008)
			(xy 60.27775 -293.260106) (xy 60.318253 -293.288062) (xy 60.353746 -293.322154) (xy 60.383311 -293.361498)
			(xy 60.406182 -293.405075) (xy 60.421766 -293.451756) (xy 60.429661 -293.500333) (xy 60.430156 -293.52494)
			(xy 60.769004 -293.52494) (xy 60.772964 -293.475886) (xy 60.784741 -293.428102) (xy 60.804032 -293.382826)
			(xy 60.830335 -293.34123) (xy 60.86297 -293.304393) (xy 60.901091 -293.273268) (xy 60.943712 -293.248661)
			(xy 60.989728 -293.231209) (xy 61.037947 -293.221365) (xy 61.087122 -293.219384) (xy 61.135977 -293.225316)
			(xy 61.183248 -293.239008) (xy 61.22771 -293.260106) (xy 61.268213 -293.288062) (xy 61.303706 -293.322154)
			(xy 61.333271 -293.361498) (xy 61.356142 -293.405075) (xy 61.371726 -293.451756) (xy 61.379621 -293.500333)
			(xy 61.380116 -293.52494) (xy 61.718964 -293.52494) (xy 61.722924 -293.475886) (xy 61.734701 -293.428102)
			(xy 61.753992 -293.382826) (xy 61.780295 -293.34123) (xy 61.81293 -293.304393) (xy 61.851051 -293.273268)
			(xy 61.893672 -293.248661) (xy 61.939688 -293.231209) (xy 61.987907 -293.221365) (xy 62.037082 -293.219384)
			(xy 62.085937 -293.225316) (xy 62.133208 -293.239008) (xy 62.17767 -293.260106) (xy 62.218173 -293.288062)
			(xy 62.253666 -293.322154) (xy 62.283231 -293.361498) (xy 62.306102 -293.405075) (xy 62.321686 -293.451756)
			(xy 62.329581 -293.500333) (xy 62.330076 -293.52494) (xy 62.669178 -293.52494) (xy 62.673138 -293.475886)
			(xy 62.684915 -293.428102) (xy 62.704206 -293.382826) (xy 62.730509 -293.34123) (xy 62.763144 -293.304393)
			(xy 62.801265 -293.273268) (xy 62.843886 -293.248661) (xy 62.889902 -293.231209) (xy 62.938121 -293.221365)
			(xy 62.987296 -293.219384) (xy 63.036151 -293.225316) (xy 63.083422 -293.239008) (xy 63.127884 -293.260106)
			(xy 63.168387 -293.288062) (xy 63.20388 -293.322154) (xy 63.233445 -293.361498) (xy 63.256316 -293.405075)
			(xy 63.2719 -293.451756) (xy 63.279795 -293.500333) (xy 63.28029 -293.52494) (xy 63.619138 -293.52494)
			(xy 63.623098 -293.475886) (xy 63.634875 -293.428102) (xy 63.654166 -293.382826) (xy 63.680469 -293.34123)
			(xy 63.713104 -293.304393) (xy 63.751225 -293.273268) (xy 63.793846 -293.248661) (xy 63.839862 -293.231209)
			(xy 63.888081 -293.221365) (xy 63.937256 -293.219384) (xy 63.986111 -293.225316) (xy 64.033382 -293.239008)
			(xy 64.077844 -293.260106) (xy 64.118347 -293.288062) (xy 64.15384 -293.322154) (xy 64.183405 -293.361498)
			(xy 64.206276 -293.405075) (xy 64.22186 -293.451756) (xy 64.229755 -293.500333) (xy 64.23025 -293.52494)
			(xy 64.569098 -293.52494) (xy 64.573058 -293.475886) (xy 64.584835 -293.428102) (xy 64.604126 -293.382826)
			(xy 64.630429 -293.34123) (xy 64.663064 -293.304393) (xy 64.701185 -293.273268) (xy 64.743806 -293.248661)
			(xy 64.789822 -293.231209) (xy 64.838041 -293.221365) (xy 64.887216 -293.219384) (xy 64.936071 -293.225316)
			(xy 64.983342 -293.239008) (xy 65.027804 -293.260106) (xy 65.068307 -293.288062) (xy 65.1038 -293.322154)
			(xy 65.133365 -293.361498) (xy 65.156236 -293.405075) (xy 65.17182 -293.451756) (xy 65.179715 -293.500333)
			(xy 65.18021 -293.52494) (xy 65.519058 -293.52494) (xy 65.523018 -293.475886) (xy 65.534795 -293.428102)
			(xy 65.554086 -293.382826) (xy 65.580389 -293.34123) (xy 65.613024 -293.304393) (xy 65.651145 -293.273268)
			(xy 65.693766 -293.248661) (xy 65.739782 -293.231209) (xy 65.788001 -293.221365) (xy 65.837176 -293.219384)
			(xy 65.886031 -293.225316) (xy 65.933302 -293.239008) (xy 65.977764 -293.260106) (xy 66.018267 -293.288062)
			(xy 66.05376 -293.322154) (xy 66.083325 -293.361498) (xy 66.106196 -293.405075) (xy 66.12178 -293.451756)
			(xy 66.129675 -293.500333) (xy 66.13017 -293.52494) (xy 66.469018 -293.52494) (xy 66.472978 -293.475886)
			(xy 66.484755 -293.428102) (xy 66.504046 -293.382826) (xy 66.530349 -293.34123) (xy 66.562984 -293.304393)
			(xy 66.601105 -293.273268) (xy 66.643726 -293.248661) (xy 66.689742 -293.231209) (xy 66.737961 -293.221365)
			(xy 66.787136 -293.219384) (xy 66.835991 -293.225316) (xy 66.883262 -293.239008) (xy 66.927724 -293.260106)
			(xy 66.968227 -293.288062) (xy 67.00372 -293.322154) (xy 67.033285 -293.361498) (xy 67.056156 -293.405075)
			(xy 67.07174 -293.451756) (xy 67.079635 -293.500333) (xy 67.08013 -293.52494) (xy 67.418978 -293.52494)
			(xy 67.422938 -293.475886) (xy 67.434715 -293.428102) (xy 67.454006 -293.382826) (xy 67.480309 -293.34123)
			(xy 67.512944 -293.304393) (xy 67.551065 -293.273268) (xy 67.593686 -293.248661) (xy 67.639702 -293.231209)
			(xy 67.687921 -293.221365) (xy 67.737096 -293.219384) (xy 67.785951 -293.225316) (xy 67.833222 -293.239008)
			(xy 67.877684 -293.260106) (xy 67.918187 -293.288062) (xy 67.95368 -293.322154) (xy 67.983245 -293.361498)
			(xy 68.006116 -293.405075) (xy 68.0217 -293.451756) (xy 68.029595 -293.500333) (xy 68.03009 -293.52494)
			(xy 68.368938 -293.52494) (xy 68.372898 -293.475886) (xy 68.384675 -293.428102) (xy 68.403966 -293.382826)
			(xy 68.430269 -293.34123) (xy 68.462904 -293.304393) (xy 68.501025 -293.273268) (xy 68.543646 -293.248661)
			(xy 68.589662 -293.231209) (xy 68.637881 -293.221365) (xy 68.687056 -293.219384) (xy 68.735911 -293.225316)
			(xy 68.783182 -293.239008) (xy 68.827644 -293.260106) (xy 68.868147 -293.288062) (xy 68.90364 -293.322154)
			(xy 68.933205 -293.361498) (xy 68.956076 -293.405075) (xy 68.97166 -293.451756) (xy 68.979555 -293.500333)
			(xy 68.98005 -293.52494) (xy 69.319152 -293.52494) (xy 69.323112 -293.475886) (xy 69.334889 -293.428102)
			(xy 69.35418 -293.382826) (xy 69.380483 -293.34123) (xy 69.413118 -293.304393) (xy 69.451239 -293.273268)
			(xy 69.49386 -293.248661) (xy 69.539876 -293.231209) (xy 69.588095 -293.221365) (xy 69.63727 -293.219384)
			(xy 69.686125 -293.225316) (xy 69.733396 -293.239008) (xy 69.777858 -293.260106) (xy 69.818361 -293.288062)
			(xy 69.853854 -293.322154) (xy 69.883419 -293.361498) (xy 69.90629 -293.405075) (xy 69.921874 -293.451756)
			(xy 69.929769 -293.500333) (xy 69.930264 -293.52494) (xy 71.219072 -293.52494) (xy 71.223032 -293.475886)
			(xy 71.234809 -293.428102) (xy 71.2541 -293.382826) (xy 71.280403 -293.34123) (xy 71.313038 -293.304393)
			(xy 71.351159 -293.273268) (xy 71.39378 -293.248661) (xy 71.439796 -293.231209) (xy 71.488015 -293.221365)
			(xy 71.53719 -293.219384) (xy 71.586045 -293.225316) (xy 71.633316 -293.239008) (xy 71.677778 -293.260106)
			(xy 71.718281 -293.288062) (xy 71.753774 -293.322154) (xy 71.783339 -293.361498) (xy 71.80621 -293.405075)
			(xy 71.821794 -293.451756) (xy 71.829689 -293.500333) (xy 71.830184 -293.52494) (xy 72.169032 -293.52494)
			(xy 72.172992 -293.475886) (xy 72.184769 -293.428102) (xy 72.20406 -293.382826) (xy 72.230363 -293.34123)
			(xy 72.262998 -293.304393) (xy 72.301119 -293.273268) (xy 72.34374 -293.248661) (xy 72.389756 -293.231209)
			(xy 72.437975 -293.221365) (xy 72.48715 -293.219384) (xy 72.536005 -293.225316) (xy 72.583276 -293.239008)
			(xy 72.627738 -293.260106) (xy 72.668241 -293.288062) (xy 72.703734 -293.322154) (xy 72.733299 -293.361498)
			(xy 72.75617 -293.405075) (xy 72.771754 -293.451756) (xy 72.779649 -293.500333) (xy 72.780144 -293.52494)
			(xy 73.118992 -293.52494) (xy 73.122952 -293.475886) (xy 73.134729 -293.428102) (xy 73.15402 -293.382826)
			(xy 73.180323 -293.34123) (xy 73.212958 -293.304393) (xy 73.251079 -293.273268) (xy 73.2937 -293.248661)
			(xy 73.339716 -293.231209) (xy 73.387935 -293.221365) (xy 73.43711 -293.219384) (xy 73.485965 -293.225316)
			(xy 73.533236 -293.239008) (xy 73.577698 -293.260106) (xy 73.618201 -293.288062) (xy 73.653694 -293.322154)
			(xy 73.683259 -293.361498) (xy 73.70613 -293.405075) (xy 73.721714 -293.451756) (xy 73.729609 -293.500333)
			(xy 73.730104 -293.52494) (xy 74.069206 -293.52494) (xy 74.073166 -293.475886) (xy 74.084943 -293.428102)
			(xy 74.104234 -293.382826) (xy 74.130537 -293.34123) (xy 74.163172 -293.304393) (xy 74.201293 -293.273268)
			(xy 74.243914 -293.248661) (xy 74.28993 -293.231209) (xy 74.338149 -293.221365) (xy 74.387324 -293.219384)
			(xy 74.436179 -293.225316) (xy 74.48345 -293.239008) (xy 74.527912 -293.260106) (xy 74.568415 -293.288062)
			(xy 74.603908 -293.322154) (xy 74.633473 -293.361498) (xy 74.656344 -293.405075) (xy 74.671928 -293.451756)
			(xy 74.679823 -293.500333) (xy 74.680318 -293.52494) (xy 75.019166 -293.52494) (xy 75.023126 -293.475886)
			(xy 75.034903 -293.428102) (xy 75.054194 -293.382826) (xy 75.080497 -293.34123) (xy 75.113132 -293.304393)
			(xy 75.151253 -293.273268) (xy 75.193874 -293.248661) (xy 75.23989 -293.231209) (xy 75.288109 -293.221365)
			(xy 75.337284 -293.219384) (xy 75.386139 -293.225316) (xy 75.43341 -293.239008) (xy 75.477872 -293.260106)
			(xy 75.518375 -293.288062) (xy 75.553868 -293.322154) (xy 75.583433 -293.361498) (xy 75.606304 -293.405075)
			(xy 75.621888 -293.451756) (xy 75.629783 -293.500333) (xy 75.630278 -293.52494) (xy 75.969126 -293.52494)
			(xy 75.973086 -293.475886) (xy 75.984863 -293.428102) (xy 76.004154 -293.382826) (xy 76.030457 -293.34123)
			(xy 76.063092 -293.304393) (xy 76.101213 -293.273268) (xy 76.143834 -293.248661) (xy 76.18985 -293.231209)
			(xy 76.238069 -293.221365) (xy 76.287244 -293.219384) (xy 76.336099 -293.225316) (xy 76.38337 -293.239008)
			(xy 76.427832 -293.260106) (xy 76.468335 -293.288062) (xy 76.503828 -293.322154) (xy 76.533393 -293.361498)
			(xy 76.556264 -293.405075) (xy 76.571848 -293.451756) (xy 76.579743 -293.500333) (xy 76.580238 -293.52494)
			(xy 76.919086 -293.52494) (xy 76.923046 -293.475886) (xy 76.934823 -293.428102) (xy 76.954114 -293.382826)
			(xy 76.980417 -293.34123) (xy 77.013052 -293.304393) (xy 77.051173 -293.273268) (xy 77.093794 -293.248661)
			(xy 77.13981 -293.231209) (xy 77.188029 -293.221365) (xy 77.237204 -293.219384) (xy 77.286059 -293.225316)
			(xy 77.33333 -293.239008) (xy 77.377792 -293.260106) (xy 77.418295 -293.288062) (xy 77.453788 -293.322154)
			(xy 77.483353 -293.361498) (xy 77.506224 -293.405075) (xy 77.521808 -293.451756) (xy 77.529703 -293.500333)
			(xy 77.530198 -293.52494) (xy 77.869046 -293.52494) (xy 77.873006 -293.475886) (xy 77.884783 -293.428102)
			(xy 77.904074 -293.382826) (xy 77.930377 -293.34123) (xy 77.963012 -293.304393) (xy 78.001133 -293.273268)
			(xy 78.043754 -293.248661) (xy 78.08977 -293.231209) (xy 78.137989 -293.221365) (xy 78.187164 -293.219384)
			(xy 78.236019 -293.225316) (xy 78.28329 -293.239008) (xy 78.327752 -293.260106) (xy 78.368255 -293.288062)
			(xy 78.403748 -293.322154) (xy 78.433313 -293.361498) (xy 78.456184 -293.405075) (xy 78.471768 -293.451756)
			(xy 78.479663 -293.500333) (xy 78.480158 -293.52494) (xy 78.479663 -293.549547) (xy 78.471768 -293.598124)
			(xy 78.456184 -293.644805) (xy 78.433313 -293.688382) (xy 78.403748 -293.727726) (xy 78.368255 -293.761818)
			(xy 78.327752 -293.789774) (xy 78.28329 -293.810872) (xy 78.236019 -293.824564) (xy 78.187164 -293.830496)
			(xy 78.137989 -293.828515) (xy 78.08977 -293.818671) (xy 78.043754 -293.801219) (xy 78.001133 -293.776612)
			(xy 77.963012 -293.745487) (xy 77.930377 -293.70865) (xy 77.904074 -293.667054) (xy 77.884783 -293.621778)
			(xy 77.873006 -293.573994) (xy 77.869046 -293.52494) (xy 77.530198 -293.52494) (xy 77.529703 -293.549547)
			(xy 77.521808 -293.598124) (xy 77.506224 -293.644805) (xy 77.483353 -293.688382) (xy 77.453788 -293.727726)
			(xy 77.418295 -293.761818) (xy 77.377792 -293.789774) (xy 77.33333 -293.810872) (xy 77.286059 -293.824564)
			(xy 77.237204 -293.830496) (xy 77.188029 -293.828515) (xy 77.13981 -293.818671) (xy 77.093794 -293.801219)
			(xy 77.051173 -293.776612) (xy 77.013052 -293.745487) (xy 76.980417 -293.70865) (xy 76.954114 -293.667054)
			(xy 76.934823 -293.621778) (xy 76.923046 -293.573994) (xy 76.919086 -293.52494) (xy 76.580238 -293.52494)
			(xy 76.579743 -293.549547) (xy 76.571848 -293.598124) (xy 76.556264 -293.644805) (xy 76.533393 -293.688382)
			(xy 76.503828 -293.727726) (xy 76.468335 -293.761818) (xy 76.427832 -293.789774) (xy 76.38337 -293.810872)
			(xy 76.336099 -293.824564) (xy 76.287244 -293.830496) (xy 76.238069 -293.828515) (xy 76.18985 -293.818671)
			(xy 76.143834 -293.801219) (xy 76.101213 -293.776612) (xy 76.063092 -293.745487) (xy 76.030457 -293.70865)
			(xy 76.004154 -293.667054) (xy 75.984863 -293.621778) (xy 75.973086 -293.573994) (xy 75.969126 -293.52494)
			(xy 75.630278 -293.52494) (xy 75.629783 -293.549547) (xy 75.621888 -293.598124) (xy 75.606304 -293.644805)
			(xy 75.583433 -293.688382) (xy 75.553868 -293.727726) (xy 75.518375 -293.761818) (xy 75.477872 -293.789774)
			(xy 75.43341 -293.810872) (xy 75.386139 -293.824564) (xy 75.337284 -293.830496) (xy 75.288109 -293.828515)
			(xy 75.23989 -293.818671) (xy 75.193874 -293.801219) (xy 75.151253 -293.776612) (xy 75.113132 -293.745487)
			(xy 75.080497 -293.70865) (xy 75.054194 -293.667054) (xy 75.034903 -293.621778) (xy 75.023126 -293.573994)
			(xy 75.019166 -293.52494) (xy 74.680318 -293.52494) (xy 74.679823 -293.549547) (xy 74.671928 -293.598124)
			(xy 74.656344 -293.644805) (xy 74.633473 -293.688382) (xy 74.603908 -293.727726) (xy 74.568415 -293.761818)
			(xy 74.527912 -293.789774) (xy 74.48345 -293.810872) (xy 74.436179 -293.824564) (xy 74.387324 -293.830496)
			(xy 74.338149 -293.828515) (xy 74.28993 -293.818671) (xy 74.243914 -293.801219) (xy 74.201293 -293.776612)
			(xy 74.163172 -293.745487) (xy 74.130537 -293.70865) (xy 74.104234 -293.667054) (xy 74.084943 -293.621778)
			(xy 74.073166 -293.573994) (xy 74.069206 -293.52494) (xy 73.730104 -293.52494) (xy 73.729609 -293.549547)
			(xy 73.721714 -293.598124) (xy 73.70613 -293.644805) (xy 73.683259 -293.688382) (xy 73.653694 -293.727726)
			(xy 73.618201 -293.761818) (xy 73.577698 -293.789774) (xy 73.533236 -293.810872) (xy 73.485965 -293.824564)
			(xy 73.43711 -293.830496) (xy 73.387935 -293.828515) (xy 73.339716 -293.818671) (xy 73.2937 -293.801219)
			(xy 73.251079 -293.776612) (xy 73.212958 -293.745487) (xy 73.180323 -293.70865) (xy 73.15402 -293.667054)
			(xy 73.134729 -293.621778) (xy 73.122952 -293.573994) (xy 73.118992 -293.52494) (xy 72.780144 -293.52494)
			(xy 72.779649 -293.549547) (xy 72.771754 -293.598124) (xy 72.75617 -293.644805) (xy 72.733299 -293.688382)
			(xy 72.703734 -293.727726) (xy 72.668241 -293.761818) (xy 72.627738 -293.789774) (xy 72.583276 -293.810872)
			(xy 72.536005 -293.824564) (xy 72.48715 -293.830496) (xy 72.437975 -293.828515) (xy 72.389756 -293.818671)
			(xy 72.34374 -293.801219) (xy 72.301119 -293.776612) (xy 72.262998 -293.745487) (xy 72.230363 -293.70865)
			(xy 72.20406 -293.667054) (xy 72.184769 -293.621778) (xy 72.172992 -293.573994) (xy 72.169032 -293.52494)
			(xy 71.830184 -293.52494) (xy 71.829689 -293.549547) (xy 71.821794 -293.598124) (xy 71.80621 -293.644805)
			(xy 71.783339 -293.688382) (xy 71.753774 -293.727726) (xy 71.718281 -293.761818) (xy 71.677778 -293.789774)
			(xy 71.633316 -293.810872) (xy 71.586045 -293.824564) (xy 71.53719 -293.830496) (xy 71.488015 -293.828515)
			(xy 71.439796 -293.818671) (xy 71.39378 -293.801219) (xy 71.351159 -293.776612) (xy 71.313038 -293.745487)
			(xy 71.280403 -293.70865) (xy 71.2541 -293.667054) (xy 71.234809 -293.621778) (xy 71.223032 -293.573994)
			(xy 71.219072 -293.52494) (xy 69.930264 -293.52494) (xy 69.929769 -293.549547) (xy 69.921874 -293.598124)
			(xy 69.90629 -293.644805) (xy 69.883419 -293.688382) (xy 69.853854 -293.727726) (xy 69.818361 -293.761818)
			(xy 69.777858 -293.789774) (xy 69.733396 -293.810872) (xy 69.686125 -293.824564) (xy 69.63727 -293.830496)
			(xy 69.588095 -293.828515) (xy 69.539876 -293.818671) (xy 69.49386 -293.801219) (xy 69.451239 -293.776612)
			(xy 69.413118 -293.745487) (xy 69.380483 -293.70865) (xy 69.35418 -293.667054) (xy 69.334889 -293.621778)
			(xy 69.323112 -293.573994) (xy 69.319152 -293.52494) (xy 68.98005 -293.52494) (xy 68.979555 -293.549547)
			(xy 68.97166 -293.598124) (xy 68.956076 -293.644805) (xy 68.933205 -293.688382) (xy 68.90364 -293.727726)
			(xy 68.868147 -293.761818) (xy 68.827644 -293.789774) (xy 68.783182 -293.810872) (xy 68.735911 -293.824564)
			(xy 68.687056 -293.830496) (xy 68.637881 -293.828515) (xy 68.589662 -293.818671) (xy 68.543646 -293.801219)
			(xy 68.501025 -293.776612) (xy 68.462904 -293.745487) (xy 68.430269 -293.70865) (xy 68.403966 -293.667054)
			(xy 68.384675 -293.621778) (xy 68.372898 -293.573994) (xy 68.368938 -293.52494) (xy 68.03009 -293.52494)
			(xy 68.029595 -293.549547) (xy 68.0217 -293.598124) (xy 68.006116 -293.644805) (xy 67.983245 -293.688382)
			(xy 67.95368 -293.727726) (xy 67.918187 -293.761818) (xy 67.877684 -293.789774) (xy 67.833222 -293.810872)
			(xy 67.785951 -293.824564) (xy 67.737096 -293.830496) (xy 67.687921 -293.828515) (xy 67.639702 -293.818671)
			(xy 67.593686 -293.801219) (xy 67.551065 -293.776612) (xy 67.512944 -293.745487) (xy 67.480309 -293.70865)
			(xy 67.454006 -293.667054) (xy 67.434715 -293.621778) (xy 67.422938 -293.573994) (xy 67.418978 -293.52494)
			(xy 67.08013 -293.52494) (xy 67.079635 -293.549547) (xy 67.07174 -293.598124) (xy 67.056156 -293.644805)
			(xy 67.033285 -293.688382) (xy 67.00372 -293.727726) (xy 66.968227 -293.761818) (xy 66.927724 -293.789774)
			(xy 66.883262 -293.810872) (xy 66.835991 -293.824564) (xy 66.787136 -293.830496) (xy 66.737961 -293.828515)
			(xy 66.689742 -293.818671) (xy 66.643726 -293.801219) (xy 66.601105 -293.776612) (xy 66.562984 -293.745487)
			(xy 66.530349 -293.70865) (xy 66.504046 -293.667054) (xy 66.484755 -293.621778) (xy 66.472978 -293.573994)
			(xy 66.469018 -293.52494) (xy 66.13017 -293.52494) (xy 66.129675 -293.549547) (xy 66.12178 -293.598124)
			(xy 66.106196 -293.644805) (xy 66.083325 -293.688382) (xy 66.05376 -293.727726) (xy 66.018267 -293.761818)
			(xy 65.977764 -293.789774) (xy 65.933302 -293.810872) (xy 65.886031 -293.824564) (xy 65.837176 -293.830496)
			(xy 65.788001 -293.828515) (xy 65.739782 -293.818671) (xy 65.693766 -293.801219) (xy 65.651145 -293.776612)
			(xy 65.613024 -293.745487) (xy 65.580389 -293.70865) (xy 65.554086 -293.667054) (xy 65.534795 -293.621778)
			(xy 65.523018 -293.573994) (xy 65.519058 -293.52494) (xy 65.18021 -293.52494) (xy 65.179715 -293.549547)
			(xy 65.17182 -293.598124) (xy 65.156236 -293.644805) (xy 65.133365 -293.688382) (xy 65.1038 -293.727726)
			(xy 65.068307 -293.761818) (xy 65.027804 -293.789774) (xy 64.983342 -293.810872) (xy 64.936071 -293.824564)
			(xy 64.887216 -293.830496) (xy 64.838041 -293.828515) (xy 64.789822 -293.818671) (xy 64.743806 -293.801219)
			(xy 64.701185 -293.776612) (xy 64.663064 -293.745487) (xy 64.630429 -293.70865) (xy 64.604126 -293.667054)
			(xy 64.584835 -293.621778) (xy 64.573058 -293.573994) (xy 64.569098 -293.52494) (xy 64.23025 -293.52494)
			(xy 64.229755 -293.549547) (xy 64.22186 -293.598124) (xy 64.206276 -293.644805) (xy 64.183405 -293.688382)
			(xy 64.15384 -293.727726) (xy 64.118347 -293.761818) (xy 64.077844 -293.789774) (xy 64.033382 -293.810872)
			(xy 63.986111 -293.824564) (xy 63.937256 -293.830496) (xy 63.888081 -293.828515) (xy 63.839862 -293.818671)
			(xy 63.793846 -293.801219) (xy 63.751225 -293.776612) (xy 63.713104 -293.745487) (xy 63.680469 -293.70865)
			(xy 63.654166 -293.667054) (xy 63.634875 -293.621778) (xy 63.623098 -293.573994) (xy 63.619138 -293.52494)
			(xy 63.28029 -293.52494) (xy 63.279795 -293.549547) (xy 63.2719 -293.598124) (xy 63.256316 -293.644805)
			(xy 63.233445 -293.688382) (xy 63.20388 -293.727726) (xy 63.168387 -293.761818) (xy 63.127884 -293.789774)
			(xy 63.083422 -293.810872) (xy 63.036151 -293.824564) (xy 62.987296 -293.830496) (xy 62.938121 -293.828515)
			(xy 62.889902 -293.818671) (xy 62.843886 -293.801219) (xy 62.801265 -293.776612) (xy 62.763144 -293.745487)
			(xy 62.730509 -293.70865) (xy 62.704206 -293.667054) (xy 62.684915 -293.621778) (xy 62.673138 -293.573994)
			(xy 62.669178 -293.52494) (xy 62.330076 -293.52494) (xy 62.329581 -293.549547) (xy 62.321686 -293.598124)
			(xy 62.306102 -293.644805) (xy 62.283231 -293.688382) (xy 62.253666 -293.727726) (xy 62.218173 -293.761818)
			(xy 62.17767 -293.789774) (xy 62.133208 -293.810872) (xy 62.085937 -293.824564) (xy 62.037082 -293.830496)
			(xy 61.987907 -293.828515) (xy 61.939688 -293.818671) (xy 61.893672 -293.801219) (xy 61.851051 -293.776612)
			(xy 61.81293 -293.745487) (xy 61.780295 -293.70865) (xy 61.753992 -293.667054) (xy 61.734701 -293.621778)
			(xy 61.722924 -293.573994) (xy 61.718964 -293.52494) (xy 61.380116 -293.52494) (xy 61.379621 -293.549547)
			(xy 61.371726 -293.598124) (xy 61.356142 -293.644805) (xy 61.333271 -293.688382) (xy 61.303706 -293.727726)
			(xy 61.268213 -293.761818) (xy 61.22771 -293.789774) (xy 61.183248 -293.810872) (xy 61.135977 -293.824564)
			(xy 61.087122 -293.830496) (xy 61.037947 -293.828515) (xy 60.989728 -293.818671) (xy 60.943712 -293.801219)
			(xy 60.901091 -293.776612) (xy 60.86297 -293.745487) (xy 60.830335 -293.70865) (xy 60.804032 -293.667054)
			(xy 60.784741 -293.621778) (xy 60.772964 -293.573994) (xy 60.769004 -293.52494) (xy 60.430156 -293.52494)
			(xy 60.429661 -293.549547) (xy 60.421766 -293.598124) (xy 60.406182 -293.644805) (xy 60.383311 -293.688382)
			(xy 60.353746 -293.727726) (xy 60.318253 -293.761818) (xy 60.27775 -293.789774) (xy 60.233288 -293.810872)
			(xy 60.186017 -293.824564) (xy 60.137162 -293.830496) (xy 60.087987 -293.828515) (xy 60.039768 -293.818671)
			(xy 59.993752 -293.801219) (xy 59.951131 -293.776612) (xy 59.91301 -293.745487) (xy 59.880375 -293.70865)
			(xy 59.854072 -293.667054) (xy 59.834781 -293.621778) (xy 59.823004 -293.573994) (xy 59.819044 -293.52494)
			(xy 58.530236 -293.52494) (xy 58.529741 -293.549547) (xy 58.521846 -293.598124) (xy 58.506262 -293.644805)
			(xy 58.483391 -293.688382) (xy 58.453826 -293.727726) (xy 58.418333 -293.761818) (xy 58.37783 -293.789774)
			(xy 58.333368 -293.810872) (xy 58.286097 -293.824564) (xy 58.237242 -293.830496) (xy 58.188067 -293.828515)
			(xy 58.139848 -293.818671) (xy 58.093832 -293.801219) (xy 58.051211 -293.776612) (xy 58.01309 -293.745487)
			(xy 57.980455 -293.70865) (xy 57.954152 -293.667054) (xy 57.934861 -293.621778) (xy 57.923084 -293.573994)
			(xy 57.919124 -293.52494) (xy 57.580276 -293.52494) (xy 57.579781 -293.549547) (xy 57.571886 -293.598124)
			(xy 57.556302 -293.644805) (xy 57.533431 -293.688382) (xy 57.503866 -293.727726) (xy 57.468373 -293.761818)
			(xy 57.42787 -293.789774) (xy 57.383408 -293.810872) (xy 57.336137 -293.824564) (xy 57.287282 -293.830496)
			(xy 57.238107 -293.828515) (xy 57.189888 -293.818671) (xy 57.143872 -293.801219) (xy 57.101251 -293.776612)
			(xy 57.06313 -293.745487) (xy 57.030495 -293.70865) (xy 57.004192 -293.667054) (xy 56.984901 -293.621778)
			(xy 56.973124 -293.573994) (xy 56.969164 -293.52494) (xy 56.630062 -293.52494) (xy 56.629567 -293.549547)
			(xy 56.621672 -293.598124) (xy 56.606088 -293.644805) (xy 56.583217 -293.688382) (xy 56.553652 -293.727726)
			(xy 56.518159 -293.761818) (xy 56.477656 -293.789774) (xy 56.433194 -293.810872) (xy 56.385923 -293.824564)
			(xy 56.337068 -293.830496) (xy 56.287893 -293.828515) (xy 56.239674 -293.818671) (xy 56.193658 -293.801219)
			(xy 56.151037 -293.776612) (xy 56.112916 -293.745487) (xy 56.080281 -293.70865) (xy 56.053978 -293.667054)
			(xy 56.034687 -293.621778) (xy 56.02291 -293.573994) (xy 56.01895 -293.52494) (xy 55.680102 -293.52494)
			(xy 55.679607 -293.549547) (xy 55.671712 -293.598124) (xy 55.656128 -293.644805) (xy 55.633257 -293.688382)
			(xy 55.603692 -293.727726) (xy 55.568199 -293.761818) (xy 55.527696 -293.789774) (xy 55.483234 -293.810872)
			(xy 55.435963 -293.824564) (xy 55.387108 -293.830496) (xy 55.337933 -293.828515) (xy 55.289714 -293.818671)
			(xy 55.243698 -293.801219) (xy 55.201077 -293.776612) (xy 55.162956 -293.745487) (xy 55.130321 -293.70865)
			(xy 55.104018 -293.667054) (xy 55.084727 -293.621778) (xy 55.07295 -293.573994) (xy 55.06899 -293.52494)
			(xy 54.730142 -293.52494) (xy 54.729647 -293.549547) (xy 54.721752 -293.598124) (xy 54.706168 -293.644805)
			(xy 54.683297 -293.688382) (xy 54.653732 -293.727726) (xy 54.618239 -293.761818) (xy 54.577736 -293.789774)
			(xy 54.533274 -293.810872) (xy 54.486003 -293.824564) (xy 54.437148 -293.830496) (xy 54.387973 -293.828515)
			(xy 54.339754 -293.818671) (xy 54.293738 -293.801219) (xy 54.251117 -293.776612) (xy 54.212996 -293.745487)
			(xy 54.180361 -293.70865) (xy 54.154058 -293.667054) (xy 54.134767 -293.621778) (xy 54.12299 -293.573994)
			(xy 54.11903 -293.52494) (xy 53.780182 -293.52494) (xy 53.779687 -293.549547) (xy 53.771792 -293.598124)
			(xy 53.756208 -293.644805) (xy 53.733337 -293.688382) (xy 53.703772 -293.727726) (xy 53.668279 -293.761818)
			(xy 53.627776 -293.789774) (xy 53.583314 -293.810872) (xy 53.536043 -293.824564) (xy 53.487188 -293.830496)
			(xy 53.438013 -293.828515) (xy 53.389794 -293.818671) (xy 53.343778 -293.801219) (xy 53.301157 -293.776612)
			(xy 53.263036 -293.745487) (xy 53.230401 -293.70865) (xy 53.204098 -293.667054) (xy 53.184807 -293.621778)
			(xy 53.17303 -293.573994) (xy 53.16907 -293.52494) (xy 52.830222 -293.52494) (xy 52.829727 -293.549547)
			(xy 52.821832 -293.598124) (xy 52.806248 -293.644805) (xy 52.783377 -293.688382) (xy 52.753812 -293.727726)
			(xy 52.718319 -293.761818) (xy 52.677816 -293.789774) (xy 52.633354 -293.810872) (xy 52.586083 -293.824564)
			(xy 52.537228 -293.830496) (xy 52.488053 -293.828515) (xy 52.439834 -293.818671) (xy 52.393818 -293.801219)
			(xy 52.351197 -293.776612) (xy 52.313076 -293.745487) (xy 52.280441 -293.70865) (xy 52.254138 -293.667054)
			(xy 52.234847 -293.621778) (xy 52.22307 -293.573994) (xy 52.21911 -293.52494) (xy 51.880262 -293.52494)
			(xy 51.879767 -293.549547) (xy 51.871872 -293.598124) (xy 51.856288 -293.644805) (xy 51.833417 -293.688382)
			(xy 51.803852 -293.727726) (xy 51.768359 -293.761818) (xy 51.727856 -293.789774) (xy 51.683394 -293.810872)
			(xy 51.636123 -293.824564) (xy 51.587268 -293.830496) (xy 51.538093 -293.828515) (xy 51.489874 -293.818671)
			(xy 51.443858 -293.801219) (xy 51.401237 -293.776612) (xy 51.363116 -293.745487) (xy 51.330481 -293.70865)
			(xy 51.304178 -293.667054) (xy 51.284887 -293.621778) (xy 51.27311 -293.573994) (xy 51.26915 -293.52494)
			(xy 50.930302 -293.52494) (xy 50.929807 -293.549547) (xy 50.921912 -293.598124) (xy 50.906328 -293.644805)
			(xy 50.883457 -293.688382) (xy 50.853892 -293.727726) (xy 50.818399 -293.761818) (xy 50.777896 -293.789774)
			(xy 50.733434 -293.810872) (xy 50.686163 -293.824564) (xy 50.637308 -293.830496) (xy 50.588133 -293.828515)
			(xy 50.539914 -293.818671) (xy 50.493898 -293.801219) (xy 50.451277 -293.776612) (xy 50.413156 -293.745487)
			(xy 50.380521 -293.70865) (xy 50.354218 -293.667054) (xy 50.334927 -293.621778) (xy 50.32315 -293.573994)
			(xy 50.31919 -293.52494) (xy 49.980088 -293.52494) (xy 49.979593 -293.549547) (xy 49.971698 -293.598124)
			(xy 49.956114 -293.644805) (xy 49.933243 -293.688382) (xy 49.903678 -293.727726) (xy 49.868185 -293.761818)
			(xy 49.827682 -293.789774) (xy 49.78322 -293.810872) (xy 49.735949 -293.824564) (xy 49.687094 -293.830496)
			(xy 49.637919 -293.828515) (xy 49.5897 -293.818671) (xy 49.543684 -293.801219) (xy 49.501063 -293.776612)
			(xy 49.462942 -293.745487) (xy 49.430307 -293.70865) (xy 49.404004 -293.667054) (xy 49.384713 -293.621778)
			(xy 49.372936 -293.573994) (xy 49.368976 -293.52494) (xy 49.030128 -293.52494) (xy 49.029633 -293.549547)
			(xy 49.021738 -293.598124) (xy 49.006154 -293.644805) (xy 48.983283 -293.688382) (xy 48.953718 -293.727726)
			(xy 48.918225 -293.761818) (xy 48.877722 -293.789774) (xy 48.83326 -293.810872) (xy 48.785989 -293.824564)
			(xy 48.737134 -293.830496) (xy 48.687959 -293.828515) (xy 48.63974 -293.818671) (xy 48.593724 -293.801219)
			(xy 48.551103 -293.776612) (xy 48.512982 -293.745487) (xy 48.480347 -293.70865) (xy 48.454044 -293.667054)
			(xy 48.434753 -293.621778) (xy 48.422976 -293.573994) (xy 48.419016 -293.52494) (xy 48.080168 -293.52494)
			(xy 48.079673 -293.549547) (xy 48.071778 -293.598124) (xy 48.056194 -293.644805) (xy 48.033323 -293.688382)
			(xy 48.003758 -293.727726) (xy 47.968265 -293.761818) (xy 47.927762 -293.789774) (xy 47.8833 -293.810872)
			(xy 47.836029 -293.824564) (xy 47.787174 -293.830496) (xy 47.737999 -293.828515) (xy 47.68978 -293.818671)
			(xy 47.643764 -293.801219) (xy 47.601143 -293.776612) (xy 47.563022 -293.745487) (xy 47.530387 -293.70865)
			(xy 47.504084 -293.667054) (xy 47.484793 -293.621778) (xy 47.473016 -293.573994) (xy 47.469056 -293.52494)
			(xy 46.180248 -293.52494) (xy 46.179753 -293.549547) (xy 46.171858 -293.598124) (xy 46.156274 -293.644805)
			(xy 46.133403 -293.688382) (xy 46.103838 -293.727726) (xy 46.068345 -293.761818) (xy 46.027842 -293.789774)
			(xy 45.98338 -293.810872) (xy 45.936109 -293.824564) (xy 45.887254 -293.830496) (xy 45.838079 -293.828515)
			(xy 45.78986 -293.818671) (xy 45.743844 -293.801219) (xy 45.701223 -293.776612) (xy 45.663102 -293.745487)
			(xy 45.630467 -293.70865) (xy 45.604164 -293.667054) (xy 45.584873 -293.621778) (xy 45.573096 -293.573994)
			(xy 45.569136 -293.52494) (xy 44.280074 -293.52494) (xy 44.279579 -293.549547) (xy 44.271684 -293.598124)
			(xy 44.2561 -293.644805) (xy 44.233229 -293.688382) (xy 44.203664 -293.727726) (xy 44.168171 -293.761818)
			(xy 44.127668 -293.789774) (xy 44.083206 -293.810872) (xy 44.035935 -293.824564) (xy 43.98708 -293.830496)
			(xy 43.937905 -293.828515) (xy 43.889686 -293.818671) (xy 43.84367 -293.801219) (xy 43.801049 -293.776612)
			(xy 43.762928 -293.745487) (xy 43.730293 -293.70865) (xy 43.70399 -293.667054) (xy 43.684699 -293.621778)
			(xy 43.672922 -293.573994) (xy 43.668962 -293.52494) (xy 43.380914 -293.52494) (xy 43.380416 -293.551589)
			(xy 43.372473 -293.604293) (xy 43.356763 -293.655223) (xy 43.333637 -293.703244) (xy 43.303613 -293.747281)
			(xy 43.267361 -293.786352) (xy 43.22569 -293.819583) (xy 43.179532 -293.846232) (xy 43.129918 -293.865704)
			(xy 43.077956 -293.877564) (xy 43.024806 -293.881548) (xy 42.971656 -293.877564) (xy 42.919694 -293.865704)
			(xy 42.87008 -293.846232) (xy 42.823922 -293.819583) (xy 42.782251 -293.786352) (xy 42.745999 -293.747281)
			(xy 42.715975 -293.703244) (xy 42.692849 -293.655223) (xy 42.677139 -293.604293) (xy 42.669196 -293.551589)
			(xy 42.379327 -293.551589) (xy 42.371764 -293.598124) (xy 42.35618 -293.644805) (xy 42.333309 -293.688382)
			(xy 42.303744 -293.727726) (xy 42.268251 -293.761818) (xy 42.227748 -293.789774) (xy 42.183286 -293.810872)
			(xy 42.136015 -293.824564) (xy 42.08716 -293.830496) (xy 42.037985 -293.828515) (xy 41.989766 -293.818671)
			(xy 41.94375 -293.801219) (xy 41.901129 -293.776612) (xy 41.863008 -293.745487) (xy 41.830373 -293.70865)
			(xy 41.80407 -293.667054) (xy 41.784779 -293.621778) (xy 41.773002 -293.573994) (xy 41.769042 -293.52494)
			(xy 41.430194 -293.52494) (xy 41.429699 -293.549547) (xy 41.421804 -293.598124) (xy 41.40622 -293.644805)
			(xy 41.383349 -293.688382) (xy 41.353784 -293.727726) (xy 41.318291 -293.761818) (xy 41.277788 -293.789774)
			(xy 41.233326 -293.810872) (xy 41.186055 -293.824564) (xy 41.1372 -293.830496) (xy 41.088025 -293.828515)
			(xy 41.039806 -293.818671) (xy 40.99379 -293.801219) (xy 40.951169 -293.776612) (xy 40.913048 -293.745487)
			(xy 40.880413 -293.70865) (xy 40.85411 -293.667054) (xy 40.834819 -293.621778) (xy 40.823042 -293.573994)
			(xy 40.819082 -293.52494) (xy 40.480234 -293.52494) (xy 40.479739 -293.549547) (xy 40.471844 -293.598124)
			(xy 40.45626 -293.644805) (xy 40.433389 -293.688382) (xy 40.403824 -293.727726) (xy 40.368331 -293.761818)
			(xy 40.327828 -293.789774) (xy 40.283366 -293.810872) (xy 40.236095 -293.824564) (xy 40.18724 -293.830496)
			(xy 40.138065 -293.828515) (xy 40.089846 -293.818671) (xy 40.04383 -293.801219) (xy 40.001209 -293.776612)
			(xy 39.963088 -293.745487) (xy 39.930453 -293.70865) (xy 39.90415 -293.667054) (xy 39.884859 -293.621778)
			(xy 39.873082 -293.573994) (xy 39.869122 -293.52494) (xy 39.530274 -293.52494) (xy 39.529779 -293.549547)
			(xy 39.521884 -293.598124) (xy 39.5063 -293.644805) (xy 39.483429 -293.688382) (xy 39.453864 -293.727726)
			(xy 39.418371 -293.761818) (xy 39.377868 -293.789774) (xy 39.333406 -293.810872) (xy 39.286135 -293.824564)
			(xy 39.23728 -293.830496) (xy 39.188105 -293.828515) (xy 39.139886 -293.818671) (xy 39.09387 -293.801219)
			(xy 39.051249 -293.776612) (xy 39.013128 -293.745487) (xy 38.980493 -293.70865) (xy 38.95419 -293.667054)
			(xy 38.934899 -293.621778) (xy 38.923122 -293.573994) (xy 38.919162 -293.52494) (xy 38.580314 -293.52494)
			(xy 38.579819 -293.549547) (xy 38.571924 -293.598124) (xy 38.55634 -293.644805) (xy 38.533469 -293.688382)
			(xy 38.503904 -293.727726) (xy 38.468411 -293.761818) (xy 38.427908 -293.789774) (xy 38.383446 -293.810872)
			(xy 38.336175 -293.824564) (xy 38.28732 -293.830496) (xy 38.238145 -293.828515) (xy 38.189926 -293.818671)
			(xy 38.14391 -293.801219) (xy 38.101289 -293.776612) (xy 38.063168 -293.745487) (xy 38.030533 -293.70865)
			(xy 38.00423 -293.667054) (xy 37.984939 -293.621778) (xy 37.973162 -293.573994) (xy 37.969202 -293.52494)
			(xy 34.383635 -293.52494) (xy 34.375859 -293.577776) (xy 34.359791 -293.631183) (xy 34.336119 -293.68168)
			(xy 34.305346 -293.728193) (xy 34.268129 -293.76973) (xy 34.225261 -293.805405) (xy 34.177655 -293.834459)
			(xy 34.126326 -293.856271) (xy 34.072369 -293.870377) (xy 34.016932 -293.876477) (xy 33.961198 -293.87444)
			(xy 33.906355 -293.86431) (xy 33.853571 -293.846303) (xy 33.803971 -293.820802) (xy 33.758613 -293.788351)
			(xy 33.718464 -293.749642) (xy 33.684378 -293.705499) (xy 33.657082 -293.656864) (xy 33.637159 -293.604773)
			(xy 33.625033 -293.550336) (xy 33.620962 -293.494714) (xy 33.498028 -293.494714) (xy 33.497519 -293.5226)
			(xy 33.489399 -293.577776) (xy 33.473331 -293.631183) (xy 33.449659 -293.68168) (xy 33.418886 -293.728193)
			(xy 33.381669 -293.76973) (xy 33.338801 -293.805405) (xy 33.291195 -293.834459) (xy 33.239866 -293.856271)
			(xy 33.185909 -293.870377) (xy 33.130472 -293.876477) (xy 33.074738 -293.87444) (xy 33.019895 -293.86431)
			(xy 32.967111 -293.846303) (xy 32.917511 -293.820802) (xy 32.872153 -293.788351) (xy 32.832004 -293.749642)
			(xy 32.797918 -293.705499) (xy 32.770622 -293.656864) (xy 32.750699 -293.604773) (xy 32.738573 -293.550336)
			(xy 32.734502 -293.494714) (xy 32.101028 -293.494714) (xy 32.100542 -293.521965) (xy 32.092786 -293.575913)
			(xy 32.077431 -293.628208) (xy 32.054789 -293.677785) (xy 32.025323 -293.723635) (xy 31.989632 -293.764826)
			(xy 31.948441 -293.800517) (xy 31.902591 -293.829983) (xy 31.853014 -293.852625) (xy 31.800719 -293.86798)
			(xy 31.746771 -293.875736) (xy 31.692269 -293.875736) (xy 31.638321 -293.86798) (xy 31.586026 -293.852625)
			(xy 31.536449 -293.829983) (xy 31.490599 -293.800517) (xy 31.449408 -293.764826) (xy 31.413717 -293.723635)
			(xy 31.384251 -293.677785) (xy 31.361609 -293.628208) (xy 31.346254 -293.575913) (xy 31.338498 -293.521965)
			(xy 31.338012 -293.494714) (xy 1.660398 -293.494714) (xy 1.660398 -294.630856) (xy 25.811478 -294.630856)
			(xy 25.815549 -294.575234) (xy 25.827675 -294.520797) (xy 25.847598 -294.468706) (xy 25.874894 -294.420071)
			(xy 25.90898 -294.375928) (xy 25.949129 -294.337219) (xy 25.994487 -294.304768) (xy 26.044087 -294.279267)
			(xy 26.096871 -294.26126) (xy 26.151714 -294.25113) (xy 26.207448 -294.249093) (xy 26.262885 -294.255193)
			(xy 26.316842 -294.269299) (xy 26.368171 -294.291111) (xy 26.415777 -294.320165) (xy 26.458645 -294.35584)
			(xy 26.495862 -294.397377) (xy 26.526635 -294.44389) (xy 26.550307 -294.494387) (xy 26.566375 -294.547794)
			(xy 26.574495 -294.60297) (xy 26.575004 -294.630856) (xy 27.296616 -294.630856) (xy 27.300687 -294.575234)
			(xy 27.312813 -294.520797) (xy 27.332736 -294.468706) (xy 27.360032 -294.420071) (xy 27.394118 -294.375928)
			(xy 27.434267 -294.337219) (xy 27.479625 -294.304768) (xy 27.529225 -294.279267) (xy 27.582009 -294.26126)
			(xy 27.636852 -294.25113) (xy 27.692586 -294.249093) (xy 27.748023 -294.255193) (xy 27.80198 -294.269299)
			(xy 27.853309 -294.291111) (xy 27.900915 -294.320165) (xy 27.943783 -294.35584) (xy 27.981 -294.397377)
			(xy 28.011773 -294.44389) (xy 28.02631 -294.4749) (xy 36.069028 -294.4749) (xy 36.072988 -294.425846)
			(xy 36.084765 -294.378062) (xy 36.104056 -294.332786) (xy 36.130359 -294.29119) (xy 36.162994 -294.254353)
			(xy 36.201115 -294.223228) (xy 36.243736 -294.198621) (xy 36.289752 -294.181169) (xy 36.337971 -294.171325)
			(xy 36.387146 -294.169344) (xy 36.436001 -294.175276) (xy 36.483272 -294.188968) (xy 36.527734 -294.210066)
			(xy 36.568237 -294.238022) (xy 36.60373 -294.272114) (xy 36.633295 -294.311458) (xy 36.656166 -294.355035)
			(xy 36.67175 -294.401716) (xy 36.679645 -294.450293) (xy 36.68014 -294.4749) (xy 37.018988 -294.4749)
			(xy 37.022948 -294.425846) (xy 37.034725 -294.378062) (xy 37.054016 -294.332786) (xy 37.080319 -294.29119)
			(xy 37.112954 -294.254353) (xy 37.151075 -294.223228) (xy 37.193696 -294.198621) (xy 37.239712 -294.181169)
			(xy 37.287931 -294.171325) (xy 37.337106 -294.169344) (xy 37.385961 -294.175276) (xy 37.433232 -294.188968)
			(xy 37.477694 -294.210066) (xy 37.518197 -294.238022) (xy 37.55369 -294.272114) (xy 37.583255 -294.311458)
			(xy 37.606126 -294.355035) (xy 37.62171 -294.401716) (xy 37.629605 -294.450293) (xy 37.6301 -294.4749)
			(xy 37.969202 -294.4749) (xy 37.973162 -294.425846) (xy 37.984939 -294.378062) (xy 38.00423 -294.332786)
			(xy 38.030533 -294.29119) (xy 38.063168 -294.254353) (xy 38.101289 -294.223228) (xy 38.14391 -294.198621)
			(xy 38.189926 -294.181169) (xy 38.238145 -294.171325) (xy 38.28732 -294.169344) (xy 38.336175 -294.175276)
			(xy 38.383446 -294.188968) (xy 38.427908 -294.210066) (xy 38.468411 -294.238022) (xy 38.503904 -294.272114)
			(xy 38.533469 -294.311458) (xy 38.55634 -294.355035) (xy 38.571924 -294.401716) (xy 38.579819 -294.450293)
			(xy 38.580314 -294.4749) (xy 40.819082 -294.4749) (xy 40.823042 -294.425846) (xy 40.834819 -294.378062)
			(xy 40.85411 -294.332786) (xy 40.880413 -294.29119) (xy 40.913048 -294.254353) (xy 40.951169 -294.223228)
			(xy 40.99379 -294.198621) (xy 41.039806 -294.181169) (xy 41.088025 -294.171325) (xy 41.1372 -294.169344)
			(xy 41.186055 -294.175276) (xy 41.233326 -294.188968) (xy 41.277788 -294.210066) (xy 41.318291 -294.238022)
			(xy 41.353784 -294.272114) (xy 41.383349 -294.311458) (xy 41.40622 -294.355035) (xy 41.421804 -294.401716)
			(xy 41.429699 -294.450293) (xy 41.430194 -294.4749) (xy 41.429699 -294.499507) (xy 41.429367 -294.501549)
			(xy 41.719236 -294.501549) (xy 41.719236 -294.448251) (xy 41.727179 -294.395547) (xy 41.742889 -294.344617)
			(xy 41.766015 -294.296596) (xy 41.796039 -294.252559) (xy 41.832291 -294.213488) (xy 41.873962 -294.180257)
			(xy 41.92012 -294.153608) (xy 41.969734 -294.134136) (xy 42.021696 -294.122276) (xy 42.074846 -294.118293)
			(xy 42.127996 -294.122276) (xy 42.179958 -294.134136) (xy 42.229572 -294.153608) (xy 42.27573 -294.180257)
			(xy 42.317401 -294.213488) (xy 42.353653 -294.252559) (xy 42.383677 -294.296596) (xy 42.406803 -294.344617)
			(xy 42.422513 -294.395547) (xy 42.430456 -294.448251) (xy 42.430954 -294.4749) (xy 42.719002 -294.4749)
			(xy 42.722962 -294.425846) (xy 42.734739 -294.378062) (xy 42.75403 -294.332786) (xy 42.780333 -294.29119)
			(xy 42.812968 -294.254353) (xy 42.851089 -294.223228) (xy 42.89371 -294.198621) (xy 42.939726 -294.181169)
			(xy 42.987945 -294.171325) (xy 43.03712 -294.169344) (xy 43.085975 -294.175276) (xy 43.133246 -294.188968)
			(xy 43.177708 -294.210066) (xy 43.218211 -294.238022) (xy 43.253704 -294.272114) (xy 43.283269 -294.311458)
			(xy 43.30614 -294.355035) (xy 43.321724 -294.401716) (xy 43.329619 -294.450293) (xy 43.330114 -294.4749)
			(xy 43.668962 -294.4749) (xy 43.672922 -294.425846) (xy 43.684699 -294.378062) (xy 43.70399 -294.332786)
			(xy 43.730293 -294.29119) (xy 43.762928 -294.254353) (xy 43.801049 -294.223228) (xy 43.84367 -294.198621)
			(xy 43.889686 -294.181169) (xy 43.937905 -294.171325) (xy 43.98708 -294.169344) (xy 44.035935 -294.175276)
			(xy 44.083206 -294.188968) (xy 44.127668 -294.210066) (xy 44.168171 -294.238022) (xy 44.203664 -294.272114)
			(xy 44.233229 -294.311458) (xy 44.2561 -294.355035) (xy 44.271684 -294.401716) (xy 44.279579 -294.450293)
			(xy 44.280074 -294.4749) (xy 44.619176 -294.4749) (xy 44.623136 -294.425846) (xy 44.634913 -294.378062)
			(xy 44.654204 -294.332786) (xy 44.680507 -294.29119) (xy 44.713142 -294.254353) (xy 44.751263 -294.223228)
			(xy 44.793884 -294.198621) (xy 44.8399 -294.181169) (xy 44.888119 -294.171325) (xy 44.937294 -294.169344)
			(xy 44.986149 -294.175276) (xy 45.03342 -294.188968) (xy 45.077882 -294.210066) (xy 45.118385 -294.238022)
			(xy 45.153878 -294.272114) (xy 45.183443 -294.311458) (xy 45.206314 -294.355035) (xy 45.221898 -294.401716)
			(xy 45.229793 -294.450293) (xy 45.230288 -294.4749) (xy 45.569136 -294.4749) (xy 45.573096 -294.425846)
			(xy 45.584873 -294.378062) (xy 45.604164 -294.332786) (xy 45.630467 -294.29119) (xy 45.663102 -294.254353)
			(xy 45.701223 -294.223228) (xy 45.743844 -294.198621) (xy 45.78986 -294.181169) (xy 45.838079 -294.171325)
			(xy 45.887254 -294.169344) (xy 45.936109 -294.175276) (xy 45.98338 -294.188968) (xy 46.027842 -294.210066)
			(xy 46.068345 -294.238022) (xy 46.103838 -294.272114) (xy 46.133403 -294.311458) (xy 46.156274 -294.355035)
			(xy 46.171858 -294.401716) (xy 46.179753 -294.450293) (xy 46.180248 -294.4749) (xy 46.519096 -294.4749)
			(xy 46.523056 -294.425846) (xy 46.534833 -294.378062) (xy 46.554124 -294.332786) (xy 46.580427 -294.29119)
			(xy 46.613062 -294.254353) (xy 46.651183 -294.223228) (xy 46.693804 -294.198621) (xy 46.73982 -294.181169)
			(xy 46.788039 -294.171325) (xy 46.837214 -294.169344) (xy 46.886069 -294.175276) (xy 46.93334 -294.188968)
			(xy 46.977802 -294.210066) (xy 47.018305 -294.238022) (xy 47.053798 -294.272114) (xy 47.083363 -294.311458)
			(xy 47.106234 -294.355035) (xy 47.121818 -294.401716) (xy 47.129713 -294.450293) (xy 47.130208 -294.4749)
			(xy 47.469056 -294.4749) (xy 47.473016 -294.425846) (xy 47.484793 -294.378062) (xy 47.504084 -294.332786)
			(xy 47.530387 -294.29119) (xy 47.563022 -294.254353) (xy 47.601143 -294.223228) (xy 47.643764 -294.198621)
			(xy 47.68978 -294.181169) (xy 47.737999 -294.171325) (xy 47.787174 -294.169344) (xy 47.836029 -294.175276)
			(xy 47.8833 -294.188968) (xy 47.927762 -294.210066) (xy 47.968265 -294.238022) (xy 48.003758 -294.272114)
			(xy 48.033323 -294.311458) (xy 48.056194 -294.355035) (xy 48.071778 -294.401716) (xy 48.079673 -294.450293)
			(xy 48.080168 -294.4749) (xy 48.419016 -294.4749) (xy 48.422976 -294.425846) (xy 48.434753 -294.378062)
			(xy 48.454044 -294.332786) (xy 48.480347 -294.29119) (xy 48.512982 -294.254353) (xy 48.551103 -294.223228)
			(xy 48.593724 -294.198621) (xy 48.63974 -294.181169) (xy 48.687959 -294.171325) (xy 48.737134 -294.169344)
			(xy 48.785989 -294.175276) (xy 48.83326 -294.188968) (xy 48.877722 -294.210066) (xy 48.918225 -294.238022)
			(xy 48.953718 -294.272114) (xy 48.983283 -294.311458) (xy 49.006154 -294.355035) (xy 49.021738 -294.401716)
			(xy 49.029633 -294.450293) (xy 49.030128 -294.4749) (xy 49.368976 -294.4749) (xy 49.372936 -294.425846)
			(xy 49.384713 -294.378062) (xy 49.404004 -294.332786) (xy 49.430307 -294.29119) (xy 49.462942 -294.254353)
			(xy 49.501063 -294.223228) (xy 49.543684 -294.198621) (xy 49.5897 -294.181169) (xy 49.637919 -294.171325)
			(xy 49.687094 -294.169344) (xy 49.735949 -294.175276) (xy 49.78322 -294.188968) (xy 49.827682 -294.210066)
			(xy 49.868185 -294.238022) (xy 49.903678 -294.272114) (xy 49.933243 -294.311458) (xy 49.956114 -294.355035)
			(xy 49.971698 -294.401716) (xy 49.979593 -294.450293) (xy 49.980088 -294.4749) (xy 50.31919 -294.4749)
			(xy 50.32315 -294.425846) (xy 50.334927 -294.378062) (xy 50.354218 -294.332786) (xy 50.380521 -294.29119)
			(xy 50.413156 -294.254353) (xy 50.451277 -294.223228) (xy 50.493898 -294.198621) (xy 50.539914 -294.181169)
			(xy 50.588133 -294.171325) (xy 50.637308 -294.169344) (xy 50.686163 -294.175276) (xy 50.733434 -294.188968)
			(xy 50.777896 -294.210066) (xy 50.818399 -294.238022) (xy 50.853892 -294.272114) (xy 50.883457 -294.311458)
			(xy 50.906328 -294.355035) (xy 50.921912 -294.401716) (xy 50.929807 -294.450293) (xy 50.930302 -294.4749)
			(xy 51.26915 -294.4749) (xy 51.27311 -294.425846) (xy 51.284887 -294.378062) (xy 51.304178 -294.332786)
			(xy 51.330481 -294.29119) (xy 51.363116 -294.254353) (xy 51.401237 -294.223228) (xy 51.443858 -294.198621)
			(xy 51.489874 -294.181169) (xy 51.538093 -294.171325) (xy 51.587268 -294.169344) (xy 51.636123 -294.175276)
			(xy 51.683394 -294.188968) (xy 51.727856 -294.210066) (xy 51.768359 -294.238022) (xy 51.803852 -294.272114)
			(xy 51.833417 -294.311458) (xy 51.856288 -294.355035) (xy 51.871872 -294.401716) (xy 51.879767 -294.450293)
			(xy 51.880262 -294.4749) (xy 52.21911 -294.4749) (xy 52.22307 -294.425846) (xy 52.234847 -294.378062)
			(xy 52.254138 -294.332786) (xy 52.280441 -294.29119) (xy 52.313076 -294.254353) (xy 52.351197 -294.223228)
			(xy 52.393818 -294.198621) (xy 52.439834 -294.181169) (xy 52.488053 -294.171325) (xy 52.537228 -294.169344)
			(xy 52.586083 -294.175276) (xy 52.633354 -294.188968) (xy 52.677816 -294.210066) (xy 52.718319 -294.238022)
			(xy 52.753812 -294.272114) (xy 52.783377 -294.311458) (xy 52.806248 -294.355035) (xy 52.821832 -294.401716)
			(xy 52.829727 -294.450293) (xy 52.830222 -294.4749) (xy 53.16907 -294.4749) (xy 53.17303 -294.425846)
			(xy 53.184807 -294.378062) (xy 53.204098 -294.332786) (xy 53.230401 -294.29119) (xy 53.263036 -294.254353)
			(xy 53.301157 -294.223228) (xy 53.343778 -294.198621) (xy 53.389794 -294.181169) (xy 53.438013 -294.171325)
			(xy 53.487188 -294.169344) (xy 53.536043 -294.175276) (xy 53.583314 -294.188968) (xy 53.627776 -294.210066)
			(xy 53.668279 -294.238022) (xy 53.703772 -294.272114) (xy 53.733337 -294.311458) (xy 53.756208 -294.355035)
			(xy 53.771792 -294.401716) (xy 53.779687 -294.450293) (xy 53.780182 -294.4749) (xy 54.11903 -294.4749)
			(xy 54.12299 -294.425846) (xy 54.134767 -294.378062) (xy 54.154058 -294.332786) (xy 54.180361 -294.29119)
			(xy 54.212996 -294.254353) (xy 54.251117 -294.223228) (xy 54.293738 -294.198621) (xy 54.339754 -294.181169)
			(xy 54.387973 -294.171325) (xy 54.437148 -294.169344) (xy 54.486003 -294.175276) (xy 54.533274 -294.188968)
			(xy 54.577736 -294.210066) (xy 54.618239 -294.238022) (xy 54.653732 -294.272114) (xy 54.683297 -294.311458)
			(xy 54.706168 -294.355035) (xy 54.721752 -294.401716) (xy 54.729647 -294.450293) (xy 54.730142 -294.4749)
			(xy 55.06899 -294.4749) (xy 55.07295 -294.425846) (xy 55.084727 -294.378062) (xy 55.104018 -294.332786)
			(xy 55.130321 -294.29119) (xy 55.162956 -294.254353) (xy 55.201077 -294.223228) (xy 55.243698 -294.198621)
			(xy 55.289714 -294.181169) (xy 55.337933 -294.171325) (xy 55.387108 -294.169344) (xy 55.435963 -294.175276)
			(xy 55.483234 -294.188968) (xy 55.527696 -294.210066) (xy 55.568199 -294.238022) (xy 55.603692 -294.272114)
			(xy 55.633257 -294.311458) (xy 55.656128 -294.355035) (xy 55.671712 -294.401716) (xy 55.679607 -294.450293)
			(xy 55.680102 -294.4749) (xy 56.01895 -294.4749) (xy 56.02291 -294.425846) (xy 56.034687 -294.378062)
			(xy 56.053978 -294.332786) (xy 56.080281 -294.29119) (xy 56.112916 -294.254353) (xy 56.151037 -294.223228)
			(xy 56.193658 -294.198621) (xy 56.239674 -294.181169) (xy 56.287893 -294.171325) (xy 56.337068 -294.169344)
			(xy 56.385923 -294.175276) (xy 56.433194 -294.188968) (xy 56.477656 -294.210066) (xy 56.518159 -294.238022)
			(xy 56.553652 -294.272114) (xy 56.583217 -294.311458) (xy 56.606088 -294.355035) (xy 56.621672 -294.401716)
			(xy 56.629567 -294.450293) (xy 56.630062 -294.4749) (xy 56.969164 -294.4749) (xy 56.973124 -294.425846)
			(xy 56.984901 -294.378062) (xy 57.004192 -294.332786) (xy 57.030495 -294.29119) (xy 57.06313 -294.254353)
			(xy 57.101251 -294.223228) (xy 57.143872 -294.198621) (xy 57.189888 -294.181169) (xy 57.238107 -294.171325)
			(xy 57.287282 -294.169344) (xy 57.336137 -294.175276) (xy 57.383408 -294.188968) (xy 57.42787 -294.210066)
			(xy 57.468373 -294.238022) (xy 57.503866 -294.272114) (xy 57.533431 -294.311458) (xy 57.556302 -294.355035)
			(xy 57.571886 -294.401716) (xy 57.579781 -294.450293) (xy 57.580276 -294.4749) (xy 57.919124 -294.4749)
			(xy 57.923084 -294.425846) (xy 57.934861 -294.378062) (xy 57.954152 -294.332786) (xy 57.980455 -294.29119)
			(xy 58.01309 -294.254353) (xy 58.051211 -294.223228) (xy 58.093832 -294.198621) (xy 58.139848 -294.181169)
			(xy 58.188067 -294.171325) (xy 58.237242 -294.169344) (xy 58.286097 -294.175276) (xy 58.333368 -294.188968)
			(xy 58.37783 -294.210066) (xy 58.418333 -294.238022) (xy 58.453826 -294.272114) (xy 58.483391 -294.311458)
			(xy 58.506262 -294.355035) (xy 58.521846 -294.401716) (xy 58.529741 -294.450293) (xy 58.530236 -294.4749)
			(xy 59.819044 -294.4749) (xy 59.823004 -294.425846) (xy 59.834781 -294.378062) (xy 59.854072 -294.332786)
			(xy 59.880375 -294.29119) (xy 59.91301 -294.254353) (xy 59.951131 -294.223228) (xy 59.993752 -294.198621)
			(xy 60.039768 -294.181169) (xy 60.087987 -294.171325) (xy 60.137162 -294.169344) (xy 60.186017 -294.175276)
			(xy 60.233288 -294.188968) (xy 60.27775 -294.210066) (xy 60.318253 -294.238022) (xy 60.353746 -294.272114)
			(xy 60.383311 -294.311458) (xy 60.406182 -294.355035) (xy 60.421766 -294.401716) (xy 60.429661 -294.450293)
			(xy 60.430156 -294.4749) (xy 60.769004 -294.4749) (xy 60.772964 -294.425846) (xy 60.784741 -294.378062)
			(xy 60.804032 -294.332786) (xy 60.830335 -294.29119) (xy 60.86297 -294.254353) (xy 60.901091 -294.223228)
			(xy 60.943712 -294.198621) (xy 60.989728 -294.181169) (xy 61.037947 -294.171325) (xy 61.087122 -294.169344)
			(xy 61.135977 -294.175276) (xy 61.183248 -294.188968) (xy 61.22771 -294.210066) (xy 61.268213 -294.238022)
			(xy 61.303706 -294.272114) (xy 61.333271 -294.311458) (xy 61.356142 -294.355035) (xy 61.371726 -294.401716)
			(xy 61.379621 -294.450293) (xy 61.380116 -294.4749) (xy 61.718964 -294.4749) (xy 61.722924 -294.425846)
			(xy 61.734701 -294.378062) (xy 61.753992 -294.332786) (xy 61.780295 -294.29119) (xy 61.81293 -294.254353)
			(xy 61.851051 -294.223228) (xy 61.893672 -294.198621) (xy 61.939688 -294.181169) (xy 61.987907 -294.171325)
			(xy 62.037082 -294.169344) (xy 62.085937 -294.175276) (xy 62.133208 -294.188968) (xy 62.17767 -294.210066)
			(xy 62.218173 -294.238022) (xy 62.253666 -294.272114) (xy 62.283231 -294.311458) (xy 62.306102 -294.355035)
			(xy 62.321686 -294.401716) (xy 62.329581 -294.450293) (xy 62.330076 -294.4749) (xy 62.669178 -294.4749)
			(xy 62.673138 -294.425846) (xy 62.684915 -294.378062) (xy 62.704206 -294.332786) (xy 62.730509 -294.29119)
			(xy 62.763144 -294.254353) (xy 62.801265 -294.223228) (xy 62.843886 -294.198621) (xy 62.889902 -294.181169)
			(xy 62.938121 -294.171325) (xy 62.987296 -294.169344) (xy 63.036151 -294.175276) (xy 63.083422 -294.188968)
			(xy 63.127884 -294.210066) (xy 63.168387 -294.238022) (xy 63.20388 -294.272114) (xy 63.233445 -294.311458)
			(xy 63.256316 -294.355035) (xy 63.2719 -294.401716) (xy 63.279795 -294.450293) (xy 63.28029 -294.4749)
			(xy 63.619138 -294.4749) (xy 63.623098 -294.425846) (xy 63.634875 -294.378062) (xy 63.654166 -294.332786)
			(xy 63.680469 -294.29119) (xy 63.713104 -294.254353) (xy 63.751225 -294.223228) (xy 63.793846 -294.198621)
			(xy 63.839862 -294.181169) (xy 63.888081 -294.171325) (xy 63.937256 -294.169344) (xy 63.986111 -294.175276)
			(xy 64.033382 -294.188968) (xy 64.077844 -294.210066) (xy 64.118347 -294.238022) (xy 64.15384 -294.272114)
			(xy 64.183405 -294.311458) (xy 64.206276 -294.355035) (xy 64.22186 -294.401716) (xy 64.229755 -294.450293)
			(xy 64.23025 -294.4749) (xy 64.569098 -294.4749) (xy 64.573058 -294.425846) (xy 64.584835 -294.378062)
			(xy 64.604126 -294.332786) (xy 64.630429 -294.29119) (xy 64.663064 -294.254353) (xy 64.701185 -294.223228)
			(xy 64.743806 -294.198621) (xy 64.789822 -294.181169) (xy 64.838041 -294.171325) (xy 64.887216 -294.169344)
			(xy 64.936071 -294.175276) (xy 64.983342 -294.188968) (xy 65.027804 -294.210066) (xy 65.068307 -294.238022)
			(xy 65.1038 -294.272114) (xy 65.133365 -294.311458) (xy 65.156236 -294.355035) (xy 65.17182 -294.401716)
			(xy 65.179715 -294.450293) (xy 65.18021 -294.4749) (xy 65.519058 -294.4749) (xy 65.523018 -294.425846)
			(xy 65.534795 -294.378062) (xy 65.554086 -294.332786) (xy 65.580389 -294.29119) (xy 65.613024 -294.254353)
			(xy 65.651145 -294.223228) (xy 65.693766 -294.198621) (xy 65.739782 -294.181169) (xy 65.788001 -294.171325)
			(xy 65.837176 -294.169344) (xy 65.886031 -294.175276) (xy 65.933302 -294.188968) (xy 65.977764 -294.210066)
			(xy 66.018267 -294.238022) (xy 66.05376 -294.272114) (xy 66.083325 -294.311458) (xy 66.106196 -294.355035)
			(xy 66.12178 -294.401716) (xy 66.129675 -294.450293) (xy 66.13017 -294.4749) (xy 66.469018 -294.4749)
			(xy 66.472978 -294.425846) (xy 66.484755 -294.378062) (xy 66.504046 -294.332786) (xy 66.530349 -294.29119)
			(xy 66.562984 -294.254353) (xy 66.601105 -294.223228) (xy 66.643726 -294.198621) (xy 66.689742 -294.181169)
			(xy 66.737961 -294.171325) (xy 66.787136 -294.169344) (xy 66.835991 -294.175276) (xy 66.883262 -294.188968)
			(xy 66.927724 -294.210066) (xy 66.968227 -294.238022) (xy 67.00372 -294.272114) (xy 67.033285 -294.311458)
			(xy 67.056156 -294.355035) (xy 67.07174 -294.401716) (xy 67.079635 -294.450293) (xy 67.08013 -294.4749)
			(xy 67.418978 -294.4749) (xy 67.422938 -294.425846) (xy 67.434715 -294.378062) (xy 67.454006 -294.332786)
			(xy 67.480309 -294.29119) (xy 67.512944 -294.254353) (xy 67.551065 -294.223228) (xy 67.593686 -294.198621)
			(xy 67.639702 -294.181169) (xy 67.687921 -294.171325) (xy 67.737096 -294.169344) (xy 67.785951 -294.175276)
			(xy 67.833222 -294.188968) (xy 67.877684 -294.210066) (xy 67.918187 -294.238022) (xy 67.95368 -294.272114)
			(xy 67.983245 -294.311458) (xy 68.006116 -294.355035) (xy 68.0217 -294.401716) (xy 68.029595 -294.450293)
			(xy 68.03009 -294.4749) (xy 68.368938 -294.4749) (xy 68.372898 -294.425846) (xy 68.384675 -294.378062)
			(xy 68.403966 -294.332786) (xy 68.430269 -294.29119) (xy 68.462904 -294.254353) (xy 68.501025 -294.223228)
			(xy 68.543646 -294.198621) (xy 68.589662 -294.181169) (xy 68.637881 -294.171325) (xy 68.687056 -294.169344)
			(xy 68.735911 -294.175276) (xy 68.783182 -294.188968) (xy 68.827644 -294.210066) (xy 68.868147 -294.238022)
			(xy 68.90364 -294.272114) (xy 68.933205 -294.311458) (xy 68.956076 -294.355035) (xy 68.97166 -294.401716)
			(xy 68.979555 -294.450293) (xy 68.98005 -294.4749) (xy 69.319152 -294.4749) (xy 69.323112 -294.425846)
			(xy 69.334889 -294.378062) (xy 69.35418 -294.332786) (xy 69.380483 -294.29119) (xy 69.413118 -294.254353)
			(xy 69.451239 -294.223228) (xy 69.49386 -294.198621) (xy 69.539876 -294.181169) (xy 69.588095 -294.171325)
			(xy 69.63727 -294.169344) (xy 69.686125 -294.175276) (xy 69.733396 -294.188968) (xy 69.777858 -294.210066)
			(xy 69.818361 -294.238022) (xy 69.853854 -294.272114) (xy 69.883419 -294.311458) (xy 69.90629 -294.355035)
			(xy 69.921874 -294.401716) (xy 69.929769 -294.450293) (xy 69.930264 -294.4749) (xy 71.219072 -294.4749)
			(xy 71.223032 -294.425846) (xy 71.234809 -294.378062) (xy 71.2541 -294.332786) (xy 71.280403 -294.29119)
			(xy 71.313038 -294.254353) (xy 71.351159 -294.223228) (xy 71.39378 -294.198621) (xy 71.439796 -294.181169)
			(xy 71.488015 -294.171325) (xy 71.53719 -294.169344) (xy 71.586045 -294.175276) (xy 71.633316 -294.188968)
			(xy 71.677778 -294.210066) (xy 71.718281 -294.238022) (xy 71.753774 -294.272114) (xy 71.783339 -294.311458)
			(xy 71.80621 -294.355035) (xy 71.821794 -294.401716) (xy 71.829689 -294.450293) (xy 71.830184 -294.4749)
			(xy 72.169032 -294.4749) (xy 72.172992 -294.425846) (xy 72.184769 -294.378062) (xy 72.20406 -294.332786)
			(xy 72.230363 -294.29119) (xy 72.262998 -294.254353) (xy 72.301119 -294.223228) (xy 72.34374 -294.198621)
			(xy 72.389756 -294.181169) (xy 72.437975 -294.171325) (xy 72.48715 -294.169344) (xy 72.536005 -294.175276)
			(xy 72.583276 -294.188968) (xy 72.627738 -294.210066) (xy 72.668241 -294.238022) (xy 72.703734 -294.272114)
			(xy 72.733299 -294.311458) (xy 72.75617 -294.355035) (xy 72.771754 -294.401716) (xy 72.779649 -294.450293)
			(xy 72.780144 -294.4749) (xy 73.118992 -294.4749) (xy 73.122952 -294.425846) (xy 73.134729 -294.378062)
			(xy 73.15402 -294.332786) (xy 73.180323 -294.29119) (xy 73.212958 -294.254353) (xy 73.251079 -294.223228)
			(xy 73.2937 -294.198621) (xy 73.339716 -294.181169) (xy 73.387935 -294.171325) (xy 73.43711 -294.169344)
			(xy 73.485965 -294.175276) (xy 73.533236 -294.188968) (xy 73.577698 -294.210066) (xy 73.618201 -294.238022)
			(xy 73.653694 -294.272114) (xy 73.683259 -294.311458) (xy 73.70613 -294.355035) (xy 73.721714 -294.401716)
			(xy 73.729609 -294.450293) (xy 73.730104 -294.4749) (xy 74.068952 -294.4749) (xy 74.072912 -294.425846)
			(xy 74.084689 -294.378062) (xy 74.10398 -294.332786) (xy 74.130283 -294.29119) (xy 74.162918 -294.254353)
			(xy 74.201039 -294.223228) (xy 74.24366 -294.198621) (xy 74.289676 -294.181169) (xy 74.337895 -294.171325)
			(xy 74.38707 -294.169344) (xy 74.435925 -294.175276) (xy 74.483196 -294.188968) (xy 74.527658 -294.210066)
			(xy 74.568161 -294.238022) (xy 74.603654 -294.272114) (xy 74.633219 -294.311458) (xy 74.65609 -294.355035)
			(xy 74.671674 -294.401716) (xy 74.679569 -294.450293) (xy 74.680064 -294.4749) (xy 75.019166 -294.4749)
			(xy 75.023126 -294.425846) (xy 75.034903 -294.378062) (xy 75.054194 -294.332786) (xy 75.080497 -294.29119)
			(xy 75.113132 -294.254353) (xy 75.151253 -294.223228) (xy 75.193874 -294.198621) (xy 75.23989 -294.181169)
			(xy 75.288109 -294.171325) (xy 75.337284 -294.169344) (xy 75.386139 -294.175276) (xy 75.43341 -294.188968)
			(xy 75.477872 -294.210066) (xy 75.518375 -294.238022) (xy 75.553868 -294.272114) (xy 75.583433 -294.311458)
			(xy 75.606304 -294.355035) (xy 75.621888 -294.401716) (xy 75.629783 -294.450293) (xy 75.630278 -294.4749)
			(xy 75.969126 -294.4749) (xy 75.973086 -294.425846) (xy 75.984863 -294.378062) (xy 76.004154 -294.332786)
			(xy 76.030457 -294.29119) (xy 76.063092 -294.254353) (xy 76.101213 -294.223228) (xy 76.143834 -294.198621)
			(xy 76.18985 -294.181169) (xy 76.238069 -294.171325) (xy 76.287244 -294.169344) (xy 76.336099 -294.175276)
			(xy 76.38337 -294.188968) (xy 76.427832 -294.210066) (xy 76.468335 -294.238022) (xy 76.503828 -294.272114)
			(xy 76.533393 -294.311458) (xy 76.556264 -294.355035) (xy 76.571848 -294.401716) (xy 76.579743 -294.450293)
			(xy 76.580238 -294.4749) (xy 77.869046 -294.4749) (xy 77.873006 -294.425846) (xy 77.884783 -294.378062)
			(xy 77.904074 -294.332786) (xy 77.930377 -294.29119) (xy 77.963012 -294.254353) (xy 78.001133 -294.223228)
			(xy 78.043754 -294.198621) (xy 78.08977 -294.181169) (xy 78.137989 -294.171325) (xy 78.187164 -294.169344)
			(xy 78.236019 -294.175276) (xy 78.28329 -294.188968) (xy 78.327752 -294.210066) (xy 78.368255 -294.238022)
			(xy 78.403748 -294.272114) (xy 78.433313 -294.311458) (xy 78.456184 -294.355035) (xy 78.471768 -294.401716)
			(xy 78.479663 -294.450293) (xy 78.480158 -294.4749) (xy 78.479663 -294.499507) (xy 78.471768 -294.548084)
			(xy 78.456184 -294.594765) (xy 78.433313 -294.638342) (xy 78.403748 -294.677686) (xy 78.368255 -294.711778)
			(xy 78.327752 -294.739734) (xy 78.28329 -294.760832) (xy 78.236019 -294.774524) (xy 78.187164 -294.780456)
			(xy 78.137989 -294.778475) (xy 78.08977 -294.768631) (xy 78.043754 -294.751179) (xy 78.001133 -294.726572)
			(xy 77.963012 -294.695447) (xy 77.930377 -294.65861) (xy 77.904074 -294.617014) (xy 77.884783 -294.571738)
			(xy 77.873006 -294.523954) (xy 77.869046 -294.4749) (xy 76.580238 -294.4749) (xy 76.579743 -294.499507)
			(xy 76.571848 -294.548084) (xy 76.556264 -294.594765) (xy 76.533393 -294.638342) (xy 76.503828 -294.677686)
			(xy 76.468335 -294.711778) (xy 76.427832 -294.739734) (xy 76.38337 -294.760832) (xy 76.336099 -294.774524)
			(xy 76.287244 -294.780456) (xy 76.238069 -294.778475) (xy 76.18985 -294.768631) (xy 76.143834 -294.751179)
			(xy 76.101213 -294.726572) (xy 76.063092 -294.695447) (xy 76.030457 -294.65861) (xy 76.004154 -294.617014)
			(xy 75.984863 -294.571738) (xy 75.973086 -294.523954) (xy 75.969126 -294.4749) (xy 75.630278 -294.4749)
			(xy 75.629783 -294.499507) (xy 75.621888 -294.548084) (xy 75.606304 -294.594765) (xy 75.583433 -294.638342)
			(xy 75.553868 -294.677686) (xy 75.518375 -294.711778) (xy 75.477872 -294.739734) (xy 75.43341 -294.760832)
			(xy 75.386139 -294.774524) (xy 75.337284 -294.780456) (xy 75.288109 -294.778475) (xy 75.23989 -294.768631)
			(xy 75.193874 -294.751179) (xy 75.151253 -294.726572) (xy 75.113132 -294.695447) (xy 75.080497 -294.65861)
			(xy 75.054194 -294.617014) (xy 75.034903 -294.571738) (xy 75.023126 -294.523954) (xy 75.019166 -294.4749)
			(xy 74.680064 -294.4749) (xy 74.679569 -294.499507) (xy 74.671674 -294.548084) (xy 74.65609 -294.594765)
			(xy 74.633219 -294.638342) (xy 74.603654 -294.677686) (xy 74.568161 -294.711778) (xy 74.527658 -294.739734)
			(xy 74.483196 -294.760832) (xy 74.435925 -294.774524) (xy 74.38707 -294.780456) (xy 74.337895 -294.778475)
			(xy 74.289676 -294.768631) (xy 74.24366 -294.751179) (xy 74.201039 -294.726572) (xy 74.162918 -294.695447)
			(xy 74.130283 -294.65861) (xy 74.10398 -294.617014) (xy 74.084689 -294.571738) (xy 74.072912 -294.523954)
			(xy 74.068952 -294.4749) (xy 73.730104 -294.4749) (xy 73.729609 -294.499507) (xy 73.721714 -294.548084)
			(xy 73.70613 -294.594765) (xy 73.683259 -294.638342) (xy 73.653694 -294.677686) (xy 73.618201 -294.711778)
			(xy 73.577698 -294.739734) (xy 73.533236 -294.760832) (xy 73.485965 -294.774524) (xy 73.43711 -294.780456)
			(xy 73.387935 -294.778475) (xy 73.339716 -294.768631) (xy 73.2937 -294.751179) (xy 73.251079 -294.726572)
			(xy 73.212958 -294.695447) (xy 73.180323 -294.65861) (xy 73.15402 -294.617014) (xy 73.134729 -294.571738)
			(xy 73.122952 -294.523954) (xy 73.118992 -294.4749) (xy 72.780144 -294.4749) (xy 72.779649 -294.499507)
			(xy 72.771754 -294.548084) (xy 72.75617 -294.594765) (xy 72.733299 -294.638342) (xy 72.703734 -294.677686)
			(xy 72.668241 -294.711778) (xy 72.627738 -294.739734) (xy 72.583276 -294.760832) (xy 72.536005 -294.774524)
			(xy 72.48715 -294.780456) (xy 72.437975 -294.778475) (xy 72.389756 -294.768631) (xy 72.34374 -294.751179)
			(xy 72.301119 -294.726572) (xy 72.262998 -294.695447) (xy 72.230363 -294.65861) (xy 72.20406 -294.617014)
			(xy 72.184769 -294.571738) (xy 72.172992 -294.523954) (xy 72.169032 -294.4749) (xy 71.830184 -294.4749)
			(xy 71.829689 -294.499507) (xy 71.821794 -294.548084) (xy 71.80621 -294.594765) (xy 71.783339 -294.638342)
			(xy 71.753774 -294.677686) (xy 71.718281 -294.711778) (xy 71.677778 -294.739734) (xy 71.633316 -294.760832)
			(xy 71.586045 -294.774524) (xy 71.53719 -294.780456) (xy 71.488015 -294.778475) (xy 71.439796 -294.768631)
			(xy 71.39378 -294.751179) (xy 71.351159 -294.726572) (xy 71.313038 -294.695447) (xy 71.280403 -294.65861)
			(xy 71.2541 -294.617014) (xy 71.234809 -294.571738) (xy 71.223032 -294.523954) (xy 71.219072 -294.4749)
			(xy 69.930264 -294.4749) (xy 69.929769 -294.499507) (xy 69.921874 -294.548084) (xy 69.90629 -294.594765)
			(xy 69.883419 -294.638342) (xy 69.853854 -294.677686) (xy 69.818361 -294.711778) (xy 69.777858 -294.739734)
			(xy 69.733396 -294.760832) (xy 69.686125 -294.774524) (xy 69.63727 -294.780456) (xy 69.588095 -294.778475)
			(xy 69.539876 -294.768631) (xy 69.49386 -294.751179) (xy 69.451239 -294.726572) (xy 69.413118 -294.695447)
			(xy 69.380483 -294.65861) (xy 69.35418 -294.617014) (xy 69.334889 -294.571738) (xy 69.323112 -294.523954)
			(xy 69.319152 -294.4749) (xy 68.98005 -294.4749) (xy 68.979555 -294.499507) (xy 68.97166 -294.548084)
			(xy 68.956076 -294.594765) (xy 68.933205 -294.638342) (xy 68.90364 -294.677686) (xy 68.868147 -294.711778)
			(xy 68.827644 -294.739734) (xy 68.783182 -294.760832) (xy 68.735911 -294.774524) (xy 68.687056 -294.780456)
			(xy 68.637881 -294.778475) (xy 68.589662 -294.768631) (xy 68.543646 -294.751179) (xy 68.501025 -294.726572)
			(xy 68.462904 -294.695447) (xy 68.430269 -294.65861) (xy 68.403966 -294.617014) (xy 68.384675 -294.571738)
			(xy 68.372898 -294.523954) (xy 68.368938 -294.4749) (xy 68.03009 -294.4749) (xy 68.029595 -294.499507)
			(xy 68.0217 -294.548084) (xy 68.006116 -294.594765) (xy 67.983245 -294.638342) (xy 67.95368 -294.677686)
			(xy 67.918187 -294.711778) (xy 67.877684 -294.739734) (xy 67.833222 -294.760832) (xy 67.785951 -294.774524)
			(xy 67.737096 -294.780456) (xy 67.687921 -294.778475) (xy 67.639702 -294.768631) (xy 67.593686 -294.751179)
			(xy 67.551065 -294.726572) (xy 67.512944 -294.695447) (xy 67.480309 -294.65861) (xy 67.454006 -294.617014)
			(xy 67.434715 -294.571738) (xy 67.422938 -294.523954) (xy 67.418978 -294.4749) (xy 67.08013 -294.4749)
			(xy 67.079635 -294.499507) (xy 67.07174 -294.548084) (xy 67.056156 -294.594765) (xy 67.033285 -294.638342)
			(xy 67.00372 -294.677686) (xy 66.968227 -294.711778) (xy 66.927724 -294.739734) (xy 66.883262 -294.760832)
			(xy 66.835991 -294.774524) (xy 66.787136 -294.780456) (xy 66.737961 -294.778475) (xy 66.689742 -294.768631)
			(xy 66.643726 -294.751179) (xy 66.601105 -294.726572) (xy 66.562984 -294.695447) (xy 66.530349 -294.65861)
			(xy 66.504046 -294.617014) (xy 66.484755 -294.571738) (xy 66.472978 -294.523954) (xy 66.469018 -294.4749)
			(xy 66.13017 -294.4749) (xy 66.129675 -294.499507) (xy 66.12178 -294.548084) (xy 66.106196 -294.594765)
			(xy 66.083325 -294.638342) (xy 66.05376 -294.677686) (xy 66.018267 -294.711778) (xy 65.977764 -294.739734)
			(xy 65.933302 -294.760832) (xy 65.886031 -294.774524) (xy 65.837176 -294.780456) (xy 65.788001 -294.778475)
			(xy 65.739782 -294.768631) (xy 65.693766 -294.751179) (xy 65.651145 -294.726572) (xy 65.613024 -294.695447)
			(xy 65.580389 -294.65861) (xy 65.554086 -294.617014) (xy 65.534795 -294.571738) (xy 65.523018 -294.523954)
			(xy 65.519058 -294.4749) (xy 65.18021 -294.4749) (xy 65.179715 -294.499507) (xy 65.17182 -294.548084)
			(xy 65.156236 -294.594765) (xy 65.133365 -294.638342) (xy 65.1038 -294.677686) (xy 65.068307 -294.711778)
			(xy 65.027804 -294.739734) (xy 64.983342 -294.760832) (xy 64.936071 -294.774524) (xy 64.887216 -294.780456)
			(xy 64.838041 -294.778475) (xy 64.789822 -294.768631) (xy 64.743806 -294.751179) (xy 64.701185 -294.726572)
			(xy 64.663064 -294.695447) (xy 64.630429 -294.65861) (xy 64.604126 -294.617014) (xy 64.584835 -294.571738)
			(xy 64.573058 -294.523954) (xy 64.569098 -294.4749) (xy 64.23025 -294.4749) (xy 64.229755 -294.499507)
			(xy 64.22186 -294.548084) (xy 64.206276 -294.594765) (xy 64.183405 -294.638342) (xy 64.15384 -294.677686)
			(xy 64.118347 -294.711778) (xy 64.077844 -294.739734) (xy 64.033382 -294.760832) (xy 63.986111 -294.774524)
			(xy 63.937256 -294.780456) (xy 63.888081 -294.778475) (xy 63.839862 -294.768631) (xy 63.793846 -294.751179)
			(xy 63.751225 -294.726572) (xy 63.713104 -294.695447) (xy 63.680469 -294.65861) (xy 63.654166 -294.617014)
			(xy 63.634875 -294.571738) (xy 63.623098 -294.523954) (xy 63.619138 -294.4749) (xy 63.28029 -294.4749)
			(xy 63.279795 -294.499507) (xy 63.2719 -294.548084) (xy 63.256316 -294.594765) (xy 63.233445 -294.638342)
			(xy 63.20388 -294.677686) (xy 63.168387 -294.711778) (xy 63.127884 -294.739734) (xy 63.083422 -294.760832)
			(xy 63.036151 -294.774524) (xy 62.987296 -294.780456) (xy 62.938121 -294.778475) (xy 62.889902 -294.768631)
			(xy 62.843886 -294.751179) (xy 62.801265 -294.726572) (xy 62.763144 -294.695447) (xy 62.730509 -294.65861)
			(xy 62.704206 -294.617014) (xy 62.684915 -294.571738) (xy 62.673138 -294.523954) (xy 62.669178 -294.4749)
			(xy 62.330076 -294.4749) (xy 62.329581 -294.499507) (xy 62.321686 -294.548084) (xy 62.306102 -294.594765)
			(xy 62.283231 -294.638342) (xy 62.253666 -294.677686) (xy 62.218173 -294.711778) (xy 62.17767 -294.739734)
			(xy 62.133208 -294.760832) (xy 62.085937 -294.774524) (xy 62.037082 -294.780456) (xy 61.987907 -294.778475)
			(xy 61.939688 -294.768631) (xy 61.893672 -294.751179) (xy 61.851051 -294.726572) (xy 61.81293 -294.695447)
			(xy 61.780295 -294.65861) (xy 61.753992 -294.617014) (xy 61.734701 -294.571738) (xy 61.722924 -294.523954)
			(xy 61.718964 -294.4749) (xy 61.380116 -294.4749) (xy 61.379621 -294.499507) (xy 61.371726 -294.548084)
			(xy 61.356142 -294.594765) (xy 61.333271 -294.638342) (xy 61.303706 -294.677686) (xy 61.268213 -294.711778)
			(xy 61.22771 -294.739734) (xy 61.183248 -294.760832) (xy 61.135977 -294.774524) (xy 61.087122 -294.780456)
			(xy 61.037947 -294.778475) (xy 60.989728 -294.768631) (xy 60.943712 -294.751179) (xy 60.901091 -294.726572)
			(xy 60.86297 -294.695447) (xy 60.830335 -294.65861) (xy 60.804032 -294.617014) (xy 60.784741 -294.571738)
			(xy 60.772964 -294.523954) (xy 60.769004 -294.4749) (xy 60.430156 -294.4749) (xy 60.429661 -294.499507)
			(xy 60.421766 -294.548084) (xy 60.406182 -294.594765) (xy 60.383311 -294.638342) (xy 60.353746 -294.677686)
			(xy 60.318253 -294.711778) (xy 60.27775 -294.739734) (xy 60.233288 -294.760832) (xy 60.186017 -294.774524)
			(xy 60.137162 -294.780456) (xy 60.087987 -294.778475) (xy 60.039768 -294.768631) (xy 59.993752 -294.751179)
			(xy 59.951131 -294.726572) (xy 59.91301 -294.695447) (xy 59.880375 -294.65861) (xy 59.854072 -294.617014)
			(xy 59.834781 -294.571738) (xy 59.823004 -294.523954) (xy 59.819044 -294.4749) (xy 58.530236 -294.4749)
			(xy 58.529741 -294.499507) (xy 58.521846 -294.548084) (xy 58.506262 -294.594765) (xy 58.483391 -294.638342)
			(xy 58.453826 -294.677686) (xy 58.418333 -294.711778) (xy 58.37783 -294.739734) (xy 58.333368 -294.760832)
			(xy 58.286097 -294.774524) (xy 58.237242 -294.780456) (xy 58.188067 -294.778475) (xy 58.139848 -294.768631)
			(xy 58.093832 -294.751179) (xy 58.051211 -294.726572) (xy 58.01309 -294.695447) (xy 57.980455 -294.65861)
			(xy 57.954152 -294.617014) (xy 57.934861 -294.571738) (xy 57.923084 -294.523954) (xy 57.919124 -294.4749)
			(xy 57.580276 -294.4749) (xy 57.579781 -294.499507) (xy 57.571886 -294.548084) (xy 57.556302 -294.594765)
			(xy 57.533431 -294.638342) (xy 57.503866 -294.677686) (xy 57.468373 -294.711778) (xy 57.42787 -294.739734)
			(xy 57.383408 -294.760832) (xy 57.336137 -294.774524) (xy 57.287282 -294.780456) (xy 57.238107 -294.778475)
			(xy 57.189888 -294.768631) (xy 57.143872 -294.751179) (xy 57.101251 -294.726572) (xy 57.06313 -294.695447)
			(xy 57.030495 -294.65861) (xy 57.004192 -294.617014) (xy 56.984901 -294.571738) (xy 56.973124 -294.523954)
			(xy 56.969164 -294.4749) (xy 56.630062 -294.4749) (xy 56.629567 -294.499507) (xy 56.621672 -294.548084)
			(xy 56.606088 -294.594765) (xy 56.583217 -294.638342) (xy 56.553652 -294.677686) (xy 56.518159 -294.711778)
			(xy 56.477656 -294.739734) (xy 56.433194 -294.760832) (xy 56.385923 -294.774524) (xy 56.337068 -294.780456)
			(xy 56.287893 -294.778475) (xy 56.239674 -294.768631) (xy 56.193658 -294.751179) (xy 56.151037 -294.726572)
			(xy 56.112916 -294.695447) (xy 56.080281 -294.65861) (xy 56.053978 -294.617014) (xy 56.034687 -294.571738)
			(xy 56.02291 -294.523954) (xy 56.01895 -294.4749) (xy 55.680102 -294.4749) (xy 55.679607 -294.499507)
			(xy 55.671712 -294.548084) (xy 55.656128 -294.594765) (xy 55.633257 -294.638342) (xy 55.603692 -294.677686)
			(xy 55.568199 -294.711778) (xy 55.527696 -294.739734) (xy 55.483234 -294.760832) (xy 55.435963 -294.774524)
			(xy 55.387108 -294.780456) (xy 55.337933 -294.778475) (xy 55.289714 -294.768631) (xy 55.243698 -294.751179)
			(xy 55.201077 -294.726572) (xy 55.162956 -294.695447) (xy 55.130321 -294.65861) (xy 55.104018 -294.617014)
			(xy 55.084727 -294.571738) (xy 55.07295 -294.523954) (xy 55.06899 -294.4749) (xy 54.730142 -294.4749)
			(xy 54.729647 -294.499507) (xy 54.721752 -294.548084) (xy 54.706168 -294.594765) (xy 54.683297 -294.638342)
			(xy 54.653732 -294.677686) (xy 54.618239 -294.711778) (xy 54.577736 -294.739734) (xy 54.533274 -294.760832)
			(xy 54.486003 -294.774524) (xy 54.437148 -294.780456) (xy 54.387973 -294.778475) (xy 54.339754 -294.768631)
			(xy 54.293738 -294.751179) (xy 54.251117 -294.726572) (xy 54.212996 -294.695447) (xy 54.180361 -294.65861)
			(xy 54.154058 -294.617014) (xy 54.134767 -294.571738) (xy 54.12299 -294.523954) (xy 54.11903 -294.4749)
			(xy 53.780182 -294.4749) (xy 53.779687 -294.499507) (xy 53.771792 -294.548084) (xy 53.756208 -294.594765)
			(xy 53.733337 -294.638342) (xy 53.703772 -294.677686) (xy 53.668279 -294.711778) (xy 53.627776 -294.739734)
			(xy 53.583314 -294.760832) (xy 53.536043 -294.774524) (xy 53.487188 -294.780456) (xy 53.438013 -294.778475)
			(xy 53.389794 -294.768631) (xy 53.343778 -294.751179) (xy 53.301157 -294.726572) (xy 53.263036 -294.695447)
			(xy 53.230401 -294.65861) (xy 53.204098 -294.617014) (xy 53.184807 -294.571738) (xy 53.17303 -294.523954)
			(xy 53.16907 -294.4749) (xy 52.830222 -294.4749) (xy 52.829727 -294.499507) (xy 52.821832 -294.548084)
			(xy 52.806248 -294.594765) (xy 52.783377 -294.638342) (xy 52.753812 -294.677686) (xy 52.718319 -294.711778)
			(xy 52.677816 -294.739734) (xy 52.633354 -294.760832) (xy 52.586083 -294.774524) (xy 52.537228 -294.780456)
			(xy 52.488053 -294.778475) (xy 52.439834 -294.768631) (xy 52.393818 -294.751179) (xy 52.351197 -294.726572)
			(xy 52.313076 -294.695447) (xy 52.280441 -294.65861) (xy 52.254138 -294.617014) (xy 52.234847 -294.571738)
			(xy 52.22307 -294.523954) (xy 52.21911 -294.4749) (xy 51.880262 -294.4749) (xy 51.879767 -294.499507)
			(xy 51.871872 -294.548084) (xy 51.856288 -294.594765) (xy 51.833417 -294.638342) (xy 51.803852 -294.677686)
			(xy 51.768359 -294.711778) (xy 51.727856 -294.739734) (xy 51.683394 -294.760832) (xy 51.636123 -294.774524)
			(xy 51.587268 -294.780456) (xy 51.538093 -294.778475) (xy 51.489874 -294.768631) (xy 51.443858 -294.751179)
			(xy 51.401237 -294.726572) (xy 51.363116 -294.695447) (xy 51.330481 -294.65861) (xy 51.304178 -294.617014)
			(xy 51.284887 -294.571738) (xy 51.27311 -294.523954) (xy 51.26915 -294.4749) (xy 50.930302 -294.4749)
			(xy 50.929807 -294.499507) (xy 50.921912 -294.548084) (xy 50.906328 -294.594765) (xy 50.883457 -294.638342)
			(xy 50.853892 -294.677686) (xy 50.818399 -294.711778) (xy 50.777896 -294.739734) (xy 50.733434 -294.760832)
			(xy 50.686163 -294.774524) (xy 50.637308 -294.780456) (xy 50.588133 -294.778475) (xy 50.539914 -294.768631)
			(xy 50.493898 -294.751179) (xy 50.451277 -294.726572) (xy 50.413156 -294.695447) (xy 50.380521 -294.65861)
			(xy 50.354218 -294.617014) (xy 50.334927 -294.571738) (xy 50.32315 -294.523954) (xy 50.31919 -294.4749)
			(xy 49.980088 -294.4749) (xy 49.979593 -294.499507) (xy 49.971698 -294.548084) (xy 49.956114 -294.594765)
			(xy 49.933243 -294.638342) (xy 49.903678 -294.677686) (xy 49.868185 -294.711778) (xy 49.827682 -294.739734)
			(xy 49.78322 -294.760832) (xy 49.735949 -294.774524) (xy 49.687094 -294.780456) (xy 49.637919 -294.778475)
			(xy 49.5897 -294.768631) (xy 49.543684 -294.751179) (xy 49.501063 -294.726572) (xy 49.462942 -294.695447)
			(xy 49.430307 -294.65861) (xy 49.404004 -294.617014) (xy 49.384713 -294.571738) (xy 49.372936 -294.523954)
			(xy 49.368976 -294.4749) (xy 49.030128 -294.4749) (xy 49.029633 -294.499507) (xy 49.021738 -294.548084)
			(xy 49.006154 -294.594765) (xy 48.983283 -294.638342) (xy 48.953718 -294.677686) (xy 48.918225 -294.711778)
			(xy 48.877722 -294.739734) (xy 48.83326 -294.760832) (xy 48.785989 -294.774524) (xy 48.737134 -294.780456)
			(xy 48.687959 -294.778475) (xy 48.63974 -294.768631) (xy 48.593724 -294.751179) (xy 48.551103 -294.726572)
			(xy 48.512982 -294.695447) (xy 48.480347 -294.65861) (xy 48.454044 -294.617014) (xy 48.434753 -294.571738)
			(xy 48.422976 -294.523954) (xy 48.419016 -294.4749) (xy 48.080168 -294.4749) (xy 48.079673 -294.499507)
			(xy 48.071778 -294.548084) (xy 48.056194 -294.594765) (xy 48.033323 -294.638342) (xy 48.003758 -294.677686)
			(xy 47.968265 -294.711778) (xy 47.927762 -294.739734) (xy 47.8833 -294.760832) (xy 47.836029 -294.774524)
			(xy 47.787174 -294.780456) (xy 47.737999 -294.778475) (xy 47.68978 -294.768631) (xy 47.643764 -294.751179)
			(xy 47.601143 -294.726572) (xy 47.563022 -294.695447) (xy 47.530387 -294.65861) (xy 47.504084 -294.617014)
			(xy 47.484793 -294.571738) (xy 47.473016 -294.523954) (xy 47.469056 -294.4749) (xy 47.130208 -294.4749)
			(xy 47.129713 -294.499507) (xy 47.121818 -294.548084) (xy 47.106234 -294.594765) (xy 47.083363 -294.638342)
			(xy 47.053798 -294.677686) (xy 47.018305 -294.711778) (xy 46.977802 -294.739734) (xy 46.93334 -294.760832)
			(xy 46.886069 -294.774524) (xy 46.837214 -294.780456) (xy 46.788039 -294.778475) (xy 46.73982 -294.768631)
			(xy 46.693804 -294.751179) (xy 46.651183 -294.726572) (xy 46.613062 -294.695447) (xy 46.580427 -294.65861)
			(xy 46.554124 -294.617014) (xy 46.534833 -294.571738) (xy 46.523056 -294.523954) (xy 46.519096 -294.4749)
			(xy 46.180248 -294.4749) (xy 46.179753 -294.499507) (xy 46.171858 -294.548084) (xy 46.156274 -294.594765)
			(xy 46.133403 -294.638342) (xy 46.103838 -294.677686) (xy 46.068345 -294.711778) (xy 46.027842 -294.739734)
			(xy 45.98338 -294.760832) (xy 45.936109 -294.774524) (xy 45.887254 -294.780456) (xy 45.838079 -294.778475)
			(xy 45.78986 -294.768631) (xy 45.743844 -294.751179) (xy 45.701223 -294.726572) (xy 45.663102 -294.695447)
			(xy 45.630467 -294.65861) (xy 45.604164 -294.617014) (xy 45.584873 -294.571738) (xy 45.573096 -294.523954)
			(xy 45.569136 -294.4749) (xy 45.230288 -294.4749) (xy 45.229793 -294.499507) (xy 45.221898 -294.548084)
			(xy 45.206314 -294.594765) (xy 45.183443 -294.638342) (xy 45.153878 -294.677686) (xy 45.118385 -294.711778)
			(xy 45.077882 -294.739734) (xy 45.03342 -294.760832) (xy 44.986149 -294.774524) (xy 44.937294 -294.780456)
			(xy 44.888119 -294.778475) (xy 44.8399 -294.768631) (xy 44.793884 -294.751179) (xy 44.751263 -294.726572)
			(xy 44.713142 -294.695447) (xy 44.680507 -294.65861) (xy 44.654204 -294.617014) (xy 44.634913 -294.571738)
			(xy 44.623136 -294.523954) (xy 44.619176 -294.4749) (xy 44.280074 -294.4749) (xy 44.279579 -294.499507)
			(xy 44.271684 -294.548084) (xy 44.2561 -294.594765) (xy 44.233229 -294.638342) (xy 44.203664 -294.677686)
			(xy 44.168171 -294.711778) (xy 44.127668 -294.739734) (xy 44.083206 -294.760832) (xy 44.035935 -294.774524)
			(xy 43.98708 -294.780456) (xy 43.937905 -294.778475) (xy 43.889686 -294.768631) (xy 43.84367 -294.751179)
			(xy 43.801049 -294.726572) (xy 43.762928 -294.695447) (xy 43.730293 -294.65861) (xy 43.70399 -294.617014)
			(xy 43.684699 -294.571738) (xy 43.672922 -294.523954) (xy 43.668962 -294.4749) (xy 43.330114 -294.4749)
			(xy 43.329619 -294.499507) (xy 43.321724 -294.548084) (xy 43.30614 -294.594765) (xy 43.283269 -294.638342)
			(xy 43.253704 -294.677686) (xy 43.218211 -294.711778) (xy 43.177708 -294.739734) (xy 43.133246 -294.760832)
			(xy 43.085975 -294.774524) (xy 43.03712 -294.780456) (xy 42.987945 -294.778475) (xy 42.939726 -294.768631)
			(xy 42.89371 -294.751179) (xy 42.851089 -294.726572) (xy 42.812968 -294.695447) (xy 42.780333 -294.65861)
			(xy 42.75403 -294.617014) (xy 42.734739 -294.571738) (xy 42.722962 -294.523954) (xy 42.719002 -294.4749)
			(xy 42.430954 -294.4749) (xy 42.430456 -294.501549) (xy 42.422513 -294.554253) (xy 42.406803 -294.605183)
			(xy 42.383677 -294.653204) (xy 42.353653 -294.697241) (xy 42.317401 -294.736312) (xy 42.27573 -294.769543)
			(xy 42.229572 -294.796192) (xy 42.179958 -294.815664) (xy 42.127996 -294.827524) (xy 42.074846 -294.831508)
			(xy 42.021696 -294.827524) (xy 41.969734 -294.815664) (xy 41.92012 -294.796192) (xy 41.873962 -294.769543)
			(xy 41.832291 -294.736312) (xy 41.796039 -294.697241) (xy 41.766015 -294.653204) (xy 41.742889 -294.605183)
			(xy 41.727179 -294.554253) (xy 41.719236 -294.501549) (xy 41.429367 -294.501549) (xy 41.421804 -294.548084)
			(xy 41.40622 -294.594765) (xy 41.383349 -294.638342) (xy 41.353784 -294.677686) (xy 41.318291 -294.711778)
			(xy 41.277788 -294.739734) (xy 41.233326 -294.760832) (xy 41.186055 -294.774524) (xy 41.1372 -294.780456)
			(xy 41.088025 -294.778475) (xy 41.039806 -294.768631) (xy 40.99379 -294.751179) (xy 40.951169 -294.726572)
			(xy 40.913048 -294.695447) (xy 40.880413 -294.65861) (xy 40.85411 -294.617014) (xy 40.834819 -294.571738)
			(xy 40.823042 -294.523954) (xy 40.819082 -294.4749) (xy 38.580314 -294.4749) (xy 38.579819 -294.499507)
			(xy 38.571924 -294.548084) (xy 38.55634 -294.594765) (xy 38.533469 -294.638342) (xy 38.503904 -294.677686)
			(xy 38.468411 -294.711778) (xy 38.427908 -294.739734) (xy 38.383446 -294.760832) (xy 38.336175 -294.774524)
			(xy 38.28732 -294.780456) (xy 38.238145 -294.778475) (xy 38.189926 -294.768631) (xy 38.14391 -294.751179)
			(xy 38.101289 -294.726572) (xy 38.063168 -294.695447) (xy 38.030533 -294.65861) (xy 38.00423 -294.617014)
			(xy 37.984939 -294.571738) (xy 37.973162 -294.523954) (xy 37.969202 -294.4749) (xy 37.6301 -294.4749)
			(xy 37.629605 -294.499507) (xy 37.62171 -294.548084) (xy 37.606126 -294.594765) (xy 37.583255 -294.638342)
			(xy 37.55369 -294.677686) (xy 37.518197 -294.711778) (xy 37.477694 -294.739734) (xy 37.433232 -294.760832)
			(xy 37.385961 -294.774524) (xy 37.337106 -294.780456) (xy 37.287931 -294.778475) (xy 37.239712 -294.768631)
			(xy 37.193696 -294.751179) (xy 37.151075 -294.726572) (xy 37.112954 -294.695447) (xy 37.080319 -294.65861)
			(xy 37.054016 -294.617014) (xy 37.034725 -294.571738) (xy 37.022948 -294.523954) (xy 37.018988 -294.4749)
			(xy 36.68014 -294.4749) (xy 36.679645 -294.499507) (xy 36.67175 -294.548084) (xy 36.656166 -294.594765)
			(xy 36.633295 -294.638342) (xy 36.60373 -294.677686) (xy 36.568237 -294.711778) (xy 36.527734 -294.739734)
			(xy 36.483272 -294.760832) (xy 36.436001 -294.774524) (xy 36.387146 -294.780456) (xy 36.337971 -294.778475)
			(xy 36.289752 -294.768631) (xy 36.243736 -294.751179) (xy 36.201115 -294.726572) (xy 36.162994 -294.695447)
			(xy 36.130359 -294.65861) (xy 36.104056 -294.617014) (xy 36.084765 -294.571738) (xy 36.072988 -294.523954)
			(xy 36.069028 -294.4749) (xy 28.02631 -294.4749) (xy 28.035445 -294.494387) (xy 28.051513 -294.547794)
			(xy 28.059633 -294.60297) (xy 28.060142 -294.630856) (xy 28.059633 -294.658742) (xy 28.051513 -294.713918)
			(xy 28.035445 -294.767325) (xy 28.011773 -294.817822) (xy 27.981 -294.864335) (xy 27.943783 -294.905872)
			(xy 27.900915 -294.941547) (xy 27.853309 -294.970601) (xy 27.80198 -294.992413) (xy 27.748023 -295.006519)
			(xy 27.692586 -295.012619) (xy 27.636852 -295.010582) (xy 27.582009 -295.000452) (xy 27.529225 -294.982445)
			(xy 27.479625 -294.956944) (xy 27.434267 -294.924493) (xy 27.394118 -294.885784) (xy 27.360032 -294.841641)
			(xy 27.332736 -294.793006) (xy 27.312813 -294.740915) (xy 27.300687 -294.686478) (xy 27.296616 -294.630856)
			(xy 26.575004 -294.630856) (xy 26.574495 -294.658742) (xy 26.566375 -294.713918) (xy 26.550307 -294.767325)
			(xy 26.526635 -294.817822) (xy 26.495862 -294.864335) (xy 26.458645 -294.905872) (xy 26.415777 -294.941547)
			(xy 26.368171 -294.970601) (xy 26.316842 -294.992413) (xy 26.262885 -295.006519) (xy 26.207448 -295.012619)
			(xy 26.151714 -295.010582) (xy 26.096871 -295.000452) (xy 26.044087 -294.982445) (xy 25.994487 -294.956944)
			(xy 25.949129 -294.924493) (xy 25.90898 -294.885784) (xy 25.874894 -294.841641) (xy 25.847598 -294.793006)
			(xy 25.827675 -294.740915) (xy 25.815549 -294.686478) (xy 25.811478 -294.630856) (xy 1.660398 -294.630856)
			(xy 1.660398 -295.933114) (xy 25.811478 -295.933114) (xy 25.815549 -295.877492) (xy 25.827675 -295.823055)
			(xy 25.847598 -295.770964) (xy 25.874894 -295.722329) (xy 25.90898 -295.678186) (xy 25.949129 -295.639477)
			(xy 25.994487 -295.607026) (xy 26.044087 -295.581525) (xy 26.096871 -295.563518) (xy 26.151714 -295.553388)
			(xy 26.207448 -295.551351) (xy 26.262885 -295.557451) (xy 26.316842 -295.571557) (xy 26.368171 -295.593369)
			(xy 26.415777 -295.622423) (xy 26.458645 -295.658098) (xy 26.495862 -295.699635) (xy 26.526635 -295.746148)
			(xy 26.550307 -295.796645) (xy 26.566375 -295.850052) (xy 26.574495 -295.905228) (xy 26.575004 -295.933114)
			(xy 27.286964 -295.933114) (xy 27.291035 -295.877492) (xy 27.303161 -295.823055) (xy 27.323084 -295.770964)
			(xy 27.35038 -295.722329) (xy 27.384466 -295.678186) (xy 27.424615 -295.639477) (xy 27.469973 -295.607026)
			(xy 27.519573 -295.581525) (xy 27.572357 -295.563518) (xy 27.6272 -295.553388) (xy 27.682934 -295.551351)
			(xy 27.738371 -295.557451) (xy 27.792328 -295.571557) (xy 27.843657 -295.593369) (xy 27.891263 -295.622423)
			(xy 27.934131 -295.658098) (xy 27.971348 -295.699635) (xy 28.002121 -295.746148) (xy 28.025793 -295.796645)
			(xy 28.041861 -295.850052) (xy 28.049981 -295.905228) (xy 28.05049 -295.933114) (xy 28.175964 -295.933114)
			(xy 28.180035 -295.877492) (xy 28.192161 -295.823055) (xy 28.212084 -295.770964) (xy 28.23938 -295.722329)
			(xy 28.273466 -295.678186) (xy 28.313615 -295.639477) (xy 28.358973 -295.607026) (xy 28.408573 -295.581525)
			(xy 28.461357 -295.563518) (xy 28.5162 -295.553388) (xy 28.571934 -295.551351) (xy 28.627371 -295.557451)
			(xy 28.681328 -295.571557) (xy 28.732657 -295.593369) (xy 28.780263 -295.622423) (xy 28.823131 -295.658098)
			(xy 28.860348 -295.699635) (xy 28.891121 -295.746148) (xy 28.914793 -295.796645) (xy 28.930861 -295.850052)
			(xy 28.938981 -295.905228) (xy 28.93949 -295.933114) (xy 28.938981 -295.961) (xy 28.930861 -296.016176)
			(xy 28.914793 -296.069583) (xy 28.891121 -296.12008) (xy 28.860348 -296.166593) (xy 28.823131 -296.20813)
			(xy 28.780263 -296.243805) (xy 28.732657 -296.272859) (xy 28.681328 -296.294671) (xy 28.627371 -296.308777)
			(xy 28.571934 -296.314877) (xy 28.5162 -296.31284) (xy 28.461357 -296.30271) (xy 28.408573 -296.284703)
			(xy 28.358973 -296.259202) (xy 28.313615 -296.226751) (xy 28.273466 -296.188042) (xy 28.23938 -296.143899)
			(xy 28.212084 -296.095264) (xy 28.192161 -296.043173) (xy 28.180035 -295.988736) (xy 28.175964 -295.933114)
			(xy 28.05049 -295.933114) (xy 28.049981 -295.961) (xy 28.041861 -296.016176) (xy 28.025793 -296.069583)
			(xy 28.002121 -296.12008) (xy 27.971348 -296.166593) (xy 27.934131 -296.20813) (xy 27.891263 -296.243805)
			(xy 27.843657 -296.272859) (xy 27.792328 -296.294671) (xy 27.738371 -296.308777) (xy 27.682934 -296.314877)
			(xy 27.6272 -296.31284) (xy 27.572357 -296.30271) (xy 27.519573 -296.284703) (xy 27.469973 -296.259202)
			(xy 27.424615 -296.226751) (xy 27.384466 -296.188042) (xy 27.35038 -296.143899) (xy 27.323084 -296.095264)
			(xy 27.303161 -296.043173) (xy 27.291035 -295.988736) (xy 27.286964 -295.933114) (xy 26.575004 -295.933114)
			(xy 26.574495 -295.961) (xy 26.566375 -296.016176) (xy 26.550307 -296.069583) (xy 26.526635 -296.12008)
			(xy 26.495862 -296.166593) (xy 26.458645 -296.20813) (xy 26.415777 -296.243805) (xy 26.368171 -296.272859)
			(xy 26.316842 -296.294671) (xy 26.262885 -296.308777) (xy 26.207448 -296.314877) (xy 26.151714 -296.31284)
			(xy 26.096871 -296.30271) (xy 26.044087 -296.284703) (xy 25.994487 -296.259202) (xy 25.949129 -296.226751)
			(xy 25.90898 -296.188042) (xy 25.874894 -296.143899) (xy 25.847598 -296.095264) (xy 25.827675 -296.043173)
			(xy 25.815549 -295.988736) (xy 25.811478 -295.933114) (xy 1.660398 -295.933114) (xy 1.660398 -296.722038)
			(xy 31.234888 -296.722038) (xy 31.235327 -296.69546) (xy 31.242726 -296.64282) (xy 31.257359 -296.591717)
			(xy 31.278942 -296.543139) (xy 31.307058 -296.498026) (xy 31.341163 -296.457252) (xy 31.380596 -296.421605)
			(xy 31.424594 -296.391776) (xy 31.448248 -296.379646) (xy 31.460777 -296.373066) (xy 31.481831 -296.354171)
			(xy 31.49689 -296.330222) (xy 31.504794 -296.303059) (xy 31.504938 -296.274769) (xy 31.49731 -296.247527)
			(xy 31.482496 -296.223426) (xy 31.472378 -296.21353) (xy 31.45335 -296.195417) (xy 31.419969 -296.154851)
			(xy 31.392474 -296.110087) (xy 31.371382 -296.061972) (xy 31.357095 -296.011418) (xy 31.349882 -295.959381)
			(xy 31.349442 -295.933114) (xy 31.349928 -295.905863) (xy 31.357684 -295.851915) (xy 31.373039 -295.79962)
			(xy 31.395681 -295.750043) (xy 31.425147 -295.704193) (xy 31.460838 -295.663002) (xy 31.502029 -295.627311)
			(xy 31.547879 -295.597845) (xy 31.597456 -295.575203) (xy 31.649751 -295.559848) (xy 31.703699 -295.552092)
			(xy 31.758201 -295.552092) (xy 31.812149 -295.559848) (xy 31.864444 -295.575203) (xy 31.914021 -295.597845)
			(xy 31.959871 -295.627311) (xy 32.001062 -295.663002) (xy 32.036753 -295.704193) (xy 32.066219 -295.750043)
			(xy 32.088861 -295.79962) (xy 32.104216 -295.851915) (xy 32.111972 -295.905863) (xy 32.112458 -295.933114)
			(xy 32.111954 -295.95969) (xy 32.104562 -296.012325) (xy 32.089937 -296.063426) (xy 32.068363 -296.112002)
			(xy 32.040256 -296.157115) (xy 32.006161 -296.19789) (xy 31.966737 -296.23354) (xy 31.922747 -296.263373)
			(xy 31.899098 -296.275506) (xy 31.886606 -296.282144) (xy 31.865564 -296.301033) (xy 31.850513 -296.32497)
			(xy 31.842608 -296.352119) (xy 31.842456 -296.380395) (xy 31.850069 -296.407627) (xy 31.864862 -296.431725)
			(xy 31.874968 -296.441622) (xy 31.893963 -296.459769) (xy 31.927348 -296.500326) (xy 31.95485 -296.545083)
			(xy 31.975947 -296.593191) (xy 31.990241 -296.64374) (xy 31.99737 -296.695114) (xy 33.620962 -296.695114)
			(xy 33.625033 -296.639492) (xy 33.637159 -296.585055) (xy 33.657082 -296.532964) (xy 33.684378 -296.484329)
			(xy 33.718464 -296.440186) (xy 33.758613 -296.401477) (xy 33.803971 -296.369026) (xy 33.853571 -296.343525)
			(xy 33.906355 -296.325518) (xy 33.961198 -296.315388) (xy 34.016932 -296.313351) (xy 34.072369 -296.319451)
			(xy 34.126326 -296.333557) (xy 34.177655 -296.355369) (xy 34.209526 -296.37482) (xy 37.019242 -296.37482)
			(xy 37.023202 -296.325766) (xy 37.034979 -296.277982) (xy 37.05427 -296.232706) (xy 37.080573 -296.19111)
			(xy 37.113208 -296.154273) (xy 37.151329 -296.123148) (xy 37.19395 -296.098541) (xy 37.239966 -296.081089)
			(xy 37.288185 -296.071245) (xy 37.33736 -296.069264) (xy 37.386215 -296.075196) (xy 37.433486 -296.088888)
			(xy 37.477948 -296.109986) (xy 37.518451 -296.137942) (xy 37.553944 -296.172034) (xy 37.583509 -296.211378)
			(xy 37.60638 -296.254955) (xy 37.621964 -296.301636) (xy 37.629859 -296.350213) (xy 37.630354 -296.37482)
			(xy 37.968948 -296.37482) (xy 37.972908 -296.325766) (xy 37.984685 -296.277982) (xy 38.003976 -296.232706)
			(xy 38.030279 -296.19111) (xy 38.062914 -296.154273) (xy 38.101035 -296.123148) (xy 38.143656 -296.098541)
			(xy 38.189672 -296.081089) (xy 38.237891 -296.071245) (xy 38.287066 -296.069264) (xy 38.335921 -296.075196)
			(xy 38.383192 -296.088888) (xy 38.427654 -296.109986) (xy 38.468157 -296.137942) (xy 38.50365 -296.172034)
			(xy 38.533215 -296.211378) (xy 38.556086 -296.254955) (xy 38.57167 -296.301636) (xy 38.579565 -296.350213)
			(xy 38.58006 -296.37482) (xy 38.919162 -296.37482) (xy 38.923122 -296.325766) (xy 38.934899 -296.277982)
			(xy 38.95419 -296.232706) (xy 38.980493 -296.19111) (xy 39.013128 -296.154273) (xy 39.051249 -296.123148)
			(xy 39.09387 -296.098541) (xy 39.139886 -296.081089) (xy 39.188105 -296.071245) (xy 39.23728 -296.069264)
			(xy 39.286135 -296.075196) (xy 39.333406 -296.088888) (xy 39.377868 -296.109986) (xy 39.418371 -296.137942)
			(xy 39.453864 -296.172034) (xy 39.483429 -296.211378) (xy 39.5063 -296.254955) (xy 39.521884 -296.301636)
			(xy 39.529779 -296.350213) (xy 39.530274 -296.37482) (xy 39.869122 -296.37482) (xy 39.873082 -296.325766)
			(xy 39.884859 -296.277982) (xy 39.90415 -296.232706) (xy 39.930453 -296.19111) (xy 39.963088 -296.154273)
			(xy 40.001209 -296.123148) (xy 40.04383 -296.098541) (xy 40.089846 -296.081089) (xy 40.138065 -296.071245)
			(xy 40.18724 -296.069264) (xy 40.236095 -296.075196) (xy 40.283366 -296.088888) (xy 40.327828 -296.109986)
			(xy 40.368331 -296.137942) (xy 40.403824 -296.172034) (xy 40.433389 -296.211378) (xy 40.45626 -296.254955)
			(xy 40.471844 -296.301636) (xy 40.479739 -296.350213) (xy 40.480234 -296.37482) (xy 41.769042 -296.37482)
			(xy 41.773002 -296.325766) (xy 41.784779 -296.277982) (xy 41.80407 -296.232706) (xy 41.830373 -296.19111)
			(xy 41.863008 -296.154273) (xy 41.901129 -296.123148) (xy 41.94375 -296.098541) (xy 41.989766 -296.081089)
			(xy 42.037985 -296.071245) (xy 42.08716 -296.069264) (xy 42.136015 -296.075196) (xy 42.183286 -296.088888)
			(xy 42.227748 -296.109986) (xy 42.268251 -296.137942) (xy 42.303744 -296.172034) (xy 42.333309 -296.211378)
			(xy 42.35618 -296.254955) (xy 42.371764 -296.301636) (xy 42.379659 -296.350213) (xy 42.380154 -296.37482)
			(xy 43.668962 -296.37482) (xy 43.672922 -296.325766) (xy 43.684699 -296.277982) (xy 43.70399 -296.232706)
			(xy 43.730293 -296.19111) (xy 43.762928 -296.154273) (xy 43.801049 -296.123148) (xy 43.84367 -296.098541)
			(xy 43.889686 -296.081089) (xy 43.937905 -296.071245) (xy 43.98708 -296.069264) (xy 44.035935 -296.075196)
			(xy 44.083206 -296.088888) (xy 44.127668 -296.109986) (xy 44.168171 -296.137942) (xy 44.203664 -296.172034)
			(xy 44.233229 -296.211378) (xy 44.2561 -296.254955) (xy 44.271684 -296.301636) (xy 44.279579 -296.350213)
			(xy 44.280074 -296.37482) (xy 44.619176 -296.37482) (xy 44.623136 -296.325766) (xy 44.634913 -296.277982)
			(xy 44.654204 -296.232706) (xy 44.680507 -296.19111) (xy 44.713142 -296.154273) (xy 44.751263 -296.123148)
			(xy 44.793884 -296.098541) (xy 44.8399 -296.081089) (xy 44.888119 -296.071245) (xy 44.937294 -296.069264)
			(xy 44.986149 -296.075196) (xy 45.03342 -296.088888) (xy 45.077882 -296.109986) (xy 45.118385 -296.137942)
			(xy 45.153878 -296.172034) (xy 45.183443 -296.211378) (xy 45.206314 -296.254955) (xy 45.221898 -296.301636)
			(xy 45.229793 -296.350213) (xy 45.230288 -296.37482) (xy 45.569136 -296.37482) (xy 45.573096 -296.325766)
			(xy 45.584873 -296.277982) (xy 45.604164 -296.232706) (xy 45.630467 -296.19111) (xy 45.663102 -296.154273)
			(xy 45.701223 -296.123148) (xy 45.743844 -296.098541) (xy 45.78986 -296.081089) (xy 45.838079 -296.071245)
			(xy 45.887254 -296.069264) (xy 45.936109 -296.075196) (xy 45.98338 -296.088888) (xy 46.027842 -296.109986)
			(xy 46.068345 -296.137942) (xy 46.103838 -296.172034) (xy 46.133403 -296.211378) (xy 46.156274 -296.254955)
			(xy 46.171858 -296.301636) (xy 46.179753 -296.350213) (xy 46.180248 -296.37482) (xy 47.469056 -296.37482)
			(xy 47.473016 -296.325766) (xy 47.484793 -296.277982) (xy 47.504084 -296.232706) (xy 47.530387 -296.19111)
			(xy 47.563022 -296.154273) (xy 47.601143 -296.123148) (xy 47.643764 -296.098541) (xy 47.68978 -296.081089)
			(xy 47.737999 -296.071245) (xy 47.787174 -296.069264) (xy 47.836029 -296.075196) (xy 47.8833 -296.088888)
			(xy 47.927762 -296.109986) (xy 47.968265 -296.137942) (xy 48.003758 -296.172034) (xy 48.033323 -296.211378)
			(xy 48.056194 -296.254955) (xy 48.071778 -296.301636) (xy 48.079673 -296.350213) (xy 48.080168 -296.37482)
			(xy 48.419016 -296.37482) (xy 48.422976 -296.325766) (xy 48.434753 -296.277982) (xy 48.454044 -296.232706)
			(xy 48.480347 -296.19111) (xy 48.512982 -296.154273) (xy 48.551103 -296.123148) (xy 48.593724 -296.098541)
			(xy 48.63974 -296.081089) (xy 48.687959 -296.071245) (xy 48.737134 -296.069264) (xy 48.785989 -296.075196)
			(xy 48.83326 -296.088888) (xy 48.877722 -296.109986) (xy 48.918225 -296.137942) (xy 48.953718 -296.172034)
			(xy 48.983283 -296.211378) (xy 49.006154 -296.254955) (xy 49.021738 -296.301636) (xy 49.029633 -296.350213)
			(xy 49.030128 -296.37482) (xy 49.368976 -296.37482) (xy 49.372936 -296.325766) (xy 49.384713 -296.277982)
			(xy 49.404004 -296.232706) (xy 49.430307 -296.19111) (xy 49.462942 -296.154273) (xy 49.501063 -296.123148)
			(xy 49.543684 -296.098541) (xy 49.5897 -296.081089) (xy 49.637919 -296.071245) (xy 49.687094 -296.069264)
			(xy 49.735949 -296.075196) (xy 49.78322 -296.088888) (xy 49.827682 -296.109986) (xy 49.868185 -296.137942)
			(xy 49.903678 -296.172034) (xy 49.933243 -296.211378) (xy 49.956114 -296.254955) (xy 49.971698 -296.301636)
			(xy 49.979593 -296.350213) (xy 49.980088 -296.37482) (xy 50.31919 -296.37482) (xy 50.32315 -296.325766)
			(xy 50.334927 -296.277982) (xy 50.354218 -296.232706) (xy 50.380521 -296.19111) (xy 50.413156 -296.154273)
			(xy 50.451277 -296.123148) (xy 50.493898 -296.098541) (xy 50.539914 -296.081089) (xy 50.588133 -296.071245)
			(xy 50.637308 -296.069264) (xy 50.686163 -296.075196) (xy 50.733434 -296.088888) (xy 50.777896 -296.109986)
			(xy 50.818399 -296.137942) (xy 50.853892 -296.172034) (xy 50.883457 -296.211378) (xy 50.906328 -296.254955)
			(xy 50.921912 -296.301636) (xy 50.929807 -296.350213) (xy 50.930302 -296.37482) (xy 51.26915 -296.37482)
			(xy 51.27311 -296.325766) (xy 51.284887 -296.277982) (xy 51.304178 -296.232706) (xy 51.330481 -296.19111)
			(xy 51.363116 -296.154273) (xy 51.401237 -296.123148) (xy 51.443858 -296.098541) (xy 51.489874 -296.081089)
			(xy 51.538093 -296.071245) (xy 51.587268 -296.069264) (xy 51.636123 -296.075196) (xy 51.683394 -296.088888)
			(xy 51.727856 -296.109986) (xy 51.768359 -296.137942) (xy 51.803852 -296.172034) (xy 51.833417 -296.211378)
			(xy 51.856288 -296.254955) (xy 51.871872 -296.301636) (xy 51.879767 -296.350213) (xy 51.880262 -296.37482)
			(xy 52.21911 -296.37482) (xy 52.22307 -296.325766) (xy 52.234847 -296.277982) (xy 52.254138 -296.232706)
			(xy 52.280441 -296.19111) (xy 52.313076 -296.154273) (xy 52.351197 -296.123148) (xy 52.393818 -296.098541)
			(xy 52.439834 -296.081089) (xy 52.488053 -296.071245) (xy 52.537228 -296.069264) (xy 52.586083 -296.075196)
			(xy 52.633354 -296.088888) (xy 52.677816 -296.109986) (xy 52.718319 -296.137942) (xy 52.753812 -296.172034)
			(xy 52.783377 -296.211378) (xy 52.806248 -296.254955) (xy 52.821832 -296.301636) (xy 52.829727 -296.350213)
			(xy 52.830222 -296.37482) (xy 53.16907 -296.37482) (xy 53.17303 -296.325766) (xy 53.184807 -296.277982)
			(xy 53.204098 -296.232706) (xy 53.230401 -296.19111) (xy 53.263036 -296.154273) (xy 53.301157 -296.123148)
			(xy 53.343778 -296.098541) (xy 53.389794 -296.081089) (xy 53.438013 -296.071245) (xy 53.487188 -296.069264)
			(xy 53.536043 -296.075196) (xy 53.583314 -296.088888) (xy 53.627776 -296.109986) (xy 53.668279 -296.137942)
			(xy 53.703772 -296.172034) (xy 53.733337 -296.211378) (xy 53.756208 -296.254955) (xy 53.771792 -296.301636)
			(xy 53.779687 -296.350213) (xy 53.780182 -296.37482) (xy 54.11903 -296.37482) (xy 54.12299 -296.325766)
			(xy 54.134767 -296.277982) (xy 54.154058 -296.232706) (xy 54.180361 -296.19111) (xy 54.212996 -296.154273)
			(xy 54.251117 -296.123148) (xy 54.293738 -296.098541) (xy 54.339754 -296.081089) (xy 54.387973 -296.071245)
			(xy 54.437148 -296.069264) (xy 54.486003 -296.075196) (xy 54.533274 -296.088888) (xy 54.577736 -296.109986)
			(xy 54.618239 -296.137942) (xy 54.653732 -296.172034) (xy 54.683297 -296.211378) (xy 54.706168 -296.254955)
			(xy 54.721752 -296.301636) (xy 54.729647 -296.350213) (xy 54.730142 -296.37482) (xy 55.06899 -296.37482)
			(xy 55.07295 -296.325766) (xy 55.084727 -296.277982) (xy 55.104018 -296.232706) (xy 55.130321 -296.19111)
			(xy 55.162956 -296.154273) (xy 55.201077 -296.123148) (xy 55.243698 -296.098541) (xy 55.289714 -296.081089)
			(xy 55.337933 -296.071245) (xy 55.387108 -296.069264) (xy 55.435963 -296.075196) (xy 55.483234 -296.088888)
			(xy 55.527696 -296.109986) (xy 55.568199 -296.137942) (xy 55.603692 -296.172034) (xy 55.633257 -296.211378)
			(xy 55.656128 -296.254955) (xy 55.671712 -296.301636) (xy 55.679607 -296.350213) (xy 55.680102 -296.37482)
			(xy 56.019204 -296.37482) (xy 56.023164 -296.325766) (xy 56.034941 -296.277982) (xy 56.054232 -296.232706)
			(xy 56.080535 -296.19111) (xy 56.11317 -296.154273) (xy 56.151291 -296.123148) (xy 56.193912 -296.098541)
			(xy 56.239928 -296.081089) (xy 56.288147 -296.071245) (xy 56.337322 -296.069264) (xy 56.386177 -296.075196)
			(xy 56.433448 -296.088888) (xy 56.47791 -296.109986) (xy 56.518413 -296.137942) (xy 56.553906 -296.172034)
			(xy 56.583471 -296.211378) (xy 56.606342 -296.254955) (xy 56.621926 -296.301636) (xy 56.629821 -296.350213)
			(xy 56.630316 -296.37482) (xy 56.969164 -296.37482) (xy 56.973124 -296.325766) (xy 56.984901 -296.277982)
			(xy 57.004192 -296.232706) (xy 57.030495 -296.19111) (xy 57.06313 -296.154273) (xy 57.101251 -296.123148)
			(xy 57.143872 -296.098541) (xy 57.189888 -296.081089) (xy 57.238107 -296.071245) (xy 57.287282 -296.069264)
			(xy 57.336137 -296.075196) (xy 57.383408 -296.088888) (xy 57.42787 -296.109986) (xy 57.468373 -296.137942)
			(xy 57.503866 -296.172034) (xy 57.533431 -296.211378) (xy 57.556302 -296.254955) (xy 57.571886 -296.301636)
			(xy 57.579781 -296.350213) (xy 57.580276 -296.37482) (xy 57.919124 -296.37482) (xy 57.923084 -296.325766)
			(xy 57.934861 -296.277982) (xy 57.954152 -296.232706) (xy 57.980455 -296.19111) (xy 58.01309 -296.154273)
			(xy 58.051211 -296.123148) (xy 58.093832 -296.098541) (xy 58.139848 -296.081089) (xy 58.188067 -296.071245)
			(xy 58.237242 -296.069264) (xy 58.286097 -296.075196) (xy 58.333368 -296.088888) (xy 58.37783 -296.109986)
			(xy 58.418333 -296.137942) (xy 58.453826 -296.172034) (xy 58.483391 -296.211378) (xy 58.506262 -296.254955)
			(xy 58.521846 -296.301636) (xy 58.529741 -296.350213) (xy 58.530236 -296.37482) (xy 59.819044 -296.37482)
			(xy 59.823004 -296.325766) (xy 59.834781 -296.277982) (xy 59.854072 -296.232706) (xy 59.880375 -296.19111)
			(xy 59.91301 -296.154273) (xy 59.951131 -296.123148) (xy 59.993752 -296.098541) (xy 60.039768 -296.081089)
			(xy 60.087987 -296.071245) (xy 60.137162 -296.069264) (xy 60.186017 -296.075196) (xy 60.233288 -296.088888)
			(xy 60.27775 -296.109986) (xy 60.318253 -296.137942) (xy 60.353746 -296.172034) (xy 60.383311 -296.211378)
			(xy 60.406182 -296.254955) (xy 60.421766 -296.301636) (xy 60.429661 -296.350213) (xy 60.430156 -296.37482)
			(xy 60.769004 -296.37482) (xy 60.772964 -296.325766) (xy 60.784741 -296.277982) (xy 60.804032 -296.232706)
			(xy 60.830335 -296.19111) (xy 60.86297 -296.154273) (xy 60.901091 -296.123148) (xy 60.943712 -296.098541)
			(xy 60.989728 -296.081089) (xy 61.037947 -296.071245) (xy 61.087122 -296.069264) (xy 61.135977 -296.075196)
			(xy 61.183248 -296.088888) (xy 61.22771 -296.109986) (xy 61.268213 -296.137942) (xy 61.303706 -296.172034)
			(xy 61.333271 -296.211378) (xy 61.356142 -296.254955) (xy 61.371726 -296.301636) (xy 61.379621 -296.350213)
			(xy 61.380116 -296.37482) (xy 61.718964 -296.37482) (xy 61.722924 -296.325766) (xy 61.734701 -296.277982)
			(xy 61.753992 -296.232706) (xy 61.780295 -296.19111) (xy 61.81293 -296.154273) (xy 61.851051 -296.123148)
			(xy 61.893672 -296.098541) (xy 61.939688 -296.081089) (xy 61.987907 -296.071245) (xy 62.037082 -296.069264)
			(xy 62.085937 -296.075196) (xy 62.133208 -296.088888) (xy 62.17767 -296.109986) (xy 62.218173 -296.137942)
			(xy 62.253666 -296.172034) (xy 62.283231 -296.211378) (xy 62.306102 -296.254955) (xy 62.321686 -296.301636)
			(xy 62.329581 -296.350213) (xy 62.330076 -296.37482) (xy 62.669178 -296.37482) (xy 62.673138 -296.325766)
			(xy 62.684915 -296.277982) (xy 62.704206 -296.232706) (xy 62.730509 -296.19111) (xy 62.763144 -296.154273)
			(xy 62.801265 -296.123148) (xy 62.843886 -296.098541) (xy 62.889902 -296.081089) (xy 62.938121 -296.071245)
			(xy 62.987296 -296.069264) (xy 63.036151 -296.075196) (xy 63.083422 -296.088888) (xy 63.127884 -296.109986)
			(xy 63.168387 -296.137942) (xy 63.20388 -296.172034) (xy 63.233445 -296.211378) (xy 63.256316 -296.254955)
			(xy 63.2719 -296.301636) (xy 63.279795 -296.350213) (xy 63.28029 -296.37482) (xy 63.619138 -296.37482)
			(xy 63.623098 -296.325766) (xy 63.634875 -296.277982) (xy 63.654166 -296.232706) (xy 63.680469 -296.19111)
			(xy 63.713104 -296.154273) (xy 63.751225 -296.123148) (xy 63.793846 -296.098541) (xy 63.839862 -296.081089)
			(xy 63.888081 -296.071245) (xy 63.937256 -296.069264) (xy 63.986111 -296.075196) (xy 64.033382 -296.088888)
			(xy 64.077844 -296.109986) (xy 64.118347 -296.137942) (xy 64.15384 -296.172034) (xy 64.183405 -296.211378)
			(xy 64.206276 -296.254955) (xy 64.22186 -296.301636) (xy 64.229755 -296.350213) (xy 64.23025 -296.37482)
			(xy 64.569098 -296.37482) (xy 64.573058 -296.325766) (xy 64.584835 -296.277982) (xy 64.604126 -296.232706)
			(xy 64.630429 -296.19111) (xy 64.663064 -296.154273) (xy 64.701185 -296.123148) (xy 64.743806 -296.098541)
			(xy 64.789822 -296.081089) (xy 64.838041 -296.071245) (xy 64.887216 -296.069264) (xy 64.936071 -296.075196)
			(xy 64.983342 -296.088888) (xy 65.027804 -296.109986) (xy 65.068307 -296.137942) (xy 65.1038 -296.172034)
			(xy 65.133365 -296.211378) (xy 65.156236 -296.254955) (xy 65.17182 -296.301636) (xy 65.179715 -296.350213)
			(xy 65.18021 -296.37482) (xy 65.519058 -296.37482) (xy 65.523018 -296.325766) (xy 65.534795 -296.277982)
			(xy 65.554086 -296.232706) (xy 65.580389 -296.19111) (xy 65.613024 -296.154273) (xy 65.651145 -296.123148)
			(xy 65.693766 -296.098541) (xy 65.739782 -296.081089) (xy 65.788001 -296.071245) (xy 65.837176 -296.069264)
			(xy 65.886031 -296.075196) (xy 65.933302 -296.088888) (xy 65.977764 -296.109986) (xy 66.018267 -296.137942)
			(xy 66.05376 -296.172034) (xy 66.083325 -296.211378) (xy 66.106196 -296.254955) (xy 66.12178 -296.301636)
			(xy 66.129675 -296.350213) (xy 66.13017 -296.37482) (xy 66.469018 -296.37482) (xy 66.472978 -296.325766)
			(xy 66.484755 -296.277982) (xy 66.504046 -296.232706) (xy 66.530349 -296.19111) (xy 66.562984 -296.154273)
			(xy 66.601105 -296.123148) (xy 66.643726 -296.098541) (xy 66.689742 -296.081089) (xy 66.737961 -296.071245)
			(xy 66.787136 -296.069264) (xy 66.835991 -296.075196) (xy 66.883262 -296.088888) (xy 66.927724 -296.109986)
			(xy 66.968227 -296.137942) (xy 67.00372 -296.172034) (xy 67.033285 -296.211378) (xy 67.056156 -296.254955)
			(xy 67.07174 -296.301636) (xy 67.079635 -296.350213) (xy 67.08013 -296.37482) (xy 67.418978 -296.37482)
			(xy 67.422938 -296.325766) (xy 67.434715 -296.277982) (xy 67.454006 -296.232706) (xy 67.480309 -296.19111)
			(xy 67.512944 -296.154273) (xy 67.551065 -296.123148) (xy 67.593686 -296.098541) (xy 67.639702 -296.081089)
			(xy 67.687921 -296.071245) (xy 67.737096 -296.069264) (xy 67.785951 -296.075196) (xy 67.833222 -296.088888)
			(xy 67.877684 -296.109986) (xy 67.918187 -296.137942) (xy 67.95368 -296.172034) (xy 67.983245 -296.211378)
			(xy 68.006116 -296.254955) (xy 68.0217 -296.301636) (xy 68.029595 -296.350213) (xy 68.03009 -296.37482)
			(xy 68.368938 -296.37482) (xy 68.372898 -296.325766) (xy 68.384675 -296.277982) (xy 68.403966 -296.232706)
			(xy 68.430269 -296.19111) (xy 68.462904 -296.154273) (xy 68.501025 -296.123148) (xy 68.543646 -296.098541)
			(xy 68.589662 -296.081089) (xy 68.637881 -296.071245) (xy 68.687056 -296.069264) (xy 68.735911 -296.075196)
			(xy 68.783182 -296.088888) (xy 68.827644 -296.109986) (xy 68.868147 -296.137942) (xy 68.90364 -296.172034)
			(xy 68.933205 -296.211378) (xy 68.956076 -296.254955) (xy 68.97166 -296.301636) (xy 68.979555 -296.350213)
			(xy 68.98005 -296.37482) (xy 69.319152 -296.37482) (xy 69.323112 -296.325766) (xy 69.334889 -296.277982)
			(xy 69.35418 -296.232706) (xy 69.380483 -296.19111) (xy 69.413118 -296.154273) (xy 69.451239 -296.123148)
			(xy 69.49386 -296.098541) (xy 69.539876 -296.081089) (xy 69.588095 -296.071245) (xy 69.63727 -296.069264)
			(xy 69.686125 -296.075196) (xy 69.733396 -296.088888) (xy 69.777858 -296.109986) (xy 69.818361 -296.137942)
			(xy 69.853854 -296.172034) (xy 69.883419 -296.211378) (xy 69.90629 -296.254955) (xy 69.921874 -296.301636)
			(xy 69.929769 -296.350213) (xy 69.930264 -296.37482) (xy 71.219072 -296.37482) (xy 71.223032 -296.325766)
			(xy 71.234809 -296.277982) (xy 71.2541 -296.232706) (xy 71.280403 -296.19111) (xy 71.313038 -296.154273)
			(xy 71.351159 -296.123148) (xy 71.39378 -296.098541) (xy 71.439796 -296.081089) (xy 71.488015 -296.071245)
			(xy 71.53719 -296.069264) (xy 71.586045 -296.075196) (xy 71.633316 -296.088888) (xy 71.677778 -296.109986)
			(xy 71.718281 -296.137942) (xy 71.753774 -296.172034) (xy 71.783339 -296.211378) (xy 71.80621 -296.254955)
			(xy 71.821794 -296.301636) (xy 71.829689 -296.350213) (xy 71.830184 -296.37482) (xy 72.169032 -296.37482)
			(xy 72.172992 -296.325766) (xy 72.184769 -296.277982) (xy 72.20406 -296.232706) (xy 72.230363 -296.19111)
			(xy 72.262998 -296.154273) (xy 72.301119 -296.123148) (xy 72.34374 -296.098541) (xy 72.389756 -296.081089)
			(xy 72.437975 -296.071245) (xy 72.48715 -296.069264) (xy 72.536005 -296.075196) (xy 72.583276 -296.088888)
			(xy 72.627738 -296.109986) (xy 72.668241 -296.137942) (xy 72.703734 -296.172034) (xy 72.733299 -296.211378)
			(xy 72.75617 -296.254955) (xy 72.771754 -296.301636) (xy 72.779649 -296.350213) (xy 72.780144 -296.37482)
			(xy 73.118992 -296.37482) (xy 73.122952 -296.325766) (xy 73.134729 -296.277982) (xy 73.15402 -296.232706)
			(xy 73.180323 -296.19111) (xy 73.212958 -296.154273) (xy 73.251079 -296.123148) (xy 73.2937 -296.098541)
			(xy 73.339716 -296.081089) (xy 73.387935 -296.071245) (xy 73.43711 -296.069264) (xy 73.485965 -296.075196)
			(xy 73.533236 -296.088888) (xy 73.577698 -296.109986) (xy 73.618201 -296.137942) (xy 73.653694 -296.172034)
			(xy 73.683259 -296.211378) (xy 73.70613 -296.254955) (xy 73.721714 -296.301636) (xy 73.729609 -296.350213)
			(xy 73.730104 -296.37482) (xy 74.068952 -296.37482) (xy 74.072912 -296.325766) (xy 74.084689 -296.277982)
			(xy 74.10398 -296.232706) (xy 74.130283 -296.19111) (xy 74.162918 -296.154273) (xy 74.201039 -296.123148)
			(xy 74.24366 -296.098541) (xy 74.289676 -296.081089) (xy 74.337895 -296.071245) (xy 74.38707 -296.069264)
			(xy 74.435925 -296.075196) (xy 74.483196 -296.088888) (xy 74.527658 -296.109986) (xy 74.568161 -296.137942)
			(xy 74.603654 -296.172034) (xy 74.633219 -296.211378) (xy 74.65609 -296.254955) (xy 74.671674 -296.301636)
			(xy 74.679569 -296.350213) (xy 74.680064 -296.37482) (xy 75.019166 -296.37482) (xy 75.023126 -296.325766)
			(xy 75.034903 -296.277982) (xy 75.054194 -296.232706) (xy 75.080497 -296.19111) (xy 75.113132 -296.154273)
			(xy 75.151253 -296.123148) (xy 75.193874 -296.098541) (xy 75.23989 -296.081089) (xy 75.288109 -296.071245)
			(xy 75.337284 -296.069264) (xy 75.386139 -296.075196) (xy 75.43341 -296.088888) (xy 75.477872 -296.109986)
			(xy 75.518375 -296.137942) (xy 75.553868 -296.172034) (xy 75.583433 -296.211378) (xy 75.606304 -296.254955)
			(xy 75.621888 -296.301636) (xy 75.629783 -296.350213) (xy 75.630278 -296.37482) (xy 75.969126 -296.37482)
			(xy 75.973086 -296.325766) (xy 75.984863 -296.277982) (xy 76.004154 -296.232706) (xy 76.030457 -296.19111)
			(xy 76.063092 -296.154273) (xy 76.101213 -296.123148) (xy 76.143834 -296.098541) (xy 76.18985 -296.081089)
			(xy 76.238069 -296.071245) (xy 76.287244 -296.069264) (xy 76.336099 -296.075196) (xy 76.38337 -296.088888)
			(xy 76.427832 -296.109986) (xy 76.468335 -296.137942) (xy 76.503828 -296.172034) (xy 76.533393 -296.211378)
			(xy 76.556264 -296.254955) (xy 76.571848 -296.301636) (xy 76.579743 -296.350213) (xy 76.580238 -296.37482)
			(xy 76.579743 -296.399427) (xy 76.571848 -296.448004) (xy 76.556264 -296.494685) (xy 76.533393 -296.538262)
			(xy 76.503828 -296.577606) (xy 76.468335 -296.611698) (xy 76.427832 -296.639654) (xy 76.38337 -296.660752)
			(xy 76.336099 -296.674444) (xy 76.287244 -296.680376) (xy 76.238069 -296.678395) (xy 76.18985 -296.668551)
			(xy 76.143834 -296.651099) (xy 76.101213 -296.626492) (xy 76.063092 -296.595367) (xy 76.030457 -296.55853)
			(xy 76.004154 -296.516934) (xy 75.984863 -296.471658) (xy 75.973086 -296.423874) (xy 75.969126 -296.37482)
			(xy 75.630278 -296.37482) (xy 75.629783 -296.399427) (xy 75.621888 -296.448004) (xy 75.606304 -296.494685)
			(xy 75.583433 -296.538262) (xy 75.553868 -296.577606) (xy 75.518375 -296.611698) (xy 75.477872 -296.639654)
			(xy 75.43341 -296.660752) (xy 75.386139 -296.674444) (xy 75.337284 -296.680376) (xy 75.288109 -296.678395)
			(xy 75.23989 -296.668551) (xy 75.193874 -296.651099) (xy 75.151253 -296.626492) (xy 75.113132 -296.595367)
			(xy 75.080497 -296.55853) (xy 75.054194 -296.516934) (xy 75.034903 -296.471658) (xy 75.023126 -296.423874)
			(xy 75.019166 -296.37482) (xy 74.680064 -296.37482) (xy 74.679569 -296.399427) (xy 74.671674 -296.448004)
			(xy 74.65609 -296.494685) (xy 74.633219 -296.538262) (xy 74.603654 -296.577606) (xy 74.568161 -296.611698)
			(xy 74.527658 -296.639654) (xy 74.483196 -296.660752) (xy 74.435925 -296.674444) (xy 74.38707 -296.680376)
			(xy 74.337895 -296.678395) (xy 74.289676 -296.668551) (xy 74.24366 -296.651099) (xy 74.201039 -296.626492)
			(xy 74.162918 -296.595367) (xy 74.130283 -296.55853) (xy 74.10398 -296.516934) (xy 74.084689 -296.471658)
			(xy 74.072912 -296.423874) (xy 74.068952 -296.37482) (xy 73.730104 -296.37482) (xy 73.729609 -296.399427)
			(xy 73.721714 -296.448004) (xy 73.70613 -296.494685) (xy 73.683259 -296.538262) (xy 73.653694 -296.577606)
			(xy 73.618201 -296.611698) (xy 73.577698 -296.639654) (xy 73.533236 -296.660752) (xy 73.485965 -296.674444)
			(xy 73.43711 -296.680376) (xy 73.387935 -296.678395) (xy 73.339716 -296.668551) (xy 73.2937 -296.651099)
			(xy 73.251079 -296.626492) (xy 73.212958 -296.595367) (xy 73.180323 -296.55853) (xy 73.15402 -296.516934)
			(xy 73.134729 -296.471658) (xy 73.122952 -296.423874) (xy 73.118992 -296.37482) (xy 72.780144 -296.37482)
			(xy 72.779649 -296.399427) (xy 72.771754 -296.448004) (xy 72.75617 -296.494685) (xy 72.733299 -296.538262)
			(xy 72.703734 -296.577606) (xy 72.668241 -296.611698) (xy 72.627738 -296.639654) (xy 72.583276 -296.660752)
			(xy 72.536005 -296.674444) (xy 72.48715 -296.680376) (xy 72.437975 -296.678395) (xy 72.389756 -296.668551)
			(xy 72.34374 -296.651099) (xy 72.301119 -296.626492) (xy 72.262998 -296.595367) (xy 72.230363 -296.55853)
			(xy 72.20406 -296.516934) (xy 72.184769 -296.471658) (xy 72.172992 -296.423874) (xy 72.169032 -296.37482)
			(xy 71.830184 -296.37482) (xy 71.829689 -296.399427) (xy 71.821794 -296.448004) (xy 71.80621 -296.494685)
			(xy 71.783339 -296.538262) (xy 71.753774 -296.577606) (xy 71.718281 -296.611698) (xy 71.677778 -296.639654)
			(xy 71.633316 -296.660752) (xy 71.586045 -296.674444) (xy 71.53719 -296.680376) (xy 71.488015 -296.678395)
			(xy 71.439796 -296.668551) (xy 71.39378 -296.651099) (xy 71.351159 -296.626492) (xy 71.313038 -296.595367)
			(xy 71.280403 -296.55853) (xy 71.2541 -296.516934) (xy 71.234809 -296.471658) (xy 71.223032 -296.423874)
			(xy 71.219072 -296.37482) (xy 69.930264 -296.37482) (xy 69.929769 -296.399427) (xy 69.921874 -296.448004)
			(xy 69.90629 -296.494685) (xy 69.883419 -296.538262) (xy 69.853854 -296.577606) (xy 69.818361 -296.611698)
			(xy 69.777858 -296.639654) (xy 69.733396 -296.660752) (xy 69.686125 -296.674444) (xy 69.63727 -296.680376)
			(xy 69.588095 -296.678395) (xy 69.539876 -296.668551) (xy 69.49386 -296.651099) (xy 69.451239 -296.626492)
			(xy 69.413118 -296.595367) (xy 69.380483 -296.55853) (xy 69.35418 -296.516934) (xy 69.334889 -296.471658)
			(xy 69.323112 -296.423874) (xy 69.319152 -296.37482) (xy 68.98005 -296.37482) (xy 68.979555 -296.399427)
			(xy 68.97166 -296.448004) (xy 68.956076 -296.494685) (xy 68.933205 -296.538262) (xy 68.90364 -296.577606)
			(xy 68.868147 -296.611698) (xy 68.827644 -296.639654) (xy 68.783182 -296.660752) (xy 68.735911 -296.674444)
			(xy 68.687056 -296.680376) (xy 68.637881 -296.678395) (xy 68.589662 -296.668551) (xy 68.543646 -296.651099)
			(xy 68.501025 -296.626492) (xy 68.462904 -296.595367) (xy 68.430269 -296.55853) (xy 68.403966 -296.516934)
			(xy 68.384675 -296.471658) (xy 68.372898 -296.423874) (xy 68.368938 -296.37482) (xy 68.03009 -296.37482)
			(xy 68.029595 -296.399427) (xy 68.0217 -296.448004) (xy 68.006116 -296.494685) (xy 67.983245 -296.538262)
			(xy 67.95368 -296.577606) (xy 67.918187 -296.611698) (xy 67.877684 -296.639654) (xy 67.833222 -296.660752)
			(xy 67.785951 -296.674444) (xy 67.737096 -296.680376) (xy 67.687921 -296.678395) (xy 67.639702 -296.668551)
			(xy 67.593686 -296.651099) (xy 67.551065 -296.626492) (xy 67.512944 -296.595367) (xy 67.480309 -296.55853)
			(xy 67.454006 -296.516934) (xy 67.434715 -296.471658) (xy 67.422938 -296.423874) (xy 67.418978 -296.37482)
			(xy 67.08013 -296.37482) (xy 67.079635 -296.399427) (xy 67.07174 -296.448004) (xy 67.056156 -296.494685)
			(xy 67.033285 -296.538262) (xy 67.00372 -296.577606) (xy 66.968227 -296.611698) (xy 66.927724 -296.639654)
			(xy 66.883262 -296.660752) (xy 66.835991 -296.674444) (xy 66.787136 -296.680376) (xy 66.737961 -296.678395)
			(xy 66.689742 -296.668551) (xy 66.643726 -296.651099) (xy 66.601105 -296.626492) (xy 66.562984 -296.595367)
			(xy 66.530349 -296.55853) (xy 66.504046 -296.516934) (xy 66.484755 -296.471658) (xy 66.472978 -296.423874)
			(xy 66.469018 -296.37482) (xy 66.13017 -296.37482) (xy 66.129675 -296.399427) (xy 66.12178 -296.448004)
			(xy 66.106196 -296.494685) (xy 66.083325 -296.538262) (xy 66.05376 -296.577606) (xy 66.018267 -296.611698)
			(xy 65.977764 -296.639654) (xy 65.933302 -296.660752) (xy 65.886031 -296.674444) (xy 65.837176 -296.680376)
			(xy 65.788001 -296.678395) (xy 65.739782 -296.668551) (xy 65.693766 -296.651099) (xy 65.651145 -296.626492)
			(xy 65.613024 -296.595367) (xy 65.580389 -296.55853) (xy 65.554086 -296.516934) (xy 65.534795 -296.471658)
			(xy 65.523018 -296.423874) (xy 65.519058 -296.37482) (xy 65.18021 -296.37482) (xy 65.179715 -296.399427)
			(xy 65.17182 -296.448004) (xy 65.156236 -296.494685) (xy 65.133365 -296.538262) (xy 65.1038 -296.577606)
			(xy 65.068307 -296.611698) (xy 65.027804 -296.639654) (xy 64.983342 -296.660752) (xy 64.936071 -296.674444)
			(xy 64.887216 -296.680376) (xy 64.838041 -296.678395) (xy 64.789822 -296.668551) (xy 64.743806 -296.651099)
			(xy 64.701185 -296.626492) (xy 64.663064 -296.595367) (xy 64.630429 -296.55853) (xy 64.604126 -296.516934)
			(xy 64.584835 -296.471658) (xy 64.573058 -296.423874) (xy 64.569098 -296.37482) (xy 64.23025 -296.37482)
			(xy 64.229755 -296.399427) (xy 64.22186 -296.448004) (xy 64.206276 -296.494685) (xy 64.183405 -296.538262)
			(xy 64.15384 -296.577606) (xy 64.118347 -296.611698) (xy 64.077844 -296.639654) (xy 64.033382 -296.660752)
			(xy 63.986111 -296.674444) (xy 63.937256 -296.680376) (xy 63.888081 -296.678395) (xy 63.839862 -296.668551)
			(xy 63.793846 -296.651099) (xy 63.751225 -296.626492) (xy 63.713104 -296.595367) (xy 63.680469 -296.55853)
			(xy 63.654166 -296.516934) (xy 63.634875 -296.471658) (xy 63.623098 -296.423874) (xy 63.619138 -296.37482)
			(xy 63.28029 -296.37482) (xy 63.279795 -296.399427) (xy 63.2719 -296.448004) (xy 63.256316 -296.494685)
			(xy 63.233445 -296.538262) (xy 63.20388 -296.577606) (xy 63.168387 -296.611698) (xy 63.127884 -296.639654)
			(xy 63.083422 -296.660752) (xy 63.036151 -296.674444) (xy 62.987296 -296.680376) (xy 62.938121 -296.678395)
			(xy 62.889902 -296.668551) (xy 62.843886 -296.651099) (xy 62.801265 -296.626492) (xy 62.763144 -296.595367)
			(xy 62.730509 -296.55853) (xy 62.704206 -296.516934) (xy 62.684915 -296.471658) (xy 62.673138 -296.423874)
			(xy 62.669178 -296.37482) (xy 62.330076 -296.37482) (xy 62.329581 -296.399427) (xy 62.321686 -296.448004)
			(xy 62.306102 -296.494685) (xy 62.283231 -296.538262) (xy 62.253666 -296.577606) (xy 62.218173 -296.611698)
			(xy 62.17767 -296.639654) (xy 62.133208 -296.660752) (xy 62.085937 -296.674444) (xy 62.037082 -296.680376)
			(xy 61.987907 -296.678395) (xy 61.939688 -296.668551) (xy 61.893672 -296.651099) (xy 61.851051 -296.626492)
			(xy 61.81293 -296.595367) (xy 61.780295 -296.55853) (xy 61.753992 -296.516934) (xy 61.734701 -296.471658)
			(xy 61.722924 -296.423874) (xy 61.718964 -296.37482) (xy 61.380116 -296.37482) (xy 61.379621 -296.399427)
			(xy 61.371726 -296.448004) (xy 61.356142 -296.494685) (xy 61.333271 -296.538262) (xy 61.303706 -296.577606)
			(xy 61.268213 -296.611698) (xy 61.22771 -296.639654) (xy 61.183248 -296.660752) (xy 61.135977 -296.674444)
			(xy 61.087122 -296.680376) (xy 61.037947 -296.678395) (xy 60.989728 -296.668551) (xy 60.943712 -296.651099)
			(xy 60.901091 -296.626492) (xy 60.86297 -296.595367) (xy 60.830335 -296.55853) (xy 60.804032 -296.516934)
			(xy 60.784741 -296.471658) (xy 60.772964 -296.423874) (xy 60.769004 -296.37482) (xy 60.430156 -296.37482)
			(xy 60.429661 -296.399427) (xy 60.421766 -296.448004) (xy 60.406182 -296.494685) (xy 60.383311 -296.538262)
			(xy 60.353746 -296.577606) (xy 60.318253 -296.611698) (xy 60.27775 -296.639654) (xy 60.233288 -296.660752)
			(xy 60.186017 -296.674444) (xy 60.137162 -296.680376) (xy 60.087987 -296.678395) (xy 60.039768 -296.668551)
			(xy 59.993752 -296.651099) (xy 59.951131 -296.626492) (xy 59.91301 -296.595367) (xy 59.880375 -296.55853)
			(xy 59.854072 -296.516934) (xy 59.834781 -296.471658) (xy 59.823004 -296.423874) (xy 59.819044 -296.37482)
			(xy 58.530236 -296.37482) (xy 58.529741 -296.399427) (xy 58.521846 -296.448004) (xy 58.506262 -296.494685)
			(xy 58.483391 -296.538262) (xy 58.453826 -296.577606) (xy 58.418333 -296.611698) (xy 58.37783 -296.639654)
			(xy 58.333368 -296.660752) (xy 58.286097 -296.674444) (xy 58.237242 -296.680376) (xy 58.188067 -296.678395)
			(xy 58.139848 -296.668551) (xy 58.093832 -296.651099) (xy 58.051211 -296.626492) (xy 58.01309 -296.595367)
			(xy 57.980455 -296.55853) (xy 57.954152 -296.516934) (xy 57.934861 -296.471658) (xy 57.923084 -296.423874)
			(xy 57.919124 -296.37482) (xy 57.580276 -296.37482) (xy 57.579781 -296.399427) (xy 57.571886 -296.448004)
			(xy 57.556302 -296.494685) (xy 57.533431 -296.538262) (xy 57.503866 -296.577606) (xy 57.468373 -296.611698)
			(xy 57.42787 -296.639654) (xy 57.383408 -296.660752) (xy 57.336137 -296.674444) (xy 57.287282 -296.680376)
			(xy 57.238107 -296.678395) (xy 57.189888 -296.668551) (xy 57.143872 -296.651099) (xy 57.101251 -296.626492)
			(xy 57.06313 -296.595367) (xy 57.030495 -296.55853) (xy 57.004192 -296.516934) (xy 56.984901 -296.471658)
			(xy 56.973124 -296.423874) (xy 56.969164 -296.37482) (xy 56.630316 -296.37482) (xy 56.629821 -296.399427)
			(xy 56.621926 -296.448004) (xy 56.606342 -296.494685) (xy 56.583471 -296.538262) (xy 56.553906 -296.577606)
			(xy 56.518413 -296.611698) (xy 56.47791 -296.639654) (xy 56.433448 -296.660752) (xy 56.386177 -296.674444)
			(xy 56.337322 -296.680376) (xy 56.288147 -296.678395) (xy 56.239928 -296.668551) (xy 56.193912 -296.651099)
			(xy 56.151291 -296.626492) (xy 56.11317 -296.595367) (xy 56.080535 -296.55853) (xy 56.054232 -296.516934)
			(xy 56.034941 -296.471658) (xy 56.023164 -296.423874) (xy 56.019204 -296.37482) (xy 55.680102 -296.37482)
			(xy 55.679607 -296.399427) (xy 55.671712 -296.448004) (xy 55.656128 -296.494685) (xy 55.633257 -296.538262)
			(xy 55.603692 -296.577606) (xy 55.568199 -296.611698) (xy 55.527696 -296.639654) (xy 55.483234 -296.660752)
			(xy 55.435963 -296.674444) (xy 55.387108 -296.680376) (xy 55.337933 -296.678395) (xy 55.289714 -296.668551)
			(xy 55.243698 -296.651099) (xy 55.201077 -296.626492) (xy 55.162956 -296.595367) (xy 55.130321 -296.55853)
			(xy 55.104018 -296.516934) (xy 55.084727 -296.471658) (xy 55.07295 -296.423874) (xy 55.06899 -296.37482)
			(xy 54.730142 -296.37482) (xy 54.729647 -296.399427) (xy 54.721752 -296.448004) (xy 54.706168 -296.494685)
			(xy 54.683297 -296.538262) (xy 54.653732 -296.577606) (xy 54.618239 -296.611698) (xy 54.577736 -296.639654)
			(xy 54.533274 -296.660752) (xy 54.486003 -296.674444) (xy 54.437148 -296.680376) (xy 54.387973 -296.678395)
			(xy 54.339754 -296.668551) (xy 54.293738 -296.651099) (xy 54.251117 -296.626492) (xy 54.212996 -296.595367)
			(xy 54.180361 -296.55853) (xy 54.154058 -296.516934) (xy 54.134767 -296.471658) (xy 54.12299 -296.423874)
			(xy 54.11903 -296.37482) (xy 53.780182 -296.37482) (xy 53.779687 -296.399427) (xy 53.771792 -296.448004)
			(xy 53.756208 -296.494685) (xy 53.733337 -296.538262) (xy 53.703772 -296.577606) (xy 53.668279 -296.611698)
			(xy 53.627776 -296.639654) (xy 53.583314 -296.660752) (xy 53.536043 -296.674444) (xy 53.487188 -296.680376)
			(xy 53.438013 -296.678395) (xy 53.389794 -296.668551) (xy 53.343778 -296.651099) (xy 53.301157 -296.626492)
			(xy 53.263036 -296.595367) (xy 53.230401 -296.55853) (xy 53.204098 -296.516934) (xy 53.184807 -296.471658)
			(xy 53.17303 -296.423874) (xy 53.16907 -296.37482) (xy 52.830222 -296.37482) (xy 52.829727 -296.399427)
			(xy 52.821832 -296.448004) (xy 52.806248 -296.494685) (xy 52.783377 -296.538262) (xy 52.753812 -296.577606)
			(xy 52.718319 -296.611698) (xy 52.677816 -296.639654) (xy 52.633354 -296.660752) (xy 52.586083 -296.674444)
			(xy 52.537228 -296.680376) (xy 52.488053 -296.678395) (xy 52.439834 -296.668551) (xy 52.393818 -296.651099)
			(xy 52.351197 -296.626492) (xy 52.313076 -296.595367) (xy 52.280441 -296.55853) (xy 52.254138 -296.516934)
			(xy 52.234847 -296.471658) (xy 52.22307 -296.423874) (xy 52.21911 -296.37482) (xy 51.880262 -296.37482)
			(xy 51.879767 -296.399427) (xy 51.871872 -296.448004) (xy 51.856288 -296.494685) (xy 51.833417 -296.538262)
			(xy 51.803852 -296.577606) (xy 51.768359 -296.611698) (xy 51.727856 -296.639654) (xy 51.683394 -296.660752)
			(xy 51.636123 -296.674444) (xy 51.587268 -296.680376) (xy 51.538093 -296.678395) (xy 51.489874 -296.668551)
			(xy 51.443858 -296.651099) (xy 51.401237 -296.626492) (xy 51.363116 -296.595367) (xy 51.330481 -296.55853)
			(xy 51.304178 -296.516934) (xy 51.284887 -296.471658) (xy 51.27311 -296.423874) (xy 51.26915 -296.37482)
			(xy 50.930302 -296.37482) (xy 50.929807 -296.399427) (xy 50.921912 -296.448004) (xy 50.906328 -296.494685)
			(xy 50.883457 -296.538262) (xy 50.853892 -296.577606) (xy 50.818399 -296.611698) (xy 50.777896 -296.639654)
			(xy 50.733434 -296.660752) (xy 50.686163 -296.674444) (xy 50.637308 -296.680376) (xy 50.588133 -296.678395)
			(xy 50.539914 -296.668551) (xy 50.493898 -296.651099) (xy 50.451277 -296.626492) (xy 50.413156 -296.595367)
			(xy 50.380521 -296.55853) (xy 50.354218 -296.516934) (xy 50.334927 -296.471658) (xy 50.32315 -296.423874)
			(xy 50.31919 -296.37482) (xy 49.980088 -296.37482) (xy 49.979593 -296.399427) (xy 49.971698 -296.448004)
			(xy 49.956114 -296.494685) (xy 49.933243 -296.538262) (xy 49.903678 -296.577606) (xy 49.868185 -296.611698)
			(xy 49.827682 -296.639654) (xy 49.78322 -296.660752) (xy 49.735949 -296.674444) (xy 49.687094 -296.680376)
			(xy 49.637919 -296.678395) (xy 49.5897 -296.668551) (xy 49.543684 -296.651099) (xy 49.501063 -296.626492)
			(xy 49.462942 -296.595367) (xy 49.430307 -296.55853) (xy 49.404004 -296.516934) (xy 49.384713 -296.471658)
			(xy 49.372936 -296.423874) (xy 49.368976 -296.37482) (xy 49.030128 -296.37482) (xy 49.029633 -296.399427)
			(xy 49.021738 -296.448004) (xy 49.006154 -296.494685) (xy 48.983283 -296.538262) (xy 48.953718 -296.577606)
			(xy 48.918225 -296.611698) (xy 48.877722 -296.639654) (xy 48.83326 -296.660752) (xy 48.785989 -296.674444)
			(xy 48.737134 -296.680376) (xy 48.687959 -296.678395) (xy 48.63974 -296.668551) (xy 48.593724 -296.651099)
			(xy 48.551103 -296.626492) (xy 48.512982 -296.595367) (xy 48.480347 -296.55853) (xy 48.454044 -296.516934)
			(xy 48.434753 -296.471658) (xy 48.422976 -296.423874) (xy 48.419016 -296.37482) (xy 48.080168 -296.37482)
			(xy 48.079673 -296.399427) (xy 48.071778 -296.448004) (xy 48.056194 -296.494685) (xy 48.033323 -296.538262)
			(xy 48.003758 -296.577606) (xy 47.968265 -296.611698) (xy 47.927762 -296.639654) (xy 47.8833 -296.660752)
			(xy 47.836029 -296.674444) (xy 47.787174 -296.680376) (xy 47.737999 -296.678395) (xy 47.68978 -296.668551)
			(xy 47.643764 -296.651099) (xy 47.601143 -296.626492) (xy 47.563022 -296.595367) (xy 47.530387 -296.55853)
			(xy 47.504084 -296.516934) (xy 47.484793 -296.471658) (xy 47.473016 -296.423874) (xy 47.469056 -296.37482)
			(xy 46.180248 -296.37482) (xy 46.179753 -296.399427) (xy 46.171858 -296.448004) (xy 46.156274 -296.494685)
			(xy 46.133403 -296.538262) (xy 46.103838 -296.577606) (xy 46.068345 -296.611698) (xy 46.027842 -296.639654)
			(xy 45.98338 -296.660752) (xy 45.936109 -296.674444) (xy 45.887254 -296.680376) (xy 45.838079 -296.678395)
			(xy 45.78986 -296.668551) (xy 45.743844 -296.651099) (xy 45.701223 -296.626492) (xy 45.663102 -296.595367)
			(xy 45.630467 -296.55853) (xy 45.604164 -296.516934) (xy 45.584873 -296.471658) (xy 45.573096 -296.423874)
			(xy 45.569136 -296.37482) (xy 45.230288 -296.37482) (xy 45.229793 -296.399427) (xy 45.221898 -296.448004)
			(xy 45.206314 -296.494685) (xy 45.183443 -296.538262) (xy 45.153878 -296.577606) (xy 45.118385 -296.611698)
			(xy 45.077882 -296.639654) (xy 45.03342 -296.660752) (xy 44.986149 -296.674444) (xy 44.937294 -296.680376)
			(xy 44.888119 -296.678395) (xy 44.8399 -296.668551) (xy 44.793884 -296.651099) (xy 44.751263 -296.626492)
			(xy 44.713142 -296.595367) (xy 44.680507 -296.55853) (xy 44.654204 -296.516934) (xy 44.634913 -296.471658)
			(xy 44.623136 -296.423874) (xy 44.619176 -296.37482) (xy 44.280074 -296.37482) (xy 44.279579 -296.399427)
			(xy 44.271684 -296.448004) (xy 44.2561 -296.494685) (xy 44.233229 -296.538262) (xy 44.203664 -296.577606)
			(xy 44.168171 -296.611698) (xy 44.127668 -296.639654) (xy 44.083206 -296.660752) (xy 44.035935 -296.674444)
			(xy 43.98708 -296.680376) (xy 43.937905 -296.678395) (xy 43.889686 -296.668551) (xy 43.84367 -296.651099)
			(xy 43.801049 -296.626492) (xy 43.762928 -296.595367) (xy 43.730293 -296.55853) (xy 43.70399 -296.516934)
			(xy 43.684699 -296.471658) (xy 43.672922 -296.423874) (xy 43.668962 -296.37482) (xy 42.380154 -296.37482)
			(xy 42.379659 -296.399427) (xy 42.371764 -296.448004) (xy 42.35618 -296.494685) (xy 42.333309 -296.538262)
			(xy 42.303744 -296.577606) (xy 42.268251 -296.611698) (xy 42.227748 -296.639654) (xy 42.183286 -296.660752)
			(xy 42.136015 -296.674444) (xy 42.08716 -296.680376) (xy 42.037985 -296.678395) (xy 41.989766 -296.668551)
			(xy 41.94375 -296.651099) (xy 41.901129 -296.626492) (xy 41.863008 -296.595367) (xy 41.830373 -296.55853)
			(xy 41.80407 -296.516934) (xy 41.784779 -296.471658) (xy 41.773002 -296.423874) (xy 41.769042 -296.37482)
			(xy 40.480234 -296.37482) (xy 40.479739 -296.399427) (xy 40.471844 -296.448004) (xy 40.45626 -296.494685)
			(xy 40.433389 -296.538262) (xy 40.403824 -296.577606) (xy 40.368331 -296.611698) (xy 40.327828 -296.639654)
			(xy 40.283366 -296.660752) (xy 40.236095 -296.674444) (xy 40.18724 -296.680376) (xy 40.138065 -296.678395)
			(xy 40.089846 -296.668551) (xy 40.04383 -296.651099) (xy 40.001209 -296.626492) (xy 39.963088 -296.595367)
			(xy 39.930453 -296.55853) (xy 39.90415 -296.516934) (xy 39.884859 -296.471658) (xy 39.873082 -296.423874)
			(xy 39.869122 -296.37482) (xy 39.530274 -296.37482) (xy 39.529779 -296.399427) (xy 39.521884 -296.448004)
			(xy 39.5063 -296.494685) (xy 39.483429 -296.538262) (xy 39.453864 -296.577606) (xy 39.418371 -296.611698)
			(xy 39.377868 -296.639654) (xy 39.333406 -296.660752) (xy 39.286135 -296.674444) (xy 39.23728 -296.680376)
			(xy 39.188105 -296.678395) (xy 39.139886 -296.668551) (xy 39.09387 -296.651099) (xy 39.051249 -296.626492)
			(xy 39.013128 -296.595367) (xy 38.980493 -296.55853) (xy 38.95419 -296.516934) (xy 38.934899 -296.471658)
			(xy 38.923122 -296.423874) (xy 38.919162 -296.37482) (xy 38.58006 -296.37482) (xy 38.579565 -296.399427)
			(xy 38.57167 -296.448004) (xy 38.556086 -296.494685) (xy 38.533215 -296.538262) (xy 38.50365 -296.577606)
			(xy 38.468157 -296.611698) (xy 38.427654 -296.639654) (xy 38.383192 -296.660752) (xy 38.335921 -296.674444)
			(xy 38.287066 -296.680376) (xy 38.237891 -296.678395) (xy 38.189672 -296.668551) (xy 38.143656 -296.651099)
			(xy 38.101035 -296.626492) (xy 38.062914 -296.595367) (xy 38.030279 -296.55853) (xy 38.003976 -296.516934)
			(xy 37.984685 -296.471658) (xy 37.972908 -296.423874) (xy 37.968948 -296.37482) (xy 37.630354 -296.37482)
			(xy 37.629859 -296.399427) (xy 37.621964 -296.448004) (xy 37.60638 -296.494685) (xy 37.583509 -296.538262)
			(xy 37.553944 -296.577606) (xy 37.518451 -296.611698) (xy 37.477948 -296.639654) (xy 37.433486 -296.660752)
			(xy 37.386215 -296.674444) (xy 37.33736 -296.680376) (xy 37.288185 -296.678395) (xy 37.239966 -296.668551)
			(xy 37.19395 -296.651099) (xy 37.151329 -296.626492) (xy 37.113208 -296.595367) (xy 37.080573 -296.55853)
			(xy 37.05427 -296.516934) (xy 37.034979 -296.471658) (xy 37.023202 -296.423874) (xy 37.019242 -296.37482)
			(xy 34.209526 -296.37482) (xy 34.225261 -296.384423) (xy 34.268129 -296.420098) (xy 34.305346 -296.461635)
			(xy 34.336119 -296.508148) (xy 34.359791 -296.558645) (xy 34.375859 -296.612052) (xy 34.383979 -296.667228)
			(xy 34.384488 -296.695114) (xy 34.383979 -296.723) (xy 34.375859 -296.778176) (xy 34.359791 -296.831583)
			(xy 34.336119 -296.88208) (xy 34.305346 -296.928593) (xy 34.268129 -296.97013) (xy 34.225261 -297.005805)
			(xy 34.177655 -297.034859) (xy 34.126326 -297.056671) (xy 34.072369 -297.070777) (xy 34.016932 -297.076877)
			(xy 33.961198 -297.07484) (xy 33.906355 -297.06471) (xy 33.853571 -297.046703) (xy 33.803971 -297.021202)
			(xy 33.758613 -296.988751) (xy 33.718464 -296.950042) (xy 33.684378 -296.905899) (xy 33.657082 -296.857264)
			(xy 33.637159 -296.805173) (xy 33.625033 -296.750736) (xy 33.620962 -296.695114) (xy 31.99737 -296.695114)
			(xy 31.997461 -296.695773) (xy 31.997904 -296.722038) (xy 31.997418 -296.749289) (xy 31.989662 -296.803237)
			(xy 31.974307 -296.855532) (xy 31.951665 -296.905109) (xy 31.922199 -296.950959) (xy 31.886508 -296.99215)
			(xy 31.845317 -297.027841) (xy 31.799467 -297.057307) (xy 31.74989 -297.079949) (xy 31.697595 -297.095304)
			(xy 31.643647 -297.10306) (xy 31.589145 -297.10306) (xy 31.535197 -297.095304) (xy 31.482902 -297.079949)
			(xy 31.433325 -297.057307) (xy 31.387475 -297.027841) (xy 31.346284 -296.99215) (xy 31.310593 -296.950959)
			(xy 31.281127 -296.905109) (xy 31.258485 -296.855532) (xy 31.24313 -296.803237) (xy 31.235374 -296.749289)
			(xy 31.234888 -296.722038) (xy 1.660398 -296.722038) (xy 1.660398 -296.935144) (xy 1.660829 -296.945211)
			(xy 1.668555 -296.963804) (xy 1.675384 -296.971212) (xy 1.925828 -297.221656) (xy 32.748218 -297.221656)
			(xy 32.752289 -297.166034) (xy 32.764415 -297.111597) (xy 32.784338 -297.059506) (xy 32.811634 -297.010871)
			(xy 32.84572 -296.966728) (xy 32.885869 -296.928019) (xy 32.931227 -296.895568) (xy 32.980827 -296.870067)
			(xy 33.033611 -296.85206) (xy 33.088454 -296.84193) (xy 33.144188 -296.839893) (xy 33.199625 -296.845993)
			(xy 33.253582 -296.860099) (xy 33.304911 -296.881911) (xy 33.352517 -296.910965) (xy 33.395385 -296.94664)
			(xy 33.432602 -296.988177) (xy 33.463375 -297.03469) (xy 33.487047 -297.085187) (xy 33.503115 -297.138594)
			(xy 33.511235 -297.19377) (xy 33.511744 -297.221656) (xy 33.511235 -297.249542) (xy 33.503115 -297.304718)
			(xy 33.497163 -297.3245) (xy 35.433795 -297.3245) (xy 35.437965 -297.274168) (xy 35.450363 -297.22521)
			(xy 35.470649 -297.178959) (xy 35.498271 -297.136678) (xy 35.532475 -297.09952) (xy 35.572329 -297.068498)
			(xy 35.616745 -297.044458) (xy 35.664511 -297.028057) (xy 35.714326 -297.019741) (xy 35.739578 -297.019218)
			(xy 35.764974 -297.019712) (xy 35.815065 -297.028128) (xy 35.863073 -297.044715) (xy 35.907676 -297.069017)
			(xy 35.947643 -297.100363) (xy 35.96513 -297.118786) (xy 35.97275 -297.127168) (xy 35.992816 -297.135804)
			(xy 36.09213 -297.133264) (xy 36.111688 -297.123612) (xy 36.1188 -297.114976) (xy 36.134612 -297.096424)
			(xy 36.17074 -297.063703) (xy 36.211277 -297.036634) (xy 36.255344 -297.015802) (xy 36.30199 -297.001658)
			(xy 36.350206 -296.994507) (xy 36.374578 -296.994072) (xy 37.324538 -296.994072) (xy 37.350522 -296.994624)
			(xy 37.401848 -297.002759) (xy 37.451271 -297.018822) (xy 37.497572 -297.042419) (xy 37.539613 -297.072968)
			(xy 37.576357 -297.109716) (xy 37.606901 -297.15176) (xy 37.630492 -297.198064) (xy 37.64655 -297.247489)
			(xy 37.654679 -297.298816) (xy 37.654679 -297.32478) (xy 37.968948 -297.32478) (xy 37.972908 -297.275726)
			(xy 37.984685 -297.227942) (xy 38.003976 -297.182666) (xy 38.030279 -297.14107) (xy 38.062914 -297.104233)
			(xy 38.101035 -297.073108) (xy 38.143656 -297.048501) (xy 38.189672 -297.031049) (xy 38.237891 -297.021205)
			(xy 38.287066 -297.019224) (xy 38.335921 -297.025156) (xy 38.383192 -297.038848) (xy 38.427654 -297.059946)
			(xy 38.468157 -297.087902) (xy 38.50365 -297.121994) (xy 38.533215 -297.161338) (xy 38.556086 -297.204915)
			(xy 38.57167 -297.251596) (xy 38.579565 -297.300173) (xy 38.58006 -297.32478) (xy 38.919162 -297.32478)
			(xy 38.923122 -297.275726) (xy 38.934899 -297.227942) (xy 38.95419 -297.182666) (xy 38.980493 -297.14107)
			(xy 39.013128 -297.104233) (xy 39.051249 -297.073108) (xy 39.09387 -297.048501) (xy 39.139886 -297.031049)
			(xy 39.188105 -297.021205) (xy 39.23728 -297.019224) (xy 39.286135 -297.025156) (xy 39.333406 -297.038848)
			(xy 39.377868 -297.059946) (xy 39.418371 -297.087902) (xy 39.453864 -297.121994) (xy 39.483429 -297.161338)
			(xy 39.5063 -297.204915) (xy 39.521884 -297.251596) (xy 39.529779 -297.300173) (xy 39.530274 -297.32478)
			(xy 41.769042 -297.32478) (xy 41.773002 -297.275726) (xy 41.784779 -297.227942) (xy 41.80407 -297.182666)
			(xy 41.830373 -297.14107) (xy 41.863008 -297.104233) (xy 41.901129 -297.073108) (xy 41.94375 -297.048501)
			(xy 41.989766 -297.031049) (xy 42.037985 -297.021205) (xy 42.08716 -297.019224) (xy 42.136015 -297.025156)
			(xy 42.183286 -297.038848) (xy 42.227748 -297.059946) (xy 42.268251 -297.087902) (xy 42.303744 -297.121994)
			(xy 42.333309 -297.161338) (xy 42.35618 -297.204915) (xy 42.371764 -297.251596) (xy 42.379659 -297.300173)
			(xy 42.380154 -297.32478) (xy 43.668962 -297.32478) (xy 43.672922 -297.275726) (xy 43.684699 -297.227942)
			(xy 43.70399 -297.182666) (xy 43.730293 -297.14107) (xy 43.762928 -297.104233) (xy 43.801049 -297.073108)
			(xy 43.84367 -297.048501) (xy 43.889686 -297.031049) (xy 43.937905 -297.021205) (xy 43.98708 -297.019224)
			(xy 44.035935 -297.025156) (xy 44.083206 -297.038848) (xy 44.127668 -297.059946) (xy 44.168171 -297.087902)
			(xy 44.203664 -297.121994) (xy 44.233229 -297.161338) (xy 44.2561 -297.204915) (xy 44.271684 -297.251596)
			(xy 44.279579 -297.300173) (xy 44.280074 -297.32478) (xy 44.619176 -297.32478) (xy 44.623136 -297.275726)
			(xy 44.634913 -297.227942) (xy 44.654204 -297.182666) (xy 44.680507 -297.14107) (xy 44.713142 -297.104233)
			(xy 44.751263 -297.073108) (xy 44.793884 -297.048501) (xy 44.8399 -297.031049) (xy 44.888119 -297.021205)
			(xy 44.937294 -297.019224) (xy 44.986149 -297.025156) (xy 45.03342 -297.038848) (xy 45.077882 -297.059946)
			(xy 45.118385 -297.087902) (xy 45.153878 -297.121994) (xy 45.183443 -297.161338) (xy 45.206314 -297.204915)
			(xy 45.221898 -297.251596) (xy 45.229793 -297.300173) (xy 45.230288 -297.32478) (xy 45.569136 -297.32478)
			(xy 45.573096 -297.275726) (xy 45.584873 -297.227942) (xy 45.604164 -297.182666) (xy 45.630467 -297.14107)
			(xy 45.663102 -297.104233) (xy 45.701223 -297.073108) (xy 45.743844 -297.048501) (xy 45.78986 -297.031049)
			(xy 45.838079 -297.021205) (xy 45.887254 -297.019224) (xy 45.936109 -297.025156) (xy 45.98338 -297.038848)
			(xy 46.027842 -297.059946) (xy 46.068345 -297.087902) (xy 46.103838 -297.121994) (xy 46.133403 -297.161338)
			(xy 46.156274 -297.204915) (xy 46.171858 -297.251596) (xy 46.179753 -297.300173) (xy 46.180248 -297.32478)
			(xy 46.519096 -297.32478) (xy 46.523056 -297.275726) (xy 46.534833 -297.227942) (xy 46.554124 -297.182666)
			(xy 46.580427 -297.14107) (xy 46.613062 -297.104233) (xy 46.651183 -297.073108) (xy 46.693804 -297.048501)
			(xy 46.73982 -297.031049) (xy 46.788039 -297.021205) (xy 46.837214 -297.019224) (xy 46.886069 -297.025156)
			(xy 46.93334 -297.038848) (xy 46.977802 -297.059946) (xy 47.018305 -297.087902) (xy 47.053798 -297.121994)
			(xy 47.083363 -297.161338) (xy 47.106234 -297.204915) (xy 47.121818 -297.251596) (xy 47.129713 -297.300173)
			(xy 47.130208 -297.32478) (xy 47.469056 -297.32478) (xy 47.473016 -297.275726) (xy 47.484793 -297.227942)
			(xy 47.504084 -297.182666) (xy 47.530387 -297.14107) (xy 47.563022 -297.104233) (xy 47.601143 -297.073108)
			(xy 47.643764 -297.048501) (xy 47.68978 -297.031049) (xy 47.737999 -297.021205) (xy 47.787174 -297.019224)
			(xy 47.836029 -297.025156) (xy 47.8833 -297.038848) (xy 47.927762 -297.059946) (xy 47.968265 -297.087902)
			(xy 48.003758 -297.121994) (xy 48.033323 -297.161338) (xy 48.056194 -297.204915) (xy 48.071778 -297.251596)
			(xy 48.079673 -297.300173) (xy 48.080168 -297.32478) (xy 48.419016 -297.32478) (xy 48.422976 -297.275726)
			(xy 48.434753 -297.227942) (xy 48.454044 -297.182666) (xy 48.480347 -297.14107) (xy 48.512982 -297.104233)
			(xy 48.551103 -297.073108) (xy 48.593724 -297.048501) (xy 48.63974 -297.031049) (xy 48.687959 -297.021205)
			(xy 48.737134 -297.019224) (xy 48.785989 -297.025156) (xy 48.83326 -297.038848) (xy 48.877722 -297.059946)
			(xy 48.918225 -297.087902) (xy 48.953718 -297.121994) (xy 48.983283 -297.161338) (xy 49.006154 -297.204915)
			(xy 49.021738 -297.251596) (xy 49.029633 -297.300173) (xy 49.030128 -297.32478) (xy 49.368976 -297.32478)
			(xy 49.372936 -297.275726) (xy 49.384713 -297.227942) (xy 49.404004 -297.182666) (xy 49.430307 -297.14107)
			(xy 49.462942 -297.104233) (xy 49.501063 -297.073108) (xy 49.543684 -297.048501) (xy 49.5897 -297.031049)
			(xy 49.637919 -297.021205) (xy 49.687094 -297.019224) (xy 49.735949 -297.025156) (xy 49.78322 -297.038848)
			(xy 49.827682 -297.059946) (xy 49.868185 -297.087902) (xy 49.903678 -297.121994) (xy 49.933243 -297.161338)
			(xy 49.956114 -297.204915) (xy 49.971698 -297.251596) (xy 49.979593 -297.300173) (xy 49.980088 -297.32478)
			(xy 50.31919 -297.32478) (xy 50.32315 -297.275726) (xy 50.334927 -297.227942) (xy 50.354218 -297.182666)
			(xy 50.380521 -297.14107) (xy 50.413156 -297.104233) (xy 50.451277 -297.073108) (xy 50.493898 -297.048501)
			(xy 50.539914 -297.031049) (xy 50.588133 -297.021205) (xy 50.637308 -297.019224) (xy 50.686163 -297.025156)
			(xy 50.733434 -297.038848) (xy 50.777896 -297.059946) (xy 50.818399 -297.087902) (xy 50.853892 -297.121994)
			(xy 50.883457 -297.161338) (xy 50.906328 -297.204915) (xy 50.921912 -297.251596) (xy 50.929807 -297.300173)
			(xy 50.930302 -297.32478) (xy 51.26915 -297.32478) (xy 51.27311 -297.275726) (xy 51.284887 -297.227942)
			(xy 51.304178 -297.182666) (xy 51.330481 -297.14107) (xy 51.363116 -297.104233) (xy 51.401237 -297.073108)
			(xy 51.443858 -297.048501) (xy 51.489874 -297.031049) (xy 51.538093 -297.021205) (xy 51.587268 -297.019224)
			(xy 51.636123 -297.025156) (xy 51.683394 -297.038848) (xy 51.727856 -297.059946) (xy 51.768359 -297.087902)
			(xy 51.803852 -297.121994) (xy 51.833417 -297.161338) (xy 51.856288 -297.204915) (xy 51.871872 -297.251596)
			(xy 51.879767 -297.300173) (xy 51.880262 -297.32478) (xy 52.21911 -297.32478) (xy 52.22307 -297.275726)
			(xy 52.234847 -297.227942) (xy 52.254138 -297.182666) (xy 52.280441 -297.14107) (xy 52.313076 -297.104233)
			(xy 52.351197 -297.073108) (xy 52.393818 -297.048501) (xy 52.439834 -297.031049) (xy 52.488053 -297.021205)
			(xy 52.537228 -297.019224) (xy 52.586083 -297.025156) (xy 52.633354 -297.038848) (xy 52.677816 -297.059946)
			(xy 52.718319 -297.087902) (xy 52.753812 -297.121994) (xy 52.783377 -297.161338) (xy 52.806248 -297.204915)
			(xy 52.821832 -297.251596) (xy 52.829727 -297.300173) (xy 52.830222 -297.32478) (xy 53.16907 -297.32478)
			(xy 53.17303 -297.275726) (xy 53.184807 -297.227942) (xy 53.204098 -297.182666) (xy 53.230401 -297.14107)
			(xy 53.263036 -297.104233) (xy 53.301157 -297.073108) (xy 53.343778 -297.048501) (xy 53.389794 -297.031049)
			(xy 53.438013 -297.021205) (xy 53.487188 -297.019224) (xy 53.536043 -297.025156) (xy 53.583314 -297.038848)
			(xy 53.627776 -297.059946) (xy 53.668279 -297.087902) (xy 53.703772 -297.121994) (xy 53.733337 -297.161338)
			(xy 53.756208 -297.204915) (xy 53.771792 -297.251596) (xy 53.779687 -297.300173) (xy 53.780182 -297.32478)
			(xy 54.11903 -297.32478) (xy 54.12299 -297.275726) (xy 54.134767 -297.227942) (xy 54.154058 -297.182666)
			(xy 54.180361 -297.14107) (xy 54.212996 -297.104233) (xy 54.251117 -297.073108) (xy 54.293738 -297.048501)
			(xy 54.339754 -297.031049) (xy 54.387973 -297.021205) (xy 54.437148 -297.019224) (xy 54.486003 -297.025156)
			(xy 54.533274 -297.038848) (xy 54.577736 -297.059946) (xy 54.618239 -297.087902) (xy 54.653732 -297.121994)
			(xy 54.683297 -297.161338) (xy 54.706168 -297.204915) (xy 54.721752 -297.251596) (xy 54.729647 -297.300173)
			(xy 54.730142 -297.32478) (xy 55.06899 -297.32478) (xy 55.07295 -297.275726) (xy 55.084727 -297.227942)
			(xy 55.104018 -297.182666) (xy 55.130321 -297.14107) (xy 55.162956 -297.104233) (xy 55.201077 -297.073108)
			(xy 55.243698 -297.048501) (xy 55.289714 -297.031049) (xy 55.337933 -297.021205) (xy 55.387108 -297.019224)
			(xy 55.435963 -297.025156) (xy 55.483234 -297.038848) (xy 55.527696 -297.059946) (xy 55.568199 -297.087902)
			(xy 55.603692 -297.121994) (xy 55.633257 -297.161338) (xy 55.656128 -297.204915) (xy 55.671712 -297.251596)
			(xy 55.679607 -297.300173) (xy 55.680102 -297.32478) (xy 56.01895 -297.32478) (xy 56.02291 -297.275726)
			(xy 56.034687 -297.227942) (xy 56.053978 -297.182666) (xy 56.080281 -297.14107) (xy 56.112916 -297.104233)
			(xy 56.151037 -297.073108) (xy 56.193658 -297.048501) (xy 56.239674 -297.031049) (xy 56.287893 -297.021205)
			(xy 56.337068 -297.019224) (xy 56.385923 -297.025156) (xy 56.433194 -297.038848) (xy 56.477656 -297.059946)
			(xy 56.518159 -297.087902) (xy 56.553652 -297.121994) (xy 56.583217 -297.161338) (xy 56.606088 -297.204915)
			(xy 56.621672 -297.251596) (xy 56.629567 -297.300173) (xy 56.630062 -297.32478) (xy 56.969164 -297.32478)
			(xy 56.973124 -297.275726) (xy 56.984901 -297.227942) (xy 57.004192 -297.182666) (xy 57.030495 -297.14107)
			(xy 57.06313 -297.104233) (xy 57.101251 -297.073108) (xy 57.143872 -297.048501) (xy 57.189888 -297.031049)
			(xy 57.238107 -297.021205) (xy 57.287282 -297.019224) (xy 57.336137 -297.025156) (xy 57.383408 -297.038848)
			(xy 57.42787 -297.059946) (xy 57.468373 -297.087902) (xy 57.503866 -297.121994) (xy 57.533431 -297.161338)
			(xy 57.556302 -297.204915) (xy 57.571886 -297.251596) (xy 57.579781 -297.300173) (xy 57.580276 -297.32478)
			(xy 57.919124 -297.32478) (xy 57.923084 -297.275726) (xy 57.934861 -297.227942) (xy 57.954152 -297.182666)
			(xy 57.980455 -297.14107) (xy 58.01309 -297.104233) (xy 58.051211 -297.073108) (xy 58.093832 -297.048501)
			(xy 58.139848 -297.031049) (xy 58.188067 -297.021205) (xy 58.237242 -297.019224) (xy 58.286097 -297.025156)
			(xy 58.333368 -297.038848) (xy 58.37783 -297.059946) (xy 58.418333 -297.087902) (xy 58.453826 -297.121994)
			(xy 58.483391 -297.161338) (xy 58.506262 -297.204915) (xy 58.521846 -297.251596) (xy 58.529741 -297.300173)
			(xy 58.530236 -297.32478) (xy 59.819044 -297.32478) (xy 59.823004 -297.275726) (xy 59.834781 -297.227942)
			(xy 59.854072 -297.182666) (xy 59.880375 -297.14107) (xy 59.91301 -297.104233) (xy 59.951131 -297.073108)
			(xy 59.993752 -297.048501) (xy 60.039768 -297.031049) (xy 60.087987 -297.021205) (xy 60.137162 -297.019224)
			(xy 60.186017 -297.025156) (xy 60.233288 -297.038848) (xy 60.27775 -297.059946) (xy 60.318253 -297.087902)
			(xy 60.353746 -297.121994) (xy 60.383311 -297.161338) (xy 60.406182 -297.204915) (xy 60.421766 -297.251596)
			(xy 60.429661 -297.300173) (xy 60.430156 -297.32478) (xy 60.769004 -297.32478) (xy 60.772964 -297.275726)
			(xy 60.784741 -297.227942) (xy 60.804032 -297.182666) (xy 60.830335 -297.14107) (xy 60.86297 -297.104233)
			(xy 60.901091 -297.073108) (xy 60.943712 -297.048501) (xy 60.989728 -297.031049) (xy 61.037947 -297.021205)
			(xy 61.087122 -297.019224) (xy 61.135977 -297.025156) (xy 61.183248 -297.038848) (xy 61.22771 -297.059946)
			(xy 61.268213 -297.087902) (xy 61.303706 -297.121994) (xy 61.333271 -297.161338) (xy 61.356142 -297.204915)
			(xy 61.371726 -297.251596) (xy 61.379621 -297.300173) (xy 61.380116 -297.32478) (xy 61.718964 -297.32478)
			(xy 61.722924 -297.275726) (xy 61.734701 -297.227942) (xy 61.753992 -297.182666) (xy 61.780295 -297.14107)
			(xy 61.81293 -297.104233) (xy 61.851051 -297.073108) (xy 61.893672 -297.048501) (xy 61.939688 -297.031049)
			(xy 61.987907 -297.021205) (xy 62.037082 -297.019224) (xy 62.085937 -297.025156) (xy 62.133208 -297.038848)
			(xy 62.17767 -297.059946) (xy 62.218173 -297.087902) (xy 62.253666 -297.121994) (xy 62.283231 -297.161338)
			(xy 62.306102 -297.204915) (xy 62.321686 -297.251596) (xy 62.329581 -297.300173) (xy 62.330076 -297.32478)
			(xy 62.669178 -297.32478) (xy 62.673138 -297.275726) (xy 62.684915 -297.227942) (xy 62.704206 -297.182666)
			(xy 62.730509 -297.14107) (xy 62.763144 -297.104233) (xy 62.801265 -297.073108) (xy 62.843886 -297.048501)
			(xy 62.889902 -297.031049) (xy 62.938121 -297.021205) (xy 62.987296 -297.019224) (xy 63.036151 -297.025156)
			(xy 63.083422 -297.038848) (xy 63.127884 -297.059946) (xy 63.168387 -297.087902) (xy 63.20388 -297.121994)
			(xy 63.233445 -297.161338) (xy 63.256316 -297.204915) (xy 63.2719 -297.251596) (xy 63.279795 -297.300173)
			(xy 63.28029 -297.32478) (xy 63.619138 -297.32478) (xy 63.623098 -297.275726) (xy 63.634875 -297.227942)
			(xy 63.654166 -297.182666) (xy 63.680469 -297.14107) (xy 63.713104 -297.104233) (xy 63.751225 -297.073108)
			(xy 63.793846 -297.048501) (xy 63.839862 -297.031049) (xy 63.888081 -297.021205) (xy 63.937256 -297.019224)
			(xy 63.986111 -297.025156) (xy 64.033382 -297.038848) (xy 64.077844 -297.059946) (xy 64.118347 -297.087902)
			(xy 64.15384 -297.121994) (xy 64.183405 -297.161338) (xy 64.206276 -297.204915) (xy 64.22186 -297.251596)
			(xy 64.229755 -297.300173) (xy 64.23025 -297.32478) (xy 64.569098 -297.32478) (xy 64.573058 -297.275726)
			(xy 64.584835 -297.227942) (xy 64.604126 -297.182666) (xy 64.630429 -297.14107) (xy 64.663064 -297.104233)
			(xy 64.701185 -297.073108) (xy 64.743806 -297.048501) (xy 64.789822 -297.031049) (xy 64.838041 -297.021205)
			(xy 64.887216 -297.019224) (xy 64.936071 -297.025156) (xy 64.983342 -297.038848) (xy 65.027804 -297.059946)
			(xy 65.068307 -297.087902) (xy 65.1038 -297.121994) (xy 65.133365 -297.161338) (xy 65.156236 -297.204915)
			(xy 65.17182 -297.251596) (xy 65.179715 -297.300173) (xy 65.18021 -297.32478) (xy 65.519058 -297.32478)
			(xy 65.523018 -297.275726) (xy 65.534795 -297.227942) (xy 65.554086 -297.182666) (xy 65.580389 -297.14107)
			(xy 65.613024 -297.104233) (xy 65.651145 -297.073108) (xy 65.693766 -297.048501) (xy 65.739782 -297.031049)
			(xy 65.788001 -297.021205) (xy 65.837176 -297.019224) (xy 65.886031 -297.025156) (xy 65.933302 -297.038848)
			(xy 65.977764 -297.059946) (xy 66.018267 -297.087902) (xy 66.05376 -297.121994) (xy 66.083325 -297.161338)
			(xy 66.106196 -297.204915) (xy 66.12178 -297.251596) (xy 66.129675 -297.300173) (xy 66.13017 -297.32478)
			(xy 66.469018 -297.32478) (xy 66.472978 -297.275726) (xy 66.484755 -297.227942) (xy 66.504046 -297.182666)
			(xy 66.530349 -297.14107) (xy 66.562984 -297.104233) (xy 66.601105 -297.073108) (xy 66.643726 -297.048501)
			(xy 66.689742 -297.031049) (xy 66.737961 -297.021205) (xy 66.787136 -297.019224) (xy 66.835991 -297.025156)
			(xy 66.883262 -297.038848) (xy 66.927724 -297.059946) (xy 66.968227 -297.087902) (xy 67.00372 -297.121994)
			(xy 67.033285 -297.161338) (xy 67.056156 -297.204915) (xy 67.07174 -297.251596) (xy 67.079635 -297.300173)
			(xy 67.08013 -297.32478) (xy 67.418978 -297.32478) (xy 67.422938 -297.275726) (xy 67.434715 -297.227942)
			(xy 67.454006 -297.182666) (xy 67.480309 -297.14107) (xy 67.512944 -297.104233) (xy 67.551065 -297.073108)
			(xy 67.593686 -297.048501) (xy 67.639702 -297.031049) (xy 67.687921 -297.021205) (xy 67.737096 -297.019224)
			(xy 67.785951 -297.025156) (xy 67.833222 -297.038848) (xy 67.877684 -297.059946) (xy 67.918187 -297.087902)
			(xy 67.95368 -297.121994) (xy 67.983245 -297.161338) (xy 68.006116 -297.204915) (xy 68.0217 -297.251596)
			(xy 68.029595 -297.300173) (xy 68.03009 -297.32478) (xy 68.368938 -297.32478) (xy 68.372898 -297.275726)
			(xy 68.384675 -297.227942) (xy 68.403966 -297.182666) (xy 68.430269 -297.14107) (xy 68.462904 -297.104233)
			(xy 68.501025 -297.073108) (xy 68.543646 -297.048501) (xy 68.589662 -297.031049) (xy 68.637881 -297.021205)
			(xy 68.687056 -297.019224) (xy 68.735911 -297.025156) (xy 68.783182 -297.038848) (xy 68.827644 -297.059946)
			(xy 68.868147 -297.087902) (xy 68.90364 -297.121994) (xy 68.933205 -297.161338) (xy 68.956076 -297.204915)
			(xy 68.97166 -297.251596) (xy 68.979555 -297.300173) (xy 68.98005 -297.32478) (xy 69.319152 -297.32478)
			(xy 69.323112 -297.275726) (xy 69.334889 -297.227942) (xy 69.35418 -297.182666) (xy 69.380483 -297.14107)
			(xy 69.413118 -297.104233) (xy 69.451239 -297.073108) (xy 69.49386 -297.048501) (xy 69.539876 -297.031049)
			(xy 69.588095 -297.021205) (xy 69.63727 -297.019224) (xy 69.686125 -297.025156) (xy 69.733396 -297.038848)
			(xy 69.777858 -297.059946) (xy 69.818361 -297.087902) (xy 69.853854 -297.121994) (xy 69.883419 -297.161338)
			(xy 69.90629 -297.204915) (xy 69.921874 -297.251596) (xy 69.929769 -297.300173) (xy 69.930264 -297.32478)
			(xy 71.219072 -297.32478) (xy 71.223032 -297.275726) (xy 71.234809 -297.227942) (xy 71.2541 -297.182666)
			(xy 71.280403 -297.14107) (xy 71.313038 -297.104233) (xy 71.351159 -297.073108) (xy 71.39378 -297.048501)
			(xy 71.439796 -297.031049) (xy 71.488015 -297.021205) (xy 71.53719 -297.019224) (xy 71.586045 -297.025156)
			(xy 71.633316 -297.038848) (xy 71.677778 -297.059946) (xy 71.718281 -297.087902) (xy 71.753774 -297.121994)
			(xy 71.783339 -297.161338) (xy 71.80621 -297.204915) (xy 71.821794 -297.251596) (xy 71.829689 -297.300173)
			(xy 71.830184 -297.32478) (xy 72.169032 -297.32478) (xy 72.172992 -297.275726) (xy 72.184769 -297.227942)
			(xy 72.20406 -297.182666) (xy 72.230363 -297.14107) (xy 72.262998 -297.104233) (xy 72.301119 -297.073108)
			(xy 72.34374 -297.048501) (xy 72.389756 -297.031049) (xy 72.437975 -297.021205) (xy 72.48715 -297.019224)
			(xy 72.536005 -297.025156) (xy 72.583276 -297.038848) (xy 72.627738 -297.059946) (xy 72.668241 -297.087902)
			(xy 72.703734 -297.121994) (xy 72.733299 -297.161338) (xy 72.75617 -297.204915) (xy 72.771754 -297.251596)
			(xy 72.779649 -297.300173) (xy 72.780144 -297.32478) (xy 73.118992 -297.32478) (xy 73.122952 -297.275726)
			(xy 73.134729 -297.227942) (xy 73.15402 -297.182666) (xy 73.180323 -297.14107) (xy 73.212958 -297.104233)
			(xy 73.251079 -297.073108) (xy 73.2937 -297.048501) (xy 73.339716 -297.031049) (xy 73.387935 -297.021205)
			(xy 73.43711 -297.019224) (xy 73.485965 -297.025156) (xy 73.533236 -297.038848) (xy 73.577698 -297.059946)
			(xy 73.618201 -297.087902) (xy 73.653694 -297.121994) (xy 73.683259 -297.161338) (xy 73.70613 -297.204915)
			(xy 73.721714 -297.251596) (xy 73.729609 -297.300173) (xy 73.730104 -297.32478) (xy 74.069206 -297.32478)
			(xy 74.073166 -297.275726) (xy 74.084943 -297.227942) (xy 74.104234 -297.182666) (xy 74.130537 -297.14107)
			(xy 74.163172 -297.104233) (xy 74.201293 -297.073108) (xy 74.243914 -297.048501) (xy 74.28993 -297.031049)
			(xy 74.338149 -297.021205) (xy 74.387324 -297.019224) (xy 74.436179 -297.025156) (xy 74.48345 -297.038848)
			(xy 74.527912 -297.059946) (xy 74.568415 -297.087902) (xy 74.603908 -297.121994) (xy 74.633473 -297.161338)
			(xy 74.656344 -297.204915) (xy 74.671928 -297.251596) (xy 74.679823 -297.300173) (xy 74.680318 -297.32478)
			(xy 75.019166 -297.32478) (xy 75.023126 -297.275726) (xy 75.034903 -297.227942) (xy 75.054194 -297.182666)
			(xy 75.080497 -297.14107) (xy 75.113132 -297.104233) (xy 75.151253 -297.073108) (xy 75.193874 -297.048501)
			(xy 75.23989 -297.031049) (xy 75.288109 -297.021205) (xy 75.337284 -297.019224) (xy 75.386139 -297.025156)
			(xy 75.43341 -297.038848) (xy 75.477872 -297.059946) (xy 75.518375 -297.087902) (xy 75.553868 -297.121994)
			(xy 75.583433 -297.161338) (xy 75.606304 -297.204915) (xy 75.621888 -297.251596) (xy 75.629783 -297.300173)
			(xy 75.630278 -297.32478) (xy 75.969126 -297.32478) (xy 75.973086 -297.275726) (xy 75.984863 -297.227942)
			(xy 76.004154 -297.182666) (xy 76.030457 -297.14107) (xy 76.063092 -297.104233) (xy 76.101213 -297.073108)
			(xy 76.143834 -297.048501) (xy 76.18985 -297.031049) (xy 76.238069 -297.021205) (xy 76.287244 -297.019224)
			(xy 76.336099 -297.025156) (xy 76.38337 -297.038848) (xy 76.427832 -297.059946) (xy 76.468335 -297.087902)
			(xy 76.503828 -297.121994) (xy 76.533393 -297.161338) (xy 76.556264 -297.204915) (xy 76.571848 -297.251596)
			(xy 76.579743 -297.300173) (xy 76.580238 -297.32478) (xy 76.919086 -297.32478) (xy 76.923046 -297.275726)
			(xy 76.934823 -297.227942) (xy 76.954114 -297.182666) (xy 76.980417 -297.14107) (xy 77.013052 -297.104233)
			(xy 77.051173 -297.073108) (xy 77.093794 -297.048501) (xy 77.13981 -297.031049) (xy 77.188029 -297.021205)
			(xy 77.237204 -297.019224) (xy 77.286059 -297.025156) (xy 77.33333 -297.038848) (xy 77.377792 -297.059946)
			(xy 77.418295 -297.087902) (xy 77.453788 -297.121994) (xy 77.483353 -297.161338) (xy 77.506224 -297.204915)
			(xy 77.521808 -297.251596) (xy 77.529703 -297.300173) (xy 77.530198 -297.32478) (xy 77.869046 -297.32478)
			(xy 77.873006 -297.275726) (xy 77.884783 -297.227942) (xy 77.904074 -297.182666) (xy 77.930377 -297.14107)
			(xy 77.963012 -297.104233) (xy 78.001133 -297.073108) (xy 78.043754 -297.048501) (xy 78.08977 -297.031049)
			(xy 78.137989 -297.021205) (xy 78.187164 -297.019224) (xy 78.236019 -297.025156) (xy 78.28329 -297.038848)
			(xy 78.327752 -297.059946) (xy 78.368255 -297.087902) (xy 78.403748 -297.121994) (xy 78.433313 -297.161338)
			(xy 78.456184 -297.204915) (xy 78.471768 -297.251596) (xy 78.479663 -297.300173) (xy 78.480158 -297.32478)
			(xy 78.479663 -297.349387) (xy 78.471768 -297.397964) (xy 78.456184 -297.444645) (xy 78.433313 -297.488222)
			(xy 78.403748 -297.527566) (xy 78.368255 -297.561658) (xy 78.327752 -297.589614) (xy 78.28329 -297.610712)
			(xy 78.236019 -297.624404) (xy 78.187164 -297.630336) (xy 78.137989 -297.628355) (xy 78.08977 -297.618511)
			(xy 78.043754 -297.601059) (xy 78.001133 -297.576452) (xy 77.963012 -297.545327) (xy 77.930377 -297.50849)
			(xy 77.904074 -297.466894) (xy 77.884783 -297.421618) (xy 77.873006 -297.373834) (xy 77.869046 -297.32478)
			(xy 77.530198 -297.32478) (xy 77.529703 -297.349387) (xy 77.521808 -297.397964) (xy 77.506224 -297.444645)
			(xy 77.483353 -297.488222) (xy 77.453788 -297.527566) (xy 77.418295 -297.561658) (xy 77.377792 -297.589614)
			(xy 77.33333 -297.610712) (xy 77.286059 -297.624404) (xy 77.237204 -297.630336) (xy 77.188029 -297.628355)
			(xy 77.13981 -297.618511) (xy 77.093794 -297.601059) (xy 77.051173 -297.576452) (xy 77.013052 -297.545327)
			(xy 76.980417 -297.50849) (xy 76.954114 -297.466894) (xy 76.934823 -297.421618) (xy 76.923046 -297.373834)
			(xy 76.919086 -297.32478) (xy 76.580238 -297.32478) (xy 76.579743 -297.349387) (xy 76.571848 -297.397964)
			(xy 76.556264 -297.444645) (xy 76.533393 -297.488222) (xy 76.503828 -297.527566) (xy 76.468335 -297.561658)
			(xy 76.427832 -297.589614) (xy 76.38337 -297.610712) (xy 76.336099 -297.624404) (xy 76.287244 -297.630336)
			(xy 76.238069 -297.628355) (xy 76.18985 -297.618511) (xy 76.143834 -297.601059) (xy 76.101213 -297.576452)
			(xy 76.063092 -297.545327) (xy 76.030457 -297.50849) (xy 76.004154 -297.466894) (xy 75.984863 -297.421618)
			(xy 75.973086 -297.373834) (xy 75.969126 -297.32478) (xy 75.630278 -297.32478) (xy 75.629783 -297.349387)
			(xy 75.621888 -297.397964) (xy 75.606304 -297.444645) (xy 75.583433 -297.488222) (xy 75.553868 -297.527566)
			(xy 75.518375 -297.561658) (xy 75.477872 -297.589614) (xy 75.43341 -297.610712) (xy 75.386139 -297.624404)
			(xy 75.337284 -297.630336) (xy 75.288109 -297.628355) (xy 75.23989 -297.618511) (xy 75.193874 -297.601059)
			(xy 75.151253 -297.576452) (xy 75.113132 -297.545327) (xy 75.080497 -297.50849) (xy 75.054194 -297.466894)
			(xy 75.034903 -297.421618) (xy 75.023126 -297.373834) (xy 75.019166 -297.32478) (xy 74.680318 -297.32478)
			(xy 74.679823 -297.349387) (xy 74.671928 -297.397964) (xy 74.656344 -297.444645) (xy 74.633473 -297.488222)
			(xy 74.603908 -297.527566) (xy 74.568415 -297.561658) (xy 74.527912 -297.589614) (xy 74.48345 -297.610712)
			(xy 74.436179 -297.624404) (xy 74.387324 -297.630336) (xy 74.338149 -297.628355) (xy 74.28993 -297.618511)
			(xy 74.243914 -297.601059) (xy 74.201293 -297.576452) (xy 74.163172 -297.545327) (xy 74.130537 -297.50849)
			(xy 74.104234 -297.466894) (xy 74.084943 -297.421618) (xy 74.073166 -297.373834) (xy 74.069206 -297.32478)
			(xy 73.730104 -297.32478) (xy 73.729609 -297.349387) (xy 73.721714 -297.397964) (xy 73.70613 -297.444645)
			(xy 73.683259 -297.488222) (xy 73.653694 -297.527566) (xy 73.618201 -297.561658) (xy 73.577698 -297.589614)
			(xy 73.533236 -297.610712) (xy 73.485965 -297.624404) (xy 73.43711 -297.630336) (xy 73.387935 -297.628355)
			(xy 73.339716 -297.618511) (xy 73.2937 -297.601059) (xy 73.251079 -297.576452) (xy 73.212958 -297.545327)
			(xy 73.180323 -297.50849) (xy 73.15402 -297.466894) (xy 73.134729 -297.421618) (xy 73.122952 -297.373834)
			(xy 73.118992 -297.32478) (xy 72.780144 -297.32478) (xy 72.779649 -297.349387) (xy 72.771754 -297.397964)
			(xy 72.75617 -297.444645) (xy 72.733299 -297.488222) (xy 72.703734 -297.527566) (xy 72.668241 -297.561658)
			(xy 72.627738 -297.589614) (xy 72.583276 -297.610712) (xy 72.536005 -297.624404) (xy 72.48715 -297.630336)
			(xy 72.437975 -297.628355) (xy 72.389756 -297.618511) (xy 72.34374 -297.601059) (xy 72.301119 -297.576452)
			(xy 72.262998 -297.545327) (xy 72.230363 -297.50849) (xy 72.20406 -297.466894) (xy 72.184769 -297.421618)
			(xy 72.172992 -297.373834) (xy 72.169032 -297.32478) (xy 71.830184 -297.32478) (xy 71.829689 -297.349387)
			(xy 71.821794 -297.397964) (xy 71.80621 -297.444645) (xy 71.783339 -297.488222) (xy 71.753774 -297.527566)
			(xy 71.718281 -297.561658) (xy 71.677778 -297.589614) (xy 71.633316 -297.610712) (xy 71.586045 -297.624404)
			(xy 71.53719 -297.630336) (xy 71.488015 -297.628355) (xy 71.439796 -297.618511) (xy 71.39378 -297.601059)
			(xy 71.351159 -297.576452) (xy 71.313038 -297.545327) (xy 71.280403 -297.50849) (xy 71.2541 -297.466894)
			(xy 71.234809 -297.421618) (xy 71.223032 -297.373834) (xy 71.219072 -297.32478) (xy 69.930264 -297.32478)
			(xy 69.929769 -297.349387) (xy 69.921874 -297.397964) (xy 69.90629 -297.444645) (xy 69.883419 -297.488222)
			(xy 69.853854 -297.527566) (xy 69.818361 -297.561658) (xy 69.777858 -297.589614) (xy 69.733396 -297.610712)
			(xy 69.686125 -297.624404) (xy 69.63727 -297.630336) (xy 69.588095 -297.628355) (xy 69.539876 -297.618511)
			(xy 69.49386 -297.601059) (xy 69.451239 -297.576452) (xy 69.413118 -297.545327) (xy 69.380483 -297.50849)
			(xy 69.35418 -297.466894) (xy 69.334889 -297.421618) (xy 69.323112 -297.373834) (xy 69.319152 -297.32478)
			(xy 68.98005 -297.32478) (xy 68.979555 -297.349387) (xy 68.97166 -297.397964) (xy 68.956076 -297.444645)
			(xy 68.933205 -297.488222) (xy 68.90364 -297.527566) (xy 68.868147 -297.561658) (xy 68.827644 -297.589614)
			(xy 68.783182 -297.610712) (xy 68.735911 -297.624404) (xy 68.687056 -297.630336) (xy 68.637881 -297.628355)
			(xy 68.589662 -297.618511) (xy 68.543646 -297.601059) (xy 68.501025 -297.576452) (xy 68.462904 -297.545327)
			(xy 68.430269 -297.50849) (xy 68.403966 -297.466894) (xy 68.384675 -297.421618) (xy 68.372898 -297.373834)
			(xy 68.368938 -297.32478) (xy 68.03009 -297.32478) (xy 68.029595 -297.349387) (xy 68.0217 -297.397964)
			(xy 68.006116 -297.444645) (xy 67.983245 -297.488222) (xy 67.95368 -297.527566) (xy 67.918187 -297.561658)
			(xy 67.877684 -297.589614) (xy 67.833222 -297.610712) (xy 67.785951 -297.624404) (xy 67.737096 -297.630336)
			(xy 67.687921 -297.628355) (xy 67.639702 -297.618511) (xy 67.593686 -297.601059) (xy 67.551065 -297.576452)
			(xy 67.512944 -297.545327) (xy 67.480309 -297.50849) (xy 67.454006 -297.466894) (xy 67.434715 -297.421618)
			(xy 67.422938 -297.373834) (xy 67.418978 -297.32478) (xy 67.08013 -297.32478) (xy 67.079635 -297.349387)
			(xy 67.07174 -297.397964) (xy 67.056156 -297.444645) (xy 67.033285 -297.488222) (xy 67.00372 -297.527566)
			(xy 66.968227 -297.561658) (xy 66.927724 -297.589614) (xy 66.883262 -297.610712) (xy 66.835991 -297.624404)
			(xy 66.787136 -297.630336) (xy 66.737961 -297.628355) (xy 66.689742 -297.618511) (xy 66.643726 -297.601059)
			(xy 66.601105 -297.576452) (xy 66.562984 -297.545327) (xy 66.530349 -297.50849) (xy 66.504046 -297.466894)
			(xy 66.484755 -297.421618) (xy 66.472978 -297.373834) (xy 66.469018 -297.32478) (xy 66.13017 -297.32478)
			(xy 66.129675 -297.349387) (xy 66.12178 -297.397964) (xy 66.106196 -297.444645) (xy 66.083325 -297.488222)
			(xy 66.05376 -297.527566) (xy 66.018267 -297.561658) (xy 65.977764 -297.589614) (xy 65.933302 -297.610712)
			(xy 65.886031 -297.624404) (xy 65.837176 -297.630336) (xy 65.788001 -297.628355) (xy 65.739782 -297.618511)
			(xy 65.693766 -297.601059) (xy 65.651145 -297.576452) (xy 65.613024 -297.545327) (xy 65.580389 -297.50849)
			(xy 65.554086 -297.466894) (xy 65.534795 -297.421618) (xy 65.523018 -297.373834) (xy 65.519058 -297.32478)
			(xy 65.18021 -297.32478) (xy 65.179715 -297.349387) (xy 65.17182 -297.397964) (xy 65.156236 -297.444645)
			(xy 65.133365 -297.488222) (xy 65.1038 -297.527566) (xy 65.068307 -297.561658) (xy 65.027804 -297.589614)
			(xy 64.983342 -297.610712) (xy 64.936071 -297.624404) (xy 64.887216 -297.630336) (xy 64.838041 -297.628355)
			(xy 64.789822 -297.618511) (xy 64.743806 -297.601059) (xy 64.701185 -297.576452) (xy 64.663064 -297.545327)
			(xy 64.630429 -297.50849) (xy 64.604126 -297.466894) (xy 64.584835 -297.421618) (xy 64.573058 -297.373834)
			(xy 64.569098 -297.32478) (xy 64.23025 -297.32478) (xy 64.229755 -297.349387) (xy 64.22186 -297.397964)
			(xy 64.206276 -297.444645) (xy 64.183405 -297.488222) (xy 64.15384 -297.527566) (xy 64.118347 -297.561658)
			(xy 64.077844 -297.589614) (xy 64.033382 -297.610712) (xy 63.986111 -297.624404) (xy 63.937256 -297.630336)
			(xy 63.888081 -297.628355) (xy 63.839862 -297.618511) (xy 63.793846 -297.601059) (xy 63.751225 -297.576452)
			(xy 63.713104 -297.545327) (xy 63.680469 -297.50849) (xy 63.654166 -297.466894) (xy 63.634875 -297.421618)
			(xy 63.623098 -297.373834) (xy 63.619138 -297.32478) (xy 63.28029 -297.32478) (xy 63.279795 -297.349387)
			(xy 63.2719 -297.397964) (xy 63.256316 -297.444645) (xy 63.233445 -297.488222) (xy 63.20388 -297.527566)
			(xy 63.168387 -297.561658) (xy 63.127884 -297.589614) (xy 63.083422 -297.610712) (xy 63.036151 -297.624404)
			(xy 62.987296 -297.630336) (xy 62.938121 -297.628355) (xy 62.889902 -297.618511) (xy 62.843886 -297.601059)
			(xy 62.801265 -297.576452) (xy 62.763144 -297.545327) (xy 62.730509 -297.50849) (xy 62.704206 -297.466894)
			(xy 62.684915 -297.421618) (xy 62.673138 -297.373834) (xy 62.669178 -297.32478) (xy 62.330076 -297.32478)
			(xy 62.329581 -297.349387) (xy 62.321686 -297.397964) (xy 62.306102 -297.444645) (xy 62.283231 -297.488222)
			(xy 62.253666 -297.527566) (xy 62.218173 -297.561658) (xy 62.17767 -297.589614) (xy 62.133208 -297.610712)
			(xy 62.085937 -297.624404) (xy 62.037082 -297.630336) (xy 61.987907 -297.628355) (xy 61.939688 -297.618511)
			(xy 61.893672 -297.601059) (xy 61.851051 -297.576452) (xy 61.81293 -297.545327) (xy 61.780295 -297.50849)
			(xy 61.753992 -297.466894) (xy 61.734701 -297.421618) (xy 61.722924 -297.373834) (xy 61.718964 -297.32478)
			(xy 61.380116 -297.32478) (xy 61.379621 -297.349387) (xy 61.371726 -297.397964) (xy 61.356142 -297.444645)
			(xy 61.333271 -297.488222) (xy 61.303706 -297.527566) (xy 61.268213 -297.561658) (xy 61.22771 -297.589614)
			(xy 61.183248 -297.610712) (xy 61.135977 -297.624404) (xy 61.087122 -297.630336) (xy 61.037947 -297.628355)
			(xy 60.989728 -297.618511) (xy 60.943712 -297.601059) (xy 60.901091 -297.576452) (xy 60.86297 -297.545327)
			(xy 60.830335 -297.50849) (xy 60.804032 -297.466894) (xy 60.784741 -297.421618) (xy 60.772964 -297.373834)
			(xy 60.769004 -297.32478) (xy 60.430156 -297.32478) (xy 60.429661 -297.349387) (xy 60.421766 -297.397964)
			(xy 60.406182 -297.444645) (xy 60.383311 -297.488222) (xy 60.353746 -297.527566) (xy 60.318253 -297.561658)
			(xy 60.27775 -297.589614) (xy 60.233288 -297.610712) (xy 60.186017 -297.624404) (xy 60.137162 -297.630336)
			(xy 60.087987 -297.628355) (xy 60.039768 -297.618511) (xy 59.993752 -297.601059) (xy 59.951131 -297.576452)
			(xy 59.91301 -297.545327) (xy 59.880375 -297.50849) (xy 59.854072 -297.466894) (xy 59.834781 -297.421618)
			(xy 59.823004 -297.373834) (xy 59.819044 -297.32478) (xy 58.530236 -297.32478) (xy 58.529741 -297.349387)
			(xy 58.521846 -297.397964) (xy 58.506262 -297.444645) (xy 58.483391 -297.488222) (xy 58.453826 -297.527566)
			(xy 58.418333 -297.561658) (xy 58.37783 -297.589614) (xy 58.333368 -297.610712) (xy 58.286097 -297.624404)
			(xy 58.237242 -297.630336) (xy 58.188067 -297.628355) (xy 58.139848 -297.618511) (xy 58.093832 -297.601059)
			(xy 58.051211 -297.576452) (xy 58.01309 -297.545327) (xy 57.980455 -297.50849) (xy 57.954152 -297.466894)
			(xy 57.934861 -297.421618) (xy 57.923084 -297.373834) (xy 57.919124 -297.32478) (xy 57.580276 -297.32478)
			(xy 57.579781 -297.349387) (xy 57.571886 -297.397964) (xy 57.556302 -297.444645) (xy 57.533431 -297.488222)
			(xy 57.503866 -297.527566) (xy 57.468373 -297.561658) (xy 57.42787 -297.589614) (xy 57.383408 -297.610712)
			(xy 57.336137 -297.624404) (xy 57.287282 -297.630336) (xy 57.238107 -297.628355) (xy 57.189888 -297.618511)
			(xy 57.143872 -297.601059) (xy 57.101251 -297.576452) (xy 57.06313 -297.545327) (xy 57.030495 -297.50849)
			(xy 57.004192 -297.466894) (xy 56.984901 -297.421618) (xy 56.973124 -297.373834) (xy 56.969164 -297.32478)
			(xy 56.630062 -297.32478) (xy 56.629567 -297.349387) (xy 56.621672 -297.397964) (xy 56.606088 -297.444645)
			(xy 56.583217 -297.488222) (xy 56.553652 -297.527566) (xy 56.518159 -297.561658) (xy 56.477656 -297.589614)
			(xy 56.433194 -297.610712) (xy 56.385923 -297.624404) (xy 56.337068 -297.630336) (xy 56.287893 -297.628355)
			(xy 56.239674 -297.618511) (xy 56.193658 -297.601059) (xy 56.151037 -297.576452) (xy 56.112916 -297.545327)
			(xy 56.080281 -297.50849) (xy 56.053978 -297.466894) (xy 56.034687 -297.421618) (xy 56.02291 -297.373834)
			(xy 56.01895 -297.32478) (xy 55.680102 -297.32478) (xy 55.679607 -297.349387) (xy 55.671712 -297.397964)
			(xy 55.656128 -297.444645) (xy 55.633257 -297.488222) (xy 55.603692 -297.527566) (xy 55.568199 -297.561658)
			(xy 55.527696 -297.589614) (xy 55.483234 -297.610712) (xy 55.435963 -297.624404) (xy 55.387108 -297.630336)
			(xy 55.337933 -297.628355) (xy 55.289714 -297.618511) (xy 55.243698 -297.601059) (xy 55.201077 -297.576452)
			(xy 55.162956 -297.545327) (xy 55.130321 -297.50849) (xy 55.104018 -297.466894) (xy 55.084727 -297.421618)
			(xy 55.07295 -297.373834) (xy 55.06899 -297.32478) (xy 54.730142 -297.32478) (xy 54.729647 -297.349387)
			(xy 54.721752 -297.397964) (xy 54.706168 -297.444645) (xy 54.683297 -297.488222) (xy 54.653732 -297.527566)
			(xy 54.618239 -297.561658) (xy 54.577736 -297.589614) (xy 54.533274 -297.610712) (xy 54.486003 -297.624404)
			(xy 54.437148 -297.630336) (xy 54.387973 -297.628355) (xy 54.339754 -297.618511) (xy 54.293738 -297.601059)
			(xy 54.251117 -297.576452) (xy 54.212996 -297.545327) (xy 54.180361 -297.50849) (xy 54.154058 -297.466894)
			(xy 54.134767 -297.421618) (xy 54.12299 -297.373834) (xy 54.11903 -297.32478) (xy 53.780182 -297.32478)
			(xy 53.779687 -297.349387) (xy 53.771792 -297.397964) (xy 53.756208 -297.444645) (xy 53.733337 -297.488222)
			(xy 53.703772 -297.527566) (xy 53.668279 -297.561658) (xy 53.627776 -297.589614) (xy 53.583314 -297.610712)
			(xy 53.536043 -297.624404) (xy 53.487188 -297.630336) (xy 53.438013 -297.628355) (xy 53.389794 -297.618511)
			(xy 53.343778 -297.601059) (xy 53.301157 -297.576452) (xy 53.263036 -297.545327) (xy 53.230401 -297.50849)
			(xy 53.204098 -297.466894) (xy 53.184807 -297.421618) (xy 53.17303 -297.373834) (xy 53.16907 -297.32478)
			(xy 52.830222 -297.32478) (xy 52.829727 -297.349387) (xy 52.821832 -297.397964) (xy 52.806248 -297.444645)
			(xy 52.783377 -297.488222) (xy 52.753812 -297.527566) (xy 52.718319 -297.561658) (xy 52.677816 -297.589614)
			(xy 52.633354 -297.610712) (xy 52.586083 -297.624404) (xy 52.537228 -297.630336) (xy 52.488053 -297.628355)
			(xy 52.439834 -297.618511) (xy 52.393818 -297.601059) (xy 52.351197 -297.576452) (xy 52.313076 -297.545327)
			(xy 52.280441 -297.50849) (xy 52.254138 -297.466894) (xy 52.234847 -297.421618) (xy 52.22307 -297.373834)
			(xy 52.21911 -297.32478) (xy 51.880262 -297.32478) (xy 51.879767 -297.349387) (xy 51.871872 -297.397964)
			(xy 51.856288 -297.444645) (xy 51.833417 -297.488222) (xy 51.803852 -297.527566) (xy 51.768359 -297.561658)
			(xy 51.727856 -297.589614) (xy 51.683394 -297.610712) (xy 51.636123 -297.624404) (xy 51.587268 -297.630336)
			(xy 51.538093 -297.628355) (xy 51.489874 -297.618511) (xy 51.443858 -297.601059) (xy 51.401237 -297.576452)
			(xy 51.363116 -297.545327) (xy 51.330481 -297.50849) (xy 51.304178 -297.466894) (xy 51.284887 -297.421618)
			(xy 51.27311 -297.373834) (xy 51.26915 -297.32478) (xy 50.930302 -297.32478) (xy 50.929807 -297.349387)
			(xy 50.921912 -297.397964) (xy 50.906328 -297.444645) (xy 50.883457 -297.488222) (xy 50.853892 -297.527566)
			(xy 50.818399 -297.561658) (xy 50.777896 -297.589614) (xy 50.733434 -297.610712) (xy 50.686163 -297.624404)
			(xy 50.637308 -297.630336) (xy 50.588133 -297.628355) (xy 50.539914 -297.618511) (xy 50.493898 -297.601059)
			(xy 50.451277 -297.576452) (xy 50.413156 -297.545327) (xy 50.380521 -297.50849) (xy 50.354218 -297.466894)
			(xy 50.334927 -297.421618) (xy 50.32315 -297.373834) (xy 50.31919 -297.32478) (xy 49.980088 -297.32478)
			(xy 49.979593 -297.349387) (xy 49.971698 -297.397964) (xy 49.956114 -297.444645) (xy 49.933243 -297.488222)
			(xy 49.903678 -297.527566) (xy 49.868185 -297.561658) (xy 49.827682 -297.589614) (xy 49.78322 -297.610712)
			(xy 49.735949 -297.624404) (xy 49.687094 -297.630336) (xy 49.637919 -297.628355) (xy 49.5897 -297.618511)
			(xy 49.543684 -297.601059) (xy 49.501063 -297.576452) (xy 49.462942 -297.545327) (xy 49.430307 -297.50849)
			(xy 49.404004 -297.466894) (xy 49.384713 -297.421618) (xy 49.372936 -297.373834) (xy 49.368976 -297.32478)
			(xy 49.030128 -297.32478) (xy 49.029633 -297.349387) (xy 49.021738 -297.397964) (xy 49.006154 -297.444645)
			(xy 48.983283 -297.488222) (xy 48.953718 -297.527566) (xy 48.918225 -297.561658) (xy 48.877722 -297.589614)
			(xy 48.83326 -297.610712) (xy 48.785989 -297.624404) (xy 48.737134 -297.630336) (xy 48.687959 -297.628355)
			(xy 48.63974 -297.618511) (xy 48.593724 -297.601059) (xy 48.551103 -297.576452) (xy 48.512982 -297.545327)
			(xy 48.480347 -297.50849) (xy 48.454044 -297.466894) (xy 48.434753 -297.421618) (xy 48.422976 -297.373834)
			(xy 48.419016 -297.32478) (xy 48.080168 -297.32478) (xy 48.079673 -297.349387) (xy 48.071778 -297.397964)
			(xy 48.056194 -297.444645) (xy 48.033323 -297.488222) (xy 48.003758 -297.527566) (xy 47.968265 -297.561658)
			(xy 47.927762 -297.589614) (xy 47.8833 -297.610712) (xy 47.836029 -297.624404) (xy 47.787174 -297.630336)
			(xy 47.737999 -297.628355) (xy 47.68978 -297.618511) (xy 47.643764 -297.601059) (xy 47.601143 -297.576452)
			(xy 47.563022 -297.545327) (xy 47.530387 -297.50849) (xy 47.504084 -297.466894) (xy 47.484793 -297.421618)
			(xy 47.473016 -297.373834) (xy 47.469056 -297.32478) (xy 47.130208 -297.32478) (xy 47.129713 -297.349387)
			(xy 47.121818 -297.397964) (xy 47.106234 -297.444645) (xy 47.083363 -297.488222) (xy 47.053798 -297.527566)
			(xy 47.018305 -297.561658) (xy 46.977802 -297.589614) (xy 46.93334 -297.610712) (xy 46.886069 -297.624404)
			(xy 46.837214 -297.630336) (xy 46.788039 -297.628355) (xy 46.73982 -297.618511) (xy 46.693804 -297.601059)
			(xy 46.651183 -297.576452) (xy 46.613062 -297.545327) (xy 46.580427 -297.50849) (xy 46.554124 -297.466894)
			(xy 46.534833 -297.421618) (xy 46.523056 -297.373834) (xy 46.519096 -297.32478) (xy 46.180248 -297.32478)
			(xy 46.179753 -297.349387) (xy 46.171858 -297.397964) (xy 46.156274 -297.444645) (xy 46.133403 -297.488222)
			(xy 46.103838 -297.527566) (xy 46.068345 -297.561658) (xy 46.027842 -297.589614) (xy 45.98338 -297.610712)
			(xy 45.936109 -297.624404) (xy 45.887254 -297.630336) (xy 45.838079 -297.628355) (xy 45.78986 -297.618511)
			(xy 45.743844 -297.601059) (xy 45.701223 -297.576452) (xy 45.663102 -297.545327) (xy 45.630467 -297.50849)
			(xy 45.604164 -297.466894) (xy 45.584873 -297.421618) (xy 45.573096 -297.373834) (xy 45.569136 -297.32478)
			(xy 45.230288 -297.32478) (xy 45.229793 -297.349387) (xy 45.221898 -297.397964) (xy 45.206314 -297.444645)
			(xy 45.183443 -297.488222) (xy 45.153878 -297.527566) (xy 45.118385 -297.561658) (xy 45.077882 -297.589614)
			(xy 45.03342 -297.610712) (xy 44.986149 -297.624404) (xy 44.937294 -297.630336) (xy 44.888119 -297.628355)
			(xy 44.8399 -297.618511) (xy 44.793884 -297.601059) (xy 44.751263 -297.576452) (xy 44.713142 -297.545327)
			(xy 44.680507 -297.50849) (xy 44.654204 -297.466894) (xy 44.634913 -297.421618) (xy 44.623136 -297.373834)
			(xy 44.619176 -297.32478) (xy 44.280074 -297.32478) (xy 44.279579 -297.349387) (xy 44.271684 -297.397964)
			(xy 44.2561 -297.444645) (xy 44.233229 -297.488222) (xy 44.203664 -297.527566) (xy 44.168171 -297.561658)
			(xy 44.127668 -297.589614) (xy 44.083206 -297.610712) (xy 44.035935 -297.624404) (xy 43.98708 -297.630336)
			(xy 43.937905 -297.628355) (xy 43.889686 -297.618511) (xy 43.84367 -297.601059) (xy 43.801049 -297.576452)
			(xy 43.762928 -297.545327) (xy 43.730293 -297.50849) (xy 43.70399 -297.466894) (xy 43.684699 -297.421618)
			(xy 43.672922 -297.373834) (xy 43.668962 -297.32478) (xy 42.380154 -297.32478) (xy 42.379659 -297.349387)
			(xy 42.371764 -297.397964) (xy 42.35618 -297.444645) (xy 42.333309 -297.488222) (xy 42.303744 -297.527566)
			(xy 42.268251 -297.561658) (xy 42.227748 -297.589614) (xy 42.183286 -297.610712) (xy 42.136015 -297.624404)
			(xy 42.08716 -297.630336) (xy 42.037985 -297.628355) (xy 41.989766 -297.618511) (xy 41.94375 -297.601059)
			(xy 41.901129 -297.576452) (xy 41.863008 -297.545327) (xy 41.830373 -297.50849) (xy 41.80407 -297.466894)
			(xy 41.784779 -297.421618) (xy 41.773002 -297.373834) (xy 41.769042 -297.32478) (xy 39.530274 -297.32478)
			(xy 39.529779 -297.349387) (xy 39.521884 -297.397964) (xy 39.5063 -297.444645) (xy 39.483429 -297.488222)
			(xy 39.453864 -297.527566) (xy 39.418371 -297.561658) (xy 39.377868 -297.589614) (xy 39.333406 -297.610712)
			(xy 39.286135 -297.624404) (xy 39.23728 -297.630336) (xy 39.188105 -297.628355) (xy 39.139886 -297.618511)
			(xy 39.09387 -297.601059) (xy 39.051249 -297.576452) (xy 39.013128 -297.545327) (xy 38.980493 -297.50849)
			(xy 38.95419 -297.466894) (xy 38.934899 -297.421618) (xy 38.923122 -297.373834) (xy 38.919162 -297.32478)
			(xy 38.58006 -297.32478) (xy 38.579565 -297.349387) (xy 38.57167 -297.397964) (xy 38.556086 -297.444645)
			(xy 38.533215 -297.488222) (xy 38.50365 -297.527566) (xy 38.468157 -297.561658) (xy 38.427654 -297.589614)
			(xy 38.383192 -297.610712) (xy 38.335921 -297.624404) (xy 38.287066 -297.630336) (xy 38.237891 -297.628355)
			(xy 38.189672 -297.618511) (xy 38.143656 -297.601059) (xy 38.101035 -297.576452) (xy 38.062914 -297.545327)
			(xy 38.030279 -297.50849) (xy 38.003976 -297.466894) (xy 37.984685 -297.421618) (xy 37.972908 -297.373834)
			(xy 37.968948 -297.32478) (xy 37.654679 -297.32478) (xy 37.654679 -297.350784) (xy 37.64655 -297.402111)
			(xy 37.630492 -297.451536) (xy 37.606901 -297.49784) (xy 37.576357 -297.539884) (xy 37.539613 -297.576632)
			(xy 37.497572 -297.607181) (xy 37.451271 -297.630778) (xy 37.401848 -297.646841) (xy 37.350522 -297.654976)
			(xy 37.324538 -297.655488) (xy 36.374578 -297.655488) (xy 36.350206 -297.655043) (xy 36.301987 -297.647903)
			(xy 36.255338 -297.633766) (xy 36.211267 -297.612937) (xy 36.17073 -297.585868) (xy 36.134603 -297.553144)
			(xy 36.1188 -297.534584) (xy 36.111434 -297.525694) (xy 36.09213 -297.516296) (xy 35.992562 -297.513502)
			(xy 35.97275 -297.522138) (xy 35.96513 -297.530266) (xy 35.947651 -297.548698) (xy 35.907685 -297.580046)
			(xy 35.86308 -297.604346) (xy 35.815069 -297.620927) (xy 35.764975 -297.629331) (xy 35.739578 -297.629834)
			(xy 35.714326 -297.629259) (xy 35.664511 -297.620943) (xy 35.616745 -297.604542) (xy 35.572329 -297.580502)
			(xy 35.532475 -297.54948) (xy 35.498271 -297.512322) (xy 35.470649 -297.470041) (xy 35.450363 -297.42379)
			(xy 35.437965 -297.374832) (xy 35.433795 -297.3245) (xy 33.497163 -297.3245) (xy 33.487047 -297.358125)
			(xy 33.463375 -297.408622) (xy 33.432602 -297.455135) (xy 33.395385 -297.496672) (xy 33.352517 -297.532347)
			(xy 33.304911 -297.561401) (xy 33.253582 -297.583213) (xy 33.199625 -297.597319) (xy 33.144188 -297.603419)
			(xy 33.088454 -297.601382) (xy 33.033611 -297.591252) (xy 32.980827 -297.573245) (xy 32.931227 -297.547744)
			(xy 32.885869 -297.515293) (xy 32.84572 -297.476584) (xy 32.811634 -297.432441) (xy 32.784338 -297.383806)
			(xy 32.764415 -297.331715) (xy 32.752289 -297.277278) (xy 32.748218 -297.221656) (xy 1.925828 -297.221656)
			(xy 2.535428 -297.831256) (xy 25.811478 -297.831256) (xy 25.815549 -297.775634) (xy 25.827675 -297.721197)
			(xy 25.847598 -297.669106) (xy 25.874894 -297.620471) (xy 25.90898 -297.576328) (xy 25.949129 -297.537619)
			(xy 25.994487 -297.505168) (xy 26.044087 -297.479667) (xy 26.096871 -297.46166) (xy 26.151714 -297.45153)
			(xy 26.207448 -297.449493) (xy 26.262885 -297.455593) (xy 26.316842 -297.469699) (xy 26.368171 -297.491511)
			(xy 26.415777 -297.520565) (xy 26.458645 -297.55624) (xy 26.495862 -297.597777) (xy 26.526635 -297.64429)
			(xy 26.550307 -297.694787) (xy 26.566375 -297.748194) (xy 26.574495 -297.80337) (xy 26.575004 -297.831256)
			(xy 27.296616 -297.831256) (xy 27.300687 -297.775634) (xy 27.312813 -297.721197) (xy 27.332736 -297.669106)
			(xy 27.360032 -297.620471) (xy 27.394118 -297.576328) (xy 27.434267 -297.537619) (xy 27.479625 -297.505168)
			(xy 27.529225 -297.479667) (xy 27.582009 -297.46166) (xy 27.636852 -297.45153) (xy 27.692586 -297.449493)
			(xy 27.748023 -297.455593) (xy 27.80198 -297.469699) (xy 27.853309 -297.491511) (xy 27.900915 -297.520565)
			(xy 27.943783 -297.55624) (xy 27.981 -297.597777) (xy 28.011773 -297.64429) (xy 28.035445 -297.694787)
			(xy 28.051513 -297.748194) (xy 28.059633 -297.80337) (xy 28.060142 -297.831256) (xy 28.059633 -297.859142)
			(xy 28.051513 -297.914318) (xy 28.035445 -297.967725) (xy 28.011773 -298.018222) (xy 27.981 -298.064735)
			(xy 27.943783 -298.106272) (xy 27.900915 -298.141947) (xy 27.853309 -298.171001) (xy 27.80198 -298.192813)
			(xy 27.748023 -298.206919) (xy 27.692586 -298.213019) (xy 27.636852 -298.210982) (xy 27.582009 -298.200852)
			(xy 27.529225 -298.182845) (xy 27.479625 -298.157344) (xy 27.434267 -298.124893) (xy 27.394118 -298.086184)
			(xy 27.360032 -298.042041) (xy 27.332736 -297.993406) (xy 27.312813 -297.941315) (xy 27.300687 -297.886878)
			(xy 27.296616 -297.831256) (xy 26.575004 -297.831256) (xy 26.574495 -297.859142) (xy 26.566375 -297.914318)
			(xy 26.550307 -297.967725) (xy 26.526635 -298.018222) (xy 26.495862 -298.064735) (xy 26.458645 -298.106272)
			(xy 26.415777 -298.141947) (xy 26.368171 -298.171001) (xy 26.316842 -298.192813) (xy 26.262885 -298.206919)
			(xy 26.207448 -298.213019) (xy 26.151714 -298.210982) (xy 26.096871 -298.200852) (xy 26.044087 -298.182845)
			(xy 25.994487 -298.157344) (xy 25.949129 -298.124893) (xy 25.90898 -298.086184) (xy 25.874894 -298.042041)
			(xy 25.847598 -297.993406) (xy 25.827675 -297.941315) (xy 25.815549 -297.886878) (xy 25.811478 -297.831256)
			(xy 2.535428 -297.831256) (xy 2.593594 -297.889422) (xy 2.600988 -297.896278) (xy 2.619587 -297.904027)
			(xy 2.629662 -297.904408) (xy 16.729456 -297.904408) (xy 16.739521 -297.904842) (xy 16.75811 -297.912571)
			(xy 16.765524 -297.919394) (xy 17.683988 -298.837858) (xy 17.690827 -298.845259) (xy 17.698542 -298.863857)
			(xy 17.698974 -298.873926) (xy 17.698974 -298.875704) (xy 17.828514 -298.9326) (xy 17.857724 -298.927774)
			(xy 17.869154 -298.917614) (xy 17.931076 -298.86164) (xy 18.059641 -298.755154) (xy 18.193309 -298.655147)
			(xy 18.331752 -298.561864) (xy 18.474634 -298.475532) (xy 18.621606 -298.396363) (xy 18.772308 -298.324549)
			(xy 18.926374 -298.260266) (xy 19.083426 -298.203671) (xy 19.243081 -298.154902) (xy 19.404951 -298.114077)
			(xy 19.568639 -298.081297) (xy 19.733747 -298.056641) (xy 19.89987 -298.04017) (xy 20.066605 -298.031923)
			(xy 20.150074 -298.031408) (xy 20.231728 -298.031901) (xy 20.394846 -298.039791) (xy 20.557392 -298.055553)
			(xy 20.718987 -298.07915) (xy 20.879253 -298.110526) (xy 21.037815 -298.149608) (xy 21.194305 -298.196306)
			(xy 21.348356 -298.250509) (xy 21.407869 -298.27474) (xy 37.018734 -298.27474) (xy 37.022694 -298.225686)
			(xy 37.034471 -298.177902) (xy 37.053762 -298.132626) (xy 37.080065 -298.09103) (xy 37.1127 -298.054193)
			(xy 37.150821 -298.023068) (xy 37.193442 -297.998461) (xy 37.239458 -297.981009) (xy 37.287677 -297.971165)
			(xy 37.336852 -297.969184) (xy 37.385707 -297.975116) (xy 37.432978 -297.988808) (xy 37.47744 -298.009906)
			(xy 37.517943 -298.037862) (xy 37.553436 -298.071954) (xy 37.583001 -298.111298) (xy 37.605872 -298.154875)
			(xy 37.621456 -298.201556) (xy 37.629351 -298.250133) (xy 37.629846 -298.27474) (xy 37.968948 -298.27474)
			(xy 37.972908 -298.225686) (xy 37.984685 -298.177902) (xy 38.003976 -298.132626) (xy 38.030279 -298.09103)
			(xy 38.062914 -298.054193) (xy 38.101035 -298.023068) (xy 38.143656 -297.998461) (xy 38.189672 -297.981009)
			(xy 38.237891 -297.971165) (xy 38.287066 -297.969184) (xy 38.335921 -297.975116) (xy 38.383192 -297.988808)
			(xy 38.427654 -298.009906) (xy 38.468157 -298.037862) (xy 38.50365 -298.071954) (xy 38.533215 -298.111298)
			(xy 38.556086 -298.154875) (xy 38.57167 -298.201556) (xy 38.579565 -298.250133) (xy 38.58006 -298.27474)
			(xy 38.579895 -298.282945) (xy 38.919314 -298.282945) (xy 38.922007 -298.233382) (xy 38.932683 -298.184907)
			(xy 38.951061 -298.138798) (xy 38.976657 -298.09627) (xy 39.008795 -298.058443) (xy 39.04663 -298.026313)
			(xy 39.089164 -298.000728) (xy 39.135278 -297.982362) (xy 39.183755 -297.971697) (xy 39.233319 -297.969016)
			(xy 39.282664 -297.974389) (xy 39.330489 -297.987674) (xy 39.375535 -298.008522) (xy 39.416615 -298.036382)
			(xy 39.452647 -298.070522) (xy 39.48268 -298.110041) (xy 39.505925 -298.153898) (xy 39.521768 -298.200938)
			(xy 39.529791 -298.249922) (xy 39.530274 -298.27474) (xy 39.530183 -298.283844) (xy 39.529037 -298.302018)
			(xy 39.527988 -298.311062) (xy 39.526718 -298.323254) (xy 39.534592 -298.345352) (xy 39.611046 -298.418504)
			(xy 39.633652 -298.425362) (xy 39.64559 -298.42333) (xy 39.659084 -298.421274) (xy 39.686297 -298.419112)
			(xy 39.699946 -298.419012) (xy 39.770304 -298.419012) (xy 39.78096 -298.418376) (xy 39.800383 -298.409578)
			(xy 39.807896 -298.401994) (xy 39.865808 -298.337732) (xy 39.872412 -298.317666) (xy 39.871396 -298.306744)
			(xy 39.869618 -298.27474) (xy 39.87014 -298.249485) (xy 39.878453 -298.199663) (xy 39.894854 -298.151889)
			(xy 39.918895 -298.107466) (xy 39.949919 -298.067606) (xy 39.987081 -298.033396) (xy 40.029367 -298.00577)
			(xy 40.075623 -297.98548) (xy 40.124588 -297.97308) (xy 40.174926 -297.968909) (xy 40.225264 -297.97308)
			(xy 40.274229 -297.98548) (xy 40.320485 -298.00577) (xy 40.362771 -298.033396) (xy 40.399933 -298.067606)
			(xy 40.430957 -298.107466) (xy 40.454998 -298.151889) (xy 40.471399 -298.199663) (xy 40.479712 -298.249485)
			(xy 40.480234 -298.27474) (xy 40.478456 -298.306744) (xy 40.47744 -298.317666) (xy 40.484044 -298.337732)
			(xy 40.541956 -298.401994) (xy 40.549387 -298.409689) (xy 40.568862 -298.418497) (xy 40.579548 -298.419012)
			(xy 40.649906 -298.419012) (xy 40.663556 -298.419101) (xy 40.690769 -298.421263) (xy 40.704262 -298.42333)
			(xy 40.7162 -298.425362) (xy 40.738806 -298.418504) (xy 40.81526 -298.345352) (xy 40.823134 -298.323254)
			(xy 40.821864 -298.311062) (xy 40.82082 -298.302017) (xy 40.819676 -298.283844) (xy 40.819578 -298.27474)
			(xy 40.820035 -298.249915) (xy 40.828061 -298.200918) (xy 40.843909 -298.153865) (xy 40.867161 -298.109996)
			(xy 40.897203 -298.070467) (xy 40.933246 -298.036319) (xy 40.974338 -298.008452) (xy 41.019397 -297.9876)
			(xy 41.067236 -297.974314) (xy 41.116595 -297.968942) (xy 41.166172 -297.971626) (xy 41.214662 -297.982296)
			(xy 41.260787 -298.000671) (xy 41.303331 -298.026266) (xy 41.341174 -298.058407) (xy 41.373319 -298.096247)
			(xy 41.398917 -298.13879) (xy 41.417296 -298.184913) (xy 41.42797 -298.233402) (xy 41.430212 -298.27474)
			(xy 41.769042 -298.27474) (xy 41.773002 -298.225686) (xy 41.784779 -298.177902) (xy 41.80407 -298.132626)
			(xy 41.830373 -298.09103) (xy 41.863008 -298.054193) (xy 41.901129 -298.023068) (xy 41.94375 -297.998461)
			(xy 41.989766 -297.981009) (xy 42.037985 -297.971165) (xy 42.08716 -297.969184) (xy 42.136015 -297.975116)
			(xy 42.183286 -297.988808) (xy 42.227748 -298.009906) (xy 42.268251 -298.037862) (xy 42.303744 -298.071954)
			(xy 42.333309 -298.111298) (xy 42.35618 -298.154875) (xy 42.371764 -298.201556) (xy 42.379659 -298.250133)
			(xy 42.380154 -298.27474) (xy 43.668962 -298.27474) (xy 43.672922 -298.225686) (xy 43.684699 -298.177902)
			(xy 43.70399 -298.132626) (xy 43.730293 -298.09103) (xy 43.762928 -298.054193) (xy 43.801049 -298.023068)
			(xy 43.84367 -297.998461) (xy 43.889686 -297.981009) (xy 43.937905 -297.971165) (xy 43.98708 -297.969184)
			(xy 44.035935 -297.975116) (xy 44.083206 -297.988808) (xy 44.127668 -298.009906) (xy 44.168171 -298.037862)
			(xy 44.203664 -298.071954) (xy 44.233229 -298.111298) (xy 44.2561 -298.154875) (xy 44.271684 -298.201556)
			(xy 44.279579 -298.250133) (xy 44.280074 -298.27474) (xy 44.619176 -298.27474) (xy 44.623136 -298.225686)
			(xy 44.634913 -298.177902) (xy 44.654204 -298.132626) (xy 44.680507 -298.09103) (xy 44.713142 -298.054193)
			(xy 44.751263 -298.023068) (xy 44.793884 -297.998461) (xy 44.8399 -297.981009) (xy 44.888119 -297.971165)
			(xy 44.937294 -297.969184) (xy 44.986149 -297.975116) (xy 45.03342 -297.988808) (xy 45.077882 -298.009906)
			(xy 45.118385 -298.037862) (xy 45.153878 -298.071954) (xy 45.183443 -298.111298) (xy 45.206314 -298.154875)
			(xy 45.221898 -298.201556) (xy 45.229793 -298.250133) (xy 45.230288 -298.27474) (xy 45.569136 -298.27474)
			(xy 45.573096 -298.225686) (xy 45.584873 -298.177902) (xy 45.604164 -298.132626) (xy 45.630467 -298.09103)
			(xy 45.663102 -298.054193) (xy 45.701223 -298.023068) (xy 45.743844 -297.998461) (xy 45.78986 -297.981009)
			(xy 45.838079 -297.971165) (xy 45.887254 -297.969184) (xy 45.936109 -297.975116) (xy 45.98338 -297.988808)
			(xy 46.027842 -298.009906) (xy 46.068345 -298.037862) (xy 46.103838 -298.071954) (xy 46.133403 -298.111298)
			(xy 46.156274 -298.154875) (xy 46.171858 -298.201556) (xy 46.179753 -298.250133) (xy 46.180248 -298.27474)
			(xy 47.469056 -298.27474) (xy 47.473016 -298.225686) (xy 47.484793 -298.177902) (xy 47.504084 -298.132626)
			(xy 47.530387 -298.09103) (xy 47.563022 -298.054193) (xy 47.601143 -298.023068) (xy 47.643764 -297.998461)
			(xy 47.68978 -297.981009) (xy 47.737999 -297.971165) (xy 47.787174 -297.969184) (xy 47.836029 -297.975116)
			(xy 47.8833 -297.988808) (xy 47.927762 -298.009906) (xy 47.968265 -298.037862) (xy 48.003758 -298.071954)
			(xy 48.033323 -298.111298) (xy 48.056194 -298.154875) (xy 48.071778 -298.201556) (xy 48.079673 -298.250133)
			(xy 48.080168 -298.27474) (xy 48.419016 -298.27474) (xy 48.422976 -298.225686) (xy 48.434753 -298.177902)
			(xy 48.454044 -298.132626) (xy 48.480347 -298.09103) (xy 48.512982 -298.054193) (xy 48.551103 -298.023068)
			(xy 48.593724 -297.998461) (xy 48.63974 -297.981009) (xy 48.687959 -297.971165) (xy 48.737134 -297.969184)
			(xy 48.785989 -297.975116) (xy 48.83326 -297.988808) (xy 48.877722 -298.009906) (xy 48.918225 -298.037862)
			(xy 48.953718 -298.071954) (xy 48.983283 -298.111298) (xy 49.006154 -298.154875) (xy 49.021738 -298.201556)
			(xy 49.029633 -298.250133) (xy 49.030128 -298.27474) (xy 49.368976 -298.27474) (xy 49.372936 -298.225686)
			(xy 49.384713 -298.177902) (xy 49.404004 -298.132626) (xy 49.430307 -298.09103) (xy 49.462942 -298.054193)
			(xy 49.501063 -298.023068) (xy 49.543684 -297.998461) (xy 49.5897 -297.981009) (xy 49.637919 -297.971165)
			(xy 49.687094 -297.969184) (xy 49.735949 -297.975116) (xy 49.78322 -297.988808) (xy 49.827682 -298.009906)
			(xy 49.868185 -298.037862) (xy 49.903678 -298.071954) (xy 49.933243 -298.111298) (xy 49.956114 -298.154875)
			(xy 49.971698 -298.201556) (xy 49.979593 -298.250133) (xy 49.980088 -298.27474) (xy 50.31919 -298.27474)
			(xy 50.32315 -298.225686) (xy 50.334927 -298.177902) (xy 50.354218 -298.132626) (xy 50.380521 -298.09103)
			(xy 50.413156 -298.054193) (xy 50.451277 -298.023068) (xy 50.493898 -297.998461) (xy 50.539914 -297.981009)
			(xy 50.588133 -297.971165) (xy 50.637308 -297.969184) (xy 50.686163 -297.975116) (xy 50.733434 -297.988808)
			(xy 50.777896 -298.009906) (xy 50.818399 -298.037862) (xy 50.853892 -298.071954) (xy 50.883457 -298.111298)
			(xy 50.906328 -298.154875) (xy 50.921912 -298.201556) (xy 50.929807 -298.250133) (xy 50.930302 -298.27474)
			(xy 51.26915 -298.27474) (xy 51.27311 -298.225686) (xy 51.284887 -298.177902) (xy 51.304178 -298.132626)
			(xy 51.330481 -298.09103) (xy 51.363116 -298.054193) (xy 51.401237 -298.023068) (xy 51.443858 -297.998461)
			(xy 51.489874 -297.981009) (xy 51.538093 -297.971165) (xy 51.587268 -297.969184) (xy 51.636123 -297.975116)
			(xy 51.683394 -297.988808) (xy 51.727856 -298.009906) (xy 51.768359 -298.037862) (xy 51.803852 -298.071954)
			(xy 51.833417 -298.111298) (xy 51.856288 -298.154875) (xy 51.871872 -298.201556) (xy 51.879767 -298.250133)
			(xy 51.880262 -298.27474) (xy 52.21911 -298.27474) (xy 52.22307 -298.225686) (xy 52.234847 -298.177902)
			(xy 52.254138 -298.132626) (xy 52.280441 -298.09103) (xy 52.313076 -298.054193) (xy 52.351197 -298.023068)
			(xy 52.393818 -297.998461) (xy 52.439834 -297.981009) (xy 52.488053 -297.971165) (xy 52.537228 -297.969184)
			(xy 52.586083 -297.975116) (xy 52.633354 -297.988808) (xy 52.677816 -298.009906) (xy 52.718319 -298.037862)
			(xy 52.753812 -298.071954) (xy 52.783377 -298.111298) (xy 52.806248 -298.154875) (xy 52.821832 -298.201556)
			(xy 52.829727 -298.250133) (xy 52.830222 -298.27474) (xy 53.16907 -298.27474) (xy 53.17303 -298.225686)
			(xy 53.184807 -298.177902) (xy 53.204098 -298.132626) (xy 53.230401 -298.09103) (xy 53.263036 -298.054193)
			(xy 53.301157 -298.023068) (xy 53.343778 -297.998461) (xy 53.389794 -297.981009) (xy 53.438013 -297.971165)
			(xy 53.487188 -297.969184) (xy 53.536043 -297.975116) (xy 53.583314 -297.988808) (xy 53.627776 -298.009906)
			(xy 53.668279 -298.037862) (xy 53.703772 -298.071954) (xy 53.733337 -298.111298) (xy 53.756208 -298.154875)
			(xy 53.771792 -298.201556) (xy 53.779687 -298.250133) (xy 53.780182 -298.27474) (xy 54.11903 -298.27474)
			(xy 54.12299 -298.225686) (xy 54.134767 -298.177902) (xy 54.154058 -298.132626) (xy 54.180361 -298.09103)
			(xy 54.212996 -298.054193) (xy 54.251117 -298.023068) (xy 54.293738 -297.998461) (xy 54.339754 -297.981009)
			(xy 54.387973 -297.971165) (xy 54.437148 -297.969184) (xy 54.486003 -297.975116) (xy 54.533274 -297.988808)
			(xy 54.577736 -298.009906) (xy 54.618239 -298.037862) (xy 54.653732 -298.071954) (xy 54.683297 -298.111298)
			(xy 54.706168 -298.154875) (xy 54.721752 -298.201556) (xy 54.729647 -298.250133) (xy 54.730142 -298.27474)
			(xy 55.06899 -298.27474) (xy 55.07295 -298.225686) (xy 55.084727 -298.177902) (xy 55.104018 -298.132626)
			(xy 55.130321 -298.09103) (xy 55.162956 -298.054193) (xy 55.201077 -298.023068) (xy 55.243698 -297.998461)
			(xy 55.289714 -297.981009) (xy 55.337933 -297.971165) (xy 55.387108 -297.969184) (xy 55.435963 -297.975116)
			(xy 55.483234 -297.988808) (xy 55.527696 -298.009906) (xy 55.568199 -298.037862) (xy 55.603692 -298.071954)
			(xy 55.633257 -298.111298) (xy 55.656128 -298.154875) (xy 55.671712 -298.201556) (xy 55.679607 -298.250133)
			(xy 55.680102 -298.27474) (xy 56.01895 -298.27474) (xy 56.02291 -298.225686) (xy 56.034687 -298.177902)
			(xy 56.053978 -298.132626) (xy 56.080281 -298.09103) (xy 56.112916 -298.054193) (xy 56.151037 -298.023068)
			(xy 56.193658 -297.998461) (xy 56.239674 -297.981009) (xy 56.287893 -297.971165) (xy 56.337068 -297.969184)
			(xy 56.385923 -297.975116) (xy 56.433194 -297.988808) (xy 56.477656 -298.009906) (xy 56.518159 -298.037862)
			(xy 56.553652 -298.071954) (xy 56.583217 -298.111298) (xy 56.606088 -298.154875) (xy 56.621672 -298.201556)
			(xy 56.629567 -298.250133) (xy 56.630062 -298.27474) (xy 56.969164 -298.27474) (xy 56.973124 -298.225686)
			(xy 56.984901 -298.177902) (xy 57.004192 -298.132626) (xy 57.030495 -298.09103) (xy 57.06313 -298.054193)
			(xy 57.101251 -298.023068) (xy 57.143872 -297.998461) (xy 57.189888 -297.981009) (xy 57.238107 -297.971165)
			(xy 57.287282 -297.969184) (xy 57.336137 -297.975116) (xy 57.383408 -297.988808) (xy 57.42787 -298.009906)
			(xy 57.468373 -298.037862) (xy 57.503866 -298.071954) (xy 57.533431 -298.111298) (xy 57.556302 -298.154875)
			(xy 57.571886 -298.201556) (xy 57.579781 -298.250133) (xy 57.580276 -298.27474) (xy 57.919124 -298.27474)
			(xy 57.923084 -298.225686) (xy 57.934861 -298.177902) (xy 57.954152 -298.132626) (xy 57.980455 -298.09103)
			(xy 58.01309 -298.054193) (xy 58.051211 -298.023068) (xy 58.093832 -297.998461) (xy 58.139848 -297.981009)
			(xy 58.188067 -297.971165) (xy 58.237242 -297.969184) (xy 58.286097 -297.975116) (xy 58.333368 -297.988808)
			(xy 58.37783 -298.009906) (xy 58.418333 -298.037862) (xy 58.453826 -298.071954) (xy 58.483391 -298.111298)
			(xy 58.506262 -298.154875) (xy 58.521846 -298.201556) (xy 58.529741 -298.250133) (xy 58.530236 -298.27474)
			(xy 59.819044 -298.27474) (xy 59.823004 -298.225686) (xy 59.834781 -298.177902) (xy 59.854072 -298.132626)
			(xy 59.880375 -298.09103) (xy 59.91301 -298.054193) (xy 59.951131 -298.023068) (xy 59.993752 -297.998461)
			(xy 60.039768 -297.981009) (xy 60.087987 -297.971165) (xy 60.137162 -297.969184) (xy 60.186017 -297.975116)
			(xy 60.233288 -297.988808) (xy 60.27775 -298.009906) (xy 60.318253 -298.037862) (xy 60.353746 -298.071954)
			(xy 60.383311 -298.111298) (xy 60.406182 -298.154875) (xy 60.421766 -298.201556) (xy 60.429661 -298.250133)
			(xy 60.430156 -298.27474) (xy 60.769004 -298.27474) (xy 60.772964 -298.225686) (xy 60.784741 -298.177902)
			(xy 60.804032 -298.132626) (xy 60.830335 -298.09103) (xy 60.86297 -298.054193) (xy 60.901091 -298.023068)
			(xy 60.943712 -297.998461) (xy 60.989728 -297.981009) (xy 61.037947 -297.971165) (xy 61.087122 -297.969184)
			(xy 61.135977 -297.975116) (xy 61.183248 -297.988808) (xy 61.22771 -298.009906) (xy 61.268213 -298.037862)
			(xy 61.303706 -298.071954) (xy 61.333271 -298.111298) (xy 61.356142 -298.154875) (xy 61.371726 -298.201556)
			(xy 61.379621 -298.250133) (xy 61.380116 -298.27474) (xy 61.718964 -298.27474) (xy 61.722924 -298.225686)
			(xy 61.734701 -298.177902) (xy 61.753992 -298.132626) (xy 61.780295 -298.09103) (xy 61.81293 -298.054193)
			(xy 61.851051 -298.023068) (xy 61.893672 -297.998461) (xy 61.939688 -297.981009) (xy 61.987907 -297.971165)
			(xy 62.037082 -297.969184) (xy 62.085937 -297.975116) (xy 62.133208 -297.988808) (xy 62.17767 -298.009906)
			(xy 62.218173 -298.037862) (xy 62.253666 -298.071954) (xy 62.283231 -298.111298) (xy 62.306102 -298.154875)
			(xy 62.321686 -298.201556) (xy 62.329581 -298.250133) (xy 62.330076 -298.27474) (xy 62.669178 -298.27474)
			(xy 62.673138 -298.225686) (xy 62.684915 -298.177902) (xy 62.704206 -298.132626) (xy 62.730509 -298.09103)
			(xy 62.763144 -298.054193) (xy 62.801265 -298.023068) (xy 62.843886 -297.998461) (xy 62.889902 -297.981009)
			(xy 62.938121 -297.971165) (xy 62.987296 -297.969184) (xy 63.036151 -297.975116) (xy 63.083422 -297.988808)
			(xy 63.127884 -298.009906) (xy 63.168387 -298.037862) (xy 63.20388 -298.071954) (xy 63.233445 -298.111298)
			(xy 63.256316 -298.154875) (xy 63.2719 -298.201556) (xy 63.279795 -298.250133) (xy 63.28029 -298.27474)
			(xy 63.619138 -298.27474) (xy 63.623098 -298.225686) (xy 63.634875 -298.177902) (xy 63.654166 -298.132626)
			(xy 63.680469 -298.09103) (xy 63.713104 -298.054193) (xy 63.751225 -298.023068) (xy 63.793846 -297.998461)
			(xy 63.839862 -297.981009) (xy 63.888081 -297.971165) (xy 63.937256 -297.969184) (xy 63.986111 -297.975116)
			(xy 64.033382 -297.988808) (xy 64.077844 -298.009906) (xy 64.118347 -298.037862) (xy 64.15384 -298.071954)
			(xy 64.183405 -298.111298) (xy 64.206276 -298.154875) (xy 64.22186 -298.201556) (xy 64.229755 -298.250133)
			(xy 64.23025 -298.27474) (xy 64.569098 -298.27474) (xy 64.573058 -298.225686) (xy 64.584835 -298.177902)
			(xy 64.604126 -298.132626) (xy 64.630429 -298.09103) (xy 64.663064 -298.054193) (xy 64.701185 -298.023068)
			(xy 64.743806 -297.998461) (xy 64.789822 -297.981009) (xy 64.838041 -297.971165) (xy 64.887216 -297.969184)
			(xy 64.936071 -297.975116) (xy 64.983342 -297.988808) (xy 65.027804 -298.009906) (xy 65.068307 -298.037862)
			(xy 65.1038 -298.071954) (xy 65.133365 -298.111298) (xy 65.156236 -298.154875) (xy 65.17182 -298.201556)
			(xy 65.179715 -298.250133) (xy 65.18021 -298.27474) (xy 65.519058 -298.27474) (xy 65.523018 -298.225686)
			(xy 65.534795 -298.177902) (xy 65.554086 -298.132626) (xy 65.580389 -298.09103) (xy 65.613024 -298.054193)
			(xy 65.651145 -298.023068) (xy 65.693766 -297.998461) (xy 65.739782 -297.981009) (xy 65.788001 -297.971165)
			(xy 65.837176 -297.969184) (xy 65.886031 -297.975116) (xy 65.933302 -297.988808) (xy 65.977764 -298.009906)
			(xy 66.018267 -298.037862) (xy 66.05376 -298.071954) (xy 66.083325 -298.111298) (xy 66.106196 -298.154875)
			(xy 66.12178 -298.201556) (xy 66.129675 -298.250133) (xy 66.13017 -298.27474) (xy 66.469018 -298.27474)
			(xy 66.472978 -298.225686) (xy 66.484755 -298.177902) (xy 66.504046 -298.132626) (xy 66.530349 -298.09103)
			(xy 66.562984 -298.054193) (xy 66.601105 -298.023068) (xy 66.643726 -297.998461) (xy 66.689742 -297.981009)
			(xy 66.737961 -297.971165) (xy 66.787136 -297.969184) (xy 66.835991 -297.975116) (xy 66.883262 -297.988808)
			(xy 66.927724 -298.009906) (xy 66.968227 -298.037862) (xy 67.00372 -298.071954) (xy 67.033285 -298.111298)
			(xy 67.056156 -298.154875) (xy 67.07174 -298.201556) (xy 67.079635 -298.250133) (xy 67.08013 -298.27474)
			(xy 67.418978 -298.27474) (xy 67.422938 -298.225686) (xy 67.434715 -298.177902) (xy 67.454006 -298.132626)
			(xy 67.480309 -298.09103) (xy 67.512944 -298.054193) (xy 67.551065 -298.023068) (xy 67.593686 -297.998461)
			(xy 67.639702 -297.981009) (xy 67.687921 -297.971165) (xy 67.737096 -297.969184) (xy 67.785951 -297.975116)
			(xy 67.833222 -297.988808) (xy 67.877684 -298.009906) (xy 67.918187 -298.037862) (xy 67.95368 -298.071954)
			(xy 67.983245 -298.111298) (xy 68.006116 -298.154875) (xy 68.0217 -298.201556) (xy 68.029595 -298.250133)
			(xy 68.03009 -298.27474) (xy 68.368938 -298.27474) (xy 68.372898 -298.225686) (xy 68.384675 -298.177902)
			(xy 68.403966 -298.132626) (xy 68.430269 -298.09103) (xy 68.462904 -298.054193) (xy 68.501025 -298.023068)
			(xy 68.543646 -297.998461) (xy 68.589662 -297.981009) (xy 68.637881 -297.971165) (xy 68.687056 -297.969184)
			(xy 68.735911 -297.975116) (xy 68.783182 -297.988808) (xy 68.827644 -298.009906) (xy 68.868147 -298.037862)
			(xy 68.90364 -298.071954) (xy 68.933205 -298.111298) (xy 68.956076 -298.154875) (xy 68.97166 -298.201556)
			(xy 68.979555 -298.250133) (xy 68.98005 -298.27474) (xy 69.319152 -298.27474) (xy 69.323112 -298.225686)
			(xy 69.334889 -298.177902) (xy 69.35418 -298.132626) (xy 69.380483 -298.09103) (xy 69.413118 -298.054193)
			(xy 69.451239 -298.023068) (xy 69.49386 -297.998461) (xy 69.539876 -297.981009) (xy 69.588095 -297.971165)
			(xy 69.63727 -297.969184) (xy 69.686125 -297.975116) (xy 69.733396 -297.988808) (xy 69.777858 -298.009906)
			(xy 69.818361 -298.037862) (xy 69.853854 -298.071954) (xy 69.883419 -298.111298) (xy 69.90629 -298.154875)
			(xy 69.921874 -298.201556) (xy 69.929769 -298.250133) (xy 69.930264 -298.27474) (xy 71.219072 -298.27474)
			(xy 71.223032 -298.225686) (xy 71.234809 -298.177902) (xy 71.2541 -298.132626) (xy 71.280403 -298.09103)
			(xy 71.313038 -298.054193) (xy 71.351159 -298.023068) (xy 71.39378 -297.998461) (xy 71.439796 -297.981009)
			(xy 71.488015 -297.971165) (xy 71.53719 -297.969184) (xy 71.586045 -297.975116) (xy 71.633316 -297.988808)
			(xy 71.677778 -298.009906) (xy 71.718281 -298.037862) (xy 71.753774 -298.071954) (xy 71.783339 -298.111298)
			(xy 71.80621 -298.154875) (xy 71.821794 -298.201556) (xy 71.829689 -298.250133) (xy 71.830184 -298.27474)
			(xy 72.169032 -298.27474) (xy 72.172992 -298.225686) (xy 72.184769 -298.177902) (xy 72.20406 -298.132626)
			(xy 72.230363 -298.09103) (xy 72.262998 -298.054193) (xy 72.301119 -298.023068) (xy 72.34374 -297.998461)
			(xy 72.389756 -297.981009) (xy 72.437975 -297.971165) (xy 72.48715 -297.969184) (xy 72.536005 -297.975116)
			(xy 72.583276 -297.988808) (xy 72.627738 -298.009906) (xy 72.668241 -298.037862) (xy 72.703734 -298.071954)
			(xy 72.733299 -298.111298) (xy 72.75617 -298.154875) (xy 72.771754 -298.201556) (xy 72.779649 -298.250133)
			(xy 72.780144 -298.27474) (xy 73.118992 -298.27474) (xy 73.122952 -298.225686) (xy 73.134729 -298.177902)
			(xy 73.15402 -298.132626) (xy 73.180323 -298.09103) (xy 73.212958 -298.054193) (xy 73.251079 -298.023068)
			(xy 73.2937 -297.998461) (xy 73.339716 -297.981009) (xy 73.387935 -297.971165) (xy 73.43711 -297.969184)
			(xy 73.485965 -297.975116) (xy 73.533236 -297.988808) (xy 73.577698 -298.009906) (xy 73.618201 -298.037862)
			(xy 73.653694 -298.071954) (xy 73.683259 -298.111298) (xy 73.70613 -298.154875) (xy 73.721714 -298.201556)
			(xy 73.729609 -298.250133) (xy 73.730104 -298.27474) (xy 74.068952 -298.27474) (xy 74.072912 -298.225686)
			(xy 74.084689 -298.177902) (xy 74.10398 -298.132626) (xy 74.130283 -298.09103) (xy 74.162918 -298.054193)
			(xy 74.201039 -298.023068) (xy 74.24366 -297.998461) (xy 74.289676 -297.981009) (xy 74.337895 -297.971165)
			(xy 74.38707 -297.969184) (xy 74.435925 -297.975116) (xy 74.483196 -297.988808) (xy 74.527658 -298.009906)
			(xy 74.568161 -298.037862) (xy 74.603654 -298.071954) (xy 74.633219 -298.111298) (xy 74.65609 -298.154875)
			(xy 74.671674 -298.201556) (xy 74.679569 -298.250133) (xy 74.680064 -298.27474) (xy 75.019166 -298.27474)
			(xy 75.023126 -298.225686) (xy 75.034903 -298.177902) (xy 75.054194 -298.132626) (xy 75.080497 -298.09103)
			(xy 75.113132 -298.054193) (xy 75.151253 -298.023068) (xy 75.193874 -297.998461) (xy 75.23989 -297.981009)
			(xy 75.288109 -297.971165) (xy 75.337284 -297.969184) (xy 75.386139 -297.975116) (xy 75.43341 -297.988808)
			(xy 75.477872 -298.009906) (xy 75.518375 -298.037862) (xy 75.553868 -298.071954) (xy 75.583433 -298.111298)
			(xy 75.606304 -298.154875) (xy 75.621888 -298.201556) (xy 75.629783 -298.250133) (xy 75.630278 -298.27474)
			(xy 75.969126 -298.27474) (xy 75.973086 -298.225686) (xy 75.984863 -298.177902) (xy 76.004154 -298.132626)
			(xy 76.030457 -298.09103) (xy 76.063092 -298.054193) (xy 76.101213 -298.023068) (xy 76.143834 -297.998461)
			(xy 76.18985 -297.981009) (xy 76.238069 -297.971165) (xy 76.287244 -297.969184) (xy 76.336099 -297.975116)
			(xy 76.38337 -297.988808) (xy 76.427832 -298.009906) (xy 76.468335 -298.037862) (xy 76.503828 -298.071954)
			(xy 76.533393 -298.111298) (xy 76.556264 -298.154875) (xy 76.571848 -298.201556) (xy 76.579743 -298.250133)
			(xy 76.580238 -298.27474) (xy 76.919086 -298.27474) (xy 76.923046 -298.225686) (xy 76.934823 -298.177902)
			(xy 76.954114 -298.132626) (xy 76.980417 -298.09103) (xy 77.013052 -298.054193) (xy 77.051173 -298.023068)
			(xy 77.093794 -297.998461) (xy 77.13981 -297.981009) (xy 77.188029 -297.971165) (xy 77.237204 -297.969184)
			(xy 77.286059 -297.975116) (xy 77.33333 -297.988808) (xy 77.377792 -298.009906) (xy 77.418295 -298.037862)
			(xy 77.453788 -298.071954) (xy 77.483353 -298.111298) (xy 77.506224 -298.154875) (xy 77.521808 -298.201556)
			(xy 77.529703 -298.250133) (xy 77.530198 -298.27474) (xy 77.869046 -298.27474) (xy 77.873006 -298.225686)
			(xy 77.884783 -298.177902) (xy 77.904074 -298.132626) (xy 77.930377 -298.09103) (xy 77.963012 -298.054193)
			(xy 78.001133 -298.023068) (xy 78.043754 -297.998461) (xy 78.08977 -297.981009) (xy 78.137989 -297.971165)
			(xy 78.187164 -297.969184) (xy 78.236019 -297.975116) (xy 78.28329 -297.988808) (xy 78.327752 -298.009906)
			(xy 78.368255 -298.037862) (xy 78.403748 -298.071954) (xy 78.433313 -298.111298) (xy 78.456184 -298.154875)
			(xy 78.471768 -298.201556) (xy 78.479663 -298.250133) (xy 78.480158 -298.27474) (xy 78.479663 -298.299347)
			(xy 78.471768 -298.347924) (xy 78.456184 -298.394605) (xy 78.433313 -298.438182) (xy 78.403748 -298.477526)
			(xy 78.368255 -298.511618) (xy 78.327752 -298.539574) (xy 78.28329 -298.560672) (xy 78.236019 -298.574364)
			(xy 78.187164 -298.580296) (xy 78.137989 -298.578315) (xy 78.08977 -298.568471) (xy 78.043754 -298.551019)
			(xy 78.001133 -298.526412) (xy 77.963012 -298.495287) (xy 77.930377 -298.45845) (xy 77.904074 -298.416854)
			(xy 77.884783 -298.371578) (xy 77.873006 -298.323794) (xy 77.869046 -298.27474) (xy 77.530198 -298.27474)
			(xy 77.529703 -298.299347) (xy 77.521808 -298.347924) (xy 77.506224 -298.394605) (xy 77.483353 -298.438182)
			(xy 77.453788 -298.477526) (xy 77.418295 -298.511618) (xy 77.377792 -298.539574) (xy 77.33333 -298.560672)
			(xy 77.286059 -298.574364) (xy 77.237204 -298.580296) (xy 77.188029 -298.578315) (xy 77.13981 -298.568471)
			(xy 77.093794 -298.551019) (xy 77.051173 -298.526412) (xy 77.013052 -298.495287) (xy 76.980417 -298.45845)
			(xy 76.954114 -298.416854) (xy 76.934823 -298.371578) (xy 76.923046 -298.323794) (xy 76.919086 -298.27474)
			(xy 76.580238 -298.27474) (xy 76.579743 -298.299347) (xy 76.571848 -298.347924) (xy 76.556264 -298.394605)
			(xy 76.533393 -298.438182) (xy 76.503828 -298.477526) (xy 76.468335 -298.511618) (xy 76.427832 -298.539574)
			(xy 76.38337 -298.560672) (xy 76.336099 -298.574364) (xy 76.287244 -298.580296) (xy 76.238069 -298.578315)
			(xy 76.18985 -298.568471) (xy 76.143834 -298.551019) (xy 76.101213 -298.526412) (xy 76.063092 -298.495287)
			(xy 76.030457 -298.45845) (xy 76.004154 -298.416854) (xy 75.984863 -298.371578) (xy 75.973086 -298.323794)
			(xy 75.969126 -298.27474) (xy 75.630278 -298.27474) (xy 75.629783 -298.299347) (xy 75.621888 -298.347924)
			(xy 75.606304 -298.394605) (xy 75.583433 -298.438182) (xy 75.553868 -298.477526) (xy 75.518375 -298.511618)
			(xy 75.477872 -298.539574) (xy 75.43341 -298.560672) (xy 75.386139 -298.574364) (xy 75.337284 -298.580296)
			(xy 75.288109 -298.578315) (xy 75.23989 -298.568471) (xy 75.193874 -298.551019) (xy 75.151253 -298.526412)
			(xy 75.113132 -298.495287) (xy 75.080497 -298.45845) (xy 75.054194 -298.416854) (xy 75.034903 -298.371578)
			(xy 75.023126 -298.323794) (xy 75.019166 -298.27474) (xy 74.680064 -298.27474) (xy 74.679569 -298.299347)
			(xy 74.671674 -298.347924) (xy 74.65609 -298.394605) (xy 74.633219 -298.438182) (xy 74.603654 -298.477526)
			(xy 74.568161 -298.511618) (xy 74.527658 -298.539574) (xy 74.483196 -298.560672) (xy 74.435925 -298.574364)
			(xy 74.38707 -298.580296) (xy 74.337895 -298.578315) (xy 74.289676 -298.568471) (xy 74.24366 -298.551019)
			(xy 74.201039 -298.526412) (xy 74.162918 -298.495287) (xy 74.130283 -298.45845) (xy 74.10398 -298.416854)
			(xy 74.084689 -298.371578) (xy 74.072912 -298.323794) (xy 74.068952 -298.27474) (xy 73.730104 -298.27474)
			(xy 73.729609 -298.299347) (xy 73.721714 -298.347924) (xy 73.70613 -298.394605) (xy 73.683259 -298.438182)
			(xy 73.653694 -298.477526) (xy 73.618201 -298.511618) (xy 73.577698 -298.539574) (xy 73.533236 -298.560672)
			(xy 73.485965 -298.574364) (xy 73.43711 -298.580296) (xy 73.387935 -298.578315) (xy 73.339716 -298.568471)
			(xy 73.2937 -298.551019) (xy 73.251079 -298.526412) (xy 73.212958 -298.495287) (xy 73.180323 -298.45845)
			(xy 73.15402 -298.416854) (xy 73.134729 -298.371578) (xy 73.122952 -298.323794) (xy 73.118992 -298.27474)
			(xy 72.780144 -298.27474) (xy 72.779649 -298.299347) (xy 72.771754 -298.347924) (xy 72.75617 -298.394605)
			(xy 72.733299 -298.438182) (xy 72.703734 -298.477526) (xy 72.668241 -298.511618) (xy 72.627738 -298.539574)
			(xy 72.583276 -298.560672) (xy 72.536005 -298.574364) (xy 72.48715 -298.580296) (xy 72.437975 -298.578315)
			(xy 72.389756 -298.568471) (xy 72.34374 -298.551019) (xy 72.301119 -298.526412) (xy 72.262998 -298.495287)
			(xy 72.230363 -298.45845) (xy 72.20406 -298.416854) (xy 72.184769 -298.371578) (xy 72.172992 -298.323794)
			(xy 72.169032 -298.27474) (xy 71.830184 -298.27474) (xy 71.829689 -298.299347) (xy 71.821794 -298.347924)
			(xy 71.80621 -298.394605) (xy 71.783339 -298.438182) (xy 71.753774 -298.477526) (xy 71.718281 -298.511618)
			(xy 71.677778 -298.539574) (xy 71.633316 -298.560672) (xy 71.586045 -298.574364) (xy 71.53719 -298.580296)
			(xy 71.488015 -298.578315) (xy 71.439796 -298.568471) (xy 71.39378 -298.551019) (xy 71.351159 -298.526412)
			(xy 71.313038 -298.495287) (xy 71.280403 -298.45845) (xy 71.2541 -298.416854) (xy 71.234809 -298.371578)
			(xy 71.223032 -298.323794) (xy 71.219072 -298.27474) (xy 69.930264 -298.27474) (xy 69.929769 -298.299347)
			(xy 69.921874 -298.347924) (xy 69.90629 -298.394605) (xy 69.883419 -298.438182) (xy 69.853854 -298.477526)
			(xy 69.818361 -298.511618) (xy 69.777858 -298.539574) (xy 69.733396 -298.560672) (xy 69.686125 -298.574364)
			(xy 69.63727 -298.580296) (xy 69.588095 -298.578315) (xy 69.539876 -298.568471) (xy 69.49386 -298.551019)
			(xy 69.451239 -298.526412) (xy 69.413118 -298.495287) (xy 69.380483 -298.45845) (xy 69.35418 -298.416854)
			(xy 69.334889 -298.371578) (xy 69.323112 -298.323794) (xy 69.319152 -298.27474) (xy 68.98005 -298.27474)
			(xy 68.979555 -298.299347) (xy 68.97166 -298.347924) (xy 68.956076 -298.394605) (xy 68.933205 -298.438182)
			(xy 68.90364 -298.477526) (xy 68.868147 -298.511618) (xy 68.827644 -298.539574) (xy 68.783182 -298.560672)
			(xy 68.735911 -298.574364) (xy 68.687056 -298.580296) (xy 68.637881 -298.578315) (xy 68.589662 -298.568471)
			(xy 68.543646 -298.551019) (xy 68.501025 -298.526412) (xy 68.462904 -298.495287) (xy 68.430269 -298.45845)
			(xy 68.403966 -298.416854) (xy 68.384675 -298.371578) (xy 68.372898 -298.323794) (xy 68.368938 -298.27474)
			(xy 68.03009 -298.27474) (xy 68.029595 -298.299347) (xy 68.0217 -298.347924) (xy 68.006116 -298.394605)
			(xy 67.983245 -298.438182) (xy 67.95368 -298.477526) (xy 67.918187 -298.511618) (xy 67.877684 -298.539574)
			(xy 67.833222 -298.560672) (xy 67.785951 -298.574364) (xy 67.737096 -298.580296) (xy 67.687921 -298.578315)
			(xy 67.639702 -298.568471) (xy 67.593686 -298.551019) (xy 67.551065 -298.526412) (xy 67.512944 -298.495287)
			(xy 67.480309 -298.45845) (xy 67.454006 -298.416854) (xy 67.434715 -298.371578) (xy 67.422938 -298.323794)
			(xy 67.418978 -298.27474) (xy 67.08013 -298.27474) (xy 67.079635 -298.299347) (xy 67.07174 -298.347924)
			(xy 67.056156 -298.394605) (xy 67.033285 -298.438182) (xy 67.00372 -298.477526) (xy 66.968227 -298.511618)
			(xy 66.927724 -298.539574) (xy 66.883262 -298.560672) (xy 66.835991 -298.574364) (xy 66.787136 -298.580296)
			(xy 66.737961 -298.578315) (xy 66.689742 -298.568471) (xy 66.643726 -298.551019) (xy 66.601105 -298.526412)
			(xy 66.562984 -298.495287) (xy 66.530349 -298.45845) (xy 66.504046 -298.416854) (xy 66.484755 -298.371578)
			(xy 66.472978 -298.323794) (xy 66.469018 -298.27474) (xy 66.13017 -298.27474) (xy 66.129675 -298.299347)
			(xy 66.12178 -298.347924) (xy 66.106196 -298.394605) (xy 66.083325 -298.438182) (xy 66.05376 -298.477526)
			(xy 66.018267 -298.511618) (xy 65.977764 -298.539574) (xy 65.933302 -298.560672) (xy 65.886031 -298.574364)
			(xy 65.837176 -298.580296) (xy 65.788001 -298.578315) (xy 65.739782 -298.568471) (xy 65.693766 -298.551019)
			(xy 65.651145 -298.526412) (xy 65.613024 -298.495287) (xy 65.580389 -298.45845) (xy 65.554086 -298.416854)
			(xy 65.534795 -298.371578) (xy 65.523018 -298.323794) (xy 65.519058 -298.27474) (xy 65.18021 -298.27474)
			(xy 65.179715 -298.299347) (xy 65.17182 -298.347924) (xy 65.156236 -298.394605) (xy 65.133365 -298.438182)
			(xy 65.1038 -298.477526) (xy 65.068307 -298.511618) (xy 65.027804 -298.539574) (xy 64.983342 -298.560672)
			(xy 64.936071 -298.574364) (xy 64.887216 -298.580296) (xy 64.838041 -298.578315) (xy 64.789822 -298.568471)
			(xy 64.743806 -298.551019) (xy 64.701185 -298.526412) (xy 64.663064 -298.495287) (xy 64.630429 -298.45845)
			(xy 64.604126 -298.416854) (xy 64.584835 -298.371578) (xy 64.573058 -298.323794) (xy 64.569098 -298.27474)
			(xy 64.23025 -298.27474) (xy 64.229755 -298.299347) (xy 64.22186 -298.347924) (xy 64.206276 -298.394605)
			(xy 64.183405 -298.438182) (xy 64.15384 -298.477526) (xy 64.118347 -298.511618) (xy 64.077844 -298.539574)
			(xy 64.033382 -298.560672) (xy 63.986111 -298.574364) (xy 63.937256 -298.580296) (xy 63.888081 -298.578315)
			(xy 63.839862 -298.568471) (xy 63.793846 -298.551019) (xy 63.751225 -298.526412) (xy 63.713104 -298.495287)
			(xy 63.680469 -298.45845) (xy 63.654166 -298.416854) (xy 63.634875 -298.371578) (xy 63.623098 -298.323794)
			(xy 63.619138 -298.27474) (xy 63.28029 -298.27474) (xy 63.279795 -298.299347) (xy 63.2719 -298.347924)
			(xy 63.256316 -298.394605) (xy 63.233445 -298.438182) (xy 63.20388 -298.477526) (xy 63.168387 -298.511618)
			(xy 63.127884 -298.539574) (xy 63.083422 -298.560672) (xy 63.036151 -298.574364) (xy 62.987296 -298.580296)
			(xy 62.938121 -298.578315) (xy 62.889902 -298.568471) (xy 62.843886 -298.551019) (xy 62.801265 -298.526412)
			(xy 62.763144 -298.495287) (xy 62.730509 -298.45845) (xy 62.704206 -298.416854) (xy 62.684915 -298.371578)
			(xy 62.673138 -298.323794) (xy 62.669178 -298.27474) (xy 62.330076 -298.27474) (xy 62.329581 -298.299347)
			(xy 62.321686 -298.347924) (xy 62.306102 -298.394605) (xy 62.283231 -298.438182) (xy 62.253666 -298.477526)
			(xy 62.218173 -298.511618) (xy 62.17767 -298.539574) (xy 62.133208 -298.560672) (xy 62.085937 -298.574364)
			(xy 62.037082 -298.580296) (xy 61.987907 -298.578315) (xy 61.939688 -298.568471) (xy 61.893672 -298.551019)
			(xy 61.851051 -298.526412) (xy 61.81293 -298.495287) (xy 61.780295 -298.45845) (xy 61.753992 -298.416854)
			(xy 61.734701 -298.371578) (xy 61.722924 -298.323794) (xy 61.718964 -298.27474) (xy 61.380116 -298.27474)
			(xy 61.379621 -298.299347) (xy 61.371726 -298.347924) (xy 61.356142 -298.394605) (xy 61.333271 -298.438182)
			(xy 61.303706 -298.477526) (xy 61.268213 -298.511618) (xy 61.22771 -298.539574) (xy 61.183248 -298.560672)
			(xy 61.135977 -298.574364) (xy 61.087122 -298.580296) (xy 61.037947 -298.578315) (xy 60.989728 -298.568471)
			(xy 60.943712 -298.551019) (xy 60.901091 -298.526412) (xy 60.86297 -298.495287) (xy 60.830335 -298.45845)
			(xy 60.804032 -298.416854) (xy 60.784741 -298.371578) (xy 60.772964 -298.323794) (xy 60.769004 -298.27474)
			(xy 60.430156 -298.27474) (xy 60.429661 -298.299347) (xy 60.421766 -298.347924) (xy 60.406182 -298.394605)
			(xy 60.383311 -298.438182) (xy 60.353746 -298.477526) (xy 60.318253 -298.511618) (xy 60.27775 -298.539574)
			(xy 60.233288 -298.560672) (xy 60.186017 -298.574364) (xy 60.137162 -298.580296) (xy 60.087987 -298.578315)
			(xy 60.039768 -298.568471) (xy 59.993752 -298.551019) (xy 59.951131 -298.526412) (xy 59.91301 -298.495287)
			(xy 59.880375 -298.45845) (xy 59.854072 -298.416854) (xy 59.834781 -298.371578) (xy 59.823004 -298.323794)
			(xy 59.819044 -298.27474) (xy 58.530236 -298.27474) (xy 58.529741 -298.299347) (xy 58.521846 -298.347924)
			(xy 58.506262 -298.394605) (xy 58.483391 -298.438182) (xy 58.453826 -298.477526) (xy 58.418333 -298.511618)
			(xy 58.37783 -298.539574) (xy 58.333368 -298.560672) (xy 58.286097 -298.574364) (xy 58.237242 -298.580296)
			(xy 58.188067 -298.578315) (xy 58.139848 -298.568471) (xy 58.093832 -298.551019) (xy 58.051211 -298.526412)
			(xy 58.01309 -298.495287) (xy 57.980455 -298.45845) (xy 57.954152 -298.416854) (xy 57.934861 -298.371578)
			(xy 57.923084 -298.323794) (xy 57.919124 -298.27474) (xy 57.580276 -298.27474) (xy 57.579781 -298.299347)
			(xy 57.571886 -298.347924) (xy 57.556302 -298.394605) (xy 57.533431 -298.438182) (xy 57.503866 -298.477526)
			(xy 57.468373 -298.511618) (xy 57.42787 -298.539574) (xy 57.383408 -298.560672) (xy 57.336137 -298.574364)
			(xy 57.287282 -298.580296) (xy 57.238107 -298.578315) (xy 57.189888 -298.568471) (xy 57.143872 -298.551019)
			(xy 57.101251 -298.526412) (xy 57.06313 -298.495287) (xy 57.030495 -298.45845) (xy 57.004192 -298.416854)
			(xy 56.984901 -298.371578) (xy 56.973124 -298.323794) (xy 56.969164 -298.27474) (xy 56.630062 -298.27474)
			(xy 56.629567 -298.299347) (xy 56.621672 -298.347924) (xy 56.606088 -298.394605) (xy 56.583217 -298.438182)
			(xy 56.553652 -298.477526) (xy 56.518159 -298.511618) (xy 56.477656 -298.539574) (xy 56.433194 -298.560672)
			(xy 56.385923 -298.574364) (xy 56.337068 -298.580296) (xy 56.287893 -298.578315) (xy 56.239674 -298.568471)
			(xy 56.193658 -298.551019) (xy 56.151037 -298.526412) (xy 56.112916 -298.495287) (xy 56.080281 -298.45845)
			(xy 56.053978 -298.416854) (xy 56.034687 -298.371578) (xy 56.02291 -298.323794) (xy 56.01895 -298.27474)
			(xy 55.680102 -298.27474) (xy 55.679607 -298.299347) (xy 55.671712 -298.347924) (xy 55.656128 -298.394605)
			(xy 55.633257 -298.438182) (xy 55.603692 -298.477526) (xy 55.568199 -298.511618) (xy 55.527696 -298.539574)
			(xy 55.483234 -298.560672) (xy 55.435963 -298.574364) (xy 55.387108 -298.580296) (xy 55.337933 -298.578315)
			(xy 55.289714 -298.568471) (xy 55.243698 -298.551019) (xy 55.201077 -298.526412) (xy 55.162956 -298.495287)
			(xy 55.130321 -298.45845) (xy 55.104018 -298.416854) (xy 55.084727 -298.371578) (xy 55.07295 -298.323794)
			(xy 55.06899 -298.27474) (xy 54.730142 -298.27474) (xy 54.729647 -298.299347) (xy 54.721752 -298.347924)
			(xy 54.706168 -298.394605) (xy 54.683297 -298.438182) (xy 54.653732 -298.477526) (xy 54.618239 -298.511618)
			(xy 54.577736 -298.539574) (xy 54.533274 -298.560672) (xy 54.486003 -298.574364) (xy 54.437148 -298.580296)
			(xy 54.387973 -298.578315) (xy 54.339754 -298.568471) (xy 54.293738 -298.551019) (xy 54.251117 -298.526412)
			(xy 54.212996 -298.495287) (xy 54.180361 -298.45845) (xy 54.154058 -298.416854) (xy 54.134767 -298.371578)
			(xy 54.12299 -298.323794) (xy 54.11903 -298.27474) (xy 53.780182 -298.27474) (xy 53.779687 -298.299347)
			(xy 53.771792 -298.347924) (xy 53.756208 -298.394605) (xy 53.733337 -298.438182) (xy 53.703772 -298.477526)
			(xy 53.668279 -298.511618) (xy 53.627776 -298.539574) (xy 53.583314 -298.560672) (xy 53.536043 -298.574364)
			(xy 53.487188 -298.580296) (xy 53.438013 -298.578315) (xy 53.389794 -298.568471) (xy 53.343778 -298.551019)
			(xy 53.301157 -298.526412) (xy 53.263036 -298.495287) (xy 53.230401 -298.45845) (xy 53.204098 -298.416854)
			(xy 53.184807 -298.371578) (xy 53.17303 -298.323794) (xy 53.16907 -298.27474) (xy 52.830222 -298.27474)
			(xy 52.829727 -298.299347) (xy 52.821832 -298.347924) (xy 52.806248 -298.394605) (xy 52.783377 -298.438182)
			(xy 52.753812 -298.477526) (xy 52.718319 -298.511618) (xy 52.677816 -298.539574) (xy 52.633354 -298.560672)
			(xy 52.586083 -298.574364) (xy 52.537228 -298.580296) (xy 52.488053 -298.578315) (xy 52.439834 -298.568471)
			(xy 52.393818 -298.551019) (xy 52.351197 -298.526412) (xy 52.313076 -298.495287) (xy 52.280441 -298.45845)
			(xy 52.254138 -298.416854) (xy 52.234847 -298.371578) (xy 52.22307 -298.323794) (xy 52.21911 -298.27474)
			(xy 51.880262 -298.27474) (xy 51.879767 -298.299347) (xy 51.871872 -298.347924) (xy 51.856288 -298.394605)
			(xy 51.833417 -298.438182) (xy 51.803852 -298.477526) (xy 51.768359 -298.511618) (xy 51.727856 -298.539574)
			(xy 51.683394 -298.560672) (xy 51.636123 -298.574364) (xy 51.587268 -298.580296) (xy 51.538093 -298.578315)
			(xy 51.489874 -298.568471) (xy 51.443858 -298.551019) (xy 51.401237 -298.526412) (xy 51.363116 -298.495287)
			(xy 51.330481 -298.45845) (xy 51.304178 -298.416854) (xy 51.284887 -298.371578) (xy 51.27311 -298.323794)
			(xy 51.26915 -298.27474) (xy 50.930302 -298.27474) (xy 50.929807 -298.299347) (xy 50.921912 -298.347924)
			(xy 50.906328 -298.394605) (xy 50.883457 -298.438182) (xy 50.853892 -298.477526) (xy 50.818399 -298.511618)
			(xy 50.777896 -298.539574) (xy 50.733434 -298.560672) (xy 50.686163 -298.574364) (xy 50.637308 -298.580296)
			(xy 50.588133 -298.578315) (xy 50.539914 -298.568471) (xy 50.493898 -298.551019) (xy 50.451277 -298.526412)
			(xy 50.413156 -298.495287) (xy 50.380521 -298.45845) (xy 50.354218 -298.416854) (xy 50.334927 -298.371578)
			(xy 50.32315 -298.323794) (xy 50.31919 -298.27474) (xy 49.980088 -298.27474) (xy 49.979593 -298.299347)
			(xy 49.971698 -298.347924) (xy 49.956114 -298.394605) (xy 49.933243 -298.438182) (xy 49.903678 -298.477526)
			(xy 49.868185 -298.511618) (xy 49.827682 -298.539574) (xy 49.78322 -298.560672) (xy 49.735949 -298.574364)
			(xy 49.687094 -298.580296) (xy 49.637919 -298.578315) (xy 49.5897 -298.568471) (xy 49.543684 -298.551019)
			(xy 49.501063 -298.526412) (xy 49.462942 -298.495287) (xy 49.430307 -298.45845) (xy 49.404004 -298.416854)
			(xy 49.384713 -298.371578) (xy 49.372936 -298.323794) (xy 49.368976 -298.27474) (xy 49.030128 -298.27474)
			(xy 49.029633 -298.299347) (xy 49.021738 -298.347924) (xy 49.006154 -298.394605) (xy 48.983283 -298.438182)
			(xy 48.953718 -298.477526) (xy 48.918225 -298.511618) (xy 48.877722 -298.539574) (xy 48.83326 -298.560672)
			(xy 48.785989 -298.574364) (xy 48.737134 -298.580296) (xy 48.687959 -298.578315) (xy 48.63974 -298.568471)
			(xy 48.593724 -298.551019) (xy 48.551103 -298.526412) (xy 48.512982 -298.495287) (xy 48.480347 -298.45845)
			(xy 48.454044 -298.416854) (xy 48.434753 -298.371578) (xy 48.422976 -298.323794) (xy 48.419016 -298.27474)
			(xy 48.080168 -298.27474) (xy 48.079673 -298.299347) (xy 48.071778 -298.347924) (xy 48.056194 -298.394605)
			(xy 48.033323 -298.438182) (xy 48.003758 -298.477526) (xy 47.968265 -298.511618) (xy 47.927762 -298.539574)
			(xy 47.8833 -298.560672) (xy 47.836029 -298.574364) (xy 47.787174 -298.580296) (xy 47.737999 -298.578315)
			(xy 47.68978 -298.568471) (xy 47.643764 -298.551019) (xy 47.601143 -298.526412) (xy 47.563022 -298.495287)
			(xy 47.530387 -298.45845) (xy 47.504084 -298.416854) (xy 47.484793 -298.371578) (xy 47.473016 -298.323794)
			(xy 47.469056 -298.27474) (xy 46.180248 -298.27474) (xy 46.179753 -298.299347) (xy 46.171858 -298.347924)
			(xy 46.156274 -298.394605) (xy 46.133403 -298.438182) (xy 46.103838 -298.477526) (xy 46.068345 -298.511618)
			(xy 46.027842 -298.539574) (xy 45.98338 -298.560672) (xy 45.936109 -298.574364) (xy 45.887254 -298.580296)
			(xy 45.838079 -298.578315) (xy 45.78986 -298.568471) (xy 45.743844 -298.551019) (xy 45.701223 -298.526412)
			(xy 45.663102 -298.495287) (xy 45.630467 -298.45845) (xy 45.604164 -298.416854) (xy 45.584873 -298.371578)
			(xy 45.573096 -298.323794) (xy 45.569136 -298.27474) (xy 45.230288 -298.27474) (xy 45.229793 -298.299347)
			(xy 45.221898 -298.347924) (xy 45.206314 -298.394605) (xy 45.183443 -298.438182) (xy 45.153878 -298.477526)
			(xy 45.118385 -298.511618) (xy 45.077882 -298.539574) (xy 45.03342 -298.560672) (xy 44.986149 -298.574364)
			(xy 44.937294 -298.580296) (xy 44.888119 -298.578315) (xy 44.8399 -298.568471) (xy 44.793884 -298.551019)
			(xy 44.751263 -298.526412) (xy 44.713142 -298.495287) (xy 44.680507 -298.45845) (xy 44.654204 -298.416854)
			(xy 44.634913 -298.371578) (xy 44.623136 -298.323794) (xy 44.619176 -298.27474) (xy 44.280074 -298.27474)
			(xy 44.279579 -298.299347) (xy 44.271684 -298.347924) (xy 44.2561 -298.394605) (xy 44.233229 -298.438182)
			(xy 44.203664 -298.477526) (xy 44.168171 -298.511618) (xy 44.127668 -298.539574) (xy 44.083206 -298.560672)
			(xy 44.035935 -298.574364) (xy 43.98708 -298.580296) (xy 43.937905 -298.578315) (xy 43.889686 -298.568471)
			(xy 43.84367 -298.551019) (xy 43.801049 -298.526412) (xy 43.762928 -298.495287) (xy 43.730293 -298.45845)
			(xy 43.70399 -298.416854) (xy 43.684699 -298.371578) (xy 43.672922 -298.323794) (xy 43.668962 -298.27474)
			(xy 42.380154 -298.27474) (xy 42.379659 -298.299347) (xy 42.371764 -298.347924) (xy 42.35618 -298.394605)
			(xy 42.333309 -298.438182) (xy 42.303744 -298.477526) (xy 42.268251 -298.511618) (xy 42.227748 -298.539574)
			(xy 42.183286 -298.560672) (xy 42.136015 -298.574364) (xy 42.08716 -298.580296) (xy 42.037985 -298.578315)
			(xy 41.989766 -298.568471) (xy 41.94375 -298.551019) (xy 41.901129 -298.526412) (xy 41.863008 -298.495287)
			(xy 41.830373 -298.45845) (xy 41.80407 -298.416854) (xy 41.784779 -298.371578) (xy 41.773002 -298.323794)
			(xy 41.769042 -298.27474) (xy 41.430212 -298.27474) (xy 41.430659 -298.282979) (xy 41.425291 -298.332338)
			(xy 41.412009 -298.380179) (xy 41.391161 -298.42524) (xy 41.363298 -298.466334) (xy 41.329153 -298.502379)
			(xy 41.289626 -298.532425) (xy 41.245759 -298.555681) (xy 41.198707 -298.571533) (xy 41.149711 -298.579563)
			(xy 41.124886 -298.580048) (xy 41.115782 -298.579955) (xy 41.097608 -298.578811) (xy 41.088564 -298.577762)
			(xy 41.076372 -298.576492) (xy 41.054274 -298.584366) (xy 40.981122 -298.66082) (xy 40.974264 -298.683426)
			(xy 40.976296 -298.695364) (xy 40.978415 -298.708854) (xy 40.980705 -298.736066) (xy 40.980868 -298.74972)
			(xy 40.980723 -298.763438) (xy 40.978434 -298.790779) (xy 40.976296 -298.80433) (xy 40.974264 -298.816268)
			(xy 40.981122 -298.838874) (xy 41.054274 -298.915328) (xy 41.076372 -298.923202) (xy 41.088564 -298.921932)
			(xy 41.097608 -298.920885) (xy 41.115782 -298.919743) (xy 41.124886 -298.919646) (xy 41.149709 -298.920163)
			(xy 41.198701 -298.928193) (xy 41.245749 -298.944043) (xy 41.289613 -298.967297) (xy 41.329136 -298.997341)
			(xy 41.363278 -299.033383) (xy 41.391139 -299.074474) (xy 41.411985 -299.119532) (xy 41.425266 -299.167368)
			(xy 41.430633 -299.216724) (xy 41.4302 -299.2247) (xy 41.769042 -299.2247) (xy 41.773002 -299.175646)
			(xy 41.784779 -299.127862) (xy 41.80407 -299.082586) (xy 41.830373 -299.04099) (xy 41.863008 -299.004153)
			(xy 41.901129 -298.973028) (xy 41.94375 -298.948421) (xy 41.989766 -298.930969) (xy 42.037985 -298.921125)
			(xy 42.08716 -298.919144) (xy 42.136015 -298.925076) (xy 42.183286 -298.938768) (xy 42.227748 -298.959866)
			(xy 42.268251 -298.987822) (xy 42.303744 -299.021914) (xy 42.333309 -299.061258) (xy 42.35618 -299.104835)
			(xy 42.371764 -299.151516) (xy 42.379659 -299.200093) (xy 42.380154 -299.2247) (xy 42.380149 -299.224954)
			(xy 43.668962 -299.224954) (xy 43.672922 -299.1759) (xy 43.684699 -299.128116) (xy 43.70399 -299.08284)
			(xy 43.730293 -299.041244) (xy 43.762928 -299.004407) (xy 43.801049 -298.973282) (xy 43.84367 -298.948675)
			(xy 43.889686 -298.931223) (xy 43.937905 -298.921379) (xy 43.98708 -298.919398) (xy 44.035935 -298.92533)
			(xy 44.083206 -298.939022) (xy 44.127668 -298.96012) (xy 44.168171 -298.988076) (xy 44.203664 -299.022168)
			(xy 44.233229 -299.061512) (xy 44.2561 -299.105089) (xy 44.271684 -299.15177) (xy 44.279579 -299.200347)
			(xy 44.280074 -299.224954) (xy 44.619176 -299.224954) (xy 44.623136 -299.1759) (xy 44.634913 -299.128116)
			(xy 44.654204 -299.08284) (xy 44.680507 -299.041244) (xy 44.713142 -299.004407) (xy 44.751263 -298.973282)
			(xy 44.793884 -298.948675) (xy 44.8399 -298.931223) (xy 44.888119 -298.921379) (xy 44.937294 -298.919398)
			(xy 44.986149 -298.92533) (xy 45.03342 -298.939022) (xy 45.077882 -298.96012) (xy 45.118385 -298.988076)
			(xy 45.153878 -299.022168) (xy 45.183443 -299.061512) (xy 45.206314 -299.105089) (xy 45.221898 -299.15177)
			(xy 45.229793 -299.200347) (xy 45.230288 -299.224954) (xy 45.569136 -299.224954) (xy 45.573096 -299.1759)
			(xy 45.584873 -299.128116) (xy 45.604164 -299.08284) (xy 45.630467 -299.041244) (xy 45.663102 -299.004407)
			(xy 45.701223 -298.973282) (xy 45.743844 -298.948675) (xy 45.78986 -298.931223) (xy 45.838079 -298.921379)
			(xy 45.887254 -298.919398) (xy 45.936109 -298.92533) (xy 45.98338 -298.939022) (xy 46.027842 -298.96012)
			(xy 46.068345 -298.988076) (xy 46.103838 -299.022168) (xy 46.133403 -299.061512) (xy 46.156274 -299.105089)
			(xy 46.171858 -299.15177) (xy 46.179753 -299.200347) (xy 46.180248 -299.224954) (xy 46.519096 -299.224954)
			(xy 46.523056 -299.1759) (xy 46.534833 -299.128116) (xy 46.554124 -299.08284) (xy 46.580427 -299.041244)
			(xy 46.613062 -299.004407) (xy 46.651183 -298.973282) (xy 46.693804 -298.948675) (xy 46.73982 -298.931223)
			(xy 46.788039 -298.921379) (xy 46.837214 -298.919398) (xy 46.886069 -298.92533) (xy 46.93334 -298.939022)
			(xy 46.977802 -298.96012) (xy 47.018305 -298.988076) (xy 47.053798 -299.022168) (xy 47.083363 -299.061512)
			(xy 47.106234 -299.105089) (xy 47.121818 -299.15177) (xy 47.129713 -299.200347) (xy 47.130208 -299.224954)
			(xy 47.469056 -299.224954) (xy 47.473016 -299.1759) (xy 47.484793 -299.128116) (xy 47.504084 -299.08284)
			(xy 47.530387 -299.041244) (xy 47.563022 -299.004407) (xy 47.601143 -298.973282) (xy 47.643764 -298.948675)
			(xy 47.68978 -298.931223) (xy 47.737999 -298.921379) (xy 47.787174 -298.919398) (xy 47.836029 -298.92533)
			(xy 47.8833 -298.939022) (xy 47.927762 -298.96012) (xy 47.968265 -298.988076) (xy 48.003758 -299.022168)
			(xy 48.033323 -299.061512) (xy 48.056194 -299.105089) (xy 48.071778 -299.15177) (xy 48.079673 -299.200347)
			(xy 48.080168 -299.224954) (xy 48.419016 -299.224954) (xy 48.422976 -299.1759) (xy 48.434753 -299.128116)
			(xy 48.454044 -299.08284) (xy 48.480347 -299.041244) (xy 48.512982 -299.004407) (xy 48.551103 -298.973282)
			(xy 48.593724 -298.948675) (xy 48.63974 -298.931223) (xy 48.687959 -298.921379) (xy 48.737134 -298.919398)
			(xy 48.785989 -298.92533) (xy 48.83326 -298.939022) (xy 48.877722 -298.96012) (xy 48.918225 -298.988076)
			(xy 48.953718 -299.022168) (xy 48.983283 -299.061512) (xy 49.006154 -299.105089) (xy 49.021738 -299.15177)
			(xy 49.029633 -299.200347) (xy 49.030128 -299.224954) (xy 49.368976 -299.224954) (xy 49.372936 -299.1759)
			(xy 49.384713 -299.128116) (xy 49.404004 -299.08284) (xy 49.430307 -299.041244) (xy 49.462942 -299.004407)
			(xy 49.501063 -298.973282) (xy 49.543684 -298.948675) (xy 49.5897 -298.931223) (xy 49.637919 -298.921379)
			(xy 49.687094 -298.919398) (xy 49.735949 -298.92533) (xy 49.78322 -298.939022) (xy 49.827682 -298.96012)
			(xy 49.868185 -298.988076) (xy 49.903678 -299.022168) (xy 49.933243 -299.061512) (xy 49.956114 -299.105089)
			(xy 49.971698 -299.15177) (xy 49.979593 -299.200347) (xy 49.980088 -299.224954) (xy 50.31919 -299.224954)
			(xy 50.32315 -299.1759) (xy 50.334927 -299.128116) (xy 50.354218 -299.08284) (xy 50.380521 -299.041244)
			(xy 50.413156 -299.004407) (xy 50.451277 -298.973282) (xy 50.493898 -298.948675) (xy 50.539914 -298.931223)
			(xy 50.588133 -298.921379) (xy 50.637308 -298.919398) (xy 50.686163 -298.92533) (xy 50.733434 -298.939022)
			(xy 50.777896 -298.96012) (xy 50.818399 -298.988076) (xy 50.853892 -299.022168) (xy 50.883457 -299.061512)
			(xy 50.906328 -299.105089) (xy 50.921912 -299.15177) (xy 50.929807 -299.200347) (xy 50.930302 -299.224954)
			(xy 51.26915 -299.224954) (xy 51.27311 -299.1759) (xy 51.284887 -299.128116) (xy 51.304178 -299.08284)
			(xy 51.330481 -299.041244) (xy 51.363116 -299.004407) (xy 51.401237 -298.973282) (xy 51.443858 -298.948675)
			(xy 51.489874 -298.931223) (xy 51.538093 -298.921379) (xy 51.587268 -298.919398) (xy 51.636123 -298.92533)
			(xy 51.683394 -298.939022) (xy 51.727856 -298.96012) (xy 51.768359 -298.988076) (xy 51.803852 -299.022168)
			(xy 51.833417 -299.061512) (xy 51.856288 -299.105089) (xy 51.871872 -299.15177) (xy 51.879767 -299.200347)
			(xy 51.880262 -299.224954) (xy 52.21911 -299.224954) (xy 52.22307 -299.1759) (xy 52.234847 -299.128116)
			(xy 52.254138 -299.08284) (xy 52.280441 -299.041244) (xy 52.313076 -299.004407) (xy 52.351197 -298.973282)
			(xy 52.393818 -298.948675) (xy 52.439834 -298.931223) (xy 52.488053 -298.921379) (xy 52.537228 -298.919398)
			(xy 52.586083 -298.92533) (xy 52.633354 -298.939022) (xy 52.677816 -298.96012) (xy 52.718319 -298.988076)
			(xy 52.753812 -299.022168) (xy 52.783377 -299.061512) (xy 52.806248 -299.105089) (xy 52.821832 -299.15177)
			(xy 52.829727 -299.200347) (xy 52.830222 -299.224954) (xy 53.16907 -299.224954) (xy 53.17303 -299.1759)
			(xy 53.184807 -299.128116) (xy 53.204098 -299.08284) (xy 53.230401 -299.041244) (xy 53.263036 -299.004407)
			(xy 53.301157 -298.973282) (xy 53.343778 -298.948675) (xy 53.389794 -298.931223) (xy 53.438013 -298.921379)
			(xy 53.487188 -298.919398) (xy 53.536043 -298.92533) (xy 53.583314 -298.939022) (xy 53.627776 -298.96012)
			(xy 53.668279 -298.988076) (xy 53.703772 -299.022168) (xy 53.733337 -299.061512) (xy 53.756208 -299.105089)
			(xy 53.771792 -299.15177) (xy 53.779687 -299.200347) (xy 53.780182 -299.224954) (xy 54.11903 -299.224954)
			(xy 54.12299 -299.1759) (xy 54.134767 -299.128116) (xy 54.154058 -299.08284) (xy 54.180361 -299.041244)
			(xy 54.212996 -299.004407) (xy 54.251117 -298.973282) (xy 54.293738 -298.948675) (xy 54.339754 -298.931223)
			(xy 54.387973 -298.921379) (xy 54.437148 -298.919398) (xy 54.486003 -298.92533) (xy 54.533274 -298.939022)
			(xy 54.577736 -298.96012) (xy 54.618239 -298.988076) (xy 54.653732 -299.022168) (xy 54.683297 -299.061512)
			(xy 54.706168 -299.105089) (xy 54.721752 -299.15177) (xy 54.729647 -299.200347) (xy 54.730142 -299.224954)
			(xy 55.06899 -299.224954) (xy 55.07295 -299.1759) (xy 55.084727 -299.128116) (xy 55.104018 -299.08284)
			(xy 55.130321 -299.041244) (xy 55.162956 -299.004407) (xy 55.201077 -298.973282) (xy 55.243698 -298.948675)
			(xy 55.289714 -298.931223) (xy 55.337933 -298.921379) (xy 55.387108 -298.919398) (xy 55.435963 -298.92533)
			(xy 55.483234 -298.939022) (xy 55.527696 -298.96012) (xy 55.568199 -298.988076) (xy 55.603692 -299.022168)
			(xy 55.633257 -299.061512) (xy 55.656128 -299.105089) (xy 55.671712 -299.15177) (xy 55.679607 -299.200347)
			(xy 55.680102 -299.224954) (xy 56.01895 -299.224954) (xy 56.02291 -299.1759) (xy 56.034687 -299.128116)
			(xy 56.053978 -299.08284) (xy 56.080281 -299.041244) (xy 56.112916 -299.004407) (xy 56.151037 -298.973282)
			(xy 56.193658 -298.948675) (xy 56.239674 -298.931223) (xy 56.287893 -298.921379) (xy 56.337068 -298.919398)
			(xy 56.385923 -298.92533) (xy 56.433194 -298.939022) (xy 56.477656 -298.96012) (xy 56.518159 -298.988076)
			(xy 56.553652 -299.022168) (xy 56.583217 -299.061512) (xy 56.606088 -299.105089) (xy 56.621672 -299.15177)
			(xy 56.629567 -299.200347) (xy 56.630062 -299.224954) (xy 56.969164 -299.224954) (xy 56.973124 -299.1759)
			(xy 56.984901 -299.128116) (xy 57.004192 -299.08284) (xy 57.030495 -299.041244) (xy 57.06313 -299.004407)
			(xy 57.101251 -298.973282) (xy 57.143872 -298.948675) (xy 57.189888 -298.931223) (xy 57.238107 -298.921379)
			(xy 57.287282 -298.919398) (xy 57.336137 -298.92533) (xy 57.383408 -298.939022) (xy 57.42787 -298.96012)
			(xy 57.468373 -298.988076) (xy 57.503866 -299.022168) (xy 57.533431 -299.061512) (xy 57.556302 -299.105089)
			(xy 57.571886 -299.15177) (xy 57.579781 -299.200347) (xy 57.580276 -299.224954) (xy 57.919124 -299.224954)
			(xy 57.923084 -299.1759) (xy 57.934861 -299.128116) (xy 57.954152 -299.08284) (xy 57.980455 -299.041244)
			(xy 58.01309 -299.004407) (xy 58.051211 -298.973282) (xy 58.093832 -298.948675) (xy 58.139848 -298.931223)
			(xy 58.188067 -298.921379) (xy 58.237242 -298.919398) (xy 58.286097 -298.92533) (xy 58.333368 -298.939022)
			(xy 58.37783 -298.96012) (xy 58.418333 -298.988076) (xy 58.453826 -299.022168) (xy 58.483391 -299.061512)
			(xy 58.506262 -299.105089) (xy 58.521846 -299.15177) (xy 58.529741 -299.200347) (xy 58.530236 -299.224954)
			(xy 59.819044 -299.224954) (xy 59.823004 -299.1759) (xy 59.834781 -299.128116) (xy 59.854072 -299.08284)
			(xy 59.880375 -299.041244) (xy 59.91301 -299.004407) (xy 59.951131 -298.973282) (xy 59.993752 -298.948675)
			(xy 60.039768 -298.931223) (xy 60.087987 -298.921379) (xy 60.137162 -298.919398) (xy 60.186017 -298.92533)
			(xy 60.233288 -298.939022) (xy 60.27775 -298.96012) (xy 60.318253 -298.988076) (xy 60.353746 -299.022168)
			(xy 60.383311 -299.061512) (xy 60.406182 -299.105089) (xy 60.421766 -299.15177) (xy 60.429661 -299.200347)
			(xy 60.430156 -299.224954) (xy 60.769004 -299.224954) (xy 60.772964 -299.1759) (xy 60.784741 -299.128116)
			(xy 60.804032 -299.08284) (xy 60.830335 -299.041244) (xy 60.86297 -299.004407) (xy 60.901091 -298.973282)
			(xy 60.943712 -298.948675) (xy 60.989728 -298.931223) (xy 61.037947 -298.921379) (xy 61.087122 -298.919398)
			(xy 61.135977 -298.92533) (xy 61.183248 -298.939022) (xy 61.22771 -298.96012) (xy 61.268213 -298.988076)
			(xy 61.303706 -299.022168) (xy 61.333271 -299.061512) (xy 61.356142 -299.105089) (xy 61.371726 -299.15177)
			(xy 61.379621 -299.200347) (xy 61.380116 -299.224954) (xy 61.718964 -299.224954) (xy 61.722924 -299.1759)
			(xy 61.734701 -299.128116) (xy 61.753992 -299.08284) (xy 61.780295 -299.041244) (xy 61.81293 -299.004407)
			(xy 61.851051 -298.973282) (xy 61.893672 -298.948675) (xy 61.939688 -298.931223) (xy 61.987907 -298.921379)
			(xy 62.037082 -298.919398) (xy 62.085937 -298.92533) (xy 62.133208 -298.939022) (xy 62.17767 -298.96012)
			(xy 62.218173 -298.988076) (xy 62.253666 -299.022168) (xy 62.283231 -299.061512) (xy 62.306102 -299.105089)
			(xy 62.321686 -299.15177) (xy 62.329581 -299.200347) (xy 62.330076 -299.224954) (xy 62.669178 -299.224954)
			(xy 62.673138 -299.1759) (xy 62.684915 -299.128116) (xy 62.704206 -299.08284) (xy 62.730509 -299.041244)
			(xy 62.763144 -299.004407) (xy 62.801265 -298.973282) (xy 62.843886 -298.948675) (xy 62.889902 -298.931223)
			(xy 62.938121 -298.921379) (xy 62.987296 -298.919398) (xy 63.036151 -298.92533) (xy 63.083422 -298.939022)
			(xy 63.127884 -298.96012) (xy 63.168387 -298.988076) (xy 63.20388 -299.022168) (xy 63.233445 -299.061512)
			(xy 63.256316 -299.105089) (xy 63.2719 -299.15177) (xy 63.279795 -299.200347) (xy 63.28029 -299.224954)
			(xy 63.619138 -299.224954) (xy 63.623098 -299.1759) (xy 63.634875 -299.128116) (xy 63.654166 -299.08284)
			(xy 63.680469 -299.041244) (xy 63.713104 -299.004407) (xy 63.751225 -298.973282) (xy 63.793846 -298.948675)
			(xy 63.839862 -298.931223) (xy 63.888081 -298.921379) (xy 63.937256 -298.919398) (xy 63.986111 -298.92533)
			(xy 64.033382 -298.939022) (xy 64.077844 -298.96012) (xy 64.118347 -298.988076) (xy 64.15384 -299.022168)
			(xy 64.183405 -299.061512) (xy 64.206276 -299.105089) (xy 64.22186 -299.15177) (xy 64.229755 -299.200347)
			(xy 64.23025 -299.224954) (xy 64.569098 -299.224954) (xy 64.573058 -299.1759) (xy 64.584835 -299.128116)
			(xy 64.604126 -299.08284) (xy 64.630429 -299.041244) (xy 64.663064 -299.004407) (xy 64.701185 -298.973282)
			(xy 64.743806 -298.948675) (xy 64.789822 -298.931223) (xy 64.838041 -298.921379) (xy 64.887216 -298.919398)
			(xy 64.936071 -298.92533) (xy 64.983342 -298.939022) (xy 65.027804 -298.96012) (xy 65.068307 -298.988076)
			(xy 65.1038 -299.022168) (xy 65.133365 -299.061512) (xy 65.156236 -299.105089) (xy 65.17182 -299.15177)
			(xy 65.179715 -299.200347) (xy 65.18021 -299.224954) (xy 65.519058 -299.224954) (xy 65.523018 -299.1759)
			(xy 65.534795 -299.128116) (xy 65.554086 -299.08284) (xy 65.580389 -299.041244) (xy 65.613024 -299.004407)
			(xy 65.651145 -298.973282) (xy 65.693766 -298.948675) (xy 65.739782 -298.931223) (xy 65.788001 -298.921379)
			(xy 65.837176 -298.919398) (xy 65.886031 -298.92533) (xy 65.933302 -298.939022) (xy 65.977764 -298.96012)
			(xy 66.018267 -298.988076) (xy 66.05376 -299.022168) (xy 66.083325 -299.061512) (xy 66.106196 -299.105089)
			(xy 66.12178 -299.15177) (xy 66.129675 -299.200347) (xy 66.13017 -299.224954) (xy 66.469018 -299.224954)
			(xy 66.472978 -299.1759) (xy 66.484755 -299.128116) (xy 66.504046 -299.08284) (xy 66.530349 -299.041244)
			(xy 66.562984 -299.004407) (xy 66.601105 -298.973282) (xy 66.643726 -298.948675) (xy 66.689742 -298.931223)
			(xy 66.737961 -298.921379) (xy 66.787136 -298.919398) (xy 66.835991 -298.92533) (xy 66.883262 -298.939022)
			(xy 66.927724 -298.96012) (xy 66.968227 -298.988076) (xy 67.00372 -299.022168) (xy 67.033285 -299.061512)
			(xy 67.056156 -299.105089) (xy 67.07174 -299.15177) (xy 67.079635 -299.200347) (xy 67.08013 -299.224954)
			(xy 67.418978 -299.224954) (xy 67.422938 -299.1759) (xy 67.434715 -299.128116) (xy 67.454006 -299.08284)
			(xy 67.480309 -299.041244) (xy 67.512944 -299.004407) (xy 67.551065 -298.973282) (xy 67.593686 -298.948675)
			(xy 67.639702 -298.931223) (xy 67.687921 -298.921379) (xy 67.737096 -298.919398) (xy 67.785951 -298.92533)
			(xy 67.833222 -298.939022) (xy 67.877684 -298.96012) (xy 67.918187 -298.988076) (xy 67.95368 -299.022168)
			(xy 67.983245 -299.061512) (xy 68.006116 -299.105089) (xy 68.0217 -299.15177) (xy 68.029595 -299.200347)
			(xy 68.03009 -299.224954) (xy 68.368938 -299.224954) (xy 68.372898 -299.1759) (xy 68.384675 -299.128116)
			(xy 68.403966 -299.08284) (xy 68.430269 -299.041244) (xy 68.462904 -299.004407) (xy 68.501025 -298.973282)
			(xy 68.543646 -298.948675) (xy 68.589662 -298.931223) (xy 68.637881 -298.921379) (xy 68.687056 -298.919398)
			(xy 68.735911 -298.92533) (xy 68.783182 -298.939022) (xy 68.827644 -298.96012) (xy 68.868147 -298.988076)
			(xy 68.90364 -299.022168) (xy 68.933205 -299.061512) (xy 68.956076 -299.105089) (xy 68.97166 -299.15177)
			(xy 68.979555 -299.200347) (xy 68.98005 -299.224954) (xy 69.319152 -299.224954) (xy 69.323112 -299.1759)
			(xy 69.334889 -299.128116) (xy 69.35418 -299.08284) (xy 69.380483 -299.041244) (xy 69.413118 -299.004407)
			(xy 69.451239 -298.973282) (xy 69.49386 -298.948675) (xy 69.539876 -298.931223) (xy 69.588095 -298.921379)
			(xy 69.63727 -298.919398) (xy 69.686125 -298.92533) (xy 69.733396 -298.939022) (xy 69.777858 -298.96012)
			(xy 69.818361 -298.988076) (xy 69.853854 -299.022168) (xy 69.883419 -299.061512) (xy 69.90629 -299.105089)
			(xy 69.921874 -299.15177) (xy 69.929769 -299.200347) (xy 69.930264 -299.224954) (xy 70.269112 -299.224954)
			(xy 70.273072 -299.1759) (xy 70.284849 -299.128116) (xy 70.30414 -299.08284) (xy 70.330443 -299.041244)
			(xy 70.363078 -299.004407) (xy 70.401199 -298.973282) (xy 70.44382 -298.948675) (xy 70.489836 -298.931223)
			(xy 70.538055 -298.921379) (xy 70.58723 -298.919398) (xy 70.636085 -298.92533) (xy 70.683356 -298.939022)
			(xy 70.727818 -298.96012) (xy 70.768321 -298.988076) (xy 70.803814 -299.022168) (xy 70.833379 -299.061512)
			(xy 70.85625 -299.105089) (xy 70.871834 -299.15177) (xy 70.879729 -299.200347) (xy 70.880224 -299.224954)
			(xy 71.219072 -299.224954) (xy 71.223032 -299.1759) (xy 71.234809 -299.128116) (xy 71.2541 -299.08284)
			(xy 71.280403 -299.041244) (xy 71.313038 -299.004407) (xy 71.351159 -298.973282) (xy 71.39378 -298.948675)
			(xy 71.439796 -298.931223) (xy 71.488015 -298.921379) (xy 71.53719 -298.919398) (xy 71.586045 -298.92533)
			(xy 71.633316 -298.939022) (xy 71.677778 -298.96012) (xy 71.718281 -298.988076) (xy 71.753774 -299.022168)
			(xy 71.783339 -299.061512) (xy 71.80621 -299.105089) (xy 71.821794 -299.15177) (xy 71.829689 -299.200347)
			(xy 71.830184 -299.224954) (xy 72.169032 -299.224954) (xy 72.172992 -299.1759) (xy 72.184769 -299.128116)
			(xy 72.20406 -299.08284) (xy 72.230363 -299.041244) (xy 72.262998 -299.004407) (xy 72.301119 -298.973282)
			(xy 72.34374 -298.948675) (xy 72.389756 -298.931223) (xy 72.437975 -298.921379) (xy 72.48715 -298.919398)
			(xy 72.536005 -298.92533) (xy 72.583276 -298.939022) (xy 72.627738 -298.96012) (xy 72.668241 -298.988076)
			(xy 72.703734 -299.022168) (xy 72.733299 -299.061512) (xy 72.75617 -299.105089) (xy 72.771754 -299.15177)
			(xy 72.779649 -299.200347) (xy 72.780144 -299.224954) (xy 73.118992 -299.224954) (xy 73.122952 -299.1759)
			(xy 73.134729 -299.128116) (xy 73.15402 -299.08284) (xy 73.180323 -299.041244) (xy 73.212958 -299.004407)
			(xy 73.251079 -298.973282) (xy 73.2937 -298.948675) (xy 73.339716 -298.931223) (xy 73.387935 -298.921379)
			(xy 73.43711 -298.919398) (xy 73.485965 -298.92533) (xy 73.533236 -298.939022) (xy 73.577698 -298.96012)
			(xy 73.618201 -298.988076) (xy 73.653694 -299.022168) (xy 73.683259 -299.061512) (xy 73.70613 -299.105089)
			(xy 73.721714 -299.15177) (xy 73.729609 -299.200347) (xy 73.730104 -299.224954) (xy 75.969126 -299.224954)
			(xy 75.973086 -299.1759) (xy 75.984863 -299.128116) (xy 76.004154 -299.08284) (xy 76.030457 -299.041244)
			(xy 76.063092 -299.004407) (xy 76.101213 -298.973282) (xy 76.143834 -298.948675) (xy 76.18985 -298.931223)
			(xy 76.238069 -298.921379) (xy 76.287244 -298.919398) (xy 76.336099 -298.92533) (xy 76.38337 -298.939022)
			(xy 76.427832 -298.96012) (xy 76.468335 -298.988076) (xy 76.503828 -299.022168) (xy 76.533393 -299.061512)
			(xy 76.556264 -299.105089) (xy 76.571848 -299.15177) (xy 76.579743 -299.200347) (xy 76.580238 -299.224954)
			(xy 76.919086 -299.224954) (xy 76.923046 -299.1759) (xy 76.934823 -299.128116) (xy 76.954114 -299.08284)
			(xy 76.980417 -299.041244) (xy 77.013052 -299.004407) (xy 77.051173 -298.973282) (xy 77.093794 -298.948675)
			(xy 77.13981 -298.931223) (xy 77.188029 -298.921379) (xy 77.237204 -298.919398) (xy 77.286059 -298.92533)
			(xy 77.33333 -298.939022) (xy 77.377792 -298.96012) (xy 77.418295 -298.988076) (xy 77.453788 -299.022168)
			(xy 77.483353 -299.061512) (xy 77.506224 -299.105089) (xy 77.521808 -299.15177) (xy 77.529703 -299.200347)
			(xy 77.530198 -299.224954) (xy 77.869046 -299.224954) (xy 77.873006 -299.1759) (xy 77.884783 -299.128116)
			(xy 77.904074 -299.08284) (xy 77.930377 -299.041244) (xy 77.963012 -299.004407) (xy 78.001133 -298.973282)
			(xy 78.043754 -298.948675) (xy 78.08977 -298.931223) (xy 78.137989 -298.921379) (xy 78.187164 -298.919398)
			(xy 78.236019 -298.92533) (xy 78.28329 -298.939022) (xy 78.327752 -298.96012) (xy 78.368255 -298.988076)
			(xy 78.403748 -299.022168) (xy 78.433313 -299.061512) (xy 78.456184 -299.105089) (xy 78.471768 -299.15177)
			(xy 78.479663 -299.200347) (xy 78.480158 -299.224954) (xy 78.479663 -299.249561) (xy 78.471768 -299.298138)
			(xy 78.456184 -299.344819) (xy 78.433313 -299.388396) (xy 78.403748 -299.42774) (xy 78.368255 -299.461832)
			(xy 78.327752 -299.489788) (xy 78.28329 -299.510886) (xy 78.236019 -299.524578) (xy 78.187164 -299.53051)
			(xy 78.137989 -299.528529) (xy 78.08977 -299.518685) (xy 78.043754 -299.501233) (xy 78.001133 -299.476626)
			(xy 77.963012 -299.445501) (xy 77.930377 -299.408664) (xy 77.904074 -299.367068) (xy 77.884783 -299.321792)
			(xy 77.873006 -299.274008) (xy 77.869046 -299.224954) (xy 77.530198 -299.224954) (xy 77.529703 -299.249561)
			(xy 77.521808 -299.298138) (xy 77.506224 -299.344819) (xy 77.483353 -299.388396) (xy 77.453788 -299.42774)
			(xy 77.418295 -299.461832) (xy 77.377792 -299.489788) (xy 77.33333 -299.510886) (xy 77.286059 -299.524578)
			(xy 77.237204 -299.53051) (xy 77.188029 -299.528529) (xy 77.13981 -299.518685) (xy 77.093794 -299.501233)
			(xy 77.051173 -299.476626) (xy 77.013052 -299.445501) (xy 76.980417 -299.408664) (xy 76.954114 -299.367068)
			(xy 76.934823 -299.321792) (xy 76.923046 -299.274008) (xy 76.919086 -299.224954) (xy 76.580238 -299.224954)
			(xy 76.579743 -299.249561) (xy 76.571848 -299.298138) (xy 76.556264 -299.344819) (xy 76.533393 -299.388396)
			(xy 76.503828 -299.42774) (xy 76.468335 -299.461832) (xy 76.427832 -299.489788) (xy 76.38337 -299.510886)
			(xy 76.336099 -299.524578) (xy 76.287244 -299.53051) (xy 76.238069 -299.528529) (xy 76.18985 -299.518685)
			(xy 76.143834 -299.501233) (xy 76.101213 -299.476626) (xy 76.063092 -299.445501) (xy 76.030457 -299.408664)
			(xy 76.004154 -299.367068) (xy 75.984863 -299.321792) (xy 75.973086 -299.274008) (xy 75.969126 -299.224954)
			(xy 73.730104 -299.224954) (xy 73.729609 -299.249561) (xy 73.721714 -299.298138) (xy 73.70613 -299.344819)
			(xy 73.683259 -299.388396) (xy 73.653694 -299.42774) (xy 73.618201 -299.461832) (xy 73.577698 -299.489788)
			(xy 73.533236 -299.510886) (xy 73.485965 -299.524578) (xy 73.43711 -299.53051) (xy 73.387935 -299.528529)
			(xy 73.339716 -299.518685) (xy 73.2937 -299.501233) (xy 73.251079 -299.476626) (xy 73.212958 -299.445501)
			(xy 73.180323 -299.408664) (xy 73.15402 -299.367068) (xy 73.134729 -299.321792) (xy 73.122952 -299.274008)
			(xy 73.118992 -299.224954) (xy 72.780144 -299.224954) (xy 72.779649 -299.249561) (xy 72.771754 -299.298138)
			(xy 72.75617 -299.344819) (xy 72.733299 -299.388396) (xy 72.703734 -299.42774) (xy 72.668241 -299.461832)
			(xy 72.627738 -299.489788) (xy 72.583276 -299.510886) (xy 72.536005 -299.524578) (xy 72.48715 -299.53051)
			(xy 72.437975 -299.528529) (xy 72.389756 -299.518685) (xy 72.34374 -299.501233) (xy 72.301119 -299.476626)
			(xy 72.262998 -299.445501) (xy 72.230363 -299.408664) (xy 72.20406 -299.367068) (xy 72.184769 -299.321792)
			(xy 72.172992 -299.274008) (xy 72.169032 -299.224954) (xy 71.830184 -299.224954) (xy 71.829689 -299.249561)
			(xy 71.821794 -299.298138) (xy 71.80621 -299.344819) (xy 71.783339 -299.388396) (xy 71.753774 -299.42774)
			(xy 71.718281 -299.461832) (xy 71.677778 -299.489788) (xy 71.633316 -299.510886) (xy 71.586045 -299.524578)
			(xy 71.53719 -299.53051) (xy 71.488015 -299.528529) (xy 71.439796 -299.518685) (xy 71.39378 -299.501233)
			(xy 71.351159 -299.476626) (xy 71.313038 -299.445501) (xy 71.280403 -299.408664) (xy 71.2541 -299.367068)
			(xy 71.234809 -299.321792) (xy 71.223032 -299.274008) (xy 71.219072 -299.224954) (xy 70.880224 -299.224954)
			(xy 70.879729 -299.249561) (xy 70.871834 -299.298138) (xy 70.85625 -299.344819) (xy 70.833379 -299.388396)
			(xy 70.803814 -299.42774) (xy 70.768321 -299.461832) (xy 70.727818 -299.489788) (xy 70.683356 -299.510886)
			(xy 70.636085 -299.524578) (xy 70.58723 -299.53051) (xy 70.538055 -299.528529) (xy 70.489836 -299.518685)
			(xy 70.44382 -299.501233) (xy 70.401199 -299.476626) (xy 70.363078 -299.445501) (xy 70.330443 -299.408664)
			(xy 70.30414 -299.367068) (xy 70.284849 -299.321792) (xy 70.273072 -299.274008) (xy 70.269112 -299.224954)
			(xy 69.930264 -299.224954) (xy 69.929769 -299.249561) (xy 69.921874 -299.298138) (xy 69.90629 -299.344819)
			(xy 69.883419 -299.388396) (xy 69.853854 -299.42774) (xy 69.818361 -299.461832) (xy 69.777858 -299.489788)
			(xy 69.733396 -299.510886) (xy 69.686125 -299.524578) (xy 69.63727 -299.53051) (xy 69.588095 -299.528529)
			(xy 69.539876 -299.518685) (xy 69.49386 -299.501233) (xy 69.451239 -299.476626) (xy 69.413118 -299.445501)
			(xy 69.380483 -299.408664) (xy 69.35418 -299.367068) (xy 69.334889 -299.321792) (xy 69.323112 -299.274008)
			(xy 69.319152 -299.224954) (xy 68.98005 -299.224954) (xy 68.979555 -299.249561) (xy 68.97166 -299.298138)
			(xy 68.956076 -299.344819) (xy 68.933205 -299.388396) (xy 68.90364 -299.42774) (xy 68.868147 -299.461832)
			(xy 68.827644 -299.489788) (xy 68.783182 -299.510886) (xy 68.735911 -299.524578) (xy 68.687056 -299.53051)
			(xy 68.637881 -299.528529) (xy 68.589662 -299.518685) (xy 68.543646 -299.501233) (xy 68.501025 -299.476626)
			(xy 68.462904 -299.445501) (xy 68.430269 -299.408664) (xy 68.403966 -299.367068) (xy 68.384675 -299.321792)
			(xy 68.372898 -299.274008) (xy 68.368938 -299.224954) (xy 68.03009 -299.224954) (xy 68.029595 -299.249561)
			(xy 68.0217 -299.298138) (xy 68.006116 -299.344819) (xy 67.983245 -299.388396) (xy 67.95368 -299.42774)
			(xy 67.918187 -299.461832) (xy 67.877684 -299.489788) (xy 67.833222 -299.510886) (xy 67.785951 -299.524578)
			(xy 67.737096 -299.53051) (xy 67.687921 -299.528529) (xy 67.639702 -299.518685) (xy 67.593686 -299.501233)
			(xy 67.551065 -299.476626) (xy 67.512944 -299.445501) (xy 67.480309 -299.408664) (xy 67.454006 -299.367068)
			(xy 67.434715 -299.321792) (xy 67.422938 -299.274008) (xy 67.418978 -299.224954) (xy 67.08013 -299.224954)
			(xy 67.079635 -299.249561) (xy 67.07174 -299.298138) (xy 67.056156 -299.344819) (xy 67.033285 -299.388396)
			(xy 67.00372 -299.42774) (xy 66.968227 -299.461832) (xy 66.927724 -299.489788) (xy 66.883262 -299.510886)
			(xy 66.835991 -299.524578) (xy 66.787136 -299.53051) (xy 66.737961 -299.528529) (xy 66.689742 -299.518685)
			(xy 66.643726 -299.501233) (xy 66.601105 -299.476626) (xy 66.562984 -299.445501) (xy 66.530349 -299.408664)
			(xy 66.504046 -299.367068) (xy 66.484755 -299.321792) (xy 66.472978 -299.274008) (xy 66.469018 -299.224954)
			(xy 66.13017 -299.224954) (xy 66.129675 -299.249561) (xy 66.12178 -299.298138) (xy 66.106196 -299.344819)
			(xy 66.083325 -299.388396) (xy 66.05376 -299.42774) (xy 66.018267 -299.461832) (xy 65.977764 -299.489788)
			(xy 65.933302 -299.510886) (xy 65.886031 -299.524578) (xy 65.837176 -299.53051) (xy 65.788001 -299.528529)
			(xy 65.739782 -299.518685) (xy 65.693766 -299.501233) (xy 65.651145 -299.476626) (xy 65.613024 -299.445501)
			(xy 65.580389 -299.408664) (xy 65.554086 -299.367068) (xy 65.534795 -299.321792) (xy 65.523018 -299.274008)
			(xy 65.519058 -299.224954) (xy 65.18021 -299.224954) (xy 65.179715 -299.249561) (xy 65.17182 -299.298138)
			(xy 65.156236 -299.344819) (xy 65.133365 -299.388396) (xy 65.1038 -299.42774) (xy 65.068307 -299.461832)
			(xy 65.027804 -299.489788) (xy 64.983342 -299.510886) (xy 64.936071 -299.524578) (xy 64.887216 -299.53051)
			(xy 64.838041 -299.528529) (xy 64.789822 -299.518685) (xy 64.743806 -299.501233) (xy 64.701185 -299.476626)
			(xy 64.663064 -299.445501) (xy 64.630429 -299.408664) (xy 64.604126 -299.367068) (xy 64.584835 -299.321792)
			(xy 64.573058 -299.274008) (xy 64.569098 -299.224954) (xy 64.23025 -299.224954) (xy 64.229755 -299.249561)
			(xy 64.22186 -299.298138) (xy 64.206276 -299.344819) (xy 64.183405 -299.388396) (xy 64.15384 -299.42774)
			(xy 64.118347 -299.461832) (xy 64.077844 -299.489788) (xy 64.033382 -299.510886) (xy 63.986111 -299.524578)
			(xy 63.937256 -299.53051) (xy 63.888081 -299.528529) (xy 63.839862 -299.518685) (xy 63.793846 -299.501233)
			(xy 63.751225 -299.476626) (xy 63.713104 -299.445501) (xy 63.680469 -299.408664) (xy 63.654166 -299.367068)
			(xy 63.634875 -299.321792) (xy 63.623098 -299.274008) (xy 63.619138 -299.224954) (xy 63.28029 -299.224954)
			(xy 63.279795 -299.249561) (xy 63.2719 -299.298138) (xy 63.256316 -299.344819) (xy 63.233445 -299.388396)
			(xy 63.20388 -299.42774) (xy 63.168387 -299.461832) (xy 63.127884 -299.489788) (xy 63.083422 -299.510886)
			(xy 63.036151 -299.524578) (xy 62.987296 -299.53051) (xy 62.938121 -299.528529) (xy 62.889902 -299.518685)
			(xy 62.843886 -299.501233) (xy 62.801265 -299.476626) (xy 62.763144 -299.445501) (xy 62.730509 -299.408664)
			(xy 62.704206 -299.367068) (xy 62.684915 -299.321792) (xy 62.673138 -299.274008) (xy 62.669178 -299.224954)
			(xy 62.330076 -299.224954) (xy 62.329581 -299.249561) (xy 62.321686 -299.298138) (xy 62.306102 -299.344819)
			(xy 62.283231 -299.388396) (xy 62.253666 -299.42774) (xy 62.218173 -299.461832) (xy 62.17767 -299.489788)
			(xy 62.133208 -299.510886) (xy 62.085937 -299.524578) (xy 62.037082 -299.53051) (xy 61.987907 -299.528529)
			(xy 61.939688 -299.518685) (xy 61.893672 -299.501233) (xy 61.851051 -299.476626) (xy 61.81293 -299.445501)
			(xy 61.780295 -299.408664) (xy 61.753992 -299.367068) (xy 61.734701 -299.321792) (xy 61.722924 -299.274008)
			(xy 61.718964 -299.224954) (xy 61.380116 -299.224954) (xy 61.379621 -299.249561) (xy 61.371726 -299.298138)
			(xy 61.356142 -299.344819) (xy 61.333271 -299.388396) (xy 61.303706 -299.42774) (xy 61.268213 -299.461832)
			(xy 61.22771 -299.489788) (xy 61.183248 -299.510886) (xy 61.135977 -299.524578) (xy 61.087122 -299.53051)
			(xy 61.037947 -299.528529) (xy 60.989728 -299.518685) (xy 60.943712 -299.501233) (xy 60.901091 -299.476626)
			(xy 60.86297 -299.445501) (xy 60.830335 -299.408664) (xy 60.804032 -299.367068) (xy 60.784741 -299.321792)
			(xy 60.772964 -299.274008) (xy 60.769004 -299.224954) (xy 60.430156 -299.224954) (xy 60.429661 -299.249561)
			(xy 60.421766 -299.298138) (xy 60.406182 -299.344819) (xy 60.383311 -299.388396) (xy 60.353746 -299.42774)
			(xy 60.318253 -299.461832) (xy 60.27775 -299.489788) (xy 60.233288 -299.510886) (xy 60.186017 -299.524578)
			(xy 60.137162 -299.53051) (xy 60.087987 -299.528529) (xy 60.039768 -299.518685) (xy 59.993752 -299.501233)
			(xy 59.951131 -299.476626) (xy 59.91301 -299.445501) (xy 59.880375 -299.408664) (xy 59.854072 -299.367068)
			(xy 59.834781 -299.321792) (xy 59.823004 -299.274008) (xy 59.819044 -299.224954) (xy 58.530236 -299.224954)
			(xy 58.529741 -299.249561) (xy 58.521846 -299.298138) (xy 58.506262 -299.344819) (xy 58.483391 -299.388396)
			(xy 58.453826 -299.42774) (xy 58.418333 -299.461832) (xy 58.37783 -299.489788) (xy 58.333368 -299.510886)
			(xy 58.286097 -299.524578) (xy 58.237242 -299.53051) (xy 58.188067 -299.528529) (xy 58.139848 -299.518685)
			(xy 58.093832 -299.501233) (xy 58.051211 -299.476626) (xy 58.01309 -299.445501) (xy 57.980455 -299.408664)
			(xy 57.954152 -299.367068) (xy 57.934861 -299.321792) (xy 57.923084 -299.274008) (xy 57.919124 -299.224954)
			(xy 57.580276 -299.224954) (xy 57.579781 -299.249561) (xy 57.571886 -299.298138) (xy 57.556302 -299.344819)
			(xy 57.533431 -299.388396) (xy 57.503866 -299.42774) (xy 57.468373 -299.461832) (xy 57.42787 -299.489788)
			(xy 57.383408 -299.510886) (xy 57.336137 -299.524578) (xy 57.287282 -299.53051) (xy 57.238107 -299.528529)
			(xy 57.189888 -299.518685) (xy 57.143872 -299.501233) (xy 57.101251 -299.476626) (xy 57.06313 -299.445501)
			(xy 57.030495 -299.408664) (xy 57.004192 -299.367068) (xy 56.984901 -299.321792) (xy 56.973124 -299.274008)
			(xy 56.969164 -299.224954) (xy 56.630062 -299.224954) (xy 56.629567 -299.249561) (xy 56.621672 -299.298138)
			(xy 56.606088 -299.344819) (xy 56.583217 -299.388396) (xy 56.553652 -299.42774) (xy 56.518159 -299.461832)
			(xy 56.477656 -299.489788) (xy 56.433194 -299.510886) (xy 56.385923 -299.524578) (xy 56.337068 -299.53051)
			(xy 56.287893 -299.528529) (xy 56.239674 -299.518685) (xy 56.193658 -299.501233) (xy 56.151037 -299.476626)
			(xy 56.112916 -299.445501) (xy 56.080281 -299.408664) (xy 56.053978 -299.367068) (xy 56.034687 -299.321792)
			(xy 56.02291 -299.274008) (xy 56.01895 -299.224954) (xy 55.680102 -299.224954) (xy 55.679607 -299.249561)
			(xy 55.671712 -299.298138) (xy 55.656128 -299.344819) (xy 55.633257 -299.388396) (xy 55.603692 -299.42774)
			(xy 55.568199 -299.461832) (xy 55.527696 -299.489788) (xy 55.483234 -299.510886) (xy 55.435963 -299.524578)
			(xy 55.387108 -299.53051) (xy 55.337933 -299.528529) (xy 55.289714 -299.518685) (xy 55.243698 -299.501233)
			(xy 55.201077 -299.476626) (xy 55.162956 -299.445501) (xy 55.130321 -299.408664) (xy 55.104018 -299.367068)
			(xy 55.084727 -299.321792) (xy 55.07295 -299.274008) (xy 55.06899 -299.224954) (xy 54.730142 -299.224954)
			(xy 54.729647 -299.249561) (xy 54.721752 -299.298138) (xy 54.706168 -299.344819) (xy 54.683297 -299.388396)
			(xy 54.653732 -299.42774) (xy 54.618239 -299.461832) (xy 54.577736 -299.489788) (xy 54.533274 -299.510886)
			(xy 54.486003 -299.524578) (xy 54.437148 -299.53051) (xy 54.387973 -299.528529) (xy 54.339754 -299.518685)
			(xy 54.293738 -299.501233) (xy 54.251117 -299.476626) (xy 54.212996 -299.445501) (xy 54.180361 -299.408664)
			(xy 54.154058 -299.367068) (xy 54.134767 -299.321792) (xy 54.12299 -299.274008) (xy 54.11903 -299.224954)
			(xy 53.780182 -299.224954) (xy 53.779687 -299.249561) (xy 53.771792 -299.298138) (xy 53.756208 -299.344819)
			(xy 53.733337 -299.388396) (xy 53.703772 -299.42774) (xy 53.668279 -299.461832) (xy 53.627776 -299.489788)
			(xy 53.583314 -299.510886) (xy 53.536043 -299.524578) (xy 53.487188 -299.53051) (xy 53.438013 -299.528529)
			(xy 53.389794 -299.518685) (xy 53.343778 -299.501233) (xy 53.301157 -299.476626) (xy 53.263036 -299.445501)
			(xy 53.230401 -299.408664) (xy 53.204098 -299.367068) (xy 53.184807 -299.321792) (xy 53.17303 -299.274008)
			(xy 53.16907 -299.224954) (xy 52.830222 -299.224954) (xy 52.829727 -299.249561) (xy 52.821832 -299.298138)
			(xy 52.806248 -299.344819) (xy 52.783377 -299.388396) (xy 52.753812 -299.42774) (xy 52.718319 -299.461832)
			(xy 52.677816 -299.489788) (xy 52.633354 -299.510886) (xy 52.586083 -299.524578) (xy 52.537228 -299.53051)
			(xy 52.488053 -299.528529) (xy 52.439834 -299.518685) (xy 52.393818 -299.501233) (xy 52.351197 -299.476626)
			(xy 52.313076 -299.445501) (xy 52.280441 -299.408664) (xy 52.254138 -299.367068) (xy 52.234847 -299.321792)
			(xy 52.22307 -299.274008) (xy 52.21911 -299.224954) (xy 51.880262 -299.224954) (xy 51.879767 -299.249561)
			(xy 51.871872 -299.298138) (xy 51.856288 -299.344819) (xy 51.833417 -299.388396) (xy 51.803852 -299.42774)
			(xy 51.768359 -299.461832) (xy 51.727856 -299.489788) (xy 51.683394 -299.510886) (xy 51.636123 -299.524578)
			(xy 51.587268 -299.53051) (xy 51.538093 -299.528529) (xy 51.489874 -299.518685) (xy 51.443858 -299.501233)
			(xy 51.401237 -299.476626) (xy 51.363116 -299.445501) (xy 51.330481 -299.408664) (xy 51.304178 -299.367068)
			(xy 51.284887 -299.321792) (xy 51.27311 -299.274008) (xy 51.26915 -299.224954) (xy 50.930302 -299.224954)
			(xy 50.929807 -299.249561) (xy 50.921912 -299.298138) (xy 50.906328 -299.344819) (xy 50.883457 -299.388396)
			(xy 50.853892 -299.42774) (xy 50.818399 -299.461832) (xy 50.777896 -299.489788) (xy 50.733434 -299.510886)
			(xy 50.686163 -299.524578) (xy 50.637308 -299.53051) (xy 50.588133 -299.528529) (xy 50.539914 -299.518685)
			(xy 50.493898 -299.501233) (xy 50.451277 -299.476626) (xy 50.413156 -299.445501) (xy 50.380521 -299.408664)
			(xy 50.354218 -299.367068) (xy 50.334927 -299.321792) (xy 50.32315 -299.274008) (xy 50.31919 -299.224954)
			(xy 49.980088 -299.224954) (xy 49.979593 -299.249561) (xy 49.971698 -299.298138) (xy 49.956114 -299.344819)
			(xy 49.933243 -299.388396) (xy 49.903678 -299.42774) (xy 49.868185 -299.461832) (xy 49.827682 -299.489788)
			(xy 49.78322 -299.510886) (xy 49.735949 -299.524578) (xy 49.687094 -299.53051) (xy 49.637919 -299.528529)
			(xy 49.5897 -299.518685) (xy 49.543684 -299.501233) (xy 49.501063 -299.476626) (xy 49.462942 -299.445501)
			(xy 49.430307 -299.408664) (xy 49.404004 -299.367068) (xy 49.384713 -299.321792) (xy 49.372936 -299.274008)
			(xy 49.368976 -299.224954) (xy 49.030128 -299.224954) (xy 49.029633 -299.249561) (xy 49.021738 -299.298138)
			(xy 49.006154 -299.344819) (xy 48.983283 -299.388396) (xy 48.953718 -299.42774) (xy 48.918225 -299.461832)
			(xy 48.877722 -299.489788) (xy 48.83326 -299.510886) (xy 48.785989 -299.524578) (xy 48.737134 -299.53051)
			(xy 48.687959 -299.528529) (xy 48.63974 -299.518685) (xy 48.593724 -299.501233) (xy 48.551103 -299.476626)
			(xy 48.512982 -299.445501) (xy 48.480347 -299.408664) (xy 48.454044 -299.367068) (xy 48.434753 -299.321792)
			(xy 48.422976 -299.274008) (xy 48.419016 -299.224954) (xy 48.080168 -299.224954) (xy 48.079673 -299.249561)
			(xy 48.071778 -299.298138) (xy 48.056194 -299.344819) (xy 48.033323 -299.388396) (xy 48.003758 -299.42774)
			(xy 47.968265 -299.461832) (xy 47.927762 -299.489788) (xy 47.8833 -299.510886) (xy 47.836029 -299.524578)
			(xy 47.787174 -299.53051) (xy 47.737999 -299.528529) (xy 47.68978 -299.518685) (xy 47.643764 -299.501233)
			(xy 47.601143 -299.476626) (xy 47.563022 -299.445501) (xy 47.530387 -299.408664) (xy 47.504084 -299.367068)
			(xy 47.484793 -299.321792) (xy 47.473016 -299.274008) (xy 47.469056 -299.224954) (xy 47.130208 -299.224954)
			(xy 47.129713 -299.249561) (xy 47.121818 -299.298138) (xy 47.106234 -299.344819) (xy 47.083363 -299.388396)
			(xy 47.053798 -299.42774) (xy 47.018305 -299.461832) (xy 46.977802 -299.489788) (xy 46.93334 -299.510886)
			(xy 46.886069 -299.524578) (xy 46.837214 -299.53051) (xy 46.788039 -299.528529) (xy 46.73982 -299.518685)
			(xy 46.693804 -299.501233) (xy 46.651183 -299.476626) (xy 46.613062 -299.445501) (xy 46.580427 -299.408664)
			(xy 46.554124 -299.367068) (xy 46.534833 -299.321792) (xy 46.523056 -299.274008) (xy 46.519096 -299.224954)
			(xy 46.180248 -299.224954) (xy 46.179753 -299.249561) (xy 46.171858 -299.298138) (xy 46.156274 -299.344819)
			(xy 46.133403 -299.388396) (xy 46.103838 -299.42774) (xy 46.068345 -299.461832) (xy 46.027842 -299.489788)
			(xy 45.98338 -299.510886) (xy 45.936109 -299.524578) (xy 45.887254 -299.53051) (xy 45.838079 -299.528529)
			(xy 45.78986 -299.518685) (xy 45.743844 -299.501233) (xy 45.701223 -299.476626) (xy 45.663102 -299.445501)
			(xy 45.630467 -299.408664) (xy 45.604164 -299.367068) (xy 45.584873 -299.321792) (xy 45.573096 -299.274008)
			(xy 45.569136 -299.224954) (xy 45.230288 -299.224954) (xy 45.229793 -299.249561) (xy 45.221898 -299.298138)
			(xy 45.206314 -299.344819) (xy 45.183443 -299.388396) (xy 45.153878 -299.42774) (xy 45.118385 -299.461832)
			(xy 45.077882 -299.489788) (xy 45.03342 -299.510886) (xy 44.986149 -299.524578) (xy 44.937294 -299.53051)
			(xy 44.888119 -299.528529) (xy 44.8399 -299.518685) (xy 44.793884 -299.501233) (xy 44.751263 -299.476626)
			(xy 44.713142 -299.445501) (xy 44.680507 -299.408664) (xy 44.654204 -299.367068) (xy 44.634913 -299.321792)
			(xy 44.623136 -299.274008) (xy 44.619176 -299.224954) (xy 44.280074 -299.224954) (xy 44.279579 -299.249561)
			(xy 44.271684 -299.298138) (xy 44.2561 -299.344819) (xy 44.233229 -299.388396) (xy 44.203664 -299.42774)
			(xy 44.168171 -299.461832) (xy 44.127668 -299.489788) (xy 44.083206 -299.510886) (xy 44.035935 -299.524578)
			(xy 43.98708 -299.53051) (xy 43.937905 -299.528529) (xy 43.889686 -299.518685) (xy 43.84367 -299.501233)
			(xy 43.801049 -299.476626) (xy 43.762928 -299.445501) (xy 43.730293 -299.408664) (xy 43.70399 -299.367068)
			(xy 43.684699 -299.321792) (xy 43.672922 -299.274008) (xy 43.668962 -299.224954) (xy 42.380149 -299.224954)
			(xy 42.379659 -299.249307) (xy 42.371764 -299.297884) (xy 42.35618 -299.344565) (xy 42.333309 -299.388142)
			(xy 42.303744 -299.427486) (xy 42.268251 -299.461578) (xy 42.227748 -299.489534) (xy 42.183286 -299.510632)
			(xy 42.136015 -299.524324) (xy 42.08716 -299.530256) (xy 42.037985 -299.528275) (xy 41.989766 -299.518431)
			(xy 41.94375 -299.500979) (xy 41.901129 -299.476372) (xy 41.863008 -299.445247) (xy 41.830373 -299.40841)
			(xy 41.80407 -299.366814) (xy 41.784779 -299.321538) (xy 41.773002 -299.273754) (xy 41.769042 -299.2247)
			(xy 41.4302 -299.2247) (xy 41.427944 -299.266297) (xy 41.41727 -299.314782) (xy 41.398893 -299.360901)
			(xy 41.373296 -299.40344) (xy 41.341154 -299.441276) (xy 41.303314 -299.473414) (xy 41.260772 -299.499007)
			(xy 41.214651 -299.51738) (xy 41.166165 -299.528048) (xy 41.116592 -299.530732) (xy 41.067237 -299.52536)
			(xy 41.019402 -299.512074) (xy 40.974346 -299.491223) (xy 40.933258 -299.463358) (xy 40.897219 -299.429212)
			(xy 40.86718 -299.389686) (xy 40.843931 -299.34582) (xy 40.828085 -299.29877) (xy 40.82006 -299.249777)
			(xy 40.819578 -299.224954) (xy 40.819664 -299.215786) (xy 40.820809 -299.197486) (xy 40.821864 -299.188378)
			(xy 40.823134 -299.176186) (xy 40.81526 -299.154088) (xy 40.738806 -299.080936) (xy 40.7162 -299.074078)
			(xy 40.704262 -299.07611) (xy 40.690769 -299.078172) (xy 40.663556 -299.08033) (xy 40.649906 -299.080428)
			(xy 39.699946 -299.080428) (xy 39.673951 -299.07991) (xy 39.6226 -299.071787) (xy 39.573151 -299.055733)
			(xy 39.526821 -299.032144) (xy 39.48475 -299.0016) (xy 39.447973 -298.964853) (xy 39.417395 -298.922806)
			(xy 39.393769 -298.876495) (xy 39.377675 -298.827059) (xy 39.369511 -298.775714) (xy 39.368984 -298.74972)
			(xy 39.369139 -298.736066) (xy 39.371427 -298.708852) (xy 39.373556 -298.695364) (xy 39.375588 -298.683426)
			(xy 39.36873 -298.66082) (xy 39.295578 -298.584366) (xy 39.27348 -298.576492) (xy 39.261288 -298.577762)
			(xy 39.252243 -298.578804) (xy 39.23407 -298.579949) (xy 39.224966 -298.580048) (xy 39.200148 -298.579485)
			(xy 39.151166 -298.57145) (xy 39.10413 -298.555595) (xy 39.060278 -298.53234) (xy 39.020766 -298.502297)
			(xy 38.986636 -298.466257) (xy 38.958785 -298.425171) (xy 38.937949 -298.38012) (xy 38.924675 -298.332291)
			(xy 38.919314 -298.282945) (xy 38.579895 -298.282945) (xy 38.579565 -298.299347) (xy 38.57167 -298.347924)
			(xy 38.556086 -298.394605) (xy 38.533215 -298.438182) (xy 38.50365 -298.477526) (xy 38.468157 -298.511618)
			(xy 38.427654 -298.539574) (xy 38.383192 -298.560672) (xy 38.335921 -298.574364) (xy 38.287066 -298.580296)
			(xy 38.237891 -298.578315) (xy 38.189672 -298.568471) (xy 38.143656 -298.551019) (xy 38.101035 -298.526412)
			(xy 38.062914 -298.495287) (xy 38.030279 -298.45845) (xy 38.003976 -298.416854) (xy 37.984685 -298.371578)
			(xy 37.972908 -298.323794) (xy 37.968948 -298.27474) (xy 37.629846 -298.27474) (xy 37.629351 -298.299347)
			(xy 37.621456 -298.347924) (xy 37.605872 -298.394605) (xy 37.583001 -298.438182) (xy 37.553436 -298.477526)
			(xy 37.517943 -298.511618) (xy 37.47744 -298.539574) (xy 37.432978 -298.560672) (xy 37.385707 -298.574364)
			(xy 37.336852 -298.580296) (xy 37.287677 -298.578315) (xy 37.239458 -298.568471) (xy 37.193442 -298.551019)
			(xy 37.150821 -298.526412) (xy 37.1127 -298.495287) (xy 37.080065 -298.45845) (xy 37.053762 -298.416854)
			(xy 37.034471 -298.371578) (xy 37.022694 -298.323794) (xy 37.018734 -298.27474) (xy 21.407869 -298.27474)
			(xy 21.499608 -298.312092) (xy 21.647708 -298.38091) (xy 21.79231 -298.456804) (xy 21.933077 -298.539595)
			(xy 22.06968 -298.62909) (xy 22.201799 -298.72508) (xy 22.329126 -298.827342) (xy 22.451364 -298.935635)
			(xy 22.568227 -299.049708) (xy 22.646167 -299.133514) (xy 25.826718 -299.133514) (xy 25.830789 -299.077892)
			(xy 25.842915 -299.023455) (xy 25.862838 -298.971364) (xy 25.890134 -298.922729) (xy 25.92422 -298.878586)
			(xy 25.964369 -298.839877) (xy 26.009727 -298.807426) (xy 26.059327 -298.781925) (xy 26.112111 -298.763918)
			(xy 26.166954 -298.753788) (xy 26.222688 -298.751751) (xy 26.278125 -298.757851) (xy 26.332082 -298.771957)
			(xy 26.383411 -298.793769) (xy 26.431017 -298.822823) (xy 26.473885 -298.858498) (xy 26.511102 -298.900035)
			(xy 26.541875 -298.946548) (xy 26.565547 -298.997045) (xy 26.581615 -299.050452) (xy 26.589735 -299.105628)
			(xy 26.590244 -299.133514) (xy 27.286964 -299.133514) (xy 27.291035 -299.077892) (xy 27.303161 -299.023455)
			(xy 27.323084 -298.971364) (xy 27.35038 -298.922729) (xy 27.384466 -298.878586) (xy 27.424615 -298.839877)
			(xy 27.469973 -298.807426) (xy 27.519573 -298.781925) (xy 27.572357 -298.763918) (xy 27.6272 -298.753788)
			(xy 27.682934 -298.751751) (xy 27.738371 -298.757851) (xy 27.792328 -298.771957) (xy 27.843657 -298.793769)
			(xy 27.891263 -298.822823) (xy 27.934131 -298.858498) (xy 27.971348 -298.900035) (xy 28.002121 -298.946548)
			(xy 28.025793 -298.997045) (xy 28.041861 -299.050452) (xy 28.049981 -299.105628) (xy 28.05049 -299.133514)
			(xy 28.175964 -299.133514) (xy 28.180035 -299.077892) (xy 28.192161 -299.023455) (xy 28.212084 -298.971364)
			(xy 28.23938 -298.922729) (xy 28.273466 -298.878586) (xy 28.313615 -298.839877) (xy 28.358973 -298.807426)
			(xy 28.408573 -298.781925) (xy 28.461357 -298.763918) (xy 28.5162 -298.753788) (xy 28.571934 -298.751751)
			(xy 28.627371 -298.757851) (xy 28.681328 -298.771957) (xy 28.732657 -298.793769) (xy 28.780263 -298.822823)
			(xy 28.823131 -298.858498) (xy 28.860348 -298.900035) (xy 28.891121 -298.946548) (xy 28.914793 -298.997045)
			(xy 28.930861 -299.050452) (xy 28.938981 -299.105628) (xy 28.93949 -299.133514) (xy 28.938981 -299.1614)
			(xy 28.930861 -299.216576) (xy 28.914793 -299.269983) (xy 28.891121 -299.32048) (xy 28.860348 -299.366993)
			(xy 28.823131 -299.40853) (xy 28.780263 -299.444205) (xy 28.732657 -299.473259) (xy 28.681328 -299.495071)
			(xy 28.627371 -299.509177) (xy 28.571934 -299.515277) (xy 28.5162 -299.51324) (xy 28.461357 -299.50311)
			(xy 28.408573 -299.485103) (xy 28.358973 -299.459602) (xy 28.313615 -299.427151) (xy 28.273466 -299.388442)
			(xy 28.23938 -299.344299) (xy 28.212084 -299.295664) (xy 28.192161 -299.243573) (xy 28.180035 -299.189136)
			(xy 28.175964 -299.133514) (xy 28.05049 -299.133514) (xy 28.049981 -299.1614) (xy 28.041861 -299.216576)
			(xy 28.025793 -299.269983) (xy 28.002121 -299.32048) (xy 27.971348 -299.366993) (xy 27.934131 -299.40853)
			(xy 27.891263 -299.444205) (xy 27.843657 -299.473259) (xy 27.792328 -299.495071) (xy 27.738371 -299.509177)
			(xy 27.682934 -299.515277) (xy 27.6272 -299.51324) (xy 27.572357 -299.50311) (xy 27.519573 -299.485103)
			(xy 27.469973 -299.459602) (xy 27.424615 -299.427151) (xy 27.384466 -299.388442) (xy 27.35038 -299.344299)
			(xy 27.323084 -299.295664) (xy 27.303161 -299.243573) (xy 27.291035 -299.189136) (xy 27.286964 -299.133514)
			(xy 26.590244 -299.133514) (xy 26.589735 -299.1614) (xy 26.581615 -299.216576) (xy 26.565547 -299.269983)
			(xy 26.541875 -299.32048) (xy 26.511102 -299.366993) (xy 26.473885 -299.40853) (xy 26.431017 -299.444205)
			(xy 26.383411 -299.473259) (xy 26.332082 -299.495071) (xy 26.278125 -299.509177) (xy 26.222688 -299.515277)
			(xy 26.166954 -299.51324) (xy 26.112111 -299.50311) (xy 26.059327 -299.485103) (xy 26.009727 -299.459602)
			(xy 25.964369 -299.427151) (xy 25.92422 -299.388442) (xy 25.890134 -299.344299) (xy 25.862838 -299.295664)
			(xy 25.842915 -299.243573) (xy 25.830789 -299.189136) (xy 25.826718 -299.133514) (xy 22.646167 -299.133514)
			(xy 22.679443 -299.169294) (xy 22.784751 -299.294113) (xy 22.883906 -299.423874) (xy 22.976675 -299.558274)
			(xy 23.062843 -299.697) (xy 23.142208 -299.839726) (xy 23.16979 -299.895514) (xy 31.308802 -299.895514)
			(xy 31.309274 -299.869238) (xy 31.31648 -299.817183) (xy 31.330758 -299.766608) (xy 31.351838 -299.71847)
			(xy 31.379322 -299.673678) (xy 31.412689 -299.633079) (xy 31.45131 -299.59744) (xy 31.472632 -299.582078)
			(xy 31.48503 -299.572838) (xy 31.503983 -299.548423) (xy 31.514782 -299.519463) (xy 31.516441 -299.4886)
			(xy 31.50881 -299.458649) (xy 31.492584 -299.432342) (xy 31.481268 -299.421804) (xy 31.460981 -299.4036)
			(xy 31.425279 -299.362414) (xy 31.395796 -299.316571) (xy 31.37313 -299.267001) (xy 31.357744 -299.214712)
			(xy 31.349949 -299.160767) (xy 31.349442 -299.133514) (xy 31.349928 -299.106263) (xy 31.357684 -299.052315)
			(xy 31.373039 -299.00002) (xy 31.395681 -298.950443) (xy 31.425147 -298.904593) (xy 31.460838 -298.863402)
			(xy 31.502029 -298.827711) (xy 31.547879 -298.798245) (xy 31.597456 -298.775603) (xy 31.649751 -298.760248)
			(xy 31.703699 -298.752492) (xy 31.758201 -298.752492) (xy 31.812149 -298.760248) (xy 31.864444 -298.775603)
			(xy 31.914021 -298.798245) (xy 31.959871 -298.827711) (xy 32.001062 -298.863402) (xy 32.036753 -298.904593)
			(xy 32.066219 -298.950443) (xy 32.088861 -299.00002) (xy 32.104216 -299.052315) (xy 32.111972 -299.106263)
			(xy 32.112458 -299.133514) (xy 32.112024 -299.159791) (xy 32.104814 -299.211849) (xy 32.101185 -299.2247)
			(xy 35.433769 -299.2247) (xy 35.43794 -299.174364) (xy 35.450338 -299.125401) (xy 35.470626 -299.079147)
			(xy 35.498251 -299.036862) (xy 35.532458 -298.999701) (xy 35.572315 -298.968676) (xy 35.616734 -298.944635)
			(xy 35.664505 -298.928232) (xy 35.714324 -298.919915) (xy 35.739578 -298.919392) (xy 35.764974 -298.919894)
			(xy 35.815064 -298.92831) (xy 35.863072 -298.944895) (xy 35.907674 -298.969195) (xy 35.947642 -299.000538)
			(xy 35.96513 -299.01896) (xy 35.97275 -299.027342) (xy 35.992816 -299.035978) (xy 36.09213 -299.033438)
			(xy 36.111688 -299.023786) (xy 36.1188 -299.01515) (xy 36.134607 -298.996582) (xy 36.170723 -298.963822)
			(xy 36.211253 -298.93671) (xy 36.255319 -298.915834) (xy 36.30197 -298.901645) (xy 36.350198 -298.894449)
			(xy 36.374578 -298.893992) (xy 37.324538 -298.893992) (xy 37.35054 -298.894597) (xy 37.401902 -298.902737)
			(xy 37.451358 -298.918812) (xy 37.497691 -298.942425) (xy 37.539761 -298.972994) (xy 37.576531 -299.009768)
			(xy 37.607095 -299.051841) (xy 37.630703 -299.098177) (xy 37.646771 -299.147635) (xy 37.654906 -299.198998)
			(xy 37.654906 -299.224954) (xy 37.968948 -299.224954) (xy 37.972908 -299.1759) (xy 37.984685 -299.128116)
			(xy 38.003976 -299.08284) (xy 38.030279 -299.041244) (xy 38.062914 -299.004407) (xy 38.101035 -298.973282)
			(xy 38.143656 -298.948675) (xy 38.189672 -298.931223) (xy 38.237891 -298.921379) (xy 38.287066 -298.919398)
			(xy 38.335921 -298.92533) (xy 38.383192 -298.939022) (xy 38.427654 -298.96012) (xy 38.468157 -298.988076)
			(xy 38.50365 -299.022168) (xy 38.533215 -299.061512) (xy 38.556086 -299.105089) (xy 38.57167 -299.15177)
			(xy 38.579565 -299.200347) (xy 38.58006 -299.224954) (xy 38.579565 -299.249561) (xy 38.57167 -299.298138)
			(xy 38.556086 -299.344819) (xy 38.533215 -299.388396) (xy 38.50365 -299.42774) (xy 38.468157 -299.461832)
			(xy 38.427654 -299.489788) (xy 38.383192 -299.510886) (xy 38.335921 -299.524578) (xy 38.287066 -299.53051)
			(xy 38.237891 -299.528529) (xy 38.189672 -299.518685) (xy 38.143656 -299.501233) (xy 38.101035 -299.476626)
			(xy 38.062914 -299.445501) (xy 38.030279 -299.408664) (xy 38.003976 -299.367068) (xy 37.984685 -299.321792)
			(xy 37.972908 -299.274008) (xy 37.968948 -299.224954) (xy 37.654906 -299.224954) (xy 37.654906 -299.251002)
			(xy 37.646771 -299.302365) (xy 37.630703 -299.351823) (xy 37.607095 -299.398159) (xy 37.576531 -299.440232)
			(xy 37.539761 -299.477006) (xy 37.497691 -299.507575) (xy 37.451358 -299.531188) (xy 37.401902 -299.547263)
			(xy 37.35054 -299.555403) (xy 37.324538 -299.555916) (xy 36.374578 -299.555916) (xy 36.350193 -299.555511)
			(xy 36.301954 -299.548332) (xy 36.255293 -299.534147) (xy 36.21122 -299.513263) (xy 36.170692 -299.486135)
			(xy 36.134587 -299.453348) (xy 36.1188 -299.434758) (xy 36.111434 -299.425868) (xy 36.09213 -299.41647)
			(xy 35.992562 -299.413676) (xy 35.97275 -299.422312) (xy 35.96513 -299.43044) (xy 35.947646 -299.448867)
			(xy 35.907681 -299.480216) (xy 35.863078 -299.504518) (xy 35.815068 -299.5211) (xy 35.764975 -299.529505)
			(xy 35.739578 -299.530008) (xy 35.714324 -299.529485) (xy 35.664505 -299.521168) (xy 35.616734 -299.504765)
			(xy 35.572315 -299.480724) (xy 35.532458 -299.449699) (xy 35.498251 -299.412538) (xy 35.470626 -299.370253)
			(xy 35.450338 -299.323999) (xy 35.43794 -299.275036) (xy 35.433769 -299.2247) (xy 32.101185 -299.2247)
			(xy 32.09053 -299.262425) (xy 32.069444 -299.310565) (xy 32.041954 -299.355356) (xy 32.00858 -299.395954)
			(xy 31.969953 -299.43159) (xy 31.948628 -299.44695) (xy 31.936206 -299.456158) (xy 31.917259 -299.480583)
			(xy 31.906467 -299.509551) (xy 31.904813 -299.540418) (xy 31.912448 -299.570373) (xy 31.928675 -299.596683)
			(xy 31.939992 -299.607224) (xy 31.960304 -299.625401) (xy 31.996002 -299.666593) (xy 32.025481 -299.712443)
			(xy 32.048141 -299.762018) (xy 32.055655 -299.787564) (xy 32.891982 -299.787564) (xy 32.896053 -299.731942)
			(xy 32.908179 -299.677505) (xy 32.928102 -299.625414) (xy 32.955398 -299.576779) (xy 32.989484 -299.532636)
			(xy 33.029633 -299.493927) (xy 33.074991 -299.461476) (xy 33.124591 -299.435975) (xy 33.177375 -299.417968)
			(xy 33.232218 -299.407838) (xy 33.287952 -299.405801) (xy 33.343389 -299.411901) (xy 33.397346 -299.426007)
			(xy 33.448675 -299.447819) (xy 33.496281 -299.476873) (xy 33.539149 -299.512548) (xy 33.576366 -299.554085)
			(xy 33.607139 -299.600598) (xy 33.630811 -299.651095) (xy 33.646879 -299.704502) (xy 33.654999 -299.759678)
			(xy 33.655508 -299.787564) (xy 33.654999 -299.81545) (xy 33.646879 -299.870626) (xy 33.642219 -299.886116)
			(xy 33.77006 -299.886116) (xy 33.774131 -299.830494) (xy 33.786257 -299.776057) (xy 33.80618 -299.723966)
			(xy 33.833476 -299.675331) (xy 33.867562 -299.631188) (xy 33.907711 -299.592479) (xy 33.953069 -299.560028)
			(xy 34.002669 -299.534527) (xy 34.055453 -299.51652) (xy 34.110296 -299.50639) (xy 34.16603 -299.504353)
			(xy 34.221467 -299.510453) (xy 34.275424 -299.524559) (xy 34.326753 -299.546371) (xy 34.374359 -299.575425)
			(xy 34.417227 -299.6111) (xy 34.454444 -299.652637) (xy 34.485217 -299.69915) (xy 34.485585 -299.699934)
			(xy 39.394142 -299.699934) (xy 39.398102 -299.65088) (xy 39.409879 -299.603096) (xy 39.42917 -299.55782)
			(xy 39.455473 -299.516224) (xy 39.488108 -299.479387) (xy 39.526229 -299.448262) (xy 39.56885 -299.423655)
			(xy 39.614866 -299.406203) (xy 39.663085 -299.396359) (xy 39.71226 -299.394378) (xy 39.761115 -299.40031)
			(xy 39.808386 -299.414002) (xy 39.852848 -299.4351) (xy 39.893351 -299.463056) (xy 39.928844 -299.497148)
			(xy 39.958409 -299.536492) (xy 39.98128 -299.580069) (xy 39.996864 -299.62675) (xy 40.004759 -299.675327)
			(xy 40.005254 -299.699934) (xy 40.004759 -299.724541) (xy 39.996864 -299.773118) (xy 39.98128 -299.819799)
			(xy 39.958409 -299.863376) (xy 39.928844 -299.90272) (xy 39.893351 -299.936812) (xy 39.852848 -299.964768)
			(xy 39.808386 -299.985866) (xy 39.761115 -299.999558) (xy 39.71226 -300.00549) (xy 39.663085 -300.003509)
			(xy 39.614866 -299.993665) (xy 39.56885 -299.976213) (xy 39.526229 -299.951606) (xy 39.488108 -299.920481)
			(xy 39.455473 -299.883644) (xy 39.42917 -299.842048) (xy 39.409879 -299.796772) (xy 39.398102 -299.748988)
			(xy 39.394142 -299.699934) (xy 34.485585 -299.699934) (xy 34.508889 -299.749647) (xy 34.524957 -299.803054)
			(xy 34.533077 -299.85823) (xy 34.533586 -299.886116) (xy 34.533077 -299.914002) (xy 34.524957 -299.969178)
			(xy 34.508889 -300.022585) (xy 34.485217 -300.073082) (xy 34.454444 -300.119595) (xy 34.417227 -300.161132)
			(xy 34.374359 -300.196807) (xy 34.326753 -300.225861) (xy 34.275424 -300.247673) (xy 34.221467 -300.261779)
			(xy 34.16603 -300.267879) (xy 34.110296 -300.265842) (xy 34.055453 -300.255712) (xy 34.002669 -300.237705)
			(xy 33.953069 -300.212204) (xy 33.907711 -300.179753) (xy 33.867562 -300.141044) (xy 33.833476 -300.096901)
			(xy 33.80618 -300.048266) (xy 33.786257 -299.996175) (xy 33.774131 -299.941738) (xy 33.77006 -299.886116)
			(xy 33.642219 -299.886116) (xy 33.630811 -299.924033) (xy 33.607139 -299.97453) (xy 33.576366 -300.021043)
			(xy 33.539149 -300.06258) (xy 33.496281 -300.098255) (xy 33.448675 -300.127309) (xy 33.397346 -300.149121)
			(xy 33.343389 -300.163227) (xy 33.287952 -300.169327) (xy 33.232218 -300.16729) (xy 33.177375 -300.15716)
			(xy 33.124591 -300.139153) (xy 33.074991 -300.113652) (xy 33.029633 -300.081201) (xy 32.989484 -300.042492)
			(xy 32.955398 -299.998349) (xy 32.928102 -299.949714) (xy 32.908179 -299.897623) (xy 32.896053 -299.843186)
			(xy 32.891982 -299.787564) (xy 32.055655 -299.787564) (xy 32.063523 -299.814311) (xy 32.071313 -299.86826)
			(xy 32.071818 -299.895514) (xy 32.071332 -299.922765) (xy 32.063576 -299.976713) (xy 32.048221 -300.029008)
			(xy 32.025579 -300.078585) (xy 31.996113 -300.124435) (xy 31.960422 -300.165626) (xy 31.919231 -300.201317)
			(xy 31.873381 -300.230783) (xy 31.823804 -300.253425) (xy 31.771509 -300.26878) (xy 31.717561 -300.276536)
			(xy 31.663059 -300.276536) (xy 31.609111 -300.26878) (xy 31.556816 -300.253425) (xy 31.507239 -300.230783)
			(xy 31.461389 -300.201317) (xy 31.420198 -300.165626) (xy 31.384507 -300.124435) (xy 31.355041 -300.078585)
			(xy 31.332399 -300.029008) (xy 31.317044 -299.976713) (xy 31.309288 -299.922765) (xy 31.308802 -299.895514)
			(xy 23.16979 -299.895514) (xy 23.214585 -299.98612) (xy 23.279805 -300.13584) (xy 23.337715 -300.288536)
			(xy 23.376064 -300.406562) (xy 25.998676 -300.406562) (xy 26.002747 -300.35094) (xy 26.014873 -300.296503)
			(xy 26.034796 -300.244412) (xy 26.062092 -300.195777) (xy 26.096178 -300.151634) (xy 26.136327 -300.112925)
			(xy 26.181685 -300.080474) (xy 26.231285 -300.054973) (xy 26.284069 -300.036966) (xy 26.338912 -300.026836)
			(xy 26.394646 -300.024799) (xy 26.450083 -300.030899) (xy 26.50404 -300.045005) (xy 26.555369 -300.066817)
			(xy 26.602975 -300.095871) (xy 26.645843 -300.131546) (xy 26.68306 -300.173083) (xy 26.713833 -300.219596)
			(xy 26.737505 -300.270093) (xy 26.753573 -300.3235) (xy 26.761693 -300.378676) (xy 26.762202 -300.406562)
			(xy 26.761693 -300.434448) (xy 26.753573 -300.489624) (xy 26.737505 -300.543031) (xy 26.713833 -300.593528)
			(xy 26.68306 -300.640041) (xy 26.674232 -300.649894) (xy 36.544008 -300.649894) (xy 36.547968 -300.60084)
			(xy 36.559745 -300.553056) (xy 36.579036 -300.50778) (xy 36.605339 -300.466184) (xy 36.637974 -300.429347)
			(xy 36.676095 -300.398222) (xy 36.718716 -300.373615) (xy 36.764732 -300.356163) (xy 36.812951 -300.346319)
			(xy 36.862126 -300.344338) (xy 36.910981 -300.35027) (xy 36.958252 -300.363962) (xy 37.002714 -300.38506)
			(xy 37.043217 -300.413016) (xy 37.07871 -300.447108) (xy 37.108275 -300.486452) (xy 37.131146 -300.530029)
			(xy 37.14673 -300.57671) (xy 37.154625 -300.625287) (xy 37.15512 -300.649894) (xy 37.493968 -300.649894)
			(xy 37.497928 -300.60084) (xy 37.509705 -300.553056) (xy 37.528996 -300.50778) (xy 37.555299 -300.466184)
			(xy 37.587934 -300.429347) (xy 37.626055 -300.398222) (xy 37.668676 -300.373615) (xy 37.714692 -300.356163)
			(xy 37.762911 -300.346319) (xy 37.812086 -300.344338) (xy 37.860941 -300.35027) (xy 37.908212 -300.363962)
			(xy 37.952674 -300.38506) (xy 37.993177 -300.413016) (xy 38.02867 -300.447108) (xy 38.058235 -300.486452)
			(xy 38.081106 -300.530029) (xy 38.09669 -300.57671) (xy 38.104585 -300.625287) (xy 38.10508 -300.649894)
			(xy 38.444182 -300.649894) (xy 38.448142 -300.60084) (xy 38.459919 -300.553056) (xy 38.47921 -300.50778)
			(xy 38.505513 -300.466184) (xy 38.538148 -300.429347) (xy 38.576269 -300.398222) (xy 38.61889 -300.373615)
			(xy 38.664906 -300.356163) (xy 38.713125 -300.346319) (xy 38.7623 -300.344338) (xy 38.811155 -300.35027)
			(xy 38.858426 -300.363962) (xy 38.902888 -300.38506) (xy 38.943391 -300.413016) (xy 38.978884 -300.447108)
			(xy 39.008449 -300.486452) (xy 39.03132 -300.530029) (xy 39.046904 -300.57671) (xy 39.054799 -300.625287)
			(xy 39.055294 -300.649894) (xy 39.394142 -300.649894) (xy 39.398102 -300.60084) (xy 39.409879 -300.553056)
			(xy 39.42917 -300.50778) (xy 39.455473 -300.466184) (xy 39.488108 -300.429347) (xy 39.526229 -300.398222)
			(xy 39.56885 -300.373615) (xy 39.614866 -300.356163) (xy 39.663085 -300.346319) (xy 39.71226 -300.344338)
			(xy 39.761115 -300.35027) (xy 39.808386 -300.363962) (xy 39.852848 -300.38506) (xy 39.893351 -300.413016)
			(xy 39.928844 -300.447108) (xy 39.958409 -300.486452) (xy 39.98128 -300.530029) (xy 39.996864 -300.57671)
			(xy 40.004759 -300.625287) (xy 40.005087 -300.641616) (xy 40.344175 -300.641616) (xy 40.349543 -300.592264)
			(xy 40.362824 -300.544431) (xy 40.383669 -300.499376) (xy 40.411529 -300.458287) (xy 40.445669 -300.422247)
			(xy 40.48519 -300.392205) (xy 40.52905 -300.368952) (xy 40.576095 -300.353102) (xy 40.625084 -300.345071)
			(xy 40.649906 -300.344586) (xy 40.664089 -300.344762) (xy 40.692329 -300.347435) (xy 40.706294 -300.34992)
			(xy 40.71874 -300.352206) (xy 40.742362 -300.34484) (xy 40.819832 -300.26737) (xy 40.827198 -300.243748)
			(xy 40.824912 -300.231302) (xy 40.82244 -300.217335) (xy 40.819765 -300.189096) (xy 40.819578 -300.174914)
			(xy 40.8201 -300.149659) (xy 40.828413 -300.099837) (xy 40.844814 -300.052063) (xy 40.868855 -300.00764)
			(xy 40.899879 -299.96778) (xy 40.937041 -299.93357) (xy 40.979327 -299.905944) (xy 41.025583 -299.885654)
			(xy 41.074548 -299.873254) (xy 41.124886 -299.869083) (xy 41.175224 -299.873254) (xy 41.224189 -299.885654)
			(xy 41.270445 -299.905944) (xy 41.312731 -299.93357) (xy 41.349893 -299.96778) (xy 41.380917 -300.00764)
			(xy 41.404958 -300.052063) (xy 41.421359 -300.099837) (xy 41.429672 -300.149659) (xy 41.430194 -300.174914)
			(xy 41.43002 -300.189097) (xy 41.427346 -300.217337) (xy 41.42486 -300.231302) (xy 41.422574 -300.243748)
			(xy 41.42994 -300.26737) (xy 41.50741 -300.34484) (xy 41.531032 -300.352206) (xy 41.543478 -300.34992)
			(xy 41.557443 -300.347437) (xy 41.585683 -300.344769) (xy 41.599866 -300.344586) (xy 41.614049 -300.344767)
			(xy 41.642289 -300.347436) (xy 41.656254 -300.34992) (xy 41.6687 -300.352206) (xy 41.692322 -300.34484)
			(xy 41.769792 -300.26737) (xy 41.777158 -300.243748) (xy 41.774872 -300.231302) (xy 41.772399 -300.217335)
			(xy 41.769725 -300.189096) (xy 41.769538 -300.174914) (xy 41.77006 -300.149659) (xy 41.778373 -300.099837)
			(xy 41.794774 -300.052063) (xy 41.818815 -300.00764) (xy 41.849839 -299.96778) (xy 41.887001 -299.93357)
			(xy 41.929287 -299.905944) (xy 41.975543 -299.885654) (xy 42.024508 -299.873254) (xy 42.074846 -299.869083)
			(xy 42.125184 -299.873254) (xy 42.174149 -299.885654) (xy 42.220405 -299.905944) (xy 42.262691 -299.93357)
			(xy 42.299853 -299.96778) (xy 42.330877 -300.00764) (xy 42.354918 -300.052063) (xy 42.371319 -300.099837)
			(xy 42.379632 -300.149659) (xy 42.380154 -300.174914) (xy 43.668962 -300.174914) (xy 43.672922 -300.12586)
			(xy 43.684699 -300.078076) (xy 43.70399 -300.0328) (xy 43.730293 -299.991204) (xy 43.762928 -299.954367)
			(xy 43.801049 -299.923242) (xy 43.84367 -299.898635) (xy 43.889686 -299.881183) (xy 43.937905 -299.871339)
			(xy 43.98708 -299.869358) (xy 44.035935 -299.87529) (xy 44.083206 -299.888982) (xy 44.127668 -299.91008)
			(xy 44.168171 -299.938036) (xy 44.203664 -299.972128) (xy 44.233229 -300.011472) (xy 44.2561 -300.055049)
			(xy 44.271684 -300.10173) (xy 44.279579 -300.150307) (xy 44.280074 -300.174914) (xy 44.619176 -300.174914)
			(xy 44.623136 -300.12586) (xy 44.634913 -300.078076) (xy 44.654204 -300.0328) (xy 44.680507 -299.991204)
			(xy 44.713142 -299.954367) (xy 44.751263 -299.923242) (xy 44.793884 -299.898635) (xy 44.8399 -299.881183)
			(xy 44.888119 -299.871339) (xy 44.937294 -299.869358) (xy 44.986149 -299.87529) (xy 45.03342 -299.888982)
			(xy 45.077882 -299.91008) (xy 45.118385 -299.938036) (xy 45.153878 -299.972128) (xy 45.183443 -300.011472)
			(xy 45.206314 -300.055049) (xy 45.221898 -300.10173) (xy 45.229793 -300.150307) (xy 45.230288 -300.174914)
			(xy 45.569136 -300.174914) (xy 45.573096 -300.12586) (xy 45.584873 -300.078076) (xy 45.604164 -300.0328)
			(xy 45.630467 -299.991204) (xy 45.663102 -299.954367) (xy 45.701223 -299.923242) (xy 45.743844 -299.898635)
			(xy 45.78986 -299.881183) (xy 45.838079 -299.871339) (xy 45.887254 -299.869358) (xy 45.936109 -299.87529)
			(xy 45.98338 -299.888982) (xy 46.027842 -299.91008) (xy 46.068345 -299.938036) (xy 46.103838 -299.972128)
			(xy 46.133403 -300.011472) (xy 46.156274 -300.055049) (xy 46.171858 -300.10173) (xy 46.179753 -300.150307)
			(xy 46.180248 -300.174914) (xy 47.469056 -300.174914) (xy 47.473016 -300.12586) (xy 47.484793 -300.078076)
			(xy 47.504084 -300.0328) (xy 47.530387 -299.991204) (xy 47.563022 -299.954367) (xy 47.601143 -299.923242)
			(xy 47.643764 -299.898635) (xy 47.68978 -299.881183) (xy 47.737999 -299.871339) (xy 47.787174 -299.869358)
			(xy 47.836029 -299.87529) (xy 47.8833 -299.888982) (xy 47.927762 -299.91008) (xy 47.968265 -299.938036)
			(xy 48.003758 -299.972128) (xy 48.033323 -300.011472) (xy 48.056194 -300.055049) (xy 48.071778 -300.10173)
			(xy 48.079673 -300.150307) (xy 48.080168 -300.174914) (xy 48.419016 -300.174914) (xy 48.422976 -300.12586)
			(xy 48.434753 -300.078076) (xy 48.454044 -300.0328) (xy 48.480347 -299.991204) (xy 48.512982 -299.954367)
			(xy 48.551103 -299.923242) (xy 48.593724 -299.898635) (xy 48.63974 -299.881183) (xy 48.687959 -299.871339)
			(xy 48.737134 -299.869358) (xy 48.785989 -299.87529) (xy 48.83326 -299.888982) (xy 48.877722 -299.91008)
			(xy 48.918225 -299.938036) (xy 48.953718 -299.972128) (xy 48.983283 -300.011472) (xy 49.006154 -300.055049)
			(xy 49.021738 -300.10173) (xy 49.029633 -300.150307) (xy 49.030128 -300.174914) (xy 49.368976 -300.174914)
			(xy 49.372936 -300.12586) (xy 49.384713 -300.078076) (xy 49.404004 -300.0328) (xy 49.430307 -299.991204)
			(xy 49.462942 -299.954367) (xy 49.501063 -299.923242) (xy 49.543684 -299.898635) (xy 49.5897 -299.881183)
			(xy 49.637919 -299.871339) (xy 49.687094 -299.869358) (xy 49.735949 -299.87529) (xy 49.78322 -299.888982)
			(xy 49.827682 -299.91008) (xy 49.868185 -299.938036) (xy 49.903678 -299.972128) (xy 49.933243 -300.011472)
			(xy 49.956114 -300.055049) (xy 49.971698 -300.10173) (xy 49.979593 -300.150307) (xy 49.980088 -300.174914)
			(xy 50.31919 -300.174914) (xy 50.32315 -300.12586) (xy 50.334927 -300.078076) (xy 50.354218 -300.0328)
			(xy 50.380521 -299.991204) (xy 50.413156 -299.954367) (xy 50.451277 -299.923242) (xy 50.493898 -299.898635)
			(xy 50.539914 -299.881183) (xy 50.588133 -299.871339) (xy 50.637308 -299.869358) (xy 50.686163 -299.87529)
			(xy 50.733434 -299.888982) (xy 50.777896 -299.91008) (xy 50.818399 -299.938036) (xy 50.853892 -299.972128)
			(xy 50.883457 -300.011472) (xy 50.906328 -300.055049) (xy 50.921912 -300.10173) (xy 50.929807 -300.150307)
			(xy 50.930302 -300.174914) (xy 51.26915 -300.174914) (xy 51.27311 -300.12586) (xy 51.284887 -300.078076)
			(xy 51.304178 -300.0328) (xy 51.330481 -299.991204) (xy 51.363116 -299.954367) (xy 51.401237 -299.923242)
			(xy 51.443858 -299.898635) (xy 51.489874 -299.881183) (xy 51.538093 -299.871339) (xy 51.587268 -299.869358)
			(xy 51.636123 -299.87529) (xy 51.683394 -299.888982) (xy 51.727856 -299.91008) (xy 51.768359 -299.938036)
			(xy 51.803852 -299.972128) (xy 51.833417 -300.011472) (xy 51.856288 -300.055049) (xy 51.871872 -300.10173)
			(xy 51.879767 -300.150307) (xy 51.880262 -300.174914) (xy 52.21911 -300.174914) (xy 52.22307 -300.12586)
			(xy 52.234847 -300.078076) (xy 52.254138 -300.0328) (xy 52.280441 -299.991204) (xy 52.313076 -299.954367)
			(xy 52.351197 -299.923242) (xy 52.393818 -299.898635) (xy 52.439834 -299.881183) (xy 52.488053 -299.871339)
			(xy 52.537228 -299.869358) (xy 52.586083 -299.87529) (xy 52.633354 -299.888982) (xy 52.677816 -299.91008)
			(xy 52.718319 -299.938036) (xy 52.753812 -299.972128) (xy 52.783377 -300.011472) (xy 52.806248 -300.055049)
			(xy 52.821832 -300.10173) (xy 52.829727 -300.150307) (xy 52.830222 -300.174914) (xy 53.16907 -300.174914)
			(xy 53.17303 -300.12586) (xy 53.184807 -300.078076) (xy 53.204098 -300.0328) (xy 53.230401 -299.991204)
			(xy 53.263036 -299.954367) (xy 53.301157 -299.923242) (xy 53.343778 -299.898635) (xy 53.389794 -299.881183)
			(xy 53.438013 -299.871339) (xy 53.487188 -299.869358) (xy 53.536043 -299.87529) (xy 53.583314 -299.888982)
			(xy 53.627776 -299.91008) (xy 53.668279 -299.938036) (xy 53.703772 -299.972128) (xy 53.733337 -300.011472)
			(xy 53.756208 -300.055049) (xy 53.771792 -300.10173) (xy 53.779687 -300.150307) (xy 53.780182 -300.174914)
			(xy 54.11903 -300.174914) (xy 54.12299 -300.12586) (xy 54.134767 -300.078076) (xy 54.154058 -300.0328)
			(xy 54.180361 -299.991204) (xy 54.212996 -299.954367) (xy 54.251117 -299.923242) (xy 54.293738 -299.898635)
			(xy 54.339754 -299.881183) (xy 54.387973 -299.871339) (xy 54.437148 -299.869358) (xy 54.486003 -299.87529)
			(xy 54.533274 -299.888982) (xy 54.577736 -299.91008) (xy 54.618239 -299.938036) (xy 54.653732 -299.972128)
			(xy 54.683297 -300.011472) (xy 54.706168 -300.055049) (xy 54.721752 -300.10173) (xy 54.729647 -300.150307)
			(xy 54.730142 -300.174914) (xy 55.06899 -300.174914) (xy 55.07295 -300.12586) (xy 55.084727 -300.078076)
			(xy 55.104018 -300.0328) (xy 55.130321 -299.991204) (xy 55.162956 -299.954367) (xy 55.201077 -299.923242)
			(xy 55.243698 -299.898635) (xy 55.289714 -299.881183) (xy 55.337933 -299.871339) (xy 55.387108 -299.869358)
			(xy 55.435963 -299.87529) (xy 55.483234 -299.888982) (xy 55.527696 -299.91008) (xy 55.568199 -299.938036)
			(xy 55.603692 -299.972128) (xy 55.633257 -300.011472) (xy 55.656128 -300.055049) (xy 55.671712 -300.10173)
			(xy 55.679607 -300.150307) (xy 55.680102 -300.174914) (xy 56.01895 -300.174914) (xy 56.02291 -300.12586)
			(xy 56.034687 -300.078076) (xy 56.053978 -300.0328) (xy 56.080281 -299.991204) (xy 56.112916 -299.954367)
			(xy 56.151037 -299.923242) (xy 56.193658 -299.898635) (xy 56.239674 -299.881183) (xy 56.287893 -299.871339)
			(xy 56.337068 -299.869358) (xy 56.385923 -299.87529) (xy 56.433194 -299.888982) (xy 56.477656 -299.91008)
			(xy 56.518159 -299.938036) (xy 56.553652 -299.972128) (xy 56.583217 -300.011472) (xy 56.606088 -300.055049)
			(xy 56.621672 -300.10173) (xy 56.629567 -300.150307) (xy 56.630062 -300.174914) (xy 56.969164 -300.174914)
			(xy 56.973124 -300.12586) (xy 56.984901 -300.078076) (xy 57.004192 -300.0328) (xy 57.030495 -299.991204)
			(xy 57.06313 -299.954367) (xy 57.101251 -299.923242) (xy 57.143872 -299.898635) (xy 57.189888 -299.881183)
			(xy 57.238107 -299.871339) (xy 57.287282 -299.869358) (xy 57.336137 -299.87529) (xy 57.383408 -299.888982)
			(xy 57.42787 -299.91008) (xy 57.468373 -299.938036) (xy 57.503866 -299.972128) (xy 57.533431 -300.011472)
			(xy 57.556302 -300.055049) (xy 57.571886 -300.10173) (xy 57.579781 -300.150307) (xy 57.580276 -300.174914)
			(xy 57.919124 -300.174914) (xy 57.923084 -300.12586) (xy 57.934861 -300.078076) (xy 57.954152 -300.0328)
			(xy 57.980455 -299.991204) (xy 58.01309 -299.954367) (xy 58.051211 -299.923242) (xy 58.093832 -299.898635)
			(xy 58.139848 -299.881183) (xy 58.188067 -299.871339) (xy 58.237242 -299.869358) (xy 58.286097 -299.87529)
			(xy 58.333368 -299.888982) (xy 58.37783 -299.91008) (xy 58.418333 -299.938036) (xy 58.453826 -299.972128)
			(xy 58.483391 -300.011472) (xy 58.506262 -300.055049) (xy 58.521846 -300.10173) (xy 58.529741 -300.150307)
			(xy 58.530236 -300.174914) (xy 59.819044 -300.174914) (xy 59.823004 -300.12586) (xy 59.834781 -300.078076)
			(xy 59.854072 -300.0328) (xy 59.880375 -299.991204) (xy 59.91301 -299.954367) (xy 59.951131 -299.923242)
			(xy 59.993752 -299.898635) (xy 60.039768 -299.881183) (xy 60.087987 -299.871339) (xy 60.137162 -299.869358)
			(xy 60.186017 -299.87529) (xy 60.233288 -299.888982) (xy 60.27775 -299.91008) (xy 60.318253 -299.938036)
			(xy 60.353746 -299.972128) (xy 60.383311 -300.011472) (xy 60.406182 -300.055049) (xy 60.421766 -300.10173)
			(xy 60.429661 -300.150307) (xy 60.430156 -300.174914) (xy 60.769004 -300.174914) (xy 60.772964 -300.12586)
			(xy 60.784741 -300.078076) (xy 60.804032 -300.0328) (xy 60.830335 -299.991204) (xy 60.86297 -299.954367)
			(xy 60.901091 -299.923242) (xy 60.943712 -299.898635) (xy 60.989728 -299.881183) (xy 61.037947 -299.871339)
			(xy 61.087122 -299.869358) (xy 61.135977 -299.87529) (xy 61.183248 -299.888982) (xy 61.22771 -299.91008)
			(xy 61.268213 -299.938036) (xy 61.303706 -299.972128) (xy 61.333271 -300.011472) (xy 61.356142 -300.055049)
			(xy 61.371726 -300.10173) (xy 61.379621 -300.150307) (xy 61.380116 -300.174914) (xy 61.718964 -300.174914)
			(xy 61.722924 -300.12586) (xy 61.734701 -300.078076) (xy 61.753992 -300.0328) (xy 61.780295 -299.991204)
			(xy 61.81293 -299.954367) (xy 61.851051 -299.923242) (xy 61.893672 -299.898635) (xy 61.939688 -299.881183)
			(xy 61.987907 -299.871339) (xy 62.037082 -299.869358) (xy 62.085937 -299.87529) (xy 62.133208 -299.888982)
			(xy 62.17767 -299.91008) (xy 62.218173 -299.938036) (xy 62.253666 -299.972128) (xy 62.283231 -300.011472)
			(xy 62.306102 -300.055049) (xy 62.321686 -300.10173) (xy 62.329581 -300.150307) (xy 62.330076 -300.174914)
			(xy 62.669178 -300.174914) (xy 62.673138 -300.12586) (xy 62.684915 -300.078076) (xy 62.704206 -300.0328)
			(xy 62.730509 -299.991204) (xy 62.763144 -299.954367) (xy 62.801265 -299.923242) (xy 62.843886 -299.898635)
			(xy 62.889902 -299.881183) (xy 62.938121 -299.871339) (xy 62.987296 -299.869358) (xy 63.036151 -299.87529)
			(xy 63.083422 -299.888982) (xy 63.127884 -299.91008) (xy 63.168387 -299.938036) (xy 63.20388 -299.972128)
			(xy 63.233445 -300.011472) (xy 63.256316 -300.055049) (xy 63.2719 -300.10173) (xy 63.279795 -300.150307)
			(xy 63.28029 -300.174914) (xy 63.619138 -300.174914) (xy 63.623098 -300.12586) (xy 63.634875 -300.078076)
			(xy 63.654166 -300.0328) (xy 63.680469 -299.991204) (xy 63.713104 -299.954367) (xy 63.751225 -299.923242)
			(xy 63.793846 -299.898635) (xy 63.839862 -299.881183) (xy 63.888081 -299.871339) (xy 63.937256 -299.869358)
			(xy 63.986111 -299.87529) (xy 64.033382 -299.888982) (xy 64.077844 -299.91008) (xy 64.118347 -299.938036)
			(xy 64.15384 -299.972128) (xy 64.183405 -300.011472) (xy 64.206276 -300.055049) (xy 64.22186 -300.10173)
			(xy 64.229755 -300.150307) (xy 64.23025 -300.174914) (xy 64.569098 -300.174914) (xy 64.573058 -300.12586)
			(xy 64.584835 -300.078076) (xy 64.604126 -300.0328) (xy 64.630429 -299.991204) (xy 64.663064 -299.954367)
			(xy 64.701185 -299.923242) (xy 64.743806 -299.898635) (xy 64.789822 -299.881183) (xy 64.838041 -299.871339)
			(xy 64.887216 -299.869358) (xy 64.936071 -299.87529) (xy 64.983342 -299.888982) (xy 65.027804 -299.91008)
			(xy 65.068307 -299.938036) (xy 65.1038 -299.972128) (xy 65.133365 -300.011472) (xy 65.156236 -300.055049)
			(xy 65.17182 -300.10173) (xy 65.179715 -300.150307) (xy 65.18021 -300.174914) (xy 65.519058 -300.174914)
			(xy 65.523018 -300.12586) (xy 65.534795 -300.078076) (xy 65.554086 -300.0328) (xy 65.580389 -299.991204)
			(xy 65.613024 -299.954367) (xy 65.651145 -299.923242) (xy 65.693766 -299.898635) (xy 65.739782 -299.881183)
			(xy 65.788001 -299.871339) (xy 65.837176 -299.869358) (xy 65.886031 -299.87529) (xy 65.933302 -299.888982)
			(xy 65.977764 -299.91008) (xy 66.018267 -299.938036) (xy 66.05376 -299.972128) (xy 66.083325 -300.011472)
			(xy 66.106196 -300.055049) (xy 66.12178 -300.10173) (xy 66.129675 -300.150307) (xy 66.13017 -300.174914)
			(xy 66.469018 -300.174914) (xy 66.472978 -300.12586) (xy 66.484755 -300.078076) (xy 66.504046 -300.0328)
			(xy 66.530349 -299.991204) (xy 66.562984 -299.954367) (xy 66.601105 -299.923242) (xy 66.643726 -299.898635)
			(xy 66.689742 -299.881183) (xy 66.737961 -299.871339) (xy 66.787136 -299.869358) (xy 66.835991 -299.87529)
			(xy 66.883262 -299.888982) (xy 66.927724 -299.91008) (xy 66.968227 -299.938036) (xy 67.00372 -299.972128)
			(xy 67.033285 -300.011472) (xy 67.056156 -300.055049) (xy 67.07174 -300.10173) (xy 67.079635 -300.150307)
			(xy 67.08013 -300.174914) (xy 67.418978 -300.174914) (xy 67.422938 -300.12586) (xy 67.434715 -300.078076)
			(xy 67.454006 -300.0328) (xy 67.480309 -299.991204) (xy 67.512944 -299.954367) (xy 67.551065 -299.923242)
			(xy 67.593686 -299.898635) (xy 67.639702 -299.881183) (xy 67.687921 -299.871339) (xy 67.737096 -299.869358)
			(xy 67.785951 -299.87529) (xy 67.833222 -299.888982) (xy 67.877684 -299.91008) (xy 67.918187 -299.938036)
			(xy 67.95368 -299.972128) (xy 67.983245 -300.011472) (xy 68.006116 -300.055049) (xy 68.0217 -300.10173)
			(xy 68.029595 -300.150307) (xy 68.03009 -300.174914) (xy 68.368938 -300.174914) (xy 68.372898 -300.12586)
			(xy 68.384675 -300.078076) (xy 68.403966 -300.0328) (xy 68.430269 -299.991204) (xy 68.462904 -299.954367)
			(xy 68.501025 -299.923242) (xy 68.543646 -299.898635) (xy 68.589662 -299.881183) (xy 68.637881 -299.871339)
			(xy 68.687056 -299.869358) (xy 68.735911 -299.87529) (xy 68.783182 -299.888982) (xy 68.827644 -299.91008)
			(xy 68.868147 -299.938036) (xy 68.90364 -299.972128) (xy 68.933205 -300.011472) (xy 68.956076 -300.055049)
			(xy 68.97166 -300.10173) (xy 68.979555 -300.150307) (xy 68.98005 -300.174914) (xy 69.319152 -300.174914)
			(xy 69.323112 -300.12586) (xy 69.334889 -300.078076) (xy 69.35418 -300.0328) (xy 69.380483 -299.991204)
			(xy 69.413118 -299.954367) (xy 69.451239 -299.923242) (xy 69.49386 -299.898635) (xy 69.539876 -299.881183)
			(xy 69.588095 -299.871339) (xy 69.63727 -299.869358) (xy 69.686125 -299.87529) (xy 69.733396 -299.888982)
			(xy 69.777858 -299.91008) (xy 69.818361 -299.938036) (xy 69.853854 -299.972128) (xy 69.883419 -300.011472)
			(xy 69.90629 -300.055049) (xy 69.921874 -300.10173) (xy 69.929769 -300.150307) (xy 69.930264 -300.174914)
			(xy 70.269112 -300.174914) (xy 70.273072 -300.12586) (xy 70.284849 -300.078076) (xy 70.30414 -300.0328)
			(xy 70.330443 -299.991204) (xy 70.363078 -299.954367) (xy 70.401199 -299.923242) (xy 70.44382 -299.898635)
			(xy 70.489836 -299.881183) (xy 70.538055 -299.871339) (xy 70.58723 -299.869358) (xy 70.636085 -299.87529)
			(xy 70.683356 -299.888982) (xy 70.727818 -299.91008) (xy 70.768321 -299.938036) (xy 70.803814 -299.972128)
			(xy 70.833379 -300.011472) (xy 70.85625 -300.055049) (xy 70.871834 -300.10173) (xy 70.879729 -300.150307)
			(xy 70.880224 -300.174914) (xy 71.219072 -300.174914) (xy 71.223032 -300.12586) (xy 71.234809 -300.078076)
			(xy 71.2541 -300.0328) (xy 71.280403 -299.991204) (xy 71.313038 -299.954367) (xy 71.351159 -299.923242)
			(xy 71.39378 -299.898635) (xy 71.439796 -299.881183) (xy 71.488015 -299.871339) (xy 71.53719 -299.869358)
			(xy 71.586045 -299.87529) (xy 71.633316 -299.888982) (xy 71.677778 -299.91008) (xy 71.718281 -299.938036)
			(xy 71.753774 -299.972128) (xy 71.783339 -300.011472) (xy 71.80621 -300.055049) (xy 71.821794 -300.10173)
			(xy 71.829689 -300.150307) (xy 71.830184 -300.174914) (xy 72.169032 -300.174914) (xy 72.172992 -300.12586)
			(xy 72.184769 -300.078076) (xy 72.20406 -300.0328) (xy 72.230363 -299.991204) (xy 72.262998 -299.954367)
			(xy 72.301119 -299.923242) (xy 72.34374 -299.898635) (xy 72.389756 -299.881183) (xy 72.437975 -299.871339)
			(xy 72.48715 -299.869358) (xy 72.536005 -299.87529) (xy 72.583276 -299.888982) (xy 72.627738 -299.91008)
			(xy 72.668241 -299.938036) (xy 72.703734 -299.972128) (xy 72.733299 -300.011472) (xy 72.75617 -300.055049)
			(xy 72.771754 -300.10173) (xy 72.779649 -300.150307) (xy 72.780144 -300.174914) (xy 73.118992 -300.174914)
			(xy 73.122952 -300.12586) (xy 73.134729 -300.078076) (xy 73.15402 -300.0328) (xy 73.180323 -299.991204)
			(xy 73.212958 -299.954367) (xy 73.251079 -299.923242) (xy 73.2937 -299.898635) (xy 73.339716 -299.881183)
			(xy 73.387935 -299.871339) (xy 73.43711 -299.869358) (xy 73.485965 -299.87529) (xy 73.533236 -299.888982)
			(xy 73.577698 -299.91008) (xy 73.618201 -299.938036) (xy 73.653694 -299.972128) (xy 73.683259 -300.011472)
			(xy 73.70613 -300.055049) (xy 73.721714 -300.10173) (xy 73.729609 -300.150307) (xy 73.730104 -300.174914)
			(xy 74.068952 -300.174914) (xy 74.072912 -300.12586) (xy 74.084689 -300.078076) (xy 74.10398 -300.0328)
			(xy 74.130283 -299.991204) (xy 74.162918 -299.954367) (xy 74.201039 -299.923242) (xy 74.24366 -299.898635)
			(xy 74.289676 -299.881183) (xy 74.337895 -299.871339) (xy 74.38707 -299.869358) (xy 74.435925 -299.87529)
			(xy 74.483196 -299.888982) (xy 74.527658 -299.91008) (xy 74.568161 -299.938036) (xy 74.603654 -299.972128)
			(xy 74.633219 -300.011472) (xy 74.65609 -300.055049) (xy 74.671674 -300.10173) (xy 74.679569 -300.150307)
			(xy 74.680064 -300.174914) (xy 75.969126 -300.174914) (xy 75.973086 -300.12586) (xy 75.984863 -300.078076)
			(xy 76.004154 -300.0328) (xy 76.030457 -299.991204) (xy 76.063092 -299.954367) (xy 76.101213 -299.923242)
			(xy 76.143834 -299.898635) (xy 76.18985 -299.881183) (xy 76.238069 -299.871339) (xy 76.287244 -299.869358)
			(xy 76.336099 -299.87529) (xy 76.38337 -299.888982) (xy 76.427832 -299.91008) (xy 76.468335 -299.938036)
			(xy 76.503828 -299.972128) (xy 76.533393 -300.011472) (xy 76.556264 -300.055049) (xy 76.571848 -300.10173)
			(xy 76.579743 -300.150307) (xy 76.580238 -300.174914) (xy 76.919086 -300.174914) (xy 76.923046 -300.12586)
			(xy 76.934823 -300.078076) (xy 76.954114 -300.0328) (xy 76.980417 -299.991204) (xy 77.013052 -299.954367)
			(xy 77.051173 -299.923242) (xy 77.093794 -299.898635) (xy 77.13981 -299.881183) (xy 77.188029 -299.871339)
			(xy 77.237204 -299.869358) (xy 77.286059 -299.87529) (xy 77.33333 -299.888982) (xy 77.377792 -299.91008)
			(xy 77.418295 -299.938036) (xy 77.453788 -299.972128) (xy 77.483353 -300.011472) (xy 77.506224 -300.055049)
			(xy 77.521808 -300.10173) (xy 77.529703 -300.150307) (xy 77.530198 -300.174914) (xy 77.869046 -300.174914)
			(xy 77.873006 -300.12586) (xy 77.884783 -300.078076) (xy 77.904074 -300.0328) (xy 77.930377 -299.991204)
			(xy 77.963012 -299.954367) (xy 78.001133 -299.923242) (xy 78.043754 -299.898635) (xy 78.08977 -299.881183)
			(xy 78.137989 -299.871339) (xy 78.187164 -299.869358) (xy 78.236019 -299.87529) (xy 78.28329 -299.888982)
			(xy 78.327752 -299.91008) (xy 78.368255 -299.938036) (xy 78.403748 -299.972128) (xy 78.433313 -300.011472)
			(xy 78.456184 -300.055049) (xy 78.471768 -300.10173) (xy 78.479663 -300.150307) (xy 78.480158 -300.174914)
			(xy 78.479663 -300.199521) (xy 78.471768 -300.248098) (xy 78.456184 -300.294779) (xy 78.433313 -300.338356)
			(xy 78.403748 -300.3777) (xy 78.368255 -300.411792) (xy 78.327752 -300.439748) (xy 78.28329 -300.460846)
			(xy 78.236019 -300.474538) (xy 78.187164 -300.48047) (xy 78.137989 -300.478489) (xy 78.08977 -300.468645)
			(xy 78.043754 -300.451193) (xy 78.001133 -300.426586) (xy 77.963012 -300.395461) (xy 77.930377 -300.358624)
			(xy 77.904074 -300.317028) (xy 77.884783 -300.271752) (xy 77.873006 -300.223968) (xy 77.869046 -300.174914)
			(xy 77.530198 -300.174914) (xy 77.529703 -300.199521) (xy 77.521808 -300.248098) (xy 77.506224 -300.294779)
			(xy 77.483353 -300.338356) (xy 77.453788 -300.3777) (xy 77.418295 -300.411792) (xy 77.377792 -300.439748)
			(xy 77.33333 -300.460846) (xy 77.286059 -300.474538) (xy 77.237204 -300.48047) (xy 77.188029 -300.478489)
			(xy 77.13981 -300.468645) (xy 77.093794 -300.451193) (xy 77.051173 -300.426586) (xy 77.013052 -300.395461)
			(xy 76.980417 -300.358624) (xy 76.954114 -300.317028) (xy 76.934823 -300.271752) (xy 76.923046 -300.223968)
			(xy 76.919086 -300.174914) (xy 76.580238 -300.174914) (xy 76.579743 -300.199521) (xy 76.571848 -300.248098)
			(xy 76.556264 -300.294779) (xy 76.533393 -300.338356) (xy 76.503828 -300.3777) (xy 76.468335 -300.411792)
			(xy 76.427832 -300.439748) (xy 76.38337 -300.460846) (xy 76.336099 -300.474538) (xy 76.287244 -300.48047)
			(xy 76.238069 -300.478489) (xy 76.18985 -300.468645) (xy 76.143834 -300.451193) (xy 76.101213 -300.426586)
			(xy 76.063092 -300.395461) (xy 76.030457 -300.358624) (xy 76.004154 -300.317028) (xy 75.984863 -300.271752)
			(xy 75.973086 -300.223968) (xy 75.969126 -300.174914) (xy 74.680064 -300.174914) (xy 74.679569 -300.199521)
			(xy 74.671674 -300.248098) (xy 74.65609 -300.294779) (xy 74.633219 -300.338356) (xy 74.603654 -300.3777)
			(xy 74.568161 -300.411792) (xy 74.527658 -300.439748) (xy 74.483196 -300.460846) (xy 74.435925 -300.474538)
			(xy 74.38707 -300.48047) (xy 74.337895 -300.478489) (xy 74.289676 -300.468645) (xy 74.24366 -300.451193)
			(xy 74.201039 -300.426586) (xy 74.162918 -300.395461) (xy 74.130283 -300.358624) (xy 74.10398 -300.317028)
			(xy 74.084689 -300.271752) (xy 74.072912 -300.223968) (xy 74.068952 -300.174914) (xy 73.730104 -300.174914)
			(xy 73.729609 -300.199521) (xy 73.721714 -300.248098) (xy 73.70613 -300.294779) (xy 73.683259 -300.338356)
			(xy 73.653694 -300.3777) (xy 73.618201 -300.411792) (xy 73.577698 -300.439748) (xy 73.533236 -300.460846)
			(xy 73.485965 -300.474538) (xy 73.43711 -300.48047) (xy 73.387935 -300.478489) (xy 73.339716 -300.468645)
			(xy 73.2937 -300.451193) (xy 73.251079 -300.426586) (xy 73.212958 -300.395461) (xy 73.180323 -300.358624)
			(xy 73.15402 -300.317028) (xy 73.134729 -300.271752) (xy 73.122952 -300.223968) (xy 73.118992 -300.174914)
			(xy 72.780144 -300.174914) (xy 72.779649 -300.199521) (xy 72.771754 -300.248098) (xy 72.75617 -300.294779)
			(xy 72.733299 -300.338356) (xy 72.703734 -300.3777) (xy 72.668241 -300.411792) (xy 72.627738 -300.439748)
			(xy 72.583276 -300.460846) (xy 72.536005 -300.474538) (xy 72.48715 -300.48047) (xy 72.437975 -300.478489)
			(xy 72.389756 -300.468645) (xy 72.34374 -300.451193) (xy 72.301119 -300.426586) (xy 72.262998 -300.395461)
			(xy 72.230363 -300.358624) (xy 72.20406 -300.317028) (xy 72.184769 -300.271752) (xy 72.172992 -300.223968)
			(xy 72.169032 -300.174914) (xy 71.830184 -300.174914) (xy 71.829689 -300.199521) (xy 71.821794 -300.248098)
			(xy 71.80621 -300.294779) (xy 71.783339 -300.338356) (xy 71.753774 -300.3777) (xy 71.718281 -300.411792)
			(xy 71.677778 -300.439748) (xy 71.633316 -300.460846) (xy 71.586045 -300.474538) (xy 71.53719 -300.48047)
			(xy 71.488015 -300.478489) (xy 71.439796 -300.468645) (xy 71.39378 -300.451193) (xy 71.351159 -300.426586)
			(xy 71.313038 -300.395461) (xy 71.280403 -300.358624) (xy 71.2541 -300.317028) (xy 71.234809 -300.271752)
			(xy 71.223032 -300.223968) (xy 71.219072 -300.174914) (xy 70.880224 -300.174914) (xy 70.879729 -300.199521)
			(xy 70.871834 -300.248098) (xy 70.85625 -300.294779) (xy 70.833379 -300.338356) (xy 70.803814 -300.3777)
			(xy 70.768321 -300.411792) (xy 70.727818 -300.439748) (xy 70.683356 -300.460846) (xy 70.636085 -300.474538)
			(xy 70.58723 -300.48047) (xy 70.538055 -300.478489) (xy 70.489836 -300.468645) (xy 70.44382 -300.451193)
			(xy 70.401199 -300.426586) (xy 70.363078 -300.395461) (xy 70.330443 -300.358624) (xy 70.30414 -300.317028)
			(xy 70.284849 -300.271752) (xy 70.273072 -300.223968) (xy 70.269112 -300.174914) (xy 69.930264 -300.174914)
			(xy 69.929769 -300.199521) (xy 69.921874 -300.248098) (xy 69.90629 -300.294779) (xy 69.883419 -300.338356)
			(xy 69.853854 -300.3777) (xy 69.818361 -300.411792) (xy 69.777858 -300.439748) (xy 69.733396 -300.460846)
			(xy 69.686125 -300.474538) (xy 69.63727 -300.48047) (xy 69.588095 -300.478489) (xy 69.539876 -300.468645)
			(xy 69.49386 -300.451193) (xy 69.451239 -300.426586) (xy 69.413118 -300.395461) (xy 69.380483 -300.358624)
			(xy 69.35418 -300.317028) (xy 69.334889 -300.271752) (xy 69.323112 -300.223968) (xy 69.319152 -300.174914)
			(xy 68.98005 -300.174914) (xy 68.979555 -300.199521) (xy 68.97166 -300.248098) (xy 68.956076 -300.294779)
			(xy 68.933205 -300.338356) (xy 68.90364 -300.3777) (xy 68.868147 -300.411792) (xy 68.827644 -300.439748)
			(xy 68.783182 -300.460846) (xy 68.735911 -300.474538) (xy 68.687056 -300.48047) (xy 68.637881 -300.478489)
			(xy 68.589662 -300.468645) (xy 68.543646 -300.451193) (xy 68.501025 -300.426586) (xy 68.462904 -300.395461)
			(xy 68.430269 -300.358624) (xy 68.403966 -300.317028) (xy 68.384675 -300.271752) (xy 68.372898 -300.223968)
			(xy 68.368938 -300.174914) (xy 68.03009 -300.174914) (xy 68.029595 -300.199521) (xy 68.0217 -300.248098)
			(xy 68.006116 -300.294779) (xy 67.983245 -300.338356) (xy 67.95368 -300.3777) (xy 67.918187 -300.411792)
			(xy 67.877684 -300.439748) (xy 67.833222 -300.460846) (xy 67.785951 -300.474538) (xy 67.737096 -300.48047)
			(xy 67.687921 -300.478489) (xy 67.639702 -300.468645) (xy 67.593686 -300.451193) (xy 67.551065 -300.426586)
			(xy 67.512944 -300.395461) (xy 67.480309 -300.358624) (xy 67.454006 -300.317028) (xy 67.434715 -300.271752)
			(xy 67.422938 -300.223968) (xy 67.418978 -300.174914) (xy 67.08013 -300.174914) (xy 67.079635 -300.199521)
			(xy 67.07174 -300.248098) (xy 67.056156 -300.294779) (xy 67.033285 -300.338356) (xy 67.00372 -300.3777)
			(xy 66.968227 -300.411792) (xy 66.927724 -300.439748) (xy 66.883262 -300.460846) (xy 66.835991 -300.474538)
			(xy 66.787136 -300.48047) (xy 66.737961 -300.478489) (xy 66.689742 -300.468645) (xy 66.643726 -300.451193)
			(xy 66.601105 -300.426586) (xy 66.562984 -300.395461) (xy 66.530349 -300.358624) (xy 66.504046 -300.317028)
			(xy 66.484755 -300.271752) (xy 66.472978 -300.223968) (xy 66.469018 -300.174914) (xy 66.13017 -300.174914)
			(xy 66.129675 -300.199521) (xy 66.12178 -300.248098) (xy 66.106196 -300.294779) (xy 66.083325 -300.338356)
			(xy 66.05376 -300.3777) (xy 66.018267 -300.411792) (xy 65.977764 -300.439748) (xy 65.933302 -300.460846)
			(xy 65.886031 -300.474538) (xy 65.837176 -300.48047) (xy 65.788001 -300.478489) (xy 65.739782 -300.468645)
			(xy 65.693766 -300.451193) (xy 65.651145 -300.426586) (xy 65.613024 -300.395461) (xy 65.580389 -300.358624)
			(xy 65.554086 -300.317028) (xy 65.534795 -300.271752) (xy 65.523018 -300.223968) (xy 65.519058 -300.174914)
			(xy 65.18021 -300.174914) (xy 65.179715 -300.199521) (xy 65.17182 -300.248098) (xy 65.156236 -300.294779)
			(xy 65.133365 -300.338356) (xy 65.1038 -300.3777) (xy 65.068307 -300.411792) (xy 65.027804 -300.439748)
			(xy 64.983342 -300.460846) (xy 64.936071 -300.474538) (xy 64.887216 -300.48047) (xy 64.838041 -300.478489)
			(xy 64.789822 -300.468645) (xy 64.743806 -300.451193) (xy 64.701185 -300.426586) (xy 64.663064 -300.395461)
			(xy 64.630429 -300.358624) (xy 64.604126 -300.317028) (xy 64.584835 -300.271752) (xy 64.573058 -300.223968)
			(xy 64.569098 -300.174914) (xy 64.23025 -300.174914) (xy 64.229755 -300.199521) (xy 64.22186 -300.248098)
			(xy 64.206276 -300.294779) (xy 64.183405 -300.338356) (xy 64.15384 -300.3777) (xy 64.118347 -300.411792)
			(xy 64.077844 -300.439748) (xy 64.033382 -300.460846) (xy 63.986111 -300.474538) (xy 63.937256 -300.48047)
			(xy 63.888081 -300.478489) (xy 63.839862 -300.468645) (xy 63.793846 -300.451193) (xy 63.751225 -300.426586)
			(xy 63.713104 -300.395461) (xy 63.680469 -300.358624) (xy 63.654166 -300.317028) (xy 63.634875 -300.271752)
			(xy 63.623098 -300.223968) (xy 63.619138 -300.174914) (xy 63.28029 -300.174914) (xy 63.279795 -300.199521)
			(xy 63.2719 -300.248098) (xy 63.256316 -300.294779) (xy 63.233445 -300.338356) (xy 63.20388 -300.3777)
			(xy 63.168387 -300.411792) (xy 63.127884 -300.439748) (xy 63.083422 -300.460846) (xy 63.036151 -300.474538)
			(xy 62.987296 -300.48047) (xy 62.938121 -300.478489) (xy 62.889902 -300.468645) (xy 62.843886 -300.451193)
			(xy 62.801265 -300.426586) (xy 62.763144 -300.395461) (xy 62.730509 -300.358624) (xy 62.704206 -300.317028)
			(xy 62.684915 -300.271752) (xy 62.673138 -300.223968) (xy 62.669178 -300.174914) (xy 62.330076 -300.174914)
			(xy 62.329581 -300.199521) (xy 62.321686 -300.248098) (xy 62.306102 -300.294779) (xy 62.283231 -300.338356)
			(xy 62.253666 -300.3777) (xy 62.218173 -300.411792) (xy 62.17767 -300.439748) (xy 62.133208 -300.460846)
			(xy 62.085937 -300.474538) (xy 62.037082 -300.48047) (xy 61.987907 -300.478489) (xy 61.939688 -300.468645)
			(xy 61.893672 -300.451193) (xy 61.851051 -300.426586) (xy 61.81293 -300.395461) (xy 61.780295 -300.358624)
			(xy 61.753992 -300.317028) (xy 61.734701 -300.271752) (xy 61.722924 -300.223968) (xy 61.718964 -300.174914)
			(xy 61.380116 -300.174914) (xy 61.379621 -300.199521) (xy 61.371726 -300.248098) (xy 61.356142 -300.294779)
			(xy 61.333271 -300.338356) (xy 61.303706 -300.3777) (xy 61.268213 -300.411792) (xy 61.22771 -300.439748)
			(xy 61.183248 -300.460846) (xy 61.135977 -300.474538) (xy 61.087122 -300.48047) (xy 61.037947 -300.478489)
			(xy 60.989728 -300.468645) (xy 60.943712 -300.451193) (xy 60.901091 -300.426586) (xy 60.86297 -300.395461)
			(xy 60.830335 -300.358624) (xy 60.804032 -300.317028) (xy 60.784741 -300.271752) (xy 60.772964 -300.223968)
			(xy 60.769004 -300.174914) (xy 60.430156 -300.174914) (xy 60.429661 -300.199521) (xy 60.421766 -300.248098)
			(xy 60.406182 -300.294779) (xy 60.383311 -300.338356) (xy 60.353746 -300.3777) (xy 60.318253 -300.411792)
			(xy 60.27775 -300.439748) (xy 60.233288 -300.460846) (xy 60.186017 -300.474538) (xy 60.137162 -300.48047)
			(xy 60.087987 -300.478489) (xy 60.039768 -300.468645) (xy 59.993752 -300.451193) (xy 59.951131 -300.426586)
			(xy 59.91301 -300.395461) (xy 59.880375 -300.358624) (xy 59.854072 -300.317028) (xy 59.834781 -300.271752)
			(xy 59.823004 -300.223968) (xy 59.819044 -300.174914) (xy 58.530236 -300.174914) (xy 58.529741 -300.199521)
			(xy 58.521846 -300.248098) (xy 58.506262 -300.294779) (xy 58.483391 -300.338356) (xy 58.453826 -300.3777)
			(xy 58.418333 -300.411792) (xy 58.37783 -300.439748) (xy 58.333368 -300.460846) (xy 58.286097 -300.474538)
			(xy 58.237242 -300.48047) (xy 58.188067 -300.478489) (xy 58.139848 -300.468645) (xy 58.093832 -300.451193)
			(xy 58.051211 -300.426586) (xy 58.01309 -300.395461) (xy 57.980455 -300.358624) (xy 57.954152 -300.317028)
			(xy 57.934861 -300.271752) (xy 57.923084 -300.223968) (xy 57.919124 -300.174914) (xy 57.580276 -300.174914)
			(xy 57.579781 -300.199521) (xy 57.571886 -300.248098) (xy 57.556302 -300.294779) (xy 57.533431 -300.338356)
			(xy 57.503866 -300.3777) (xy 57.468373 -300.411792) (xy 57.42787 -300.439748) (xy 57.383408 -300.460846)
			(xy 57.336137 -300.474538) (xy 57.287282 -300.48047) (xy 57.238107 -300.478489) (xy 57.189888 -300.468645)
			(xy 57.143872 -300.451193) (xy 57.101251 -300.426586) (xy 57.06313 -300.395461) (xy 57.030495 -300.358624)
			(xy 57.004192 -300.317028) (xy 56.984901 -300.271752) (xy 56.973124 -300.223968) (xy 56.969164 -300.174914)
			(xy 56.630062 -300.174914) (xy 56.629567 -300.199521) (xy 56.621672 -300.248098) (xy 56.606088 -300.294779)
			(xy 56.583217 -300.338356) (xy 56.553652 -300.3777) (xy 56.518159 -300.411792) (xy 56.477656 -300.439748)
			(xy 56.433194 -300.460846) (xy 56.385923 -300.474538) (xy 56.337068 -300.48047) (xy 56.287893 -300.478489)
			(xy 56.239674 -300.468645) (xy 56.193658 -300.451193) (xy 56.151037 -300.426586) (xy 56.112916 -300.395461)
			(xy 56.080281 -300.358624) (xy 56.053978 -300.317028) (xy 56.034687 -300.271752) (xy 56.02291 -300.223968)
			(xy 56.01895 -300.174914) (xy 55.680102 -300.174914) (xy 55.679607 -300.199521) (xy 55.671712 -300.248098)
			(xy 55.656128 -300.294779) (xy 55.633257 -300.338356) (xy 55.603692 -300.3777) (xy 55.568199 -300.411792)
			(xy 55.527696 -300.439748) (xy 55.483234 -300.460846) (xy 55.435963 -300.474538) (xy 55.387108 -300.48047)
			(xy 55.337933 -300.478489) (xy 55.289714 -300.468645) (xy 55.243698 -300.451193) (xy 55.201077 -300.426586)
			(xy 55.162956 -300.395461) (xy 55.130321 -300.358624) (xy 55.104018 -300.317028) (xy 55.084727 -300.271752)
			(xy 55.07295 -300.223968) (xy 55.06899 -300.174914) (xy 54.730142 -300.174914) (xy 54.729647 -300.199521)
			(xy 54.721752 -300.248098) (xy 54.706168 -300.294779) (xy 54.683297 -300.338356) (xy 54.653732 -300.3777)
			(xy 54.618239 -300.411792) (xy 54.577736 -300.439748) (xy 54.533274 -300.460846) (xy 54.486003 -300.474538)
			(xy 54.437148 -300.48047) (xy 54.387973 -300.478489) (xy 54.339754 -300.468645) (xy 54.293738 -300.451193)
			(xy 54.251117 -300.426586) (xy 54.212996 -300.395461) (xy 54.180361 -300.358624) (xy 54.154058 -300.317028)
			(xy 54.134767 -300.271752) (xy 54.12299 -300.223968) (xy 54.11903 -300.174914) (xy 53.780182 -300.174914)
			(xy 53.779687 -300.199521) (xy 53.771792 -300.248098) (xy 53.756208 -300.294779) (xy 53.733337 -300.338356)
			(xy 53.703772 -300.3777) (xy 53.668279 -300.411792) (xy 53.627776 -300.439748) (xy 53.583314 -300.460846)
			(xy 53.536043 -300.474538) (xy 53.487188 -300.48047) (xy 53.438013 -300.478489) (xy 53.389794 -300.468645)
			(xy 53.343778 -300.451193) (xy 53.301157 -300.426586) (xy 53.263036 -300.395461) (xy 53.230401 -300.358624)
			(xy 53.204098 -300.317028) (xy 53.184807 -300.271752) (xy 53.17303 -300.223968) (xy 53.16907 -300.174914)
			(xy 52.830222 -300.174914) (xy 52.829727 -300.199521) (xy 52.821832 -300.248098) (xy 52.806248 -300.294779)
			(xy 52.783377 -300.338356) (xy 52.753812 -300.3777) (xy 52.718319 -300.411792) (xy 52.677816 -300.439748)
			(xy 52.633354 -300.460846) (xy 52.586083 -300.474538) (xy 52.537228 -300.48047) (xy 52.488053 -300.478489)
			(xy 52.439834 -300.468645) (xy 52.393818 -300.451193) (xy 52.351197 -300.426586) (xy 52.313076 -300.395461)
			(xy 52.280441 -300.358624) (xy 52.254138 -300.317028) (xy 52.234847 -300.271752) (xy 52.22307 -300.223968)
			(xy 52.21911 -300.174914) (xy 51.880262 -300.174914) (xy 51.879767 -300.199521) (xy 51.871872 -300.248098)
			(xy 51.856288 -300.294779) (xy 51.833417 -300.338356) (xy 51.803852 -300.3777) (xy 51.768359 -300.411792)
			(xy 51.727856 -300.439748) (xy 51.683394 -300.460846) (xy 51.636123 -300.474538) (xy 51.587268 -300.48047)
			(xy 51.538093 -300.478489) (xy 51.489874 -300.468645) (xy 51.443858 -300.451193) (xy 51.401237 -300.426586)
			(xy 51.363116 -300.395461) (xy 51.330481 -300.358624) (xy 51.304178 -300.317028) (xy 51.284887 -300.271752)
			(xy 51.27311 -300.223968) (xy 51.26915 -300.174914) (xy 50.930302 -300.174914) (xy 50.929807 -300.199521)
			(xy 50.921912 -300.248098) (xy 50.906328 -300.294779) (xy 50.883457 -300.338356) (xy 50.853892 -300.3777)
			(xy 50.818399 -300.411792) (xy 50.777896 -300.439748) (xy 50.733434 -300.460846) (xy 50.686163 -300.474538)
			(xy 50.637308 -300.48047) (xy 50.588133 -300.478489) (xy 50.539914 -300.468645) (xy 50.493898 -300.451193)
			(xy 50.451277 -300.426586) (xy 50.413156 -300.395461) (xy 50.380521 -300.358624) (xy 50.354218 -300.317028)
			(xy 50.334927 -300.271752) (xy 50.32315 -300.223968) (xy 50.31919 -300.174914) (xy 49.980088 -300.174914)
			(xy 49.979593 -300.199521) (xy 49.971698 -300.248098) (xy 49.956114 -300.294779) (xy 49.933243 -300.338356)
			(xy 49.903678 -300.3777) (xy 49.868185 -300.411792) (xy 49.827682 -300.439748) (xy 49.78322 -300.460846)
			(xy 49.735949 -300.474538) (xy 49.687094 -300.48047) (xy 49.637919 -300.478489) (xy 49.5897 -300.468645)
			(xy 49.543684 -300.451193) (xy 49.501063 -300.426586) (xy 49.462942 -300.395461) (xy 49.430307 -300.358624)
			(xy 49.404004 -300.317028) (xy 49.384713 -300.271752) (xy 49.372936 -300.223968) (xy 49.368976 -300.174914)
			(xy 49.030128 -300.174914) (xy 49.029633 -300.199521) (xy 49.021738 -300.248098) (xy 49.006154 -300.294779)
			(xy 48.983283 -300.338356) (xy 48.953718 -300.3777) (xy 48.918225 -300.411792) (xy 48.877722 -300.439748)
			(xy 48.83326 -300.460846) (xy 48.785989 -300.474538) (xy 48.737134 -300.48047) (xy 48.687959 -300.478489)
			(xy 48.63974 -300.468645) (xy 48.593724 -300.451193) (xy 48.551103 -300.426586) (xy 48.512982 -300.395461)
			(xy 48.480347 -300.358624) (xy 48.454044 -300.317028) (xy 48.434753 -300.271752) (xy 48.422976 -300.223968)
			(xy 48.419016 -300.174914) (xy 48.080168 -300.174914) (xy 48.079673 -300.199521) (xy 48.071778 -300.248098)
			(xy 48.056194 -300.294779) (xy 48.033323 -300.338356) (xy 48.003758 -300.3777) (xy 47.968265 -300.411792)
			(xy 47.927762 -300.439748) (xy 47.8833 -300.460846) (xy 47.836029 -300.474538) (xy 47.787174 -300.48047)
			(xy 47.737999 -300.478489) (xy 47.68978 -300.468645) (xy 47.643764 -300.451193) (xy 47.601143 -300.426586)
			(xy 47.563022 -300.395461) (xy 47.530387 -300.358624) (xy 47.504084 -300.317028) (xy 47.484793 -300.271752)
			(xy 47.473016 -300.223968) (xy 47.469056 -300.174914) (xy 46.180248 -300.174914) (xy 46.179753 -300.199521)
			(xy 46.171858 -300.248098) (xy 46.156274 -300.294779) (xy 46.133403 -300.338356) (xy 46.103838 -300.3777)
			(xy 46.068345 -300.411792) (xy 46.027842 -300.439748) (xy 45.98338 -300.460846) (xy 45.936109 -300.474538)
			(xy 45.887254 -300.48047) (xy 45.838079 -300.478489) (xy 45.78986 -300.468645) (xy 45.743844 -300.451193)
			(xy 45.701223 -300.426586) (xy 45.663102 -300.395461) (xy 45.630467 -300.358624) (xy 45.604164 -300.317028)
			(xy 45.584873 -300.271752) (xy 45.573096 -300.223968) (xy 45.569136 -300.174914) (xy 45.230288 -300.174914)
			(xy 45.229793 -300.199521) (xy 45.221898 -300.248098) (xy 45.206314 -300.294779) (xy 45.183443 -300.338356)
			(xy 45.153878 -300.3777) (xy 45.118385 -300.411792) (xy 45.077882 -300.439748) (xy 45.03342 -300.460846)
			(xy 44.986149 -300.474538) (xy 44.937294 -300.48047) (xy 44.888119 -300.478489) (xy 44.8399 -300.468645)
			(xy 44.793884 -300.451193) (xy 44.751263 -300.426586) (xy 44.713142 -300.395461) (xy 44.680507 -300.358624)
			(xy 44.654204 -300.317028) (xy 44.634913 -300.271752) (xy 44.623136 -300.223968) (xy 44.619176 -300.174914)
			(xy 44.280074 -300.174914) (xy 44.279579 -300.199521) (xy 44.271684 -300.248098) (xy 44.2561 -300.294779)
			(xy 44.233229 -300.338356) (xy 44.203664 -300.3777) (xy 44.168171 -300.411792) (xy 44.127668 -300.439748)
			(xy 44.083206 -300.460846) (xy 44.035935 -300.474538) (xy 43.98708 -300.48047) (xy 43.937905 -300.478489)
			(xy 43.889686 -300.468645) (xy 43.84367 -300.451193) (xy 43.801049 -300.426586) (xy 43.762928 -300.395461)
			(xy 43.730293 -300.358624) (xy 43.70399 -300.317028) (xy 43.684699 -300.271752) (xy 43.672922 -300.223968)
			(xy 43.668962 -300.174914) (xy 42.380154 -300.174914) (xy 42.379979 -300.189097) (xy 42.377306 -300.217337)
			(xy 42.37482 -300.231302) (xy 42.372534 -300.243748) (xy 42.3799 -300.26737) (xy 42.45737 -300.34484)
			(xy 42.480992 -300.352206) (xy 42.493438 -300.34992) (xy 42.507404 -300.347442) (xy 42.535643 -300.344771)
			(xy 42.549826 -300.344586) (xy 42.574644 -300.345106) (xy 42.623627 -300.35314) (xy 42.670664 -300.368993)
			(xy 42.714517 -300.392247) (xy 42.75403 -300.422289) (xy 42.788162 -300.458327) (xy 42.816015 -300.499413)
			(xy 42.836854 -300.544464) (xy 42.85013 -300.592292) (xy 42.855493 -300.641638) (xy 42.852803 -300.691202)
			(xy 42.84213 -300.739678) (xy 42.823754 -300.785788) (xy 42.798162 -300.828319) (xy 42.766025 -300.866148)
			(xy 42.728193 -300.89828) (xy 42.68566 -300.923869) (xy 42.639547 -300.942239) (xy 42.591071 -300.952907)
			(xy 42.541506 -300.955593) (xy 42.492161 -300.950224) (xy 42.444334 -300.936943) (xy 42.399285 -300.916099)
			(xy 42.358202 -300.888242) (xy 42.322167 -300.854106) (xy 42.29213 -300.81459) (xy 42.268881 -300.770734)
			(xy 42.253033 -300.723695) (xy 42.245003 -300.674712) (xy 42.244518 -300.649894) (xy 42.244693 -300.635711)
			(xy 42.247366 -300.607471) (xy 42.249852 -300.593506) (xy 42.252138 -300.58106) (xy 42.244772 -300.557438)
			(xy 42.167302 -300.479968) (xy 42.14368 -300.472602) (xy 42.131234 -300.474888) (xy 42.117269 -300.477369)
			(xy 42.089029 -300.480038) (xy 42.074846 -300.480222) (xy 42.060663 -300.480039) (xy 42.032423 -300.477371)
			(xy 42.018458 -300.474888) (xy 42.006012 -300.472602) (xy 41.98239 -300.479968) (xy 41.90492 -300.557438)
			(xy 41.897554 -300.58106) (xy 41.89984 -300.593506) (xy 41.902313 -300.607472) (xy 41.904987 -300.635712)
			(xy 41.905174 -300.649894) (xy 41.904652 -300.675149) (xy 41.896339 -300.724971) (xy 41.879938 -300.772745)
			(xy 41.855897 -300.817168) (xy 41.824873 -300.857028) (xy 41.787711 -300.891238) (xy 41.745425 -300.918864)
			(xy 41.699169 -300.939154) (xy 41.650204 -300.951554) (xy 41.599866 -300.955725) (xy 41.549528 -300.951554)
			(xy 41.500563 -300.939154) (xy 41.454307 -300.918864) (xy 41.412021 -300.891238) (xy 41.374859 -300.857028)
			(xy 41.343835 -300.817168) (xy 41.319794 -300.772745) (xy 41.303393 -300.724971) (xy 41.29508 -300.675149)
			(xy 41.294558 -300.649894) (xy 41.294734 -300.635711) (xy 41.297407 -300.607471) (xy 41.299892 -300.593506)
			(xy 41.302178 -300.58106) (xy 41.294812 -300.557438) (xy 41.217342 -300.479968) (xy 41.19372 -300.472602)
			(xy 41.181274 -300.474888) (xy 41.167308 -300.477364) (xy 41.139069 -300.480036) (xy 41.124886 -300.480222)
			(xy 41.110703 -300.480047) (xy 41.082463 -300.477374) (xy 41.068498 -300.474888) (xy 41.056052 -300.472602)
			(xy 41.03243 -300.479968) (xy 40.95496 -300.557438) (xy 40.947594 -300.58106) (xy 40.94988 -300.593506)
			(xy 40.952353 -300.607472) (xy 40.955027 -300.635712) (xy 40.955214 -300.649894) (xy 40.954729 -300.674716)
			(xy 40.946698 -300.723705) (xy 40.930848 -300.77075) (xy 40.907595 -300.81461) (xy 40.877553 -300.854131)
			(xy 40.841513 -300.888271) (xy 40.800424 -300.916131) (xy 40.755369 -300.936976) (xy 40.707536 -300.950257)
			(xy 40.658184 -300.955625) (xy 40.608614 -300.952937) (xy 40.560131 -300.942266) (xy 40.514014 -300.923891)
			(xy 40.471477 -300.898298) (xy 40.433641 -300.866159) (xy 40.401502 -300.828323) (xy 40.375909 -300.785786)
			(xy 40.357534 -300.739669) (xy 40.346863 -300.691186) (xy 40.344175 -300.641616) (xy 40.005087 -300.641616)
			(xy 40.005254 -300.649894) (xy 40.004759 -300.674501) (xy 39.996864 -300.723078) (xy 39.98128 -300.769759)
			(xy 39.958409 -300.813336) (xy 39.928844 -300.85268) (xy 39.893351 -300.886772) (xy 39.852848 -300.914728)
			(xy 39.808386 -300.935826) (xy 39.761115 -300.949518) (xy 39.71226 -300.95545) (xy 39.663085 -300.953469)
			(xy 39.614866 -300.943625) (xy 39.56885 -300.926173) (xy 39.526229 -300.901566) (xy 39.488108 -300.870441)
			(xy 39.455473 -300.833604) (xy 39.42917 -300.792008) (xy 39.409879 -300.746732) (xy 39.398102 -300.698948)
			(xy 39.394142 -300.649894) (xy 39.055294 -300.649894) (xy 39.054799 -300.674501) (xy 39.046904 -300.723078)
			(xy 39.03132 -300.769759) (xy 39.008449 -300.813336) (xy 38.978884 -300.85268) (xy 38.943391 -300.886772)
			(xy 38.902888 -300.914728) (xy 38.858426 -300.935826) (xy 38.811155 -300.949518) (xy 38.7623 -300.95545)
			(xy 38.713125 -300.953469) (xy 38.664906 -300.943625) (xy 38.61889 -300.926173) (xy 38.576269 -300.901566)
			(xy 38.538148 -300.870441) (xy 38.505513 -300.833604) (xy 38.47921 -300.792008) (xy 38.459919 -300.746732)
			(xy 38.448142 -300.698948) (xy 38.444182 -300.649894) (xy 38.10508 -300.649894) (xy 38.104585 -300.674501)
			(xy 38.09669 -300.723078) (xy 38.081106 -300.769759) (xy 38.058235 -300.813336) (xy 38.02867 -300.85268)
			(xy 37.993177 -300.886772) (xy 37.952674 -300.914728) (xy 37.908212 -300.935826) (xy 37.860941 -300.949518)
			(xy 37.812086 -300.95545) (xy 37.762911 -300.953469) (xy 37.714692 -300.943625) (xy 37.668676 -300.926173)
			(xy 37.626055 -300.901566) (xy 37.587934 -300.870441) (xy 37.555299 -300.833604) (xy 37.528996 -300.792008)
			(xy 37.509705 -300.746732) (xy 37.497928 -300.698948) (xy 37.493968 -300.649894) (xy 37.15512 -300.649894)
			(xy 37.154625 -300.674501) (xy 37.14673 -300.723078) (xy 37.131146 -300.769759) (xy 37.108275 -300.813336)
			(xy 37.07871 -300.85268) (xy 37.043217 -300.886772) (xy 37.002714 -300.914728) (xy 36.958252 -300.935826)
			(xy 36.910981 -300.949518) (xy 36.862126 -300.95545) (xy 36.812951 -300.953469) (xy 36.764732 -300.943625)
			(xy 36.718716 -300.926173) (xy 36.676095 -300.901566) (xy 36.637974 -300.870441) (xy 36.605339 -300.833604)
			(xy 36.579036 -300.792008) (xy 36.559745 -300.746732) (xy 36.547968 -300.698948) (xy 36.544008 -300.649894)
			(xy 26.674232 -300.649894) (xy 26.645843 -300.681578) (xy 26.602975 -300.717253) (xy 26.555369 -300.746307)
			(xy 26.50404 -300.768119) (xy 26.450083 -300.782225) (xy 26.394646 -300.788325) (xy 26.338912 -300.786288)
			(xy 26.284069 -300.776158) (xy 26.231285 -300.758151) (xy 26.181685 -300.73265) (xy 26.136327 -300.700199)
			(xy 26.096178 -300.66149) (xy 26.062092 -300.617347) (xy 26.034796 -300.568712) (xy 26.014873 -300.516621)
			(xy 26.002747 -300.462184) (xy 25.998676 -300.406562) (xy 23.376064 -300.406562) (xy 23.38818 -300.443851)
			(xy 23.431082 -300.601424) (xy 23.466321 -300.760885) (xy 23.493816 -300.921862) (xy 23.5135 -301.08398)
			(xy 23.525329 -301.246859) (xy 23.529276 -301.41012) (xy 23.525329 -301.573381) (xy 23.523406 -301.599854)
			(xy 36.544008 -301.599854) (xy 36.547968 -301.5508) (xy 36.559745 -301.503016) (xy 36.579036 -301.45774)
			(xy 36.605339 -301.416144) (xy 36.637974 -301.379307) (xy 36.676095 -301.348182) (xy 36.718716 -301.323575)
			(xy 36.764732 -301.306123) (xy 36.812951 -301.296279) (xy 36.862126 -301.294298) (xy 36.910981 -301.30023)
			(xy 36.958252 -301.313922) (xy 37.002714 -301.33502) (xy 37.043217 -301.362976) (xy 37.07871 -301.397068)
			(xy 37.108275 -301.436412) (xy 37.131146 -301.479989) (xy 37.14673 -301.52667) (xy 37.154625 -301.575247)
			(xy 37.15512 -301.599854) (xy 37.493968 -301.599854) (xy 37.497928 -301.5508) (xy 37.509705 -301.503016)
			(xy 37.528996 -301.45774) (xy 37.555299 -301.416144) (xy 37.587934 -301.379307) (xy 37.626055 -301.348182)
			(xy 37.668676 -301.323575) (xy 37.714692 -301.306123) (xy 37.762911 -301.296279) (xy 37.812086 -301.294298)
			(xy 37.860941 -301.30023) (xy 37.908212 -301.313922) (xy 37.952674 -301.33502) (xy 37.993177 -301.362976)
			(xy 38.02867 -301.397068) (xy 38.058235 -301.436412) (xy 38.081106 -301.479989) (xy 38.09669 -301.52667)
			(xy 38.104585 -301.575247) (xy 38.10508 -301.599854) (xy 38.104585 -301.624461) (xy 38.104406 -301.625562)
			(xy 38.423338 -301.625562) (xy 38.423338 -301.574146) (xy 38.431381 -301.523364) (xy 38.447269 -301.474465)
			(xy 38.470612 -301.428653) (xy 38.500833 -301.387057) (xy 38.537189 -301.350701) (xy 38.578785 -301.32048)
			(xy 38.624597 -301.297137) (xy 38.673496 -301.281249) (xy 38.724278 -301.273206) (xy 38.775694 -301.273206)
			(xy 38.826476 -301.281249) (xy 38.875375 -301.297137) (xy 38.921187 -301.32048) (xy 38.962783 -301.350701)
			(xy 38.999139 -301.387057) (xy 39.02936 -301.428653) (xy 39.052703 -301.474465) (xy 39.068591 -301.523364)
			(xy 39.076634 -301.574146) (xy 39.077138 -301.599854) (xy 39.076634 -301.625562) (xy 39.373298 -301.625562)
			(xy 39.373298 -301.574146) (xy 39.381341 -301.523364) (xy 39.397229 -301.474465) (xy 39.420572 -301.428653)
			(xy 39.450793 -301.387057) (xy 39.487149 -301.350701) (xy 39.528745 -301.32048) (xy 39.574557 -301.297137)
			(xy 39.623456 -301.281249) (xy 39.674238 -301.273206) (xy 39.725654 -301.273206) (xy 39.776436 -301.281249)
			(xy 39.825335 -301.297137) (xy 39.871147 -301.32048) (xy 39.912743 -301.350701) (xy 39.949099 -301.387057)
			(xy 39.97932 -301.428653) (xy 40.002663 -301.474465) (xy 40.018551 -301.523364) (xy 40.026594 -301.574146)
			(xy 40.027098 -301.599854) (xy 40.344102 -301.599854) (xy 40.348062 -301.5508) (xy 40.359839 -301.503016)
			(xy 40.37913 -301.45774) (xy 40.405433 -301.416144) (xy 40.438068 -301.379307) (xy 40.476189 -301.348182)
			(xy 40.51881 -301.323575) (xy 40.564826 -301.306123) (xy 40.613045 -301.296279) (xy 40.66222 -301.294298)
			(xy 40.711075 -301.30023) (xy 40.758346 -301.313922) (xy 40.802808 -301.33502) (xy 40.843311 -301.362976)
			(xy 40.878804 -301.397068) (xy 40.908369 -301.436412) (xy 40.93124 -301.479989) (xy 40.946824 -301.52667)
			(xy 40.954719 -301.575247) (xy 40.955214 -301.599854) (xy 40.954719 -301.624461) (xy 40.95454 -301.625562)
			(xy 41.273218 -301.625562) (xy 41.273218 -301.574146) (xy 41.281261 -301.523364) (xy 41.297149 -301.474465)
			(xy 41.320492 -301.428653) (xy 41.350713 -301.387057) (xy 41.387069 -301.350701) (xy 41.428665 -301.32048)
			(xy 41.474477 -301.297137) (xy 41.523376 -301.281249) (xy 41.574158 -301.273206) (xy 41.625574 -301.273206)
			(xy 41.676356 -301.281249) (xy 41.725255 -301.297137) (xy 41.771067 -301.32048) (xy 41.812663 -301.350701)
			(xy 41.849019 -301.387057) (xy 41.87924 -301.428653) (xy 41.902583 -301.474465) (xy 41.918471 -301.523364)
			(xy 41.926514 -301.574146) (xy 41.927018 -301.599854) (xy 41.926514 -301.625562) (xy 42.223178 -301.625562)
			(xy 42.223178 -301.574146) (xy 42.231221 -301.523364) (xy 42.247109 -301.474465) (xy 42.270452 -301.428653)
			(xy 42.300673 -301.387057) (xy 42.337029 -301.350701) (xy 42.378625 -301.32048) (xy 42.424437 -301.297137)
			(xy 42.473336 -301.281249) (xy 42.524118 -301.273206) (xy 42.575534 -301.273206) (xy 42.626316 -301.281249)
			(xy 42.675215 -301.297137) (xy 42.721027 -301.32048) (xy 42.762623 -301.350701) (xy 42.798979 -301.387057)
			(xy 42.8292 -301.428653) (xy 42.852543 -301.474465) (xy 42.868431 -301.523364) (xy 42.876474 -301.574146)
			(xy 42.876817 -301.591642) (xy 43.194034 -301.591642) (xy 43.199398 -301.542282) (xy 43.212678 -301.49444)
			(xy 43.233522 -301.449377) (xy 43.261382 -301.40828) (xy 43.295525 -301.372232) (xy 43.335049 -301.342183)
			(xy 43.378914 -301.318924) (xy 43.425965 -301.303068) (xy 43.474961 -301.295033) (xy 43.499786 -301.294546)
			(xy 43.513969 -301.294725) (xy 43.542209 -301.297396) (xy 43.556174 -301.29988) (xy 43.56862 -301.302166)
			(xy 43.592242 -301.2948) (xy 43.669712 -301.21733) (xy 43.677078 -301.193708) (xy 43.674792 -301.181262)
			(xy 43.672314 -301.167296) (xy 43.669643 -301.139057) (xy 43.669458 -301.124874) (xy 43.66998 -301.099619)
			(xy 43.678293 -301.049797) (xy 43.694694 -301.002023) (xy 43.718735 -300.9576) (xy 43.749759 -300.91774)
			(xy 43.786921 -300.88353) (xy 43.829207 -300.855904) (xy 43.875463 -300.835614) (xy 43.924428 -300.823214)
			(xy 43.974766 -300.819043) (xy 44.025104 -300.823214) (xy 44.074069 -300.835614) (xy 44.120325 -300.855904)
			(xy 44.162611 -300.88353) (xy 44.199773 -300.91774) (xy 44.230797 -300.9576) (xy 44.254838 -301.002023)
			(xy 44.271239 -301.049797) (xy 44.279552 -301.099619) (xy 44.280074 -301.124874) (xy 44.279894 -301.139057)
			(xy 44.277224 -301.167297) (xy 44.27474 -301.181262) (xy 44.272454 -301.193708) (xy 44.27982 -301.21733)
			(xy 44.35729 -301.2948) (xy 44.380912 -301.302166) (xy 44.393358 -301.29988) (xy 44.407323 -301.297399)
			(xy 44.435563 -301.29473) (xy 44.449746 -301.294546) (xy 44.463993 -301.294708) (xy 44.492361 -301.29738)
			(xy 44.506388 -301.29988) (xy 44.51858 -301.302166) (xy 44.54271 -301.2948) (xy 44.619926 -301.217584)
			(xy 44.627292 -301.193708) (xy 44.625006 -301.181262) (xy 44.622528 -301.167296) (xy 44.619857 -301.139057)
			(xy 44.619672 -301.124874) (xy 44.620194 -301.099619) (xy 44.628507 -301.049797) (xy 44.644908 -301.002023)
			(xy 44.668949 -300.9576) (xy 44.699973 -300.91774) (xy 44.737135 -300.88353) (xy 44.779421 -300.855904)
			(xy 44.825677 -300.835614) (xy 44.874642 -300.823214) (xy 44.92498 -300.819043) (xy 44.975318 -300.823214)
			(xy 45.024283 -300.835614) (xy 45.070539 -300.855904) (xy 45.112825 -300.88353) (xy 45.149987 -300.91774)
			(xy 45.181011 -300.9576) (xy 45.205052 -301.002023) (xy 45.221453 -301.049797) (xy 45.229766 -301.099619)
			(xy 45.230288 -301.124874) (xy 45.230108 -301.139057) (xy 45.227438 -301.167297) (xy 45.224954 -301.181262)
			(xy 45.222668 -301.193708) (xy 45.230034 -301.21733) (xy 45.307504 -301.2948) (xy 45.331126 -301.302166)
			(xy 45.343572 -301.29988) (xy 45.357537 -301.297397) (xy 45.385777 -301.29473) (xy 45.39996 -301.294546)
			(xy 45.424786 -301.295035) (xy 45.473784 -301.303062) (xy 45.520838 -301.31891) (xy 45.564707 -301.342163)
			(xy 45.604237 -301.372207) (xy 45.638385 -301.40825) (xy 45.666252 -301.449344) (xy 45.687102 -301.494405)
			(xy 45.700388 -301.542245) (xy 45.705759 -301.591605) (xy 45.705758 -301.591619) (xy 46.044135 -301.591619)
			(xy 46.049503 -301.542258) (xy 46.062786 -301.494417) (xy 46.083635 -301.449354) (xy 46.1115 -301.408259)
			(xy 46.145646 -301.372213) (xy 46.185174 -301.342167) (xy 46.229043 -301.318911) (xy 46.276096 -301.30306)
			(xy 46.325094 -301.29503) (xy 46.34992 -301.294546) (xy 46.364103 -301.294721) (xy 46.392343 -301.297394)
			(xy 46.406308 -301.29988) (xy 46.420268 -301.302096) (xy 46.448409 -301.299514) (xy 46.474764 -301.289319)
			(xy 46.497316 -301.27229) (xy 46.514337 -301.249732) (xy 46.524523 -301.223373) (xy 46.527094 -301.195232)
			(xy 46.524926 -301.181262) (xy 46.522448 -301.167296) (xy 46.519777 -301.139057) (xy 46.519592 -301.124874)
			(xy 46.520106 -301.100056) (xy 46.52814 -301.051074) (xy 46.543993 -301.004037) (xy 46.567247 -300.960184)
			(xy 46.597288 -300.920671) (xy 46.633327 -300.886538) (xy 46.674412 -300.858686) (xy 46.719462 -300.837847)
			(xy 46.767291 -300.82457) (xy 46.816636 -300.819207) (xy 46.8662 -300.821897) (xy 46.914676 -300.83257)
			(xy 46.960786 -300.850944) (xy 47.003316 -300.876537) (xy 47.041146 -300.908672) (xy 47.073278 -300.946505)
			(xy 47.098867 -300.989037) (xy 47.117238 -301.035149) (xy 47.127907 -301.083626) (xy 47.130142 -301.124874)
			(xy 47.469056 -301.124874) (xy 47.473016 -301.07582) (xy 47.484793 -301.028036) (xy 47.504084 -300.98276)
			(xy 47.530387 -300.941164) (xy 47.563022 -300.904327) (xy 47.601143 -300.873202) (xy 47.643764 -300.848595)
			(xy 47.68978 -300.831143) (xy 47.737999 -300.821299) (xy 47.787174 -300.819318) (xy 47.836029 -300.82525)
			(xy 47.8833 -300.838942) (xy 47.927762 -300.86004) (xy 47.968265 -300.887996) (xy 48.003758 -300.922088)
			(xy 48.033323 -300.961432) (xy 48.056194 -301.005009) (xy 48.071778 -301.05169) (xy 48.079673 -301.100267)
			(xy 48.080168 -301.124874) (xy 48.419016 -301.124874) (xy 48.422976 -301.07582) (xy 48.434753 -301.028036)
			(xy 48.454044 -300.98276) (xy 48.480347 -300.941164) (xy 48.512982 -300.904327) (xy 48.551103 -300.873202)
			(xy 48.593724 -300.848595) (xy 48.63974 -300.831143) (xy 48.687959 -300.821299) (xy 48.737134 -300.819318)
			(xy 48.785989 -300.82525) (xy 48.83326 -300.838942) (xy 48.877722 -300.86004) (xy 48.918225 -300.887996)
			(xy 48.953718 -300.922088) (xy 48.983283 -300.961432) (xy 49.006154 -301.005009) (xy 49.021738 -301.05169)
			(xy 49.029633 -301.100267) (xy 49.030128 -301.124874) (xy 49.368976 -301.124874) (xy 49.372936 -301.07582)
			(xy 49.384713 -301.028036) (xy 49.404004 -300.98276) (xy 49.430307 -300.941164) (xy 49.462942 -300.904327)
			(xy 49.501063 -300.873202) (xy 49.543684 -300.848595) (xy 49.5897 -300.831143) (xy 49.637919 -300.821299)
			(xy 49.687094 -300.819318) (xy 49.735949 -300.82525) (xy 49.78322 -300.838942) (xy 49.827682 -300.86004)
			(xy 49.868185 -300.887996) (xy 49.903678 -300.922088) (xy 49.933243 -300.961432) (xy 49.956114 -301.005009)
			(xy 49.971698 -301.05169) (xy 49.979593 -301.100267) (xy 49.980088 -301.124874) (xy 50.31919 -301.124874)
			(xy 50.32315 -301.07582) (xy 50.334927 -301.028036) (xy 50.354218 -300.98276) (xy 50.380521 -300.941164)
			(xy 50.413156 -300.904327) (xy 50.451277 -300.873202) (xy 50.493898 -300.848595) (xy 50.539914 -300.831143)
			(xy 50.588133 -300.821299) (xy 50.637308 -300.819318) (xy 50.686163 -300.82525) (xy 50.733434 -300.838942)
			(xy 50.777896 -300.86004) (xy 50.818399 -300.887996) (xy 50.853892 -300.922088) (xy 50.883457 -300.961432)
			(xy 50.906328 -301.005009) (xy 50.921912 -301.05169) (xy 50.929807 -301.100267) (xy 50.930302 -301.124874)
			(xy 51.26915 -301.124874) (xy 51.27311 -301.07582) (xy 51.284887 -301.028036) (xy 51.304178 -300.98276)
			(xy 51.330481 -300.941164) (xy 51.363116 -300.904327) (xy 51.401237 -300.873202) (xy 51.443858 -300.848595)
			(xy 51.489874 -300.831143) (xy 51.538093 -300.821299) (xy 51.587268 -300.819318) (xy 51.636123 -300.82525)
			(xy 51.683394 -300.838942) (xy 51.727856 -300.86004) (xy 51.768359 -300.887996) (xy 51.803852 -300.922088)
			(xy 51.833417 -300.961432) (xy 51.856288 -301.005009) (xy 51.871872 -301.05169) (xy 51.879767 -301.100267)
			(xy 51.880262 -301.124874) (xy 52.21911 -301.124874) (xy 52.22307 -301.07582) (xy 52.234847 -301.028036)
			(xy 52.254138 -300.98276) (xy 52.280441 -300.941164) (xy 52.313076 -300.904327) (xy 52.351197 -300.873202)
			(xy 52.393818 -300.848595) (xy 52.439834 -300.831143) (xy 52.488053 -300.821299) (xy 52.537228 -300.819318)
			(xy 52.586083 -300.82525) (xy 52.633354 -300.838942) (xy 52.677816 -300.86004) (xy 52.718319 -300.887996)
			(xy 52.753812 -300.922088) (xy 52.783377 -300.961432) (xy 52.806248 -301.005009) (xy 52.821832 -301.05169)
			(xy 52.829727 -301.100267) (xy 52.830222 -301.124874) (xy 53.16907 -301.124874) (xy 53.17303 -301.07582)
			(xy 53.184807 -301.028036) (xy 53.204098 -300.98276) (xy 53.230401 -300.941164) (xy 53.263036 -300.904327)
			(xy 53.301157 -300.873202) (xy 53.343778 -300.848595) (xy 53.389794 -300.831143) (xy 53.438013 -300.821299)
			(xy 53.487188 -300.819318) (xy 53.536043 -300.82525) (xy 53.583314 -300.838942) (xy 53.627776 -300.86004)
			(xy 53.668279 -300.887996) (xy 53.703772 -300.922088) (xy 53.733337 -300.961432) (xy 53.756208 -301.005009)
			(xy 53.771792 -301.05169) (xy 53.779687 -301.100267) (xy 53.780182 -301.124874) (xy 54.11903 -301.124874)
			(xy 54.12299 -301.07582) (xy 54.134767 -301.028036) (xy 54.154058 -300.98276) (xy 54.180361 -300.941164)
			(xy 54.212996 -300.904327) (xy 54.251117 -300.873202) (xy 54.293738 -300.848595) (xy 54.339754 -300.831143)
			(xy 54.387973 -300.821299) (xy 54.437148 -300.819318) (xy 54.486003 -300.82525) (xy 54.533274 -300.838942)
			(xy 54.577736 -300.86004) (xy 54.618239 -300.887996) (xy 54.653732 -300.922088) (xy 54.683297 -300.961432)
			(xy 54.706168 -301.005009) (xy 54.721752 -301.05169) (xy 54.729647 -301.100267) (xy 54.730142 -301.124874)
			(xy 55.06899 -301.124874) (xy 55.07295 -301.07582) (xy 55.084727 -301.028036) (xy 55.104018 -300.98276)
			(xy 55.130321 -300.941164) (xy 55.162956 -300.904327) (xy 55.201077 -300.873202) (xy 55.243698 -300.848595)
			(xy 55.289714 -300.831143) (xy 55.337933 -300.821299) (xy 55.387108 -300.819318) (xy 55.435963 -300.82525)
			(xy 55.483234 -300.838942) (xy 55.527696 -300.86004) (xy 55.568199 -300.887996) (xy 55.603692 -300.922088)
			(xy 55.633257 -300.961432) (xy 55.656128 -301.005009) (xy 55.671712 -301.05169) (xy 55.679607 -301.100267)
			(xy 55.680102 -301.124874) (xy 56.01895 -301.124874) (xy 56.02291 -301.07582) (xy 56.034687 -301.028036)
			(xy 56.053978 -300.98276) (xy 56.080281 -300.941164) (xy 56.112916 -300.904327) (xy 56.151037 -300.873202)
			(xy 56.193658 -300.848595) (xy 56.239674 -300.831143) (xy 56.287893 -300.821299) (xy 56.337068 -300.819318)
			(xy 56.385923 -300.82525) (xy 56.433194 -300.838942) (xy 56.477656 -300.86004) (xy 56.518159 -300.887996)
			(xy 56.553652 -300.922088) (xy 56.583217 -300.961432) (xy 56.606088 -301.005009) (xy 56.621672 -301.05169)
			(xy 56.629567 -301.100267) (xy 56.630062 -301.124874) (xy 56.969164 -301.124874) (xy 56.973124 -301.07582)
			(xy 56.984901 -301.028036) (xy 57.004192 -300.98276) (xy 57.030495 -300.941164) (xy 57.06313 -300.904327)
			(xy 57.101251 -300.873202) (xy 57.143872 -300.848595) (xy 57.189888 -300.831143) (xy 57.238107 -300.821299)
			(xy 57.287282 -300.819318) (xy 57.336137 -300.82525) (xy 57.383408 -300.838942) (xy 57.42787 -300.86004)
			(xy 57.468373 -300.887996) (xy 57.503866 -300.922088) (xy 57.533431 -300.961432) (xy 57.556302 -301.005009)
			(xy 57.571886 -301.05169) (xy 57.579781 -301.100267) (xy 57.580276 -301.124874) (xy 57.919124 -301.124874)
			(xy 57.923084 -301.07582) (xy 57.934861 -301.028036) (xy 57.954152 -300.98276) (xy 57.980455 -300.941164)
			(xy 58.01309 -300.904327) (xy 58.051211 -300.873202) (xy 58.093832 -300.848595) (xy 58.139848 -300.831143)
			(xy 58.188067 -300.821299) (xy 58.237242 -300.819318) (xy 58.286097 -300.82525) (xy 58.333368 -300.838942)
			(xy 58.37783 -300.86004) (xy 58.418333 -300.887996) (xy 58.453826 -300.922088) (xy 58.483391 -300.961432)
			(xy 58.506262 -301.005009) (xy 58.521846 -301.05169) (xy 58.529741 -301.100267) (xy 58.530236 -301.124874)
			(xy 59.819044 -301.124874) (xy 59.823004 -301.07582) (xy 59.834781 -301.028036) (xy 59.854072 -300.98276)
			(xy 59.880375 -300.941164) (xy 59.91301 -300.904327) (xy 59.951131 -300.873202) (xy 59.993752 -300.848595)
			(xy 60.039768 -300.831143) (xy 60.087987 -300.821299) (xy 60.137162 -300.819318) (xy 60.186017 -300.82525)
			(xy 60.233288 -300.838942) (xy 60.27775 -300.86004) (xy 60.318253 -300.887996) (xy 60.353746 -300.922088)
			(xy 60.383311 -300.961432) (xy 60.406182 -301.005009) (xy 60.421766 -301.05169) (xy 60.429661 -301.100267)
			(xy 60.430156 -301.124874) (xy 60.769004 -301.124874) (xy 60.772964 -301.07582) (xy 60.784741 -301.028036)
			(xy 60.804032 -300.98276) (xy 60.830335 -300.941164) (xy 60.86297 -300.904327) (xy 60.901091 -300.873202)
			(xy 60.943712 -300.848595) (xy 60.989728 -300.831143) (xy 61.037947 -300.821299) (xy 61.087122 -300.819318)
			(xy 61.135977 -300.82525) (xy 61.183248 -300.838942) (xy 61.22771 -300.86004) (xy 61.268213 -300.887996)
			(xy 61.303706 -300.922088) (xy 61.333271 -300.961432) (xy 61.356142 -301.005009) (xy 61.371726 -301.05169)
			(xy 61.379621 -301.100267) (xy 61.380116 -301.124874) (xy 61.718964 -301.124874) (xy 61.722924 -301.07582)
			(xy 61.734701 -301.028036) (xy 61.753992 -300.98276) (xy 61.780295 -300.941164) (xy 61.81293 -300.904327)
			(xy 61.851051 -300.873202) (xy 61.893672 -300.848595) (xy 61.939688 -300.831143) (xy 61.987907 -300.821299)
			(xy 62.037082 -300.819318) (xy 62.085937 -300.82525) (xy 62.133208 -300.838942) (xy 62.17767 -300.86004)
			(xy 62.218173 -300.887996) (xy 62.253666 -300.922088) (xy 62.283231 -300.961432) (xy 62.306102 -301.005009)
			(xy 62.321686 -301.05169) (xy 62.329581 -301.100267) (xy 62.330076 -301.124874) (xy 62.669178 -301.124874)
			(xy 62.673138 -301.07582) (xy 62.684915 -301.028036) (xy 62.704206 -300.98276) (xy 62.730509 -300.941164)
			(xy 62.763144 -300.904327) (xy 62.801265 -300.873202) (xy 62.843886 -300.848595) (xy 62.889902 -300.831143)
			(xy 62.938121 -300.821299) (xy 62.987296 -300.819318) (xy 63.036151 -300.82525) (xy 63.083422 -300.838942)
			(xy 63.127884 -300.86004) (xy 63.168387 -300.887996) (xy 63.20388 -300.922088) (xy 63.233445 -300.961432)
			(xy 63.256316 -301.005009) (xy 63.2719 -301.05169) (xy 63.279795 -301.100267) (xy 63.28029 -301.124874)
			(xy 63.619138 -301.124874) (xy 63.623098 -301.07582) (xy 63.634875 -301.028036) (xy 63.654166 -300.98276)
			(xy 63.680469 -300.941164) (xy 63.713104 -300.904327) (xy 63.751225 -300.873202) (xy 63.793846 -300.848595)
			(xy 63.839862 -300.831143) (xy 63.888081 -300.821299) (xy 63.937256 -300.819318) (xy 63.986111 -300.82525)
			(xy 64.033382 -300.838942) (xy 64.077844 -300.86004) (xy 64.118347 -300.887996) (xy 64.15384 -300.922088)
			(xy 64.183405 -300.961432) (xy 64.206276 -301.005009) (xy 64.22186 -301.05169) (xy 64.229755 -301.100267)
			(xy 64.23025 -301.124874) (xy 64.569098 -301.124874) (xy 64.573058 -301.07582) (xy 64.584835 -301.028036)
			(xy 64.604126 -300.98276) (xy 64.630429 -300.941164) (xy 64.663064 -300.904327) (xy 64.701185 -300.873202)
			(xy 64.743806 -300.848595) (xy 64.789822 -300.831143) (xy 64.838041 -300.821299) (xy 64.887216 -300.819318)
			(xy 64.936071 -300.82525) (xy 64.983342 -300.838942) (xy 65.027804 -300.86004) (xy 65.068307 -300.887996)
			(xy 65.1038 -300.922088) (xy 65.133365 -300.961432) (xy 65.156236 -301.005009) (xy 65.17182 -301.05169)
			(xy 65.179715 -301.100267) (xy 65.18021 -301.124874) (xy 65.519058 -301.124874) (xy 65.523018 -301.07582)
			(xy 65.534795 -301.028036) (xy 65.554086 -300.98276) (xy 65.580389 -300.941164) (xy 65.613024 -300.904327)
			(xy 65.651145 -300.873202) (xy 65.693766 -300.848595) (xy 65.739782 -300.831143) (xy 65.788001 -300.821299)
			(xy 65.837176 -300.819318) (xy 65.886031 -300.82525) (xy 65.933302 -300.838942) (xy 65.977764 -300.86004)
			(xy 66.018267 -300.887996) (xy 66.05376 -300.922088) (xy 66.083325 -300.961432) (xy 66.106196 -301.005009)
			(xy 66.12178 -301.05169) (xy 66.129675 -301.100267) (xy 66.13017 -301.124874) (xy 66.469018 -301.124874)
			(xy 66.472978 -301.07582) (xy 66.484755 -301.028036) (xy 66.504046 -300.98276) (xy 66.530349 -300.941164)
			(xy 66.562984 -300.904327) (xy 66.601105 -300.873202) (xy 66.643726 -300.848595) (xy 66.689742 -300.831143)
			(xy 66.737961 -300.821299) (xy 66.787136 -300.819318) (xy 66.835991 -300.82525) (xy 66.883262 -300.838942)
			(xy 66.927724 -300.86004) (xy 66.968227 -300.887996) (xy 67.00372 -300.922088) (xy 67.033285 -300.961432)
			(xy 67.056156 -301.005009) (xy 67.07174 -301.05169) (xy 67.079635 -301.100267) (xy 67.08013 -301.124874)
			(xy 67.418978 -301.124874) (xy 67.422938 -301.07582) (xy 67.434715 -301.028036) (xy 67.454006 -300.98276)
			(xy 67.480309 -300.941164) (xy 67.512944 -300.904327) (xy 67.551065 -300.873202) (xy 67.593686 -300.848595)
			(xy 67.639702 -300.831143) (xy 67.687921 -300.821299) (xy 67.737096 -300.819318) (xy 67.785951 -300.82525)
			(xy 67.833222 -300.838942) (xy 67.877684 -300.86004) (xy 67.918187 -300.887996) (xy 67.95368 -300.922088)
			(xy 67.983245 -300.961432) (xy 68.006116 -301.005009) (xy 68.0217 -301.05169) (xy 68.029595 -301.100267)
			(xy 68.03009 -301.124874) (xy 68.368938 -301.124874) (xy 68.372898 -301.07582) (xy 68.384675 -301.028036)
			(xy 68.403966 -300.98276) (xy 68.430269 -300.941164) (xy 68.462904 -300.904327) (xy 68.501025 -300.873202)
			(xy 68.543646 -300.848595) (xy 68.589662 -300.831143) (xy 68.637881 -300.821299) (xy 68.687056 -300.819318)
			(xy 68.735911 -300.82525) (xy 68.783182 -300.838942) (xy 68.827644 -300.86004) (xy 68.868147 -300.887996)
			(xy 68.90364 -300.922088) (xy 68.933205 -300.961432) (xy 68.956076 -301.005009) (xy 68.97166 -301.05169)
			(xy 68.979555 -301.100267) (xy 68.98005 -301.124874) (xy 69.319152 -301.124874) (xy 69.323112 -301.07582)
			(xy 69.334889 -301.028036) (xy 69.35418 -300.98276) (xy 69.380483 -300.941164) (xy 69.413118 -300.904327)
			(xy 69.451239 -300.873202) (xy 69.49386 -300.848595) (xy 69.539876 -300.831143) (xy 69.588095 -300.821299)
			(xy 69.63727 -300.819318) (xy 69.686125 -300.82525) (xy 69.733396 -300.838942) (xy 69.777858 -300.86004)
			(xy 69.818361 -300.887996) (xy 69.853854 -300.922088) (xy 69.883419 -300.961432) (xy 69.90629 -301.005009)
			(xy 69.921874 -301.05169) (xy 69.929769 -301.100267) (xy 69.930264 -301.124874) (xy 70.269112 -301.124874)
			(xy 70.273072 -301.07582) (xy 70.284849 -301.028036) (xy 70.30414 -300.98276) (xy 70.330443 -300.941164)
			(xy 70.363078 -300.904327) (xy 70.401199 -300.873202) (xy 70.44382 -300.848595) (xy 70.489836 -300.831143)
			(xy 70.538055 -300.821299) (xy 70.58723 -300.819318) (xy 70.636085 -300.82525) (xy 70.683356 -300.838942)
			(xy 70.727818 -300.86004) (xy 70.768321 -300.887996) (xy 70.803814 -300.922088) (xy 70.833379 -300.961432)
			(xy 70.85625 -301.005009) (xy 70.871834 -301.05169) (xy 70.879729 -301.100267) (xy 70.880224 -301.124874)
			(xy 71.219072 -301.124874) (xy 71.223032 -301.07582) (xy 71.234809 -301.028036) (xy 71.2541 -300.98276)
			(xy 71.280403 -300.941164) (xy 71.313038 -300.904327) (xy 71.351159 -300.873202) (xy 71.39378 -300.848595)
			(xy 71.439796 -300.831143) (xy 71.488015 -300.821299) (xy 71.53719 -300.819318) (xy 71.586045 -300.82525)
			(xy 71.633316 -300.838942) (xy 71.677778 -300.86004) (xy 71.718281 -300.887996) (xy 71.753774 -300.922088)
			(xy 71.783339 -300.961432) (xy 71.80621 -301.005009) (xy 71.821794 -301.05169) (xy 71.829689 -301.100267)
			(xy 71.830184 -301.124874) (xy 72.169032 -301.124874) (xy 72.172992 -301.07582) (xy 72.184769 -301.028036)
			(xy 72.20406 -300.98276) (xy 72.230363 -300.941164) (xy 72.262998 -300.904327) (xy 72.301119 -300.873202)
			(xy 72.34374 -300.848595) (xy 72.389756 -300.831143) (xy 72.437975 -300.821299) (xy 72.48715 -300.819318)
			(xy 72.536005 -300.82525) (xy 72.583276 -300.838942) (xy 72.627738 -300.86004) (xy 72.668241 -300.887996)
			(xy 72.703734 -300.922088) (xy 72.733299 -300.961432) (xy 72.75617 -301.005009) (xy 72.771754 -301.05169)
			(xy 72.779649 -301.100267) (xy 72.780144 -301.124874) (xy 73.118992 -301.124874) (xy 73.122952 -301.07582)
			(xy 73.134729 -301.028036) (xy 73.15402 -300.98276) (xy 73.180323 -300.941164) (xy 73.212958 -300.904327)
			(xy 73.251079 -300.873202) (xy 73.2937 -300.848595) (xy 73.339716 -300.831143) (xy 73.387935 -300.821299)
			(xy 73.43711 -300.819318) (xy 73.485965 -300.82525) (xy 73.533236 -300.838942) (xy 73.577698 -300.86004)
			(xy 73.618201 -300.887996) (xy 73.653694 -300.922088) (xy 73.683259 -300.961432) (xy 73.70613 -301.005009)
			(xy 73.721714 -301.05169) (xy 73.729609 -301.100267) (xy 73.730104 -301.124874) (xy 73.729609 -301.149481)
			(xy 73.721714 -301.198058) (xy 73.70613 -301.244739) (xy 73.683259 -301.288316) (xy 73.653694 -301.32766)
			(xy 73.618201 -301.361752) (xy 73.577698 -301.389708) (xy 73.533236 -301.410806) (xy 73.485965 -301.424498)
			(xy 73.43711 -301.43043) (xy 73.387935 -301.428449) (xy 73.339716 -301.418605) (xy 73.2937 -301.401153)
			(xy 73.251079 -301.376546) (xy 73.212958 -301.345421) (xy 73.180323 -301.308584) (xy 73.15402 -301.266988)
			(xy 73.134729 -301.221712) (xy 73.122952 -301.173928) (xy 73.118992 -301.124874) (xy 72.780144 -301.124874)
			(xy 72.779649 -301.149481) (xy 72.771754 -301.198058) (xy 72.75617 -301.244739) (xy 72.733299 -301.288316)
			(xy 72.703734 -301.32766) (xy 72.668241 -301.361752) (xy 72.627738 -301.389708) (xy 72.583276 -301.410806)
			(xy 72.536005 -301.424498) (xy 72.48715 -301.43043) (xy 72.437975 -301.428449) (xy 72.389756 -301.418605)
			(xy 72.34374 -301.401153) (xy 72.301119 -301.376546) (xy 72.262998 -301.345421) (xy 72.230363 -301.308584)
			(xy 72.20406 -301.266988) (xy 72.184769 -301.221712) (xy 72.172992 -301.173928) (xy 72.169032 -301.124874)
			(xy 71.830184 -301.124874) (xy 71.829689 -301.149481) (xy 71.821794 -301.198058) (xy 71.80621 -301.244739)
			(xy 71.783339 -301.288316) (xy 71.753774 -301.32766) (xy 71.718281 -301.361752) (xy 71.677778 -301.389708)
			(xy 71.633316 -301.410806) (xy 71.586045 -301.424498) (xy 71.53719 -301.43043) (xy 71.488015 -301.428449)
			(xy 71.439796 -301.418605) (xy 71.39378 -301.401153) (xy 71.351159 -301.376546) (xy 71.313038 -301.345421)
			(xy 71.280403 -301.308584) (xy 71.2541 -301.266988) (xy 71.234809 -301.221712) (xy 71.223032 -301.173928)
			(xy 71.219072 -301.124874) (xy 70.880224 -301.124874) (xy 70.879729 -301.149481) (xy 70.871834 -301.198058)
			(xy 70.85625 -301.244739) (xy 70.833379 -301.288316) (xy 70.803814 -301.32766) (xy 70.768321 -301.361752)
			(xy 70.727818 -301.389708) (xy 70.683356 -301.410806) (xy 70.636085 -301.424498) (xy 70.58723 -301.43043)
			(xy 70.538055 -301.428449) (xy 70.489836 -301.418605) (xy 70.44382 -301.401153) (xy 70.401199 -301.376546)
			(xy 70.363078 -301.345421) (xy 70.330443 -301.308584) (xy 70.30414 -301.266988) (xy 70.284849 -301.221712)
			(xy 70.273072 -301.173928) (xy 70.269112 -301.124874) (xy 69.930264 -301.124874) (xy 69.929769 -301.149481)
			(xy 69.921874 -301.198058) (xy 69.90629 -301.244739) (xy 69.883419 -301.288316) (xy 69.853854 -301.32766)
			(xy 69.818361 -301.361752) (xy 69.777858 -301.389708) (xy 69.733396 -301.410806) (xy 69.686125 -301.424498)
			(xy 69.63727 -301.43043) (xy 69.588095 -301.428449) (xy 69.539876 -301.418605) (xy 69.49386 -301.401153)
			(xy 69.451239 -301.376546) (xy 69.413118 -301.345421) (xy 69.380483 -301.308584) (xy 69.35418 -301.266988)
			(xy 69.334889 -301.221712) (xy 69.323112 -301.173928) (xy 69.319152 -301.124874) (xy 68.98005 -301.124874)
			(xy 68.979555 -301.149481) (xy 68.97166 -301.198058) (xy 68.956076 -301.244739) (xy 68.933205 -301.288316)
			(xy 68.90364 -301.32766) (xy 68.868147 -301.361752) (xy 68.827644 -301.389708) (xy 68.783182 -301.410806)
			(xy 68.735911 -301.424498) (xy 68.687056 -301.43043) (xy 68.637881 -301.428449) (xy 68.589662 -301.418605)
			(xy 68.543646 -301.401153) (xy 68.501025 -301.376546) (xy 68.462904 -301.345421) (xy 68.430269 -301.308584)
			(xy 68.403966 -301.266988) (xy 68.384675 -301.221712) (xy 68.372898 -301.173928) (xy 68.368938 -301.124874)
			(xy 68.03009 -301.124874) (xy 68.029595 -301.149481) (xy 68.0217 -301.198058) (xy 68.006116 -301.244739)
			(xy 67.983245 -301.288316) (xy 67.95368 -301.32766) (xy 67.918187 -301.361752) (xy 67.877684 -301.389708)
			(xy 67.833222 -301.410806) (xy 67.785951 -301.424498) (xy 67.737096 -301.43043) (xy 67.687921 -301.428449)
			(xy 67.639702 -301.418605) (xy 67.593686 -301.401153) (xy 67.551065 -301.376546) (xy 67.512944 -301.345421)
			(xy 67.480309 -301.308584) (xy 67.454006 -301.266988) (xy 67.434715 -301.221712) (xy 67.422938 -301.173928)
			(xy 67.418978 -301.124874) (xy 67.08013 -301.124874) (xy 67.079635 -301.149481) (xy 67.07174 -301.198058)
			(xy 67.056156 -301.244739) (xy 67.033285 -301.288316) (xy 67.00372 -301.32766) (xy 66.968227 -301.361752)
			(xy 66.927724 -301.389708) (xy 66.883262 -301.410806) (xy 66.835991 -301.424498) (xy 66.787136 -301.43043)
			(xy 66.737961 -301.428449) (xy 66.689742 -301.418605) (xy 66.643726 -301.401153) (xy 66.601105 -301.376546)
			(xy 66.562984 -301.345421) (xy 66.530349 -301.308584) (xy 66.504046 -301.266988) (xy 66.484755 -301.221712)
			(xy 66.472978 -301.173928) (xy 66.469018 -301.124874) (xy 66.13017 -301.124874) (xy 66.129675 -301.149481)
			(xy 66.12178 -301.198058) (xy 66.106196 -301.244739) (xy 66.083325 -301.288316) (xy 66.05376 -301.32766)
			(xy 66.018267 -301.361752) (xy 65.977764 -301.389708) (xy 65.933302 -301.410806) (xy 65.886031 -301.424498)
			(xy 65.837176 -301.43043) (xy 65.788001 -301.428449) (xy 65.739782 -301.418605) (xy 65.693766 -301.401153)
			(xy 65.651145 -301.376546) (xy 65.613024 -301.345421) (xy 65.580389 -301.308584) (xy 65.554086 -301.266988)
			(xy 65.534795 -301.221712) (xy 65.523018 -301.173928) (xy 65.519058 -301.124874) (xy 65.18021 -301.124874)
			(xy 65.179715 -301.149481) (xy 65.17182 -301.198058) (xy 65.156236 -301.244739) (xy 65.133365 -301.288316)
			(xy 65.1038 -301.32766) (xy 65.068307 -301.361752) (xy 65.027804 -301.389708) (xy 64.983342 -301.410806)
			(xy 64.936071 -301.424498) (xy 64.887216 -301.43043) (xy 64.838041 -301.428449) (xy 64.789822 -301.418605)
			(xy 64.743806 -301.401153) (xy 64.701185 -301.376546) (xy 64.663064 -301.345421) (xy 64.630429 -301.308584)
			(xy 64.604126 -301.266988) (xy 64.584835 -301.221712) (xy 64.573058 -301.173928) (xy 64.569098 -301.124874)
			(xy 64.23025 -301.124874) (xy 64.229755 -301.149481) (xy 64.22186 -301.198058) (xy 64.206276 -301.244739)
			(xy 64.183405 -301.288316) (xy 64.15384 -301.32766) (xy 64.118347 -301.361752) (xy 64.077844 -301.389708)
			(xy 64.033382 -301.410806) (xy 63.986111 -301.424498) (xy 63.937256 -301.43043) (xy 63.888081 -301.428449)
			(xy 63.839862 -301.418605) (xy 63.793846 -301.401153) (xy 63.751225 -301.376546) (xy 63.713104 -301.345421)
			(xy 63.680469 -301.308584) (xy 63.654166 -301.266988) (xy 63.634875 -301.221712) (xy 63.623098 -301.173928)
			(xy 63.619138 -301.124874) (xy 63.28029 -301.124874) (xy 63.279795 -301.149481) (xy 63.2719 -301.198058)
			(xy 63.256316 -301.244739) (xy 63.233445 -301.288316) (xy 63.20388 -301.32766) (xy 63.168387 -301.361752)
			(xy 63.127884 -301.389708) (xy 63.083422 -301.410806) (xy 63.036151 -301.424498) (xy 62.987296 -301.43043)
			(xy 62.938121 -301.428449) (xy 62.889902 -301.418605) (xy 62.843886 -301.401153) (xy 62.801265 -301.376546)
			(xy 62.763144 -301.345421) (xy 62.730509 -301.308584) (xy 62.704206 -301.266988) (xy 62.684915 -301.221712)
			(xy 62.673138 -301.173928) (xy 62.669178 -301.124874) (xy 62.330076 -301.124874) (xy 62.329581 -301.149481)
			(xy 62.321686 -301.198058) (xy 62.306102 -301.244739) (xy 62.283231 -301.288316) (xy 62.253666 -301.32766)
			(xy 62.218173 -301.361752) (xy 62.17767 -301.389708) (xy 62.133208 -301.410806) (xy 62.085937 -301.424498)
			(xy 62.037082 -301.43043) (xy 61.987907 -301.428449) (xy 61.939688 -301.418605) (xy 61.893672 -301.401153)
			(xy 61.851051 -301.376546) (xy 61.81293 -301.345421) (xy 61.780295 -301.308584) (xy 61.753992 -301.266988)
			(xy 61.734701 -301.221712) (xy 61.722924 -301.173928) (xy 61.718964 -301.124874) (xy 61.380116 -301.124874)
			(xy 61.379621 -301.149481) (xy 61.371726 -301.198058) (xy 61.356142 -301.244739) (xy 61.333271 -301.288316)
			(xy 61.303706 -301.32766) (xy 61.268213 -301.361752) (xy 61.22771 -301.389708) (xy 61.183248 -301.410806)
			(xy 61.135977 -301.424498) (xy 61.087122 -301.43043) (xy 61.037947 -301.428449) (xy 60.989728 -301.418605)
			(xy 60.943712 -301.401153) (xy 60.901091 -301.376546) (xy 60.86297 -301.345421) (xy 60.830335 -301.308584)
			(xy 60.804032 -301.266988) (xy 60.784741 -301.221712) (xy 60.772964 -301.173928) (xy 60.769004 -301.124874)
			(xy 60.430156 -301.124874) (xy 60.429661 -301.149481) (xy 60.421766 -301.198058) (xy 60.406182 -301.244739)
			(xy 60.383311 -301.288316) (xy 60.353746 -301.32766) (xy 60.318253 -301.361752) (xy 60.27775 -301.389708)
			(xy 60.233288 -301.410806) (xy 60.186017 -301.424498) (xy 60.137162 -301.43043) (xy 60.087987 -301.428449)
			(xy 60.039768 -301.418605) (xy 59.993752 -301.401153) (xy 59.951131 -301.376546) (xy 59.91301 -301.345421)
			(xy 59.880375 -301.308584) (xy 59.854072 -301.266988) (xy 59.834781 -301.221712) (xy 59.823004 -301.173928)
			(xy 59.819044 -301.124874) (xy 58.530236 -301.124874) (xy 58.529741 -301.149481) (xy 58.521846 -301.198058)
			(xy 58.506262 -301.244739) (xy 58.483391 -301.288316) (xy 58.453826 -301.32766) (xy 58.418333 -301.361752)
			(xy 58.37783 -301.389708) (xy 58.333368 -301.410806) (xy 58.286097 -301.424498) (xy 58.237242 -301.43043)
			(xy 58.188067 -301.428449) (xy 58.139848 -301.418605) (xy 58.093832 -301.401153) (xy 58.051211 -301.376546)
			(xy 58.01309 -301.345421) (xy 57.980455 -301.308584) (xy 57.954152 -301.266988) (xy 57.934861 -301.221712)
			(xy 57.923084 -301.173928) (xy 57.919124 -301.124874) (xy 57.580276 -301.124874) (xy 57.579781 -301.149481)
			(xy 57.571886 -301.198058) (xy 57.556302 -301.244739) (xy 57.533431 -301.288316) (xy 57.503866 -301.32766)
			(xy 57.468373 -301.361752) (xy 57.42787 -301.389708) (xy 57.383408 -301.410806) (xy 57.336137 -301.424498)
			(xy 57.287282 -301.43043) (xy 57.238107 -301.428449) (xy 57.189888 -301.418605) (xy 57.143872 -301.401153)
			(xy 57.101251 -301.376546) (xy 57.06313 -301.345421) (xy 57.030495 -301.308584) (xy 57.004192 -301.266988)
			(xy 56.984901 -301.221712) (xy 56.973124 -301.173928) (xy 56.969164 -301.124874) (xy 56.630062 -301.124874)
			(xy 56.629567 -301.149481) (xy 56.621672 -301.198058) (xy 56.606088 -301.244739) (xy 56.583217 -301.288316)
			(xy 56.553652 -301.32766) (xy 56.518159 -301.361752) (xy 56.477656 -301.389708) (xy 56.433194 -301.410806)
			(xy 56.385923 -301.424498) (xy 56.337068 -301.43043) (xy 56.287893 -301.428449) (xy 56.239674 -301.418605)
			(xy 56.193658 -301.401153) (xy 56.151037 -301.376546) (xy 56.112916 -301.345421) (xy 56.080281 -301.308584)
			(xy 56.053978 -301.266988) (xy 56.034687 -301.221712) (xy 56.02291 -301.173928) (xy 56.01895 -301.124874)
			(xy 55.680102 -301.124874) (xy 55.679607 -301.149481) (xy 55.671712 -301.198058) (xy 55.656128 -301.244739)
			(xy 55.633257 -301.288316) (xy 55.603692 -301.32766) (xy 55.568199 -301.361752) (xy 55.527696 -301.389708)
			(xy 55.483234 -301.410806) (xy 55.435963 -301.424498) (xy 55.387108 -301.43043) (xy 55.337933 -301.428449)
			(xy 55.289714 -301.418605) (xy 55.243698 -301.401153) (xy 55.201077 -301.376546) (xy 55.162956 -301.345421)
			(xy 55.130321 -301.308584) (xy 55.104018 -301.266988) (xy 55.084727 -301.221712) (xy 55.07295 -301.173928)
			(xy 55.06899 -301.124874) (xy 54.730142 -301.124874) (xy 54.729647 -301.149481) (xy 54.721752 -301.198058)
			(xy 54.706168 -301.244739) (xy 54.683297 -301.288316) (xy 54.653732 -301.32766) (xy 54.618239 -301.361752)
			(xy 54.577736 -301.389708) (xy 54.533274 -301.410806) (xy 54.486003 -301.424498) (xy 54.437148 -301.43043)
			(xy 54.387973 -301.428449) (xy 54.339754 -301.418605) (xy 54.293738 -301.401153) (xy 54.251117 -301.376546)
			(xy 54.212996 -301.345421) (xy 54.180361 -301.308584) (xy 54.154058 -301.266988) (xy 54.134767 -301.221712)
			(xy 54.12299 -301.173928) (xy 54.11903 -301.124874) (xy 53.780182 -301.124874) (xy 53.779687 -301.149481)
			(xy 53.771792 -301.198058) (xy 53.756208 -301.244739) (xy 53.733337 -301.288316) (xy 53.703772 -301.32766)
			(xy 53.668279 -301.361752) (xy 53.627776 -301.389708) (xy 53.583314 -301.410806) (xy 53.536043 -301.424498)
			(xy 53.487188 -301.43043) (xy 53.438013 -301.428449) (xy 53.389794 -301.418605) (xy 53.343778 -301.401153)
			(xy 53.301157 -301.376546) (xy 53.263036 -301.345421) (xy 53.230401 -301.308584) (xy 53.204098 -301.266988)
			(xy 53.184807 -301.221712) (xy 53.17303 -301.173928) (xy 53.16907 -301.124874) (xy 52.830222 -301.124874)
			(xy 52.829727 -301.149481) (xy 52.821832 -301.198058) (xy 52.806248 -301.244739) (xy 52.783377 -301.288316)
			(xy 52.753812 -301.32766) (xy 52.718319 -301.361752) (xy 52.677816 -301.389708) (xy 52.633354 -301.410806)
			(xy 52.586083 -301.424498) (xy 52.537228 -301.43043) (xy 52.488053 -301.428449) (xy 52.439834 -301.418605)
			(xy 52.393818 -301.401153) (xy 52.351197 -301.376546) (xy 52.313076 -301.345421) (xy 52.280441 -301.308584)
			(xy 52.254138 -301.266988) (xy 52.234847 -301.221712) (xy 52.22307 -301.173928) (xy 52.21911 -301.124874)
			(xy 51.880262 -301.124874) (xy 51.879767 -301.149481) (xy 51.871872 -301.198058) (xy 51.856288 -301.244739)
			(xy 51.833417 -301.288316) (xy 51.803852 -301.32766) (xy 51.768359 -301.361752) (xy 51.727856 -301.389708)
			(xy 51.683394 -301.410806) (xy 51.636123 -301.424498) (xy 51.587268 -301.43043) (xy 51.538093 -301.428449)
			(xy 51.489874 -301.418605) (xy 51.443858 -301.401153) (xy 51.401237 -301.376546) (xy 51.363116 -301.345421)
			(xy 51.330481 -301.308584) (xy 51.304178 -301.266988) (xy 51.284887 -301.221712) (xy 51.27311 -301.173928)
			(xy 51.26915 -301.124874) (xy 50.930302 -301.124874) (xy 50.929807 -301.149481) (xy 50.921912 -301.198058)
			(xy 50.906328 -301.244739) (xy 50.883457 -301.288316) (xy 50.853892 -301.32766) (xy 50.818399 -301.361752)
			(xy 50.777896 -301.389708) (xy 50.733434 -301.410806) (xy 50.686163 -301.424498) (xy 50.637308 -301.43043)
			(xy 50.588133 -301.428449) (xy 50.539914 -301.418605) (xy 50.493898 -301.401153) (xy 50.451277 -301.376546)
			(xy 50.413156 -301.345421) (xy 50.380521 -301.308584) (xy 50.354218 -301.266988) (xy 50.334927 -301.221712)
			(xy 50.32315 -301.173928) (xy 50.31919 -301.124874) (xy 49.980088 -301.124874) (xy 49.979593 -301.149481)
			(xy 49.971698 -301.198058) (xy 49.956114 -301.244739) (xy 49.933243 -301.288316) (xy 49.903678 -301.32766)
			(xy 49.868185 -301.361752) (xy 49.827682 -301.389708) (xy 49.78322 -301.410806) (xy 49.735949 -301.424498)
			(xy 49.687094 -301.43043) (xy 49.637919 -301.428449) (xy 49.5897 -301.418605) (xy 49.543684 -301.401153)
			(xy 49.501063 -301.376546) (xy 49.462942 -301.345421) (xy 49.430307 -301.308584) (xy 49.404004 -301.266988)
			(xy 49.384713 -301.221712) (xy 49.372936 -301.173928) (xy 49.368976 -301.124874) (xy 49.030128 -301.124874)
			(xy 49.029633 -301.149481) (xy 49.021738 -301.198058) (xy 49.006154 -301.244739) (xy 48.983283 -301.288316)
			(xy 48.953718 -301.32766) (xy 48.918225 -301.361752) (xy 48.877722 -301.389708) (xy 48.83326 -301.410806)
			(xy 48.785989 -301.424498) (xy 48.737134 -301.43043) (xy 48.687959 -301.428449) (xy 48.63974 -301.418605)
			(xy 48.593724 -301.401153) (xy 48.551103 -301.376546) (xy 48.512982 -301.345421) (xy 48.480347 -301.308584)
			(xy 48.454044 -301.266988) (xy 48.434753 -301.221712) (xy 48.422976 -301.173928) (xy 48.419016 -301.124874)
			(xy 48.080168 -301.124874) (xy 48.079673 -301.149481) (xy 48.071778 -301.198058) (xy 48.056194 -301.244739)
			(xy 48.033323 -301.288316) (xy 48.003758 -301.32766) (xy 47.968265 -301.361752) (xy 47.927762 -301.389708)
			(xy 47.8833 -301.410806) (xy 47.836029 -301.424498) (xy 47.787174 -301.43043) (xy 47.737999 -301.428449)
			(xy 47.68978 -301.418605) (xy 47.643764 -301.401153) (xy 47.601143 -301.376546) (xy 47.563022 -301.345421)
			(xy 47.530387 -301.308584) (xy 47.504084 -301.266988) (xy 47.484793 -301.221712) (xy 47.473016 -301.173928)
			(xy 47.469056 -301.124874) (xy 47.130142 -301.124874) (xy 47.130593 -301.13319) (xy 47.125225 -301.182535)
			(xy 47.111944 -301.230362) (xy 47.091102 -301.275411) (xy 47.063245 -301.316494) (xy 47.02911 -301.352529)
			(xy 46.989594 -301.382568) (xy 46.945739 -301.405817) (xy 46.898701 -301.421666) (xy 46.849718 -301.429696)
			(xy 46.8249 -301.430182) (xy 46.810717 -301.430006) (xy 46.782477 -301.427333) (xy 46.768512 -301.424848)
			(xy 46.754541 -301.422738) (xy 46.726418 -301.425314) (xy 46.700077 -301.435497) (xy 46.677534 -301.452508)
			(xy 46.660515 -301.475044) (xy 46.650322 -301.501382) (xy 46.647736 -301.529504) (xy 46.649894 -301.543466)
			(xy 46.652376 -301.557431) (xy 46.655044 -301.585671) (xy 46.655228 -301.599854) (xy 46.655227 -301.5999)
			(xy 75.494122 -301.5999) (xy 75.498293 -301.549559) (xy 75.510692 -301.500592) (xy 75.530981 -301.454332)
			(xy 75.558607 -301.412043) (xy 75.592815 -301.374876) (xy 75.632674 -301.343847) (xy 75.677097 -301.3198)
			(xy 75.724871 -301.303393) (xy 75.774694 -301.295071) (xy 75.79995 -301.294546) (xy 75.814133 -301.29473)
			(xy 75.842373 -301.297397) (xy 75.856338 -301.29988) (xy 75.868784 -301.302166) (xy 75.892406 -301.2948)
			(xy 75.969876 -301.21733) (xy 75.977242 -301.193708) (xy 75.974956 -301.181262) (xy 75.972479 -301.167296)
			(xy 75.969807 -301.139057) (xy 75.969622 -301.124874) (xy 75.970106 -301.100056) (xy 75.97814 -301.051075)
			(xy 75.993992 -301.004039) (xy 76.017245 -300.960187) (xy 76.047285 -300.920674) (xy 76.083322 -300.886542)
			(xy 76.124406 -300.858689) (xy 76.169455 -300.837849) (xy 76.217282 -300.824572) (xy 76.266627 -300.819207)
			(xy 76.316189 -300.821895) (xy 76.364664 -300.832566) (xy 76.410774 -300.850939) (xy 76.453305 -300.876529)
			(xy 76.491135 -300.908662) (xy 76.523269 -300.946492) (xy 76.54886 -300.989022) (xy 76.567233 -301.035132)
			(xy 76.577904 -301.083607) (xy 76.580143 -301.124874) (xy 76.919086 -301.124874) (xy 76.923046 -301.07582)
			(xy 76.934823 -301.028036) (xy 76.954114 -300.98276) (xy 76.980417 -300.941164) (xy 77.013052 -300.904327)
			(xy 77.051173 -300.873202) (xy 77.093794 -300.848595) (xy 77.13981 -300.831143) (xy 77.188029 -300.821299)
			(xy 77.237204 -300.819318) (xy 77.286059 -300.82525) (xy 77.33333 -300.838942) (xy 77.377792 -300.86004)
			(xy 77.418295 -300.887996) (xy 77.453788 -300.922088) (xy 77.483353 -300.961432) (xy 77.506224 -301.005009)
			(xy 77.521808 -301.05169) (xy 77.529703 -301.100267) (xy 77.530198 -301.124874) (xy 77.869046 -301.124874)
			(xy 77.873006 -301.07582) (xy 77.884783 -301.028036) (xy 77.904074 -300.98276) (xy 77.930377 -300.941164)
			(xy 77.963012 -300.904327) (xy 78.001133 -300.873202) (xy 78.043754 -300.848595) (xy 78.08977 -300.831143)
			(xy 78.137989 -300.821299) (xy 78.187164 -300.819318) (xy 78.236019 -300.82525) (xy 78.28329 -300.838942)
			(xy 78.327752 -300.86004) (xy 78.368255 -300.887996) (xy 78.403748 -300.922088) (xy 78.433313 -300.961432)
			(xy 78.456184 -301.005009) (xy 78.471768 -301.05169) (xy 78.479663 -301.100267) (xy 78.480158 -301.124874)
			(xy 78.479663 -301.149481) (xy 78.471768 -301.198058) (xy 78.456184 -301.244739) (xy 78.433313 -301.288316)
			(xy 78.403748 -301.32766) (xy 78.368255 -301.361752) (xy 78.327752 -301.389708) (xy 78.28329 -301.410806)
			(xy 78.236019 -301.424498) (xy 78.187164 -301.43043) (xy 78.137989 -301.428449) (xy 78.08977 -301.418605)
			(xy 78.043754 -301.401153) (xy 78.001133 -301.376546) (xy 77.963012 -301.345421) (xy 77.930377 -301.308584)
			(xy 77.904074 -301.266988) (xy 77.884783 -301.221712) (xy 77.873006 -301.173928) (xy 77.869046 -301.124874)
			(xy 77.530198 -301.124874) (xy 77.529703 -301.149481) (xy 77.521808 -301.198058) (xy 77.506224 -301.244739)
			(xy 77.483353 -301.288316) (xy 77.453788 -301.32766) (xy 77.418295 -301.361752) (xy 77.377792 -301.389708)
			(xy 77.33333 -301.410806) (xy 77.286059 -301.424498) (xy 77.237204 -301.43043) (xy 77.188029 -301.428449)
			(xy 77.13981 -301.418605) (xy 77.093794 -301.401153) (xy 77.051173 -301.376546) (xy 77.013052 -301.345421)
			(xy 76.980417 -301.308584) (xy 76.954114 -301.266988) (xy 76.934823 -301.221712) (xy 76.923046 -301.173928)
			(xy 76.919086 -301.124874) (xy 76.580143 -301.124874) (xy 76.580593 -301.133169) (xy 76.575229 -301.182514)
			(xy 76.561952 -301.230341) (xy 76.541113 -301.27539) (xy 76.513261 -301.316475) (xy 76.479129 -301.352512)
			(xy 76.439616 -301.382553) (xy 76.395765 -301.405806) (xy 76.348729 -301.421659) (xy 76.299748 -301.429694)
			(xy 76.27493 -301.430182) (xy 76.260747 -301.430002) (xy 76.232507 -301.427332) (xy 76.218542 -301.424848)
			(xy 76.206096 -301.422562) (xy 76.182474 -301.429928) (xy 76.105004 -301.507398) (xy 76.097638 -301.53102)
			(xy 76.099924 -301.543466) (xy 76.102406 -301.557431) (xy 76.105074 -301.585671) (xy 76.105258 -301.599854)
			(xy 76.105076 -301.614037) (xy 76.102408 -301.642277) (xy 76.099924 -301.656242) (xy 76.097638 -301.668688)
			(xy 76.105004 -301.69231) (xy 76.182474 -301.76978) (xy 76.206096 -301.777146) (xy 76.218542 -301.77486)
			(xy 76.232508 -301.772382) (xy 76.260747 -301.769711) (xy 76.27493 -301.769526) (xy 76.299747 -301.77001)
			(xy 76.348727 -301.778045) (xy 76.395762 -301.793897) (xy 76.439613 -301.81715) (xy 76.479125 -301.84719)
			(xy 76.513257 -301.883227) (xy 76.541109 -301.92431) (xy 76.561948 -301.969358) (xy 76.575224 -302.017184)
			(xy 76.580589 -302.066528) (xy 76.580139 -302.074834) (xy 76.919086 -302.074834) (xy 76.923046 -302.02578)
			(xy 76.934823 -301.977996) (xy 76.954114 -301.93272) (xy 76.980417 -301.891124) (xy 77.013052 -301.854287)
			(xy 77.051173 -301.823162) (xy 77.093794 -301.798555) (xy 77.13981 -301.781103) (xy 77.188029 -301.771259)
			(xy 77.237204 -301.769278) (xy 77.286059 -301.77521) (xy 77.33333 -301.788902) (xy 77.377792 -301.81)
			(xy 77.418295 -301.837956) (xy 77.453788 -301.872048) (xy 77.483353 -301.911392) (xy 77.506224 -301.954969)
			(xy 77.521808 -302.00165) (xy 77.529703 -302.050227) (xy 77.530198 -302.074834) (xy 77.869046 -302.074834)
			(xy 77.873006 -302.02578) (xy 77.884783 -301.977996) (xy 77.904074 -301.93272) (xy 77.930377 -301.891124)
			(xy 77.963012 -301.854287) (xy 78.001133 -301.823162) (xy 78.043754 -301.798555) (xy 78.08977 -301.781103)
			(xy 78.137989 -301.771259) (xy 78.187164 -301.769278) (xy 78.236019 -301.77521) (xy 78.28329 -301.788902)
			(xy 78.327752 -301.81) (xy 78.368255 -301.837956) (xy 78.403748 -301.872048) (xy 78.433313 -301.911392)
			(xy 78.456184 -301.954969) (xy 78.471768 -302.00165) (xy 78.479663 -302.050227) (xy 78.480158 -302.074834)
			(xy 78.479663 -302.099441) (xy 78.471768 -302.148018) (xy 78.456184 -302.194699) (xy 78.433313 -302.238276)
			(xy 78.403748 -302.27762) (xy 78.368255 -302.311712) (xy 78.327752 -302.339668) (xy 78.28329 -302.360766)
			(xy 78.236019 -302.374458) (xy 78.187164 -302.38039) (xy 78.137989 -302.378409) (xy 78.08977 -302.368565)
			(xy 78.043754 -302.351113) (xy 78.001133 -302.326506) (xy 77.963012 -302.295381) (xy 77.930377 -302.258544)
			(xy 77.904074 -302.216948) (xy 77.884783 -302.171672) (xy 77.873006 -302.123888) (xy 77.869046 -302.074834)
			(xy 77.530198 -302.074834) (xy 77.529703 -302.099441) (xy 77.521808 -302.148018) (xy 77.506224 -302.194699)
			(xy 77.483353 -302.238276) (xy 77.453788 -302.27762) (xy 77.418295 -302.311712) (xy 77.377792 -302.339668)
			(xy 77.33333 -302.360766) (xy 77.286059 -302.374458) (xy 77.237204 -302.38039) (xy 77.188029 -302.378409)
			(xy 77.13981 -302.368565) (xy 77.093794 -302.351113) (xy 77.051173 -302.326506) (xy 77.013052 -302.295381)
			(xy 76.980417 -302.258544) (xy 76.954114 -302.216948) (xy 76.934823 -302.171672) (xy 76.923046 -302.123888)
			(xy 76.919086 -302.074834) (xy 76.580139 -302.074834) (xy 76.577901 -302.11609) (xy 76.56723 -302.164564)
			(xy 76.548858 -302.210673) (xy 76.523268 -302.253203) (xy 76.491135 -302.291033) (xy 76.453306 -302.323166)
			(xy 76.410777 -302.348756) (xy 76.364668 -302.367129) (xy 76.316194 -302.3778) (xy 76.266632 -302.380489)
			(xy 76.217288 -302.375125) (xy 76.169462 -302.361849) (xy 76.124414 -302.341011) (xy 76.08333 -302.313159)
			(xy 76.047293 -302.279028) (xy 76.017252 -302.239517) (xy 75.993999 -302.195666) (xy 75.978146 -302.148631)
			(xy 75.97011 -302.099651) (xy 75.969622 -302.074834) (xy 75.969803 -302.060651) (xy 75.972472 -302.032411)
			(xy 75.974956 -302.018446) (xy 75.977242 -302.006) (xy 75.969876 -301.982378) (xy 75.892406 -301.904908)
			(xy 75.868784 -301.897542) (xy 75.856338 -301.899828) (xy 75.842373 -301.902309) (xy 75.814133 -301.904978)
			(xy 75.79995 -301.905162) (xy 75.774694 -301.904729) (xy 75.724871 -301.896407) (xy 75.677097 -301.88)
			(xy 75.632674 -301.855953) (xy 75.592815 -301.824924) (xy 75.558607 -301.787757) (xy 75.530981 -301.745468)
			(xy 75.510692 -301.699208) (xy 75.498293 -301.650241) (xy 75.494122 -301.5999) (xy 46.655227 -301.5999)
			(xy 46.654772 -301.62468) (xy 46.646746 -301.673678) (xy 46.630899 -301.720733) (xy 46.607647 -301.764604)
			(xy 46.577604 -301.804135) (xy 46.541561 -301.838284) (xy 46.500468 -301.866152) (xy 46.455408 -301.887005)
			(xy 46.407567 -301.900292) (xy 46.358207 -301.905665) (xy 46.308628 -301.90298) (xy 46.260137 -301.89231)
			(xy 46.214011 -301.873935) (xy 46.171465 -301.848339) (xy 46.133621 -301.816197) (xy 46.101476 -301.778356)
			(xy 46.075877 -301.735813) (xy 46.057498 -301.689688) (xy 46.046823 -301.641197) (xy 46.044135 -301.591619)
			(xy 45.705758 -301.591619) (xy 45.703072 -301.641184) (xy 45.6924 -301.689674) (xy 45.674023 -301.735799)
			(xy 45.648425 -301.778344) (xy 45.616281 -301.816186) (xy 45.578439 -301.848329) (xy 45.535894 -301.873925)
			(xy 45.489769 -301.892302) (xy 45.441278 -301.902973) (xy 45.391699 -301.905658) (xy 45.34234 -301.900287)
			(xy 45.294499 -301.887) (xy 45.249439 -301.866149) (xy 45.208346 -301.838281) (xy 45.172303 -301.804133)
			(xy 45.142259 -301.764602) (xy 45.119008 -301.720732) (xy 45.10316 -301.673678) (xy 45.095134 -301.62468)
			(xy 45.094652 -301.599854) (xy 45.094837 -301.585671) (xy 45.097504 -301.557431) (xy 45.099986 -301.543466)
			(xy 45.102272 -301.53102) (xy 45.094906 -301.507398) (xy 45.017436 -301.429928) (xy 44.993814 -301.422562)
			(xy 44.981368 -301.424848) (xy 44.967402 -301.427324) (xy 44.939163 -301.429996) (xy 44.92498 -301.430182)
			(xy 44.910733 -301.430011) (xy 44.882366 -301.427341) (xy 44.868338 -301.424848) (xy 44.856146 -301.422562)
			(xy 44.832016 -301.429928) (xy 44.7548 -301.507144) (xy 44.747434 -301.53102) (xy 44.74972 -301.543466)
			(xy 44.752202 -301.557431) (xy 44.75487 -301.585671) (xy 44.755054 -301.599854) (xy 44.754532 -301.625109)
			(xy 44.746219 -301.674931) (xy 44.729818 -301.722705) (xy 44.705777 -301.767128) (xy 44.674753 -301.806988)
			(xy 44.637591 -301.841198) (xy 44.595305 -301.868824) (xy 44.549049 -301.889114) (xy 44.500084 -301.901514)
			(xy 44.449746 -301.905685) (xy 44.399408 -301.901514) (xy 44.350443 -301.889114) (xy 44.304187 -301.868824)
			(xy 44.261901 -301.841198) (xy 44.224739 -301.806988) (xy 44.193715 -301.767128) (xy 44.169674 -301.722705)
			(xy 44.153273 -301.674931) (xy 44.14496 -301.625109) (xy 44.144438 -301.599854) (xy 44.144621 -301.585671)
			(xy 44.147289 -301.557431) (xy 44.149772 -301.543466) (xy 44.152058 -301.53102) (xy 44.144692 -301.507398)
			(xy 44.067222 -301.429928) (xy 44.0436 -301.422562) (xy 44.031154 -301.424848) (xy 44.017188 -301.427326)
			(xy 43.988949 -301.429997) (xy 43.974766 -301.430182) (xy 43.960583 -301.430011) (xy 43.932343 -301.427335)
			(xy 43.918378 -301.424848) (xy 43.905932 -301.422562) (xy 43.88231 -301.429928) (xy 43.80484 -301.507398)
			(xy 43.797474 -301.53102) (xy 43.79976 -301.543466) (xy 43.802241 -301.557431) (xy 43.80491 -301.585671)
			(xy 43.805094 -301.599854) (xy 43.804672 -301.624679) (xy 43.796647 -301.673677) (xy 43.7808 -301.72073)
			(xy 43.75755 -301.7646) (xy 43.727508 -301.804131) (xy 43.691466 -301.83828) (xy 43.650375 -301.866148)
			(xy 43.605316 -301.887002) (xy 43.557477 -301.90029) (xy 43.508119 -301.905664) (xy 43.458541 -301.902982)
			(xy 43.41005 -301.892314) (xy 43.363924 -301.873942) (xy 43.321378 -301.848348) (xy 43.283533 -301.816209)
			(xy 43.251387 -301.778371) (xy 43.225785 -301.73583) (xy 43.207404 -301.689708) (xy 43.196726 -301.641219)
			(xy 43.194034 -301.591642) (xy 42.876817 -301.591642) (xy 42.876978 -301.599854) (xy 42.876474 -301.625562)
			(xy 42.868431 -301.676344) (xy 42.852543 -301.725243) (xy 42.8292 -301.771055) (xy 42.798979 -301.812651)
			(xy 42.762623 -301.849007) (xy 42.721027 -301.879228) (xy 42.675215 -301.902571) (xy 42.626316 -301.918459)
			(xy 42.575534 -301.926502) (xy 42.524118 -301.926502) (xy 42.473336 -301.918459) (xy 42.424437 -301.902571)
			(xy 42.378625 -301.879228) (xy 42.337029 -301.849007) (xy 42.300673 -301.812651) (xy 42.270452 -301.771055)
			(xy 42.247109 -301.725243) (xy 42.231221 -301.676344) (xy 42.223178 -301.625562) (xy 41.926514 -301.625562)
			(xy 41.918471 -301.676344) (xy 41.902583 -301.725243) (xy 41.87924 -301.771055) (xy 41.849019 -301.812651)
			(xy 41.812663 -301.849007) (xy 41.771067 -301.879228) (xy 41.725255 -301.902571) (xy 41.676356 -301.918459)
			(xy 41.625574 -301.926502) (xy 41.574158 -301.926502) (xy 41.523376 -301.918459) (xy 41.474477 -301.902571)
			(xy 41.428665 -301.879228) (xy 41.387069 -301.849007) (xy 41.350713 -301.812651) (xy 41.320492 -301.771055)
			(xy 41.297149 -301.725243) (xy 41.281261 -301.676344) (xy 41.273218 -301.625562) (xy 40.95454 -301.625562)
			(xy 40.946824 -301.673038) (xy 40.93124 -301.719719) (xy 40.908369 -301.763296) (xy 40.878804 -301.80264)
			(xy 40.843311 -301.836732) (xy 40.802808 -301.864688) (xy 40.758346 -301.885786) (xy 40.711075 -301.899478)
			(xy 40.66222 -301.90541) (xy 40.613045 -301.903429) (xy 40.564826 -301.893585) (xy 40.51881 -301.876133)
			(xy 40.476189 -301.851526) (xy 40.438068 -301.820401) (xy 40.405433 -301.783564) (xy 40.37913 -301.741968)
			(xy 40.359839 -301.696692) (xy 40.348062 -301.648908) (xy 40.344102 -301.599854) (xy 40.027098 -301.599854)
			(xy 40.026594 -301.625562) (xy 40.018551 -301.676344) (xy 40.002663 -301.725243) (xy 39.97932 -301.771055)
			(xy 39.949099 -301.812651) (xy 39.912743 -301.849007) (xy 39.871147 -301.879228) (xy 39.825335 -301.902571)
			(xy 39.776436 -301.918459) (xy 39.725654 -301.926502) (xy 39.674238 -301.926502) (xy 39.623456 -301.918459)
			(xy 39.574557 -301.902571) (xy 39.528745 -301.879228) (xy 39.487149 -301.849007) (xy 39.450793 -301.812651)
			(xy 39.420572 -301.771055) (xy 39.397229 -301.725243) (xy 39.381341 -301.676344) (xy 39.373298 -301.625562)
			(xy 39.076634 -301.625562) (xy 39.068591 -301.676344) (xy 39.052703 -301.725243) (xy 39.02936 -301.771055)
			(xy 38.999139 -301.812651) (xy 38.962783 -301.849007) (xy 38.921187 -301.879228) (xy 38.875375 -301.902571)
			(xy 38.826476 -301.918459) (xy 38.775694 -301.926502) (xy 38.724278 -301.926502) (xy 38.673496 -301.918459)
			(xy 38.624597 -301.902571) (xy 38.578785 -301.879228) (xy 38.537189 -301.849007) (xy 38.500833 -301.812651)
			(xy 38.470612 -301.771055) (xy 38.447269 -301.725243) (xy 38.431381 -301.676344) (xy 38.423338 -301.625562)
			(xy 38.104406 -301.625562) (xy 38.09669 -301.673038) (xy 38.081106 -301.719719) (xy 38.058235 -301.763296)
			(xy 38.02867 -301.80264) (xy 37.993177 -301.836732) (xy 37.952674 -301.864688) (xy 37.908212 -301.885786)
			(xy 37.860941 -301.899478) (xy 37.812086 -301.90541) (xy 37.762911 -301.903429) (xy 37.714692 -301.893585)
			(xy 37.668676 -301.876133) (xy 37.626055 -301.851526) (xy 37.587934 -301.820401) (xy 37.555299 -301.783564)
			(xy 37.528996 -301.741968) (xy 37.509705 -301.696692) (xy 37.497928 -301.648908) (xy 37.493968 -301.599854)
			(xy 37.15512 -301.599854) (xy 37.154625 -301.624461) (xy 37.14673 -301.673038) (xy 37.131146 -301.719719)
			(xy 37.108275 -301.763296) (xy 37.07871 -301.80264) (xy 37.043217 -301.836732) (xy 37.002714 -301.864688)
			(xy 36.958252 -301.885786) (xy 36.910981 -301.899478) (xy 36.862126 -301.90541) (xy 36.812951 -301.903429)
			(xy 36.764732 -301.893585) (xy 36.718716 -301.876133) (xy 36.676095 -301.851526) (xy 36.637974 -301.820401)
			(xy 36.605339 -301.783564) (xy 36.579036 -301.741968) (xy 36.559745 -301.696692) (xy 36.547968 -301.648908)
			(xy 36.544008 -301.599854) (xy 23.523406 -301.599854) (xy 23.5135 -301.73626) (xy 23.493816 -301.898378)
			(xy 23.466321 -302.059355) (xy 23.4629 -302.074834) (xy 49.368976 -302.074834) (xy 49.372936 -302.02578)
			(xy 49.384713 -301.977996) (xy 49.404004 -301.93272) (xy 49.430307 -301.891124) (xy 49.462942 -301.854287)
			(xy 49.501063 -301.823162) (xy 49.543684 -301.798555) (xy 49.5897 -301.781103) (xy 49.637919 -301.771259)
			(xy 49.687094 -301.769278) (xy 49.735949 -301.77521) (xy 49.78322 -301.788902) (xy 49.827682 -301.81)
			(xy 49.868185 -301.837956) (xy 49.903678 -301.872048) (xy 49.933243 -301.911392) (xy 49.956114 -301.954969)
			(xy 49.971698 -302.00165) (xy 49.979593 -302.050227) (xy 49.980088 -302.074834) (xy 50.31919 -302.074834)
			(xy 50.32315 -302.02578) (xy 50.334927 -301.977996) (xy 50.354218 -301.93272) (xy 50.380521 -301.891124)
			(xy 50.413156 -301.854287) (xy 50.451277 -301.823162) (xy 50.493898 -301.798555) (xy 50.539914 -301.781103)
			(xy 50.588133 -301.771259) (xy 50.637308 -301.769278) (xy 50.686163 -301.77521) (xy 50.733434 -301.788902)
			(xy 50.777896 -301.81) (xy 50.818399 -301.837956) (xy 50.853892 -301.872048) (xy 50.883457 -301.911392)
			(xy 50.906328 -301.954969) (xy 50.921912 -302.00165) (xy 50.929807 -302.050227) (xy 50.930302 -302.074834)
			(xy 51.26915 -302.074834) (xy 51.27311 -302.02578) (xy 51.284887 -301.977996) (xy 51.304178 -301.93272)
			(xy 51.330481 -301.891124) (xy 51.363116 -301.854287) (xy 51.401237 -301.823162) (xy 51.443858 -301.798555)
			(xy 51.489874 -301.781103) (xy 51.538093 -301.771259) (xy 51.587268 -301.769278) (xy 51.636123 -301.77521)
			(xy 51.683394 -301.788902) (xy 51.727856 -301.81) (xy 51.768359 -301.837956) (xy 51.803852 -301.872048)
			(xy 51.833417 -301.911392) (xy 51.856288 -301.954969) (xy 51.871872 -302.00165) (xy 51.879767 -302.050227)
			(xy 51.880262 -302.074834) (xy 52.21911 -302.074834) (xy 52.22307 -302.02578) (xy 52.234847 -301.977996)
			(xy 52.254138 -301.93272) (xy 52.280441 -301.891124) (xy 52.313076 -301.854287) (xy 52.351197 -301.823162)
			(xy 52.393818 -301.798555) (xy 52.439834 -301.781103) (xy 52.488053 -301.771259) (xy 52.537228 -301.769278)
			(xy 52.586083 -301.77521) (xy 52.633354 -301.788902) (xy 52.677816 -301.81) (xy 52.718319 -301.837956)
			(xy 52.753812 -301.872048) (xy 52.783377 -301.911392) (xy 52.806248 -301.954969) (xy 52.821832 -302.00165)
			(xy 52.829727 -302.050227) (xy 52.830222 -302.074834) (xy 53.16907 -302.074834) (xy 53.17303 -302.02578)
			(xy 53.184807 -301.977996) (xy 53.204098 -301.93272) (xy 53.230401 -301.891124) (xy 53.263036 -301.854287)
			(xy 53.301157 -301.823162) (xy 53.343778 -301.798555) (xy 53.389794 -301.781103) (xy 53.438013 -301.771259)
			(xy 53.487188 -301.769278) (xy 53.536043 -301.77521) (xy 53.583314 -301.788902) (xy 53.627776 -301.81)
			(xy 53.668279 -301.837956) (xy 53.703772 -301.872048) (xy 53.733337 -301.911392) (xy 53.756208 -301.954969)
			(xy 53.771792 -302.00165) (xy 53.779687 -302.050227) (xy 53.780182 -302.074834) (xy 54.11903 -302.074834)
			(xy 54.12299 -302.02578) (xy 54.134767 -301.977996) (xy 54.154058 -301.93272) (xy 54.180361 -301.891124)
			(xy 54.212996 -301.854287) (xy 54.251117 -301.823162) (xy 54.293738 -301.798555) (xy 54.339754 -301.781103)
			(xy 54.387973 -301.771259) (xy 54.437148 -301.769278) (xy 54.486003 -301.77521) (xy 54.533274 -301.788902)
			(xy 54.577736 -301.81) (xy 54.618239 -301.837956) (xy 54.653732 -301.872048) (xy 54.683297 -301.911392)
			(xy 54.706168 -301.954969) (xy 54.721752 -302.00165) (xy 54.729647 -302.050227) (xy 54.730142 -302.074834)
			(xy 55.06899 -302.074834) (xy 55.07295 -302.02578) (xy 55.084727 -301.977996) (xy 55.104018 -301.93272)
			(xy 55.130321 -301.891124) (xy 55.162956 -301.854287) (xy 55.201077 -301.823162) (xy 55.243698 -301.798555)
			(xy 55.289714 -301.781103) (xy 55.337933 -301.771259) (xy 55.387108 -301.769278) (xy 55.435963 -301.77521)
			(xy 55.483234 -301.788902) (xy 55.527696 -301.81) (xy 55.568199 -301.837956) (xy 55.603692 -301.872048)
			(xy 55.633257 -301.911392) (xy 55.656128 -301.954969) (xy 55.671712 -302.00165) (xy 55.679607 -302.050227)
			(xy 55.680102 -302.074834) (xy 56.01895 -302.074834) (xy 56.02291 -302.02578) (xy 56.034687 -301.977996)
			(xy 56.053978 -301.93272) (xy 56.080281 -301.891124) (xy 56.112916 -301.854287) (xy 56.151037 -301.823162)
			(xy 56.193658 -301.798555) (xy 56.239674 -301.781103) (xy 56.287893 -301.771259) (xy 56.337068 -301.769278)
			(xy 56.385923 -301.77521) (xy 56.433194 -301.788902) (xy 56.477656 -301.81) (xy 56.518159 -301.837956)
			(xy 56.553652 -301.872048) (xy 56.583217 -301.911392) (xy 56.606088 -301.954969) (xy 56.621672 -302.00165)
			(xy 56.629567 -302.050227) (xy 56.630062 -302.074834) (xy 56.969164 -302.074834) (xy 56.973124 -302.02578)
			(xy 56.984901 -301.977996) (xy 57.004192 -301.93272) (xy 57.030495 -301.891124) (xy 57.06313 -301.854287)
			(xy 57.101251 -301.823162) (xy 57.143872 -301.798555) (xy 57.189888 -301.781103) (xy 57.238107 -301.771259)
			(xy 57.287282 -301.769278) (xy 57.336137 -301.77521) (xy 57.383408 -301.788902) (xy 57.42787 -301.81)
			(xy 57.468373 -301.837956) (xy 57.503866 -301.872048) (xy 57.533431 -301.911392) (xy 57.556302 -301.954969)
			(xy 57.571886 -302.00165) (xy 57.579781 -302.050227) (xy 57.580276 -302.074834) (xy 57.919124 -302.074834)
			(xy 57.923084 -302.02578) (xy 57.934861 -301.977996) (xy 57.954152 -301.93272) (xy 57.980455 -301.891124)
			(xy 58.01309 -301.854287) (xy 58.051211 -301.823162) (xy 58.093832 -301.798555) (xy 58.139848 -301.781103)
			(xy 58.188067 -301.771259) (xy 58.237242 -301.769278) (xy 58.286097 -301.77521) (xy 58.333368 -301.788902)
			(xy 58.37783 -301.81) (xy 58.418333 -301.837956) (xy 58.453826 -301.872048) (xy 58.483391 -301.911392)
			(xy 58.506262 -301.954969) (xy 58.521846 -302.00165) (xy 58.529741 -302.050227) (xy 58.530236 -302.074834)
			(xy 59.819044 -302.074834) (xy 59.823004 -302.02578) (xy 59.834781 -301.977996) (xy 59.854072 -301.93272)
			(xy 59.880375 -301.891124) (xy 59.91301 -301.854287) (xy 59.951131 -301.823162) (xy 59.993752 -301.798555)
			(xy 60.039768 -301.781103) (xy 60.087987 -301.771259) (xy 60.137162 -301.769278) (xy 60.186017 -301.77521)
			(xy 60.233288 -301.788902) (xy 60.27775 -301.81) (xy 60.318253 -301.837956) (xy 60.353746 -301.872048)
			(xy 60.383311 -301.911392) (xy 60.406182 -301.954969) (xy 60.421766 -302.00165) (xy 60.429661 -302.050227)
			(xy 60.430156 -302.074834) (xy 60.769004 -302.074834) (xy 60.772964 -302.02578) (xy 60.784741 -301.977996)
			(xy 60.804032 -301.93272) (xy 60.830335 -301.891124) (xy 60.86297 -301.854287) (xy 60.901091 -301.823162)
			(xy 60.943712 -301.798555) (xy 60.989728 -301.781103) (xy 61.037947 -301.771259) (xy 61.087122 -301.769278)
			(xy 61.135977 -301.77521) (xy 61.183248 -301.788902) (xy 61.22771 -301.81) (xy 61.268213 -301.837956)
			(xy 61.303706 -301.872048) (xy 61.333271 -301.911392) (xy 61.356142 -301.954969) (xy 61.371726 -302.00165)
			(xy 61.379621 -302.050227) (xy 61.380116 -302.074834) (xy 61.718964 -302.074834) (xy 61.722924 -302.02578)
			(xy 61.734701 -301.977996) (xy 61.753992 -301.93272) (xy 61.780295 -301.891124) (xy 61.81293 -301.854287)
			(xy 61.851051 -301.823162) (xy 61.893672 -301.798555) (xy 61.939688 -301.781103) (xy 61.987907 -301.771259)
			(xy 62.037082 -301.769278) (xy 62.085937 -301.77521) (xy 62.133208 -301.788902) (xy 62.17767 -301.81)
			(xy 62.218173 -301.837956) (xy 62.253666 -301.872048) (xy 62.283231 -301.911392) (xy 62.306102 -301.954969)
			(xy 62.321686 -302.00165) (xy 62.329581 -302.050227) (xy 62.330076 -302.074834) (xy 62.669178 -302.074834)
			(xy 62.673138 -302.02578) (xy 62.684915 -301.977996) (xy 62.704206 -301.93272) (xy 62.730509 -301.891124)
			(xy 62.763144 -301.854287) (xy 62.801265 -301.823162) (xy 62.843886 -301.798555) (xy 62.889902 -301.781103)
			(xy 62.938121 -301.771259) (xy 62.987296 -301.769278) (xy 63.036151 -301.77521) (xy 63.083422 -301.788902)
			(xy 63.127884 -301.81) (xy 63.168387 -301.837956) (xy 63.20388 -301.872048) (xy 63.233445 -301.911392)
			(xy 63.256316 -301.954969) (xy 63.2719 -302.00165) (xy 63.279795 -302.050227) (xy 63.28029 -302.074834)
			(xy 63.619138 -302.074834) (xy 63.623098 -302.02578) (xy 63.634875 -301.977996) (xy 63.654166 -301.93272)
			(xy 63.680469 -301.891124) (xy 63.713104 -301.854287) (xy 63.751225 -301.823162) (xy 63.793846 -301.798555)
			(xy 63.839862 -301.781103) (xy 63.888081 -301.771259) (xy 63.937256 -301.769278) (xy 63.986111 -301.77521)
			(xy 64.033382 -301.788902) (xy 64.077844 -301.81) (xy 64.118347 -301.837956) (xy 64.15384 -301.872048)
			(xy 64.183405 -301.911392) (xy 64.206276 -301.954969) (xy 64.22186 -302.00165) (xy 64.229755 -302.050227)
			(xy 64.23025 -302.074834) (xy 64.569098 -302.074834) (xy 64.573058 -302.02578) (xy 64.584835 -301.977996)
			(xy 64.604126 -301.93272) (xy 64.630429 -301.891124) (xy 64.663064 -301.854287) (xy 64.701185 -301.823162)
			(xy 64.743806 -301.798555) (xy 64.789822 -301.781103) (xy 64.838041 -301.771259) (xy 64.887216 -301.769278)
			(xy 64.936071 -301.77521) (xy 64.983342 -301.788902) (xy 65.027804 -301.81) (xy 65.068307 -301.837956)
			(xy 65.1038 -301.872048) (xy 65.133365 -301.911392) (xy 65.156236 -301.954969) (xy 65.17182 -302.00165)
			(xy 65.179715 -302.050227) (xy 65.18021 -302.074834) (xy 65.519058 -302.074834) (xy 65.523018 -302.02578)
			(xy 65.534795 -301.977996) (xy 65.554086 -301.93272) (xy 65.580389 -301.891124) (xy 65.613024 -301.854287)
			(xy 65.651145 -301.823162) (xy 65.693766 -301.798555) (xy 65.739782 -301.781103) (xy 65.788001 -301.771259)
			(xy 65.837176 -301.769278) (xy 65.886031 -301.77521) (xy 65.933302 -301.788902) (xy 65.977764 -301.81)
			(xy 66.018267 -301.837956) (xy 66.05376 -301.872048) (xy 66.083325 -301.911392) (xy 66.106196 -301.954969)
			(xy 66.12178 -302.00165) (xy 66.129675 -302.050227) (xy 66.13017 -302.074834) (xy 66.469018 -302.074834)
			(xy 66.472978 -302.02578) (xy 66.484755 -301.977996) (xy 66.504046 -301.93272) (xy 66.530349 -301.891124)
			(xy 66.562984 -301.854287) (xy 66.601105 -301.823162) (xy 66.643726 -301.798555) (xy 66.689742 -301.781103)
			(xy 66.737961 -301.771259) (xy 66.787136 -301.769278) (xy 66.835991 -301.77521) (xy 66.883262 -301.788902)
			(xy 66.927724 -301.81) (xy 66.968227 -301.837956) (xy 67.00372 -301.872048) (xy 67.033285 -301.911392)
			(xy 67.056156 -301.954969) (xy 67.07174 -302.00165) (xy 67.079635 -302.050227) (xy 67.08013 -302.074834)
			(xy 67.418978 -302.074834) (xy 67.422938 -302.02578) (xy 67.434715 -301.977996) (xy 67.454006 -301.93272)
			(xy 67.480309 -301.891124) (xy 67.512944 -301.854287) (xy 67.551065 -301.823162) (xy 67.593686 -301.798555)
			(xy 67.639702 -301.781103) (xy 67.687921 -301.771259) (xy 67.737096 -301.769278) (xy 67.785951 -301.77521)
			(xy 67.833222 -301.788902) (xy 67.877684 -301.81) (xy 67.918187 -301.837956) (xy 67.95368 -301.872048)
			(xy 67.983245 -301.911392) (xy 68.006116 -301.954969) (xy 68.0217 -302.00165) (xy 68.029595 -302.050227)
			(xy 68.03009 -302.074834) (xy 68.368938 -302.074834) (xy 68.372898 -302.02578) (xy 68.384675 -301.977996)
			(xy 68.403966 -301.93272) (xy 68.430269 -301.891124) (xy 68.462904 -301.854287) (xy 68.501025 -301.823162)
			(xy 68.543646 -301.798555) (xy 68.589662 -301.781103) (xy 68.637881 -301.771259) (xy 68.687056 -301.769278)
			(xy 68.735911 -301.77521) (xy 68.783182 -301.788902) (xy 68.827644 -301.81) (xy 68.868147 -301.837956)
			(xy 68.90364 -301.872048) (xy 68.933205 -301.911392) (xy 68.956076 -301.954969) (xy 68.97166 -302.00165)
			(xy 68.979555 -302.050227) (xy 68.98005 -302.074834) (xy 69.319152 -302.074834) (xy 69.323112 -302.02578)
			(xy 69.334889 -301.977996) (xy 69.35418 -301.93272) (xy 69.380483 -301.891124) (xy 69.413118 -301.854287)
			(xy 69.451239 -301.823162) (xy 69.49386 -301.798555) (xy 69.539876 -301.781103) (xy 69.588095 -301.771259)
			(xy 69.63727 -301.769278) (xy 69.686125 -301.77521) (xy 69.733396 -301.788902) (xy 69.777858 -301.81)
			(xy 69.818361 -301.837956) (xy 69.853854 -301.872048) (xy 69.883419 -301.911392) (xy 69.90629 -301.954969)
			(xy 69.921874 -302.00165) (xy 69.929769 -302.050227) (xy 69.930264 -302.074834) (xy 70.269112 -302.074834)
			(xy 70.273072 -302.02578) (xy 70.284849 -301.977996) (xy 70.30414 -301.93272) (xy 70.330443 -301.891124)
			(xy 70.363078 -301.854287) (xy 70.401199 -301.823162) (xy 70.44382 -301.798555) (xy 70.489836 -301.781103)
			(xy 70.538055 -301.771259) (xy 70.58723 -301.769278) (xy 70.636085 -301.77521) (xy 70.683356 -301.788902)
			(xy 70.727818 -301.81) (xy 70.768321 -301.837956) (xy 70.803814 -301.872048) (xy 70.833379 -301.911392)
			(xy 70.85625 -301.954969) (xy 70.871834 -302.00165) (xy 70.879729 -302.050227) (xy 70.880224 -302.074834)
			(xy 71.219072 -302.074834) (xy 71.223032 -302.02578) (xy 71.234809 -301.977996) (xy 71.2541 -301.93272)
			(xy 71.280403 -301.891124) (xy 71.313038 -301.854287) (xy 71.351159 -301.823162) (xy 71.39378 -301.798555)
			(xy 71.439796 -301.781103) (xy 71.488015 -301.771259) (xy 71.53719 -301.769278) (xy 71.586045 -301.77521)
			(xy 71.633316 -301.788902) (xy 71.677778 -301.81) (xy 71.718281 -301.837956) (xy 71.753774 -301.872048)
			(xy 71.783339 -301.911392) (xy 71.80621 -301.954969) (xy 71.821794 -302.00165) (xy 71.829689 -302.050227)
			(xy 71.830184 -302.074834) (xy 72.169032 -302.074834) (xy 72.172992 -302.02578) (xy 72.184769 -301.977996)
			(xy 72.20406 -301.93272) (xy 72.230363 -301.891124) (xy 72.262998 -301.854287) (xy 72.301119 -301.823162)
			(xy 72.34374 -301.798555) (xy 72.389756 -301.781103) (xy 72.437975 -301.771259) (xy 72.48715 -301.769278)
			(xy 72.536005 -301.77521) (xy 72.583276 -301.788902) (xy 72.627738 -301.81) (xy 72.668241 -301.837956)
			(xy 72.703734 -301.872048) (xy 72.733299 -301.911392) (xy 72.75617 -301.954969) (xy 72.771754 -302.00165)
			(xy 72.779649 -302.050227) (xy 72.780144 -302.074834) (xy 72.779978 -302.083068) (xy 73.119085 -302.083068)
			(xy 73.121775 -302.033499) (xy 73.132449 -301.985018) (xy 73.150826 -301.938902) (xy 73.176421 -301.896368)
			(xy 73.208561 -301.858534) (xy 73.246398 -301.826399) (xy 73.288936 -301.800809) (xy 73.335054 -301.782438)
			(xy 73.383536 -301.77177) (xy 73.433106 -301.769086) (xy 73.482456 -301.774457) (xy 73.530288 -301.787742)
			(xy 73.57534 -301.80859) (xy 73.616426 -301.836452) (xy 73.652462 -301.870594) (xy 73.682501 -301.910117)
			(xy 73.705749 -301.953979) (xy 73.721595 -302.001024) (xy 73.729621 -302.050013) (xy 73.730104 -302.074834)
			(xy 73.729932 -302.089017) (xy 73.727257 -302.117257) (xy 73.72477 -302.131222) (xy 73.722484 -302.143668)
			(xy 73.72985 -302.16729) (xy 73.80732 -302.24476) (xy 73.830942 -302.252126) (xy 73.843388 -302.24984)
			(xy 73.857355 -302.247369) (xy 73.885594 -302.244694) (xy 73.899776 -302.244506) (xy 73.913959 -302.244686)
			(xy 73.942199 -302.247356) (xy 73.956164 -302.24984) (xy 73.96861 -302.252126) (xy 73.992232 -302.24476)
			(xy 74.069702 -302.16729) (xy 74.077068 -302.143668) (xy 74.074782 -302.131222) (xy 74.072299 -302.117257)
			(xy 74.069631 -302.089017) (xy 74.069448 -302.074834) (xy 74.069941 -302.050009) (xy 74.077969 -302.001012)
			(xy 74.093818 -301.95396) (xy 74.11707 -301.910092) (xy 74.147114 -301.870563) (xy 74.183158 -301.836417)
			(xy 74.224251 -301.808551) (xy 74.269311 -301.787702) (xy 74.31715 -301.774417) (xy 74.366509 -301.769047)
			(xy 74.416086 -301.771734) (xy 74.464575 -301.782407) (xy 74.510699 -301.800784) (xy 74.553242 -301.826381)
			(xy 74.591083 -301.858524) (xy 74.623225 -301.896366) (xy 74.648821 -301.93891) (xy 74.667196 -301.985034)
			(xy 74.677867 -302.033524) (xy 74.680552 -302.083101) (xy 74.675181 -302.13246) (xy 74.661895 -302.180299)
			(xy 74.641044 -302.225358) (xy 74.613177 -302.26645) (xy 74.579029 -302.302492) (xy 74.5395 -302.332535)
			(xy 74.495631 -302.355786) (xy 74.448578 -302.371634) (xy 74.399581 -302.379659) (xy 74.374756 -302.380142)
			(xy 74.360573 -302.379957) (xy 74.332333 -302.37729) (xy 74.318368 -302.374808) (xy 74.305922 -302.372522)
			(xy 74.2823 -302.379888) (xy 74.20483 -302.457358) (xy 74.197464 -302.48098) (xy 74.19975 -302.493426)
			(xy 74.202226 -302.507392) (xy 74.204898 -302.535632) (xy 74.205084 -302.549814) (xy 74.204562 -302.575069)
			(xy 74.196249 -302.624891) (xy 74.179848 -302.672665) (xy 74.155807 -302.717088) (xy 74.124783 -302.756948)
			(xy 74.087621 -302.791158) (xy 74.045335 -302.818784) (xy 73.999079 -302.839074) (xy 73.950114 -302.851474)
			(xy 73.899776 -302.855645) (xy 73.849438 -302.851474) (xy 73.800473 -302.839074) (xy 73.754217 -302.818784)
			(xy 73.711931 -302.791158) (xy 73.674769 -302.756948) (xy 73.643745 -302.717088) (xy 73.619704 -302.672665)
			(xy 73.603303 -302.624891) (xy 73.59499 -302.575069) (xy 73.594468 -302.549814) (xy 73.594647 -302.535631)
			(xy 73.597318 -302.507391) (xy 73.599802 -302.493426) (xy 73.602088 -302.48098) (xy 73.594722 -302.457358)
			(xy 73.517252 -302.379888) (xy 73.49363 -302.372522) (xy 73.481184 -302.374808) (xy 73.467218 -302.377283)
			(xy 73.438978 -302.379956) (xy 73.424796 -302.380142) (xy 73.399975 -302.379618) (xy 73.350987 -302.371586)
			(xy 73.303944 -302.355734) (xy 73.260085 -302.33248) (xy 73.220566 -302.302437) (xy 73.186428 -302.266396)
			(xy 73.158571 -302.225307) (xy 73.137729 -302.180252) (xy 73.12445 -302.132419) (xy 73.119085 -302.083068)
			(xy 72.779978 -302.083068) (xy 72.779649 -302.099441) (xy 72.771754 -302.148018) (xy 72.75617 -302.194699)
			(xy 72.733299 -302.238276) (xy 72.703734 -302.27762) (xy 72.668241 -302.311712) (xy 72.627738 -302.339668)
			(xy 72.583276 -302.360766) (xy 72.536005 -302.374458) (xy 72.48715 -302.38039) (xy 72.437975 -302.378409)
			(xy 72.389756 -302.368565) (xy 72.34374 -302.351113) (xy 72.301119 -302.326506) (xy 72.262998 -302.295381)
			(xy 72.230363 -302.258544) (xy 72.20406 -302.216948) (xy 72.184769 -302.171672) (xy 72.172992 -302.123888)
			(xy 72.169032 -302.074834) (xy 71.830184 -302.074834) (xy 71.829689 -302.099441) (xy 71.821794 -302.148018)
			(xy 71.80621 -302.194699) (xy 71.783339 -302.238276) (xy 71.753774 -302.27762) (xy 71.718281 -302.311712)
			(xy 71.677778 -302.339668) (xy 71.633316 -302.360766) (xy 71.586045 -302.374458) (xy 71.53719 -302.38039)
			(xy 71.488015 -302.378409) (xy 71.439796 -302.368565) (xy 71.39378 -302.351113) (xy 71.351159 -302.326506)
			(xy 71.313038 -302.295381) (xy 71.280403 -302.258544) (xy 71.2541 -302.216948) (xy 71.234809 -302.171672)
			(xy 71.223032 -302.123888) (xy 71.219072 -302.074834) (xy 70.880224 -302.074834) (xy 70.879729 -302.099441)
			(xy 70.871834 -302.148018) (xy 70.85625 -302.194699) (xy 70.833379 -302.238276) (xy 70.803814 -302.27762)
			(xy 70.768321 -302.311712) (xy 70.727818 -302.339668) (xy 70.683356 -302.360766) (xy 70.636085 -302.374458)
			(xy 70.58723 -302.38039) (xy 70.538055 -302.378409) (xy 70.489836 -302.368565) (xy 70.44382 -302.351113)
			(xy 70.401199 -302.326506) (xy 70.363078 -302.295381) (xy 70.330443 -302.258544) (xy 70.30414 -302.216948)
			(xy 70.284849 -302.171672) (xy 70.273072 -302.123888) (xy 70.269112 -302.074834) (xy 69.930264 -302.074834)
			(xy 69.929769 -302.099441) (xy 69.921874 -302.148018) (xy 69.90629 -302.194699) (xy 69.883419 -302.238276)
			(xy 69.853854 -302.27762) (xy 69.818361 -302.311712) (xy 69.777858 -302.339668) (xy 69.733396 -302.360766)
			(xy 69.686125 -302.374458) (xy 69.63727 -302.38039) (xy 69.588095 -302.378409) (xy 69.539876 -302.368565)
			(xy 69.49386 -302.351113) (xy 69.451239 -302.326506) (xy 69.413118 -302.295381) (xy 69.380483 -302.258544)
			(xy 69.35418 -302.216948) (xy 69.334889 -302.171672) (xy 69.323112 -302.123888) (xy 69.319152 -302.074834)
			(xy 68.98005 -302.074834) (xy 68.979555 -302.099441) (xy 68.97166 -302.148018) (xy 68.956076 -302.194699)
			(xy 68.933205 -302.238276) (xy 68.90364 -302.27762) (xy 68.868147 -302.311712) (xy 68.827644 -302.339668)
			(xy 68.783182 -302.360766) (xy 68.735911 -302.374458) (xy 68.687056 -302.38039) (xy 68.637881 -302.378409)
			(xy 68.589662 -302.368565) (xy 68.543646 -302.351113) (xy 68.501025 -302.326506) (xy 68.462904 -302.295381)
			(xy 68.430269 -302.258544) (xy 68.403966 -302.216948) (xy 68.384675 -302.171672) (xy 68.372898 -302.123888)
			(xy 68.368938 -302.074834) (xy 68.03009 -302.074834) (xy 68.029595 -302.099441) (xy 68.0217 -302.148018)
			(xy 68.006116 -302.194699) (xy 67.983245 -302.238276) (xy 67.95368 -302.27762) (xy 67.918187 -302.311712)
			(xy 67.877684 -302.339668) (xy 67.833222 -302.360766) (xy 67.785951 -302.374458) (xy 67.737096 -302.38039)
			(xy 67.687921 -302.378409) (xy 67.639702 -302.368565) (xy 67.593686 -302.351113) (xy 67.551065 -302.326506)
			(xy 67.512944 -302.295381) (xy 67.480309 -302.258544) (xy 67.454006 -302.216948) (xy 67.434715 -302.171672)
			(xy 67.422938 -302.123888) (xy 67.418978 -302.074834) (xy 67.08013 -302.074834) (xy 67.079635 -302.099441)
			(xy 67.07174 -302.148018) (xy 67.056156 -302.194699) (xy 67.033285 -302.238276) (xy 67.00372 -302.27762)
			(xy 66.968227 -302.311712) (xy 66.927724 -302.339668) (xy 66.883262 -302.360766) (xy 66.835991 -302.374458)
			(xy 66.787136 -302.38039) (xy 66.737961 -302.378409) (xy 66.689742 -302.368565) (xy 66.643726 -302.351113)
			(xy 66.601105 -302.326506) (xy 66.562984 -302.295381) (xy 66.530349 -302.258544) (xy 66.504046 -302.216948)
			(xy 66.484755 -302.171672) (xy 66.472978 -302.123888) (xy 66.469018 -302.074834) (xy 66.13017 -302.074834)
			(xy 66.129675 -302.099441) (xy 66.12178 -302.148018) (xy 66.106196 -302.194699) (xy 66.083325 -302.238276)
			(xy 66.05376 -302.27762) (xy 66.018267 -302.311712) (xy 65.977764 -302.339668) (xy 65.933302 -302.360766)
			(xy 65.886031 -302.374458) (xy 65.837176 -302.38039) (xy 65.788001 -302.378409) (xy 65.739782 -302.368565)
			(xy 65.693766 -302.351113) (xy 65.651145 -302.326506) (xy 65.613024 -302.295381) (xy 65.580389 -302.258544)
			(xy 65.554086 -302.216948) (xy 65.534795 -302.171672) (xy 65.523018 -302.123888) (xy 65.519058 -302.074834)
			(xy 65.18021 -302.074834) (xy 65.179715 -302.099441) (xy 65.17182 -302.148018) (xy 65.156236 -302.194699)
			(xy 65.133365 -302.238276) (xy 65.1038 -302.27762) (xy 65.068307 -302.311712) (xy 65.027804 -302.339668)
			(xy 64.983342 -302.360766) (xy 64.936071 -302.374458) (xy 64.887216 -302.38039) (xy 64.838041 -302.378409)
			(xy 64.789822 -302.368565) (xy 64.743806 -302.351113) (xy 64.701185 -302.326506) (xy 64.663064 -302.295381)
			(xy 64.630429 -302.258544) (xy 64.604126 -302.216948) (xy 64.584835 -302.171672) (xy 64.573058 -302.123888)
			(xy 64.569098 -302.074834) (xy 64.23025 -302.074834) (xy 64.229755 -302.099441) (xy 64.22186 -302.148018)
			(xy 64.206276 -302.194699) (xy 64.183405 -302.238276) (xy 64.15384 -302.27762) (xy 64.118347 -302.311712)
			(xy 64.077844 -302.339668) (xy 64.033382 -302.360766) (xy 63.986111 -302.374458) (xy 63.937256 -302.38039)
			(xy 63.888081 -302.378409) (xy 63.839862 -302.368565) (xy 63.793846 -302.351113) (xy 63.751225 -302.326506)
			(xy 63.713104 -302.295381) (xy 63.680469 -302.258544) (xy 63.654166 -302.216948) (xy 63.634875 -302.171672)
			(xy 63.623098 -302.123888) (xy 63.619138 -302.074834) (xy 63.28029 -302.074834) (xy 63.279795 -302.099441)
			(xy 63.2719 -302.148018) (xy 63.256316 -302.194699) (xy 63.233445 -302.238276) (xy 63.20388 -302.27762)
			(xy 63.168387 -302.311712) (xy 63.127884 -302.339668) (xy 63.083422 -302.360766) (xy 63.036151 -302.374458)
			(xy 62.987296 -302.38039) (xy 62.938121 -302.378409) (xy 62.889902 -302.368565) (xy 62.843886 -302.351113)
			(xy 62.801265 -302.326506) (xy 62.763144 -302.295381) (xy 62.730509 -302.258544) (xy 62.704206 -302.216948)
			(xy 62.684915 -302.171672) (xy 62.673138 -302.123888) (xy 62.669178 -302.074834) (xy 62.330076 -302.074834)
			(xy 62.329581 -302.099441) (xy 62.321686 -302.148018) (xy 62.306102 -302.194699) (xy 62.283231 -302.238276)
			(xy 62.253666 -302.27762) (xy 62.218173 -302.311712) (xy 62.17767 -302.339668) (xy 62.133208 -302.360766)
			(xy 62.085937 -302.374458) (xy 62.037082 -302.38039) (xy 61.987907 -302.378409) (xy 61.939688 -302.368565)
			(xy 61.893672 -302.351113) (xy 61.851051 -302.326506) (xy 61.81293 -302.295381) (xy 61.780295 -302.258544)
			(xy 61.753992 -302.216948) (xy 61.734701 -302.171672) (xy 61.722924 -302.123888) (xy 61.718964 -302.074834)
			(xy 61.380116 -302.074834) (xy 61.379621 -302.099441) (xy 61.371726 -302.148018) (xy 61.356142 -302.194699)
			(xy 61.333271 -302.238276) (xy 61.303706 -302.27762) (xy 61.268213 -302.311712) (xy 61.22771 -302.339668)
			(xy 61.183248 -302.360766) (xy 61.135977 -302.374458) (xy 61.087122 -302.38039) (xy 61.037947 -302.378409)
			(xy 60.989728 -302.368565) (xy 60.943712 -302.351113) (xy 60.901091 -302.326506) (xy 60.86297 -302.295381)
			(xy 60.830335 -302.258544) (xy 60.804032 -302.216948) (xy 60.784741 -302.171672) (xy 60.772964 -302.123888)
			(xy 60.769004 -302.074834) (xy 60.430156 -302.074834) (xy 60.429661 -302.099441) (xy 60.421766 -302.148018)
			(xy 60.406182 -302.194699) (xy 60.383311 -302.238276) (xy 60.353746 -302.27762) (xy 60.318253 -302.311712)
			(xy 60.27775 -302.339668) (xy 60.233288 -302.360766) (xy 60.186017 -302.374458) (xy 60.137162 -302.38039)
			(xy 60.087987 -302.378409) (xy 60.039768 -302.368565) (xy 59.993752 -302.351113) (xy 59.951131 -302.326506)
			(xy 59.91301 -302.295381) (xy 59.880375 -302.258544) (xy 59.854072 -302.216948) (xy 59.834781 -302.171672)
			(xy 59.823004 -302.123888) (xy 59.819044 -302.074834) (xy 58.530236 -302.074834) (xy 58.529741 -302.099441)
			(xy 58.521846 -302.148018) (xy 58.506262 -302.194699) (xy 58.483391 -302.238276) (xy 58.453826 -302.27762)
			(xy 58.418333 -302.311712) (xy 58.37783 -302.339668) (xy 58.333368 -302.360766) (xy 58.286097 -302.374458)
			(xy 58.237242 -302.38039) (xy 58.188067 -302.378409) (xy 58.139848 -302.368565) (xy 58.093832 -302.351113)
			(xy 58.051211 -302.326506) (xy 58.01309 -302.295381) (xy 57.980455 -302.258544) (xy 57.954152 -302.216948)
			(xy 57.934861 -302.171672) (xy 57.923084 -302.123888) (xy 57.919124 -302.074834) (xy 57.580276 -302.074834)
			(xy 57.579781 -302.099441) (xy 57.571886 -302.148018) (xy 57.556302 -302.194699) (xy 57.533431 -302.238276)
			(xy 57.503866 -302.27762) (xy 57.468373 -302.311712) (xy 57.42787 -302.339668) (xy 57.383408 -302.360766)
			(xy 57.336137 -302.374458) (xy 57.287282 -302.38039) (xy 57.238107 -302.378409) (xy 57.189888 -302.368565)
			(xy 57.143872 -302.351113) (xy 57.101251 -302.326506) (xy 57.06313 -302.295381) (xy 57.030495 -302.258544)
			(xy 57.004192 -302.216948) (xy 56.984901 -302.171672) (xy 56.973124 -302.123888) (xy 56.969164 -302.074834)
			(xy 56.630062 -302.074834) (xy 56.629567 -302.099441) (xy 56.621672 -302.148018) (xy 56.606088 -302.194699)
			(xy 56.583217 -302.238276) (xy 56.553652 -302.27762) (xy 56.518159 -302.311712) (xy 56.477656 -302.339668)
			(xy 56.433194 -302.360766) (xy 56.385923 -302.374458) (xy 56.337068 -302.38039) (xy 56.287893 -302.378409)
			(xy 56.239674 -302.368565) (xy 56.193658 -302.351113) (xy 56.151037 -302.326506) (xy 56.112916 -302.295381)
			(xy 56.080281 -302.258544) (xy 56.053978 -302.216948) (xy 56.034687 -302.171672) (xy 56.02291 -302.123888)
			(xy 56.01895 -302.074834) (xy 55.680102 -302.074834) (xy 55.679607 -302.099441) (xy 55.671712 -302.148018)
			(xy 55.656128 -302.194699) (xy 55.633257 -302.238276) (xy 55.603692 -302.27762) (xy 55.568199 -302.311712)
			(xy 55.527696 -302.339668) (xy 55.483234 -302.360766) (xy 55.435963 -302.374458) (xy 55.387108 -302.38039)
			(xy 55.337933 -302.378409) (xy 55.289714 -302.368565) (xy 55.243698 -302.351113) (xy 55.201077 -302.326506)
			(xy 55.162956 -302.295381) (xy 55.130321 -302.258544) (xy 55.104018 -302.216948) (xy 55.084727 -302.171672)
			(xy 55.07295 -302.123888) (xy 55.06899 -302.074834) (xy 54.730142 -302.074834) (xy 54.729647 -302.099441)
			(xy 54.721752 -302.148018) (xy 54.706168 -302.194699) (xy 54.683297 -302.238276) (xy 54.653732 -302.27762)
			(xy 54.618239 -302.311712) (xy 54.577736 -302.339668) (xy 54.533274 -302.360766) (xy 54.486003 -302.374458)
			(xy 54.437148 -302.38039) (xy 54.387973 -302.378409) (xy 54.339754 -302.368565) (xy 54.293738 -302.351113)
			(xy 54.251117 -302.326506) (xy 54.212996 -302.295381) (xy 54.180361 -302.258544) (xy 54.154058 -302.216948)
			(xy 54.134767 -302.171672) (xy 54.12299 -302.123888) (xy 54.11903 -302.074834) (xy 53.780182 -302.074834)
			(xy 53.779687 -302.099441) (xy 53.771792 -302.148018) (xy 53.756208 -302.194699) (xy 53.733337 -302.238276)
			(xy 53.703772 -302.27762) (xy 53.668279 -302.311712) (xy 53.627776 -302.339668) (xy 53.583314 -302.360766)
			(xy 53.536043 -302.374458) (xy 53.487188 -302.38039) (xy 53.438013 -302.378409) (xy 53.389794 -302.368565)
			(xy 53.343778 -302.351113) (xy 53.301157 -302.326506) (xy 53.263036 -302.295381) (xy 53.230401 -302.258544)
			(xy 53.204098 -302.216948) (xy 53.184807 -302.171672) (xy 53.17303 -302.123888) (xy 53.16907 -302.074834)
			(xy 52.830222 -302.074834) (xy 52.829727 -302.099441) (xy 52.821832 -302.148018) (xy 52.806248 -302.194699)
			(xy 52.783377 -302.238276) (xy 52.753812 -302.27762) (xy 52.718319 -302.311712) (xy 52.677816 -302.339668)
			(xy 52.633354 -302.360766) (xy 52.586083 -302.374458) (xy 52.537228 -302.38039) (xy 52.488053 -302.378409)
			(xy 52.439834 -302.368565) (xy 52.393818 -302.351113) (xy 52.351197 -302.326506) (xy 52.313076 -302.295381)
			(xy 52.280441 -302.258544) (xy 52.254138 -302.216948) (xy 52.234847 -302.171672) (xy 52.22307 -302.123888)
			(xy 52.21911 -302.074834) (xy 51.880262 -302.074834) (xy 51.879767 -302.099441) (xy 51.871872 -302.148018)
			(xy 51.856288 -302.194699) (xy 51.833417 -302.238276) (xy 51.803852 -302.27762) (xy 51.768359 -302.311712)
			(xy 51.727856 -302.339668) (xy 51.683394 -302.360766) (xy 51.636123 -302.374458) (xy 51.587268 -302.38039)
			(xy 51.538093 -302.378409) (xy 51.489874 -302.368565) (xy 51.443858 -302.351113) (xy 51.401237 -302.326506)
			(xy 51.363116 -302.295381) (xy 51.330481 -302.258544) (xy 51.304178 -302.216948) (xy 51.284887 -302.171672)
			(xy 51.27311 -302.123888) (xy 51.26915 -302.074834) (xy 50.930302 -302.074834) (xy 50.929807 -302.099441)
			(xy 50.921912 -302.148018) (xy 50.906328 -302.194699) (xy 50.883457 -302.238276) (xy 50.853892 -302.27762)
			(xy 50.818399 -302.311712) (xy 50.777896 -302.339668) (xy 50.733434 -302.360766) (xy 50.686163 -302.374458)
			(xy 50.637308 -302.38039) (xy 50.588133 -302.378409) (xy 50.539914 -302.368565) (xy 50.493898 -302.351113)
			(xy 50.451277 -302.326506) (xy 50.413156 -302.295381) (xy 50.380521 -302.258544) (xy 50.354218 -302.216948)
			(xy 50.334927 -302.171672) (xy 50.32315 -302.123888) (xy 50.31919 -302.074834) (xy 49.980088 -302.074834)
			(xy 49.979593 -302.099441) (xy 49.971698 -302.148018) (xy 49.956114 -302.194699) (xy 49.933243 -302.238276)
			(xy 49.903678 -302.27762) (xy 49.868185 -302.311712) (xy 49.827682 -302.339668) (xy 49.78322 -302.360766)
			(xy 49.735949 -302.374458) (xy 49.687094 -302.38039) (xy 49.637919 -302.378409) (xy 49.5897 -302.368565)
			(xy 49.543684 -302.351113) (xy 49.501063 -302.326506) (xy 49.462942 -302.295381) (xy 49.430307 -302.258544)
			(xy 49.404004 -302.216948) (xy 49.384713 -302.171672) (xy 49.372936 -302.123888) (xy 49.368976 -302.074834)
			(xy 23.4629 -302.074834) (xy 23.431082 -302.218816) (xy 23.38818 -302.376389) (xy 23.337715 -302.531704)
			(xy 23.33075 -302.550068) (xy 35.593794 -302.550068) (xy 35.597754 -302.501014) (xy 35.609531 -302.45323)
			(xy 35.628822 -302.407954) (xy 35.655125 -302.366358) (xy 35.68776 -302.329521) (xy 35.725881 -302.298396)
			(xy 35.768502 -302.273789) (xy 35.814518 -302.256337) (xy 35.862737 -302.246493) (xy 35.911912 -302.244512)
			(xy 35.960767 -302.250444) (xy 36.008038 -302.264136) (xy 36.0525 -302.285234) (xy 36.093003 -302.31319)
			(xy 36.128496 -302.347282) (xy 36.158061 -302.386626) (xy 36.180932 -302.430203) (xy 36.196516 -302.476884)
			(xy 36.204411 -302.525461) (xy 36.204906 -302.550068) (xy 36.204411 -302.574675) (xy 36.204273 -302.575522)
			(xy 36.523164 -302.575522) (xy 36.523164 -302.524106) (xy 36.531207 -302.473324) (xy 36.547095 -302.424425)
			(xy 36.570438 -302.378613) (xy 36.600659 -302.337017) (xy 36.637015 -302.300661) (xy 36.678611 -302.27044)
			(xy 36.724423 -302.247097) (xy 36.773322 -302.231209) (xy 36.824104 -302.223166) (xy 36.87552 -302.223166)
			(xy 36.926302 -302.231209) (xy 36.975201 -302.247097) (xy 37.021013 -302.27044) (xy 37.062609 -302.300661)
			(xy 37.098965 -302.337017) (xy 37.129186 -302.378613) (xy 37.152529 -302.424425) (xy 37.168417 -302.473324)
			(xy 37.17646 -302.524106) (xy 37.176964 -302.549814) (xy 37.17646 -302.575522) (xy 37.473124 -302.575522)
			(xy 37.473124 -302.524106) (xy 37.481167 -302.473324) (xy 37.497055 -302.424425) (xy 37.520398 -302.378613)
			(xy 37.550619 -302.337017) (xy 37.586975 -302.300661) (xy 37.628571 -302.27044) (xy 37.674383 -302.247097)
			(xy 37.723282 -302.231209) (xy 37.774064 -302.223166) (xy 37.82548 -302.223166) (xy 37.876262 -302.231209)
			(xy 37.925161 -302.247097) (xy 37.970973 -302.27044) (xy 38.012569 -302.300661) (xy 38.048925 -302.337017)
			(xy 38.079146 -302.378613) (xy 38.102489 -302.424425) (xy 38.118377 -302.473324) (xy 38.12642 -302.524106)
			(xy 38.126924 -302.549814) (xy 38.444182 -302.549814) (xy 38.448142 -302.50076) (xy 38.459919 -302.452976)
			(xy 38.47921 -302.4077) (xy 38.505513 -302.366104) (xy 38.538148 -302.329267) (xy 38.576269 -302.298142)
			(xy 38.61889 -302.273535) (xy 38.664906 -302.256083) (xy 38.713125 -302.246239) (xy 38.7623 -302.244258)
			(xy 38.811155 -302.25019) (xy 38.858426 -302.263882) (xy 38.902888 -302.28498) (xy 38.943391 -302.312936)
			(xy 38.978884 -302.347028) (xy 39.008449 -302.386372) (xy 39.03132 -302.429949) (xy 39.046904 -302.47663)
			(xy 39.054799 -302.525207) (xy 39.055294 -302.549814) (xy 39.394142 -302.549814) (xy 39.398102 -302.50076)
			(xy 39.409879 -302.452976) (xy 39.42917 -302.4077) (xy 39.455473 -302.366104) (xy 39.488108 -302.329267)
			(xy 39.526229 -302.298142) (xy 39.56885 -302.273535) (xy 39.614866 -302.256083) (xy 39.663085 -302.246239)
			(xy 39.71226 -302.244258) (xy 39.761115 -302.25019) (xy 39.808386 -302.263882) (xy 39.852848 -302.28498)
			(xy 39.893351 -302.312936) (xy 39.928844 -302.347028) (xy 39.958409 -302.386372) (xy 39.98128 -302.429949)
			(xy 39.996864 -302.47663) (xy 40.004759 -302.525207) (xy 40.005254 -302.549814) (xy 40.344102 -302.549814)
			(xy 40.348062 -302.50076) (xy 40.359839 -302.452976) (xy 40.37913 -302.4077) (xy 40.405433 -302.366104)
			(xy 40.438068 -302.329267) (xy 40.476189 -302.298142) (xy 40.51881 -302.273535) (xy 40.564826 -302.256083)
			(xy 40.613045 -302.246239) (xy 40.66222 -302.244258) (xy 40.711075 -302.25019) (xy 40.758346 -302.263882)
			(xy 40.802808 -302.28498) (xy 40.843311 -302.312936) (xy 40.878804 -302.347028) (xy 40.908369 -302.386372)
			(xy 40.93124 -302.429949) (xy 40.946824 -302.47663) (xy 40.954719 -302.525207) (xy 40.955214 -302.549814)
			(xy 41.294062 -302.549814) (xy 41.298022 -302.50076) (xy 41.309799 -302.452976) (xy 41.32909 -302.4077)
			(xy 41.355393 -302.366104) (xy 41.388028 -302.329267) (xy 41.426149 -302.298142) (xy 41.46877 -302.273535)
			(xy 41.514786 -302.256083) (xy 41.563005 -302.246239) (xy 41.61218 -302.244258) (xy 41.661035 -302.25019)
			(xy 41.708306 -302.263882) (xy 41.752768 -302.28498) (xy 41.793271 -302.312936) (xy 41.828764 -302.347028)
			(xy 41.858329 -302.386372) (xy 41.8812 -302.429949) (xy 41.896784 -302.47663) (xy 41.904679 -302.525207)
			(xy 41.905174 -302.549814) (xy 42.244022 -302.549814) (xy 42.247982 -302.50076) (xy 42.259759 -302.452976)
			(xy 42.27905 -302.4077) (xy 42.305353 -302.366104) (xy 42.337988 -302.329267) (xy 42.376109 -302.298142)
			(xy 42.41873 -302.273535) (xy 42.464746 -302.256083) (xy 42.512965 -302.246239) (xy 42.56214 -302.244258)
			(xy 42.610995 -302.25019) (xy 42.658266 -302.263882) (xy 42.702728 -302.28498) (xy 42.743231 -302.312936)
			(xy 42.778724 -302.347028) (xy 42.808289 -302.386372) (xy 42.83116 -302.429949) (xy 42.846744 -302.47663)
			(xy 42.854639 -302.525207) (xy 42.855134 -302.549814) (xy 42.854639 -302.574421) (xy 42.85446 -302.575522)
			(xy 43.173138 -302.575522) (xy 43.173138 -302.524106) (xy 43.181181 -302.473324) (xy 43.197069 -302.424425)
			(xy 43.220412 -302.378613) (xy 43.250633 -302.337017) (xy 43.286989 -302.300661) (xy 43.328585 -302.27044)
			(xy 43.374397 -302.247097) (xy 43.423296 -302.231209) (xy 43.474078 -302.223166) (xy 43.525494 -302.223166)
			(xy 43.576276 -302.231209) (xy 43.625175 -302.247097) (xy 43.670987 -302.27044) (xy 43.712583 -302.300661)
			(xy 43.748939 -302.337017) (xy 43.77916 -302.378613) (xy 43.802503 -302.424425) (xy 43.818391 -302.473324)
			(xy 43.826434 -302.524106) (xy 43.826938 -302.549814) (xy 43.826434 -302.575522) (xy 44.123098 -302.575522)
			(xy 44.123098 -302.524106) (xy 44.131141 -302.473324) (xy 44.147029 -302.424425) (xy 44.170372 -302.378613)
			(xy 44.200593 -302.337017) (xy 44.236949 -302.300661) (xy 44.278545 -302.27044) (xy 44.324357 -302.247097)
			(xy 44.373256 -302.231209) (xy 44.424038 -302.223166) (xy 44.475454 -302.223166) (xy 44.526236 -302.231209)
			(xy 44.575135 -302.247097) (xy 44.620947 -302.27044) (xy 44.662543 -302.300661) (xy 44.698899 -302.337017)
			(xy 44.72912 -302.378613) (xy 44.752463 -302.424425) (xy 44.768351 -302.473324) (xy 44.776394 -302.524106)
			(xy 44.776898 -302.549814) (xy 45.094156 -302.549814) (xy 45.098116 -302.50076) (xy 45.109893 -302.452976)
			(xy 45.129184 -302.4077) (xy 45.155487 -302.366104) (xy 45.188122 -302.329267) (xy 45.226243 -302.298142)
			(xy 45.268864 -302.273535) (xy 45.31488 -302.256083) (xy 45.363099 -302.246239) (xy 45.412274 -302.244258)
			(xy 45.461129 -302.25019) (xy 45.5084 -302.263882) (xy 45.552862 -302.28498) (xy 45.593365 -302.312936)
			(xy 45.628858 -302.347028) (xy 45.658423 -302.386372) (xy 45.681294 -302.429949) (xy 45.696878 -302.47663)
			(xy 45.704773 -302.525207) (xy 45.705268 -302.549814) (xy 45.705101 -302.558091) (xy 46.044161 -302.558091)
			(xy 46.046848 -302.508518) (xy 46.057519 -302.460032) (xy 46.075894 -302.413912) (xy 46.101489 -302.371372)
			(xy 46.133629 -302.333533) (xy 46.171467 -302.301392) (xy 46.214006 -302.275797) (xy 46.260126 -302.257421)
			(xy 46.308612 -302.246749) (xy 46.358185 -302.244061) (xy 46.40754 -302.249429) (xy 46.455376 -302.262712)
			(xy 46.500434 -302.283559) (xy 46.541525 -302.31142) (xy 46.577567 -302.345563) (xy 46.60761 -302.385087)
			(xy 46.630863 -302.428951) (xy 46.646713 -302.475998) (xy 46.654743 -302.524991) (xy 46.655228 -302.549814)
			(xy 46.655053 -302.563997) (xy 46.65238 -302.592237) (xy 46.649894 -302.606202) (xy 46.647715 -302.620166)
			(xy 46.650295 -302.648301) (xy 46.660486 -302.674651) (xy 46.677509 -302.697199) (xy 46.700059 -302.714219)
			(xy 46.72641 -302.724408) (xy 46.754545 -302.726985) (xy 46.768512 -302.72482) (xy 46.782478 -302.722346)
			(xy 46.810718 -302.719673) (xy 46.8249 -302.719486) (xy 46.849721 -302.719978) (xy 46.898709 -302.728009)
			(xy 46.945752 -302.74386) (xy 46.989611 -302.767113) (xy 47.029131 -302.797155) (xy 47.063269 -302.833195)
			(xy 47.091128 -302.874283) (xy 47.111972 -302.919337) (xy 47.125252 -302.967169) (xy 47.130619 -303.01652)
			(xy 47.13017 -303.024794) (xy 47.469056 -303.024794) (xy 47.473016 -302.97574) (xy 47.484793 -302.927956)
			(xy 47.504084 -302.88268) (xy 47.530387 -302.841084) (xy 47.563022 -302.804247) (xy 47.601143 -302.773122)
			(xy 47.643764 -302.748515) (xy 47.68978 -302.731063) (xy 47.737999 -302.721219) (xy 47.787174 -302.719238)
			(xy 47.836029 -302.72517) (xy 47.8833 -302.738862) (xy 47.927762 -302.75996) (xy 47.968265 -302.787916)
			(xy 48.003758 -302.822008) (xy 48.033323 -302.861352) (xy 48.056194 -302.904929) (xy 48.071778 -302.95161)
			(xy 48.079673 -303.000187) (xy 48.080168 -303.024794) (xy 48.419016 -303.024794) (xy 48.422976 -302.97574)
			(xy 48.434753 -302.927956) (xy 48.454044 -302.88268) (xy 48.480347 -302.841084) (xy 48.512982 -302.804247)
			(xy 48.551103 -302.773122) (xy 48.593724 -302.748515) (xy 48.63974 -302.731063) (xy 48.687959 -302.721219)
			(xy 48.737134 -302.719238) (xy 48.785989 -302.72517) (xy 48.83326 -302.738862) (xy 48.877722 -302.75996)
			(xy 48.918225 -302.787916) (xy 48.953718 -302.822008) (xy 48.983283 -302.861352) (xy 49.006154 -302.904929)
			(xy 49.021738 -302.95161) (xy 49.029633 -303.000187) (xy 49.030128 -303.024794) (xy 49.368976 -303.024794)
			(xy 49.372936 -302.97574) (xy 49.384713 -302.927956) (xy 49.404004 -302.88268) (xy 49.430307 -302.841084)
			(xy 49.462942 -302.804247) (xy 49.501063 -302.773122) (xy 49.543684 -302.748515) (xy 49.5897 -302.731063)
			(xy 49.637919 -302.721219) (xy 49.687094 -302.719238) (xy 49.735949 -302.72517) (xy 49.78322 -302.738862)
			(xy 49.827682 -302.75996) (xy 49.868185 -302.787916) (xy 49.903678 -302.822008) (xy 49.933243 -302.861352)
			(xy 49.956114 -302.904929) (xy 49.971698 -302.95161) (xy 49.979593 -303.000187) (xy 49.980088 -303.024794)
			(xy 68.368938 -303.024794) (xy 68.372898 -302.97574) (xy 68.384675 -302.927956) (xy 68.403966 -302.88268)
			(xy 68.430269 -302.841084) (xy 68.462904 -302.804247) (xy 68.501025 -302.773122) (xy 68.543646 -302.748515)
			(xy 68.589662 -302.731063) (xy 68.637881 -302.721219) (xy 68.687056 -302.719238) (xy 68.735911 -302.72517)
			(xy 68.783182 -302.738862) (xy 68.827644 -302.75996) (xy 68.868147 -302.787916) (xy 68.90364 -302.822008)
			(xy 68.933205 -302.861352) (xy 68.956076 -302.904929) (xy 68.97166 -302.95161) (xy 68.979555 -303.000187)
			(xy 68.98005 -303.024794) (xy 69.319152 -303.024794) (xy 69.323112 -302.97574) (xy 69.334889 -302.927956)
			(xy 69.35418 -302.88268) (xy 69.380483 -302.841084) (xy 69.413118 -302.804247) (xy 69.451239 -302.773122)
			(xy 69.49386 -302.748515) (xy 69.539876 -302.731063) (xy 69.588095 -302.721219) (xy 69.63727 -302.719238)
			(xy 69.686125 -302.72517) (xy 69.733396 -302.738862) (xy 69.777858 -302.75996) (xy 69.818361 -302.787916)
			(xy 69.853854 -302.822008) (xy 69.883419 -302.861352) (xy 69.90629 -302.904929) (xy 69.921874 -302.95161)
			(xy 69.929769 -303.000187) (xy 69.930264 -303.024794) (xy 70.269112 -303.024794) (xy 70.273072 -302.97574)
			(xy 70.284849 -302.927956) (xy 70.30414 -302.88268) (xy 70.330443 -302.841084) (xy 70.363078 -302.804247)
			(xy 70.401199 -302.773122) (xy 70.44382 -302.748515) (xy 70.489836 -302.731063) (xy 70.538055 -302.721219)
			(xy 70.58723 -302.719238) (xy 70.636085 -302.72517) (xy 70.683356 -302.738862) (xy 70.727818 -302.75996)
			(xy 70.768321 -302.787916) (xy 70.803814 -302.822008) (xy 70.833379 -302.861352) (xy 70.85625 -302.904929)
			(xy 70.871834 -302.95161) (xy 70.879729 -303.000187) (xy 70.880224 -303.024794) (xy 71.219072 -303.024794)
			(xy 71.223032 -302.97574) (xy 71.234809 -302.927956) (xy 71.2541 -302.88268) (xy 71.280403 -302.841084)
			(xy 71.313038 -302.804247) (xy 71.351159 -302.773122) (xy 71.39378 -302.748515) (xy 71.439796 -302.731063)
			(xy 71.488015 -302.721219) (xy 71.53719 -302.719238) (xy 71.586045 -302.72517) (xy 71.633316 -302.738862)
			(xy 71.677778 -302.75996) (xy 71.718281 -302.787916) (xy 71.753774 -302.822008) (xy 71.783339 -302.861352)
			(xy 71.80621 -302.904929) (xy 71.821794 -302.95161) (xy 71.829689 -303.000187) (xy 71.830184 -303.024794)
			(xy 72.169032 -303.024794) (xy 72.172992 -302.97574) (xy 72.184769 -302.927956) (xy 72.20406 -302.88268)
			(xy 72.230363 -302.841084) (xy 72.262998 -302.804247) (xy 72.301119 -302.773122) (xy 72.34374 -302.748515)
			(xy 72.389756 -302.731063) (xy 72.437975 -302.721219) (xy 72.48715 -302.719238) (xy 72.536005 -302.72517)
			(xy 72.583276 -302.738862) (xy 72.627738 -302.75996) (xy 72.668241 -302.787916) (xy 72.703734 -302.822008)
			(xy 72.733299 -302.861352) (xy 72.75617 -302.904929) (xy 72.771754 -302.95161) (xy 72.779649 -303.000187)
			(xy 72.780144 -303.024794) (xy 76.919086 -303.024794) (xy 76.923046 -302.97574) (xy 76.934823 -302.927956)
			(xy 76.954114 -302.88268) (xy 76.980417 -302.841084) (xy 77.013052 -302.804247) (xy 77.051173 -302.773122)
			(xy 77.093794 -302.748515) (xy 77.13981 -302.731063) (xy 77.188029 -302.721219) (xy 77.237204 -302.719238)
			(xy 77.286059 -302.72517) (xy 77.33333 -302.738862) (xy 77.377792 -302.75996) (xy 77.418295 -302.787916)
			(xy 77.453788 -302.822008) (xy 77.483353 -302.861352) (xy 77.506224 -302.904929) (xy 77.521808 -302.95161)
			(xy 77.529703 -303.000187) (xy 77.530198 -303.024794) (xy 77.869046 -303.024794) (xy 77.873006 -302.97574)
			(xy 77.884783 -302.927956) (xy 77.904074 -302.88268) (xy 77.930377 -302.841084) (xy 77.963012 -302.804247)
			(xy 78.001133 -302.773122) (xy 78.043754 -302.748515) (xy 78.08977 -302.731063) (xy 78.137989 -302.721219)
			(xy 78.187164 -302.719238) (xy 78.236019 -302.72517) (xy 78.28329 -302.738862) (xy 78.327752 -302.75996)
			(xy 78.368255 -302.787916) (xy 78.403748 -302.822008) (xy 78.433313 -302.861352) (xy 78.456184 -302.904929)
			(xy 78.471768 -302.95161) (xy 78.479663 -303.000187) (xy 78.480158 -303.024794) (xy 78.479663 -303.049401)
			(xy 78.471768 -303.097978) (xy 78.456184 -303.144659) (xy 78.433313 -303.188236) (xy 78.403748 -303.22758)
			(xy 78.368255 -303.261672) (xy 78.327752 -303.289628) (xy 78.28329 -303.310726) (xy 78.236019 -303.324418)
			(xy 78.187164 -303.33035) (xy 78.137989 -303.328369) (xy 78.08977 -303.318525) (xy 78.043754 -303.301073)
			(xy 78.001133 -303.276466) (xy 77.963012 -303.245341) (xy 77.930377 -303.208504) (xy 77.904074 -303.166908)
			(xy 77.884783 -303.121632) (xy 77.873006 -303.073848) (xy 77.869046 -303.024794) (xy 77.530198 -303.024794)
			(xy 77.529703 -303.049401) (xy 77.521808 -303.097978) (xy 77.506224 -303.144659) (xy 77.483353 -303.188236)
			(xy 77.453788 -303.22758) (xy 77.418295 -303.261672) (xy 77.377792 -303.289628) (xy 77.33333 -303.310726)
			(xy 77.286059 -303.324418) (xy 77.237204 -303.33035) (xy 77.188029 -303.328369) (xy 77.13981 -303.318525)
			(xy 77.093794 -303.301073) (xy 77.051173 -303.276466) (xy 77.013052 -303.245341) (xy 76.980417 -303.208504)
			(xy 76.954114 -303.166908) (xy 76.934823 -303.121632) (xy 76.923046 -303.073848) (xy 76.919086 -303.024794)
			(xy 72.780144 -303.024794) (xy 72.779649 -303.049401) (xy 72.771754 -303.097978) (xy 72.75617 -303.144659)
			(xy 72.733299 -303.188236) (xy 72.703734 -303.22758) (xy 72.668241 -303.261672) (xy 72.627738 -303.289628)
			(xy 72.583276 -303.310726) (xy 72.536005 -303.324418) (xy 72.48715 -303.33035) (xy 72.437975 -303.328369)
			(xy 72.389756 -303.318525) (xy 72.34374 -303.301073) (xy 72.301119 -303.276466) (xy 72.262998 -303.245341)
			(xy 72.230363 -303.208504) (xy 72.20406 -303.166908) (xy 72.184769 -303.121632) (xy 72.172992 -303.073848)
			(xy 72.169032 -303.024794) (xy 71.830184 -303.024794) (xy 71.829689 -303.049401) (xy 71.821794 -303.097978)
			(xy 71.80621 -303.144659) (xy 71.783339 -303.188236) (xy 71.753774 -303.22758) (xy 71.718281 -303.261672)
			(xy 71.677778 -303.289628) (xy 71.633316 -303.310726) (xy 71.586045 -303.324418) (xy 71.53719 -303.33035)
			(xy 71.488015 -303.328369) (xy 71.439796 -303.318525) (xy 71.39378 -303.301073) (xy 71.351159 -303.276466)
			(xy 71.313038 -303.245341) (xy 71.280403 -303.208504) (xy 71.2541 -303.166908) (xy 71.234809 -303.121632)
			(xy 71.223032 -303.073848) (xy 71.219072 -303.024794) (xy 70.880224 -303.024794) (xy 70.879729 -303.049401)
			(xy 70.871834 -303.097978) (xy 70.85625 -303.144659) (xy 70.833379 -303.188236) (xy 70.803814 -303.22758)
			(xy 70.768321 -303.261672) (xy 70.727818 -303.289628) (xy 70.683356 -303.310726) (xy 70.636085 -303.324418)
			(xy 70.58723 -303.33035) (xy 70.538055 -303.328369) (xy 70.489836 -303.318525) (xy 70.44382 -303.301073)
			(xy 70.401199 -303.276466) (xy 70.363078 -303.245341) (xy 70.330443 -303.208504) (xy 70.30414 -303.166908)
			(xy 70.284849 -303.121632) (xy 70.273072 -303.073848) (xy 70.269112 -303.024794) (xy 69.930264 -303.024794)
			(xy 69.929769 -303.049401) (xy 69.921874 -303.097978) (xy 69.90629 -303.144659) (xy 69.883419 -303.188236)
			(xy 69.853854 -303.22758) (xy 69.818361 -303.261672) (xy 69.777858 -303.289628) (xy 69.733396 -303.310726)
			(xy 69.686125 -303.324418) (xy 69.63727 -303.33035) (xy 69.588095 -303.328369) (xy 69.539876 -303.318525)
			(xy 69.49386 -303.301073) (xy 69.451239 -303.276466) (xy 69.413118 -303.245341) (xy 69.380483 -303.208504)
			(xy 69.35418 -303.166908) (xy 69.334889 -303.121632) (xy 69.323112 -303.073848) (xy 69.319152 -303.024794)
			(xy 68.98005 -303.024794) (xy 68.979555 -303.049401) (xy 68.97166 -303.097978) (xy 68.956076 -303.144659)
			(xy 68.933205 -303.188236) (xy 68.90364 -303.22758) (xy 68.868147 -303.261672) (xy 68.827644 -303.289628)
			(xy 68.783182 -303.310726) (xy 68.735911 -303.324418) (xy 68.687056 -303.33035) (xy 68.637881 -303.328369)
			(xy 68.589662 -303.318525) (xy 68.543646 -303.301073) (xy 68.501025 -303.276466) (xy 68.462904 -303.245341)
			(xy 68.430269 -303.208504) (xy 68.403966 -303.166908) (xy 68.384675 -303.121632) (xy 68.372898 -303.073848)
			(xy 68.368938 -303.024794) (xy 49.980088 -303.024794) (xy 49.979593 -303.049401) (xy 49.971698 -303.097978)
			(xy 49.956114 -303.144659) (xy 49.933243 -303.188236) (xy 49.903678 -303.22758) (xy 49.868185 -303.261672)
			(xy 49.827682 -303.289628) (xy 49.78322 -303.310726) (xy 49.735949 -303.324418) (xy 49.687094 -303.33035)
			(xy 49.637919 -303.328369) (xy 49.5897 -303.318525) (xy 49.543684 -303.301073) (xy 49.501063 -303.276466)
			(xy 49.462942 -303.245341) (xy 49.430307 -303.208504) (xy 49.404004 -303.166908) (xy 49.384713 -303.121632)
			(xy 49.372936 -303.073848) (xy 49.368976 -303.024794) (xy 49.030128 -303.024794) (xy 49.029633 -303.049401)
			(xy 49.021738 -303.097978) (xy 49.006154 -303.144659) (xy 48.983283 -303.188236) (xy 48.953718 -303.22758)
			(xy 48.918225 -303.261672) (xy 48.877722 -303.289628) (xy 48.83326 -303.310726) (xy 48.785989 -303.324418)
			(xy 48.737134 -303.33035) (xy 48.687959 -303.328369) (xy 48.63974 -303.318525) (xy 48.593724 -303.301073)
			(xy 48.551103 -303.276466) (xy 48.512982 -303.245341) (xy 48.480347 -303.208504) (xy 48.454044 -303.166908)
			(xy 48.434753 -303.121632) (xy 48.422976 -303.073848) (xy 48.419016 -303.024794) (xy 48.080168 -303.024794)
			(xy 48.079673 -303.049401) (xy 48.071778 -303.097978) (xy 48.056194 -303.144659) (xy 48.033323 -303.188236)
			(xy 48.003758 -303.22758) (xy 47.968265 -303.261672) (xy 47.927762 -303.289628) (xy 47.8833 -303.310726)
			(xy 47.836029 -303.324418) (xy 47.787174 -303.33035) (xy 47.737999 -303.328369) (xy 47.68978 -303.318525)
			(xy 47.643764 -303.301073) (xy 47.601143 -303.276466) (xy 47.563022 -303.245341) (xy 47.530387 -303.208504)
			(xy 47.504084 -303.166908) (xy 47.484793 -303.121632) (xy 47.473016 -303.073848) (xy 47.469056 -303.024794)
			(xy 47.13017 -303.024794) (xy 47.127931 -303.066089) (xy 47.117259 -303.114571) (xy 47.098884 -303.160687)
			(xy 47.073291 -303.203222) (xy 47.041153 -303.241057) (xy 47.003318 -303.273194) (xy 46.960781 -303.298787)
			(xy 46.914665 -303.317161) (xy 46.866183 -303.327832) (xy 46.816614 -303.330519) (xy 46.767263 -303.325151)
			(xy 46.719431 -303.31187) (xy 46.674378 -303.291025) (xy 46.63329 -303.263166) (xy 46.597251 -303.229026)
			(xy 46.567209 -303.189506) (xy 46.543958 -303.145647) (xy 46.528108 -303.098603) (xy 46.520077 -303.049615)
			(xy 46.519592 -303.024794) (xy 46.519768 -303.010611) (xy 46.52244 -302.982371) (xy 46.524926 -302.968406)
			(xy 46.527073 -302.954438) (xy 46.524495 -302.926309) (xy 46.514308 -302.899963) (xy 46.497291 -302.877417)
			(xy 46.474747 -302.860398) (xy 46.448402 -302.850207) (xy 46.420273 -302.847627) (xy 46.406308 -302.849788)
			(xy 46.392341 -302.852259) (xy 46.364102 -302.854935) (xy 46.34992 -302.855122) (xy 46.325097 -302.854644)
			(xy 46.276104 -302.846615) (xy 46.229056 -302.830765) (xy 46.185192 -302.807513) (xy 46.145667 -302.777471)
			(xy 46.111524 -302.741429) (xy 46.083662 -302.700339) (xy 46.062814 -302.655282) (xy 46.049531 -302.607446)
			(xy 46.044161 -302.558091) (xy 45.705101 -302.558091) (xy 45.704773 -302.574421) (xy 45.696878 -302.622998)
			(xy 45.681294 -302.669679) (xy 45.658423 -302.713256) (xy 45.628858 -302.7526) (xy 45.593365 -302.786692)
			(xy 45.552862 -302.814648) (xy 45.5084 -302.835746) (xy 45.461129 -302.849438) (xy 45.412274 -302.85537)
			(xy 45.363099 -302.853389) (xy 45.31488 -302.843545) (xy 45.268864 -302.826093) (xy 45.226243 -302.801486)
			(xy 45.188122 -302.770361) (xy 45.155487 -302.733524) (xy 45.129184 -302.691928) (xy 45.109893 -302.646652)
			(xy 45.098116 -302.598868) (xy 45.094156 -302.549814) (xy 44.776898 -302.549814) (xy 44.776394 -302.575522)
			(xy 44.768351 -302.626304) (xy 44.752463 -302.675203) (xy 44.72912 -302.721015) (xy 44.698899 -302.762611)
			(xy 44.662543 -302.798967) (xy 44.620947 -302.829188) (xy 44.575135 -302.852531) (xy 44.526236 -302.868419)
			(xy 44.475454 -302.876462) (xy 44.424038 -302.876462) (xy 44.373256 -302.868419) (xy 44.324357 -302.852531)
			(xy 44.278545 -302.829188) (xy 44.236949 -302.798967) (xy 44.200593 -302.762611) (xy 44.170372 -302.721015)
			(xy 44.147029 -302.675203) (xy 44.131141 -302.626304) (xy 44.123098 -302.575522) (xy 43.826434 -302.575522)
			(xy 43.818391 -302.626304) (xy 43.802503 -302.675203) (xy 43.77916 -302.721015) (xy 43.748939 -302.762611)
			(xy 43.712583 -302.798967) (xy 43.670987 -302.829188) (xy 43.625175 -302.852531) (xy 43.576276 -302.868419)
			(xy 43.525494 -302.876462) (xy 43.474078 -302.876462) (xy 43.423296 -302.868419) (xy 43.374397 -302.852531)
			(xy 43.328585 -302.829188) (xy 43.286989 -302.798967) (xy 43.250633 -302.762611) (xy 43.220412 -302.721015)
			(xy 43.197069 -302.675203) (xy 43.181181 -302.626304) (xy 43.173138 -302.575522) (xy 42.85446 -302.575522)
			(xy 42.846744 -302.622998) (xy 42.83116 -302.669679) (xy 42.808289 -302.713256) (xy 42.778724 -302.7526)
			(xy 42.743231 -302.786692) (xy 42.702728 -302.814648) (xy 42.658266 -302.835746) (xy 42.610995 -302.849438)
			(xy 42.56214 -302.85537) (xy 42.512965 -302.853389) (xy 42.464746 -302.843545) (xy 42.41873 -302.826093)
			(xy 42.376109 -302.801486) (xy 42.337988 -302.770361) (xy 42.305353 -302.733524) (xy 42.27905 -302.691928)
			(xy 42.259759 -302.646652) (xy 42.247982 -302.598868) (xy 42.244022 -302.549814) (xy 41.905174 -302.549814)
			(xy 41.904679 -302.574421) (xy 41.896784 -302.622998) (xy 41.8812 -302.669679) (xy 41.858329 -302.713256)
			(xy 41.828764 -302.7526) (xy 41.793271 -302.786692) (xy 41.752768 -302.814648) (xy 41.708306 -302.835746)
			(xy 41.661035 -302.849438) (xy 41.61218 -302.85537) (xy 41.563005 -302.853389) (xy 41.514786 -302.843545)
			(xy 41.46877 -302.826093) (xy 41.426149 -302.801486) (xy 41.388028 -302.770361) (xy 41.355393 -302.733524)
			(xy 41.32909 -302.691928) (xy 41.309799 -302.646652) (xy 41.298022 -302.598868) (xy 41.294062 -302.549814)
			(xy 40.955214 -302.549814) (xy 40.954719 -302.574421) (xy 40.946824 -302.622998) (xy 40.93124 -302.669679)
			(xy 40.908369 -302.713256) (xy 40.878804 -302.7526) (xy 40.843311 -302.786692) (xy 40.802808 -302.814648)
			(xy 40.758346 -302.835746) (xy 40.711075 -302.849438) (xy 40.66222 -302.85537) (xy 40.613045 -302.853389)
			(xy 40.564826 -302.843545) (xy 40.51881 -302.826093) (xy 40.476189 -302.801486) (xy 40.438068 -302.770361)
			(xy 40.405433 -302.733524) (xy 40.37913 -302.691928) (xy 40.359839 -302.646652) (xy 40.348062 -302.598868)
			(xy 40.344102 -302.549814) (xy 40.005254 -302.549814) (xy 40.004759 -302.574421) (xy 39.996864 -302.622998)
			(xy 39.98128 -302.669679) (xy 39.958409 -302.713256) (xy 39.928844 -302.7526) (xy 39.893351 -302.786692)
			(xy 39.852848 -302.814648) (xy 39.808386 -302.835746) (xy 39.761115 -302.849438) (xy 39.71226 -302.85537)
			(xy 39.663085 -302.853389) (xy 39.614866 -302.843545) (xy 39.56885 -302.826093) (xy 39.526229 -302.801486)
			(xy 39.488108 -302.770361) (xy 39.455473 -302.733524) (xy 39.42917 -302.691928) (xy 39.409879 -302.646652)
			(xy 39.398102 -302.598868) (xy 39.394142 -302.549814) (xy 39.055294 -302.549814) (xy 39.054799 -302.574421)
			(xy 39.046904 -302.622998) (xy 39.03132 -302.669679) (xy 39.008449 -302.713256) (xy 38.978884 -302.7526)
			(xy 38.943391 -302.786692) (xy 38.902888 -302.814648) (xy 38.858426 -302.835746) (xy 38.811155 -302.849438)
			(xy 38.7623 -302.85537) (xy 38.713125 -302.853389) (xy 38.664906 -302.843545) (xy 38.61889 -302.826093)
			(xy 38.576269 -302.801486) (xy 38.538148 -302.770361) (xy 38.505513 -302.733524) (xy 38.47921 -302.691928)
			(xy 38.459919 -302.646652) (xy 38.448142 -302.598868) (xy 38.444182 -302.549814) (xy 38.126924 -302.549814)
			(xy 38.12642 -302.575522) (xy 38.118377 -302.626304) (xy 38.102489 -302.675203) (xy 38.079146 -302.721015)
			(xy 38.048925 -302.762611) (xy 38.012569 -302.798967) (xy 37.970973 -302.829188) (xy 37.925161 -302.852531)
			(xy 37.876262 -302.868419) (xy 37.82548 -302.876462) (xy 37.774064 -302.876462) (xy 37.723282 -302.868419)
			(xy 37.674383 -302.852531) (xy 37.628571 -302.829188) (xy 37.586975 -302.798967) (xy 37.550619 -302.762611)
			(xy 37.520398 -302.721015) (xy 37.497055 -302.675203) (xy 37.481167 -302.626304) (xy 37.473124 -302.575522)
			(xy 37.17646 -302.575522) (xy 37.168417 -302.626304) (xy 37.152529 -302.675203) (xy 37.129186 -302.721015)
			(xy 37.098965 -302.762611) (xy 37.062609 -302.798967) (xy 37.021013 -302.829188) (xy 36.975201 -302.852531)
			(xy 36.926302 -302.868419) (xy 36.87552 -302.876462) (xy 36.824104 -302.876462) (xy 36.773322 -302.868419)
			(xy 36.724423 -302.852531) (xy 36.678611 -302.829188) (xy 36.637015 -302.798967) (xy 36.600659 -302.762611)
			(xy 36.570438 -302.721015) (xy 36.547095 -302.675203) (xy 36.531207 -302.626304) (xy 36.523164 -302.575522)
			(xy 36.204273 -302.575522) (xy 36.196516 -302.623252) (xy 36.180932 -302.669933) (xy 36.158061 -302.71351)
			(xy 36.128496 -302.752854) (xy 36.093003 -302.786946) (xy 36.0525 -302.814902) (xy 36.008038 -302.836)
			(xy 35.960767 -302.849692) (xy 35.911912 -302.855624) (xy 35.862737 -302.853643) (xy 35.814518 -302.843799)
			(xy 35.768502 -302.826347) (xy 35.725881 -302.80174) (xy 35.68776 -302.770615) (xy 35.655125 -302.733778)
			(xy 35.628822 -302.692182) (xy 35.609531 -302.646906) (xy 35.597754 -302.599122) (xy 35.593794 -302.550068)
			(xy 23.33075 -302.550068) (xy 23.279805 -302.6844) (xy 23.214585 -302.83412) (xy 23.142208 -302.980514)
			(xy 23.062843 -303.12324) (xy 22.976675 -303.261966) (xy 22.883906 -303.396366) (xy 22.804888 -303.499774)
			(xy 36.544008 -303.499774) (xy 36.547968 -303.45072) (xy 36.559745 -303.402936) (xy 36.579036 -303.35766)
			(xy 36.605339 -303.316064) (xy 36.637974 -303.279227) (xy 36.676095 -303.248102) (xy 36.718716 -303.223495)
			(xy 36.764732 -303.206043) (xy 36.812951 -303.196199) (xy 36.862126 -303.194218) (xy 36.910981 -303.20015)
			(xy 36.958252 -303.213842) (xy 37.002714 -303.23494) (xy 37.043217 -303.262896) (xy 37.07871 -303.296988)
			(xy 37.108275 -303.336332) (xy 37.131146 -303.379909) (xy 37.14673 -303.42659) (xy 37.154625 -303.475167)
			(xy 37.15512 -303.499774) (xy 37.493968 -303.499774) (xy 37.497928 -303.45072) (xy 37.509705 -303.402936)
			(xy 37.528996 -303.35766) (xy 37.555299 -303.316064) (xy 37.587934 -303.279227) (xy 37.626055 -303.248102)
			(xy 37.668676 -303.223495) (xy 37.714692 -303.206043) (xy 37.762911 -303.196199) (xy 37.812086 -303.194218)
			(xy 37.860941 -303.20015) (xy 37.908212 -303.213842) (xy 37.952674 -303.23494) (xy 37.993177 -303.262896)
			(xy 38.02867 -303.296988) (xy 38.058235 -303.336332) (xy 38.081106 -303.379909) (xy 38.09669 -303.42659)
			(xy 38.104585 -303.475167) (xy 38.10508 -303.499774) (xy 38.104585 -303.524381) (xy 38.104406 -303.525482)
			(xy 38.423338 -303.525482) (xy 38.423338 -303.474066) (xy 38.431381 -303.423284) (xy 38.447269 -303.374385)
			(xy 38.470612 -303.328573) (xy 38.500833 -303.286977) (xy 38.537189 -303.250621) (xy 38.578785 -303.2204)
			(xy 38.624597 -303.197057) (xy 38.673496 -303.181169) (xy 38.724278 -303.173126) (xy 38.775694 -303.173126)
			(xy 38.826476 -303.181169) (xy 38.875375 -303.197057) (xy 38.921187 -303.2204) (xy 38.962783 -303.250621)
			(xy 38.999139 -303.286977) (xy 39.02936 -303.328573) (xy 39.052703 -303.374385) (xy 39.068591 -303.423284)
			(xy 39.076634 -303.474066) (xy 39.077138 -303.499774) (xy 39.076634 -303.525482) (xy 39.373298 -303.525482)
			(xy 39.373298 -303.474066) (xy 39.381341 -303.423284) (xy 39.397229 -303.374385) (xy 39.420572 -303.328573)
			(xy 39.450793 -303.286977) (xy 39.487149 -303.250621) (xy 39.528745 -303.2204) (xy 39.574557 -303.197057)
			(xy 39.623456 -303.181169) (xy 39.674238 -303.173126) (xy 39.725654 -303.173126) (xy 39.776436 -303.181169)
			(xy 39.825335 -303.197057) (xy 39.871147 -303.2204) (xy 39.912743 -303.250621) (xy 39.949099 -303.286977)
			(xy 39.97932 -303.328573) (xy 40.002663 -303.374385) (xy 40.018551 -303.423284) (xy 40.026594 -303.474066)
			(xy 40.027098 -303.499774) (xy 40.344102 -303.499774) (xy 40.348062 -303.45072) (xy 40.359839 -303.402936)
			(xy 40.37913 -303.35766) (xy 40.405433 -303.316064) (xy 40.438068 -303.279227) (xy 40.476189 -303.248102)
			(xy 40.51881 -303.223495) (xy 40.564826 -303.206043) (xy 40.613045 -303.196199) (xy 40.66222 -303.194218)
			(xy 40.711075 -303.20015) (xy 40.758346 -303.213842) (xy 40.802808 -303.23494) (xy 40.843311 -303.262896)
			(xy 40.878804 -303.296988) (xy 40.908369 -303.336332) (xy 40.93124 -303.379909) (xy 40.946824 -303.42659)
			(xy 40.954719 -303.475167) (xy 40.955214 -303.499774) (xy 40.954719 -303.524381) (xy 40.95454 -303.525482)
			(xy 41.273218 -303.525482) (xy 41.273218 -303.474066) (xy 41.281261 -303.423284) (xy 41.297149 -303.374385)
			(xy 41.320492 -303.328573) (xy 41.350713 -303.286977) (xy 41.387069 -303.250621) (xy 41.428665 -303.2204)
			(xy 41.474477 -303.197057) (xy 41.523376 -303.181169) (xy 41.574158 -303.173126) (xy 41.625574 -303.173126)
			(xy 41.676356 -303.181169) (xy 41.725255 -303.197057) (xy 41.771067 -303.2204) (xy 41.812663 -303.250621)
			(xy 41.849019 -303.286977) (xy 41.87924 -303.328573) (xy 41.902583 -303.374385) (xy 41.918471 -303.423284)
			(xy 41.926514 -303.474066) (xy 41.927018 -303.499774) (xy 41.926514 -303.525482) (xy 42.223178 -303.525482)
			(xy 42.223178 -303.474066) (xy 42.231221 -303.423284) (xy 42.247109 -303.374385) (xy 42.270452 -303.328573)
			(xy 42.300673 -303.286977) (xy 42.337029 -303.250621) (xy 42.378625 -303.2204) (xy 42.424437 -303.197057)
			(xy 42.473336 -303.181169) (xy 42.524118 -303.173126) (xy 42.575534 -303.173126) (xy 42.626316 -303.181169)
			(xy 42.675215 -303.197057) (xy 42.721027 -303.2204) (xy 42.762623 -303.250621) (xy 42.798979 -303.286977)
			(xy 42.8292 -303.328573) (xy 42.852543 -303.374385) (xy 42.868431 -303.423284) (xy 42.876474 -303.474066)
			(xy 42.876978 -303.499774) (xy 43.193982 -303.499774) (xy 43.197942 -303.45072) (xy 43.209719 -303.402936)
			(xy 43.22901 -303.35766) (xy 43.255313 -303.316064) (xy 43.287948 -303.279227) (xy 43.326069 -303.248102)
			(xy 43.36869 -303.223495) (xy 43.414706 -303.206043) (xy 43.462925 -303.196199) (xy 43.5121 -303.194218)
			(xy 43.560955 -303.20015) (xy 43.608226 -303.213842) (xy 43.652688 -303.23494) (xy 43.693191 -303.262896)
			(xy 43.728684 -303.296988) (xy 43.758249 -303.336332) (xy 43.78112 -303.379909) (xy 43.796704 -303.42659)
			(xy 43.804599 -303.475167) (xy 43.805094 -303.499774) (xy 44.143942 -303.499774) (xy 44.147902 -303.45072)
			(xy 44.159679 -303.402936) (xy 44.17897 -303.35766) (xy 44.205273 -303.316064) (xy 44.237908 -303.279227)
			(xy 44.276029 -303.248102) (xy 44.31865 -303.223495) (xy 44.364666 -303.206043) (xy 44.412885 -303.196199)
			(xy 44.46206 -303.194218) (xy 44.510915 -303.20015) (xy 44.558186 -303.213842) (xy 44.602648 -303.23494)
			(xy 44.643151 -303.262896) (xy 44.678644 -303.296988) (xy 44.708209 -303.336332) (xy 44.73108 -303.379909)
			(xy 44.746664 -303.42659) (xy 44.754559 -303.475167) (xy 44.755054 -303.499774) (xy 45.094156 -303.499774)
			(xy 45.098116 -303.45072) (xy 45.109893 -303.402936) (xy 45.129184 -303.35766) (xy 45.155487 -303.316064)
			(xy 45.188122 -303.279227) (xy 45.226243 -303.248102) (xy 45.268864 -303.223495) (xy 45.31488 -303.206043)
			(xy 45.363099 -303.196199) (xy 45.412274 -303.194218) (xy 45.461129 -303.20015) (xy 45.5084 -303.213842)
			(xy 45.552862 -303.23494) (xy 45.593365 -303.262896) (xy 45.628858 -303.296988) (xy 45.658423 -303.336332)
			(xy 45.681294 -303.379909) (xy 45.696878 -303.42659) (xy 45.704773 -303.475167) (xy 45.705268 -303.499774)
			(xy 73.593972 -303.499774) (xy 73.597932 -303.45072) (xy 73.609709 -303.402936) (xy 73.629 -303.35766)
			(xy 73.655303 -303.316064) (xy 73.687938 -303.279227) (xy 73.726059 -303.248102) (xy 73.76868 -303.223495)
			(xy 73.814696 -303.206043) (xy 73.862915 -303.196199) (xy 73.91209 -303.194218) (xy 73.960945 -303.20015)
			(xy 74.008216 -303.213842) (xy 74.052678 -303.23494) (xy 74.093181 -303.262896) (xy 74.128674 -303.296988)
			(xy 74.158239 -303.336332) (xy 74.18111 -303.379909) (xy 74.196694 -303.42659) (xy 74.204589 -303.475167)
			(xy 74.205084 -303.499774) (xy 74.544186 -303.499774) (xy 74.548146 -303.45072) (xy 74.559923 -303.402936)
			(xy 74.579214 -303.35766) (xy 74.605517 -303.316064) (xy 74.638152 -303.279227) (xy 74.676273 -303.248102)
			(xy 74.718894 -303.223495) (xy 74.76491 -303.206043) (xy 74.813129 -303.196199) (xy 74.862304 -303.194218)
			(xy 74.911159 -303.20015) (xy 74.95843 -303.213842) (xy 75.002892 -303.23494) (xy 75.043395 -303.262896)
			(xy 75.078888 -303.296988) (xy 75.108453 -303.336332) (xy 75.131324 -303.379909) (xy 75.146908 -303.42659)
			(xy 75.154803 -303.475167) (xy 75.155298 -303.499774) (xy 75.494146 -303.499774) (xy 75.498106 -303.45072)
			(xy 75.509883 -303.402936) (xy 75.529174 -303.35766) (xy 75.555477 -303.316064) (xy 75.588112 -303.279227)
			(xy 75.626233 -303.248102) (xy 75.668854 -303.223495) (xy 75.71487 -303.206043) (xy 75.763089 -303.196199)
			(xy 75.812264 -303.194218) (xy 75.861119 -303.20015) (xy 75.90839 -303.213842) (xy 75.952852 -303.23494)
			(xy 75.993355 -303.262896) (xy 76.028848 -303.296988) (xy 76.058413 -303.336332) (xy 76.081284 -303.379909)
			(xy 76.096868 -303.42659) (xy 76.104763 -303.475167) (xy 76.105258 -303.499774) (xy 76.104763 -303.524381)
			(xy 76.096868 -303.572958) (xy 76.081284 -303.619639) (xy 76.058413 -303.663216) (xy 76.028848 -303.70256)
			(xy 75.993355 -303.736652) (xy 75.952852 -303.764608) (xy 75.90839 -303.785706) (xy 75.861119 -303.799398)
			(xy 75.812264 -303.80533) (xy 75.763089 -303.803349) (xy 75.71487 -303.793505) (xy 75.668854 -303.776053)
			(xy 75.626233 -303.751446) (xy 75.588112 -303.720321) (xy 75.555477 -303.683484) (xy 75.529174 -303.641888)
			(xy 75.509883 -303.596612) (xy 75.498106 -303.548828) (xy 75.494146 -303.499774) (xy 75.155298 -303.499774)
			(xy 75.154803 -303.524381) (xy 75.146908 -303.572958) (xy 75.131324 -303.619639) (xy 75.108453 -303.663216)
			(xy 75.078888 -303.70256) (xy 75.043395 -303.736652) (xy 75.002892 -303.764608) (xy 74.95843 -303.785706)
			(xy 74.911159 -303.799398) (xy 74.862304 -303.80533) (xy 74.813129 -303.803349) (xy 74.76491 -303.793505)
			(xy 74.718894 -303.776053) (xy 74.676273 -303.751446) (xy 74.638152 -303.720321) (xy 74.605517 -303.683484)
			(xy 74.579214 -303.641888) (xy 74.559923 -303.596612) (xy 74.548146 -303.548828) (xy 74.544186 -303.499774)
			(xy 74.205084 -303.499774) (xy 74.204589 -303.524381) (xy 74.196694 -303.572958) (xy 74.18111 -303.619639)
			(xy 74.158239 -303.663216) (xy 74.128674 -303.70256) (xy 74.093181 -303.736652) (xy 74.052678 -303.764608)
			(xy 74.008216 -303.785706) (xy 73.960945 -303.799398) (xy 73.91209 -303.80533) (xy 73.862915 -303.803349)
			(xy 73.814696 -303.793505) (xy 73.76868 -303.776053) (xy 73.726059 -303.751446) (xy 73.687938 -303.720321)
			(xy 73.655303 -303.683484) (xy 73.629 -303.641888) (xy 73.609709 -303.596612) (xy 73.597932 -303.548828)
			(xy 73.593972 -303.499774) (xy 45.705268 -303.499774) (xy 45.704773 -303.524381) (xy 45.696878 -303.572958)
			(xy 45.681294 -303.619639) (xy 45.658423 -303.663216) (xy 45.628858 -303.70256) (xy 45.593365 -303.736652)
			(xy 45.552862 -303.764608) (xy 45.5084 -303.785706) (xy 45.461129 -303.799398) (xy 45.412274 -303.80533)
			(xy 45.363099 -303.803349) (xy 45.31488 -303.793505) (xy 45.268864 -303.776053) (xy 45.226243 -303.751446)
			(xy 45.188122 -303.720321) (xy 45.155487 -303.683484) (xy 45.129184 -303.641888) (xy 45.109893 -303.596612)
			(xy 45.098116 -303.548828) (xy 45.094156 -303.499774) (xy 44.755054 -303.499774) (xy 44.754559 -303.524381)
			(xy 44.746664 -303.572958) (xy 44.73108 -303.619639) (xy 44.708209 -303.663216) (xy 44.678644 -303.70256)
			(xy 44.643151 -303.736652) (xy 44.602648 -303.764608) (xy 44.558186 -303.785706) (xy 44.510915 -303.799398)
			(xy 44.46206 -303.80533) (xy 44.412885 -303.803349) (xy 44.364666 -303.793505) (xy 44.31865 -303.776053)
			(xy 44.276029 -303.751446) (xy 44.237908 -303.720321) (xy 44.205273 -303.683484) (xy 44.17897 -303.641888)
			(xy 44.159679 -303.596612) (xy 44.147902 -303.548828) (xy 44.143942 -303.499774) (xy 43.805094 -303.499774)
			(xy 43.804599 -303.524381) (xy 43.796704 -303.572958) (xy 43.78112 -303.619639) (xy 43.758249 -303.663216)
			(xy 43.728684 -303.70256) (xy 43.693191 -303.736652) (xy 43.652688 -303.764608) (xy 43.608226 -303.785706)
			(xy 43.560955 -303.799398) (xy 43.5121 -303.80533) (xy 43.462925 -303.803349) (xy 43.414706 -303.793505)
			(xy 43.36869 -303.776053) (xy 43.326069 -303.751446) (xy 43.287948 -303.720321) (xy 43.255313 -303.683484)
			(xy 43.22901 -303.641888) (xy 43.209719 -303.596612) (xy 43.197942 -303.548828) (xy 43.193982 -303.499774)
			(xy 42.876978 -303.499774) (xy 42.876474 -303.525482) (xy 42.868431 -303.576264) (xy 42.852543 -303.625163)
			(xy 42.8292 -303.670975) (xy 42.798979 -303.712571) (xy 42.762623 -303.748927) (xy 42.721027 -303.779148)
			(xy 42.675215 -303.802491) (xy 42.626316 -303.818379) (xy 42.575534 -303.826422) (xy 42.524118 -303.826422)
			(xy 42.473336 -303.818379) (xy 42.424437 -303.802491) (xy 42.378625 -303.779148) (xy 42.337029 -303.748927)
			(xy 42.300673 -303.712571) (xy 42.270452 -303.670975) (xy 42.247109 -303.625163) (xy 42.231221 -303.576264)
			(xy 42.223178 -303.525482) (xy 41.926514 -303.525482) (xy 41.918471 -303.576264) (xy 41.902583 -303.625163)
			(xy 41.87924 -303.670975) (xy 41.849019 -303.712571) (xy 41.812663 -303.748927) (xy 41.771067 -303.779148)
			(xy 41.725255 -303.802491) (xy 41.676356 -303.818379) (xy 41.625574 -303.826422) (xy 41.574158 -303.826422)
			(xy 41.523376 -303.818379) (xy 41.474477 -303.802491) (xy 41.428665 -303.779148) (xy 41.387069 -303.748927)
			(xy 41.350713 -303.712571) (xy 41.320492 -303.670975) (xy 41.297149 -303.625163) (xy 41.281261 -303.576264)
			(xy 41.273218 -303.525482) (xy 40.95454 -303.525482) (xy 40.946824 -303.572958) (xy 40.93124 -303.619639)
			(xy 40.908369 -303.663216) (xy 40.878804 -303.70256) (xy 40.843311 -303.736652) (xy 40.802808 -303.764608)
			(xy 40.758346 -303.785706) (xy 40.711075 -303.799398) (xy 40.66222 -303.80533) (xy 40.613045 -303.803349)
			(xy 40.564826 -303.793505) (xy 40.51881 -303.776053) (xy 40.476189 -303.751446) (xy 40.438068 -303.720321)
			(xy 40.405433 -303.683484) (xy 40.37913 -303.641888) (xy 40.359839 -303.596612) (xy 40.348062 -303.548828)
			(xy 40.344102 -303.499774) (xy 40.027098 -303.499774) (xy 40.026594 -303.525482) (xy 40.018551 -303.576264)
			(xy 40.002663 -303.625163) (xy 39.97932 -303.670975) (xy 39.949099 -303.712571) (xy 39.912743 -303.748927)
			(xy 39.871147 -303.779148) (xy 39.825335 -303.802491) (xy 39.776436 -303.818379) (xy 39.725654 -303.826422)
			(xy 39.674238 -303.826422) (xy 39.623456 -303.818379) (xy 39.574557 -303.802491) (xy 39.528745 -303.779148)
			(xy 39.487149 -303.748927) (xy 39.450793 -303.712571) (xy 39.420572 -303.670975) (xy 39.397229 -303.625163)
			(xy 39.381341 -303.576264) (xy 39.373298 -303.525482) (xy 39.076634 -303.525482) (xy 39.068591 -303.576264)
			(xy 39.052703 -303.625163) (xy 39.02936 -303.670975) (xy 38.999139 -303.712571) (xy 38.962783 -303.748927)
			(xy 38.921187 -303.779148) (xy 38.875375 -303.802491) (xy 38.826476 -303.818379) (xy 38.775694 -303.826422)
			(xy 38.724278 -303.826422) (xy 38.673496 -303.818379) (xy 38.624597 -303.802491) (xy 38.578785 -303.779148)
			(xy 38.537189 -303.748927) (xy 38.500833 -303.712571) (xy 38.470612 -303.670975) (xy 38.447269 -303.625163)
			(xy 38.431381 -303.576264) (xy 38.423338 -303.525482) (xy 38.104406 -303.525482) (xy 38.09669 -303.572958)
			(xy 38.081106 -303.619639) (xy 38.058235 -303.663216) (xy 38.02867 -303.70256) (xy 37.993177 -303.736652)
			(xy 37.952674 -303.764608) (xy 37.908212 -303.785706) (xy 37.860941 -303.799398) (xy 37.812086 -303.80533)
			(xy 37.762911 -303.803349) (xy 37.714692 -303.793505) (xy 37.668676 -303.776053) (xy 37.626055 -303.751446)
			(xy 37.587934 -303.720321) (xy 37.555299 -303.683484) (xy 37.528996 -303.641888) (xy 37.509705 -303.596612)
			(xy 37.497928 -303.548828) (xy 37.493968 -303.499774) (xy 37.15512 -303.499774) (xy 37.154625 -303.524381)
			(xy 37.14673 -303.572958) (xy 37.131146 -303.619639) (xy 37.108275 -303.663216) (xy 37.07871 -303.70256)
			(xy 37.043217 -303.736652) (xy 37.002714 -303.764608) (xy 36.958252 -303.785706) (xy 36.910981 -303.799398)
			(xy 36.862126 -303.80533) (xy 36.812951 -303.803349) (xy 36.764732 -303.793505) (xy 36.718716 -303.776053)
			(xy 36.676095 -303.751446) (xy 36.637974 -303.720321) (xy 36.605339 -303.683484) (xy 36.579036 -303.641888)
			(xy 36.559745 -303.596612) (xy 36.547968 -303.548828) (xy 36.544008 -303.499774) (xy 22.804888 -303.499774)
			(xy 22.784751 -303.526127) (xy 22.679443 -303.650946) (xy 22.568227 -303.770532) (xy 22.451364 -303.884605)
			(xy 22.329126 -303.992898) (xy 22.201799 -304.09516) (xy 22.06968 -304.19115) (xy 21.933077 -304.280645)
			(xy 21.79231 -304.363436) (xy 21.647708 -304.43933) (xy 21.624771 -304.449988) (xy 35.593794 -304.449988)
			(xy 35.597754 -304.400934) (xy 35.609531 -304.35315) (xy 35.628822 -304.307874) (xy 35.655125 -304.266278)
			(xy 35.68776 -304.229441) (xy 35.725881 -304.198316) (xy 35.768502 -304.173709) (xy 35.814518 -304.156257)
			(xy 35.862737 -304.146413) (xy 35.911912 -304.144432) (xy 35.960767 -304.150364) (xy 36.008038 -304.164056)
			(xy 36.0525 -304.185154) (xy 36.093003 -304.21311) (xy 36.128496 -304.247202) (xy 36.158061 -304.286546)
			(xy 36.180932 -304.330123) (xy 36.196516 -304.376804) (xy 36.204411 -304.425381) (xy 36.204906 -304.449988)
			(xy 36.204411 -304.474595) (xy 36.204273 -304.475442) (xy 36.523164 -304.475442) (xy 36.523164 -304.424026)
			(xy 36.531207 -304.373244) (xy 36.547095 -304.324345) (xy 36.570438 -304.278533) (xy 36.600659 -304.236937)
			(xy 36.637015 -304.200581) (xy 36.678611 -304.17036) (xy 36.724423 -304.147017) (xy 36.773322 -304.131129)
			(xy 36.824104 -304.123086) (xy 36.87552 -304.123086) (xy 36.926302 -304.131129) (xy 36.975201 -304.147017)
			(xy 37.021013 -304.17036) (xy 37.062609 -304.200581) (xy 37.098965 -304.236937) (xy 37.129186 -304.278533)
			(xy 37.152529 -304.324345) (xy 37.168417 -304.373244) (xy 37.17646 -304.424026) (xy 37.176964 -304.449734)
			(xy 37.17646 -304.475442) (xy 37.473124 -304.475442) (xy 37.473124 -304.424026) (xy 37.481167 -304.373244)
			(xy 37.497055 -304.324345) (xy 37.520398 -304.278533) (xy 37.550619 -304.236937) (xy 37.586975 -304.200581)
			(xy 37.628571 -304.17036) (xy 37.674383 -304.147017) (xy 37.723282 -304.131129) (xy 37.774064 -304.123086)
			(xy 37.82548 -304.123086) (xy 37.876262 -304.131129) (xy 37.925161 -304.147017) (xy 37.970973 -304.17036)
			(xy 38.012569 -304.200581) (xy 38.048925 -304.236937) (xy 38.079146 -304.278533) (xy 38.102489 -304.324345)
			(xy 38.118377 -304.373244) (xy 38.12642 -304.424026) (xy 38.126924 -304.449734) (xy 38.444182 -304.449734)
			(xy 38.448142 -304.40068) (xy 38.459919 -304.352896) (xy 38.47921 -304.30762) (xy 38.505513 -304.266024)
			(xy 38.538148 -304.229187) (xy 38.576269 -304.198062) (xy 38.61889 -304.173455) (xy 38.664906 -304.156003)
			(xy 38.713125 -304.146159) (xy 38.7623 -304.144178) (xy 38.811155 -304.15011) (xy 38.858426 -304.163802)
			(xy 38.902888 -304.1849) (xy 38.943391 -304.212856) (xy 38.978884 -304.246948) (xy 39.008449 -304.286292)
			(xy 39.03132 -304.329869) (xy 39.046904 -304.37655) (xy 39.054799 -304.425127) (xy 39.055294 -304.449734)
			(xy 39.394142 -304.449734) (xy 39.398102 -304.40068) (xy 39.409879 -304.352896) (xy 39.42917 -304.30762)
			(xy 39.455473 -304.266024) (xy 39.488108 -304.229187) (xy 39.526229 -304.198062) (xy 39.56885 -304.173455)
			(xy 39.614866 -304.156003) (xy 39.663085 -304.146159) (xy 39.71226 -304.144178) (xy 39.761115 -304.15011)
			(xy 39.808386 -304.163802) (xy 39.852848 -304.1849) (xy 39.893351 -304.212856) (xy 39.928844 -304.246948)
			(xy 39.958409 -304.286292) (xy 39.98128 -304.329869) (xy 39.996864 -304.37655) (xy 40.004759 -304.425127)
			(xy 40.005254 -304.449734) (xy 40.344102 -304.449734) (xy 40.348062 -304.40068) (xy 40.359839 -304.352896)
			(xy 40.37913 -304.30762) (xy 40.405433 -304.266024) (xy 40.438068 -304.229187) (xy 40.476189 -304.198062)
			(xy 40.51881 -304.173455) (xy 40.564826 -304.156003) (xy 40.613045 -304.146159) (xy 40.66222 -304.144178)
			(xy 40.711075 -304.15011) (xy 40.758346 -304.163802) (xy 40.802808 -304.1849) (xy 40.843311 -304.212856)
			(xy 40.878804 -304.246948) (xy 40.908369 -304.286292) (xy 40.93124 -304.329869) (xy 40.946824 -304.37655)
			(xy 40.954719 -304.425127) (xy 40.955214 -304.449734) (xy 41.294062 -304.449734) (xy 41.298022 -304.40068)
			(xy 41.309799 -304.352896) (xy 41.32909 -304.30762) (xy 41.355393 -304.266024) (xy 41.388028 -304.229187)
			(xy 41.426149 -304.198062) (xy 41.46877 -304.173455) (xy 41.514786 -304.156003) (xy 41.563005 -304.146159)
			(xy 41.61218 -304.144178) (xy 41.661035 -304.15011) (xy 41.708306 -304.163802) (xy 41.752768 -304.1849)
			(xy 41.793271 -304.212856) (xy 41.828764 -304.246948) (xy 41.858329 -304.286292) (xy 41.8812 -304.329869)
			(xy 41.896784 -304.37655) (xy 41.904679 -304.425127) (xy 41.905174 -304.449734) (xy 42.244022 -304.449734)
			(xy 42.247982 -304.40068) (xy 42.259759 -304.352896) (xy 42.27905 -304.30762) (xy 42.305353 -304.266024)
			(xy 42.337988 -304.229187) (xy 42.376109 -304.198062) (xy 42.41873 -304.173455) (xy 42.464746 -304.156003)
			(xy 42.512965 -304.146159) (xy 42.56214 -304.144178) (xy 42.610995 -304.15011) (xy 42.658266 -304.163802)
			(xy 42.702728 -304.1849) (xy 42.743231 -304.212856) (xy 42.778724 -304.246948) (xy 42.808289 -304.286292)
			(xy 42.83116 -304.329869) (xy 42.846744 -304.37655) (xy 42.854639 -304.425127) (xy 42.855134 -304.449734)
			(xy 42.854639 -304.474341) (xy 42.85446 -304.475442) (xy 43.173138 -304.475442) (xy 43.173138 -304.424026)
			(xy 43.181181 -304.373244) (xy 43.197069 -304.324345) (xy 43.220412 -304.278533) (xy 43.250633 -304.236937)
			(xy 43.286989 -304.200581) (xy 43.328585 -304.17036) (xy 43.374397 -304.147017) (xy 43.423296 -304.131129)
			(xy 43.474078 -304.123086) (xy 43.525494 -304.123086) (xy 43.576276 -304.131129) (xy 43.625175 -304.147017)
			(xy 43.670987 -304.17036) (xy 43.712583 -304.200581) (xy 43.748939 -304.236937) (xy 43.77916 -304.278533)
			(xy 43.802503 -304.324345) (xy 43.818391 -304.373244) (xy 43.826434 -304.424026) (xy 43.826938 -304.449734)
			(xy 43.826434 -304.475442) (xy 44.123098 -304.475442) (xy 44.123098 -304.424026) (xy 44.131141 -304.373244)
			(xy 44.147029 -304.324345) (xy 44.170372 -304.278533) (xy 44.200593 -304.236937) (xy 44.236949 -304.200581)
			(xy 44.278545 -304.17036) (xy 44.324357 -304.147017) (xy 44.373256 -304.131129) (xy 44.424038 -304.123086)
			(xy 44.475454 -304.123086) (xy 44.526236 -304.131129) (xy 44.575135 -304.147017) (xy 44.620947 -304.17036)
			(xy 44.662543 -304.200581) (xy 44.698899 -304.236937) (xy 44.72912 -304.278533) (xy 44.752463 -304.324345)
			(xy 44.768351 -304.373244) (xy 44.776394 -304.424026) (xy 44.776898 -304.449734) (xy 45.094156 -304.449734)
			(xy 45.098116 -304.40068) (xy 45.109893 -304.352896) (xy 45.129184 -304.30762) (xy 45.155487 -304.266024)
			(xy 45.188122 -304.229187) (xy 45.226243 -304.198062) (xy 45.268864 -304.173455) (xy 45.31488 -304.156003)
			(xy 45.363099 -304.146159) (xy 45.412274 -304.144178) (xy 45.461129 -304.15011) (xy 45.5084 -304.163802)
			(xy 45.552862 -304.1849) (xy 45.593365 -304.212856) (xy 45.628858 -304.246948) (xy 45.658423 -304.286292)
			(xy 45.681294 -304.329869) (xy 45.696878 -304.37655) (xy 45.704773 -304.425127) (xy 45.7051 -304.441395)
			(xy 46.044216 -304.441395) (xy 46.049586 -304.39205) (xy 46.062869 -304.344225) (xy 46.083714 -304.299178)
			(xy 46.111572 -304.258097) (xy 46.145709 -304.222065) (xy 46.185226 -304.192029) (xy 46.229081 -304.168783)
			(xy 46.27612 -304.152937) (xy 46.325102 -304.14491) (xy 46.34992 -304.144426) (xy 46.364103 -304.144599)
			(xy 46.392343 -304.147274) (xy 46.406308 -304.14976) (xy 46.418754 -304.152046) (xy 46.442376 -304.14468)
			(xy 46.519846 -304.06721) (xy 46.527212 -304.043588) (xy 46.524926 -304.031142) (xy 46.522446 -304.017177)
			(xy 46.519776 -303.988937) (xy 46.519592 -303.974754) (xy 46.520114 -303.949499) (xy 46.528427 -303.899677)
			(xy 46.544828 -303.851903) (xy 46.568869 -303.80748) (xy 46.599893 -303.76762) (xy 46.637055 -303.73341)
			(xy 46.679341 -303.705784) (xy 46.725597 -303.685494) (xy 46.774562 -303.673094) (xy 46.8249 -303.668923)
			(xy 46.875238 -303.673094) (xy 46.924203 -303.685494) (xy 46.970459 -303.705784) (xy 47.012745 -303.73341)
			(xy 47.049907 -303.76762) (xy 47.080931 -303.80748) (xy 47.104972 -303.851903) (xy 47.121373 -303.899677)
			(xy 47.129686 -303.949499) (xy 47.130208 -303.974754) (xy 47.130025 -303.988937) (xy 47.127357 -304.017177)
			(xy 47.124874 -304.031142) (xy 47.122588 -304.043588) (xy 47.129954 -304.06721) (xy 47.207424 -304.14468)
			(xy 47.231046 -304.152046) (xy 47.243492 -304.14976) (xy 47.257459 -304.147289) (xy 47.285698 -304.144614)
			(xy 47.29988 -304.144426) (xy 47.314063 -304.144605) (xy 47.342303 -304.147275) (xy 47.356268 -304.14976)
			(xy 47.368714 -304.152046) (xy 47.392336 -304.14468) (xy 47.469806 -304.06721) (xy 47.477172 -304.043588)
			(xy 47.474886 -304.031142) (xy 47.472405 -304.017177) (xy 47.469736 -303.988937) (xy 47.469552 -303.974754)
			(xy 47.470127 -303.949937) (xy 47.478165 -303.900958) (xy 47.49402 -303.853925) (xy 47.517275 -303.810076)
			(xy 47.547319 -303.770567) (xy 47.583358 -303.736439) (xy 47.624443 -303.708591) (xy 47.669493 -303.687757)
			(xy 47.71732 -303.674485) (xy 47.766664 -303.669126) (xy 47.816224 -303.67182) (xy 47.864697 -303.682497)
			(xy 47.910803 -303.700875) (xy 47.953328 -303.72647) (xy 47.991153 -303.758608) (xy 48.02328 -303.796441)
			(xy 48.048863 -303.838974) (xy 48.067228 -303.885086) (xy 48.077891 -303.933561) (xy 48.080119 -303.974754)
			(xy 48.419016 -303.974754) (xy 48.422976 -303.9257) (xy 48.434753 -303.877916) (xy 48.454044 -303.83264)
			(xy 48.480347 -303.791044) (xy 48.512982 -303.754207) (xy 48.551103 -303.723082) (xy 48.593724 -303.698475)
			(xy 48.63974 -303.681023) (xy 48.687959 -303.671179) (xy 48.737134 -303.669198) (xy 48.785989 -303.67513)
			(xy 48.83326 -303.688822) (xy 48.877722 -303.70992) (xy 48.918225 -303.737876) (xy 48.953718 -303.771968)
			(xy 48.983283 -303.811312) (xy 49.006154 -303.854889) (xy 49.021738 -303.90157) (xy 49.029633 -303.950147)
			(xy 49.030128 -303.974754) (xy 49.368976 -303.974754) (xy 49.372936 -303.9257) (xy 49.384713 -303.877916)
			(xy 49.404004 -303.83264) (xy 49.430307 -303.791044) (xy 49.462942 -303.754207) (xy 49.501063 -303.723082)
			(xy 49.543684 -303.698475) (xy 49.5897 -303.681023) (xy 49.637919 -303.671179) (xy 49.687094 -303.669198)
			(xy 49.735949 -303.67513) (xy 49.78322 -303.688822) (xy 49.827682 -303.70992) (xy 49.868185 -303.737876)
			(xy 49.903678 -303.771968) (xy 49.933243 -303.811312) (xy 49.956114 -303.854889) (xy 49.971698 -303.90157)
			(xy 49.979593 -303.950147) (xy 49.980088 -303.974754) (xy 50.31919 -303.974754) (xy 50.32315 -303.9257)
			(xy 50.334927 -303.877916) (xy 50.354218 -303.83264) (xy 50.380521 -303.791044) (xy 50.413156 -303.754207)
			(xy 50.451277 -303.723082) (xy 50.493898 -303.698475) (xy 50.539914 -303.681023) (xy 50.588133 -303.671179)
			(xy 50.637308 -303.669198) (xy 50.686163 -303.67513) (xy 50.733434 -303.688822) (xy 50.777896 -303.70992)
			(xy 50.818399 -303.737876) (xy 50.853892 -303.771968) (xy 50.883457 -303.811312) (xy 50.906328 -303.854889)
			(xy 50.921912 -303.90157) (xy 50.929807 -303.950147) (xy 50.930302 -303.974754) (xy 51.26915 -303.974754)
			(xy 51.27311 -303.9257) (xy 51.284887 -303.877916) (xy 51.304178 -303.83264) (xy 51.330481 -303.791044)
			(xy 51.363116 -303.754207) (xy 51.401237 -303.723082) (xy 51.443858 -303.698475) (xy 51.489874 -303.681023)
			(xy 51.538093 -303.671179) (xy 51.587268 -303.669198) (xy 51.636123 -303.67513) (xy 51.683394 -303.688822)
			(xy 51.727856 -303.70992) (xy 51.768359 -303.737876) (xy 51.803852 -303.771968) (xy 51.833417 -303.811312)
			(xy 51.856288 -303.854889) (xy 51.871872 -303.90157) (xy 51.879767 -303.950147) (xy 51.880262 -303.974754)
			(xy 52.21911 -303.974754) (xy 52.22307 -303.9257) (xy 52.234847 -303.877916) (xy 52.254138 -303.83264)
			(xy 52.280441 -303.791044) (xy 52.313076 -303.754207) (xy 52.351197 -303.723082) (xy 52.393818 -303.698475)
			(xy 52.439834 -303.681023) (xy 52.488053 -303.671179) (xy 52.537228 -303.669198) (xy 52.586083 -303.67513)
			(xy 52.633354 -303.688822) (xy 52.677816 -303.70992) (xy 52.718319 -303.737876) (xy 52.753812 -303.771968)
			(xy 52.783377 -303.811312) (xy 52.806248 -303.854889) (xy 52.821832 -303.90157) (xy 52.829727 -303.950147)
			(xy 52.830222 -303.974754) (xy 53.16907 -303.974754) (xy 53.17303 -303.9257) (xy 53.184807 -303.877916)
			(xy 53.204098 -303.83264) (xy 53.230401 -303.791044) (xy 53.263036 -303.754207) (xy 53.301157 -303.723082)
			(xy 53.343778 -303.698475) (xy 53.389794 -303.681023) (xy 53.438013 -303.671179) (xy 53.487188 -303.669198)
			(xy 53.536043 -303.67513) (xy 53.583314 -303.688822) (xy 53.627776 -303.70992) (xy 53.668279 -303.737876)
			(xy 53.703772 -303.771968) (xy 53.733337 -303.811312) (xy 53.756208 -303.854889) (xy 53.771792 -303.90157)
			(xy 53.779687 -303.950147) (xy 53.780182 -303.974754) (xy 54.11903 -303.974754) (xy 54.12299 -303.9257)
			(xy 54.134767 -303.877916) (xy 54.154058 -303.83264) (xy 54.180361 -303.791044) (xy 54.212996 -303.754207)
			(xy 54.251117 -303.723082) (xy 54.293738 -303.698475) (xy 54.339754 -303.681023) (xy 54.387973 -303.671179)
			(xy 54.437148 -303.669198) (xy 54.486003 -303.67513) (xy 54.533274 -303.688822) (xy 54.577736 -303.70992)
			(xy 54.618239 -303.737876) (xy 54.653732 -303.771968) (xy 54.683297 -303.811312) (xy 54.706168 -303.854889)
			(xy 54.721752 -303.90157) (xy 54.729647 -303.950147) (xy 54.730142 -303.974754) (xy 55.06899 -303.974754)
			(xy 55.07295 -303.9257) (xy 55.084727 -303.877916) (xy 55.104018 -303.83264) (xy 55.130321 -303.791044)
			(xy 55.162956 -303.754207) (xy 55.201077 -303.723082) (xy 55.243698 -303.698475) (xy 55.289714 -303.681023)
			(xy 55.337933 -303.671179) (xy 55.387108 -303.669198) (xy 55.435963 -303.67513) (xy 55.483234 -303.688822)
			(xy 55.527696 -303.70992) (xy 55.568199 -303.737876) (xy 55.603692 -303.771968) (xy 55.633257 -303.811312)
			(xy 55.656128 -303.854889) (xy 55.671712 -303.90157) (xy 55.679607 -303.950147) (xy 55.680102 -303.974754)
			(xy 56.01895 -303.974754) (xy 56.02291 -303.9257) (xy 56.034687 -303.877916) (xy 56.053978 -303.83264)
			(xy 56.080281 -303.791044) (xy 56.112916 -303.754207) (xy 56.151037 -303.723082) (xy 56.193658 -303.698475)
			(xy 56.239674 -303.681023) (xy 56.287893 -303.671179) (xy 56.337068 -303.669198) (xy 56.385923 -303.67513)
			(xy 56.433194 -303.688822) (xy 56.477656 -303.70992) (xy 56.518159 -303.737876) (xy 56.553652 -303.771968)
			(xy 56.583217 -303.811312) (xy 56.606088 -303.854889) (xy 56.621672 -303.90157) (xy 56.629567 -303.950147)
			(xy 56.630062 -303.974754) (xy 56.969164 -303.974754) (xy 56.973124 -303.9257) (xy 56.984901 -303.877916)
			(xy 57.004192 -303.83264) (xy 57.030495 -303.791044) (xy 57.06313 -303.754207) (xy 57.101251 -303.723082)
			(xy 57.143872 -303.698475) (xy 57.189888 -303.681023) (xy 57.238107 -303.671179) (xy 57.287282 -303.669198)
			(xy 57.336137 -303.67513) (xy 57.383408 -303.688822) (xy 57.42787 -303.70992) (xy 57.468373 -303.737876)
			(xy 57.503866 -303.771968) (xy 57.533431 -303.811312) (xy 57.556302 -303.854889) (xy 57.571886 -303.90157)
			(xy 57.579781 -303.950147) (xy 57.580276 -303.974754) (xy 57.919124 -303.974754) (xy 57.923084 -303.9257)
			(xy 57.934861 -303.877916) (xy 57.954152 -303.83264) (xy 57.980455 -303.791044) (xy 58.01309 -303.754207)
			(xy 58.051211 -303.723082) (xy 58.093832 -303.698475) (xy 58.139848 -303.681023) (xy 58.188067 -303.671179)
			(xy 58.237242 -303.669198) (xy 58.286097 -303.67513) (xy 58.333368 -303.688822) (xy 58.37783 -303.70992)
			(xy 58.418333 -303.737876) (xy 58.453826 -303.771968) (xy 58.483391 -303.811312) (xy 58.506262 -303.854889)
			(xy 58.521846 -303.90157) (xy 58.529741 -303.950147) (xy 58.530236 -303.974754) (xy 59.819044 -303.974754)
			(xy 59.823004 -303.9257) (xy 59.834781 -303.877916) (xy 59.854072 -303.83264) (xy 59.880375 -303.791044)
			(xy 59.91301 -303.754207) (xy 59.951131 -303.723082) (xy 59.993752 -303.698475) (xy 60.039768 -303.681023)
			(xy 60.087987 -303.671179) (xy 60.137162 -303.669198) (xy 60.186017 -303.67513) (xy 60.233288 -303.688822)
			(xy 60.27775 -303.70992) (xy 60.318253 -303.737876) (xy 60.353746 -303.771968) (xy 60.383311 -303.811312)
			(xy 60.406182 -303.854889) (xy 60.421766 -303.90157) (xy 60.429661 -303.950147) (xy 60.430156 -303.974754)
			(xy 60.769004 -303.974754) (xy 60.772964 -303.9257) (xy 60.784741 -303.877916) (xy 60.804032 -303.83264)
			(xy 60.830335 -303.791044) (xy 60.86297 -303.754207) (xy 60.901091 -303.723082) (xy 60.943712 -303.698475)
			(xy 60.989728 -303.681023) (xy 61.037947 -303.671179) (xy 61.087122 -303.669198) (xy 61.135977 -303.67513)
			(xy 61.183248 -303.688822) (xy 61.22771 -303.70992) (xy 61.268213 -303.737876) (xy 61.303706 -303.771968)
			(xy 61.333271 -303.811312) (xy 61.356142 -303.854889) (xy 61.371726 -303.90157) (xy 61.379621 -303.950147)
			(xy 61.380116 -303.974754) (xy 61.718964 -303.974754) (xy 61.722924 -303.9257) (xy 61.734701 -303.877916)
			(xy 61.753992 -303.83264) (xy 61.780295 -303.791044) (xy 61.81293 -303.754207) (xy 61.851051 -303.723082)
			(xy 61.893672 -303.698475) (xy 61.939688 -303.681023) (xy 61.987907 -303.671179) (xy 62.037082 -303.669198)
			(xy 62.085937 -303.67513) (xy 62.133208 -303.688822) (xy 62.17767 -303.70992) (xy 62.218173 -303.737876)
			(xy 62.253666 -303.771968) (xy 62.283231 -303.811312) (xy 62.306102 -303.854889) (xy 62.321686 -303.90157)
			(xy 62.329581 -303.950147) (xy 62.330076 -303.974754) (xy 62.669178 -303.974754) (xy 62.673138 -303.9257)
			(xy 62.684915 -303.877916) (xy 62.704206 -303.83264) (xy 62.730509 -303.791044) (xy 62.763144 -303.754207)
			(xy 62.801265 -303.723082) (xy 62.843886 -303.698475) (xy 62.889902 -303.681023) (xy 62.938121 -303.671179)
			(xy 62.987296 -303.669198) (xy 63.036151 -303.67513) (xy 63.083422 -303.688822) (xy 63.127884 -303.70992)
			(xy 63.168387 -303.737876) (xy 63.20388 -303.771968) (xy 63.233445 -303.811312) (xy 63.256316 -303.854889)
			(xy 63.2719 -303.90157) (xy 63.279795 -303.950147) (xy 63.28029 -303.974754) (xy 63.619138 -303.974754)
			(xy 63.623098 -303.9257) (xy 63.634875 -303.877916) (xy 63.654166 -303.83264) (xy 63.680469 -303.791044)
			(xy 63.713104 -303.754207) (xy 63.751225 -303.723082) (xy 63.793846 -303.698475) (xy 63.839862 -303.681023)
			(xy 63.888081 -303.671179) (xy 63.937256 -303.669198) (xy 63.986111 -303.67513) (xy 64.033382 -303.688822)
			(xy 64.077844 -303.70992) (xy 64.118347 -303.737876) (xy 64.15384 -303.771968) (xy 64.183405 -303.811312)
			(xy 64.206276 -303.854889) (xy 64.22186 -303.90157) (xy 64.229755 -303.950147) (xy 64.23025 -303.974754)
			(xy 64.569098 -303.974754) (xy 64.573058 -303.9257) (xy 64.584835 -303.877916) (xy 64.604126 -303.83264)
			(xy 64.630429 -303.791044) (xy 64.663064 -303.754207) (xy 64.701185 -303.723082) (xy 64.743806 -303.698475)
			(xy 64.789822 -303.681023) (xy 64.838041 -303.671179) (xy 64.887216 -303.669198) (xy 64.936071 -303.67513)
			(xy 64.983342 -303.688822) (xy 65.027804 -303.70992) (xy 65.068307 -303.737876) (xy 65.1038 -303.771968)
			(xy 65.133365 -303.811312) (xy 65.156236 -303.854889) (xy 65.17182 -303.90157) (xy 65.179715 -303.950147)
			(xy 65.18021 -303.974754) (xy 65.519058 -303.974754) (xy 65.523018 -303.9257) (xy 65.534795 -303.877916)
			(xy 65.554086 -303.83264) (xy 65.580389 -303.791044) (xy 65.613024 -303.754207) (xy 65.651145 -303.723082)
			(xy 65.693766 -303.698475) (xy 65.739782 -303.681023) (xy 65.788001 -303.671179) (xy 65.837176 -303.669198)
			(xy 65.886031 -303.67513) (xy 65.933302 -303.688822) (xy 65.977764 -303.70992) (xy 66.018267 -303.737876)
			(xy 66.05376 -303.771968) (xy 66.083325 -303.811312) (xy 66.106196 -303.854889) (xy 66.12178 -303.90157)
			(xy 66.129675 -303.950147) (xy 66.13017 -303.974754) (xy 66.469018 -303.974754) (xy 66.472978 -303.9257)
			(xy 66.484755 -303.877916) (xy 66.504046 -303.83264) (xy 66.530349 -303.791044) (xy 66.562984 -303.754207)
			(xy 66.601105 -303.723082) (xy 66.643726 -303.698475) (xy 66.689742 -303.681023) (xy 66.737961 -303.671179)
			(xy 66.787136 -303.669198) (xy 66.835991 -303.67513) (xy 66.883262 -303.688822) (xy 66.927724 -303.70992)
			(xy 66.968227 -303.737876) (xy 67.00372 -303.771968) (xy 67.033285 -303.811312) (xy 67.056156 -303.854889)
			(xy 67.07174 -303.90157) (xy 67.079635 -303.950147) (xy 67.08013 -303.974754) (xy 67.418978 -303.974754)
			(xy 67.422938 -303.9257) (xy 67.434715 -303.877916) (xy 67.454006 -303.83264) (xy 67.480309 -303.791044)
			(xy 67.512944 -303.754207) (xy 67.551065 -303.723082) (xy 67.593686 -303.698475) (xy 67.639702 -303.681023)
			(xy 67.687921 -303.671179) (xy 67.737096 -303.669198) (xy 67.785951 -303.67513) (xy 67.833222 -303.688822)
			(xy 67.877684 -303.70992) (xy 67.918187 -303.737876) (xy 67.95368 -303.771968) (xy 67.983245 -303.811312)
			(xy 68.006116 -303.854889) (xy 68.0217 -303.90157) (xy 68.029595 -303.950147) (xy 68.029993 -303.969928)
			(xy 68.374018 -303.969928) (xy 68.377978 -303.920874) (xy 68.389755 -303.87309) (xy 68.409046 -303.827814)
			(xy 68.435349 -303.786218) (xy 68.467984 -303.749381) (xy 68.506105 -303.718256) (xy 68.548726 -303.693649)
			(xy 68.594742 -303.676197) (xy 68.642961 -303.666353) (xy 68.692136 -303.664372) (xy 68.740991 -303.670304)
			(xy 68.788262 -303.683996) (xy 68.832724 -303.705094) (xy 68.873227 -303.73305) (xy 68.90872 -303.767142)
			(xy 68.938285 -303.806486) (xy 68.961156 -303.850063) (xy 68.97674 -303.896744) (xy 68.984635 -303.945321)
			(xy 68.98513 -303.969928) (xy 68.985033 -303.974754) (xy 69.319152 -303.974754) (xy 69.323112 -303.9257)
			(xy 69.334889 -303.877916) (xy 69.35418 -303.83264) (xy 69.380483 -303.791044) (xy 69.413118 -303.754207)
			(xy 69.451239 -303.723082) (xy 69.49386 -303.698475) (xy 69.539876 -303.681023) (xy 69.588095 -303.671179)
			(xy 69.63727 -303.669198) (xy 69.686125 -303.67513) (xy 69.733396 -303.688822) (xy 69.777858 -303.70992)
			(xy 69.818361 -303.737876) (xy 69.853854 -303.771968) (xy 69.883419 -303.811312) (xy 69.90629 -303.854889)
			(xy 69.921874 -303.90157) (xy 69.929769 -303.950147) (xy 69.930264 -303.974754) (xy 70.269112 -303.974754)
			(xy 70.273072 -303.9257) (xy 70.284849 -303.877916) (xy 70.30414 -303.83264) (xy 70.330443 -303.791044)
			(xy 70.363078 -303.754207) (xy 70.401199 -303.723082) (xy 70.44382 -303.698475) (xy 70.489836 -303.681023)
			(xy 70.538055 -303.671179) (xy 70.58723 -303.669198) (xy 70.636085 -303.67513) (xy 70.683356 -303.688822)
			(xy 70.727818 -303.70992) (xy 70.768321 -303.737876) (xy 70.803814 -303.771968) (xy 70.833379 -303.811312)
			(xy 70.85625 -303.854889) (xy 70.871834 -303.90157) (xy 70.879729 -303.950147) (xy 70.880224 -303.974754)
			(xy 71.219072 -303.974754) (xy 71.223032 -303.9257) (xy 71.234809 -303.877916) (xy 71.2541 -303.83264)
			(xy 71.280403 -303.791044) (xy 71.313038 -303.754207) (xy 71.351159 -303.723082) (xy 71.39378 -303.698475)
			(xy 71.439796 -303.681023) (xy 71.488015 -303.671179) (xy 71.53719 -303.669198) (xy 71.586045 -303.67513)
			(xy 71.633316 -303.688822) (xy 71.677778 -303.70992) (xy 71.718281 -303.737876) (xy 71.753774 -303.771968)
			(xy 71.783339 -303.811312) (xy 71.80621 -303.854889) (xy 71.821794 -303.90157) (xy 71.829689 -303.950147)
			(xy 71.830184 -303.974754) (xy 72.169032 -303.974754) (xy 72.172992 -303.9257) (xy 72.184769 -303.877916)
			(xy 72.20406 -303.83264) (xy 72.230363 -303.791044) (xy 72.262998 -303.754207) (xy 72.301119 -303.723082)
			(xy 72.34374 -303.698475) (xy 72.389756 -303.681023) (xy 72.437975 -303.671179) (xy 72.48715 -303.669198)
			(xy 72.536005 -303.67513) (xy 72.583276 -303.688822) (xy 72.627738 -303.70992) (xy 72.668241 -303.737876)
			(xy 72.703734 -303.771968) (xy 72.733299 -303.811312) (xy 72.75617 -303.854889) (xy 72.771754 -303.90157)
			(xy 72.779649 -303.950147) (xy 72.780144 -303.974754) (xy 72.779649 -303.999361) (xy 72.771754 -304.047938)
			(xy 72.75617 -304.094619) (xy 72.733299 -304.138196) (xy 72.703734 -304.17754) (xy 72.668241 -304.211632)
			(xy 72.627738 -304.239588) (xy 72.583276 -304.260686) (xy 72.536005 -304.274378) (xy 72.48715 -304.28031)
			(xy 72.437975 -304.278329) (xy 72.389756 -304.268485) (xy 72.34374 -304.251033) (xy 72.301119 -304.226426)
			(xy 72.262998 -304.195301) (xy 72.230363 -304.158464) (xy 72.20406 -304.116868) (xy 72.184769 -304.071592)
			(xy 72.172992 -304.023808) (xy 72.169032 -303.974754) (xy 71.830184 -303.974754) (xy 71.829689 -303.999361)
			(xy 71.821794 -304.047938) (xy 71.80621 -304.094619) (xy 71.783339 -304.138196) (xy 71.753774 -304.17754)
			(xy 71.718281 -304.211632) (xy 71.677778 -304.239588) (xy 71.633316 -304.260686) (xy 71.586045 -304.274378)
			(xy 71.53719 -304.28031) (xy 71.488015 -304.278329) (xy 71.439796 -304.268485) (xy 71.39378 -304.251033)
			(xy 71.351159 -304.226426) (xy 71.313038 -304.195301) (xy 71.280403 -304.158464) (xy 71.2541 -304.116868)
			(xy 71.234809 -304.071592) (xy 71.223032 -304.023808) (xy 71.219072 -303.974754) (xy 70.880224 -303.974754)
			(xy 70.879729 -303.999361) (xy 70.871834 -304.047938) (xy 70.85625 -304.094619) (xy 70.833379 -304.138196)
			(xy 70.803814 -304.17754) (xy 70.768321 -304.211632) (xy 70.727818 -304.239588) (xy 70.683356 -304.260686)
			(xy 70.636085 -304.274378) (xy 70.58723 -304.28031) (xy 70.538055 -304.278329) (xy 70.489836 -304.268485)
			(xy 70.44382 -304.251033) (xy 70.401199 -304.226426) (xy 70.363078 -304.195301) (xy 70.330443 -304.158464)
			(xy 70.30414 -304.116868) (xy 70.284849 -304.071592) (xy 70.273072 -304.023808) (xy 70.269112 -303.974754)
			(xy 69.930264 -303.974754) (xy 69.929769 -303.999361) (xy 69.921874 -304.047938) (xy 69.90629 -304.094619)
			(xy 69.883419 -304.138196) (xy 69.853854 -304.17754) (xy 69.818361 -304.211632) (xy 69.777858 -304.239588)
			(xy 69.733396 -304.260686) (xy 69.686125 -304.274378) (xy 69.63727 -304.28031) (xy 69.588095 -304.278329)
			(xy 69.539876 -304.268485) (xy 69.49386 -304.251033) (xy 69.451239 -304.226426) (xy 69.413118 -304.195301)
			(xy 69.380483 -304.158464) (xy 69.35418 -304.116868) (xy 69.334889 -304.071592) (xy 69.323112 -304.023808)
			(xy 69.319152 -303.974754) (xy 68.985033 -303.974754) (xy 68.984635 -303.994535) (xy 68.97674 -304.043112)
			(xy 68.961156 -304.089793) (xy 68.938285 -304.13337) (xy 68.90872 -304.172714) (xy 68.873227 -304.206806)
			(xy 68.832724 -304.234762) (xy 68.788262 -304.25586) (xy 68.740991 -304.269552) (xy 68.692136 -304.275484)
			(xy 68.642961 -304.273503) (xy 68.594742 -304.263659) (xy 68.548726 -304.246207) (xy 68.506105 -304.2216)
			(xy 68.467984 -304.190475) (xy 68.435349 -304.153638) (xy 68.409046 -304.112042) (xy 68.389755 -304.066766)
			(xy 68.377978 -304.018982) (xy 68.374018 -303.969928) (xy 68.029993 -303.969928) (xy 68.03009 -303.974754)
			(xy 68.029595 -303.999361) (xy 68.0217 -304.047938) (xy 68.006116 -304.094619) (xy 67.983245 -304.138196)
			(xy 67.95368 -304.17754) (xy 67.918187 -304.211632) (xy 67.877684 -304.239588) (xy 67.833222 -304.260686)
			(xy 67.785951 -304.274378) (xy 67.737096 -304.28031) (xy 67.687921 -304.278329) (xy 67.639702 -304.268485)
			(xy 67.593686 -304.251033) (xy 67.551065 -304.226426) (xy 67.512944 -304.195301) (xy 67.480309 -304.158464)
			(xy 67.454006 -304.116868) (xy 67.434715 -304.071592) (xy 67.422938 -304.023808) (xy 67.418978 -303.974754)
			(xy 67.08013 -303.974754) (xy 67.079635 -303.999361) (xy 67.07174 -304.047938) (xy 67.056156 -304.094619)
			(xy 67.033285 -304.138196) (xy 67.00372 -304.17754) (xy 66.968227 -304.211632) (xy 66.927724 -304.239588)
			(xy 66.883262 -304.260686) (xy 66.835991 -304.274378) (xy 66.787136 -304.28031) (xy 66.737961 -304.278329)
			(xy 66.689742 -304.268485) (xy 66.643726 -304.251033) (xy 66.601105 -304.226426) (xy 66.562984 -304.195301)
			(xy 66.530349 -304.158464) (xy 66.504046 -304.116868) (xy 66.484755 -304.071592) (xy 66.472978 -304.023808)
			(xy 66.469018 -303.974754) (xy 66.13017 -303.974754) (xy 66.129675 -303.999361) (xy 66.12178 -304.047938)
			(xy 66.106196 -304.094619) (xy 66.083325 -304.138196) (xy 66.05376 -304.17754) (xy 66.018267 -304.211632)
			(xy 65.977764 -304.239588) (xy 65.933302 -304.260686) (xy 65.886031 -304.274378) (xy 65.837176 -304.28031)
			(xy 65.788001 -304.278329) (xy 65.739782 -304.268485) (xy 65.693766 -304.251033) (xy 65.651145 -304.226426)
			(xy 65.613024 -304.195301) (xy 65.580389 -304.158464) (xy 65.554086 -304.116868) (xy 65.534795 -304.071592)
			(xy 65.523018 -304.023808) (xy 65.519058 -303.974754) (xy 65.18021 -303.974754) (xy 65.179715 -303.999361)
			(xy 65.17182 -304.047938) (xy 65.156236 -304.094619) (xy 65.133365 -304.138196) (xy 65.1038 -304.17754)
			(xy 65.068307 -304.211632) (xy 65.027804 -304.239588) (xy 64.983342 -304.260686) (xy 64.936071 -304.274378)
			(xy 64.887216 -304.28031) (xy 64.838041 -304.278329) (xy 64.789822 -304.268485) (xy 64.743806 -304.251033)
			(xy 64.701185 -304.226426) (xy 64.663064 -304.195301) (xy 64.630429 -304.158464) (xy 64.604126 -304.116868)
			(xy 64.584835 -304.071592) (xy 64.573058 -304.023808) (xy 64.569098 -303.974754) (xy 64.23025 -303.974754)
			(xy 64.229755 -303.999361) (xy 64.22186 -304.047938) (xy 64.206276 -304.094619) (xy 64.183405 -304.138196)
			(xy 64.15384 -304.17754) (xy 64.118347 -304.211632) (xy 64.077844 -304.239588) (xy 64.033382 -304.260686)
			(xy 63.986111 -304.274378) (xy 63.937256 -304.28031) (xy 63.888081 -304.278329) (xy 63.839862 -304.268485)
			(xy 63.793846 -304.251033) (xy 63.751225 -304.226426) (xy 63.713104 -304.195301) (xy 63.680469 -304.158464)
			(xy 63.654166 -304.116868) (xy 63.634875 -304.071592) (xy 63.623098 -304.023808) (xy 63.619138 -303.974754)
			(xy 63.28029 -303.974754) (xy 63.279795 -303.999361) (xy 63.2719 -304.047938) (xy 63.256316 -304.094619)
			(xy 63.233445 -304.138196) (xy 63.20388 -304.17754) (xy 63.168387 -304.211632) (xy 63.127884 -304.239588)
			(xy 63.083422 -304.260686) (xy 63.036151 -304.274378) (xy 62.987296 -304.28031) (xy 62.938121 -304.278329)
			(xy 62.889902 -304.268485) (xy 62.843886 -304.251033) (xy 62.801265 -304.226426) (xy 62.763144 -304.195301)
			(xy 62.730509 -304.158464) (xy 62.704206 -304.116868) (xy 62.684915 -304.071592) (xy 62.673138 -304.023808)
			(xy 62.669178 -303.974754) (xy 62.330076 -303.974754) (xy 62.329581 -303.999361) (xy 62.321686 -304.047938)
			(xy 62.306102 -304.094619) (xy 62.283231 -304.138196) (xy 62.253666 -304.17754) (xy 62.218173 -304.211632)
			(xy 62.17767 -304.239588) (xy 62.133208 -304.260686) (xy 62.085937 -304.274378) (xy 62.037082 -304.28031)
			(xy 61.987907 -304.278329) (xy 61.939688 -304.268485) (xy 61.893672 -304.251033) (xy 61.851051 -304.226426)
			(xy 61.81293 -304.195301) (xy 61.780295 -304.158464) (xy 61.753992 -304.116868) (xy 61.734701 -304.071592)
			(xy 61.722924 -304.023808) (xy 61.718964 -303.974754) (xy 61.380116 -303.974754) (xy 61.379621 -303.999361)
			(xy 61.371726 -304.047938) (xy 61.356142 -304.094619) (xy 61.333271 -304.138196) (xy 61.303706 -304.17754)
			(xy 61.268213 -304.211632) (xy 61.22771 -304.239588) (xy 61.183248 -304.260686) (xy 61.135977 -304.274378)
			(xy 61.087122 -304.28031) (xy 61.037947 -304.278329) (xy 60.989728 -304.268485) (xy 60.943712 -304.251033)
			(xy 60.901091 -304.226426) (xy 60.86297 -304.195301) (xy 60.830335 -304.158464) (xy 60.804032 -304.116868)
			(xy 60.784741 -304.071592) (xy 60.772964 -304.023808) (xy 60.769004 -303.974754) (xy 60.430156 -303.974754)
			(xy 60.429661 -303.999361) (xy 60.421766 -304.047938) (xy 60.406182 -304.094619) (xy 60.383311 -304.138196)
			(xy 60.353746 -304.17754) (xy 60.318253 -304.211632) (xy 60.27775 -304.239588) (xy 60.233288 -304.260686)
			(xy 60.186017 -304.274378) (xy 60.137162 -304.28031) (xy 60.087987 -304.278329) (xy 60.039768 -304.268485)
			(xy 59.993752 -304.251033) (xy 59.951131 -304.226426) (xy 59.91301 -304.195301) (xy 59.880375 -304.158464)
			(xy 59.854072 -304.116868) (xy 59.834781 -304.071592) (xy 59.823004 -304.023808) (xy 59.819044 -303.974754)
			(xy 58.530236 -303.974754) (xy 58.529741 -303.999361) (xy 58.521846 -304.047938) (xy 58.506262 -304.094619)
			(xy 58.483391 -304.138196) (xy 58.453826 -304.17754) (xy 58.418333 -304.211632) (xy 58.37783 -304.239588)
			(xy 58.333368 -304.260686) (xy 58.286097 -304.274378) (xy 58.237242 -304.28031) (xy 58.188067 -304.278329)
			(xy 58.139848 -304.268485) (xy 58.093832 -304.251033) (xy 58.051211 -304.226426) (xy 58.01309 -304.195301)
			(xy 57.980455 -304.158464) (xy 57.954152 -304.116868) (xy 57.934861 -304.071592) (xy 57.923084 -304.023808)
			(xy 57.919124 -303.974754) (xy 57.580276 -303.974754) (xy 57.579781 -303.999361) (xy 57.571886 -304.047938)
			(xy 57.556302 -304.094619) (xy 57.533431 -304.138196) (xy 57.503866 -304.17754) (xy 57.468373 -304.211632)
			(xy 57.42787 -304.239588) (xy 57.383408 -304.260686) (xy 57.336137 -304.274378) (xy 57.287282 -304.28031)
			(xy 57.238107 -304.278329) (xy 57.189888 -304.268485) (xy 57.143872 -304.251033) (xy 57.101251 -304.226426)
			(xy 57.06313 -304.195301) (xy 57.030495 -304.158464) (xy 57.004192 -304.116868) (xy 56.984901 -304.071592)
			(xy 56.973124 -304.023808) (xy 56.969164 -303.974754) (xy 56.630062 -303.974754) (xy 56.629567 -303.999361)
			(xy 56.621672 -304.047938) (xy 56.606088 -304.094619) (xy 56.583217 -304.138196) (xy 56.553652 -304.17754)
			(xy 56.518159 -304.211632) (xy 56.477656 -304.239588) (xy 56.433194 -304.260686) (xy 56.385923 -304.274378)
			(xy 56.337068 -304.28031) (xy 56.287893 -304.278329) (xy 56.239674 -304.268485) (xy 56.193658 -304.251033)
			(xy 56.151037 -304.226426) (xy 56.112916 -304.195301) (xy 56.080281 -304.158464) (xy 56.053978 -304.116868)
			(xy 56.034687 -304.071592) (xy 56.02291 -304.023808) (xy 56.01895 -303.974754) (xy 55.680102 -303.974754)
			(xy 55.679607 -303.999361) (xy 55.671712 -304.047938) (xy 55.656128 -304.094619) (xy 55.633257 -304.138196)
			(xy 55.603692 -304.17754) (xy 55.568199 -304.211632) (xy 55.527696 -304.239588) (xy 55.483234 -304.260686)
			(xy 55.435963 -304.274378) (xy 55.387108 -304.28031) (xy 55.337933 -304.278329) (xy 55.289714 -304.268485)
			(xy 55.243698 -304.251033) (xy 55.201077 -304.226426) (xy 55.162956 -304.195301) (xy 55.130321 -304.158464)
			(xy 55.104018 -304.116868) (xy 55.084727 -304.071592) (xy 55.07295 -304.023808) (xy 55.06899 -303.974754)
			(xy 54.730142 -303.974754) (xy 54.729647 -303.999361) (xy 54.721752 -304.047938) (xy 54.706168 -304.094619)
			(xy 54.683297 -304.138196) (xy 54.653732 -304.17754) (xy 54.618239 -304.211632) (xy 54.577736 -304.239588)
			(xy 54.533274 -304.260686) (xy 54.486003 -304.274378) (xy 54.437148 -304.28031) (xy 54.387973 -304.278329)
			(xy 54.339754 -304.268485) (xy 54.293738 -304.251033) (xy 54.251117 -304.226426) (xy 54.212996 -304.195301)
			(xy 54.180361 -304.158464) (xy 54.154058 -304.116868) (xy 54.134767 -304.071592) (xy 54.12299 -304.023808)
			(xy 54.11903 -303.974754) (xy 53.780182 -303.974754) (xy 53.779687 -303.999361) (xy 53.771792 -304.047938)
			(xy 53.756208 -304.094619) (xy 53.733337 -304.138196) (xy 53.703772 -304.17754) (xy 53.668279 -304.211632)
			(xy 53.627776 -304.239588) (xy 53.583314 -304.260686) (xy 53.536043 -304.274378) (xy 53.487188 -304.28031)
			(xy 53.438013 -304.278329) (xy 53.389794 -304.268485) (xy 53.343778 -304.251033) (xy 53.301157 -304.226426)
			(xy 53.263036 -304.195301) (xy 53.230401 -304.158464) (xy 53.204098 -304.116868) (xy 53.184807 -304.071592)
			(xy 53.17303 -304.023808) (xy 53.16907 -303.974754) (xy 52.830222 -303.974754) (xy 52.829727 -303.999361)
			(xy 52.821832 -304.047938) (xy 52.806248 -304.094619) (xy 52.783377 -304.138196) (xy 52.753812 -304.17754)
			(xy 52.718319 -304.211632) (xy 52.677816 -304.239588) (xy 52.633354 -304.260686) (xy 52.586083 -304.274378)
			(xy 52.537228 -304.28031) (xy 52.488053 -304.278329) (xy 52.439834 -304.268485) (xy 52.393818 -304.251033)
			(xy 52.351197 -304.226426) (xy 52.313076 -304.195301) (xy 52.280441 -304.158464) (xy 52.254138 -304.116868)
			(xy 52.234847 -304.071592) (xy 52.22307 -304.023808) (xy 52.21911 -303.974754) (xy 51.880262 -303.974754)
			(xy 51.879767 -303.999361) (xy 51.871872 -304.047938) (xy 51.856288 -304.094619) (xy 51.833417 -304.138196)
			(xy 51.803852 -304.17754) (xy 51.768359 -304.211632) (xy 51.727856 -304.239588) (xy 51.683394 -304.260686)
			(xy 51.636123 -304.274378) (xy 51.587268 -304.28031) (xy 51.538093 -304.278329) (xy 51.489874 -304.268485)
			(xy 51.443858 -304.251033) (xy 51.401237 -304.226426) (xy 51.363116 -304.195301) (xy 51.330481 -304.158464)
			(xy 51.304178 -304.116868) (xy 51.284887 -304.071592) (xy 51.27311 -304.023808) (xy 51.26915 -303.974754)
			(xy 50.930302 -303.974754) (xy 50.929807 -303.999361) (xy 50.921912 -304.047938) (xy 50.906328 -304.094619)
			(xy 50.883457 -304.138196) (xy 50.853892 -304.17754) (xy 50.818399 -304.211632) (xy 50.777896 -304.239588)
			(xy 50.733434 -304.260686) (xy 50.686163 -304.274378) (xy 50.637308 -304.28031) (xy 50.588133 -304.278329)
			(xy 50.539914 -304.268485) (xy 50.493898 -304.251033) (xy 50.451277 -304.226426) (xy 50.413156 -304.195301)
			(xy 50.380521 -304.158464) (xy 50.354218 -304.116868) (xy 50.334927 -304.071592) (xy 50.32315 -304.023808)
			(xy 50.31919 -303.974754) (xy 49.980088 -303.974754) (xy 49.979593 -303.999361) (xy 49.971698 -304.047938)
			(xy 49.956114 -304.094619) (xy 49.933243 -304.138196) (xy 49.903678 -304.17754) (xy 49.868185 -304.211632)
			(xy 49.827682 -304.239588) (xy 49.78322 -304.260686) (xy 49.735949 -304.274378) (xy 49.687094 -304.28031)
			(xy 49.637919 -304.278329) (xy 49.5897 -304.268485) (xy 49.543684 -304.251033) (xy 49.501063 -304.226426)
			(xy 49.462942 -304.195301) (xy 49.430307 -304.158464) (xy 49.404004 -304.116868) (xy 49.384713 -304.071592)
			(xy 49.372936 -304.023808) (xy 49.368976 -303.974754) (xy 49.030128 -303.974754) (xy 49.029633 -303.999361)
			(xy 49.021738 -304.047938) (xy 49.006154 -304.094619) (xy 48.983283 -304.138196) (xy 48.953718 -304.17754)
			(xy 48.918225 -304.211632) (xy 48.877722 -304.239588) (xy 48.83326 -304.260686) (xy 48.785989 -304.274378)
			(xy 48.737134 -304.28031) (xy 48.687959 -304.278329) (xy 48.63974 -304.268485) (xy 48.593724 -304.251033)
			(xy 48.551103 -304.226426) (xy 48.512982 -304.195301) (xy 48.480347 -304.158464) (xy 48.454044 -304.116868)
			(xy 48.434753 -304.071592) (xy 48.422976 -304.023808) (xy 48.419016 -303.974754) (xy 48.080119 -303.974754)
			(xy 48.080572 -303.983122) (xy 48.075199 -304.032465) (xy 48.061914 -304.080288) (xy 48.041067 -304.125332)
			(xy 48.013207 -304.166409) (xy 47.979069 -304.202439) (xy 47.939552 -304.232471) (xy 47.895696 -304.255714)
			(xy 47.848658 -304.271556) (xy 47.799677 -304.27958) (xy 47.77486 -304.280062) (xy 47.760677 -304.279892)
			(xy 47.732437 -304.277215) (xy 47.718472 -304.274728) (xy 47.706026 -304.272442) (xy 47.682404 -304.279808)
			(xy 47.604934 -304.357278) (xy 47.597568 -304.3809) (xy 47.599854 -304.393346) (xy 47.602332 -304.407312)
			(xy 47.605003 -304.435551) (xy 47.605188 -304.449734) (xy 73.593972 -304.449734) (xy 73.597932 -304.40068)
			(xy 73.609709 -304.352896) (xy 73.629 -304.30762) (xy 73.655303 -304.266024) (xy 73.687938 -304.229187)
			(xy 73.726059 -304.198062) (xy 73.76868 -304.173455) (xy 73.814696 -304.156003) (xy 73.862915 -304.146159)
			(xy 73.91209 -304.144178) (xy 73.960945 -304.15011) (xy 74.008216 -304.163802) (xy 74.052678 -304.1849)
			(xy 74.093181 -304.212856) (xy 74.128674 -304.246948) (xy 74.158239 -304.286292) (xy 74.18111 -304.329869)
			(xy 74.196694 -304.37655) (xy 74.204589 -304.425127) (xy 74.205084 -304.449734) (xy 74.204589 -304.474341)
			(xy 74.20441 -304.475442) (xy 74.523342 -304.475442) (xy 74.523342 -304.424026) (xy 74.531385 -304.373244)
			(xy 74.547273 -304.324345) (xy 74.570616 -304.278533) (xy 74.600837 -304.236937) (xy 74.637193 -304.200581)
			(xy 74.678789 -304.17036) (xy 74.724601 -304.147017) (xy 74.7735 -304.131129) (xy 74.824282 -304.123086)
			(xy 74.875698 -304.123086) (xy 74.92648 -304.131129) (xy 74.975379 -304.147017) (xy 75.021191 -304.17036)
			(xy 75.062787 -304.200581) (xy 75.099143 -304.236937) (xy 75.129364 -304.278533) (xy 75.152707 -304.324345)
			(xy 75.168595 -304.373244) (xy 75.176638 -304.424026) (xy 75.177142 -304.449734) (xy 75.176638 -304.475442)
			(xy 75.473302 -304.475442) (xy 75.473302 -304.424026) (xy 75.481345 -304.373244) (xy 75.497233 -304.324345)
			(xy 75.520576 -304.278533) (xy 75.550797 -304.236937) (xy 75.587153 -304.200581) (xy 75.628749 -304.17036)
			(xy 75.674561 -304.147017) (xy 75.72346 -304.131129) (xy 75.774242 -304.123086) (xy 75.825658 -304.123086)
			(xy 75.87644 -304.131129) (xy 75.925339 -304.147017) (xy 75.971151 -304.17036) (xy 76.012747 -304.200581)
			(xy 76.049103 -304.236937) (xy 76.079324 -304.278533) (xy 76.102667 -304.324345) (xy 76.118555 -304.373244)
			(xy 76.126598 -304.424026) (xy 76.127102 -304.449734) (xy 76.444106 -304.449734) (xy 76.448066 -304.40068)
			(xy 76.459843 -304.352896) (xy 76.479134 -304.30762) (xy 76.505437 -304.266024) (xy 76.538072 -304.229187)
			(xy 76.576193 -304.198062) (xy 76.618814 -304.173455) (xy 76.66483 -304.156003) (xy 76.713049 -304.146159)
			(xy 76.762224 -304.144178) (xy 76.811079 -304.15011) (xy 76.85835 -304.163802) (xy 76.902812 -304.1849)
			(xy 76.943315 -304.212856) (xy 76.978808 -304.246948) (xy 77.008373 -304.286292) (xy 77.031244 -304.329869)
			(xy 77.046828 -304.37655) (xy 77.054723 -304.425127) (xy 77.055218 -304.449734) (xy 77.394066 -304.449734)
			(xy 77.398026 -304.40068) (xy 77.409803 -304.352896) (xy 77.429094 -304.30762) (xy 77.455397 -304.266024)
			(xy 77.488032 -304.229187) (xy 77.526153 -304.198062) (xy 77.568774 -304.173455) (xy 77.61479 -304.156003)
			(xy 77.663009 -304.146159) (xy 77.712184 -304.144178) (xy 77.761039 -304.15011) (xy 77.80831 -304.163802)
			(xy 77.852772 -304.1849) (xy 77.893275 -304.212856) (xy 77.928768 -304.246948) (xy 77.958333 -304.286292)
			(xy 77.981204 -304.329869) (xy 77.996788 -304.37655) (xy 78.004683 -304.425127) (xy 78.005178 -304.449734)
			(xy 78.004683 -304.474341) (xy 77.996788 -304.522918) (xy 77.981204 -304.569599) (xy 77.958333 -304.613176)
			(xy 77.928768 -304.65252) (xy 77.893275 -304.686612) (xy 77.852772 -304.714568) (xy 77.80831 -304.735666)
			(xy 77.761039 -304.749358) (xy 77.712184 -304.75529) (xy 77.663009 -304.753309) (xy 77.61479 -304.743465)
			(xy 77.568774 -304.726013) (xy 77.526153 -304.701406) (xy 77.488032 -304.670281) (xy 77.455397 -304.633444)
			(xy 77.429094 -304.591848) (xy 77.409803 -304.546572) (xy 77.398026 -304.498788) (xy 77.394066 -304.449734)
			(xy 77.055218 -304.449734) (xy 77.054723 -304.474341) (xy 77.046828 -304.522918) (xy 77.031244 -304.569599)
			(xy 77.008373 -304.613176) (xy 76.978808 -304.65252) (xy 76.943315 -304.686612) (xy 76.902812 -304.714568)
			(xy 76.85835 -304.735666) (xy 76.811079 -304.749358) (xy 76.762224 -304.75529) (xy 76.713049 -304.753309)
			(xy 76.66483 -304.743465) (xy 76.618814 -304.726013) (xy 76.576193 -304.701406) (xy 76.538072 -304.670281)
			(xy 76.505437 -304.633444) (xy 76.479134 -304.591848) (xy 76.459843 -304.546572) (xy 76.448066 -304.498788)
			(xy 76.444106 -304.449734) (xy 76.127102 -304.449734) (xy 76.126598 -304.475442) (xy 76.118555 -304.526224)
			(xy 76.102667 -304.575123) (xy 76.079324 -304.620935) (xy 76.049103 -304.662531) (xy 76.012747 -304.698887)
			(xy 75.971151 -304.729108) (xy 75.925339 -304.752451) (xy 75.87644 -304.768339) (xy 75.825658 -304.776382)
			(xy 75.774242 -304.776382) (xy 75.72346 -304.768339) (xy 75.674561 -304.752451) (xy 75.628749 -304.729108)
			(xy 75.587153 -304.698887) (xy 75.550797 -304.662531) (xy 75.520576 -304.620935) (xy 75.497233 -304.575123)
			(xy 75.481345 -304.526224) (xy 75.473302 -304.475442) (xy 75.176638 -304.475442) (xy 75.168595 -304.526224)
			(xy 75.152707 -304.575123) (xy 75.129364 -304.620935) (xy 75.099143 -304.662531) (xy 75.062787 -304.698887)
			(xy 75.021191 -304.729108) (xy 74.975379 -304.752451) (xy 74.92648 -304.768339) (xy 74.875698 -304.776382)
			(xy 74.824282 -304.776382) (xy 74.7735 -304.768339) (xy 74.724601 -304.752451) (xy 74.678789 -304.729108)
			(xy 74.637193 -304.698887) (xy 74.600837 -304.662531) (xy 74.570616 -304.620935) (xy 74.547273 -304.575123)
			(xy 74.531385 -304.526224) (xy 74.523342 -304.475442) (xy 74.20441 -304.475442) (xy 74.196694 -304.522918)
			(xy 74.18111 -304.569599) (xy 74.158239 -304.613176) (xy 74.128674 -304.65252) (xy 74.093181 -304.686612)
			(xy 74.052678 -304.714568) (xy 74.008216 -304.735666) (xy 73.960945 -304.749358) (xy 73.91209 -304.75529)
			(xy 73.862915 -304.753309) (xy 73.814696 -304.743465) (xy 73.76868 -304.726013) (xy 73.726059 -304.701406)
			(xy 73.687938 -304.670281) (xy 73.655303 -304.633444) (xy 73.629 -304.591848) (xy 73.609709 -304.546572)
			(xy 73.597932 -304.498788) (xy 73.593972 -304.449734) (xy 47.605188 -304.449734) (xy 47.605016 -304.463917)
			(xy 47.602341 -304.492157) (xy 47.599854 -304.506122) (xy 47.597568 -304.518568) (xy 47.604934 -304.54219)
			(xy 47.682404 -304.61966) (xy 47.706026 -304.627026) (xy 47.718472 -304.62474) (xy 47.732437 -304.622258)
			(xy 47.760677 -304.61959) (xy 47.77486 -304.619406) (xy 47.799685 -304.619835) (xy 47.848681 -304.627861)
			(xy 47.895733 -304.643708) (xy 47.939601 -304.666959) (xy 47.97913 -304.697) (xy 48.013278 -304.733041)
			(xy 48.041145 -304.774132) (xy 48.061997 -304.81919) (xy 48.075285 -304.867028) (xy 48.080658 -304.916386)
			(xy 48.080207 -304.924714) (xy 48.419016 -304.924714) (xy 48.422976 -304.87566) (xy 48.434753 -304.827876)
			(xy 48.454044 -304.7826) (xy 48.480347 -304.741004) (xy 48.512982 -304.704167) (xy 48.551103 -304.673042)
			(xy 48.593724 -304.648435) (xy 48.63974 -304.630983) (xy 48.687959 -304.621139) (xy 48.737134 -304.619158)
			(xy 48.785989 -304.62509) (xy 48.83326 -304.638782) (xy 48.877722 -304.65988) (xy 48.918225 -304.687836)
			(xy 48.953718 -304.721928) (xy 48.983283 -304.761272) (xy 49.006154 -304.804849) (xy 49.021738 -304.85153)
			(xy 49.029633 -304.900107) (xy 49.030128 -304.924714) (xy 49.368976 -304.924714) (xy 49.372936 -304.87566)
			(xy 49.384713 -304.827876) (xy 49.404004 -304.7826) (xy 49.430307 -304.741004) (xy 49.462942 -304.704167)
			(xy 49.501063 -304.673042) (xy 49.543684 -304.648435) (xy 49.5897 -304.630983) (xy 49.637919 -304.621139)
			(xy 49.687094 -304.619158) (xy 49.735949 -304.62509) (xy 49.78322 -304.638782) (xy 49.827682 -304.65988)
			(xy 49.868185 -304.687836) (xy 49.903678 -304.721928) (xy 49.933243 -304.761272) (xy 49.956114 -304.804849)
			(xy 49.971698 -304.85153) (xy 49.979593 -304.900107) (xy 49.980088 -304.924714) (xy 50.31919 -304.924714)
			(xy 50.32315 -304.87566) (xy 50.334927 -304.827876) (xy 50.354218 -304.7826) (xy 50.380521 -304.741004)
			(xy 50.413156 -304.704167) (xy 50.451277 -304.673042) (xy 50.493898 -304.648435) (xy 50.539914 -304.630983)
			(xy 50.588133 -304.621139) (xy 50.637308 -304.619158) (xy 50.686163 -304.62509) (xy 50.733434 -304.638782)
			(xy 50.777896 -304.65988) (xy 50.818399 -304.687836) (xy 50.853892 -304.721928) (xy 50.883457 -304.761272)
			(xy 50.906328 -304.804849) (xy 50.921912 -304.85153) (xy 50.929807 -304.900107) (xy 50.930302 -304.924714)
			(xy 51.26915 -304.924714) (xy 51.27311 -304.87566) (xy 51.284887 -304.827876) (xy 51.304178 -304.7826)
			(xy 51.330481 -304.741004) (xy 51.363116 -304.704167) (xy 51.401237 -304.673042) (xy 51.443858 -304.648435)
			(xy 51.489874 -304.630983) (xy 51.538093 -304.621139) (xy 51.587268 -304.619158) (xy 51.636123 -304.62509)
			(xy 51.683394 -304.638782) (xy 51.727856 -304.65988) (xy 51.768359 -304.687836) (xy 51.803852 -304.721928)
			(xy 51.833417 -304.761272) (xy 51.856288 -304.804849) (xy 51.871872 -304.85153) (xy 51.879767 -304.900107)
			(xy 51.880262 -304.924714) (xy 52.21911 -304.924714) (xy 52.22307 -304.87566) (xy 52.234847 -304.827876)
			(xy 52.254138 -304.7826) (xy 52.280441 -304.741004) (xy 52.313076 -304.704167) (xy 52.351197 -304.673042)
			(xy 52.393818 -304.648435) (xy 52.439834 -304.630983) (xy 52.488053 -304.621139) (xy 52.537228 -304.619158)
			(xy 52.586083 -304.62509) (xy 52.633354 -304.638782) (xy 52.677816 -304.65988) (xy 52.718319 -304.687836)
			(xy 52.753812 -304.721928) (xy 52.783377 -304.761272) (xy 52.806248 -304.804849) (xy 52.821832 -304.85153)
			(xy 52.829727 -304.900107) (xy 52.830222 -304.924714) (xy 53.16907 -304.924714) (xy 53.17303 -304.87566)
			(xy 53.184807 -304.827876) (xy 53.204098 -304.7826) (xy 53.230401 -304.741004) (xy 53.263036 -304.704167)
			(xy 53.301157 -304.673042) (xy 53.343778 -304.648435) (xy 53.389794 -304.630983) (xy 53.438013 -304.621139)
			(xy 53.487188 -304.619158) (xy 53.536043 -304.62509) (xy 53.583314 -304.638782) (xy 53.627776 -304.65988)
			(xy 53.668279 -304.687836) (xy 53.703772 -304.721928) (xy 53.733337 -304.761272) (xy 53.756208 -304.804849)
			(xy 53.771792 -304.85153) (xy 53.779687 -304.900107) (xy 53.780182 -304.924714) (xy 54.11903 -304.924714)
			(xy 54.12299 -304.87566) (xy 54.134767 -304.827876) (xy 54.154058 -304.7826) (xy 54.180361 -304.741004)
			(xy 54.212996 -304.704167) (xy 54.251117 -304.673042) (xy 54.293738 -304.648435) (xy 54.339754 -304.630983)
			(xy 54.387973 -304.621139) (xy 54.437148 -304.619158) (xy 54.486003 -304.62509) (xy 54.533274 -304.638782)
			(xy 54.577736 -304.65988) (xy 54.618239 -304.687836) (xy 54.653732 -304.721928) (xy 54.683297 -304.761272)
			(xy 54.706168 -304.804849) (xy 54.721752 -304.85153) (xy 54.729647 -304.900107) (xy 54.730142 -304.924714)
			(xy 55.06899 -304.924714) (xy 55.07295 -304.87566) (xy 55.084727 -304.827876) (xy 55.104018 -304.7826)
			(xy 55.130321 -304.741004) (xy 55.162956 -304.704167) (xy 55.201077 -304.673042) (xy 55.243698 -304.648435)
			(xy 55.289714 -304.630983) (xy 55.337933 -304.621139) (xy 55.387108 -304.619158) (xy 55.435963 -304.62509)
			(xy 55.483234 -304.638782) (xy 55.527696 -304.65988) (xy 55.568199 -304.687836) (xy 55.603692 -304.721928)
			(xy 55.633257 -304.761272) (xy 55.656128 -304.804849) (xy 55.671712 -304.85153) (xy 55.679607 -304.900107)
			(xy 55.680102 -304.924714) (xy 56.01895 -304.924714) (xy 56.02291 -304.87566) (xy 56.034687 -304.827876)
			(xy 56.053978 -304.7826) (xy 56.080281 -304.741004) (xy 56.112916 -304.704167) (xy 56.151037 -304.673042)
			(xy 56.193658 -304.648435) (xy 56.239674 -304.630983) (xy 56.287893 -304.621139) (xy 56.337068 -304.619158)
			(xy 56.385923 -304.62509) (xy 56.433194 -304.638782) (xy 56.477656 -304.65988) (xy 56.518159 -304.687836)
			(xy 56.553652 -304.721928) (xy 56.583217 -304.761272) (xy 56.606088 -304.804849) (xy 56.621672 -304.85153)
			(xy 56.629567 -304.900107) (xy 56.630062 -304.924714) (xy 56.969164 -304.924714) (xy 56.973124 -304.87566)
			(xy 56.984901 -304.827876) (xy 57.004192 -304.7826) (xy 57.030495 -304.741004) (xy 57.06313 -304.704167)
			(xy 57.101251 -304.673042) (xy 57.143872 -304.648435) (xy 57.189888 -304.630983) (xy 57.238107 -304.621139)
			(xy 57.287282 -304.619158) (xy 57.336137 -304.62509) (xy 57.383408 -304.638782) (xy 57.42787 -304.65988)
			(xy 57.468373 -304.687836) (xy 57.503866 -304.721928) (xy 57.533431 -304.761272) (xy 57.556302 -304.804849)
			(xy 57.571886 -304.85153) (xy 57.579781 -304.900107) (xy 57.580276 -304.924714) (xy 57.919124 -304.924714)
			(xy 57.923084 -304.87566) (xy 57.934861 -304.827876) (xy 57.954152 -304.7826) (xy 57.980455 -304.741004)
			(xy 58.01309 -304.704167) (xy 58.051211 -304.673042) (xy 58.093832 -304.648435) (xy 58.139848 -304.630983)
			(xy 58.188067 -304.621139) (xy 58.237242 -304.619158) (xy 58.286097 -304.62509) (xy 58.333368 -304.638782)
			(xy 58.37783 -304.65988) (xy 58.418333 -304.687836) (xy 58.453826 -304.721928) (xy 58.483391 -304.761272)
			(xy 58.506262 -304.804849) (xy 58.521846 -304.85153) (xy 58.529741 -304.900107) (xy 58.530236 -304.924714)
			(xy 59.819044 -304.924714) (xy 59.823004 -304.87566) (xy 59.834781 -304.827876) (xy 59.854072 -304.7826)
			(xy 59.880375 -304.741004) (xy 59.91301 -304.704167) (xy 59.951131 -304.673042) (xy 59.993752 -304.648435)
			(xy 60.039768 -304.630983) (xy 60.087987 -304.621139) (xy 60.137162 -304.619158) (xy 60.186017 -304.62509)
			(xy 60.233288 -304.638782) (xy 60.27775 -304.65988) (xy 60.318253 -304.687836) (xy 60.353746 -304.721928)
			(xy 60.383311 -304.761272) (xy 60.406182 -304.804849) (xy 60.421766 -304.85153) (xy 60.429661 -304.900107)
			(xy 60.430156 -304.924714) (xy 60.769004 -304.924714) (xy 60.772964 -304.87566) (xy 60.784741 -304.827876)
			(xy 60.804032 -304.7826) (xy 60.830335 -304.741004) (xy 60.86297 -304.704167) (xy 60.901091 -304.673042)
			(xy 60.943712 -304.648435) (xy 60.989728 -304.630983) (xy 61.037947 -304.621139) (xy 61.087122 -304.619158)
			(xy 61.135977 -304.62509) (xy 61.183248 -304.638782) (xy 61.22771 -304.65988) (xy 61.268213 -304.687836)
			(xy 61.303706 -304.721928) (xy 61.333271 -304.761272) (xy 61.356142 -304.804849) (xy 61.371726 -304.85153)
			(xy 61.379621 -304.900107) (xy 61.380116 -304.924714) (xy 61.718964 -304.924714) (xy 61.722924 -304.87566)
			(xy 61.734701 -304.827876) (xy 61.753992 -304.7826) (xy 61.780295 -304.741004) (xy 61.81293 -304.704167)
			(xy 61.851051 -304.673042) (xy 61.893672 -304.648435) (xy 61.939688 -304.630983) (xy 61.987907 -304.621139)
			(xy 62.037082 -304.619158) (xy 62.085937 -304.62509) (xy 62.133208 -304.638782) (xy 62.17767 -304.65988)
			(xy 62.218173 -304.687836) (xy 62.253666 -304.721928) (xy 62.283231 -304.761272) (xy 62.306102 -304.804849)
			(xy 62.321686 -304.85153) (xy 62.329581 -304.900107) (xy 62.330076 -304.924714) (xy 62.669178 -304.924714)
			(xy 62.673138 -304.87566) (xy 62.684915 -304.827876) (xy 62.704206 -304.7826) (xy 62.730509 -304.741004)
			(xy 62.763144 -304.704167) (xy 62.801265 -304.673042) (xy 62.843886 -304.648435) (xy 62.889902 -304.630983)
			(xy 62.938121 -304.621139) (xy 62.987296 -304.619158) (xy 63.036151 -304.62509) (xy 63.083422 -304.638782)
			(xy 63.127884 -304.65988) (xy 63.168387 -304.687836) (xy 63.20388 -304.721928) (xy 63.233445 -304.761272)
			(xy 63.256316 -304.804849) (xy 63.2719 -304.85153) (xy 63.279795 -304.900107) (xy 63.28029 -304.924714)
			(xy 63.619138 -304.924714) (xy 63.623098 -304.87566) (xy 63.634875 -304.827876) (xy 63.654166 -304.7826)
			(xy 63.680469 -304.741004) (xy 63.713104 -304.704167) (xy 63.751225 -304.673042) (xy 63.793846 -304.648435)
			(xy 63.839862 -304.630983) (xy 63.888081 -304.621139) (xy 63.937256 -304.619158) (xy 63.986111 -304.62509)
			(xy 64.033382 -304.638782) (xy 64.077844 -304.65988) (xy 64.118347 -304.687836) (xy 64.15384 -304.721928)
			(xy 64.183405 -304.761272) (xy 64.206276 -304.804849) (xy 64.22186 -304.85153) (xy 64.229755 -304.900107)
			(xy 64.23025 -304.924714) (xy 64.569098 -304.924714) (xy 64.573058 -304.87566) (xy 64.584835 -304.827876)
			(xy 64.604126 -304.7826) (xy 64.630429 -304.741004) (xy 64.663064 -304.704167) (xy 64.701185 -304.673042)
			(xy 64.743806 -304.648435) (xy 64.789822 -304.630983) (xy 64.838041 -304.621139) (xy 64.887216 -304.619158)
			(xy 64.936071 -304.62509) (xy 64.983342 -304.638782) (xy 65.027804 -304.65988) (xy 65.068307 -304.687836)
			(xy 65.1038 -304.721928) (xy 65.133365 -304.761272) (xy 65.156236 -304.804849) (xy 65.17182 -304.85153)
			(xy 65.179715 -304.900107) (xy 65.18021 -304.924714) (xy 65.519058 -304.924714) (xy 65.523018 -304.87566)
			(xy 65.534795 -304.827876) (xy 65.554086 -304.7826) (xy 65.580389 -304.741004) (xy 65.613024 -304.704167)
			(xy 65.651145 -304.673042) (xy 65.693766 -304.648435) (xy 65.739782 -304.630983) (xy 65.788001 -304.621139)
			(xy 65.837176 -304.619158) (xy 65.886031 -304.62509) (xy 65.933302 -304.638782) (xy 65.977764 -304.65988)
			(xy 66.018267 -304.687836) (xy 66.05376 -304.721928) (xy 66.083325 -304.761272) (xy 66.106196 -304.804849)
			(xy 66.12178 -304.85153) (xy 66.129675 -304.900107) (xy 66.13017 -304.924714) (xy 66.469018 -304.924714)
			(xy 66.472978 -304.87566) (xy 66.484755 -304.827876) (xy 66.504046 -304.7826) (xy 66.530349 -304.741004)
			(xy 66.562984 -304.704167) (xy 66.601105 -304.673042) (xy 66.643726 -304.648435) (xy 66.689742 -304.630983)
			(xy 66.737961 -304.621139) (xy 66.787136 -304.619158) (xy 66.835991 -304.62509) (xy 66.883262 -304.638782)
			(xy 66.927724 -304.65988) (xy 66.968227 -304.687836) (xy 67.00372 -304.721928) (xy 67.033285 -304.761272)
			(xy 67.056156 -304.804849) (xy 67.07174 -304.85153) (xy 67.079635 -304.900107) (xy 67.08013 -304.924714)
			(xy 67.418978 -304.924714) (xy 67.422938 -304.87566) (xy 67.434715 -304.827876) (xy 67.454006 -304.7826)
			(xy 67.480309 -304.741004) (xy 67.512944 -304.704167) (xy 67.551065 -304.673042) (xy 67.593686 -304.648435)
			(xy 67.639702 -304.630983) (xy 67.687921 -304.621139) (xy 67.737096 -304.619158) (xy 67.785951 -304.62509)
			(xy 67.833222 -304.638782) (xy 67.877684 -304.65988) (xy 67.918187 -304.687836) (xy 67.95368 -304.721928)
			(xy 67.983245 -304.761272) (xy 68.006116 -304.804849) (xy 68.0217 -304.85153) (xy 68.029595 -304.900107)
			(xy 68.03009 -304.924714) (xy 68.368938 -304.924714) (xy 68.372898 -304.87566) (xy 68.384675 -304.827876)
			(xy 68.403966 -304.7826) (xy 68.430269 -304.741004) (xy 68.462904 -304.704167) (xy 68.501025 -304.673042)
			(xy 68.543646 -304.648435) (xy 68.589662 -304.630983) (xy 68.637881 -304.621139) (xy 68.687056 -304.619158)
			(xy 68.735911 -304.62509) (xy 68.783182 -304.638782) (xy 68.827644 -304.65988) (xy 68.868147 -304.687836)
			(xy 68.90364 -304.721928) (xy 68.933205 -304.761272) (xy 68.956076 -304.804849) (xy 68.97166 -304.85153)
			(xy 68.979555 -304.900107) (xy 68.98005 -304.924714) (xy 69.319152 -304.924714) (xy 69.323112 -304.87566)
			(xy 69.334889 -304.827876) (xy 69.35418 -304.7826) (xy 69.380483 -304.741004) (xy 69.413118 -304.704167)
			(xy 69.451239 -304.673042) (xy 69.49386 -304.648435) (xy 69.539876 -304.630983) (xy 69.588095 -304.621139)
			(xy 69.63727 -304.619158) (xy 69.686125 -304.62509) (xy 69.733396 -304.638782) (xy 69.777858 -304.65988)
			(xy 69.818361 -304.687836) (xy 69.853854 -304.721928) (xy 69.883419 -304.761272) (xy 69.90629 -304.804849)
			(xy 69.921874 -304.85153) (xy 69.929769 -304.900107) (xy 69.930264 -304.924714) (xy 70.269112 -304.924714)
			(xy 70.273072 -304.87566) (xy 70.284849 -304.827876) (xy 70.30414 -304.7826) (xy 70.330443 -304.741004)
			(xy 70.363078 -304.704167) (xy 70.401199 -304.673042) (xy 70.44382 -304.648435) (xy 70.489836 -304.630983)
			(xy 70.538055 -304.621139) (xy 70.58723 -304.619158) (xy 70.636085 -304.62509) (xy 70.683356 -304.638782)
			(xy 70.727818 -304.65988) (xy 70.768321 -304.687836) (xy 70.803814 -304.721928) (xy 70.833379 -304.761272)
			(xy 70.85625 -304.804849) (xy 70.871834 -304.85153) (xy 70.879729 -304.900107) (xy 70.880224 -304.924714)
			(xy 71.219072 -304.924714) (xy 71.223032 -304.87566) (xy 71.234809 -304.827876) (xy 71.2541 -304.7826)
			(xy 71.280403 -304.741004) (xy 71.313038 -304.704167) (xy 71.351159 -304.673042) (xy 71.39378 -304.648435)
			(xy 71.439796 -304.630983) (xy 71.488015 -304.621139) (xy 71.53719 -304.619158) (xy 71.586045 -304.62509)
			(xy 71.633316 -304.638782) (xy 71.677778 -304.65988) (xy 71.718281 -304.687836) (xy 71.753774 -304.721928)
			(xy 71.783339 -304.761272) (xy 71.80621 -304.804849) (xy 71.821794 -304.85153) (xy 71.829689 -304.900107)
			(xy 71.830184 -304.924714) (xy 72.169032 -304.924714) (xy 72.172992 -304.87566) (xy 72.184769 -304.827876)
			(xy 72.20406 -304.7826) (xy 72.230363 -304.741004) (xy 72.262998 -304.704167) (xy 72.301119 -304.673042)
			(xy 72.34374 -304.648435) (xy 72.389756 -304.630983) (xy 72.437975 -304.621139) (xy 72.48715 -304.619158)
			(xy 72.536005 -304.62509) (xy 72.583276 -304.638782) (xy 72.627738 -304.65988) (xy 72.668241 -304.687836)
			(xy 72.703734 -304.721928) (xy 72.733299 -304.761272) (xy 72.75617 -304.804849) (xy 72.771754 -304.85153)
			(xy 72.779649 -304.900107) (xy 72.780144 -304.924714) (xy 72.779649 -304.949321) (xy 72.771754 -304.997898)
			(xy 72.75617 -305.044579) (xy 72.733299 -305.088156) (xy 72.703734 -305.1275) (xy 72.668241 -305.161592)
			(xy 72.627738 -305.189548) (xy 72.583276 -305.210646) (xy 72.536005 -305.224338) (xy 72.48715 -305.23027)
			(xy 72.437975 -305.228289) (xy 72.389756 -305.218445) (xy 72.34374 -305.200993) (xy 72.301119 -305.176386)
			(xy 72.262998 -305.145261) (xy 72.230363 -305.108424) (xy 72.20406 -305.066828) (xy 72.184769 -305.021552)
			(xy 72.172992 -304.973768) (xy 72.169032 -304.924714) (xy 71.830184 -304.924714) (xy 71.829689 -304.949321)
			(xy 71.821794 -304.997898) (xy 71.80621 -305.044579) (xy 71.783339 -305.088156) (xy 71.753774 -305.1275)
			(xy 71.718281 -305.161592) (xy 71.677778 -305.189548) (xy 71.633316 -305.210646) (xy 71.586045 -305.224338)
			(xy 71.53719 -305.23027) (xy 71.488015 -305.228289) (xy 71.439796 -305.218445) (xy 71.39378 -305.200993)
			(xy 71.351159 -305.176386) (xy 71.313038 -305.145261) (xy 71.280403 -305.108424) (xy 71.2541 -305.066828)
			(xy 71.234809 -305.021552) (xy 71.223032 -304.973768) (xy 71.219072 -304.924714) (xy 70.880224 -304.924714)
			(xy 70.879729 -304.949321) (xy 70.871834 -304.997898) (xy 70.85625 -305.044579) (xy 70.833379 -305.088156)
			(xy 70.803814 -305.1275) (xy 70.768321 -305.161592) (xy 70.727818 -305.189548) (xy 70.683356 -305.210646)
			(xy 70.636085 -305.224338) (xy 70.58723 -305.23027) (xy 70.538055 -305.228289) (xy 70.489836 -305.218445)
			(xy 70.44382 -305.200993) (xy 70.401199 -305.176386) (xy 70.363078 -305.145261) (xy 70.330443 -305.108424)
			(xy 70.30414 -305.066828) (xy 70.284849 -305.021552) (xy 70.273072 -304.973768) (xy 70.269112 -304.924714)
			(xy 69.930264 -304.924714) (xy 69.929769 -304.949321) (xy 69.921874 -304.997898) (xy 69.90629 -305.044579)
			(xy 69.883419 -305.088156) (xy 69.853854 -305.1275) (xy 69.818361 -305.161592) (xy 69.777858 -305.189548)
			(xy 69.733396 -305.210646) (xy 69.686125 -305.224338) (xy 69.63727 -305.23027) (xy 69.588095 -305.228289)
			(xy 69.539876 -305.218445) (xy 69.49386 -305.200993) (xy 69.451239 -305.176386) (xy 69.413118 -305.145261)
			(xy 69.380483 -305.108424) (xy 69.35418 -305.066828) (xy 69.334889 -305.021552) (xy 69.323112 -304.973768)
			(xy 69.319152 -304.924714) (xy 68.98005 -304.924714) (xy 68.979555 -304.949321) (xy 68.97166 -304.997898)
			(xy 68.956076 -305.044579) (xy 68.933205 -305.088156) (xy 68.90364 -305.1275) (xy 68.868147 -305.161592)
			(xy 68.827644 -305.189548) (xy 68.783182 -305.210646) (xy 68.735911 -305.224338) (xy 68.687056 -305.23027)
			(xy 68.637881 -305.228289) (xy 68.589662 -305.218445) (xy 68.543646 -305.200993) (xy 68.501025 -305.176386)
			(xy 68.462904 -305.145261) (xy 68.430269 -305.108424) (xy 68.403966 -305.066828) (xy 68.384675 -305.021552)
			(xy 68.372898 -304.973768) (xy 68.368938 -304.924714) (xy 68.03009 -304.924714) (xy 68.029595 -304.949321)
			(xy 68.0217 -304.997898) (xy 68.006116 -305.044579) (xy 67.983245 -305.088156) (xy 67.95368 -305.1275)
			(xy 67.918187 -305.161592) (xy 67.877684 -305.189548) (xy 67.833222 -305.210646) (xy 67.785951 -305.224338)
			(xy 67.737096 -305.23027) (xy 67.687921 -305.228289) (xy 67.639702 -305.218445) (xy 67.593686 -305.200993)
			(xy 67.551065 -305.176386) (xy 67.512944 -305.145261) (xy 67.480309 -305.108424) (xy 67.454006 -305.066828)
			(xy 67.434715 -305.021552) (xy 67.422938 -304.973768) (xy 67.418978 -304.924714) (xy 67.08013 -304.924714)
			(xy 67.079635 -304.949321) (xy 67.07174 -304.997898) (xy 67.056156 -305.044579) (xy 67.033285 -305.088156)
			(xy 67.00372 -305.1275) (xy 66.968227 -305.161592) (xy 66.927724 -305.189548) (xy 66.883262 -305.210646)
			(xy 66.835991 -305.224338) (xy 66.787136 -305.23027) (xy 66.737961 -305.228289) (xy 66.689742 -305.218445)
			(xy 66.643726 -305.200993) (xy 66.601105 -305.176386) (xy 66.562984 -305.145261) (xy 66.530349 -305.108424)
			(xy 66.504046 -305.066828) (xy 66.484755 -305.021552) (xy 66.472978 -304.973768) (xy 66.469018 -304.924714)
			(xy 66.13017 -304.924714) (xy 66.129675 -304.949321) (xy 66.12178 -304.997898) (xy 66.106196 -305.044579)
			(xy 66.083325 -305.088156) (xy 66.05376 -305.1275) (xy 66.018267 -305.161592) (xy 65.977764 -305.189548)
			(xy 65.933302 -305.210646) (xy 65.886031 -305.224338) (xy 65.837176 -305.23027) (xy 65.788001 -305.228289)
			(xy 65.739782 -305.218445) (xy 65.693766 -305.200993) (xy 65.651145 -305.176386) (xy 65.613024 -305.145261)
			(xy 65.580389 -305.108424) (xy 65.554086 -305.066828) (xy 65.534795 -305.021552) (xy 65.523018 -304.973768)
			(xy 65.519058 -304.924714) (xy 65.18021 -304.924714) (xy 65.179715 -304.949321) (xy 65.17182 -304.997898)
			(xy 65.156236 -305.044579) (xy 65.133365 -305.088156) (xy 65.1038 -305.1275) (xy 65.068307 -305.161592)
			(xy 65.027804 -305.189548) (xy 64.983342 -305.210646) (xy 64.936071 -305.224338) (xy 64.887216 -305.23027)
			(xy 64.838041 -305.228289) (xy 64.789822 -305.218445) (xy 64.743806 -305.200993) (xy 64.701185 -305.176386)
			(xy 64.663064 -305.145261) (xy 64.630429 -305.108424) (xy 64.604126 -305.066828) (xy 64.584835 -305.021552)
			(xy 64.573058 -304.973768) (xy 64.569098 -304.924714) (xy 64.23025 -304.924714) (xy 64.229755 -304.949321)
			(xy 64.22186 -304.997898) (xy 64.206276 -305.044579) (xy 64.183405 -305.088156) (xy 64.15384 -305.1275)
			(xy 64.118347 -305.161592) (xy 64.077844 -305.189548) (xy 64.033382 -305.210646) (xy 63.986111 -305.224338)
			(xy 63.937256 -305.23027) (xy 63.888081 -305.228289) (xy 63.839862 -305.218445) (xy 63.793846 -305.200993)
			(xy 63.751225 -305.176386) (xy 63.713104 -305.145261) (xy 63.680469 -305.108424) (xy 63.654166 -305.066828)
			(xy 63.634875 -305.021552) (xy 63.623098 -304.973768) (xy 63.619138 -304.924714) (xy 63.28029 -304.924714)
			(xy 63.279795 -304.949321) (xy 63.2719 -304.997898) (xy 63.256316 -305.044579) (xy 63.233445 -305.088156)
			(xy 63.20388 -305.1275) (xy 63.168387 -305.161592) (xy 63.127884 -305.189548) (xy 63.083422 -305.210646)
			(xy 63.036151 -305.224338) (xy 62.987296 -305.23027) (xy 62.938121 -305.228289) (xy 62.889902 -305.218445)
			(xy 62.843886 -305.200993) (xy 62.801265 -305.176386) (xy 62.763144 -305.145261) (xy 62.730509 -305.108424)
			(xy 62.704206 -305.066828) (xy 62.684915 -305.021552) (xy 62.673138 -304.973768) (xy 62.669178 -304.924714)
			(xy 62.330076 -304.924714) (xy 62.329581 -304.949321) (xy 62.321686 -304.997898) (xy 62.306102 -305.044579)
			(xy 62.283231 -305.088156) (xy 62.253666 -305.1275) (xy 62.218173 -305.161592) (xy 62.17767 -305.189548)
			(xy 62.133208 -305.210646) (xy 62.085937 -305.224338) (xy 62.037082 -305.23027) (xy 61.987907 -305.228289)
			(xy 61.939688 -305.218445) (xy 61.893672 -305.200993) (xy 61.851051 -305.176386) (xy 61.81293 -305.145261)
			(xy 61.780295 -305.108424) (xy 61.753992 -305.066828) (xy 61.734701 -305.021552) (xy 61.722924 -304.973768)
			(xy 61.718964 -304.924714) (xy 61.380116 -304.924714) (xy 61.379621 -304.949321) (xy 61.371726 -304.997898)
			(xy 61.356142 -305.044579) (xy 61.333271 -305.088156) (xy 61.303706 -305.1275) (xy 61.268213 -305.161592)
			(xy 61.22771 -305.189548) (xy 61.183248 -305.210646) (xy 61.135977 -305.224338) (xy 61.087122 -305.23027)
			(xy 61.037947 -305.228289) (xy 60.989728 -305.218445) (xy 60.943712 -305.200993) (xy 60.901091 -305.176386)
			(xy 60.86297 -305.145261) (xy 60.830335 -305.108424) (xy 60.804032 -305.066828) (xy 60.784741 -305.021552)
			(xy 60.772964 -304.973768) (xy 60.769004 -304.924714) (xy 60.430156 -304.924714) (xy 60.429661 -304.949321)
			(xy 60.421766 -304.997898) (xy 60.406182 -305.044579) (xy 60.383311 -305.088156) (xy 60.353746 -305.1275)
			(xy 60.318253 -305.161592) (xy 60.27775 -305.189548) (xy 60.233288 -305.210646) (xy 60.186017 -305.224338)
			(xy 60.137162 -305.23027) (xy 60.087987 -305.228289) (xy 60.039768 -305.218445) (xy 59.993752 -305.200993)
			(xy 59.951131 -305.176386) (xy 59.91301 -305.145261) (xy 59.880375 -305.108424) (xy 59.854072 -305.066828)
			(xy 59.834781 -305.021552) (xy 59.823004 -304.973768) (xy 59.819044 -304.924714) (xy 58.530236 -304.924714)
			(xy 58.529741 -304.949321) (xy 58.521846 -304.997898) (xy 58.506262 -305.044579) (xy 58.483391 -305.088156)
			(xy 58.453826 -305.1275) (xy 58.418333 -305.161592) (xy 58.37783 -305.189548) (xy 58.333368 -305.210646)
			(xy 58.286097 -305.224338) (xy 58.237242 -305.23027) (xy 58.188067 -305.228289) (xy 58.139848 -305.218445)
			(xy 58.093832 -305.200993) (xy 58.051211 -305.176386) (xy 58.01309 -305.145261) (xy 57.980455 -305.108424)
			(xy 57.954152 -305.066828) (xy 57.934861 -305.021552) (xy 57.923084 -304.973768) (xy 57.919124 -304.924714)
			(xy 57.580276 -304.924714) (xy 57.579781 -304.949321) (xy 57.571886 -304.997898) (xy 57.556302 -305.044579)
			(xy 57.533431 -305.088156) (xy 57.503866 -305.1275) (xy 57.468373 -305.161592) (xy 57.42787 -305.189548)
			(xy 57.383408 -305.210646) (xy 57.336137 -305.224338) (xy 57.287282 -305.23027) (xy 57.238107 -305.228289)
			(xy 57.189888 -305.218445) (xy 57.143872 -305.200993) (xy 57.101251 -305.176386) (xy 57.06313 -305.145261)
			(xy 57.030495 -305.108424) (xy 57.004192 -305.066828) (xy 56.984901 -305.021552) (xy 56.973124 -304.973768)
			(xy 56.969164 -304.924714) (xy 56.630062 -304.924714) (xy 56.629567 -304.949321) (xy 56.621672 -304.997898)
			(xy 56.606088 -305.044579) (xy 56.583217 -305.088156) (xy 56.553652 -305.1275) (xy 56.518159 -305.161592)
			(xy 56.477656 -305.189548) (xy 56.433194 -305.210646) (xy 56.385923 -305.224338) (xy 56.337068 -305.23027)
			(xy 56.287893 -305.228289) (xy 56.239674 -305.218445) (xy 56.193658 -305.200993) (xy 56.151037 -305.176386)
			(xy 56.112916 -305.145261) (xy 56.080281 -305.108424) (xy 56.053978 -305.066828) (xy 56.034687 -305.021552)
			(xy 56.02291 -304.973768) (xy 56.01895 -304.924714) (xy 55.680102 -304.924714) (xy 55.679607 -304.949321)
			(xy 55.671712 -304.997898) (xy 55.656128 -305.044579) (xy 55.633257 -305.088156) (xy 55.603692 -305.1275)
			(xy 55.568199 -305.161592) (xy 55.527696 -305.189548) (xy 55.483234 -305.210646) (xy 55.435963 -305.224338)
			(xy 55.387108 -305.23027) (xy 55.337933 -305.228289) (xy 55.289714 -305.218445) (xy 55.243698 -305.200993)
			(xy 55.201077 -305.176386) (xy 55.162956 -305.145261) (xy 55.130321 -305.108424) (xy 55.104018 -305.066828)
			(xy 55.084727 -305.021552) (xy 55.07295 -304.973768) (xy 55.06899 -304.924714) (xy 54.730142 -304.924714)
			(xy 54.729647 -304.949321) (xy 54.721752 -304.997898) (xy 54.706168 -305.044579) (xy 54.683297 -305.088156)
			(xy 54.653732 -305.1275) (xy 54.618239 -305.161592) (xy 54.577736 -305.189548) (xy 54.533274 -305.210646)
			(xy 54.486003 -305.224338) (xy 54.437148 -305.23027) (xy 54.387973 -305.228289) (xy 54.339754 -305.218445)
			(xy 54.293738 -305.200993) (xy 54.251117 -305.176386) (xy 54.212996 -305.145261) (xy 54.180361 -305.108424)
			(xy 54.154058 -305.066828) (xy 54.134767 -305.021552) (xy 54.12299 -304.973768) (xy 54.11903 -304.924714)
			(xy 53.780182 -304.924714) (xy 53.779687 -304.949321) (xy 53.771792 -304.997898) (xy 53.756208 -305.044579)
			(xy 53.733337 -305.088156) (xy 53.703772 -305.1275) (xy 53.668279 -305.161592) (xy 53.627776 -305.189548)
			(xy 53.583314 -305.210646) (xy 53.536043 -305.224338) (xy 53.487188 -305.23027) (xy 53.438013 -305.228289)
			(xy 53.389794 -305.218445) (xy 53.343778 -305.200993) (xy 53.301157 -305.176386) (xy 53.263036 -305.145261)
			(xy 53.230401 -305.108424) (xy 53.204098 -305.066828) (xy 53.184807 -305.021552) (xy 53.17303 -304.973768)
			(xy 53.16907 -304.924714) (xy 52.830222 -304.924714) (xy 52.829727 -304.949321) (xy 52.821832 -304.997898)
			(xy 52.806248 -305.044579) (xy 52.783377 -305.088156) (xy 52.753812 -305.1275) (xy 52.718319 -305.161592)
			(xy 52.677816 -305.189548) (xy 52.633354 -305.210646) (xy 52.586083 -305.224338) (xy 52.537228 -305.23027)
			(xy 52.488053 -305.228289) (xy 52.439834 -305.218445) (xy 52.393818 -305.200993) (xy 52.351197 -305.176386)
			(xy 52.313076 -305.145261) (xy 52.280441 -305.108424) (xy 52.254138 -305.066828) (xy 52.234847 -305.021552)
			(xy 52.22307 -304.973768) (xy 52.21911 -304.924714) (xy 51.880262 -304.924714) (xy 51.879767 -304.949321)
			(xy 51.871872 -304.997898) (xy 51.856288 -305.044579) (xy 51.833417 -305.088156) (xy 51.803852 -305.1275)
			(xy 51.768359 -305.161592) (xy 51.727856 -305.189548) (xy 51.683394 -305.210646) (xy 51.636123 -305.224338)
			(xy 51.587268 -305.23027) (xy 51.538093 -305.228289) (xy 51.489874 -305.218445) (xy 51.443858 -305.200993)
			(xy 51.401237 -305.176386) (xy 51.363116 -305.145261) (xy 51.330481 -305.108424) (xy 51.304178 -305.066828)
			(xy 51.284887 -305.021552) (xy 51.27311 -304.973768) (xy 51.26915 -304.924714) (xy 50.930302 -304.924714)
			(xy 50.929807 -304.949321) (xy 50.921912 -304.997898) (xy 50.906328 -305.044579) (xy 50.883457 -305.088156)
			(xy 50.853892 -305.1275) (xy 50.818399 -305.161592) (xy 50.777896 -305.189548) (xy 50.733434 -305.210646)
			(xy 50.686163 -305.224338) (xy 50.637308 -305.23027) (xy 50.588133 -305.228289) (xy 50.539914 -305.218445)
			(xy 50.493898 -305.200993) (xy 50.451277 -305.176386) (xy 50.413156 -305.145261) (xy 50.380521 -305.108424)
			(xy 50.354218 -305.066828) (xy 50.334927 -305.021552) (xy 50.32315 -304.973768) (xy 50.31919 -304.924714)
			(xy 49.980088 -304.924714) (xy 49.979593 -304.949321) (xy 49.971698 -304.997898) (xy 49.956114 -305.044579)
			(xy 49.933243 -305.088156) (xy 49.903678 -305.1275) (xy 49.868185 -305.161592) (xy 49.827682 -305.189548)
			(xy 49.78322 -305.210646) (xy 49.735949 -305.224338) (xy 49.687094 -305.23027) (xy 49.637919 -305.228289)
			(xy 49.5897 -305.218445) (xy 49.543684 -305.200993) (xy 49.501063 -305.176386) (xy 49.462942 -305.145261)
			(xy 49.430307 -305.108424) (xy 49.404004 -305.066828) (xy 49.384713 -305.021552) (xy 49.372936 -304.973768)
			(xy 49.368976 -304.924714) (xy 49.030128 -304.924714) (xy 49.029633 -304.949321) (xy 49.021738 -304.997898)
			(xy 49.006154 -305.044579) (xy 48.983283 -305.088156) (xy 48.953718 -305.1275) (xy 48.918225 -305.161592)
			(xy 48.877722 -305.189548) (xy 48.83326 -305.210646) (xy 48.785989 -305.224338) (xy 48.737134 -305.23027)
			(xy 48.687959 -305.228289) (xy 48.63974 -305.218445) (xy 48.593724 -305.200993) (xy 48.551103 -305.176386)
			(xy 48.512982 -305.145261) (xy 48.480347 -305.108424) (xy 48.454044 -305.066828) (xy 48.434753 -305.021552)
			(xy 48.422976 -304.973768) (xy 48.419016 -304.924714) (xy 48.080207 -304.924714) (xy 48.077975 -304.965962)
			(xy 48.067307 -305.014452) (xy 48.048934 -305.060576) (xy 48.023341 -305.103121) (xy 47.991203 -305.140964)
			(xy 47.953365 -305.17311) (xy 47.910825 -305.19871) (xy 47.864703 -305.217091) (xy 47.816216 -305.227768)
			(xy 47.76664 -305.230459) (xy 47.717281 -305.225095) (xy 47.669441 -305.211816) (xy 47.624379 -305.190972)
			(xy 47.583284 -305.163112) (xy 47.547236 -305.12897) (xy 47.517188 -305.089447) (xy 47.493929 -305.045582)
			(xy 47.478074 -304.998533) (xy 47.470039 -304.949539) (xy 47.469552 -304.924714) (xy 47.469731 -304.910531)
			(xy 47.472402 -304.882291) (xy 47.474886 -304.868326) (xy 47.477172 -304.85588) (xy 47.469806 -304.832258)
			(xy 47.392336 -304.754788) (xy 47.368714 -304.747422) (xy 47.356268 -304.749708) (xy 47.342302 -304.752185)
			(xy 47.314063 -304.754856) (xy 47.29988 -304.755042) (xy 47.27589 -304.754556) (xy 47.228501 -304.747048)
			(xy 47.182869 -304.73222) (xy 47.140119 -304.710437) (xy 47.101302 -304.682235) (xy 47.067374 -304.648309)
			(xy 47.039171 -304.609493) (xy 47.017385 -304.566744) (xy 47.002555 -304.521113) (xy 46.995045 -304.473724)
			(xy 46.994572 -304.449734) (xy 46.994754 -304.435551) (xy 46.997422 -304.407311) (xy 46.999906 -304.393346)
			(xy 47.002192 -304.3809) (xy 46.994826 -304.357278) (xy 46.917356 -304.279808) (xy 46.893734 -304.272442)
			(xy 46.881288 -304.274728) (xy 46.867322 -304.277202) (xy 46.839082 -304.279876) (xy 46.8249 -304.280062)
			(xy 46.810717 -304.279886) (xy 46.782477 -304.277214) (xy 46.768512 -304.274728) (xy 46.756066 -304.272442)
			(xy 46.732444 -304.279808) (xy 46.654974 -304.357278) (xy 46.647608 -304.3809) (xy 46.649894 -304.393346)
			(xy 46.652373 -304.407312) (xy 46.655043 -304.435551) (xy 46.655228 -304.449734) (xy 46.654685 -304.474552)
			(xy 46.64665 -304.523533) (xy 46.630796 -304.570568) (xy 46.607542 -304.61442) (xy 46.577499 -304.653931)
			(xy 46.54146 -304.688062) (xy 46.500375 -304.715913) (xy 46.455324 -304.73675) (xy 46.407497 -304.750024)
			(xy 46.358151 -304.755386) (xy 46.308589 -304.752694) (xy 46.260114 -304.742019) (xy 46.214006 -304.723643)
			(xy 46.171477 -304.698049) (xy 46.13365 -304.665912) (xy 46.10152 -304.628079) (xy 46.075933 -304.585546)
			(xy 46.057565 -304.539434) (xy 46.046899 -304.490958) (xy 46.044216 -304.441395) (xy 45.7051 -304.441395)
			(xy 45.705268 -304.449734) (xy 45.704773 -304.474341) (xy 45.696878 -304.522918) (xy 45.681294 -304.569599)
			(xy 45.658423 -304.613176) (xy 45.628858 -304.65252) (xy 45.593365 -304.686612) (xy 45.552862 -304.714568)
			(xy 45.5084 -304.735666) (xy 45.461129 -304.749358) (xy 45.412274 -304.75529) (xy 45.363099 -304.753309)
			(xy 45.31488 -304.743465) (xy 45.268864 -304.726013) (xy 45.226243 -304.701406) (xy 45.188122 -304.670281)
			(xy 45.155487 -304.633444) (xy 45.129184 -304.591848) (xy 45.109893 -304.546572) (xy 45.098116 -304.498788)
			(xy 45.094156 -304.449734) (xy 44.776898 -304.449734) (xy 44.776394 -304.475442) (xy 44.768351 -304.526224)
			(xy 44.752463 -304.575123) (xy 44.72912 -304.620935) (xy 44.698899 -304.662531) (xy 44.662543 -304.698887)
			(xy 44.620947 -304.729108) (xy 44.575135 -304.752451) (xy 44.526236 -304.768339) (xy 44.475454 -304.776382)
			(xy 44.424038 -304.776382) (xy 44.373256 -304.768339) (xy 44.324357 -304.752451) (xy 44.278545 -304.729108)
			(xy 44.236949 -304.698887) (xy 44.200593 -304.662531) (xy 44.170372 -304.620935) (xy 44.147029 -304.575123)
			(xy 44.131141 -304.526224) (xy 44.123098 -304.475442) (xy 43.826434 -304.475442) (xy 43.818391 -304.526224)
			(xy 43.802503 -304.575123) (xy 43.77916 -304.620935) (xy 43.748939 -304.662531) (xy 43.712583 -304.698887)
			(xy 43.670987 -304.729108) (xy 43.625175 -304.752451) (xy 43.576276 -304.768339) (xy 43.525494 -304.776382)
			(xy 43.474078 -304.776382) (xy 43.423296 -304.768339) (xy 43.374397 -304.752451) (xy 43.328585 -304.729108)
			(xy 43.286989 -304.698887) (xy 43.250633 -304.662531) (xy 43.220412 -304.620935) (xy 43.197069 -304.575123)
			(xy 43.181181 -304.526224) (xy 43.173138 -304.475442) (xy 42.85446 -304.475442) (xy 42.846744 -304.522918)
			(xy 42.83116 -304.569599) (xy 42.808289 -304.613176) (xy 42.778724 -304.65252) (xy 42.743231 -304.686612)
			(xy 42.702728 -304.714568) (xy 42.658266 -304.735666) (xy 42.610995 -304.749358) (xy 42.56214 -304.75529)
			(xy 42.512965 -304.753309) (xy 42.464746 -304.743465) (xy 42.41873 -304.726013) (xy 42.376109 -304.701406)
			(xy 42.337988 -304.670281) (xy 42.305353 -304.633444) (xy 42.27905 -304.591848) (xy 42.259759 -304.546572)
			(xy 42.247982 -304.498788) (xy 42.244022 -304.449734) (xy 41.905174 -304.449734) (xy 41.904679 -304.474341)
			(xy 41.896784 -304.522918) (xy 41.8812 -304.569599) (xy 41.858329 -304.613176) (xy 41.828764 -304.65252)
			(xy 41.793271 -304.686612) (xy 41.752768 -304.714568) (xy 41.708306 -304.735666) (xy 41.661035 -304.749358)
			(xy 41.61218 -304.75529) (xy 41.563005 -304.753309) (xy 41.514786 -304.743465) (xy 41.46877 -304.726013)
			(xy 41.426149 -304.701406) (xy 41.388028 -304.670281) (xy 41.355393 -304.633444) (xy 41.32909 -304.591848)
			(xy 41.309799 -304.546572) (xy 41.298022 -304.498788) (xy 41.294062 -304.449734) (xy 40.955214 -304.449734)
			(xy 40.954719 -304.474341) (xy 40.946824 -304.522918) (xy 40.93124 -304.569599) (xy 40.908369 -304.613176)
			(xy 40.878804 -304.65252) (xy 40.843311 -304.686612) (xy 40.802808 -304.714568) (xy 40.758346 -304.735666)
			(xy 40.711075 -304.749358) (xy 40.66222 -304.75529) (xy 40.613045 -304.753309) (xy 40.564826 -304.743465)
			(xy 40.51881 -304.726013) (xy 40.476189 -304.701406) (xy 40.438068 -304.670281) (xy 40.405433 -304.633444)
			(xy 40.37913 -304.591848) (xy 40.359839 -304.546572) (xy 40.348062 -304.498788) (xy 40.344102 -304.449734)
			(xy 40.005254 -304.449734) (xy 40.004759 -304.474341) (xy 39.996864 -304.522918) (xy 39.98128 -304.569599)
			(xy 39.958409 -304.613176) (xy 39.928844 -304.65252) (xy 39.893351 -304.686612) (xy 39.852848 -304.714568)
			(xy 39.808386 -304.735666) (xy 39.761115 -304.749358) (xy 39.71226 -304.75529) (xy 39.663085 -304.753309)
			(xy 39.614866 -304.743465) (xy 39.56885 -304.726013) (xy 39.526229 -304.701406) (xy 39.488108 -304.670281)
			(xy 39.455473 -304.633444) (xy 39.42917 -304.591848) (xy 39.409879 -304.546572) (xy 39.398102 -304.498788)
			(xy 39.394142 -304.449734) (xy 39.055294 -304.449734) (xy 39.054799 -304.474341) (xy 39.046904 -304.522918)
			(xy 39.03132 -304.569599) (xy 39.008449 -304.613176) (xy 38.978884 -304.65252) (xy 38.943391 -304.686612)
			(xy 38.902888 -304.714568) (xy 38.858426 -304.735666) (xy 38.811155 -304.749358) (xy 38.7623 -304.75529)
			(xy 38.713125 -304.753309) (xy 38.664906 -304.743465) (xy 38.61889 -304.726013) (xy 38.576269 -304.701406)
			(xy 38.538148 -304.670281) (xy 38.505513 -304.633444) (xy 38.47921 -304.591848) (xy 38.459919 -304.546572)
			(xy 38.448142 -304.498788) (xy 38.444182 -304.449734) (xy 38.126924 -304.449734) (xy 38.12642 -304.475442)
			(xy 38.118377 -304.526224) (xy 38.102489 -304.575123) (xy 38.079146 -304.620935) (xy 38.048925 -304.662531)
			(xy 38.012569 -304.698887) (xy 37.970973 -304.729108) (xy 37.925161 -304.752451) (xy 37.876262 -304.768339)
			(xy 37.82548 -304.776382) (xy 37.774064 -304.776382) (xy 37.723282 -304.768339) (xy 37.674383 -304.752451)
			(xy 37.628571 -304.729108) (xy 37.586975 -304.698887) (xy 37.550619 -304.662531) (xy 37.520398 -304.620935)
			(xy 37.497055 -304.575123) (xy 37.481167 -304.526224) (xy 37.473124 -304.475442) (xy 37.17646 -304.475442)
			(xy 37.168417 -304.526224) (xy 37.152529 -304.575123) (xy 37.129186 -304.620935) (xy 37.098965 -304.662531)
			(xy 37.062609 -304.698887) (xy 37.021013 -304.729108) (xy 36.975201 -304.752451) (xy 36.926302 -304.768339)
			(xy 36.87552 -304.776382) (xy 36.824104 -304.776382) (xy 36.773322 -304.768339) (xy 36.724423 -304.752451)
			(xy 36.678611 -304.729108) (xy 36.637015 -304.698887) (xy 36.600659 -304.662531) (xy 36.570438 -304.620935)
			(xy 36.547095 -304.575123) (xy 36.531207 -304.526224) (xy 36.523164 -304.475442) (xy 36.204273 -304.475442)
			(xy 36.196516 -304.523172) (xy 36.180932 -304.569853) (xy 36.158061 -304.61343) (xy 36.128496 -304.652774)
			(xy 36.093003 -304.686866) (xy 36.0525 -304.714822) (xy 36.008038 -304.73592) (xy 35.960767 -304.749612)
			(xy 35.911912 -304.755544) (xy 35.862737 -304.753563) (xy 35.814518 -304.743719) (xy 35.768502 -304.726267)
			(xy 35.725881 -304.70166) (xy 35.68776 -304.670535) (xy 35.655125 -304.633698) (xy 35.628822 -304.592102)
			(xy 35.609531 -304.546826) (xy 35.597754 -304.499042) (xy 35.593794 -304.449988) (xy 21.624771 -304.449988)
			(xy 21.499608 -304.508148) (xy 21.348356 -304.569731) (xy 21.194305 -304.623934) (xy 21.037815 -304.670632)
			(xy 20.879253 -304.709714) (xy 20.718987 -304.74109) (xy 20.557392 -304.764687) (xy 20.394846 -304.780449)
			(xy 20.231728 -304.788339) (xy 20.150074 -304.788824) (xy 20.066605 -304.788309) (xy 19.899871 -304.780063)
			(xy 19.733747 -304.763591) (xy 19.56864 -304.738935) (xy 19.404952 -304.706154) (xy 19.243083 -304.665329)
			(xy 19.083428 -304.616559) (xy 18.926377 -304.559962) (xy 18.772312 -304.495678) (xy 18.621611 -304.423863)
			(xy 18.47464 -304.344693) (xy 18.331759 -304.25836) (xy 18.193316 -304.165076) (xy 18.05965 -304.065068)
			(xy 17.931086 -303.95858) (xy 17.869154 -303.902618) (xy 17.857724 -303.892458) (xy 17.828514 -303.887632)
			(xy 17.7292 -303.931066) (xy 17.720404 -303.935443) (xy 17.706744 -303.949538) (xy 17.699384 -303.967734)
			(xy 17.698974 -303.977548) (xy 17.698974 -304.767234) (xy 17.699329 -304.775932) (xy 17.705153 -304.792326)
			(xy 17.716119 -304.805832) (xy 17.723358 -304.810668) (xy 17.808702 -304.862738) (xy 17.834864 -304.863754)
			(xy 17.846802 -304.857658) (xy 17.873837 -304.844449) (xy 17.931034 -304.825778) (xy 17.990454 -304.816329)
			(xy 18.020538 -304.815748) (xy 18.047809 -304.816211) (xy 18.101796 -304.823973) (xy 18.154129 -304.839339)
			(xy 18.203743 -304.861997) (xy 18.249626 -304.891484) (xy 18.290847 -304.927202) (xy 18.326564 -304.968422)
			(xy 18.356052 -305.014306) (xy 18.37871 -305.063919) (xy 18.394076 -305.116252) (xy 18.401839 -305.170239)
			(xy 18.401839 -305.224781) (xy 18.394076 -305.278768) (xy 18.37871 -305.331101) (xy 18.377312 -305.334162)
			(xy 27.409392 -305.334162) (xy 27.413463 -305.27854) (xy 27.425589 -305.224103) (xy 27.445512 -305.172012)
			(xy 27.472808 -305.123377) (xy 27.506894 -305.079234) (xy 27.547043 -305.040525) (xy 27.592401 -305.008074)
			(xy 27.642001 -304.982573) (xy 27.694785 -304.964566) (xy 27.749628 -304.954436) (xy 27.805362 -304.952399)
			(xy 27.860799 -304.958499) (xy 27.914756 -304.972605) (xy 27.966085 -304.994417) (xy 28.013691 -305.023471)
			(xy 28.056559 -305.059146) (xy 28.093776 -305.100683) (xy 28.124549 -305.147196) (xy 28.148221 -305.197693)
			(xy 28.164289 -305.2511) (xy 28.172409 -305.306276) (xy 28.172918 -305.334162) (xy 28.172409 -305.362048)
			(xy 28.166831 -305.399948) (xy 36.544008 -305.399948) (xy 36.547968 -305.350894) (xy 36.559745 -305.30311)
			(xy 36.579036 -305.257834) (xy 36.605339 -305.216238) (xy 36.637974 -305.179401) (xy 36.676095 -305.148276)
			(xy 36.718716 -305.123669) (xy 36.764732 -305.106217) (xy 36.812951 -305.096373) (xy 36.862126 -305.094392)
			(xy 36.910981 -305.100324) (xy 36.958252 -305.114016) (xy 37.002714 -305.135114) (xy 37.043217 -305.16307)
			(xy 37.07871 -305.197162) (xy 37.108275 -305.236506) (xy 37.131146 -305.280083) (xy 37.14673 -305.326764)
			(xy 37.154625 -305.375341) (xy 37.15512 -305.399948) (xy 37.493968 -305.399948) (xy 37.497928 -305.350894)
			(xy 37.509705 -305.30311) (xy 37.528996 -305.257834) (xy 37.555299 -305.216238) (xy 37.587934 -305.179401)
			(xy 37.626055 -305.148276) (xy 37.668676 -305.123669) (xy 37.714692 -305.106217) (xy 37.762911 -305.096373)
			(xy 37.812086 -305.094392) (xy 37.860941 -305.100324) (xy 37.908212 -305.114016) (xy 37.952674 -305.135114)
			(xy 37.993177 -305.16307) (xy 38.02867 -305.197162) (xy 38.058235 -305.236506) (xy 38.081106 -305.280083)
			(xy 38.09669 -305.326764) (xy 38.104585 -305.375341) (xy 38.10508 -305.399948) (xy 38.104585 -305.424555)
			(xy 38.104406 -305.425656) (xy 38.423338 -305.425656) (xy 38.423338 -305.37424) (xy 38.431381 -305.323458)
			(xy 38.447269 -305.274559) (xy 38.470612 -305.228747) (xy 38.500833 -305.187151) (xy 38.537189 -305.150795)
			(xy 38.578785 -305.120574) (xy 38.624597 -305.097231) (xy 38.673496 -305.081343) (xy 38.724278 -305.0733)
			(xy 38.775694 -305.0733) (xy 38.826476 -305.081343) (xy 38.875375 -305.097231) (xy 38.921187 -305.120574)
			(xy 38.962783 -305.150795) (xy 38.999139 -305.187151) (xy 39.02936 -305.228747) (xy 39.052703 -305.274559)
			(xy 39.068591 -305.323458) (xy 39.076634 -305.37424) (xy 39.077138 -305.399948) (xy 39.076634 -305.425656)
			(xy 39.373298 -305.425656) (xy 39.373298 -305.37424) (xy 39.381341 -305.323458) (xy 39.397229 -305.274559)
			(xy 39.420572 -305.228747) (xy 39.450793 -305.187151) (xy 39.487149 -305.150795) (xy 39.528745 -305.120574)
			(xy 39.574557 -305.097231) (xy 39.623456 -305.081343) (xy 39.674238 -305.0733) (xy 39.725654 -305.0733)
			(xy 39.776436 -305.081343) (xy 39.825335 -305.097231) (xy 39.871147 -305.120574) (xy 39.912743 -305.150795)
			(xy 39.949099 -305.187151) (xy 39.97932 -305.228747) (xy 40.002663 -305.274559) (xy 40.018551 -305.323458)
			(xy 40.026594 -305.37424) (xy 40.027098 -305.399948) (xy 40.344102 -305.399948) (xy 40.348062 -305.350894)
			(xy 40.359839 -305.30311) (xy 40.37913 -305.257834) (xy 40.405433 -305.216238) (xy 40.438068 -305.179401)
			(xy 40.476189 -305.148276) (xy 40.51881 -305.123669) (xy 40.564826 -305.106217) (xy 40.613045 -305.096373)
			(xy 40.66222 -305.094392) (xy 40.711075 -305.100324) (xy 40.758346 -305.114016) (xy 40.802808 -305.135114)
			(xy 40.843311 -305.16307) (xy 40.878804 -305.197162) (xy 40.908369 -305.236506) (xy 40.93124 -305.280083)
			(xy 40.946824 -305.326764) (xy 40.954719 -305.375341) (xy 40.955214 -305.399948) (xy 40.954719 -305.424555)
			(xy 40.95454 -305.425656) (xy 41.273218 -305.425656) (xy 41.273218 -305.37424) (xy 41.281261 -305.323458)
			(xy 41.297149 -305.274559) (xy 41.320492 -305.228747) (xy 41.350713 -305.187151) (xy 41.387069 -305.150795)
			(xy 41.428665 -305.120574) (xy 41.474477 -305.097231) (xy 41.523376 -305.081343) (xy 41.574158 -305.0733)
			(xy 41.625574 -305.0733) (xy 41.676356 -305.081343) (xy 41.725255 -305.097231) (xy 41.771067 -305.120574)
			(xy 41.812663 -305.150795) (xy 41.849019 -305.187151) (xy 41.87924 -305.228747) (xy 41.902583 -305.274559)
			(xy 41.918471 -305.323458) (xy 41.926514 -305.37424) (xy 41.927018 -305.399948) (xy 41.926514 -305.425656)
			(xy 42.223178 -305.425656) (xy 42.223178 -305.37424) (xy 42.231221 -305.323458) (xy 42.247109 -305.274559)
			(xy 42.270452 -305.228747) (xy 42.300673 -305.187151) (xy 42.337029 -305.150795) (xy 42.378625 -305.120574)
			(xy 42.424437 -305.097231) (xy 42.473336 -305.081343) (xy 42.524118 -305.0733) (xy 42.575534 -305.0733)
			(xy 42.626316 -305.081343) (xy 42.675215 -305.097231) (xy 42.721027 -305.120574) (xy 42.762623 -305.150795)
			(xy 42.798979 -305.187151) (xy 42.8292 -305.228747) (xy 42.852543 -305.274559) (xy 42.868431 -305.323458)
			(xy 42.876474 -305.37424) (xy 42.876978 -305.399948) (xy 43.193982 -305.399948) (xy 43.197942 -305.350894)
			(xy 43.209719 -305.30311) (xy 43.22901 -305.257834) (xy 43.255313 -305.216238) (xy 43.287948 -305.179401)
			(xy 43.326069 -305.148276) (xy 43.36869 -305.123669) (xy 43.414706 -305.106217) (xy 43.462925 -305.096373)
			(xy 43.5121 -305.094392) (xy 43.560955 -305.100324) (xy 43.608226 -305.114016) (xy 43.652688 -305.135114)
			(xy 43.693191 -305.16307) (xy 43.728684 -305.197162) (xy 43.758249 -305.236506) (xy 43.78112 -305.280083)
			(xy 43.796704 -305.326764) (xy 43.804599 -305.375341) (xy 43.805094 -305.399948) (xy 44.143942 -305.399948)
			(xy 44.147902 -305.350894) (xy 44.159679 -305.30311) (xy 44.17897 -305.257834) (xy 44.205273 -305.216238)
			(xy 44.237908 -305.179401) (xy 44.276029 -305.148276) (xy 44.31865 -305.123669) (xy 44.364666 -305.106217)
			(xy 44.412885 -305.096373) (xy 44.46206 -305.094392) (xy 44.510915 -305.100324) (xy 44.558186 -305.114016)
			(xy 44.602648 -305.135114) (xy 44.643151 -305.16307) (xy 44.678644 -305.197162) (xy 44.708209 -305.236506)
			(xy 44.73108 -305.280083) (xy 44.746664 -305.326764) (xy 44.754559 -305.375341) (xy 44.755054 -305.399948)
			(xy 45.094156 -305.399948) (xy 45.098116 -305.350894) (xy 45.109893 -305.30311) (xy 45.129184 -305.257834)
			(xy 45.155487 -305.216238) (xy 45.188122 -305.179401) (xy 45.226243 -305.148276) (xy 45.268864 -305.123669)
			(xy 45.31488 -305.106217) (xy 45.363099 -305.096373) (xy 45.412274 -305.094392) (xy 45.461129 -305.100324)
			(xy 45.5084 -305.114016) (xy 45.552862 -305.135114) (xy 45.593365 -305.16307) (xy 45.628858 -305.197162)
			(xy 45.658423 -305.236506) (xy 45.681294 -305.280083) (xy 45.696878 -305.326764) (xy 45.704773 -305.375341)
			(xy 45.705268 -305.399948) (xy 46.044116 -305.399948) (xy 46.048076 -305.350894) (xy 46.059853 -305.30311)
			(xy 46.079144 -305.257834) (xy 46.105447 -305.216238) (xy 46.138082 -305.179401) (xy 46.176203 -305.148276)
			(xy 46.218824 -305.123669) (xy 46.26484 -305.106217) (xy 46.313059 -305.096373) (xy 46.362234 -305.094392)
			(xy 46.411089 -305.100324) (xy 46.45836 -305.114016) (xy 46.502822 -305.135114) (xy 46.543325 -305.16307)
			(xy 46.578818 -305.197162) (xy 46.608383 -305.236506) (xy 46.631254 -305.280083) (xy 46.646838 -305.326764)
			(xy 46.654733 -305.375341) (xy 46.655228 -305.399948) (xy 73.593972 -305.399948) (xy 73.597932 -305.350894)
			(xy 73.609709 -305.30311) (xy 73.629 -305.257834) (xy 73.655303 -305.216238) (xy 73.687938 -305.179401)
			(xy 73.726059 -305.148276) (xy 73.76868 -305.123669) (xy 73.814696 -305.106217) (xy 73.862915 -305.096373)
			(xy 73.91209 -305.094392) (xy 73.960945 -305.100324) (xy 74.008216 -305.114016) (xy 74.052678 -305.135114)
			(xy 74.093181 -305.16307) (xy 74.128674 -305.197162) (xy 74.158239 -305.236506) (xy 74.18111 -305.280083)
			(xy 74.196694 -305.326764) (xy 74.204589 -305.375341) (xy 74.205084 -305.399948) (xy 74.544186 -305.399948)
			(xy 74.548146 -305.350894) (xy 74.559923 -305.30311) (xy 74.579214 -305.257834) (xy 74.605517 -305.216238)
			(xy 74.638152 -305.179401) (xy 74.676273 -305.148276) (xy 74.718894 -305.123669) (xy 74.76491 -305.106217)
			(xy 74.813129 -305.096373) (xy 74.862304 -305.094392) (xy 74.911159 -305.100324) (xy 74.95843 -305.114016)
			(xy 75.002892 -305.135114) (xy 75.043395 -305.16307) (xy 75.078888 -305.197162) (xy 75.108453 -305.236506)
			(xy 75.131324 -305.280083) (xy 75.146908 -305.326764) (xy 75.154803 -305.375341) (xy 75.155298 -305.399948)
			(xy 75.494146 -305.399948) (xy 75.498106 -305.350894) (xy 75.509883 -305.30311) (xy 75.529174 -305.257834)
			(xy 75.555477 -305.216238) (xy 75.588112 -305.179401) (xy 75.626233 -305.148276) (xy 75.668854 -305.123669)
			(xy 75.71487 -305.106217) (xy 75.763089 -305.096373) (xy 75.812264 -305.094392) (xy 75.861119 -305.100324)
			(xy 75.90839 -305.114016) (xy 75.952852 -305.135114) (xy 75.993355 -305.16307) (xy 76.028848 -305.197162)
			(xy 76.058413 -305.236506) (xy 76.081284 -305.280083) (xy 76.096868 -305.326764) (xy 76.104763 -305.375341)
			(xy 76.105258 -305.399948) (xy 76.104763 -305.424555) (xy 76.104584 -305.425656) (xy 76.423262 -305.425656)
			(xy 76.423262 -305.37424) (xy 76.431305 -305.323458) (xy 76.447193 -305.274559) (xy 76.470536 -305.228747)
			(xy 76.500757 -305.187151) (xy 76.537113 -305.150795) (xy 76.578709 -305.120574) (xy 76.624521 -305.097231)
			(xy 76.67342 -305.081343) (xy 76.724202 -305.0733) (xy 76.775618 -305.0733) (xy 76.8264 -305.081343)
			(xy 76.875299 -305.097231) (xy 76.921111 -305.120574) (xy 76.962707 -305.150795) (xy 76.999063 -305.187151)
			(xy 77.029284 -305.228747) (xy 77.052627 -305.274559) (xy 77.068515 -305.323458) (xy 77.076558 -305.37424)
			(xy 77.077062 -305.399948) (xy 77.076558 -305.425656) (xy 77.373222 -305.425656) (xy 77.373222 -305.37424)
			(xy 77.381265 -305.323458) (xy 77.397153 -305.274559) (xy 77.420496 -305.228747) (xy 77.450717 -305.187151)
			(xy 77.487073 -305.150795) (xy 77.528669 -305.120574) (xy 77.574481 -305.097231) (xy 77.62338 -305.081343)
			(xy 77.674162 -305.0733) (xy 77.725578 -305.0733) (xy 77.77636 -305.081343) (xy 77.825259 -305.097231)
			(xy 77.871071 -305.120574) (xy 77.912667 -305.150795) (xy 77.949023 -305.187151) (xy 77.979244 -305.228747)
			(xy 78.002587 -305.274559) (xy 78.018475 -305.323458) (xy 78.026518 -305.37424) (xy 78.027022 -305.399948)
			(xy 78.026518 -305.425656) (xy 78.018475 -305.476438) (xy 78.002587 -305.525337) (xy 77.979244 -305.571149)
			(xy 77.949023 -305.612745) (xy 77.912667 -305.649101) (xy 77.871071 -305.679322) (xy 77.825259 -305.702665)
			(xy 77.77636 -305.718553) (xy 77.725578 -305.726596) (xy 77.674162 -305.726596) (xy 77.62338 -305.718553)
			(xy 77.574481 -305.702665) (xy 77.528669 -305.679322) (xy 77.487073 -305.649101) (xy 77.450717 -305.612745)
			(xy 77.420496 -305.571149) (xy 77.397153 -305.525337) (xy 77.381265 -305.476438) (xy 77.373222 -305.425656)
			(xy 77.076558 -305.425656) (xy 77.068515 -305.476438) (xy 77.052627 -305.525337) (xy 77.029284 -305.571149)
			(xy 76.999063 -305.612745) (xy 76.962707 -305.649101) (xy 76.921111 -305.679322) (xy 76.875299 -305.702665)
			(xy 76.8264 -305.718553) (xy 76.775618 -305.726596) (xy 76.724202 -305.726596) (xy 76.67342 -305.718553)
			(xy 76.624521 -305.702665) (xy 76.578709 -305.679322) (xy 76.537113 -305.649101) (xy 76.500757 -305.612745)
			(xy 76.470536 -305.571149) (xy 76.447193 -305.525337) (xy 76.431305 -305.476438) (xy 76.423262 -305.425656)
			(xy 76.104584 -305.425656) (xy 76.096868 -305.473132) (xy 76.081284 -305.519813) (xy 76.058413 -305.56339)
			(xy 76.028848 -305.602734) (xy 75.993355 -305.636826) (xy 75.952852 -305.664782) (xy 75.90839 -305.68588)
			(xy 75.861119 -305.699572) (xy 75.812264 -305.705504) (xy 75.763089 -305.703523) (xy 75.71487 -305.693679)
			(xy 75.668854 -305.676227) (xy 75.626233 -305.65162) (xy 75.588112 -305.620495) (xy 75.555477 -305.583658)
			(xy 75.529174 -305.542062) (xy 75.509883 -305.496786) (xy 75.498106 -305.449002) (xy 75.494146 -305.399948)
			(xy 75.155298 -305.399948) (xy 75.154803 -305.424555) (xy 75.146908 -305.473132) (xy 75.131324 -305.519813)
			(xy 75.108453 -305.56339) (xy 75.078888 -305.602734) (xy 75.043395 -305.636826) (xy 75.002892 -305.664782)
			(xy 74.95843 -305.68588) (xy 74.911159 -305.699572) (xy 74.862304 -305.705504) (xy 74.813129 -305.703523)
			(xy 74.76491 -305.693679) (xy 74.718894 -305.676227) (xy 74.676273 -305.65162) (xy 74.638152 -305.620495)
			(xy 74.605517 -305.583658) (xy 74.579214 -305.542062) (xy 74.559923 -305.496786) (xy 74.548146 -305.449002)
			(xy 74.544186 -305.399948) (xy 74.205084 -305.399948) (xy 74.204589 -305.424555) (xy 74.196694 -305.473132)
			(xy 74.18111 -305.519813) (xy 74.158239 -305.56339) (xy 74.128674 -305.602734) (xy 74.093181 -305.636826)
			(xy 74.052678 -305.664782) (xy 74.008216 -305.68588) (xy 73.960945 -305.699572) (xy 73.91209 -305.705504)
			(xy 73.862915 -305.703523) (xy 73.814696 -305.693679) (xy 73.76868 -305.676227) (xy 73.726059 -305.65162)
			(xy 73.687938 -305.620495) (xy 73.655303 -305.583658) (xy 73.629 -305.542062) (xy 73.609709 -305.496786)
			(xy 73.597932 -305.449002) (xy 73.593972 -305.399948) (xy 46.655228 -305.399948) (xy 46.654733 -305.424555)
			(xy 46.646838 -305.473132) (xy 46.631254 -305.519813) (xy 46.608383 -305.56339) (xy 46.578818 -305.602734)
			(xy 46.543325 -305.636826) (xy 46.502822 -305.664782) (xy 46.45836 -305.68588) (xy 46.411089 -305.699572)
			(xy 46.362234 -305.705504) (xy 46.313059 -305.703523) (xy 46.26484 -305.693679) (xy 46.218824 -305.676227)
			(xy 46.176203 -305.65162) (xy 46.138082 -305.620495) (xy 46.105447 -305.583658) (xy 46.079144 -305.542062)
			(xy 46.059853 -305.496786) (xy 46.048076 -305.449002) (xy 46.044116 -305.399948) (xy 45.705268 -305.399948)
			(xy 45.704773 -305.424555) (xy 45.696878 -305.473132) (xy 45.681294 -305.519813) (xy 45.658423 -305.56339)
			(xy 45.628858 -305.602734) (xy 45.593365 -305.636826) (xy 45.552862 -305.664782) (xy 45.5084 -305.68588)
			(xy 45.461129 -305.699572) (xy 45.412274 -305.705504) (xy 45.363099 -305.703523) (xy 45.31488 -305.693679)
			(xy 45.268864 -305.676227) (xy 45.226243 -305.65162) (xy 45.188122 -305.620495) (xy 45.155487 -305.583658)
			(xy 45.129184 -305.542062) (xy 45.109893 -305.496786) (xy 45.098116 -305.449002) (xy 45.094156 -305.399948)
			(xy 44.755054 -305.399948) (xy 44.754559 -305.424555) (xy 44.746664 -305.473132) (xy 44.73108 -305.519813)
			(xy 44.708209 -305.56339) (xy 44.678644 -305.602734) (xy 44.643151 -305.636826) (xy 44.602648 -305.664782)
			(xy 44.558186 -305.68588) (xy 44.510915 -305.699572) (xy 44.46206 -305.705504) (xy 44.412885 -305.703523)
			(xy 44.364666 -305.693679) (xy 44.31865 -305.676227) (xy 44.276029 -305.65162) (xy 44.237908 -305.620495)
			(xy 44.205273 -305.583658) (xy 44.17897 -305.542062) (xy 44.159679 -305.496786) (xy 44.147902 -305.449002)
			(xy 44.143942 -305.399948) (xy 43.805094 -305.399948) (xy 43.804599 -305.424555) (xy 43.796704 -305.473132)
			(xy 43.78112 -305.519813) (xy 43.758249 -305.56339) (xy 43.728684 -305.602734) (xy 43.693191 -305.636826)
			(xy 43.652688 -305.664782) (xy 43.608226 -305.68588) (xy 43.560955 -305.699572) (xy 43.5121 -305.705504)
			(xy 43.462925 -305.703523) (xy 43.414706 -305.693679) (xy 43.36869 -305.676227) (xy 43.326069 -305.65162)
			(xy 43.287948 -305.620495) (xy 43.255313 -305.583658) (xy 43.22901 -305.542062) (xy 43.209719 -305.496786)
			(xy 43.197942 -305.449002) (xy 43.193982 -305.399948) (xy 42.876978 -305.399948) (xy 42.876474 -305.425656)
			(xy 42.868431 -305.476438) (xy 42.852543 -305.525337) (xy 42.8292 -305.571149) (xy 42.798979 -305.612745)
			(xy 42.762623 -305.649101) (xy 42.721027 -305.679322) (xy 42.675215 -305.702665) (xy 42.626316 -305.718553)
			(xy 42.575534 -305.726596) (xy 42.524118 -305.726596) (xy 42.473336 -305.718553) (xy 42.424437 -305.702665)
			(xy 42.378625 -305.679322) (xy 42.337029 -305.649101) (xy 42.300673 -305.612745) (xy 42.270452 -305.571149)
			(xy 42.247109 -305.525337) (xy 42.231221 -305.476438) (xy 42.223178 -305.425656) (xy 41.926514 -305.425656)
			(xy 41.918471 -305.476438) (xy 41.902583 -305.525337) (xy 41.87924 -305.571149) (xy 41.849019 -305.612745)
			(xy 41.812663 -305.649101) (xy 41.771067 -305.679322) (xy 41.725255 -305.702665) (xy 41.676356 -305.718553)
			(xy 41.625574 -305.726596) (xy 41.574158 -305.726596) (xy 41.523376 -305.718553) (xy 41.474477 -305.702665)
			(xy 41.428665 -305.679322) (xy 41.387069 -305.649101) (xy 41.350713 -305.612745) (xy 41.320492 -305.571149)
			(xy 41.297149 -305.525337) (xy 41.281261 -305.476438) (xy 41.273218 -305.425656) (xy 40.95454 -305.425656)
			(xy 40.946824 -305.473132) (xy 40.93124 -305.519813) (xy 40.908369 -305.56339) (xy 40.878804 -305.602734)
			(xy 40.843311 -305.636826) (xy 40.802808 -305.664782) (xy 40.758346 -305.68588) (xy 40.711075 -305.699572)
			(xy 40.66222 -305.705504) (xy 40.613045 -305.703523) (xy 40.564826 -305.693679) (xy 40.51881 -305.676227)
			(xy 40.476189 -305.65162) (xy 40.438068 -305.620495) (xy 40.405433 -305.583658) (xy 40.37913 -305.542062)
			(xy 40.359839 -305.496786) (xy 40.348062 -305.449002) (xy 40.344102 -305.399948) (xy 40.027098 -305.399948)
			(xy 40.026594 -305.425656) (xy 40.018551 -305.476438) (xy 40.002663 -305.525337) (xy 39.97932 -305.571149)
			(xy 39.949099 -305.612745) (xy 39.912743 -305.649101) (xy 39.871147 -305.679322) (xy 39.825335 -305.702665)
			(xy 39.776436 -305.718553) (xy 39.725654 -305.726596) (xy 39.674238 -305.726596) (xy 39.623456 -305.718553)
			(xy 39.574557 -305.702665) (xy 39.528745 -305.679322) (xy 39.487149 -305.649101) (xy 39.450793 -305.612745)
			(xy 39.420572 -305.571149) (xy 39.397229 -305.525337) (xy 39.381341 -305.476438) (xy 39.373298 -305.425656)
			(xy 39.076634 -305.425656) (xy 39.068591 -305.476438) (xy 39.052703 -305.525337) (xy 39.02936 -305.571149)
			(xy 38.999139 -305.612745) (xy 38.962783 -305.649101) (xy 38.921187 -305.679322) (xy 38.875375 -305.702665)
			(xy 38.826476 -305.718553) (xy 38.775694 -305.726596) (xy 38.724278 -305.726596) (xy 38.673496 -305.718553)
			(xy 38.624597 -305.702665) (xy 38.578785 -305.679322) (xy 38.537189 -305.649101) (xy 38.500833 -305.612745)
			(xy 38.470612 -305.571149) (xy 38.447269 -305.525337) (xy 38.431381 -305.476438) (xy 38.423338 -305.425656)
			(xy 38.104406 -305.425656) (xy 38.09669 -305.473132) (xy 38.081106 -305.519813) (xy 38.058235 -305.56339)
			(xy 38.02867 -305.602734) (xy 37.993177 -305.636826) (xy 37.952674 -305.664782) (xy 37.908212 -305.68588)
			(xy 37.860941 -305.699572) (xy 37.812086 -305.705504) (xy 37.762911 -305.703523) (xy 37.714692 -305.693679)
			(xy 37.668676 -305.676227) (xy 37.626055 -305.65162) (xy 37.587934 -305.620495) (xy 37.555299 -305.583658)
			(xy 37.528996 -305.542062) (xy 37.509705 -305.496786) (xy 37.497928 -305.449002) (xy 37.493968 -305.399948)
			(xy 37.15512 -305.399948) (xy 37.154625 -305.424555) (xy 37.14673 -305.473132) (xy 37.131146 -305.519813)
			(xy 37.108275 -305.56339) (xy 37.07871 -305.602734) (xy 37.043217 -305.636826) (xy 37.002714 -305.664782)
			(xy 36.958252 -305.68588) (xy 36.910981 -305.699572) (xy 36.862126 -305.705504) (xy 36.812951 -305.703523)
			(xy 36.764732 -305.693679) (xy 36.718716 -305.676227) (xy 36.676095 -305.65162) (xy 36.637974 -305.620495)
			(xy 36.605339 -305.583658) (xy 36.579036 -305.542062) (xy 36.559745 -305.496786) (xy 36.547968 -305.449002)
			(xy 36.544008 -305.399948) (xy 28.166831 -305.399948) (xy 28.164289 -305.417224) (xy 28.148221 -305.470631)
			(xy 28.124549 -305.521128) (xy 28.093776 -305.567641) (xy 28.056559 -305.609178) (xy 28.013691 -305.644853)
			(xy 27.966085 -305.673907) (xy 27.914756 -305.695719) (xy 27.860799 -305.709825) (xy 27.805362 -305.715925)
			(xy 27.749628 -305.713888) (xy 27.694785 -305.703758) (xy 27.642001 -305.685751) (xy 27.592401 -305.66025)
			(xy 27.547043 -305.627799) (xy 27.506894 -305.58909) (xy 27.472808 -305.544947) (xy 27.445512 -305.496312)
			(xy 27.425589 -305.444221) (xy 27.413463 -305.389784) (xy 27.409392 -305.334162) (xy 18.377312 -305.334162)
			(xy 18.356052 -305.380714) (xy 18.326564 -305.426598) (xy 18.290847 -305.467818) (xy 18.249626 -305.503536)
			(xy 18.203743 -305.533023) (xy 18.154129 -305.555681) (xy 18.101796 -305.571047) (xy 18.047809 -305.578809)
			(xy 18.020538 -305.579272) (xy 17.990457 -305.578683) (xy 17.931044 -305.569207) (xy 17.873847 -305.550546)
			(xy 17.846802 -305.537362) (xy 17.834864 -305.531266) (xy 17.808702 -305.532282) (xy 17.723358 -305.584352)
			(xy 17.716106 -305.589175) (xy 17.705128 -305.602679) (xy 17.699316 -305.619084) (xy 17.698974 -305.627786)
			(xy 17.698974 -305.851814) (xy 17.699326 -305.860514) (xy 17.705145 -305.876913) (xy 17.716109 -305.890424)
			(xy 17.723358 -305.895248) (xy 17.808702 -305.947318) (xy 17.834864 -305.948334) (xy 17.846802 -305.942238)
			(xy 17.873837 -305.92903) (xy 17.931034 -305.91036) (xy 17.990454 -305.900911) (xy 18.020538 -305.900328)
			(xy 18.047809 -305.900791) (xy 18.101796 -305.908553) (xy 18.154129 -305.923919) (xy 18.203743 -305.946577)
			(xy 18.249626 -305.976064) (xy 18.290847 -306.011782) (xy 18.326327 -306.052728) (xy 26.690826 -306.052728)
			(xy 26.694897 -305.997106) (xy 26.707023 -305.942669) (xy 26.726946 -305.890578) (xy 26.754242 -305.841943)
			(xy 26.788328 -305.7978) (xy 26.828477 -305.759091) (xy 26.873835 -305.72664) (xy 26.923435 -305.701139)
			(xy 26.976219 -305.683132) (xy 27.031062 -305.673002) (xy 27.086796 -305.670965) (xy 27.142233 -305.677065)
			(xy 27.19619 -305.691171) (xy 27.247519 -305.712983) (xy 27.295125 -305.742037) (xy 27.337993 -305.777712)
			(xy 27.37521 -305.819249) (xy 27.405983 -305.865762) (xy 27.429655 -305.916259) (xy 27.445723 -305.969666)
			(xy 27.453843 -306.024842) (xy 27.454352 -306.052728) (xy 27.453843 -306.080614) (xy 27.445723 -306.13579)
			(xy 27.429655 -306.189197) (xy 27.405983 -306.239694) (xy 27.37521 -306.286207) (xy 27.337993 -306.327744)
			(xy 27.311055 -306.350162) (xy 35.593794 -306.350162) (xy 35.597754 -306.301108) (xy 35.609531 -306.253324)
			(xy 35.628822 -306.208048) (xy 35.655125 -306.166452) (xy 35.68776 -306.129615) (xy 35.725881 -306.09849)
			(xy 35.768502 -306.073883) (xy 35.814518 -306.056431) (xy 35.862737 -306.046587) (xy 35.911912 -306.044606)
			(xy 35.960767 -306.050538) (xy 36.008038 -306.06423) (xy 36.0525 -306.085328) (xy 36.093003 -306.113284)
			(xy 36.128496 -306.147376) (xy 36.158061 -306.18672) (xy 36.180932 -306.230297) (xy 36.196516 -306.276978)
			(xy 36.204411 -306.325555) (xy 36.204906 -306.350162) (xy 36.204411 -306.374769) (xy 36.204273 -306.375616)
			(xy 36.523164 -306.375616) (xy 36.523164 -306.3242) (xy 36.531207 -306.273418) (xy 36.547095 -306.224519)
			(xy 36.570438 -306.178707) (xy 36.600659 -306.137111) (xy 36.637015 -306.100755) (xy 36.678611 -306.070534)
			(xy 36.724423 -306.047191) (xy 36.773322 -306.031303) (xy 36.824104 -306.02326) (xy 36.87552 -306.02326)
			(xy 36.926302 -306.031303) (xy 36.975201 -306.047191) (xy 37.021013 -306.070534) (xy 37.062609 -306.100755)
			(xy 37.098965 -306.137111) (xy 37.129186 -306.178707) (xy 37.152529 -306.224519) (xy 37.168417 -306.273418)
			(xy 37.17646 -306.3242) (xy 37.176964 -306.349908) (xy 37.17646 -306.375616) (xy 37.473124 -306.375616)
			(xy 37.473124 -306.3242) (xy 37.481167 -306.273418) (xy 37.497055 -306.224519) (xy 37.520398 -306.178707)
			(xy 37.550619 -306.137111) (xy 37.586975 -306.100755) (xy 37.628571 -306.070534) (xy 37.674383 -306.047191)
			(xy 37.723282 -306.031303) (xy 37.774064 -306.02326) (xy 37.82548 -306.02326) (xy 37.876262 -306.031303)
			(xy 37.925161 -306.047191) (xy 37.970973 -306.070534) (xy 38.012569 -306.100755) (xy 38.048925 -306.137111)
			(xy 38.079146 -306.178707) (xy 38.102489 -306.224519) (xy 38.118377 -306.273418) (xy 38.12642 -306.3242)
			(xy 38.126924 -306.349908) (xy 38.444182 -306.349908) (xy 38.448142 -306.300854) (xy 38.459919 -306.25307)
			(xy 38.47921 -306.207794) (xy 38.505513 -306.166198) (xy 38.538148 -306.129361) (xy 38.576269 -306.098236)
			(xy 38.61889 -306.073629) (xy 38.664906 -306.056177) (xy 38.713125 -306.046333) (xy 38.7623 -306.044352)
			(xy 38.811155 -306.050284) (xy 38.858426 -306.063976) (xy 38.902888 -306.085074) (xy 38.943391 -306.11303)
			(xy 38.978884 -306.147122) (xy 39.008449 -306.186466) (xy 39.03132 -306.230043) (xy 39.046904 -306.276724)
			(xy 39.054799 -306.325301) (xy 39.055294 -306.349908) (xy 39.394142 -306.349908) (xy 39.398102 -306.300854)
			(xy 39.409879 -306.25307) (xy 39.42917 -306.207794) (xy 39.455473 -306.166198) (xy 39.488108 -306.129361)
			(xy 39.526229 -306.098236) (xy 39.56885 -306.073629) (xy 39.614866 -306.056177) (xy 39.663085 -306.046333)
			(xy 39.71226 -306.044352) (xy 39.761115 -306.050284) (xy 39.808386 -306.063976) (xy 39.852848 -306.085074)
			(xy 39.893351 -306.11303) (xy 39.928844 -306.147122) (xy 39.958409 -306.186466) (xy 39.98128 -306.230043)
			(xy 39.996864 -306.276724) (xy 40.004759 -306.325301) (xy 40.005254 -306.349908) (xy 40.344102 -306.349908)
			(xy 40.348062 -306.300854) (xy 40.359839 -306.25307) (xy 40.37913 -306.207794) (xy 40.405433 -306.166198)
			(xy 40.438068 -306.129361) (xy 40.476189 -306.098236) (xy 40.51881 -306.073629) (xy 40.564826 -306.056177)
			(xy 40.613045 -306.046333) (xy 40.66222 -306.044352) (xy 40.711075 -306.050284) (xy 40.758346 -306.063976)
			(xy 40.802808 -306.085074) (xy 40.843311 -306.11303) (xy 40.878804 -306.147122) (xy 40.908369 -306.186466)
			(xy 40.93124 -306.230043) (xy 40.946824 -306.276724) (xy 40.954719 -306.325301) (xy 40.955214 -306.349908)
			(xy 41.294062 -306.349908) (xy 41.298022 -306.300854) (xy 41.309799 -306.25307) (xy 41.32909 -306.207794)
			(xy 41.355393 -306.166198) (xy 41.388028 -306.129361) (xy 41.426149 -306.098236) (xy 41.46877 -306.073629)
			(xy 41.514786 -306.056177) (xy 41.563005 -306.046333) (xy 41.61218 -306.044352) (xy 41.661035 -306.050284)
			(xy 41.708306 -306.063976) (xy 41.752768 -306.085074) (xy 41.793271 -306.11303) (xy 41.828764 -306.147122)
			(xy 41.858329 -306.186466) (xy 41.8812 -306.230043) (xy 41.896784 -306.276724) (xy 41.904679 -306.325301)
			(xy 41.905174 -306.349908) (xy 42.244022 -306.349908) (xy 42.247982 -306.300854) (xy 42.259759 -306.25307)
			(xy 42.27905 -306.207794) (xy 42.305353 -306.166198) (xy 42.337988 -306.129361) (xy 42.376109 -306.098236)
			(xy 42.41873 -306.073629) (xy 42.464746 -306.056177) (xy 42.512965 -306.046333) (xy 42.56214 -306.044352)
			(xy 42.610995 -306.050284) (xy 42.658266 -306.063976) (xy 42.702728 -306.085074) (xy 42.743231 -306.11303)
			(xy 42.778724 -306.147122) (xy 42.808289 -306.186466) (xy 42.83116 -306.230043) (xy 42.846744 -306.276724)
			(xy 42.854639 -306.325301) (xy 42.855134 -306.349908) (xy 42.854639 -306.374515) (xy 42.85446 -306.375616)
			(xy 43.173138 -306.375616) (xy 43.173138 -306.3242) (xy 43.181181 -306.273418) (xy 43.197069 -306.224519)
			(xy 43.220412 -306.178707) (xy 43.250633 -306.137111) (xy 43.286989 -306.100755) (xy 43.328585 -306.070534)
			(xy 43.374397 -306.047191) (xy 43.423296 -306.031303) (xy 43.474078 -306.02326) (xy 43.525494 -306.02326)
			(xy 43.576276 -306.031303) (xy 43.625175 -306.047191) (xy 43.670987 -306.070534) (xy 43.712583 -306.100755)
			(xy 43.748939 -306.137111) (xy 43.77916 -306.178707) (xy 43.802503 -306.224519) (xy 43.818391 -306.273418)
			(xy 43.826434 -306.3242) (xy 43.826938 -306.349908) (xy 43.826434 -306.375616) (xy 44.123098 -306.375616)
			(xy 44.123098 -306.3242) (xy 44.131141 -306.273418) (xy 44.147029 -306.224519) (xy 44.170372 -306.178707)
			(xy 44.200593 -306.137111) (xy 44.236949 -306.100755) (xy 44.278545 -306.070534) (xy 44.324357 -306.047191)
			(xy 44.373256 -306.031303) (xy 44.424038 -306.02326) (xy 44.475454 -306.02326) (xy 44.526236 -306.031303)
			(xy 44.575135 -306.047191) (xy 44.620947 -306.070534) (xy 44.662543 -306.100755) (xy 44.698899 -306.137111)
			(xy 44.72912 -306.178707) (xy 44.752463 -306.224519) (xy 44.768351 -306.273418) (xy 44.776394 -306.3242)
			(xy 44.776898 -306.349908) (xy 45.094156 -306.349908) (xy 45.098116 -306.300854) (xy 45.109893 -306.25307)
			(xy 45.129184 -306.207794) (xy 45.155487 -306.166198) (xy 45.188122 -306.129361) (xy 45.226243 -306.098236)
			(xy 45.268864 -306.073629) (xy 45.31488 -306.056177) (xy 45.363099 -306.046333) (xy 45.412274 -306.044352)
			(xy 45.461129 -306.050284) (xy 45.5084 -306.063976) (xy 45.552862 -306.085074) (xy 45.593365 -306.11303)
			(xy 45.628858 -306.147122) (xy 45.658423 -306.186466) (xy 45.681294 -306.230043) (xy 45.696878 -306.276724)
			(xy 45.704773 -306.325301) (xy 45.705268 -306.349908) (xy 46.044116 -306.349908) (xy 46.048076 -306.300854)
			(xy 46.059853 -306.25307) (xy 46.079144 -306.207794) (xy 46.105447 -306.166198) (xy 46.138082 -306.129361)
			(xy 46.176203 -306.098236) (xy 46.218824 -306.073629) (xy 46.26484 -306.056177) (xy 46.313059 -306.046333)
			(xy 46.362234 -306.044352) (xy 46.411089 -306.050284) (xy 46.45836 -306.063976) (xy 46.502822 -306.085074)
			(xy 46.543325 -306.11303) (xy 46.578818 -306.147122) (xy 46.608383 -306.186466) (xy 46.631254 -306.230043)
			(xy 46.646838 -306.276724) (xy 46.654733 -306.325301) (xy 46.655061 -306.341629) (xy 46.994189 -306.341629)
			(xy 46.999554 -306.292281) (xy 47.012832 -306.24445) (xy 47.033673 -306.199398) (xy 47.061528 -306.15831)
			(xy 47.095663 -306.122271) (xy 47.13518 -306.092228) (xy 47.179035 -306.068974) (xy 47.226075 -306.053121)
			(xy 47.27506 -306.045087) (xy 47.29988 -306.0446) (xy 47.314063 -306.044779) (xy 47.342303 -306.04745)
			(xy 47.356268 -306.049934) (xy 47.37024 -306.052045) (xy 47.398366 -306.049473) (xy 47.424709 -306.039292)
			(xy 47.447254 -306.022281) (xy 47.464274 -305.999743) (xy 47.474465 -305.973403) (xy 47.477047 -305.945279)
			(xy 47.474886 -305.931316) (xy 47.472402 -305.917351) (xy 47.469735 -305.889111) (xy 47.469552 -305.874928)
			(xy 47.470048 -305.850104) (xy 47.478076 -305.801108) (xy 47.493925 -305.754058) (xy 47.517178 -305.710191)
			(xy 47.547222 -305.670664) (xy 47.583264 -305.636519) (xy 47.624357 -305.608655) (xy 47.669416 -305.587806)
			(xy 47.717254 -305.574522) (xy 47.766612 -305.569153) (xy 47.816188 -305.57184) (xy 47.864676 -305.582513)
			(xy 47.910798 -305.60089) (xy 47.953339 -305.626487) (xy 47.991179 -305.658629) (xy 48.02332 -305.69647)
			(xy 48.048915 -305.739013) (xy 48.06729 -305.785136) (xy 48.077961 -305.833624) (xy 48.080198 -305.874928)
			(xy 48.419016 -305.874928) (xy 48.422976 -305.825874) (xy 48.434753 -305.77809) (xy 48.454044 -305.732814)
			(xy 48.480347 -305.691218) (xy 48.512982 -305.654381) (xy 48.551103 -305.623256) (xy 48.593724 -305.598649)
			(xy 48.63974 -305.581197) (xy 48.687959 -305.571353) (xy 48.737134 -305.569372) (xy 48.785989 -305.575304)
			(xy 48.83326 -305.588996) (xy 48.877722 -305.610094) (xy 48.918225 -305.63805) (xy 48.953718 -305.672142)
			(xy 48.983283 -305.711486) (xy 49.006154 -305.755063) (xy 49.021738 -305.801744) (xy 49.029633 -305.850321)
			(xy 49.030128 -305.874928) (xy 49.368976 -305.874928) (xy 49.372936 -305.825874) (xy 49.384713 -305.77809)
			(xy 49.404004 -305.732814) (xy 49.430307 -305.691218) (xy 49.462942 -305.654381) (xy 49.501063 -305.623256)
			(xy 49.543684 -305.598649) (xy 49.5897 -305.581197) (xy 49.637919 -305.571353) (xy 49.687094 -305.569372)
			(xy 49.735949 -305.575304) (xy 49.78322 -305.588996) (xy 49.827682 -305.610094) (xy 49.868185 -305.63805)
			(xy 49.903678 -305.672142) (xy 49.933243 -305.711486) (xy 49.956114 -305.755063) (xy 49.971698 -305.801744)
			(xy 49.979593 -305.850321) (xy 49.980088 -305.874928) (xy 50.31919 -305.874928) (xy 50.32315 -305.825874)
			(xy 50.334927 -305.77809) (xy 50.354218 -305.732814) (xy 50.380521 -305.691218) (xy 50.413156 -305.654381)
			(xy 50.451277 -305.623256) (xy 50.493898 -305.598649) (xy 50.539914 -305.581197) (xy 50.588133 -305.571353)
			(xy 50.637308 -305.569372) (xy 50.686163 -305.575304) (xy 50.733434 -305.588996) (xy 50.777896 -305.610094)
			(xy 50.818399 -305.63805) (xy 50.853892 -305.672142) (xy 50.883457 -305.711486) (xy 50.906328 -305.755063)
			(xy 50.921912 -305.801744) (xy 50.929807 -305.850321) (xy 50.930302 -305.874928) (xy 51.26915 -305.874928)
			(xy 51.27311 -305.825874) (xy 51.284887 -305.77809) (xy 51.304178 -305.732814) (xy 51.330481 -305.691218)
			(xy 51.363116 -305.654381) (xy 51.401237 -305.623256) (xy 51.443858 -305.598649) (xy 51.489874 -305.581197)
			(xy 51.538093 -305.571353) (xy 51.587268 -305.569372) (xy 51.636123 -305.575304) (xy 51.683394 -305.588996)
			(xy 51.727856 -305.610094) (xy 51.768359 -305.63805) (xy 51.803852 -305.672142) (xy 51.833417 -305.711486)
			(xy 51.856288 -305.755063) (xy 51.871872 -305.801744) (xy 51.879767 -305.850321) (xy 51.880262 -305.874928)
			(xy 52.21911 -305.874928) (xy 52.22307 -305.825874) (xy 52.234847 -305.77809) (xy 52.254138 -305.732814)
			(xy 52.280441 -305.691218) (xy 52.313076 -305.654381) (xy 52.351197 -305.623256) (xy 52.393818 -305.598649)
			(xy 52.439834 -305.581197) (xy 52.488053 -305.571353) (xy 52.537228 -305.569372) (xy 52.586083 -305.575304)
			(xy 52.633354 -305.588996) (xy 52.677816 -305.610094) (xy 52.718319 -305.63805) (xy 52.753812 -305.672142)
			(xy 52.783377 -305.711486) (xy 52.806248 -305.755063) (xy 52.821832 -305.801744) (xy 52.829727 -305.850321)
			(xy 52.830222 -305.874928) (xy 53.16907 -305.874928) (xy 53.17303 -305.825874) (xy 53.184807 -305.77809)
			(xy 53.204098 -305.732814) (xy 53.230401 -305.691218) (xy 53.263036 -305.654381) (xy 53.301157 -305.623256)
			(xy 53.343778 -305.598649) (xy 53.389794 -305.581197) (xy 53.438013 -305.571353) (xy 53.487188 -305.569372)
			(xy 53.536043 -305.575304) (xy 53.583314 -305.588996) (xy 53.627776 -305.610094) (xy 53.668279 -305.63805)
			(xy 53.703772 -305.672142) (xy 53.733337 -305.711486) (xy 53.756208 -305.755063) (xy 53.771792 -305.801744)
			(xy 53.779687 -305.850321) (xy 53.780182 -305.874928) (xy 54.11903 -305.874928) (xy 54.12299 -305.825874)
			(xy 54.134767 -305.77809) (xy 54.154058 -305.732814) (xy 54.180361 -305.691218) (xy 54.212996 -305.654381)
			(xy 54.251117 -305.623256) (xy 54.293738 -305.598649) (xy 54.339754 -305.581197) (xy 54.387973 -305.571353)
			(xy 54.437148 -305.569372) (xy 54.486003 -305.575304) (xy 54.533274 -305.588996) (xy 54.577736 -305.610094)
			(xy 54.618239 -305.63805) (xy 54.653732 -305.672142) (xy 54.683297 -305.711486) (xy 54.706168 -305.755063)
			(xy 54.721752 -305.801744) (xy 54.729647 -305.850321) (xy 54.730142 -305.874928) (xy 55.06899 -305.874928)
			(xy 55.07295 -305.825874) (xy 55.084727 -305.77809) (xy 55.104018 -305.732814) (xy 55.130321 -305.691218)
			(xy 55.162956 -305.654381) (xy 55.201077 -305.623256) (xy 55.243698 -305.598649) (xy 55.289714 -305.581197)
			(xy 55.337933 -305.571353) (xy 55.387108 -305.569372) (xy 55.435963 -305.575304) (xy 55.483234 -305.588996)
			(xy 55.527696 -305.610094) (xy 55.568199 -305.63805) (xy 55.603692 -305.672142) (xy 55.633257 -305.711486)
			(xy 55.656128 -305.755063) (xy 55.671712 -305.801744) (xy 55.679607 -305.850321) (xy 55.680102 -305.874928)
			(xy 56.01895 -305.874928) (xy 56.02291 -305.825874) (xy 56.034687 -305.77809) (xy 56.053978 -305.732814)
			(xy 56.080281 -305.691218) (xy 56.112916 -305.654381) (xy 56.151037 -305.623256) (xy 56.193658 -305.598649)
			(xy 56.239674 -305.581197) (xy 56.287893 -305.571353) (xy 56.337068 -305.569372) (xy 56.385923 -305.575304)
			(xy 56.433194 -305.588996) (xy 56.477656 -305.610094) (xy 56.518159 -305.63805) (xy 56.553652 -305.672142)
			(xy 56.583217 -305.711486) (xy 56.606088 -305.755063) (xy 56.621672 -305.801744) (xy 56.629567 -305.850321)
			(xy 56.630062 -305.874928) (xy 56.969164 -305.874928) (xy 56.973124 -305.825874) (xy 56.984901 -305.77809)
			(xy 57.004192 -305.732814) (xy 57.030495 -305.691218) (xy 57.06313 -305.654381) (xy 57.101251 -305.623256)
			(xy 57.143872 -305.598649) (xy 57.189888 -305.581197) (xy 57.238107 -305.571353) (xy 57.287282 -305.569372)
			(xy 57.336137 -305.575304) (xy 57.383408 -305.588996) (xy 57.42787 -305.610094) (xy 57.468373 -305.63805)
			(xy 57.503866 -305.672142) (xy 57.533431 -305.711486) (xy 57.556302 -305.755063) (xy 57.571886 -305.801744)
			(xy 57.579781 -305.850321) (xy 57.580276 -305.874928) (xy 57.919124 -305.874928) (xy 57.923084 -305.825874)
			(xy 57.934861 -305.77809) (xy 57.954152 -305.732814) (xy 57.980455 -305.691218) (xy 58.01309 -305.654381)
			(xy 58.051211 -305.623256) (xy 58.093832 -305.598649) (xy 58.139848 -305.581197) (xy 58.188067 -305.571353)
			(xy 58.237242 -305.569372) (xy 58.286097 -305.575304) (xy 58.333368 -305.588996) (xy 58.37783 -305.610094)
			(xy 58.418333 -305.63805) (xy 58.453826 -305.672142) (xy 58.483391 -305.711486) (xy 58.506262 -305.755063)
			(xy 58.521846 -305.801744) (xy 58.529741 -305.850321) (xy 58.530236 -305.874928) (xy 59.819044 -305.874928)
			(xy 59.823004 -305.825874) (xy 59.834781 -305.77809) (xy 59.854072 -305.732814) (xy 59.880375 -305.691218)
			(xy 59.91301 -305.654381) (xy 59.951131 -305.623256) (xy 59.993752 -305.598649) (xy 60.039768 -305.581197)
			(xy 60.087987 -305.571353) (xy 60.137162 -305.569372) (xy 60.186017 -305.575304) (xy 60.233288 -305.588996)
			(xy 60.27775 -305.610094) (xy 60.318253 -305.63805) (xy 60.353746 -305.672142) (xy 60.383311 -305.711486)
			(xy 60.406182 -305.755063) (xy 60.421766 -305.801744) (xy 60.429661 -305.850321) (xy 60.430156 -305.874928)
			(xy 60.769004 -305.874928) (xy 60.772964 -305.825874) (xy 60.784741 -305.77809) (xy 60.804032 -305.732814)
			(xy 60.830335 -305.691218) (xy 60.86297 -305.654381) (xy 60.901091 -305.623256) (xy 60.943712 -305.598649)
			(xy 60.989728 -305.581197) (xy 61.037947 -305.571353) (xy 61.087122 -305.569372) (xy 61.135977 -305.575304)
			(xy 61.183248 -305.588996) (xy 61.22771 -305.610094) (xy 61.268213 -305.63805) (xy 61.303706 -305.672142)
			(xy 61.333271 -305.711486) (xy 61.356142 -305.755063) (xy 61.371726 -305.801744) (xy 61.379621 -305.850321)
			(xy 61.380116 -305.874928) (xy 61.718964 -305.874928) (xy 61.722924 -305.825874) (xy 61.734701 -305.77809)
			(xy 61.753992 -305.732814) (xy 61.780295 -305.691218) (xy 61.81293 -305.654381) (xy 61.851051 -305.623256)
			(xy 61.893672 -305.598649) (xy 61.939688 -305.581197) (xy 61.987907 -305.571353) (xy 62.037082 -305.569372)
			(xy 62.085937 -305.575304) (xy 62.133208 -305.588996) (xy 62.17767 -305.610094) (xy 62.218173 -305.63805)
			(xy 62.253666 -305.672142) (xy 62.283231 -305.711486) (xy 62.306102 -305.755063) (xy 62.321686 -305.801744)
			(xy 62.329581 -305.850321) (xy 62.330076 -305.874928) (xy 62.669178 -305.874928) (xy 62.673138 -305.825874)
			(xy 62.684915 -305.77809) (xy 62.704206 -305.732814) (xy 62.730509 -305.691218) (xy 62.763144 -305.654381)
			(xy 62.801265 -305.623256) (xy 62.843886 -305.598649) (xy 62.889902 -305.581197) (xy 62.938121 -305.571353)
			(xy 62.987296 -305.569372) (xy 63.036151 -305.575304) (xy 63.083422 -305.588996) (xy 63.127884 -305.610094)
			(xy 63.168387 -305.63805) (xy 63.20388 -305.672142) (xy 63.233445 -305.711486) (xy 63.256316 -305.755063)
			(xy 63.2719 -305.801744) (xy 63.279795 -305.850321) (xy 63.28029 -305.874928) (xy 63.619138 -305.874928)
			(xy 63.623098 -305.825874) (xy 63.634875 -305.77809) (xy 63.654166 -305.732814) (xy 63.680469 -305.691218)
			(xy 63.713104 -305.654381) (xy 63.751225 -305.623256) (xy 63.793846 -305.598649) (xy 63.839862 -305.581197)
			(xy 63.888081 -305.571353) (xy 63.937256 -305.569372) (xy 63.986111 -305.575304) (xy 64.033382 -305.588996)
			(xy 64.077844 -305.610094) (xy 64.118347 -305.63805) (xy 64.15384 -305.672142) (xy 64.183405 -305.711486)
			(xy 64.206276 -305.755063) (xy 64.22186 -305.801744) (xy 64.229755 -305.850321) (xy 64.23025 -305.874928)
			(xy 64.569098 -305.874928) (xy 64.573058 -305.825874) (xy 64.584835 -305.77809) (xy 64.604126 -305.732814)
			(xy 64.630429 -305.691218) (xy 64.663064 -305.654381) (xy 64.701185 -305.623256) (xy 64.743806 -305.598649)
			(xy 64.789822 -305.581197) (xy 64.838041 -305.571353) (xy 64.887216 -305.569372) (xy 64.936071 -305.575304)
			(xy 64.983342 -305.588996) (xy 65.027804 -305.610094) (xy 65.068307 -305.63805) (xy 65.1038 -305.672142)
			(xy 65.133365 -305.711486) (xy 65.156236 -305.755063) (xy 65.17182 -305.801744) (xy 65.179715 -305.850321)
			(xy 65.18021 -305.874928) (xy 65.519058 -305.874928) (xy 65.523018 -305.825874) (xy 65.534795 -305.77809)
			(xy 65.554086 -305.732814) (xy 65.580389 -305.691218) (xy 65.613024 -305.654381) (xy 65.651145 -305.623256)
			(xy 65.693766 -305.598649) (xy 65.739782 -305.581197) (xy 65.788001 -305.571353) (xy 65.837176 -305.569372)
			(xy 65.886031 -305.575304) (xy 65.933302 -305.588996) (xy 65.977764 -305.610094) (xy 66.018267 -305.63805)
			(xy 66.05376 -305.672142) (xy 66.083325 -305.711486) (xy 66.106196 -305.755063) (xy 66.12178 -305.801744)
			(xy 66.129675 -305.850321) (xy 66.13017 -305.874928) (xy 66.469018 -305.874928) (xy 66.472978 -305.825874)
			(xy 66.484755 -305.77809) (xy 66.504046 -305.732814) (xy 66.530349 -305.691218) (xy 66.562984 -305.654381)
			(xy 66.601105 -305.623256) (xy 66.643726 -305.598649) (xy 66.689742 -305.581197) (xy 66.737961 -305.571353)
			(xy 66.787136 -305.569372) (xy 66.835991 -305.575304) (xy 66.883262 -305.588996) (xy 66.927724 -305.610094)
			(xy 66.968227 -305.63805) (xy 67.00372 -305.672142) (xy 67.033285 -305.711486) (xy 67.056156 -305.755063)
			(xy 67.07174 -305.801744) (xy 67.079635 -305.850321) (xy 67.08013 -305.874928) (xy 67.418978 -305.874928)
			(xy 67.422938 -305.825874) (xy 67.434715 -305.77809) (xy 67.454006 -305.732814) (xy 67.480309 -305.691218)
			(xy 67.512944 -305.654381) (xy 67.551065 -305.623256) (xy 67.593686 -305.598649) (xy 67.639702 -305.581197)
			(xy 67.687921 -305.571353) (xy 67.737096 -305.569372) (xy 67.785951 -305.575304) (xy 67.833222 -305.588996)
			(xy 67.877684 -305.610094) (xy 67.918187 -305.63805) (xy 67.95368 -305.672142) (xy 67.983245 -305.711486)
			(xy 68.006116 -305.755063) (xy 68.0217 -305.801744) (xy 68.029595 -305.850321) (xy 68.03009 -305.874928)
			(xy 68.368938 -305.874928) (xy 68.372898 -305.825874) (xy 68.384675 -305.77809) (xy 68.403966 -305.732814)
			(xy 68.430269 -305.691218) (xy 68.462904 -305.654381) (xy 68.501025 -305.623256) (xy 68.543646 -305.598649)
			(xy 68.589662 -305.581197) (xy 68.637881 -305.571353) (xy 68.687056 -305.569372) (xy 68.735911 -305.575304)
			(xy 68.783182 -305.588996) (xy 68.827644 -305.610094) (xy 68.868147 -305.63805) (xy 68.90364 -305.672142)
			(xy 68.933205 -305.711486) (xy 68.956076 -305.755063) (xy 68.97166 -305.801744) (xy 68.979555 -305.850321)
			(xy 68.98005 -305.874928) (xy 69.319152 -305.874928) (xy 69.323112 -305.825874) (xy 69.334889 -305.77809)
			(xy 69.35418 -305.732814) (xy 69.380483 -305.691218) (xy 69.413118 -305.654381) (xy 69.451239 -305.623256)
			(xy 69.49386 -305.598649) (xy 69.539876 -305.581197) (xy 69.588095 -305.571353) (xy 69.63727 -305.569372)
			(xy 69.686125 -305.575304) (xy 69.733396 -305.588996) (xy 69.777858 -305.610094) (xy 69.818361 -305.63805)
			(xy 69.853854 -305.672142) (xy 69.883419 -305.711486) (xy 69.90629 -305.755063) (xy 69.921874 -305.801744)
			(xy 69.929769 -305.850321) (xy 69.930264 -305.874928) (xy 70.269112 -305.874928) (xy 70.273072 -305.825874)
			(xy 70.284849 -305.77809) (xy 70.30414 -305.732814) (xy 70.330443 -305.691218) (xy 70.363078 -305.654381)
			(xy 70.401199 -305.623256) (xy 70.44382 -305.598649) (xy 70.489836 -305.581197) (xy 70.538055 -305.571353)
			(xy 70.58723 -305.569372) (xy 70.636085 -305.575304) (xy 70.683356 -305.588996) (xy 70.727818 -305.610094)
			(xy 70.768321 -305.63805) (xy 70.803814 -305.672142) (xy 70.833379 -305.711486) (xy 70.85625 -305.755063)
			(xy 70.871834 -305.801744) (xy 70.879729 -305.850321) (xy 70.880224 -305.874928) (xy 71.219072 -305.874928)
			(xy 71.223032 -305.825874) (xy 71.234809 -305.77809) (xy 71.2541 -305.732814) (xy 71.280403 -305.691218)
			(xy 71.313038 -305.654381) (xy 71.351159 -305.623256) (xy 71.39378 -305.598649) (xy 71.439796 -305.581197)
			(xy 71.488015 -305.571353) (xy 71.53719 -305.569372) (xy 71.586045 -305.575304) (xy 71.633316 -305.588996)
			(xy 71.677778 -305.610094) (xy 71.718281 -305.63805) (xy 71.753774 -305.672142) (xy 71.783339 -305.711486)
			(xy 71.80621 -305.755063) (xy 71.821794 -305.801744) (xy 71.829689 -305.850321) (xy 71.830184 -305.874928)
			(xy 72.169032 -305.874928) (xy 72.172992 -305.825874) (xy 72.184769 -305.77809) (xy 72.20406 -305.732814)
			(xy 72.230363 -305.691218) (xy 72.262998 -305.654381) (xy 72.301119 -305.623256) (xy 72.34374 -305.598649)
			(xy 72.389756 -305.581197) (xy 72.437975 -305.571353) (xy 72.48715 -305.569372) (xy 72.536005 -305.575304)
			(xy 72.583276 -305.588996) (xy 72.627738 -305.610094) (xy 72.668241 -305.63805) (xy 72.703734 -305.672142)
			(xy 72.733299 -305.711486) (xy 72.75617 -305.755063) (xy 72.771754 -305.801744) (xy 72.779649 -305.850321)
			(xy 72.780144 -305.874928) (xy 72.779649 -305.899535) (xy 72.771754 -305.948112) (xy 72.75617 -305.994793)
			(xy 72.733299 -306.03837) (xy 72.703734 -306.077714) (xy 72.668241 -306.111806) (xy 72.627738 -306.139762)
			(xy 72.583276 -306.16086) (xy 72.536005 -306.174552) (xy 72.48715 -306.180484) (xy 72.437975 -306.178503)
			(xy 72.389756 -306.168659) (xy 72.34374 -306.151207) (xy 72.301119 -306.1266) (xy 72.262998 -306.095475)
			(xy 72.230363 -306.058638) (xy 72.20406 -306.017042) (xy 72.184769 -305.971766) (xy 72.172992 -305.923982)
			(xy 72.169032 -305.874928) (xy 71.830184 -305.874928) (xy 71.829689 -305.899535) (xy 71.821794 -305.948112)
			(xy 71.80621 -305.994793) (xy 71.783339 -306.03837) (xy 71.753774 -306.077714) (xy 71.718281 -306.111806)
			(xy 71.677778 -306.139762) (xy 71.633316 -306.16086) (xy 71.586045 -306.174552) (xy 71.53719 -306.180484)
			(xy 71.488015 -306.178503) (xy 71.439796 -306.168659) (xy 71.39378 -306.151207) (xy 71.351159 -306.1266)
			(xy 71.313038 -306.095475) (xy 71.280403 -306.058638) (xy 71.2541 -306.017042) (xy 71.234809 -305.971766)
			(xy 71.223032 -305.923982) (xy 71.219072 -305.874928) (xy 70.880224 -305.874928) (xy 70.879729 -305.899535)
			(xy 70.871834 -305.948112) (xy 70.85625 -305.994793) (xy 70.833379 -306.03837) (xy 70.803814 -306.077714)
			(xy 70.768321 -306.111806) (xy 70.727818 -306.139762) (xy 70.683356 -306.16086) (xy 70.636085 -306.174552)
			(xy 70.58723 -306.180484) (xy 70.538055 -306.178503) (xy 70.489836 -306.168659) (xy 70.44382 -306.151207)
			(xy 70.401199 -306.1266) (xy 70.363078 -306.095475) (xy 70.330443 -306.058638) (xy 70.30414 -306.017042)
			(xy 70.284849 -305.971766) (xy 70.273072 -305.923982) (xy 70.269112 -305.874928) (xy 69.930264 -305.874928)
			(xy 69.929769 -305.899535) (xy 69.921874 -305.948112) (xy 69.90629 -305.994793) (xy 69.883419 -306.03837)
			(xy 69.853854 -306.077714) (xy 69.818361 -306.111806) (xy 69.777858 -306.139762) (xy 69.733396 -306.16086)
			(xy 69.686125 -306.174552) (xy 69.63727 -306.180484) (xy 69.588095 -306.178503) (xy 69.539876 -306.168659)
			(xy 69.49386 -306.151207) (xy 69.451239 -306.1266) (xy 69.413118 -306.095475) (xy 69.380483 -306.058638)
			(xy 69.35418 -306.017042) (xy 69.334889 -305.971766) (xy 69.323112 -305.923982) (xy 69.319152 -305.874928)
			(xy 68.98005 -305.874928) (xy 68.979555 -305.899535) (xy 68.97166 -305.948112) (xy 68.956076 -305.994793)
			(xy 68.933205 -306.03837) (xy 68.90364 -306.077714) (xy 68.868147 -306.111806) (xy 68.827644 -306.139762)
			(xy 68.783182 -306.16086) (xy 68.735911 -306.174552) (xy 68.687056 -306.180484) (xy 68.637881 -306.178503)
			(xy 68.589662 -306.168659) (xy 68.543646 -306.151207) (xy 68.501025 -306.1266) (xy 68.462904 -306.095475)
			(xy 68.430269 -306.058638) (xy 68.403966 -306.017042) (xy 68.384675 -305.971766) (xy 68.372898 -305.923982)
			(xy 68.368938 -305.874928) (xy 68.03009 -305.874928) (xy 68.029595 -305.899535) (xy 68.0217 -305.948112)
			(xy 68.006116 -305.994793) (xy 67.983245 -306.03837) (xy 67.95368 -306.077714) (xy 67.918187 -306.111806)
			(xy 67.877684 -306.139762) (xy 67.833222 -306.16086) (xy 67.785951 -306.174552) (xy 67.737096 -306.180484)
			(xy 67.687921 -306.178503) (xy 67.639702 -306.168659) (xy 67.593686 -306.151207) (xy 67.551065 -306.1266)
			(xy 67.512944 -306.095475) (xy 67.480309 -306.058638) (xy 67.454006 -306.017042) (xy 67.434715 -305.971766)
			(xy 67.422938 -305.923982) (xy 67.418978 -305.874928) (xy 67.08013 -305.874928) (xy 67.079635 -305.899535)
			(xy 67.07174 -305.948112) (xy 67.056156 -305.994793) (xy 67.033285 -306.03837) (xy 67.00372 -306.077714)
			(xy 66.968227 -306.111806) (xy 66.927724 -306.139762) (xy 66.883262 -306.16086) (xy 66.835991 -306.174552)
			(xy 66.787136 -306.180484) (xy 66.737961 -306.178503) (xy 66.689742 -306.168659) (xy 66.643726 -306.151207)
			(xy 66.601105 -306.1266) (xy 66.562984 -306.095475) (xy 66.530349 -306.058638) (xy 66.504046 -306.017042)
			(xy 66.484755 -305.971766) (xy 66.472978 -305.923982) (xy 66.469018 -305.874928) (xy 66.13017 -305.874928)
			(xy 66.129675 -305.899535) (xy 66.12178 -305.948112) (xy 66.106196 -305.994793) (xy 66.083325 -306.03837)
			(xy 66.05376 -306.077714) (xy 66.018267 -306.111806) (xy 65.977764 -306.139762) (xy 65.933302 -306.16086)
			(xy 65.886031 -306.174552) (xy 65.837176 -306.180484) (xy 65.788001 -306.178503) (xy 65.739782 -306.168659)
			(xy 65.693766 -306.151207) (xy 65.651145 -306.1266) (xy 65.613024 -306.095475) (xy 65.580389 -306.058638)
			(xy 65.554086 -306.017042) (xy 65.534795 -305.971766) (xy 65.523018 -305.923982) (xy 65.519058 -305.874928)
			(xy 65.18021 -305.874928) (xy 65.179715 -305.899535) (xy 65.17182 -305.948112) (xy 65.156236 -305.994793)
			(xy 65.133365 -306.03837) (xy 65.1038 -306.077714) (xy 65.068307 -306.111806) (xy 65.027804 -306.139762)
			(xy 64.983342 -306.16086) (xy 64.936071 -306.174552) (xy 64.887216 -306.180484) (xy 64.838041 -306.178503)
			(xy 64.789822 -306.168659) (xy 64.743806 -306.151207) (xy 64.701185 -306.1266) (xy 64.663064 -306.095475)
			(xy 64.630429 -306.058638) (xy 64.604126 -306.017042) (xy 64.584835 -305.971766) (xy 64.573058 -305.923982)
			(xy 64.569098 -305.874928) (xy 64.23025 -305.874928) (xy 64.229755 -305.899535) (xy 64.22186 -305.948112)
			(xy 64.206276 -305.994793) (xy 64.183405 -306.03837) (xy 64.15384 -306.077714) (xy 64.118347 -306.111806)
			(xy 64.077844 -306.139762) (xy 64.033382 -306.16086) (xy 63.986111 -306.174552) (xy 63.937256 -306.180484)
			(xy 63.888081 -306.178503) (xy 63.839862 -306.168659) (xy 63.793846 -306.151207) (xy 63.751225 -306.1266)
			(xy 63.713104 -306.095475) (xy 63.680469 -306.058638) (xy 63.654166 -306.017042) (xy 63.634875 -305.971766)
			(xy 63.623098 -305.923982) (xy 63.619138 -305.874928) (xy 63.28029 -305.874928) (xy 63.279795 -305.899535)
			(xy 63.2719 -305.948112) (xy 63.256316 -305.994793) (xy 63.233445 -306.03837) (xy 63.20388 -306.077714)
			(xy 63.168387 -306.111806) (xy 63.127884 -306.139762) (xy 63.083422 -306.16086) (xy 63.036151 -306.174552)
			(xy 62.987296 -306.180484) (xy 62.938121 -306.178503) (xy 62.889902 -306.168659) (xy 62.843886 -306.151207)
			(xy 62.801265 -306.1266) (xy 62.763144 -306.095475) (xy 62.730509 -306.058638) (xy 62.704206 -306.017042)
			(xy 62.684915 -305.971766) (xy 62.673138 -305.923982) (xy 62.669178 -305.874928) (xy 62.330076 -305.874928)
			(xy 62.329581 -305.899535) (xy 62.321686 -305.948112) (xy 62.306102 -305.994793) (xy 62.283231 -306.03837)
			(xy 62.253666 -306.077714) (xy 62.218173 -306.111806) (xy 62.17767 -306.139762) (xy 62.133208 -306.16086)
			(xy 62.085937 -306.174552) (xy 62.037082 -306.180484) (xy 61.987907 -306.178503) (xy 61.939688 -306.168659)
			(xy 61.893672 -306.151207) (xy 61.851051 -306.1266) (xy 61.81293 -306.095475) (xy 61.780295 -306.058638)
			(xy 61.753992 -306.017042) (xy 61.734701 -305.971766) (xy 61.722924 -305.923982) (xy 61.718964 -305.874928)
			(xy 61.380116 -305.874928) (xy 61.379621 -305.899535) (xy 61.371726 -305.948112) (xy 61.356142 -305.994793)
			(xy 61.333271 -306.03837) (xy 61.303706 -306.077714) (xy 61.268213 -306.111806) (xy 61.22771 -306.139762)
			(xy 61.183248 -306.16086) (xy 61.135977 -306.174552) (xy 61.087122 -306.180484) (xy 61.037947 -306.178503)
			(xy 60.989728 -306.168659) (xy 60.943712 -306.151207) (xy 60.901091 -306.1266) (xy 60.86297 -306.095475)
			(xy 60.830335 -306.058638) (xy 60.804032 -306.017042) (xy 60.784741 -305.971766) (xy 60.772964 -305.923982)
			(xy 60.769004 -305.874928) (xy 60.430156 -305.874928) (xy 60.429661 -305.899535) (xy 60.421766 -305.948112)
			(xy 60.406182 -305.994793) (xy 60.383311 -306.03837) (xy 60.353746 -306.077714) (xy 60.318253 -306.111806)
			(xy 60.27775 -306.139762) (xy 60.233288 -306.16086) (xy 60.186017 -306.174552) (xy 60.137162 -306.180484)
			(xy 60.087987 -306.178503) (xy 60.039768 -306.168659) (xy 59.993752 -306.151207) (xy 59.951131 -306.1266)
			(xy 59.91301 -306.095475) (xy 59.880375 -306.058638) (xy 59.854072 -306.017042) (xy 59.834781 -305.971766)
			(xy 59.823004 -305.923982) (xy 59.819044 -305.874928) (xy 58.530236 -305.874928) (xy 58.529741 -305.899535)
			(xy 58.521846 -305.948112) (xy 58.506262 -305.994793) (xy 58.483391 -306.03837) (xy 58.453826 -306.077714)
			(xy 58.418333 -306.111806) (xy 58.37783 -306.139762) (xy 58.333368 -306.16086) (xy 58.286097 -306.174552)
			(xy 58.237242 -306.180484) (xy 58.188067 -306.178503) (xy 58.139848 -306.168659) (xy 58.093832 -306.151207)
			(xy 58.051211 -306.1266) (xy 58.01309 -306.095475) (xy 57.980455 -306.058638) (xy 57.954152 -306.017042)
			(xy 57.934861 -305.971766) (xy 57.923084 -305.923982) (xy 57.919124 -305.874928) (xy 57.580276 -305.874928)
			(xy 57.579781 -305.899535) (xy 57.571886 -305.948112) (xy 57.556302 -305.994793) (xy 57.533431 -306.03837)
			(xy 57.503866 -306.077714) (xy 57.468373 -306.111806) (xy 57.42787 -306.139762) (xy 57.383408 -306.16086)
			(xy 57.336137 -306.174552) (xy 57.287282 -306.180484) (xy 57.238107 -306.178503) (xy 57.189888 -306.168659)
			(xy 57.143872 -306.151207) (xy 57.101251 -306.1266) (xy 57.06313 -306.095475) (xy 57.030495 -306.058638)
			(xy 57.004192 -306.017042) (xy 56.984901 -305.971766) (xy 56.973124 -305.923982) (xy 56.969164 -305.874928)
			(xy 56.630062 -305.874928) (xy 56.629567 -305.899535) (xy 56.621672 -305.948112) (xy 56.606088 -305.994793)
			(xy 56.583217 -306.03837) (xy 56.553652 -306.077714) (xy 56.518159 -306.111806) (xy 56.477656 -306.139762)
			(xy 56.433194 -306.16086) (xy 56.385923 -306.174552) (xy 56.337068 -306.180484) (xy 56.287893 -306.178503)
			(xy 56.239674 -306.168659) (xy 56.193658 -306.151207) (xy 56.151037 -306.1266) (xy 56.112916 -306.095475)
			(xy 56.080281 -306.058638) (xy 56.053978 -306.017042) (xy 56.034687 -305.971766) (xy 56.02291 -305.923982)
			(xy 56.01895 -305.874928) (xy 55.680102 -305.874928) (xy 55.679607 -305.899535) (xy 55.671712 -305.948112)
			(xy 55.656128 -305.994793) (xy 55.633257 -306.03837) (xy 55.603692 -306.077714) (xy 55.568199 -306.111806)
			(xy 55.527696 -306.139762) (xy 55.483234 -306.16086) (xy 55.435963 -306.174552) (xy 55.387108 -306.180484)
			(xy 55.337933 -306.178503) (xy 55.289714 -306.168659) (xy 55.243698 -306.151207) (xy 55.201077 -306.1266)
			(xy 55.162956 -306.095475) (xy 55.130321 -306.058638) (xy 55.104018 -306.017042) (xy 55.084727 -305.971766)
			(xy 55.07295 -305.923982) (xy 55.06899 -305.874928) (xy 54.730142 -305.874928) (xy 54.729647 -305.899535)
			(xy 54.721752 -305.948112) (xy 54.706168 -305.994793) (xy 54.683297 -306.03837) (xy 54.653732 -306.077714)
			(xy 54.618239 -306.111806) (xy 54.577736 -306.139762) (xy 54.533274 -306.16086) (xy 54.486003 -306.174552)
			(xy 54.437148 -306.180484) (xy 54.387973 -306.178503) (xy 54.339754 -306.168659) (xy 54.293738 -306.151207)
			(xy 54.251117 -306.1266) (xy 54.212996 -306.095475) (xy 54.180361 -306.058638) (xy 54.154058 -306.017042)
			(xy 54.134767 -305.971766) (xy 54.12299 -305.923982) (xy 54.11903 -305.874928) (xy 53.780182 -305.874928)
			(xy 53.779687 -305.899535) (xy 53.771792 -305.948112) (xy 53.756208 -305.994793) (xy 53.733337 -306.03837)
			(xy 53.703772 -306.077714) (xy 53.668279 -306.111806) (xy 53.627776 -306.139762) (xy 53.583314 -306.16086)
			(xy 53.536043 -306.174552) (xy 53.487188 -306.180484) (xy 53.438013 -306.178503) (xy 53.389794 -306.168659)
			(xy 53.343778 -306.151207) (xy 53.301157 -306.1266) (xy 53.263036 -306.095475) (xy 53.230401 -306.058638)
			(xy 53.204098 -306.017042) (xy 53.184807 -305.971766) (xy 53.17303 -305.923982) (xy 53.16907 -305.874928)
			(xy 52.830222 -305.874928) (xy 52.829727 -305.899535) (xy 52.821832 -305.948112) (xy 52.806248 -305.994793)
			(xy 52.783377 -306.03837) (xy 52.753812 -306.077714) (xy 52.718319 -306.111806) (xy 52.677816 -306.139762)
			(xy 52.633354 -306.16086) (xy 52.586083 -306.174552) (xy 52.537228 -306.180484) (xy 52.488053 -306.178503)
			(xy 52.439834 -306.168659) (xy 52.393818 -306.151207) (xy 52.351197 -306.1266) (xy 52.313076 -306.095475)
			(xy 52.280441 -306.058638) (xy 52.254138 -306.017042) (xy 52.234847 -305.971766) (xy 52.22307 -305.923982)
			(xy 52.21911 -305.874928) (xy 51.880262 -305.874928) (xy 51.879767 -305.899535) (xy 51.871872 -305.948112)
			(xy 51.856288 -305.994793) (xy 51.833417 -306.03837) (xy 51.803852 -306.077714) (xy 51.768359 -306.111806)
			(xy 51.727856 -306.139762) (xy 51.683394 -306.16086) (xy 51.636123 -306.174552) (xy 51.587268 -306.180484)
			(xy 51.538093 -306.178503) (xy 51.489874 -306.168659) (xy 51.443858 -306.151207) (xy 51.401237 -306.1266)
			(xy 51.363116 -306.095475) (xy 51.330481 -306.058638) (xy 51.304178 -306.017042) (xy 51.284887 -305.971766)
			(xy 51.27311 -305.923982) (xy 51.26915 -305.874928) (xy 50.930302 -305.874928) (xy 50.929807 -305.899535)
			(xy 50.921912 -305.948112) (xy 50.906328 -305.994793) (xy 50.883457 -306.03837) (xy 50.853892 -306.077714)
			(xy 50.818399 -306.111806) (xy 50.777896 -306.139762) (xy 50.733434 -306.16086) (xy 50.686163 -306.174552)
			(xy 50.637308 -306.180484) (xy 50.588133 -306.178503) (xy 50.539914 -306.168659) (xy 50.493898 -306.151207)
			(xy 50.451277 -306.1266) (xy 50.413156 -306.095475) (xy 50.380521 -306.058638) (xy 50.354218 -306.017042)
			(xy 50.334927 -305.971766) (xy 50.32315 -305.923982) (xy 50.31919 -305.874928) (xy 49.980088 -305.874928)
			(xy 49.979593 -305.899535) (xy 49.971698 -305.948112) (xy 49.956114 -305.994793) (xy 49.933243 -306.03837)
			(xy 49.903678 -306.077714) (xy 49.868185 -306.111806) (xy 49.827682 -306.139762) (xy 49.78322 -306.16086)
			(xy 49.735949 -306.174552) (xy 49.687094 -306.180484) (xy 49.637919 -306.178503) (xy 49.5897 -306.168659)
			(xy 49.543684 -306.151207) (xy 49.501063 -306.1266) (xy 49.462942 -306.095475) (xy 49.430307 -306.058638)
			(xy 49.404004 -306.017042) (xy 49.384713 -305.971766) (xy 49.372936 -305.923982) (xy 49.368976 -305.874928)
			(xy 49.030128 -305.874928) (xy 49.029633 -305.899535) (xy 49.021738 -305.948112) (xy 49.006154 -305.994793)
			(xy 48.983283 -306.03837) (xy 48.953718 -306.077714) (xy 48.918225 -306.111806) (xy 48.877722 -306.139762)
			(xy 48.83326 -306.16086) (xy 48.785989 -306.174552) (xy 48.737134 -306.180484) (xy 48.687959 -306.178503)
			(xy 48.63974 -306.168659) (xy 48.593724 -306.151207) (xy 48.551103 -306.1266) (xy 48.512982 -306.095475)
			(xy 48.480347 -306.058638) (xy 48.454044 -306.017042) (xy 48.434753 -305.971766) (xy 48.422976 -305.923982)
			(xy 48.419016 -305.874928) (xy 48.080198 -305.874928) (xy 48.080646 -305.8832) (xy 48.075275 -305.932557)
			(xy 48.06199 -305.980395) (xy 48.041139 -306.025454) (xy 48.013274 -306.066545) (xy 47.979127 -306.102586)
			(xy 47.939599 -306.132628) (xy 47.895731 -306.15588) (xy 47.84868 -306.171727) (xy 47.799684 -306.179753)
			(xy 47.77486 -306.180236) (xy 47.760677 -306.180064) (xy 47.732437 -306.177389) (xy 47.718472 -306.174902)
			(xy 47.704512 -306.172687) (xy 47.676374 -306.175273) (xy 47.650021 -306.18547) (xy 47.627472 -306.202499)
			(xy 47.610452 -306.225055) (xy 47.600264 -306.251412) (xy 47.597689 -306.279551) (xy 47.599854 -306.29352)
			(xy 47.602329 -306.307486) (xy 47.605002 -306.335726) (xy 47.605188 -306.349908) (xy 73.593972 -306.349908)
			(xy 73.597932 -306.300854) (xy 73.609709 -306.25307) (xy 73.629 -306.207794) (xy 73.655303 -306.166198)
			(xy 73.687938 -306.129361) (xy 73.726059 -306.098236) (xy 73.76868 -306.073629) (xy 73.814696 -306.056177)
			(xy 73.862915 -306.046333) (xy 73.91209 -306.044352) (xy 73.960945 -306.050284) (xy 74.008216 -306.063976)
			(xy 74.052678 -306.085074) (xy 74.093181 -306.11303) (xy 74.128674 -306.147122) (xy 74.158239 -306.186466)
			(xy 74.18111 -306.230043) (xy 74.196694 -306.276724) (xy 74.204589 -306.325301) (xy 74.205084 -306.349908)
			(xy 74.204589 -306.374515) (xy 74.20441 -306.375616) (xy 74.523342 -306.375616) (xy 74.523342 -306.3242)
			(xy 74.531385 -306.273418) (xy 74.547273 -306.224519) (xy 74.570616 -306.178707) (xy 74.600837 -306.137111)
			(xy 74.637193 -306.100755) (xy 74.678789 -306.070534) (xy 74.724601 -306.047191) (xy 74.7735 -306.031303)
			(xy 74.824282 -306.02326) (xy 74.875698 -306.02326) (xy 74.92648 -306.031303) (xy 74.975379 -306.047191)
			(xy 75.021191 -306.070534) (xy 75.062787 -306.100755) (xy 75.099143 -306.137111) (xy 75.129364 -306.178707)
			(xy 75.152707 -306.224519) (xy 75.168595 -306.273418) (xy 75.176638 -306.3242) (xy 75.177142 -306.349908)
			(xy 75.176638 -306.375616) (xy 75.473302 -306.375616) (xy 75.473302 -306.3242) (xy 75.481345 -306.273418)
			(xy 75.497233 -306.224519) (xy 75.520576 -306.178707) (xy 75.550797 -306.137111) (xy 75.587153 -306.100755)
			(xy 75.628749 -306.070534) (xy 75.674561 -306.047191) (xy 75.72346 -306.031303) (xy 75.774242 -306.02326)
			(xy 75.825658 -306.02326) (xy 75.87644 -306.031303) (xy 75.925339 -306.047191) (xy 75.971151 -306.070534)
			(xy 76.012747 -306.100755) (xy 76.049103 -306.137111) (xy 76.079324 -306.178707) (xy 76.102667 -306.224519)
			(xy 76.118555 -306.273418) (xy 76.126598 -306.3242) (xy 76.127102 -306.349908) (xy 76.444106 -306.349908)
			(xy 76.448066 -306.300854) (xy 76.459843 -306.25307) (xy 76.479134 -306.207794) (xy 76.505437 -306.166198)
			(xy 76.538072 -306.129361) (xy 76.576193 -306.098236) (xy 76.618814 -306.073629) (xy 76.66483 -306.056177)
			(xy 76.713049 -306.046333) (xy 76.762224 -306.044352) (xy 76.811079 -306.050284) (xy 76.85835 -306.063976)
			(xy 76.902812 -306.085074) (xy 76.943315 -306.11303) (xy 76.978808 -306.147122) (xy 77.008373 -306.186466)
			(xy 77.031244 -306.230043) (xy 77.046828 -306.276724) (xy 77.054723 -306.325301) (xy 77.055218 -306.349908)
			(xy 77.394066 -306.349908) (xy 77.398026 -306.300854) (xy 77.409803 -306.25307) (xy 77.429094 -306.207794)
			(xy 77.455397 -306.166198) (xy 77.488032 -306.129361) (xy 77.526153 -306.098236) (xy 77.568774 -306.073629)
			(xy 77.61479 -306.056177) (xy 77.663009 -306.046333) (xy 77.712184 -306.044352) (xy 77.761039 -306.050284)
			(xy 77.80831 -306.063976) (xy 77.852772 -306.085074) (xy 77.893275 -306.11303) (xy 77.928768 -306.147122)
			(xy 77.958333 -306.186466) (xy 77.981204 -306.230043) (xy 77.996788 -306.276724) (xy 78.004683 -306.325301)
			(xy 78.005178 -306.349908) (xy 78.004683 -306.374515) (xy 77.996788 -306.423092) (xy 77.981204 -306.469773)
			(xy 77.958333 -306.51335) (xy 77.928768 -306.552694) (xy 77.893275 -306.586786) (xy 77.852772 -306.614742)
			(xy 77.80831 -306.63584) (xy 77.761039 -306.649532) (xy 77.712184 -306.655464) (xy 77.663009 -306.653483)
			(xy 77.61479 -306.643639) (xy 77.568774 -306.626187) (xy 77.526153 -306.60158) (xy 77.488032 -306.570455)
			(xy 77.455397 -306.533618) (xy 77.429094 -306.492022) (xy 77.409803 -306.446746) (xy 77.398026 -306.398962)
			(xy 77.394066 -306.349908) (xy 77.055218 -306.349908) (xy 77.054723 -306.374515) (xy 77.046828 -306.423092)
			(xy 77.031244 -306.469773) (xy 77.008373 -306.51335) (xy 76.978808 -306.552694) (xy 76.943315 -306.586786)
			(xy 76.902812 -306.614742) (xy 76.85835 -306.63584) (xy 76.811079 -306.649532) (xy 76.762224 -306.655464)
			(xy 76.713049 -306.653483) (xy 76.66483 -306.643639) (xy 76.618814 -306.626187) (xy 76.576193 -306.60158)
			(xy 76.538072 -306.570455) (xy 76.505437 -306.533618) (xy 76.479134 -306.492022) (xy 76.459843 -306.446746)
			(xy 76.448066 -306.398962) (xy 76.444106 -306.349908) (xy 76.127102 -306.349908) (xy 76.126598 -306.375616)
			(xy 76.118555 -306.426398) (xy 76.102667 -306.475297) (xy 76.079324 -306.521109) (xy 76.049103 -306.562705)
			(xy 76.012747 -306.599061) (xy 75.971151 -306.629282) (xy 75.925339 -306.652625) (xy 75.87644 -306.668513)
			(xy 75.825658 -306.676556) (xy 75.774242 -306.676556) (xy 75.72346 -306.668513) (xy 75.674561 -306.652625)
			(xy 75.628749 -306.629282) (xy 75.587153 -306.599061) (xy 75.550797 -306.562705) (xy 75.520576 -306.521109)
			(xy 75.497233 -306.475297) (xy 75.481345 -306.426398) (xy 75.473302 -306.375616) (xy 75.176638 -306.375616)
			(xy 75.168595 -306.426398) (xy 75.152707 -306.475297) (xy 75.129364 -306.521109) (xy 75.099143 -306.562705)
			(xy 75.062787 -306.599061) (xy 75.021191 -306.629282) (xy 74.975379 -306.652625) (xy 74.92648 -306.668513)
			(xy 74.875698 -306.676556) (xy 74.824282 -306.676556) (xy 74.7735 -306.668513) (xy 74.724601 -306.652625)
			(xy 74.678789 -306.629282) (xy 74.637193 -306.599061) (xy 74.600837 -306.562705) (xy 74.570616 -306.521109)
			(xy 74.547273 -306.475297) (xy 74.531385 -306.426398) (xy 74.523342 -306.375616) (xy 74.20441 -306.375616)
			(xy 74.196694 -306.423092) (xy 74.18111 -306.469773) (xy 74.158239 -306.51335) (xy 74.128674 -306.552694)
			(xy 74.093181 -306.586786) (xy 74.052678 -306.614742) (xy 74.008216 -306.63584) (xy 73.960945 -306.649532)
			(xy 73.91209 -306.655464) (xy 73.862915 -306.653483) (xy 73.814696 -306.643639) (xy 73.76868 -306.626187)
			(xy 73.726059 -306.60158) (xy 73.687938 -306.570455) (xy 73.655303 -306.533618) (xy 73.629 -306.492022)
			(xy 73.609709 -306.446746) (xy 73.597932 -306.398962) (xy 73.593972 -306.349908) (xy 47.605188 -306.349908)
			(xy 47.604714 -306.374728) (xy 47.596682 -306.423713) (xy 47.580831 -306.470754) (xy 47.557578 -306.51461)
			(xy 47.527537 -306.554128) (xy 47.491499 -306.588264) (xy 47.450413 -306.616121) (xy 47.405361 -306.636964)
			(xy 47.357531 -306.650244) (xy 47.308183 -306.655611) (xy 47.258616 -306.652924) (xy 47.210137 -306.642253)
			(xy 47.164023 -306.62388) (xy 47.121489 -306.598289) (xy 47.083655 -306.566154) (xy 47.051518 -306.528321)
			(xy 47.025925 -306.485788) (xy 47.00755 -306.439674) (xy 46.996878 -306.391196) (xy 46.994189 -306.341629)
			(xy 46.655061 -306.341629) (xy 46.655228 -306.349908) (xy 46.654733 -306.374515) (xy 46.646838 -306.423092)
			(xy 46.631254 -306.469773) (xy 46.608383 -306.51335) (xy 46.578818 -306.552694) (xy 46.543325 -306.586786)
			(xy 46.502822 -306.614742) (xy 46.45836 -306.63584) (xy 46.411089 -306.649532) (xy 46.362234 -306.655464)
			(xy 46.313059 -306.653483) (xy 46.26484 -306.643639) (xy 46.218824 -306.626187) (xy 46.176203 -306.60158)
			(xy 46.138082 -306.570455) (xy 46.105447 -306.533618) (xy 46.079144 -306.492022) (xy 46.059853 -306.446746)
			(xy 46.048076 -306.398962) (xy 46.044116 -306.349908) (xy 45.705268 -306.349908) (xy 45.704773 -306.374515)
			(xy 45.696878 -306.423092) (xy 45.681294 -306.469773) (xy 45.658423 -306.51335) (xy 45.628858 -306.552694)
			(xy 45.593365 -306.586786) (xy 45.552862 -306.614742) (xy 45.5084 -306.63584) (xy 45.461129 -306.649532)
			(xy 45.412274 -306.655464) (xy 45.363099 -306.653483) (xy 45.31488 -306.643639) (xy 45.268864 -306.626187)
			(xy 45.226243 -306.60158) (xy 45.188122 -306.570455) (xy 45.155487 -306.533618) (xy 45.129184 -306.492022)
			(xy 45.109893 -306.446746) (xy 45.098116 -306.398962) (xy 45.094156 -306.349908) (xy 44.776898 -306.349908)
			(xy 44.776394 -306.375616) (xy 44.768351 -306.426398) (xy 44.752463 -306.475297) (xy 44.72912 -306.521109)
			(xy 44.698899 -306.562705) (xy 44.662543 -306.599061) (xy 44.620947 -306.629282) (xy 44.575135 -306.652625)
			(xy 44.526236 -306.668513) (xy 44.475454 -306.676556) (xy 44.424038 -306.676556) (xy 44.373256 -306.668513)
			(xy 44.324357 -306.652625) (xy 44.278545 -306.629282) (xy 44.236949 -306.599061) (xy 44.200593 -306.562705)
			(xy 44.170372 -306.521109) (xy 44.147029 -306.475297) (xy 44.131141 -306.426398) (xy 44.123098 -306.375616)
			(xy 43.826434 -306.375616) (xy 43.818391 -306.426398) (xy 43.802503 -306.475297) (xy 43.77916 -306.521109)
			(xy 43.748939 -306.562705) (xy 43.712583 -306.599061) (xy 43.670987 -306.629282) (xy 43.625175 -306.652625)
			(xy 43.576276 -306.668513) (xy 43.525494 -306.676556) (xy 43.474078 -306.676556) (xy 43.423296 -306.668513)
			(xy 43.374397 -306.652625) (xy 43.328585 -306.629282) (xy 43.286989 -306.599061) (xy 43.250633 -306.562705)
			(xy 43.220412 -306.521109) (xy 43.197069 -306.475297) (xy 43.181181 -306.426398) (xy 43.173138 -306.375616)
			(xy 42.85446 -306.375616) (xy 42.846744 -306.423092) (xy 42.83116 -306.469773) (xy 42.808289 -306.51335)
			(xy 42.778724 -306.552694) (xy 42.743231 -306.586786) (xy 42.702728 -306.614742) (xy 42.658266 -306.63584)
			(xy 42.610995 -306.649532) (xy 42.56214 -306.655464) (xy 42.512965 -306.653483) (xy 42.464746 -306.643639)
			(xy 42.41873 -306.626187) (xy 42.376109 -306.60158) (xy 42.337988 -306.570455) (xy 42.305353 -306.533618)
			(xy 42.27905 -306.492022) (xy 42.259759 -306.446746) (xy 42.247982 -306.398962) (xy 42.244022 -306.349908)
			(xy 41.905174 -306.349908) (xy 41.904679 -306.374515) (xy 41.896784 -306.423092) (xy 41.8812 -306.469773)
			(xy 41.858329 -306.51335) (xy 41.828764 -306.552694) (xy 41.793271 -306.586786) (xy 41.752768 -306.614742)
			(xy 41.708306 -306.63584) (xy 41.661035 -306.649532) (xy 41.61218 -306.655464) (xy 41.563005 -306.653483)
			(xy 41.514786 -306.643639) (xy 41.46877 -306.626187) (xy 41.426149 -306.60158) (xy 41.388028 -306.570455)
			(xy 41.355393 -306.533618) (xy 41.32909 -306.492022) (xy 41.309799 -306.446746) (xy 41.298022 -306.398962)
			(xy 41.294062 -306.349908) (xy 40.955214 -306.349908) (xy 40.954719 -306.374515) (xy 40.946824 -306.423092)
			(xy 40.93124 -306.469773) (xy 40.908369 -306.51335) (xy 40.878804 -306.552694) (xy 40.843311 -306.586786)
			(xy 40.802808 -306.614742) (xy 40.758346 -306.63584) (xy 40.711075 -306.649532) (xy 40.66222 -306.655464)
			(xy 40.613045 -306.653483) (xy 40.564826 -306.643639) (xy 40.51881 -306.626187) (xy 40.476189 -306.60158)
			(xy 40.438068 -306.570455) (xy 40.405433 -306.533618) (xy 40.37913 -306.492022) (xy 40.359839 -306.446746)
			(xy 40.348062 -306.398962) (xy 40.344102 -306.349908) (xy 40.005254 -306.349908) (xy 40.004759 -306.374515)
			(xy 39.996864 -306.423092) (xy 39.98128 -306.469773) (xy 39.958409 -306.51335) (xy 39.928844 -306.552694)
			(xy 39.893351 -306.586786) (xy 39.852848 -306.614742) (xy 39.808386 -306.63584) (xy 39.761115 -306.649532)
			(xy 39.71226 -306.655464) (xy 39.663085 -306.653483) (xy 39.614866 -306.643639) (xy 39.56885 -306.626187)
			(xy 39.526229 -306.60158) (xy 39.488108 -306.570455) (xy 39.455473 -306.533618) (xy 39.42917 -306.492022)
			(xy 39.409879 -306.446746) (xy 39.398102 -306.398962) (xy 39.394142 -306.349908) (xy 39.055294 -306.349908)
			(xy 39.054799 -306.374515) (xy 39.046904 -306.423092) (xy 39.03132 -306.469773) (xy 39.008449 -306.51335)
			(xy 38.978884 -306.552694) (xy 38.943391 -306.586786) (xy 38.902888 -306.614742) (xy 38.858426 -306.63584)
			(xy 38.811155 -306.649532) (xy 38.7623 -306.655464) (xy 38.713125 -306.653483) (xy 38.664906 -306.643639)
			(xy 38.61889 -306.626187) (xy 38.576269 -306.60158) (xy 38.538148 -306.570455) (xy 38.505513 -306.533618)
			(xy 38.47921 -306.492022) (xy 38.459919 -306.446746) (xy 38.448142 -306.398962) (xy 38.444182 -306.349908)
			(xy 38.126924 -306.349908) (xy 38.12642 -306.375616) (xy 38.118377 -306.426398) (xy 38.102489 -306.475297)
			(xy 38.079146 -306.521109) (xy 38.048925 -306.562705) (xy 38.012569 -306.599061) (xy 37.970973 -306.629282)
			(xy 37.925161 -306.652625) (xy 37.876262 -306.668513) (xy 37.82548 -306.676556) (xy 37.774064 -306.676556)
			(xy 37.723282 -306.668513) (xy 37.674383 -306.652625) (xy 37.628571 -306.629282) (xy 37.586975 -306.599061)
			(xy 37.550619 -306.562705) (xy 37.520398 -306.521109) (xy 37.497055 -306.475297) (xy 37.481167 -306.426398)
			(xy 37.473124 -306.375616) (xy 37.17646 -306.375616) (xy 37.168417 -306.426398) (xy 37.152529 -306.475297)
			(xy 37.129186 -306.521109) (xy 37.098965 -306.562705) (xy 37.062609 -306.599061) (xy 37.021013 -306.629282)
			(xy 36.975201 -306.652625) (xy 36.926302 -306.668513) (xy 36.87552 -306.676556) (xy 36.824104 -306.676556)
			(xy 36.773322 -306.668513) (xy 36.724423 -306.652625) (xy 36.678611 -306.629282) (xy 36.637015 -306.599061)
			(xy 36.600659 -306.562705) (xy 36.570438 -306.521109) (xy 36.547095 -306.475297) (xy 36.531207 -306.426398)
			(xy 36.523164 -306.375616) (xy 36.204273 -306.375616) (xy 36.196516 -306.423346) (xy 36.180932 -306.470027)
			(xy 36.158061 -306.513604) (xy 36.128496 -306.552948) (xy 36.093003 -306.58704) (xy 36.0525 -306.614996)
			(xy 36.008038 -306.636094) (xy 35.960767 -306.649786) (xy 35.911912 -306.655718) (xy 35.862737 -306.653737)
			(xy 35.814518 -306.643893) (xy 35.768502 -306.626441) (xy 35.725881 -306.601834) (xy 35.68776 -306.570709)
			(xy 35.655125 -306.533872) (xy 35.628822 -306.492276) (xy 35.609531 -306.447) (xy 35.597754 -306.399216)
			(xy 35.593794 -306.350162) (xy 27.311055 -306.350162) (xy 27.295125 -306.363419) (xy 27.247519 -306.392473)
			(xy 27.19619 -306.414285) (xy 27.142233 -306.428391) (xy 27.086796 -306.434491) (xy 27.031062 -306.432454)
			(xy 26.976219 -306.422324) (xy 26.923435 -306.404317) (xy 26.873835 -306.378816) (xy 26.828477 -306.346365)
			(xy 26.788328 -306.307656) (xy 26.754242 -306.263513) (xy 26.726946 -306.214878) (xy 26.707023 -306.162787)
			(xy 26.694897 -306.10835) (xy 26.690826 -306.052728) (xy 18.326327 -306.052728) (xy 18.326564 -306.053002)
			(xy 18.356052 -306.098886) (xy 18.37871 -306.148499) (xy 18.394076 -306.200832) (xy 18.401839 -306.254819)
			(xy 18.401839 -306.309361) (xy 18.394076 -306.363348) (xy 18.37871 -306.415681) (xy 18.356052 -306.465294)
			(xy 18.326564 -306.511178) (xy 18.290847 -306.552398) (xy 18.249626 -306.588116) (xy 18.203743 -306.617603)
			(xy 18.154129 -306.640261) (xy 18.101796 -306.655627) (xy 18.047809 -306.663389) (xy 18.020538 -306.663852)
			(xy 17.992677 -306.663322) (xy 17.937552 -306.655184) (xy 17.884191 -306.639132) (xy 17.85874 -306.627784)
			(xy 17.846802 -306.622196) (xy 17.820894 -306.62372) (xy 17.737582 -306.676806) (xy 17.730532 -306.681651)
			(xy 17.7199 -306.695039) (xy 17.714275 -306.711184) (xy 17.71396 -306.719732) (xy 17.71396 -306.765198)
			(xy 29.725364 -306.765198) (xy 29.729435 -306.709576) (xy 29.741561 -306.655139) (xy 29.761484 -306.603048)
			(xy 29.78878 -306.554413) (xy 29.822866 -306.51027) (xy 29.863015 -306.471561) (xy 29.908373 -306.43911)
			(xy 29.957973 -306.413609) (xy 30.010757 -306.395602) (xy 30.0656 -306.385472) (xy 30.121334 -306.383435)
			(xy 30.176771 -306.389535) (xy 30.230728 -306.403641) (xy 30.282057 -306.425453) (xy 30.329663 -306.454507)
			(xy 30.372531 -306.490182) (xy 30.409748 -306.531719) (xy 30.440521 -306.578232) (xy 30.464193 -306.628729)
			(xy 30.480261 -306.682136) (xy 30.488381 -306.737312) (xy 30.48889 -306.765198) (xy 30.488381 -306.793084)
			(xy 30.480261 -306.84826) (xy 30.464193 -306.901667) (xy 30.440521 -306.952164) (xy 30.409748 -306.998677)
			(xy 30.372531 -307.040214) (xy 30.329663 -307.075889) (xy 30.282057 -307.104943) (xy 30.230728 -307.126755)
			(xy 30.176771 -307.140861) (xy 30.121334 -307.146961) (xy 30.0656 -307.144924) (xy 30.010757 -307.134794)
			(xy 29.957973 -307.116787) (xy 29.908373 -307.091286) (xy 29.863015 -307.058835) (xy 29.822866 -307.020126)
			(xy 29.78878 -306.975983) (xy 29.761484 -306.927348) (xy 29.741561 -306.875257) (xy 29.729435 -306.82082)
			(xy 29.725364 -306.765198) (xy 17.71396 -306.765198) (xy 17.71396 -307.240178) (xy 31.85998 -307.240178)
			(xy 31.864051 -307.184556) (xy 31.876177 -307.130119) (xy 31.8961 -307.078028) (xy 31.923396 -307.029393)
			(xy 31.957482 -306.98525) (xy 31.997631 -306.946541) (xy 32.042989 -306.91409) (xy 32.092589 -306.888589)
			(xy 32.145373 -306.870582) (xy 32.200216 -306.860452) (xy 32.25595 -306.858415) (xy 32.311387 -306.864515)
			(xy 32.365344 -306.878621) (xy 32.416673 -306.900433) (xy 32.464279 -306.929487) (xy 32.507147 -306.965162)
			(xy 32.544364 -307.006699) (xy 32.575137 -307.053212) (xy 32.598809 -307.103709) (xy 32.614877 -307.157116)
			(xy 32.622997 -307.212292) (xy 32.623506 -307.240178) (xy 32.622997 -307.268064) (xy 32.618317 -307.299868)
			(xy 36.544008 -307.299868) (xy 36.547968 -307.250814) (xy 36.559745 -307.20303) (xy 36.579036 -307.157754)
			(xy 36.605339 -307.116158) (xy 36.637974 -307.079321) (xy 36.676095 -307.048196) (xy 36.718716 -307.023589)
			(xy 36.764732 -307.006137) (xy 36.812951 -306.996293) (xy 36.862126 -306.994312) (xy 36.910981 -307.000244)
			(xy 36.958252 -307.013936) (xy 37.002714 -307.035034) (xy 37.043217 -307.06299) (xy 37.07871 -307.097082)
			(xy 37.108275 -307.136426) (xy 37.131146 -307.180003) (xy 37.14673 -307.226684) (xy 37.154625 -307.275261)
			(xy 37.15512 -307.299868) (xy 37.493968 -307.299868) (xy 37.497928 -307.250814) (xy 37.509705 -307.20303)
			(xy 37.528996 -307.157754) (xy 37.555299 -307.116158) (xy 37.587934 -307.079321) (xy 37.626055 -307.048196)
			(xy 37.668676 -307.023589) (xy 37.714692 -307.006137) (xy 37.762911 -306.996293) (xy 37.812086 -306.994312)
			(xy 37.860941 -307.000244) (xy 37.908212 -307.013936) (xy 37.952674 -307.035034) (xy 37.993177 -307.06299)
			(xy 38.02867 -307.097082) (xy 38.058235 -307.136426) (xy 38.081106 -307.180003) (xy 38.09669 -307.226684)
			(xy 38.104585 -307.275261) (xy 38.10508 -307.299868) (xy 38.104585 -307.324475) (xy 38.104406 -307.325576)
			(xy 38.423338 -307.325576) (xy 38.423338 -307.27416) (xy 38.431381 -307.223378) (xy 38.447269 -307.174479)
			(xy 38.470612 -307.128667) (xy 38.500833 -307.087071) (xy 38.537189 -307.050715) (xy 38.578785 -307.020494)
			(xy 38.624597 -306.997151) (xy 38.673496 -306.981263) (xy 38.724278 -306.97322) (xy 38.775694 -306.97322)
			(xy 38.826476 -306.981263) (xy 38.875375 -306.997151) (xy 38.921187 -307.020494) (xy 38.962783 -307.050715)
			(xy 38.999139 -307.087071) (xy 39.02936 -307.128667) (xy 39.052703 -307.174479) (xy 39.068591 -307.223378)
			(xy 39.076634 -307.27416) (xy 39.077138 -307.299868) (xy 39.076634 -307.325576) (xy 39.373298 -307.325576)
			(xy 39.373298 -307.27416) (xy 39.381341 -307.223378) (xy 39.397229 -307.174479) (xy 39.420572 -307.128667)
			(xy 39.450793 -307.087071) (xy 39.487149 -307.050715) (xy 39.528745 -307.020494) (xy 39.574557 -306.997151)
			(xy 39.623456 -306.981263) (xy 39.674238 -306.97322) (xy 39.725654 -306.97322) (xy 39.776436 -306.981263)
			(xy 39.825335 -306.997151) (xy 39.871147 -307.020494) (xy 39.912743 -307.050715) (xy 39.949099 -307.087071)
			(xy 39.97932 -307.128667) (xy 40.002663 -307.174479) (xy 40.018551 -307.223378) (xy 40.026594 -307.27416)
			(xy 40.027098 -307.299868) (xy 40.344102 -307.299868) (xy 40.348062 -307.250814) (xy 40.359839 -307.20303)
			(xy 40.37913 -307.157754) (xy 40.405433 -307.116158) (xy 40.438068 -307.079321) (xy 40.476189 -307.048196)
			(xy 40.51881 -307.023589) (xy 40.564826 -307.006137) (xy 40.613045 -306.996293) (xy 40.66222 -306.994312)
			(xy 40.711075 -307.000244) (xy 40.758346 -307.013936) (xy 40.802808 -307.035034) (xy 40.843311 -307.06299)
			(xy 40.878804 -307.097082) (xy 40.908369 -307.136426) (xy 40.93124 -307.180003) (xy 40.946824 -307.226684)
			(xy 40.954719 -307.275261) (xy 40.955214 -307.299868) (xy 40.954719 -307.324475) (xy 40.95454 -307.325576)
			(xy 41.273218 -307.325576) (xy 41.273218 -307.27416) (xy 41.281261 -307.223378) (xy 41.297149 -307.174479)
			(xy 41.320492 -307.128667) (xy 41.350713 -307.087071) (xy 41.387069 -307.050715) (xy 41.428665 -307.020494)
			(xy 41.474477 -306.997151) (xy 41.523376 -306.981263) (xy 41.574158 -306.97322) (xy 41.625574 -306.97322)
			(xy 41.676356 -306.981263) (xy 41.725255 -306.997151) (xy 41.771067 -307.020494) (xy 41.812663 -307.050715)
			(xy 41.849019 -307.087071) (xy 41.87924 -307.128667) (xy 41.902583 -307.174479) (xy 41.918471 -307.223378)
			(xy 41.926514 -307.27416) (xy 41.927018 -307.299868) (xy 41.926514 -307.325576) (xy 42.223178 -307.325576)
			(xy 42.223178 -307.27416) (xy 42.231221 -307.223378) (xy 42.247109 -307.174479) (xy 42.270452 -307.128667)
			(xy 42.300673 -307.087071) (xy 42.337029 -307.050715) (xy 42.378625 -307.020494) (xy 42.424437 -306.997151)
			(xy 42.473336 -306.981263) (xy 42.524118 -306.97322) (xy 42.575534 -306.97322) (xy 42.626316 -306.981263)
			(xy 42.675215 -306.997151) (xy 42.721027 -307.020494) (xy 42.762623 -307.050715) (xy 42.798979 -307.087071)
			(xy 42.8292 -307.128667) (xy 42.852543 -307.174479) (xy 42.868431 -307.223378) (xy 42.876474 -307.27416)
			(xy 42.876978 -307.299868) (xy 43.193982 -307.299868) (xy 43.197942 -307.250814) (xy 43.209719 -307.20303)
			(xy 43.22901 -307.157754) (xy 43.255313 -307.116158) (xy 43.287948 -307.079321) (xy 43.326069 -307.048196)
			(xy 43.36869 -307.023589) (xy 43.414706 -307.006137) (xy 43.462925 -306.996293) (xy 43.5121 -306.994312)
			(xy 43.560955 -307.000244) (xy 43.608226 -307.013936) (xy 43.652688 -307.035034) (xy 43.693191 -307.06299)
			(xy 43.728684 -307.097082) (xy 43.758249 -307.136426) (xy 43.78112 -307.180003) (xy 43.796704 -307.226684)
			(xy 43.804599 -307.275261) (xy 43.805094 -307.299868) (xy 44.143942 -307.299868) (xy 44.147902 -307.250814)
			(xy 44.159679 -307.20303) (xy 44.17897 -307.157754) (xy 44.205273 -307.116158) (xy 44.237908 -307.079321)
			(xy 44.276029 -307.048196) (xy 44.31865 -307.023589) (xy 44.364666 -307.006137) (xy 44.412885 -306.996293)
			(xy 44.46206 -306.994312) (xy 44.510915 -307.000244) (xy 44.558186 -307.013936) (xy 44.602648 -307.035034)
			(xy 44.643151 -307.06299) (xy 44.678644 -307.097082) (xy 44.708209 -307.136426) (xy 44.73108 -307.180003)
			(xy 44.746664 -307.226684) (xy 44.754559 -307.275261) (xy 44.755054 -307.299868) (xy 45.094156 -307.299868)
			(xy 45.098116 -307.250814) (xy 45.109893 -307.20303) (xy 45.129184 -307.157754) (xy 45.155487 -307.116158)
			(xy 45.188122 -307.079321) (xy 45.226243 -307.048196) (xy 45.268864 -307.023589) (xy 45.31488 -307.006137)
			(xy 45.363099 -306.996293) (xy 45.412274 -306.994312) (xy 45.461129 -307.000244) (xy 45.5084 -307.013936)
			(xy 45.552862 -307.035034) (xy 45.593365 -307.06299) (xy 45.628858 -307.097082) (xy 45.658423 -307.136426)
			(xy 45.681294 -307.180003) (xy 45.696878 -307.226684) (xy 45.704773 -307.275261) (xy 45.705268 -307.299868)
			(xy 46.044116 -307.299868) (xy 46.048076 -307.250814) (xy 46.059853 -307.20303) (xy 46.079144 -307.157754)
			(xy 46.105447 -307.116158) (xy 46.138082 -307.079321) (xy 46.176203 -307.048196) (xy 46.218824 -307.023589)
			(xy 46.26484 -307.006137) (xy 46.313059 -306.996293) (xy 46.362234 -306.994312) (xy 46.411089 -307.000244)
			(xy 46.45836 -307.013936) (xy 46.502822 -307.035034) (xy 46.543325 -307.06299) (xy 46.578818 -307.097082)
			(xy 46.608383 -307.136426) (xy 46.631254 -307.180003) (xy 46.646838 -307.226684) (xy 46.654733 -307.275261)
			(xy 46.655228 -307.299868) (xy 46.994076 -307.299868) (xy 46.998036 -307.250814) (xy 47.009813 -307.20303)
			(xy 47.029104 -307.157754) (xy 47.055407 -307.116158) (xy 47.088042 -307.079321) (xy 47.126163 -307.048196)
			(xy 47.168784 -307.023589) (xy 47.2148 -307.006137) (xy 47.263019 -306.996293) (xy 47.312194 -306.994312)
			(xy 47.361049 -307.000244) (xy 47.40832 -307.013936) (xy 47.452782 -307.035034) (xy 47.493285 -307.06299)
			(xy 47.528778 -307.097082) (xy 47.558343 -307.136426) (xy 47.581214 -307.180003) (xy 47.596798 -307.226684)
			(xy 47.604693 -307.275261) (xy 47.605022 -307.291601) (xy 47.94405 -307.291601) (xy 47.949421 -307.242243)
			(xy 47.962706 -307.194404) (xy 47.983557 -307.149345) (xy 48.011423 -307.108253) (xy 48.04557 -307.072211)
			(xy 48.085098 -307.042168) (xy 48.128967 -307.018917) (xy 48.176019 -307.003069) (xy 48.225015 -306.995043)
			(xy 48.24984 -306.99456) (xy 48.264023 -306.994732) (xy 48.292263 -306.997407) (xy 48.306228 -306.999894)
			(xy 48.318674 -307.00218) (xy 48.342296 -306.994814) (xy 48.419766 -306.917344) (xy 48.427132 -306.893722)
			(xy 48.424846 -306.881276) (xy 48.422371 -306.86731) (xy 48.419698 -306.83907) (xy 48.419512 -306.824888)
			(xy 48.420034 -306.799633) (xy 48.428347 -306.749811) (xy 48.444748 -306.702037) (xy 48.468789 -306.657614)
			(xy 48.499813 -306.617754) (xy 48.536975 -306.583544) (xy 48.579261 -306.555918) (xy 48.625517 -306.535628)
			(xy 48.674482 -306.523228) (xy 48.72482 -306.519057) (xy 48.775158 -306.523228) (xy 48.824123 -306.535628)
			(xy 48.870379 -306.555918) (xy 48.912665 -306.583544) (xy 48.949827 -306.617754) (xy 48.980851 -306.657614)
			(xy 49.004892 -306.702037) (xy 49.021293 -306.749811) (xy 49.029606 -306.799633) (xy 49.030128 -306.824888)
			(xy 49.029949 -306.839071) (xy 49.027279 -306.867311) (xy 49.024794 -306.881276) (xy 49.022508 -306.893722)
			(xy 49.029874 -306.917344) (xy 49.107344 -306.994814) (xy 49.130966 -307.00218) (xy 49.143412 -306.999894)
			(xy 49.157378 -306.99742) (xy 49.185618 -306.994747) (xy 49.1998 -306.99456) (xy 49.213983 -306.994737)
			(xy 49.242223 -306.997409) (xy 49.256188 -306.999894) (xy 49.268634 -307.00218) (xy 49.292256 -306.994814)
			(xy 49.369726 -306.917344) (xy 49.377092 -306.893722) (xy 49.374806 -306.881276) (xy 49.37233 -306.86731)
			(xy 49.369658 -306.839071) (xy 49.369472 -306.824888) (xy 49.369994 -306.799633) (xy 49.378307 -306.749811)
			(xy 49.394708 -306.702037) (xy 49.418749 -306.657614) (xy 49.449773 -306.617754) (xy 49.486935 -306.583544)
			(xy 49.529221 -306.555918) (xy 49.575477 -306.535628) (xy 49.624442 -306.523228) (xy 49.67478 -306.519057)
			(xy 49.725118 -306.523228) (xy 49.774083 -306.535628) (xy 49.820339 -306.555918) (xy 49.862625 -306.583544)
			(xy 49.899787 -306.617754) (xy 49.930811 -306.657614) (xy 49.954852 -306.702037) (xy 49.971253 -306.749811)
			(xy 49.979566 -306.799633) (xy 49.980088 -306.824888) (xy 49.97991 -306.839071) (xy 49.977239 -306.867311)
			(xy 49.974754 -306.881276) (xy 49.972468 -306.893722) (xy 49.979834 -306.917344) (xy 50.057304 -306.994814)
			(xy 50.080926 -307.00218) (xy 50.093372 -306.999894) (xy 50.107337 -306.997412) (xy 50.135577 -306.994744)
			(xy 50.14976 -306.99456) (xy 50.164007 -306.99472) (xy 50.192375 -306.997394) (xy 50.206402 -306.999894)
			(xy 50.218594 -307.00218) (xy 50.242724 -306.994814) (xy 50.31994 -306.917598) (xy 50.327306 -306.893722)
			(xy 50.32502 -306.881276) (xy 50.322544 -306.86731) (xy 50.319872 -306.83907) (xy 50.319686 -306.824888)
			(xy 50.320191 -306.800068) (xy 50.328223 -306.751083) (xy 50.344075 -306.704042) (xy 50.367328 -306.660186)
			(xy 50.397371 -306.62067) (xy 50.43341 -306.586534) (xy 50.474497 -306.558678) (xy 50.519549 -306.537837)
			(xy 50.56738 -306.524558) (xy 50.616729 -306.519193) (xy 50.666295 -306.521882) (xy 50.714774 -306.532555)
			(xy 50.760887 -306.550929) (xy 50.803421 -306.576523) (xy 50.841253 -306.60866) (xy 50.873388 -306.646494)
			(xy 50.898979 -306.689029) (xy 50.917351 -306.735143) (xy 50.928021 -306.783623) (xy 50.930257 -306.824888)
			(xy 51.26915 -306.824888) (xy 51.27311 -306.775834) (xy 51.284887 -306.72805) (xy 51.304178 -306.682774)
			(xy 51.330481 -306.641178) (xy 51.363116 -306.604341) (xy 51.401237 -306.573216) (xy 51.443858 -306.548609)
			(xy 51.489874 -306.531157) (xy 51.538093 -306.521313) (xy 51.587268 -306.519332) (xy 51.636123 -306.525264)
			(xy 51.683394 -306.538956) (xy 51.727856 -306.560054) (xy 51.768359 -306.58801) (xy 51.803852 -306.622102)
			(xy 51.833417 -306.661446) (xy 51.856288 -306.705023) (xy 51.871872 -306.751704) (xy 51.879767 -306.800281)
			(xy 51.880262 -306.824888) (xy 52.21911 -306.824888) (xy 52.22307 -306.775834) (xy 52.234847 -306.72805)
			(xy 52.254138 -306.682774) (xy 52.280441 -306.641178) (xy 52.313076 -306.604341) (xy 52.351197 -306.573216)
			(xy 52.393818 -306.548609) (xy 52.439834 -306.531157) (xy 52.488053 -306.521313) (xy 52.537228 -306.519332)
			(xy 52.586083 -306.525264) (xy 52.633354 -306.538956) (xy 52.677816 -306.560054) (xy 52.718319 -306.58801)
			(xy 52.753812 -306.622102) (xy 52.783377 -306.661446) (xy 52.806248 -306.705023) (xy 52.821832 -306.751704)
			(xy 52.829727 -306.800281) (xy 52.830222 -306.824888) (xy 53.16907 -306.824888) (xy 53.17303 -306.775834)
			(xy 53.184807 -306.72805) (xy 53.204098 -306.682774) (xy 53.230401 -306.641178) (xy 53.263036 -306.604341)
			(xy 53.301157 -306.573216) (xy 53.343778 -306.548609) (xy 53.389794 -306.531157) (xy 53.438013 -306.521313)
			(xy 53.487188 -306.519332) (xy 53.536043 -306.525264) (xy 53.583314 -306.538956) (xy 53.627776 -306.560054)
			(xy 53.668279 -306.58801) (xy 53.703772 -306.622102) (xy 53.733337 -306.661446) (xy 53.756208 -306.705023)
			(xy 53.771792 -306.751704) (xy 53.779687 -306.800281) (xy 53.780182 -306.824888) (xy 54.11903 -306.824888)
			(xy 54.12299 -306.775834) (xy 54.134767 -306.72805) (xy 54.154058 -306.682774) (xy 54.180361 -306.641178)
			(xy 54.212996 -306.604341) (xy 54.251117 -306.573216) (xy 54.293738 -306.548609) (xy 54.339754 -306.531157)
			(xy 54.387973 -306.521313) (xy 54.437148 -306.519332) (xy 54.486003 -306.525264) (xy 54.533274 -306.538956)
			(xy 54.577736 -306.560054) (xy 54.618239 -306.58801) (xy 54.653732 -306.622102) (xy 54.683297 -306.661446)
			(xy 54.706168 -306.705023) (xy 54.721752 -306.751704) (xy 54.729647 -306.800281) (xy 54.730142 -306.824888)
			(xy 55.06899 -306.824888) (xy 55.07295 -306.775834) (xy 55.084727 -306.72805) (xy 55.104018 -306.682774)
			(xy 55.130321 -306.641178) (xy 55.162956 -306.604341) (xy 55.201077 -306.573216) (xy 55.243698 -306.548609)
			(xy 55.289714 -306.531157) (xy 55.337933 -306.521313) (xy 55.387108 -306.519332) (xy 55.435963 -306.525264)
			(xy 55.483234 -306.538956) (xy 55.527696 -306.560054) (xy 55.568199 -306.58801) (xy 55.603692 -306.622102)
			(xy 55.633257 -306.661446) (xy 55.656128 -306.705023) (xy 55.671712 -306.751704) (xy 55.679607 -306.800281)
			(xy 55.680102 -306.824888) (xy 56.01895 -306.824888) (xy 56.02291 -306.775834) (xy 56.034687 -306.72805)
			(xy 56.053978 -306.682774) (xy 56.080281 -306.641178) (xy 56.112916 -306.604341) (xy 56.151037 -306.573216)
			(xy 56.193658 -306.548609) (xy 56.239674 -306.531157) (xy 56.287893 -306.521313) (xy 56.337068 -306.519332)
			(xy 56.385923 -306.525264) (xy 56.433194 -306.538956) (xy 56.477656 -306.560054) (xy 56.518159 -306.58801)
			(xy 56.553652 -306.622102) (xy 56.583217 -306.661446) (xy 56.606088 -306.705023) (xy 56.621672 -306.751704)
			(xy 56.629567 -306.800281) (xy 56.630062 -306.824888) (xy 56.969164 -306.824888) (xy 56.973124 -306.775834)
			(xy 56.984901 -306.72805) (xy 57.004192 -306.682774) (xy 57.030495 -306.641178) (xy 57.06313 -306.604341)
			(xy 57.101251 -306.573216) (xy 57.143872 -306.548609) (xy 57.189888 -306.531157) (xy 57.238107 -306.521313)
			(xy 57.287282 -306.519332) (xy 57.336137 -306.525264) (xy 57.383408 -306.538956) (xy 57.42787 -306.560054)
			(xy 57.468373 -306.58801) (xy 57.503866 -306.622102) (xy 57.533431 -306.661446) (xy 57.556302 -306.705023)
			(xy 57.571886 -306.751704) (xy 57.579781 -306.800281) (xy 57.580276 -306.824888) (xy 57.919124 -306.824888)
			(xy 57.923084 -306.775834) (xy 57.934861 -306.72805) (xy 57.954152 -306.682774) (xy 57.980455 -306.641178)
			(xy 58.01309 -306.604341) (xy 58.051211 -306.573216) (xy 58.093832 -306.548609) (xy 58.139848 -306.531157)
			(xy 58.188067 -306.521313) (xy 58.237242 -306.519332) (xy 58.286097 -306.525264) (xy 58.333368 -306.538956)
			(xy 58.37783 -306.560054) (xy 58.418333 -306.58801) (xy 58.453826 -306.622102) (xy 58.483391 -306.661446)
			(xy 58.506262 -306.705023) (xy 58.521846 -306.751704) (xy 58.529741 -306.800281) (xy 58.530236 -306.824888)
			(xy 59.819044 -306.824888) (xy 59.823004 -306.775834) (xy 59.834781 -306.72805) (xy 59.854072 -306.682774)
			(xy 59.880375 -306.641178) (xy 59.91301 -306.604341) (xy 59.951131 -306.573216) (xy 59.993752 -306.548609)
			(xy 60.039768 -306.531157) (xy 60.087987 -306.521313) (xy 60.137162 -306.519332) (xy 60.186017 -306.525264)
			(xy 60.233288 -306.538956) (xy 60.27775 -306.560054) (xy 60.318253 -306.58801) (xy 60.353746 -306.622102)
			(xy 60.383311 -306.661446) (xy 60.406182 -306.705023) (xy 60.421766 -306.751704) (xy 60.429661 -306.800281)
			(xy 60.430156 -306.824888) (xy 60.769004 -306.824888) (xy 60.772964 -306.775834) (xy 60.784741 -306.72805)
			(xy 60.804032 -306.682774) (xy 60.830335 -306.641178) (xy 60.86297 -306.604341) (xy 60.901091 -306.573216)
			(xy 60.943712 -306.548609) (xy 60.989728 -306.531157) (xy 61.037947 -306.521313) (xy 61.087122 -306.519332)
			(xy 61.135977 -306.525264) (xy 61.183248 -306.538956) (xy 61.22771 -306.560054) (xy 61.268213 -306.58801)
			(xy 61.303706 -306.622102) (xy 61.333271 -306.661446) (xy 61.356142 -306.705023) (xy 61.371726 -306.751704)
			(xy 61.379621 -306.800281) (xy 61.380116 -306.824888) (xy 61.718964 -306.824888) (xy 61.722924 -306.775834)
			(xy 61.734701 -306.72805) (xy 61.753992 -306.682774) (xy 61.780295 -306.641178) (xy 61.81293 -306.604341)
			(xy 61.851051 -306.573216) (xy 61.893672 -306.548609) (xy 61.939688 -306.531157) (xy 61.987907 -306.521313)
			(xy 62.037082 -306.519332) (xy 62.085937 -306.525264) (xy 62.133208 -306.538956) (xy 62.17767 -306.560054)
			(xy 62.218173 -306.58801) (xy 62.253666 -306.622102) (xy 62.283231 -306.661446) (xy 62.306102 -306.705023)
			(xy 62.321686 -306.751704) (xy 62.329581 -306.800281) (xy 62.330076 -306.824888) (xy 62.669178 -306.824888)
			(xy 62.673138 -306.775834) (xy 62.684915 -306.72805) (xy 62.704206 -306.682774) (xy 62.730509 -306.641178)
			(xy 62.763144 -306.604341) (xy 62.801265 -306.573216) (xy 62.843886 -306.548609) (xy 62.889902 -306.531157)
			(xy 62.938121 -306.521313) (xy 62.987296 -306.519332) (xy 63.036151 -306.525264) (xy 63.083422 -306.538956)
			(xy 63.127884 -306.560054) (xy 63.168387 -306.58801) (xy 63.20388 -306.622102) (xy 63.233445 -306.661446)
			(xy 63.256316 -306.705023) (xy 63.2719 -306.751704) (xy 63.279795 -306.800281) (xy 63.28029 -306.824888)
			(xy 63.619138 -306.824888) (xy 63.623098 -306.775834) (xy 63.634875 -306.72805) (xy 63.654166 -306.682774)
			(xy 63.680469 -306.641178) (xy 63.713104 -306.604341) (xy 63.751225 -306.573216) (xy 63.793846 -306.548609)
			(xy 63.839862 -306.531157) (xy 63.888081 -306.521313) (xy 63.937256 -306.519332) (xy 63.986111 -306.525264)
			(xy 64.033382 -306.538956) (xy 64.077844 -306.560054) (xy 64.118347 -306.58801) (xy 64.15384 -306.622102)
			(xy 64.183405 -306.661446) (xy 64.206276 -306.705023) (xy 64.22186 -306.751704) (xy 64.229755 -306.800281)
			(xy 64.23025 -306.824888) (xy 64.569098 -306.824888) (xy 64.573058 -306.775834) (xy 64.584835 -306.72805)
			(xy 64.604126 -306.682774) (xy 64.630429 -306.641178) (xy 64.663064 -306.604341) (xy 64.701185 -306.573216)
			(xy 64.743806 -306.548609) (xy 64.789822 -306.531157) (xy 64.838041 -306.521313) (xy 64.887216 -306.519332)
			(xy 64.936071 -306.525264) (xy 64.983342 -306.538956) (xy 65.027804 -306.560054) (xy 65.068307 -306.58801)
			(xy 65.1038 -306.622102) (xy 65.133365 -306.661446) (xy 65.156236 -306.705023) (xy 65.17182 -306.751704)
			(xy 65.179715 -306.800281) (xy 65.18021 -306.824888) (xy 65.519058 -306.824888) (xy 65.523018 -306.775834)
			(xy 65.534795 -306.72805) (xy 65.554086 -306.682774) (xy 65.580389 -306.641178) (xy 65.613024 -306.604341)
			(xy 65.651145 -306.573216) (xy 65.693766 -306.548609) (xy 65.739782 -306.531157) (xy 65.788001 -306.521313)
			(xy 65.837176 -306.519332) (xy 65.886031 -306.525264) (xy 65.933302 -306.538956) (xy 65.977764 -306.560054)
			(xy 66.018267 -306.58801) (xy 66.05376 -306.622102) (xy 66.083325 -306.661446) (xy 66.106196 -306.705023)
			(xy 66.12178 -306.751704) (xy 66.129675 -306.800281) (xy 66.13017 -306.824888) (xy 66.469018 -306.824888)
			(xy 66.472978 -306.775834) (xy 66.484755 -306.72805) (xy 66.504046 -306.682774) (xy 66.530349 -306.641178)
			(xy 66.562984 -306.604341) (xy 66.601105 -306.573216) (xy 66.643726 -306.548609) (xy 66.689742 -306.531157)
			(xy 66.737961 -306.521313) (xy 66.787136 -306.519332) (xy 66.835991 -306.525264) (xy 66.883262 -306.538956)
			(xy 66.927724 -306.560054) (xy 66.968227 -306.58801) (xy 67.00372 -306.622102) (xy 67.033285 -306.661446)
			(xy 67.056156 -306.705023) (xy 67.07174 -306.751704) (xy 67.079635 -306.800281) (xy 67.08013 -306.824888)
			(xy 67.418978 -306.824888) (xy 67.422938 -306.775834) (xy 67.434715 -306.72805) (xy 67.454006 -306.682774)
			(xy 67.480309 -306.641178) (xy 67.512944 -306.604341) (xy 67.551065 -306.573216) (xy 67.593686 -306.548609)
			(xy 67.639702 -306.531157) (xy 67.687921 -306.521313) (xy 67.737096 -306.519332) (xy 67.785951 -306.525264)
			(xy 67.833222 -306.538956) (xy 67.877684 -306.560054) (xy 67.918187 -306.58801) (xy 67.95368 -306.622102)
			(xy 67.983245 -306.661446) (xy 68.006116 -306.705023) (xy 68.0217 -306.751704) (xy 68.029595 -306.800281)
			(xy 68.03009 -306.824888) (xy 68.368938 -306.824888) (xy 68.372898 -306.775834) (xy 68.384675 -306.72805)
			(xy 68.403966 -306.682774) (xy 68.430269 -306.641178) (xy 68.462904 -306.604341) (xy 68.501025 -306.573216)
			(xy 68.543646 -306.548609) (xy 68.589662 -306.531157) (xy 68.637881 -306.521313) (xy 68.687056 -306.519332)
			(xy 68.735911 -306.525264) (xy 68.783182 -306.538956) (xy 68.827644 -306.560054) (xy 68.868147 -306.58801)
			(xy 68.90364 -306.622102) (xy 68.933205 -306.661446) (xy 68.956076 -306.705023) (xy 68.97166 -306.751704)
			(xy 68.979555 -306.800281) (xy 68.98005 -306.824888) (xy 69.319152 -306.824888) (xy 69.323112 -306.775834)
			(xy 69.334889 -306.72805) (xy 69.35418 -306.682774) (xy 69.380483 -306.641178) (xy 69.413118 -306.604341)
			(xy 69.451239 -306.573216) (xy 69.49386 -306.548609) (xy 69.539876 -306.531157) (xy 69.588095 -306.521313)
			(xy 69.63727 -306.519332) (xy 69.686125 -306.525264) (xy 69.733396 -306.538956) (xy 69.777858 -306.560054)
			(xy 69.818361 -306.58801) (xy 69.853854 -306.622102) (xy 69.883419 -306.661446) (xy 69.90629 -306.705023)
			(xy 69.921874 -306.751704) (xy 69.929769 -306.800281) (xy 69.930264 -306.824888) (xy 70.269112 -306.824888)
			(xy 70.273072 -306.775834) (xy 70.284849 -306.72805) (xy 70.30414 -306.682774) (xy 70.330443 -306.641178)
			(xy 70.363078 -306.604341) (xy 70.401199 -306.573216) (xy 70.44382 -306.548609) (xy 70.489836 -306.531157)
			(xy 70.538055 -306.521313) (xy 70.58723 -306.519332) (xy 70.636085 -306.525264) (xy 70.683356 -306.538956)
			(xy 70.727818 -306.560054) (xy 70.768321 -306.58801) (xy 70.803814 -306.622102) (xy 70.833379 -306.661446)
			(xy 70.85625 -306.705023) (xy 70.871834 -306.751704) (xy 70.879729 -306.800281) (xy 70.880224 -306.824888)
			(xy 71.219072 -306.824888) (xy 71.223032 -306.775834) (xy 71.234809 -306.72805) (xy 71.2541 -306.682774)
			(xy 71.280403 -306.641178) (xy 71.313038 -306.604341) (xy 71.351159 -306.573216) (xy 71.39378 -306.548609)
			(xy 71.439796 -306.531157) (xy 71.488015 -306.521313) (xy 71.53719 -306.519332) (xy 71.586045 -306.525264)
			(xy 71.633316 -306.538956) (xy 71.677778 -306.560054) (xy 71.718281 -306.58801) (xy 71.753774 -306.622102)
			(xy 71.783339 -306.661446) (xy 71.80621 -306.705023) (xy 71.821794 -306.751704) (xy 71.829689 -306.800281)
			(xy 71.830184 -306.824888) (xy 72.169032 -306.824888) (xy 72.172992 -306.775834) (xy 72.184769 -306.72805)
			(xy 72.20406 -306.682774) (xy 72.230363 -306.641178) (xy 72.262998 -306.604341) (xy 72.301119 -306.573216)
			(xy 72.34374 -306.548609) (xy 72.389756 -306.531157) (xy 72.437975 -306.521313) (xy 72.48715 -306.519332)
			(xy 72.536005 -306.525264) (xy 72.583276 -306.538956) (xy 72.627738 -306.560054) (xy 72.668241 -306.58801)
			(xy 72.703734 -306.622102) (xy 72.733299 -306.661446) (xy 72.75617 -306.705023) (xy 72.771754 -306.751704)
			(xy 72.779649 -306.800281) (xy 72.780144 -306.824888) (xy 72.779649 -306.849495) (xy 72.771754 -306.898072)
			(xy 72.75617 -306.944753) (xy 72.733299 -306.98833) (xy 72.703734 -307.027674) (xy 72.668241 -307.061766)
			(xy 72.627738 -307.089722) (xy 72.583276 -307.11082) (xy 72.536005 -307.124512) (xy 72.48715 -307.130444)
			(xy 72.437975 -307.128463) (xy 72.389756 -307.118619) (xy 72.34374 -307.101167) (xy 72.301119 -307.07656)
			(xy 72.262998 -307.045435) (xy 72.230363 -307.008598) (xy 72.20406 -306.967002) (xy 72.184769 -306.921726)
			(xy 72.172992 -306.873942) (xy 72.169032 -306.824888) (xy 71.830184 -306.824888) (xy 71.829689 -306.849495)
			(xy 71.821794 -306.898072) (xy 71.80621 -306.944753) (xy 71.783339 -306.98833) (xy 71.753774 -307.027674)
			(xy 71.718281 -307.061766) (xy 71.677778 -307.089722) (xy 71.633316 -307.11082) (xy 71.586045 -307.124512)
			(xy 71.53719 -307.130444) (xy 71.488015 -307.128463) (xy 71.439796 -307.118619) (xy 71.39378 -307.101167)
			(xy 71.351159 -307.07656) (xy 71.313038 -307.045435) (xy 71.280403 -307.008598) (xy 71.2541 -306.967002)
			(xy 71.234809 -306.921726) (xy 71.223032 -306.873942) (xy 71.219072 -306.824888) (xy 70.880224 -306.824888)
			(xy 70.879729 -306.849495) (xy 70.871834 -306.898072) (xy 70.85625 -306.944753) (xy 70.833379 -306.98833)
			(xy 70.803814 -307.027674) (xy 70.768321 -307.061766) (xy 70.727818 -307.089722) (xy 70.683356 -307.11082)
			(xy 70.636085 -307.124512) (xy 70.58723 -307.130444) (xy 70.538055 -307.128463) (xy 70.489836 -307.118619)
			(xy 70.44382 -307.101167) (xy 70.401199 -307.07656) (xy 70.363078 -307.045435) (xy 70.330443 -307.008598)
			(xy 70.30414 -306.967002) (xy 70.284849 -306.921726) (xy 70.273072 -306.873942) (xy 70.269112 -306.824888)
			(xy 69.930264 -306.824888) (xy 69.929769 -306.849495) (xy 69.921874 -306.898072) (xy 69.90629 -306.944753)
			(xy 69.883419 -306.98833) (xy 69.853854 -307.027674) (xy 69.818361 -307.061766) (xy 69.777858 -307.089722)
			(xy 69.733396 -307.11082) (xy 69.686125 -307.124512) (xy 69.63727 -307.130444) (xy 69.588095 -307.128463)
			(xy 69.539876 -307.118619) (xy 69.49386 -307.101167) (xy 69.451239 -307.07656) (xy 69.413118 -307.045435)
			(xy 69.380483 -307.008598) (xy 69.35418 -306.967002) (xy 69.334889 -306.921726) (xy 69.323112 -306.873942)
			(xy 69.319152 -306.824888) (xy 68.98005 -306.824888) (xy 68.979555 -306.849495) (xy 68.97166 -306.898072)
			(xy 68.956076 -306.944753) (xy 68.933205 -306.98833) (xy 68.90364 -307.027674) (xy 68.868147 -307.061766)
			(xy 68.827644 -307.089722) (xy 68.783182 -307.11082) (xy 68.735911 -307.124512) (xy 68.687056 -307.130444)
			(xy 68.637881 -307.128463) (xy 68.589662 -307.118619) (xy 68.543646 -307.101167) (xy 68.501025 -307.07656)
			(xy 68.462904 -307.045435) (xy 68.430269 -307.008598) (xy 68.403966 -306.967002) (xy 68.384675 -306.921726)
			(xy 68.372898 -306.873942) (xy 68.368938 -306.824888) (xy 68.03009 -306.824888) (xy 68.029595 -306.849495)
			(xy 68.0217 -306.898072) (xy 68.006116 -306.944753) (xy 67.983245 -306.98833) (xy 67.95368 -307.027674)
			(xy 67.918187 -307.061766) (xy 67.877684 -307.089722) (xy 67.833222 -307.11082) (xy 67.785951 -307.124512)
			(xy 67.737096 -307.130444) (xy 67.687921 -307.128463) (xy 67.639702 -307.118619) (xy 67.593686 -307.101167)
			(xy 67.551065 -307.07656) (xy 67.512944 -307.045435) (xy 67.480309 -307.008598) (xy 67.454006 -306.967002)
			(xy 67.434715 -306.921726) (xy 67.422938 -306.873942) (xy 67.418978 -306.824888) (xy 67.08013 -306.824888)
			(xy 67.079635 -306.849495) (xy 67.07174 -306.898072) (xy 67.056156 -306.944753) (xy 67.033285 -306.98833)
			(xy 67.00372 -307.027674) (xy 66.968227 -307.061766) (xy 66.927724 -307.089722) (xy 66.883262 -307.11082)
			(xy 66.835991 -307.124512) (xy 66.787136 -307.130444) (xy 66.737961 -307.128463) (xy 66.689742 -307.118619)
			(xy 66.643726 -307.101167) (xy 66.601105 -307.07656) (xy 66.562984 -307.045435) (xy 66.530349 -307.008598)
			(xy 66.504046 -306.967002) (xy 66.484755 -306.921726) (xy 66.472978 -306.873942) (xy 66.469018 -306.824888)
			(xy 66.13017 -306.824888) (xy 66.129675 -306.849495) (xy 66.12178 -306.898072) (xy 66.106196 -306.944753)
			(xy 66.083325 -306.98833) (xy 66.05376 -307.027674) (xy 66.018267 -307.061766) (xy 65.977764 -307.089722)
			(xy 65.933302 -307.11082) (xy 65.886031 -307.124512) (xy 65.837176 -307.130444) (xy 65.788001 -307.128463)
			(xy 65.739782 -307.118619) (xy 65.693766 -307.101167) (xy 65.651145 -307.07656) (xy 65.613024 -307.045435)
			(xy 65.580389 -307.008598) (xy 65.554086 -306.967002) (xy 65.534795 -306.921726) (xy 65.523018 -306.873942)
			(xy 65.519058 -306.824888) (xy 65.18021 -306.824888) (xy 65.179715 -306.849495) (xy 65.17182 -306.898072)
			(xy 65.156236 -306.944753) (xy 65.133365 -306.98833) (xy 65.1038 -307.027674) (xy 65.068307 -307.061766)
			(xy 65.027804 -307.089722) (xy 64.983342 -307.11082) (xy 64.936071 -307.124512) (xy 64.887216 -307.130444)
			(xy 64.838041 -307.128463) (xy 64.789822 -307.118619) (xy 64.743806 -307.101167) (xy 64.701185 -307.07656)
			(xy 64.663064 -307.045435) (xy 64.630429 -307.008598) (xy 64.604126 -306.967002) (xy 64.584835 -306.921726)
			(xy 64.573058 -306.873942) (xy 64.569098 -306.824888) (xy 64.23025 -306.824888) (xy 64.229755 -306.849495)
			(xy 64.22186 -306.898072) (xy 64.206276 -306.944753) (xy 64.183405 -306.98833) (xy 64.15384 -307.027674)
			(xy 64.118347 -307.061766) (xy 64.077844 -307.089722) (xy 64.033382 -307.11082) (xy 63.986111 -307.124512)
			(xy 63.937256 -307.130444) (xy 63.888081 -307.128463) (xy 63.839862 -307.118619) (xy 63.793846 -307.101167)
			(xy 63.751225 -307.07656) (xy 63.713104 -307.045435) (xy 63.680469 -307.008598) (xy 63.654166 -306.967002)
			(xy 63.634875 -306.921726) (xy 63.623098 -306.873942) (xy 63.619138 -306.824888) (xy 63.28029 -306.824888)
			(xy 63.279795 -306.849495) (xy 63.2719 -306.898072) (xy 63.256316 -306.944753) (xy 63.233445 -306.98833)
			(xy 63.20388 -307.027674) (xy 63.168387 -307.061766) (xy 63.127884 -307.089722) (xy 63.083422 -307.11082)
			(xy 63.036151 -307.124512) (xy 62.987296 -307.130444) (xy 62.938121 -307.128463) (xy 62.889902 -307.118619)
			(xy 62.843886 -307.101167) (xy 62.801265 -307.07656) (xy 62.763144 -307.045435) (xy 62.730509 -307.008598)
			(xy 62.704206 -306.967002) (xy 62.684915 -306.921726) (xy 62.673138 -306.873942) (xy 62.669178 -306.824888)
			(xy 62.330076 -306.824888) (xy 62.329581 -306.849495) (xy 62.321686 -306.898072) (xy 62.306102 -306.944753)
			(xy 62.283231 -306.98833) (xy 62.253666 -307.027674) (xy 62.218173 -307.061766) (xy 62.17767 -307.089722)
			(xy 62.133208 -307.11082) (xy 62.085937 -307.124512) (xy 62.037082 -307.130444) (xy 61.987907 -307.128463)
			(xy 61.939688 -307.118619) (xy 61.893672 -307.101167) (xy 61.851051 -307.07656) (xy 61.81293 -307.045435)
			(xy 61.780295 -307.008598) (xy 61.753992 -306.967002) (xy 61.734701 -306.921726) (xy 61.722924 -306.873942)
			(xy 61.718964 -306.824888) (xy 61.380116 -306.824888) (xy 61.379621 -306.849495) (xy 61.371726 -306.898072)
			(xy 61.356142 -306.944753) (xy 61.333271 -306.98833) (xy 61.303706 -307.027674) (xy 61.268213 -307.061766)
			(xy 61.22771 -307.089722) (xy 61.183248 -307.11082) (xy 61.135977 -307.124512) (xy 61.087122 -307.130444)
			(xy 61.037947 -307.128463) (xy 60.989728 -307.118619) (xy 60.943712 -307.101167) (xy 60.901091 -307.07656)
			(xy 60.86297 -307.045435) (xy 60.830335 -307.008598) (xy 60.804032 -306.967002) (xy 60.784741 -306.921726)
			(xy 60.772964 -306.873942) (xy 60.769004 -306.824888) (xy 60.430156 -306.824888) (xy 60.429661 -306.849495)
			(xy 60.421766 -306.898072) (xy 60.406182 -306.944753) (xy 60.383311 -306.98833) (xy 60.353746 -307.027674)
			(xy 60.318253 -307.061766) (xy 60.27775 -307.089722) (xy 60.233288 -307.11082) (xy 60.186017 -307.124512)
			(xy 60.137162 -307.130444) (xy 60.087987 -307.128463) (xy 60.039768 -307.118619) (xy 59.993752 -307.101167)
			(xy 59.951131 -307.07656) (xy 59.91301 -307.045435) (xy 59.880375 -307.008598) (xy 59.854072 -306.967002)
			(xy 59.834781 -306.921726) (xy 59.823004 -306.873942) (xy 59.819044 -306.824888) (xy 58.530236 -306.824888)
			(xy 58.529741 -306.849495) (xy 58.521846 -306.898072) (xy 58.506262 -306.944753) (xy 58.483391 -306.98833)
			(xy 58.453826 -307.027674) (xy 58.418333 -307.061766) (xy 58.37783 -307.089722) (xy 58.333368 -307.11082)
			(xy 58.286097 -307.124512) (xy 58.237242 -307.130444) (xy 58.188067 -307.128463) (xy 58.139848 -307.118619)
			(xy 58.093832 -307.101167) (xy 58.051211 -307.07656) (xy 58.01309 -307.045435) (xy 57.980455 -307.008598)
			(xy 57.954152 -306.967002) (xy 57.934861 -306.921726) (xy 57.923084 -306.873942) (xy 57.919124 -306.824888)
			(xy 57.580276 -306.824888) (xy 57.579781 -306.849495) (xy 57.571886 -306.898072) (xy 57.556302 -306.944753)
			(xy 57.533431 -306.98833) (xy 57.503866 -307.027674) (xy 57.468373 -307.061766) (xy 57.42787 -307.089722)
			(xy 57.383408 -307.11082) (xy 57.336137 -307.124512) (xy 57.287282 -307.130444) (xy 57.238107 -307.128463)
			(xy 57.189888 -307.118619) (xy 57.143872 -307.101167) (xy 57.101251 -307.07656) (xy 57.06313 -307.045435)
			(xy 57.030495 -307.008598) (xy 57.004192 -306.967002) (xy 56.984901 -306.921726) (xy 56.973124 -306.873942)
			(xy 56.969164 -306.824888) (xy 56.630062 -306.824888) (xy 56.629567 -306.849495) (xy 56.621672 -306.898072)
			(xy 56.606088 -306.944753) (xy 56.583217 -306.98833) (xy 56.553652 -307.027674) (xy 56.518159 -307.061766)
			(xy 56.477656 -307.089722) (xy 56.433194 -307.11082) (xy 56.385923 -307.124512) (xy 56.337068 -307.130444)
			(xy 56.287893 -307.128463) (xy 56.239674 -307.118619) (xy 56.193658 -307.101167) (xy 56.151037 -307.07656)
			(xy 56.112916 -307.045435) (xy 56.080281 -307.008598) (xy 56.053978 -306.967002) (xy 56.034687 -306.921726)
			(xy 56.02291 -306.873942) (xy 56.01895 -306.824888) (xy 55.680102 -306.824888) (xy 55.679607 -306.849495)
			(xy 55.671712 -306.898072) (xy 55.656128 -306.944753) (xy 55.633257 -306.98833) (xy 55.603692 -307.027674)
			(xy 55.568199 -307.061766) (xy 55.527696 -307.089722) (xy 55.483234 -307.11082) (xy 55.435963 -307.124512)
			(xy 55.387108 -307.130444) (xy 55.337933 -307.128463) (xy 55.289714 -307.118619) (xy 55.243698 -307.101167)
			(xy 55.201077 -307.07656) (xy 55.162956 -307.045435) (xy 55.130321 -307.008598) (xy 55.104018 -306.967002)
			(xy 55.084727 -306.921726) (xy 55.07295 -306.873942) (xy 55.06899 -306.824888) (xy 54.730142 -306.824888)
			(xy 54.729647 -306.849495) (xy 54.721752 -306.898072) (xy 54.706168 -306.944753) (xy 54.683297 -306.98833)
			(xy 54.653732 -307.027674) (xy 54.618239 -307.061766) (xy 54.577736 -307.089722) (xy 54.533274 -307.11082)
			(xy 54.486003 -307.124512) (xy 54.437148 -307.130444) (xy 54.387973 -307.128463) (xy 54.339754 -307.118619)
			(xy 54.293738 -307.101167) (xy 54.251117 -307.07656) (xy 54.212996 -307.045435) (xy 54.180361 -307.008598)
			(xy 54.154058 -306.967002) (xy 54.134767 -306.921726) (xy 54.12299 -306.873942) (xy 54.11903 -306.824888)
			(xy 53.780182 -306.824888) (xy 53.779687 -306.849495) (xy 53.771792 -306.898072) (xy 53.756208 -306.944753)
			(xy 53.733337 -306.98833) (xy 53.703772 -307.027674) (xy 53.668279 -307.061766) (xy 53.627776 -307.089722)
			(xy 53.583314 -307.11082) (xy 53.536043 -307.124512) (xy 53.487188 -307.130444) (xy 53.438013 -307.128463)
			(xy 53.389794 -307.118619) (xy 53.343778 -307.101167) (xy 53.301157 -307.07656) (xy 53.263036 -307.045435)
			(xy 53.230401 -307.008598) (xy 53.204098 -306.967002) (xy 53.184807 -306.921726) (xy 53.17303 -306.873942)
			(xy 53.16907 -306.824888) (xy 52.830222 -306.824888) (xy 52.829727 -306.849495) (xy 52.821832 -306.898072)
			(xy 52.806248 -306.944753) (xy 52.783377 -306.98833) (xy 52.753812 -307.027674) (xy 52.718319 -307.061766)
			(xy 52.677816 -307.089722) (xy 52.633354 -307.11082) (xy 52.586083 -307.124512) (xy 52.537228 -307.130444)
			(xy 52.488053 -307.128463) (xy 52.439834 -307.118619) (xy 52.393818 -307.101167) (xy 52.351197 -307.07656)
			(xy 52.313076 -307.045435) (xy 52.280441 -307.008598) (xy 52.254138 -306.967002) (xy 52.234847 -306.921726)
			(xy 52.22307 -306.873942) (xy 52.21911 -306.824888) (xy 51.880262 -306.824888) (xy 51.879767 -306.849495)
			(xy 51.871872 -306.898072) (xy 51.856288 -306.944753) (xy 51.833417 -306.98833) (xy 51.803852 -307.027674)
			(xy 51.768359 -307.061766) (xy 51.727856 -307.089722) (xy 51.683394 -307.11082) (xy 51.636123 -307.124512)
			(xy 51.587268 -307.130444) (xy 51.538093 -307.128463) (xy 51.489874 -307.118619) (xy 51.443858 -307.101167)
			(xy 51.401237 -307.07656) (xy 51.363116 -307.045435) (xy 51.330481 -307.008598) (xy 51.304178 -306.967002)
			(xy 51.284887 -306.921726) (xy 51.27311 -306.873942) (xy 51.26915 -306.824888) (xy 50.930257 -306.824888)
			(xy 50.930707 -306.833189) (xy 50.925338 -306.882538) (xy 50.912057 -306.930368) (xy 50.891213 -306.975419)
			(xy 50.863355 -307.016504) (xy 50.829217 -307.052542) (xy 50.789699 -307.082581) (xy 50.745841 -307.105832)
			(xy 50.6988 -307.121681) (xy 50.649814 -307.129711) (xy 50.624994 -307.130196) (xy 50.610748 -307.130023)
			(xy 50.58238 -307.127354) (xy 50.568352 -307.124862) (xy 50.55616 -307.122576) (xy 50.53203 -307.129942)
			(xy 50.454814 -307.207158) (xy 50.447448 -307.231034) (xy 50.449734 -307.24348) (xy 50.452217 -307.257445)
			(xy 50.454885 -307.285685) (xy 50.455068 -307.299868) (xy 73.593972 -307.299868) (xy 73.597932 -307.250814)
			(xy 73.609709 -307.20303) (xy 73.629 -307.157754) (xy 73.655303 -307.116158) (xy 73.687938 -307.079321)
			(xy 73.726059 -307.048196) (xy 73.76868 -307.023589) (xy 73.814696 -307.006137) (xy 73.862915 -306.996293)
			(xy 73.91209 -306.994312) (xy 73.960945 -307.000244) (xy 74.008216 -307.013936) (xy 74.052678 -307.035034)
			(xy 74.093181 -307.06299) (xy 74.128674 -307.097082) (xy 74.158239 -307.136426) (xy 74.18111 -307.180003)
			(xy 74.196694 -307.226684) (xy 74.204589 -307.275261) (xy 74.205084 -307.299868) (xy 74.544186 -307.299868)
			(xy 74.548146 -307.250814) (xy 74.559923 -307.20303) (xy 74.579214 -307.157754) (xy 74.605517 -307.116158)
			(xy 74.638152 -307.079321) (xy 74.676273 -307.048196) (xy 74.718894 -307.023589) (xy 74.76491 -307.006137)
			(xy 74.813129 -306.996293) (xy 74.862304 -306.994312) (xy 74.911159 -307.000244) (xy 74.95843 -307.013936)
			(xy 75.002892 -307.035034) (xy 75.043395 -307.06299) (xy 75.078888 -307.097082) (xy 75.108453 -307.136426)
			(xy 75.131324 -307.180003) (xy 75.146908 -307.226684) (xy 75.154803 -307.275261) (xy 75.155298 -307.299868)
			(xy 75.494146 -307.299868) (xy 75.498106 -307.250814) (xy 75.509883 -307.20303) (xy 75.529174 -307.157754)
			(xy 75.555477 -307.116158) (xy 75.588112 -307.079321) (xy 75.626233 -307.048196) (xy 75.668854 -307.023589)
			(xy 75.71487 -307.006137) (xy 75.763089 -306.996293) (xy 75.812264 -306.994312) (xy 75.861119 -307.000244)
			(xy 75.90839 -307.013936) (xy 75.952852 -307.035034) (xy 75.993355 -307.06299) (xy 76.028848 -307.097082)
			(xy 76.058413 -307.136426) (xy 76.081284 -307.180003) (xy 76.096868 -307.226684) (xy 76.104763 -307.275261)
			(xy 76.105258 -307.299868) (xy 76.104763 -307.324475) (xy 76.104584 -307.325576) (xy 76.423262 -307.325576)
			(xy 76.423262 -307.27416) (xy 76.431305 -307.223378) (xy 76.447193 -307.174479) (xy 76.470536 -307.128667)
			(xy 76.500757 -307.087071) (xy 76.537113 -307.050715) (xy 76.578709 -307.020494) (xy 76.624521 -306.997151)
			(xy 76.67342 -306.981263) (xy 76.724202 -306.97322) (xy 76.775618 -306.97322) (xy 76.8264 -306.981263)
			(xy 76.875299 -306.997151) (xy 76.921111 -307.020494) (xy 76.962707 -307.050715) (xy 76.999063 -307.087071)
			(xy 77.029284 -307.128667) (xy 77.052627 -307.174479) (xy 77.068515 -307.223378) (xy 77.076558 -307.27416)
			(xy 77.077062 -307.299868) (xy 77.076558 -307.325576) (xy 77.373222 -307.325576) (xy 77.373222 -307.27416)
			(xy 77.381265 -307.223378) (xy 77.397153 -307.174479) (xy 77.420496 -307.128667) (xy 77.450717 -307.087071)
			(xy 77.487073 -307.050715) (xy 77.528669 -307.020494) (xy 77.574481 -306.997151) (xy 77.62338 -306.981263)
			(xy 77.674162 -306.97322) (xy 77.725578 -306.97322) (xy 77.77636 -306.981263) (xy 77.825259 -306.997151)
			(xy 77.871071 -307.020494) (xy 77.912667 -307.050715) (xy 77.949023 -307.087071) (xy 77.979244 -307.128667)
			(xy 78.002587 -307.174479) (xy 78.018475 -307.223378) (xy 78.026518 -307.27416) (xy 78.027022 -307.299868)
			(xy 78.026518 -307.325576) (xy 78.018475 -307.376358) (xy 78.002587 -307.425257) (xy 77.979244 -307.471069)
			(xy 77.949023 -307.512665) (xy 77.912667 -307.549021) (xy 77.871071 -307.579242) (xy 77.825259 -307.602585)
			(xy 77.77636 -307.618473) (xy 77.725578 -307.626516) (xy 77.674162 -307.626516) (xy 77.62338 -307.618473)
			(xy 77.574481 -307.602585) (xy 77.528669 -307.579242) (xy 77.487073 -307.549021) (xy 77.450717 -307.512665)
			(xy 77.420496 -307.471069) (xy 77.397153 -307.425257) (xy 77.381265 -307.376358) (xy 77.373222 -307.325576)
			(xy 77.076558 -307.325576) (xy 77.068515 -307.376358) (xy 77.052627 -307.425257) (xy 77.029284 -307.471069)
			(xy 76.999063 -307.512665) (xy 76.962707 -307.549021) (xy 76.921111 -307.579242) (xy 76.875299 -307.602585)
			(xy 76.8264 -307.618473) (xy 76.775618 -307.626516) (xy 76.724202 -307.626516) (xy 76.67342 -307.618473)
			(xy 76.624521 -307.602585) (xy 76.578709 -307.579242) (xy 76.537113 -307.549021) (xy 76.500757 -307.512665)
			(xy 76.470536 -307.471069) (xy 76.447193 -307.425257) (xy 76.431305 -307.376358) (xy 76.423262 -307.325576)
			(xy 76.104584 -307.325576) (xy 76.096868 -307.373052) (xy 76.081284 -307.419733) (xy 76.058413 -307.46331)
			(xy 76.028848 -307.502654) (xy 75.993355 -307.536746) (xy 75.952852 -307.564702) (xy 75.90839 -307.5858)
			(xy 75.861119 -307.599492) (xy 75.812264 -307.605424) (xy 75.763089 -307.603443) (xy 75.71487 -307.593599)
			(xy 75.668854 -307.576147) (xy 75.626233 -307.55154) (xy 75.588112 -307.520415) (xy 75.555477 -307.483578)
			(xy 75.529174 -307.441982) (xy 75.509883 -307.396706) (xy 75.498106 -307.348922) (xy 75.494146 -307.299868)
			(xy 75.155298 -307.299868) (xy 75.154803 -307.324475) (xy 75.146908 -307.373052) (xy 75.131324 -307.419733)
			(xy 75.108453 -307.46331) (xy 75.078888 -307.502654) (xy 75.043395 -307.536746) (xy 75.002892 -307.564702)
			(xy 74.95843 -307.5858) (xy 74.911159 -307.599492) (xy 74.862304 -307.605424) (xy 74.813129 -307.603443)
			(xy 74.76491 -307.593599) (xy 74.718894 -307.576147) (xy 74.676273 -307.55154) (xy 74.638152 -307.520415)
			(xy 74.605517 -307.483578) (xy 74.579214 -307.441982) (xy 74.559923 -307.396706) (xy 74.548146 -307.348922)
			(xy 74.544186 -307.299868) (xy 74.205084 -307.299868) (xy 74.204589 -307.324475) (xy 74.196694 -307.373052)
			(xy 74.18111 -307.419733) (xy 74.158239 -307.46331) (xy 74.128674 -307.502654) (xy 74.093181 -307.536746)
			(xy 74.052678 -307.564702) (xy 74.008216 -307.5858) (xy 73.960945 -307.599492) (xy 73.91209 -307.605424)
			(xy 73.862915 -307.603443) (xy 73.814696 -307.593599) (xy 73.76868 -307.576147) (xy 73.726059 -307.55154)
			(xy 73.687938 -307.520415) (xy 73.655303 -307.483578) (xy 73.629 -307.441982) (xy 73.609709 -307.396706)
			(xy 73.597932 -307.348922) (xy 73.593972 -307.299868) (xy 50.455068 -307.299868) (xy 50.454546 -307.325123)
			(xy 50.446233 -307.374945) (xy 50.429832 -307.422719) (xy 50.405791 -307.467142) (xy 50.374767 -307.507002)
			(xy 50.337605 -307.541212) (xy 50.295319 -307.568838) (xy 50.249063 -307.589128) (xy 50.200098 -307.601528)
			(xy 50.14976 -307.605699) (xy 50.099422 -307.601528) (xy 50.050457 -307.589128) (xy 50.004201 -307.568838)
			(xy 49.961915 -307.541212) (xy 49.924753 -307.507002) (xy 49.893729 -307.467142) (xy 49.869688 -307.422719)
			(xy 49.853287 -307.374945) (xy 49.844974 -307.325123) (xy 49.844452 -307.299868) (xy 49.844625 -307.285685)
			(xy 49.8473 -307.257445) (xy 49.849786 -307.24348) (xy 49.852072 -307.231034) (xy 49.844706 -307.207412)
			(xy 49.767236 -307.129942) (xy 49.743614 -307.122576) (xy 49.731168 -307.124862) (xy 49.717202 -307.127339)
			(xy 49.688963 -307.13001) (xy 49.67478 -307.130196) (xy 49.660597 -307.130022) (xy 49.632357 -307.127348)
			(xy 49.618392 -307.124862) (xy 49.605946 -307.122576) (xy 49.582324 -307.129942) (xy 49.504854 -307.207412)
			(xy 49.497488 -307.231034) (xy 49.499774 -307.24348) (xy 49.502257 -307.257445) (xy 49.504925 -307.285685)
			(xy 49.505108 -307.299868) (xy 49.504586 -307.325123) (xy 49.496273 -307.374945) (xy 49.479872 -307.422719)
			(xy 49.455831 -307.467142) (xy 49.424807 -307.507002) (xy 49.387645 -307.541212) (xy 49.345359 -307.568838)
			(xy 49.299103 -307.589128) (xy 49.250138 -307.601528) (xy 49.1998 -307.605699) (xy 49.149462 -307.601528)
			(xy 49.100497 -307.589128) (xy 49.054241 -307.568838) (xy 49.011955 -307.541212) (xy 48.974793 -307.507002)
			(xy 48.943769 -307.467142) (xy 48.919728 -307.422719) (xy 48.903327 -307.374945) (xy 48.895014 -307.325123)
			(xy 48.894492 -307.299868) (xy 48.894664 -307.285685) (xy 48.897339 -307.257445) (xy 48.899826 -307.24348)
			(xy 48.902112 -307.231034) (xy 48.894746 -307.207412) (xy 48.817276 -307.129942) (xy 48.793654 -307.122576)
			(xy 48.781208 -307.124862) (xy 48.767241 -307.127333) (xy 48.739002 -307.130009) (xy 48.72482 -307.130196)
			(xy 48.710637 -307.130017) (xy 48.682397 -307.127346) (xy 48.668432 -307.124862) (xy 48.655986 -307.122576)
			(xy 48.632364 -307.129942) (xy 48.554894 -307.207412) (xy 48.547528 -307.231034) (xy 48.549814 -307.24348)
			(xy 48.552298 -307.257445) (xy 48.554965 -307.285685) (xy 48.555148 -307.299868) (xy 48.554657 -307.324693)
			(xy 48.546629 -307.373689) (xy 48.53078 -307.420741) (xy 48.507527 -307.464608) (xy 48.477484 -307.504136)
			(xy 48.441441 -307.538282) (xy 48.400348 -307.566147) (xy 48.355288 -307.586996) (xy 48.307449 -307.600281)
			(xy 48.258091 -307.605651) (xy 48.208514 -307.602964) (xy 48.160026 -307.592291) (xy 48.113902 -307.573915)
			(xy 48.07136 -307.548318) (xy 48.033519 -307.516175) (xy 48.001378 -307.478334) (xy 47.975782 -307.43579)
			(xy 47.957406 -307.389667) (xy 47.946735 -307.341178) (xy 47.94405 -307.291601) (xy 47.605022 -307.291601)
			(xy 47.605188 -307.299868) (xy 47.604693 -307.324475) (xy 47.596798 -307.373052) (xy 47.581214 -307.419733)
			(xy 47.558343 -307.46331) (xy 47.528778 -307.502654) (xy 47.493285 -307.536746) (xy 47.452782 -307.564702)
			(xy 47.40832 -307.5858) (xy 47.361049 -307.599492) (xy 47.312194 -307.605424) (xy 47.263019 -307.603443)
			(xy 47.2148 -307.593599) (xy 47.168784 -307.576147) (xy 47.126163 -307.55154) (xy 47.088042 -307.520415)
			(xy 47.055407 -307.483578) (xy 47.029104 -307.441982) (xy 47.009813 -307.396706) (xy 46.998036 -307.348922)
			(xy 46.994076 -307.299868) (xy 46.655228 -307.299868) (xy 46.654733 -307.324475) (xy 46.646838 -307.373052)
			(xy 46.631254 -307.419733) (xy 46.608383 -307.46331) (xy 46.578818 -307.502654) (xy 46.543325 -307.536746)
			(xy 46.502822 -307.564702) (xy 46.45836 -307.5858) (xy 46.411089 -307.599492) (xy 46.362234 -307.605424)
			(xy 46.313059 -307.603443) (xy 46.26484 -307.593599) (xy 46.218824 -307.576147) (xy 46.176203 -307.55154)
			(xy 46.138082 -307.520415) (xy 46.105447 -307.483578) (xy 46.079144 -307.441982) (xy 46.059853 -307.396706)
			(xy 46.048076 -307.348922) (xy 46.044116 -307.299868) (xy 45.705268 -307.299868) (xy 45.704773 -307.324475)
			(xy 45.696878 -307.373052) (xy 45.681294 -307.419733) (xy 45.658423 -307.46331) (xy 45.628858 -307.502654)
			(xy 45.593365 -307.536746) (xy 45.552862 -307.564702) (xy 45.5084 -307.5858) (xy 45.461129 -307.599492)
			(xy 45.412274 -307.605424) (xy 45.363099 -307.603443) (xy 45.31488 -307.593599) (xy 45.268864 -307.576147)
			(xy 45.226243 -307.55154) (xy 45.188122 -307.520415) (xy 45.155487 -307.483578) (xy 45.129184 -307.441982)
			(xy 45.109893 -307.396706) (xy 45.098116 -307.348922) (xy 45.094156 -307.299868) (xy 44.755054 -307.299868)
			(xy 44.754559 -307.324475) (xy 44.746664 -307.373052) (xy 44.73108 -307.419733) (xy 44.708209 -307.46331)
			(xy 44.678644 -307.502654) (xy 44.643151 -307.536746) (xy 44.602648 -307.564702) (xy 44.558186 -307.5858)
			(xy 44.510915 -307.599492) (xy 44.46206 -307.605424) (xy 44.412885 -307.603443) (xy 44.364666 -307.593599)
			(xy 44.31865 -307.576147) (xy 44.276029 -307.55154) (xy 44.237908 -307.520415) (xy 44.205273 -307.483578)
			(xy 44.17897 -307.441982) (xy 44.159679 -307.396706) (xy 44.147902 -307.348922) (xy 44.143942 -307.299868)
			(xy 43.805094 -307.299868) (xy 43.804599 -307.324475) (xy 43.796704 -307.373052) (xy 43.78112 -307.419733)
			(xy 43.758249 -307.46331) (xy 43.728684 -307.502654) (xy 43.693191 -307.536746) (xy 43.652688 -307.564702)
			(xy 43.608226 -307.5858) (xy 43.560955 -307.599492) (xy 43.5121 -307.605424) (xy 43.462925 -307.603443)
			(xy 43.414706 -307.593599) (xy 43.36869 -307.576147) (xy 43.326069 -307.55154) (xy 43.287948 -307.520415)
			(xy 43.255313 -307.483578) (xy 43.22901 -307.441982) (xy 43.209719 -307.396706) (xy 43.197942 -307.348922)
			(xy 43.193982 -307.299868) (xy 42.876978 -307.299868) (xy 42.876474 -307.325576) (xy 42.868431 -307.376358)
			(xy 42.852543 -307.425257) (xy 42.8292 -307.471069) (xy 42.798979 -307.512665) (xy 42.762623 -307.549021)
			(xy 42.721027 -307.579242) (xy 42.675215 -307.602585) (xy 42.626316 -307.618473) (xy 42.575534 -307.626516)
			(xy 42.524118 -307.626516) (xy 42.473336 -307.618473) (xy 42.424437 -307.602585) (xy 42.378625 -307.579242)
			(xy 42.337029 -307.549021) (xy 42.300673 -307.512665) (xy 42.270452 -307.471069) (xy 42.247109 -307.425257)
			(xy 42.231221 -307.376358) (xy 42.223178 -307.325576) (xy 41.926514 -307.325576) (xy 41.918471 -307.376358)
			(xy 41.902583 -307.425257) (xy 41.87924 -307.471069) (xy 41.849019 -307.512665) (xy 41.812663 -307.549021)
			(xy 41.771067 -307.579242) (xy 41.725255 -307.602585) (xy 41.676356 -307.618473) (xy 41.625574 -307.626516)
			(xy 41.574158 -307.626516) (xy 41.523376 -307.618473) (xy 41.474477 -307.602585) (xy 41.428665 -307.579242)
			(xy 41.387069 -307.549021) (xy 41.350713 -307.512665) (xy 41.320492 -307.471069) (xy 41.297149 -307.425257)
			(xy 41.281261 -307.376358) (xy 41.273218 -307.325576) (xy 40.95454 -307.325576) (xy 40.946824 -307.373052)
			(xy 40.93124 -307.419733) (xy 40.908369 -307.46331) (xy 40.878804 -307.502654) (xy 40.843311 -307.536746)
			(xy 40.802808 -307.564702) (xy 40.758346 -307.5858) (xy 40.711075 -307.599492) (xy 40.66222 -307.605424)
			(xy 40.613045 -307.603443) (xy 40.564826 -307.593599) (xy 40.51881 -307.576147) (xy 40.476189 -307.55154)
			(xy 40.438068 -307.520415) (xy 40.405433 -307.483578) (xy 40.37913 -307.441982) (xy 40.359839 -307.396706)
			(xy 40.348062 -307.348922) (xy 40.344102 -307.299868) (xy 40.027098 -307.299868) (xy 40.026594 -307.325576)
			(xy 40.018551 -307.376358) (xy 40.002663 -307.425257) (xy 39.97932 -307.471069) (xy 39.949099 -307.512665)
			(xy 39.912743 -307.549021) (xy 39.871147 -307.579242) (xy 39.825335 -307.602585) (xy 39.776436 -307.618473)
			(xy 39.725654 -307.626516) (xy 39.674238 -307.626516) (xy 39.623456 -307.618473) (xy 39.574557 -307.602585)
			(xy 39.528745 -307.579242) (xy 39.487149 -307.549021) (xy 39.450793 -307.512665) (xy 39.420572 -307.471069)
			(xy 39.397229 -307.425257) (xy 39.381341 -307.376358) (xy 39.373298 -307.325576) (xy 39.076634 -307.325576)
			(xy 39.068591 -307.376358) (xy 39.052703 -307.425257) (xy 39.02936 -307.471069) (xy 38.999139 -307.512665)
			(xy 38.962783 -307.549021) (xy 38.921187 -307.579242) (xy 38.875375 -307.602585) (xy 38.826476 -307.618473)
			(xy 38.775694 -307.626516) (xy 38.724278 -307.626516) (xy 38.673496 -307.618473) (xy 38.624597 -307.602585)
			(xy 38.578785 -307.579242) (xy 38.537189 -307.549021) (xy 38.500833 -307.512665) (xy 38.470612 -307.471069)
			(xy 38.447269 -307.425257) (xy 38.431381 -307.376358) (xy 38.423338 -307.325576) (xy 38.104406 -307.325576)
			(xy 38.09669 -307.373052) (xy 38.081106 -307.419733) (xy 38.058235 -307.46331) (xy 38.02867 -307.502654)
			(xy 37.993177 -307.536746) (xy 37.952674 -307.564702) (xy 37.908212 -307.5858) (xy 37.860941 -307.599492)
			(xy 37.812086 -307.605424) (xy 37.762911 -307.603443) (xy 37.714692 -307.593599) (xy 37.668676 -307.576147)
			(xy 37.626055 -307.55154) (xy 37.587934 -307.520415) (xy 37.555299 -307.483578) (xy 37.528996 -307.441982)
			(xy 37.509705 -307.396706) (xy 37.497928 -307.348922) (xy 37.493968 -307.299868) (xy 37.15512 -307.299868)
			(xy 37.154625 -307.324475) (xy 37.14673 -307.373052) (xy 37.131146 -307.419733) (xy 37.108275 -307.46331)
			(xy 37.07871 -307.502654) (xy 37.043217 -307.536746) (xy 37.002714 -307.564702) (xy 36.958252 -307.5858)
			(xy 36.910981 -307.599492) (xy 36.862126 -307.605424) (xy 36.812951 -307.603443) (xy 36.764732 -307.593599)
			(xy 36.718716 -307.576147) (xy 36.676095 -307.55154) (xy 36.637974 -307.520415) (xy 36.605339 -307.483578)
			(xy 36.579036 -307.441982) (xy 36.559745 -307.396706) (xy 36.547968 -307.348922) (xy 36.544008 -307.299868)
			(xy 32.618317 -307.299868) (xy 32.614877 -307.32324) (xy 32.598809 -307.376647) (xy 32.575137 -307.427144)
			(xy 32.544364 -307.473657) (xy 32.507147 -307.515194) (xy 32.464279 -307.550869) (xy 32.416673 -307.579923)
			(xy 32.365344 -307.601735) (xy 32.311387 -307.615841) (xy 32.25595 -307.621941) (xy 32.200216 -307.619904)
			(xy 32.145373 -307.609774) (xy 32.092589 -307.591767) (xy 32.042989 -307.566266) (xy 31.997631 -307.533815)
			(xy 31.957482 -307.495106) (xy 31.923396 -307.450963) (xy 31.8961 -307.402328) (xy 31.876177 -307.350237)
			(xy 31.864051 -307.2958) (xy 31.85998 -307.240178) (xy 17.71396 -307.240178) (xy 17.71396 -307.824886)
			(xy 17.714214 -307.827172) (xy 17.715738 -307.861716) (xy 17.714214 -307.89626) (xy 17.71396 -307.898546)
			(xy 17.71396 -308.450488) (xy 28.078174 -308.450488) (xy 28.082245 -308.394866) (xy 28.094371 -308.340429)
			(xy 28.114294 -308.288338) (xy 28.14159 -308.239703) (xy 28.175676 -308.19556) (xy 28.215825 -308.156851)
			(xy 28.261183 -308.1244) (xy 28.310783 -308.098899) (xy 28.363567 -308.080892) (xy 28.41841 -308.070762)
			(xy 28.474144 -308.068725) (xy 28.529581 -308.074825) (xy 28.583538 -308.088931) (xy 28.634867 -308.110743)
			(xy 28.682473 -308.139797) (xy 28.725341 -308.175472) (xy 28.762558 -308.217009) (xy 28.784439 -308.250082)
			(xy 35.593794 -308.250082) (xy 35.597754 -308.201028) (xy 35.609531 -308.153244) (xy 35.628822 -308.107968)
			(xy 35.655125 -308.066372) (xy 35.68776 -308.029535) (xy 35.725881 -307.99841) (xy 35.768502 -307.973803)
			(xy 35.814518 -307.956351) (xy 35.862737 -307.946507) (xy 35.911912 -307.944526) (xy 35.960767 -307.950458)
			(xy 36.008038 -307.96415) (xy 36.0525 -307.985248) (xy 36.093003 -308.013204) (xy 36.128496 -308.047296)
			(xy 36.158061 -308.08664) (xy 36.180932 -308.130217) (xy 36.196516 -308.176898) (xy 36.204411 -308.225475)
			(xy 36.204906 -308.250082) (xy 36.204411 -308.274689) (xy 36.204273 -308.275536) (xy 36.523164 -308.275536)
			(xy 36.523164 -308.22412) (xy 36.531207 -308.173338) (xy 36.547095 -308.124439) (xy 36.570438 -308.078627)
			(xy 36.600659 -308.037031) (xy 36.637015 -308.000675) (xy 36.678611 -307.970454) (xy 36.724423 -307.947111)
			(xy 36.773322 -307.931223) (xy 36.824104 -307.92318) (xy 36.87552 -307.92318) (xy 36.926302 -307.931223)
			(xy 36.975201 -307.947111) (xy 37.021013 -307.970454) (xy 37.062609 -308.000675) (xy 37.098965 -308.037031)
			(xy 37.129186 -308.078627) (xy 37.152529 -308.124439) (xy 37.168417 -308.173338) (xy 37.17646 -308.22412)
			(xy 37.176964 -308.249828) (xy 37.17646 -308.275536) (xy 37.473124 -308.275536) (xy 37.473124 -308.22412)
			(xy 37.481167 -308.173338) (xy 37.497055 -308.124439) (xy 37.520398 -308.078627) (xy 37.550619 -308.037031)
			(xy 37.586975 -308.000675) (xy 37.628571 -307.970454) (xy 37.674383 -307.947111) (xy 37.723282 -307.931223)
			(xy 37.774064 -307.92318) (xy 37.82548 -307.92318) (xy 37.876262 -307.931223) (xy 37.925161 -307.947111)
			(xy 37.970973 -307.970454) (xy 38.012569 -308.000675) (xy 38.048925 -308.037031) (xy 38.079146 -308.078627)
			(xy 38.102489 -308.124439) (xy 38.118377 -308.173338) (xy 38.12642 -308.22412) (xy 38.126924 -308.249828)
			(xy 38.444182 -308.249828) (xy 38.448142 -308.200774) (xy 38.459919 -308.15299) (xy 38.47921 -308.107714)
			(xy 38.505513 -308.066118) (xy 38.538148 -308.029281) (xy 38.576269 -307.998156) (xy 38.61889 -307.973549)
			(xy 38.664906 -307.956097) (xy 38.713125 -307.946253) (xy 38.7623 -307.944272) (xy 38.811155 -307.950204)
			(xy 38.858426 -307.963896) (xy 38.902888 -307.984994) (xy 38.943391 -308.01295) (xy 38.978884 -308.047042)
			(xy 39.008449 -308.086386) (xy 39.03132 -308.129963) (xy 39.046904 -308.176644) (xy 39.054799 -308.225221)
			(xy 39.055294 -308.249828) (xy 39.394142 -308.249828) (xy 39.398102 -308.200774) (xy 39.409879 -308.15299)
			(xy 39.42917 -308.107714) (xy 39.455473 -308.066118) (xy 39.488108 -308.029281) (xy 39.526229 -307.998156)
			(xy 39.56885 -307.973549) (xy 39.614866 -307.956097) (xy 39.663085 -307.946253) (xy 39.71226 -307.944272)
			(xy 39.761115 -307.950204) (xy 39.808386 -307.963896) (xy 39.852848 -307.984994) (xy 39.893351 -308.01295)
			(xy 39.928844 -308.047042) (xy 39.958409 -308.086386) (xy 39.98128 -308.129963) (xy 39.996864 -308.176644)
			(xy 40.004759 -308.225221) (xy 40.005254 -308.249828) (xy 40.344102 -308.249828) (xy 40.348062 -308.200774)
			(xy 40.359839 -308.15299) (xy 40.37913 -308.107714) (xy 40.405433 -308.066118) (xy 40.438068 -308.029281)
			(xy 40.476189 -307.998156) (xy 40.51881 -307.973549) (xy 40.564826 -307.956097) (xy 40.613045 -307.946253)
			(xy 40.66222 -307.944272) (xy 40.711075 -307.950204) (xy 40.758346 -307.963896) (xy 40.802808 -307.984994)
			(xy 40.843311 -308.01295) (xy 40.878804 -308.047042) (xy 40.908369 -308.086386) (xy 40.93124 -308.129963)
			(xy 40.946824 -308.176644) (xy 40.954719 -308.225221) (xy 40.955214 -308.249828) (xy 41.294062 -308.249828)
			(xy 41.298022 -308.200774) (xy 41.309799 -308.15299) (xy 41.32909 -308.107714) (xy 41.355393 -308.066118)
			(xy 41.388028 -308.029281) (xy 41.426149 -307.998156) (xy 41.46877 -307.973549) (xy 41.514786 -307.956097)
			(xy 41.563005 -307.946253) (xy 41.61218 -307.944272) (xy 41.661035 -307.950204) (xy 41.708306 -307.963896)
			(xy 41.752768 -307.984994) (xy 41.793271 -308.01295) (xy 41.828764 -308.047042) (xy 41.858329 -308.086386)
			(xy 41.8812 -308.129963) (xy 41.896784 -308.176644) (xy 41.904679 -308.225221) (xy 41.905174 -308.249828)
			(xy 42.244022 -308.249828) (xy 42.247982 -308.200774) (xy 42.259759 -308.15299) (xy 42.27905 -308.107714)
			(xy 42.305353 -308.066118) (xy 42.337988 -308.029281) (xy 42.376109 -307.998156) (xy 42.41873 -307.973549)
			(xy 42.464746 -307.956097) (xy 42.512965 -307.946253) (xy 42.56214 -307.944272) (xy 42.610995 -307.950204)
			(xy 42.658266 -307.963896) (xy 42.702728 -307.984994) (xy 42.743231 -308.01295) (xy 42.778724 -308.047042)
			(xy 42.808289 -308.086386) (xy 42.83116 -308.129963) (xy 42.846744 -308.176644) (xy 42.854639 -308.225221)
			(xy 42.855134 -308.249828) (xy 42.854639 -308.274435) (xy 42.85446 -308.275536) (xy 43.173138 -308.275536)
			(xy 43.173138 -308.22412) (xy 43.181181 -308.173338) (xy 43.197069 -308.124439) (xy 43.220412 -308.078627)
			(xy 43.250633 -308.037031) (xy 43.286989 -308.000675) (xy 43.328585 -307.970454) (xy 43.374397 -307.947111)
			(xy 43.423296 -307.931223) (xy 43.474078 -307.92318) (xy 43.525494 -307.92318) (xy 43.576276 -307.931223)
			(xy 43.625175 -307.947111) (xy 43.670987 -307.970454) (xy 43.712583 -308.000675) (xy 43.748939 -308.037031)
			(xy 43.77916 -308.078627) (xy 43.802503 -308.124439) (xy 43.818391 -308.173338) (xy 43.826434 -308.22412)
			(xy 43.826938 -308.249828) (xy 43.826434 -308.275536) (xy 44.123098 -308.275536) (xy 44.123098 -308.22412)
			(xy 44.131141 -308.173338) (xy 44.147029 -308.124439) (xy 44.170372 -308.078627) (xy 44.200593 -308.037031)
			(xy 44.236949 -308.000675) (xy 44.278545 -307.970454) (xy 44.324357 -307.947111) (xy 44.373256 -307.931223)
			(xy 44.424038 -307.92318) (xy 44.475454 -307.92318) (xy 44.526236 -307.931223) (xy 44.575135 -307.947111)
			(xy 44.620947 -307.970454) (xy 44.662543 -308.000675) (xy 44.698899 -308.037031) (xy 44.72912 -308.078627)
			(xy 44.752463 -308.124439) (xy 44.768351 -308.173338) (xy 44.776394 -308.22412) (xy 44.776898 -308.249828)
			(xy 45.094156 -308.249828) (xy 45.098116 -308.200774) (xy 45.109893 -308.15299) (xy 45.129184 -308.107714)
			(xy 45.155487 -308.066118) (xy 45.188122 -308.029281) (xy 45.226243 -307.998156) (xy 45.268864 -307.973549)
			(xy 45.31488 -307.956097) (xy 45.363099 -307.946253) (xy 45.412274 -307.944272) (xy 45.461129 -307.950204)
			(xy 45.5084 -307.963896) (xy 45.552862 -307.984994) (xy 45.593365 -308.01295) (xy 45.628858 -308.047042)
			(xy 45.658423 -308.086386) (xy 45.681294 -308.129963) (xy 45.696878 -308.176644) (xy 45.704773 -308.225221)
			(xy 45.705268 -308.249828) (xy 46.044116 -308.249828) (xy 46.048076 -308.200774) (xy 46.059853 -308.15299)
			(xy 46.079144 -308.107714) (xy 46.105447 -308.066118) (xy 46.138082 -308.029281) (xy 46.176203 -307.998156)
			(xy 46.218824 -307.973549) (xy 46.26484 -307.956097) (xy 46.313059 -307.946253) (xy 46.362234 -307.944272)
			(xy 46.411089 -307.950204) (xy 46.45836 -307.963896) (xy 46.502822 -307.984994) (xy 46.543325 -308.01295)
			(xy 46.578818 -308.047042) (xy 46.608383 -308.086386) (xy 46.631254 -308.129963) (xy 46.646838 -308.176644)
			(xy 46.654733 -308.225221) (xy 46.655228 -308.249828) (xy 46.994076 -308.249828) (xy 46.998036 -308.200774)
			(xy 47.009813 -308.15299) (xy 47.029104 -308.107714) (xy 47.055407 -308.066118) (xy 47.088042 -308.029281)
			(xy 47.126163 -307.998156) (xy 47.168784 -307.973549) (xy 47.2148 -307.956097) (xy 47.263019 -307.946253)
			(xy 47.312194 -307.944272) (xy 47.361049 -307.950204) (xy 47.40832 -307.963896) (xy 47.452782 -307.984994)
			(xy 47.493285 -308.01295) (xy 47.528778 -308.047042) (xy 47.558343 -308.086386) (xy 47.581214 -308.129963)
			(xy 47.596798 -308.176644) (xy 47.604693 -308.225221) (xy 47.605188 -308.249828) (xy 47.944036 -308.249828)
			(xy 47.947996 -308.200774) (xy 47.959773 -308.15299) (xy 47.979064 -308.107714) (xy 48.005367 -308.066118)
			(xy 48.038002 -308.029281) (xy 48.076123 -307.998156) (xy 48.118744 -307.973549) (xy 48.16476 -307.956097)
			(xy 48.212979 -307.946253) (xy 48.262154 -307.944272) (xy 48.311009 -307.950204) (xy 48.35828 -307.963896)
			(xy 48.402742 -307.984994) (xy 48.443245 -308.01295) (xy 48.478738 -308.047042) (xy 48.508303 -308.086386)
			(xy 48.531174 -308.129963) (xy 48.546758 -308.176644) (xy 48.554653 -308.225221) (xy 48.555148 -308.249828)
			(xy 48.554982 -308.258073) (xy 48.894081 -308.258073) (xy 48.89677 -308.208503) (xy 48.907443 -308.160021)
			(xy 48.92582 -308.113905) (xy 48.951415 -308.071369) (xy 48.983555 -308.033535) (xy 49.021392 -308.001399)
			(xy 49.06393 -307.975807) (xy 49.110048 -307.957435) (xy 49.158531 -307.946766) (xy 49.208101 -307.944082)
			(xy 49.257452 -307.949452) (xy 49.305284 -307.962736) (xy 49.350337 -307.983584) (xy 49.391424 -308.011445)
			(xy 49.427462 -308.045587) (xy 49.457501 -308.08511) (xy 49.48075 -308.128972) (xy 49.496597 -308.176017)
			(xy 49.504624 -308.225007) (xy 49.505108 -308.249828) (xy 49.504935 -308.264011) (xy 49.502261 -308.292251)
			(xy 49.499774 -308.306216) (xy 49.497488 -308.318662) (xy 49.504854 -308.342284) (xy 49.582324 -308.419754)
			(xy 49.605946 -308.42712) (xy 49.618392 -308.424834) (xy 49.632359 -308.422363) (xy 49.660598 -308.419687)
			(xy 49.67478 -308.4195) (xy 49.698773 -308.419957) (xy 49.746169 -308.427461) (xy 49.791807 -308.442287)
			(xy 49.834563 -308.464071) (xy 49.873386 -308.492275) (xy 49.907317 -308.526205) (xy 49.935523 -308.565027)
			(xy 49.957308 -308.607782) (xy 49.972137 -308.65342) (xy 49.979642 -308.700815) (xy 49.980088 -308.724808)
			(xy 49.979913 -308.738991) (xy 49.97724 -308.767231) (xy 49.974754 -308.781196) (xy 49.972468 -308.793642)
			(xy 49.979834 -308.817264) (xy 50.057304 -308.894734) (xy 50.080926 -308.9021) (xy 50.093372 -308.899814)
			(xy 50.107337 -308.897332) (xy 50.135577 -308.894664) (xy 50.14976 -308.89448) (xy 50.174585 -308.894935)
			(xy 50.223582 -308.902961) (xy 50.270635 -308.918809) (xy 50.314504 -308.94206) (xy 50.354033 -308.972103)
			(xy 50.388181 -309.008145) (xy 50.416048 -309.049237) (xy 50.436899 -309.094297) (xy 50.450186 -309.142136)
			(xy 50.455558 -309.191494) (xy 50.455556 -309.191539) (xy 50.794269 -309.191539) (xy 50.799632 -309.142187)
			(xy 50.81291 -309.094352) (xy 50.833751 -309.049296) (xy 50.861607 -309.008205) (xy 50.895744 -308.972161)
			(xy 50.935262 -308.942115) (xy 50.979121 -308.918858) (xy 51.026164 -308.903003) (xy 51.075152 -308.894968)
			(xy 51.099974 -308.89448) (xy 51.114157 -308.89466) (xy 51.142397 -308.89733) (xy 51.156362 -308.899814)
			(xy 51.168808 -308.9021) (xy 51.19243 -308.894734) (xy 51.2699 -308.817264) (xy 51.277266 -308.793642)
			(xy 51.27498 -308.781196) (xy 51.272507 -308.76723) (xy 51.269833 -308.73899) (xy 51.269646 -308.724808)
			(xy 51.269825 -308.710625) (xy 51.272495 -308.682385) (xy 51.27498 -308.66842) (xy 51.277266 -308.655974)
			(xy 51.2699 -308.632352) (xy 51.19243 -308.554882) (xy 51.168808 -308.547516) (xy 51.156362 -308.549802)
			(xy 51.142396 -308.55228) (xy 51.114157 -308.554951) (xy 51.099974 -308.555136) (xy 51.075155 -308.554594)
			(xy 51.026172 -308.546559) (xy 50.979134 -308.530706) (xy 50.935281 -308.507452) (xy 50.895768 -308.477409)
			(xy 50.861635 -308.441369) (xy 50.833783 -308.400282) (xy 50.812944 -308.355231) (xy 50.799669 -308.307401)
			(xy 50.794306 -308.258054) (xy 50.796998 -308.20849) (xy 50.807673 -308.160014) (xy 50.82605 -308.113903)
			(xy 50.851644 -308.071373) (xy 50.883782 -308.033544) (xy 50.921617 -308.001413) (xy 50.964152 -307.975826)
			(xy 51.010265 -307.957457) (xy 51.058743 -307.946791) (xy 51.108308 -307.944108) (xy 51.157654 -307.949479)
			(xy 51.205482 -307.962763) (xy 51.25053 -307.983609) (xy 51.291611 -308.011469) (xy 51.327645 -308.045608)
			(xy 51.357681 -308.085127) (xy 51.380927 -308.128984) (xy 51.396772 -308.176025) (xy 51.404798 -308.225009)
			(xy 51.405282 -308.249828) (xy 51.40511 -308.264011) (xy 51.402435 -308.292251) (xy 51.399948 -308.306216)
			(xy 51.397662 -308.318662) (xy 51.405028 -308.342284) (xy 51.482498 -308.419754) (xy 51.50612 -308.42712)
			(xy 51.518566 -308.424834) (xy 51.532531 -308.422353) (xy 51.560771 -308.419684) (xy 51.574954 -308.4195)
			(xy 51.589137 -308.419683) (xy 51.617377 -308.422351) (xy 51.631342 -308.424834) (xy 51.643788 -308.42712)
			(xy 51.66741 -308.419754) (xy 51.74488 -308.342284) (xy 51.752246 -308.318662) (xy 51.74996 -308.306216)
			(xy 51.747477 -308.292251) (xy 51.744809 -308.264011) (xy 51.744626 -308.249828) (xy 51.745048 -308.225005)
			(xy 51.753075 -308.176012) (xy 51.768923 -308.128963) (xy 51.792173 -308.085098) (xy 51.822214 -308.045573)
			(xy 51.858254 -308.011428) (xy 51.899342 -307.983563) (xy 51.944398 -307.962713) (xy 51.992233 -307.949426)
			(xy 52.041588 -307.944054) (xy 52.091161 -307.946737) (xy 52.139647 -307.957404) (xy 52.185769 -307.975776)
			(xy 52.228311 -308.001367) (xy 52.266153 -308.033503) (xy 52.298297 -308.071338) (xy 52.323897 -308.113875)
			(xy 52.342277 -308.159993) (xy 52.352955 -308.208477) (xy 52.3552 -308.2498) (xy 52.694097 -308.2498)
			(xy 52.698268 -308.199467) (xy 52.710666 -308.150507) (xy 52.730953 -308.104256) (xy 52.758577 -308.061974)
			(xy 52.792783 -308.024816) (xy 52.832638 -307.993794) (xy 52.877056 -307.969756) (xy 52.924825 -307.953356)
			(xy 52.974641 -307.945042) (xy 52.999894 -307.94452) (xy 53.014077 -307.944697) (xy 53.042317 -307.947369)
			(xy 53.056282 -307.949854) (xy 53.068728 -307.95214) (xy 53.09235 -307.944774) (xy 53.16982 -307.867304)
			(xy 53.177186 -307.843682) (xy 53.1749 -307.831236) (xy 53.172419 -307.817271) (xy 53.16975 -307.789031)
			(xy 53.169566 -307.774848) (xy 53.170026 -307.750022) (xy 53.178051 -307.701023) (xy 53.193899 -307.653967)
			(xy 53.21715 -307.610096) (xy 53.247194 -307.570565) (xy 53.283237 -307.536415) (xy 53.32433 -307.508546)
			(xy 53.369391 -307.487693) (xy 53.417233 -307.474406) (xy 53.466593 -307.469033) (xy 53.516173 -307.471718)
			(xy 53.564665 -307.482388) (xy 53.610791 -307.500764) (xy 53.653337 -307.52636) (xy 53.691182 -307.558503)
			(xy 53.723327 -307.596345) (xy 53.748926 -307.638889) (xy 53.767305 -307.685014) (xy 53.777979 -307.733505)
			(xy 53.78022 -307.774848) (xy 54.11903 -307.774848) (xy 54.12299 -307.725794) (xy 54.134767 -307.67801)
			(xy 54.154058 -307.632734) (xy 54.180361 -307.591138) (xy 54.212996 -307.554301) (xy 54.251117 -307.523176)
			(xy 54.293738 -307.498569) (xy 54.339754 -307.481117) (xy 54.387973 -307.471273) (xy 54.437148 -307.469292)
			(xy 54.486003 -307.475224) (xy 54.533274 -307.488916) (xy 54.577736 -307.510014) (xy 54.618239 -307.53797)
			(xy 54.653732 -307.572062) (xy 54.683297 -307.611406) (xy 54.706168 -307.654983) (xy 54.721752 -307.701664)
			(xy 54.729647 -307.750241) (xy 54.730142 -307.774848) (xy 55.06899 -307.774848) (xy 55.07295 -307.725794)
			(xy 55.084727 -307.67801) (xy 55.104018 -307.632734) (xy 55.130321 -307.591138) (xy 55.162956 -307.554301)
			(xy 55.201077 -307.523176) (xy 55.243698 -307.498569) (xy 55.289714 -307.481117) (xy 55.337933 -307.471273)
			(xy 55.387108 -307.469292) (xy 55.435963 -307.475224) (xy 55.483234 -307.488916) (xy 55.527696 -307.510014)
			(xy 55.568199 -307.53797) (xy 55.603692 -307.572062) (xy 55.633257 -307.611406) (xy 55.656128 -307.654983)
			(xy 55.671712 -307.701664) (xy 55.679607 -307.750241) (xy 55.680102 -307.774848) (xy 56.019204 -307.774848)
			(xy 56.023164 -307.725794) (xy 56.034941 -307.67801) (xy 56.054232 -307.632734) (xy 56.080535 -307.591138)
			(xy 56.11317 -307.554301) (xy 56.151291 -307.523176) (xy 56.193912 -307.498569) (xy 56.239928 -307.481117)
			(xy 56.288147 -307.471273) (xy 56.337322 -307.469292) (xy 56.386177 -307.475224) (xy 56.433448 -307.488916)
			(xy 56.47791 -307.510014) (xy 56.518413 -307.53797) (xy 56.553906 -307.572062) (xy 56.583471 -307.611406)
			(xy 56.606342 -307.654983) (xy 56.621926 -307.701664) (xy 56.629821 -307.750241) (xy 56.630316 -307.774848)
			(xy 56.969164 -307.774848) (xy 56.973124 -307.725794) (xy 56.984901 -307.67801) (xy 57.004192 -307.632734)
			(xy 57.030495 -307.591138) (xy 57.06313 -307.554301) (xy 57.101251 -307.523176) (xy 57.143872 -307.498569)
			(xy 57.189888 -307.481117) (xy 57.238107 -307.471273) (xy 57.287282 -307.469292) (xy 57.336137 -307.475224)
			(xy 57.383408 -307.488916) (xy 57.42787 -307.510014) (xy 57.468373 -307.53797) (xy 57.503866 -307.572062)
			(xy 57.533431 -307.611406) (xy 57.556302 -307.654983) (xy 57.571886 -307.701664) (xy 57.579781 -307.750241)
			(xy 57.580276 -307.774848) (xy 57.919124 -307.774848) (xy 57.923084 -307.725794) (xy 57.934861 -307.67801)
			(xy 57.954152 -307.632734) (xy 57.980455 -307.591138) (xy 58.01309 -307.554301) (xy 58.051211 -307.523176)
			(xy 58.093832 -307.498569) (xy 58.139848 -307.481117) (xy 58.188067 -307.471273) (xy 58.237242 -307.469292)
			(xy 58.286097 -307.475224) (xy 58.333368 -307.488916) (xy 58.37783 -307.510014) (xy 58.418333 -307.53797)
			(xy 58.453826 -307.572062) (xy 58.483391 -307.611406) (xy 58.506262 -307.654983) (xy 58.521846 -307.701664)
			(xy 58.529741 -307.750241) (xy 58.530236 -307.774848) (xy 59.819044 -307.774848) (xy 59.823004 -307.725794)
			(xy 59.834781 -307.67801) (xy 59.854072 -307.632734) (xy 59.880375 -307.591138) (xy 59.91301 -307.554301)
			(xy 59.951131 -307.523176) (xy 59.993752 -307.498569) (xy 60.039768 -307.481117) (xy 60.087987 -307.471273)
			(xy 60.137162 -307.469292) (xy 60.186017 -307.475224) (xy 60.233288 -307.488916) (xy 60.27775 -307.510014)
			(xy 60.318253 -307.53797) (xy 60.353746 -307.572062) (xy 60.383311 -307.611406) (xy 60.406182 -307.654983)
			(xy 60.421766 -307.701664) (xy 60.429661 -307.750241) (xy 60.430156 -307.774848) (xy 60.769004 -307.774848)
			(xy 60.772964 -307.725794) (xy 60.784741 -307.67801) (xy 60.804032 -307.632734) (xy 60.830335 -307.591138)
			(xy 60.86297 -307.554301) (xy 60.901091 -307.523176) (xy 60.943712 -307.498569) (xy 60.989728 -307.481117)
			(xy 61.037947 -307.471273) (xy 61.087122 -307.469292) (xy 61.135977 -307.475224) (xy 61.183248 -307.488916)
			(xy 61.22771 -307.510014) (xy 61.268213 -307.53797) (xy 61.303706 -307.572062) (xy 61.333271 -307.611406)
			(xy 61.356142 -307.654983) (xy 61.371726 -307.701664) (xy 61.379621 -307.750241) (xy 61.380116 -307.774848)
			(xy 61.718964 -307.774848) (xy 61.722924 -307.725794) (xy 61.734701 -307.67801) (xy 61.753992 -307.632734)
			(xy 61.780295 -307.591138) (xy 61.81293 -307.554301) (xy 61.851051 -307.523176) (xy 61.893672 -307.498569)
			(xy 61.939688 -307.481117) (xy 61.987907 -307.471273) (xy 62.037082 -307.469292) (xy 62.085937 -307.475224)
			(xy 62.133208 -307.488916) (xy 62.17767 -307.510014) (xy 62.218173 -307.53797) (xy 62.253666 -307.572062)
			(xy 62.283231 -307.611406) (xy 62.306102 -307.654983) (xy 62.321686 -307.701664) (xy 62.329581 -307.750241)
			(xy 62.330071 -307.774594) (xy 62.668924 -307.774594) (xy 62.672884 -307.72554) (xy 62.684661 -307.677756)
			(xy 62.703952 -307.63248) (xy 62.730255 -307.590884) (xy 62.76289 -307.554047) (xy 62.801011 -307.522922)
			(xy 62.843632 -307.498315) (xy 62.889648 -307.480863) (xy 62.937867 -307.471019) (xy 62.987042 -307.469038)
			(xy 63.035897 -307.47497) (xy 63.083168 -307.488662) (xy 63.12763 -307.50976) (xy 63.168133 -307.537716)
			(xy 63.203626 -307.571808) (xy 63.233191 -307.611152) (xy 63.256062 -307.654729) (xy 63.271646 -307.70141)
			(xy 63.279541 -307.749987) (xy 63.280036 -307.774594) (xy 63.619138 -307.774594) (xy 63.623098 -307.72554)
			(xy 63.634875 -307.677756) (xy 63.654166 -307.63248) (xy 63.680469 -307.590884) (xy 63.713104 -307.554047)
			(xy 63.751225 -307.522922) (xy 63.793846 -307.498315) (xy 63.839862 -307.480863) (xy 63.888081 -307.471019)
			(xy 63.937256 -307.469038) (xy 63.986111 -307.47497) (xy 64.033382 -307.488662) (xy 64.077844 -307.50976)
			(xy 64.118347 -307.537716) (xy 64.15384 -307.571808) (xy 64.183405 -307.611152) (xy 64.206276 -307.654729)
			(xy 64.22186 -307.70141) (xy 64.229755 -307.749987) (xy 64.23025 -307.774594) (xy 64.230245 -307.774848)
			(xy 64.569098 -307.774848) (xy 64.573058 -307.725794) (xy 64.584835 -307.67801) (xy 64.604126 -307.632734)
			(xy 64.630429 -307.591138) (xy 64.663064 -307.554301) (xy 64.701185 -307.523176) (xy 64.743806 -307.498569)
			(xy 64.789822 -307.481117) (xy 64.838041 -307.471273) (xy 64.887216 -307.469292) (xy 64.936071 -307.475224)
			(xy 64.983342 -307.488916) (xy 65.027804 -307.510014) (xy 65.068307 -307.53797) (xy 65.1038 -307.572062)
			(xy 65.133365 -307.611406) (xy 65.156236 -307.654983) (xy 65.17182 -307.701664) (xy 65.179715 -307.750241)
			(xy 65.18021 -307.774848) (xy 65.519058 -307.774848) (xy 65.523018 -307.725794) (xy 65.534795 -307.67801)
			(xy 65.554086 -307.632734) (xy 65.580389 -307.591138) (xy 65.613024 -307.554301) (xy 65.651145 -307.523176)
			(xy 65.693766 -307.498569) (xy 65.739782 -307.481117) (xy 65.788001 -307.471273) (xy 65.837176 -307.469292)
			(xy 65.886031 -307.475224) (xy 65.933302 -307.488916) (xy 65.977764 -307.510014) (xy 66.018267 -307.53797)
			(xy 66.05376 -307.572062) (xy 66.083325 -307.611406) (xy 66.106196 -307.654983) (xy 66.12178 -307.701664)
			(xy 66.129675 -307.750241) (xy 66.13017 -307.774848) (xy 66.469018 -307.774848) (xy 66.472978 -307.725794)
			(xy 66.484755 -307.67801) (xy 66.504046 -307.632734) (xy 66.530349 -307.591138) (xy 66.562984 -307.554301)
			(xy 66.601105 -307.523176) (xy 66.643726 -307.498569) (xy 66.689742 -307.481117) (xy 66.737961 -307.471273)
			(xy 66.787136 -307.469292) (xy 66.835991 -307.475224) (xy 66.883262 -307.488916) (xy 66.927724 -307.510014)
			(xy 66.968227 -307.53797) (xy 67.00372 -307.572062) (xy 67.033285 -307.611406) (xy 67.056156 -307.654983)
			(xy 67.07174 -307.701664) (xy 67.079635 -307.750241) (xy 67.08013 -307.774848) (xy 67.418978 -307.774848)
			(xy 67.422938 -307.725794) (xy 67.434715 -307.67801) (xy 67.454006 -307.632734) (xy 67.480309 -307.591138)
			(xy 67.512944 -307.554301) (xy 67.551065 -307.523176) (xy 67.593686 -307.498569) (xy 67.639702 -307.481117)
			(xy 67.687921 -307.471273) (xy 67.737096 -307.469292) (xy 67.785951 -307.475224) (xy 67.833222 -307.488916)
			(xy 67.877684 -307.510014) (xy 67.918187 -307.53797) (xy 67.95368 -307.572062) (xy 67.983245 -307.611406)
			(xy 68.006116 -307.654983) (xy 68.0217 -307.701664) (xy 68.029595 -307.750241) (xy 68.03009 -307.774848)
			(xy 68.368938 -307.774848) (xy 68.372898 -307.725794) (xy 68.384675 -307.67801) (xy 68.403966 -307.632734)
			(xy 68.430269 -307.591138) (xy 68.462904 -307.554301) (xy 68.501025 -307.523176) (xy 68.543646 -307.498569)
			(xy 68.589662 -307.481117) (xy 68.637881 -307.471273) (xy 68.687056 -307.469292) (xy 68.735911 -307.475224)
			(xy 68.783182 -307.488916) (xy 68.827644 -307.510014) (xy 68.868147 -307.53797) (xy 68.90364 -307.572062)
			(xy 68.933205 -307.611406) (xy 68.956076 -307.654983) (xy 68.97166 -307.701664) (xy 68.979555 -307.750241)
			(xy 68.98005 -307.774848) (xy 69.319152 -307.774848) (xy 69.323112 -307.725794) (xy 69.334889 -307.67801)
			(xy 69.35418 -307.632734) (xy 69.380483 -307.591138) (xy 69.413118 -307.554301) (xy 69.451239 -307.523176)
			(xy 69.49386 -307.498569) (xy 69.539876 -307.481117) (xy 69.588095 -307.471273) (xy 69.63727 -307.469292)
			(xy 69.686125 -307.475224) (xy 69.733396 -307.488916) (xy 69.777858 -307.510014) (xy 69.818361 -307.53797)
			(xy 69.853854 -307.572062) (xy 69.883419 -307.611406) (xy 69.90629 -307.654983) (xy 69.921874 -307.701664)
			(xy 69.929769 -307.750241) (xy 69.930264 -307.774848) (xy 70.269112 -307.774848) (xy 70.273072 -307.725794)
			(xy 70.284849 -307.67801) (xy 70.30414 -307.632734) (xy 70.330443 -307.591138) (xy 70.363078 -307.554301)
			(xy 70.401199 -307.523176) (xy 70.44382 -307.498569) (xy 70.489836 -307.481117) (xy 70.538055 -307.471273)
			(xy 70.58723 -307.469292) (xy 70.636085 -307.475224) (xy 70.683356 -307.488916) (xy 70.727818 -307.510014)
			(xy 70.768321 -307.53797) (xy 70.803814 -307.572062) (xy 70.833379 -307.611406) (xy 70.85625 -307.654983)
			(xy 70.871834 -307.701664) (xy 70.879729 -307.750241) (xy 70.880224 -307.774848) (xy 71.219072 -307.774848)
			(xy 71.223032 -307.725794) (xy 71.234809 -307.67801) (xy 71.2541 -307.632734) (xy 71.280403 -307.591138)
			(xy 71.313038 -307.554301) (xy 71.351159 -307.523176) (xy 71.39378 -307.498569) (xy 71.439796 -307.481117)
			(xy 71.488015 -307.471273) (xy 71.53719 -307.469292) (xy 71.586045 -307.475224) (xy 71.633316 -307.488916)
			(xy 71.677778 -307.510014) (xy 71.718281 -307.53797) (xy 71.753774 -307.572062) (xy 71.783339 -307.611406)
			(xy 71.80621 -307.654983) (xy 71.821794 -307.701664) (xy 71.829689 -307.750241) (xy 71.830184 -307.774848)
			(xy 72.169032 -307.774848) (xy 72.172992 -307.725794) (xy 72.184769 -307.67801) (xy 72.20406 -307.632734)
			(xy 72.230363 -307.591138) (xy 72.262998 -307.554301) (xy 72.301119 -307.523176) (xy 72.34374 -307.498569)
			(xy 72.389756 -307.481117) (xy 72.437975 -307.471273) (xy 72.48715 -307.469292) (xy 72.536005 -307.475224)
			(xy 72.583276 -307.488916) (xy 72.627738 -307.510014) (xy 72.668241 -307.53797) (xy 72.703734 -307.572062)
			(xy 72.733299 -307.611406) (xy 72.75617 -307.654983) (xy 72.771754 -307.701664) (xy 72.779649 -307.750241)
			(xy 72.780144 -307.774848) (xy 72.779649 -307.799455) (xy 72.771754 -307.848032) (xy 72.75617 -307.894713)
			(xy 72.733299 -307.93829) (xy 72.703734 -307.977634) (xy 72.668241 -308.011726) (xy 72.627738 -308.039682)
			(xy 72.583276 -308.06078) (xy 72.536005 -308.074472) (xy 72.48715 -308.080404) (xy 72.437975 -308.078423)
			(xy 72.389756 -308.068579) (xy 72.34374 -308.051127) (xy 72.301119 -308.02652) (xy 72.262998 -307.995395)
			(xy 72.230363 -307.958558) (xy 72.20406 -307.916962) (xy 72.184769 -307.871686) (xy 72.172992 -307.823902)
			(xy 72.169032 -307.774848) (xy 71.830184 -307.774848) (xy 71.829689 -307.799455) (xy 71.821794 -307.848032)
			(xy 71.80621 -307.894713) (xy 71.783339 -307.93829) (xy 71.753774 -307.977634) (xy 71.718281 -308.011726)
			(xy 71.677778 -308.039682) (xy 71.633316 -308.06078) (xy 71.586045 -308.074472) (xy 71.53719 -308.080404)
			(xy 71.488015 -308.078423) (xy 71.439796 -308.068579) (xy 71.39378 -308.051127) (xy 71.351159 -308.02652)
			(xy 71.313038 -307.995395) (xy 71.280403 -307.958558) (xy 71.2541 -307.916962) (xy 71.234809 -307.871686)
			(xy 71.223032 -307.823902) (xy 71.219072 -307.774848) (xy 70.880224 -307.774848) (xy 70.879729 -307.799455)
			(xy 70.871834 -307.848032) (xy 70.85625 -307.894713) (xy 70.833379 -307.93829) (xy 70.803814 -307.977634)
			(xy 70.768321 -308.011726) (xy 70.727818 -308.039682) (xy 70.683356 -308.06078) (xy 70.636085 -308.074472)
			(xy 70.58723 -308.080404) (xy 70.538055 -308.078423) (xy 70.489836 -308.068579) (xy 70.44382 -308.051127)
			(xy 70.401199 -308.02652) (xy 70.363078 -307.995395) (xy 70.330443 -307.958558) (xy 70.30414 -307.916962)
			(xy 70.284849 -307.871686) (xy 70.273072 -307.823902) (xy 70.269112 -307.774848) (xy 69.930264 -307.774848)
			(xy 69.929769 -307.799455) (xy 69.921874 -307.848032) (xy 69.90629 -307.894713) (xy 69.883419 -307.93829)
			(xy 69.853854 -307.977634) (xy 69.818361 -308.011726) (xy 69.777858 -308.039682) (xy 69.733396 -308.06078)
			(xy 69.686125 -308.074472) (xy 69.63727 -308.080404) (xy 69.588095 -308.078423) (xy 69.539876 -308.068579)
			(xy 69.49386 -308.051127) (xy 69.451239 -308.02652) (xy 69.413118 -307.995395) (xy 69.380483 -307.958558)
			(xy 69.35418 -307.916962) (xy 69.334889 -307.871686) (xy 69.323112 -307.823902) (xy 69.319152 -307.774848)
			(xy 68.98005 -307.774848) (xy 68.979555 -307.799455) (xy 68.97166 -307.848032) (xy 68.956076 -307.894713)
			(xy 68.933205 -307.93829) (xy 68.90364 -307.977634) (xy 68.868147 -308.011726) (xy 68.827644 -308.039682)
			(xy 68.783182 -308.06078) (xy 68.735911 -308.074472) (xy 68.687056 -308.080404) (xy 68.637881 -308.078423)
			(xy 68.589662 -308.068579) (xy 68.543646 -308.051127) (xy 68.501025 -308.02652) (xy 68.462904 -307.995395)
			(xy 68.430269 -307.958558) (xy 68.403966 -307.916962) (xy 68.384675 -307.871686) (xy 68.372898 -307.823902)
			(xy 68.368938 -307.774848) (xy 68.03009 -307.774848) (xy 68.029595 -307.799455) (xy 68.0217 -307.848032)
			(xy 68.006116 -307.894713) (xy 67.983245 -307.93829) (xy 67.95368 -307.977634) (xy 67.918187 -308.011726)
			(xy 67.877684 -308.039682) (xy 67.833222 -308.06078) (xy 67.785951 -308.074472) (xy 67.737096 -308.080404)
			(xy 67.687921 -308.078423) (xy 67.639702 -308.068579) (xy 67.593686 -308.051127) (xy 67.551065 -308.02652)
			(xy 67.512944 -307.995395) (xy 67.480309 -307.958558) (xy 67.454006 -307.916962) (xy 67.434715 -307.871686)
			(xy 67.422938 -307.823902) (xy 67.418978 -307.774848) (xy 67.08013 -307.774848) (xy 67.079635 -307.799455)
			(xy 67.07174 -307.848032) (xy 67.056156 -307.894713) (xy 67.033285 -307.93829) (xy 67.00372 -307.977634)
			(xy 66.968227 -308.011726) (xy 66.927724 -308.039682) (xy 66.883262 -308.06078) (xy 66.835991 -308.074472)
			(xy 66.787136 -308.080404) (xy 66.737961 -308.078423) (xy 66.689742 -308.068579) (xy 66.643726 -308.051127)
			(xy 66.601105 -308.02652) (xy 66.562984 -307.995395) (xy 66.530349 -307.958558) (xy 66.504046 -307.916962)
			(xy 66.484755 -307.871686) (xy 66.472978 -307.823902) (xy 66.469018 -307.774848) (xy 66.13017 -307.774848)
			(xy 66.129675 -307.799455) (xy 66.12178 -307.848032) (xy 66.106196 -307.894713) (xy 66.083325 -307.93829)
			(xy 66.05376 -307.977634) (xy 66.018267 -308.011726) (xy 65.977764 -308.039682) (xy 65.933302 -308.06078)
			(xy 65.886031 -308.074472) (xy 65.837176 -308.080404) (xy 65.788001 -308.078423) (xy 65.739782 -308.068579)
			(xy 65.693766 -308.051127) (xy 65.651145 -308.02652) (xy 65.613024 -307.995395) (xy 65.580389 -307.958558)
			(xy 65.554086 -307.916962) (xy 65.534795 -307.871686) (xy 65.523018 -307.823902) (xy 65.519058 -307.774848)
			(xy 65.18021 -307.774848) (xy 65.179715 -307.799455) (xy 65.17182 -307.848032) (xy 65.156236 -307.894713)
			(xy 65.133365 -307.93829) (xy 65.1038 -307.977634) (xy 65.068307 -308.011726) (xy 65.027804 -308.039682)
			(xy 64.983342 -308.06078) (xy 64.936071 -308.074472) (xy 64.887216 -308.080404) (xy 64.838041 -308.078423)
			(xy 64.789822 -308.068579) (xy 64.743806 -308.051127) (xy 64.701185 -308.02652) (xy 64.663064 -307.995395)
			(xy 64.630429 -307.958558) (xy 64.604126 -307.916962) (xy 64.584835 -307.871686) (xy 64.573058 -307.823902)
			(xy 64.569098 -307.774848) (xy 64.230245 -307.774848) (xy 64.229755 -307.799201) (xy 64.22186 -307.847778)
			(xy 64.206276 -307.894459) (xy 64.183405 -307.938036) (xy 64.15384 -307.97738) (xy 64.118347 -308.011472)
			(xy 64.077844 -308.039428) (xy 64.033382 -308.060526) (xy 63.986111 -308.074218) (xy 63.937256 -308.08015)
			(xy 63.888081 -308.078169) (xy 63.839862 -308.068325) (xy 63.793846 -308.050873) (xy 63.751225 -308.026266)
			(xy 63.713104 -307.995141) (xy 63.680469 -307.958304) (xy 63.654166 -307.916708) (xy 63.634875 -307.871432)
			(xy 63.623098 -307.823648) (xy 63.619138 -307.774594) (xy 63.280036 -307.774594) (xy 63.279541 -307.799201)
			(xy 63.271646 -307.847778) (xy 63.256062 -307.894459) (xy 63.233191 -307.938036) (xy 63.203626 -307.97738)
			(xy 63.168133 -308.011472) (xy 63.12763 -308.039428) (xy 63.083168 -308.060526) (xy 63.035897 -308.074218)
			(xy 62.987042 -308.08015) (xy 62.937867 -308.078169) (xy 62.889648 -308.068325) (xy 62.843632 -308.050873)
			(xy 62.801011 -308.026266) (xy 62.76289 -307.995141) (xy 62.730255 -307.958304) (xy 62.703952 -307.916708)
			(xy 62.684661 -307.871432) (xy 62.672884 -307.823648) (xy 62.668924 -307.774594) (xy 62.330071 -307.774594)
			(xy 62.330076 -307.774848) (xy 62.329581 -307.799455) (xy 62.321686 -307.848032) (xy 62.306102 -307.894713)
			(xy 62.283231 -307.93829) (xy 62.253666 -307.977634) (xy 62.218173 -308.011726) (xy 62.17767 -308.039682)
			(xy 62.133208 -308.06078) (xy 62.085937 -308.074472) (xy 62.037082 -308.080404) (xy 61.987907 -308.078423)
			(xy 61.939688 -308.068579) (xy 61.893672 -308.051127) (xy 61.851051 -308.02652) (xy 61.81293 -307.995395)
			(xy 61.780295 -307.958558) (xy 61.753992 -307.916962) (xy 61.734701 -307.871686) (xy 61.722924 -307.823902)
			(xy 61.718964 -307.774848) (xy 61.380116 -307.774848) (xy 61.379621 -307.799455) (xy 61.371726 -307.848032)
			(xy 61.356142 -307.894713) (xy 61.333271 -307.93829) (xy 61.303706 -307.977634) (xy 61.268213 -308.011726)
			(xy 61.22771 -308.039682) (xy 61.183248 -308.06078) (xy 61.135977 -308.074472) (xy 61.087122 -308.080404)
			(xy 61.037947 -308.078423) (xy 60.989728 -308.068579) (xy 60.943712 -308.051127) (xy 60.901091 -308.02652)
			(xy 60.86297 -307.995395) (xy 60.830335 -307.958558) (xy 60.804032 -307.916962) (xy 60.784741 -307.871686)
			(xy 60.772964 -307.823902) (xy 60.769004 -307.774848) (xy 60.430156 -307.774848) (xy 60.429661 -307.799455)
			(xy 60.421766 -307.848032) (xy 60.406182 -307.894713) (xy 60.383311 -307.93829) (xy 60.353746 -307.977634)
			(xy 60.318253 -308.011726) (xy 60.27775 -308.039682) (xy 60.233288 -308.06078) (xy 60.186017 -308.074472)
			(xy 60.137162 -308.080404) (xy 60.087987 -308.078423) (xy 60.039768 -308.068579) (xy 59.993752 -308.051127)
			(xy 59.951131 -308.02652) (xy 59.91301 -307.995395) (xy 59.880375 -307.958558) (xy 59.854072 -307.916962)
			(xy 59.834781 -307.871686) (xy 59.823004 -307.823902) (xy 59.819044 -307.774848) (xy 58.530236 -307.774848)
			(xy 58.529741 -307.799455) (xy 58.521846 -307.848032) (xy 58.506262 -307.894713) (xy 58.483391 -307.93829)
			(xy 58.453826 -307.977634) (xy 58.418333 -308.011726) (xy 58.37783 -308.039682) (xy 58.333368 -308.06078)
			(xy 58.286097 -308.074472) (xy 58.237242 -308.080404) (xy 58.188067 -308.078423) (xy 58.139848 -308.068579)
			(xy 58.093832 -308.051127) (xy 58.051211 -308.02652) (xy 58.01309 -307.995395) (xy 57.980455 -307.958558)
			(xy 57.954152 -307.916962) (xy 57.934861 -307.871686) (xy 57.923084 -307.823902) (xy 57.919124 -307.774848)
			(xy 57.580276 -307.774848) (xy 57.579781 -307.799455) (xy 57.571886 -307.848032) (xy 57.556302 -307.894713)
			(xy 57.533431 -307.93829) (xy 57.503866 -307.977634) (xy 57.468373 -308.011726) (xy 57.42787 -308.039682)
			(xy 57.383408 -308.06078) (xy 57.336137 -308.074472) (xy 57.287282 -308.080404) (xy 57.238107 -308.078423)
			(xy 57.189888 -308.068579) (xy 57.143872 -308.051127) (xy 57.101251 -308.02652) (xy 57.06313 -307.995395)
			(xy 57.030495 -307.958558) (xy 57.004192 -307.916962) (xy 56.984901 -307.871686) (xy 56.973124 -307.823902)
			(xy 56.969164 -307.774848) (xy 56.630316 -307.774848) (xy 56.629821 -307.799455) (xy 56.621926 -307.848032)
			(xy 56.606342 -307.894713) (xy 56.583471 -307.93829) (xy 56.553906 -307.977634) (xy 56.518413 -308.011726)
			(xy 56.47791 -308.039682) (xy 56.433448 -308.06078) (xy 56.386177 -308.074472) (xy 56.337322 -308.080404)
			(xy 56.288147 -308.078423) (xy 56.239928 -308.068579) (xy 56.193912 -308.051127) (xy 56.151291 -308.02652)
			(xy 56.11317 -307.995395) (xy 56.080535 -307.958558) (xy 56.054232 -307.916962) (xy 56.034941 -307.871686)
			(xy 56.023164 -307.823902) (xy 56.019204 -307.774848) (xy 55.680102 -307.774848) (xy 55.679607 -307.799455)
			(xy 55.671712 -307.848032) (xy 55.656128 -307.894713) (xy 55.633257 -307.93829) (xy 55.603692 -307.977634)
			(xy 55.568199 -308.011726) (xy 55.527696 -308.039682) (xy 55.483234 -308.06078) (xy 55.435963 -308.074472)
			(xy 55.387108 -308.080404) (xy 55.337933 -308.078423) (xy 55.289714 -308.068579) (xy 55.243698 -308.051127)
			(xy 55.201077 -308.02652) (xy 55.162956 -307.995395) (xy 55.130321 -307.958558) (xy 55.104018 -307.916962)
			(xy 55.084727 -307.871686) (xy 55.07295 -307.823902) (xy 55.06899 -307.774848) (xy 54.730142 -307.774848)
			(xy 54.729647 -307.799455) (xy 54.721752 -307.848032) (xy 54.706168 -307.894713) (xy 54.683297 -307.93829)
			(xy 54.653732 -307.977634) (xy 54.618239 -308.011726) (xy 54.577736 -308.039682) (xy 54.533274 -308.06078)
			(xy 54.486003 -308.074472) (xy 54.437148 -308.080404) (xy 54.387973 -308.078423) (xy 54.339754 -308.068579)
			(xy 54.293738 -308.051127) (xy 54.251117 -308.02652) (xy 54.212996 -307.995395) (xy 54.180361 -307.958558)
			(xy 54.154058 -307.916962) (xy 54.134767 -307.871686) (xy 54.12299 -307.823902) (xy 54.11903 -307.774848)
			(xy 53.78022 -307.774848) (xy 53.780667 -307.783085) (xy 53.775298 -307.832446) (xy 53.762014 -307.880288)
			(xy 53.741165 -307.92535) (xy 53.713299 -307.966446) (xy 53.679152 -308.002492) (xy 53.639622 -308.032538)
			(xy 53.595753 -308.055793) (xy 53.548699 -308.071643) (xy 53.4997 -308.079672) (xy 53.474874 -308.080156)
			(xy 53.460691 -308.079984) (xy 53.432451 -308.077309) (xy 53.418486 -308.074822) (xy 53.40604 -308.072536)
			(xy 53.382418 -308.079902) (xy 53.304948 -308.157372) (xy 53.297582 -308.180994) (xy 53.299868 -308.19344)
			(xy 53.302346 -308.207406) (xy 53.305017 -308.235645) (xy 53.305202 -308.249828) (xy 73.593972 -308.249828)
			(xy 73.597932 -308.200774) (xy 73.609709 -308.15299) (xy 73.629 -308.107714) (xy 73.655303 -308.066118)
			(xy 73.687938 -308.029281) (xy 73.726059 -307.998156) (xy 73.76868 -307.973549) (xy 73.814696 -307.956097)
			(xy 73.862915 -307.946253) (xy 73.91209 -307.944272) (xy 73.960945 -307.950204) (xy 74.008216 -307.963896)
			(xy 74.052678 -307.984994) (xy 74.093181 -308.01295) (xy 74.128674 -308.047042) (xy 74.158239 -308.086386)
			(xy 74.18111 -308.129963) (xy 74.196694 -308.176644) (xy 74.204589 -308.225221) (xy 74.205084 -308.249828)
			(xy 74.204589 -308.274435) (xy 74.20441 -308.275536) (xy 74.523342 -308.275536) (xy 74.523342 -308.22412)
			(xy 74.531385 -308.173338) (xy 74.547273 -308.124439) (xy 74.570616 -308.078627) (xy 74.600837 -308.037031)
			(xy 74.637193 -308.000675) (xy 74.678789 -307.970454) (xy 74.724601 -307.947111) (xy 74.7735 -307.931223)
			(xy 74.824282 -307.92318) (xy 74.875698 -307.92318) (xy 74.92648 -307.931223) (xy 74.975379 -307.947111)
			(xy 75.021191 -307.970454) (xy 75.062787 -308.000675) (xy 75.099143 -308.037031) (xy 75.129364 -308.078627)
			(xy 75.152707 -308.124439) (xy 75.168595 -308.173338) (xy 75.176638 -308.22412) (xy 75.177142 -308.249828)
			(xy 75.176638 -308.275536) (xy 75.473302 -308.275536) (xy 75.473302 -308.22412) (xy 75.481345 -308.173338)
			(xy 75.497233 -308.124439) (xy 75.520576 -308.078627) (xy 75.550797 -308.037031) (xy 75.587153 -308.000675)
			(xy 75.628749 -307.970454) (xy 75.674561 -307.947111) (xy 75.72346 -307.931223) (xy 75.774242 -307.92318)
			(xy 75.825658 -307.92318) (xy 75.87644 -307.931223) (xy 75.925339 -307.947111) (xy 75.971151 -307.970454)
			(xy 76.012747 -308.000675) (xy 76.049103 -308.037031) (xy 76.079324 -308.078627) (xy 76.102667 -308.124439)
			(xy 76.118555 -308.173338) (xy 76.126598 -308.22412) (xy 76.127102 -308.249828) (xy 76.444106 -308.249828)
			(xy 76.448066 -308.200774) (xy 76.459843 -308.15299) (xy 76.479134 -308.107714) (xy 76.505437 -308.066118)
			(xy 76.538072 -308.029281) (xy 76.576193 -307.998156) (xy 76.618814 -307.973549) (xy 76.66483 -307.956097)
			(xy 76.713049 -307.946253) (xy 76.762224 -307.944272) (xy 76.811079 -307.950204) (xy 76.85835 -307.963896)
			(xy 76.902812 -307.984994) (xy 76.943315 -308.01295) (xy 76.978808 -308.047042) (xy 77.008373 -308.086386)
			(xy 77.031244 -308.129963) (xy 77.046828 -308.176644) (xy 77.054723 -308.225221) (xy 77.055218 -308.249828)
			(xy 77.394066 -308.249828) (xy 77.398026 -308.200774) (xy 77.409803 -308.15299) (xy 77.429094 -308.107714)
			(xy 77.455397 -308.066118) (xy 77.488032 -308.029281) (xy 77.526153 -307.998156) (xy 77.568774 -307.973549)
			(xy 77.61479 -307.956097) (xy 77.663009 -307.946253) (xy 77.712184 -307.944272) (xy 77.761039 -307.950204)
			(xy 77.80831 -307.963896) (xy 77.852772 -307.984994) (xy 77.893275 -308.01295) (xy 77.928768 -308.047042)
			(xy 77.958333 -308.086386) (xy 77.981204 -308.129963) (xy 77.996788 -308.176644) (xy 78.004683 -308.225221)
			(xy 78.005178 -308.249828) (xy 78.004683 -308.274435) (xy 77.996788 -308.323012) (xy 77.981204 -308.369693)
			(xy 77.958333 -308.41327) (xy 77.928768 -308.452614) (xy 77.893275 -308.486706) (xy 77.852772 -308.514662)
			(xy 77.80831 -308.53576) (xy 77.761039 -308.549452) (xy 77.712184 -308.555384) (xy 77.663009 -308.553403)
			(xy 77.61479 -308.543559) (xy 77.568774 -308.526107) (xy 77.526153 -308.5015) (xy 77.488032 -308.470375)
			(xy 77.455397 -308.433538) (xy 77.429094 -308.391942) (xy 77.409803 -308.346666) (xy 77.398026 -308.298882)
			(xy 77.394066 -308.249828) (xy 77.055218 -308.249828) (xy 77.054723 -308.274435) (xy 77.046828 -308.323012)
			(xy 77.031244 -308.369693) (xy 77.008373 -308.41327) (xy 76.978808 -308.452614) (xy 76.943315 -308.486706)
			(xy 76.902812 -308.514662) (xy 76.85835 -308.53576) (xy 76.811079 -308.549452) (xy 76.762224 -308.555384)
			(xy 76.713049 -308.553403) (xy 76.66483 -308.543559) (xy 76.618814 -308.526107) (xy 76.576193 -308.5015)
			(xy 76.538072 -308.470375) (xy 76.505437 -308.433538) (xy 76.479134 -308.391942) (xy 76.459843 -308.346666)
			(xy 76.448066 -308.298882) (xy 76.444106 -308.249828) (xy 76.127102 -308.249828) (xy 76.126598 -308.275536)
			(xy 76.118555 -308.326318) (xy 76.102667 -308.375217) (xy 76.079324 -308.421029) (xy 76.049103 -308.462625)
			(xy 76.012747 -308.498981) (xy 75.971151 -308.529202) (xy 75.925339 -308.552545) (xy 75.87644 -308.568433)
			(xy 75.825658 -308.576476) (xy 75.774242 -308.576476) (xy 75.72346 -308.568433) (xy 75.674561 -308.552545)
			(xy 75.628749 -308.529202) (xy 75.587153 -308.498981) (xy 75.550797 -308.462625) (xy 75.520576 -308.421029)
			(xy 75.497233 -308.375217) (xy 75.481345 -308.326318) (xy 75.473302 -308.275536) (xy 75.176638 -308.275536)
			(xy 75.168595 -308.326318) (xy 75.152707 -308.375217) (xy 75.129364 -308.421029) (xy 75.099143 -308.462625)
			(xy 75.062787 -308.498981) (xy 75.021191 -308.529202) (xy 74.975379 -308.552545) (xy 74.92648 -308.568433)
			(xy 74.875698 -308.576476) (xy 74.824282 -308.576476) (xy 74.7735 -308.568433) (xy 74.724601 -308.552545)
			(xy 74.678789 -308.529202) (xy 74.637193 -308.498981) (xy 74.600837 -308.462625) (xy 74.570616 -308.421029)
			(xy 74.547273 -308.375217) (xy 74.531385 -308.326318) (xy 74.523342 -308.275536) (xy 74.20441 -308.275536)
			(xy 74.196694 -308.323012) (xy 74.18111 -308.369693) (xy 74.158239 -308.41327) (xy 74.128674 -308.452614)
			(xy 74.093181 -308.486706) (xy 74.052678 -308.514662) (xy 74.008216 -308.53576) (xy 73.960945 -308.549452)
			(xy 73.91209 -308.555384) (xy 73.862915 -308.553403) (xy 73.814696 -308.543559) (xy 73.76868 -308.526107)
			(xy 73.726059 -308.5015) (xy 73.687938 -308.470375) (xy 73.655303 -308.433538) (xy 73.629 -308.391942)
			(xy 73.609709 -308.346666) (xy 73.597932 -308.298882) (xy 73.593972 -308.249828) (xy 53.305202 -308.249828)
			(xy 53.305029 -308.264011) (xy 53.302355 -308.292251) (xy 53.299868 -308.306216) (xy 53.297582 -308.318662)
			(xy 53.304948 -308.342284) (xy 53.382418 -308.419754) (xy 53.40604 -308.42712) (xy 53.418486 -308.424834)
			(xy 53.432453 -308.422364) (xy 53.460692 -308.419688) (xy 53.474874 -308.4195) (xy 53.500134 -308.419975)
			(xy 53.549965 -308.428286) (xy 53.597748 -308.444687) (xy 53.64218 -308.468729) (xy 53.682049 -308.499756)
			(xy 53.716266 -308.536923) (xy 53.743899 -308.579216) (xy 53.764193 -308.62548) (xy 53.776596 -308.674453)
			(xy 53.780768 -308.7248) (xy 53.780767 -308.724808) (xy 54.11903 -308.724808) (xy 54.12299 -308.675754)
			(xy 54.134767 -308.62797) (xy 54.154058 -308.582694) (xy 54.180361 -308.541098) (xy 54.212996 -308.504261)
			(xy 54.251117 -308.473136) (xy 54.293738 -308.448529) (xy 54.339754 -308.431077) (xy 54.387973 -308.421233)
			(xy 54.437148 -308.419252) (xy 54.486003 -308.425184) (xy 54.533274 -308.438876) (xy 54.577736 -308.459974)
			(xy 54.618239 -308.48793) (xy 54.653732 -308.522022) (xy 54.683297 -308.561366) (xy 54.706168 -308.604943)
			(xy 54.721752 -308.651624) (xy 54.729647 -308.700201) (xy 54.730142 -308.724808) (xy 54.729976 -308.733075)
			(xy 55.069087 -308.733075) (xy 55.071776 -308.683507) (xy 55.082448 -308.635027) (xy 55.100823 -308.588912)
			(xy 55.126416 -308.546378) (xy 55.158554 -308.508544) (xy 55.196389 -308.476408) (xy 55.238925 -308.450817)
			(xy 55.28504 -308.432444) (xy 55.333521 -308.421774) (xy 55.383089 -308.419087) (xy 55.432439 -308.424456)
			(xy 55.48027 -308.437737) (xy 55.525322 -308.458582) (xy 55.566408 -308.486441) (xy 55.602447 -308.52058)
			(xy 55.632487 -308.560099) (xy 55.655738 -308.603958) (xy 55.671587 -308.651001) (xy 55.679617 -308.699988)
			(xy 55.680102 -308.724808) (xy 55.679927 -308.738991) (xy 55.677254 -308.767231) (xy 55.674768 -308.781196)
			(xy 55.672482 -308.793642) (xy 55.679848 -308.817264) (xy 55.757318 -308.894734) (xy 55.78094 -308.9021)
			(xy 55.793386 -308.899814) (xy 55.807353 -308.897343) (xy 55.835592 -308.894668) (xy 55.849774 -308.89448)
			(xy 55.864021 -308.894637) (xy 55.892389 -308.897313) (xy 55.906416 -308.899814) (xy 55.918608 -308.9021)
			(xy 55.942738 -308.894734) (xy 56.019954 -308.817518) (xy 56.02732 -308.793642) (xy 56.025034 -308.781196)
			(xy 56.022561 -308.76723) (xy 56.019887 -308.73899) (xy 56.0197 -308.724808) (xy 56.020169 -308.699986)
			(xy 56.028199 -308.650997) (xy 56.044049 -308.603952) (xy 56.067301 -308.560092) (xy 56.097343 -308.52057)
			(xy 56.133383 -308.48643) (xy 56.174471 -308.45857) (xy 56.219525 -308.437724) (xy 56.267358 -308.424442)
			(xy 56.31671 -308.419073) (xy 56.36628 -308.42176) (xy 56.414763 -308.43243) (xy 56.460881 -308.450804)
			(xy 56.503418 -308.476396) (xy 56.541255 -308.508534) (xy 56.573394 -308.546369) (xy 56.598989 -308.588905)
			(xy 56.617365 -308.635022) (xy 56.628038 -308.683504) (xy 56.630279 -308.724808) (xy 57.919124 -308.724808)
			(xy 57.923084 -308.675754) (xy 57.934861 -308.62797) (xy 57.954152 -308.582694) (xy 57.980455 -308.541098)
			(xy 58.01309 -308.504261) (xy 58.051211 -308.473136) (xy 58.093832 -308.448529) (xy 58.139848 -308.431077)
			(xy 58.188067 -308.421233) (xy 58.237242 -308.419252) (xy 58.286097 -308.425184) (xy 58.333368 -308.438876)
			(xy 58.37783 -308.459974) (xy 58.418333 -308.48793) (xy 58.453826 -308.522022) (xy 58.483391 -308.561366)
			(xy 58.506262 -308.604943) (xy 58.521846 -308.651624) (xy 58.529741 -308.700201) (xy 58.530236 -308.724808)
			(xy 58.530069 -308.733113) (xy 59.819033 -308.733113) (xy 59.821717 -308.683534) (xy 59.832386 -308.635042)
			(xy 59.85076 -308.588916) (xy 59.876355 -308.546369) (xy 59.908496 -308.508525) (xy 59.946337 -308.476379)
			(xy 59.98888 -308.450778) (xy 60.035004 -308.432398) (xy 60.083494 -308.421722) (xy 60.133073 -308.419032)
			(xy 60.182433 -308.424399) (xy 60.230275 -308.437681) (xy 60.275338 -308.458528) (xy 60.316435 -308.486392)
			(xy 60.352481 -308.520537) (xy 60.382529 -308.560064) (xy 60.405786 -308.603932) (xy 60.421639 -308.650985)
			(xy 60.429671 -308.699982) (xy 60.430156 -308.724808) (xy 60.429981 -308.738991) (xy 60.427308 -308.767231)
			(xy 60.424822 -308.781196) (xy 60.422536 -308.793642) (xy 60.429902 -308.817264) (xy 60.507372 -308.894734)
			(xy 60.530994 -308.9021) (xy 60.54344 -308.899814) (xy 60.557406 -308.897336) (xy 60.585645 -308.894665)
			(xy 60.599828 -308.89448) (xy 60.614011 -308.894653) (xy 60.642251 -308.897328) (xy 60.656216 -308.899814)
			(xy 60.668662 -308.9021) (xy 60.692284 -308.894734) (xy 60.769754 -308.817264) (xy 60.77712 -308.793642)
			(xy 60.774834 -308.781196) (xy 60.772361 -308.76723) (xy 60.769687 -308.73899) (xy 60.7695 -308.724808)
			(xy 60.770022 -308.699553) (xy 60.778335 -308.649731) (xy 60.794736 -308.601957) (xy 60.818777 -308.557534)
			(xy 60.849801 -308.517674) (xy 60.886963 -308.483464) (xy 60.929249 -308.455838) (xy 60.975505 -308.435548)
			(xy 61.02447 -308.423148) (xy 61.074808 -308.418977) (xy 61.125146 -308.423148) (xy 61.174111 -308.435548)
			(xy 61.220367 -308.455838) (xy 61.262653 -308.483464) (xy 61.299815 -308.517674) (xy 61.330839 -308.557534)
			(xy 61.35488 -308.601957) (xy 61.371281 -308.649731) (xy 61.379594 -308.699553) (xy 61.380116 -308.724808)
			(xy 61.37994 -308.738991) (xy 61.377268 -308.767231) (xy 61.374782 -308.781196) (xy 61.372496 -308.793642)
			(xy 61.379862 -308.817264) (xy 61.457332 -308.894734) (xy 61.480954 -308.9021) (xy 61.4934 -308.899814)
			(xy 61.507367 -308.897342) (xy 61.535606 -308.894667) (xy 61.549788 -308.89448) (xy 61.563971 -308.894659)
			(xy 61.592211 -308.897329) (xy 61.606176 -308.899814) (xy 61.618622 -308.9021) (xy 61.642244 -308.894734)
			(xy 61.719714 -308.817264) (xy 61.72708 -308.793642) (xy 61.724794 -308.781196) (xy 61.722321 -308.76723)
			(xy 61.719647 -308.73899) (xy 61.71946 -308.724808) (xy 61.719969 -308.699986) (xy 61.728 -308.650995)
			(xy 61.743851 -308.603949) (xy 61.767104 -308.560088) (xy 61.797147 -308.520566) (xy 61.833188 -308.486425)
			(xy 61.874279 -308.458565) (xy 61.919335 -308.437721) (xy 61.96717 -308.42444) (xy 62.016523 -308.419073)
			(xy 62.066095 -308.421762) (xy 62.114578 -308.432435) (xy 62.160696 -308.450811) (xy 62.203233 -308.476407)
			(xy 62.241069 -308.508548) (xy 62.273207 -308.546386) (xy 62.298799 -308.588925) (xy 62.317172 -308.635045)
			(xy 62.327842 -308.683529) (xy 62.330063 -308.724554) (xy 62.668924 -308.724554) (xy 62.672884 -308.6755)
			(xy 62.684661 -308.627716) (xy 62.703952 -308.58244) (xy 62.730255 -308.540844) (xy 62.76289 -308.504007)
			(xy 62.801011 -308.472882) (xy 62.843632 -308.448275) (xy 62.889648 -308.430823) (xy 62.937867 -308.420979)
			(xy 62.987042 -308.418998) (xy 63.035897 -308.42493) (xy 63.083168 -308.438622) (xy 63.12763 -308.45972)
			(xy 63.168133 -308.487676) (xy 63.203626 -308.521768) (xy 63.233191 -308.561112) (xy 63.256062 -308.604689)
			(xy 63.271646 -308.65137) (xy 63.279541 -308.699947) (xy 63.280036 -308.724554) (xy 63.280031 -308.724808)
			(xy 63.619138 -308.724808) (xy 63.623098 -308.675754) (xy 63.634875 -308.62797) (xy 63.654166 -308.582694)
			(xy 63.680469 -308.541098) (xy 63.713104 -308.504261) (xy 63.751225 -308.473136) (xy 63.793846 -308.448529)
			(xy 63.839862 -308.431077) (xy 63.888081 -308.421233) (xy 63.937256 -308.419252) (xy 63.986111 -308.425184)
			(xy 64.033382 -308.438876) (xy 64.077844 -308.459974) (xy 64.118347 -308.48793) (xy 64.15384 -308.522022)
			(xy 64.183405 -308.561366) (xy 64.206276 -308.604943) (xy 64.22186 -308.651624) (xy 64.229755 -308.700201)
			(xy 64.23025 -308.724808) (xy 64.569098 -308.724808) (xy 64.573058 -308.675754) (xy 64.584835 -308.62797)
			(xy 64.604126 -308.582694) (xy 64.630429 -308.541098) (xy 64.663064 -308.504261) (xy 64.701185 -308.473136)
			(xy 64.743806 -308.448529) (xy 64.789822 -308.431077) (xy 64.838041 -308.421233) (xy 64.887216 -308.419252)
			(xy 64.936071 -308.425184) (xy 64.983342 -308.438876) (xy 65.027804 -308.459974) (xy 65.068307 -308.48793)
			(xy 65.1038 -308.522022) (xy 65.133365 -308.561366) (xy 65.156236 -308.604943) (xy 65.17182 -308.651624)
			(xy 65.179715 -308.700201) (xy 65.18021 -308.724808) (xy 65.519058 -308.724808) (xy 65.523018 -308.675754)
			(xy 65.534795 -308.62797) (xy 65.554086 -308.582694) (xy 65.580389 -308.541098) (xy 65.613024 -308.504261)
			(xy 65.651145 -308.473136) (xy 65.693766 -308.448529) (xy 65.739782 -308.431077) (xy 65.788001 -308.421233)
			(xy 65.837176 -308.419252) (xy 65.886031 -308.425184) (xy 65.933302 -308.438876) (xy 65.977764 -308.459974)
			(xy 66.018267 -308.48793) (xy 66.05376 -308.522022) (xy 66.083325 -308.561366) (xy 66.106196 -308.604943)
			(xy 66.12178 -308.651624) (xy 66.129675 -308.700201) (xy 66.13017 -308.724808) (xy 66.469018 -308.724808)
			(xy 66.472978 -308.675754) (xy 66.484755 -308.62797) (xy 66.504046 -308.582694) (xy 66.530349 -308.541098)
			(xy 66.562984 -308.504261) (xy 66.601105 -308.473136) (xy 66.643726 -308.448529) (xy 66.689742 -308.431077)
			(xy 66.737961 -308.421233) (xy 66.787136 -308.419252) (xy 66.835991 -308.425184) (xy 66.883262 -308.438876)
			(xy 66.927724 -308.459974) (xy 66.968227 -308.48793) (xy 67.00372 -308.522022) (xy 67.033285 -308.561366)
			(xy 67.056156 -308.604943) (xy 67.07174 -308.651624) (xy 67.079635 -308.700201) (xy 67.08013 -308.724808)
			(xy 67.418978 -308.724808) (xy 67.422938 -308.675754) (xy 67.434715 -308.62797) (xy 67.454006 -308.582694)
			(xy 67.480309 -308.541098) (xy 67.512944 -308.504261) (xy 67.551065 -308.473136) (xy 67.593686 -308.448529)
			(xy 67.639702 -308.431077) (xy 67.687921 -308.421233) (xy 67.737096 -308.419252) (xy 67.785951 -308.425184)
			(xy 67.833222 -308.438876) (xy 67.877684 -308.459974) (xy 67.918187 -308.48793) (xy 67.95368 -308.522022)
			(xy 67.983245 -308.561366) (xy 68.006116 -308.604943) (xy 68.0217 -308.651624) (xy 68.029595 -308.700201)
			(xy 68.03009 -308.724808) (xy 68.369192 -308.724808) (xy 68.373152 -308.675754) (xy 68.384929 -308.62797)
			(xy 68.40422 -308.582694) (xy 68.430523 -308.541098) (xy 68.463158 -308.504261) (xy 68.501279 -308.473136)
			(xy 68.5439 -308.448529) (xy 68.589916 -308.431077) (xy 68.638135 -308.421233) (xy 68.68731 -308.419252)
			(xy 68.736165 -308.425184) (xy 68.783436 -308.438876) (xy 68.827898 -308.459974) (xy 68.868401 -308.48793)
			(xy 68.903894 -308.522022) (xy 68.933459 -308.561366) (xy 68.95633 -308.604943) (xy 68.971914 -308.651624)
			(xy 68.979809 -308.700201) (xy 68.980304 -308.724808) (xy 69.319152 -308.724808) (xy 69.323112 -308.675754)
			(xy 69.334889 -308.62797) (xy 69.35418 -308.582694) (xy 69.380483 -308.541098) (xy 69.413118 -308.504261)
			(xy 69.451239 -308.473136) (xy 69.49386 -308.448529) (xy 69.539876 -308.431077) (xy 69.588095 -308.421233)
			(xy 69.63727 -308.419252) (xy 69.686125 -308.425184) (xy 69.733396 -308.438876) (xy 69.777858 -308.459974)
			(xy 69.818361 -308.48793) (xy 69.853854 -308.522022) (xy 69.883419 -308.561366) (xy 69.90629 -308.604943)
			(xy 69.921874 -308.651624) (xy 69.929769 -308.700201) (xy 69.930264 -308.724808) (xy 70.269112 -308.724808)
			(xy 70.273072 -308.675754) (xy 70.284849 -308.62797) (xy 70.30414 -308.582694) (xy 70.330443 -308.541098)
			(xy 70.363078 -308.504261) (xy 70.401199 -308.473136) (xy 70.44382 -308.448529) (xy 70.489836 -308.431077)
			(xy 70.538055 -308.421233) (xy 70.58723 -308.419252) (xy 70.636085 -308.425184) (xy 70.683356 -308.438876)
			(xy 70.727818 -308.459974) (xy 70.768321 -308.48793) (xy 70.803814 -308.522022) (xy 70.833379 -308.561366)
			(xy 70.85625 -308.604943) (xy 70.871834 -308.651624) (xy 70.879729 -308.700201) (xy 70.880224 -308.724808)
			(xy 71.219072 -308.724808) (xy 71.223032 -308.675754) (xy 71.234809 -308.62797) (xy 71.2541 -308.582694)
			(xy 71.280403 -308.541098) (xy 71.313038 -308.504261) (xy 71.351159 -308.473136) (xy 71.39378 -308.448529)
			(xy 71.439796 -308.431077) (xy 71.488015 -308.421233) (xy 71.53719 -308.419252) (xy 71.586045 -308.425184)
			(xy 71.633316 -308.438876) (xy 71.677778 -308.459974) (xy 71.718281 -308.48793) (xy 71.753774 -308.522022)
			(xy 71.783339 -308.561366) (xy 71.80621 -308.604943) (xy 71.821794 -308.651624) (xy 71.829689 -308.700201)
			(xy 71.830184 -308.724808) (xy 72.169032 -308.724808) (xy 72.172992 -308.675754) (xy 72.184769 -308.62797)
			(xy 72.20406 -308.582694) (xy 72.230363 -308.541098) (xy 72.262998 -308.504261) (xy 72.301119 -308.473136)
			(xy 72.34374 -308.448529) (xy 72.389756 -308.431077) (xy 72.437975 -308.421233) (xy 72.48715 -308.419252)
			(xy 72.536005 -308.425184) (xy 72.583276 -308.438876) (xy 72.627738 -308.459974) (xy 72.668241 -308.48793)
			(xy 72.703734 -308.522022) (xy 72.733299 -308.561366) (xy 72.75617 -308.604943) (xy 72.771754 -308.651624)
			(xy 72.779649 -308.700201) (xy 72.780144 -308.724808) (xy 72.779649 -308.749415) (xy 72.771754 -308.797992)
			(xy 72.75617 -308.844673) (xy 72.733299 -308.88825) (xy 72.703734 -308.927594) (xy 72.668241 -308.961686)
			(xy 72.627738 -308.989642) (xy 72.583276 -309.01074) (xy 72.536005 -309.024432) (xy 72.48715 -309.030364)
			(xy 72.437975 -309.028383) (xy 72.389756 -309.018539) (xy 72.34374 -309.001087) (xy 72.301119 -308.97648)
			(xy 72.262998 -308.945355) (xy 72.230363 -308.908518) (xy 72.20406 -308.866922) (xy 72.184769 -308.821646)
			(xy 72.172992 -308.773862) (xy 72.169032 -308.724808) (xy 71.830184 -308.724808) (xy 71.829689 -308.749415)
			(xy 71.821794 -308.797992) (xy 71.80621 -308.844673) (xy 71.783339 -308.88825) (xy 71.753774 -308.927594)
			(xy 71.718281 -308.961686) (xy 71.677778 -308.989642) (xy 71.633316 -309.01074) (xy 71.586045 -309.024432)
			(xy 71.53719 -309.030364) (xy 71.488015 -309.028383) (xy 71.439796 -309.018539) (xy 71.39378 -309.001087)
			(xy 71.351159 -308.97648) (xy 71.313038 -308.945355) (xy 71.280403 -308.908518) (xy 71.2541 -308.866922)
			(xy 71.234809 -308.821646) (xy 71.223032 -308.773862) (xy 71.219072 -308.724808) (xy 70.880224 -308.724808)
			(xy 70.879729 -308.749415) (xy 70.871834 -308.797992) (xy 70.85625 -308.844673) (xy 70.833379 -308.88825)
			(xy 70.803814 -308.927594) (xy 70.768321 -308.961686) (xy 70.727818 -308.989642) (xy 70.683356 -309.01074)
			(xy 70.636085 -309.024432) (xy 70.58723 -309.030364) (xy 70.538055 -309.028383) (xy 70.489836 -309.018539)
			(xy 70.44382 -309.001087) (xy 70.401199 -308.97648) (xy 70.363078 -308.945355) (xy 70.330443 -308.908518)
			(xy 70.30414 -308.866922) (xy 70.284849 -308.821646) (xy 70.273072 -308.773862) (xy 70.269112 -308.724808)
			(xy 69.930264 -308.724808) (xy 69.929769 -308.749415) (xy 69.921874 -308.797992) (xy 69.90629 -308.844673)
			(xy 69.883419 -308.88825) (xy 69.853854 -308.927594) (xy 69.818361 -308.961686) (xy 69.777858 -308.989642)
			(xy 69.733396 -309.01074) (xy 69.686125 -309.024432) (xy 69.63727 -309.030364) (xy 69.588095 -309.028383)
			(xy 69.539876 -309.018539) (xy 69.49386 -309.001087) (xy 69.451239 -308.97648) (xy 69.413118 -308.945355)
			(xy 69.380483 -308.908518) (xy 69.35418 -308.866922) (xy 69.334889 -308.821646) (xy 69.323112 -308.773862)
			(xy 69.319152 -308.724808) (xy 68.980304 -308.724808) (xy 68.979809 -308.749415) (xy 68.971914 -308.797992)
			(xy 68.95633 -308.844673) (xy 68.933459 -308.88825) (xy 68.903894 -308.927594) (xy 68.868401 -308.961686)
			(xy 68.827898 -308.989642) (xy 68.783436 -309.01074) (xy 68.736165 -309.024432) (xy 68.68731 -309.030364)
			(xy 68.638135 -309.028383) (xy 68.589916 -309.018539) (xy 68.5439 -309.001087) (xy 68.501279 -308.97648)
			(xy 68.463158 -308.945355) (xy 68.430523 -308.908518) (xy 68.40422 -308.866922) (xy 68.384929 -308.821646)
			(xy 68.373152 -308.773862) (xy 68.369192 -308.724808) (xy 68.03009 -308.724808) (xy 68.029595 -308.749415)
			(xy 68.0217 -308.797992) (xy 68.006116 -308.844673) (xy 67.983245 -308.88825) (xy 67.95368 -308.927594)
			(xy 67.918187 -308.961686) (xy 67.877684 -308.989642) (xy 67.833222 -309.01074) (xy 67.785951 -309.024432)
			(xy 67.737096 -309.030364) (xy 67.687921 -309.028383) (xy 67.639702 -309.018539) (xy 67.593686 -309.001087)
			(xy 67.551065 -308.97648) (xy 67.512944 -308.945355) (xy 67.480309 -308.908518) (xy 67.454006 -308.866922)
			(xy 67.434715 -308.821646) (xy 67.422938 -308.773862) (xy 67.418978 -308.724808) (xy 67.08013 -308.724808)
			(xy 67.079635 -308.749415) (xy 67.07174 -308.797992) (xy 67.056156 -308.844673) (xy 67.033285 -308.88825)
			(xy 67.00372 -308.927594) (xy 66.968227 -308.961686) (xy 66.927724 -308.989642) (xy 66.883262 -309.01074)
			(xy 66.835991 -309.024432) (xy 66.787136 -309.030364) (xy 66.737961 -309.028383) (xy 66.689742 -309.018539)
			(xy 66.643726 -309.001087) (xy 66.601105 -308.97648) (xy 66.562984 -308.945355) (xy 66.530349 -308.908518)
			(xy 66.504046 -308.866922) (xy 66.484755 -308.821646) (xy 66.472978 -308.773862) (xy 66.469018 -308.724808)
			(xy 66.13017 -308.724808) (xy 66.129675 -308.749415) (xy 66.12178 -308.797992) (xy 66.106196 -308.844673)
			(xy 66.083325 -308.88825) (xy 66.05376 -308.927594) (xy 66.018267 -308.961686) (xy 65.977764 -308.989642)
			(xy 65.933302 -309.01074) (xy 65.886031 -309.024432) (xy 65.837176 -309.030364) (xy 65.788001 -309.028383)
			(xy 65.739782 -309.018539) (xy 65.693766 -309.001087) (xy 65.651145 -308.97648) (xy 65.613024 -308.945355)
			(xy 65.580389 -308.908518) (xy 65.554086 -308.866922) (xy 65.534795 -308.821646) (xy 65.523018 -308.773862)
			(xy 65.519058 -308.724808) (xy 65.18021 -308.724808) (xy 65.179715 -308.749415) (xy 65.17182 -308.797992)
			(xy 65.156236 -308.844673) (xy 65.133365 -308.88825) (xy 65.1038 -308.927594) (xy 65.068307 -308.961686)
			(xy 65.027804 -308.989642) (xy 64.983342 -309.01074) (xy 64.936071 -309.024432) (xy 64.887216 -309.030364)
			(xy 64.838041 -309.028383) (xy 64.789822 -309.018539) (xy 64.743806 -309.001087) (xy 64.701185 -308.97648)
			(xy 64.663064 -308.945355) (xy 64.630429 -308.908518) (xy 64.604126 -308.866922) (xy 64.584835 -308.821646)
			(xy 64.573058 -308.773862) (xy 64.569098 -308.724808) (xy 64.23025 -308.724808) (xy 64.229755 -308.749415)
			(xy 64.22186 -308.797992) (xy 64.206276 -308.844673) (xy 64.183405 -308.88825) (xy 64.15384 -308.927594)
			(xy 64.118347 -308.961686) (xy 64.077844 -308.989642) (xy 64.033382 -309.01074) (xy 63.986111 -309.024432)
			(xy 63.937256 -309.030364) (xy 63.888081 -309.028383) (xy 63.839862 -309.018539) (xy 63.793846 -309.001087)
			(xy 63.751225 -308.97648) (xy 63.713104 -308.945355) (xy 63.680469 -308.908518) (xy 63.654166 -308.866922)
			(xy 63.634875 -308.821646) (xy 63.623098 -308.773862) (xy 63.619138 -308.724808) (xy 63.280031 -308.724808)
			(xy 63.279541 -308.749161) (xy 63.271646 -308.797738) (xy 63.256062 -308.844419) (xy 63.233191 -308.887996)
			(xy 63.203626 -308.92734) (xy 63.168133 -308.961432) (xy 63.12763 -308.989388) (xy 63.083168 -309.010486)
			(xy 63.035897 -309.024178) (xy 62.987042 -309.03011) (xy 62.937867 -309.028129) (xy 62.889648 -309.018285)
			(xy 62.843632 -309.000833) (xy 62.801011 -308.976226) (xy 62.76289 -308.945101) (xy 62.730255 -308.908264)
			(xy 62.703952 -308.866668) (xy 62.684661 -308.821392) (xy 62.672884 -308.773608) (xy 62.668924 -308.724554)
			(xy 62.330063 -308.724554) (xy 62.330526 -308.733101) (xy 62.325156 -308.782454) (xy 62.311871 -308.830288)
			(xy 62.291023 -308.875342) (xy 62.26316 -308.91643) (xy 62.229016 -308.952469) (xy 62.189492 -308.982509)
			(xy 62.145629 -309.005759) (xy 62.098581 -309.021606) (xy 62.04959 -309.029633) (xy 62.024768 -309.030116)
			(xy 62.010585 -309.029944) (xy 61.982345 -309.027269) (xy 61.96838 -309.024782) (xy 61.955934 -309.022496)
			(xy 61.932312 -309.029862) (xy 61.854842 -309.107332) (xy 61.847476 -309.130954) (xy 61.849762 -309.1434)
			(xy 61.852234 -309.157367) (xy 61.854909 -309.185606) (xy 61.855096 -309.199788) (xy 73.593972 -309.199788)
			(xy 73.597932 -309.150734) (xy 73.609709 -309.10295) (xy 73.629 -309.057674) (xy 73.655303 -309.016078)
			(xy 73.687938 -308.979241) (xy 73.726059 -308.948116) (xy 73.76868 -308.923509) (xy 73.814696 -308.906057)
			(xy 73.862915 -308.896213) (xy 73.91209 -308.894232) (xy 73.960945 -308.900164) (xy 74.008216 -308.913856)
			(xy 74.052678 -308.934954) (xy 74.093181 -308.96291) (xy 74.128674 -308.997002) (xy 74.158239 -309.036346)
			(xy 74.18111 -309.079923) (xy 74.196694 -309.126604) (xy 74.204589 -309.175181) (xy 74.205084 -309.199788)
			(xy 74.544186 -309.199788) (xy 74.548146 -309.150734) (xy 74.559923 -309.10295) (xy 74.579214 -309.057674)
			(xy 74.605517 -309.016078) (xy 74.638152 -308.979241) (xy 74.676273 -308.948116) (xy 74.718894 -308.923509)
			(xy 74.76491 -308.906057) (xy 74.813129 -308.896213) (xy 74.862304 -308.894232) (xy 74.911159 -308.900164)
			(xy 74.95843 -308.913856) (xy 75.002892 -308.934954) (xy 75.043395 -308.96291) (xy 75.078888 -308.997002)
			(xy 75.108453 -309.036346) (xy 75.131324 -309.079923) (xy 75.146908 -309.126604) (xy 75.154803 -309.175181)
			(xy 75.155298 -309.199788) (xy 75.494146 -309.199788) (xy 75.498106 -309.150734) (xy 75.509883 -309.10295)
			(xy 75.529174 -309.057674) (xy 75.555477 -309.016078) (xy 75.588112 -308.979241) (xy 75.626233 -308.948116)
			(xy 75.668854 -308.923509) (xy 75.71487 -308.906057) (xy 75.763089 -308.896213) (xy 75.812264 -308.894232)
			(xy 75.861119 -308.900164) (xy 75.90839 -308.913856) (xy 75.952852 -308.934954) (xy 75.993355 -308.96291)
			(xy 76.028848 -308.997002) (xy 76.058413 -309.036346) (xy 76.081284 -309.079923) (xy 76.096868 -309.126604)
			(xy 76.104763 -309.175181) (xy 76.105258 -309.199788) (xy 76.104763 -309.224395) (xy 76.104584 -309.225496)
			(xy 76.423262 -309.225496) (xy 76.423262 -309.17408) (xy 76.431305 -309.123298) (xy 76.447193 -309.074399)
			(xy 76.470536 -309.028587) (xy 76.500757 -308.986991) (xy 76.537113 -308.950635) (xy 76.578709 -308.920414)
			(xy 76.624521 -308.897071) (xy 76.67342 -308.881183) (xy 76.724202 -308.87314) (xy 76.775618 -308.87314)
			(xy 76.8264 -308.881183) (xy 76.875299 -308.897071) (xy 76.921111 -308.920414) (xy 76.962707 -308.950635)
			(xy 76.999063 -308.986991) (xy 77.029284 -309.028587) (xy 77.052627 -309.074399) (xy 77.068515 -309.123298)
			(xy 77.076558 -309.17408) (xy 77.077062 -309.199788) (xy 77.076558 -309.225496) (xy 77.373222 -309.225496)
			(xy 77.373222 -309.17408) (xy 77.381265 -309.123298) (xy 77.397153 -309.074399) (xy 77.420496 -309.028587)
			(xy 77.450717 -308.986991) (xy 77.487073 -308.950635) (xy 77.528669 -308.920414) (xy 77.574481 -308.897071)
			(xy 77.62338 -308.881183) (xy 77.674162 -308.87314) (xy 77.725578 -308.87314) (xy 77.77636 -308.881183)
			(xy 77.825259 -308.897071) (xy 77.871071 -308.920414) (xy 77.912667 -308.950635) (xy 77.949023 -308.986991)
			(xy 77.979244 -309.028587) (xy 78.002587 -309.074399) (xy 78.018475 -309.123298) (xy 78.026518 -309.17408)
			(xy 78.027022 -309.199788) (xy 78.026518 -309.225496) (xy 78.018475 -309.276278) (xy 78.002587 -309.325177)
			(xy 77.979244 -309.370989) (xy 77.949023 -309.412585) (xy 77.912667 -309.448941) (xy 77.871071 -309.479162)
			(xy 77.825259 -309.502505) (xy 77.77636 -309.518393) (xy 77.725578 -309.526436) (xy 77.674162 -309.526436)
			(xy 77.62338 -309.518393) (xy 77.574481 -309.502505) (xy 77.528669 -309.479162) (xy 77.487073 -309.448941)
			(xy 77.450717 -309.412585) (xy 77.420496 -309.370989) (xy 77.397153 -309.325177) (xy 77.381265 -309.276278)
			(xy 77.373222 -309.225496) (xy 77.076558 -309.225496) (xy 77.068515 -309.276278) (xy 77.052627 -309.325177)
			(xy 77.029284 -309.370989) (xy 76.999063 -309.412585) (xy 76.962707 -309.448941) (xy 76.921111 -309.479162)
			(xy 76.875299 -309.502505) (xy 76.8264 -309.518393) (xy 76.775618 -309.526436) (xy 76.724202 -309.526436)
			(xy 76.67342 -309.518393) (xy 76.624521 -309.502505) (xy 76.578709 -309.479162) (xy 76.537113 -309.448941)
			(xy 76.500757 -309.412585) (xy 76.470536 -309.370989) (xy 76.447193 -309.325177) (xy 76.431305 -309.276278)
			(xy 76.423262 -309.225496) (xy 76.104584 -309.225496) (xy 76.096868 -309.272972) (xy 76.081284 -309.319653)
			(xy 76.058413 -309.36323) (xy 76.028848 -309.402574) (xy 75.993355 -309.436666) (xy 75.952852 -309.464622)
			(xy 75.90839 -309.48572) (xy 75.861119 -309.499412) (xy 75.812264 -309.505344) (xy 75.763089 -309.503363)
			(xy 75.71487 -309.493519) (xy 75.668854 -309.476067) (xy 75.626233 -309.45146) (xy 75.588112 -309.420335)
			(xy 75.555477 -309.383498) (xy 75.529174 -309.341902) (xy 75.509883 -309.296626) (xy 75.498106 -309.248842)
			(xy 75.494146 -309.199788) (xy 75.155298 -309.199788) (xy 75.154803 -309.224395) (xy 75.146908 -309.272972)
			(xy 75.131324 -309.319653) (xy 75.108453 -309.36323) (xy 75.078888 -309.402574) (xy 75.043395 -309.436666)
			(xy 75.002892 -309.464622) (xy 74.95843 -309.48572) (xy 74.911159 -309.499412) (xy 74.862304 -309.505344)
			(xy 74.813129 -309.503363) (xy 74.76491 -309.493519) (xy 74.718894 -309.476067) (xy 74.676273 -309.45146)
			(xy 74.638152 -309.420335) (xy 74.605517 -309.383498) (xy 74.579214 -309.341902) (xy 74.559923 -309.296626)
			(xy 74.548146 -309.248842) (xy 74.544186 -309.199788) (xy 74.205084 -309.199788) (xy 74.204589 -309.224395)
			(xy 74.196694 -309.272972) (xy 74.18111 -309.319653) (xy 74.158239 -309.36323) (xy 74.128674 -309.402574)
			(xy 74.093181 -309.436666) (xy 74.052678 -309.464622) (xy 74.008216 -309.48572) (xy 73.960945 -309.499412)
			(xy 73.91209 -309.505344) (xy 73.862915 -309.503363) (xy 73.814696 -309.493519) (xy 73.76868 -309.476067)
			(xy 73.726059 -309.45146) (xy 73.687938 -309.420335) (xy 73.655303 -309.383498) (xy 73.629 -309.341902)
			(xy 73.609709 -309.296626) (xy 73.597932 -309.248842) (xy 73.593972 -309.199788) (xy 61.855096 -309.199788)
			(xy 61.854574 -309.225043) (xy 61.846261 -309.274865) (xy 61.82986 -309.322639) (xy 61.805819 -309.367062)
			(xy 61.774795 -309.406922) (xy 61.737633 -309.441132) (xy 61.695347 -309.468758) (xy 61.649091 -309.489048)
			(xy 61.600126 -309.501448) (xy 61.549788 -309.505619) (xy 61.49945 -309.501448) (xy 61.450485 -309.489048)
			(xy 61.404229 -309.468758) (xy 61.361943 -309.441132) (xy 61.324781 -309.406922) (xy 61.293757 -309.367062)
			(xy 61.269716 -309.322639) (xy 61.253315 -309.274865) (xy 61.245002 -309.225043) (xy 61.24448 -309.199788)
			(xy 61.244655 -309.185605) (xy 61.247328 -309.157365) (xy 61.249814 -309.1434) (xy 61.2521 -309.130954)
			(xy 61.244734 -309.107332) (xy 61.167264 -309.029862) (xy 61.143642 -309.022496) (xy 61.131196 -309.024782)
			(xy 61.11723 -309.027255) (xy 61.08899 -309.029929) (xy 61.074808 -309.030116) (xy 61.060625 -309.029938)
			(xy 61.032385 -309.027267) (xy 61.01842 -309.024782) (xy 61.005974 -309.022496) (xy 60.982352 -309.029862)
			(xy 60.904882 -309.107332) (xy 60.897516 -309.130954) (xy 60.899802 -309.1434) (xy 60.902275 -309.157367)
			(xy 60.904949 -309.185606) (xy 60.905136 -309.199788) (xy 60.904614 -309.225043) (xy 60.896301 -309.274865)
			(xy 60.8799 -309.322639) (xy 60.855859 -309.367062) (xy 60.824835 -309.406922) (xy 60.787673 -309.441132)
			(xy 60.745387 -309.468758) (xy 60.699131 -309.489048) (xy 60.650166 -309.501448) (xy 60.599828 -309.505619)
			(xy 60.54949 -309.501448) (xy 60.500525 -309.489048) (xy 60.454269 -309.468758) (xy 60.411983 -309.441132)
			(xy 60.374821 -309.406922) (xy 60.343797 -309.367062) (xy 60.319756 -309.322639) (xy 60.303355 -309.274865)
			(xy 60.295042 -309.225043) (xy 60.29452 -309.199788) (xy 60.294695 -309.185605) (xy 60.297368 -309.157365)
			(xy 60.299854 -309.1434) (xy 60.30214 -309.130954) (xy 60.294774 -309.107332) (xy 60.217304 -309.029862)
			(xy 60.193682 -309.022496) (xy 60.181236 -309.024782) (xy 60.167271 -309.027263) (xy 60.139031 -309.029932)
			(xy 60.124848 -309.030116) (xy 60.100022 -309.029674) (xy 60.051024 -309.021649) (xy 60.003969 -309.005802)
			(xy 59.960098 -308.982551) (xy 59.920567 -308.952508) (xy 59.886417 -308.916466) (xy 59.858548 -308.875373)
			(xy 59.837695 -308.830313) (xy 59.824407 -308.782473) (xy 59.819033 -308.733113) (xy 58.530069 -308.733113)
			(xy 58.529741 -308.749415) (xy 58.521846 -308.797992) (xy 58.506262 -308.844673) (xy 58.483391 -308.88825)
			(xy 58.453826 -308.927594) (xy 58.418333 -308.961686) (xy 58.37783 -308.989642) (xy 58.333368 -309.01074)
			(xy 58.286097 -309.024432) (xy 58.237242 -309.030364) (xy 58.188067 -309.028383) (xy 58.139848 -309.018539)
			(xy 58.093832 -309.001087) (xy 58.051211 -308.97648) (xy 58.01309 -308.945355) (xy 57.980455 -308.908518)
			(xy 57.954152 -308.866922) (xy 57.934861 -308.821646) (xy 57.923084 -308.773862) (xy 57.919124 -308.724808)
			(xy 56.630279 -308.724808) (xy 56.630727 -308.733074) (xy 56.625361 -308.782426) (xy 56.612081 -308.83026)
			(xy 56.591238 -308.875315) (xy 56.56338 -308.916405) (xy 56.529242 -308.952446) (xy 56.489722 -308.98249)
			(xy 56.445862 -309.005744) (xy 56.398818 -309.021597) (xy 56.349829 -309.029629) (xy 56.325008 -309.030116)
			(xy 56.310762 -309.029941) (xy 56.282394 -309.027274) (xy 56.268366 -309.024782) (xy 56.256174 -309.022496)
			(xy 56.232044 -309.029862) (xy 56.154828 -309.107078) (xy 56.147462 -309.130954) (xy 56.149748 -309.1434)
			(xy 56.15222 -309.157367) (xy 56.154895 -309.185606) (xy 56.155082 -309.199788) (xy 56.15456 -309.225043)
			(xy 56.146247 -309.274865) (xy 56.129846 -309.322639) (xy 56.105805 -309.367062) (xy 56.074781 -309.406922)
			(xy 56.037619 -309.441132) (xy 55.995333 -309.468758) (xy 55.949077 -309.489048) (xy 55.900112 -309.501448)
			(xy 55.849774 -309.505619) (xy 55.799436 -309.501448) (xy 55.750471 -309.489048) (xy 55.704215 -309.468758)
			(xy 55.661929 -309.441132) (xy 55.624767 -309.406922) (xy 55.593743 -309.367062) (xy 55.569702 -309.322639)
			(xy 55.553301 -309.274865) (xy 55.544988 -309.225043) (xy 55.544466 -309.199788) (xy 55.544641 -309.185605)
			(xy 55.547314 -309.157365) (xy 55.5498 -309.1434) (xy 55.552086 -309.130954) (xy 55.54472 -309.107332)
			(xy 55.46725 -309.029862) (xy 55.443628 -309.022496) (xy 55.431182 -309.024782) (xy 55.417216 -309.027257)
			(xy 55.388976 -309.02993) (xy 55.374794 -309.030116) (xy 55.349974 -309.029616) (xy 55.300987 -309.021584)
			(xy 55.253945 -309.005732) (xy 55.210087 -308.982479) (xy 55.170569 -308.952437) (xy 55.136432 -308.916397)
			(xy 55.108575 -308.87531) (xy 55.087732 -308.830256) (xy 55.074453 -308.782425) (xy 55.069087 -308.733075)
			(xy 54.729976 -308.733075) (xy 54.729647 -308.749415) (xy 54.721752 -308.797992) (xy 54.706168 -308.844673)
			(xy 54.683297 -308.88825) (xy 54.653732 -308.927594) (xy 54.618239 -308.961686) (xy 54.577736 -308.989642)
			(xy 54.533274 -309.01074) (xy 54.486003 -309.024432) (xy 54.437148 -309.030364) (xy 54.387973 -309.028383)
			(xy 54.339754 -309.018539) (xy 54.293738 -309.001087) (xy 54.251117 -308.97648) (xy 54.212996 -308.945355)
			(xy 54.180361 -308.908518) (xy 54.154058 -308.866922) (xy 54.134767 -308.821646) (xy 54.12299 -308.773862)
			(xy 54.11903 -308.724808) (xy 53.780767 -308.724808) (xy 53.776596 -308.775147) (xy 53.764193 -308.82412)
			(xy 53.743899 -308.870384) (xy 53.716266 -308.912677) (xy 53.682049 -308.949844) (xy 53.64218 -308.980871)
			(xy 53.597748 -309.004913) (xy 53.549965 -309.021314) (xy 53.500134 -309.029625) (xy 53.474874 -309.030116)
			(xy 53.460691 -309.029943) (xy 53.432451 -309.027268) (xy 53.418486 -309.024782) (xy 53.40604 -309.022496)
			(xy 53.382418 -309.029862) (xy 53.304948 -309.107332) (xy 53.297582 -309.130954) (xy 53.299868 -309.1434)
			(xy 53.30234 -309.157367) (xy 53.305015 -309.185606) (xy 53.305202 -309.199788) (xy 53.304735 -309.22461)
			(xy 53.296705 -309.2736) (xy 53.280856 -309.320646) (xy 53.257604 -309.364508) (xy 53.227562 -309.40403)
			(xy 53.191522 -309.438171) (xy 53.150433 -309.466032) (xy 53.105379 -309.486879) (xy 53.057545 -309.500161)
			(xy 53.008192 -309.505531) (xy 52.958621 -309.502845) (xy 52.910137 -309.492174) (xy 52.864019 -309.4738)
			(xy 52.82148 -309.448208) (xy 52.783643 -309.41607) (xy 52.751503 -309.378234) (xy 52.725908 -309.335697)
			(xy 52.707531 -309.28958) (xy 52.696858 -309.241097) (xy 52.694169 -309.191526) (xy 52.699535 -309.142173)
			(xy 52.712815 -309.094338) (xy 52.733659 -309.049282) (xy 52.761517 -309.008192) (xy 52.795657 -308.97215)
			(xy 52.835177 -308.942106) (xy 52.879038 -308.918851) (xy 52.926082 -308.902999) (xy 52.975072 -308.894966)
			(xy 52.999894 -308.89448) (xy 53.014077 -308.894658) (xy 53.042317 -308.897329) (xy 53.056282 -308.899814)
			(xy 53.068728 -308.9021) (xy 53.09235 -308.894734) (xy 53.16982 -308.817264) (xy 53.177186 -308.793642)
			(xy 53.1749 -308.781196) (xy 53.172427 -308.76723) (xy 53.169753 -308.73899) (xy 53.169566 -308.724808)
			(xy 53.169744 -308.710625) (xy 53.172415 -308.682385) (xy 53.1749 -308.66842) (xy 53.177186 -308.655974)
			(xy 53.16982 -308.632352) (xy 53.09235 -308.554882) (xy 53.068728 -308.547516) (xy 53.056282 -308.549802)
			(xy 53.042316 -308.552277) (xy 53.014076 -308.55495) (xy 52.999894 -308.555136) (xy 52.974641 -308.554558)
			(xy 52.924825 -308.546244) (xy 52.877056 -308.529844) (xy 52.832638 -308.505806) (xy 52.792783 -308.474784)
			(xy 52.758577 -308.437626) (xy 52.730953 -308.395344) (xy 52.710666 -308.349093) (xy 52.698268 -308.300133)
			(xy 52.694097 -308.2498) (xy 52.3552 -308.2498) (xy 52.355648 -308.25805) (xy 52.350285 -308.307406)
			(xy 52.337009 -308.355244) (xy 52.316168 -308.400304) (xy 52.288311 -308.441398) (xy 52.254174 -308.477445)
			(xy 52.214654 -308.507493) (xy 52.170794 -308.530753) (xy 52.123748 -308.54661) (xy 52.074757 -308.554647)
			(xy 52.049934 -308.555136) (xy 52.035751 -308.554954) (xy 52.007511 -308.552285) (xy 51.993546 -308.549802)
			(xy 51.9811 -308.547516) (xy 51.957478 -308.554882) (xy 51.880008 -308.632352) (xy 51.872642 -308.655974)
			(xy 51.874928 -308.66842) (xy 51.877404 -308.682386) (xy 51.880076 -308.710626) (xy 51.880262 -308.724808)
			(xy 51.879869 -308.748804) (xy 51.87236 -308.796204) (xy 51.857527 -308.841846) (xy 51.835737 -308.884605)
			(xy 51.807525 -308.923428) (xy 51.773587 -308.95736) (xy 51.734759 -308.985565) (xy 51.691996 -309.007348)
			(xy 51.646351 -309.022172) (xy 51.59895 -309.029673) (xy 51.574954 -309.030116) (xy 51.560771 -309.029932)
			(xy 51.532531 -309.027265) (xy 51.518566 -309.024782) (xy 51.50612 -309.022496) (xy 51.482498 -309.029862)
			(xy 51.405028 -309.107332) (xy 51.397662 -309.130954) (xy 51.399948 -309.1434) (xy 51.40242 -309.157367)
			(xy 51.405095 -309.185606) (xy 51.405282 -309.199788) (xy 51.404835 -309.22461) (xy 51.396806 -309.273599)
			(xy 51.380957 -309.320644) (xy 51.357705 -309.364506) (xy 51.327664 -309.404028) (xy 51.291625 -309.438169)
			(xy 51.250537 -309.46603) (xy 51.205484 -309.486877) (xy 51.157651 -309.50016) (xy 51.108299 -309.50553)
			(xy 51.058728 -309.502845) (xy 51.010245 -309.492176) (xy 50.964127 -309.473804) (xy 50.921588 -309.448213)
			(xy 50.88375 -309.416077) (xy 50.851609 -309.378243) (xy 50.826013 -309.335708) (xy 50.807635 -309.289591)
			(xy 50.79696 -309.24111) (xy 50.794269 -309.191539) (xy 50.455556 -309.191539) (xy 50.452874 -309.241072)
			(xy 50.442204 -309.289561) (xy 50.423829 -309.335686) (xy 50.398234 -309.378231) (xy 50.366093 -309.416074)
			(xy 50.328253 -309.448218) (xy 50.285711 -309.473817) (xy 50.239588 -309.492196) (xy 50.191099 -309.50287)
			(xy 50.141522 -309.505559) (xy 50.092163 -309.500192) (xy 50.044323 -309.486909) (xy 49.999262 -309.466062)
			(xy 49.958167 -309.438199) (xy 49.922122 -309.404054) (xy 49.892075 -309.364527) (xy 49.86882 -309.320661)
			(xy 49.852968 -309.273609) (xy 49.844937 -309.224613) (xy 49.844452 -309.199788) (xy 49.844628 -309.185605)
			(xy 49.8473 -309.157365) (xy 49.849786 -309.1434) (xy 49.852072 -309.130954) (xy 49.844706 -309.107332)
			(xy 49.767236 -309.029862) (xy 49.743614 -309.022496) (xy 49.731168 -309.024782) (xy 49.717202 -309.027259)
			(xy 49.688963 -309.02993) (xy 49.67478 -309.030116) (xy 49.650789 -309.029656) (xy 49.603397 -309.022147)
			(xy 49.557763 -309.007317) (xy 49.515011 -308.985532) (xy 49.476193 -308.957327) (xy 49.442265 -308.923398)
			(xy 49.414062 -308.884579) (xy 49.392278 -308.841826) (xy 49.37745 -308.796191) (xy 49.369943 -308.748799)
			(xy 49.369472 -308.724808) (xy 49.36965 -308.710625) (xy 49.372321 -308.682385) (xy 49.374806 -308.66842)
			(xy 49.377092 -308.655974) (xy 49.369726 -308.632352) (xy 49.292256 -308.554882) (xy 49.268634 -308.547516)
			(xy 49.256188 -308.549802) (xy 49.242222 -308.552276) (xy 49.213982 -308.554949) (xy 49.1998 -308.555136)
			(xy 49.174979 -308.554622) (xy 49.12599 -308.546591) (xy 49.078946 -308.530739) (xy 49.035086 -308.507486)
			(xy 48.995567 -308.477443) (xy 48.961428 -308.441402) (xy 48.93357 -308.400313) (xy 48.912726 -308.355258)
			(xy 48.899447 -308.307424) (xy 48.894081 -308.258073) (xy 48.554982 -308.258073) (xy 48.554653 -308.274435)
			(xy 48.546758 -308.323012) (xy 48.531174 -308.369693) (xy 48.508303 -308.41327) (xy 48.478738 -308.452614)
			(xy 48.443245 -308.486706) (xy 48.402742 -308.514662) (xy 48.35828 -308.53576) (xy 48.311009 -308.549452)
			(xy 48.262154 -308.555384) (xy 48.212979 -308.553403) (xy 48.16476 -308.543559) (xy 48.118744 -308.526107)
			(xy 48.076123 -308.5015) (xy 48.038002 -308.470375) (xy 48.005367 -308.433538) (xy 47.979064 -308.391942)
			(xy 47.959773 -308.346666) (xy 47.947996 -308.298882) (xy 47.944036 -308.249828) (xy 47.605188 -308.249828)
			(xy 47.604693 -308.274435) (xy 47.596798 -308.323012) (xy 47.581214 -308.369693) (xy 47.558343 -308.41327)
			(xy 47.528778 -308.452614) (xy 47.493285 -308.486706) (xy 47.452782 -308.514662) (xy 47.40832 -308.53576)
			(xy 47.361049 -308.549452) (xy 47.312194 -308.555384) (xy 47.263019 -308.553403) (xy 47.2148 -308.543559)
			(xy 47.168784 -308.526107) (xy 47.126163 -308.5015) (xy 47.088042 -308.470375) (xy 47.055407 -308.433538)
			(xy 47.029104 -308.391942) (xy 47.009813 -308.346666) (xy 46.998036 -308.298882) (xy 46.994076 -308.249828)
			(xy 46.655228 -308.249828) (xy 46.654733 -308.274435) (xy 46.646838 -308.323012) (xy 46.631254 -308.369693)
			(xy 46.608383 -308.41327) (xy 46.578818 -308.452614) (xy 46.543325 -308.486706) (xy 46.502822 -308.514662)
			(xy 46.45836 -308.53576) (xy 46.411089 -308.549452) (xy 46.362234 -308.555384) (xy 46.313059 -308.553403)
			(xy 46.26484 -308.543559) (xy 46.218824 -308.526107) (xy 46.176203 -308.5015) (xy 46.138082 -308.470375)
			(xy 46.105447 -308.433538) (xy 46.079144 -308.391942) (xy 46.059853 -308.346666) (xy 46.048076 -308.298882)
			(xy 46.044116 -308.249828) (xy 45.705268 -308.249828) (xy 45.704773 -308.274435) (xy 45.696878 -308.323012)
			(xy 45.681294 -308.369693) (xy 45.658423 -308.41327) (xy 45.628858 -308.452614) (xy 45.593365 -308.486706)
			(xy 45.552862 -308.514662) (xy 45.5084 -308.53576) (xy 45.461129 -308.549452) (xy 45.412274 -308.555384)
			(xy 45.363099 -308.553403) (xy 45.31488 -308.543559) (xy 45.268864 -308.526107) (xy 45.226243 -308.5015)
			(xy 45.188122 -308.470375) (xy 45.155487 -308.433538) (xy 45.129184 -308.391942) (xy 45.109893 -308.346666)
			(xy 45.098116 -308.298882) (xy 45.094156 -308.249828) (xy 44.776898 -308.249828) (xy 44.776394 -308.275536)
			(xy 44.768351 -308.326318) (xy 44.752463 -308.375217) (xy 44.72912 -308.421029) (xy 44.698899 -308.462625)
			(xy 44.662543 -308.498981) (xy 44.620947 -308.529202) (xy 44.575135 -308.552545) (xy 44.526236 -308.568433)
			(xy 44.475454 -308.576476) (xy 44.424038 -308.576476) (xy 44.373256 -308.568433) (xy 44.324357 -308.552545)
			(xy 44.278545 -308.529202) (xy 44.236949 -308.498981) (xy 44.200593 -308.462625) (xy 44.170372 -308.421029)
			(xy 44.147029 -308.375217) (xy 44.131141 -308.326318) (xy 44.123098 -308.275536) (xy 43.826434 -308.275536)
			(xy 43.818391 -308.326318) (xy 43.802503 -308.375217) (xy 43.77916 -308.421029) (xy 43.748939 -308.462625)
			(xy 43.712583 -308.498981) (xy 43.670987 -308.529202) (xy 43.625175 -308.552545) (xy 43.576276 -308.568433)
			(xy 43.525494 -308.576476) (xy 43.474078 -308.576476) (xy 43.423296 -308.568433) (xy 43.374397 -308.552545)
			(xy 43.328585 -308.529202) (xy 43.286989 -308.498981) (xy 43.250633 -308.462625) (xy 43.220412 -308.421029)
			(xy 43.197069 -308.375217) (xy 43.181181 -308.326318) (xy 43.173138 -308.275536) (xy 42.85446 -308.275536)
			(xy 42.846744 -308.323012) (xy 42.83116 -308.369693) (xy 42.808289 -308.41327) (xy 42.778724 -308.452614)
			(xy 42.743231 -308.486706) (xy 42.702728 -308.514662) (xy 42.658266 -308.53576) (xy 42.610995 -308.549452)
			(xy 42.56214 -308.555384) (xy 42.512965 -308.553403) (xy 42.464746 -308.543559) (xy 42.41873 -308.526107)
			(xy 42.376109 -308.5015) (xy 42.337988 -308.470375) (xy 42.305353 -308.433538) (xy 42.27905 -308.391942)
			(xy 42.259759 -308.346666) (xy 42.247982 -308.298882) (xy 42.244022 -308.249828) (xy 41.905174 -308.249828)
			(xy 41.904679 -308.274435) (xy 41.896784 -308.323012) (xy 41.8812 -308.369693) (xy 41.858329 -308.41327)
			(xy 41.828764 -308.452614) (xy 41.793271 -308.486706) (xy 41.752768 -308.514662) (xy 41.708306 -308.53576)
			(xy 41.661035 -308.549452) (xy 41.61218 -308.555384) (xy 41.563005 -308.553403) (xy 41.514786 -308.543559)
			(xy 41.46877 -308.526107) (xy 41.426149 -308.5015) (xy 41.388028 -308.470375) (xy 41.355393 -308.433538)
			(xy 41.32909 -308.391942) (xy 41.309799 -308.346666) (xy 41.298022 -308.298882) (xy 41.294062 -308.249828)
			(xy 40.955214 -308.249828) (xy 40.954719 -308.274435) (xy 40.946824 -308.323012) (xy 40.93124 -308.369693)
			(xy 40.908369 -308.41327) (xy 40.878804 -308.452614) (xy 40.843311 -308.486706) (xy 40.802808 -308.514662)
			(xy 40.758346 -308.53576) (xy 40.711075 -308.549452) (xy 40.66222 -308.555384) (xy 40.613045 -308.553403)
			(xy 40.564826 -308.543559) (xy 40.51881 -308.526107) (xy 40.476189 -308.5015) (xy 40.438068 -308.470375)
			(xy 40.405433 -308.433538) (xy 40.37913 -308.391942) (xy 40.359839 -308.346666) (xy 40.348062 -308.298882)
			(xy 40.344102 -308.249828) (xy 40.005254 -308.249828) (xy 40.004759 -308.274435) (xy 39.996864 -308.323012)
			(xy 39.98128 -308.369693) (xy 39.958409 -308.41327) (xy 39.928844 -308.452614) (xy 39.893351 -308.486706)
			(xy 39.852848 -308.514662) (xy 39.808386 -308.53576) (xy 39.761115 -308.549452) (xy 39.71226 -308.555384)
			(xy 39.663085 -308.553403) (xy 39.614866 -308.543559) (xy 39.56885 -308.526107) (xy 39.526229 -308.5015)
			(xy 39.488108 -308.470375) (xy 39.455473 -308.433538) (xy 39.42917 -308.391942) (xy 39.409879 -308.346666)
			(xy 39.398102 -308.298882) (xy 39.394142 -308.249828) (xy 39.055294 -308.249828) (xy 39.054799 -308.274435)
			(xy 39.046904 -308.323012) (xy 39.03132 -308.369693) (xy 39.008449 -308.41327) (xy 38.978884 -308.452614)
			(xy 38.943391 -308.486706) (xy 38.902888 -308.514662) (xy 38.858426 -308.53576) (xy 38.811155 -308.549452)
			(xy 38.7623 -308.555384) (xy 38.713125 -308.553403) (xy 38.664906 -308.543559) (xy 38.61889 -308.526107)
			(xy 38.576269 -308.5015) (xy 38.538148 -308.470375) (xy 38.505513 -308.433538) (xy 38.47921 -308.391942)
			(xy 38.459919 -308.346666) (xy 38.448142 -308.298882) (xy 38.444182 -308.249828) (xy 38.126924 -308.249828)
			(xy 38.12642 -308.275536) (xy 38.118377 -308.326318) (xy 38.102489 -308.375217) (xy 38.079146 -308.421029)
			(xy 38.048925 -308.462625) (xy 38.012569 -308.498981) (xy 37.970973 -308.529202) (xy 37.925161 -308.552545)
			(xy 37.876262 -308.568433) (xy 37.82548 -308.576476) (xy 37.774064 -308.576476) (xy 37.723282 -308.568433)
			(xy 37.674383 -308.552545) (xy 37.628571 -308.529202) (xy 37.586975 -308.498981) (xy 37.550619 -308.462625)
			(xy 37.520398 -308.421029) (xy 37.497055 -308.375217) (xy 37.481167 -308.326318) (xy 37.473124 -308.275536)
			(xy 37.17646 -308.275536) (xy 37.168417 -308.326318) (xy 37.152529 -308.375217) (xy 37.129186 -308.421029)
			(xy 37.098965 -308.462625) (xy 37.062609 -308.498981) (xy 37.021013 -308.529202) (xy 36.975201 -308.552545)
			(xy 36.926302 -308.568433) (xy 36.87552 -308.576476) (xy 36.824104 -308.576476) (xy 36.773322 -308.568433)
			(xy 36.724423 -308.552545) (xy 36.678611 -308.529202) (xy 36.637015 -308.498981) (xy 36.600659 -308.462625)
			(xy 36.570438 -308.421029) (xy 36.547095 -308.375217) (xy 36.531207 -308.326318) (xy 36.523164 -308.275536)
			(xy 36.204273 -308.275536) (xy 36.196516 -308.323266) (xy 36.180932 -308.369947) (xy 36.158061 -308.413524)
			(xy 36.128496 -308.452868) (xy 36.093003 -308.48696) (xy 36.0525 -308.514916) (xy 36.008038 -308.536014)
			(xy 35.960767 -308.549706) (xy 35.911912 -308.555638) (xy 35.862737 -308.553657) (xy 35.814518 -308.543813)
			(xy 35.768502 -308.526361) (xy 35.725881 -308.501754) (xy 35.68776 -308.470629) (xy 35.655125 -308.433792)
			(xy 35.628822 -308.392196) (xy 35.609531 -308.34692) (xy 35.597754 -308.299136) (xy 35.593794 -308.250082)
			(xy 28.784439 -308.250082) (xy 28.793331 -308.263522) (xy 28.817003 -308.314019) (xy 28.833071 -308.367426)
			(xy 28.841191 -308.422602) (xy 28.8417 -308.450488) (xy 28.841191 -308.478374) (xy 28.833071 -308.53355)
			(xy 28.817003 -308.586957) (xy 28.793331 -308.637454) (xy 28.778726 -308.65953) (xy 30.405576 -308.65953)
			(xy 30.409647 -308.603908) (xy 30.421773 -308.549471) (xy 30.441696 -308.49738) (xy 30.468992 -308.448745)
			(xy 30.503078 -308.404602) (xy 30.543227 -308.365893) (xy 30.588585 -308.333442) (xy 30.638185 -308.307941)
			(xy 30.690969 -308.289934) (xy 30.745812 -308.279804) (xy 30.801546 -308.277767) (xy 30.856983 -308.283867)
			(xy 30.91094 -308.297973) (xy 30.962269 -308.319785) (xy 31.009875 -308.348839) (xy 31.052743 -308.384514)
			(xy 31.08996 -308.426051) (xy 31.120733 -308.472564) (xy 31.144405 -308.523061) (xy 31.160473 -308.576468)
			(xy 31.168593 -308.631644) (xy 31.169102 -308.65953) (xy 31.168593 -308.687416) (xy 31.160473 -308.742592)
			(xy 31.144405 -308.795999) (xy 31.120733 -308.846496) (xy 31.08996 -308.893009) (xy 31.052743 -308.934546)
			(xy 31.009875 -308.970221) (xy 30.962269 -308.999275) (xy 30.91094 -309.021087) (xy 30.856983 -309.035193)
			(xy 30.801546 -309.041293) (xy 30.745812 -309.039256) (xy 30.690969 -309.029126) (xy 30.638185 -309.011119)
			(xy 30.588585 -308.985618) (xy 30.543227 -308.953167) (xy 30.503078 -308.914458) (xy 30.468992 -308.870315)
			(xy 30.441696 -308.82168) (xy 30.421773 -308.769589) (xy 30.409647 -308.715152) (xy 30.405576 -308.65953)
			(xy 28.778726 -308.65953) (xy 28.762558 -308.683967) (xy 28.725341 -308.725504) (xy 28.682473 -308.761179)
			(xy 28.634867 -308.790233) (xy 28.583538 -308.812045) (xy 28.529581 -308.826151) (xy 28.474144 -308.832251)
			(xy 28.41841 -308.830214) (xy 28.363567 -308.820084) (xy 28.310783 -308.802077) (xy 28.261183 -308.776576)
			(xy 28.215825 -308.744125) (xy 28.175676 -308.705416) (xy 28.14159 -308.661273) (xy 28.114294 -308.612638)
			(xy 28.094371 -308.560547) (xy 28.082245 -308.50611) (xy 28.078174 -308.450488) (xy 17.71396 -308.450488)
			(xy 17.71396 -309.414926) (xy 26.999944 -309.414926) (xy 27.004015 -309.359304) (xy 27.016141 -309.304867)
			(xy 27.036064 -309.252776) (xy 27.06336 -309.204141) (xy 27.097446 -309.159998) (xy 27.137595 -309.121289)
			(xy 27.182953 -309.088838) (xy 27.232553 -309.063337) (xy 27.285337 -309.04533) (xy 27.34018 -309.0352)
			(xy 27.395914 -309.033163) (xy 27.451351 -309.039263) (xy 27.505308 -309.053369) (xy 27.556637 -309.075181)
			(xy 27.604243 -309.104235) (xy 27.647111 -309.13991) (xy 27.684328 -309.181447) (xy 27.696462 -309.199788)
			(xy 36.544008 -309.199788) (xy 36.547968 -309.150734) (xy 36.559745 -309.10295) (xy 36.579036 -309.057674)
			(xy 36.605339 -309.016078) (xy 36.637974 -308.979241) (xy 36.676095 -308.948116) (xy 36.718716 -308.923509)
			(xy 36.764732 -308.906057) (xy 36.812951 -308.896213) (xy 36.862126 -308.894232) (xy 36.910981 -308.900164)
			(xy 36.958252 -308.913856) (xy 37.002714 -308.934954) (xy 37.043217 -308.96291) (xy 37.07871 -308.997002)
			(xy 37.108275 -309.036346) (xy 37.131146 -309.079923) (xy 37.14673 -309.126604) (xy 37.154625 -309.175181)
			(xy 37.15512 -309.199788) (xy 37.493968 -309.199788) (xy 37.497928 -309.150734) (xy 37.509705 -309.10295)
			(xy 37.528996 -309.057674) (xy 37.555299 -309.016078) (xy 37.587934 -308.979241) (xy 37.626055 -308.948116)
			(xy 37.668676 -308.923509) (xy 37.714692 -308.906057) (xy 37.762911 -308.896213) (xy 37.812086 -308.894232)
			(xy 37.860941 -308.900164) (xy 37.908212 -308.913856) (xy 37.952674 -308.934954) (xy 37.993177 -308.96291)
			(xy 38.02867 -308.997002) (xy 38.058235 -309.036346) (xy 38.081106 -309.079923) (xy 38.09669 -309.126604)
			(xy 38.104585 -309.175181) (xy 38.10508 -309.199788) (xy 38.104585 -309.224395) (xy 38.104406 -309.225496)
			(xy 38.423338 -309.225496) (xy 38.423338 -309.17408) (xy 38.431381 -309.123298) (xy 38.447269 -309.074399)
			(xy 38.470612 -309.028587) (xy 38.500833 -308.986991) (xy 38.537189 -308.950635) (xy 38.578785 -308.920414)
			(xy 38.624597 -308.897071) (xy 38.673496 -308.881183) (xy 38.724278 -308.87314) (xy 38.775694 -308.87314)
			(xy 38.826476 -308.881183) (xy 38.875375 -308.897071) (xy 38.921187 -308.920414) (xy 38.962783 -308.950635)
			(xy 38.999139 -308.986991) (xy 39.02936 -309.028587) (xy 39.052703 -309.074399) (xy 39.068591 -309.123298)
			(xy 39.076634 -309.17408) (xy 39.077138 -309.199788) (xy 39.076634 -309.225496) (xy 39.373298 -309.225496)
			(xy 39.373298 -309.17408) (xy 39.381341 -309.123298) (xy 39.397229 -309.074399) (xy 39.420572 -309.028587)
			(xy 39.450793 -308.986991) (xy 39.487149 -308.950635) (xy 39.528745 -308.920414) (xy 39.574557 -308.897071)
			(xy 39.623456 -308.881183) (xy 39.674238 -308.87314) (xy 39.725654 -308.87314) (xy 39.776436 -308.881183)
			(xy 39.825335 -308.897071) (xy 39.871147 -308.920414) (xy 39.912743 -308.950635) (xy 39.949099 -308.986991)
			(xy 39.97932 -309.028587) (xy 40.002663 -309.074399) (xy 40.018551 -309.123298) (xy 40.026594 -309.17408)
			(xy 40.027098 -309.199788) (xy 40.344102 -309.199788) (xy 40.348062 -309.150734) (xy 40.359839 -309.10295)
			(xy 40.37913 -309.057674) (xy 40.405433 -309.016078) (xy 40.438068 -308.979241) (xy 40.476189 -308.948116)
			(xy 40.51881 -308.923509) (xy 40.564826 -308.906057) (xy 40.613045 -308.896213) (xy 40.66222 -308.894232)
			(xy 40.711075 -308.900164) (xy 40.758346 -308.913856) (xy 40.802808 -308.934954) (xy 40.843311 -308.96291)
			(xy 40.878804 -308.997002) (xy 40.908369 -309.036346) (xy 40.93124 -309.079923) (xy 40.946824 -309.126604)
			(xy 40.954719 -309.175181) (xy 40.955214 -309.199788) (xy 40.954719 -309.224395) (xy 40.95454 -309.225496)
			(xy 41.273218 -309.225496) (xy 41.273218 -309.17408) (xy 41.281261 -309.123298) (xy 41.297149 -309.074399)
			(xy 41.320492 -309.028587) (xy 41.350713 -308.986991) (xy 41.387069 -308.950635) (xy 41.428665 -308.920414)
			(xy 41.474477 -308.897071) (xy 41.523376 -308.881183) (xy 41.574158 -308.87314) (xy 41.625574 -308.87314)
			(xy 41.676356 -308.881183) (xy 41.725255 -308.897071) (xy 41.771067 -308.920414) (xy 41.812663 -308.950635)
			(xy 41.849019 -308.986991) (xy 41.87924 -309.028587) (xy 41.902583 -309.074399) (xy 41.918471 -309.123298)
			(xy 41.926514 -309.17408) (xy 41.927018 -309.199788) (xy 41.926514 -309.225496) (xy 42.223178 -309.225496)
			(xy 42.223178 -309.17408) (xy 42.231221 -309.123298) (xy 42.247109 -309.074399) (xy 42.270452 -309.028587)
			(xy 42.300673 -308.986991) (xy 42.337029 -308.950635) (xy 42.378625 -308.920414) (xy 42.424437 -308.897071)
			(xy 42.473336 -308.881183) (xy 42.524118 -308.87314) (xy 42.575534 -308.87314) (xy 42.626316 -308.881183)
			(xy 42.675215 -308.897071) (xy 42.721027 -308.920414) (xy 42.762623 -308.950635) (xy 42.798979 -308.986991)
			(xy 42.8292 -309.028587) (xy 42.852543 -309.074399) (xy 42.868431 -309.123298) (xy 42.876474 -309.17408)
			(xy 42.876978 -309.199788) (xy 43.193982 -309.199788) (xy 43.197942 -309.150734) (xy 43.209719 -309.10295)
			(xy 43.22901 -309.057674) (xy 43.255313 -309.016078) (xy 43.287948 -308.979241) (xy 43.326069 -308.948116)
			(xy 43.36869 -308.923509) (xy 43.414706 -308.906057) (xy 43.462925 -308.896213) (xy 43.5121 -308.894232)
			(xy 43.560955 -308.900164) (xy 43.608226 -308.913856) (xy 43.652688 -308.934954) (xy 43.693191 -308.96291)
			(xy 43.728684 -308.997002) (xy 43.758249 -309.036346) (xy 43.78112 -309.079923) (xy 43.796704 -309.126604)
			(xy 43.804599 -309.175181) (xy 43.805094 -309.199788) (xy 44.143942 -309.199788) (xy 44.147902 -309.150734)
			(xy 44.159679 -309.10295) (xy 44.17897 -309.057674) (xy 44.205273 -309.016078) (xy 44.237908 -308.979241)
			(xy 44.276029 -308.948116) (xy 44.31865 -308.923509) (xy 44.364666 -308.906057) (xy 44.412885 -308.896213)
			(xy 44.46206 -308.894232) (xy 44.510915 -308.900164) (xy 44.558186 -308.913856) (xy 44.602648 -308.934954)
			(xy 44.643151 -308.96291) (xy 44.678644 -308.997002) (xy 44.708209 -309.036346) (xy 44.73108 -309.079923)
			(xy 44.746664 -309.126604) (xy 44.754559 -309.175181) (xy 44.755054 -309.199788) (xy 45.094156 -309.199788)
			(xy 45.098116 -309.150734) (xy 45.109893 -309.10295) (xy 45.129184 -309.057674) (xy 45.155487 -309.016078)
			(xy 45.188122 -308.979241) (xy 45.226243 -308.948116) (xy 45.268864 -308.923509) (xy 45.31488 -308.906057)
			(xy 45.363099 -308.896213) (xy 45.412274 -308.894232) (xy 45.461129 -308.900164) (xy 45.5084 -308.913856)
			(xy 45.552862 -308.934954) (xy 45.593365 -308.96291) (xy 45.628858 -308.997002) (xy 45.658423 -309.036346)
			(xy 45.681294 -309.079923) (xy 45.696878 -309.126604) (xy 45.704773 -309.175181) (xy 45.705268 -309.199788)
			(xy 46.044116 -309.199788) (xy 46.048076 -309.150734) (xy 46.059853 -309.10295) (xy 46.079144 -309.057674)
			(xy 46.105447 -309.016078) (xy 46.138082 -308.979241) (xy 46.176203 -308.948116) (xy 46.218824 -308.923509)
			(xy 46.26484 -308.906057) (xy 46.313059 -308.896213) (xy 46.362234 -308.894232) (xy 46.411089 -308.900164)
			(xy 46.45836 -308.913856) (xy 46.502822 -308.934954) (xy 46.543325 -308.96291) (xy 46.578818 -308.997002)
			(xy 46.608383 -309.036346) (xy 46.631254 -309.079923) (xy 46.646838 -309.126604) (xy 46.654733 -309.175181)
			(xy 46.655228 -309.199788) (xy 46.994076 -309.199788) (xy 46.998036 -309.150734) (xy 47.009813 -309.10295)
			(xy 47.029104 -309.057674) (xy 47.055407 -309.016078) (xy 47.088042 -308.979241) (xy 47.126163 -308.948116)
			(xy 47.168784 -308.923509) (xy 47.2148 -308.906057) (xy 47.263019 -308.896213) (xy 47.312194 -308.894232)
			(xy 47.361049 -308.900164) (xy 47.40832 -308.913856) (xy 47.452782 -308.934954) (xy 47.493285 -308.96291)
			(xy 47.528778 -308.997002) (xy 47.558343 -309.036346) (xy 47.581214 -309.079923) (xy 47.596798 -309.126604)
			(xy 47.604693 -309.175181) (xy 47.605188 -309.199788) (xy 47.605021 -309.208114) (xy 47.944042 -309.208114)
			(xy 47.946725 -309.158537) (xy 47.957393 -309.110048) (xy 47.975766 -309.063923) (xy 48.001359 -309.021378)
			(xy 48.033498 -308.983535) (xy 48.071336 -308.95139) (xy 48.113876 -308.925789) (xy 48.159998 -308.907409)
			(xy 48.208485 -308.896732) (xy 48.258062 -308.894041) (xy 48.30742 -308.899405) (xy 48.35526 -308.912685)
			(xy 48.400322 -308.933529) (xy 48.441418 -308.961389) (xy 48.477465 -308.995531) (xy 48.507513 -309.035055)
			(xy 48.530771 -309.078919) (xy 48.546627 -309.125969) (xy 48.554661 -309.174963) (xy 48.555148 -309.199788)
			(xy 48.554969 -309.213971) (xy 48.552298 -309.242211) (xy 48.549814 -309.256176) (xy 48.547528 -309.268622)
			(xy 48.554894 -309.292244) (xy 48.632364 -309.369714) (xy 48.655986 -309.37708) (xy 48.668432 -309.374794)
			(xy 48.682398 -309.372317) (xy 48.710637 -309.369646) (xy 48.72482 -309.36946) (xy 48.74881 -309.369944)
			(xy 48.796199 -309.377452) (xy 48.841831 -309.39228) (xy 48.884582 -309.414064) (xy 48.923399 -309.442266)
			(xy 48.957327 -309.476192) (xy 48.98553 -309.515008) (xy 49.007315 -309.557758) (xy 49.022145 -309.603389)
			(xy 49.029655 -309.650778) (xy 49.030128 -309.674768) (xy 49.029947 -309.688951) (xy 49.027278 -309.717191)
			(xy 49.024794 -309.731156) (xy 49.022508 -309.743602) (xy 49.029874 -309.767224) (xy 49.107344 -309.844694)
			(xy 49.130966 -309.85206) (xy 49.143412 -309.849774) (xy 49.157378 -309.8473) (xy 49.185618 -309.844626)
			(xy 49.1998 -309.84444) (xy 49.22462 -309.844878) (xy 49.273606 -309.852908) (xy 49.320648 -309.868758)
			(xy 49.364506 -309.892009) (xy 49.404025 -309.922049) (xy 49.438163 -309.958087) (xy 49.466022 -309.999172)
			(xy 49.486867 -310.044224) (xy 49.500149 -310.092054) (xy 49.505518 -310.141403) (xy 49.505066 -310.149748)
			(xy 49.843956 -310.149748) (xy 49.847916 -310.100694) (xy 49.859693 -310.05291) (xy 49.878984 -310.007634)
			(xy 49.905287 -309.966038) (xy 49.937922 -309.929201) (xy 49.976043 -309.898076) (xy 50.018664 -309.873469)
			(xy 50.06468 -309.856017) (xy 50.112899 -309.846173) (xy 50.162074 -309.844192) (xy 50.210929 -309.850124)
			(xy 50.2582 -309.863816) (xy 50.302662 -309.884914) (xy 50.343165 -309.91287) (xy 50.378658 -309.946962)
			(xy 50.408223 -309.986306) (xy 50.431094 -310.029883) (xy 50.446678 -310.076564) (xy 50.454573 -310.125141)
			(xy 50.455068 -310.149748) (xy 50.79417 -310.149748) (xy 50.79813 -310.100694) (xy 50.809907 -310.05291)
			(xy 50.829198 -310.007634) (xy 50.855501 -309.966038) (xy 50.888136 -309.929201) (xy 50.926257 -309.898076)
			(xy 50.968878 -309.873469) (xy 51.014894 -309.856017) (xy 51.063113 -309.846173) (xy 51.112288 -309.844192)
			(xy 51.161143 -309.850124) (xy 51.208414 -309.863816) (xy 51.252876 -309.884914) (xy 51.293379 -309.91287)
			(xy 51.328872 -309.946962) (xy 51.358437 -309.986306) (xy 51.381308 -310.029883) (xy 51.396892 -310.076564)
			(xy 51.404787 -310.125141) (xy 51.405282 -310.149748) (xy 51.74413 -310.149748) (xy 51.74809 -310.100694)
			(xy 51.759867 -310.05291) (xy 51.779158 -310.007634) (xy 51.805461 -309.966038) (xy 51.838096 -309.929201)
			(xy 51.876217 -309.898076) (xy 51.918838 -309.873469) (xy 51.964854 -309.856017) (xy 52.013073 -309.846173)
			(xy 52.062248 -309.844192) (xy 52.111103 -309.850124) (xy 52.158374 -309.863816) (xy 52.202836 -309.884914)
			(xy 52.243339 -309.91287) (xy 52.278832 -309.946962) (xy 52.308397 -309.986306) (xy 52.331268 -310.029883)
			(xy 52.346852 -310.076564) (xy 52.354747 -310.125141) (xy 52.355242 -310.149748) (xy 52.69409 -310.149748)
			(xy 52.69805 -310.100694) (xy 52.709827 -310.05291) (xy 52.729118 -310.007634) (xy 52.755421 -309.966038)
			(xy 52.788056 -309.929201) (xy 52.826177 -309.898076) (xy 52.868798 -309.873469) (xy 52.914814 -309.856017)
			(xy 52.963033 -309.846173) (xy 53.012208 -309.844192) (xy 53.061063 -309.850124) (xy 53.108334 -309.863816)
			(xy 53.152796 -309.884914) (xy 53.193299 -309.91287) (xy 53.228792 -309.946962) (xy 53.258357 -309.986306)
			(xy 53.281228 -310.029883) (xy 53.296812 -310.076564) (xy 53.304707 -310.125141) (xy 53.305202 -310.149748)
			(xy 53.64405 -310.149748) (xy 53.64801 -310.100694) (xy 53.659787 -310.05291) (xy 53.679078 -310.007634)
			(xy 53.705381 -309.966038) (xy 53.738016 -309.929201) (xy 53.776137 -309.898076) (xy 53.818758 -309.873469)
			(xy 53.864774 -309.856017) (xy 53.912993 -309.846173) (xy 53.962168 -309.844192) (xy 54.011023 -309.850124)
			(xy 54.058294 -309.863816) (xy 54.102756 -309.884914) (xy 54.143259 -309.91287) (xy 54.178752 -309.946962)
			(xy 54.208317 -309.986306) (xy 54.231188 -310.029883) (xy 54.246772 -310.076564) (xy 54.254667 -310.125141)
			(xy 54.255162 -310.149748) (xy 54.59401 -310.149748) (xy 54.59797 -310.100694) (xy 54.609747 -310.05291)
			(xy 54.629038 -310.007634) (xy 54.655341 -309.966038) (xy 54.687976 -309.929201) (xy 54.726097 -309.898076)
			(xy 54.768718 -309.873469) (xy 54.814734 -309.856017) (xy 54.862953 -309.846173) (xy 54.912128 -309.844192)
			(xy 54.960983 -309.850124) (xy 55.008254 -309.863816) (xy 55.052716 -309.884914) (xy 55.093219 -309.91287)
			(xy 55.128712 -309.946962) (xy 55.158277 -309.986306) (xy 55.181148 -310.029883) (xy 55.196732 -310.076564)
			(xy 55.204627 -310.125141) (xy 55.205122 -310.149748) (xy 55.54397 -310.149748) (xy 55.54793 -310.100694)
			(xy 55.559707 -310.05291) (xy 55.578998 -310.007634) (xy 55.605301 -309.966038) (xy 55.637936 -309.929201)
			(xy 55.676057 -309.898076) (xy 55.718678 -309.873469) (xy 55.764694 -309.856017) (xy 55.812913 -309.846173)
			(xy 55.862088 -309.844192) (xy 55.910943 -309.850124) (xy 55.958214 -309.863816) (xy 56.002676 -309.884914)
			(xy 56.043179 -309.91287) (xy 56.078672 -309.946962) (xy 56.108237 -309.986306) (xy 56.131108 -310.029883)
			(xy 56.146692 -310.076564) (xy 56.154587 -310.125141) (xy 56.155082 -310.149748) (xy 56.494184 -310.149748)
			(xy 56.498144 -310.100694) (xy 56.509921 -310.05291) (xy 56.529212 -310.007634) (xy 56.555515 -309.966038)
			(xy 56.58815 -309.929201) (xy 56.626271 -309.898076) (xy 56.668892 -309.873469) (xy 56.714908 -309.856017)
			(xy 56.763127 -309.846173) (xy 56.812302 -309.844192) (xy 56.861157 -309.850124) (xy 56.908428 -309.863816)
			(xy 56.95289 -309.884914) (xy 56.993393 -309.91287) (xy 57.028886 -309.946962) (xy 57.058451 -309.986306)
			(xy 57.081322 -310.029883) (xy 57.096906 -310.076564) (xy 57.104801 -310.125141) (xy 57.105296 -310.149748)
			(xy 57.444144 -310.149748) (xy 57.448104 -310.100694) (xy 57.459881 -310.05291) (xy 57.479172 -310.007634)
			(xy 57.505475 -309.966038) (xy 57.53811 -309.929201) (xy 57.576231 -309.898076) (xy 57.618852 -309.873469)
			(xy 57.664868 -309.856017) (xy 57.713087 -309.846173) (xy 57.762262 -309.844192) (xy 57.811117 -309.850124)
			(xy 57.858388 -309.863816) (xy 57.90285 -309.884914) (xy 57.943353 -309.91287) (xy 57.978846 -309.946962)
			(xy 58.008411 -309.986306) (xy 58.031282 -310.029883) (xy 58.046866 -310.076564) (xy 58.054761 -310.125141)
			(xy 58.055256 -310.149748) (xy 58.394104 -310.149748) (xy 58.398064 -310.100694) (xy 58.409841 -310.05291)
			(xy 58.429132 -310.007634) (xy 58.455435 -309.966038) (xy 58.48807 -309.929201) (xy 58.526191 -309.898076)
			(xy 58.568812 -309.873469) (xy 58.614828 -309.856017) (xy 58.663047 -309.846173) (xy 58.712222 -309.844192)
			(xy 58.761077 -309.850124) (xy 58.808348 -309.863816) (xy 58.85281 -309.884914) (xy 58.893313 -309.91287)
			(xy 58.928806 -309.946962) (xy 58.958371 -309.986306) (xy 58.981242 -310.029883) (xy 58.996826 -310.076564)
			(xy 59.004721 -310.125141) (xy 59.005216 -310.149748) (xy 59.344064 -310.149748) (xy 59.348024 -310.100694)
			(xy 59.359801 -310.05291) (xy 59.379092 -310.007634) (xy 59.405395 -309.966038) (xy 59.43803 -309.929201)
			(xy 59.476151 -309.898076) (xy 59.518772 -309.873469) (xy 59.564788 -309.856017) (xy 59.613007 -309.846173)
			(xy 59.662182 -309.844192) (xy 59.711037 -309.850124) (xy 59.758308 -309.863816) (xy 59.80277 -309.884914)
			(xy 59.843273 -309.91287) (xy 59.878766 -309.946962) (xy 59.908331 -309.986306) (xy 59.931202 -310.029883)
			(xy 59.946786 -310.076564) (xy 59.954681 -310.125141) (xy 59.955176 -310.149748) (xy 60.294024 -310.149748)
			(xy 60.297984 -310.100694) (xy 60.309761 -310.05291) (xy 60.329052 -310.007634) (xy 60.355355 -309.966038)
			(xy 60.38799 -309.929201) (xy 60.426111 -309.898076) (xy 60.468732 -309.873469) (xy 60.514748 -309.856017)
			(xy 60.562967 -309.846173) (xy 60.612142 -309.844192) (xy 60.660997 -309.850124) (xy 60.708268 -309.863816)
			(xy 60.75273 -309.884914) (xy 60.793233 -309.91287) (xy 60.828726 -309.946962) (xy 60.858291 -309.986306)
			(xy 60.881162 -310.029883) (xy 60.896746 -310.076564) (xy 60.904641 -310.125141) (xy 60.905136 -310.149748)
			(xy 61.243984 -310.149748) (xy 61.247944 -310.100694) (xy 61.259721 -310.05291) (xy 61.279012 -310.007634)
			(xy 61.305315 -309.966038) (xy 61.33795 -309.929201) (xy 61.376071 -309.898076) (xy 61.418692 -309.873469)
			(xy 61.464708 -309.856017) (xy 61.512927 -309.846173) (xy 61.562102 -309.844192) (xy 61.610957 -309.850124)
			(xy 61.658228 -309.863816) (xy 61.70269 -309.884914) (xy 61.743193 -309.91287) (xy 61.778686 -309.946962)
			(xy 61.808251 -309.986306) (xy 61.831122 -310.029883) (xy 61.846706 -310.076564) (xy 61.854601 -310.125141)
			(xy 61.855096 -310.149748) (xy 62.193944 -310.149748) (xy 62.197904 -310.100694) (xy 62.209681 -310.05291)
			(xy 62.228972 -310.007634) (xy 62.255275 -309.966038) (xy 62.28791 -309.929201) (xy 62.326031 -309.898076)
			(xy 62.368652 -309.873469) (xy 62.414668 -309.856017) (xy 62.462887 -309.846173) (xy 62.512062 -309.844192)
			(xy 62.560917 -309.850124) (xy 62.608188 -309.863816) (xy 62.65265 -309.884914) (xy 62.693153 -309.91287)
			(xy 62.728646 -309.946962) (xy 62.758211 -309.986306) (xy 62.781082 -310.029883) (xy 62.796666 -310.076564)
			(xy 62.804561 -310.125141) (xy 62.805056 -310.149748) (xy 63.144158 -310.149748) (xy 63.148118 -310.100694)
			(xy 63.159895 -310.05291) (xy 63.179186 -310.007634) (xy 63.205489 -309.966038) (xy 63.238124 -309.929201)
			(xy 63.276245 -309.898076) (xy 63.318866 -309.873469) (xy 63.364882 -309.856017) (xy 63.413101 -309.846173)
			(xy 63.462276 -309.844192) (xy 63.511131 -309.850124) (xy 63.558402 -309.863816) (xy 63.602864 -309.884914)
			(xy 63.643367 -309.91287) (xy 63.67886 -309.946962) (xy 63.708425 -309.986306) (xy 63.731296 -310.029883)
			(xy 63.74688 -310.076564) (xy 63.754775 -310.125141) (xy 63.75527 -310.149748) (xy 64.094118 -310.149748)
			(xy 64.098078 -310.100694) (xy 64.109855 -310.05291) (xy 64.129146 -310.007634) (xy 64.155449 -309.966038)
			(xy 64.188084 -309.929201) (xy 64.226205 -309.898076) (xy 64.268826 -309.873469) (xy 64.314842 -309.856017)
			(xy 64.363061 -309.846173) (xy 64.412236 -309.844192) (xy 64.461091 -309.850124) (xy 64.508362 -309.863816)
			(xy 64.552824 -309.884914) (xy 64.593327 -309.91287) (xy 64.62882 -309.946962) (xy 64.658385 -309.986306)
			(xy 64.681256 -310.029883) (xy 64.69684 -310.076564) (xy 64.704735 -310.125141) (xy 64.70523 -310.149748)
			(xy 65.044078 -310.149748) (xy 65.048038 -310.100694) (xy 65.059815 -310.05291) (xy 65.079106 -310.007634)
			(xy 65.105409 -309.966038) (xy 65.138044 -309.929201) (xy 65.176165 -309.898076) (xy 65.218786 -309.873469)
			(xy 65.264802 -309.856017) (xy 65.313021 -309.846173) (xy 65.362196 -309.844192) (xy 65.411051 -309.850124)
			(xy 65.458322 -309.863816) (xy 65.502784 -309.884914) (xy 65.543287 -309.91287) (xy 65.57878 -309.946962)
			(xy 65.608345 -309.986306) (xy 65.631216 -310.029883) (xy 65.6468 -310.076564) (xy 65.654695 -310.125141)
			(xy 65.65519 -310.149748) (xy 65.994038 -310.149748) (xy 65.997998 -310.100694) (xy 66.009775 -310.05291)
			(xy 66.029066 -310.007634) (xy 66.055369 -309.966038) (xy 66.088004 -309.929201) (xy 66.126125 -309.898076)
			(xy 66.168746 -309.873469) (xy 66.214762 -309.856017) (xy 66.262981 -309.846173) (xy 66.312156 -309.844192)
			(xy 66.361011 -309.850124) (xy 66.408282 -309.863816) (xy 66.452744 -309.884914) (xy 66.493247 -309.91287)
			(xy 66.52874 -309.946962) (xy 66.558305 -309.986306) (xy 66.581176 -310.029883) (xy 66.59676 -310.076564)
			(xy 66.604655 -310.125141) (xy 66.60515 -310.149748) (xy 66.943998 -310.149748) (xy 66.947958 -310.100694)
			(xy 66.959735 -310.05291) (xy 66.979026 -310.007634) (xy 67.005329 -309.966038) (xy 67.037964 -309.929201)
			(xy 67.076085 -309.898076) (xy 67.118706 -309.873469) (xy 67.164722 -309.856017) (xy 67.212941 -309.846173)
			(xy 67.262116 -309.844192) (xy 67.310971 -309.850124) (xy 67.358242 -309.863816) (xy 67.402704 -309.884914)
			(xy 67.443207 -309.91287) (xy 67.4787 -309.946962) (xy 67.508265 -309.986306) (xy 67.531136 -310.029883)
			(xy 67.54672 -310.076564) (xy 67.554615 -310.125141) (xy 67.55511 -310.149748) (xy 67.893958 -310.149748)
			(xy 67.897918 -310.100694) (xy 67.909695 -310.05291) (xy 67.928986 -310.007634) (xy 67.955289 -309.966038)
			(xy 67.987924 -309.929201) (xy 68.026045 -309.898076) (xy 68.068666 -309.873469) (xy 68.114682 -309.856017)
			(xy 68.162901 -309.846173) (xy 68.212076 -309.844192) (xy 68.260931 -309.850124) (xy 68.308202 -309.863816)
			(xy 68.352664 -309.884914) (xy 68.393167 -309.91287) (xy 68.42866 -309.946962) (xy 68.458225 -309.986306)
			(xy 68.481096 -310.029883) (xy 68.49668 -310.076564) (xy 68.504575 -310.125141) (xy 68.50507 -310.149748)
			(xy 68.844172 -310.149748) (xy 68.848132 -310.100694) (xy 68.859909 -310.05291) (xy 68.8792 -310.007634)
			(xy 68.905503 -309.966038) (xy 68.938138 -309.929201) (xy 68.976259 -309.898076) (xy 69.01888 -309.873469)
			(xy 69.064896 -309.856017) (xy 69.113115 -309.846173) (xy 69.16229 -309.844192) (xy 69.211145 -309.850124)
			(xy 69.258416 -309.863816) (xy 69.302878 -309.884914) (xy 69.343381 -309.91287) (xy 69.378874 -309.946962)
			(xy 69.408439 -309.986306) (xy 69.43131 -310.029883) (xy 69.446894 -310.076564) (xy 69.454789 -310.125141)
			(xy 69.455284 -310.149748) (xy 69.794132 -310.149748) (xy 69.798092 -310.100694) (xy 69.809869 -310.05291)
			(xy 69.82916 -310.007634) (xy 69.855463 -309.966038) (xy 69.888098 -309.929201) (xy 69.926219 -309.898076)
			(xy 69.96884 -309.873469) (xy 70.014856 -309.856017) (xy 70.063075 -309.846173) (xy 70.11225 -309.844192)
			(xy 70.161105 -309.850124) (xy 70.208376 -309.863816) (xy 70.252838 -309.884914) (xy 70.293341 -309.91287)
			(xy 70.328834 -309.946962) (xy 70.358399 -309.986306) (xy 70.38127 -310.029883) (xy 70.396854 -310.076564)
			(xy 70.404749 -310.125141) (xy 70.405244 -310.149748) (xy 70.744092 -310.149748) (xy 70.748052 -310.100694)
			(xy 70.759829 -310.05291) (xy 70.77912 -310.007634) (xy 70.805423 -309.966038) (xy 70.838058 -309.929201)
			(xy 70.876179 -309.898076) (xy 70.9188 -309.873469) (xy 70.964816 -309.856017) (xy 71.013035 -309.846173)
			(xy 71.06221 -309.844192) (xy 71.111065 -309.850124) (xy 71.158336 -309.863816) (xy 71.202798 -309.884914)
			(xy 71.243301 -309.91287) (xy 71.278794 -309.946962) (xy 71.308359 -309.986306) (xy 71.33123 -310.029883)
			(xy 71.346814 -310.076564) (xy 71.354709 -310.125141) (xy 71.355204 -310.149748) (xy 71.694052 -310.149748)
			(xy 71.698012 -310.100694) (xy 71.709789 -310.05291) (xy 71.72908 -310.007634) (xy 71.755383 -309.966038)
			(xy 71.788018 -309.929201) (xy 71.826139 -309.898076) (xy 71.86876 -309.873469) (xy 71.914776 -309.856017)
			(xy 71.962995 -309.846173) (xy 72.01217 -309.844192) (xy 72.061025 -309.850124) (xy 72.108296 -309.863816)
			(xy 72.152758 -309.884914) (xy 72.193261 -309.91287) (xy 72.228754 -309.946962) (xy 72.258319 -309.986306)
			(xy 72.28119 -310.029883) (xy 72.296774 -310.076564) (xy 72.304669 -310.125141) (xy 72.305164 -310.149748)
			(xy 72.644012 -310.149748) (xy 72.647972 -310.100694) (xy 72.659749 -310.05291) (xy 72.67904 -310.007634)
			(xy 72.705343 -309.966038) (xy 72.737978 -309.929201) (xy 72.776099 -309.898076) (xy 72.81872 -309.873469)
			(xy 72.864736 -309.856017) (xy 72.912955 -309.846173) (xy 72.96213 -309.844192) (xy 73.010985 -309.850124)
			(xy 73.058256 -309.863816) (xy 73.102718 -309.884914) (xy 73.143221 -309.91287) (xy 73.178714 -309.946962)
			(xy 73.208279 -309.986306) (xy 73.23115 -310.029883) (xy 73.246734 -310.076564) (xy 73.254629 -310.125141)
			(xy 73.255124 -310.149748) (xy 73.593972 -310.149748) (xy 73.597932 -310.100694) (xy 73.609709 -310.05291)
			(xy 73.629 -310.007634) (xy 73.655303 -309.966038) (xy 73.687938 -309.929201) (xy 73.726059 -309.898076)
			(xy 73.76868 -309.873469) (xy 73.814696 -309.856017) (xy 73.862915 -309.846173) (xy 73.91209 -309.844192)
			(xy 73.960945 -309.850124) (xy 74.008216 -309.863816) (xy 74.052678 -309.884914) (xy 74.093181 -309.91287)
			(xy 74.128674 -309.946962) (xy 74.158239 -309.986306) (xy 74.18111 -310.029883) (xy 74.196694 -310.076564)
			(xy 74.204589 -310.125141) (xy 74.205084 -310.149748) (xy 74.544186 -310.149748) (xy 74.548146 -310.100694)
			(xy 74.559923 -310.05291) (xy 74.579214 -310.007634) (xy 74.605517 -309.966038) (xy 74.638152 -309.929201)
			(xy 74.676273 -309.898076) (xy 74.718894 -309.873469) (xy 74.76491 -309.856017) (xy 74.813129 -309.846173)
			(xy 74.862304 -309.844192) (xy 74.911159 -309.850124) (xy 74.95843 -309.863816) (xy 75.002892 -309.884914)
			(xy 75.043395 -309.91287) (xy 75.078888 -309.946962) (xy 75.108453 -309.986306) (xy 75.131324 -310.029883)
			(xy 75.146908 -310.076564) (xy 75.154803 -310.125141) (xy 75.155298 -310.149748) (xy 75.494146 -310.149748)
			(xy 75.498106 -310.100694) (xy 75.509883 -310.05291) (xy 75.529174 -310.007634) (xy 75.555477 -309.966038)
			(xy 75.588112 -309.929201) (xy 75.626233 -309.898076) (xy 75.668854 -309.873469) (xy 75.71487 -309.856017)
			(xy 75.763089 -309.846173) (xy 75.812264 -309.844192) (xy 75.861119 -309.850124) (xy 75.90839 -309.863816)
			(xy 75.952852 -309.884914) (xy 75.993355 -309.91287) (xy 76.028848 -309.946962) (xy 76.058413 -309.986306)
			(xy 76.081284 -310.029883) (xy 76.096868 -310.076564) (xy 76.104763 -310.125141) (xy 76.105258 -310.149748)
			(xy 76.444106 -310.149748) (xy 76.448066 -310.100694) (xy 76.459843 -310.05291) (xy 76.479134 -310.007634)
			(xy 76.505437 -309.966038) (xy 76.538072 -309.929201) (xy 76.576193 -309.898076) (xy 76.618814 -309.873469)
			(xy 76.66483 -309.856017) (xy 76.713049 -309.846173) (xy 76.762224 -309.844192) (xy 76.811079 -309.850124)
			(xy 76.85835 -309.863816) (xy 76.902812 -309.884914) (xy 76.943315 -309.91287) (xy 76.978808 -309.946962)
			(xy 77.008373 -309.986306) (xy 77.031244 -310.029883) (xy 77.046828 -310.076564) (xy 77.054723 -310.125141)
			(xy 77.055218 -310.149748) (xy 77.394066 -310.149748) (xy 77.398026 -310.100694) (xy 77.409803 -310.05291)
			(xy 77.429094 -310.007634) (xy 77.455397 -309.966038) (xy 77.488032 -309.929201) (xy 77.526153 -309.898076)
			(xy 77.568774 -309.873469) (xy 77.61479 -309.856017) (xy 77.663009 -309.846173) (xy 77.712184 -309.844192)
			(xy 77.761039 -309.850124) (xy 77.80831 -309.863816) (xy 77.852772 -309.884914) (xy 77.893275 -309.91287)
			(xy 77.928768 -309.946962) (xy 77.958333 -309.986306) (xy 77.981204 -310.029883) (xy 77.996788 -310.076564)
			(xy 78.004683 -310.125141) (xy 78.005178 -310.149748) (xy 78.004683 -310.174355) (xy 77.996788 -310.222932)
			(xy 77.981204 -310.269613) (xy 77.958333 -310.31319) (xy 77.928768 -310.352534) (xy 77.893275 -310.386626)
			(xy 77.852772 -310.414582) (xy 77.80831 -310.43568) (xy 77.761039 -310.449372) (xy 77.712184 -310.455304)
			(xy 77.663009 -310.453323) (xy 77.61479 -310.443479) (xy 77.568774 -310.426027) (xy 77.526153 -310.40142)
			(xy 77.488032 -310.370295) (xy 77.455397 -310.333458) (xy 77.429094 -310.291862) (xy 77.409803 -310.246586)
			(xy 77.398026 -310.198802) (xy 77.394066 -310.149748) (xy 77.055218 -310.149748) (xy 77.054723 -310.174355)
			(xy 77.046828 -310.222932) (xy 77.031244 -310.269613) (xy 77.008373 -310.31319) (xy 76.978808 -310.352534)
			(xy 76.943315 -310.386626) (xy 76.902812 -310.414582) (xy 76.85835 -310.43568) (xy 76.811079 -310.449372)
			(xy 76.762224 -310.455304) (xy 76.713049 -310.453323) (xy 76.66483 -310.443479) (xy 76.618814 -310.426027)
			(xy 76.576193 -310.40142) (xy 76.538072 -310.370295) (xy 76.505437 -310.333458) (xy 76.479134 -310.291862)
			(xy 76.459843 -310.246586) (xy 76.448066 -310.198802) (xy 76.444106 -310.149748) (xy 76.105258 -310.149748)
			(xy 76.104763 -310.174355) (xy 76.096868 -310.222932) (xy 76.081284 -310.269613) (xy 76.058413 -310.31319)
			(xy 76.028848 -310.352534) (xy 75.993355 -310.386626) (xy 75.952852 -310.414582) (xy 75.90839 -310.43568)
			(xy 75.861119 -310.449372) (xy 75.812264 -310.455304) (xy 75.763089 -310.453323) (xy 75.71487 -310.443479)
			(xy 75.668854 -310.426027) (xy 75.626233 -310.40142) (xy 75.588112 -310.370295) (xy 75.555477 -310.333458)
			(xy 75.529174 -310.291862) (xy 75.509883 -310.246586) (xy 75.498106 -310.198802) (xy 75.494146 -310.149748)
			(xy 75.155298 -310.149748) (xy 75.154803 -310.174355) (xy 75.146908 -310.222932) (xy 75.131324 -310.269613)
			(xy 75.108453 -310.31319) (xy 75.078888 -310.352534) (xy 75.043395 -310.386626) (xy 75.002892 -310.414582)
			(xy 74.95843 -310.43568) (xy 74.911159 -310.449372) (xy 74.862304 -310.455304) (xy 74.813129 -310.453323)
			(xy 74.76491 -310.443479) (xy 74.718894 -310.426027) (xy 74.676273 -310.40142) (xy 74.638152 -310.370295)
			(xy 74.605517 -310.333458) (xy 74.579214 -310.291862) (xy 74.559923 -310.246586) (xy 74.548146 -310.198802)
			(xy 74.544186 -310.149748) (xy 74.205084 -310.149748) (xy 74.204589 -310.174355) (xy 74.196694 -310.222932)
			(xy 74.18111 -310.269613) (xy 74.158239 -310.31319) (xy 74.128674 -310.352534) (xy 74.093181 -310.386626)
			(xy 74.052678 -310.414582) (xy 74.008216 -310.43568) (xy 73.960945 -310.449372) (xy 73.91209 -310.455304)
			(xy 73.862915 -310.453323) (xy 73.814696 -310.443479) (xy 73.76868 -310.426027) (xy 73.726059 -310.40142)
			(xy 73.687938 -310.370295) (xy 73.655303 -310.333458) (xy 73.629 -310.291862) (xy 73.609709 -310.246586)
			(xy 73.597932 -310.198802) (xy 73.593972 -310.149748) (xy 73.255124 -310.149748) (xy 73.254629 -310.174355)
			(xy 73.246734 -310.222932) (xy 73.23115 -310.269613) (xy 73.208279 -310.31319) (xy 73.178714 -310.352534)
			(xy 73.143221 -310.386626) (xy 73.102718 -310.414582) (xy 73.058256 -310.43568) (xy 73.010985 -310.449372)
			(xy 72.96213 -310.455304) (xy 72.912955 -310.453323) (xy 72.864736 -310.443479) (xy 72.81872 -310.426027)
			(xy 72.776099 -310.40142) (xy 72.737978 -310.370295) (xy 72.705343 -310.333458) (xy 72.67904 -310.291862)
			(xy 72.659749 -310.246586) (xy 72.647972 -310.198802) (xy 72.644012 -310.149748) (xy 72.305164 -310.149748)
			(xy 72.304669 -310.174355) (xy 72.296774 -310.222932) (xy 72.28119 -310.269613) (xy 72.258319 -310.31319)
			(xy 72.228754 -310.352534) (xy 72.193261 -310.386626) (xy 72.152758 -310.414582) (xy 72.108296 -310.43568)
			(xy 72.061025 -310.449372) (xy 72.01217 -310.455304) (xy 71.962995 -310.453323) (xy 71.914776 -310.443479)
			(xy 71.86876 -310.426027) (xy 71.826139 -310.40142) (xy 71.788018 -310.370295) (xy 71.755383 -310.333458)
			(xy 71.72908 -310.291862) (xy 71.709789 -310.246586) (xy 71.698012 -310.198802) (xy 71.694052 -310.149748)
			(xy 71.355204 -310.149748) (xy 71.354709 -310.174355) (xy 71.346814 -310.222932) (xy 71.33123 -310.269613)
			(xy 71.308359 -310.31319) (xy 71.278794 -310.352534) (xy 71.243301 -310.386626) (xy 71.202798 -310.414582)
			(xy 71.158336 -310.43568) (xy 71.111065 -310.449372) (xy 71.06221 -310.455304) (xy 71.013035 -310.453323)
			(xy 70.964816 -310.443479) (xy 70.9188 -310.426027) (xy 70.876179 -310.40142) (xy 70.838058 -310.370295)
			(xy 70.805423 -310.333458) (xy 70.77912 -310.291862) (xy 70.759829 -310.246586) (xy 70.748052 -310.198802)
			(xy 70.744092 -310.149748) (xy 70.405244 -310.149748) (xy 70.404749 -310.174355) (xy 70.396854 -310.222932)
			(xy 70.38127 -310.269613) (xy 70.358399 -310.31319) (xy 70.328834 -310.352534) (xy 70.293341 -310.386626)
			(xy 70.252838 -310.414582) (xy 70.208376 -310.43568) (xy 70.161105 -310.449372) (xy 70.11225 -310.455304)
			(xy 70.063075 -310.453323) (xy 70.014856 -310.443479) (xy 69.96884 -310.426027) (xy 69.926219 -310.40142)
			(xy 69.888098 -310.370295) (xy 69.855463 -310.333458) (xy 69.82916 -310.291862) (xy 69.809869 -310.246586)
			(xy 69.798092 -310.198802) (xy 69.794132 -310.149748) (xy 69.455284 -310.149748) (xy 69.454789 -310.174355)
			(xy 69.446894 -310.222932) (xy 69.43131 -310.269613) (xy 69.408439 -310.31319) (xy 69.378874 -310.352534)
			(xy 69.343381 -310.386626) (xy 69.302878 -310.414582) (xy 69.258416 -310.43568) (xy 69.211145 -310.449372)
			(xy 69.16229 -310.455304) (xy 69.113115 -310.453323) (xy 69.064896 -310.443479) (xy 69.01888 -310.426027)
			(xy 68.976259 -310.40142) (xy 68.938138 -310.370295) (xy 68.905503 -310.333458) (xy 68.8792 -310.291862)
			(xy 68.859909 -310.246586) (xy 68.848132 -310.198802) (xy 68.844172 -310.149748) (xy 68.50507 -310.149748)
			(xy 68.504575 -310.174355) (xy 68.49668 -310.222932) (xy 68.481096 -310.269613) (xy 68.458225 -310.31319)
			(xy 68.42866 -310.352534) (xy 68.393167 -310.386626) (xy 68.352664 -310.414582) (xy 68.308202 -310.43568)
			(xy 68.260931 -310.449372) (xy 68.212076 -310.455304) (xy 68.162901 -310.453323) (xy 68.114682 -310.443479)
			(xy 68.068666 -310.426027) (xy 68.026045 -310.40142) (xy 67.987924 -310.370295) (xy 67.955289 -310.333458)
			(xy 67.928986 -310.291862) (xy 67.909695 -310.246586) (xy 67.897918 -310.198802) (xy 67.893958 -310.149748)
			(xy 67.55511 -310.149748) (xy 67.554615 -310.174355) (xy 67.54672 -310.222932) (xy 67.531136 -310.269613)
			(xy 67.508265 -310.31319) (xy 67.4787 -310.352534) (xy 67.443207 -310.386626) (xy 67.402704 -310.414582)
			(xy 67.358242 -310.43568) (xy 67.310971 -310.449372) (xy 67.262116 -310.455304) (xy 67.212941 -310.453323)
			(xy 67.164722 -310.443479) (xy 67.118706 -310.426027) (xy 67.076085 -310.40142) (xy 67.037964 -310.370295)
			(xy 67.005329 -310.333458) (xy 66.979026 -310.291862) (xy 66.959735 -310.246586) (xy 66.947958 -310.198802)
			(xy 66.943998 -310.149748) (xy 66.60515 -310.149748) (xy 66.604655 -310.174355) (xy 66.59676 -310.222932)
			(xy 66.581176 -310.269613) (xy 66.558305 -310.31319) (xy 66.52874 -310.352534) (xy 66.493247 -310.386626)
			(xy 66.452744 -310.414582) (xy 66.408282 -310.43568) (xy 66.361011 -310.449372) (xy 66.312156 -310.455304)
			(xy 66.262981 -310.453323) (xy 66.214762 -310.443479) (xy 66.168746 -310.426027) (xy 66.126125 -310.40142)
			(xy 66.088004 -310.370295) (xy 66.055369 -310.333458) (xy 66.029066 -310.291862) (xy 66.009775 -310.246586)
			(xy 65.997998 -310.198802) (xy 65.994038 -310.149748) (xy 65.65519 -310.149748) (xy 65.654695 -310.174355)
			(xy 65.6468 -310.222932) (xy 65.631216 -310.269613) (xy 65.608345 -310.31319) (xy 65.57878 -310.352534)
			(xy 65.543287 -310.386626) (xy 65.502784 -310.414582) (xy 65.458322 -310.43568) (xy 65.411051 -310.449372)
			(xy 65.362196 -310.455304) (xy 65.313021 -310.453323) (xy 65.264802 -310.443479) (xy 65.218786 -310.426027)
			(xy 65.176165 -310.40142) (xy 65.138044 -310.370295) (xy 65.105409 -310.333458) (xy 65.079106 -310.291862)
			(xy 65.059815 -310.246586) (xy 65.048038 -310.198802) (xy 65.044078 -310.149748) (xy 64.70523 -310.149748)
			(xy 64.704735 -310.174355) (xy 64.69684 -310.222932) (xy 64.681256 -310.269613) (xy 64.658385 -310.31319)
			(xy 64.62882 -310.352534) (xy 64.593327 -310.386626) (xy 64.552824 -310.414582) (xy 64.508362 -310.43568)
			(xy 64.461091 -310.449372) (xy 64.412236 -310.455304) (xy 64.363061 -310.453323) (xy 64.314842 -310.443479)
			(xy 64.268826 -310.426027) (xy 64.226205 -310.40142) (xy 64.188084 -310.370295) (xy 64.155449 -310.333458)
			(xy 64.129146 -310.291862) (xy 64.109855 -310.246586) (xy 64.098078 -310.198802) (xy 64.094118 -310.149748)
			(xy 63.75527 -310.149748) (xy 63.754775 -310.174355) (xy 63.74688 -310.222932) (xy 63.731296 -310.269613)
			(xy 63.708425 -310.31319) (xy 63.67886 -310.352534) (xy 63.643367 -310.386626) (xy 63.602864 -310.414582)
			(xy 63.558402 -310.43568) (xy 63.511131 -310.449372) (xy 63.462276 -310.455304) (xy 63.413101 -310.453323)
			(xy 63.364882 -310.443479) (xy 63.318866 -310.426027) (xy 63.276245 -310.40142) (xy 63.238124 -310.370295)
			(xy 63.205489 -310.333458) (xy 63.179186 -310.291862) (xy 63.159895 -310.246586) (xy 63.148118 -310.198802)
			(xy 63.144158 -310.149748) (xy 62.805056 -310.149748) (xy 62.804561 -310.174355) (xy 62.796666 -310.222932)
			(xy 62.781082 -310.269613) (xy 62.758211 -310.31319) (xy 62.728646 -310.352534) (xy 62.693153 -310.386626)
			(xy 62.65265 -310.414582) (xy 62.608188 -310.43568) (xy 62.560917 -310.449372) (xy 62.512062 -310.455304)
			(xy 62.462887 -310.453323) (xy 62.414668 -310.443479) (xy 62.368652 -310.426027) (xy 62.326031 -310.40142)
			(xy 62.28791 -310.370295) (xy 62.255275 -310.333458) (xy 62.228972 -310.291862) (xy 62.209681 -310.246586)
			(xy 62.197904 -310.198802) (xy 62.193944 -310.149748) (xy 61.855096 -310.149748) (xy 61.854601 -310.174355)
			(xy 61.846706 -310.222932) (xy 61.831122 -310.269613) (xy 61.808251 -310.31319) (xy 61.778686 -310.352534)
			(xy 61.743193 -310.386626) (xy 61.70269 -310.414582) (xy 61.658228 -310.43568) (xy 61.610957 -310.449372)
			(xy 61.562102 -310.455304) (xy 61.512927 -310.453323) (xy 61.464708 -310.443479) (xy 61.418692 -310.426027)
			(xy 61.376071 -310.40142) (xy 61.33795 -310.370295) (xy 61.305315 -310.333458) (xy 61.279012 -310.291862)
			(xy 61.259721 -310.246586) (xy 61.247944 -310.198802) (xy 61.243984 -310.149748) (xy 60.905136 -310.149748)
			(xy 60.904641 -310.174355) (xy 60.896746 -310.222932) (xy 60.881162 -310.269613) (xy 60.858291 -310.31319)
			(xy 60.828726 -310.352534) (xy 60.793233 -310.386626) (xy 60.75273 -310.414582) (xy 60.708268 -310.43568)
			(xy 60.660997 -310.449372) (xy 60.612142 -310.455304) (xy 60.562967 -310.453323) (xy 60.514748 -310.443479)
			(xy 60.468732 -310.426027) (xy 60.426111 -310.40142) (xy 60.38799 -310.370295) (xy 60.355355 -310.333458)
			(xy 60.329052 -310.291862) (xy 60.309761 -310.246586) (xy 60.297984 -310.198802) (xy 60.294024 -310.149748)
			(xy 59.955176 -310.149748) (xy 59.954681 -310.174355) (xy 59.946786 -310.222932) (xy 59.931202 -310.269613)
			(xy 59.908331 -310.31319) (xy 59.878766 -310.352534) (xy 59.843273 -310.386626) (xy 59.80277 -310.414582)
			(xy 59.758308 -310.43568) (xy 59.711037 -310.449372) (xy 59.662182 -310.455304) (xy 59.613007 -310.453323)
			(xy 59.564788 -310.443479) (xy 59.518772 -310.426027) (xy 59.476151 -310.40142) (xy 59.43803 -310.370295)
			(xy 59.405395 -310.333458) (xy 59.379092 -310.291862) (xy 59.359801 -310.246586) (xy 59.348024 -310.198802)
			(xy 59.344064 -310.149748) (xy 59.005216 -310.149748) (xy 59.004721 -310.174355) (xy 58.996826 -310.222932)
			(xy 58.981242 -310.269613) (xy 58.958371 -310.31319) (xy 58.928806 -310.352534) (xy 58.893313 -310.386626)
			(xy 58.85281 -310.414582) (xy 58.808348 -310.43568) (xy 58.761077 -310.449372) (xy 58.712222 -310.455304)
			(xy 58.663047 -310.453323) (xy 58.614828 -310.443479) (xy 58.568812 -310.426027) (xy 58.526191 -310.40142)
			(xy 58.48807 -310.370295) (xy 58.455435 -310.333458) (xy 58.429132 -310.291862) (xy 58.409841 -310.246586)
			(xy 58.398064 -310.198802) (xy 58.394104 -310.149748) (xy 58.055256 -310.149748) (xy 58.054761 -310.174355)
			(xy 58.046866 -310.222932) (xy 58.031282 -310.269613) (xy 58.008411 -310.31319) (xy 57.978846 -310.352534)
			(xy 57.943353 -310.386626) (xy 57.90285 -310.414582) (xy 57.858388 -310.43568) (xy 57.811117 -310.449372)
			(xy 57.762262 -310.455304) (xy 57.713087 -310.453323) (xy 57.664868 -310.443479) (xy 57.618852 -310.426027)
			(xy 57.576231 -310.40142) (xy 57.53811 -310.370295) (xy 57.505475 -310.333458) (xy 57.479172 -310.291862)
			(xy 57.459881 -310.246586) (xy 57.448104 -310.198802) (xy 57.444144 -310.149748) (xy 57.105296 -310.149748)
			(xy 57.104801 -310.174355) (xy 57.096906 -310.222932) (xy 57.081322 -310.269613) (xy 57.058451 -310.31319)
			(xy 57.028886 -310.352534) (xy 56.993393 -310.386626) (xy 56.95289 -310.414582) (xy 56.908428 -310.43568)
			(xy 56.861157 -310.449372) (xy 56.812302 -310.455304) (xy 56.763127 -310.453323) (xy 56.714908 -310.443479)
			(xy 56.668892 -310.426027) (xy 56.626271 -310.40142) (xy 56.58815 -310.370295) (xy 56.555515 -310.333458)
			(xy 56.529212 -310.291862) (xy 56.509921 -310.246586) (xy 56.498144 -310.198802) (xy 56.494184 -310.149748)
			(xy 56.155082 -310.149748) (xy 56.154587 -310.174355) (xy 56.146692 -310.222932) (xy 56.131108 -310.269613)
			(xy 56.108237 -310.31319) (xy 56.078672 -310.352534) (xy 56.043179 -310.386626) (xy 56.002676 -310.414582)
			(xy 55.958214 -310.43568) (xy 55.910943 -310.449372) (xy 55.862088 -310.455304) (xy 55.812913 -310.453323)
			(xy 55.764694 -310.443479) (xy 55.718678 -310.426027) (xy 55.676057 -310.40142) (xy 55.637936 -310.370295)
			(xy 55.605301 -310.333458) (xy 55.578998 -310.291862) (xy 55.559707 -310.246586) (xy 55.54793 -310.198802)
			(xy 55.54397 -310.149748) (xy 55.205122 -310.149748) (xy 55.204627 -310.174355) (xy 55.196732 -310.222932)
			(xy 55.181148 -310.269613) (xy 55.158277 -310.31319) (xy 55.128712 -310.352534) (xy 55.093219 -310.386626)
			(xy 55.052716 -310.414582) (xy 55.008254 -310.43568) (xy 54.960983 -310.449372) (xy 54.912128 -310.455304)
			(xy 54.862953 -310.453323) (xy 54.814734 -310.443479) (xy 54.768718 -310.426027) (xy 54.726097 -310.40142)
			(xy 54.687976 -310.370295) (xy 54.655341 -310.333458) (xy 54.629038 -310.291862) (xy 54.609747 -310.246586)
			(xy 54.59797 -310.198802) (xy 54.59401 -310.149748) (xy 54.255162 -310.149748) (xy 54.254667 -310.174355)
			(xy 54.246772 -310.222932) (xy 54.231188 -310.269613) (xy 54.208317 -310.31319) (xy 54.178752 -310.352534)
			(xy 54.143259 -310.386626) (xy 54.102756 -310.414582) (xy 54.058294 -310.43568) (xy 54.011023 -310.449372)
			(xy 53.962168 -310.455304) (xy 53.912993 -310.453323) (xy 53.864774 -310.443479) (xy 53.818758 -310.426027)
			(xy 53.776137 -310.40142) (xy 53.738016 -310.370295) (xy 53.705381 -310.333458) (xy 53.679078 -310.291862)
			(xy 53.659787 -310.246586) (xy 53.64801 -310.198802) (xy 53.64405 -310.149748) (xy 53.305202 -310.149748)
			(xy 53.304707 -310.174355) (xy 53.296812 -310.222932) (xy 53.281228 -310.269613) (xy 53.258357 -310.31319)
			(xy 53.228792 -310.352534) (xy 53.193299 -310.386626) (xy 53.152796 -310.414582) (xy 53.108334 -310.43568)
			(xy 53.061063 -310.449372) (xy 53.012208 -310.455304) (xy 52.963033 -310.453323) (xy 52.914814 -310.443479)
			(xy 52.868798 -310.426027) (xy 52.826177 -310.40142) (xy 52.788056 -310.370295) (xy 52.755421 -310.333458)
			(xy 52.729118 -310.291862) (xy 52.709827 -310.246586) (xy 52.69805 -310.198802) (xy 52.69409 -310.149748)
			(xy 52.355242 -310.149748) (xy 52.354747 -310.174355) (xy 52.346852 -310.222932) (xy 52.331268 -310.269613)
			(xy 52.308397 -310.31319) (xy 52.278832 -310.352534) (xy 52.243339 -310.386626) (xy 52.202836 -310.414582)
			(xy 52.158374 -310.43568) (xy 52.111103 -310.449372) (xy 52.062248 -310.455304) (xy 52.013073 -310.453323)
			(xy 51.964854 -310.443479) (xy 51.918838 -310.426027) (xy 51.876217 -310.40142) (xy 51.838096 -310.370295)
			(xy 51.805461 -310.333458) (xy 51.779158 -310.291862) (xy 51.759867 -310.246586) (xy 51.74809 -310.198802)
			(xy 51.74413 -310.149748) (xy 51.405282 -310.149748) (xy 51.404787 -310.174355) (xy 51.396892 -310.222932)
			(xy 51.381308 -310.269613) (xy 51.358437 -310.31319) (xy 51.328872 -310.352534) (xy 51.293379 -310.386626)
			(xy 51.252876 -310.414582) (xy 51.208414 -310.43568) (xy 51.161143 -310.449372) (xy 51.112288 -310.455304)
			(xy 51.063113 -310.453323) (xy 51.014894 -310.443479) (xy 50.968878 -310.426027) (xy 50.926257 -310.40142)
			(xy 50.888136 -310.370295) (xy 50.855501 -310.333458) (xy 50.829198 -310.291862) (xy 50.809907 -310.246586)
			(xy 50.79813 -310.198802) (xy 50.79417 -310.149748) (xy 50.455068 -310.149748) (xy 50.454573 -310.174355)
			(xy 50.446678 -310.222932) (xy 50.431094 -310.269613) (xy 50.408223 -310.31319) (xy 50.378658 -310.352534)
			(xy 50.343165 -310.386626) (xy 50.302662 -310.414582) (xy 50.2582 -310.43568) (xy 50.210929 -310.449372)
			(xy 50.162074 -310.455304) (xy 50.112899 -310.453323) (xy 50.06468 -310.443479) (xy 50.018664 -310.426027)
			(xy 49.976043 -310.40142) (xy 49.937922 -310.370295) (xy 49.905287 -310.333458) (xy 49.878984 -310.291862)
			(xy 49.859693 -310.246586) (xy 49.847916 -310.198802) (xy 49.843956 -310.149748) (xy 49.505066 -310.149748)
			(xy 49.502834 -310.19097) (xy 49.492165 -310.23945) (xy 49.473795 -310.285566) (xy 49.448206 -310.328102)
			(xy 49.416072 -310.365938) (xy 49.378241 -310.398078) (xy 49.335709 -310.423673) (xy 49.289596 -310.442051)
			(xy 49.241118 -310.452727) (xy 49.191551 -310.45542) (xy 49.142201 -310.450058) (xy 49.094369 -310.436783)
			(xy 49.049314 -310.415945) (xy 49.008224 -310.388093) (xy 48.972181 -310.35396) (xy 48.942135 -310.314446)
			(xy 48.918877 -310.270592) (xy 48.90302 -310.223553) (xy 48.894982 -310.174568) (xy 48.894492 -310.149748)
			(xy 48.894675 -310.135565) (xy 48.897343 -310.107325) (xy 48.899826 -310.09336) (xy 48.902112 -310.080914)
			(xy 48.894746 -310.057292) (xy 48.817276 -309.979822) (xy 48.793654 -309.972456) (xy 48.781208 -309.974742)
			(xy 48.767241 -309.977213) (xy 48.739002 -309.979889) (xy 48.72482 -309.980076) (xy 48.710637 -309.979897)
			(xy 48.682397 -309.977227) (xy 48.668432 -309.974742) (xy 48.655986 -309.972456) (xy 48.632364 -309.979822)
			(xy 48.554894 -310.057292) (xy 48.547528 -310.080914) (xy 48.549814 -310.09336) (xy 48.552295 -310.107325)
			(xy 48.554964 -310.135565) (xy 48.555148 -310.149748) (xy 48.55457 -310.174565) (xy 48.546533 -310.223543)
			(xy 48.530677 -310.270576) (xy 48.507422 -310.314425) (xy 48.477379 -310.353933) (xy 48.44134 -310.388061)
			(xy 48.400254 -310.415908) (xy 48.355205 -310.436742) (xy 48.307378 -310.450013) (xy 48.258035 -310.455372)
			(xy 48.208475 -310.452678) (xy 48.160003 -310.442001) (xy 48.113897 -310.423623) (xy 48.071372 -310.398028)
			(xy 48.033548 -310.36589) (xy 48.001421 -310.328057) (xy 47.975838 -310.285524) (xy 47.957473 -310.239413)
			(xy 47.94681 -310.190938) (xy 47.94413 -310.141377) (xy 47.949503 -310.092035) (xy 47.962789 -310.044212)
			(xy 47.983635 -309.999169) (xy 48.011495 -309.958091) (xy 48.045633 -309.922062) (xy 48.08515 -309.892031)
			(xy 48.129005 -309.868788) (xy 48.176042 -309.852946) (xy 48.225023 -309.844922) (xy 48.24984 -309.84444)
			(xy 48.264023 -309.84461) (xy 48.292263 -309.847287) (xy 48.306228 -309.849774) (xy 48.318674 -309.85206)
			(xy 48.342296 -309.844694) (xy 48.419766 -309.767224) (xy 48.427132 -309.743602) (xy 48.424846 -309.731156)
			(xy 48.422368 -309.71719) (xy 48.419697 -309.688951) (xy 48.419512 -309.674768) (xy 48.419684 -309.660585)
			(xy 48.422359 -309.632345) (xy 48.424846 -309.61838) (xy 48.427132 -309.605934) (xy 48.419766 -309.582312)
			(xy 48.342296 -309.504842) (xy 48.318674 -309.497476) (xy 48.306228 -309.499762) (xy 48.292263 -309.502244)
			(xy 48.264023 -309.504912) (xy 48.24984 -309.505096) (xy 48.225015 -309.504665) (xy 48.176019 -309.496639)
			(xy 48.128967 -309.480792) (xy 48.085099 -309.457541) (xy 48.04557 -309.427499) (xy 48.011422 -309.391458)
			(xy 47.983555 -309.350367) (xy 47.962703 -309.305309) (xy 47.949415 -309.257471) (xy 47.944042 -309.208114)
			(xy 47.605021 -309.208114) (xy 47.604693 -309.224395) (xy 47.596798 -309.272972) (xy 47.581214 -309.319653)
			(xy 47.558343 -309.36323) (xy 47.528778 -309.402574) (xy 47.493285 -309.436666) (xy 47.452782 -309.464622)
			(xy 47.40832 -309.48572) (xy 47.361049 -309.499412) (xy 47.312194 -309.505344) (xy 47.263019 -309.503363)
			(xy 47.2148 -309.493519) (xy 47.168784 -309.476067) (xy 47.126163 -309.45146) (xy 47.088042 -309.420335)
			(xy 47.055407 -309.383498) (xy 47.029104 -309.341902) (xy 47.009813 -309.296626) (xy 46.998036 -309.248842)
			(xy 46.994076 -309.199788) (xy 46.655228 -309.199788) (xy 46.654733 -309.224395) (xy 46.646838 -309.272972)
			(xy 46.631254 -309.319653) (xy 46.608383 -309.36323) (xy 46.578818 -309.402574) (xy 46.543325 -309.436666)
			(xy 46.502822 -309.464622) (xy 46.45836 -309.48572) (xy 46.411089 -309.499412) (xy 46.362234 -309.505344)
			(xy 46.313059 -309.503363) (xy 46.26484 -309.493519) (xy 46.218824 -309.476067) (xy 46.176203 -309.45146)
			(xy 46.138082 -309.420335) (xy 46.105447 -309.383498) (xy 46.079144 -309.341902) (xy 46.059853 -309.296626)
			(xy 46.048076 -309.248842) (xy 46.044116 -309.199788) (xy 45.705268 -309.199788) (xy 45.704773 -309.224395)
			(xy 45.696878 -309.272972) (xy 45.681294 -309.319653) (xy 45.658423 -309.36323) (xy 45.628858 -309.402574)
			(xy 45.593365 -309.436666) (xy 45.552862 -309.464622) (xy 45.5084 -309.48572) (xy 45.461129 -309.499412)
			(xy 45.412274 -309.505344) (xy 45.363099 -309.503363) (xy 45.31488 -309.493519) (xy 45.268864 -309.476067)
			(xy 45.226243 -309.45146) (xy 45.188122 -309.420335) (xy 45.155487 -309.383498) (xy 45.129184 -309.341902)
			(xy 45.109893 -309.296626) (xy 45.098116 -309.248842) (xy 45.094156 -309.199788) (xy 44.755054 -309.199788)
			(xy 44.754559 -309.224395) (xy 44.746664 -309.272972) (xy 44.73108 -309.319653) (xy 44.708209 -309.36323)
			(xy 44.678644 -309.402574) (xy 44.643151 -309.436666) (xy 44.602648 -309.464622) (xy 44.558186 -309.48572)
			(xy 44.510915 -309.499412) (xy 44.46206 -309.505344) (xy 44.412885 -309.503363) (xy 44.364666 -309.493519)
			(xy 44.31865 -309.476067) (xy 44.276029 -309.45146) (xy 44.237908 -309.420335) (xy 44.205273 -309.383498)
			(xy 44.17897 -309.341902) (xy 44.159679 -309.296626) (xy 44.147902 -309.248842) (xy 44.143942 -309.199788)
			(xy 43.805094 -309.199788) (xy 43.804599 -309.224395) (xy 43.796704 -309.272972) (xy 43.78112 -309.319653)
			(xy 43.758249 -309.36323) (xy 43.728684 -309.402574) (xy 43.693191 -309.436666) (xy 43.652688 -309.464622)
			(xy 43.608226 -309.48572) (xy 43.560955 -309.499412) (xy 43.5121 -309.505344) (xy 43.462925 -309.503363)
			(xy 43.414706 -309.493519) (xy 43.36869 -309.476067) (xy 43.326069 -309.45146) (xy 43.287948 -309.420335)
			(xy 43.255313 -309.383498) (xy 43.22901 -309.341902) (xy 43.209719 -309.296626) (xy 43.197942 -309.248842)
			(xy 43.193982 -309.199788) (xy 42.876978 -309.199788) (xy 42.876474 -309.225496) (xy 42.868431 -309.276278)
			(xy 42.852543 -309.325177) (xy 42.8292 -309.370989) (xy 42.798979 -309.412585) (xy 42.762623 -309.448941)
			(xy 42.721027 -309.479162) (xy 42.675215 -309.502505) (xy 42.626316 -309.518393) (xy 42.575534 -309.526436)
			(xy 42.524118 -309.526436) (xy 42.473336 -309.518393) (xy 42.424437 -309.502505) (xy 42.378625 -309.479162)
			(xy 42.337029 -309.448941) (xy 42.300673 -309.412585) (xy 42.270452 -309.370989) (xy 42.247109 -309.325177)
			(xy 42.231221 -309.276278) (xy 42.223178 -309.225496) (xy 41.926514 -309.225496) (xy 41.918471 -309.276278)
			(xy 41.902583 -309.325177) (xy 41.87924 -309.370989) (xy 41.849019 -309.412585) (xy 41.812663 -309.448941)
			(xy 41.771067 -309.479162) (xy 41.725255 -309.502505) (xy 41.676356 -309.518393) (xy 41.625574 -309.526436)
			(xy 41.574158 -309.526436) (xy 41.523376 -309.518393) (xy 41.474477 -309.502505) (xy 41.428665 -309.479162)
			(xy 41.387069 -309.448941) (xy 41.350713 -309.412585) (xy 41.320492 -309.370989) (xy 41.297149 -309.325177)
			(xy 41.281261 -309.276278) (xy 41.273218 -309.225496) (xy 40.95454 -309.225496) (xy 40.946824 -309.272972)
			(xy 40.93124 -309.319653) (xy 40.908369 -309.36323) (xy 40.878804 -309.402574) (xy 40.843311 -309.436666)
			(xy 40.802808 -309.464622) (xy 40.758346 -309.48572) (xy 40.711075 -309.499412) (xy 40.66222 -309.505344)
			(xy 40.613045 -309.503363) (xy 40.564826 -309.493519) (xy 40.51881 -309.476067) (xy 40.476189 -309.45146)
			(xy 40.438068 -309.420335) (xy 40.405433 -309.383498) (xy 40.37913 -309.341902) (xy 40.359839 -309.296626)
			(xy 40.348062 -309.248842) (xy 40.344102 -309.199788) (xy 40.027098 -309.199788) (xy 40.026594 -309.225496)
			(xy 40.018551 -309.276278) (xy 40.002663 -309.325177) (xy 39.97932 -309.370989) (xy 39.949099 -309.412585)
			(xy 39.912743 -309.448941) (xy 39.871147 -309.479162) (xy 39.825335 -309.502505) (xy 39.776436 -309.518393)
			(xy 39.725654 -309.526436) (xy 39.674238 -309.526436) (xy 39.623456 -309.518393) (xy 39.574557 -309.502505)
			(xy 39.528745 -309.479162) (xy 39.487149 -309.448941) (xy 39.450793 -309.412585) (xy 39.420572 -309.370989)
			(xy 39.397229 -309.325177) (xy 39.381341 -309.276278) (xy 39.373298 -309.225496) (xy 39.076634 -309.225496)
			(xy 39.068591 -309.276278) (xy 39.052703 -309.325177) (xy 39.02936 -309.370989) (xy 38.999139 -309.412585)
			(xy 38.962783 -309.448941) (xy 38.921187 -309.479162) (xy 38.875375 -309.502505) (xy 38.826476 -309.518393)
			(xy 38.775694 -309.526436) (xy 38.724278 -309.526436) (xy 38.673496 -309.518393) (xy 38.624597 -309.502505)
			(xy 38.578785 -309.479162) (xy 38.537189 -309.448941) (xy 38.500833 -309.412585) (xy 38.470612 -309.370989)
			(xy 38.447269 -309.325177) (xy 38.431381 -309.276278) (xy 38.423338 -309.225496) (xy 38.104406 -309.225496)
			(xy 38.09669 -309.272972) (xy 38.081106 -309.319653) (xy 38.058235 -309.36323) (xy 38.02867 -309.402574)
			(xy 37.993177 -309.436666) (xy 37.952674 -309.464622) (xy 37.908212 -309.48572) (xy 37.860941 -309.499412)
			(xy 37.812086 -309.505344) (xy 37.762911 -309.503363) (xy 37.714692 -309.493519) (xy 37.668676 -309.476067)
			(xy 37.626055 -309.45146) (xy 37.587934 -309.420335) (xy 37.555299 -309.383498) (xy 37.528996 -309.341902)
			(xy 37.509705 -309.296626) (xy 37.497928 -309.248842) (xy 37.493968 -309.199788) (xy 37.15512 -309.199788)
			(xy 37.154625 -309.224395) (xy 37.14673 -309.272972) (xy 37.131146 -309.319653) (xy 37.108275 -309.36323)
			(xy 37.07871 -309.402574) (xy 37.043217 -309.436666) (xy 37.002714 -309.464622) (xy 36.958252 -309.48572)
			(xy 36.910981 -309.499412) (xy 36.862126 -309.505344) (xy 36.812951 -309.503363) (xy 36.764732 -309.493519)
			(xy 36.718716 -309.476067) (xy 36.676095 -309.45146) (xy 36.637974 -309.420335) (xy 36.605339 -309.383498)
			(xy 36.579036 -309.341902) (xy 36.559745 -309.296626) (xy 36.547968 -309.248842) (xy 36.544008 -309.199788)
			(xy 27.696462 -309.199788) (xy 27.715101 -309.22796) (xy 27.738773 -309.278457) (xy 27.754841 -309.331864)
			(xy 27.762961 -309.38704) (xy 27.76347 -309.414926) (xy 27.762961 -309.442812) (xy 27.754841 -309.497988)
			(xy 27.738773 -309.551395) (xy 27.715101 -309.601892) (xy 27.684328 -309.648405) (xy 27.647111 -309.689942)
			(xy 27.604243 -309.725617) (xy 27.556637 -309.754671) (xy 27.505308 -309.776483) (xy 27.451351 -309.790589)
			(xy 27.395914 -309.796689) (xy 27.34018 -309.794652) (xy 27.285337 -309.784522) (xy 27.232553 -309.766515)
			(xy 27.182953 -309.741014) (xy 27.137595 -309.708563) (xy 27.097446 -309.669854) (xy 27.06336 -309.625711)
			(xy 27.036064 -309.577076) (xy 27.016141 -309.524985) (xy 27.004015 -309.470548) (xy 26.999944 -309.414926)
			(xy 17.71396 -309.414926) (xy 17.71396 -310.237378) (xy 34.10077 -310.237378) (xy 34.101256 -310.210127)
			(xy 34.109012 -310.156179) (xy 34.124367 -310.103884) (xy 34.147009 -310.054307) (xy 34.176475 -310.008457)
			(xy 34.212166 -309.967266) (xy 34.253357 -309.931575) (xy 34.299207 -309.902109) (xy 34.348784 -309.879467)
			(xy 34.401079 -309.864112) (xy 34.455027 -309.856356) (xy 34.509529 -309.856356) (xy 34.563477 -309.864112)
			(xy 34.615772 -309.879467) (xy 34.665349 -309.902109) (xy 34.711199 -309.931575) (xy 34.75239 -309.967266)
			(xy 34.788081 -310.008457) (xy 34.817547 -310.054307) (xy 34.840189 -310.103884) (xy 34.85373 -310.150002)
			(xy 35.593794 -310.150002) (xy 35.597754 -310.100948) (xy 35.609531 -310.053164) (xy 35.628822 -310.007888)
			(xy 35.655125 -309.966292) (xy 35.68776 -309.929455) (xy 35.725881 -309.89833) (xy 35.768502 -309.873723)
			(xy 35.814518 -309.856271) (xy 35.862737 -309.846427) (xy 35.911912 -309.844446) (xy 35.960767 -309.850378)
			(xy 36.008038 -309.86407) (xy 36.0525 -309.885168) (xy 36.093003 -309.913124) (xy 36.128496 -309.947216)
			(xy 36.158061 -309.98656) (xy 36.180932 -310.030137) (xy 36.196516 -310.076818) (xy 36.204411 -310.125395)
			(xy 36.204906 -310.150002) (xy 36.204411 -310.174609) (xy 36.204273 -310.175456) (xy 36.523164 -310.175456)
			(xy 36.523164 -310.12404) (xy 36.531207 -310.073258) (xy 36.547095 -310.024359) (xy 36.570438 -309.978547)
			(xy 36.600659 -309.936951) (xy 36.637015 -309.900595) (xy 36.678611 -309.870374) (xy 36.724423 -309.847031)
			(xy 36.773322 -309.831143) (xy 36.824104 -309.8231) (xy 36.87552 -309.8231) (xy 36.926302 -309.831143)
			(xy 36.975201 -309.847031) (xy 37.021013 -309.870374) (xy 37.062609 -309.900595) (xy 37.098965 -309.936951)
			(xy 37.129186 -309.978547) (xy 37.152529 -310.024359) (xy 37.168417 -310.073258) (xy 37.17646 -310.12404)
			(xy 37.176964 -310.149748) (xy 37.17646 -310.175456) (xy 37.473124 -310.175456) (xy 37.473124 -310.12404)
			(xy 37.481167 -310.073258) (xy 37.497055 -310.024359) (xy 37.520398 -309.978547) (xy 37.550619 -309.936951)
			(xy 37.586975 -309.900595) (xy 37.628571 -309.870374) (xy 37.674383 -309.847031) (xy 37.723282 -309.831143)
			(xy 37.774064 -309.8231) (xy 37.82548 -309.8231) (xy 37.876262 -309.831143) (xy 37.925161 -309.847031)
			(xy 37.970973 -309.870374) (xy 38.012569 -309.900595) (xy 38.048925 -309.936951) (xy 38.079146 -309.978547)
			(xy 38.102489 -310.024359) (xy 38.118377 -310.073258) (xy 38.12642 -310.12404) (xy 38.126924 -310.149748)
			(xy 38.444182 -310.149748) (xy 38.448142 -310.100694) (xy 38.459919 -310.05291) (xy 38.47921 -310.007634)
			(xy 38.505513 -309.966038) (xy 38.538148 -309.929201) (xy 38.576269 -309.898076) (xy 38.61889 -309.873469)
			(xy 38.664906 -309.856017) (xy 38.713125 -309.846173) (xy 38.7623 -309.844192) (xy 38.811155 -309.850124)
			(xy 38.858426 -309.863816) (xy 38.902888 -309.884914) (xy 38.943391 -309.91287) (xy 38.978884 -309.946962)
			(xy 39.008449 -309.986306) (xy 39.03132 -310.029883) (xy 39.046904 -310.076564) (xy 39.054799 -310.125141)
			(xy 39.055294 -310.149748) (xy 39.394142 -310.149748) (xy 39.398102 -310.100694) (xy 39.409879 -310.05291)
			(xy 39.42917 -310.007634) (xy 39.455473 -309.966038) (xy 39.488108 -309.929201) (xy 39.526229 -309.898076)
			(xy 39.56885 -309.873469) (xy 39.614866 -309.856017) (xy 39.663085 -309.846173) (xy 39.71226 -309.844192)
			(xy 39.761115 -309.850124) (xy 39.808386 -309.863816) (xy 39.852848 -309.884914) (xy 39.893351 -309.91287)
			(xy 39.928844 -309.946962) (xy 39.958409 -309.986306) (xy 39.98128 -310.029883) (xy 39.996864 -310.076564)
			(xy 40.004759 -310.125141) (xy 40.005254 -310.149748) (xy 40.344102 -310.149748) (xy 40.348062 -310.100694)
			(xy 40.359839 -310.05291) (xy 40.37913 -310.007634) (xy 40.405433 -309.966038) (xy 40.438068 -309.929201)
			(xy 40.476189 -309.898076) (xy 40.51881 -309.873469) (xy 40.564826 -309.856017) (xy 40.613045 -309.846173)
			(xy 40.66222 -309.844192) (xy 40.711075 -309.850124) (xy 40.758346 -309.863816) (xy 40.802808 -309.884914)
			(xy 40.843311 -309.91287) (xy 40.878804 -309.946962) (xy 40.908369 -309.986306) (xy 40.93124 -310.029883)
			(xy 40.946824 -310.076564) (xy 40.954719 -310.125141) (xy 40.955214 -310.149748) (xy 41.294062 -310.149748)
			(xy 41.298022 -310.100694) (xy 41.309799 -310.05291) (xy 41.32909 -310.007634) (xy 41.355393 -309.966038)
			(xy 41.388028 -309.929201) (xy 41.426149 -309.898076) (xy 41.46877 -309.873469) (xy 41.514786 -309.856017)
			(xy 41.563005 -309.846173) (xy 41.61218 -309.844192) (xy 41.661035 -309.850124) (xy 41.708306 -309.863816)
			(xy 41.752768 -309.884914) (xy 41.793271 -309.91287) (xy 41.828764 -309.946962) (xy 41.858329 -309.986306)
			(xy 41.8812 -310.029883) (xy 41.896784 -310.076564) (xy 41.904679 -310.125141) (xy 41.905174 -310.149748)
			(xy 42.244022 -310.149748) (xy 42.247982 -310.100694) (xy 42.259759 -310.05291) (xy 42.27905 -310.007634)
			(xy 42.305353 -309.966038) (xy 42.337988 -309.929201) (xy 42.376109 -309.898076) (xy 42.41873 -309.873469)
			(xy 42.464746 -309.856017) (xy 42.512965 -309.846173) (xy 42.56214 -309.844192) (xy 42.610995 -309.850124)
			(xy 42.658266 -309.863816) (xy 42.702728 -309.884914) (xy 42.743231 -309.91287) (xy 42.778724 -309.946962)
			(xy 42.808289 -309.986306) (xy 42.83116 -310.029883) (xy 42.846744 -310.076564) (xy 42.854639 -310.125141)
			(xy 42.855134 -310.149748) (xy 43.193982 -310.149748) (xy 43.197942 -310.100694) (xy 43.209719 -310.05291)
			(xy 43.22901 -310.007634) (xy 43.255313 -309.966038) (xy 43.287948 -309.929201) (xy 43.326069 -309.898076)
			(xy 43.36869 -309.873469) (xy 43.414706 -309.856017) (xy 43.462925 -309.846173) (xy 43.5121 -309.844192)
			(xy 43.560955 -309.850124) (xy 43.608226 -309.863816) (xy 43.652688 -309.884914) (xy 43.693191 -309.91287)
			(xy 43.728684 -309.946962) (xy 43.758249 -309.986306) (xy 43.78112 -310.029883) (xy 43.796704 -310.076564)
			(xy 43.804599 -310.125141) (xy 43.805094 -310.149748) (xy 44.143942 -310.149748) (xy 44.147902 -310.100694)
			(xy 44.159679 -310.05291) (xy 44.17897 -310.007634) (xy 44.205273 -309.966038) (xy 44.237908 -309.929201)
			(xy 44.276029 -309.898076) (xy 44.31865 -309.873469) (xy 44.364666 -309.856017) (xy 44.412885 -309.846173)
			(xy 44.46206 -309.844192) (xy 44.510915 -309.850124) (xy 44.558186 -309.863816) (xy 44.602648 -309.884914)
			(xy 44.643151 -309.91287) (xy 44.678644 -309.946962) (xy 44.708209 -309.986306) (xy 44.73108 -310.029883)
			(xy 44.746664 -310.076564) (xy 44.754559 -310.125141) (xy 44.755054 -310.149748) (xy 45.094156 -310.149748)
			(xy 45.098116 -310.100694) (xy 45.109893 -310.05291) (xy 45.129184 -310.007634) (xy 45.155487 -309.966038)
			(xy 45.188122 -309.929201) (xy 45.226243 -309.898076) (xy 45.268864 -309.873469) (xy 45.31488 -309.856017)
			(xy 45.363099 -309.846173) (xy 45.412274 -309.844192) (xy 45.461129 -309.850124) (xy 45.5084 -309.863816)
			(xy 45.552862 -309.884914) (xy 45.593365 -309.91287) (xy 45.628858 -309.946962) (xy 45.658423 -309.986306)
			(xy 45.681294 -310.029883) (xy 45.696878 -310.076564) (xy 45.704773 -310.125141) (xy 45.705268 -310.149748)
			(xy 46.044116 -310.149748) (xy 46.048076 -310.100694) (xy 46.059853 -310.05291) (xy 46.079144 -310.007634)
			(xy 46.105447 -309.966038) (xy 46.138082 -309.929201) (xy 46.176203 -309.898076) (xy 46.218824 -309.873469)
			(xy 46.26484 -309.856017) (xy 46.313059 -309.846173) (xy 46.362234 -309.844192) (xy 46.411089 -309.850124)
			(xy 46.45836 -309.863816) (xy 46.502822 -309.884914) (xy 46.543325 -309.91287) (xy 46.578818 -309.946962)
			(xy 46.608383 -309.986306) (xy 46.631254 -310.029883) (xy 46.646838 -310.076564) (xy 46.654733 -310.125141)
			(xy 46.655228 -310.149748) (xy 46.994076 -310.149748) (xy 46.998036 -310.100694) (xy 47.009813 -310.05291)
			(xy 47.029104 -310.007634) (xy 47.055407 -309.966038) (xy 47.088042 -309.929201) (xy 47.126163 -309.898076)
			(xy 47.168784 -309.873469) (xy 47.2148 -309.856017) (xy 47.263019 -309.846173) (xy 47.312194 -309.844192)
			(xy 47.361049 -309.850124) (xy 47.40832 -309.863816) (xy 47.452782 -309.884914) (xy 47.493285 -309.91287)
			(xy 47.528778 -309.946962) (xy 47.558343 -309.986306) (xy 47.581214 -310.029883) (xy 47.596798 -310.076564)
			(xy 47.604693 -310.125141) (xy 47.605188 -310.149748) (xy 47.604693 -310.174355) (xy 47.596798 -310.222932)
			(xy 47.581214 -310.269613) (xy 47.558343 -310.31319) (xy 47.528778 -310.352534) (xy 47.493285 -310.386626)
			(xy 47.452782 -310.414582) (xy 47.40832 -310.43568) (xy 47.361049 -310.449372) (xy 47.312194 -310.455304)
			(xy 47.263019 -310.453323) (xy 47.2148 -310.443479) (xy 47.168784 -310.426027) (xy 47.126163 -310.40142)
			(xy 47.088042 -310.370295) (xy 47.055407 -310.333458) (xy 47.029104 -310.291862) (xy 47.009813 -310.246586)
			(xy 46.998036 -310.198802) (xy 46.994076 -310.149748) (xy 46.655228 -310.149748) (xy 46.654733 -310.174355)
			(xy 46.646838 -310.222932) (xy 46.631254 -310.269613) (xy 46.608383 -310.31319) (xy 46.578818 -310.352534)
			(xy 46.543325 -310.386626) (xy 46.502822 -310.414582) (xy 46.45836 -310.43568) (xy 46.411089 -310.449372)
			(xy 46.362234 -310.455304) (xy 46.313059 -310.453323) (xy 46.26484 -310.443479) (xy 46.218824 -310.426027)
			(xy 46.176203 -310.40142) (xy 46.138082 -310.370295) (xy 46.105447 -310.333458) (xy 46.079144 -310.291862)
			(xy 46.059853 -310.246586) (xy 46.048076 -310.198802) (xy 46.044116 -310.149748) (xy 45.705268 -310.149748)
			(xy 45.704773 -310.174355) (xy 45.696878 -310.222932) (xy 45.681294 -310.269613) (xy 45.658423 -310.31319)
			(xy 45.628858 -310.352534) (xy 45.593365 -310.386626) (xy 45.552862 -310.414582) (xy 45.5084 -310.43568)
			(xy 45.461129 -310.449372) (xy 45.412274 -310.455304) (xy 45.363099 -310.453323) (xy 45.31488 -310.443479)
			(xy 45.268864 -310.426027) (xy 45.226243 -310.40142) (xy 45.188122 -310.370295) (xy 45.155487 -310.333458)
			(xy 45.129184 -310.291862) (xy 45.109893 -310.246586) (xy 45.098116 -310.198802) (xy 45.094156 -310.149748)
			(xy 44.755054 -310.149748) (xy 44.754559 -310.174355) (xy 44.746664 -310.222932) (xy 44.73108 -310.269613)
			(xy 44.708209 -310.31319) (xy 44.678644 -310.352534) (xy 44.643151 -310.386626) (xy 44.602648 -310.414582)
			(xy 44.558186 -310.43568) (xy 44.510915 -310.449372) (xy 44.46206 -310.455304) (xy 44.412885 -310.453323)
			(xy 44.364666 -310.443479) (xy 44.31865 -310.426027) (xy 44.276029 -310.40142) (xy 44.237908 -310.370295)
			(xy 44.205273 -310.333458) (xy 44.17897 -310.291862) (xy 44.159679 -310.246586) (xy 44.147902 -310.198802)
			(xy 44.143942 -310.149748) (xy 43.805094 -310.149748) (xy 43.804599 -310.174355) (xy 43.796704 -310.222932)
			(xy 43.78112 -310.269613) (xy 43.758249 -310.31319) (xy 43.728684 -310.352534) (xy 43.693191 -310.386626)
			(xy 43.652688 -310.414582) (xy 43.608226 -310.43568) (xy 43.560955 -310.449372) (xy 43.5121 -310.455304)
			(xy 43.462925 -310.453323) (xy 43.414706 -310.443479) (xy 43.36869 -310.426027) (xy 43.326069 -310.40142)
			(xy 43.287948 -310.370295) (xy 43.255313 -310.333458) (xy 43.22901 -310.291862) (xy 43.209719 -310.246586)
			(xy 43.197942 -310.198802) (xy 43.193982 -310.149748) (xy 42.855134 -310.149748) (xy 42.854639 -310.174355)
			(xy 42.846744 -310.222932) (xy 42.83116 -310.269613) (xy 42.808289 -310.31319) (xy 42.778724 -310.352534)
			(xy 42.743231 -310.386626) (xy 42.702728 -310.414582) (xy 42.658266 -310.43568) (xy 42.610995 -310.449372)
			(xy 42.56214 -310.455304) (xy 42.512965 -310.453323) (xy 42.464746 -310.443479) (xy 42.41873 -310.426027)
			(xy 42.376109 -310.40142) (xy 42.337988 -310.370295) (xy 42.305353 -310.333458) (xy 42.27905 -310.291862)
			(xy 42.259759 -310.246586) (xy 42.247982 -310.198802) (xy 42.244022 -310.149748) (xy 41.905174 -310.149748)
			(xy 41.904679 -310.174355) (xy 41.896784 -310.222932) (xy 41.8812 -310.269613) (xy 41.858329 -310.31319)
			(xy 41.828764 -310.352534) (xy 41.793271 -310.386626) (xy 41.752768 -310.414582) (xy 41.708306 -310.43568)
			(xy 41.661035 -310.449372) (xy 41.61218 -310.455304) (xy 41.563005 -310.453323) (xy 41.514786 -310.443479)
			(xy 41.46877 -310.426027) (xy 41.426149 -310.40142) (xy 41.388028 -310.370295) (xy 41.355393 -310.333458)
			(xy 41.32909 -310.291862) (xy 41.309799 -310.246586) (xy 41.298022 -310.198802) (xy 41.294062 -310.149748)
			(xy 40.955214 -310.149748) (xy 40.954719 -310.174355) (xy 40.946824 -310.222932) (xy 40.93124 -310.269613)
			(xy 40.908369 -310.31319) (xy 40.878804 -310.352534) (xy 40.843311 -310.386626) (xy 40.802808 -310.414582)
			(xy 40.758346 -310.43568) (xy 40.711075 -310.449372) (xy 40.66222 -310.455304) (xy 40.613045 -310.453323)
			(xy 40.564826 -310.443479) (xy 40.51881 -310.426027) (xy 40.476189 -310.40142) (xy 40.438068 -310.370295)
			(xy 40.405433 -310.333458) (xy 40.37913 -310.291862) (xy 40.359839 -310.246586) (xy 40.348062 -310.198802)
			(xy 40.344102 -310.149748) (xy 40.005254 -310.149748) (xy 40.004759 -310.174355) (xy 39.996864 -310.222932)
			(xy 39.98128 -310.269613) (xy 39.958409 -310.31319) (xy 39.928844 -310.352534) (xy 39.893351 -310.386626)
			(xy 39.852848 -310.414582) (xy 39.808386 -310.43568) (xy 39.761115 -310.449372) (xy 39.71226 -310.455304)
			(xy 39.663085 -310.453323) (xy 39.614866 -310.443479) (xy 39.56885 -310.426027) (xy 39.526229 -310.40142)
			(xy 39.488108 -310.370295) (xy 39.455473 -310.333458) (xy 39.42917 -310.291862) (xy 39.409879 -310.246586)
			(xy 39.398102 -310.198802) (xy 39.394142 -310.149748) (xy 39.055294 -310.149748) (xy 39.054799 -310.174355)
			(xy 39.046904 -310.222932) (xy 39.03132 -310.269613) (xy 39.008449 -310.31319) (xy 38.978884 -310.352534)
			(xy 38.943391 -310.386626) (xy 38.902888 -310.414582) (xy 38.858426 -310.43568) (xy 38.811155 -310.449372)
			(xy 38.7623 -310.455304) (xy 38.713125 -310.453323) (xy 38.664906 -310.443479) (xy 38.61889 -310.426027)
			(xy 38.576269 -310.40142) (xy 38.538148 -310.370295) (xy 38.505513 -310.333458) (xy 38.47921 -310.291862)
			(xy 38.459919 -310.246586) (xy 38.448142 -310.198802) (xy 38.444182 -310.149748) (xy 38.126924 -310.149748)
			(xy 38.12642 -310.175456) (xy 38.118377 -310.226238) (xy 38.102489 -310.275137) (xy 38.079146 -310.320949)
			(xy 38.048925 -310.362545) (xy 38.012569 -310.398901) (xy 37.970973 -310.429122) (xy 37.925161 -310.452465)
			(xy 37.876262 -310.468353) (xy 37.82548 -310.476396) (xy 37.774064 -310.476396) (xy 37.723282 -310.468353)
			(xy 37.674383 -310.452465) (xy 37.628571 -310.429122) (xy 37.586975 -310.398901) (xy 37.550619 -310.362545)
			(xy 37.520398 -310.320949) (xy 37.497055 -310.275137) (xy 37.481167 -310.226238) (xy 37.473124 -310.175456)
			(xy 37.17646 -310.175456) (xy 37.168417 -310.226238) (xy 37.152529 -310.275137) (xy 37.129186 -310.320949)
			(xy 37.098965 -310.362545) (xy 37.062609 -310.398901) (xy 37.021013 -310.429122) (xy 36.975201 -310.452465)
			(xy 36.926302 -310.468353) (xy 36.87552 -310.476396) (xy 36.824104 -310.476396) (xy 36.773322 -310.468353)
			(xy 36.724423 -310.452465) (xy 36.678611 -310.429122) (xy 36.637015 -310.398901) (xy 36.600659 -310.362545)
			(xy 36.570438 -310.320949) (xy 36.547095 -310.275137) (xy 36.531207 -310.226238) (xy 36.523164 -310.175456)
			(xy 36.204273 -310.175456) (xy 36.196516 -310.223186) (xy 36.180932 -310.269867) (xy 36.158061 -310.313444)
			(xy 36.128496 -310.352788) (xy 36.093003 -310.38688) (xy 36.0525 -310.414836) (xy 36.008038 -310.435934)
			(xy 35.960767 -310.449626) (xy 35.911912 -310.455558) (xy 35.862737 -310.453577) (xy 35.814518 -310.443733)
			(xy 35.768502 -310.426281) (xy 35.725881 -310.401674) (xy 35.68776 -310.370549) (xy 35.655125 -310.333712)
			(xy 35.628822 -310.292116) (xy 35.609531 -310.24684) (xy 35.597754 -310.199056) (xy 35.593794 -310.150002)
			(xy 34.85373 -310.150002) (xy 34.855544 -310.156179) (xy 34.8633 -310.210127) (xy 34.863786 -310.237378)
			(xy 34.863273 -310.266153) (xy 34.854619 -310.323048) (xy 34.837521 -310.377998) (xy 34.812365 -310.429758)
			(xy 34.779721 -310.477154) (xy 34.760408 -310.49849) (xy 34.751082 -310.509071) (xy 34.73817 -310.534137)
			(xy 34.732608 -310.56178) (xy 34.734821 -310.589889) (xy 34.74464 -310.61632) (xy 34.761315 -310.639057)
			(xy 34.783574 -310.656364) (xy 34.796476 -310.662066) (xy 34.822543 -310.67316) (xy 34.871364 -310.701893)
			(xy 34.915401 -310.737528) (xy 34.953685 -310.779283) (xy 34.985374 -310.82624) (xy 35.009771 -310.877366)
			(xy 35.026341 -310.931537) (xy 35.034719 -310.987564) (xy 35.035236 -311.015888) (xy 35.03475 -311.043139)
			(xy 35.026994 -311.097087) (xy 35.02615 -311.099962) (xy 36.544008 -311.099962) (xy 36.547968 -311.050908)
			(xy 36.559745 -311.003124) (xy 36.579036 -310.957848) (xy 36.605339 -310.916252) (xy 36.637974 -310.879415)
			(xy 36.676095 -310.84829) (xy 36.718716 -310.823683) (xy 36.764732 -310.806231) (xy 36.812951 -310.796387)
			(xy 36.862126 -310.794406) (xy 36.910981 -310.800338) (xy 36.958252 -310.81403) (xy 37.002714 -310.835128)
			(xy 37.043217 -310.863084) (xy 37.07871 -310.897176) (xy 37.108275 -310.93652) (xy 37.131146 -310.980097)
			(xy 37.14673 -311.026778) (xy 37.154625 -311.075355) (xy 37.15512 -311.099962) (xy 37.493968 -311.099962)
			(xy 37.497928 -311.050908) (xy 37.509705 -311.003124) (xy 37.528996 -310.957848) (xy 37.555299 -310.916252)
			(xy 37.587934 -310.879415) (xy 37.626055 -310.84829) (xy 37.668676 -310.823683) (xy 37.714692 -310.806231)
			(xy 37.762911 -310.796387) (xy 37.812086 -310.794406) (xy 37.860941 -310.800338) (xy 37.908212 -310.81403)
			(xy 37.952674 -310.835128) (xy 37.993177 -310.863084) (xy 38.02867 -310.897176) (xy 38.058235 -310.93652)
			(xy 38.081106 -310.980097) (xy 38.09669 -311.026778) (xy 38.104585 -311.075355) (xy 38.10508 -311.099962)
			(xy 38.444182 -311.099962) (xy 38.448142 -311.050908) (xy 38.459919 -311.003124) (xy 38.47921 -310.957848)
			(xy 38.505513 -310.916252) (xy 38.538148 -310.879415) (xy 38.576269 -310.84829) (xy 38.61889 -310.823683)
			(xy 38.664906 -310.806231) (xy 38.713125 -310.796387) (xy 38.7623 -310.794406) (xy 38.811155 -310.800338)
			(xy 38.858426 -310.81403) (xy 38.902888 -310.835128) (xy 38.943391 -310.863084) (xy 38.978884 -310.897176)
			(xy 39.008449 -310.93652) (xy 39.03132 -310.980097) (xy 39.046904 -311.026778) (xy 39.054799 -311.075355)
			(xy 39.055294 -311.099962) (xy 39.054799 -311.124569) (xy 39.05462 -311.12567) (xy 39.373298 -311.12567)
			(xy 39.373298 -311.074254) (xy 39.381341 -311.023472) (xy 39.397229 -310.974573) (xy 39.420572 -310.928761)
			(xy 39.450793 -310.887165) (xy 39.487149 -310.850809) (xy 39.528745 -310.820588) (xy 39.574557 -310.797245)
			(xy 39.623456 -310.781357) (xy 39.674238 -310.773314) (xy 39.725654 -310.773314) (xy 39.776436 -310.781357)
			(xy 39.825335 -310.797245) (xy 39.871147 -310.820588) (xy 39.912743 -310.850809) (xy 39.949099 -310.887165)
			(xy 39.97932 -310.928761) (xy 40.002663 -310.974573) (xy 40.018551 -311.023472) (xy 40.026594 -311.074254)
			(xy 40.027098 -311.099962) (xy 40.344102 -311.099962) (xy 40.348062 -311.050908) (xy 40.359839 -311.003124)
			(xy 40.37913 -310.957848) (xy 40.405433 -310.916252) (xy 40.438068 -310.879415) (xy 40.476189 -310.84829)
			(xy 40.51881 -310.823683) (xy 40.564826 -310.806231) (xy 40.613045 -310.796387) (xy 40.66222 -310.794406)
			(xy 40.711075 -310.800338) (xy 40.758346 -310.81403) (xy 40.802808 -310.835128) (xy 40.843311 -310.863084)
			(xy 40.878804 -310.897176) (xy 40.908369 -310.93652) (xy 40.93124 -310.980097) (xy 40.946824 -311.026778)
			(xy 40.954719 -311.075355) (xy 40.955214 -311.099962) (xy 40.954719 -311.124569) (xy 40.95454 -311.12567)
			(xy 41.273218 -311.12567) (xy 41.273218 -311.074254) (xy 41.281261 -311.023472) (xy 41.297149 -310.974573)
			(xy 41.320492 -310.928761) (xy 41.350713 -310.887165) (xy 41.387069 -310.850809) (xy 41.428665 -310.820588)
			(xy 41.474477 -310.797245) (xy 41.523376 -310.781357) (xy 41.574158 -310.773314) (xy 41.625574 -310.773314)
			(xy 41.676356 -310.781357) (xy 41.725255 -310.797245) (xy 41.771067 -310.820588) (xy 41.812663 -310.850809)
			(xy 41.849019 -310.887165) (xy 41.87924 -310.928761) (xy 41.902583 -310.974573) (xy 41.918471 -311.023472)
			(xy 41.926514 -311.074254) (xy 41.927018 -311.099962) (xy 42.244022 -311.099962) (xy 42.247982 -311.050908)
			(xy 42.259759 -311.003124) (xy 42.27905 -310.957848) (xy 42.305353 -310.916252) (xy 42.337988 -310.879415)
			(xy 42.376109 -310.84829) (xy 42.41873 -310.823683) (xy 42.464746 -310.806231) (xy 42.512965 -310.796387)
			(xy 42.56214 -310.794406) (xy 42.610995 -310.800338) (xy 42.658266 -310.81403) (xy 42.702728 -310.835128)
			(xy 42.743231 -310.863084) (xy 42.778724 -310.897176) (xy 42.808289 -310.93652) (xy 42.83116 -310.980097)
			(xy 42.846744 -311.026778) (xy 42.854639 -311.075355) (xy 42.855134 -311.099962) (xy 42.854639 -311.124569)
			(xy 42.85446 -311.12567) (xy 43.173138 -311.12567) (xy 43.173138 -311.074254) (xy 43.181181 -311.023472)
			(xy 43.197069 -310.974573) (xy 43.220412 -310.928761) (xy 43.250633 -310.887165) (xy 43.286989 -310.850809)
			(xy 43.328585 -310.820588) (xy 43.374397 -310.797245) (xy 43.423296 -310.781357) (xy 43.474078 -310.773314)
			(xy 43.525494 -310.773314) (xy 43.576276 -310.781357) (xy 43.625175 -310.797245) (xy 43.670987 -310.820588)
			(xy 43.712583 -310.850809) (xy 43.748939 -310.887165) (xy 43.77916 -310.928761) (xy 43.802503 -310.974573)
			(xy 43.818391 -311.023472) (xy 43.826434 -311.074254) (xy 43.826938 -311.099962) (xy 44.143942 -311.099962)
			(xy 44.147902 -311.050908) (xy 44.159679 -311.003124) (xy 44.17897 -310.957848) (xy 44.205273 -310.916252)
			(xy 44.237908 -310.879415) (xy 44.276029 -310.84829) (xy 44.31865 -310.823683) (xy 44.364666 -310.806231)
			(xy 44.412885 -310.796387) (xy 44.46206 -310.794406) (xy 44.510915 -310.800338) (xy 44.558186 -310.81403)
			(xy 44.602648 -310.835128) (xy 44.643151 -310.863084) (xy 44.678644 -310.897176) (xy 44.708209 -310.93652)
			(xy 44.73108 -310.980097) (xy 44.746664 -311.026778) (xy 44.754559 -311.075355) (xy 44.755054 -311.099962)
			(xy 44.754559 -311.124569) (xy 44.75438 -311.12567) (xy 45.073312 -311.12567) (xy 45.073312 -311.074254)
			(xy 45.081355 -311.023472) (xy 45.097243 -310.974573) (xy 45.120586 -310.928761) (xy 45.150807 -310.887165)
			(xy 45.187163 -310.850809) (xy 45.228759 -310.820588) (xy 45.274571 -310.797245) (xy 45.32347 -310.781357)
			(xy 45.374252 -310.773314) (xy 45.425668 -310.773314) (xy 45.47645 -310.781357) (xy 45.525349 -310.797245)
			(xy 45.571161 -310.820588) (xy 45.612757 -310.850809) (xy 45.649113 -310.887165) (xy 45.679334 -310.928761)
			(xy 45.702677 -310.974573) (xy 45.718565 -311.023472) (xy 45.726608 -311.074254) (xy 45.727112 -311.099962)
			(xy 46.044116 -311.099962) (xy 46.048076 -311.050908) (xy 46.059853 -311.003124) (xy 46.079144 -310.957848)
			(xy 46.105447 -310.916252) (xy 46.138082 -310.879415) (xy 46.176203 -310.84829) (xy 46.218824 -310.823683)
			(xy 46.26484 -310.806231) (xy 46.313059 -310.796387) (xy 46.362234 -310.794406) (xy 46.411089 -310.800338)
			(xy 46.45836 -310.81403) (xy 46.502822 -310.835128) (xy 46.543325 -310.863084) (xy 46.578818 -310.897176)
			(xy 46.608383 -310.93652) (xy 46.631254 -310.980097) (xy 46.646838 -311.026778) (xy 46.654733 -311.075355)
			(xy 46.655228 -311.099962) (xy 46.654733 -311.124569) (xy 46.654554 -311.12567) (xy 46.973232 -311.12567)
			(xy 46.973232 -311.074254) (xy 46.981275 -311.023472) (xy 46.997163 -310.974573) (xy 47.020506 -310.928761)
			(xy 47.050727 -310.887165) (xy 47.087083 -310.850809) (xy 47.128679 -310.820588) (xy 47.174491 -310.797245)
			(xy 47.22339 -310.781357) (xy 47.274172 -310.773314) (xy 47.325588 -310.773314) (xy 47.37637 -310.781357)
			(xy 47.425269 -310.797245) (xy 47.471081 -310.820588) (xy 47.512677 -310.850809) (xy 47.549033 -310.887165)
			(xy 47.579254 -310.928761) (xy 47.602597 -310.974573) (xy 47.618485 -311.023472) (xy 47.626528 -311.074254)
			(xy 47.627032 -311.099962) (xy 47.944036 -311.099962) (xy 47.947996 -311.050908) (xy 47.959773 -311.003124)
			(xy 47.979064 -310.957848) (xy 48.005367 -310.916252) (xy 48.038002 -310.879415) (xy 48.076123 -310.84829)
			(xy 48.118744 -310.823683) (xy 48.16476 -310.806231) (xy 48.212979 -310.796387) (xy 48.262154 -310.794406)
			(xy 48.311009 -310.800338) (xy 48.35828 -310.81403) (xy 48.402742 -310.835128) (xy 48.443245 -310.863084)
			(xy 48.478738 -310.897176) (xy 48.508303 -310.93652) (xy 48.531174 -310.980097) (xy 48.546758 -311.026778)
			(xy 48.554653 -311.075355) (xy 48.555148 -311.099962) (xy 48.554653 -311.124569) (xy 48.554474 -311.12567)
			(xy 48.873152 -311.12567) (xy 48.873152 -311.074254) (xy 48.881195 -311.023472) (xy 48.897083 -310.974573)
			(xy 48.920426 -310.928761) (xy 48.950647 -310.887165) (xy 48.987003 -310.850809) (xy 49.028599 -310.820588)
			(xy 49.074411 -310.797245) (xy 49.12331 -310.781357) (xy 49.174092 -310.773314) (xy 49.225508 -310.773314)
			(xy 49.27629 -310.781357) (xy 49.325189 -310.797245) (xy 49.371001 -310.820588) (xy 49.412597 -310.850809)
			(xy 49.448953 -310.887165) (xy 49.479174 -310.928761) (xy 49.502517 -310.974573) (xy 49.518405 -311.023472)
			(xy 49.526448 -311.074254) (xy 49.526952 -311.099962) (xy 49.843956 -311.099962) (xy 49.847916 -311.050908)
			(xy 49.859693 -311.003124) (xy 49.878984 -310.957848) (xy 49.905287 -310.916252) (xy 49.937922 -310.879415)
			(xy 49.976043 -310.84829) (xy 50.018664 -310.823683) (xy 50.06468 -310.806231) (xy 50.112899 -310.796387)
			(xy 50.162074 -310.794406) (xy 50.210929 -310.800338) (xy 50.2582 -310.81403) (xy 50.302662 -310.835128)
			(xy 50.343165 -310.863084) (xy 50.378658 -310.897176) (xy 50.408223 -310.93652) (xy 50.431094 -310.980097)
			(xy 50.446678 -311.026778) (xy 50.454573 -311.075355) (xy 50.455068 -311.099962) (xy 50.454573 -311.124569)
			(xy 50.454394 -311.12567) (xy 50.773326 -311.12567) (xy 50.773326 -311.074254) (xy 50.781369 -311.023472)
			(xy 50.797257 -310.974573) (xy 50.8206 -310.928761) (xy 50.850821 -310.887165) (xy 50.887177 -310.850809)
			(xy 50.928773 -310.820588) (xy 50.974585 -310.797245) (xy 51.023484 -310.781357) (xy 51.074266 -310.773314)
			(xy 51.125682 -310.773314) (xy 51.176464 -310.781357) (xy 51.225363 -310.797245) (xy 51.271175 -310.820588)
			(xy 51.312771 -310.850809) (xy 51.349127 -310.887165) (xy 51.379348 -310.928761) (xy 51.402691 -310.974573)
			(xy 51.418579 -311.023472) (xy 51.426622 -311.074254) (xy 51.427126 -311.099962) (xy 51.74413 -311.099962)
			(xy 51.74809 -311.050908) (xy 51.759867 -311.003124) (xy 51.779158 -310.957848) (xy 51.805461 -310.916252)
			(xy 51.838096 -310.879415) (xy 51.876217 -310.84829) (xy 51.918838 -310.823683) (xy 51.964854 -310.806231)
			(xy 52.013073 -310.796387) (xy 52.062248 -310.794406) (xy 52.111103 -310.800338) (xy 52.158374 -310.81403)
			(xy 52.202836 -310.835128) (xy 52.243339 -310.863084) (xy 52.278832 -310.897176) (xy 52.308397 -310.93652)
			(xy 52.331268 -310.980097) (xy 52.346852 -311.026778) (xy 52.354747 -311.075355) (xy 52.355242 -311.099962)
			(xy 52.354747 -311.124569) (xy 52.354568 -311.12567) (xy 52.673246 -311.12567) (xy 52.673246 -311.074254)
			(xy 52.681289 -311.023472) (xy 52.697177 -310.974573) (xy 52.72052 -310.928761) (xy 52.750741 -310.887165)
			(xy 52.787097 -310.850809) (xy 52.828693 -310.820588) (xy 52.874505 -310.797245) (xy 52.923404 -310.781357)
			(xy 52.974186 -310.773314) (xy 53.025602 -310.773314) (xy 53.076384 -310.781357) (xy 53.125283 -310.797245)
			(xy 53.171095 -310.820588) (xy 53.212691 -310.850809) (xy 53.249047 -310.887165) (xy 53.279268 -310.928761)
			(xy 53.302611 -310.974573) (xy 53.318499 -311.023472) (xy 53.326542 -311.074254) (xy 53.327046 -311.099962)
			(xy 53.64405 -311.099962) (xy 53.64801 -311.050908) (xy 53.659787 -311.003124) (xy 53.679078 -310.957848)
			(xy 53.705381 -310.916252) (xy 53.738016 -310.879415) (xy 53.776137 -310.84829) (xy 53.818758 -310.823683)
			(xy 53.864774 -310.806231) (xy 53.912993 -310.796387) (xy 53.962168 -310.794406) (xy 54.011023 -310.800338)
			(xy 54.058294 -310.81403) (xy 54.102756 -310.835128) (xy 54.143259 -310.863084) (xy 54.178752 -310.897176)
			(xy 54.208317 -310.93652) (xy 54.231188 -310.980097) (xy 54.246772 -311.026778) (xy 54.254667 -311.075355)
			(xy 54.255162 -311.099962) (xy 54.254667 -311.124569) (xy 54.254488 -311.12567) (xy 54.573166 -311.12567)
			(xy 54.573166 -311.074254) (xy 54.581209 -311.023472) (xy 54.597097 -310.974573) (xy 54.62044 -310.928761)
			(xy 54.650661 -310.887165) (xy 54.687017 -310.850809) (xy 54.728613 -310.820588) (xy 54.774425 -310.797245)
			(xy 54.823324 -310.781357) (xy 54.874106 -310.773314) (xy 54.925522 -310.773314) (xy 54.976304 -310.781357)
			(xy 55.025203 -310.797245) (xy 55.071015 -310.820588) (xy 55.112611 -310.850809) (xy 55.148967 -310.887165)
			(xy 55.179188 -310.928761) (xy 55.202531 -310.974573) (xy 55.218419 -311.023472) (xy 55.226462 -311.074254)
			(xy 55.226966 -311.099962) (xy 55.54397 -311.099962) (xy 55.54793 -311.050908) (xy 55.559707 -311.003124)
			(xy 55.578998 -310.957848) (xy 55.605301 -310.916252) (xy 55.637936 -310.879415) (xy 55.676057 -310.84829)
			(xy 55.718678 -310.823683) (xy 55.764694 -310.806231) (xy 55.812913 -310.796387) (xy 55.862088 -310.794406)
			(xy 55.910943 -310.800338) (xy 55.958214 -310.81403) (xy 56.002676 -310.835128) (xy 56.043179 -310.863084)
			(xy 56.078672 -310.897176) (xy 56.108237 -310.93652) (xy 56.131108 -310.980097) (xy 56.146692 -311.026778)
			(xy 56.154587 -311.075355) (xy 56.155082 -311.099962) (xy 56.154587 -311.124569) (xy 56.154408 -311.12567)
			(xy 56.47334 -311.12567) (xy 56.47334 -311.074254) (xy 56.481383 -311.023472) (xy 56.497271 -310.974573)
			(xy 56.520614 -310.928761) (xy 56.550835 -310.887165) (xy 56.587191 -310.850809) (xy 56.628787 -310.820588)
			(xy 56.674599 -310.797245) (xy 56.723498 -310.781357) (xy 56.77428 -310.773314) (xy 56.825696 -310.773314)
			(xy 56.876478 -310.781357) (xy 56.925377 -310.797245) (xy 56.971189 -310.820588) (xy 57.012785 -310.850809)
			(xy 57.049141 -310.887165) (xy 57.079362 -310.928761) (xy 57.102705 -310.974573) (xy 57.118593 -311.023472)
			(xy 57.126636 -311.074254) (xy 57.12714 -311.099962) (xy 57.444144 -311.099962) (xy 57.448104 -311.050908)
			(xy 57.459881 -311.003124) (xy 57.479172 -310.957848) (xy 57.505475 -310.916252) (xy 57.53811 -310.879415)
			(xy 57.576231 -310.84829) (xy 57.618852 -310.823683) (xy 57.664868 -310.806231) (xy 57.713087 -310.796387)
			(xy 57.762262 -310.794406) (xy 57.811117 -310.800338) (xy 57.858388 -310.81403) (xy 57.90285 -310.835128)
			(xy 57.943353 -310.863084) (xy 57.978846 -310.897176) (xy 58.008411 -310.93652) (xy 58.031282 -310.980097)
			(xy 58.046866 -311.026778) (xy 58.054761 -311.075355) (xy 58.055256 -311.099962) (xy 58.054761 -311.124569)
			(xy 58.054582 -311.12567) (xy 58.37326 -311.12567) (xy 58.37326 -311.074254) (xy 58.381303 -311.023472)
			(xy 58.397191 -310.974573) (xy 58.420534 -310.928761) (xy 58.450755 -310.887165) (xy 58.487111 -310.850809)
			(xy 58.528707 -310.820588) (xy 58.574519 -310.797245) (xy 58.623418 -310.781357) (xy 58.6742 -310.773314)
			(xy 58.725616 -310.773314) (xy 58.776398 -310.781357) (xy 58.825297 -310.797245) (xy 58.871109 -310.820588)
			(xy 58.912705 -310.850809) (xy 58.949061 -310.887165) (xy 58.979282 -310.928761) (xy 59.002625 -310.974573)
			(xy 59.018513 -311.023472) (xy 59.026556 -311.074254) (xy 59.02706 -311.099962) (xy 59.344064 -311.099962)
			(xy 59.348024 -311.050908) (xy 59.359801 -311.003124) (xy 59.379092 -310.957848) (xy 59.405395 -310.916252)
			(xy 59.43803 -310.879415) (xy 59.476151 -310.84829) (xy 59.518772 -310.823683) (xy 59.564788 -310.806231)
			(xy 59.613007 -310.796387) (xy 59.662182 -310.794406) (xy 59.711037 -310.800338) (xy 59.758308 -310.81403)
			(xy 59.80277 -310.835128) (xy 59.843273 -310.863084) (xy 59.878766 -310.897176) (xy 59.908331 -310.93652)
			(xy 59.931202 -310.980097) (xy 59.946786 -311.026778) (xy 59.954681 -311.075355) (xy 59.955176 -311.099962)
			(xy 59.954681 -311.124569) (xy 59.954502 -311.12567) (xy 60.27318 -311.12567) (xy 60.27318 -311.074254)
			(xy 60.281223 -311.023472) (xy 60.297111 -310.974573) (xy 60.320454 -310.928761) (xy 60.350675 -310.887165)
			(xy 60.387031 -310.850809) (xy 60.428627 -310.820588) (xy 60.474439 -310.797245) (xy 60.523338 -310.781357)
			(xy 60.57412 -310.773314) (xy 60.625536 -310.773314) (xy 60.676318 -310.781357) (xy 60.725217 -310.797245)
			(xy 60.771029 -310.820588) (xy 60.812625 -310.850809) (xy 60.848981 -310.887165) (xy 60.879202 -310.928761)
			(xy 60.902545 -310.974573) (xy 60.918433 -311.023472) (xy 60.926476 -311.074254) (xy 60.92698 -311.099962)
			(xy 61.243984 -311.099962) (xy 61.247944 -311.050908) (xy 61.259721 -311.003124) (xy 61.279012 -310.957848)
			(xy 61.305315 -310.916252) (xy 61.33795 -310.879415) (xy 61.376071 -310.84829) (xy 61.418692 -310.823683)
			(xy 61.464708 -310.806231) (xy 61.512927 -310.796387) (xy 61.562102 -310.794406) (xy 61.610957 -310.800338)
			(xy 61.658228 -310.81403) (xy 61.70269 -310.835128) (xy 61.743193 -310.863084) (xy 61.778686 -310.897176)
			(xy 61.808251 -310.93652) (xy 61.831122 -310.980097) (xy 61.846706 -311.026778) (xy 61.854601 -311.075355)
			(xy 61.855096 -311.099962) (xy 61.854601 -311.124569) (xy 61.854422 -311.12567) (xy 62.1731 -311.12567)
			(xy 62.1731 -311.074254) (xy 62.181143 -311.023472) (xy 62.197031 -310.974573) (xy 62.220374 -310.928761)
			(xy 62.250595 -310.887165) (xy 62.286951 -310.850809) (xy 62.328547 -310.820588) (xy 62.374359 -310.797245)
			(xy 62.423258 -310.781357) (xy 62.47404 -310.773314) (xy 62.525456 -310.773314) (xy 62.576238 -310.781357)
			(xy 62.625137 -310.797245) (xy 62.670949 -310.820588) (xy 62.712545 -310.850809) (xy 62.748901 -310.887165)
			(xy 62.779122 -310.928761) (xy 62.802465 -310.974573) (xy 62.818353 -311.023472) (xy 62.826396 -311.074254)
			(xy 62.8269 -311.099962) (xy 63.144158 -311.099962) (xy 63.148118 -311.050908) (xy 63.159895 -311.003124)
			(xy 63.179186 -310.957848) (xy 63.205489 -310.916252) (xy 63.238124 -310.879415) (xy 63.276245 -310.84829)
			(xy 63.318866 -310.823683) (xy 63.364882 -310.806231) (xy 63.413101 -310.796387) (xy 63.462276 -310.794406)
			(xy 63.511131 -310.800338) (xy 63.558402 -310.81403) (xy 63.602864 -310.835128) (xy 63.643367 -310.863084)
			(xy 63.67886 -310.897176) (xy 63.708425 -310.93652) (xy 63.731296 -310.980097) (xy 63.74688 -311.026778)
			(xy 63.754775 -311.075355) (xy 63.75527 -311.099962) (xy 63.754775 -311.124569) (xy 63.754596 -311.12567)
			(xy 64.073274 -311.12567) (xy 64.073274 -311.074254) (xy 64.081317 -311.023472) (xy 64.097205 -310.974573)
			(xy 64.120548 -310.928761) (xy 64.150769 -310.887165) (xy 64.187125 -310.850809) (xy 64.228721 -310.820588)
			(xy 64.274533 -310.797245) (xy 64.323432 -310.781357) (xy 64.374214 -310.773314) (xy 64.42563 -310.773314)
			(xy 64.476412 -310.781357) (xy 64.525311 -310.797245) (xy 64.571123 -310.820588) (xy 64.612719 -310.850809)
			(xy 64.649075 -310.887165) (xy 64.679296 -310.928761) (xy 64.702639 -310.974573) (xy 64.718527 -311.023472)
			(xy 64.72657 -311.074254) (xy 64.727074 -311.099962) (xy 65.044078 -311.099962) (xy 65.048038 -311.050908)
			(xy 65.059815 -311.003124) (xy 65.079106 -310.957848) (xy 65.105409 -310.916252) (xy 65.138044 -310.879415)
			(xy 65.176165 -310.84829) (xy 65.218786 -310.823683) (xy 65.264802 -310.806231) (xy 65.313021 -310.796387)
			(xy 65.362196 -310.794406) (xy 65.411051 -310.800338) (xy 65.458322 -310.81403) (xy 65.502784 -310.835128)
			(xy 65.543287 -310.863084) (xy 65.57878 -310.897176) (xy 65.608345 -310.93652) (xy 65.631216 -310.980097)
			(xy 65.6468 -311.026778) (xy 65.654695 -311.075355) (xy 65.65519 -311.099962) (xy 65.654695 -311.124569)
			(xy 65.654516 -311.12567) (xy 65.973194 -311.12567) (xy 65.973194 -311.074254) (xy 65.981237 -311.023472)
			(xy 65.997125 -310.974573) (xy 66.020468 -310.928761) (xy 66.050689 -310.887165) (xy 66.087045 -310.850809)
			(xy 66.128641 -310.820588) (xy 66.174453 -310.797245) (xy 66.223352 -310.781357) (xy 66.274134 -310.773314)
			(xy 66.32555 -310.773314) (xy 66.376332 -310.781357) (xy 66.425231 -310.797245) (xy 66.471043 -310.820588)
			(xy 66.512639 -310.850809) (xy 66.548995 -310.887165) (xy 66.579216 -310.928761) (xy 66.602559 -310.974573)
			(xy 66.618447 -311.023472) (xy 66.62649 -311.074254) (xy 66.626994 -311.099962) (xy 66.943998 -311.099962)
			(xy 66.947958 -311.050908) (xy 66.959735 -311.003124) (xy 66.979026 -310.957848) (xy 67.005329 -310.916252)
			(xy 67.037964 -310.879415) (xy 67.076085 -310.84829) (xy 67.118706 -310.823683) (xy 67.164722 -310.806231)
			(xy 67.212941 -310.796387) (xy 67.262116 -310.794406) (xy 67.310971 -310.800338) (xy 67.358242 -310.81403)
			(xy 67.402704 -310.835128) (xy 67.443207 -310.863084) (xy 67.4787 -310.897176) (xy 67.508265 -310.93652)
			(xy 67.531136 -310.980097) (xy 67.54672 -311.026778) (xy 67.554615 -311.075355) (xy 67.55511 -311.099962)
			(xy 67.554615 -311.124569) (xy 67.554436 -311.12567) (xy 67.873114 -311.12567) (xy 67.873114 -311.074254)
			(xy 67.881157 -311.023472) (xy 67.897045 -310.974573) (xy 67.920388 -310.928761) (xy 67.950609 -310.887165)
			(xy 67.986965 -310.850809) (xy 68.028561 -310.820588) (xy 68.074373 -310.797245) (xy 68.123272 -310.781357)
			(xy 68.174054 -310.773314) (xy 68.22547 -310.773314) (xy 68.276252 -310.781357) (xy 68.325151 -310.797245)
			(xy 68.370963 -310.820588) (xy 68.412559 -310.850809) (xy 68.448915 -310.887165) (xy 68.479136 -310.928761)
			(xy 68.502479 -310.974573) (xy 68.518367 -311.023472) (xy 68.52641 -311.074254) (xy 68.526914 -311.099962)
			(xy 68.844172 -311.099962) (xy 68.848132 -311.050908) (xy 68.859909 -311.003124) (xy 68.8792 -310.957848)
			(xy 68.905503 -310.916252) (xy 68.938138 -310.879415) (xy 68.976259 -310.84829) (xy 69.01888 -310.823683)
			(xy 69.064896 -310.806231) (xy 69.113115 -310.796387) (xy 69.16229 -310.794406) (xy 69.211145 -310.800338)
			(xy 69.258416 -310.81403) (xy 69.302878 -310.835128) (xy 69.343381 -310.863084) (xy 69.378874 -310.897176)
			(xy 69.408439 -310.93652) (xy 69.43131 -310.980097) (xy 69.446894 -311.026778) (xy 69.454789 -311.075355)
			(xy 69.455284 -311.099962) (xy 69.454789 -311.124569) (xy 69.45461 -311.12567) (xy 69.773288 -311.12567)
			(xy 69.773288 -311.074254) (xy 69.781331 -311.023472) (xy 69.797219 -310.974573) (xy 69.820562 -310.928761)
			(xy 69.850783 -310.887165) (xy 69.887139 -310.850809) (xy 69.928735 -310.820588) (xy 69.974547 -310.797245)
			(xy 70.023446 -310.781357) (xy 70.074228 -310.773314) (xy 70.125644 -310.773314) (xy 70.176426 -310.781357)
			(xy 70.225325 -310.797245) (xy 70.271137 -310.820588) (xy 70.312733 -310.850809) (xy 70.349089 -310.887165)
			(xy 70.37931 -310.928761) (xy 70.402653 -310.974573) (xy 70.418541 -311.023472) (xy 70.426584 -311.074254)
			(xy 70.427088 -311.099962) (xy 70.744092 -311.099962) (xy 70.748052 -311.050908) (xy 70.759829 -311.003124)
			(xy 70.77912 -310.957848) (xy 70.805423 -310.916252) (xy 70.838058 -310.879415) (xy 70.876179 -310.84829)
			(xy 70.9188 -310.823683) (xy 70.964816 -310.806231) (xy 71.013035 -310.796387) (xy 71.06221 -310.794406)
			(xy 71.111065 -310.800338) (xy 71.158336 -310.81403) (xy 71.202798 -310.835128) (xy 71.243301 -310.863084)
			(xy 71.278794 -310.897176) (xy 71.308359 -310.93652) (xy 71.33123 -310.980097) (xy 71.346814 -311.026778)
			(xy 71.354709 -311.075355) (xy 71.355204 -311.099962) (xy 71.354709 -311.124569) (xy 71.35453 -311.12567)
			(xy 71.673208 -311.12567) (xy 71.673208 -311.074254) (xy 71.681251 -311.023472) (xy 71.697139 -310.974573)
			(xy 71.720482 -310.928761) (xy 71.750703 -310.887165) (xy 71.787059 -310.850809) (xy 71.828655 -310.820588)
			(xy 71.874467 -310.797245) (xy 71.923366 -310.781357) (xy 71.974148 -310.773314) (xy 72.025564 -310.773314)
			(xy 72.076346 -310.781357) (xy 72.125245 -310.797245) (xy 72.171057 -310.820588) (xy 72.212653 -310.850809)
			(xy 72.249009 -310.887165) (xy 72.27923 -310.928761) (xy 72.302573 -310.974573) (xy 72.318461 -311.023472)
			(xy 72.326504 -311.074254) (xy 72.327008 -311.099962) (xy 72.644012 -311.099962) (xy 72.647972 -311.050908)
			(xy 72.659749 -311.003124) (xy 72.67904 -310.957848) (xy 72.705343 -310.916252) (xy 72.737978 -310.879415)
			(xy 72.776099 -310.84829) (xy 72.81872 -310.823683) (xy 72.864736 -310.806231) (xy 72.912955 -310.796387)
			(xy 72.96213 -310.794406) (xy 73.010985 -310.800338) (xy 73.058256 -310.81403) (xy 73.102718 -310.835128)
			(xy 73.143221 -310.863084) (xy 73.178714 -310.897176) (xy 73.208279 -310.93652) (xy 73.23115 -310.980097)
			(xy 73.246734 -311.026778) (xy 73.254629 -311.075355) (xy 73.255124 -311.099962) (xy 73.254629 -311.124569)
			(xy 73.25445 -311.12567) (xy 73.573128 -311.12567) (xy 73.573128 -311.074254) (xy 73.581171 -311.023472)
			(xy 73.597059 -310.974573) (xy 73.620402 -310.928761) (xy 73.650623 -310.887165) (xy 73.686979 -310.850809)
			(xy 73.728575 -310.820588) (xy 73.774387 -310.797245) (xy 73.823286 -310.781357) (xy 73.874068 -310.773314)
			(xy 73.925484 -310.773314) (xy 73.976266 -310.781357) (xy 74.025165 -310.797245) (xy 74.070977 -310.820588)
			(xy 74.112573 -310.850809) (xy 74.148929 -310.887165) (xy 74.17915 -310.928761) (xy 74.202493 -310.974573)
			(xy 74.218381 -311.023472) (xy 74.226424 -311.074254) (xy 74.226928 -311.099962) (xy 74.544186 -311.099962)
			(xy 74.548146 -311.050908) (xy 74.559923 -311.003124) (xy 74.579214 -310.957848) (xy 74.605517 -310.916252)
			(xy 74.638152 -310.879415) (xy 74.676273 -310.84829) (xy 74.718894 -310.823683) (xy 74.76491 -310.806231)
			(xy 74.813129 -310.796387) (xy 74.862304 -310.794406) (xy 74.911159 -310.800338) (xy 74.95843 -310.81403)
			(xy 75.002892 -310.835128) (xy 75.043395 -310.863084) (xy 75.078888 -310.897176) (xy 75.108453 -310.93652)
			(xy 75.131324 -310.980097) (xy 75.146908 -311.026778) (xy 75.154803 -311.075355) (xy 75.155298 -311.099962)
			(xy 75.154803 -311.124569) (xy 75.154624 -311.12567) (xy 75.473302 -311.12567) (xy 75.473302 -311.074254)
			(xy 75.481345 -311.023472) (xy 75.497233 -310.974573) (xy 75.520576 -310.928761) (xy 75.550797 -310.887165)
			(xy 75.587153 -310.850809) (xy 75.628749 -310.820588) (xy 75.674561 -310.797245) (xy 75.72346 -310.781357)
			(xy 75.774242 -310.773314) (xy 75.825658 -310.773314) (xy 75.87644 -310.781357) (xy 75.925339 -310.797245)
			(xy 75.971151 -310.820588) (xy 76.012747 -310.850809) (xy 76.049103 -310.887165) (xy 76.079324 -310.928761)
			(xy 76.102667 -310.974573) (xy 76.118555 -311.023472) (xy 76.126598 -311.074254) (xy 76.127102 -311.099962)
			(xy 76.444106 -311.099962) (xy 76.448066 -311.050908) (xy 76.459843 -311.003124) (xy 76.479134 -310.957848)
			(xy 76.505437 -310.916252) (xy 76.538072 -310.879415) (xy 76.576193 -310.84829) (xy 76.618814 -310.823683)
			(xy 76.66483 -310.806231) (xy 76.713049 -310.796387) (xy 76.762224 -310.794406) (xy 76.811079 -310.800338)
			(xy 76.85835 -310.81403) (xy 76.902812 -310.835128) (xy 76.943315 -310.863084) (xy 76.978808 -310.897176)
			(xy 77.008373 -310.93652) (xy 77.031244 -310.980097) (xy 77.046828 -311.026778) (xy 77.054723 -311.075355)
			(xy 77.055218 -311.099962) (xy 77.054723 -311.124569) (xy 77.054544 -311.12567) (xy 77.373222 -311.12567)
			(xy 77.373222 -311.074254) (xy 77.381265 -311.023472) (xy 77.397153 -310.974573) (xy 77.420496 -310.928761)
			(xy 77.450717 -310.887165) (xy 77.487073 -310.850809) (xy 77.528669 -310.820588) (xy 77.574481 -310.797245)
			(xy 77.62338 -310.781357) (xy 77.674162 -310.773314) (xy 77.725578 -310.773314) (xy 77.77636 -310.781357)
			(xy 77.825259 -310.797245) (xy 77.871071 -310.820588) (xy 77.912667 -310.850809) (xy 77.949023 -310.887165)
			(xy 77.979244 -310.928761) (xy 78.002587 -310.974573) (xy 78.018475 -311.023472) (xy 78.026518 -311.074254)
			(xy 78.027022 -311.099962) (xy 78.026518 -311.12567) (xy 78.018475 -311.176452) (xy 78.002587 -311.225351)
			(xy 77.979244 -311.271163) (xy 77.949023 -311.312759) (xy 77.912667 -311.349115) (xy 77.871071 -311.379336)
			(xy 77.825259 -311.402679) (xy 77.77636 -311.418567) (xy 77.725578 -311.42661) (xy 77.674162 -311.42661)
			(xy 77.62338 -311.418567) (xy 77.574481 -311.402679) (xy 77.528669 -311.379336) (xy 77.487073 -311.349115)
			(xy 77.450717 -311.312759) (xy 77.420496 -311.271163) (xy 77.397153 -311.225351) (xy 77.381265 -311.176452)
			(xy 77.373222 -311.12567) (xy 77.054544 -311.12567) (xy 77.046828 -311.173146) (xy 77.031244 -311.219827)
			(xy 77.008373 -311.263404) (xy 76.978808 -311.302748) (xy 76.943315 -311.33684) (xy 76.902812 -311.364796)
			(xy 76.85835 -311.385894) (xy 76.811079 -311.399586) (xy 76.762224 -311.405518) (xy 76.713049 -311.403537)
			(xy 76.66483 -311.393693) (xy 76.618814 -311.376241) (xy 76.576193 -311.351634) (xy 76.538072 -311.320509)
			(xy 76.505437 -311.283672) (xy 76.479134 -311.242076) (xy 76.459843 -311.1968) (xy 76.448066 -311.149016)
			(xy 76.444106 -311.099962) (xy 76.127102 -311.099962) (xy 76.126598 -311.12567) (xy 76.118555 -311.176452)
			(xy 76.102667 -311.225351) (xy 76.079324 -311.271163) (xy 76.049103 -311.312759) (xy 76.012747 -311.349115)
			(xy 75.971151 -311.379336) (xy 75.925339 -311.402679) (xy 75.87644 -311.418567) (xy 75.825658 -311.42661)
			(xy 75.774242 -311.42661) (xy 75.72346 -311.418567) (xy 75.674561 -311.402679) (xy 75.628749 -311.379336)
			(xy 75.587153 -311.349115) (xy 75.550797 -311.312759) (xy 75.520576 -311.271163) (xy 75.497233 -311.225351)
			(xy 75.481345 -311.176452) (xy 75.473302 -311.12567) (xy 75.154624 -311.12567) (xy 75.146908 -311.173146)
			(xy 75.131324 -311.219827) (xy 75.108453 -311.263404) (xy 75.078888 -311.302748) (xy 75.043395 -311.33684)
			(xy 75.002892 -311.364796) (xy 74.95843 -311.385894) (xy 74.911159 -311.399586) (xy 74.862304 -311.405518)
			(xy 74.813129 -311.403537) (xy 74.76491 -311.393693) (xy 74.718894 -311.376241) (xy 74.676273 -311.351634)
			(xy 74.638152 -311.320509) (xy 74.605517 -311.283672) (xy 74.579214 -311.242076) (xy 74.559923 -311.1968)
			(xy 74.548146 -311.149016) (xy 74.544186 -311.099962) (xy 74.226928 -311.099962) (xy 74.226424 -311.12567)
			(xy 74.218381 -311.176452) (xy 74.202493 -311.225351) (xy 74.17915 -311.271163) (xy 74.148929 -311.312759)
			(xy 74.112573 -311.349115) (xy 74.070977 -311.379336) (xy 74.025165 -311.402679) (xy 73.976266 -311.418567)
			(xy 73.925484 -311.42661) (xy 73.874068 -311.42661) (xy 73.823286 -311.418567) (xy 73.774387 -311.402679)
			(xy 73.728575 -311.379336) (xy 73.686979 -311.349115) (xy 73.650623 -311.312759) (xy 73.620402 -311.271163)
			(xy 73.597059 -311.225351) (xy 73.581171 -311.176452) (xy 73.573128 -311.12567) (xy 73.25445 -311.12567)
			(xy 73.246734 -311.173146) (xy 73.23115 -311.219827) (xy 73.208279 -311.263404) (xy 73.178714 -311.302748)
			(xy 73.143221 -311.33684) (xy 73.102718 -311.364796) (xy 73.058256 -311.385894) (xy 73.010985 -311.399586)
			(xy 72.96213 -311.405518) (xy 72.912955 -311.403537) (xy 72.864736 -311.393693) (xy 72.81872 -311.376241)
			(xy 72.776099 -311.351634) (xy 72.737978 -311.320509) (xy 72.705343 -311.283672) (xy 72.67904 -311.242076)
			(xy 72.659749 -311.1968) (xy 72.647972 -311.149016) (xy 72.644012 -311.099962) (xy 72.327008 -311.099962)
			(xy 72.326504 -311.12567) (xy 72.318461 -311.176452) (xy 72.302573 -311.225351) (xy 72.27923 -311.271163)
			(xy 72.249009 -311.312759) (xy 72.212653 -311.349115) (xy 72.171057 -311.379336) (xy 72.125245 -311.402679)
			(xy 72.076346 -311.418567) (xy 72.025564 -311.42661) (xy 71.974148 -311.42661) (xy 71.923366 -311.418567)
			(xy 71.874467 -311.402679) (xy 71.828655 -311.379336) (xy 71.787059 -311.349115) (xy 71.750703 -311.312759)
			(xy 71.720482 -311.271163) (xy 71.697139 -311.225351) (xy 71.681251 -311.176452) (xy 71.673208 -311.12567)
			(xy 71.35453 -311.12567) (xy 71.346814 -311.173146) (xy 71.33123 -311.219827) (xy 71.308359 -311.263404)
			(xy 71.278794 -311.302748) (xy 71.243301 -311.33684) (xy 71.202798 -311.364796) (xy 71.158336 -311.385894)
			(xy 71.111065 -311.399586) (xy 71.06221 -311.405518) (xy 71.013035 -311.403537) (xy 70.964816 -311.393693)
			(xy 70.9188 -311.376241) (xy 70.876179 -311.351634) (xy 70.838058 -311.320509) (xy 70.805423 -311.283672)
			(xy 70.77912 -311.242076) (xy 70.759829 -311.1968) (xy 70.748052 -311.149016) (xy 70.744092 -311.099962)
			(xy 70.427088 -311.099962) (xy 70.426584 -311.12567) (xy 70.418541 -311.176452) (xy 70.402653 -311.225351)
			(xy 70.37931 -311.271163) (xy 70.349089 -311.312759) (xy 70.312733 -311.349115) (xy 70.271137 -311.379336)
			(xy 70.225325 -311.402679) (xy 70.176426 -311.418567) (xy 70.125644 -311.42661) (xy 70.074228 -311.42661)
			(xy 70.023446 -311.418567) (xy 69.974547 -311.402679) (xy 69.928735 -311.379336) (xy 69.887139 -311.349115)
			(xy 69.850783 -311.312759) (xy 69.820562 -311.271163) (xy 69.797219 -311.225351) (xy 69.781331 -311.176452)
			(xy 69.773288 -311.12567) (xy 69.45461 -311.12567) (xy 69.446894 -311.173146) (xy 69.43131 -311.219827)
			(xy 69.408439 -311.263404) (xy 69.378874 -311.302748) (xy 69.343381 -311.33684) (xy 69.302878 -311.364796)
			(xy 69.258416 -311.385894) (xy 69.211145 -311.399586) (xy 69.16229 -311.405518) (xy 69.113115 -311.403537)
			(xy 69.064896 -311.393693) (xy 69.01888 -311.376241) (xy 68.976259 -311.351634) (xy 68.938138 -311.320509)
			(xy 68.905503 -311.283672) (xy 68.8792 -311.242076) (xy 68.859909 -311.1968) (xy 68.848132 -311.149016)
			(xy 68.844172 -311.099962) (xy 68.526914 -311.099962) (xy 68.52641 -311.12567) (xy 68.518367 -311.176452)
			(xy 68.502479 -311.225351) (xy 68.479136 -311.271163) (xy 68.448915 -311.312759) (xy 68.412559 -311.349115)
			(xy 68.370963 -311.379336) (xy 68.325151 -311.402679) (xy 68.276252 -311.418567) (xy 68.22547 -311.42661)
			(xy 68.174054 -311.42661) (xy 68.123272 -311.418567) (xy 68.074373 -311.402679) (xy 68.028561 -311.379336)
			(xy 67.986965 -311.349115) (xy 67.950609 -311.312759) (xy 67.920388 -311.271163) (xy 67.897045 -311.225351)
			(xy 67.881157 -311.176452) (xy 67.873114 -311.12567) (xy 67.554436 -311.12567) (xy 67.54672 -311.173146)
			(xy 67.531136 -311.219827) (xy 67.508265 -311.263404) (xy 67.4787 -311.302748) (xy 67.443207 -311.33684)
			(xy 67.402704 -311.364796) (xy 67.358242 -311.385894) (xy 67.310971 -311.399586) (xy 67.262116 -311.405518)
			(xy 67.212941 -311.403537) (xy 67.164722 -311.393693) (xy 67.118706 -311.376241) (xy 67.076085 -311.351634)
			(xy 67.037964 -311.320509) (xy 67.005329 -311.283672) (xy 66.979026 -311.242076) (xy 66.959735 -311.1968)
			(xy 66.947958 -311.149016) (xy 66.943998 -311.099962) (xy 66.626994 -311.099962) (xy 66.62649 -311.12567)
			(xy 66.618447 -311.176452) (xy 66.602559 -311.225351) (xy 66.579216 -311.271163) (xy 66.548995 -311.312759)
			(xy 66.512639 -311.349115) (xy 66.471043 -311.379336) (xy 66.425231 -311.402679) (xy 66.376332 -311.418567)
			(xy 66.32555 -311.42661) (xy 66.274134 -311.42661) (xy 66.223352 -311.418567) (xy 66.174453 -311.402679)
			(xy 66.128641 -311.379336) (xy 66.087045 -311.349115) (xy 66.050689 -311.312759) (xy 66.020468 -311.271163)
			(xy 65.997125 -311.225351) (xy 65.981237 -311.176452) (xy 65.973194 -311.12567) (xy 65.654516 -311.12567)
			(xy 65.6468 -311.173146) (xy 65.631216 -311.219827) (xy 65.608345 -311.263404) (xy 65.57878 -311.302748)
			(xy 65.543287 -311.33684) (xy 65.502784 -311.364796) (xy 65.458322 -311.385894) (xy 65.411051 -311.399586)
			(xy 65.362196 -311.405518) (xy 65.313021 -311.403537) (xy 65.264802 -311.393693) (xy 65.218786 -311.376241)
			(xy 65.176165 -311.351634) (xy 65.138044 -311.320509) (xy 65.105409 -311.283672) (xy 65.079106 -311.242076)
			(xy 65.059815 -311.1968) (xy 65.048038 -311.149016) (xy 65.044078 -311.099962) (xy 64.727074 -311.099962)
			(xy 64.72657 -311.12567) (xy 64.718527 -311.176452) (xy 64.702639 -311.225351) (xy 64.679296 -311.271163)
			(xy 64.649075 -311.312759) (xy 64.612719 -311.349115) (xy 64.571123 -311.379336) (xy 64.525311 -311.402679)
			(xy 64.476412 -311.418567) (xy 64.42563 -311.42661) (xy 64.374214 -311.42661) (xy 64.323432 -311.418567)
			(xy 64.274533 -311.402679) (xy 64.228721 -311.379336) (xy 64.187125 -311.349115) (xy 64.150769 -311.312759)
			(xy 64.120548 -311.271163) (xy 64.097205 -311.225351) (xy 64.081317 -311.176452) (xy 64.073274 -311.12567)
			(xy 63.754596 -311.12567) (xy 63.74688 -311.173146) (xy 63.731296 -311.219827) (xy 63.708425 -311.263404)
			(xy 63.67886 -311.302748) (xy 63.643367 -311.33684) (xy 63.602864 -311.364796) (xy 63.558402 -311.385894)
			(xy 63.511131 -311.399586) (xy 63.462276 -311.405518) (xy 63.413101 -311.403537) (xy 63.364882 -311.393693)
			(xy 63.318866 -311.376241) (xy 63.276245 -311.351634) (xy 63.238124 -311.320509) (xy 63.205489 -311.283672)
			(xy 63.179186 -311.242076) (xy 63.159895 -311.1968) (xy 63.148118 -311.149016) (xy 63.144158 -311.099962)
			(xy 62.8269 -311.099962) (xy 62.826396 -311.12567) (xy 62.818353 -311.176452) (xy 62.802465 -311.225351)
			(xy 62.779122 -311.271163) (xy 62.748901 -311.312759) (xy 62.712545 -311.349115) (xy 62.670949 -311.379336)
			(xy 62.625137 -311.402679) (xy 62.576238 -311.418567) (xy 62.525456 -311.42661) (xy 62.47404 -311.42661)
			(xy 62.423258 -311.418567) (xy 62.374359 -311.402679) (xy 62.328547 -311.379336) (xy 62.286951 -311.349115)
			(xy 62.250595 -311.312759) (xy 62.220374 -311.271163) (xy 62.197031 -311.225351) (xy 62.181143 -311.176452)
			(xy 62.1731 -311.12567) (xy 61.854422 -311.12567) (xy 61.846706 -311.173146) (xy 61.831122 -311.219827)
			(xy 61.808251 -311.263404) (xy 61.778686 -311.302748) (xy 61.743193 -311.33684) (xy 61.70269 -311.364796)
			(xy 61.658228 -311.385894) (xy 61.610957 -311.399586) (xy 61.562102 -311.405518) (xy 61.512927 -311.403537)
			(xy 61.464708 -311.393693) (xy 61.418692 -311.376241) (xy 61.376071 -311.351634) (xy 61.33795 -311.320509)
			(xy 61.305315 -311.283672) (xy 61.279012 -311.242076) (xy 61.259721 -311.1968) (xy 61.247944 -311.149016)
			(xy 61.243984 -311.099962) (xy 60.92698 -311.099962) (xy 60.926476 -311.12567) (xy 60.918433 -311.176452)
			(xy 60.902545 -311.225351) (xy 60.879202 -311.271163) (xy 60.848981 -311.312759) (xy 60.812625 -311.349115)
			(xy 60.771029 -311.379336) (xy 60.725217 -311.402679) (xy 60.676318 -311.418567) (xy 60.625536 -311.42661)
			(xy 60.57412 -311.42661) (xy 60.523338 -311.418567) (xy 60.474439 -311.402679) (xy 60.428627 -311.379336)
			(xy 60.387031 -311.349115) (xy 60.350675 -311.312759) (xy 60.320454 -311.271163) (xy 60.297111 -311.225351)
			(xy 60.281223 -311.176452) (xy 60.27318 -311.12567) (xy 59.954502 -311.12567) (xy 59.946786 -311.173146)
			(xy 59.931202 -311.219827) (xy 59.908331 -311.263404) (xy 59.878766 -311.302748) (xy 59.843273 -311.33684)
			(xy 59.80277 -311.364796) (xy 59.758308 -311.385894) (xy 59.711037 -311.399586) (xy 59.662182 -311.405518)
			(xy 59.613007 -311.403537) (xy 59.564788 -311.393693) (xy 59.518772 -311.376241) (xy 59.476151 -311.351634)
			(xy 59.43803 -311.320509) (xy 59.405395 -311.283672) (xy 59.379092 -311.242076) (xy 59.359801 -311.1968)
			(xy 59.348024 -311.149016) (xy 59.344064 -311.099962) (xy 59.02706 -311.099962) (xy 59.026556 -311.12567)
			(xy 59.018513 -311.176452) (xy 59.002625 -311.225351) (xy 58.979282 -311.271163) (xy 58.949061 -311.312759)
			(xy 58.912705 -311.349115) (xy 58.871109 -311.379336) (xy 58.825297 -311.402679) (xy 58.776398 -311.418567)
			(xy 58.725616 -311.42661) (xy 58.6742 -311.42661) (xy 58.623418 -311.418567) (xy 58.574519 -311.402679)
			(xy 58.528707 -311.379336) (xy 58.487111 -311.349115) (xy 58.450755 -311.312759) (xy 58.420534 -311.271163)
			(xy 58.397191 -311.225351) (xy 58.381303 -311.176452) (xy 58.37326 -311.12567) (xy 58.054582 -311.12567)
			(xy 58.046866 -311.173146) (xy 58.031282 -311.219827) (xy 58.008411 -311.263404) (xy 57.978846 -311.302748)
			(xy 57.943353 -311.33684) (xy 57.90285 -311.364796) (xy 57.858388 -311.385894) (xy 57.811117 -311.399586)
			(xy 57.762262 -311.405518) (xy 57.713087 -311.403537) (xy 57.664868 -311.393693) (xy 57.618852 -311.376241)
			(xy 57.576231 -311.351634) (xy 57.53811 -311.320509) (xy 57.505475 -311.283672) (xy 57.479172 -311.242076)
			(xy 57.459881 -311.1968) (xy 57.448104 -311.149016) (xy 57.444144 -311.099962) (xy 57.12714 -311.099962)
			(xy 57.126636 -311.12567) (xy 57.118593 -311.176452) (xy 57.102705 -311.225351) (xy 57.079362 -311.271163)
			(xy 57.049141 -311.312759) (xy 57.012785 -311.349115) (xy 56.971189 -311.379336) (xy 56.925377 -311.402679)
			(xy 56.876478 -311.418567) (xy 56.825696 -311.42661) (xy 56.77428 -311.42661) (xy 56.723498 -311.418567)
			(xy 56.674599 -311.402679) (xy 56.628787 -311.379336) (xy 56.587191 -311.349115) (xy 56.550835 -311.312759)
			(xy 56.520614 -311.271163) (xy 56.497271 -311.225351) (xy 56.481383 -311.176452) (xy 56.47334 -311.12567)
			(xy 56.154408 -311.12567) (xy 56.146692 -311.173146) (xy 56.131108 -311.219827) (xy 56.108237 -311.263404)
			(xy 56.078672 -311.302748) (xy 56.043179 -311.33684) (xy 56.002676 -311.364796) (xy 55.958214 -311.385894)
			(xy 55.910943 -311.399586) (xy 55.862088 -311.405518) (xy 55.812913 -311.403537) (xy 55.764694 -311.393693)
			(xy 55.718678 -311.376241) (xy 55.676057 -311.351634) (xy 55.637936 -311.320509) (xy 55.605301 -311.283672)
			(xy 55.578998 -311.242076) (xy 55.559707 -311.1968) (xy 55.54793 -311.149016) (xy 55.54397 -311.099962)
			(xy 55.226966 -311.099962) (xy 55.226462 -311.12567) (xy 55.218419 -311.176452) (xy 55.202531 -311.225351)
			(xy 55.179188 -311.271163) (xy 55.148967 -311.312759) (xy 55.112611 -311.349115) (xy 55.071015 -311.379336)
			(xy 55.025203 -311.402679) (xy 54.976304 -311.418567) (xy 54.925522 -311.42661) (xy 54.874106 -311.42661)
			(xy 54.823324 -311.418567) (xy 54.774425 -311.402679) (xy 54.728613 -311.379336) (xy 54.687017 -311.349115)
			(xy 54.650661 -311.312759) (xy 54.62044 -311.271163) (xy 54.597097 -311.225351) (xy 54.581209 -311.176452)
			(xy 54.573166 -311.12567) (xy 54.254488 -311.12567) (xy 54.246772 -311.173146) (xy 54.231188 -311.219827)
			(xy 54.208317 -311.263404) (xy 54.178752 -311.302748) (xy 54.143259 -311.33684) (xy 54.102756 -311.364796)
			(xy 54.058294 -311.385894) (xy 54.011023 -311.399586) (xy 53.962168 -311.405518) (xy 53.912993 -311.403537)
			(xy 53.864774 -311.393693) (xy 53.818758 -311.376241) (xy 53.776137 -311.351634) (xy 53.738016 -311.320509)
			(xy 53.705381 -311.283672) (xy 53.679078 -311.242076) (xy 53.659787 -311.1968) (xy 53.64801 -311.149016)
			(xy 53.64405 -311.099962) (xy 53.327046 -311.099962) (xy 53.326542 -311.12567) (xy 53.318499 -311.176452)
			(xy 53.302611 -311.225351) (xy 53.279268 -311.271163) (xy 53.249047 -311.312759) (xy 53.212691 -311.349115)
			(xy 53.171095 -311.379336) (xy 53.125283 -311.402679) (xy 53.076384 -311.418567) (xy 53.025602 -311.42661)
			(xy 52.974186 -311.42661) (xy 52.923404 -311.418567) (xy 52.874505 -311.402679) (xy 52.828693 -311.379336)
			(xy 52.787097 -311.349115) (xy 52.750741 -311.312759) (xy 52.72052 -311.271163) (xy 52.697177 -311.225351)
			(xy 52.681289 -311.176452) (xy 52.673246 -311.12567) (xy 52.354568 -311.12567) (xy 52.346852 -311.173146)
			(xy 52.331268 -311.219827) (xy 52.308397 -311.263404) (xy 52.278832 -311.302748) (xy 52.243339 -311.33684)
			(xy 52.202836 -311.364796) (xy 52.158374 -311.385894) (xy 52.111103 -311.399586) (xy 52.062248 -311.405518)
			(xy 52.013073 -311.403537) (xy 51.964854 -311.393693) (xy 51.918838 -311.376241) (xy 51.876217 -311.351634)
			(xy 51.838096 -311.320509) (xy 51.805461 -311.283672) (xy 51.779158 -311.242076) (xy 51.759867 -311.1968)
			(xy 51.74809 -311.149016) (xy 51.74413 -311.099962) (xy 51.427126 -311.099962) (xy 51.426622 -311.12567)
			(xy 51.418579 -311.176452) (xy 51.402691 -311.225351) (xy 51.379348 -311.271163) (xy 51.349127 -311.312759)
			(xy 51.312771 -311.349115) (xy 51.271175 -311.379336) (xy 51.225363 -311.402679) (xy 51.176464 -311.418567)
			(xy 51.125682 -311.42661) (xy 51.074266 -311.42661) (xy 51.023484 -311.418567) (xy 50.974585 -311.402679)
			(xy 50.928773 -311.379336) (xy 50.887177 -311.349115) (xy 50.850821 -311.312759) (xy 50.8206 -311.271163)
			(xy 50.797257 -311.225351) (xy 50.781369 -311.176452) (xy 50.773326 -311.12567) (xy 50.454394 -311.12567)
			(xy 50.446678 -311.173146) (xy 50.431094 -311.219827) (xy 50.408223 -311.263404) (xy 50.378658 -311.302748)
			(xy 50.343165 -311.33684) (xy 50.302662 -311.364796) (xy 50.2582 -311.385894) (xy 50.210929 -311.399586)
			(xy 50.162074 -311.405518) (xy 50.112899 -311.403537) (xy 50.06468 -311.393693) (xy 50.018664 -311.376241)
			(xy 49.976043 -311.351634) (xy 49.937922 -311.320509) (xy 49.905287 -311.283672) (xy 49.878984 -311.242076)
			(xy 49.859693 -311.1968) (xy 49.847916 -311.149016) (xy 49.843956 -311.099962) (xy 49.526952 -311.099962)
			(xy 49.526448 -311.12567) (xy 49.518405 -311.176452) (xy 49.502517 -311.225351) (xy 49.479174 -311.271163)
			(xy 49.448953 -311.312759) (xy 49.412597 -311.349115) (xy 49.371001 -311.379336) (xy 49.325189 -311.402679)
			(xy 49.27629 -311.418567) (xy 49.225508 -311.42661) (xy 49.174092 -311.42661) (xy 49.12331 -311.418567)
			(xy 49.074411 -311.402679) (xy 49.028599 -311.379336) (xy 48.987003 -311.349115) (xy 48.950647 -311.312759)
			(xy 48.920426 -311.271163) (xy 48.897083 -311.225351) (xy 48.881195 -311.176452) (xy 48.873152 -311.12567)
			(xy 48.554474 -311.12567) (xy 48.546758 -311.173146) (xy 48.531174 -311.219827) (xy 48.508303 -311.263404)
			(xy 48.478738 -311.302748) (xy 48.443245 -311.33684) (xy 48.402742 -311.364796) (xy 48.35828 -311.385894)
			(xy 48.311009 -311.399586) (xy 48.262154 -311.405518) (xy 48.212979 -311.403537) (xy 48.16476 -311.393693)
			(xy 48.118744 -311.376241) (xy 48.076123 -311.351634) (xy 48.038002 -311.320509) (xy 48.005367 -311.283672)
			(xy 47.979064 -311.242076) (xy 47.959773 -311.1968) (xy 47.947996 -311.149016) (xy 47.944036 -311.099962)
			(xy 47.627032 -311.099962) (xy 47.626528 -311.12567) (xy 47.618485 -311.176452) (xy 47.602597 -311.225351)
			(xy 47.579254 -311.271163) (xy 47.549033 -311.312759) (xy 47.512677 -311.349115) (xy 47.471081 -311.379336)
			(xy 47.425269 -311.402679) (xy 47.37637 -311.418567) (xy 47.325588 -311.42661) (xy 47.274172 -311.42661)
			(xy 47.22339 -311.418567) (xy 47.174491 -311.402679) (xy 47.128679 -311.379336) (xy 47.087083 -311.349115)
			(xy 47.050727 -311.312759) (xy 47.020506 -311.271163) (xy 46.997163 -311.225351) (xy 46.981275 -311.176452)
			(xy 46.973232 -311.12567) (xy 46.654554 -311.12567) (xy 46.646838 -311.173146) (xy 46.631254 -311.219827)
			(xy 46.608383 -311.263404) (xy 46.578818 -311.302748) (xy 46.543325 -311.33684) (xy 46.502822 -311.364796)
			(xy 46.45836 -311.385894) (xy 46.411089 -311.399586) (xy 46.362234 -311.405518) (xy 46.313059 -311.403537)
			(xy 46.26484 -311.393693) (xy 46.218824 -311.376241) (xy 46.176203 -311.351634) (xy 46.138082 -311.320509)
			(xy 46.105447 -311.283672) (xy 46.079144 -311.242076) (xy 46.059853 -311.1968) (xy 46.048076 -311.149016)
			(xy 46.044116 -311.099962) (xy 45.727112 -311.099962) (xy 45.726608 -311.12567) (xy 45.718565 -311.176452)
			(xy 45.702677 -311.225351) (xy 45.679334 -311.271163) (xy 45.649113 -311.312759) (xy 45.612757 -311.349115)
			(xy 45.571161 -311.379336) (xy 45.525349 -311.402679) (xy 45.47645 -311.418567) (xy 45.425668 -311.42661)
			(xy 45.374252 -311.42661) (xy 45.32347 -311.418567) (xy 45.274571 -311.402679) (xy 45.228759 -311.379336)
			(xy 45.187163 -311.349115) (xy 45.150807 -311.312759) (xy 45.120586 -311.271163) (xy 45.097243 -311.225351)
			(xy 45.081355 -311.176452) (xy 45.073312 -311.12567) (xy 44.75438 -311.12567) (xy 44.746664 -311.173146)
			(xy 44.73108 -311.219827) (xy 44.708209 -311.263404) (xy 44.678644 -311.302748) (xy 44.643151 -311.33684)
			(xy 44.602648 -311.364796) (xy 44.558186 -311.385894) (xy 44.510915 -311.399586) (xy 44.46206 -311.405518)
			(xy 44.412885 -311.403537) (xy 44.364666 -311.393693) (xy 44.31865 -311.376241) (xy 44.276029 -311.351634)
			(xy 44.237908 -311.320509) (xy 44.205273 -311.283672) (xy 44.17897 -311.242076) (xy 44.159679 -311.1968)
			(xy 44.147902 -311.149016) (xy 44.143942 -311.099962) (xy 43.826938 -311.099962) (xy 43.826434 -311.12567)
			(xy 43.818391 -311.176452) (xy 43.802503 -311.225351) (xy 43.77916 -311.271163) (xy 43.748939 -311.312759)
			(xy 43.712583 -311.349115) (xy 43.670987 -311.379336) (xy 43.625175 -311.402679) (xy 43.576276 -311.418567)
			(xy 43.525494 -311.42661) (xy 43.474078 -311.42661) (xy 43.423296 -311.418567) (xy 43.374397 -311.402679)
			(xy 43.328585 -311.379336) (xy 43.286989 -311.349115) (xy 43.250633 -311.312759) (xy 43.220412 -311.271163)
			(xy 43.197069 -311.225351) (xy 43.181181 -311.176452) (xy 43.173138 -311.12567) (xy 42.85446 -311.12567)
			(xy 42.846744 -311.173146) (xy 42.83116 -311.219827) (xy 42.808289 -311.263404) (xy 42.778724 -311.302748)
			(xy 42.743231 -311.33684) (xy 42.702728 -311.364796) (xy 42.658266 -311.385894) (xy 42.610995 -311.399586)
			(xy 42.56214 -311.405518) (xy 42.512965 -311.403537) (xy 42.464746 -311.393693) (xy 42.41873 -311.376241)
			(xy 42.376109 -311.351634) (xy 42.337988 -311.320509) (xy 42.305353 -311.283672) (xy 42.27905 -311.242076)
			(xy 42.259759 -311.1968) (xy 42.247982 -311.149016) (xy 42.244022 -311.099962) (xy 41.927018 -311.099962)
			(xy 41.926514 -311.12567) (xy 41.918471 -311.176452) (xy 41.902583 -311.225351) (xy 41.87924 -311.271163)
			(xy 41.849019 -311.312759) (xy 41.812663 -311.349115) (xy 41.771067 -311.379336) (xy 41.725255 -311.402679)
			(xy 41.676356 -311.418567) (xy 41.625574 -311.42661) (xy 41.574158 -311.42661) (xy 41.523376 -311.418567)
			(xy 41.474477 -311.402679) (xy 41.428665 -311.379336) (xy 41.387069 -311.349115) (xy 41.350713 -311.312759)
			(xy 41.320492 -311.271163) (xy 41.297149 -311.225351) (xy 41.281261 -311.176452) (xy 41.273218 -311.12567)
			(xy 40.95454 -311.12567) (xy 40.946824 -311.173146) (xy 40.93124 -311.219827) (xy 40.908369 -311.263404)
			(xy 40.878804 -311.302748) (xy 40.843311 -311.33684) (xy 40.802808 -311.364796) (xy 40.758346 -311.385894)
			(xy 40.711075 -311.399586) (xy 40.66222 -311.405518) (xy 40.613045 -311.403537) (xy 40.564826 -311.393693)
			(xy 40.51881 -311.376241) (xy 40.476189 -311.351634) (xy 40.438068 -311.320509) (xy 40.405433 -311.283672)
			(xy 40.37913 -311.242076) (xy 40.359839 -311.1968) (xy 40.348062 -311.149016) (xy 40.344102 -311.099962)
			(xy 40.027098 -311.099962) (xy 40.026594 -311.12567) (xy 40.018551 -311.176452) (xy 40.002663 -311.225351)
			(xy 39.97932 -311.271163) (xy 39.949099 -311.312759) (xy 39.912743 -311.349115) (xy 39.871147 -311.379336)
			(xy 39.825335 -311.402679) (xy 39.776436 -311.418567) (xy 39.725654 -311.42661) (xy 39.674238 -311.42661)
			(xy 39.623456 -311.418567) (xy 39.574557 -311.402679) (xy 39.528745 -311.379336) (xy 39.487149 -311.349115)
			(xy 39.450793 -311.312759) (xy 39.420572 -311.271163) (xy 39.397229 -311.225351) (xy 39.381341 -311.176452)
			(xy 39.373298 -311.12567) (xy 39.05462 -311.12567) (xy 39.046904 -311.173146) (xy 39.03132 -311.219827)
			(xy 39.008449 -311.263404) (xy 38.978884 -311.302748) (xy 38.943391 -311.33684) (xy 38.902888 -311.364796)
			(xy 38.858426 -311.385894) (xy 38.811155 -311.399586) (xy 38.7623 -311.405518) (xy 38.713125 -311.403537)
			(xy 38.664906 -311.393693) (xy 38.61889 -311.376241) (xy 38.576269 -311.351634) (xy 38.538148 -311.320509)
			(xy 38.505513 -311.283672) (xy 38.47921 -311.242076) (xy 38.459919 -311.1968) (xy 38.448142 -311.149016)
			(xy 38.444182 -311.099962) (xy 38.10508 -311.099962) (xy 38.104585 -311.124569) (xy 38.09669 -311.173146)
			(xy 38.081106 -311.219827) (xy 38.058235 -311.263404) (xy 38.02867 -311.302748) (xy 37.993177 -311.33684)
			(xy 37.952674 -311.364796) (xy 37.908212 -311.385894) (xy 37.860941 -311.399586) (xy 37.812086 -311.405518)
			(xy 37.762911 -311.403537) (xy 37.714692 -311.393693) (xy 37.668676 -311.376241) (xy 37.626055 -311.351634)
			(xy 37.587934 -311.320509) (xy 37.555299 -311.283672) (xy 37.528996 -311.242076) (xy 37.509705 -311.1968)
			(xy 37.497928 -311.149016) (xy 37.493968 -311.099962) (xy 37.15512 -311.099962) (xy 37.154625 -311.124569)
			(xy 37.14673 -311.173146) (xy 37.131146 -311.219827) (xy 37.108275 -311.263404) (xy 37.07871 -311.302748)
			(xy 37.043217 -311.33684) (xy 37.002714 -311.364796) (xy 36.958252 -311.385894) (xy 36.910981 -311.399586)
			(xy 36.862126 -311.405518) (xy 36.812951 -311.403537) (xy 36.764732 -311.393693) (xy 36.718716 -311.376241)
			(xy 36.676095 -311.351634) (xy 36.637974 -311.320509) (xy 36.605339 -311.283672) (xy 36.579036 -311.242076)
			(xy 36.559745 -311.1968) (xy 36.547968 -311.149016) (xy 36.544008 -311.099962) (xy 35.02615 -311.099962)
			(xy 35.011639 -311.149382) (xy 34.988997 -311.198959) (xy 34.959531 -311.244809) (xy 34.92384 -311.286)
			(xy 34.882649 -311.321691) (xy 34.836799 -311.351157) (xy 34.787222 -311.373799) (xy 34.734927 -311.389154)
			(xy 34.680979 -311.39691) (xy 34.626477 -311.39691) (xy 34.572529 -311.389154) (xy 34.520234 -311.373799)
			(xy 34.470657 -311.351157) (xy 34.424807 -311.321691) (xy 34.383616 -311.286) (xy 34.347925 -311.244809)
			(xy 34.318459 -311.198959) (xy 34.295817 -311.149382) (xy 34.280462 -311.097087) (xy 34.272706 -311.043139)
			(xy 34.27222 -311.015888) (xy 34.272711 -310.987113) (xy 34.28137 -310.930217) (xy 34.298473 -310.875266)
			(xy 34.323634 -310.823506) (xy 34.356282 -310.776112) (xy 34.375598 -310.754776) (xy 34.384845 -310.74413)
			(xy 34.397761 -310.719082) (xy 34.40333 -310.691456) (xy 34.401129 -310.66336) (xy 34.391325 -310.636939)
			(xy 34.374666 -310.614208) (xy 34.352424 -310.596902) (xy 34.33953 -310.5912) (xy 34.31343 -310.580181)
			(xy 34.26461 -310.551434) (xy 34.220577 -310.515786) (xy 34.182297 -310.474019) (xy 34.150614 -310.427052)
			(xy 34.126222 -310.375917) (xy 34.109657 -310.321738) (xy 34.101285 -310.265705) (xy 34.10077 -310.237378)
			(xy 17.71396 -310.237378) (xy 17.71396 -310.549798) (xy 17.71431 -310.5585) (xy 17.720124 -310.574904)
			(xy 17.731085 -310.588422) (xy 17.738344 -310.593232) (xy 17.824196 -310.645048) (xy 17.850612 -310.646064)
			(xy 17.86255 -310.639714) (xy 17.889967 -310.626112) (xy 17.94806 -310.606858) (xy 18.00848 -310.597121)
			(xy 18.03908 -310.596534) (xy 18.066331 -310.59702) (xy 18.120279 -310.604776) (xy 18.172573 -310.620131)
			(xy 18.22215 -310.642772) (xy 18.268 -310.672238) (xy 18.30919 -310.70793) (xy 18.344882 -310.74912)
			(xy 18.374348 -310.79497) (xy 18.391371 -310.832246) (xy 28.267912 -310.832246) (xy 28.271983 -310.776624)
			(xy 28.284109 -310.722187) (xy 28.304032 -310.670096) (xy 28.331328 -310.621461) (xy 28.365414 -310.577318)
			(xy 28.405563 -310.538609) (xy 28.450921 -310.506158) (xy 28.500521 -310.480657) (xy 28.553305 -310.46265)
			(xy 28.608148 -310.45252) (xy 28.663882 -310.450483) (xy 28.719319 -310.456583) (xy 28.773276 -310.470689)
			(xy 28.824605 -310.492501) (xy 28.872211 -310.521555) (xy 28.915079 -310.55723) (xy 28.952296 -310.598767)
			(xy 28.983069 -310.64528) (xy 29.006741 -310.695777) (xy 29.022809 -310.749184) (xy 29.030929 -310.80436)
			(xy 29.031438 -310.832246) (xy 29.030929 -310.860132) (xy 29.022809 -310.915308) (xy 29.006741 -310.968715)
			(xy 28.983069 -311.019212) (xy 28.952296 -311.065725) (xy 28.915079 -311.107262) (xy 28.872211 -311.142937)
			(xy 28.824605 -311.171991) (xy 28.773276 -311.193803) (xy 28.719319 -311.207909) (xy 28.663882 -311.214009)
			(xy 28.608148 -311.211972) (xy 28.553305 -311.201842) (xy 28.500521 -311.183835) (xy 28.450921 -311.158334)
			(xy 28.405563 -311.125883) (xy 28.365414 -311.087174) (xy 28.331328 -311.043031) (xy 28.304032 -310.994396)
			(xy 28.284109 -310.942305) (xy 28.271983 -310.887868) (xy 28.267912 -310.832246) (xy 18.391371 -310.832246)
			(xy 18.396989 -310.844547) (xy 18.412344 -310.896841) (xy 18.4201 -310.950789) (xy 18.4201 -311.005291)
			(xy 18.412344 -311.059239) (xy 18.396989 -311.111533) (xy 18.374348 -311.16111) (xy 18.344882 -311.20696)
			(xy 18.30919 -311.24815) (xy 18.268 -311.283842) (xy 18.22215 -311.313308) (xy 18.172573 -311.335949)
			(xy 18.120279 -311.351304) (xy 18.066331 -311.35906) (xy 18.03908 -311.35955) (xy 18.008479 -311.358964)
			(xy 17.948058 -311.349232) (xy 17.889967 -311.329973) (xy 17.86255 -311.31637) (xy 17.850612 -311.31002)
			(xy 17.824196 -311.311036) (xy 17.738344 -311.362852) (xy 17.731093 -311.367675) (xy 17.720118 -311.38118)
			(xy 17.714308 -311.397584) (xy 17.71396 -311.406286) (xy 17.71396 -311.655714) (xy 17.714355 -311.664367)
			(xy 17.720209 -311.680657) (xy 17.731145 -311.694075) (xy 17.738344 -311.698894) (xy 17.823688 -311.751218)
			(xy 17.84985 -311.752234) (xy 17.861788 -311.746138) (xy 17.888829 -311.732947) (xy 17.946028 -311.714294)
			(xy 18.005443 -311.704829) (xy 18.035524 -311.704228) (xy 18.062775 -311.704714) (xy 18.116723 -311.712471)
			(xy 18.169018 -311.727827) (xy 18.218595 -311.750468) (xy 18.264446 -311.779935) (xy 18.305636 -311.815627)
			(xy 18.312111 -311.8231) (xy 32.447482 -311.8231) (xy 32.451553 -311.767478) (xy 32.463679 -311.713041)
			(xy 32.483602 -311.66095) (xy 32.510898 -311.612315) (xy 32.544984 -311.568172) (xy 32.585133 -311.529463)
			(xy 32.630491 -311.497012) (xy 32.680091 -311.471511) (xy 32.732875 -311.453504) (xy 32.787718 -311.443374)
			(xy 32.843452 -311.441337) (xy 32.898889 -311.447437) (xy 32.952846 -311.461543) (xy 33.004175 -311.483355)
			(xy 33.051781 -311.512409) (xy 33.094649 -311.548084) (xy 33.131866 -311.589621) (xy 33.162639 -311.636134)
			(xy 33.186311 -311.686631) (xy 33.202379 -311.740038) (xy 33.210499 -311.795214) (xy 33.211008 -311.8231)
			(xy 33.210499 -311.850986) (xy 33.202379 -311.906162) (xy 33.186311 -311.959569) (xy 33.162639 -312.010066)
			(xy 33.131866 -312.056579) (xy 33.094649 -312.098116) (xy 33.051781 -312.133791) (xy 33.004175 -312.162845)
			(xy 32.952846 -312.184657) (xy 32.898889 -312.198763) (xy 32.843452 -312.204863) (xy 32.787718 -312.202826)
			(xy 32.732875 -312.192696) (xy 32.680091 -312.174689) (xy 32.630491 -312.149188) (xy 32.585133 -312.116737)
			(xy 32.544984 -312.078028) (xy 32.510898 -312.033885) (xy 32.483602 -311.98525) (xy 32.463679 -311.933159)
			(xy 32.451553 -311.878722) (xy 32.447482 -311.8231) (xy 18.312111 -311.8231) (xy 18.341327 -311.856818)
			(xy 18.370794 -311.902668) (xy 18.393435 -311.952246) (xy 18.40879 -312.004541) (xy 18.416546 -312.058489)
			(xy 18.416546 -312.112991) (xy 18.40879 -312.166939) (xy 18.393435 -312.219234) (xy 18.370794 -312.268812)
			(xy 18.341327 -312.314662) (xy 18.305636 -312.355853) (xy 18.264446 -312.391545) (xy 18.218595 -312.421012)
			(xy 18.169018 -312.443653) (xy 18.116723 -312.459009) (xy 18.062775 -312.466766) (xy 18.035524 -312.467244)
			(xy 18.005439 -312.466684) (xy 17.946014 -312.457237) (xy 17.888817 -312.438559) (xy 17.861788 -312.425334)
			(xy 17.84985 -312.419238) (xy 17.823688 -312.420254) (xy 17.738344 -312.472578) (xy 17.731129 -312.477375)
			(xy 17.720191 -312.490797) (xy 17.714363 -312.507102) (xy 17.71396 -312.515758) (xy 17.71396 -312.523378)
			(xy 31.731964 -312.523378) (xy 31.736035 -312.467756) (xy 31.748161 -312.413319) (xy 31.768084 -312.361228)
			(xy 31.79538 -312.312593) (xy 31.829466 -312.26845) (xy 31.869615 -312.229741) (xy 31.914973 -312.19729)
			(xy 31.964573 -312.171789) (xy 32.017357 -312.153782) (xy 32.0722 -312.143652) (xy 32.127934 -312.141615)
			(xy 32.183371 -312.147715) (xy 32.237328 -312.161821) (xy 32.288657 -312.183633) (xy 32.336263 -312.212687)
			(xy 32.379131 -312.248362) (xy 32.396823 -312.268108) (xy 34.021774 -312.268108) (xy 34.025845 -312.212486)
			(xy 34.037971 -312.158049) (xy 34.057894 -312.105958) (xy 34.08519 -312.057323) (xy 34.119276 -312.01318)
			(xy 34.159425 -311.974471) (xy 34.204783 -311.94202) (xy 34.254383 -311.916519) (xy 34.307167 -311.898512)
			(xy 34.36201 -311.888382) (xy 34.417744 -311.886345) (xy 34.473181 -311.892445) (xy 34.527138 -311.906551)
			(xy 34.578467 -311.928363) (xy 34.626073 -311.957417) (xy 34.668941 -311.993092) (xy 34.706158 -312.034629)
			(xy 34.716108 -312.049668) (xy 35.593794 -312.049668) (xy 35.597754 -312.000614) (xy 35.609531 -311.95283)
			(xy 35.628822 -311.907554) (xy 35.655125 -311.865958) (xy 35.68776 -311.829121) (xy 35.725881 -311.797996)
			(xy 35.768502 -311.773389) (xy 35.814518 -311.755937) (xy 35.862737 -311.746093) (xy 35.911912 -311.744112)
			(xy 35.960767 -311.750044) (xy 36.008038 -311.763736) (xy 36.0525 -311.784834) (xy 36.093003 -311.81279)
			(xy 36.128496 -311.846882) (xy 36.158061 -311.886226) (xy 36.180932 -311.929803) (xy 36.196516 -311.976484)
			(xy 36.204411 -312.025061) (xy 36.204906 -312.049668) (xy 36.204411 -312.074275) (xy 36.204191 -312.07563)
			(xy 36.523164 -312.07563) (xy 36.523164 -312.024214) (xy 36.531207 -311.973432) (xy 36.547095 -311.924533)
			(xy 36.570438 -311.878721) (xy 36.600659 -311.837125) (xy 36.637015 -311.800769) (xy 36.678611 -311.770548)
			(xy 36.724423 -311.747205) (xy 36.773322 -311.731317) (xy 36.824104 -311.723274) (xy 36.87552 -311.723274)
			(xy 36.926302 -311.731317) (xy 36.975201 -311.747205) (xy 37.021013 -311.770548) (xy 37.062609 -311.800769)
			(xy 37.098965 -311.837125) (xy 37.129186 -311.878721) (xy 37.152529 -311.924533) (xy 37.168417 -311.973432)
			(xy 37.17646 -312.024214) (xy 37.176964 -312.049922) (xy 37.17646 -312.07563) (xy 37.473124 -312.07563)
			(xy 37.473124 -312.024214) (xy 37.481167 -311.973432) (xy 37.497055 -311.924533) (xy 37.520398 -311.878721)
			(xy 37.550619 -311.837125) (xy 37.586975 -311.800769) (xy 37.628571 -311.770548) (xy 37.674383 -311.747205)
			(xy 37.723282 -311.731317) (xy 37.774064 -311.723274) (xy 37.82548 -311.723274) (xy 37.876262 -311.731317)
			(xy 37.925161 -311.747205) (xy 37.970973 -311.770548) (xy 38.012569 -311.800769) (xy 38.048925 -311.837125)
			(xy 38.079146 -311.878721) (xy 38.102489 -311.924533) (xy 38.118377 -311.973432) (xy 38.12642 -312.024214)
			(xy 38.126924 -312.049922) (xy 38.444182 -312.049922) (xy 38.448142 -312.000868) (xy 38.459919 -311.953084)
			(xy 38.47921 -311.907808) (xy 38.505513 -311.866212) (xy 38.538148 -311.829375) (xy 38.576269 -311.79825)
			(xy 38.61889 -311.773643) (xy 38.664906 -311.756191) (xy 38.713125 -311.746347) (xy 38.7623 -311.744366)
			(xy 38.811155 -311.750298) (xy 38.858426 -311.76399) (xy 38.902888 -311.785088) (xy 38.943391 -311.813044)
			(xy 38.978884 -311.847136) (xy 39.008449 -311.88648) (xy 39.03132 -311.930057) (xy 39.046904 -311.976738)
			(xy 39.054799 -312.025315) (xy 39.055294 -312.049922) (xy 39.054799 -312.074529) (xy 39.05462 -312.07563)
			(xy 39.373298 -312.07563) (xy 39.373298 -312.024214) (xy 39.381341 -311.973432) (xy 39.397229 -311.924533)
			(xy 39.420572 -311.878721) (xy 39.450793 -311.837125) (xy 39.487149 -311.800769) (xy 39.528745 -311.770548)
			(xy 39.574557 -311.747205) (xy 39.623456 -311.731317) (xy 39.674238 -311.723274) (xy 39.725654 -311.723274)
			(xy 39.776436 -311.731317) (xy 39.825335 -311.747205) (xy 39.871147 -311.770548) (xy 39.912743 -311.800769)
			(xy 39.949099 -311.837125) (xy 39.97932 -311.878721) (xy 40.002663 -311.924533) (xy 40.018551 -311.973432)
			(xy 40.026594 -312.024214) (xy 40.027098 -312.049922) (xy 40.344102 -312.049922) (xy 40.348062 -312.000868)
			(xy 40.359839 -311.953084) (xy 40.37913 -311.907808) (xy 40.405433 -311.866212) (xy 40.438068 -311.829375)
			(xy 40.476189 -311.79825) (xy 40.51881 -311.773643) (xy 40.564826 -311.756191) (xy 40.613045 -311.746347)
			(xy 40.66222 -311.744366) (xy 40.711075 -311.750298) (xy 40.758346 -311.76399) (xy 40.802808 -311.785088)
			(xy 40.843311 -311.813044) (xy 40.878804 -311.847136) (xy 40.908369 -311.88648) (xy 40.93124 -311.930057)
			(xy 40.946824 -311.976738) (xy 40.954719 -312.025315) (xy 40.955214 -312.049922) (xy 40.954719 -312.074529)
			(xy 40.95454 -312.07563) (xy 41.273218 -312.07563) (xy 41.273218 -312.024214) (xy 41.281261 -311.973432)
			(xy 41.297149 -311.924533) (xy 41.320492 -311.878721) (xy 41.350713 -311.837125) (xy 41.387069 -311.800769)
			(xy 41.428665 -311.770548) (xy 41.474477 -311.747205) (xy 41.523376 -311.731317) (xy 41.574158 -311.723274)
			(xy 41.625574 -311.723274) (xy 41.676356 -311.731317) (xy 41.725255 -311.747205) (xy 41.771067 -311.770548)
			(xy 41.812663 -311.800769) (xy 41.849019 -311.837125) (xy 41.87924 -311.878721) (xy 41.902583 -311.924533)
			(xy 41.918471 -311.973432) (xy 41.926514 -312.024214) (xy 41.927018 -312.049922) (xy 42.244022 -312.049922)
			(xy 42.247982 -312.000868) (xy 42.259759 -311.953084) (xy 42.27905 -311.907808) (xy 42.305353 -311.866212)
			(xy 42.337988 -311.829375) (xy 42.376109 -311.79825) (xy 42.41873 -311.773643) (xy 42.464746 -311.756191)
			(xy 42.512965 -311.746347) (xy 42.56214 -311.744366) (xy 42.610995 -311.750298) (xy 42.658266 -311.76399)
			(xy 42.702728 -311.785088) (xy 42.743231 -311.813044) (xy 42.778724 -311.847136) (xy 42.808289 -311.88648)
			(xy 42.83116 -311.930057) (xy 42.846744 -311.976738) (xy 42.854639 -312.025315) (xy 42.855134 -312.049922)
			(xy 42.854639 -312.074529) (xy 42.85446 -312.07563) (xy 43.173138 -312.07563) (xy 43.173138 -312.024214)
			(xy 43.181181 -311.973432) (xy 43.197069 -311.924533) (xy 43.220412 -311.878721) (xy 43.250633 -311.837125)
			(xy 43.286989 -311.800769) (xy 43.328585 -311.770548) (xy 43.374397 -311.747205) (xy 43.423296 -311.731317)
			(xy 43.474078 -311.723274) (xy 43.525494 -311.723274) (xy 43.576276 -311.731317) (xy 43.625175 -311.747205)
			(xy 43.670987 -311.770548) (xy 43.712583 -311.800769) (xy 43.748939 -311.837125) (xy 43.77916 -311.878721)
			(xy 43.802503 -311.924533) (xy 43.818391 -311.973432) (xy 43.826434 -312.024214) (xy 43.826938 -312.049922)
			(xy 44.143942 -312.049922) (xy 44.147902 -312.000868) (xy 44.159679 -311.953084) (xy 44.17897 -311.907808)
			(xy 44.205273 -311.866212) (xy 44.237908 -311.829375) (xy 44.276029 -311.79825) (xy 44.31865 -311.773643)
			(xy 44.364666 -311.756191) (xy 44.412885 -311.746347) (xy 44.46206 -311.744366) (xy 44.510915 -311.750298)
			(xy 44.558186 -311.76399) (xy 44.602648 -311.785088) (xy 44.643151 -311.813044) (xy 44.678644 -311.847136)
			(xy 44.708209 -311.88648) (xy 44.73108 -311.930057) (xy 44.746664 -311.976738) (xy 44.754559 -312.025315)
			(xy 44.755054 -312.049922) (xy 44.754559 -312.074529) (xy 44.75438 -312.07563) (xy 45.073312 -312.07563)
			(xy 45.073312 -312.024214) (xy 45.081355 -311.973432) (xy 45.097243 -311.924533) (xy 45.120586 -311.878721)
			(xy 45.150807 -311.837125) (xy 45.187163 -311.800769) (xy 45.228759 -311.770548) (xy 45.274571 -311.747205)
			(xy 45.32347 -311.731317) (xy 45.374252 -311.723274) (xy 45.425668 -311.723274) (xy 45.47645 -311.731317)
			(xy 45.525349 -311.747205) (xy 45.571161 -311.770548) (xy 45.612757 -311.800769) (xy 45.649113 -311.837125)
			(xy 45.679334 -311.878721) (xy 45.702677 -311.924533) (xy 45.718565 -311.973432) (xy 45.726608 -312.024214)
			(xy 45.727112 -312.049922) (xy 46.044116 -312.049922) (xy 46.048076 -312.000868) (xy 46.059853 -311.953084)
			(xy 46.079144 -311.907808) (xy 46.105447 -311.866212) (xy 46.138082 -311.829375) (xy 46.176203 -311.79825)
			(xy 46.218824 -311.773643) (xy 46.26484 -311.756191) (xy 46.313059 -311.746347) (xy 46.362234 -311.744366)
			(xy 46.411089 -311.750298) (xy 46.45836 -311.76399) (xy 46.502822 -311.785088) (xy 46.543325 -311.813044)
			(xy 46.578818 -311.847136) (xy 46.608383 -311.88648) (xy 46.631254 -311.930057) (xy 46.646838 -311.976738)
			(xy 46.654733 -312.025315) (xy 46.655228 -312.049922) (xy 46.654733 -312.074529) (xy 46.654554 -312.07563)
			(xy 46.973232 -312.07563) (xy 46.973232 -312.024214) (xy 46.981275 -311.973432) (xy 46.997163 -311.924533)
			(xy 47.020506 -311.878721) (xy 47.050727 -311.837125) (xy 47.087083 -311.800769) (xy 47.128679 -311.770548)
			(xy 47.174491 -311.747205) (xy 47.22339 -311.731317) (xy 47.274172 -311.723274) (xy 47.325588 -311.723274)
			(xy 47.37637 -311.731317) (xy 47.425269 -311.747205) (xy 47.471081 -311.770548) (xy 47.512677 -311.800769)
			(xy 47.549033 -311.837125) (xy 47.579254 -311.878721) (xy 47.602597 -311.924533) (xy 47.618485 -311.973432)
			(xy 47.626528 -312.024214) (xy 47.627032 -312.049922) (xy 47.944036 -312.049922) (xy 47.947996 -312.000868)
			(xy 47.959773 -311.953084) (xy 47.979064 -311.907808) (xy 48.005367 -311.866212) (xy 48.038002 -311.829375)
			(xy 48.076123 -311.79825) (xy 48.118744 -311.773643) (xy 48.16476 -311.756191) (xy 48.212979 -311.746347)
			(xy 48.262154 -311.744366) (xy 48.311009 -311.750298) (xy 48.35828 -311.76399) (xy 48.402742 -311.785088)
			(xy 48.443245 -311.813044) (xy 48.478738 -311.847136) (xy 48.508303 -311.88648) (xy 48.531174 -311.930057)
			(xy 48.546758 -311.976738) (xy 48.554653 -312.025315) (xy 48.555148 -312.049922) (xy 48.554653 -312.074529)
			(xy 48.554474 -312.07563) (xy 48.873152 -312.07563) (xy 48.873152 -312.024214) (xy 48.881195 -311.973432)
			(xy 48.897083 -311.924533) (xy 48.920426 -311.878721) (xy 48.950647 -311.837125) (xy 48.987003 -311.800769)
			(xy 49.028599 -311.770548) (xy 49.074411 -311.747205) (xy 49.12331 -311.731317) (xy 49.174092 -311.723274)
			(xy 49.225508 -311.723274) (xy 49.27629 -311.731317) (xy 49.325189 -311.747205) (xy 49.371001 -311.770548)
			(xy 49.412597 -311.800769) (xy 49.448953 -311.837125) (xy 49.479174 -311.878721) (xy 49.502517 -311.924533)
			(xy 49.518405 -311.973432) (xy 49.526448 -312.024214) (xy 49.526952 -312.049922) (xy 49.843956 -312.049922)
			(xy 49.847916 -312.000868) (xy 49.859693 -311.953084) (xy 49.878984 -311.907808) (xy 49.905287 -311.866212)
			(xy 49.937922 -311.829375) (xy 49.976043 -311.79825) (xy 50.018664 -311.773643) (xy 50.06468 -311.756191)
			(xy 50.112899 -311.746347) (xy 50.162074 -311.744366) (xy 50.210929 -311.750298) (xy 50.2582 -311.76399)
			(xy 50.302662 -311.785088) (xy 50.343165 -311.813044) (xy 50.378658 -311.847136) (xy 50.408223 -311.88648)
			(xy 50.431094 -311.930057) (xy 50.446678 -311.976738) (xy 50.454573 -312.025315) (xy 50.455068 -312.049922)
			(xy 50.454573 -312.074529) (xy 50.454394 -312.07563) (xy 50.773326 -312.07563) (xy 50.773326 -312.024214)
			(xy 50.781369 -311.973432) (xy 50.797257 -311.924533) (xy 50.8206 -311.878721) (xy 50.850821 -311.837125)
			(xy 50.887177 -311.800769) (xy 50.928773 -311.770548) (xy 50.974585 -311.747205) (xy 51.023484 -311.731317)
			(xy 51.074266 -311.723274) (xy 51.125682 -311.723274) (xy 51.176464 -311.731317) (xy 51.225363 -311.747205)
			(xy 51.271175 -311.770548) (xy 51.312771 -311.800769) (xy 51.349127 -311.837125) (xy 51.379348 -311.878721)
			(xy 51.402691 -311.924533) (xy 51.418579 -311.973432) (xy 51.426622 -312.024214) (xy 51.427126 -312.049922)
			(xy 51.74413 -312.049922) (xy 51.74809 -312.000868) (xy 51.759867 -311.953084) (xy 51.779158 -311.907808)
			(xy 51.805461 -311.866212) (xy 51.838096 -311.829375) (xy 51.876217 -311.79825) (xy 51.918838 -311.773643)
			(xy 51.964854 -311.756191) (xy 52.013073 -311.746347) (xy 52.062248 -311.744366) (xy 52.111103 -311.750298)
			(xy 52.158374 -311.76399) (xy 52.202836 -311.785088) (xy 52.243339 -311.813044) (xy 52.278832 -311.847136)
			(xy 52.308397 -311.88648) (xy 52.331268 -311.930057) (xy 52.346852 -311.976738) (xy 52.354747 -312.025315)
			(xy 52.355242 -312.049922) (xy 52.354747 -312.074529) (xy 52.354568 -312.07563) (xy 52.673246 -312.07563)
			(xy 52.673246 -312.024214) (xy 52.681289 -311.973432) (xy 52.697177 -311.924533) (xy 52.72052 -311.878721)
			(xy 52.750741 -311.837125) (xy 52.787097 -311.800769) (xy 52.828693 -311.770548) (xy 52.874505 -311.747205)
			(xy 52.923404 -311.731317) (xy 52.974186 -311.723274) (xy 53.025602 -311.723274) (xy 53.076384 -311.731317)
			(xy 53.125283 -311.747205) (xy 53.171095 -311.770548) (xy 53.212691 -311.800769) (xy 53.249047 -311.837125)
			(xy 53.279268 -311.878721) (xy 53.302611 -311.924533) (xy 53.318499 -311.973432) (xy 53.326542 -312.024214)
			(xy 53.327046 -312.049922) (xy 53.64405 -312.049922) (xy 53.64801 -312.000868) (xy 53.659787 -311.953084)
			(xy 53.679078 -311.907808) (xy 53.705381 -311.866212) (xy 53.738016 -311.829375) (xy 53.776137 -311.79825)
			(xy 53.818758 -311.773643) (xy 53.864774 -311.756191) (xy 53.912993 -311.746347) (xy 53.962168 -311.744366)
			(xy 54.011023 -311.750298) (xy 54.058294 -311.76399) (xy 54.102756 -311.785088) (xy 54.143259 -311.813044)
			(xy 54.178752 -311.847136) (xy 54.208317 -311.88648) (xy 54.231188 -311.930057) (xy 54.246772 -311.976738)
			(xy 54.254667 -312.025315) (xy 54.255162 -312.049922) (xy 54.254667 -312.074529) (xy 54.254488 -312.07563)
			(xy 54.573166 -312.07563) (xy 54.573166 -312.024214) (xy 54.581209 -311.973432) (xy 54.597097 -311.924533)
			(xy 54.62044 -311.878721) (xy 54.650661 -311.837125) (xy 54.687017 -311.800769) (xy 54.728613 -311.770548)
			(xy 54.774425 -311.747205) (xy 54.823324 -311.731317) (xy 54.874106 -311.723274) (xy 54.925522 -311.723274)
			(xy 54.976304 -311.731317) (xy 55.025203 -311.747205) (xy 55.071015 -311.770548) (xy 55.112611 -311.800769)
			(xy 55.148967 -311.837125) (xy 55.179188 -311.878721) (xy 55.202531 -311.924533) (xy 55.218419 -311.973432)
			(xy 55.226462 -312.024214) (xy 55.226966 -312.049922) (xy 55.54397 -312.049922) (xy 55.54793 -312.000868)
			(xy 55.559707 -311.953084) (xy 55.578998 -311.907808) (xy 55.605301 -311.866212) (xy 55.637936 -311.829375)
			(xy 55.676057 -311.79825) (xy 55.718678 -311.773643) (xy 55.764694 -311.756191) (xy 55.812913 -311.746347)
			(xy 55.862088 -311.744366) (xy 55.910943 -311.750298) (xy 55.958214 -311.76399) (xy 56.002676 -311.785088)
			(xy 56.043179 -311.813044) (xy 56.078672 -311.847136) (xy 56.108237 -311.88648) (xy 56.131108 -311.930057)
			(xy 56.146692 -311.976738) (xy 56.154587 -312.025315) (xy 56.155082 -312.049922) (xy 56.154587 -312.074529)
			(xy 56.154408 -312.07563) (xy 56.47334 -312.07563) (xy 56.47334 -312.024214) (xy 56.481383 -311.973432)
			(xy 56.497271 -311.924533) (xy 56.520614 -311.878721) (xy 56.550835 -311.837125) (xy 56.587191 -311.800769)
			(xy 56.628787 -311.770548) (xy 56.674599 -311.747205) (xy 56.723498 -311.731317) (xy 56.77428 -311.723274)
			(xy 56.825696 -311.723274) (xy 56.876478 -311.731317) (xy 56.925377 -311.747205) (xy 56.971189 -311.770548)
			(xy 57.012785 -311.800769) (xy 57.049141 -311.837125) (xy 57.079362 -311.878721) (xy 57.102705 -311.924533)
			(xy 57.118593 -311.973432) (xy 57.126636 -312.024214) (xy 57.12714 -312.049922) (xy 57.444144 -312.049922)
			(xy 57.448104 -312.000868) (xy 57.459881 -311.953084) (xy 57.479172 -311.907808) (xy 57.505475 -311.866212)
			(xy 57.53811 -311.829375) (xy 57.576231 -311.79825) (xy 57.618852 -311.773643) (xy 57.664868 -311.756191)
			(xy 57.713087 -311.746347) (xy 57.762262 -311.744366) (xy 57.811117 -311.750298) (xy 57.858388 -311.76399)
			(xy 57.90285 -311.785088) (xy 57.943353 -311.813044) (xy 57.978846 -311.847136) (xy 58.008411 -311.88648)
			(xy 58.031282 -311.930057) (xy 58.046866 -311.976738) (xy 58.054761 -312.025315) (xy 58.055256 -312.049922)
			(xy 58.054761 -312.074529) (xy 58.054582 -312.07563) (xy 58.37326 -312.07563) (xy 58.37326 -312.024214)
			(xy 58.381303 -311.973432) (xy 58.397191 -311.924533) (xy 58.420534 -311.878721) (xy 58.450755 -311.837125)
			(xy 58.487111 -311.800769) (xy 58.528707 -311.770548) (xy 58.574519 -311.747205) (xy 58.623418 -311.731317)
			(xy 58.6742 -311.723274) (xy 58.725616 -311.723274) (xy 58.776398 -311.731317) (xy 58.825297 -311.747205)
			(xy 58.871109 -311.770548) (xy 58.912705 -311.800769) (xy 58.949061 -311.837125) (xy 58.979282 -311.878721)
			(xy 59.002625 -311.924533) (xy 59.018513 -311.973432) (xy 59.026556 -312.024214) (xy 59.02706 -312.049922)
			(xy 59.344064 -312.049922) (xy 59.348024 -312.000868) (xy 59.359801 -311.953084) (xy 59.379092 -311.907808)
			(xy 59.405395 -311.866212) (xy 59.43803 -311.829375) (xy 59.476151 -311.79825) (xy 59.518772 -311.773643)
			(xy 59.564788 -311.756191) (xy 59.613007 -311.746347) (xy 59.662182 -311.744366) (xy 59.711037 -311.750298)
			(xy 59.758308 -311.76399) (xy 59.80277 -311.785088) (xy 59.843273 -311.813044) (xy 59.878766 -311.847136)
			(xy 59.908331 -311.88648) (xy 59.931202 -311.930057) (xy 59.946786 -311.976738) (xy 59.954681 -312.025315)
			(xy 59.955176 -312.049922) (xy 59.954681 -312.074529) (xy 59.954502 -312.07563) (xy 60.27318 -312.07563)
			(xy 60.27318 -312.024214) (xy 60.281223 -311.973432) (xy 60.297111 -311.924533) (xy 60.320454 -311.878721)
			(xy 60.350675 -311.837125) (xy 60.387031 -311.800769) (xy 60.428627 -311.770548) (xy 60.474439 -311.747205)
			(xy 60.523338 -311.731317) (xy 60.57412 -311.723274) (xy 60.625536 -311.723274) (xy 60.676318 -311.731317)
			(xy 60.725217 -311.747205) (xy 60.771029 -311.770548) (xy 60.812625 -311.800769) (xy 60.848981 -311.837125)
			(xy 60.879202 -311.878721) (xy 60.902545 -311.924533) (xy 60.918433 -311.973432) (xy 60.926476 -312.024214)
			(xy 60.92698 -312.049922) (xy 61.243984 -312.049922) (xy 61.247944 -312.000868) (xy 61.259721 -311.953084)
			(xy 61.279012 -311.907808) (xy 61.305315 -311.866212) (xy 61.33795 -311.829375) (xy 61.376071 -311.79825)
			(xy 61.418692 -311.773643) (xy 61.464708 -311.756191) (xy 61.512927 -311.746347) (xy 61.562102 -311.744366)
			(xy 61.610957 -311.750298) (xy 61.658228 -311.76399) (xy 61.70269 -311.785088) (xy 61.743193 -311.813044)
			(xy 61.778686 -311.847136) (xy 61.808251 -311.88648) (xy 61.831122 -311.930057) (xy 61.846706 -311.976738)
			(xy 61.854601 -312.025315) (xy 61.855096 -312.049922) (xy 61.854601 -312.074529) (xy 61.854422 -312.07563)
			(xy 62.1731 -312.07563) (xy 62.1731 -312.024214) (xy 62.181143 -311.973432) (xy 62.197031 -311.924533)
			(xy 62.220374 -311.878721) (xy 62.250595 -311.837125) (xy 62.286951 -311.800769) (xy 62.328547 -311.770548)
			(xy 62.374359 -311.747205) (xy 62.423258 -311.731317) (xy 62.47404 -311.723274) (xy 62.525456 -311.723274)
			(xy 62.576238 -311.731317) (xy 62.625137 -311.747205) (xy 62.670949 -311.770548) (xy 62.712545 -311.800769)
			(xy 62.748901 -311.837125) (xy 62.779122 -311.878721) (xy 62.802465 -311.924533) (xy 62.818353 -311.973432)
			(xy 62.826396 -312.024214) (xy 62.8269 -312.049922) (xy 63.144158 -312.049922) (xy 63.148118 -312.000868)
			(xy 63.159895 -311.953084) (xy 63.179186 -311.907808) (xy 63.205489 -311.866212) (xy 63.238124 -311.829375)
			(xy 63.276245 -311.79825) (xy 63.318866 -311.773643) (xy 63.364882 -311.756191) (xy 63.413101 -311.746347)
			(xy 63.462276 -311.744366) (xy 63.511131 -311.750298) (xy 63.558402 -311.76399) (xy 63.602864 -311.785088)
			(xy 63.643367 -311.813044) (xy 63.67886 -311.847136) (xy 63.708425 -311.88648) (xy 63.731296 -311.930057)
			(xy 63.74688 -311.976738) (xy 63.754775 -312.025315) (xy 63.75527 -312.049922) (xy 63.754775 -312.074529)
			(xy 63.754596 -312.07563) (xy 64.073274 -312.07563) (xy 64.073274 -312.024214) (xy 64.081317 -311.973432)
			(xy 64.097205 -311.924533) (xy 64.120548 -311.878721) (xy 64.150769 -311.837125) (xy 64.187125 -311.800769)
			(xy 64.228721 -311.770548) (xy 64.274533 -311.747205) (xy 64.323432 -311.731317) (xy 64.374214 -311.723274)
			(xy 64.42563 -311.723274) (xy 64.476412 -311.731317) (xy 64.525311 -311.747205) (xy 64.571123 -311.770548)
			(xy 64.612719 -311.800769) (xy 64.649075 -311.837125) (xy 64.679296 -311.878721) (xy 64.702639 -311.924533)
			(xy 64.718527 -311.973432) (xy 64.72657 -312.024214) (xy 64.727074 -312.049922) (xy 65.044078 -312.049922)
			(xy 65.048038 -312.000868) (xy 65.059815 -311.953084) (xy 65.079106 -311.907808) (xy 65.105409 -311.866212)
			(xy 65.138044 -311.829375) (xy 65.176165 -311.79825) (xy 65.218786 -311.773643) (xy 65.264802 -311.756191)
			(xy 65.313021 -311.746347) (xy 65.362196 -311.744366) (xy 65.411051 -311.750298) (xy 65.458322 -311.76399)
			(xy 65.502784 -311.785088) (xy 65.543287 -311.813044) (xy 65.57878 -311.847136) (xy 65.608345 -311.88648)
			(xy 65.631216 -311.930057) (xy 65.6468 -311.976738) (xy 65.654695 -312.025315) (xy 65.65519 -312.049922)
			(xy 65.654695 -312.074529) (xy 65.654516 -312.07563) (xy 65.973194 -312.07563) (xy 65.973194 -312.024214)
			(xy 65.981237 -311.973432) (xy 65.997125 -311.924533) (xy 66.020468 -311.878721) (xy 66.050689 -311.837125)
			(xy 66.087045 -311.800769) (xy 66.128641 -311.770548) (xy 66.174453 -311.747205) (xy 66.223352 -311.731317)
			(xy 66.274134 -311.723274) (xy 66.32555 -311.723274) (xy 66.376332 -311.731317) (xy 66.425231 -311.747205)
			(xy 66.471043 -311.770548) (xy 66.512639 -311.800769) (xy 66.548995 -311.837125) (xy 66.579216 -311.878721)
			(xy 66.602559 -311.924533) (xy 66.618447 -311.973432) (xy 66.62649 -312.024214) (xy 66.626994 -312.049922)
			(xy 66.943998 -312.049922) (xy 66.947958 -312.000868) (xy 66.959735 -311.953084) (xy 66.979026 -311.907808)
			(xy 67.005329 -311.866212) (xy 67.037964 -311.829375) (xy 67.076085 -311.79825) (xy 67.118706 -311.773643)
			(xy 67.164722 -311.756191) (xy 67.212941 -311.746347) (xy 67.262116 -311.744366) (xy 67.310971 -311.750298)
			(xy 67.358242 -311.76399) (xy 67.402704 -311.785088) (xy 67.443207 -311.813044) (xy 67.4787 -311.847136)
			(xy 67.508265 -311.88648) (xy 67.531136 -311.930057) (xy 67.54672 -311.976738) (xy 67.554615 -312.025315)
			(xy 67.55511 -312.049922) (xy 67.554615 -312.074529) (xy 67.554436 -312.07563) (xy 67.873114 -312.07563)
			(xy 67.873114 -312.024214) (xy 67.881157 -311.973432) (xy 67.897045 -311.924533) (xy 67.920388 -311.878721)
			(xy 67.950609 -311.837125) (xy 67.986965 -311.800769) (xy 68.028561 -311.770548) (xy 68.074373 -311.747205)
			(xy 68.123272 -311.731317) (xy 68.174054 -311.723274) (xy 68.22547 -311.723274) (xy 68.276252 -311.731317)
			(xy 68.325151 -311.747205) (xy 68.370963 -311.770548) (xy 68.412559 -311.800769) (xy 68.448915 -311.837125)
			(xy 68.479136 -311.878721) (xy 68.502479 -311.924533) (xy 68.518367 -311.973432) (xy 68.52641 -312.024214)
			(xy 68.526914 -312.049922) (xy 68.844172 -312.049922) (xy 68.848132 -312.000868) (xy 68.859909 -311.953084)
			(xy 68.8792 -311.907808) (xy 68.905503 -311.866212) (xy 68.938138 -311.829375) (xy 68.976259 -311.79825)
			(xy 69.01888 -311.773643) (xy 69.064896 -311.756191) (xy 69.113115 -311.746347) (xy 69.16229 -311.744366)
			(xy 69.211145 -311.750298) (xy 69.258416 -311.76399) (xy 69.302878 -311.785088) (xy 69.343381 -311.813044)
			(xy 69.378874 -311.847136) (xy 69.408439 -311.88648) (xy 69.43131 -311.930057) (xy 69.446894 -311.976738)
			(xy 69.454789 -312.025315) (xy 69.455284 -312.049922) (xy 69.454789 -312.074529) (xy 69.45461 -312.07563)
			(xy 69.773288 -312.07563) (xy 69.773288 -312.024214) (xy 69.781331 -311.973432) (xy 69.797219 -311.924533)
			(xy 69.820562 -311.878721) (xy 69.850783 -311.837125) (xy 69.887139 -311.800769) (xy 69.928735 -311.770548)
			(xy 69.974547 -311.747205) (xy 70.023446 -311.731317) (xy 70.074228 -311.723274) (xy 70.125644 -311.723274)
			(xy 70.176426 -311.731317) (xy 70.225325 -311.747205) (xy 70.271137 -311.770548) (xy 70.312733 -311.800769)
			(xy 70.349089 -311.837125) (xy 70.37931 -311.878721) (xy 70.402653 -311.924533) (xy 70.418541 -311.973432)
			(xy 70.426584 -312.024214) (xy 70.427088 -312.049922) (xy 70.744092 -312.049922) (xy 70.748052 -312.000868)
			(xy 70.759829 -311.953084) (xy 70.77912 -311.907808) (xy 70.805423 -311.866212) (xy 70.838058 -311.829375)
			(xy 70.876179 -311.79825) (xy 70.9188 -311.773643) (xy 70.964816 -311.756191) (xy 71.013035 -311.746347)
			(xy 71.06221 -311.744366) (xy 71.111065 -311.750298) (xy 71.158336 -311.76399) (xy 71.202798 -311.785088)
			(xy 71.243301 -311.813044) (xy 71.278794 -311.847136) (xy 71.308359 -311.88648) (xy 71.33123 -311.930057)
			(xy 71.346814 -311.976738) (xy 71.354709 -312.025315) (xy 71.355204 -312.049922) (xy 71.354709 -312.074529)
			(xy 71.35453 -312.07563) (xy 71.673208 -312.07563) (xy 71.673208 -312.024214) (xy 71.681251 -311.973432)
			(xy 71.697139 -311.924533) (xy 71.720482 -311.878721) (xy 71.750703 -311.837125) (xy 71.787059 -311.800769)
			(xy 71.828655 -311.770548) (xy 71.874467 -311.747205) (xy 71.923366 -311.731317) (xy 71.974148 -311.723274)
			(xy 72.025564 -311.723274) (xy 72.076346 -311.731317) (xy 72.125245 -311.747205) (xy 72.171057 -311.770548)
			(xy 72.212653 -311.800769) (xy 72.249009 -311.837125) (xy 72.27923 -311.878721) (xy 72.302573 -311.924533)
			(xy 72.318461 -311.973432) (xy 72.326504 -312.024214) (xy 72.327008 -312.049922) (xy 72.644012 -312.049922)
			(xy 72.647972 -312.000868) (xy 72.659749 -311.953084) (xy 72.67904 -311.907808) (xy 72.705343 -311.866212)
			(xy 72.737978 -311.829375) (xy 72.776099 -311.79825) (xy 72.81872 -311.773643) (xy 72.864736 -311.756191)
			(xy 72.912955 -311.746347) (xy 72.96213 -311.744366) (xy 73.010985 -311.750298) (xy 73.058256 -311.76399)
			(xy 73.102718 -311.785088) (xy 73.143221 -311.813044) (xy 73.178714 -311.847136) (xy 73.208279 -311.88648)
			(xy 73.23115 -311.930057) (xy 73.246734 -311.976738) (xy 73.254629 -312.025315) (xy 73.255124 -312.049922)
			(xy 73.254629 -312.074529) (xy 73.25445 -312.07563) (xy 73.573128 -312.07563) (xy 73.573128 -312.024214)
			(xy 73.581171 -311.973432) (xy 73.597059 -311.924533) (xy 73.620402 -311.878721) (xy 73.650623 -311.837125)
			(xy 73.686979 -311.800769) (xy 73.728575 -311.770548) (xy 73.774387 -311.747205) (xy 73.823286 -311.731317)
			(xy 73.874068 -311.723274) (xy 73.925484 -311.723274) (xy 73.976266 -311.731317) (xy 74.025165 -311.747205)
			(xy 74.070977 -311.770548) (xy 74.112573 -311.800769) (xy 74.148929 -311.837125) (xy 74.17915 -311.878721)
			(xy 74.202493 -311.924533) (xy 74.218381 -311.973432) (xy 74.226424 -312.024214) (xy 74.226928 -312.049922)
			(xy 74.544186 -312.049922) (xy 74.548146 -312.000868) (xy 74.559923 -311.953084) (xy 74.579214 -311.907808)
			(xy 74.605517 -311.866212) (xy 74.638152 -311.829375) (xy 74.676273 -311.79825) (xy 74.718894 -311.773643)
			(xy 74.76491 -311.756191) (xy 74.813129 -311.746347) (xy 74.862304 -311.744366) (xy 74.911159 -311.750298)
			(xy 74.95843 -311.76399) (xy 75.002892 -311.785088) (xy 75.043395 -311.813044) (xy 75.078888 -311.847136)
			(xy 75.108453 -311.88648) (xy 75.131324 -311.930057) (xy 75.146908 -311.976738) (xy 75.154803 -312.025315)
			(xy 75.155298 -312.049922) (xy 75.154803 -312.074529) (xy 75.154624 -312.07563) (xy 75.473302 -312.07563)
			(xy 75.473302 -312.024214) (xy 75.481345 -311.973432) (xy 75.497233 -311.924533) (xy 75.520576 -311.878721)
			(xy 75.550797 -311.837125) (xy 75.587153 -311.800769) (xy 75.628749 -311.770548) (xy 75.674561 -311.747205)
			(xy 75.72346 -311.731317) (xy 75.774242 -311.723274) (xy 75.825658 -311.723274) (xy 75.87644 -311.731317)
			(xy 75.925339 -311.747205) (xy 75.971151 -311.770548) (xy 76.012747 -311.800769) (xy 76.049103 -311.837125)
			(xy 76.079324 -311.878721) (xy 76.102667 -311.924533) (xy 76.118555 -311.973432) (xy 76.126598 -312.024214)
			(xy 76.127102 -312.049922) (xy 76.444106 -312.049922) (xy 76.448066 -312.000868) (xy 76.459843 -311.953084)
			(xy 76.479134 -311.907808) (xy 76.505437 -311.866212) (xy 76.538072 -311.829375) (xy 76.576193 -311.79825)
			(xy 76.618814 -311.773643) (xy 76.66483 -311.756191) (xy 76.713049 -311.746347) (xy 76.762224 -311.744366)
			(xy 76.811079 -311.750298) (xy 76.85835 -311.76399) (xy 76.902812 -311.785088) (xy 76.943315 -311.813044)
			(xy 76.978808 -311.847136) (xy 77.008373 -311.88648) (xy 77.031244 -311.930057) (xy 77.046828 -311.976738)
			(xy 77.054723 -312.025315) (xy 77.055218 -312.049922) (xy 77.054723 -312.074529) (xy 77.054544 -312.07563)
			(xy 77.373222 -312.07563) (xy 77.373222 -312.024214) (xy 77.381265 -311.973432) (xy 77.397153 -311.924533)
			(xy 77.420496 -311.878721) (xy 77.450717 -311.837125) (xy 77.487073 -311.800769) (xy 77.528669 -311.770548)
			(xy 77.574481 -311.747205) (xy 77.62338 -311.731317) (xy 77.674162 -311.723274) (xy 77.725578 -311.723274)
			(xy 77.77636 -311.731317) (xy 77.825259 -311.747205) (xy 77.871071 -311.770548) (xy 77.912667 -311.800769)
			(xy 77.949023 -311.837125) (xy 77.979244 -311.878721) (xy 78.002587 -311.924533) (xy 78.018475 -311.973432)
			(xy 78.026518 -312.024214) (xy 78.027022 -312.049922) (xy 78.026518 -312.07563) (xy 78.018475 -312.126412)
			(xy 78.002587 -312.175311) (xy 77.979244 -312.221123) (xy 77.949023 -312.262719) (xy 77.912667 -312.299075)
			(xy 77.871071 -312.329296) (xy 77.825259 -312.352639) (xy 77.77636 -312.368527) (xy 77.725578 -312.37657)
			(xy 77.674162 -312.37657) (xy 77.62338 -312.368527) (xy 77.574481 -312.352639) (xy 77.528669 -312.329296)
			(xy 77.487073 -312.299075) (xy 77.450717 -312.262719) (xy 77.420496 -312.221123) (xy 77.397153 -312.175311)
			(xy 77.381265 -312.126412) (xy 77.373222 -312.07563) (xy 77.054544 -312.07563) (xy 77.046828 -312.123106)
			(xy 77.031244 -312.169787) (xy 77.008373 -312.213364) (xy 76.978808 -312.252708) (xy 76.943315 -312.2868)
			(xy 76.902812 -312.314756) (xy 76.85835 -312.335854) (xy 76.811079 -312.349546) (xy 76.762224 -312.355478)
			(xy 76.713049 -312.353497) (xy 76.66483 -312.343653) (xy 76.618814 -312.326201) (xy 76.576193 -312.301594)
			(xy 76.538072 -312.270469) (xy 76.505437 -312.233632) (xy 76.479134 -312.192036) (xy 76.459843 -312.14676)
			(xy 76.448066 -312.098976) (xy 76.444106 -312.049922) (xy 76.127102 -312.049922) (xy 76.126598 -312.07563)
			(xy 76.118555 -312.126412) (xy 76.102667 -312.175311) (xy 76.079324 -312.221123) (xy 76.049103 -312.262719)
			(xy 76.012747 -312.299075) (xy 75.971151 -312.329296) (xy 75.925339 -312.352639) (xy 75.87644 -312.368527)
			(xy 75.825658 -312.37657) (xy 75.774242 -312.37657) (xy 75.72346 -312.368527) (xy 75.674561 -312.352639)
			(xy 75.628749 -312.329296) (xy 75.587153 -312.299075) (xy 75.550797 -312.262719) (xy 75.520576 -312.221123)
			(xy 75.497233 -312.175311) (xy 75.481345 -312.126412) (xy 75.473302 -312.07563) (xy 75.154624 -312.07563)
			(xy 75.146908 -312.123106) (xy 75.131324 -312.169787) (xy 75.108453 -312.213364) (xy 75.078888 -312.252708)
			(xy 75.043395 -312.2868) (xy 75.002892 -312.314756) (xy 74.95843 -312.335854) (xy 74.911159 -312.349546)
			(xy 74.862304 -312.355478) (xy 74.813129 -312.353497) (xy 74.76491 -312.343653) (xy 74.718894 -312.326201)
			(xy 74.676273 -312.301594) (xy 74.638152 -312.270469) (xy 74.605517 -312.233632) (xy 74.579214 -312.192036)
			(xy 74.559923 -312.14676) (xy 74.548146 -312.098976) (xy 74.544186 -312.049922) (xy 74.226928 -312.049922)
			(xy 74.226424 -312.07563) (xy 74.218381 -312.126412) (xy 74.202493 -312.175311) (xy 74.17915 -312.221123)
			(xy 74.148929 -312.262719) (xy 74.112573 -312.299075) (xy 74.070977 -312.329296) (xy 74.025165 -312.352639)
			(xy 73.976266 -312.368527) (xy 73.925484 -312.37657) (xy 73.874068 -312.37657) (xy 73.823286 -312.368527)
			(xy 73.774387 -312.352639) (xy 73.728575 -312.329296) (xy 73.686979 -312.299075) (xy 73.650623 -312.262719)
			(xy 73.620402 -312.221123) (xy 73.597059 -312.175311) (xy 73.581171 -312.126412) (xy 73.573128 -312.07563)
			(xy 73.25445 -312.07563) (xy 73.246734 -312.123106) (xy 73.23115 -312.169787) (xy 73.208279 -312.213364)
			(xy 73.178714 -312.252708) (xy 73.143221 -312.2868) (xy 73.102718 -312.314756) (xy 73.058256 -312.335854)
			(xy 73.010985 -312.349546) (xy 72.96213 -312.355478) (xy 72.912955 -312.353497) (xy 72.864736 -312.343653)
			(xy 72.81872 -312.326201) (xy 72.776099 -312.301594) (xy 72.737978 -312.270469) (xy 72.705343 -312.233632)
			(xy 72.67904 -312.192036) (xy 72.659749 -312.14676) (xy 72.647972 -312.098976) (xy 72.644012 -312.049922)
			(xy 72.327008 -312.049922) (xy 72.326504 -312.07563) (xy 72.318461 -312.126412) (xy 72.302573 -312.175311)
			(xy 72.27923 -312.221123) (xy 72.249009 -312.262719) (xy 72.212653 -312.299075) (xy 72.171057 -312.329296)
			(xy 72.125245 -312.352639) (xy 72.076346 -312.368527) (xy 72.025564 -312.37657) (xy 71.974148 -312.37657)
			(xy 71.923366 -312.368527) (xy 71.874467 -312.352639) (xy 71.828655 -312.329296) (xy 71.787059 -312.299075)
			(xy 71.750703 -312.262719) (xy 71.720482 -312.221123) (xy 71.697139 -312.175311) (xy 71.681251 -312.126412)
			(xy 71.673208 -312.07563) (xy 71.35453 -312.07563) (xy 71.346814 -312.123106) (xy 71.33123 -312.169787)
			(xy 71.308359 -312.213364) (xy 71.278794 -312.252708) (xy 71.243301 -312.2868) (xy 71.202798 -312.314756)
			(xy 71.158336 -312.335854) (xy 71.111065 -312.349546) (xy 71.06221 -312.355478) (xy 71.013035 -312.353497)
			(xy 70.964816 -312.343653) (xy 70.9188 -312.326201) (xy 70.876179 -312.301594) (xy 70.838058 -312.270469)
			(xy 70.805423 -312.233632) (xy 70.77912 -312.192036) (xy 70.759829 -312.14676) (xy 70.748052 -312.098976)
			(xy 70.744092 -312.049922) (xy 70.427088 -312.049922) (xy 70.426584 -312.07563) (xy 70.418541 -312.126412)
			(xy 70.402653 -312.175311) (xy 70.37931 -312.221123) (xy 70.349089 -312.262719) (xy 70.312733 -312.299075)
			(xy 70.271137 -312.329296) (xy 70.225325 -312.352639) (xy 70.176426 -312.368527) (xy 70.125644 -312.37657)
			(xy 70.074228 -312.37657) (xy 70.023446 -312.368527) (xy 69.974547 -312.352639) (xy 69.928735 -312.329296)
			(xy 69.887139 -312.299075) (xy 69.850783 -312.262719) (xy 69.820562 -312.221123) (xy 69.797219 -312.175311)
			(xy 69.781331 -312.126412) (xy 69.773288 -312.07563) (xy 69.45461 -312.07563) (xy 69.446894 -312.123106)
			(xy 69.43131 -312.169787) (xy 69.408439 -312.213364) (xy 69.378874 -312.252708) (xy 69.343381 -312.2868)
			(xy 69.302878 -312.314756) (xy 69.258416 -312.335854) (xy 69.211145 -312.349546) (xy 69.16229 -312.355478)
			(xy 69.113115 -312.353497) (xy 69.064896 -312.343653) (xy 69.01888 -312.326201) (xy 68.976259 -312.301594)
			(xy 68.938138 -312.270469) (xy 68.905503 -312.233632) (xy 68.8792 -312.192036) (xy 68.859909 -312.14676)
			(xy 68.848132 -312.098976) (xy 68.844172 -312.049922) (xy 68.526914 -312.049922) (xy 68.52641 -312.07563)
			(xy 68.518367 -312.126412) (xy 68.502479 -312.175311) (xy 68.479136 -312.221123) (xy 68.448915 -312.262719)
			(xy 68.412559 -312.299075) (xy 68.370963 -312.329296) (xy 68.325151 -312.352639) (xy 68.276252 -312.368527)
			(xy 68.22547 -312.37657) (xy 68.174054 -312.37657) (xy 68.123272 -312.368527) (xy 68.074373 -312.352639)
			(xy 68.028561 -312.329296) (xy 67.986965 -312.299075) (xy 67.950609 -312.262719) (xy 67.920388 -312.221123)
			(xy 67.897045 -312.175311) (xy 67.881157 -312.126412) (xy 67.873114 -312.07563) (xy 67.554436 -312.07563)
			(xy 67.54672 -312.123106) (xy 67.531136 -312.169787) (xy 67.508265 -312.213364) (xy 67.4787 -312.252708)
			(xy 67.443207 -312.2868) (xy 67.402704 -312.314756) (xy 67.358242 -312.335854) (xy 67.310971 -312.349546)
			(xy 67.262116 -312.355478) (xy 67.212941 -312.353497) (xy 67.164722 -312.343653) (xy 67.118706 -312.326201)
			(xy 67.076085 -312.301594) (xy 67.037964 -312.270469) (xy 67.005329 -312.233632) (xy 66.979026 -312.192036)
			(xy 66.959735 -312.14676) (xy 66.947958 -312.098976) (xy 66.943998 -312.049922) (xy 66.626994 -312.049922)
			(xy 66.62649 -312.07563) (xy 66.618447 -312.126412) (xy 66.602559 -312.175311) (xy 66.579216 -312.221123)
			(xy 66.548995 -312.262719) (xy 66.512639 -312.299075) (xy 66.471043 -312.329296) (xy 66.425231 -312.352639)
			(xy 66.376332 -312.368527) (xy 66.32555 -312.37657) (xy 66.274134 -312.37657) (xy 66.223352 -312.368527)
			(xy 66.174453 -312.352639) (xy 66.128641 -312.329296) (xy 66.087045 -312.299075) (xy 66.050689 -312.262719)
			(xy 66.020468 -312.221123) (xy 65.997125 -312.175311) (xy 65.981237 -312.126412) (xy 65.973194 -312.07563)
			(xy 65.654516 -312.07563) (xy 65.6468 -312.123106) (xy 65.631216 -312.169787) (xy 65.608345 -312.213364)
			(xy 65.57878 -312.252708) (xy 65.543287 -312.2868) (xy 65.502784 -312.314756) (xy 65.458322 -312.335854)
			(xy 65.411051 -312.349546) (xy 65.362196 -312.355478) (xy 65.313021 -312.353497) (xy 65.264802 -312.343653)
			(xy 65.218786 -312.326201) (xy 65.176165 -312.301594) (xy 65.138044 -312.270469) (xy 65.105409 -312.233632)
			(xy 65.079106 -312.192036) (xy 65.059815 -312.14676) (xy 65.048038 -312.098976) (xy 65.044078 -312.049922)
			(xy 64.727074 -312.049922) (xy 64.72657 -312.07563) (xy 64.718527 -312.126412) (xy 64.702639 -312.175311)
			(xy 64.679296 -312.221123) (xy 64.649075 -312.262719) (xy 64.612719 -312.299075) (xy 64.571123 -312.329296)
			(xy 64.525311 -312.352639) (xy 64.476412 -312.368527) (xy 64.42563 -312.37657) (xy 64.374214 -312.37657)
			(xy 64.323432 -312.368527) (xy 64.274533 -312.352639) (xy 64.228721 -312.329296) (xy 64.187125 -312.299075)
			(xy 64.150769 -312.262719) (xy 64.120548 -312.221123) (xy 64.097205 -312.175311) (xy 64.081317 -312.126412)
			(xy 64.073274 -312.07563) (xy 63.754596 -312.07563) (xy 63.74688 -312.123106) (xy 63.731296 -312.169787)
			(xy 63.708425 -312.213364) (xy 63.67886 -312.252708) (xy 63.643367 -312.2868) (xy 63.602864 -312.314756)
			(xy 63.558402 -312.335854) (xy 63.511131 -312.349546) (xy 63.462276 -312.355478) (xy 63.413101 -312.353497)
			(xy 63.364882 -312.343653) (xy 63.318866 -312.326201) (xy 63.276245 -312.301594) (xy 63.238124 -312.270469)
			(xy 63.205489 -312.233632) (xy 63.179186 -312.192036) (xy 63.159895 -312.14676) (xy 63.148118 -312.098976)
			(xy 63.144158 -312.049922) (xy 62.8269 -312.049922) (xy 62.826396 -312.07563) (xy 62.818353 -312.126412)
			(xy 62.802465 -312.175311) (xy 62.779122 -312.221123) (xy 62.748901 -312.262719) (xy 62.712545 -312.299075)
			(xy 62.670949 -312.329296) (xy 62.625137 -312.352639) (xy 62.576238 -312.368527) (xy 62.525456 -312.37657)
			(xy 62.47404 -312.37657) (xy 62.423258 -312.368527) (xy 62.374359 -312.352639) (xy 62.328547 -312.329296)
			(xy 62.286951 -312.299075) (xy 62.250595 -312.262719) (xy 62.220374 -312.221123) (xy 62.197031 -312.175311)
			(xy 62.181143 -312.126412) (xy 62.1731 -312.07563) (xy 61.854422 -312.07563) (xy 61.846706 -312.123106)
			(xy 61.831122 -312.169787) (xy 61.808251 -312.213364) (xy 61.778686 -312.252708) (xy 61.743193 -312.2868)
			(xy 61.70269 -312.314756) (xy 61.658228 -312.335854) (xy 61.610957 -312.349546) (xy 61.562102 -312.355478)
			(xy 61.512927 -312.353497) (xy 61.464708 -312.343653) (xy 61.418692 -312.326201) (xy 61.376071 -312.301594)
			(xy 61.33795 -312.270469) (xy 61.305315 -312.233632) (xy 61.279012 -312.192036) (xy 61.259721 -312.14676)
			(xy 61.247944 -312.098976) (xy 61.243984 -312.049922) (xy 60.92698 -312.049922) (xy 60.926476 -312.07563)
			(xy 60.918433 -312.126412) (xy 60.902545 -312.175311) (xy 60.879202 -312.221123) (xy 60.848981 -312.262719)
			(xy 60.812625 -312.299075) (xy 60.771029 -312.329296) (xy 60.725217 -312.352639) (xy 60.676318 -312.368527)
			(xy 60.625536 -312.37657) (xy 60.57412 -312.37657) (xy 60.523338 -312.368527) (xy 60.474439 -312.352639)
			(xy 60.428627 -312.329296) (xy 60.387031 -312.299075) (xy 60.350675 -312.262719) (xy 60.320454 -312.221123)
			(xy 60.297111 -312.175311) (xy 60.281223 -312.126412) (xy 60.27318 -312.07563) (xy 59.954502 -312.07563)
			(xy 59.946786 -312.123106) (xy 59.931202 -312.169787) (xy 59.908331 -312.213364) (xy 59.878766 -312.252708)
			(xy 59.843273 -312.2868) (xy 59.80277 -312.314756) (xy 59.758308 -312.335854) (xy 59.711037 -312.349546)
			(xy 59.662182 -312.355478) (xy 59.613007 -312.353497) (xy 59.564788 -312.343653) (xy 59.518772 -312.326201)
			(xy 59.476151 -312.301594) (xy 59.43803 -312.270469) (xy 59.405395 -312.233632) (xy 59.379092 -312.192036)
			(xy 59.359801 -312.14676) (xy 59.348024 -312.098976) (xy 59.344064 -312.049922) (xy 59.02706 -312.049922)
			(xy 59.026556 -312.07563) (xy 59.018513 -312.126412) (xy 59.002625 -312.175311) (xy 58.979282 -312.221123)
			(xy 58.949061 -312.262719) (xy 58.912705 -312.299075) (xy 58.871109 -312.329296) (xy 58.825297 -312.352639)
			(xy 58.776398 -312.368527) (xy 58.725616 -312.37657) (xy 58.6742 -312.37657) (xy 58.623418 -312.368527)
			(xy 58.574519 -312.352639) (xy 58.528707 -312.329296) (xy 58.487111 -312.299075) (xy 58.450755 -312.262719)
			(xy 58.420534 -312.221123) (xy 58.397191 -312.175311) (xy 58.381303 -312.126412) (xy 58.37326 -312.07563)
			(xy 58.054582 -312.07563) (xy 58.046866 -312.123106) (xy 58.031282 -312.169787) (xy 58.008411 -312.213364)
			(xy 57.978846 -312.252708) (xy 57.943353 -312.2868) (xy 57.90285 -312.314756) (xy 57.858388 -312.335854)
			(xy 57.811117 -312.349546) (xy 57.762262 -312.355478) (xy 57.713087 -312.353497) (xy 57.664868 -312.343653)
			(xy 57.618852 -312.326201) (xy 57.576231 -312.301594) (xy 57.53811 -312.270469) (xy 57.505475 -312.233632)
			(xy 57.479172 -312.192036) (xy 57.459881 -312.14676) (xy 57.448104 -312.098976) (xy 57.444144 -312.049922)
			(xy 57.12714 -312.049922) (xy 57.126636 -312.07563) (xy 57.118593 -312.126412) (xy 57.102705 -312.175311)
			(xy 57.079362 -312.221123) (xy 57.049141 -312.262719) (xy 57.012785 -312.299075) (xy 56.971189 -312.329296)
			(xy 56.925377 -312.352639) (xy 56.876478 -312.368527) (xy 56.825696 -312.37657) (xy 56.77428 -312.37657)
			(xy 56.723498 -312.368527) (xy 56.674599 -312.352639) (xy 56.628787 -312.329296) (xy 56.587191 -312.299075)
			(xy 56.550835 -312.262719) (xy 56.520614 -312.221123) (xy 56.497271 -312.175311) (xy 56.481383 -312.126412)
			(xy 56.47334 -312.07563) (xy 56.154408 -312.07563) (xy 56.146692 -312.123106) (xy 56.131108 -312.169787)
			(xy 56.108237 -312.213364) (xy 56.078672 -312.252708) (xy 56.043179 -312.2868) (xy 56.002676 -312.314756)
			(xy 55.958214 -312.335854) (xy 55.910943 -312.349546) (xy 55.862088 -312.355478) (xy 55.812913 -312.353497)
			(xy 55.764694 -312.343653) (xy 55.718678 -312.326201) (xy 55.676057 -312.301594) (xy 55.637936 -312.270469)
			(xy 55.605301 -312.233632) (xy 55.578998 -312.192036) (xy 55.559707 -312.14676) (xy 55.54793 -312.098976)
			(xy 55.54397 -312.049922) (xy 55.226966 -312.049922) (xy 55.226462 -312.07563) (xy 55.218419 -312.126412)
			(xy 55.202531 -312.175311) (xy 55.179188 -312.221123) (xy 55.148967 -312.262719) (xy 55.112611 -312.299075)
			(xy 55.071015 -312.329296) (xy 55.025203 -312.352639) (xy 54.976304 -312.368527) (xy 54.925522 -312.37657)
			(xy 54.874106 -312.37657) (xy 54.823324 -312.368527) (xy 54.774425 -312.352639) (xy 54.728613 -312.329296)
			(xy 54.687017 -312.299075) (xy 54.650661 -312.262719) (xy 54.62044 -312.221123) (xy 54.597097 -312.175311)
			(xy 54.581209 -312.126412) (xy 54.573166 -312.07563) (xy 54.254488 -312.07563) (xy 54.246772 -312.123106)
			(xy 54.231188 -312.169787) (xy 54.208317 -312.213364) (xy 54.178752 -312.252708) (xy 54.143259 -312.2868)
			(xy 54.102756 -312.314756) (xy 54.058294 -312.335854) (xy 54.011023 -312.349546) (xy 53.962168 -312.355478)
			(xy 53.912993 -312.353497) (xy 53.864774 -312.343653) (xy 53.818758 -312.326201) (xy 53.776137 -312.301594)
			(xy 53.738016 -312.270469) (xy 53.705381 -312.233632) (xy 53.679078 -312.192036) (xy 53.659787 -312.14676)
			(xy 53.64801 -312.098976) (xy 53.64405 -312.049922) (xy 53.327046 -312.049922) (xy 53.326542 -312.07563)
			(xy 53.318499 -312.126412) (xy 53.302611 -312.175311) (xy 53.279268 -312.221123) (xy 53.249047 -312.262719)
			(xy 53.212691 -312.299075) (xy 53.171095 -312.329296) (xy 53.125283 -312.352639) (xy 53.076384 -312.368527)
			(xy 53.025602 -312.37657) (xy 52.974186 -312.37657) (xy 52.923404 -312.368527) (xy 52.874505 -312.352639)
			(xy 52.828693 -312.329296) (xy 52.787097 -312.299075) (xy 52.750741 -312.262719) (xy 52.72052 -312.221123)
			(xy 52.697177 -312.175311) (xy 52.681289 -312.126412) (xy 52.673246 -312.07563) (xy 52.354568 -312.07563)
			(xy 52.346852 -312.123106) (xy 52.331268 -312.169787) (xy 52.308397 -312.213364) (xy 52.278832 -312.252708)
			(xy 52.243339 -312.2868) (xy 52.202836 -312.314756) (xy 52.158374 -312.335854) (xy 52.111103 -312.349546)
			(xy 52.062248 -312.355478) (xy 52.013073 -312.353497) (xy 51.964854 -312.343653) (xy 51.918838 -312.326201)
			(xy 51.876217 -312.301594) (xy 51.838096 -312.270469) (xy 51.805461 -312.233632) (xy 51.779158 -312.192036)
			(xy 51.759867 -312.14676) (xy 51.74809 -312.098976) (xy 51.74413 -312.049922) (xy 51.427126 -312.049922)
			(xy 51.426622 -312.07563) (xy 51.418579 -312.126412) (xy 51.402691 -312.175311) (xy 51.379348 -312.221123)
			(xy 51.349127 -312.262719) (xy 51.312771 -312.299075) (xy 51.271175 -312.329296) (xy 51.225363 -312.352639)
			(xy 51.176464 -312.368527) (xy 51.125682 -312.37657) (xy 51.074266 -312.37657) (xy 51.023484 -312.368527)
			(xy 50.974585 -312.352639) (xy 50.928773 -312.329296) (xy 50.887177 -312.299075) (xy 50.850821 -312.262719)
			(xy 50.8206 -312.221123) (xy 50.797257 -312.175311) (xy 50.781369 -312.126412) (xy 50.773326 -312.07563)
			(xy 50.454394 -312.07563) (xy 50.446678 -312.123106) (xy 50.431094 -312.169787) (xy 50.408223 -312.213364)
			(xy 50.378658 -312.252708) (xy 50.343165 -312.2868) (xy 50.302662 -312.314756) (xy 50.2582 -312.335854)
			(xy 50.210929 -312.349546) (xy 50.162074 -312.355478) (xy 50.112899 -312.353497) (xy 50.06468 -312.343653)
			(xy 50.018664 -312.326201) (xy 49.976043 -312.301594) (xy 49.937922 -312.270469) (xy 49.905287 -312.233632)
			(xy 49.878984 -312.192036) (xy 49.859693 -312.14676) (xy 49.847916 -312.098976) (xy 49.843956 -312.049922)
			(xy 49.526952 -312.049922) (xy 49.526448 -312.07563) (xy 49.518405 -312.126412) (xy 49.502517 -312.175311)
			(xy 49.479174 -312.221123) (xy 49.448953 -312.262719) (xy 49.412597 -312.299075) (xy 49.371001 -312.329296)
			(xy 49.325189 -312.352639) (xy 49.27629 -312.368527) (xy 49.225508 -312.37657) (xy 49.174092 -312.37657)
			(xy 49.12331 -312.368527) (xy 49.074411 -312.352639) (xy 49.028599 -312.329296) (xy 48.987003 -312.299075)
			(xy 48.950647 -312.262719) (xy 48.920426 -312.221123) (xy 48.897083 -312.175311) (xy 48.881195 -312.126412)
			(xy 48.873152 -312.07563) (xy 48.554474 -312.07563) (xy 48.546758 -312.123106) (xy 48.531174 -312.169787)
			(xy 48.508303 -312.213364) (xy 48.478738 -312.252708) (xy 48.443245 -312.2868) (xy 48.402742 -312.314756)
			(xy 48.35828 -312.335854) (xy 48.311009 -312.349546) (xy 48.262154 -312.355478) (xy 48.212979 -312.353497)
			(xy 48.16476 -312.343653) (xy 48.118744 -312.326201) (xy 48.076123 -312.301594) (xy 48.038002 -312.270469)
			(xy 48.005367 -312.233632) (xy 47.979064 -312.192036) (xy 47.959773 -312.14676) (xy 47.947996 -312.098976)
			(xy 47.944036 -312.049922) (xy 47.627032 -312.049922) (xy 47.626528 -312.07563) (xy 47.618485 -312.126412)
			(xy 47.602597 -312.175311) (xy 47.579254 -312.221123) (xy 47.549033 -312.262719) (xy 47.512677 -312.299075)
			(xy 47.471081 -312.329296) (xy 47.425269 -312.352639) (xy 47.37637 -312.368527) (xy 47.325588 -312.37657)
			(xy 47.274172 -312.37657) (xy 47.22339 -312.368527) (xy 47.174491 -312.352639) (xy 47.128679 -312.329296)
			(xy 47.087083 -312.299075) (xy 47.050727 -312.262719) (xy 47.020506 -312.221123) (xy 46.997163 -312.175311)
			(xy 46.981275 -312.126412) (xy 46.973232 -312.07563) (xy 46.654554 -312.07563) (xy 46.646838 -312.123106)
			(xy 46.631254 -312.169787) (xy 46.608383 -312.213364) (xy 46.578818 -312.252708) (xy 46.543325 -312.2868)
			(xy 46.502822 -312.314756) (xy 46.45836 -312.335854) (xy 46.411089 -312.349546) (xy 46.362234 -312.355478)
			(xy 46.313059 -312.353497) (xy 46.26484 -312.343653) (xy 46.218824 -312.326201) (xy 46.176203 -312.301594)
			(xy 46.138082 -312.270469) (xy 46.105447 -312.233632) (xy 46.079144 -312.192036) (xy 46.059853 -312.14676)
			(xy 46.048076 -312.098976) (xy 46.044116 -312.049922) (xy 45.727112 -312.049922) (xy 45.726608 -312.07563)
			(xy 45.718565 -312.126412) (xy 45.702677 -312.175311) (xy 45.679334 -312.221123) (xy 45.649113 -312.262719)
			(xy 45.612757 -312.299075) (xy 45.571161 -312.329296) (xy 45.525349 -312.352639) (xy 45.47645 -312.368527)
			(xy 45.425668 -312.37657) (xy 45.374252 -312.37657) (xy 45.32347 -312.368527) (xy 45.274571 -312.352639)
			(xy 45.228759 -312.329296) (xy 45.187163 -312.299075) (xy 45.150807 -312.262719) (xy 45.120586 -312.221123)
			(xy 45.097243 -312.175311) (xy 45.081355 -312.126412) (xy 45.073312 -312.07563) (xy 44.75438 -312.07563)
			(xy 44.746664 -312.123106) (xy 44.73108 -312.169787) (xy 44.708209 -312.213364) (xy 44.678644 -312.252708)
			(xy 44.643151 -312.2868) (xy 44.602648 -312.314756) (xy 44.558186 -312.335854) (xy 44.510915 -312.349546)
			(xy 44.46206 -312.355478) (xy 44.412885 -312.353497) (xy 44.364666 -312.343653) (xy 44.31865 -312.326201)
			(xy 44.276029 -312.301594) (xy 44.237908 -312.270469) (xy 44.205273 -312.233632) (xy 44.17897 -312.192036)
			(xy 44.159679 -312.14676) (xy 44.147902 -312.098976) (xy 44.143942 -312.049922) (xy 43.826938 -312.049922)
			(xy 43.826434 -312.07563) (xy 43.818391 -312.126412) (xy 43.802503 -312.175311) (xy 43.77916 -312.221123)
			(xy 43.748939 -312.262719) (xy 43.712583 -312.299075) (xy 43.670987 -312.329296) (xy 43.625175 -312.352639)
			(xy 43.576276 -312.368527) (xy 43.525494 -312.37657) (xy 43.474078 -312.37657) (xy 43.423296 -312.368527)
			(xy 43.374397 -312.352639) (xy 43.328585 -312.329296) (xy 43.286989 -312.299075) (xy 43.250633 -312.262719)
			(xy 43.220412 -312.221123) (xy 43.197069 -312.175311) (xy 43.181181 -312.126412) (xy 43.173138 -312.07563)
			(xy 42.85446 -312.07563) (xy 42.846744 -312.123106) (xy 42.83116 -312.169787) (xy 42.808289 -312.213364)
			(xy 42.778724 -312.252708) (xy 42.743231 -312.2868) (xy 42.702728 -312.314756) (xy 42.658266 -312.335854)
			(xy 42.610995 -312.349546) (xy 42.56214 -312.355478) (xy 42.512965 -312.353497) (xy 42.464746 -312.343653)
			(xy 42.41873 -312.326201) (xy 42.376109 -312.301594) (xy 42.337988 -312.270469) (xy 42.305353 -312.233632)
			(xy 42.27905 -312.192036) (xy 42.259759 -312.14676) (xy 42.247982 -312.098976) (xy 42.244022 -312.049922)
			(xy 41.927018 -312.049922) (xy 41.926514 -312.07563) (xy 41.918471 -312.126412) (xy 41.902583 -312.175311)
			(xy 41.87924 -312.221123) (xy 41.849019 -312.262719) (xy 41.812663 -312.299075) (xy 41.771067 -312.329296)
			(xy 41.725255 -312.352639) (xy 41.676356 -312.368527) (xy 41.625574 -312.37657) (xy 41.574158 -312.37657)
			(xy 41.523376 -312.368527) (xy 41.474477 -312.352639) (xy 41.428665 -312.329296) (xy 41.387069 -312.299075)
			(xy 41.350713 -312.262719) (xy 41.320492 -312.221123) (xy 41.297149 -312.175311) (xy 41.281261 -312.126412)
			(xy 41.273218 -312.07563) (xy 40.95454 -312.07563) (xy 40.946824 -312.123106) (xy 40.93124 -312.169787)
			(xy 40.908369 -312.213364) (xy 40.878804 -312.252708) (xy 40.843311 -312.2868) (xy 40.802808 -312.314756)
			(xy 40.758346 -312.335854) (xy 40.711075 -312.349546) (xy 40.66222 -312.355478) (xy 40.613045 -312.353497)
			(xy 40.564826 -312.343653) (xy 40.51881 -312.326201) (xy 40.476189 -312.301594) (xy 40.438068 -312.270469)
			(xy 40.405433 -312.233632) (xy 40.37913 -312.192036) (xy 40.359839 -312.14676) (xy 40.348062 -312.098976)
			(xy 40.344102 -312.049922) (xy 40.027098 -312.049922) (xy 40.026594 -312.07563) (xy 40.018551 -312.126412)
			(xy 40.002663 -312.175311) (xy 39.97932 -312.221123) (xy 39.949099 -312.262719) (xy 39.912743 -312.299075)
			(xy 39.871147 -312.329296) (xy 39.825335 -312.352639) (xy 39.776436 -312.368527) (xy 39.725654 -312.37657)
			(xy 39.674238 -312.37657) (xy 39.623456 -312.368527) (xy 39.574557 -312.352639) (xy 39.528745 -312.329296)
			(xy 39.487149 -312.299075) (xy 39.450793 -312.262719) (xy 39.420572 -312.221123) (xy 39.397229 -312.175311)
			(xy 39.381341 -312.126412) (xy 39.373298 -312.07563) (xy 39.05462 -312.07563) (xy 39.046904 -312.123106)
			(xy 39.03132 -312.169787) (xy 39.008449 -312.213364) (xy 38.978884 -312.252708) (xy 38.943391 -312.2868)
			(xy 38.902888 -312.314756) (xy 38.858426 -312.335854) (xy 38.811155 -312.349546) (xy 38.7623 -312.355478)
			(xy 38.713125 -312.353497) (xy 38.664906 -312.343653) (xy 38.61889 -312.326201) (xy 38.576269 -312.301594)
			(xy 38.538148 -312.270469) (xy 38.505513 -312.233632) (xy 38.47921 -312.192036) (xy 38.459919 -312.14676)
			(xy 38.448142 -312.098976) (xy 38.444182 -312.049922) (xy 38.126924 -312.049922) (xy 38.12642 -312.07563)
			(xy 38.118377 -312.126412) (xy 38.102489 -312.175311) (xy 38.079146 -312.221123) (xy 38.048925 -312.262719)
			(xy 38.012569 -312.299075) (xy 37.970973 -312.329296) (xy 37.925161 -312.352639) (xy 37.876262 -312.368527)
			(xy 37.82548 -312.37657) (xy 37.774064 -312.37657) (xy 37.723282 -312.368527) (xy 37.674383 -312.352639)
			(xy 37.628571 -312.329296) (xy 37.586975 -312.299075) (xy 37.550619 -312.262719) (xy 37.520398 -312.221123)
			(xy 37.497055 -312.175311) (xy 37.481167 -312.126412) (xy 37.473124 -312.07563) (xy 37.17646 -312.07563)
			(xy 37.168417 -312.126412) (xy 37.152529 -312.175311) (xy 37.129186 -312.221123) (xy 37.098965 -312.262719)
			(xy 37.062609 -312.299075) (xy 37.021013 -312.329296) (xy 36.975201 -312.352639) (xy 36.926302 -312.368527)
			(xy 36.87552 -312.37657) (xy 36.824104 -312.37657) (xy 36.773322 -312.368527) (xy 36.724423 -312.352639)
			(xy 36.678611 -312.329296) (xy 36.637015 -312.299075) (xy 36.600659 -312.262719) (xy 36.570438 -312.221123)
			(xy 36.547095 -312.175311) (xy 36.531207 -312.126412) (xy 36.523164 -312.07563) (xy 36.204191 -312.07563)
			(xy 36.196516 -312.122852) (xy 36.180932 -312.169533) (xy 36.158061 -312.21311) (xy 36.128496 -312.252454)
			(xy 36.093003 -312.286546) (xy 36.0525 -312.314502) (xy 36.008038 -312.3356) (xy 35.960767 -312.349292)
			(xy 35.911912 -312.355224) (xy 35.862737 -312.353243) (xy 35.814518 -312.343399) (xy 35.768502 -312.325947)
			(xy 35.725881 -312.30134) (xy 35.68776 -312.270215) (xy 35.655125 -312.233378) (xy 35.628822 -312.191782)
			(xy 35.609531 -312.146506) (xy 35.597754 -312.098722) (xy 35.593794 -312.049668) (xy 34.716108 -312.049668)
			(xy 34.736931 -312.081142) (xy 34.760603 -312.131639) (xy 34.776671 -312.185046) (xy 34.784791 -312.240222)
			(xy 34.7853 -312.268108) (xy 34.784791 -312.295994) (xy 34.776671 -312.35117) (xy 34.760603 -312.404577)
			(xy 34.736931 -312.455074) (xy 34.706158 -312.501587) (xy 34.668941 -312.543124) (xy 34.626073 -312.578799)
			(xy 34.578467 -312.607853) (xy 34.527138 -312.629665) (xy 34.473181 -312.643771) (xy 34.417744 -312.649871)
			(xy 34.36201 -312.647834) (xy 34.307167 -312.637704) (xy 34.254383 -312.619697) (xy 34.204783 -312.594196)
			(xy 34.159425 -312.561745) (xy 34.119276 -312.523036) (xy 34.08519 -312.478893) (xy 34.057894 -312.430258)
			(xy 34.037971 -312.378167) (xy 34.025845 -312.32373) (xy 34.021774 -312.268108) (xy 32.396823 -312.268108)
			(xy 32.416348 -312.289899) (xy 32.447121 -312.336412) (xy 32.470793 -312.386909) (xy 32.486861 -312.440316)
			(xy 32.494981 -312.495492) (xy 32.49549 -312.523378) (xy 32.494981 -312.551264) (xy 32.486861 -312.60644)
			(xy 32.470793 -312.659847) (xy 32.447121 -312.710344) (xy 32.416348 -312.756857) (xy 32.379131 -312.798394)
			(xy 32.336263 -312.834069) (xy 32.288657 -312.863123) (xy 32.237328 -312.884935) (xy 32.183371 -312.899041)
			(xy 32.127934 -312.905141) (xy 32.0722 -312.903104) (xy 32.017357 -312.892974) (xy 31.964573 -312.874967)
			(xy 31.914973 -312.849466) (xy 31.869615 -312.817015) (xy 31.829466 -312.778306) (xy 31.79538 -312.734163)
			(xy 31.768084 -312.685528) (xy 31.748161 -312.633437) (xy 31.736035 -312.579) (xy 31.731964 -312.523378)
			(xy 17.71396 -312.523378) (xy 17.71396 -312.999882) (xy 36.544008 -312.999882) (xy 36.547968 -312.950828)
			(xy 36.559745 -312.903044) (xy 36.579036 -312.857768) (xy 36.605339 -312.816172) (xy 36.637974 -312.779335)
			(xy 36.676095 -312.74821) (xy 36.718716 -312.723603) (xy 36.764732 -312.706151) (xy 36.812951 -312.696307)
			(xy 36.862126 -312.694326) (xy 36.910981 -312.700258) (xy 36.958252 -312.71395) (xy 37.002714 -312.735048)
			(xy 37.043217 -312.763004) (xy 37.07871 -312.797096) (xy 37.108275 -312.83644) (xy 37.131146 -312.880017)
			(xy 37.14673 -312.926698) (xy 37.154625 -312.975275) (xy 37.15512 -312.999882) (xy 37.493968 -312.999882)
			(xy 37.497928 -312.950828) (xy 37.509705 -312.903044) (xy 37.528996 -312.857768) (xy 37.555299 -312.816172)
			(xy 37.587934 -312.779335) (xy 37.626055 -312.74821) (xy 37.668676 -312.723603) (xy 37.714692 -312.706151)
			(xy 37.762911 -312.696307) (xy 37.812086 -312.694326) (xy 37.860941 -312.700258) (xy 37.908212 -312.71395)
			(xy 37.952674 -312.735048) (xy 37.993177 -312.763004) (xy 38.02867 -312.797096) (xy 38.058235 -312.83644)
			(xy 38.081106 -312.880017) (xy 38.09669 -312.926698) (xy 38.104585 -312.975275) (xy 38.10508 -312.999882)
			(xy 38.104585 -313.024489) (xy 38.104406 -313.02559) (xy 38.423338 -313.02559) (xy 38.423338 -312.974174)
			(xy 38.431381 -312.923392) (xy 38.447269 -312.874493) (xy 38.470612 -312.828681) (xy 38.500833 -312.787085)
			(xy 38.537189 -312.750729) (xy 38.578785 -312.720508) (xy 38.624597 -312.697165) (xy 38.673496 -312.681277)
			(xy 38.724278 -312.673234) (xy 38.775694 -312.673234) (xy 38.826476 -312.681277) (xy 38.875375 -312.697165)
			(xy 38.921187 -312.720508) (xy 38.962783 -312.750729) (xy 38.999139 -312.787085) (xy 39.02936 -312.828681)
			(xy 39.052703 -312.874493) (xy 39.068591 -312.923392) (xy 39.076634 -312.974174) (xy 39.077138 -312.999882)
			(xy 39.394142 -312.999882) (xy 39.398102 -312.950828) (xy 39.409879 -312.903044) (xy 39.42917 -312.857768)
			(xy 39.455473 -312.816172) (xy 39.488108 -312.779335) (xy 39.526229 -312.74821) (xy 39.56885 -312.723603)
			(xy 39.614866 -312.706151) (xy 39.663085 -312.696307) (xy 39.71226 -312.694326) (xy 39.761115 -312.700258)
			(xy 39.808386 -312.71395) (xy 39.852848 -312.735048) (xy 39.893351 -312.763004) (xy 39.928844 -312.797096)
			(xy 39.958409 -312.83644) (xy 39.98128 -312.880017) (xy 39.996864 -312.926698) (xy 40.004759 -312.975275)
			(xy 40.005254 -312.999882) (xy 40.004759 -313.024489) (xy 40.00458 -313.02559) (xy 40.323258 -313.02559)
			(xy 40.323258 -312.974174) (xy 40.331301 -312.923392) (xy 40.347189 -312.874493) (xy 40.370532 -312.828681)
			(xy 40.400753 -312.787085) (xy 40.437109 -312.750729) (xy 40.478705 -312.720508) (xy 40.524517 -312.697165)
			(xy 40.573416 -312.681277) (xy 40.624198 -312.673234) (xy 40.675614 -312.673234) (xy 40.726396 -312.681277)
			(xy 40.775295 -312.697165) (xy 40.821107 -312.720508) (xy 40.862703 -312.750729) (xy 40.899059 -312.787085)
			(xy 40.92928 -312.828681) (xy 40.952623 -312.874493) (xy 40.968511 -312.923392) (xy 40.976554 -312.974174)
			(xy 40.977058 -312.999882) (xy 41.294062 -312.999882) (xy 41.298022 -312.950828) (xy 41.309799 -312.903044)
			(xy 41.32909 -312.857768) (xy 41.355393 -312.816172) (xy 41.388028 -312.779335) (xy 41.426149 -312.74821)
			(xy 41.46877 -312.723603) (xy 41.514786 -312.706151) (xy 41.563005 -312.696307) (xy 41.61218 -312.694326)
			(xy 41.661035 -312.700258) (xy 41.708306 -312.71395) (xy 41.752768 -312.735048) (xy 41.793271 -312.763004)
			(xy 41.828764 -312.797096) (xy 41.858329 -312.83644) (xy 41.8812 -312.880017) (xy 41.896784 -312.926698)
			(xy 41.904679 -312.975275) (xy 41.905174 -312.999882) (xy 41.904679 -313.024489) (xy 41.9045 -313.02559)
			(xy 42.223178 -313.02559) (xy 42.223178 -312.974174) (xy 42.231221 -312.923392) (xy 42.247109 -312.874493)
			(xy 42.270452 -312.828681) (xy 42.300673 -312.787085) (xy 42.337029 -312.750729) (xy 42.378625 -312.720508)
			(xy 42.424437 -312.697165) (xy 42.473336 -312.681277) (xy 42.524118 -312.673234) (xy 42.575534 -312.673234)
			(xy 42.626316 -312.681277) (xy 42.675215 -312.697165) (xy 42.721027 -312.720508) (xy 42.762623 -312.750729)
			(xy 42.798979 -312.787085) (xy 42.8292 -312.828681) (xy 42.852543 -312.874493) (xy 42.868431 -312.923392)
			(xy 42.876474 -312.974174) (xy 42.876978 -312.999882) (xy 43.193982 -312.999882) (xy 43.197942 -312.950828)
			(xy 43.209719 -312.903044) (xy 43.22901 -312.857768) (xy 43.255313 -312.816172) (xy 43.287948 -312.779335)
			(xy 43.326069 -312.74821) (xy 43.36869 -312.723603) (xy 43.414706 -312.706151) (xy 43.462925 -312.696307)
			(xy 43.5121 -312.694326) (xy 43.560955 -312.700258) (xy 43.608226 -312.71395) (xy 43.652688 -312.735048)
			(xy 43.693191 -312.763004) (xy 43.728684 -312.797096) (xy 43.758249 -312.83644) (xy 43.78112 -312.880017)
			(xy 43.796704 -312.926698) (xy 43.804599 -312.975275) (xy 43.805094 -312.999882) (xy 43.804599 -313.024489)
			(xy 43.80442 -313.02559) (xy 44.123098 -313.02559) (xy 44.123098 -312.974174) (xy 44.131141 -312.923392)
			(xy 44.147029 -312.874493) (xy 44.170372 -312.828681) (xy 44.200593 -312.787085) (xy 44.236949 -312.750729)
			(xy 44.278545 -312.720508) (xy 44.324357 -312.697165) (xy 44.373256 -312.681277) (xy 44.424038 -312.673234)
			(xy 44.475454 -312.673234) (xy 44.526236 -312.681277) (xy 44.575135 -312.697165) (xy 44.620947 -312.720508)
			(xy 44.662543 -312.750729) (xy 44.698899 -312.787085) (xy 44.72912 -312.828681) (xy 44.752463 -312.874493)
			(xy 44.768351 -312.923392) (xy 44.776394 -312.974174) (xy 44.776898 -312.999882) (xy 45.094156 -312.999882)
			(xy 45.098116 -312.950828) (xy 45.109893 -312.903044) (xy 45.129184 -312.857768) (xy 45.155487 -312.816172)
			(xy 45.188122 -312.779335) (xy 45.226243 -312.74821) (xy 45.268864 -312.723603) (xy 45.31488 -312.706151)
			(xy 45.363099 -312.696307) (xy 45.412274 -312.694326) (xy 45.461129 -312.700258) (xy 45.5084 -312.71395)
			(xy 45.552862 -312.735048) (xy 45.593365 -312.763004) (xy 45.628858 -312.797096) (xy 45.658423 -312.83644)
			(xy 45.681294 -312.880017) (xy 45.696878 -312.926698) (xy 45.704773 -312.975275) (xy 45.705268 -312.999882)
			(xy 45.704773 -313.024489) (xy 45.704594 -313.02559) (xy 46.023272 -313.02559) (xy 46.023272 -312.974174)
			(xy 46.031315 -312.923392) (xy 46.047203 -312.874493) (xy 46.070546 -312.828681) (xy 46.100767 -312.787085)
			(xy 46.137123 -312.750729) (xy 46.178719 -312.720508) (xy 46.224531 -312.697165) (xy 46.27343 -312.681277)
			(xy 46.324212 -312.673234) (xy 46.375628 -312.673234) (xy 46.42641 -312.681277) (xy 46.475309 -312.697165)
			(xy 46.521121 -312.720508) (xy 46.562717 -312.750729) (xy 46.599073 -312.787085) (xy 46.629294 -312.828681)
			(xy 46.652637 -312.874493) (xy 46.668525 -312.923392) (xy 46.676568 -312.974174) (xy 46.677072 -312.999882)
			(xy 46.994076 -312.999882) (xy 46.998036 -312.950828) (xy 47.009813 -312.903044) (xy 47.029104 -312.857768)
			(xy 47.055407 -312.816172) (xy 47.088042 -312.779335) (xy 47.126163 -312.74821) (xy 47.168784 -312.723603)
			(xy 47.2148 -312.706151) (xy 47.263019 -312.696307) (xy 47.312194 -312.694326) (xy 47.361049 -312.700258)
			(xy 47.40832 -312.71395) (xy 47.452782 -312.735048) (xy 47.493285 -312.763004) (xy 47.528778 -312.797096)
			(xy 47.558343 -312.83644) (xy 47.581214 -312.880017) (xy 47.596798 -312.926698) (xy 47.604693 -312.975275)
			(xy 47.605188 -312.999882) (xy 47.604693 -313.024489) (xy 47.604514 -313.02559) (xy 47.923192 -313.02559)
			(xy 47.923192 -312.974174) (xy 47.931235 -312.923392) (xy 47.947123 -312.874493) (xy 47.970466 -312.828681)
			(xy 48.000687 -312.787085) (xy 48.037043 -312.750729) (xy 48.078639 -312.720508) (xy 48.124451 -312.697165)
			(xy 48.17335 -312.681277) (xy 48.224132 -312.673234) (xy 48.275548 -312.673234) (xy 48.32633 -312.681277)
			(xy 48.375229 -312.697165) (xy 48.421041 -312.720508) (xy 48.462637 -312.750729) (xy 48.498993 -312.787085)
			(xy 48.529214 -312.828681) (xy 48.552557 -312.874493) (xy 48.568445 -312.923392) (xy 48.576488 -312.974174)
			(xy 48.576992 -312.999882) (xy 48.893996 -312.999882) (xy 48.897956 -312.950828) (xy 48.909733 -312.903044)
			(xy 48.929024 -312.857768) (xy 48.955327 -312.816172) (xy 48.987962 -312.779335) (xy 49.026083 -312.74821)
			(xy 49.068704 -312.723603) (xy 49.11472 -312.706151) (xy 49.162939 -312.696307) (xy 49.212114 -312.694326)
			(xy 49.260969 -312.700258) (xy 49.30824 -312.71395) (xy 49.352702 -312.735048) (xy 49.393205 -312.763004)
			(xy 49.428698 -312.797096) (xy 49.458263 -312.83644) (xy 49.481134 -312.880017) (xy 49.496718 -312.926698)
			(xy 49.504613 -312.975275) (xy 49.505108 -312.999882) (xy 49.504613 -313.024489) (xy 49.504434 -313.02559)
			(xy 49.823112 -313.02559) (xy 49.823112 -312.974174) (xy 49.831155 -312.923392) (xy 49.847043 -312.874493)
			(xy 49.870386 -312.828681) (xy 49.900607 -312.787085) (xy 49.936963 -312.750729) (xy 49.978559 -312.720508)
			(xy 50.024371 -312.697165) (xy 50.07327 -312.681277) (xy 50.124052 -312.673234) (xy 50.175468 -312.673234)
			(xy 50.22625 -312.681277) (xy 50.275149 -312.697165) (xy 50.320961 -312.720508) (xy 50.362557 -312.750729)
			(xy 50.398913 -312.787085) (xy 50.429134 -312.828681) (xy 50.452477 -312.874493) (xy 50.468365 -312.923392)
			(xy 50.476408 -312.974174) (xy 50.476912 -312.999882) (xy 50.79417 -312.999882) (xy 50.79813 -312.950828)
			(xy 50.809907 -312.903044) (xy 50.829198 -312.857768) (xy 50.855501 -312.816172) (xy 50.888136 -312.779335)
			(xy 50.926257 -312.74821) (xy 50.968878 -312.723603) (xy 51.014894 -312.706151) (xy 51.063113 -312.696307)
			(xy 51.112288 -312.694326) (xy 51.161143 -312.700258) (xy 51.208414 -312.71395) (xy 51.252876 -312.735048)
			(xy 51.293379 -312.763004) (xy 51.328872 -312.797096) (xy 51.358437 -312.83644) (xy 51.381308 -312.880017)
			(xy 51.396892 -312.926698) (xy 51.404787 -312.975275) (xy 51.405282 -312.999882) (xy 51.404787 -313.024489)
			(xy 51.404608 -313.02559) (xy 51.723286 -313.02559) (xy 51.723286 -312.974174) (xy 51.731329 -312.923392)
			(xy 51.747217 -312.874493) (xy 51.77056 -312.828681) (xy 51.800781 -312.787085) (xy 51.837137 -312.750729)
			(xy 51.878733 -312.720508) (xy 51.924545 -312.697165) (xy 51.973444 -312.681277) (xy 52.024226 -312.673234)
			(xy 52.075642 -312.673234) (xy 52.126424 -312.681277) (xy 52.175323 -312.697165) (xy 52.221135 -312.720508)
			(xy 52.262731 -312.750729) (xy 52.299087 -312.787085) (xy 52.329308 -312.828681) (xy 52.352651 -312.874493)
			(xy 52.368539 -312.923392) (xy 52.376582 -312.974174) (xy 52.377086 -312.999882) (xy 52.69409 -312.999882)
			(xy 52.69805 -312.950828) (xy 52.709827 -312.903044) (xy 52.729118 -312.857768) (xy 52.755421 -312.816172)
			(xy 52.788056 -312.779335) (xy 52.826177 -312.74821) (xy 52.868798 -312.723603) (xy 52.914814 -312.706151)
			(xy 52.963033 -312.696307) (xy 53.012208 -312.694326) (xy 53.061063 -312.700258) (xy 53.108334 -312.71395)
			(xy 53.152796 -312.735048) (xy 53.193299 -312.763004) (xy 53.228792 -312.797096) (xy 53.258357 -312.83644)
			(xy 53.281228 -312.880017) (xy 53.296812 -312.926698) (xy 53.304707 -312.975275) (xy 53.305202 -312.999882)
			(xy 53.304707 -313.024489) (xy 53.304528 -313.02559) (xy 53.623206 -313.02559) (xy 53.623206 -312.974174)
			(xy 53.631249 -312.923392) (xy 53.647137 -312.874493) (xy 53.67048 -312.828681) (xy 53.700701 -312.787085)
			(xy 53.737057 -312.750729) (xy 53.778653 -312.720508) (xy 53.824465 -312.697165) (xy 53.873364 -312.681277)
			(xy 53.924146 -312.673234) (xy 53.975562 -312.673234) (xy 54.026344 -312.681277) (xy 54.075243 -312.697165)
			(xy 54.121055 -312.720508) (xy 54.162651 -312.750729) (xy 54.199007 -312.787085) (xy 54.229228 -312.828681)
			(xy 54.252571 -312.874493) (xy 54.268459 -312.923392) (xy 54.276502 -312.974174) (xy 54.277006 -312.999882)
			(xy 54.59401 -312.999882) (xy 54.59797 -312.950828) (xy 54.609747 -312.903044) (xy 54.629038 -312.857768)
			(xy 54.655341 -312.816172) (xy 54.687976 -312.779335) (xy 54.726097 -312.74821) (xy 54.768718 -312.723603)
			(xy 54.814734 -312.706151) (xy 54.862953 -312.696307) (xy 54.912128 -312.694326) (xy 54.960983 -312.700258)
			(xy 55.008254 -312.71395) (xy 55.052716 -312.735048) (xy 55.093219 -312.763004) (xy 55.128712 -312.797096)
			(xy 55.158277 -312.83644) (xy 55.181148 -312.880017) (xy 55.196732 -312.926698) (xy 55.204627 -312.975275)
			(xy 55.205122 -312.999882) (xy 55.204627 -313.024489) (xy 55.204448 -313.02559) (xy 55.523126 -313.02559)
			(xy 55.523126 -312.974174) (xy 55.531169 -312.923392) (xy 55.547057 -312.874493) (xy 55.5704 -312.828681)
			(xy 55.600621 -312.787085) (xy 55.636977 -312.750729) (xy 55.678573 -312.720508) (xy 55.724385 -312.697165)
			(xy 55.773284 -312.681277) (xy 55.824066 -312.673234) (xy 55.875482 -312.673234) (xy 55.926264 -312.681277)
			(xy 55.975163 -312.697165) (xy 56.020975 -312.720508) (xy 56.062571 -312.750729) (xy 56.098927 -312.787085)
			(xy 56.129148 -312.828681) (xy 56.152491 -312.874493) (xy 56.168379 -312.923392) (xy 56.176422 -312.974174)
			(xy 56.176926 -312.999882) (xy 56.494184 -312.999882) (xy 56.498144 -312.950828) (xy 56.509921 -312.903044)
			(xy 56.529212 -312.857768) (xy 56.555515 -312.816172) (xy 56.58815 -312.779335) (xy 56.626271 -312.74821)
			(xy 56.668892 -312.723603) (xy 56.714908 -312.706151) (xy 56.763127 -312.696307) (xy 56.812302 -312.694326)
			(xy 56.861157 -312.700258) (xy 56.908428 -312.71395) (xy 56.95289 -312.735048) (xy 56.993393 -312.763004)
			(xy 57.028886 -312.797096) (xy 57.058451 -312.83644) (xy 57.081322 -312.880017) (xy 57.096906 -312.926698)
			(xy 57.104801 -312.975275) (xy 57.105296 -312.999882) (xy 57.104801 -313.024489) (xy 57.104622 -313.02559)
			(xy 57.4233 -313.02559) (xy 57.4233 -312.974174) (xy 57.431343 -312.923392) (xy 57.447231 -312.874493)
			(xy 57.470574 -312.828681) (xy 57.500795 -312.787085) (xy 57.537151 -312.750729) (xy 57.578747 -312.720508)
			(xy 57.624559 -312.697165) (xy 57.673458 -312.681277) (xy 57.72424 -312.673234) (xy 57.775656 -312.673234)
			(xy 57.826438 -312.681277) (xy 57.875337 -312.697165) (xy 57.921149 -312.720508) (xy 57.962745 -312.750729)
			(xy 57.999101 -312.787085) (xy 58.029322 -312.828681) (xy 58.052665 -312.874493) (xy 58.068553 -312.923392)
			(xy 58.076596 -312.974174) (xy 58.0771 -312.999882) (xy 58.394104 -312.999882) (xy 58.398064 -312.950828)
			(xy 58.409841 -312.903044) (xy 58.429132 -312.857768) (xy 58.455435 -312.816172) (xy 58.48807 -312.779335)
			(xy 58.526191 -312.74821) (xy 58.568812 -312.723603) (xy 58.614828 -312.706151) (xy 58.663047 -312.696307)
			(xy 58.712222 -312.694326) (xy 58.761077 -312.700258) (xy 58.808348 -312.71395) (xy 58.85281 -312.735048)
			(xy 58.893313 -312.763004) (xy 58.928806 -312.797096) (xy 58.958371 -312.83644) (xy 58.981242 -312.880017)
			(xy 58.996826 -312.926698) (xy 59.004721 -312.975275) (xy 59.005216 -312.999882) (xy 59.004721 -313.024489)
			(xy 59.004542 -313.02559) (xy 59.32322 -313.02559) (xy 59.32322 -312.974174) (xy 59.331263 -312.923392)
			(xy 59.347151 -312.874493) (xy 59.370494 -312.828681) (xy 59.400715 -312.787085) (xy 59.437071 -312.750729)
			(xy 59.478667 -312.720508) (xy 59.524479 -312.697165) (xy 59.573378 -312.681277) (xy 59.62416 -312.673234)
			(xy 59.675576 -312.673234) (xy 59.726358 -312.681277) (xy 59.775257 -312.697165) (xy 59.821069 -312.720508)
			(xy 59.862665 -312.750729) (xy 59.899021 -312.787085) (xy 59.929242 -312.828681) (xy 59.952585 -312.874493)
			(xy 59.968473 -312.923392) (xy 59.976516 -312.974174) (xy 59.97702 -312.999882) (xy 60.294024 -312.999882)
			(xy 60.297984 -312.950828) (xy 60.309761 -312.903044) (xy 60.329052 -312.857768) (xy 60.355355 -312.816172)
			(xy 60.38799 -312.779335) (xy 60.426111 -312.74821) (xy 60.468732 -312.723603) (xy 60.514748 -312.706151)
			(xy 60.562967 -312.696307) (xy 60.612142 -312.694326) (xy 60.660997 -312.700258) (xy 60.708268 -312.71395)
			(xy 60.75273 -312.735048) (xy 60.793233 -312.763004) (xy 60.828726 -312.797096) (xy 60.858291 -312.83644)
			(xy 60.881162 -312.880017) (xy 60.896746 -312.926698) (xy 60.904641 -312.975275) (xy 60.905136 -312.999882)
			(xy 60.904641 -313.024489) (xy 60.904462 -313.02559) (xy 61.22314 -313.02559) (xy 61.22314 -312.974174)
			(xy 61.231183 -312.923392) (xy 61.247071 -312.874493) (xy 61.270414 -312.828681) (xy 61.300635 -312.787085)
			(xy 61.336991 -312.750729) (xy 61.378587 -312.720508) (xy 61.424399 -312.697165) (xy 61.473298 -312.681277)
			(xy 61.52408 -312.673234) (xy 61.575496 -312.673234) (xy 61.626278 -312.681277) (xy 61.675177 -312.697165)
			(xy 61.720989 -312.720508) (xy 61.762585 -312.750729) (xy 61.798941 -312.787085) (xy 61.829162 -312.828681)
			(xy 61.852505 -312.874493) (xy 61.868393 -312.923392) (xy 61.876436 -312.974174) (xy 61.87694 -312.999882)
			(xy 62.193944 -312.999882) (xy 62.197904 -312.950828) (xy 62.209681 -312.903044) (xy 62.228972 -312.857768)
			(xy 62.255275 -312.816172) (xy 62.28791 -312.779335) (xy 62.326031 -312.74821) (xy 62.368652 -312.723603)
			(xy 62.414668 -312.706151) (xy 62.462887 -312.696307) (xy 62.512062 -312.694326) (xy 62.560917 -312.700258)
			(xy 62.608188 -312.71395) (xy 62.65265 -312.735048) (xy 62.693153 -312.763004) (xy 62.728646 -312.797096)
			(xy 62.758211 -312.83644) (xy 62.781082 -312.880017) (xy 62.796666 -312.926698) (xy 62.804561 -312.975275)
			(xy 62.805056 -312.999882) (xy 62.804561 -313.024489) (xy 62.804382 -313.02559) (xy 63.123314 -313.02559)
			(xy 63.123314 -312.974174) (xy 63.131357 -312.923392) (xy 63.147245 -312.874493) (xy 63.170588 -312.828681)
			(xy 63.200809 -312.787085) (xy 63.237165 -312.750729) (xy 63.278761 -312.720508) (xy 63.324573 -312.697165)
			(xy 63.373472 -312.681277) (xy 63.424254 -312.673234) (xy 63.47567 -312.673234) (xy 63.526452 -312.681277)
			(xy 63.575351 -312.697165) (xy 63.621163 -312.720508) (xy 63.662759 -312.750729) (xy 63.699115 -312.787085)
			(xy 63.729336 -312.828681) (xy 63.752679 -312.874493) (xy 63.768567 -312.923392) (xy 63.77661 -312.974174)
			(xy 63.777114 -312.999882) (xy 64.094118 -312.999882) (xy 64.098078 -312.950828) (xy 64.109855 -312.903044)
			(xy 64.129146 -312.857768) (xy 64.155449 -312.816172) (xy 64.188084 -312.779335) (xy 64.226205 -312.74821)
			(xy 64.268826 -312.723603) (xy 64.314842 -312.706151) (xy 64.363061 -312.696307) (xy 64.412236 -312.694326)
			(xy 64.461091 -312.700258) (xy 64.508362 -312.71395) (xy 64.552824 -312.735048) (xy 64.593327 -312.763004)
			(xy 64.62882 -312.797096) (xy 64.658385 -312.83644) (xy 64.681256 -312.880017) (xy 64.69684 -312.926698)
			(xy 64.704735 -312.975275) (xy 64.70523 -312.999882) (xy 64.704735 -313.024489) (xy 64.704556 -313.02559)
			(xy 65.023234 -313.02559) (xy 65.023234 -312.974174) (xy 65.031277 -312.923392) (xy 65.047165 -312.874493)
			(xy 65.070508 -312.828681) (xy 65.100729 -312.787085) (xy 65.137085 -312.750729) (xy 65.178681 -312.720508)
			(xy 65.224493 -312.697165) (xy 65.273392 -312.681277) (xy 65.324174 -312.673234) (xy 65.37559 -312.673234)
			(xy 65.426372 -312.681277) (xy 65.475271 -312.697165) (xy 65.521083 -312.720508) (xy 65.562679 -312.750729)
			(xy 65.599035 -312.787085) (xy 65.629256 -312.828681) (xy 65.652599 -312.874493) (xy 65.668487 -312.923392)
			(xy 65.67653 -312.974174) (xy 65.677034 -312.999882) (xy 65.994038 -312.999882) (xy 65.997998 -312.950828)
			(xy 66.009775 -312.903044) (xy 66.029066 -312.857768) (xy 66.055369 -312.816172) (xy 66.088004 -312.779335)
			(xy 66.126125 -312.74821) (xy 66.168746 -312.723603) (xy 66.214762 -312.706151) (xy 66.262981 -312.696307)
			(xy 66.312156 -312.694326) (xy 66.361011 -312.700258) (xy 66.408282 -312.71395) (xy 66.452744 -312.735048)
			(xy 66.493247 -312.763004) (xy 66.52874 -312.797096) (xy 66.558305 -312.83644) (xy 66.581176 -312.880017)
			(xy 66.59676 -312.926698) (xy 66.604655 -312.975275) (xy 66.60515 -312.999882) (xy 66.604655 -313.024489)
			(xy 66.604476 -313.02559) (xy 66.923154 -313.02559) (xy 66.923154 -312.974174) (xy 66.931197 -312.923392)
			(xy 66.947085 -312.874493) (xy 66.970428 -312.828681) (xy 67.000649 -312.787085) (xy 67.037005 -312.750729)
			(xy 67.078601 -312.720508) (xy 67.124413 -312.697165) (xy 67.173312 -312.681277) (xy 67.224094 -312.673234)
			(xy 67.27551 -312.673234) (xy 67.326292 -312.681277) (xy 67.375191 -312.697165) (xy 67.421003 -312.720508)
			(xy 67.462599 -312.750729) (xy 67.498955 -312.787085) (xy 67.529176 -312.828681) (xy 67.552519 -312.874493)
			(xy 67.568407 -312.923392) (xy 67.57645 -312.974174) (xy 67.576954 -312.999882) (xy 67.893958 -312.999882)
			(xy 67.897918 -312.950828) (xy 67.909695 -312.903044) (xy 67.928986 -312.857768) (xy 67.955289 -312.816172)
			(xy 67.987924 -312.779335) (xy 68.026045 -312.74821) (xy 68.068666 -312.723603) (xy 68.114682 -312.706151)
			(xy 68.162901 -312.696307) (xy 68.212076 -312.694326) (xy 68.260931 -312.700258) (xy 68.308202 -312.71395)
			(xy 68.352664 -312.735048) (xy 68.393167 -312.763004) (xy 68.42866 -312.797096) (xy 68.458225 -312.83644)
			(xy 68.481096 -312.880017) (xy 68.49668 -312.926698) (xy 68.504575 -312.975275) (xy 68.50507 -312.999882)
			(xy 68.504575 -313.024489) (xy 68.504396 -313.02559) (xy 68.823328 -313.02559) (xy 68.823328 -312.974174)
			(xy 68.831371 -312.923392) (xy 68.847259 -312.874493) (xy 68.870602 -312.828681) (xy 68.900823 -312.787085)
			(xy 68.937179 -312.750729) (xy 68.978775 -312.720508) (xy 69.024587 -312.697165) (xy 69.073486 -312.681277)
			(xy 69.124268 -312.673234) (xy 69.175684 -312.673234) (xy 69.226466 -312.681277) (xy 69.275365 -312.697165)
			(xy 69.321177 -312.720508) (xy 69.362773 -312.750729) (xy 69.399129 -312.787085) (xy 69.42935 -312.828681)
			(xy 69.452693 -312.874493) (xy 69.468581 -312.923392) (xy 69.476624 -312.974174) (xy 69.477128 -312.999882)
			(xy 69.794132 -312.999882) (xy 69.798092 -312.950828) (xy 69.809869 -312.903044) (xy 69.82916 -312.857768)
			(xy 69.855463 -312.816172) (xy 69.888098 -312.779335) (xy 69.926219 -312.74821) (xy 69.96884 -312.723603)
			(xy 70.014856 -312.706151) (xy 70.063075 -312.696307) (xy 70.11225 -312.694326) (xy 70.161105 -312.700258)
			(xy 70.208376 -312.71395) (xy 70.252838 -312.735048) (xy 70.293341 -312.763004) (xy 70.328834 -312.797096)
			(xy 70.358399 -312.83644) (xy 70.38127 -312.880017) (xy 70.396854 -312.926698) (xy 70.404749 -312.975275)
			(xy 70.405244 -312.999882) (xy 70.404749 -313.024489) (xy 70.40457 -313.02559) (xy 70.723248 -313.02559)
			(xy 70.723248 -312.974174) (xy 70.731291 -312.923392) (xy 70.747179 -312.874493) (xy 70.770522 -312.828681)
			(xy 70.800743 -312.787085) (xy 70.837099 -312.750729) (xy 70.878695 -312.720508) (xy 70.924507 -312.697165)
			(xy 70.973406 -312.681277) (xy 71.024188 -312.673234) (xy 71.075604 -312.673234) (xy 71.126386 -312.681277)
			(xy 71.175285 -312.697165) (xy 71.221097 -312.720508) (xy 71.262693 -312.750729) (xy 71.299049 -312.787085)
			(xy 71.32927 -312.828681) (xy 71.352613 -312.874493) (xy 71.368501 -312.923392) (xy 71.376544 -312.974174)
			(xy 71.377048 -312.999882) (xy 71.694052 -312.999882) (xy 71.698012 -312.950828) (xy 71.709789 -312.903044)
			(xy 71.72908 -312.857768) (xy 71.755383 -312.816172) (xy 71.788018 -312.779335) (xy 71.826139 -312.74821)
			(xy 71.86876 -312.723603) (xy 71.914776 -312.706151) (xy 71.962995 -312.696307) (xy 72.01217 -312.694326)
			(xy 72.061025 -312.700258) (xy 72.108296 -312.71395) (xy 72.152758 -312.735048) (xy 72.193261 -312.763004)
			(xy 72.228754 -312.797096) (xy 72.258319 -312.83644) (xy 72.28119 -312.880017) (xy 72.296774 -312.926698)
			(xy 72.304669 -312.975275) (xy 72.305164 -312.999882) (xy 72.304669 -313.024489) (xy 72.30449 -313.02559)
			(xy 72.623168 -313.02559) (xy 72.623168 -312.974174) (xy 72.631211 -312.923392) (xy 72.647099 -312.874493)
			(xy 72.670442 -312.828681) (xy 72.700663 -312.787085) (xy 72.737019 -312.750729) (xy 72.778615 -312.720508)
			(xy 72.824427 -312.697165) (xy 72.873326 -312.681277) (xy 72.924108 -312.673234) (xy 72.975524 -312.673234)
			(xy 73.026306 -312.681277) (xy 73.075205 -312.697165) (xy 73.121017 -312.720508) (xy 73.162613 -312.750729)
			(xy 73.198969 -312.787085) (xy 73.22919 -312.828681) (xy 73.252533 -312.874493) (xy 73.268421 -312.923392)
			(xy 73.276464 -312.974174) (xy 73.276968 -312.999882) (xy 73.593972 -312.999882) (xy 73.597932 -312.950828)
			(xy 73.609709 -312.903044) (xy 73.629 -312.857768) (xy 73.655303 -312.816172) (xy 73.687938 -312.779335)
			(xy 73.726059 -312.74821) (xy 73.76868 -312.723603) (xy 73.814696 -312.706151) (xy 73.862915 -312.696307)
			(xy 73.91209 -312.694326) (xy 73.960945 -312.700258) (xy 74.008216 -312.71395) (xy 74.052678 -312.735048)
			(xy 74.093181 -312.763004) (xy 74.128674 -312.797096) (xy 74.158239 -312.83644) (xy 74.18111 -312.880017)
			(xy 74.196694 -312.926698) (xy 74.204589 -312.975275) (xy 74.205084 -312.999882) (xy 74.204589 -313.024489)
			(xy 74.20441 -313.02559) (xy 74.523342 -313.02559) (xy 74.523342 -312.974174) (xy 74.531385 -312.923392)
			(xy 74.547273 -312.874493) (xy 74.570616 -312.828681) (xy 74.600837 -312.787085) (xy 74.637193 -312.750729)
			(xy 74.678789 -312.720508) (xy 74.724601 -312.697165) (xy 74.7735 -312.681277) (xy 74.824282 -312.673234)
			(xy 74.875698 -312.673234) (xy 74.92648 -312.681277) (xy 74.975379 -312.697165) (xy 75.021191 -312.720508)
			(xy 75.062787 -312.750729) (xy 75.099143 -312.787085) (xy 75.129364 -312.828681) (xy 75.152707 -312.874493)
			(xy 75.168595 -312.923392) (xy 75.176638 -312.974174) (xy 75.177142 -312.999882) (xy 75.494146 -312.999882)
			(xy 75.498106 -312.950828) (xy 75.509883 -312.903044) (xy 75.529174 -312.857768) (xy 75.555477 -312.816172)
			(xy 75.588112 -312.779335) (xy 75.626233 -312.74821) (xy 75.668854 -312.723603) (xy 75.71487 -312.706151)
			(xy 75.763089 -312.696307) (xy 75.812264 -312.694326) (xy 75.861119 -312.700258) (xy 75.90839 -312.71395)
			(xy 75.952852 -312.735048) (xy 75.993355 -312.763004) (xy 76.028848 -312.797096) (xy 76.058413 -312.83644)
			(xy 76.081284 -312.880017) (xy 76.096868 -312.926698) (xy 76.104763 -312.975275) (xy 76.105258 -312.999882)
			(xy 76.104763 -313.024489) (xy 76.104584 -313.02559) (xy 76.423262 -313.02559) (xy 76.423262 -312.974174)
			(xy 76.431305 -312.923392) (xy 76.447193 -312.874493) (xy 76.470536 -312.828681) (xy 76.500757 -312.787085)
			(xy 76.537113 -312.750729) (xy 76.578709 -312.720508) (xy 76.624521 -312.697165) (xy 76.67342 -312.681277)
			(xy 76.724202 -312.673234) (xy 76.775618 -312.673234) (xy 76.8264 -312.681277) (xy 76.875299 -312.697165)
			(xy 76.921111 -312.720508) (xy 76.962707 -312.750729) (xy 76.999063 -312.787085) (xy 77.029284 -312.828681)
			(xy 77.052627 -312.874493) (xy 77.068515 -312.923392) (xy 77.076558 -312.974174) (xy 77.077062 -312.999882)
			(xy 77.394066 -312.999882) (xy 77.398026 -312.950828) (xy 77.409803 -312.903044) (xy 77.429094 -312.857768)
			(xy 77.455397 -312.816172) (xy 77.488032 -312.779335) (xy 77.526153 -312.74821) (xy 77.568774 -312.723603)
			(xy 77.61479 -312.706151) (xy 77.663009 -312.696307) (xy 77.712184 -312.694326) (xy 77.761039 -312.700258)
			(xy 77.80831 -312.71395) (xy 77.852772 -312.735048) (xy 77.893275 -312.763004) (xy 77.928768 -312.797096)
			(xy 77.958333 -312.83644) (xy 77.981204 -312.880017) (xy 77.996788 -312.926698) (xy 78.004683 -312.975275)
			(xy 78.005178 -312.999882) (xy 78.004683 -313.024489) (xy 77.996788 -313.073066) (xy 77.981204 -313.119747)
			(xy 77.958333 -313.163324) (xy 77.928768 -313.202668) (xy 77.893275 -313.23676) (xy 77.852772 -313.264716)
			(xy 77.80831 -313.285814) (xy 77.761039 -313.299506) (xy 77.712184 -313.305438) (xy 77.663009 -313.303457)
			(xy 77.61479 -313.293613) (xy 77.568774 -313.276161) (xy 77.526153 -313.251554) (xy 77.488032 -313.220429)
			(xy 77.455397 -313.183592) (xy 77.429094 -313.141996) (xy 77.409803 -313.09672) (xy 77.398026 -313.048936)
			(xy 77.394066 -312.999882) (xy 77.077062 -312.999882) (xy 77.076558 -313.02559) (xy 77.068515 -313.076372)
			(xy 77.052627 -313.125271) (xy 77.029284 -313.171083) (xy 76.999063 -313.212679) (xy 76.962707 -313.249035)
			(xy 76.921111 -313.279256) (xy 76.875299 -313.302599) (xy 76.8264 -313.318487) (xy 76.775618 -313.32653)
			(xy 76.724202 -313.32653) (xy 76.67342 -313.318487) (xy 76.624521 -313.302599) (xy 76.578709 -313.279256)
			(xy 76.537113 -313.249035) (xy 76.500757 -313.212679) (xy 76.470536 -313.171083) (xy 76.447193 -313.125271)
			(xy 76.431305 -313.076372) (xy 76.423262 -313.02559) (xy 76.104584 -313.02559) (xy 76.096868 -313.073066)
			(xy 76.081284 -313.119747) (xy 76.058413 -313.163324) (xy 76.028848 -313.202668) (xy 75.993355 -313.23676)
			(xy 75.952852 -313.264716) (xy 75.90839 -313.285814) (xy 75.861119 -313.299506) (xy 75.812264 -313.305438)
			(xy 75.763089 -313.303457) (xy 75.71487 -313.293613) (xy 75.668854 -313.276161) (xy 75.626233 -313.251554)
			(xy 75.588112 -313.220429) (xy 75.555477 -313.183592) (xy 75.529174 -313.141996) (xy 75.509883 -313.09672)
			(xy 75.498106 -313.048936) (xy 75.494146 -312.999882) (xy 75.177142 -312.999882) (xy 75.176638 -313.02559)
			(xy 75.168595 -313.076372) (xy 75.152707 -313.125271) (xy 75.129364 -313.171083) (xy 75.099143 -313.212679)
			(xy 75.062787 -313.249035) (xy 75.021191 -313.279256) (xy 74.975379 -313.302599) (xy 74.92648 -313.318487)
			(xy 74.875698 -313.32653) (xy 74.824282 -313.32653) (xy 74.7735 -313.318487) (xy 74.724601 -313.302599)
			(xy 74.678789 -313.279256) (xy 74.637193 -313.249035) (xy 74.600837 -313.212679) (xy 74.570616 -313.171083)
			(xy 74.547273 -313.125271) (xy 74.531385 -313.076372) (xy 74.523342 -313.02559) (xy 74.20441 -313.02559)
			(xy 74.196694 -313.073066) (xy 74.18111 -313.119747) (xy 74.158239 -313.163324) (xy 74.128674 -313.202668)
			(xy 74.093181 -313.23676) (xy 74.052678 -313.264716) (xy 74.008216 -313.285814) (xy 73.960945 -313.299506)
			(xy 73.91209 -313.305438) (xy 73.862915 -313.303457) (xy 73.814696 -313.293613) (xy 73.76868 -313.276161)
			(xy 73.726059 -313.251554) (xy 73.687938 -313.220429) (xy 73.655303 -313.183592) (xy 73.629 -313.141996)
			(xy 73.609709 -313.09672) (xy 73.597932 -313.048936) (xy 73.593972 -312.999882) (xy 73.276968 -312.999882)
			(xy 73.276464 -313.02559) (xy 73.268421 -313.076372) (xy 73.252533 -313.125271) (xy 73.22919 -313.171083)
			(xy 73.198969 -313.212679) (xy 73.162613 -313.249035) (xy 73.121017 -313.279256) (xy 73.075205 -313.302599)
			(xy 73.026306 -313.318487) (xy 72.975524 -313.32653) (xy 72.924108 -313.32653) (xy 72.873326 -313.318487)
			(xy 72.824427 -313.302599) (xy 72.778615 -313.279256) (xy 72.737019 -313.249035) (xy 72.700663 -313.212679)
			(xy 72.670442 -313.171083) (xy 72.647099 -313.125271) (xy 72.631211 -313.076372) (xy 72.623168 -313.02559)
			(xy 72.30449 -313.02559) (xy 72.296774 -313.073066) (xy 72.28119 -313.119747) (xy 72.258319 -313.163324)
			(xy 72.228754 -313.202668) (xy 72.193261 -313.23676) (xy 72.152758 -313.264716) (xy 72.108296 -313.285814)
			(xy 72.061025 -313.299506) (xy 72.01217 -313.305438) (xy 71.962995 -313.303457) (xy 71.914776 -313.293613)
			(xy 71.86876 -313.276161) (xy 71.826139 -313.251554) (xy 71.788018 -313.220429) (xy 71.755383 -313.183592)
			(xy 71.72908 -313.141996) (xy 71.709789 -313.09672) (xy 71.698012 -313.048936) (xy 71.694052 -312.999882)
			(xy 71.377048 -312.999882) (xy 71.376544 -313.02559) (xy 71.368501 -313.076372) (xy 71.352613 -313.125271)
			(xy 71.32927 -313.171083) (xy 71.299049 -313.212679) (xy 71.262693 -313.249035) (xy 71.221097 -313.279256)
			(xy 71.175285 -313.302599) (xy 71.126386 -313.318487) (xy 71.075604 -313.32653) (xy 71.024188 -313.32653)
			(xy 70.973406 -313.318487) (xy 70.924507 -313.302599) (xy 70.878695 -313.279256) (xy 70.837099 -313.249035)
			(xy 70.800743 -313.212679) (xy 70.770522 -313.171083) (xy 70.747179 -313.125271) (xy 70.731291 -313.076372)
			(xy 70.723248 -313.02559) (xy 70.40457 -313.02559) (xy 70.396854 -313.073066) (xy 70.38127 -313.119747)
			(xy 70.358399 -313.163324) (xy 70.328834 -313.202668) (xy 70.293341 -313.23676) (xy 70.252838 -313.264716)
			(xy 70.208376 -313.285814) (xy 70.161105 -313.299506) (xy 70.11225 -313.305438) (xy 70.063075 -313.303457)
			(xy 70.014856 -313.293613) (xy 69.96884 -313.276161) (xy 69.926219 -313.251554) (xy 69.888098 -313.220429)
			(xy 69.855463 -313.183592) (xy 69.82916 -313.141996) (xy 69.809869 -313.09672) (xy 69.798092 -313.048936)
			(xy 69.794132 -312.999882) (xy 69.477128 -312.999882) (xy 69.476624 -313.02559) (xy 69.468581 -313.076372)
			(xy 69.452693 -313.125271) (xy 69.42935 -313.171083) (xy 69.399129 -313.212679) (xy 69.362773 -313.249035)
			(xy 69.321177 -313.279256) (xy 69.275365 -313.302599) (xy 69.226466 -313.318487) (xy 69.175684 -313.32653)
			(xy 69.124268 -313.32653) (xy 69.073486 -313.318487) (xy 69.024587 -313.302599) (xy 68.978775 -313.279256)
			(xy 68.937179 -313.249035) (xy 68.900823 -313.212679) (xy 68.870602 -313.171083) (xy 68.847259 -313.125271)
			(xy 68.831371 -313.076372) (xy 68.823328 -313.02559) (xy 68.504396 -313.02559) (xy 68.49668 -313.073066)
			(xy 68.481096 -313.119747) (xy 68.458225 -313.163324) (xy 68.42866 -313.202668) (xy 68.393167 -313.23676)
			(xy 68.352664 -313.264716) (xy 68.308202 -313.285814) (xy 68.260931 -313.299506) (xy 68.212076 -313.305438)
			(xy 68.162901 -313.303457) (xy 68.114682 -313.293613) (xy 68.068666 -313.276161) (xy 68.026045 -313.251554)
			(xy 67.987924 -313.220429) (xy 67.955289 -313.183592) (xy 67.928986 -313.141996) (xy 67.909695 -313.09672)
			(xy 67.897918 -313.048936) (xy 67.893958 -312.999882) (xy 67.576954 -312.999882) (xy 67.57645 -313.02559)
			(xy 67.568407 -313.076372) (xy 67.552519 -313.125271) (xy 67.529176 -313.171083) (xy 67.498955 -313.212679)
			(xy 67.462599 -313.249035) (xy 67.421003 -313.279256) (xy 67.375191 -313.302599) (xy 67.326292 -313.318487)
			(xy 67.27551 -313.32653) (xy 67.224094 -313.32653) (xy 67.173312 -313.318487) (xy 67.124413 -313.302599)
			(xy 67.078601 -313.279256) (xy 67.037005 -313.249035) (xy 67.000649 -313.212679) (xy 66.970428 -313.171083)
			(xy 66.947085 -313.125271) (xy 66.931197 -313.076372) (xy 66.923154 -313.02559) (xy 66.604476 -313.02559)
			(xy 66.59676 -313.073066) (xy 66.581176 -313.119747) (xy 66.558305 -313.163324) (xy 66.52874 -313.202668)
			(xy 66.493247 -313.23676) (xy 66.452744 -313.264716) (xy 66.408282 -313.285814) (xy 66.361011 -313.299506)
			(xy 66.312156 -313.305438) (xy 66.262981 -313.303457) (xy 66.214762 -313.293613) (xy 66.168746 -313.276161)
			(xy 66.126125 -313.251554) (xy 66.088004 -313.220429) (xy 66.055369 -313.183592) (xy 66.029066 -313.141996)
			(xy 66.009775 -313.09672) (xy 65.997998 -313.048936) (xy 65.994038 -312.999882) (xy 65.677034 -312.999882)
			(xy 65.67653 -313.02559) (xy 65.668487 -313.076372) (xy 65.652599 -313.125271) (xy 65.629256 -313.171083)
			(xy 65.599035 -313.212679) (xy 65.562679 -313.249035) (xy 65.521083 -313.279256) (xy 65.475271 -313.302599)
			(xy 65.426372 -313.318487) (xy 65.37559 -313.32653) (xy 65.324174 -313.32653) (xy 65.273392 -313.318487)
			(xy 65.224493 -313.302599) (xy 65.178681 -313.279256) (xy 65.137085 -313.249035) (xy 65.100729 -313.212679)
			(xy 65.070508 -313.171083) (xy 65.047165 -313.125271) (xy 65.031277 -313.076372) (xy 65.023234 -313.02559)
			(xy 64.704556 -313.02559) (xy 64.69684 -313.073066) (xy 64.681256 -313.119747) (xy 64.658385 -313.163324)
			(xy 64.62882 -313.202668) (xy 64.593327 -313.23676) (xy 64.552824 -313.264716) (xy 64.508362 -313.285814)
			(xy 64.461091 -313.299506) (xy 64.412236 -313.305438) (xy 64.363061 -313.303457) (xy 64.314842 -313.293613)
			(xy 64.268826 -313.276161) (xy 64.226205 -313.251554) (xy 64.188084 -313.220429) (xy 64.155449 -313.183592)
			(xy 64.129146 -313.141996) (xy 64.109855 -313.09672) (xy 64.098078 -313.048936) (xy 64.094118 -312.999882)
			(xy 63.777114 -312.999882) (xy 63.77661 -313.02559) (xy 63.768567 -313.076372) (xy 63.752679 -313.125271)
			(xy 63.729336 -313.171083) (xy 63.699115 -313.212679) (xy 63.662759 -313.249035) (xy 63.621163 -313.279256)
			(xy 63.575351 -313.302599) (xy 63.526452 -313.318487) (xy 63.47567 -313.32653) (xy 63.424254 -313.32653)
			(xy 63.373472 -313.318487) (xy 63.324573 -313.302599) (xy 63.278761 -313.279256) (xy 63.237165 -313.249035)
			(xy 63.200809 -313.212679) (xy 63.170588 -313.171083) (xy 63.147245 -313.125271) (xy 63.131357 -313.076372)
			(xy 63.123314 -313.02559) (xy 62.804382 -313.02559) (xy 62.796666 -313.073066) (xy 62.781082 -313.119747)
			(xy 62.758211 -313.163324) (xy 62.728646 -313.202668) (xy 62.693153 -313.23676) (xy 62.65265 -313.264716)
			(xy 62.608188 -313.285814) (xy 62.560917 -313.299506) (xy 62.512062 -313.305438) (xy 62.462887 -313.303457)
			(xy 62.414668 -313.293613) (xy 62.368652 -313.276161) (xy 62.326031 -313.251554) (xy 62.28791 -313.220429)
			(xy 62.255275 -313.183592) (xy 62.228972 -313.141996) (xy 62.209681 -313.09672) (xy 62.197904 -313.048936)
			(xy 62.193944 -312.999882) (xy 61.87694 -312.999882) (xy 61.876436 -313.02559) (xy 61.868393 -313.076372)
			(xy 61.852505 -313.125271) (xy 61.829162 -313.171083) (xy 61.798941 -313.212679) (xy 61.762585 -313.249035)
			(xy 61.720989 -313.279256) (xy 61.675177 -313.302599) (xy 61.626278 -313.318487) (xy 61.575496 -313.32653)
			(xy 61.52408 -313.32653) (xy 61.473298 -313.318487) (xy 61.424399 -313.302599) (xy 61.378587 -313.279256)
			(xy 61.336991 -313.249035) (xy 61.300635 -313.212679) (xy 61.270414 -313.171083) (xy 61.247071 -313.125271)
			(xy 61.231183 -313.076372) (xy 61.22314 -313.02559) (xy 60.904462 -313.02559) (xy 60.896746 -313.073066)
			(xy 60.881162 -313.119747) (xy 60.858291 -313.163324) (xy 60.828726 -313.202668) (xy 60.793233 -313.23676)
			(xy 60.75273 -313.264716) (xy 60.708268 -313.285814) (xy 60.660997 -313.299506) (xy 60.612142 -313.305438)
			(xy 60.562967 -313.303457) (xy 60.514748 -313.293613) (xy 60.468732 -313.276161) (xy 60.426111 -313.251554)
			(xy 60.38799 -313.220429) (xy 60.355355 -313.183592) (xy 60.329052 -313.141996) (xy 60.309761 -313.09672)
			(xy 60.297984 -313.048936) (xy 60.294024 -312.999882) (xy 59.97702 -312.999882) (xy 59.976516 -313.02559)
			(xy 59.968473 -313.076372) (xy 59.952585 -313.125271) (xy 59.929242 -313.171083) (xy 59.899021 -313.212679)
			(xy 59.862665 -313.249035) (xy 59.821069 -313.279256) (xy 59.775257 -313.302599) (xy 59.726358 -313.318487)
			(xy 59.675576 -313.32653) (xy 59.62416 -313.32653) (xy 59.573378 -313.318487) (xy 59.524479 -313.302599)
			(xy 59.478667 -313.279256) (xy 59.437071 -313.249035) (xy 59.400715 -313.212679) (xy 59.370494 -313.171083)
			(xy 59.347151 -313.125271) (xy 59.331263 -313.076372) (xy 59.32322 -313.02559) (xy 59.004542 -313.02559)
			(xy 58.996826 -313.073066) (xy 58.981242 -313.119747) (xy 58.958371 -313.163324) (xy 58.928806 -313.202668)
			(xy 58.893313 -313.23676) (xy 58.85281 -313.264716) (xy 58.808348 -313.285814) (xy 58.761077 -313.299506)
			(xy 58.712222 -313.305438) (xy 58.663047 -313.303457) (xy 58.614828 -313.293613) (xy 58.568812 -313.276161)
			(xy 58.526191 -313.251554) (xy 58.48807 -313.220429) (xy 58.455435 -313.183592) (xy 58.429132 -313.141996)
			(xy 58.409841 -313.09672) (xy 58.398064 -313.048936) (xy 58.394104 -312.999882) (xy 58.0771 -312.999882)
			(xy 58.076596 -313.02559) (xy 58.068553 -313.076372) (xy 58.052665 -313.125271) (xy 58.029322 -313.171083)
			(xy 57.999101 -313.212679) (xy 57.962745 -313.249035) (xy 57.921149 -313.279256) (xy 57.875337 -313.302599)
			(xy 57.826438 -313.318487) (xy 57.775656 -313.32653) (xy 57.72424 -313.32653) (xy 57.673458 -313.318487)
			(xy 57.624559 -313.302599) (xy 57.578747 -313.279256) (xy 57.537151 -313.249035) (xy 57.500795 -313.212679)
			(xy 57.470574 -313.171083) (xy 57.447231 -313.125271) (xy 57.431343 -313.076372) (xy 57.4233 -313.02559)
			(xy 57.104622 -313.02559) (xy 57.096906 -313.073066) (xy 57.081322 -313.119747) (xy 57.058451 -313.163324)
			(xy 57.028886 -313.202668) (xy 56.993393 -313.23676) (xy 56.95289 -313.264716) (xy 56.908428 -313.285814)
			(xy 56.861157 -313.299506) (xy 56.812302 -313.305438) (xy 56.763127 -313.303457) (xy 56.714908 -313.293613)
			(xy 56.668892 -313.276161) (xy 56.626271 -313.251554) (xy 56.58815 -313.220429) (xy 56.555515 -313.183592)
			(xy 56.529212 -313.141996) (xy 56.509921 -313.09672) (xy 56.498144 -313.048936) (xy 56.494184 -312.999882)
			(xy 56.176926 -312.999882) (xy 56.176422 -313.02559) (xy 56.168379 -313.076372) (xy 56.152491 -313.125271)
			(xy 56.129148 -313.171083) (xy 56.098927 -313.212679) (xy 56.062571 -313.249035) (xy 56.020975 -313.279256)
			(xy 55.975163 -313.302599) (xy 55.926264 -313.318487) (xy 55.875482 -313.32653) (xy 55.824066 -313.32653)
			(xy 55.773284 -313.318487) (xy 55.724385 -313.302599) (xy 55.678573 -313.279256) (xy 55.636977 -313.249035)
			(xy 55.600621 -313.212679) (xy 55.5704 -313.171083) (xy 55.547057 -313.125271) (xy 55.531169 -313.076372)
			(xy 55.523126 -313.02559) (xy 55.204448 -313.02559) (xy 55.196732 -313.073066) (xy 55.181148 -313.119747)
			(xy 55.158277 -313.163324) (xy 55.128712 -313.202668) (xy 55.093219 -313.23676) (xy 55.052716 -313.264716)
			(xy 55.008254 -313.285814) (xy 54.960983 -313.299506) (xy 54.912128 -313.305438) (xy 54.862953 -313.303457)
			(xy 54.814734 -313.293613) (xy 54.768718 -313.276161) (xy 54.726097 -313.251554) (xy 54.687976 -313.220429)
			(xy 54.655341 -313.183592) (xy 54.629038 -313.141996) (xy 54.609747 -313.09672) (xy 54.59797 -313.048936)
			(xy 54.59401 -312.999882) (xy 54.277006 -312.999882) (xy 54.276502 -313.02559) (xy 54.268459 -313.076372)
			(xy 54.252571 -313.125271) (xy 54.229228 -313.171083) (xy 54.199007 -313.212679) (xy 54.162651 -313.249035)
			(xy 54.121055 -313.279256) (xy 54.075243 -313.302599) (xy 54.026344 -313.318487) (xy 53.975562 -313.32653)
			(xy 53.924146 -313.32653) (xy 53.873364 -313.318487) (xy 53.824465 -313.302599) (xy 53.778653 -313.279256)
			(xy 53.737057 -313.249035) (xy 53.700701 -313.212679) (xy 53.67048 -313.171083) (xy 53.647137 -313.125271)
			(xy 53.631249 -313.076372) (xy 53.623206 -313.02559) (xy 53.304528 -313.02559) (xy 53.296812 -313.073066)
			(xy 53.281228 -313.119747) (xy 53.258357 -313.163324) (xy 53.228792 -313.202668) (xy 53.193299 -313.23676)
			(xy 53.152796 -313.264716) (xy 53.108334 -313.285814) (xy 53.061063 -313.299506) (xy 53.012208 -313.305438)
			(xy 52.963033 -313.303457) (xy 52.914814 -313.293613) (xy 52.868798 -313.276161) (xy 52.826177 -313.251554)
			(xy 52.788056 -313.220429) (xy 52.755421 -313.183592) (xy 52.729118 -313.141996) (xy 52.709827 -313.09672)
			(xy 52.69805 -313.048936) (xy 52.69409 -312.999882) (xy 52.377086 -312.999882) (xy 52.376582 -313.02559)
			(xy 52.368539 -313.076372) (xy 52.352651 -313.125271) (xy 52.329308 -313.171083) (xy 52.299087 -313.212679)
			(xy 52.262731 -313.249035) (xy 52.221135 -313.279256) (xy 52.175323 -313.302599) (xy 52.126424 -313.318487)
			(xy 52.075642 -313.32653) (xy 52.024226 -313.32653) (xy 51.973444 -313.318487) (xy 51.924545 -313.302599)
			(xy 51.878733 -313.279256) (xy 51.837137 -313.249035) (xy 51.800781 -313.212679) (xy 51.77056 -313.171083)
			(xy 51.747217 -313.125271) (xy 51.731329 -313.076372) (xy 51.723286 -313.02559) (xy 51.404608 -313.02559)
			(xy 51.396892 -313.073066) (xy 51.381308 -313.119747) (xy 51.358437 -313.163324) (xy 51.328872 -313.202668)
			(xy 51.293379 -313.23676) (xy 51.252876 -313.264716) (xy 51.208414 -313.285814) (xy 51.161143 -313.299506)
			(xy 51.112288 -313.305438) (xy 51.063113 -313.303457) (xy 51.014894 -313.293613) (xy 50.968878 -313.276161)
			(xy 50.926257 -313.251554) (xy 50.888136 -313.220429) (xy 50.855501 -313.183592) (xy 50.829198 -313.141996)
			(xy 50.809907 -313.09672) (xy 50.79813 -313.048936) (xy 50.79417 -312.999882) (xy 50.476912 -312.999882)
			(xy 50.476408 -313.02559) (xy 50.468365 -313.076372) (xy 50.452477 -313.125271) (xy 50.429134 -313.171083)
			(xy 50.398913 -313.212679) (xy 50.362557 -313.249035) (xy 50.320961 -313.279256) (xy 50.275149 -313.302599)
			(xy 50.22625 -313.318487) (xy 50.175468 -313.32653) (xy 50.124052 -313.32653) (xy 50.07327 -313.318487)
			(xy 50.024371 -313.302599) (xy 49.978559 -313.279256) (xy 49.936963 -313.249035) (xy 49.900607 -313.212679)
			(xy 49.870386 -313.171083) (xy 49.847043 -313.125271) (xy 49.831155 -313.076372) (xy 49.823112 -313.02559)
			(xy 49.504434 -313.02559) (xy 49.496718 -313.073066) (xy 49.481134 -313.119747) (xy 49.458263 -313.163324)
			(xy 49.428698 -313.202668) (xy 49.393205 -313.23676) (xy 49.352702 -313.264716) (xy 49.30824 -313.285814)
			(xy 49.260969 -313.299506) (xy 49.212114 -313.305438) (xy 49.162939 -313.303457) (xy 49.11472 -313.293613)
			(xy 49.068704 -313.276161) (xy 49.026083 -313.251554) (xy 48.987962 -313.220429) (xy 48.955327 -313.183592)
			(xy 48.929024 -313.141996) (xy 48.909733 -313.09672) (xy 48.897956 -313.048936) (xy 48.893996 -312.999882)
			(xy 48.576992 -312.999882) (xy 48.576488 -313.02559) (xy 48.568445 -313.076372) (xy 48.552557 -313.125271)
			(xy 48.529214 -313.171083) (xy 48.498993 -313.212679) (xy 48.462637 -313.249035) (xy 48.421041 -313.279256)
			(xy 48.375229 -313.302599) (xy 48.32633 -313.318487) (xy 48.275548 -313.32653) (xy 48.224132 -313.32653)
			(xy 48.17335 -313.318487) (xy 48.124451 -313.302599) (xy 48.078639 -313.279256) (xy 48.037043 -313.249035)
			(xy 48.000687 -313.212679) (xy 47.970466 -313.171083) (xy 47.947123 -313.125271) (xy 47.931235 -313.076372)
			(xy 47.923192 -313.02559) (xy 47.604514 -313.02559) (xy 47.596798 -313.073066) (xy 47.581214 -313.119747)
			(xy 47.558343 -313.163324) (xy 47.528778 -313.202668) (xy 47.493285 -313.23676) (xy 47.452782 -313.264716)
			(xy 47.40832 -313.285814) (xy 47.361049 -313.299506) (xy 47.312194 -313.305438) (xy 47.263019 -313.303457)
			(xy 47.2148 -313.293613) (xy 47.168784 -313.276161) (xy 47.126163 -313.251554) (xy 47.088042 -313.220429)
			(xy 47.055407 -313.183592) (xy 47.029104 -313.141996) (xy 47.009813 -313.09672) (xy 46.998036 -313.048936)
			(xy 46.994076 -312.999882) (xy 46.677072 -312.999882) (xy 46.676568 -313.02559) (xy 46.668525 -313.076372)
			(xy 46.652637 -313.125271) (xy 46.629294 -313.171083) (xy 46.599073 -313.212679) (xy 46.562717 -313.249035)
			(xy 46.521121 -313.279256) (xy 46.475309 -313.302599) (xy 46.42641 -313.318487) (xy 46.375628 -313.32653)
			(xy 46.324212 -313.32653) (xy 46.27343 -313.318487) (xy 46.224531 -313.302599) (xy 46.178719 -313.279256)
			(xy 46.137123 -313.249035) (xy 46.100767 -313.212679) (xy 46.070546 -313.171083) (xy 46.047203 -313.125271)
			(xy 46.031315 -313.076372) (xy 46.023272 -313.02559) (xy 45.704594 -313.02559) (xy 45.696878 -313.073066)
			(xy 45.681294 -313.119747) (xy 45.658423 -313.163324) (xy 45.628858 -313.202668) (xy 45.593365 -313.23676)
			(xy 45.552862 -313.264716) (xy 45.5084 -313.285814) (xy 45.461129 -313.299506) (xy 45.412274 -313.305438)
			(xy 45.363099 -313.303457) (xy 45.31488 -313.293613) (xy 45.268864 -313.276161) (xy 45.226243 -313.251554)
			(xy 45.188122 -313.220429) (xy 45.155487 -313.183592) (xy 45.129184 -313.141996) (xy 45.109893 -313.09672)
			(xy 45.098116 -313.048936) (xy 45.094156 -312.999882) (xy 44.776898 -312.999882) (xy 44.776394 -313.02559)
			(xy 44.768351 -313.076372) (xy 44.752463 -313.125271) (xy 44.72912 -313.171083) (xy 44.698899 -313.212679)
			(xy 44.662543 -313.249035) (xy 44.620947 -313.279256) (xy 44.575135 -313.302599) (xy 44.526236 -313.318487)
			(xy 44.475454 -313.32653) (xy 44.424038 -313.32653) (xy 44.373256 -313.318487) (xy 44.324357 -313.302599)
			(xy 44.278545 -313.279256) (xy 44.236949 -313.249035) (xy 44.200593 -313.212679) (xy 44.170372 -313.171083)
			(xy 44.147029 -313.125271) (xy 44.131141 -313.076372) (xy 44.123098 -313.02559) (xy 43.80442 -313.02559)
			(xy 43.796704 -313.073066) (xy 43.78112 -313.119747) (xy 43.758249 -313.163324) (xy 43.728684 -313.202668)
			(xy 43.693191 -313.23676) (xy 43.652688 -313.264716) (xy 43.608226 -313.285814) (xy 43.560955 -313.299506)
			(xy 43.5121 -313.305438) (xy 43.462925 -313.303457) (xy 43.414706 -313.293613) (xy 43.36869 -313.276161)
			(xy 43.326069 -313.251554) (xy 43.287948 -313.220429) (xy 43.255313 -313.183592) (xy 43.22901 -313.141996)
			(xy 43.209719 -313.09672) (xy 43.197942 -313.048936) (xy 43.193982 -312.999882) (xy 42.876978 -312.999882)
			(xy 42.876474 -313.02559) (xy 42.868431 -313.076372) (xy 42.852543 -313.125271) (xy 42.8292 -313.171083)
			(xy 42.798979 -313.212679) (xy 42.762623 -313.249035) (xy 42.721027 -313.279256) (xy 42.675215 -313.302599)
			(xy 42.626316 -313.318487) (xy 42.575534 -313.32653) (xy 42.524118 -313.32653) (xy 42.473336 -313.318487)
			(xy 42.424437 -313.302599) (xy 42.378625 -313.279256) (xy 42.337029 -313.249035) (xy 42.300673 -313.212679)
			(xy 42.270452 -313.171083) (xy 42.247109 -313.125271) (xy 42.231221 -313.076372) (xy 42.223178 -313.02559)
			(xy 41.9045 -313.02559) (xy 41.896784 -313.073066) (xy 41.8812 -313.119747) (xy 41.858329 -313.163324)
			(xy 41.828764 -313.202668) (xy 41.793271 -313.23676) (xy 41.752768 -313.264716) (xy 41.708306 -313.285814)
			(xy 41.661035 -313.299506) (xy 41.61218 -313.305438) (xy 41.563005 -313.303457) (xy 41.514786 -313.293613)
			(xy 41.46877 -313.276161) (xy 41.426149 -313.251554) (xy 41.388028 -313.220429) (xy 41.355393 -313.183592)
			(xy 41.32909 -313.141996) (xy 41.309799 -313.09672) (xy 41.298022 -313.048936) (xy 41.294062 -312.999882)
			(xy 40.977058 -312.999882) (xy 40.976554 -313.02559) (xy 40.968511 -313.076372) (xy 40.952623 -313.125271)
			(xy 40.92928 -313.171083) (xy 40.899059 -313.212679) (xy 40.862703 -313.249035) (xy 40.821107 -313.279256)
			(xy 40.775295 -313.302599) (xy 40.726396 -313.318487) (xy 40.675614 -313.32653) (xy 40.624198 -313.32653)
			(xy 40.573416 -313.318487) (xy 40.524517 -313.302599) (xy 40.478705 -313.279256) (xy 40.437109 -313.249035)
			(xy 40.400753 -313.212679) (xy 40.370532 -313.171083) (xy 40.347189 -313.125271) (xy 40.331301 -313.076372)
			(xy 40.323258 -313.02559) (xy 40.00458 -313.02559) (xy 39.996864 -313.073066) (xy 39.98128 -313.119747)
			(xy 39.958409 -313.163324) (xy 39.928844 -313.202668) (xy 39.893351 -313.23676) (xy 39.852848 -313.264716)
			(xy 39.808386 -313.285814) (xy 39.761115 -313.299506) (xy 39.71226 -313.305438) (xy 39.663085 -313.303457)
			(xy 39.614866 -313.293613) (xy 39.56885 -313.276161) (xy 39.526229 -313.251554) (xy 39.488108 -313.220429)
			(xy 39.455473 -313.183592) (xy 39.42917 -313.141996) (xy 39.409879 -313.09672) (xy 39.398102 -313.048936)
			(xy 39.394142 -312.999882) (xy 39.077138 -312.999882) (xy 39.076634 -313.02559) (xy 39.068591 -313.076372)
			(xy 39.052703 -313.125271) (xy 39.02936 -313.171083) (xy 38.999139 -313.212679) (xy 38.962783 -313.249035)
			(xy 38.921187 -313.279256) (xy 38.875375 -313.302599) (xy 38.826476 -313.318487) (xy 38.775694 -313.32653)
			(xy 38.724278 -313.32653) (xy 38.673496 -313.318487) (xy 38.624597 -313.302599) (xy 38.578785 -313.279256)
			(xy 38.537189 -313.249035) (xy 38.500833 -313.212679) (xy 38.470612 -313.171083) (xy 38.447269 -313.125271)
			(xy 38.431381 -313.076372) (xy 38.423338 -313.02559) (xy 38.104406 -313.02559) (xy 38.09669 -313.073066)
			(xy 38.081106 -313.119747) (xy 38.058235 -313.163324) (xy 38.02867 -313.202668) (xy 37.993177 -313.23676)
			(xy 37.952674 -313.264716) (xy 37.908212 -313.285814) (xy 37.860941 -313.299506) (xy 37.812086 -313.305438)
			(xy 37.762911 -313.303457) (xy 37.714692 -313.293613) (xy 37.668676 -313.276161) (xy 37.626055 -313.251554)
			(xy 37.587934 -313.220429) (xy 37.555299 -313.183592) (xy 37.528996 -313.141996) (xy 37.509705 -313.09672)
			(xy 37.497928 -313.048936) (xy 37.493968 -312.999882) (xy 37.15512 -312.999882) (xy 37.154625 -313.024489)
			(xy 37.14673 -313.073066) (xy 37.131146 -313.119747) (xy 37.108275 -313.163324) (xy 37.07871 -313.202668)
			(xy 37.043217 -313.23676) (xy 37.002714 -313.264716) (xy 36.958252 -313.285814) (xy 36.910981 -313.299506)
			(xy 36.862126 -313.305438) (xy 36.812951 -313.303457) (xy 36.764732 -313.293613) (xy 36.718716 -313.276161)
			(xy 36.676095 -313.251554) (xy 36.637974 -313.220429) (xy 36.605339 -313.183592) (xy 36.579036 -313.141996)
			(xy 36.559745 -313.09672) (xy 36.547968 -313.048936) (xy 36.544008 -312.999882) (xy 17.71396 -312.999882)
			(xy 17.71396 -313.669934) (xy 34.021774 -313.669934) (xy 34.025845 -313.614312) (xy 34.037971 -313.559875)
			(xy 34.057894 -313.507784) (xy 34.08519 -313.459149) (xy 34.119276 -313.415006) (xy 34.159425 -313.376297)
			(xy 34.204783 -313.343846) (xy 34.254383 -313.318345) (xy 34.307167 -313.300338) (xy 34.36201 -313.290208)
			(xy 34.417744 -313.288171) (xy 34.473181 -313.294271) (xy 34.527138 -313.308377) (xy 34.578467 -313.330189)
			(xy 34.626073 -313.359243) (xy 34.668941 -313.394918) (xy 34.706158 -313.436455) (xy 34.736931 -313.482968)
			(xy 34.760603 -313.533465) (xy 34.776671 -313.586872) (xy 34.784791 -313.642048) (xy 34.7853 -313.669934)
			(xy 34.784791 -313.69782) (xy 34.776671 -313.752996) (xy 34.760603 -313.806403) (xy 34.736931 -313.8569)
			(xy 34.706158 -313.903413) (xy 34.668941 -313.94495) (xy 34.663063 -313.949842) (xy 36.544008 -313.949842)
			(xy 36.547968 -313.900788) (xy 36.559745 -313.853004) (xy 36.579036 -313.807728) (xy 36.605339 -313.766132)
			(xy 36.637974 -313.729295) (xy 36.676095 -313.69817) (xy 36.718716 -313.673563) (xy 36.764732 -313.656111)
			(xy 36.812951 -313.646267) (xy 36.862126 -313.644286) (xy 36.910981 -313.650218) (xy 36.958252 -313.66391)
			(xy 37.002714 -313.685008) (xy 37.043217 -313.712964) (xy 37.07871 -313.747056) (xy 37.108275 -313.7864)
			(xy 37.131146 -313.829977) (xy 37.14673 -313.876658) (xy 37.154625 -313.925235) (xy 37.15512 -313.949842)
			(xy 37.493968 -313.949842) (xy 37.497928 -313.900788) (xy 37.509705 -313.853004) (xy 37.528996 -313.807728)
			(xy 37.555299 -313.766132) (xy 37.587934 -313.729295) (xy 37.626055 -313.69817) (xy 37.668676 -313.673563)
			(xy 37.714692 -313.656111) (xy 37.762911 -313.646267) (xy 37.812086 -313.644286) (xy 37.860941 -313.650218)
			(xy 37.908212 -313.66391) (xy 37.952674 -313.685008) (xy 37.993177 -313.712964) (xy 38.02867 -313.747056)
			(xy 38.058235 -313.7864) (xy 38.081106 -313.829977) (xy 38.09669 -313.876658) (xy 38.104585 -313.925235)
			(xy 38.10508 -313.949842) (xy 38.104585 -313.974449) (xy 38.104406 -313.97555) (xy 38.423338 -313.97555)
			(xy 38.423338 -313.924134) (xy 38.431381 -313.873352) (xy 38.447269 -313.824453) (xy 38.470612 -313.778641)
			(xy 38.500833 -313.737045) (xy 38.537189 -313.700689) (xy 38.578785 -313.670468) (xy 38.624597 -313.647125)
			(xy 38.673496 -313.631237) (xy 38.724278 -313.623194) (xy 38.775694 -313.623194) (xy 38.826476 -313.631237)
			(xy 38.875375 -313.647125) (xy 38.921187 -313.670468) (xy 38.962783 -313.700689) (xy 38.999139 -313.737045)
			(xy 39.02936 -313.778641) (xy 39.052703 -313.824453) (xy 39.068591 -313.873352) (xy 39.076634 -313.924134)
			(xy 39.077138 -313.949842) (xy 39.394142 -313.949842) (xy 39.398102 -313.900788) (xy 39.409879 -313.853004)
			(xy 39.42917 -313.807728) (xy 39.455473 -313.766132) (xy 39.488108 -313.729295) (xy 39.526229 -313.69817)
			(xy 39.56885 -313.673563) (xy 39.614866 -313.656111) (xy 39.663085 -313.646267) (xy 39.71226 -313.644286)
			(xy 39.761115 -313.650218) (xy 39.808386 -313.66391) (xy 39.852848 -313.685008) (xy 39.893351 -313.712964)
			(xy 39.928844 -313.747056) (xy 39.958409 -313.7864) (xy 39.98128 -313.829977) (xy 39.996864 -313.876658)
			(xy 40.004759 -313.925235) (xy 40.005254 -313.949842) (xy 40.004759 -313.974449) (xy 40.00458 -313.97555)
			(xy 40.323258 -313.97555) (xy 40.323258 -313.924134) (xy 40.331301 -313.873352) (xy 40.347189 -313.824453)
			(xy 40.370532 -313.778641) (xy 40.400753 -313.737045) (xy 40.437109 -313.700689) (xy 40.478705 -313.670468)
			(xy 40.524517 -313.647125) (xy 40.573416 -313.631237) (xy 40.624198 -313.623194) (xy 40.675614 -313.623194)
			(xy 40.726396 -313.631237) (xy 40.775295 -313.647125) (xy 40.821107 -313.670468) (xy 40.862703 -313.700689)
			(xy 40.899059 -313.737045) (xy 40.92928 -313.778641) (xy 40.952623 -313.824453) (xy 40.968511 -313.873352)
			(xy 40.976554 -313.924134) (xy 40.977058 -313.949842) (xy 41.294062 -313.949842) (xy 41.298022 -313.900788)
			(xy 41.309799 -313.853004) (xy 41.32909 -313.807728) (xy 41.355393 -313.766132) (xy 41.388028 -313.729295)
			(xy 41.426149 -313.69817) (xy 41.46877 -313.673563) (xy 41.514786 -313.656111) (xy 41.563005 -313.646267)
			(xy 41.61218 -313.644286) (xy 41.661035 -313.650218) (xy 41.708306 -313.66391) (xy 41.752768 -313.685008)
			(xy 41.793271 -313.712964) (xy 41.828764 -313.747056) (xy 41.858329 -313.7864) (xy 41.8812 -313.829977)
			(xy 41.896784 -313.876658) (xy 41.904679 -313.925235) (xy 41.905174 -313.949842) (xy 41.904679 -313.974449)
			(xy 41.9045 -313.97555) (xy 42.223178 -313.97555) (xy 42.223178 -313.924134) (xy 42.231221 -313.873352)
			(xy 42.247109 -313.824453) (xy 42.270452 -313.778641) (xy 42.300673 -313.737045) (xy 42.337029 -313.700689)
			(xy 42.378625 -313.670468) (xy 42.424437 -313.647125) (xy 42.473336 -313.631237) (xy 42.524118 -313.623194)
			(xy 42.575534 -313.623194) (xy 42.626316 -313.631237) (xy 42.675215 -313.647125) (xy 42.721027 -313.670468)
			(xy 42.762623 -313.700689) (xy 42.798979 -313.737045) (xy 42.8292 -313.778641) (xy 42.852543 -313.824453)
			(xy 42.868431 -313.873352) (xy 42.876474 -313.924134) (xy 42.876978 -313.949842) (xy 43.193982 -313.949842)
			(xy 43.197942 -313.900788) (xy 43.209719 -313.853004) (xy 43.22901 -313.807728) (xy 43.255313 -313.766132)
			(xy 43.287948 -313.729295) (xy 43.326069 -313.69817) (xy 43.36869 -313.673563) (xy 43.414706 -313.656111)
			(xy 43.462925 -313.646267) (xy 43.5121 -313.644286) (xy 43.560955 -313.650218) (xy 43.608226 -313.66391)
			(xy 43.652688 -313.685008) (xy 43.693191 -313.712964) (xy 43.728684 -313.747056) (xy 43.758249 -313.7864)
			(xy 43.78112 -313.829977) (xy 43.796704 -313.876658) (xy 43.804599 -313.925235) (xy 43.805094 -313.949842)
			(xy 43.804599 -313.974449) (xy 43.80442 -313.97555) (xy 44.123098 -313.97555) (xy 44.123098 -313.924134)
			(xy 44.131141 -313.873352) (xy 44.147029 -313.824453) (xy 44.170372 -313.778641) (xy 44.200593 -313.737045)
			(xy 44.236949 -313.700689) (xy 44.278545 -313.670468) (xy 44.324357 -313.647125) (xy 44.373256 -313.631237)
			(xy 44.424038 -313.623194) (xy 44.475454 -313.623194) (xy 44.526236 -313.631237) (xy 44.575135 -313.647125)
			(xy 44.620947 -313.670468) (xy 44.662543 -313.700689) (xy 44.698899 -313.737045) (xy 44.72912 -313.778641)
			(xy 44.752463 -313.824453) (xy 44.768351 -313.873352) (xy 44.776394 -313.924134) (xy 44.776898 -313.949842)
			(xy 45.094156 -313.949842) (xy 45.098116 -313.900788) (xy 45.109893 -313.853004) (xy 45.129184 -313.807728)
			(xy 45.155487 -313.766132) (xy 45.188122 -313.729295) (xy 45.226243 -313.69817) (xy 45.268864 -313.673563)
			(xy 45.31488 -313.656111) (xy 45.363099 -313.646267) (xy 45.412274 -313.644286) (xy 45.461129 -313.650218)
			(xy 45.5084 -313.66391) (xy 45.552862 -313.685008) (xy 45.593365 -313.712964) (xy 45.628858 -313.747056)
			(xy 45.658423 -313.7864) (xy 45.681294 -313.829977) (xy 45.696878 -313.876658) (xy 45.704773 -313.925235)
			(xy 45.705268 -313.949842) (xy 45.704773 -313.974449) (xy 45.704594 -313.97555) (xy 46.023272 -313.97555)
			(xy 46.023272 -313.924134) (xy 46.031315 -313.873352) (xy 46.047203 -313.824453) (xy 46.070546 -313.778641)
			(xy 46.100767 -313.737045) (xy 46.137123 -313.700689) (xy 46.178719 -313.670468) (xy 46.224531 -313.647125)
			(xy 46.27343 -313.631237) (xy 46.324212 -313.623194) (xy 46.375628 -313.623194) (xy 46.42641 -313.631237)
			(xy 46.475309 -313.647125) (xy 46.521121 -313.670468) (xy 46.562717 -313.700689) (xy 46.599073 -313.737045)
			(xy 46.629294 -313.778641) (xy 46.652637 -313.824453) (xy 46.668525 -313.873352) (xy 46.676568 -313.924134)
			(xy 46.677072 -313.949842) (xy 46.994076 -313.949842) (xy 46.998036 -313.900788) (xy 47.009813 -313.853004)
			(xy 47.029104 -313.807728) (xy 47.055407 -313.766132) (xy 47.088042 -313.729295) (xy 47.126163 -313.69817)
			(xy 47.168784 -313.673563) (xy 47.2148 -313.656111) (xy 47.263019 -313.646267) (xy 47.312194 -313.644286)
			(xy 47.361049 -313.650218) (xy 47.40832 -313.66391) (xy 47.452782 -313.685008) (xy 47.493285 -313.712964)
			(xy 47.528778 -313.747056) (xy 47.558343 -313.7864) (xy 47.581214 -313.829977) (xy 47.596798 -313.876658)
			(xy 47.604693 -313.925235) (xy 47.605188 -313.949842) (xy 47.604693 -313.974449) (xy 47.604514 -313.97555)
			(xy 47.923192 -313.97555) (xy 47.923192 -313.924134) (xy 47.931235 -313.873352) (xy 47.947123 -313.824453)
			(xy 47.970466 -313.778641) (xy 48.000687 -313.737045) (xy 48.037043 -313.700689) (xy 48.078639 -313.670468)
			(xy 48.124451 -313.647125) (xy 48.17335 -313.631237) (xy 48.224132 -313.623194) (xy 48.275548 -313.623194)
			(xy 48.32633 -313.631237) (xy 48.375229 -313.647125) (xy 48.421041 -313.670468) (xy 48.462637 -313.700689)
			(xy 48.498993 -313.737045) (xy 48.529214 -313.778641) (xy 48.552557 -313.824453) (xy 48.568445 -313.873352)
			(xy 48.576488 -313.924134) (xy 48.576992 -313.949842) (xy 48.893996 -313.949842) (xy 48.897956 -313.900788)
			(xy 48.909733 -313.853004) (xy 48.929024 -313.807728) (xy 48.955327 -313.766132) (xy 48.987962 -313.729295)
			(xy 49.026083 -313.69817) (xy 49.068704 -313.673563) (xy 49.11472 -313.656111) (xy 49.162939 -313.646267)
			(xy 49.212114 -313.644286) (xy 49.260969 -313.650218) (xy 49.30824 -313.66391) (xy 49.352702 -313.685008)
			(xy 49.393205 -313.712964) (xy 49.428698 -313.747056) (xy 49.458263 -313.7864) (xy 49.481134 -313.829977)
			(xy 49.496718 -313.876658) (xy 49.504613 -313.925235) (xy 49.505108 -313.949842) (xy 49.504613 -313.974449)
			(xy 49.504434 -313.97555) (xy 49.823112 -313.97555) (xy 49.823112 -313.924134) (xy 49.831155 -313.873352)
			(xy 49.847043 -313.824453) (xy 49.870386 -313.778641) (xy 49.900607 -313.737045) (xy 49.936963 -313.700689)
			(xy 49.978559 -313.670468) (xy 50.024371 -313.647125) (xy 50.07327 -313.631237) (xy 50.124052 -313.623194)
			(xy 50.175468 -313.623194) (xy 50.22625 -313.631237) (xy 50.275149 -313.647125) (xy 50.320961 -313.670468)
			(xy 50.362557 -313.700689) (xy 50.398913 -313.737045) (xy 50.429134 -313.778641) (xy 50.452477 -313.824453)
			(xy 50.468365 -313.873352) (xy 50.476408 -313.924134) (xy 50.476912 -313.949842) (xy 50.79417 -313.949842)
			(xy 50.79813 -313.900788) (xy 50.809907 -313.853004) (xy 50.829198 -313.807728) (xy 50.855501 -313.766132)
			(xy 50.888136 -313.729295) (xy 50.926257 -313.69817) (xy 50.968878 -313.673563) (xy 51.014894 -313.656111)
			(xy 51.063113 -313.646267) (xy 51.112288 -313.644286) (xy 51.161143 -313.650218) (xy 51.208414 -313.66391)
			(xy 51.252876 -313.685008) (xy 51.293379 -313.712964) (xy 51.328872 -313.747056) (xy 51.358437 -313.7864)
			(xy 51.381308 -313.829977) (xy 51.396892 -313.876658) (xy 51.404787 -313.925235) (xy 51.405282 -313.949842)
			(xy 51.404787 -313.974449) (xy 51.404608 -313.97555) (xy 51.723286 -313.97555) (xy 51.723286 -313.924134)
			(xy 51.731329 -313.873352) (xy 51.747217 -313.824453) (xy 51.77056 -313.778641) (xy 51.800781 -313.737045)
			(xy 51.837137 -313.700689) (xy 51.878733 -313.670468) (xy 51.924545 -313.647125) (xy 51.973444 -313.631237)
			(xy 52.024226 -313.623194) (xy 52.075642 -313.623194) (xy 52.126424 -313.631237) (xy 52.175323 -313.647125)
			(xy 52.221135 -313.670468) (xy 52.262731 -313.700689) (xy 52.299087 -313.737045) (xy 52.329308 -313.778641)
			(xy 52.352651 -313.824453) (xy 52.368539 -313.873352) (xy 52.376582 -313.924134) (xy 52.377086 -313.949842)
			(xy 52.69409 -313.949842) (xy 52.69805 -313.900788) (xy 52.709827 -313.853004) (xy 52.729118 -313.807728)
			(xy 52.755421 -313.766132) (xy 52.788056 -313.729295) (xy 52.826177 -313.69817) (xy 52.868798 -313.673563)
			(xy 52.914814 -313.656111) (xy 52.963033 -313.646267) (xy 53.012208 -313.644286) (xy 53.061063 -313.650218)
			(xy 53.108334 -313.66391) (xy 53.152796 -313.685008) (xy 53.193299 -313.712964) (xy 53.228792 -313.747056)
			(xy 53.258357 -313.7864) (xy 53.281228 -313.829977) (xy 53.296812 -313.876658) (xy 53.304707 -313.925235)
			(xy 53.305202 -313.949842) (xy 53.304707 -313.974449) (xy 53.304528 -313.97555) (xy 53.623206 -313.97555)
			(xy 53.623206 -313.924134) (xy 53.631249 -313.873352) (xy 53.647137 -313.824453) (xy 53.67048 -313.778641)
			(xy 53.700701 -313.737045) (xy 53.737057 -313.700689) (xy 53.778653 -313.670468) (xy 53.824465 -313.647125)
			(xy 53.873364 -313.631237) (xy 53.924146 -313.623194) (xy 53.975562 -313.623194) (xy 54.026344 -313.631237)
			(xy 54.075243 -313.647125) (xy 54.121055 -313.670468) (xy 54.162651 -313.700689) (xy 54.199007 -313.737045)
			(xy 54.229228 -313.778641) (xy 54.252571 -313.824453) (xy 54.268459 -313.873352) (xy 54.276502 -313.924134)
			(xy 54.277006 -313.949842) (xy 54.59401 -313.949842) (xy 54.59797 -313.900788) (xy 54.609747 -313.853004)
			(xy 54.629038 -313.807728) (xy 54.655341 -313.766132) (xy 54.687976 -313.729295) (xy 54.726097 -313.69817)
			(xy 54.768718 -313.673563) (xy 54.814734 -313.656111) (xy 54.862953 -313.646267) (xy 54.912128 -313.644286)
			(xy 54.960983 -313.650218) (xy 55.008254 -313.66391) (xy 55.052716 -313.685008) (xy 55.093219 -313.712964)
			(xy 55.128712 -313.747056) (xy 55.158277 -313.7864) (xy 55.181148 -313.829977) (xy 55.196732 -313.876658)
			(xy 55.204627 -313.925235) (xy 55.205122 -313.949842) (xy 55.204627 -313.974449) (xy 55.204448 -313.97555)
			(xy 55.523126 -313.97555) (xy 55.523126 -313.924134) (xy 55.531169 -313.873352) (xy 55.547057 -313.824453)
			(xy 55.5704 -313.778641) (xy 55.600621 -313.737045) (xy 55.636977 -313.700689) (xy 55.678573 -313.670468)
			(xy 55.724385 -313.647125) (xy 55.773284 -313.631237) (xy 55.824066 -313.623194) (xy 55.875482 -313.623194)
			(xy 55.926264 -313.631237) (xy 55.975163 -313.647125) (xy 56.020975 -313.670468) (xy 56.062571 -313.700689)
			(xy 56.098927 -313.737045) (xy 56.129148 -313.778641) (xy 56.152491 -313.824453) (xy 56.168379 -313.873352)
			(xy 56.176422 -313.924134) (xy 56.176926 -313.949842) (xy 56.494184 -313.949842) (xy 56.498144 -313.900788)
			(xy 56.509921 -313.853004) (xy 56.529212 -313.807728) (xy 56.555515 -313.766132) (xy 56.58815 -313.729295)
			(xy 56.626271 -313.69817) (xy 56.668892 -313.673563) (xy 56.714908 -313.656111) (xy 56.763127 -313.646267)
			(xy 56.812302 -313.644286) (xy 56.861157 -313.650218) (xy 56.908428 -313.66391) (xy 56.95289 -313.685008)
			(xy 56.993393 -313.712964) (xy 57.028886 -313.747056) (xy 57.058451 -313.7864) (xy 57.081322 -313.829977)
			(xy 57.096906 -313.876658) (xy 57.104801 -313.925235) (xy 57.105296 -313.949842) (xy 57.104801 -313.974449)
			(xy 57.104622 -313.97555) (xy 57.4233 -313.97555) (xy 57.4233 -313.924134) (xy 57.431343 -313.873352)
			(xy 57.447231 -313.824453) (xy 57.470574 -313.778641) (xy 57.500795 -313.737045) (xy 57.537151 -313.700689)
			(xy 57.578747 -313.670468) (xy 57.624559 -313.647125) (xy 57.673458 -313.631237) (xy 57.72424 -313.623194)
			(xy 57.775656 -313.623194) (xy 57.826438 -313.631237) (xy 57.875337 -313.647125) (xy 57.921149 -313.670468)
			(xy 57.962745 -313.700689) (xy 57.999101 -313.737045) (xy 58.029322 -313.778641) (xy 58.052665 -313.824453)
			(xy 58.068553 -313.873352) (xy 58.076596 -313.924134) (xy 58.0771 -313.949842) (xy 58.394104 -313.949842)
			(xy 58.398064 -313.900788) (xy 58.409841 -313.853004) (xy 58.429132 -313.807728) (xy 58.455435 -313.766132)
			(xy 58.48807 -313.729295) (xy 58.526191 -313.69817) (xy 58.568812 -313.673563) (xy 58.614828 -313.656111)
			(xy 58.663047 -313.646267) (xy 58.712222 -313.644286) (xy 58.761077 -313.650218) (xy 58.808348 -313.66391)
			(xy 58.85281 -313.685008) (xy 58.893313 -313.712964) (xy 58.928806 -313.747056) (xy 58.958371 -313.7864)
			(xy 58.981242 -313.829977) (xy 58.996826 -313.876658) (xy 59.004721 -313.925235) (xy 59.005216 -313.949842)
			(xy 59.004721 -313.974449) (xy 59.004542 -313.97555) (xy 59.32322 -313.97555) (xy 59.32322 -313.924134)
			(xy 59.331263 -313.873352) (xy 59.347151 -313.824453) (xy 59.370494 -313.778641) (xy 59.400715 -313.737045)
			(xy 59.437071 -313.700689) (xy 59.478667 -313.670468) (xy 59.524479 -313.647125) (xy 59.573378 -313.631237)
			(xy 59.62416 -313.623194) (xy 59.675576 -313.623194) (xy 59.726358 -313.631237) (xy 59.775257 -313.647125)
			(xy 59.821069 -313.670468) (xy 59.862665 -313.700689) (xy 59.899021 -313.737045) (xy 59.929242 -313.778641)
			(xy 59.952585 -313.824453) (xy 59.968473 -313.873352) (xy 59.976516 -313.924134) (xy 59.97702 -313.949842)
			(xy 60.294024 -313.949842) (xy 60.297984 -313.900788) (xy 60.309761 -313.853004) (xy 60.329052 -313.807728)
			(xy 60.355355 -313.766132) (xy 60.38799 -313.729295) (xy 60.426111 -313.69817) (xy 60.468732 -313.673563)
			(xy 60.514748 -313.656111) (xy 60.562967 -313.646267) (xy 60.612142 -313.644286) (xy 60.660997 -313.650218)
			(xy 60.708268 -313.66391) (xy 60.75273 -313.685008) (xy 60.793233 -313.712964) (xy 60.828726 -313.747056)
			(xy 60.858291 -313.7864) (xy 60.881162 -313.829977) (xy 60.896746 -313.876658) (xy 60.904641 -313.925235)
			(xy 60.905136 -313.949842) (xy 60.904641 -313.974449) (xy 60.904462 -313.97555) (xy 61.22314 -313.97555)
			(xy 61.22314 -313.924134) (xy 61.231183 -313.873352) (xy 61.247071 -313.824453) (xy 61.270414 -313.778641)
			(xy 61.300635 -313.737045) (xy 61.336991 -313.700689) (xy 61.378587 -313.670468) (xy 61.424399 -313.647125)
			(xy 61.473298 -313.631237) (xy 61.52408 -313.623194) (xy 61.575496 -313.623194) (xy 61.626278 -313.631237)
			(xy 61.675177 -313.647125) (xy 61.720989 -313.670468) (xy 61.762585 -313.700689) (xy 61.798941 -313.737045)
			(xy 61.829162 -313.778641) (xy 61.852505 -313.824453) (xy 61.868393 -313.873352) (xy 61.876436 -313.924134)
			(xy 61.87694 -313.949842) (xy 62.193944 -313.949842) (xy 62.197904 -313.900788) (xy 62.209681 -313.853004)
			(xy 62.228972 -313.807728) (xy 62.255275 -313.766132) (xy 62.28791 -313.729295) (xy 62.326031 -313.69817)
			(xy 62.368652 -313.673563) (xy 62.414668 -313.656111) (xy 62.462887 -313.646267) (xy 62.512062 -313.644286)
			(xy 62.560917 -313.650218) (xy 62.608188 -313.66391) (xy 62.65265 -313.685008) (xy 62.693153 -313.712964)
			(xy 62.728646 -313.747056) (xy 62.758211 -313.7864) (xy 62.781082 -313.829977) (xy 62.796666 -313.876658)
			(xy 62.804561 -313.925235) (xy 62.805056 -313.949842) (xy 62.804561 -313.974449) (xy 62.804382 -313.97555)
			(xy 63.123314 -313.97555) (xy 63.123314 -313.924134) (xy 63.131357 -313.873352) (xy 63.147245 -313.824453)
			(xy 63.170588 -313.778641) (xy 63.200809 -313.737045) (xy 63.237165 -313.700689) (xy 63.278761 -313.670468)
			(xy 63.324573 -313.647125) (xy 63.373472 -313.631237) (xy 63.424254 -313.623194) (xy 63.47567 -313.623194)
			(xy 63.526452 -313.631237) (xy 63.575351 -313.647125) (xy 63.621163 -313.670468) (xy 63.662759 -313.700689)
			(xy 63.699115 -313.737045) (xy 63.729336 -313.778641) (xy 63.752679 -313.824453) (xy 63.768567 -313.873352)
			(xy 63.77661 -313.924134) (xy 63.777114 -313.949842) (xy 64.094118 -313.949842) (xy 64.098078 -313.900788)
			(xy 64.109855 -313.853004) (xy 64.129146 -313.807728) (xy 64.155449 -313.766132) (xy 64.188084 -313.729295)
			(xy 64.226205 -313.69817) (xy 64.268826 -313.673563) (xy 64.314842 -313.656111) (xy 64.363061 -313.646267)
			(xy 64.412236 -313.644286) (xy 64.461091 -313.650218) (xy 64.508362 -313.66391) (xy 64.552824 -313.685008)
			(xy 64.593327 -313.712964) (xy 64.62882 -313.747056) (xy 64.658385 -313.7864) (xy 64.681256 -313.829977)
			(xy 64.69684 -313.876658) (xy 64.704735 -313.925235) (xy 64.70523 -313.949842) (xy 64.704735 -313.974449)
			(xy 64.704556 -313.97555) (xy 65.023234 -313.97555) (xy 65.023234 -313.924134) (xy 65.031277 -313.873352)
			(xy 65.047165 -313.824453) (xy 65.070508 -313.778641) (xy 65.100729 -313.737045) (xy 65.137085 -313.700689)
			(xy 65.178681 -313.670468) (xy 65.224493 -313.647125) (xy 65.273392 -313.631237) (xy 65.324174 -313.623194)
			(xy 65.37559 -313.623194) (xy 65.426372 -313.631237) (xy 65.475271 -313.647125) (xy 65.521083 -313.670468)
			(xy 65.562679 -313.700689) (xy 65.599035 -313.737045) (xy 65.629256 -313.778641) (xy 65.652599 -313.824453)
			(xy 65.668487 -313.873352) (xy 65.67653 -313.924134) (xy 65.677034 -313.949842) (xy 65.994038 -313.949842)
			(xy 65.997998 -313.900788) (xy 66.009775 -313.853004) (xy 66.029066 -313.807728) (xy 66.055369 -313.766132)
			(xy 66.088004 -313.729295) (xy 66.126125 -313.69817) (xy 66.168746 -313.673563) (xy 66.214762 -313.656111)
			(xy 66.262981 -313.646267) (xy 66.312156 -313.644286) (xy 66.361011 -313.650218) (xy 66.408282 -313.66391)
			(xy 66.452744 -313.685008) (xy 66.493247 -313.712964) (xy 66.52874 -313.747056) (xy 66.558305 -313.7864)
			(xy 66.581176 -313.829977) (xy 66.59676 -313.876658) (xy 66.604655 -313.925235) (xy 66.60515 -313.949842)
			(xy 66.604655 -313.974449) (xy 66.604476 -313.97555) (xy 66.923154 -313.97555) (xy 66.923154 -313.924134)
			(xy 66.931197 -313.873352) (xy 66.947085 -313.824453) (xy 66.970428 -313.778641) (xy 67.000649 -313.737045)
			(xy 67.037005 -313.700689) (xy 67.078601 -313.670468) (xy 67.124413 -313.647125) (xy 67.173312 -313.631237)
			(xy 67.224094 -313.623194) (xy 67.27551 -313.623194) (xy 67.326292 -313.631237) (xy 67.375191 -313.647125)
			(xy 67.421003 -313.670468) (xy 67.462599 -313.700689) (xy 67.498955 -313.737045) (xy 67.529176 -313.778641)
			(xy 67.552519 -313.824453) (xy 67.568407 -313.873352) (xy 67.57645 -313.924134) (xy 67.576954 -313.949842)
			(xy 67.893958 -313.949842) (xy 67.897918 -313.900788) (xy 67.909695 -313.853004) (xy 67.928986 -313.807728)
			(xy 67.955289 -313.766132) (xy 67.987924 -313.729295) (xy 68.026045 -313.69817) (xy 68.068666 -313.673563)
			(xy 68.114682 -313.656111) (xy 68.162901 -313.646267) (xy 68.212076 -313.644286) (xy 68.260931 -313.650218)
			(xy 68.308202 -313.66391) (xy 68.352664 -313.685008) (xy 68.393167 -313.712964) (xy 68.42866 -313.747056)
			(xy 68.458225 -313.7864) (xy 68.481096 -313.829977) (xy 68.49668 -313.876658) (xy 68.504575 -313.925235)
			(xy 68.50507 -313.949842) (xy 68.504575 -313.974449) (xy 68.504396 -313.97555) (xy 68.823328 -313.97555)
			(xy 68.823328 -313.924134) (xy 68.831371 -313.873352) (xy 68.847259 -313.824453) (xy 68.870602 -313.778641)
			(xy 68.900823 -313.737045) (xy 68.937179 -313.700689) (xy 68.978775 -313.670468) (xy 69.024587 -313.647125)
			(xy 69.073486 -313.631237) (xy 69.124268 -313.623194) (xy 69.175684 -313.623194) (xy 69.226466 -313.631237)
			(xy 69.275365 -313.647125) (xy 69.321177 -313.670468) (xy 69.362773 -313.700689) (xy 69.399129 -313.737045)
			(xy 69.42935 -313.778641) (xy 69.452693 -313.824453) (xy 69.468581 -313.873352) (xy 69.476624 -313.924134)
			(xy 69.477128 -313.949842) (xy 69.794132 -313.949842) (xy 69.798092 -313.900788) (xy 69.809869 -313.853004)
			(xy 69.82916 -313.807728) (xy 69.855463 -313.766132) (xy 69.888098 -313.729295) (xy 69.926219 -313.69817)
			(xy 69.96884 -313.673563) (xy 70.014856 -313.656111) (xy 70.063075 -313.646267) (xy 70.11225 -313.644286)
			(xy 70.161105 -313.650218) (xy 70.208376 -313.66391) (xy 70.252838 -313.685008) (xy 70.293341 -313.712964)
			(xy 70.328834 -313.747056) (xy 70.358399 -313.7864) (xy 70.38127 -313.829977) (xy 70.396854 -313.876658)
			(xy 70.404749 -313.925235) (xy 70.405244 -313.949842) (xy 70.404749 -313.974449) (xy 70.40457 -313.97555)
			(xy 70.723248 -313.97555) (xy 70.723248 -313.924134) (xy 70.731291 -313.873352) (xy 70.747179 -313.824453)
			(xy 70.770522 -313.778641) (xy 70.800743 -313.737045) (xy 70.837099 -313.700689) (xy 70.878695 -313.670468)
			(xy 70.924507 -313.647125) (xy 70.973406 -313.631237) (xy 71.024188 -313.623194) (xy 71.075604 -313.623194)
			(xy 71.126386 -313.631237) (xy 71.175285 -313.647125) (xy 71.221097 -313.670468) (xy 71.262693 -313.700689)
			(xy 71.299049 -313.737045) (xy 71.32927 -313.778641) (xy 71.352613 -313.824453) (xy 71.368501 -313.873352)
			(xy 71.376544 -313.924134) (xy 71.377048 -313.949842) (xy 71.694052 -313.949842) (xy 71.698012 -313.900788)
			(xy 71.709789 -313.853004) (xy 71.72908 -313.807728) (xy 71.755383 -313.766132) (xy 71.788018 -313.729295)
			(xy 71.826139 -313.69817) (xy 71.86876 -313.673563) (xy 71.914776 -313.656111) (xy 71.962995 -313.646267)
			(xy 72.01217 -313.644286) (xy 72.061025 -313.650218) (xy 72.108296 -313.66391) (xy 72.152758 -313.685008)
			(xy 72.193261 -313.712964) (xy 72.228754 -313.747056) (xy 72.258319 -313.7864) (xy 72.28119 -313.829977)
			(xy 72.296774 -313.876658) (xy 72.304669 -313.925235) (xy 72.305164 -313.949842) (xy 72.304669 -313.974449)
			(xy 72.30449 -313.97555) (xy 72.623168 -313.97555) (xy 72.623168 -313.924134) (xy 72.631211 -313.873352)
			(xy 72.647099 -313.824453) (xy 72.670442 -313.778641) (xy 72.700663 -313.737045) (xy 72.737019 -313.700689)
			(xy 72.778615 -313.670468) (xy 72.824427 -313.647125) (xy 72.873326 -313.631237) (xy 72.924108 -313.623194)
			(xy 72.975524 -313.623194) (xy 73.026306 -313.631237) (xy 73.075205 -313.647125) (xy 73.121017 -313.670468)
			(xy 73.162613 -313.700689) (xy 73.198969 -313.737045) (xy 73.22919 -313.778641) (xy 73.252533 -313.824453)
			(xy 73.268421 -313.873352) (xy 73.276464 -313.924134) (xy 73.276968 -313.949842) (xy 73.593972 -313.949842)
			(xy 73.597932 -313.900788) (xy 73.609709 -313.853004) (xy 73.629 -313.807728) (xy 73.655303 -313.766132)
			(xy 73.687938 -313.729295) (xy 73.726059 -313.69817) (xy 73.76868 -313.673563) (xy 73.814696 -313.656111)
			(xy 73.862915 -313.646267) (xy 73.91209 -313.644286) (xy 73.960945 -313.650218) (xy 74.008216 -313.66391)
			(xy 74.052678 -313.685008) (xy 74.093181 -313.712964) (xy 74.128674 -313.747056) (xy 74.158239 -313.7864)
			(xy 74.18111 -313.829977) (xy 74.196694 -313.876658) (xy 74.204589 -313.925235) (xy 74.205084 -313.949842)
			(xy 74.204589 -313.974449) (xy 74.20441 -313.97555) (xy 74.523342 -313.97555) (xy 74.523342 -313.924134)
			(xy 74.531385 -313.873352) (xy 74.547273 -313.824453) (xy 74.570616 -313.778641) (xy 74.600837 -313.737045)
			(xy 74.637193 -313.700689) (xy 74.678789 -313.670468) (xy 74.724601 -313.647125) (xy 74.7735 -313.631237)
			(xy 74.824282 -313.623194) (xy 74.875698 -313.623194) (xy 74.92648 -313.631237) (xy 74.975379 -313.647125)
			(xy 75.021191 -313.670468) (xy 75.062787 -313.700689) (xy 75.099143 -313.737045) (xy 75.129364 -313.778641)
			(xy 75.152707 -313.824453) (xy 75.168595 -313.873352) (xy 75.176638 -313.924134) (xy 75.177142 -313.949842)
			(xy 75.494146 -313.949842) (xy 75.498106 -313.900788) (xy 75.509883 -313.853004) (xy 75.529174 -313.807728)
			(xy 75.555477 -313.766132) (xy 75.588112 -313.729295) (xy 75.626233 -313.69817) (xy 75.668854 -313.673563)
			(xy 75.71487 -313.656111) (xy 75.763089 -313.646267) (xy 75.812264 -313.644286) (xy 75.861119 -313.650218)
			(xy 75.90839 -313.66391) (xy 75.952852 -313.685008) (xy 75.993355 -313.712964) (xy 76.028848 -313.747056)
			(xy 76.058413 -313.7864) (xy 76.081284 -313.829977) (xy 76.096868 -313.876658) (xy 76.104763 -313.925235)
			(xy 76.105258 -313.949842) (xy 76.104763 -313.974449) (xy 76.104584 -313.97555) (xy 76.423262 -313.97555)
			(xy 76.423262 -313.924134) (xy 76.431305 -313.873352) (xy 76.447193 -313.824453) (xy 76.470536 -313.778641)
			(xy 76.500757 -313.737045) (xy 76.537113 -313.700689) (xy 76.578709 -313.670468) (xy 76.624521 -313.647125)
			(xy 76.67342 -313.631237) (xy 76.724202 -313.623194) (xy 76.775618 -313.623194) (xy 76.8264 -313.631237)
			(xy 76.875299 -313.647125) (xy 76.921111 -313.670468) (xy 76.962707 -313.700689) (xy 76.999063 -313.737045)
			(xy 77.029284 -313.778641) (xy 77.052627 -313.824453) (xy 77.068515 -313.873352) (xy 77.076558 -313.924134)
			(xy 77.077062 -313.949842) (xy 77.394066 -313.949842) (xy 77.398026 -313.900788) (xy 77.409803 -313.853004)
			(xy 77.429094 -313.807728) (xy 77.455397 -313.766132) (xy 77.488032 -313.729295) (xy 77.526153 -313.69817)
			(xy 77.568774 -313.673563) (xy 77.61479 -313.656111) (xy 77.663009 -313.646267) (xy 77.712184 -313.644286)
			(xy 77.761039 -313.650218) (xy 77.80831 -313.66391) (xy 77.852772 -313.685008) (xy 77.893275 -313.712964)
			(xy 77.928768 -313.747056) (xy 77.958333 -313.7864) (xy 77.981204 -313.829977) (xy 77.996788 -313.876658)
			(xy 78.004683 -313.925235) (xy 78.005178 -313.949842) (xy 78.004683 -313.974449) (xy 77.996788 -314.023026)
			(xy 77.981204 -314.069707) (xy 77.958333 -314.113284) (xy 77.928768 -314.152628) (xy 77.893275 -314.18672)
			(xy 77.852772 -314.214676) (xy 77.80831 -314.235774) (xy 77.761039 -314.249466) (xy 77.712184 -314.255398)
			(xy 77.663009 -314.253417) (xy 77.61479 -314.243573) (xy 77.568774 -314.226121) (xy 77.526153 -314.201514)
			(xy 77.488032 -314.170389) (xy 77.455397 -314.133552) (xy 77.429094 -314.091956) (xy 77.409803 -314.04668)
			(xy 77.398026 -313.998896) (xy 77.394066 -313.949842) (xy 77.077062 -313.949842) (xy 77.076558 -313.97555)
			(xy 77.068515 -314.026332) (xy 77.052627 -314.075231) (xy 77.029284 -314.121043) (xy 76.999063 -314.162639)
			(xy 76.962707 -314.198995) (xy 76.921111 -314.229216) (xy 76.875299 -314.252559) (xy 76.8264 -314.268447)
			(xy 76.775618 -314.27649) (xy 76.724202 -314.27649) (xy 76.67342 -314.268447) (xy 76.624521 -314.252559)
			(xy 76.578709 -314.229216) (xy 76.537113 -314.198995) (xy 76.500757 -314.162639) (xy 76.470536 -314.121043)
			(xy 76.447193 -314.075231) (xy 76.431305 -314.026332) (xy 76.423262 -313.97555) (xy 76.104584 -313.97555)
			(xy 76.096868 -314.023026) (xy 76.081284 -314.069707) (xy 76.058413 -314.113284) (xy 76.028848 -314.152628)
			(xy 75.993355 -314.18672) (xy 75.952852 -314.214676) (xy 75.90839 -314.235774) (xy 75.861119 -314.249466)
			(xy 75.812264 -314.255398) (xy 75.763089 -314.253417) (xy 75.71487 -314.243573) (xy 75.668854 -314.226121)
			(xy 75.626233 -314.201514) (xy 75.588112 -314.170389) (xy 75.555477 -314.133552) (xy 75.529174 -314.091956)
			(xy 75.509883 -314.04668) (xy 75.498106 -313.998896) (xy 75.494146 -313.949842) (xy 75.177142 -313.949842)
			(xy 75.176638 -313.97555) (xy 75.168595 -314.026332) (xy 75.152707 -314.075231) (xy 75.129364 -314.121043)
			(xy 75.099143 -314.162639) (xy 75.062787 -314.198995) (xy 75.021191 -314.229216) (xy 74.975379 -314.252559)
			(xy 74.92648 -314.268447) (xy 74.875698 -314.27649) (xy 74.824282 -314.27649) (xy 74.7735 -314.268447)
			(xy 74.724601 -314.252559) (xy 74.678789 -314.229216) (xy 74.637193 -314.198995) (xy 74.600837 -314.162639)
			(xy 74.570616 -314.121043) (xy 74.547273 -314.075231) (xy 74.531385 -314.026332) (xy 74.523342 -313.97555)
			(xy 74.20441 -313.97555) (xy 74.196694 -314.023026) (xy 74.18111 -314.069707) (xy 74.158239 -314.113284)
			(xy 74.128674 -314.152628) (xy 74.093181 -314.18672) (xy 74.052678 -314.214676) (xy 74.008216 -314.235774)
			(xy 73.960945 -314.249466) (xy 73.91209 -314.255398) (xy 73.862915 -314.253417) (xy 73.814696 -314.243573)
			(xy 73.76868 -314.226121) (xy 73.726059 -314.201514) (xy 73.687938 -314.170389) (xy 73.655303 -314.133552)
			(xy 73.629 -314.091956) (xy 73.609709 -314.04668) (xy 73.597932 -313.998896) (xy 73.593972 -313.949842)
			(xy 73.276968 -313.949842) (xy 73.276464 -313.97555) (xy 73.268421 -314.026332) (xy 73.252533 -314.075231)
			(xy 73.22919 -314.121043) (xy 73.198969 -314.162639) (xy 73.162613 -314.198995) (xy 73.121017 -314.229216)
			(xy 73.075205 -314.252559) (xy 73.026306 -314.268447) (xy 72.975524 -314.27649) (xy 72.924108 -314.27649)
			(xy 72.873326 -314.268447) (xy 72.824427 -314.252559) (xy 72.778615 -314.229216) (xy 72.737019 -314.198995)
			(xy 72.700663 -314.162639) (xy 72.670442 -314.121043) (xy 72.647099 -314.075231) (xy 72.631211 -314.026332)
			(xy 72.623168 -313.97555) (xy 72.30449 -313.97555) (xy 72.296774 -314.023026) (xy 72.28119 -314.069707)
			(xy 72.258319 -314.113284) (xy 72.228754 -314.152628) (xy 72.193261 -314.18672) (xy 72.152758 -314.214676)
			(xy 72.108296 -314.235774) (xy 72.061025 -314.249466) (xy 72.01217 -314.255398) (xy 71.962995 -314.253417)
			(xy 71.914776 -314.243573) (xy 71.86876 -314.226121) (xy 71.826139 -314.201514) (xy 71.788018 -314.170389)
			(xy 71.755383 -314.133552) (xy 71.72908 -314.091956) (xy 71.709789 -314.04668) (xy 71.698012 -313.998896)
			(xy 71.694052 -313.949842) (xy 71.377048 -313.949842) (xy 71.376544 -313.97555) (xy 71.368501 -314.026332)
			(xy 71.352613 -314.075231) (xy 71.32927 -314.121043) (xy 71.299049 -314.162639) (xy 71.262693 -314.198995)
			(xy 71.221097 -314.229216) (xy 71.175285 -314.252559) (xy 71.126386 -314.268447) (xy 71.075604 -314.27649)
			(xy 71.024188 -314.27649) (xy 70.973406 -314.268447) (xy 70.924507 -314.252559) (xy 70.878695 -314.229216)
			(xy 70.837099 -314.198995) (xy 70.800743 -314.162639) (xy 70.770522 -314.121043) (xy 70.747179 -314.075231)
			(xy 70.731291 -314.026332) (xy 70.723248 -313.97555) (xy 70.40457 -313.97555) (xy 70.396854 -314.023026)
			(xy 70.38127 -314.069707) (xy 70.358399 -314.113284) (xy 70.328834 -314.152628) (xy 70.293341 -314.18672)
			(xy 70.252838 -314.214676) (xy 70.208376 -314.235774) (xy 70.161105 -314.249466) (xy 70.11225 -314.255398)
			(xy 70.063075 -314.253417) (xy 70.014856 -314.243573) (xy 69.96884 -314.226121) (xy 69.926219 -314.201514)
			(xy 69.888098 -314.170389) (xy 69.855463 -314.133552) (xy 69.82916 -314.091956) (xy 69.809869 -314.04668)
			(xy 69.798092 -313.998896) (xy 69.794132 -313.949842) (xy 69.477128 -313.949842) (xy 69.476624 -313.97555)
			(xy 69.468581 -314.026332) (xy 69.452693 -314.075231) (xy 69.42935 -314.121043) (xy 69.399129 -314.162639)
			(xy 69.362773 -314.198995) (xy 69.321177 -314.229216) (xy 69.275365 -314.252559) (xy 69.226466 -314.268447)
			(xy 69.175684 -314.27649) (xy 69.124268 -314.27649) (xy 69.073486 -314.268447) (xy 69.024587 -314.252559)
			(xy 68.978775 -314.229216) (xy 68.937179 -314.198995) (xy 68.900823 -314.162639) (xy 68.870602 -314.121043)
			(xy 68.847259 -314.075231) (xy 68.831371 -314.026332) (xy 68.823328 -313.97555) (xy 68.504396 -313.97555)
			(xy 68.49668 -314.023026) (xy 68.481096 -314.069707) (xy 68.458225 -314.113284) (xy 68.42866 -314.152628)
			(xy 68.393167 -314.18672) (xy 68.352664 -314.214676) (xy 68.308202 -314.235774) (xy 68.260931 -314.249466)
			(xy 68.212076 -314.255398) (xy 68.162901 -314.253417) (xy 68.114682 -314.243573) (xy 68.068666 -314.226121)
			(xy 68.026045 -314.201514) (xy 67.987924 -314.170389) (xy 67.955289 -314.133552) (xy 67.928986 -314.091956)
			(xy 67.909695 -314.04668) (xy 67.897918 -313.998896) (xy 67.893958 -313.949842) (xy 67.576954 -313.949842)
			(xy 67.57645 -313.97555) (xy 67.568407 -314.026332) (xy 67.552519 -314.075231) (xy 67.529176 -314.121043)
			(xy 67.498955 -314.162639) (xy 67.462599 -314.198995) (xy 67.421003 -314.229216) (xy 67.375191 -314.252559)
			(xy 67.326292 -314.268447) (xy 67.27551 -314.27649) (xy 67.224094 -314.27649) (xy 67.173312 -314.268447)
			(xy 67.124413 -314.252559) (xy 67.078601 -314.229216) (xy 67.037005 -314.198995) (xy 67.000649 -314.162639)
			(xy 66.970428 -314.121043) (xy 66.947085 -314.075231) (xy 66.931197 -314.026332) (xy 66.923154 -313.97555)
			(xy 66.604476 -313.97555) (xy 66.59676 -314.023026) (xy 66.581176 -314.069707) (xy 66.558305 -314.113284)
			(xy 66.52874 -314.152628) (xy 66.493247 -314.18672) (xy 66.452744 -314.214676) (xy 66.408282 -314.235774)
			(xy 66.361011 -314.249466) (xy 66.312156 -314.255398) (xy 66.262981 -314.253417) (xy 66.214762 -314.243573)
			(xy 66.168746 -314.226121) (xy 66.126125 -314.201514) (xy 66.088004 -314.170389) (xy 66.055369 -314.133552)
			(xy 66.029066 -314.091956) (xy 66.009775 -314.04668) (xy 65.997998 -313.998896) (xy 65.994038 -313.949842)
			(xy 65.677034 -313.949842) (xy 65.67653 -313.97555) (xy 65.668487 -314.026332) (xy 65.652599 -314.075231)
			(xy 65.629256 -314.121043) (xy 65.599035 -314.162639) (xy 65.562679 -314.198995) (xy 65.521083 -314.229216)
			(xy 65.475271 -314.252559) (xy 65.426372 -314.268447) (xy 65.37559 -314.27649) (xy 65.324174 -314.27649)
			(xy 65.273392 -314.268447) (xy 65.224493 -314.252559) (xy 65.178681 -314.229216) (xy 65.137085 -314.198995)
			(xy 65.100729 -314.162639) (xy 65.070508 -314.121043) (xy 65.047165 -314.075231) (xy 65.031277 -314.026332)
			(xy 65.023234 -313.97555) (xy 64.704556 -313.97555) (xy 64.69684 -314.023026) (xy 64.681256 -314.069707)
			(xy 64.658385 -314.113284) (xy 64.62882 -314.152628) (xy 64.593327 -314.18672) (xy 64.552824 -314.214676)
			(xy 64.508362 -314.235774) (xy 64.461091 -314.249466) (xy 64.412236 -314.255398) (xy 64.363061 -314.253417)
			(xy 64.314842 -314.243573) (xy 64.268826 -314.226121) (xy 64.226205 -314.201514) (xy 64.188084 -314.170389)
			(xy 64.155449 -314.133552) (xy 64.129146 -314.091956) (xy 64.109855 -314.04668) (xy 64.098078 -313.998896)
			(xy 64.094118 -313.949842) (xy 63.777114 -313.949842) (xy 63.77661 -313.97555) (xy 63.768567 -314.026332)
			(xy 63.752679 -314.075231) (xy 63.729336 -314.121043) (xy 63.699115 -314.162639) (xy 63.662759 -314.198995)
			(xy 63.621163 -314.229216) (xy 63.575351 -314.252559) (xy 63.526452 -314.268447) (xy 63.47567 -314.27649)
			(xy 63.424254 -314.27649) (xy 63.373472 -314.268447) (xy 63.324573 -314.252559) (xy 63.278761 -314.229216)
			(xy 63.237165 -314.198995) (xy 63.200809 -314.162639) (xy 63.170588 -314.121043) (xy 63.147245 -314.075231)
			(xy 63.131357 -314.026332) (xy 63.123314 -313.97555) (xy 62.804382 -313.97555) (xy 62.796666 -314.023026)
			(xy 62.781082 -314.069707) (xy 62.758211 -314.113284) (xy 62.728646 -314.152628) (xy 62.693153 -314.18672)
			(xy 62.65265 -314.214676) (xy 62.608188 -314.235774) (xy 62.560917 -314.249466) (xy 62.512062 -314.255398)
			(xy 62.462887 -314.253417) (xy 62.414668 -314.243573) (xy 62.368652 -314.226121) (xy 62.326031 -314.201514)
			(xy 62.28791 -314.170389) (xy 62.255275 -314.133552) (xy 62.228972 -314.091956) (xy 62.209681 -314.04668)
			(xy 62.197904 -313.998896) (xy 62.193944 -313.949842) (xy 61.87694 -313.949842) (xy 61.876436 -313.97555)
			(xy 61.868393 -314.026332) (xy 61.852505 -314.075231) (xy 61.829162 -314.121043) (xy 61.798941 -314.162639)
			(xy 61.762585 -314.198995) (xy 61.720989 -314.229216) (xy 61.675177 -314.252559) (xy 61.626278 -314.268447)
			(xy 61.575496 -314.27649) (xy 61.52408 -314.27649) (xy 61.473298 -314.268447) (xy 61.424399 -314.252559)
			(xy 61.378587 -314.229216) (xy 61.336991 -314.198995) (xy 61.300635 -314.162639) (xy 61.270414 -314.121043)
			(xy 61.247071 -314.075231) (xy 61.231183 -314.026332) (xy 61.22314 -313.97555) (xy 60.904462 -313.97555)
			(xy 60.896746 -314.023026) (xy 60.881162 -314.069707) (xy 60.858291 -314.113284) (xy 60.828726 -314.152628)
			(xy 60.793233 -314.18672) (xy 60.75273 -314.214676) (xy 60.708268 -314.235774) (xy 60.660997 -314.249466)
			(xy 60.612142 -314.255398) (xy 60.562967 -314.253417) (xy 60.514748 -314.243573) (xy 60.468732 -314.226121)
			(xy 60.426111 -314.201514) (xy 60.38799 -314.170389) (xy 60.355355 -314.133552) (xy 60.329052 -314.091956)
			(xy 60.309761 -314.04668) (xy 60.297984 -313.998896) (xy 60.294024 -313.949842) (xy 59.97702 -313.949842)
			(xy 59.976516 -313.97555) (xy 59.968473 -314.026332) (xy 59.952585 -314.075231) (xy 59.929242 -314.121043)
			(xy 59.899021 -314.162639) (xy 59.862665 -314.198995) (xy 59.821069 -314.229216) (xy 59.775257 -314.252559)
			(xy 59.726358 -314.268447) (xy 59.675576 -314.27649) (xy 59.62416 -314.27649) (xy 59.573378 -314.268447)
			(xy 59.524479 -314.252559) (xy 59.478667 -314.229216) (xy 59.437071 -314.198995) (xy 59.400715 -314.162639)
			(xy 59.370494 -314.121043) (xy 59.347151 -314.075231) (xy 59.331263 -314.026332) (xy 59.32322 -313.97555)
			(xy 59.004542 -313.97555) (xy 58.996826 -314.023026) (xy 58.981242 -314.069707) (xy 58.958371 -314.113284)
			(xy 58.928806 -314.152628) (xy 58.893313 -314.18672) (xy 58.85281 -314.214676) (xy 58.808348 -314.235774)
			(xy 58.761077 -314.249466) (xy 58.712222 -314.255398) (xy 58.663047 -314.253417) (xy 58.614828 -314.243573)
			(xy 58.568812 -314.226121) (xy 58.526191 -314.201514) (xy 58.48807 -314.170389) (xy 58.455435 -314.133552)
			(xy 58.429132 -314.091956) (xy 58.409841 -314.04668) (xy 58.398064 -313.998896) (xy 58.394104 -313.949842)
			(xy 58.0771 -313.949842) (xy 58.076596 -313.97555) (xy 58.068553 -314.026332) (xy 58.052665 -314.075231)
			(xy 58.029322 -314.121043) (xy 57.999101 -314.162639) (xy 57.962745 -314.198995) (xy 57.921149 -314.229216)
			(xy 57.875337 -314.252559) (xy 57.826438 -314.268447) (xy 57.775656 -314.27649) (xy 57.72424 -314.27649)
			(xy 57.673458 -314.268447) (xy 57.624559 -314.252559) (xy 57.578747 -314.229216) (xy 57.537151 -314.198995)
			(xy 57.500795 -314.162639) (xy 57.470574 -314.121043) (xy 57.447231 -314.075231) (xy 57.431343 -314.026332)
			(xy 57.4233 -313.97555) (xy 57.104622 -313.97555) (xy 57.096906 -314.023026) (xy 57.081322 -314.069707)
			(xy 57.058451 -314.113284) (xy 57.028886 -314.152628) (xy 56.993393 -314.18672) (xy 56.95289 -314.214676)
			(xy 56.908428 -314.235774) (xy 56.861157 -314.249466) (xy 56.812302 -314.255398) (xy 56.763127 -314.253417)
			(xy 56.714908 -314.243573) (xy 56.668892 -314.226121) (xy 56.626271 -314.201514) (xy 56.58815 -314.170389)
			(xy 56.555515 -314.133552) (xy 56.529212 -314.091956) (xy 56.509921 -314.04668) (xy 56.498144 -313.998896)
			(xy 56.494184 -313.949842) (xy 56.176926 -313.949842) (xy 56.176422 -313.97555) (xy 56.168379 -314.026332)
			(xy 56.152491 -314.075231) (xy 56.129148 -314.121043) (xy 56.098927 -314.162639) (xy 56.062571 -314.198995)
			(xy 56.020975 -314.229216) (xy 55.975163 -314.252559) (xy 55.926264 -314.268447) (xy 55.875482 -314.27649)
			(xy 55.824066 -314.27649) (xy 55.773284 -314.268447) (xy 55.724385 -314.252559) (xy 55.678573 -314.229216)
			(xy 55.636977 -314.198995) (xy 55.600621 -314.162639) (xy 55.5704 -314.121043) (xy 55.547057 -314.075231)
			(xy 55.531169 -314.026332) (xy 55.523126 -313.97555) (xy 55.204448 -313.97555) (xy 55.196732 -314.023026)
			(xy 55.181148 -314.069707) (xy 55.158277 -314.113284) (xy 55.128712 -314.152628) (xy 55.093219 -314.18672)
			(xy 55.052716 -314.214676) (xy 55.008254 -314.235774) (xy 54.960983 -314.249466) (xy 54.912128 -314.255398)
			(xy 54.862953 -314.253417) (xy 54.814734 -314.243573) (xy 54.768718 -314.226121) (xy 54.726097 -314.201514)
			(xy 54.687976 -314.170389) (xy 54.655341 -314.133552) (xy 54.629038 -314.091956) (xy 54.609747 -314.04668)
			(xy 54.59797 -313.998896) (xy 54.59401 -313.949842) (xy 54.277006 -313.949842) (xy 54.276502 -313.97555)
			(xy 54.268459 -314.026332) (xy 54.252571 -314.075231) (xy 54.229228 -314.121043) (xy 54.199007 -314.162639)
			(xy 54.162651 -314.198995) (xy 54.121055 -314.229216) (xy 54.075243 -314.252559) (xy 54.026344 -314.268447)
			(xy 53.975562 -314.27649) (xy 53.924146 -314.27649) (xy 53.873364 -314.268447) (xy 53.824465 -314.252559)
			(xy 53.778653 -314.229216) (xy 53.737057 -314.198995) (xy 53.700701 -314.162639) (xy 53.67048 -314.121043)
			(xy 53.647137 -314.075231) (xy 53.631249 -314.026332) (xy 53.623206 -313.97555) (xy 53.304528 -313.97555)
			(xy 53.296812 -314.023026) (xy 53.281228 -314.069707) (xy 53.258357 -314.113284) (xy 53.228792 -314.152628)
			(xy 53.193299 -314.18672) (xy 53.152796 -314.214676) (xy 53.108334 -314.235774) (xy 53.061063 -314.249466)
			(xy 53.012208 -314.255398) (xy 52.963033 -314.253417) (xy 52.914814 -314.243573) (xy 52.868798 -314.226121)
			(xy 52.826177 -314.201514) (xy 52.788056 -314.170389) (xy 52.755421 -314.133552) (xy 52.729118 -314.091956)
			(xy 52.709827 -314.04668) (xy 52.69805 -313.998896) (xy 52.69409 -313.949842) (xy 52.377086 -313.949842)
			(xy 52.376582 -313.97555) (xy 52.368539 -314.026332) (xy 52.352651 -314.075231) (xy 52.329308 -314.121043)
			(xy 52.299087 -314.162639) (xy 52.262731 -314.198995) (xy 52.221135 -314.229216) (xy 52.175323 -314.252559)
			(xy 52.126424 -314.268447) (xy 52.075642 -314.27649) (xy 52.024226 -314.27649) (xy 51.973444 -314.268447)
			(xy 51.924545 -314.252559) (xy 51.878733 -314.229216) (xy 51.837137 -314.198995) (xy 51.800781 -314.162639)
			(xy 51.77056 -314.121043) (xy 51.747217 -314.075231) (xy 51.731329 -314.026332) (xy 51.723286 -313.97555)
			(xy 51.404608 -313.97555) (xy 51.396892 -314.023026) (xy 51.381308 -314.069707) (xy 51.358437 -314.113284)
			(xy 51.328872 -314.152628) (xy 51.293379 -314.18672) (xy 51.252876 -314.214676) (xy 51.208414 -314.235774)
			(xy 51.161143 -314.249466) (xy 51.112288 -314.255398) (xy 51.063113 -314.253417) (xy 51.014894 -314.243573)
			(xy 50.968878 -314.226121) (xy 50.926257 -314.201514) (xy 50.888136 -314.170389) (xy 50.855501 -314.133552)
			(xy 50.829198 -314.091956) (xy 50.809907 -314.04668) (xy 50.79813 -313.998896) (xy 50.79417 -313.949842)
			(xy 50.476912 -313.949842) (xy 50.476408 -313.97555) (xy 50.468365 -314.026332) (xy 50.452477 -314.075231)
			(xy 50.429134 -314.121043) (xy 50.398913 -314.162639) (xy 50.362557 -314.198995) (xy 50.320961 -314.229216)
			(xy 50.275149 -314.252559) (xy 50.22625 -314.268447) (xy 50.175468 -314.27649) (xy 50.124052 -314.27649)
			(xy 50.07327 -314.268447) (xy 50.024371 -314.252559) (xy 49.978559 -314.229216) (xy 49.936963 -314.198995)
			(xy 49.900607 -314.162639) (xy 49.870386 -314.121043) (xy 49.847043 -314.075231) (xy 49.831155 -314.026332)
			(xy 49.823112 -313.97555) (xy 49.504434 -313.97555) (xy 49.496718 -314.023026) (xy 49.481134 -314.069707)
			(xy 49.458263 -314.113284) (xy 49.428698 -314.152628) (xy 49.393205 -314.18672) (xy 49.352702 -314.214676)
			(xy 49.30824 -314.235774) (xy 49.260969 -314.249466) (xy 49.212114 -314.255398) (xy 49.162939 -314.253417)
			(xy 49.11472 -314.243573) (xy 49.068704 -314.226121) (xy 49.026083 -314.201514) (xy 48.987962 -314.170389)
			(xy 48.955327 -314.133552) (xy 48.929024 -314.091956) (xy 48.909733 -314.04668) (xy 48.897956 -313.998896)
			(xy 48.893996 -313.949842) (xy 48.576992 -313.949842) (xy 48.576488 -313.97555) (xy 48.568445 -314.026332)
			(xy 48.552557 -314.075231) (xy 48.529214 -314.121043) (xy 48.498993 -314.162639) (xy 48.462637 -314.198995)
			(xy 48.421041 -314.229216) (xy 48.375229 -314.252559) (xy 48.32633 -314.268447) (xy 48.275548 -314.27649)
			(xy 48.224132 -314.27649) (xy 48.17335 -314.268447) (xy 48.124451 -314.252559) (xy 48.078639 -314.229216)
			(xy 48.037043 -314.198995) (xy 48.000687 -314.162639) (xy 47.970466 -314.121043) (xy 47.947123 -314.075231)
			(xy 47.931235 -314.026332) (xy 47.923192 -313.97555) (xy 47.604514 -313.97555) (xy 47.596798 -314.023026)
			(xy 47.581214 -314.069707) (xy 47.558343 -314.113284) (xy 47.528778 -314.152628) (xy 47.493285 -314.18672)
			(xy 47.452782 -314.214676) (xy 47.40832 -314.235774) (xy 47.361049 -314.249466) (xy 47.312194 -314.255398)
			(xy 47.263019 -314.253417) (xy 47.2148 -314.243573) (xy 47.168784 -314.226121) (xy 47.126163 -314.201514)
			(xy 47.088042 -314.170389) (xy 47.055407 -314.133552) (xy 47.029104 -314.091956) (xy 47.009813 -314.04668)
			(xy 46.998036 -313.998896) (xy 46.994076 -313.949842) (xy 46.677072 -313.949842) (xy 46.676568 -313.97555)
			(xy 46.668525 -314.026332) (xy 46.652637 -314.075231) (xy 46.629294 -314.121043) (xy 46.599073 -314.162639)
			(xy 46.562717 -314.198995) (xy 46.521121 -314.229216) (xy 46.475309 -314.252559) (xy 46.42641 -314.268447)
			(xy 46.375628 -314.27649) (xy 46.324212 -314.27649) (xy 46.27343 -314.268447) (xy 46.224531 -314.252559)
			(xy 46.178719 -314.229216) (xy 46.137123 -314.198995) (xy 46.100767 -314.162639) (xy 46.070546 -314.121043)
			(xy 46.047203 -314.075231) (xy 46.031315 -314.026332) (xy 46.023272 -313.97555) (xy 45.704594 -313.97555)
			(xy 45.696878 -314.023026) (xy 45.681294 -314.069707) (xy 45.658423 -314.113284) (xy 45.628858 -314.152628)
			(xy 45.593365 -314.18672) (xy 45.552862 -314.214676) (xy 45.5084 -314.235774) (xy 45.461129 -314.249466)
			(xy 45.412274 -314.255398) (xy 45.363099 -314.253417) (xy 45.31488 -314.243573) (xy 45.268864 -314.226121)
			(xy 45.226243 -314.201514) (xy 45.188122 -314.170389) (xy 45.155487 -314.133552) (xy 45.129184 -314.091956)
			(xy 45.109893 -314.04668) (xy 45.098116 -313.998896) (xy 45.094156 -313.949842) (xy 44.776898 -313.949842)
			(xy 44.776394 -313.97555) (xy 44.768351 -314.026332) (xy 44.752463 -314.075231) (xy 44.72912 -314.121043)
			(xy 44.698899 -314.162639) (xy 44.662543 -314.198995) (xy 44.620947 -314.229216) (xy 44.575135 -314.252559)
			(xy 44.526236 -314.268447) (xy 44.475454 -314.27649) (xy 44.424038 -314.27649) (xy 44.373256 -314.268447)
			(xy 44.324357 -314.252559) (xy 44.278545 -314.229216) (xy 44.236949 -314.198995) (xy 44.200593 -314.162639)
			(xy 44.170372 -314.121043) (xy 44.147029 -314.075231) (xy 44.131141 -314.026332) (xy 44.123098 -313.97555)
			(xy 43.80442 -313.97555) (xy 43.796704 -314.023026) (xy 43.78112 -314.069707) (xy 43.758249 -314.113284)
			(xy 43.728684 -314.152628) (xy 43.693191 -314.18672) (xy 43.652688 -314.214676) (xy 43.608226 -314.235774)
			(xy 43.560955 -314.249466) (xy 43.5121 -314.255398) (xy 43.462925 -314.253417) (xy 43.414706 -314.243573)
			(xy 43.36869 -314.226121) (xy 43.326069 -314.201514) (xy 43.287948 -314.170389) (xy 43.255313 -314.133552)
			(xy 43.22901 -314.091956) (xy 43.209719 -314.04668) (xy 43.197942 -313.998896) (xy 43.193982 -313.949842)
			(xy 42.876978 -313.949842) (xy 42.876474 -313.97555) (xy 42.868431 -314.026332) (xy 42.852543 -314.075231)
			(xy 42.8292 -314.121043) (xy 42.798979 -314.162639) (xy 42.762623 -314.198995) (xy 42.721027 -314.229216)
			(xy 42.675215 -314.252559) (xy 42.626316 -314.268447) (xy 42.575534 -314.27649) (xy 42.524118 -314.27649)
			(xy 42.473336 -314.268447) (xy 42.424437 -314.252559) (xy 42.378625 -314.229216) (xy 42.337029 -314.198995)
			(xy 42.300673 -314.162639) (xy 42.270452 -314.121043) (xy 42.247109 -314.075231) (xy 42.231221 -314.026332)
			(xy 42.223178 -313.97555) (xy 41.9045 -313.97555) (xy 41.896784 -314.023026) (xy 41.8812 -314.069707)
			(xy 41.858329 -314.113284) (xy 41.828764 -314.152628) (xy 41.793271 -314.18672) (xy 41.752768 -314.214676)
			(xy 41.708306 -314.235774) (xy 41.661035 -314.249466) (xy 41.61218 -314.255398) (xy 41.563005 -314.253417)
			(xy 41.514786 -314.243573) (xy 41.46877 -314.226121) (xy 41.426149 -314.201514) (xy 41.388028 -314.170389)
			(xy 41.355393 -314.133552) (xy 41.32909 -314.091956) (xy 41.309799 -314.04668) (xy 41.298022 -313.998896)
			(xy 41.294062 -313.949842) (xy 40.977058 -313.949842) (xy 40.976554 -313.97555) (xy 40.968511 -314.026332)
			(xy 40.952623 -314.075231) (xy 40.92928 -314.121043) (xy 40.899059 -314.162639) (xy 40.862703 -314.198995)
			(xy 40.821107 -314.229216) (xy 40.775295 -314.252559) (xy 40.726396 -314.268447) (xy 40.675614 -314.27649)
			(xy 40.624198 -314.27649) (xy 40.573416 -314.268447) (xy 40.524517 -314.252559) (xy 40.478705 -314.229216)
			(xy 40.437109 -314.198995) (xy 40.400753 -314.162639) (xy 40.370532 -314.121043) (xy 40.347189 -314.075231)
			(xy 40.331301 -314.026332) (xy 40.323258 -313.97555) (xy 40.00458 -313.97555) (xy 39.996864 -314.023026)
			(xy 39.98128 -314.069707) (xy 39.958409 -314.113284) (xy 39.928844 -314.152628) (xy 39.893351 -314.18672)
			(xy 39.852848 -314.214676) (xy 39.808386 -314.235774) (xy 39.761115 -314.249466) (xy 39.71226 -314.255398)
			(xy 39.663085 -314.253417) (xy 39.614866 -314.243573) (xy 39.56885 -314.226121) (xy 39.526229 -314.201514)
			(xy 39.488108 -314.170389) (xy 39.455473 -314.133552) (xy 39.42917 -314.091956) (xy 39.409879 -314.04668)
			(xy 39.398102 -313.998896) (xy 39.394142 -313.949842) (xy 39.077138 -313.949842) (xy 39.076634 -313.97555)
			(xy 39.068591 -314.026332) (xy 39.052703 -314.075231) (xy 39.02936 -314.121043) (xy 38.999139 -314.162639)
			(xy 38.962783 -314.198995) (xy 38.921187 -314.229216) (xy 38.875375 -314.252559) (xy 38.826476 -314.268447)
			(xy 38.775694 -314.27649) (xy 38.724278 -314.27649) (xy 38.673496 -314.268447) (xy 38.624597 -314.252559)
			(xy 38.578785 -314.229216) (xy 38.537189 -314.198995) (xy 38.500833 -314.162639) (xy 38.470612 -314.121043)
			(xy 38.447269 -314.075231) (xy 38.431381 -314.026332) (xy 38.423338 -313.97555) (xy 38.104406 -313.97555)
			(xy 38.09669 -314.023026) (xy 38.081106 -314.069707) (xy 38.058235 -314.113284) (xy 38.02867 -314.152628)
			(xy 37.993177 -314.18672) (xy 37.952674 -314.214676) (xy 37.908212 -314.235774) (xy 37.860941 -314.249466)
			(xy 37.812086 -314.255398) (xy 37.762911 -314.253417) (xy 37.714692 -314.243573) (xy 37.668676 -314.226121)
			(xy 37.626055 -314.201514) (xy 37.587934 -314.170389) (xy 37.555299 -314.133552) (xy 37.528996 -314.091956)
			(xy 37.509705 -314.04668) (xy 37.497928 -313.998896) (xy 37.493968 -313.949842) (xy 37.15512 -313.949842)
			(xy 37.154625 -313.974449) (xy 37.14673 -314.023026) (xy 37.131146 -314.069707) (xy 37.108275 -314.113284)
			(xy 37.07871 -314.152628) (xy 37.043217 -314.18672) (xy 37.002714 -314.214676) (xy 36.958252 -314.235774)
			(xy 36.910981 -314.249466) (xy 36.862126 -314.255398) (xy 36.812951 -314.253417) (xy 36.764732 -314.243573)
			(xy 36.718716 -314.226121) (xy 36.676095 -314.201514) (xy 36.637974 -314.170389) (xy 36.605339 -314.133552)
			(xy 36.579036 -314.091956) (xy 36.559745 -314.04668) (xy 36.547968 -313.998896) (xy 36.544008 -313.949842)
			(xy 34.663063 -313.949842) (xy 34.626073 -313.980625) (xy 34.578467 -314.009679) (xy 34.527138 -314.031491)
			(xy 34.473181 -314.045597) (xy 34.417744 -314.051697) (xy 34.36201 -314.04966) (xy 34.307167 -314.03953)
			(xy 34.254383 -314.021523) (xy 34.204783 -313.996022) (xy 34.159425 -313.963571) (xy 34.119276 -313.924862)
			(xy 34.08519 -313.880719) (xy 34.057894 -313.832084) (xy 34.037971 -313.779993) (xy 34.025845 -313.725556)
			(xy 34.021774 -313.669934) (xy 17.71396 -313.669934) (xy 17.71396 -314.899548) (xy 35.59354 -314.899548)
			(xy 35.5975 -314.850494) (xy 35.609277 -314.80271) (xy 35.628568 -314.757434) (xy 35.654871 -314.715838)
			(xy 35.687506 -314.679001) (xy 35.725627 -314.647876) (xy 35.768248 -314.623269) (xy 35.814264 -314.605817)
			(xy 35.862483 -314.595973) (xy 35.911658 -314.593992) (xy 35.960513 -314.599924) (xy 36.007784 -314.613616)
			(xy 36.052246 -314.634714) (xy 36.092749 -314.66267) (xy 36.128242 -314.696762) (xy 36.157807 -314.736106)
			(xy 36.180678 -314.779683) (xy 36.196262 -314.826364) (xy 36.204157 -314.874941) (xy 36.204652 -314.899548)
			(xy 36.204157 -314.924155) (xy 36.203937 -314.92551) (xy 36.523164 -314.92551) (xy 36.523164 -314.874094)
			(xy 36.531207 -314.823312) (xy 36.547095 -314.774413) (xy 36.570438 -314.728601) (xy 36.600659 -314.687005)
			(xy 36.637015 -314.650649) (xy 36.678611 -314.620428) (xy 36.724423 -314.597085) (xy 36.773322 -314.581197)
			(xy 36.824104 -314.573154) (xy 36.87552 -314.573154) (xy 36.926302 -314.581197) (xy 36.975201 -314.597085)
			(xy 37.021013 -314.620428) (xy 37.062609 -314.650649) (xy 37.098965 -314.687005) (xy 37.129186 -314.728601)
			(xy 37.152529 -314.774413) (xy 37.168417 -314.823312) (xy 37.17646 -314.874094) (xy 37.176964 -314.899802)
			(xy 37.17646 -314.92551) (xy 37.473124 -314.92551) (xy 37.473124 -314.874094) (xy 37.481167 -314.823312)
			(xy 37.497055 -314.774413) (xy 37.520398 -314.728601) (xy 37.550619 -314.687005) (xy 37.586975 -314.650649)
			(xy 37.628571 -314.620428) (xy 37.674383 -314.597085) (xy 37.723282 -314.581197) (xy 37.774064 -314.573154)
			(xy 37.82548 -314.573154) (xy 37.876262 -314.581197) (xy 37.925161 -314.597085) (xy 37.970973 -314.620428)
			(xy 38.012569 -314.650649) (xy 38.048925 -314.687005) (xy 38.079146 -314.728601) (xy 38.102489 -314.774413)
			(xy 38.118377 -314.823312) (xy 38.12642 -314.874094) (xy 38.126924 -314.899802) (xy 38.444182 -314.899802)
			(xy 38.448142 -314.850748) (xy 38.459919 -314.802964) (xy 38.47921 -314.757688) (xy 38.505513 -314.716092)
			(xy 38.538148 -314.679255) (xy 38.576269 -314.64813) (xy 38.61889 -314.623523) (xy 38.664906 -314.606071)
			(xy 38.713125 -314.596227) (xy 38.7623 -314.594246) (xy 38.811155 -314.600178) (xy 38.858426 -314.61387)
			(xy 38.902888 -314.634968) (xy 38.943391 -314.662924) (xy 38.978884 -314.697016) (xy 39.008449 -314.73636)
			(xy 39.03132 -314.779937) (xy 39.046904 -314.826618) (xy 39.054799 -314.875195) (xy 39.055294 -314.899802)
			(xy 39.394142 -314.899802) (xy 39.398102 -314.850748) (xy 39.409879 -314.802964) (xy 39.42917 -314.757688)
			(xy 39.455473 -314.716092) (xy 39.488108 -314.679255) (xy 39.526229 -314.64813) (xy 39.56885 -314.623523)
			(xy 39.614866 -314.606071) (xy 39.663085 -314.596227) (xy 39.71226 -314.594246) (xy 39.761115 -314.600178)
			(xy 39.808386 -314.61387) (xy 39.852848 -314.634968) (xy 39.893351 -314.662924) (xy 39.928844 -314.697016)
			(xy 39.958409 -314.73636) (xy 39.98128 -314.779937) (xy 39.996864 -314.826618) (xy 40.004759 -314.875195)
			(xy 40.005254 -314.899802) (xy 40.344102 -314.899802) (xy 40.348062 -314.850748) (xy 40.359839 -314.802964)
			(xy 40.37913 -314.757688) (xy 40.405433 -314.716092) (xy 40.438068 -314.679255) (xy 40.476189 -314.64813)
			(xy 40.51881 -314.623523) (xy 40.564826 -314.606071) (xy 40.613045 -314.596227) (xy 40.66222 -314.594246)
			(xy 40.711075 -314.600178) (xy 40.758346 -314.61387) (xy 40.802808 -314.634968) (xy 40.843311 -314.662924)
			(xy 40.878804 -314.697016) (xy 40.908369 -314.73636) (xy 40.93124 -314.779937) (xy 40.946824 -314.826618)
			(xy 40.954719 -314.875195) (xy 40.955214 -314.899802) (xy 41.294062 -314.899802) (xy 41.298022 -314.850748)
			(xy 41.309799 -314.802964) (xy 41.32909 -314.757688) (xy 41.355393 -314.716092) (xy 41.388028 -314.679255)
			(xy 41.426149 -314.64813) (xy 41.46877 -314.623523) (xy 41.514786 -314.606071) (xy 41.563005 -314.596227)
			(xy 41.61218 -314.594246) (xy 41.661035 -314.600178) (xy 41.708306 -314.61387) (xy 41.752768 -314.634968)
			(xy 41.793271 -314.662924) (xy 41.828764 -314.697016) (xy 41.858329 -314.73636) (xy 41.8812 -314.779937)
			(xy 41.896784 -314.826618) (xy 41.904679 -314.875195) (xy 41.905174 -314.899802) (xy 42.244022 -314.899802)
			(xy 42.247982 -314.850748) (xy 42.259759 -314.802964) (xy 42.27905 -314.757688) (xy 42.305353 -314.716092)
			(xy 42.337988 -314.679255) (xy 42.376109 -314.64813) (xy 42.41873 -314.623523) (xy 42.464746 -314.606071)
			(xy 42.512965 -314.596227) (xy 42.56214 -314.594246) (xy 42.610995 -314.600178) (xy 42.658266 -314.61387)
			(xy 42.702728 -314.634968) (xy 42.743231 -314.662924) (xy 42.778724 -314.697016) (xy 42.808289 -314.73636)
			(xy 42.83116 -314.779937) (xy 42.846744 -314.826618) (xy 42.854639 -314.875195) (xy 42.855134 -314.899802)
			(xy 43.193982 -314.899802) (xy 43.197942 -314.850748) (xy 43.209719 -314.802964) (xy 43.22901 -314.757688)
			(xy 43.255313 -314.716092) (xy 43.287948 -314.679255) (xy 43.326069 -314.64813) (xy 43.36869 -314.623523)
			(xy 43.414706 -314.606071) (xy 43.462925 -314.596227) (xy 43.5121 -314.594246) (xy 43.560955 -314.600178)
			(xy 43.608226 -314.61387) (xy 43.652688 -314.634968) (xy 43.693191 -314.662924) (xy 43.728684 -314.697016)
			(xy 43.758249 -314.73636) (xy 43.78112 -314.779937) (xy 43.796704 -314.826618) (xy 43.804599 -314.875195)
			(xy 43.805094 -314.899802) (xy 44.143942 -314.899802) (xy 44.147902 -314.850748) (xy 44.159679 -314.802964)
			(xy 44.17897 -314.757688) (xy 44.205273 -314.716092) (xy 44.237908 -314.679255) (xy 44.276029 -314.64813)
			(xy 44.31865 -314.623523) (xy 44.364666 -314.606071) (xy 44.412885 -314.596227) (xy 44.46206 -314.594246)
			(xy 44.510915 -314.600178) (xy 44.558186 -314.61387) (xy 44.602648 -314.634968) (xy 44.643151 -314.662924)
			(xy 44.678644 -314.697016) (xy 44.708209 -314.73636) (xy 44.73108 -314.779937) (xy 44.746664 -314.826618)
			(xy 44.754559 -314.875195) (xy 44.755054 -314.899802) (xy 45.094156 -314.899802) (xy 45.098116 -314.850748)
			(xy 45.109893 -314.802964) (xy 45.129184 -314.757688) (xy 45.155487 -314.716092) (xy 45.188122 -314.679255)
			(xy 45.226243 -314.64813) (xy 45.268864 -314.623523) (xy 45.31488 -314.606071) (xy 45.363099 -314.596227)
			(xy 45.412274 -314.594246) (xy 45.461129 -314.600178) (xy 45.5084 -314.61387) (xy 45.552862 -314.634968)
			(xy 45.593365 -314.662924) (xy 45.628858 -314.697016) (xy 45.658423 -314.73636) (xy 45.681294 -314.779937)
			(xy 45.696878 -314.826618) (xy 45.704773 -314.875195) (xy 45.705268 -314.899802) (xy 46.044116 -314.899802)
			(xy 46.048076 -314.850748) (xy 46.059853 -314.802964) (xy 46.079144 -314.757688) (xy 46.105447 -314.716092)
			(xy 46.138082 -314.679255) (xy 46.176203 -314.64813) (xy 46.218824 -314.623523) (xy 46.26484 -314.606071)
			(xy 46.313059 -314.596227) (xy 46.362234 -314.594246) (xy 46.411089 -314.600178) (xy 46.45836 -314.61387)
			(xy 46.502822 -314.634968) (xy 46.543325 -314.662924) (xy 46.578818 -314.697016) (xy 46.608383 -314.73636)
			(xy 46.631254 -314.779937) (xy 46.646838 -314.826618) (xy 46.654733 -314.875195) (xy 46.655228 -314.899802)
			(xy 46.994076 -314.899802) (xy 46.998036 -314.850748) (xy 47.009813 -314.802964) (xy 47.029104 -314.757688)
			(xy 47.055407 -314.716092) (xy 47.088042 -314.679255) (xy 47.126163 -314.64813) (xy 47.168784 -314.623523)
			(xy 47.2148 -314.606071) (xy 47.263019 -314.596227) (xy 47.312194 -314.594246) (xy 47.361049 -314.600178)
			(xy 47.40832 -314.61387) (xy 47.452782 -314.634968) (xy 47.493285 -314.662924) (xy 47.528778 -314.697016)
			(xy 47.558343 -314.73636) (xy 47.581214 -314.779937) (xy 47.596798 -314.826618) (xy 47.604693 -314.875195)
			(xy 47.605188 -314.899802) (xy 47.944036 -314.899802) (xy 47.947996 -314.850748) (xy 47.959773 -314.802964)
			(xy 47.979064 -314.757688) (xy 48.005367 -314.716092) (xy 48.038002 -314.679255) (xy 48.076123 -314.64813)
			(xy 48.118744 -314.623523) (xy 48.16476 -314.606071) (xy 48.212979 -314.596227) (xy 48.262154 -314.594246)
			(xy 48.311009 -314.600178) (xy 48.35828 -314.61387) (xy 48.402742 -314.634968) (xy 48.443245 -314.662924)
			(xy 48.478738 -314.697016) (xy 48.508303 -314.73636) (xy 48.531174 -314.779937) (xy 48.546758 -314.826618)
			(xy 48.554653 -314.875195) (xy 48.555148 -314.899802) (xy 48.893996 -314.899802) (xy 48.897956 -314.850748)
			(xy 48.909733 -314.802964) (xy 48.929024 -314.757688) (xy 48.955327 -314.716092) (xy 48.987962 -314.679255)
			(xy 49.026083 -314.64813) (xy 49.068704 -314.623523) (xy 49.11472 -314.606071) (xy 49.162939 -314.596227)
			(xy 49.212114 -314.594246) (xy 49.260969 -314.600178) (xy 49.30824 -314.61387) (xy 49.352702 -314.634968)
			(xy 49.393205 -314.662924) (xy 49.428698 -314.697016) (xy 49.458263 -314.73636) (xy 49.481134 -314.779937)
			(xy 49.496718 -314.826618) (xy 49.504613 -314.875195) (xy 49.505108 -314.899802) (xy 49.843956 -314.899802)
			(xy 49.847916 -314.850748) (xy 49.859693 -314.802964) (xy 49.878984 -314.757688) (xy 49.905287 -314.716092)
			(xy 49.937922 -314.679255) (xy 49.976043 -314.64813) (xy 50.018664 -314.623523) (xy 50.06468 -314.606071)
			(xy 50.112899 -314.596227) (xy 50.162074 -314.594246) (xy 50.210929 -314.600178) (xy 50.2582 -314.61387)
			(xy 50.302662 -314.634968) (xy 50.343165 -314.662924) (xy 50.378658 -314.697016) (xy 50.408223 -314.73636)
			(xy 50.431094 -314.779937) (xy 50.446678 -314.826618) (xy 50.454573 -314.875195) (xy 50.455068 -314.899802)
			(xy 50.79417 -314.899802) (xy 50.79813 -314.850748) (xy 50.809907 -314.802964) (xy 50.829198 -314.757688)
			(xy 50.855501 -314.716092) (xy 50.888136 -314.679255) (xy 50.926257 -314.64813) (xy 50.968878 -314.623523)
			(xy 51.014894 -314.606071) (xy 51.063113 -314.596227) (xy 51.112288 -314.594246) (xy 51.161143 -314.600178)
			(xy 51.208414 -314.61387) (xy 51.252876 -314.634968) (xy 51.293379 -314.662924) (xy 51.328872 -314.697016)
			(xy 51.358437 -314.73636) (xy 51.381308 -314.779937) (xy 51.396892 -314.826618) (xy 51.404787 -314.875195)
			(xy 51.405282 -314.899802) (xy 51.74413 -314.899802) (xy 51.74809 -314.850748) (xy 51.759867 -314.802964)
			(xy 51.779158 -314.757688) (xy 51.805461 -314.716092) (xy 51.838096 -314.679255) (xy 51.876217 -314.64813)
			(xy 51.918838 -314.623523) (xy 51.964854 -314.606071) (xy 52.013073 -314.596227) (xy 52.062248 -314.594246)
			(xy 52.111103 -314.600178) (xy 52.158374 -314.61387) (xy 52.202836 -314.634968) (xy 52.243339 -314.662924)
			(xy 52.278832 -314.697016) (xy 52.308397 -314.73636) (xy 52.331268 -314.779937) (xy 52.346852 -314.826618)
			(xy 52.354747 -314.875195) (xy 52.355242 -314.899802) (xy 52.69409 -314.899802) (xy 52.69805 -314.850748)
			(xy 52.709827 -314.802964) (xy 52.729118 -314.757688) (xy 52.755421 -314.716092) (xy 52.788056 -314.679255)
			(xy 52.826177 -314.64813) (xy 52.868798 -314.623523) (xy 52.914814 -314.606071) (xy 52.963033 -314.596227)
			(xy 53.012208 -314.594246) (xy 53.061063 -314.600178) (xy 53.108334 -314.61387) (xy 53.152796 -314.634968)
			(xy 53.193299 -314.662924) (xy 53.228792 -314.697016) (xy 53.258357 -314.73636) (xy 53.281228 -314.779937)
			(xy 53.296812 -314.826618) (xy 53.304707 -314.875195) (xy 53.305202 -314.899802) (xy 53.64405 -314.899802)
			(xy 53.64801 -314.850748) (xy 53.659787 -314.802964) (xy 53.679078 -314.757688) (xy 53.705381 -314.716092)
			(xy 53.738016 -314.679255) (xy 53.776137 -314.64813) (xy 53.818758 -314.623523) (xy 53.864774 -314.606071)
			(xy 53.912993 -314.596227) (xy 53.962168 -314.594246) (xy 54.011023 -314.600178) (xy 54.058294 -314.61387)
			(xy 54.102756 -314.634968) (xy 54.143259 -314.662924) (xy 54.178752 -314.697016) (xy 54.208317 -314.73636)
			(xy 54.231188 -314.779937) (xy 54.246772 -314.826618) (xy 54.254667 -314.875195) (xy 54.255162 -314.899802)
			(xy 54.59401 -314.899802) (xy 54.59797 -314.850748) (xy 54.609747 -314.802964) (xy 54.629038 -314.757688)
			(xy 54.655341 -314.716092) (xy 54.687976 -314.679255) (xy 54.726097 -314.64813) (xy 54.768718 -314.623523)
			(xy 54.814734 -314.606071) (xy 54.862953 -314.596227) (xy 54.912128 -314.594246) (xy 54.960983 -314.600178)
			(xy 55.008254 -314.61387) (xy 55.052716 -314.634968) (xy 55.093219 -314.662924) (xy 55.128712 -314.697016)
			(xy 55.158277 -314.73636) (xy 55.181148 -314.779937) (xy 55.196732 -314.826618) (xy 55.204627 -314.875195)
			(xy 55.205122 -314.899802) (xy 55.54397 -314.899802) (xy 55.54793 -314.850748) (xy 55.559707 -314.802964)
			(xy 55.578998 -314.757688) (xy 55.605301 -314.716092) (xy 55.637936 -314.679255) (xy 55.676057 -314.64813)
			(xy 55.718678 -314.623523) (xy 55.764694 -314.606071) (xy 55.812913 -314.596227) (xy 55.862088 -314.594246)
			(xy 55.910943 -314.600178) (xy 55.958214 -314.61387) (xy 56.002676 -314.634968) (xy 56.043179 -314.662924)
			(xy 56.078672 -314.697016) (xy 56.108237 -314.73636) (xy 56.131108 -314.779937) (xy 56.146692 -314.826618)
			(xy 56.154587 -314.875195) (xy 56.155082 -314.899802) (xy 56.494184 -314.899802) (xy 56.498144 -314.850748)
			(xy 56.509921 -314.802964) (xy 56.529212 -314.757688) (xy 56.555515 -314.716092) (xy 56.58815 -314.679255)
			(xy 56.626271 -314.64813) (xy 56.668892 -314.623523) (xy 56.714908 -314.606071) (xy 56.763127 -314.596227)
			(xy 56.812302 -314.594246) (xy 56.861157 -314.600178) (xy 56.908428 -314.61387) (xy 56.95289 -314.634968)
			(xy 56.993393 -314.662924) (xy 57.028886 -314.697016) (xy 57.058451 -314.73636) (xy 57.081322 -314.779937)
			(xy 57.096906 -314.826618) (xy 57.104801 -314.875195) (xy 57.105296 -314.899802) (xy 57.444144 -314.899802)
			(xy 57.448104 -314.850748) (xy 57.459881 -314.802964) (xy 57.479172 -314.757688) (xy 57.505475 -314.716092)
			(xy 57.53811 -314.679255) (xy 57.576231 -314.64813) (xy 57.618852 -314.623523) (xy 57.664868 -314.606071)
			(xy 57.713087 -314.596227) (xy 57.762262 -314.594246) (xy 57.811117 -314.600178) (xy 57.858388 -314.61387)
			(xy 57.90285 -314.634968) (xy 57.943353 -314.662924) (xy 57.978846 -314.697016) (xy 58.008411 -314.73636)
			(xy 58.031282 -314.779937) (xy 58.046866 -314.826618) (xy 58.054761 -314.875195) (xy 58.055256 -314.899802)
			(xy 58.394104 -314.899802) (xy 58.398064 -314.850748) (xy 58.409841 -314.802964) (xy 58.429132 -314.757688)
			(xy 58.455435 -314.716092) (xy 58.48807 -314.679255) (xy 58.526191 -314.64813) (xy 58.568812 -314.623523)
			(xy 58.614828 -314.606071) (xy 58.663047 -314.596227) (xy 58.712222 -314.594246) (xy 58.761077 -314.600178)
			(xy 58.808348 -314.61387) (xy 58.85281 -314.634968) (xy 58.893313 -314.662924) (xy 58.928806 -314.697016)
			(xy 58.958371 -314.73636) (xy 58.981242 -314.779937) (xy 58.996826 -314.826618) (xy 59.004721 -314.875195)
			(xy 59.005216 -314.899802) (xy 59.344064 -314.899802) (xy 59.348024 -314.850748) (xy 59.359801 -314.802964)
			(xy 59.379092 -314.757688) (xy 59.405395 -314.716092) (xy 59.43803 -314.679255) (xy 59.476151 -314.64813)
			(xy 59.518772 -314.623523) (xy 59.564788 -314.606071) (xy 59.613007 -314.596227) (xy 59.662182 -314.594246)
			(xy 59.711037 -314.600178) (xy 59.758308 -314.61387) (xy 59.80277 -314.634968) (xy 59.843273 -314.662924)
			(xy 59.878766 -314.697016) (xy 59.908331 -314.73636) (xy 59.931202 -314.779937) (xy 59.946786 -314.826618)
			(xy 59.954681 -314.875195) (xy 59.955176 -314.899802) (xy 60.294024 -314.899802) (xy 60.297984 -314.850748)
			(xy 60.309761 -314.802964) (xy 60.329052 -314.757688) (xy 60.355355 -314.716092) (xy 60.38799 -314.679255)
			(xy 60.426111 -314.64813) (xy 60.468732 -314.623523) (xy 60.514748 -314.606071) (xy 60.562967 -314.596227)
			(xy 60.612142 -314.594246) (xy 60.660997 -314.600178) (xy 60.708268 -314.61387) (xy 60.75273 -314.634968)
			(xy 60.793233 -314.662924) (xy 60.828726 -314.697016) (xy 60.858291 -314.73636) (xy 60.881162 -314.779937)
			(xy 60.896746 -314.826618) (xy 60.904641 -314.875195) (xy 60.905136 -314.899802) (xy 61.243984 -314.899802)
			(xy 61.247944 -314.850748) (xy 61.259721 -314.802964) (xy 61.279012 -314.757688) (xy 61.305315 -314.716092)
			(xy 61.33795 -314.679255) (xy 61.376071 -314.64813) (xy 61.418692 -314.623523) (xy 61.464708 -314.606071)
			(xy 61.512927 -314.596227) (xy 61.562102 -314.594246) (xy 61.610957 -314.600178) (xy 61.658228 -314.61387)
			(xy 61.70269 -314.634968) (xy 61.743193 -314.662924) (xy 61.778686 -314.697016) (xy 61.808251 -314.73636)
			(xy 61.831122 -314.779937) (xy 61.846706 -314.826618) (xy 61.854601 -314.875195) (xy 61.855096 -314.899802)
			(xy 62.193944 -314.899802) (xy 62.197904 -314.850748) (xy 62.209681 -314.802964) (xy 62.228972 -314.757688)
			(xy 62.255275 -314.716092) (xy 62.28791 -314.679255) (xy 62.326031 -314.64813) (xy 62.368652 -314.623523)
			(xy 62.414668 -314.606071) (xy 62.462887 -314.596227) (xy 62.512062 -314.594246) (xy 62.560917 -314.600178)
			(xy 62.608188 -314.61387) (xy 62.65265 -314.634968) (xy 62.693153 -314.662924) (xy 62.728646 -314.697016)
			(xy 62.758211 -314.73636) (xy 62.781082 -314.779937) (xy 62.796666 -314.826618) (xy 62.804561 -314.875195)
			(xy 62.805056 -314.899802) (xy 63.144158 -314.899802) (xy 63.148118 -314.850748) (xy 63.159895 -314.802964)
			(xy 63.179186 -314.757688) (xy 63.205489 -314.716092) (xy 63.238124 -314.679255) (xy 63.276245 -314.64813)
			(xy 63.318866 -314.623523) (xy 63.364882 -314.606071) (xy 63.413101 -314.596227) (xy 63.462276 -314.594246)
			(xy 63.511131 -314.600178) (xy 63.558402 -314.61387) (xy 63.602864 -314.634968) (xy 63.643367 -314.662924)
			(xy 63.67886 -314.697016) (xy 63.708425 -314.73636) (xy 63.731296 -314.779937) (xy 63.74688 -314.826618)
			(xy 63.754775 -314.875195) (xy 63.75527 -314.899802) (xy 64.094118 -314.899802) (xy 64.098078 -314.850748)
			(xy 64.109855 -314.802964) (xy 64.129146 -314.757688) (xy 64.155449 -314.716092) (xy 64.188084 -314.679255)
			(xy 64.226205 -314.64813) (xy 64.268826 -314.623523) (xy 64.314842 -314.606071) (xy 64.363061 -314.596227)
			(xy 64.412236 -314.594246) (xy 64.461091 -314.600178) (xy 64.508362 -314.61387) (xy 64.552824 -314.634968)
			(xy 64.593327 -314.662924) (xy 64.62882 -314.697016) (xy 64.658385 -314.73636) (xy 64.681256 -314.779937)
			(xy 64.69684 -314.826618) (xy 64.704735 -314.875195) (xy 64.70523 -314.899802) (xy 65.044078 -314.899802)
			(xy 65.048038 -314.850748) (xy 65.059815 -314.802964) (xy 65.079106 -314.757688) (xy 65.105409 -314.716092)
			(xy 65.138044 -314.679255) (xy 65.176165 -314.64813) (xy 65.218786 -314.623523) (xy 65.264802 -314.606071)
			(xy 65.313021 -314.596227) (xy 65.362196 -314.594246) (xy 65.411051 -314.600178) (xy 65.458322 -314.61387)
			(xy 65.502784 -314.634968) (xy 65.543287 -314.662924) (xy 65.57878 -314.697016) (xy 65.608345 -314.73636)
			(xy 65.631216 -314.779937) (xy 65.6468 -314.826618) (xy 65.654695 -314.875195) (xy 65.65519 -314.899802)
			(xy 65.994038 -314.899802) (xy 65.997998 -314.850748) (xy 66.009775 -314.802964) (xy 66.029066 -314.757688)
			(xy 66.055369 -314.716092) (xy 66.088004 -314.679255) (xy 66.126125 -314.64813) (xy 66.168746 -314.623523)
			(xy 66.214762 -314.606071) (xy 66.262981 -314.596227) (xy 66.312156 -314.594246) (xy 66.361011 -314.600178)
			(xy 66.408282 -314.61387) (xy 66.452744 -314.634968) (xy 66.493247 -314.662924) (xy 66.52874 -314.697016)
			(xy 66.558305 -314.73636) (xy 66.581176 -314.779937) (xy 66.59676 -314.826618) (xy 66.604655 -314.875195)
			(xy 66.60515 -314.899802) (xy 66.943998 -314.899802) (xy 66.947958 -314.850748) (xy 66.959735 -314.802964)
			(xy 66.979026 -314.757688) (xy 67.005329 -314.716092) (xy 67.037964 -314.679255) (xy 67.076085 -314.64813)
			(xy 67.118706 -314.623523) (xy 67.164722 -314.606071) (xy 67.212941 -314.596227) (xy 67.262116 -314.594246)
			(xy 67.310971 -314.600178) (xy 67.358242 -314.61387) (xy 67.402704 -314.634968) (xy 67.443207 -314.662924)
			(xy 67.4787 -314.697016) (xy 67.508265 -314.73636) (xy 67.531136 -314.779937) (xy 67.54672 -314.826618)
			(xy 67.554615 -314.875195) (xy 67.55511 -314.899802) (xy 67.893958 -314.899802) (xy 67.897918 -314.850748)
			(xy 67.909695 -314.802964) (xy 67.928986 -314.757688) (xy 67.955289 -314.716092) (xy 67.987924 -314.679255)
			(xy 68.026045 -314.64813) (xy 68.068666 -314.623523) (xy 68.114682 -314.606071) (xy 68.162901 -314.596227)
			(xy 68.212076 -314.594246) (xy 68.260931 -314.600178) (xy 68.308202 -314.61387) (xy 68.352664 -314.634968)
			(xy 68.393167 -314.662924) (xy 68.42866 -314.697016) (xy 68.458225 -314.73636) (xy 68.481096 -314.779937)
			(xy 68.49668 -314.826618) (xy 68.504575 -314.875195) (xy 68.50507 -314.899802) (xy 68.844172 -314.899802)
			(xy 68.848132 -314.850748) (xy 68.859909 -314.802964) (xy 68.8792 -314.757688) (xy 68.905503 -314.716092)
			(xy 68.938138 -314.679255) (xy 68.976259 -314.64813) (xy 69.01888 -314.623523) (xy 69.064896 -314.606071)
			(xy 69.113115 -314.596227) (xy 69.16229 -314.594246) (xy 69.211145 -314.600178) (xy 69.258416 -314.61387)
			(xy 69.302878 -314.634968) (xy 69.343381 -314.662924) (xy 69.378874 -314.697016) (xy 69.408439 -314.73636)
			(xy 69.43131 -314.779937) (xy 69.446894 -314.826618) (xy 69.454789 -314.875195) (xy 69.455284 -314.899802)
			(xy 69.794132 -314.899802) (xy 69.798092 -314.850748) (xy 69.809869 -314.802964) (xy 69.82916 -314.757688)
			(xy 69.855463 -314.716092) (xy 69.888098 -314.679255) (xy 69.926219 -314.64813) (xy 69.96884 -314.623523)
			(xy 70.014856 -314.606071) (xy 70.063075 -314.596227) (xy 70.11225 -314.594246) (xy 70.161105 -314.600178)
			(xy 70.208376 -314.61387) (xy 70.252838 -314.634968) (xy 70.293341 -314.662924) (xy 70.328834 -314.697016)
			(xy 70.358399 -314.73636) (xy 70.38127 -314.779937) (xy 70.396854 -314.826618) (xy 70.404749 -314.875195)
			(xy 70.405244 -314.899802) (xy 70.744092 -314.899802) (xy 70.748052 -314.850748) (xy 70.759829 -314.802964)
			(xy 70.77912 -314.757688) (xy 70.805423 -314.716092) (xy 70.838058 -314.679255) (xy 70.876179 -314.64813)
			(xy 70.9188 -314.623523) (xy 70.964816 -314.606071) (xy 71.013035 -314.596227) (xy 71.06221 -314.594246)
			(xy 71.111065 -314.600178) (xy 71.158336 -314.61387) (xy 71.202798 -314.634968) (xy 71.243301 -314.662924)
			(xy 71.278794 -314.697016) (xy 71.308359 -314.73636) (xy 71.33123 -314.779937) (xy 71.346814 -314.826618)
			(xy 71.354709 -314.875195) (xy 71.355204 -314.899802) (xy 71.354709 -314.924409) (xy 71.346814 -314.972986)
			(xy 71.33123 -315.019667) (xy 71.308359 -315.063244) (xy 71.278794 -315.102588) (xy 71.243301 -315.13668)
			(xy 71.202798 -315.164636) (xy 71.158336 -315.185734) (xy 71.111065 -315.199426) (xy 71.06221 -315.205358)
			(xy 71.013035 -315.203377) (xy 70.964816 -315.193533) (xy 70.9188 -315.176081) (xy 70.876179 -315.151474)
			(xy 70.838058 -315.120349) (xy 70.805423 -315.083512) (xy 70.77912 -315.041916) (xy 70.759829 -314.99664)
			(xy 70.748052 -314.948856) (xy 70.744092 -314.899802) (xy 70.405244 -314.899802) (xy 70.404749 -314.924409)
			(xy 70.396854 -314.972986) (xy 70.38127 -315.019667) (xy 70.358399 -315.063244) (xy 70.328834 -315.102588)
			(xy 70.293341 -315.13668) (xy 70.252838 -315.164636) (xy 70.208376 -315.185734) (xy 70.161105 -315.199426)
			(xy 70.11225 -315.205358) (xy 70.063075 -315.203377) (xy 70.014856 -315.193533) (xy 69.96884 -315.176081)
			(xy 69.926219 -315.151474) (xy 69.888098 -315.120349) (xy 69.855463 -315.083512) (xy 69.82916 -315.041916)
			(xy 69.809869 -314.99664) (xy 69.798092 -314.948856) (xy 69.794132 -314.899802) (xy 69.455284 -314.899802)
			(xy 69.454789 -314.924409) (xy 69.446894 -314.972986) (xy 69.43131 -315.019667) (xy 69.408439 -315.063244)
			(xy 69.378874 -315.102588) (xy 69.343381 -315.13668) (xy 69.302878 -315.164636) (xy 69.258416 -315.185734)
			(xy 69.211145 -315.199426) (xy 69.16229 -315.205358) (xy 69.113115 -315.203377) (xy 69.064896 -315.193533)
			(xy 69.01888 -315.176081) (xy 68.976259 -315.151474) (xy 68.938138 -315.120349) (xy 68.905503 -315.083512)
			(xy 68.8792 -315.041916) (xy 68.859909 -314.99664) (xy 68.848132 -314.948856) (xy 68.844172 -314.899802)
			(xy 68.50507 -314.899802) (xy 68.504575 -314.924409) (xy 68.49668 -314.972986) (xy 68.481096 -315.019667)
			(xy 68.458225 -315.063244) (xy 68.42866 -315.102588) (xy 68.393167 -315.13668) (xy 68.352664 -315.164636)
			(xy 68.308202 -315.185734) (xy 68.260931 -315.199426) (xy 68.212076 -315.205358) (xy 68.162901 -315.203377)
			(xy 68.114682 -315.193533) (xy 68.068666 -315.176081) (xy 68.026045 -315.151474) (xy 67.987924 -315.120349)
			(xy 67.955289 -315.083512) (xy 67.928986 -315.041916) (xy 67.909695 -314.99664) (xy 67.897918 -314.948856)
			(xy 67.893958 -314.899802) (xy 67.55511 -314.899802) (xy 67.554615 -314.924409) (xy 67.54672 -314.972986)
			(xy 67.531136 -315.019667) (xy 67.508265 -315.063244) (xy 67.4787 -315.102588) (xy 67.443207 -315.13668)
			(xy 67.402704 -315.164636) (xy 67.358242 -315.185734) (xy 67.310971 -315.199426) (xy 67.262116 -315.205358)
			(xy 67.212941 -315.203377) (xy 67.164722 -315.193533) (xy 67.118706 -315.176081) (xy 67.076085 -315.151474)
			(xy 67.037964 -315.120349) (xy 67.005329 -315.083512) (xy 66.979026 -315.041916) (xy 66.959735 -314.99664)
			(xy 66.947958 -314.948856) (xy 66.943998 -314.899802) (xy 66.60515 -314.899802) (xy 66.604655 -314.924409)
			(xy 66.59676 -314.972986) (xy 66.581176 -315.019667) (xy 66.558305 -315.063244) (xy 66.52874 -315.102588)
			(xy 66.493247 -315.13668) (xy 66.452744 -315.164636) (xy 66.408282 -315.185734) (xy 66.361011 -315.199426)
			(xy 66.312156 -315.205358) (xy 66.262981 -315.203377) (xy 66.214762 -315.193533) (xy 66.168746 -315.176081)
			(xy 66.126125 -315.151474) (xy 66.088004 -315.120349) (xy 66.055369 -315.083512) (xy 66.029066 -315.041916)
			(xy 66.009775 -314.99664) (xy 65.997998 -314.948856) (xy 65.994038 -314.899802) (xy 65.65519 -314.899802)
			(xy 65.654695 -314.924409) (xy 65.6468 -314.972986) (xy 65.631216 -315.019667) (xy 65.608345 -315.063244)
			(xy 65.57878 -315.102588) (xy 65.543287 -315.13668) (xy 65.502784 -315.164636) (xy 65.458322 -315.185734)
			(xy 65.411051 -315.199426) (xy 65.362196 -315.205358) (xy 65.313021 -315.203377) (xy 65.264802 -315.193533)
			(xy 65.218786 -315.176081) (xy 65.176165 -315.151474) (xy 65.138044 -315.120349) (xy 65.105409 -315.083512)
			(xy 65.079106 -315.041916) (xy 65.059815 -314.99664) (xy 65.048038 -314.948856) (xy 65.044078 -314.899802)
			(xy 64.70523 -314.899802) (xy 64.704735 -314.924409) (xy 64.69684 -314.972986) (xy 64.681256 -315.019667)
			(xy 64.658385 -315.063244) (xy 64.62882 -315.102588) (xy 64.593327 -315.13668) (xy 64.552824 -315.164636)
			(xy 64.508362 -315.185734) (xy 64.461091 -315.199426) (xy 64.412236 -315.205358) (xy 64.363061 -315.203377)
			(xy 64.314842 -315.193533) (xy 64.268826 -315.176081) (xy 64.226205 -315.151474) (xy 64.188084 -315.120349)
			(xy 64.155449 -315.083512) (xy 64.129146 -315.041916) (xy 64.109855 -314.99664) (xy 64.098078 -314.948856)
			(xy 64.094118 -314.899802) (xy 63.75527 -314.899802) (xy 63.754775 -314.924409) (xy 63.74688 -314.972986)
			(xy 63.731296 -315.019667) (xy 63.708425 -315.063244) (xy 63.67886 -315.102588) (xy 63.643367 -315.13668)
			(xy 63.602864 -315.164636) (xy 63.558402 -315.185734) (xy 63.511131 -315.199426) (xy 63.462276 -315.205358)
			(xy 63.413101 -315.203377) (xy 63.364882 -315.193533) (xy 63.318866 -315.176081) (xy 63.276245 -315.151474)
			(xy 63.238124 -315.120349) (xy 63.205489 -315.083512) (xy 63.179186 -315.041916) (xy 63.159895 -314.99664)
			(xy 63.148118 -314.948856) (xy 63.144158 -314.899802) (xy 62.805056 -314.899802) (xy 62.804561 -314.924409)
			(xy 62.796666 -314.972986) (xy 62.781082 -315.019667) (xy 62.758211 -315.063244) (xy 62.728646 -315.102588)
			(xy 62.693153 -315.13668) (xy 62.65265 -315.164636) (xy 62.608188 -315.185734) (xy 62.560917 -315.199426)
			(xy 62.512062 -315.205358) (xy 62.462887 -315.203377) (xy 62.414668 -315.193533) (xy 62.368652 -315.176081)
			(xy 62.326031 -315.151474) (xy 62.28791 -315.120349) (xy 62.255275 -315.083512) (xy 62.228972 -315.041916)
			(xy 62.209681 -314.99664) (xy 62.197904 -314.948856) (xy 62.193944 -314.899802) (xy 61.855096 -314.899802)
			(xy 61.854601 -314.924409) (xy 61.846706 -314.972986) (xy 61.831122 -315.019667) (xy 61.808251 -315.063244)
			(xy 61.778686 -315.102588) (xy 61.743193 -315.13668) (xy 61.70269 -315.164636) (xy 61.658228 -315.185734)
			(xy 61.610957 -315.199426) (xy 61.562102 -315.205358) (xy 61.512927 -315.203377) (xy 61.464708 -315.193533)
			(xy 61.418692 -315.176081) (xy 61.376071 -315.151474) (xy 61.33795 -315.120349) (xy 61.305315 -315.083512)
			(xy 61.279012 -315.041916) (xy 61.259721 -314.99664) (xy 61.247944 -314.948856) (xy 61.243984 -314.899802)
			(xy 60.905136 -314.899802) (xy 60.904641 -314.924409) (xy 60.896746 -314.972986) (xy 60.881162 -315.019667)
			(xy 60.858291 -315.063244) (xy 60.828726 -315.102588) (xy 60.793233 -315.13668) (xy 60.75273 -315.164636)
			(xy 60.708268 -315.185734) (xy 60.660997 -315.199426) (xy 60.612142 -315.205358) (xy 60.562967 -315.203377)
			(xy 60.514748 -315.193533) (xy 60.468732 -315.176081) (xy 60.426111 -315.151474) (xy 60.38799 -315.120349)
			(xy 60.355355 -315.083512) (xy 60.329052 -315.041916) (xy 60.309761 -314.99664) (xy 60.297984 -314.948856)
			(xy 60.294024 -314.899802) (xy 59.955176 -314.899802) (xy 59.954681 -314.924409) (xy 59.946786 -314.972986)
			(xy 59.931202 -315.019667) (xy 59.908331 -315.063244) (xy 59.878766 -315.102588) (xy 59.843273 -315.13668)
			(xy 59.80277 -315.164636) (xy 59.758308 -315.185734) (xy 59.711037 -315.199426) (xy 59.662182 -315.205358)
			(xy 59.613007 -315.203377) (xy 59.564788 -315.193533) (xy 59.518772 -315.176081) (xy 59.476151 -315.151474)
			(xy 59.43803 -315.120349) (xy 59.405395 -315.083512) (xy 59.379092 -315.041916) (xy 59.359801 -314.99664)
			(xy 59.348024 -314.948856) (xy 59.344064 -314.899802) (xy 59.005216 -314.899802) (xy 59.004721 -314.924409)
			(xy 58.996826 -314.972986) (xy 58.981242 -315.019667) (xy 58.958371 -315.063244) (xy 58.928806 -315.102588)
			(xy 58.893313 -315.13668) (xy 58.85281 -315.164636) (xy 58.808348 -315.185734) (xy 58.761077 -315.199426)
			(xy 58.712222 -315.205358) (xy 58.663047 -315.203377) (xy 58.614828 -315.193533) (xy 58.568812 -315.176081)
			(xy 58.526191 -315.151474) (xy 58.48807 -315.120349) (xy 58.455435 -315.083512) (xy 58.429132 -315.041916)
			(xy 58.409841 -314.99664) (xy 58.398064 -314.948856) (xy 58.394104 -314.899802) (xy 58.055256 -314.899802)
			(xy 58.054761 -314.924409) (xy 58.046866 -314.972986) (xy 58.031282 -315.019667) (xy 58.008411 -315.063244)
			(xy 57.978846 -315.102588) (xy 57.943353 -315.13668) (xy 57.90285 -315.164636) (xy 57.858388 -315.185734)
			(xy 57.811117 -315.199426) (xy 57.762262 -315.205358) (xy 57.713087 -315.203377) (xy 57.664868 -315.193533)
			(xy 57.618852 -315.176081) (xy 57.576231 -315.151474) (xy 57.53811 -315.120349) (xy 57.505475 -315.083512)
			(xy 57.479172 -315.041916) (xy 57.459881 -314.99664) (xy 57.448104 -314.948856) (xy 57.444144 -314.899802)
			(xy 57.105296 -314.899802) (xy 57.104801 -314.924409) (xy 57.096906 -314.972986) (xy 57.081322 -315.019667)
			(xy 57.058451 -315.063244) (xy 57.028886 -315.102588) (xy 56.993393 -315.13668) (xy 56.95289 -315.164636)
			(xy 56.908428 -315.185734) (xy 56.861157 -315.199426) (xy 56.812302 -315.205358) (xy 56.763127 -315.203377)
			(xy 56.714908 -315.193533) (xy 56.668892 -315.176081) (xy 56.626271 -315.151474) (xy 56.58815 -315.120349)
			(xy 56.555515 -315.083512) (xy 56.529212 -315.041916) (xy 56.509921 -314.99664) (xy 56.498144 -314.948856)
			(xy 56.494184 -314.899802) (xy 56.155082 -314.899802) (xy 56.154587 -314.924409) (xy 56.146692 -314.972986)
			(xy 56.131108 -315.019667) (xy 56.108237 -315.063244) (xy 56.078672 -315.102588) (xy 56.043179 -315.13668)
			(xy 56.002676 -315.164636) (xy 55.958214 -315.185734) (xy 55.910943 -315.199426) (xy 55.862088 -315.205358)
			(xy 55.812913 -315.203377) (xy 55.764694 -315.193533) (xy 55.718678 -315.176081) (xy 55.676057 -315.151474)
			(xy 55.637936 -315.120349) (xy 55.605301 -315.083512) (xy 55.578998 -315.041916) (xy 55.559707 -314.99664)
			(xy 55.54793 -314.948856) (xy 55.54397 -314.899802) (xy 55.205122 -314.899802) (xy 55.204627 -314.924409)
			(xy 55.196732 -314.972986) (xy 55.181148 -315.019667) (xy 55.158277 -315.063244) (xy 55.128712 -315.102588)
			(xy 55.093219 -315.13668) (xy 55.052716 -315.164636) (xy 55.008254 -315.185734) (xy 54.960983 -315.199426)
			(xy 54.912128 -315.205358) (xy 54.862953 -315.203377) (xy 54.814734 -315.193533) (xy 54.768718 -315.176081)
			(xy 54.726097 -315.151474) (xy 54.687976 -315.120349) (xy 54.655341 -315.083512) (xy 54.629038 -315.041916)
			(xy 54.609747 -314.99664) (xy 54.59797 -314.948856) (xy 54.59401 -314.899802) (xy 54.255162 -314.899802)
			(xy 54.254667 -314.924409) (xy 54.246772 -314.972986) (xy 54.231188 -315.019667) (xy 54.208317 -315.063244)
			(xy 54.178752 -315.102588) (xy 54.143259 -315.13668) (xy 54.102756 -315.164636) (xy 54.058294 -315.185734)
			(xy 54.011023 -315.199426) (xy 53.962168 -315.205358) (xy 53.912993 -315.203377) (xy 53.864774 -315.193533)
			(xy 53.818758 -315.176081) (xy 53.776137 -315.151474) (xy 53.738016 -315.120349) (xy 53.705381 -315.083512)
			(xy 53.679078 -315.041916) (xy 53.659787 -314.99664) (xy 53.64801 -314.948856) (xy 53.64405 -314.899802)
			(xy 53.305202 -314.899802) (xy 53.304707 -314.924409) (xy 53.296812 -314.972986) (xy 53.281228 -315.019667)
			(xy 53.258357 -315.063244) (xy 53.228792 -315.102588) (xy 53.193299 -315.13668) (xy 53.152796 -315.164636)
			(xy 53.108334 -315.185734) (xy 53.061063 -315.199426) (xy 53.012208 -315.205358) (xy 52.963033 -315.203377)
			(xy 52.914814 -315.193533) (xy 52.868798 -315.176081) (xy 52.826177 -315.151474) (xy 52.788056 -315.120349)
			(xy 52.755421 -315.083512) (xy 52.729118 -315.041916) (xy 52.709827 -314.99664) (xy 52.69805 -314.948856)
			(xy 52.69409 -314.899802) (xy 52.355242 -314.899802) (xy 52.354747 -314.924409) (xy 52.346852 -314.972986)
			(xy 52.331268 -315.019667) (xy 52.308397 -315.063244) (xy 52.278832 -315.102588) (xy 52.243339 -315.13668)
			(xy 52.202836 -315.164636) (xy 52.158374 -315.185734) (xy 52.111103 -315.199426) (xy 52.062248 -315.205358)
			(xy 52.013073 -315.203377) (xy 51.964854 -315.193533) (xy 51.918838 -315.176081) (xy 51.876217 -315.151474)
			(xy 51.838096 -315.120349) (xy 51.805461 -315.083512) (xy 51.779158 -315.041916) (xy 51.759867 -314.99664)
			(xy 51.74809 -314.948856) (xy 51.74413 -314.899802) (xy 51.405282 -314.899802) (xy 51.404787 -314.924409)
			(xy 51.396892 -314.972986) (xy 51.381308 -315.019667) (xy 51.358437 -315.063244) (xy 51.328872 -315.102588)
			(xy 51.293379 -315.13668) (xy 51.252876 -315.164636) (xy 51.208414 -315.185734) (xy 51.161143 -315.199426)
			(xy 51.112288 -315.205358) (xy 51.063113 -315.203377) (xy 51.014894 -315.193533) (xy 50.968878 -315.176081)
			(xy 50.926257 -315.151474) (xy 50.888136 -315.120349) (xy 50.855501 -315.083512) (xy 50.829198 -315.041916)
			(xy 50.809907 -314.99664) (xy 50.79813 -314.948856) (xy 50.79417 -314.899802) (xy 50.455068 -314.899802)
			(xy 50.454573 -314.924409) (xy 50.446678 -314.972986) (xy 50.431094 -315.019667) (xy 50.408223 -315.063244)
			(xy 50.378658 -315.102588) (xy 50.343165 -315.13668) (xy 50.302662 -315.164636) (xy 50.2582 -315.185734)
			(xy 50.210929 -315.199426) (xy 50.162074 -315.205358) (xy 50.112899 -315.203377) (xy 50.06468 -315.193533)
			(xy 50.018664 -315.176081) (xy 49.976043 -315.151474) (xy 49.937922 -315.120349) (xy 49.905287 -315.083512)
			(xy 49.878984 -315.041916) (xy 49.859693 -314.99664) (xy 49.847916 -314.948856) (xy 49.843956 -314.899802)
			(xy 49.505108 -314.899802) (xy 49.504613 -314.924409) (xy 49.496718 -314.972986) (xy 49.481134 -315.019667)
			(xy 49.458263 -315.063244) (xy 49.428698 -315.102588) (xy 49.393205 -315.13668) (xy 49.352702 -315.164636)
			(xy 49.30824 -315.185734) (xy 49.260969 -315.199426) (xy 49.212114 -315.205358) (xy 49.162939 -315.203377)
			(xy 49.11472 -315.193533) (xy 49.068704 -315.176081) (xy 49.026083 -315.151474) (xy 48.987962 -315.120349)
			(xy 48.955327 -315.083512) (xy 48.929024 -315.041916) (xy 48.909733 -314.99664) (xy 48.897956 -314.948856)
			(xy 48.893996 -314.899802) (xy 48.555148 -314.899802) (xy 48.554653 -314.924409) (xy 48.546758 -314.972986)
			(xy 48.531174 -315.019667) (xy 48.508303 -315.063244) (xy 48.478738 -315.102588) (xy 48.443245 -315.13668)
			(xy 48.402742 -315.164636) (xy 48.35828 -315.185734) (xy 48.311009 -315.199426) (xy 48.262154 -315.205358)
			(xy 48.212979 -315.203377) (xy 48.16476 -315.193533) (xy 48.118744 -315.176081) (xy 48.076123 -315.151474)
			(xy 48.038002 -315.120349) (xy 48.005367 -315.083512) (xy 47.979064 -315.041916) (xy 47.959773 -314.99664)
			(xy 47.947996 -314.948856) (xy 47.944036 -314.899802) (xy 47.605188 -314.899802) (xy 47.604693 -314.924409)
			(xy 47.596798 -314.972986) (xy 47.581214 -315.019667) (xy 47.558343 -315.063244) (xy 47.528778 -315.102588)
			(xy 47.493285 -315.13668) (xy 47.452782 -315.164636) (xy 47.40832 -315.185734) (xy 47.361049 -315.199426)
			(xy 47.312194 -315.205358) (xy 47.263019 -315.203377) (xy 47.2148 -315.193533) (xy 47.168784 -315.176081)
			(xy 47.126163 -315.151474) (xy 47.088042 -315.120349) (xy 47.055407 -315.083512) (xy 47.029104 -315.041916)
			(xy 47.009813 -314.99664) (xy 46.998036 -314.948856) (xy 46.994076 -314.899802) (xy 46.655228 -314.899802)
			(xy 46.654733 -314.924409) (xy 46.646838 -314.972986) (xy 46.631254 -315.019667) (xy 46.608383 -315.063244)
			(xy 46.578818 -315.102588) (xy 46.543325 -315.13668) (xy 46.502822 -315.164636) (xy 46.45836 -315.185734)
			(xy 46.411089 -315.199426) (xy 46.362234 -315.205358) (xy 46.313059 -315.203377) (xy 46.26484 -315.193533)
			(xy 46.218824 -315.176081) (xy 46.176203 -315.151474) (xy 46.138082 -315.120349) (xy 46.105447 -315.083512)
			(xy 46.079144 -315.041916) (xy 46.059853 -314.99664) (xy 46.048076 -314.948856) (xy 46.044116 -314.899802)
			(xy 45.705268 -314.899802) (xy 45.704773 -314.924409) (xy 45.696878 -314.972986) (xy 45.681294 -315.019667)
			(xy 45.658423 -315.063244) (xy 45.628858 -315.102588) (xy 45.593365 -315.13668) (xy 45.552862 -315.164636)
			(xy 45.5084 -315.185734) (xy 45.461129 -315.199426) (xy 45.412274 -315.205358) (xy 45.363099 -315.203377)
			(xy 45.31488 -315.193533) (xy 45.268864 -315.176081) (xy 45.226243 -315.151474) (xy 45.188122 -315.120349)
			(xy 45.155487 -315.083512) (xy 45.129184 -315.041916) (xy 45.109893 -314.99664) (xy 45.098116 -314.948856)
			(xy 45.094156 -314.899802) (xy 44.755054 -314.899802) (xy 44.754559 -314.924409) (xy 44.746664 -314.972986)
			(xy 44.73108 -315.019667) (xy 44.708209 -315.063244) (xy 44.678644 -315.102588) (xy 44.643151 -315.13668)
			(xy 44.602648 -315.164636) (xy 44.558186 -315.185734) (xy 44.510915 -315.199426) (xy 44.46206 -315.205358)
			(xy 44.412885 -315.203377) (xy 44.364666 -315.193533) (xy 44.31865 -315.176081) (xy 44.276029 -315.151474)
			(xy 44.237908 -315.120349) (xy 44.205273 -315.083512) (xy 44.17897 -315.041916) (xy 44.159679 -314.99664)
			(xy 44.147902 -314.948856) (xy 44.143942 -314.899802) (xy 43.805094 -314.899802) (xy 43.804599 -314.924409)
			(xy 43.796704 -314.972986) (xy 43.78112 -315.019667) (xy 43.758249 -315.063244) (xy 43.728684 -315.102588)
			(xy 43.693191 -315.13668) (xy 43.652688 -315.164636) (xy 43.608226 -315.185734) (xy 43.560955 -315.199426)
			(xy 43.5121 -315.205358) (xy 43.462925 -315.203377) (xy 43.414706 -315.193533) (xy 43.36869 -315.176081)
			(xy 43.326069 -315.151474) (xy 43.287948 -315.120349) (xy 43.255313 -315.083512) (xy 43.22901 -315.041916)
			(xy 43.209719 -314.99664) (xy 43.197942 -314.948856) (xy 43.193982 -314.899802) (xy 42.855134 -314.899802)
			(xy 42.854639 -314.924409) (xy 42.846744 -314.972986) (xy 42.83116 -315.019667) (xy 42.808289 -315.063244)
			(xy 42.778724 -315.102588) (xy 42.743231 -315.13668) (xy 42.702728 -315.164636) (xy 42.658266 -315.185734)
			(xy 42.610995 -315.199426) (xy 42.56214 -315.205358) (xy 42.512965 -315.203377) (xy 42.464746 -315.193533)
			(xy 42.41873 -315.176081) (xy 42.376109 -315.151474) (xy 42.337988 -315.120349) (xy 42.305353 -315.083512)
			(xy 42.27905 -315.041916) (xy 42.259759 -314.99664) (xy 42.247982 -314.948856) (xy 42.244022 -314.899802)
			(xy 41.905174 -314.899802) (xy 41.904679 -314.924409) (xy 41.896784 -314.972986) (xy 41.8812 -315.019667)
			(xy 41.858329 -315.063244) (xy 41.828764 -315.102588) (xy 41.793271 -315.13668) (xy 41.752768 -315.164636)
			(xy 41.708306 -315.185734) (xy 41.661035 -315.199426) (xy 41.61218 -315.205358) (xy 41.563005 -315.203377)
			(xy 41.514786 -315.193533) (xy 41.46877 -315.176081) (xy 41.426149 -315.151474) (xy 41.388028 -315.120349)
			(xy 41.355393 -315.083512) (xy 41.32909 -315.041916) (xy 41.309799 -314.99664) (xy 41.298022 -314.948856)
			(xy 41.294062 -314.899802) (xy 40.955214 -314.899802) (xy 40.954719 -314.924409) (xy 40.946824 -314.972986)
			(xy 40.93124 -315.019667) (xy 40.908369 -315.063244) (xy 40.878804 -315.102588) (xy 40.843311 -315.13668)
			(xy 40.802808 -315.164636) (xy 40.758346 -315.185734) (xy 40.711075 -315.199426) (xy 40.66222 -315.205358)
			(xy 40.613045 -315.203377) (xy 40.564826 -315.193533) (xy 40.51881 -315.176081) (xy 40.476189 -315.151474)
			(xy 40.438068 -315.120349) (xy 40.405433 -315.083512) (xy 40.37913 -315.041916) (xy 40.359839 -314.99664)
			(xy 40.348062 -314.948856) (xy 40.344102 -314.899802) (xy 40.005254 -314.899802) (xy 40.004759 -314.924409)
			(xy 39.996864 -314.972986) (xy 39.98128 -315.019667) (xy 39.958409 -315.063244) (xy 39.928844 -315.102588)
			(xy 39.893351 -315.13668) (xy 39.852848 -315.164636) (xy 39.808386 -315.185734) (xy 39.761115 -315.199426)
			(xy 39.71226 -315.205358) (xy 39.663085 -315.203377) (xy 39.614866 -315.193533) (xy 39.56885 -315.176081)
			(xy 39.526229 -315.151474) (xy 39.488108 -315.120349) (xy 39.455473 -315.083512) (xy 39.42917 -315.041916)
			(xy 39.409879 -314.99664) (xy 39.398102 -314.948856) (xy 39.394142 -314.899802) (xy 39.055294 -314.899802)
			(xy 39.054799 -314.924409) (xy 39.046904 -314.972986) (xy 39.03132 -315.019667) (xy 39.008449 -315.063244)
			(xy 38.978884 -315.102588) (xy 38.943391 -315.13668) (xy 38.902888 -315.164636) (xy 38.858426 -315.185734)
			(xy 38.811155 -315.199426) (xy 38.7623 -315.205358) (xy 38.713125 -315.203377) (xy 38.664906 -315.193533)
			(xy 38.61889 -315.176081) (xy 38.576269 -315.151474) (xy 38.538148 -315.120349) (xy 38.505513 -315.083512)
			(xy 38.47921 -315.041916) (xy 38.459919 -314.99664) (xy 38.448142 -314.948856) (xy 38.444182 -314.899802)
			(xy 38.126924 -314.899802) (xy 38.12642 -314.92551) (xy 38.118377 -314.976292) (xy 38.102489 -315.025191)
			(xy 38.079146 -315.071003) (xy 38.048925 -315.112599) (xy 38.012569 -315.148955) (xy 37.970973 -315.179176)
			(xy 37.925161 -315.202519) (xy 37.876262 -315.218407) (xy 37.82548 -315.22645) (xy 37.774064 -315.22645)
			(xy 37.723282 -315.218407) (xy 37.674383 -315.202519) (xy 37.628571 -315.179176) (xy 37.586975 -315.148955)
			(xy 37.550619 -315.112599) (xy 37.520398 -315.071003) (xy 37.497055 -315.025191) (xy 37.481167 -314.976292)
			(xy 37.473124 -314.92551) (xy 37.17646 -314.92551) (xy 37.168417 -314.976292) (xy 37.152529 -315.025191)
			(xy 37.129186 -315.071003) (xy 37.098965 -315.112599) (xy 37.062609 -315.148955) (xy 37.021013 -315.179176)
			(xy 36.975201 -315.202519) (xy 36.926302 -315.218407) (xy 36.87552 -315.22645) (xy 36.824104 -315.22645)
			(xy 36.773322 -315.218407) (xy 36.724423 -315.202519) (xy 36.678611 -315.179176) (xy 36.637015 -315.148955)
			(xy 36.600659 -315.112599) (xy 36.570438 -315.071003) (xy 36.547095 -315.025191) (xy 36.531207 -314.976292)
			(xy 36.523164 -314.92551) (xy 36.203937 -314.92551) (xy 36.196262 -314.972732) (xy 36.180678 -315.019413)
			(xy 36.157807 -315.06299) (xy 36.128242 -315.102334) (xy 36.092749 -315.136426) (xy 36.052246 -315.164382)
			(xy 36.007784 -315.18548) (xy 35.960513 -315.199172) (xy 35.911658 -315.205104) (xy 35.862483 -315.203123)
			(xy 35.814264 -315.193279) (xy 35.768248 -315.175827) (xy 35.725627 -315.15122) (xy 35.687506 -315.120095)
			(xy 35.654871 -315.083258) (xy 35.628568 -315.041662) (xy 35.609277 -314.996386) (xy 35.5975 -314.948602)
			(xy 35.59354 -314.899548) (xy 17.71396 -314.899548) (xy 17.71396 -315.849762) (xy 36.544008 -315.849762)
			(xy 36.547968 -315.800708) (xy 36.559745 -315.752924) (xy 36.579036 -315.707648) (xy 36.605339 -315.666052)
			(xy 36.637974 -315.629215) (xy 36.676095 -315.59809) (xy 36.718716 -315.573483) (xy 36.764732 -315.556031)
			(xy 36.812951 -315.546187) (xy 36.862126 -315.544206) (xy 36.910981 -315.550138) (xy 36.958252 -315.56383)
			(xy 37.002714 -315.584928) (xy 37.043217 -315.612884) (xy 37.07871 -315.646976) (xy 37.108275 -315.68632)
			(xy 37.131146 -315.729897) (xy 37.14673 -315.776578) (xy 37.154625 -315.825155) (xy 37.15512 -315.849762)
			(xy 37.493968 -315.849762) (xy 37.497928 -315.800708) (xy 37.509705 -315.752924) (xy 37.528996 -315.707648)
			(xy 37.555299 -315.666052) (xy 37.587934 -315.629215) (xy 37.626055 -315.59809) (xy 37.668676 -315.573483)
			(xy 37.714692 -315.556031) (xy 37.762911 -315.546187) (xy 37.812086 -315.544206) (xy 37.860941 -315.550138)
			(xy 37.908212 -315.56383) (xy 37.952674 -315.584928) (xy 37.993177 -315.612884) (xy 38.02867 -315.646976)
			(xy 38.058235 -315.68632) (xy 38.081106 -315.729897) (xy 38.09669 -315.776578) (xy 38.104585 -315.825155)
			(xy 38.10508 -315.849762) (xy 38.444182 -315.849762) (xy 38.448142 -315.800708) (xy 38.459919 -315.752924)
			(xy 38.47921 -315.707648) (xy 38.505513 -315.666052) (xy 38.538148 -315.629215) (xy 38.576269 -315.59809)
			(xy 38.61889 -315.573483) (xy 38.664906 -315.556031) (xy 38.713125 -315.546187) (xy 38.7623 -315.544206)
			(xy 38.811155 -315.550138) (xy 38.858426 -315.56383) (xy 38.902888 -315.584928) (xy 38.943391 -315.612884)
			(xy 38.978884 -315.646976) (xy 39.008449 -315.68632) (xy 39.03132 -315.729897) (xy 39.046904 -315.776578)
			(xy 39.054799 -315.825155) (xy 39.055294 -315.849762) (xy 39.054799 -315.874369) (xy 39.05462 -315.87547)
			(xy 39.373298 -315.87547) (xy 39.373298 -315.824054) (xy 39.381341 -315.773272) (xy 39.397229 -315.724373)
			(xy 39.420572 -315.678561) (xy 39.450793 -315.636965) (xy 39.487149 -315.600609) (xy 39.528745 -315.570388)
			(xy 39.574557 -315.547045) (xy 39.623456 -315.531157) (xy 39.674238 -315.523114) (xy 39.725654 -315.523114)
			(xy 39.776436 -315.531157) (xy 39.825335 -315.547045) (xy 39.871147 -315.570388) (xy 39.912743 -315.600609)
			(xy 39.949099 -315.636965) (xy 39.97932 -315.678561) (xy 40.002663 -315.724373) (xy 40.018551 -315.773272)
			(xy 40.026594 -315.824054) (xy 40.027098 -315.849762) (xy 40.344102 -315.849762) (xy 40.348062 -315.800708)
			(xy 40.359839 -315.752924) (xy 40.37913 -315.707648) (xy 40.405433 -315.666052) (xy 40.438068 -315.629215)
			(xy 40.476189 -315.59809) (xy 40.51881 -315.573483) (xy 40.564826 -315.556031) (xy 40.613045 -315.546187)
			(xy 40.66222 -315.544206) (xy 40.711075 -315.550138) (xy 40.758346 -315.56383) (xy 40.802808 -315.584928)
			(xy 40.843311 -315.612884) (xy 40.878804 -315.646976) (xy 40.908369 -315.68632) (xy 40.93124 -315.729897)
			(xy 40.946824 -315.776578) (xy 40.954719 -315.825155) (xy 40.955214 -315.849762) (xy 40.954719 -315.874369)
			(xy 40.95454 -315.87547) (xy 41.273218 -315.87547) (xy 41.273218 -315.824054) (xy 41.281261 -315.773272)
			(xy 41.297149 -315.724373) (xy 41.320492 -315.678561) (xy 41.350713 -315.636965) (xy 41.387069 -315.600609)
			(xy 41.428665 -315.570388) (xy 41.474477 -315.547045) (xy 41.523376 -315.531157) (xy 41.574158 -315.523114)
			(xy 41.625574 -315.523114) (xy 41.676356 -315.531157) (xy 41.725255 -315.547045) (xy 41.771067 -315.570388)
			(xy 41.812663 -315.600609) (xy 41.849019 -315.636965) (xy 41.87924 -315.678561) (xy 41.902583 -315.724373)
			(xy 41.918471 -315.773272) (xy 41.926514 -315.824054) (xy 41.927018 -315.849762) (xy 42.244022 -315.849762)
			(xy 42.247982 -315.800708) (xy 42.259759 -315.752924) (xy 42.27905 -315.707648) (xy 42.305353 -315.666052)
			(xy 42.337988 -315.629215) (xy 42.376109 -315.59809) (xy 42.41873 -315.573483) (xy 42.464746 -315.556031)
			(xy 42.512965 -315.546187) (xy 42.56214 -315.544206) (xy 42.610995 -315.550138) (xy 42.658266 -315.56383)
			(xy 42.702728 -315.584928) (xy 42.743231 -315.612884) (xy 42.778724 -315.646976) (xy 42.808289 -315.68632)
			(xy 42.83116 -315.729897) (xy 42.846744 -315.776578) (xy 42.854639 -315.825155) (xy 42.855134 -315.849762)
			(xy 42.854639 -315.874369) (xy 42.85446 -315.87547) (xy 43.173138 -315.87547) (xy 43.173138 -315.824054)
			(xy 43.181181 -315.773272) (xy 43.197069 -315.724373) (xy 43.220412 -315.678561) (xy 43.250633 -315.636965)
			(xy 43.286989 -315.600609) (xy 43.328585 -315.570388) (xy 43.374397 -315.547045) (xy 43.423296 -315.531157)
			(xy 43.474078 -315.523114) (xy 43.525494 -315.523114) (xy 43.576276 -315.531157) (xy 43.625175 -315.547045)
			(xy 43.670987 -315.570388) (xy 43.712583 -315.600609) (xy 43.748939 -315.636965) (xy 43.77916 -315.678561)
			(xy 43.802503 -315.724373) (xy 43.818391 -315.773272) (xy 43.826434 -315.824054) (xy 43.826938 -315.849762)
			(xy 44.143942 -315.849762) (xy 44.147902 -315.800708) (xy 44.159679 -315.752924) (xy 44.17897 -315.707648)
			(xy 44.205273 -315.666052) (xy 44.237908 -315.629215) (xy 44.276029 -315.59809) (xy 44.31865 -315.573483)
			(xy 44.364666 -315.556031) (xy 44.412885 -315.546187) (xy 44.46206 -315.544206) (xy 44.510915 -315.550138)
			(xy 44.558186 -315.56383) (xy 44.602648 -315.584928) (xy 44.643151 -315.612884) (xy 44.678644 -315.646976)
			(xy 44.708209 -315.68632) (xy 44.73108 -315.729897) (xy 44.746664 -315.776578) (xy 44.754559 -315.825155)
			(xy 44.755054 -315.849762) (xy 44.754559 -315.874369) (xy 44.75438 -315.87547) (xy 45.073312 -315.87547)
			(xy 45.073312 -315.824054) (xy 45.081355 -315.773272) (xy 45.097243 -315.724373) (xy 45.120586 -315.678561)
			(xy 45.150807 -315.636965) (xy 45.187163 -315.600609) (xy 45.228759 -315.570388) (xy 45.274571 -315.547045)
			(xy 45.32347 -315.531157) (xy 45.374252 -315.523114) (xy 45.425668 -315.523114) (xy 45.47645 -315.531157)
			(xy 45.525349 -315.547045) (xy 45.571161 -315.570388) (xy 45.612757 -315.600609) (xy 45.649113 -315.636965)
			(xy 45.679334 -315.678561) (xy 45.702677 -315.724373) (xy 45.718565 -315.773272) (xy 45.726608 -315.824054)
			(xy 45.727112 -315.849762) (xy 46.044116 -315.849762) (xy 46.048076 -315.800708) (xy 46.059853 -315.752924)
			(xy 46.079144 -315.707648) (xy 46.105447 -315.666052) (xy 46.138082 -315.629215) (xy 46.176203 -315.59809)
			(xy 46.218824 -315.573483) (xy 46.26484 -315.556031) (xy 46.313059 -315.546187) (xy 46.362234 -315.544206)
			(xy 46.411089 -315.550138) (xy 46.45836 -315.56383) (xy 46.502822 -315.584928) (xy 46.543325 -315.612884)
			(xy 46.578818 -315.646976) (xy 46.608383 -315.68632) (xy 46.631254 -315.729897) (xy 46.646838 -315.776578)
			(xy 46.654733 -315.825155) (xy 46.655228 -315.849762) (xy 46.654733 -315.874369) (xy 46.654554 -315.87547)
			(xy 46.973232 -315.87547) (xy 46.973232 -315.824054) (xy 46.981275 -315.773272) (xy 46.997163 -315.724373)
			(xy 47.020506 -315.678561) (xy 47.050727 -315.636965) (xy 47.087083 -315.600609) (xy 47.128679 -315.570388)
			(xy 47.174491 -315.547045) (xy 47.22339 -315.531157) (xy 47.274172 -315.523114) (xy 47.325588 -315.523114)
			(xy 47.37637 -315.531157) (xy 47.425269 -315.547045) (xy 47.471081 -315.570388) (xy 47.512677 -315.600609)
			(xy 47.549033 -315.636965) (xy 47.579254 -315.678561) (xy 47.602597 -315.724373) (xy 47.618485 -315.773272)
			(xy 47.626528 -315.824054) (xy 47.627032 -315.849762) (xy 47.944036 -315.849762) (xy 47.947996 -315.800708)
			(xy 47.959773 -315.752924) (xy 47.979064 -315.707648) (xy 48.005367 -315.666052) (xy 48.038002 -315.629215)
			(xy 48.076123 -315.59809) (xy 48.118744 -315.573483) (xy 48.16476 -315.556031) (xy 48.212979 -315.546187)
			(xy 48.262154 -315.544206) (xy 48.311009 -315.550138) (xy 48.35828 -315.56383) (xy 48.402742 -315.584928)
			(xy 48.443245 -315.612884) (xy 48.478738 -315.646976) (xy 48.508303 -315.68632) (xy 48.531174 -315.729897)
			(xy 48.546758 -315.776578) (xy 48.554653 -315.825155) (xy 48.555148 -315.849762) (xy 48.554653 -315.874369)
			(xy 48.554474 -315.87547) (xy 48.873152 -315.87547) (xy 48.873152 -315.824054) (xy 48.881195 -315.773272)
			(xy 48.897083 -315.724373) (xy 48.920426 -315.678561) (xy 48.950647 -315.636965) (xy 48.987003 -315.600609)
			(xy 49.028599 -315.570388) (xy 49.074411 -315.547045) (xy 49.12331 -315.531157) (xy 49.174092 -315.523114)
			(xy 49.225508 -315.523114) (xy 49.27629 -315.531157) (xy 49.325189 -315.547045) (xy 49.371001 -315.570388)
			(xy 49.412597 -315.600609) (xy 49.448953 -315.636965) (xy 49.479174 -315.678561) (xy 49.502517 -315.724373)
			(xy 49.518405 -315.773272) (xy 49.526448 -315.824054) (xy 49.526952 -315.849762) (xy 49.843956 -315.849762)
			(xy 49.847916 -315.800708) (xy 49.859693 -315.752924) (xy 49.878984 -315.707648) (xy 49.905287 -315.666052)
			(xy 49.937922 -315.629215) (xy 49.976043 -315.59809) (xy 50.018664 -315.573483) (xy 50.06468 -315.556031)
			(xy 50.112899 -315.546187) (xy 50.162074 -315.544206) (xy 50.210929 -315.550138) (xy 50.2582 -315.56383)
			(xy 50.302662 -315.584928) (xy 50.343165 -315.612884) (xy 50.378658 -315.646976) (xy 50.408223 -315.68632)
			(xy 50.431094 -315.729897) (xy 50.446678 -315.776578) (xy 50.454573 -315.825155) (xy 50.455068 -315.849762)
			(xy 50.454573 -315.874369) (xy 50.454394 -315.87547) (xy 50.773326 -315.87547) (xy 50.773326 -315.824054)
			(xy 50.781369 -315.773272) (xy 50.797257 -315.724373) (xy 50.8206 -315.678561) (xy 50.850821 -315.636965)
			(xy 50.887177 -315.600609) (xy 50.928773 -315.570388) (xy 50.974585 -315.547045) (xy 51.023484 -315.531157)
			(xy 51.074266 -315.523114) (xy 51.125682 -315.523114) (xy 51.176464 -315.531157) (xy 51.225363 -315.547045)
			(xy 51.271175 -315.570388) (xy 51.312771 -315.600609) (xy 51.349127 -315.636965) (xy 51.379348 -315.678561)
			(xy 51.402691 -315.724373) (xy 51.418579 -315.773272) (xy 51.426622 -315.824054) (xy 51.427126 -315.849762)
			(xy 51.74413 -315.849762) (xy 51.74809 -315.800708) (xy 51.759867 -315.752924) (xy 51.779158 -315.707648)
			(xy 51.805461 -315.666052) (xy 51.838096 -315.629215) (xy 51.876217 -315.59809) (xy 51.918838 -315.573483)
			(xy 51.964854 -315.556031) (xy 52.013073 -315.546187) (xy 52.062248 -315.544206) (xy 52.111103 -315.550138)
			(xy 52.158374 -315.56383) (xy 52.202836 -315.584928) (xy 52.243339 -315.612884) (xy 52.278832 -315.646976)
			(xy 52.308397 -315.68632) (xy 52.331268 -315.729897) (xy 52.346852 -315.776578) (xy 52.354747 -315.825155)
			(xy 52.355242 -315.849762) (xy 52.354747 -315.874369) (xy 52.354568 -315.87547) (xy 52.673246 -315.87547)
			(xy 52.673246 -315.824054) (xy 52.681289 -315.773272) (xy 52.697177 -315.724373) (xy 52.72052 -315.678561)
			(xy 52.750741 -315.636965) (xy 52.787097 -315.600609) (xy 52.828693 -315.570388) (xy 52.874505 -315.547045)
			(xy 52.923404 -315.531157) (xy 52.974186 -315.523114) (xy 53.025602 -315.523114) (xy 53.076384 -315.531157)
			(xy 53.125283 -315.547045) (xy 53.171095 -315.570388) (xy 53.212691 -315.600609) (xy 53.249047 -315.636965)
			(xy 53.279268 -315.678561) (xy 53.302611 -315.724373) (xy 53.318499 -315.773272) (xy 53.326542 -315.824054)
			(xy 53.327046 -315.849762) (xy 53.64405 -315.849762) (xy 53.64801 -315.800708) (xy 53.659787 -315.752924)
			(xy 53.679078 -315.707648) (xy 53.705381 -315.666052) (xy 53.738016 -315.629215) (xy 53.776137 -315.59809)
			(xy 53.818758 -315.573483) (xy 53.864774 -315.556031) (xy 53.912993 -315.546187) (xy 53.962168 -315.544206)
			(xy 54.011023 -315.550138) (xy 54.058294 -315.56383) (xy 54.102756 -315.584928) (xy 54.143259 -315.612884)
			(xy 54.178752 -315.646976) (xy 54.208317 -315.68632) (xy 54.231188 -315.729897) (xy 54.246772 -315.776578)
			(xy 54.254667 -315.825155) (xy 54.255162 -315.849762) (xy 54.254667 -315.874369) (xy 54.254488 -315.87547)
			(xy 54.573166 -315.87547) (xy 54.573166 -315.824054) (xy 54.581209 -315.773272) (xy 54.597097 -315.724373)
			(xy 54.62044 -315.678561) (xy 54.650661 -315.636965) (xy 54.687017 -315.600609) (xy 54.728613 -315.570388)
			(xy 54.774425 -315.547045) (xy 54.823324 -315.531157) (xy 54.874106 -315.523114) (xy 54.925522 -315.523114)
			(xy 54.976304 -315.531157) (xy 55.025203 -315.547045) (xy 55.071015 -315.570388) (xy 55.112611 -315.600609)
			(xy 55.148967 -315.636965) (xy 55.179188 -315.678561) (xy 55.202531 -315.724373) (xy 55.218419 -315.773272)
			(xy 55.226462 -315.824054) (xy 55.226966 -315.849762) (xy 55.54397 -315.849762) (xy 55.54793 -315.800708)
			(xy 55.559707 -315.752924) (xy 55.578998 -315.707648) (xy 55.605301 -315.666052) (xy 55.637936 -315.629215)
			(xy 55.676057 -315.59809) (xy 55.718678 -315.573483) (xy 55.764694 -315.556031) (xy 55.812913 -315.546187)
			(xy 55.862088 -315.544206) (xy 55.910943 -315.550138) (xy 55.958214 -315.56383) (xy 56.002676 -315.584928)
			(xy 56.043179 -315.612884) (xy 56.078672 -315.646976) (xy 56.108237 -315.68632) (xy 56.131108 -315.729897)
			(xy 56.146692 -315.776578) (xy 56.154587 -315.825155) (xy 56.155082 -315.849762) (xy 56.154587 -315.874369)
			(xy 56.154408 -315.87547) (xy 56.47334 -315.87547) (xy 56.47334 -315.824054) (xy 56.481383 -315.773272)
			(xy 56.497271 -315.724373) (xy 56.520614 -315.678561) (xy 56.550835 -315.636965) (xy 56.587191 -315.600609)
			(xy 56.628787 -315.570388) (xy 56.674599 -315.547045) (xy 56.723498 -315.531157) (xy 56.77428 -315.523114)
			(xy 56.825696 -315.523114) (xy 56.876478 -315.531157) (xy 56.925377 -315.547045) (xy 56.971189 -315.570388)
			(xy 57.012785 -315.600609) (xy 57.049141 -315.636965) (xy 57.079362 -315.678561) (xy 57.102705 -315.724373)
			(xy 57.118593 -315.773272) (xy 57.126636 -315.824054) (xy 57.12714 -315.849762) (xy 57.444144 -315.849762)
			(xy 57.448104 -315.800708) (xy 57.459881 -315.752924) (xy 57.479172 -315.707648) (xy 57.505475 -315.666052)
			(xy 57.53811 -315.629215) (xy 57.576231 -315.59809) (xy 57.618852 -315.573483) (xy 57.664868 -315.556031)
			(xy 57.713087 -315.546187) (xy 57.762262 -315.544206) (xy 57.811117 -315.550138) (xy 57.858388 -315.56383)
			(xy 57.90285 -315.584928) (xy 57.943353 -315.612884) (xy 57.978846 -315.646976) (xy 58.008411 -315.68632)
			(xy 58.031282 -315.729897) (xy 58.046866 -315.776578) (xy 58.054761 -315.825155) (xy 58.055256 -315.849762)
			(xy 58.054761 -315.874369) (xy 58.054582 -315.87547) (xy 58.37326 -315.87547) (xy 58.37326 -315.824054)
			(xy 58.381303 -315.773272) (xy 58.397191 -315.724373) (xy 58.420534 -315.678561) (xy 58.450755 -315.636965)
			(xy 58.487111 -315.600609) (xy 58.528707 -315.570388) (xy 58.574519 -315.547045) (xy 58.623418 -315.531157)
			(xy 58.6742 -315.523114) (xy 58.725616 -315.523114) (xy 58.776398 -315.531157) (xy 58.825297 -315.547045)
			(xy 58.871109 -315.570388) (xy 58.912705 -315.600609) (xy 58.949061 -315.636965) (xy 58.979282 -315.678561)
			(xy 59.002625 -315.724373) (xy 59.018513 -315.773272) (xy 59.026556 -315.824054) (xy 59.02706 -315.849762)
			(xy 59.344064 -315.849762) (xy 59.348024 -315.800708) (xy 59.359801 -315.752924) (xy 59.379092 -315.707648)
			(xy 59.405395 -315.666052) (xy 59.43803 -315.629215) (xy 59.476151 -315.59809) (xy 59.518772 -315.573483)
			(xy 59.564788 -315.556031) (xy 59.613007 -315.546187) (xy 59.662182 -315.544206) (xy 59.711037 -315.550138)
			(xy 59.758308 -315.56383) (xy 59.80277 -315.584928) (xy 59.843273 -315.612884) (xy 59.878766 -315.646976)
			(xy 59.908331 -315.68632) (xy 59.931202 -315.729897) (xy 59.946786 -315.776578) (xy 59.954681 -315.825155)
			(xy 59.955176 -315.849762) (xy 59.954681 -315.874369) (xy 59.954502 -315.87547) (xy 60.27318 -315.87547)
			(xy 60.27318 -315.824054) (xy 60.281223 -315.773272) (xy 60.297111 -315.724373) (xy 60.320454 -315.678561)
			(xy 60.350675 -315.636965) (xy 60.387031 -315.600609) (xy 60.428627 -315.570388) (xy 60.474439 -315.547045)
			(xy 60.523338 -315.531157) (xy 60.57412 -315.523114) (xy 60.625536 -315.523114) (xy 60.676318 -315.531157)
			(xy 60.725217 -315.547045) (xy 60.771029 -315.570388) (xy 60.812625 -315.600609) (xy 60.848981 -315.636965)
			(xy 60.879202 -315.678561) (xy 60.902545 -315.724373) (xy 60.918433 -315.773272) (xy 60.926476 -315.824054)
			(xy 60.92698 -315.849762) (xy 61.243984 -315.849762) (xy 61.247944 -315.800708) (xy 61.259721 -315.752924)
			(xy 61.279012 -315.707648) (xy 61.305315 -315.666052) (xy 61.33795 -315.629215) (xy 61.376071 -315.59809)
			(xy 61.418692 -315.573483) (xy 61.464708 -315.556031) (xy 61.512927 -315.546187) (xy 61.562102 -315.544206)
			(xy 61.610957 -315.550138) (xy 61.658228 -315.56383) (xy 61.70269 -315.584928) (xy 61.743193 -315.612884)
			(xy 61.778686 -315.646976) (xy 61.808251 -315.68632) (xy 61.831122 -315.729897) (xy 61.846706 -315.776578)
			(xy 61.854601 -315.825155) (xy 61.855096 -315.849762) (xy 61.854601 -315.874369) (xy 61.854422 -315.87547)
			(xy 62.1731 -315.87547) (xy 62.1731 -315.824054) (xy 62.181143 -315.773272) (xy 62.197031 -315.724373)
			(xy 62.220374 -315.678561) (xy 62.250595 -315.636965) (xy 62.286951 -315.600609) (xy 62.328547 -315.570388)
			(xy 62.374359 -315.547045) (xy 62.423258 -315.531157) (xy 62.47404 -315.523114) (xy 62.525456 -315.523114)
			(xy 62.576238 -315.531157) (xy 62.625137 -315.547045) (xy 62.670949 -315.570388) (xy 62.712545 -315.600609)
			(xy 62.748901 -315.636965) (xy 62.779122 -315.678561) (xy 62.802465 -315.724373) (xy 62.818353 -315.773272)
			(xy 62.826396 -315.824054) (xy 62.8269 -315.849762) (xy 63.144158 -315.849762) (xy 63.148118 -315.800708)
			(xy 63.159895 -315.752924) (xy 63.179186 -315.707648) (xy 63.205489 -315.666052) (xy 63.238124 -315.629215)
			(xy 63.276245 -315.59809) (xy 63.318866 -315.573483) (xy 63.364882 -315.556031) (xy 63.413101 -315.546187)
			(xy 63.462276 -315.544206) (xy 63.511131 -315.550138) (xy 63.558402 -315.56383) (xy 63.602864 -315.584928)
			(xy 63.643367 -315.612884) (xy 63.67886 -315.646976) (xy 63.708425 -315.68632) (xy 63.731296 -315.729897)
			(xy 63.74688 -315.776578) (xy 63.754775 -315.825155) (xy 63.75527 -315.849762) (xy 63.754775 -315.874369)
			(xy 63.754596 -315.87547) (xy 64.073274 -315.87547) (xy 64.073274 -315.824054) (xy 64.081317 -315.773272)
			(xy 64.097205 -315.724373) (xy 64.120548 -315.678561) (xy 64.150769 -315.636965) (xy 64.187125 -315.600609)
			(xy 64.228721 -315.570388) (xy 64.274533 -315.547045) (xy 64.323432 -315.531157) (xy 64.374214 -315.523114)
			(xy 64.42563 -315.523114) (xy 64.476412 -315.531157) (xy 64.525311 -315.547045) (xy 64.571123 -315.570388)
			(xy 64.612719 -315.600609) (xy 64.649075 -315.636965) (xy 64.679296 -315.678561) (xy 64.702639 -315.724373)
			(xy 64.718527 -315.773272) (xy 64.72657 -315.824054) (xy 64.727074 -315.849762) (xy 65.044078 -315.849762)
			(xy 65.048038 -315.800708) (xy 65.059815 -315.752924) (xy 65.079106 -315.707648) (xy 65.105409 -315.666052)
			(xy 65.138044 -315.629215) (xy 65.176165 -315.59809) (xy 65.218786 -315.573483) (xy 65.264802 -315.556031)
			(xy 65.313021 -315.546187) (xy 65.362196 -315.544206) (xy 65.411051 -315.550138) (xy 65.458322 -315.56383)
			(xy 65.502784 -315.584928) (xy 65.543287 -315.612884) (xy 65.57878 -315.646976) (xy 65.608345 -315.68632)
			(xy 65.631216 -315.729897) (xy 65.6468 -315.776578) (xy 65.654695 -315.825155) (xy 65.65519 -315.849762)
			(xy 65.654695 -315.874369) (xy 65.654516 -315.87547) (xy 65.973194 -315.87547) (xy 65.973194 -315.824054)
			(xy 65.981237 -315.773272) (xy 65.997125 -315.724373) (xy 66.020468 -315.678561) (xy 66.050689 -315.636965)
			(xy 66.087045 -315.600609) (xy 66.128641 -315.570388) (xy 66.174453 -315.547045) (xy 66.223352 -315.531157)
			(xy 66.274134 -315.523114) (xy 66.32555 -315.523114) (xy 66.376332 -315.531157) (xy 66.425231 -315.547045)
			(xy 66.471043 -315.570388) (xy 66.512639 -315.600609) (xy 66.548995 -315.636965) (xy 66.579216 -315.678561)
			(xy 66.602559 -315.724373) (xy 66.618447 -315.773272) (xy 66.62649 -315.824054) (xy 66.626994 -315.849762)
			(xy 66.943998 -315.849762) (xy 66.947958 -315.800708) (xy 66.959735 -315.752924) (xy 66.979026 -315.707648)
			(xy 67.005329 -315.666052) (xy 67.037964 -315.629215) (xy 67.076085 -315.59809) (xy 67.118706 -315.573483)
			(xy 67.164722 -315.556031) (xy 67.212941 -315.546187) (xy 67.262116 -315.544206) (xy 67.310971 -315.550138)
			(xy 67.358242 -315.56383) (xy 67.402704 -315.584928) (xy 67.443207 -315.612884) (xy 67.4787 -315.646976)
			(xy 67.508265 -315.68632) (xy 67.531136 -315.729897) (xy 67.54672 -315.776578) (xy 67.554615 -315.825155)
			(xy 67.55511 -315.849762) (xy 67.554615 -315.874369) (xy 67.554436 -315.87547) (xy 67.873114 -315.87547)
			(xy 67.873114 -315.824054) (xy 67.881157 -315.773272) (xy 67.897045 -315.724373) (xy 67.920388 -315.678561)
			(xy 67.950609 -315.636965) (xy 67.986965 -315.600609) (xy 68.028561 -315.570388) (xy 68.074373 -315.547045)
			(xy 68.123272 -315.531157) (xy 68.174054 -315.523114) (xy 68.22547 -315.523114) (xy 68.276252 -315.531157)
			(xy 68.325151 -315.547045) (xy 68.370963 -315.570388) (xy 68.412559 -315.600609) (xy 68.448915 -315.636965)
			(xy 68.479136 -315.678561) (xy 68.502479 -315.724373) (xy 68.518367 -315.773272) (xy 68.52641 -315.824054)
			(xy 68.526914 -315.849762) (xy 68.844172 -315.849762) (xy 68.848132 -315.800708) (xy 68.859909 -315.752924)
			(xy 68.8792 -315.707648) (xy 68.905503 -315.666052) (xy 68.938138 -315.629215) (xy 68.976259 -315.59809)
			(xy 69.01888 -315.573483) (xy 69.064896 -315.556031) (xy 69.113115 -315.546187) (xy 69.16229 -315.544206)
			(xy 69.211145 -315.550138) (xy 69.258416 -315.56383) (xy 69.302878 -315.584928) (xy 69.343381 -315.612884)
			(xy 69.378874 -315.646976) (xy 69.408439 -315.68632) (xy 69.43131 -315.729897) (xy 69.446894 -315.776578)
			(xy 69.454789 -315.825155) (xy 69.455284 -315.849762) (xy 69.454789 -315.874369) (xy 69.45461 -315.87547)
			(xy 69.773288 -315.87547) (xy 69.773288 -315.824054) (xy 69.781331 -315.773272) (xy 69.797219 -315.724373)
			(xy 69.820562 -315.678561) (xy 69.850783 -315.636965) (xy 69.887139 -315.600609) (xy 69.928735 -315.570388)
			(xy 69.974547 -315.547045) (xy 70.023446 -315.531157) (xy 70.074228 -315.523114) (xy 70.125644 -315.523114)
			(xy 70.176426 -315.531157) (xy 70.225325 -315.547045) (xy 70.271137 -315.570388) (xy 70.312733 -315.600609)
			(xy 70.349089 -315.636965) (xy 70.37931 -315.678561) (xy 70.402653 -315.724373) (xy 70.418541 -315.773272)
			(xy 70.426584 -315.824054) (xy 70.427088 -315.849762) (xy 70.744092 -315.849762) (xy 70.748052 -315.800708)
			(xy 70.759829 -315.752924) (xy 70.77912 -315.707648) (xy 70.805423 -315.666052) (xy 70.838058 -315.629215)
			(xy 70.876179 -315.59809) (xy 70.9188 -315.573483) (xy 70.964816 -315.556031) (xy 71.013035 -315.546187)
			(xy 71.06221 -315.544206) (xy 71.111065 -315.550138) (xy 71.158336 -315.56383) (xy 71.202798 -315.584928)
			(xy 71.243301 -315.612884) (xy 71.278794 -315.646976) (xy 71.308359 -315.68632) (xy 71.33123 -315.729897)
			(xy 71.346814 -315.776578) (xy 71.354709 -315.825155) (xy 71.355204 -315.849762) (xy 71.354709 -315.874369)
			(xy 71.346814 -315.922946) (xy 71.33123 -315.969627) (xy 71.308359 -316.013204) (xy 71.278794 -316.052548)
			(xy 71.243301 -316.08664) (xy 71.202798 -316.114596) (xy 71.158336 -316.135694) (xy 71.111065 -316.149386)
			(xy 71.06221 -316.155318) (xy 71.013035 -316.153337) (xy 70.964816 -316.143493) (xy 70.9188 -316.126041)
			(xy 70.876179 -316.101434) (xy 70.838058 -316.070309) (xy 70.805423 -316.033472) (xy 70.77912 -315.991876)
			(xy 70.759829 -315.9466) (xy 70.748052 -315.898816) (xy 70.744092 -315.849762) (xy 70.427088 -315.849762)
			(xy 70.426584 -315.87547) (xy 70.418541 -315.926252) (xy 70.402653 -315.975151) (xy 70.37931 -316.020963)
			(xy 70.349089 -316.062559) (xy 70.312733 -316.098915) (xy 70.271137 -316.129136) (xy 70.225325 -316.152479)
			(xy 70.176426 -316.168367) (xy 70.125644 -316.17641) (xy 70.074228 -316.17641) (xy 70.023446 -316.168367)
			(xy 69.974547 -316.152479) (xy 69.928735 -316.129136) (xy 69.887139 -316.098915) (xy 69.850783 -316.062559)
			(xy 69.820562 -316.020963) (xy 69.797219 -315.975151) (xy 69.781331 -315.926252) (xy 69.773288 -315.87547)
			(xy 69.45461 -315.87547) (xy 69.446894 -315.922946) (xy 69.43131 -315.969627) (xy 69.408439 -316.013204)
			(xy 69.378874 -316.052548) (xy 69.343381 -316.08664) (xy 69.302878 -316.114596) (xy 69.258416 -316.135694)
			(xy 69.211145 -316.149386) (xy 69.16229 -316.155318) (xy 69.113115 -316.153337) (xy 69.064896 -316.143493)
			(xy 69.01888 -316.126041) (xy 68.976259 -316.101434) (xy 68.938138 -316.070309) (xy 68.905503 -316.033472)
			(xy 68.8792 -315.991876) (xy 68.859909 -315.9466) (xy 68.848132 -315.898816) (xy 68.844172 -315.849762)
			(xy 68.526914 -315.849762) (xy 68.52641 -315.87547) (xy 68.518367 -315.926252) (xy 68.502479 -315.975151)
			(xy 68.479136 -316.020963) (xy 68.448915 -316.062559) (xy 68.412559 -316.098915) (xy 68.370963 -316.129136)
			(xy 68.325151 -316.152479) (xy 68.276252 -316.168367) (xy 68.22547 -316.17641) (xy 68.174054 -316.17641)
			(xy 68.123272 -316.168367) (xy 68.074373 -316.152479) (xy 68.028561 -316.129136) (xy 67.986965 -316.098915)
			(xy 67.950609 -316.062559) (xy 67.920388 -316.020963) (xy 67.897045 -315.975151) (xy 67.881157 -315.926252)
			(xy 67.873114 -315.87547) (xy 67.554436 -315.87547) (xy 67.54672 -315.922946) (xy 67.531136 -315.969627)
			(xy 67.508265 -316.013204) (xy 67.4787 -316.052548) (xy 67.443207 -316.08664) (xy 67.402704 -316.114596)
			(xy 67.358242 -316.135694) (xy 67.310971 -316.149386) (xy 67.262116 -316.155318) (xy 67.212941 -316.153337)
			(xy 67.164722 -316.143493) (xy 67.118706 -316.126041) (xy 67.076085 -316.101434) (xy 67.037964 -316.070309)
			(xy 67.005329 -316.033472) (xy 66.979026 -315.991876) (xy 66.959735 -315.9466) (xy 66.947958 -315.898816)
			(xy 66.943998 -315.849762) (xy 66.626994 -315.849762) (xy 66.62649 -315.87547) (xy 66.618447 -315.926252)
			(xy 66.602559 -315.975151) (xy 66.579216 -316.020963) (xy 66.548995 -316.062559) (xy 66.512639 -316.098915)
			(xy 66.471043 -316.129136) (xy 66.425231 -316.152479) (xy 66.376332 -316.168367) (xy 66.32555 -316.17641)
			(xy 66.274134 -316.17641) (xy 66.223352 -316.168367) (xy 66.174453 -316.152479) (xy 66.128641 -316.129136)
			(xy 66.087045 -316.098915) (xy 66.050689 -316.062559) (xy 66.020468 -316.020963) (xy 65.997125 -315.975151)
			(xy 65.981237 -315.926252) (xy 65.973194 -315.87547) (xy 65.654516 -315.87547) (xy 65.6468 -315.922946)
			(xy 65.631216 -315.969627) (xy 65.608345 -316.013204) (xy 65.57878 -316.052548) (xy 65.543287 -316.08664)
			(xy 65.502784 -316.114596) (xy 65.458322 -316.135694) (xy 65.411051 -316.149386) (xy 65.362196 -316.155318)
			(xy 65.313021 -316.153337) (xy 65.264802 -316.143493) (xy 65.218786 -316.126041) (xy 65.176165 -316.101434)
			(xy 65.138044 -316.070309) (xy 65.105409 -316.033472) (xy 65.079106 -315.991876) (xy 65.059815 -315.9466)
			(xy 65.048038 -315.898816) (xy 65.044078 -315.849762) (xy 64.727074 -315.849762) (xy 64.72657 -315.87547)
			(xy 64.718527 -315.926252) (xy 64.702639 -315.975151) (xy 64.679296 -316.020963) (xy 64.649075 -316.062559)
			(xy 64.612719 -316.098915) (xy 64.571123 -316.129136) (xy 64.525311 -316.152479) (xy 64.476412 -316.168367)
			(xy 64.42563 -316.17641) (xy 64.374214 -316.17641) (xy 64.323432 -316.168367) (xy 64.274533 -316.152479)
			(xy 64.228721 -316.129136) (xy 64.187125 -316.098915) (xy 64.150769 -316.062559) (xy 64.120548 -316.020963)
			(xy 64.097205 -315.975151) (xy 64.081317 -315.926252) (xy 64.073274 -315.87547) (xy 63.754596 -315.87547)
			(xy 63.74688 -315.922946) (xy 63.731296 -315.969627) (xy 63.708425 -316.013204) (xy 63.67886 -316.052548)
			(xy 63.643367 -316.08664) (xy 63.602864 -316.114596) (xy 63.558402 -316.135694) (xy 63.511131 -316.149386)
			(xy 63.462276 -316.155318) (xy 63.413101 -316.153337) (xy 63.364882 -316.143493) (xy 63.318866 -316.126041)
			(xy 63.276245 -316.101434) (xy 63.238124 -316.070309) (xy 63.205489 -316.033472) (xy 63.179186 -315.991876)
			(xy 63.159895 -315.9466) (xy 63.148118 -315.898816) (xy 63.144158 -315.849762) (xy 62.8269 -315.849762)
			(xy 62.826396 -315.87547) (xy 62.818353 -315.926252) (xy 62.802465 -315.975151) (xy 62.779122 -316.020963)
			(xy 62.748901 -316.062559) (xy 62.712545 -316.098915) (xy 62.670949 -316.129136) (xy 62.625137 -316.152479)
			(xy 62.576238 -316.168367) (xy 62.525456 -316.17641) (xy 62.47404 -316.17641) (xy 62.423258 -316.168367)
			(xy 62.374359 -316.152479) (xy 62.328547 -316.129136) (xy 62.286951 -316.098915) (xy 62.250595 -316.062559)
			(xy 62.220374 -316.020963) (xy 62.197031 -315.975151) (xy 62.181143 -315.926252) (xy 62.1731 -315.87547)
			(xy 61.854422 -315.87547) (xy 61.846706 -315.922946) (xy 61.831122 -315.969627) (xy 61.808251 -316.013204)
			(xy 61.778686 -316.052548) (xy 61.743193 -316.08664) (xy 61.70269 -316.114596) (xy 61.658228 -316.135694)
			(xy 61.610957 -316.149386) (xy 61.562102 -316.155318) (xy 61.512927 -316.153337) (xy 61.464708 -316.143493)
			(xy 61.418692 -316.126041) (xy 61.376071 -316.101434) (xy 61.33795 -316.070309) (xy 61.305315 -316.033472)
			(xy 61.279012 -315.991876) (xy 61.259721 -315.9466) (xy 61.247944 -315.898816) (xy 61.243984 -315.849762)
			(xy 60.92698 -315.849762) (xy 60.926476 -315.87547) (xy 60.918433 -315.926252) (xy 60.902545 -315.975151)
			(xy 60.879202 -316.020963) (xy 60.848981 -316.062559) (xy 60.812625 -316.098915) (xy 60.771029 -316.129136)
			(xy 60.725217 -316.152479) (xy 60.676318 -316.168367) (xy 60.625536 -316.17641) (xy 60.57412 -316.17641)
			(xy 60.523338 -316.168367) (xy 60.474439 -316.152479) (xy 60.428627 -316.129136) (xy 60.387031 -316.098915)
			(xy 60.350675 -316.062559) (xy 60.320454 -316.020963) (xy 60.297111 -315.975151) (xy 60.281223 -315.926252)
			(xy 60.27318 -315.87547) (xy 59.954502 -315.87547) (xy 59.946786 -315.922946) (xy 59.931202 -315.969627)
			(xy 59.908331 -316.013204) (xy 59.878766 -316.052548) (xy 59.843273 -316.08664) (xy 59.80277 -316.114596)
			(xy 59.758308 -316.135694) (xy 59.711037 -316.149386) (xy 59.662182 -316.155318) (xy 59.613007 -316.153337)
			(xy 59.564788 -316.143493) (xy 59.518772 -316.126041) (xy 59.476151 -316.101434) (xy 59.43803 -316.070309)
			(xy 59.405395 -316.033472) (xy 59.379092 -315.991876) (xy 59.359801 -315.9466) (xy 59.348024 -315.898816)
			(xy 59.344064 -315.849762) (xy 59.02706 -315.849762) (xy 59.026556 -315.87547) (xy 59.018513 -315.926252)
			(xy 59.002625 -315.975151) (xy 58.979282 -316.020963) (xy 58.949061 -316.062559) (xy 58.912705 -316.098915)
			(xy 58.871109 -316.129136) (xy 58.825297 -316.152479) (xy 58.776398 -316.168367) (xy 58.725616 -316.17641)
			(xy 58.6742 -316.17641) (xy 58.623418 -316.168367) (xy 58.574519 -316.152479) (xy 58.528707 -316.129136)
			(xy 58.487111 -316.098915) (xy 58.450755 -316.062559) (xy 58.420534 -316.020963) (xy 58.397191 -315.975151)
			(xy 58.381303 -315.926252) (xy 58.37326 -315.87547) (xy 58.054582 -315.87547) (xy 58.046866 -315.922946)
			(xy 58.031282 -315.969627) (xy 58.008411 -316.013204) (xy 57.978846 -316.052548) (xy 57.943353 -316.08664)
			(xy 57.90285 -316.114596) (xy 57.858388 -316.135694) (xy 57.811117 -316.149386) (xy 57.762262 -316.155318)
			(xy 57.713087 -316.153337) (xy 57.664868 -316.143493) (xy 57.618852 -316.126041) (xy 57.576231 -316.101434)
			(xy 57.53811 -316.070309) (xy 57.505475 -316.033472) (xy 57.479172 -315.991876) (xy 57.459881 -315.9466)
			(xy 57.448104 -315.898816) (xy 57.444144 -315.849762) (xy 57.12714 -315.849762) (xy 57.126636 -315.87547)
			(xy 57.118593 -315.926252) (xy 57.102705 -315.975151) (xy 57.079362 -316.020963) (xy 57.049141 -316.062559)
			(xy 57.012785 -316.098915) (xy 56.971189 -316.129136) (xy 56.925377 -316.152479) (xy 56.876478 -316.168367)
			(xy 56.825696 -316.17641) (xy 56.77428 -316.17641) (xy 56.723498 -316.168367) (xy 56.674599 -316.152479)
			(xy 56.628787 -316.129136) (xy 56.587191 -316.098915) (xy 56.550835 -316.062559) (xy 56.520614 -316.020963)
			(xy 56.497271 -315.975151) (xy 56.481383 -315.926252) (xy 56.47334 -315.87547) (xy 56.154408 -315.87547)
			(xy 56.146692 -315.922946) (xy 56.131108 -315.969627) (xy 56.108237 -316.013204) (xy 56.078672 -316.052548)
			(xy 56.043179 -316.08664) (xy 56.002676 -316.114596) (xy 55.958214 -316.135694) (xy 55.910943 -316.149386)
			(xy 55.862088 -316.155318) (xy 55.812913 -316.153337) (xy 55.764694 -316.143493) (xy 55.718678 -316.126041)
			(xy 55.676057 -316.101434) (xy 55.637936 -316.070309) (xy 55.605301 -316.033472) (xy 55.578998 -315.991876)
			(xy 55.559707 -315.9466) (xy 55.54793 -315.898816) (xy 55.54397 -315.849762) (xy 55.226966 -315.849762)
			(xy 55.226462 -315.87547) (xy 55.218419 -315.926252) (xy 55.202531 -315.975151) (xy 55.179188 -316.020963)
			(xy 55.148967 -316.062559) (xy 55.112611 -316.098915) (xy 55.071015 -316.129136) (xy 55.025203 -316.152479)
			(xy 54.976304 -316.168367) (xy 54.925522 -316.17641) (xy 54.874106 -316.17641) (xy 54.823324 -316.168367)
			(xy 54.774425 -316.152479) (xy 54.728613 -316.129136) (xy 54.687017 -316.098915) (xy 54.650661 -316.062559)
			(xy 54.62044 -316.020963) (xy 54.597097 -315.975151) (xy 54.581209 -315.926252) (xy 54.573166 -315.87547)
			(xy 54.254488 -315.87547) (xy 54.246772 -315.922946) (xy 54.231188 -315.969627) (xy 54.208317 -316.013204)
			(xy 54.178752 -316.052548) (xy 54.143259 -316.08664) (xy 54.102756 -316.114596) (xy 54.058294 -316.135694)
			(xy 54.011023 -316.149386) (xy 53.962168 -316.155318) (xy 53.912993 -316.153337) (xy 53.864774 -316.143493)
			(xy 53.818758 -316.126041) (xy 53.776137 -316.101434) (xy 53.738016 -316.070309) (xy 53.705381 -316.033472)
			(xy 53.679078 -315.991876) (xy 53.659787 -315.9466) (xy 53.64801 -315.898816) (xy 53.64405 -315.849762)
			(xy 53.327046 -315.849762) (xy 53.326542 -315.87547) (xy 53.318499 -315.926252) (xy 53.302611 -315.975151)
			(xy 53.279268 -316.020963) (xy 53.249047 -316.062559) (xy 53.212691 -316.098915) (xy 53.171095 -316.129136)
			(xy 53.125283 -316.152479) (xy 53.076384 -316.168367) (xy 53.025602 -316.17641) (xy 52.974186 -316.17641)
			(xy 52.923404 -316.168367) (xy 52.874505 -316.152479) (xy 52.828693 -316.129136) (xy 52.787097 -316.098915)
			(xy 52.750741 -316.062559) (xy 52.72052 -316.020963) (xy 52.697177 -315.975151) (xy 52.681289 -315.926252)
			(xy 52.673246 -315.87547) (xy 52.354568 -315.87547) (xy 52.346852 -315.922946) (xy 52.331268 -315.969627)
			(xy 52.308397 -316.013204) (xy 52.278832 -316.052548) (xy 52.243339 -316.08664) (xy 52.202836 -316.114596)
			(xy 52.158374 -316.135694) (xy 52.111103 -316.149386) (xy 52.062248 -316.155318) (xy 52.013073 -316.153337)
			(xy 51.964854 -316.143493) (xy 51.918838 -316.126041) (xy 51.876217 -316.101434) (xy 51.838096 -316.070309)
			(xy 51.805461 -316.033472) (xy 51.779158 -315.991876) (xy 51.759867 -315.9466) (xy 51.74809 -315.898816)
			(xy 51.74413 -315.849762) (xy 51.427126 -315.849762) (xy 51.426622 -315.87547) (xy 51.418579 -315.926252)
			(xy 51.402691 -315.975151) (xy 51.379348 -316.020963) (xy 51.349127 -316.062559) (xy 51.312771 -316.098915)
			(xy 51.271175 -316.129136) (xy 51.225363 -316.152479) (xy 51.176464 -316.168367) (xy 51.125682 -316.17641)
			(xy 51.074266 -316.17641) (xy 51.023484 -316.168367) (xy 50.974585 -316.152479) (xy 50.928773 -316.129136)
			(xy 50.887177 -316.098915) (xy 50.850821 -316.062559) (xy 50.8206 -316.020963) (xy 50.797257 -315.975151)
			(xy 50.781369 -315.926252) (xy 50.773326 -315.87547) (xy 50.454394 -315.87547) (xy 50.446678 -315.922946)
			(xy 50.431094 -315.969627) (xy 50.408223 -316.013204) (xy 50.378658 -316.052548) (xy 50.343165 -316.08664)
			(xy 50.302662 -316.114596) (xy 50.2582 -316.135694) (xy 50.210929 -316.149386) (xy 50.162074 -316.155318)
			(xy 50.112899 -316.153337) (xy 50.06468 -316.143493) (xy 50.018664 -316.126041) (xy 49.976043 -316.101434)
			(xy 49.937922 -316.070309) (xy 49.905287 -316.033472) (xy 49.878984 -315.991876) (xy 49.859693 -315.9466)
			(xy 49.847916 -315.898816) (xy 49.843956 -315.849762) (xy 49.526952 -315.849762) (xy 49.526448 -315.87547)
			(xy 49.518405 -315.926252) (xy 49.502517 -315.975151) (xy 49.479174 -316.020963) (xy 49.448953 -316.062559)
			(xy 49.412597 -316.098915) (xy 49.371001 -316.129136) (xy 49.325189 -316.152479) (xy 49.27629 -316.168367)
			(xy 49.225508 -316.17641) (xy 49.174092 -316.17641) (xy 49.12331 -316.168367) (xy 49.074411 -316.152479)
			(xy 49.028599 -316.129136) (xy 48.987003 -316.098915) (xy 48.950647 -316.062559) (xy 48.920426 -316.020963)
			(xy 48.897083 -315.975151) (xy 48.881195 -315.926252) (xy 48.873152 -315.87547) (xy 48.554474 -315.87547)
			(xy 48.546758 -315.922946) (xy 48.531174 -315.969627) (xy 48.508303 -316.013204) (xy 48.478738 -316.052548)
			(xy 48.443245 -316.08664) (xy 48.402742 -316.114596) (xy 48.35828 -316.135694) (xy 48.311009 -316.149386)
			(xy 48.262154 -316.155318) (xy 48.212979 -316.153337) (xy 48.16476 -316.143493) (xy 48.118744 -316.126041)
			(xy 48.076123 -316.101434) (xy 48.038002 -316.070309) (xy 48.005367 -316.033472) (xy 47.979064 -315.991876)
			(xy 47.959773 -315.9466) (xy 47.947996 -315.898816) (xy 47.944036 -315.849762) (xy 47.627032 -315.849762)
			(xy 47.626528 -315.87547) (xy 47.618485 -315.926252) (xy 47.602597 -315.975151) (xy 47.579254 -316.020963)
			(xy 47.549033 -316.062559) (xy 47.512677 -316.098915) (xy 47.471081 -316.129136) (xy 47.425269 -316.152479)
			(xy 47.37637 -316.168367) (xy 47.325588 -316.17641) (xy 47.274172 -316.17641) (xy 47.22339 -316.168367)
			(xy 47.174491 -316.152479) (xy 47.128679 -316.129136) (xy 47.087083 -316.098915) (xy 47.050727 -316.062559)
			(xy 47.020506 -316.020963) (xy 46.997163 -315.975151) (xy 46.981275 -315.926252) (xy 46.973232 -315.87547)
			(xy 46.654554 -315.87547) (xy 46.646838 -315.922946) (xy 46.631254 -315.969627) (xy 46.608383 -316.013204)
			(xy 46.578818 -316.052548) (xy 46.543325 -316.08664) (xy 46.502822 -316.114596) (xy 46.45836 -316.135694)
			(xy 46.411089 -316.149386) (xy 46.362234 -316.155318) (xy 46.313059 -316.153337) (xy 46.26484 -316.143493)
			(xy 46.218824 -316.126041) (xy 46.176203 -316.101434) (xy 46.138082 -316.070309) (xy 46.105447 -316.033472)
			(xy 46.079144 -315.991876) (xy 46.059853 -315.9466) (xy 46.048076 -315.898816) (xy 46.044116 -315.849762)
			(xy 45.727112 -315.849762) (xy 45.726608 -315.87547) (xy 45.718565 -315.926252) (xy 45.702677 -315.975151)
			(xy 45.679334 -316.020963) (xy 45.649113 -316.062559) (xy 45.612757 -316.098915) (xy 45.571161 -316.129136)
			(xy 45.525349 -316.152479) (xy 45.47645 -316.168367) (xy 45.425668 -316.17641) (xy 45.374252 -316.17641)
			(xy 45.32347 -316.168367) (xy 45.274571 -316.152479) (xy 45.228759 -316.129136) (xy 45.187163 -316.098915)
			(xy 45.150807 -316.062559) (xy 45.120586 -316.020963) (xy 45.097243 -315.975151) (xy 45.081355 -315.926252)
			(xy 45.073312 -315.87547) (xy 44.75438 -315.87547) (xy 44.746664 -315.922946) (xy 44.73108 -315.969627)
			(xy 44.708209 -316.013204) (xy 44.678644 -316.052548) (xy 44.643151 -316.08664) (xy 44.602648 -316.114596)
			(xy 44.558186 -316.135694) (xy 44.510915 -316.149386) (xy 44.46206 -316.155318) (xy 44.412885 -316.153337)
			(xy 44.364666 -316.143493) (xy 44.31865 -316.126041) (xy 44.276029 -316.101434) (xy 44.237908 -316.070309)
			(xy 44.205273 -316.033472) (xy 44.17897 -315.991876) (xy 44.159679 -315.9466) (xy 44.147902 -315.898816)
			(xy 44.143942 -315.849762) (xy 43.826938 -315.849762) (xy 43.826434 -315.87547) (xy 43.818391 -315.926252)
			(xy 43.802503 -315.975151) (xy 43.77916 -316.020963) (xy 43.748939 -316.062559) (xy 43.712583 -316.098915)
			(xy 43.670987 -316.129136) (xy 43.625175 -316.152479) (xy 43.576276 -316.168367) (xy 43.525494 -316.17641)
			(xy 43.474078 -316.17641) (xy 43.423296 -316.168367) (xy 43.374397 -316.152479) (xy 43.328585 -316.129136)
			(xy 43.286989 -316.098915) (xy 43.250633 -316.062559) (xy 43.220412 -316.020963) (xy 43.197069 -315.975151)
			(xy 43.181181 -315.926252) (xy 43.173138 -315.87547) (xy 42.85446 -315.87547) (xy 42.846744 -315.922946)
			(xy 42.83116 -315.969627) (xy 42.808289 -316.013204) (xy 42.778724 -316.052548) (xy 42.743231 -316.08664)
			(xy 42.702728 -316.114596) (xy 42.658266 -316.135694) (xy 42.610995 -316.149386) (xy 42.56214 -316.155318)
			(xy 42.512965 -316.153337) (xy 42.464746 -316.143493) (xy 42.41873 -316.126041) (xy 42.376109 -316.101434)
			(xy 42.337988 -316.070309) (xy 42.305353 -316.033472) (xy 42.27905 -315.991876) (xy 42.259759 -315.9466)
			(xy 42.247982 -315.898816) (xy 42.244022 -315.849762) (xy 41.927018 -315.849762) (xy 41.926514 -315.87547)
			(xy 41.918471 -315.926252) (xy 41.902583 -315.975151) (xy 41.87924 -316.020963) (xy 41.849019 -316.062559)
			(xy 41.812663 -316.098915) (xy 41.771067 -316.129136) (xy 41.725255 -316.152479) (xy 41.676356 -316.168367)
			(xy 41.625574 -316.17641) (xy 41.574158 -316.17641) (xy 41.523376 -316.168367) (xy 41.474477 -316.152479)
			(xy 41.428665 -316.129136) (xy 41.387069 -316.098915) (xy 41.350713 -316.062559) (xy 41.320492 -316.020963)
			(xy 41.297149 -315.975151) (xy 41.281261 -315.926252) (xy 41.273218 -315.87547) (xy 40.95454 -315.87547)
			(xy 40.946824 -315.922946) (xy 40.93124 -315.969627) (xy 40.908369 -316.013204) (xy 40.878804 -316.052548)
			(xy 40.843311 -316.08664) (xy 40.802808 -316.114596) (xy 40.758346 -316.135694) (xy 40.711075 -316.149386)
			(xy 40.66222 -316.155318) (xy 40.613045 -316.153337) (xy 40.564826 -316.143493) (xy 40.51881 -316.126041)
			(xy 40.476189 -316.101434) (xy 40.438068 -316.070309) (xy 40.405433 -316.033472) (xy 40.37913 -315.991876)
			(xy 40.359839 -315.9466) (xy 40.348062 -315.898816) (xy 40.344102 -315.849762) (xy 40.027098 -315.849762)
			(xy 40.026594 -315.87547) (xy 40.018551 -315.926252) (xy 40.002663 -315.975151) (xy 39.97932 -316.020963)
			(xy 39.949099 -316.062559) (xy 39.912743 -316.098915) (xy 39.871147 -316.129136) (xy 39.825335 -316.152479)
			(xy 39.776436 -316.168367) (xy 39.725654 -316.17641) (xy 39.674238 -316.17641) (xy 39.623456 -316.168367)
			(xy 39.574557 -316.152479) (xy 39.528745 -316.129136) (xy 39.487149 -316.098915) (xy 39.450793 -316.062559)
			(xy 39.420572 -316.020963) (xy 39.397229 -315.975151) (xy 39.381341 -315.926252) (xy 39.373298 -315.87547)
			(xy 39.05462 -315.87547) (xy 39.046904 -315.922946) (xy 39.03132 -315.969627) (xy 39.008449 -316.013204)
			(xy 38.978884 -316.052548) (xy 38.943391 -316.08664) (xy 38.902888 -316.114596) (xy 38.858426 -316.135694)
			(xy 38.811155 -316.149386) (xy 38.7623 -316.155318) (xy 38.713125 -316.153337) (xy 38.664906 -316.143493)
			(xy 38.61889 -316.126041) (xy 38.576269 -316.101434) (xy 38.538148 -316.070309) (xy 38.505513 -316.033472)
			(xy 38.47921 -315.991876) (xy 38.459919 -315.9466) (xy 38.448142 -315.898816) (xy 38.444182 -315.849762)
			(xy 38.10508 -315.849762) (xy 38.104585 -315.874369) (xy 38.09669 -315.922946) (xy 38.081106 -315.969627)
			(xy 38.058235 -316.013204) (xy 38.02867 -316.052548) (xy 37.993177 -316.08664) (xy 37.952674 -316.114596)
			(xy 37.908212 -316.135694) (xy 37.860941 -316.149386) (xy 37.812086 -316.155318) (xy 37.762911 -316.153337)
			(xy 37.714692 -316.143493) (xy 37.668676 -316.126041) (xy 37.626055 -316.101434) (xy 37.587934 -316.070309)
			(xy 37.555299 -316.033472) (xy 37.528996 -315.991876) (xy 37.509705 -315.9466) (xy 37.497928 -315.898816)
			(xy 37.493968 -315.849762) (xy 37.15512 -315.849762) (xy 37.154625 -315.874369) (xy 37.14673 -315.922946)
			(xy 37.131146 -315.969627) (xy 37.108275 -316.013204) (xy 37.07871 -316.052548) (xy 37.043217 -316.08664)
			(xy 37.002714 -316.114596) (xy 36.958252 -316.135694) (xy 36.910981 -316.149386) (xy 36.862126 -316.155318)
			(xy 36.812951 -316.153337) (xy 36.764732 -316.143493) (xy 36.718716 -316.126041) (xy 36.676095 -316.101434)
			(xy 36.637974 -316.070309) (xy 36.605339 -316.033472) (xy 36.579036 -315.991876) (xy 36.559745 -315.9466)
			(xy 36.547968 -315.898816) (xy 36.544008 -315.849762) (xy 17.71396 -315.849762) (xy 17.71396 -318.22136)
			(xy 17.714396 -318.231424) (xy 17.722132 -318.250007) (xy 17.728946 -318.257428) (xy 19.13382 -319.662302)
			(xy 19.14122 -319.669145) (xy 19.159818 -319.676872) (xy 19.169888 -319.677288)
		)
		(stroke
			(width 0)
			(type solid)
		)
		(fill yes)
		(layer "In15.Cu")
		(net "P1V25_PEX0")
	)
	(gr_poly
		(pts
			(xy 112.999012 -70.286626) (xy 113.00755 -70.286073) (xy 113.023552 -70.280046) (xy 113.036709 -70.269124)
			(xy 113.04143 -70.261988) (xy 113.0427 -70.259448) (xy 113.089542 -70.17106) (xy 113.189061 -69.997502)
			(xy 113.295111 -69.827857) (xy 113.407538 -69.662369) (xy 113.52618 -69.501279) (xy 113.650866 -69.344819)
			(xy 113.781414 -69.193217) (xy 113.917635 -69.046691) (xy 114.059333 -68.905455) (xy 114.206302 -68.769711)
			(xy 114.358329 -68.639658) (xy 114.515194 -68.515483) (xy 114.595656 -68.456048) (xy 114.632994 -68.42887)
			(xy 114.715908 -68.369935) (xy 114.885631 -68.25775) (xy 115.059567 -68.152214) (xy 115.237454 -68.053485)
			(xy 115.419028 -67.961711) (xy 115.604016 -67.87703) (xy 115.792141 -67.799567) (xy 115.983121 -67.729439)
			(xy 116.176671 -67.666751) (xy 116.372501 -67.611597) (xy 116.570318 -67.56406) (xy 116.769826 -67.524209)
			(xy 116.970726 -67.492106) (xy 117.172718 -67.467798) (xy 117.375498 -67.451322) (xy 117.578764 -67.442701)
			(xy 117.680486 -67.441826) (xy 117.683788 -67.441826) (xy 117.684296 -67.441826) (xy 117.700044 -67.441572)
			(xy 117.700552 -67.441572) (xy 117.802718 -67.442075) (xy 118.006896 -67.450034) (xy 118.210611 -67.465919)
			(xy 118.399461 -67.488054) (xy 134.879332 -67.488054) (xy 134.883403 -67.432432) (xy 134.895529 -67.377995)
			(xy 134.915452 -67.325904) (xy 134.942748 -67.277269) (xy 134.976834 -67.233126) (xy 135.016983 -67.194417)
			(xy 135.062341 -67.161966) (xy 135.111941 -67.136465) (xy 135.164725 -67.118458) (xy 135.219568 -67.108328)
			(xy 135.275302 -67.106291) (xy 135.330739 -67.112391) (xy 135.384696 -67.126497) (xy 135.390469 -67.12895)
			(xy 156.466798 -67.12895) (xy 156.466798 -67.07445) (xy 156.474554 -67.020506) (xy 156.489908 -66.968215)
			(xy 156.512548 -66.918641) (xy 156.542012 -66.872793) (xy 156.577701 -66.831605) (xy 156.618888 -66.795915)
			(xy 156.664735 -66.766451) (xy 156.714309 -66.74381) (xy 156.7666 -66.728455) (xy 156.820544 -66.720699)
			(xy 156.847794 -66.720212) (xy 156.875164 -66.720679) (xy 156.929343 -66.728496) (xy 156.981847 -66.743985)
			(xy 157.031594 -66.766826) (xy 157.07756 -66.796551) (xy 157.098492 -66.814192) (xy 157.098746 -66.814446)
			(xy 157.10584 -66.820022) (xy 157.122751 -66.826274) (xy 157.131766 -66.826638) (xy 157.198822 -66.826638)
			(xy 157.207839 -66.826283) (xy 157.224756 -66.820033) (xy 157.231842 -66.814446) (xy 157.23235 -66.813938)
			(xy 157.253289 -66.796361) (xy 157.299221 -66.766719) (xy 157.348916 -66.743939) (xy 157.401354 -66.728488)
			(xy 157.455461 -66.720682) (xy 157.482794 -66.720212) (xy 157.510049 -66.720634) (xy 157.564003 -66.728391)
			(xy 157.616304 -66.743748) (xy 157.665888 -66.766391) (xy 157.711744 -66.79586) (xy 157.75294 -66.831556)
			(xy 157.788636 -66.872751) (xy 157.818106 -66.918607) (xy 157.84075 -66.96819) (xy 157.856108 -67.020491)
			(xy 157.863865 -67.074445) (xy 157.863865 -67.128955) (xy 157.856108 -67.182909) (xy 157.84075 -67.23521)
			(xy 157.818106 -67.284793) (xy 157.788636 -67.330649) (xy 157.75294 -67.371844) (xy 157.711744 -67.40754)
			(xy 157.665888 -67.437009) (xy 157.616304 -67.459652) (xy 157.564003 -67.475009) (xy 157.510049 -67.482766)
			(xy 157.482794 -67.483228) (xy 157.455423 -67.482783) (xy 157.401242 -67.474963) (xy 157.348738 -67.45947)
			(xy 157.298991 -67.436623) (xy 157.253026 -67.406892) (xy 157.232096 -67.389248) (xy 157.231842 -67.388994)
			(xy 157.224748 -67.383418) (xy 157.207837 -67.377165) (xy 157.198822 -67.376802) (xy 157.131766 -67.376802)
			(xy 157.122747 -67.377142) (xy 157.105831 -67.383402) (xy 157.098746 -67.388994) (xy 157.098238 -67.389502)
			(xy 157.077309 -67.40709) (xy 157.031373 -67.436729) (xy 156.981676 -67.459506) (xy 156.929236 -67.474955)
			(xy 156.875128 -67.482759) (xy 156.847794 -67.483228) (xy 156.820544 -67.482701) (xy 156.7666 -67.474945)
			(xy 156.714309 -67.45959) (xy 156.664735 -67.436949) (xy 156.618888 -67.407485) (xy 156.577701 -67.371795)
			(xy 156.542012 -67.330607) (xy 156.512548 -67.284759) (xy 156.489908 -67.235185) (xy 156.474554 -67.182894)
			(xy 156.466798 -67.12895) (xy 135.390469 -67.12895) (xy 135.436025 -67.148309) (xy 135.483631 -67.177363)
			(xy 135.526499 -67.213038) (xy 135.563716 -67.254575) (xy 135.594489 -67.301088) (xy 135.618161 -67.351585)
			(xy 135.634229 -67.404992) (xy 135.642349 -67.460168) (xy 135.642858 -67.488054) (xy 135.642349 -67.51594)
			(xy 135.639164 -67.537584) (xy 136.17143 -67.537584) (xy 136.175501 -67.481962) (xy 136.187627 -67.427525)
			(xy 136.20755 -67.375434) (xy 136.234846 -67.326799) (xy 136.268932 -67.282656) (xy 136.309081 -67.243947)
			(xy 136.354439 -67.211496) (xy 136.404039 -67.185995) (xy 136.456823 -67.167988) (xy 136.511666 -67.157858)
			(xy 136.5674 -67.155821) (xy 136.622837 -67.161921) (xy 136.676794 -67.176027) (xy 136.728123 -67.197839)
			(xy 136.775729 -67.226893) (xy 136.818597 -67.262568) (xy 136.855814 -67.304105) (xy 136.886587 -67.350618)
			(xy 136.910259 -67.401115) (xy 136.926327 -67.454522) (xy 136.934447 -67.509698) (xy 136.934956 -67.537584)
			(xy 136.934447 -67.56547) (xy 136.930402 -67.592956) (xy 137.445494 -67.592956) (xy 137.449565 -67.537334)
			(xy 137.461691 -67.482897) (xy 137.481614 -67.430806) (xy 137.50891 -67.382171) (xy 137.542996 -67.338028)
			(xy 137.583145 -67.299319) (xy 137.628503 -67.266868) (xy 137.678103 -67.241367) (xy 137.730887 -67.22336)
			(xy 137.78573 -67.21323) (xy 137.841464 -67.211193) (xy 137.896901 -67.217293) (xy 137.950858 -67.231399)
			(xy 138.002187 -67.253211) (xy 138.049793 -67.282265) (xy 138.092661 -67.31794) (xy 138.129878 -67.359477)
			(xy 138.160651 -67.40599) (xy 138.184323 -67.456487) (xy 138.19382 -67.488054) (xy 160.87928 -67.488054)
			(xy 160.883351 -67.432432) (xy 160.895477 -67.377995) (xy 160.9154 -67.325904) (xy 160.942696 -67.277269)
			(xy 160.976782 -67.233126) (xy 161.016931 -67.194417) (xy 161.062289 -67.161966) (xy 161.111889 -67.136465)
			(xy 161.164673 -67.118458) (xy 161.219516 -67.108328) (xy 161.27525 -67.106291) (xy 161.330687 -67.112391)
			(xy 161.384644 -67.126497) (xy 161.390424 -67.128953) (xy 182.466675 -67.128953) (xy 182.466675 -67.074447)
			(xy 182.474433 -67.020495) (xy 182.48979 -66.968196) (xy 182.512435 -66.918616) (xy 182.541905 -66.872763)
			(xy 182.577601 -66.831572) (xy 182.618797 -66.79588) (xy 182.664653 -66.766415) (xy 182.714236 -66.743776)
			(xy 182.766536 -66.728424) (xy 182.820489 -66.720672) (xy 182.847742 -66.720212) (xy 182.875111 -66.720709)
			(xy 182.929289 -66.728519) (xy 182.981792 -66.744001) (xy 183.031539 -66.766836) (xy 183.077507 -66.796554)
			(xy 183.09844 -66.814192) (xy 183.098694 -66.814446) (xy 183.105774 -66.820042) (xy 183.122696 -66.826282)
			(xy 183.131714 -66.826638) (xy 183.19877 -66.826638) (xy 183.207784 -66.826258) (xy 183.224701 -66.820026)
			(xy 183.23179 -66.814446) (xy 183.232298 -66.813938) (xy 183.253219 -66.796339) (xy 183.299156 -66.7667)
			(xy 183.348855 -66.743925) (xy 183.401297 -66.728478) (xy 183.455407 -66.720678) (xy 183.482742 -66.720212)
			(xy 183.509993 -66.720661) (xy 183.563939 -66.728422) (xy 183.616231 -66.743782) (xy 183.665806 -66.766427)
			(xy 183.711653 -66.795896) (xy 183.752841 -66.831589) (xy 183.788529 -66.87278) (xy 183.817993 -66.918631)
			(xy 183.840633 -66.968208) (xy 183.855986 -67.020502) (xy 183.863742 -67.074449) (xy 183.863742 -67.128951)
			(xy 183.855986 -67.182898) (xy 183.840633 -67.235192) (xy 183.817993 -67.284769) (xy 183.788529 -67.33062)
			(xy 183.752841 -67.371811) (xy 183.711653 -67.407504) (xy 183.665806 -67.436973) (xy 183.616231 -67.459618)
			(xy 183.563939 -67.474978) (xy 183.509993 -67.482739) (xy 183.482742 -67.483228) (xy 183.455372 -67.482755)
			(xy 183.401192 -67.474941) (xy 183.348689 -67.459455) (xy 183.298942 -67.436614) (xy 183.252975 -67.40689)
			(xy 183.232044 -67.389248) (xy 183.23179 -67.388994) (xy 183.224711 -67.383396) (xy 183.207788 -67.377157)
			(xy 183.19877 -67.376802) (xy 183.131714 -67.376802) (xy 183.122698 -67.377165) (xy 183.105781 -67.383408)
			(xy 183.098694 -67.388994) (xy 183.098186 -67.389502) (xy 183.077277 -67.407115) (xy 183.031335 -67.43675)
			(xy 182.981633 -67.459522) (xy 182.929189 -67.474965) (xy 182.875077 -67.482763) (xy 182.847742 -67.483228)
			(xy 182.820489 -67.482728) (xy 182.766536 -67.474976) (xy 182.714236 -67.459624) (xy 182.664653 -67.436985)
			(xy 182.618797 -67.40752) (xy 182.577601 -67.371828) (xy 182.541905 -67.330637) (xy 182.512435 -67.284784)
			(xy 182.48979 -67.235204) (xy 182.474433 -67.182905) (xy 182.466675 -67.128953) (xy 161.390424 -67.128953)
			(xy 161.435973 -67.148309) (xy 161.483579 -67.177363) (xy 161.526447 -67.213038) (xy 161.563664 -67.254575)
			(xy 161.594437 -67.301088) (xy 161.618109 -67.351585) (xy 161.634177 -67.404992) (xy 161.642297 -67.460168)
			(xy 161.642806 -67.488054) (xy 161.642297 -67.51594) (xy 161.639112 -67.537584) (xy 162.171378 -67.537584)
			(xy 162.175449 -67.481962) (xy 162.187575 -67.427525) (xy 162.207498 -67.375434) (xy 162.234794 -67.326799)
			(xy 162.26888 -67.282656) (xy 162.309029 -67.243947) (xy 162.354387 -67.211496) (xy 162.403987 -67.185995)
			(xy 162.456771 -67.167988) (xy 162.511614 -67.157858) (xy 162.567348 -67.155821) (xy 162.622785 -67.161921)
			(xy 162.676742 -67.176027) (xy 162.728071 -67.197839) (xy 162.775677 -67.226893) (xy 162.818545 -67.262568)
			(xy 162.855762 -67.304105) (xy 162.886535 -67.350618) (xy 162.910207 -67.401115) (xy 162.926275 -67.454522)
			(xy 162.934395 -67.509698) (xy 162.934904 -67.537584) (xy 162.934395 -67.56547) (xy 162.93035 -67.592956)
			(xy 163.445442 -67.592956) (xy 163.449513 -67.537334) (xy 163.461639 -67.482897) (xy 163.481562 -67.430806)
			(xy 163.508858 -67.382171) (xy 163.542944 -67.338028) (xy 163.583093 -67.299319) (xy 163.628451 -67.266868)
			(xy 163.678051 -67.241367) (xy 163.730835 -67.22336) (xy 163.785678 -67.21323) (xy 163.841412 -67.211193)
			(xy 163.896849 -67.217293) (xy 163.950806 -67.231399) (xy 164.002135 -67.253211) (xy 164.049741 -67.282265)
			(xy 164.092609 -67.31794) (xy 164.129826 -67.359477) (xy 164.160599 -67.40599) (xy 164.184271 -67.456487)
			(xy 164.193768 -67.488054) (xy 186.879228 -67.488054) (xy 186.883299 -67.432432) (xy 186.895425 -67.377995)
			(xy 186.915348 -67.325904) (xy 186.942644 -67.277269) (xy 186.97673 -67.233126) (xy 187.016879 -67.194417)
			(xy 187.062237 -67.161966) (xy 187.111837 -67.136465) (xy 187.164621 -67.118458) (xy 187.219464 -67.108328)
			(xy 187.275198 -67.106291) (xy 187.330635 -67.112391) (xy 187.384592 -67.126497) (xy 187.390362 -67.128949)
			(xy 208.466698 -67.128949) (xy 208.466698 -67.074451) (xy 208.474454 -67.020507) (xy 208.489808 -66.968216)
			(xy 208.512447 -66.918642) (xy 208.541911 -66.872794) (xy 208.577599 -66.831606) (xy 208.618786 -66.795917)
			(xy 208.664633 -66.766452) (xy 208.714206 -66.743811) (xy 208.766497 -66.728456) (xy 208.820441 -66.720699)
			(xy 208.84769 -66.720212) (xy 208.87506 -66.720681) (xy 208.929239 -66.728498) (xy 208.981742 -66.743986)
			(xy 209.031489 -66.766827) (xy 209.077456 -66.796551) (xy 209.098388 -66.814192) (xy 209.098642 -66.814446)
			(xy 209.105737 -66.82002) (xy 209.122647 -66.826273) (xy 209.131662 -66.826638) (xy 209.198718 -66.826638)
			(xy 209.207735 -66.826282) (xy 209.224651 -66.820033) (xy 209.231738 -66.814446) (xy 209.232246 -66.813938)
			(xy 209.253186 -66.796363) (xy 209.299119 -66.766721) (xy 209.348813 -66.743941) (xy 209.40125 -66.728489)
			(xy 209.455357 -66.720682) (xy 209.48269 -66.720212) (xy 209.509945 -66.720634) (xy 209.5639 -66.72839)
			(xy 209.616202 -66.743746) (xy 209.629349 -66.74975) (xy 223.930976 -66.74975) (xy 223.930976 -66.69525)
			(xy 223.938732 -66.641304) (xy 223.954085 -66.589012) (xy 223.976725 -66.539436) (xy 224.006188 -66.493587)
			(xy 224.041877 -66.452397) (xy 224.083064 -66.416705) (xy 224.128911 -66.387238) (xy 224.178485 -66.364595)
			(xy 224.230777 -66.349237) (xy 224.284722 -66.341478) (xy 224.311972 -66.34099) (xy 224.337143 -66.341398)
			(xy 224.38705 -66.348012) (xy 224.435654 -66.361129) (xy 224.459038 -66.370454) (xy 224.47161 -66.375293)
			(xy 224.498309 -66.378812) (xy 224.525001 -66.375236) (xy 224.549833 -66.364812) (xy 224.57108 -66.348264)
			(xy 224.587268 -66.326742) (xy 224.597273 -66.301738) (xy 224.599246 -66.288412) (xy 224.602964 -66.260871)
			(xy 224.617258 -66.207171) (xy 224.639194 -66.156114) (xy 224.668306 -66.10878) (xy 224.70398 -66.066172)
			(xy 224.745459 -66.029192) (xy 224.791865 -65.998622) (xy 224.842217 -65.975111) (xy 224.895447 -65.959155)
			(xy 224.950429 -65.951093) (xy 224.978214 -65.950592) (xy 225.005465 -65.951079) (xy 225.059411 -65.958837)
			(xy 225.111704 -65.974193) (xy 225.161279 -65.996835) (xy 225.207128 -66.026302) (xy 225.248317 -66.061993)
			(xy 225.284007 -66.103183) (xy 225.313472 -66.149033) (xy 225.336112 -66.198609) (xy 225.351466 -66.250903)
			(xy 225.359222 -66.304849) (xy 225.359222 -66.359351) (xy 225.351466 -66.413297) (xy 225.336112 -66.465591)
			(xy 225.313472 -66.515167) (xy 225.284007 -66.561017) (xy 225.248317 -66.602207) (xy 225.207128 -66.637898)
			(xy 225.161279 -66.667365) (xy 225.111704 -66.690007) (xy 225.059411 -66.705363) (xy 225.005465 -66.713121)
			(xy 224.978214 -66.713608) (xy 224.953042 -66.713205) (xy 224.903136 -66.706589) (xy 224.854532 -66.693469)
			(xy 224.831148 -66.684144) (xy 224.81854 -66.679409) (xy 224.791855 -66.675873) (xy 224.765174 -66.679432)
			(xy 224.740349 -66.689839) (xy 224.719106 -66.70637) (xy 224.702919 -66.727877) (xy 224.692914 -66.752866)
			(xy 224.69094 -66.766186) (xy 224.687234 -66.793729) (xy 224.67294 -66.84743) (xy 224.651003 -66.898488)
			(xy 224.621889 -66.945823) (xy 224.586215 -66.988431) (xy 224.544734 -67.025411) (xy 224.498326 -67.05598)
			(xy 224.447973 -67.079491) (xy 224.394741 -67.095445) (xy 224.339758 -67.103506) (xy 224.311972 -67.104006)
			(xy 224.284722 -67.103522) (xy 224.230777 -67.095763) (xy 224.178485 -67.080405) (xy 224.128911 -67.057762)
			(xy 224.083064 -67.028295) (xy 224.041877 -66.992603) (xy 224.006188 -66.951413) (xy 223.976725 -66.905564)
			(xy 223.954085 -66.855988) (xy 223.938732 -66.803696) (xy 223.930976 -66.74975) (xy 209.629349 -66.74975)
			(xy 209.665786 -66.76639) (xy 209.711642 -66.795859) (xy 209.752838 -66.831554) (xy 209.788535 -66.87275)
			(xy 209.818006 -66.918606) (xy 209.84065 -66.968189) (xy 209.856007 -67.020491) (xy 209.863765 -67.074445)
			(xy 209.863765 -67.128955) (xy 209.856007 -67.182909) (xy 209.84065 -67.235211) (xy 209.818006 -67.284794)
			(xy 209.788535 -67.33065) (xy 209.752838 -67.371846) (xy 209.711642 -67.407541) (xy 209.665786 -67.43701)
			(xy 209.616202 -67.459654) (xy 209.5639 -67.47501) (xy 209.509945 -67.482766) (xy 209.48269 -67.483228)
			(xy 209.455319 -67.482785) (xy 209.401138 -67.474965) (xy 209.348634 -67.459471) (xy 209.298887 -67.436624)
			(xy 209.252922 -67.406893) (xy 209.231992 -67.389248) (xy 209.231738 -67.388994) (xy 209.224645 -67.383417)
			(xy 209.207733 -67.377165) (xy 209.198718 -67.376802) (xy 209.131662 -67.376802) (xy 209.122643 -67.377141)
			(xy 209.105726 -67.383401) (xy 209.098642 -67.388994) (xy 209.098134 -67.389502) (xy 209.077207 -67.407092)
			(xy 209.03127 -67.436731) (xy 208.981573 -67.459508) (xy 208.929133 -67.474956) (xy 208.875024 -67.482759)
			(xy 208.84769 -67.483228) (xy 208.820441 -67.482701) (xy 208.766497 -67.474944) (xy 208.714206 -67.459589)
			(xy 208.664633 -67.436948) (xy 208.618786 -67.407483) (xy 208.577599 -67.371794) (xy 208.541911 -67.330606)
			(xy 208.512447 -67.284758) (xy 208.489808 -67.235184) (xy 208.474454 -67.182893) (xy 208.466698 -67.128949)
			(xy 187.390362 -67.128949) (xy 187.435921 -67.148309) (xy 187.483527 -67.177363) (xy 187.526395 -67.213038)
			(xy 187.563612 -67.254575) (xy 187.594385 -67.301088) (xy 187.618057 -67.351585) (xy 187.634125 -67.404992)
			(xy 187.642245 -67.460168) (xy 187.642754 -67.488054) (xy 187.642245 -67.51594) (xy 187.63906 -67.537584)
			(xy 188.171326 -67.537584) (xy 188.175397 -67.481962) (xy 188.187523 -67.427525) (xy 188.207446 -67.375434)
			(xy 188.234742 -67.326799) (xy 188.268828 -67.282656) (xy 188.308977 -67.243947) (xy 188.354335 -67.211496)
			(xy 188.403935 -67.185995) (xy 188.456719 -67.167988) (xy 188.511562 -67.157858) (xy 188.567296 -67.155821)
			(xy 188.622733 -67.161921) (xy 188.67669 -67.176027) (xy 188.728019 -67.197839) (xy 188.775625 -67.226893)
			(xy 188.818493 -67.262568) (xy 188.85571 -67.304105) (xy 188.886483 -67.350618) (xy 188.910155 -67.401115)
			(xy 188.926223 -67.454522) (xy 188.934343 -67.509698) (xy 188.934852 -67.537584) (xy 188.934343 -67.56547)
			(xy 188.930298 -67.592956) (xy 189.44539 -67.592956) (xy 189.449461 -67.537334) (xy 189.461587 -67.482897)
			(xy 189.48151 -67.430806) (xy 189.508806 -67.382171) (xy 189.542892 -67.338028) (xy 189.583041 -67.299319)
			(xy 189.628399 -67.266868) (xy 189.677999 -67.241367) (xy 189.730783 -67.22336) (xy 189.785626 -67.21323)
			(xy 189.84136 -67.211193) (xy 189.896797 -67.217293) (xy 189.950754 -67.231399) (xy 190.002083 -67.253211)
			(xy 190.049689 -67.282265) (xy 190.092557 -67.31794) (xy 190.129774 -67.359477) (xy 190.160547 -67.40599)
			(xy 190.184219 -67.456487) (xy 190.193716 -67.488054) (xy 212.879176 -67.488054) (xy 212.883247 -67.432432)
			(xy 212.895373 -67.377995) (xy 212.915296 -67.325904) (xy 212.942592 -67.277269) (xy 212.976678 -67.233126)
			(xy 213.016827 -67.194417) (xy 213.062185 -67.161966) (xy 213.111785 -67.136465) (xy 213.164569 -67.118458)
			(xy 213.219412 -67.108328) (xy 213.275146 -67.106291) (xy 213.330583 -67.112391) (xy 213.38454 -67.126497)
			(xy 213.435869 -67.148309) (xy 213.483475 -67.177363) (xy 213.526343 -67.213038) (xy 213.56356 -67.254575)
			(xy 213.594333 -67.301088) (xy 213.618005 -67.351585) (xy 213.634073 -67.404992) (xy 213.642193 -67.460168)
			(xy 213.642702 -67.488054) (xy 213.642193 -67.51594) (xy 213.639008 -67.537584) (xy 214.171274 -67.537584)
			(xy 214.175345 -67.481962) (xy 214.187471 -67.427525) (xy 214.207394 -67.375434) (xy 214.23469 -67.326799)
			(xy 214.268776 -67.282656) (xy 214.308925 -67.243947) (xy 214.354283 -67.211496) (xy 214.403883 -67.185995)
			(xy 214.456667 -67.167988) (xy 214.51151 -67.157858) (xy 214.567244 -67.155821) (xy 214.622681 -67.161921)
			(xy 214.676638 -67.176027) (xy 214.727967 -67.197839) (xy 214.775573 -67.226893) (xy 214.818441 -67.262568)
			(xy 214.855658 -67.304105) (xy 214.886431 -67.350618) (xy 214.910103 -67.401115) (xy 214.926171 -67.454522)
			(xy 214.934291 -67.509698) (xy 214.9348 -67.537584) (xy 214.934291 -67.56547) (xy 214.930246 -67.592956)
			(xy 215.445338 -67.592956) (xy 215.449409 -67.537334) (xy 215.461535 -67.482897) (xy 215.481458 -67.430806)
			(xy 215.508754 -67.382171) (xy 215.54284 -67.338028) (xy 215.582989 -67.299319) (xy 215.628347 -67.266868)
			(xy 215.677947 -67.241367) (xy 215.730731 -67.22336) (xy 215.785574 -67.21323) (xy 215.841308 -67.211193)
			(xy 215.896745 -67.217293) (xy 215.950702 -67.231399) (xy 216.002031 -67.253211) (xy 216.049637 -67.282265)
			(xy 216.092505 -67.31794) (xy 216.129722 -67.359477) (xy 216.160495 -67.40599) (xy 216.184167 -67.456487)
			(xy 216.200235 -67.509894) (xy 216.208355 -67.56507) (xy 216.208864 -67.592956) (xy 216.208355 -67.620842)
			(xy 216.200235 -67.676018) (xy 216.184167 -67.729425) (xy 216.160495 -67.779922) (xy 216.129722 -67.826435)
			(xy 216.092505 -67.867972) (xy 216.049637 -67.903647) (xy 216.002031 -67.932701) (xy 215.950702 -67.954513)
			(xy 215.896745 -67.968619) (xy 215.841308 -67.974719) (xy 215.785574 -67.972682) (xy 215.730731 -67.962552)
			(xy 215.677947 -67.944545) (xy 215.628347 -67.919044) (xy 215.582989 -67.886593) (xy 215.54284 -67.847884)
			(xy 215.508754 -67.803741) (xy 215.481458 -67.755106) (xy 215.461535 -67.703015) (xy 215.449409 -67.648578)
			(xy 215.445338 -67.592956) (xy 214.930246 -67.592956) (xy 214.926171 -67.620646) (xy 214.910103 -67.674053)
			(xy 214.886431 -67.72455) (xy 214.855658 -67.771063) (xy 214.818441 -67.8126) (xy 214.775573 -67.848275)
			(xy 214.727967 -67.877329) (xy 214.676638 -67.899141) (xy 214.622681 -67.913247) (xy 214.567244 -67.919347)
			(xy 214.51151 -67.91731) (xy 214.456667 -67.90718) (xy 214.403883 -67.889173) (xy 214.354283 -67.863672)
			(xy 214.308925 -67.831221) (xy 214.268776 -67.792512) (xy 214.23469 -67.748369) (xy 214.207394 -67.699734)
			(xy 214.187471 -67.647643) (xy 214.175345 -67.593206) (xy 214.171274 -67.537584) (xy 213.639008 -67.537584)
			(xy 213.634073 -67.571116) (xy 213.618005 -67.624523) (xy 213.594333 -67.67502) (xy 213.56356 -67.721533)
			(xy 213.526343 -67.76307) (xy 213.483475 -67.798745) (xy 213.435869 -67.827799) (xy 213.38454 -67.849611)
			(xy 213.330583 -67.863717) (xy 213.275146 -67.869817) (xy 213.219412 -67.86778) (xy 213.164569 -67.85765)
			(xy 213.111785 -67.839643) (xy 213.062185 -67.814142) (xy 213.016827 -67.781691) (xy 212.976678 -67.742982)
			(xy 212.942592 -67.698839) (xy 212.915296 -67.650204) (xy 212.895373 -67.598113) (xy 212.883247 -67.543676)
			(xy 212.879176 -67.488054) (xy 190.193716 -67.488054) (xy 190.200287 -67.509894) (xy 190.208407 -67.56507)
			(xy 190.208916 -67.592956) (xy 190.208407 -67.620842) (xy 190.200287 -67.676018) (xy 190.184219 -67.729425)
			(xy 190.160547 -67.779922) (xy 190.129774 -67.826435) (xy 190.092557 -67.867972) (xy 190.049689 -67.903647)
			(xy 190.002083 -67.932701) (xy 189.950754 -67.954513) (xy 189.896797 -67.968619) (xy 189.84136 -67.974719)
			(xy 189.785626 -67.972682) (xy 189.730783 -67.962552) (xy 189.677999 -67.944545) (xy 189.628399 -67.919044)
			(xy 189.583041 -67.886593) (xy 189.542892 -67.847884) (xy 189.508806 -67.803741) (xy 189.48151 -67.755106)
			(xy 189.461587 -67.703015) (xy 189.449461 -67.648578) (xy 189.44539 -67.592956) (xy 188.930298 -67.592956)
			(xy 188.926223 -67.620646) (xy 188.910155 -67.674053) (xy 188.886483 -67.72455) (xy 188.85571 -67.771063)
			(xy 188.818493 -67.8126) (xy 188.775625 -67.848275) (xy 188.728019 -67.877329) (xy 188.67669 -67.899141)
			(xy 188.622733 -67.913247) (xy 188.567296 -67.919347) (xy 188.511562 -67.91731) (xy 188.456719 -67.90718)
			(xy 188.403935 -67.889173) (xy 188.354335 -67.863672) (xy 188.308977 -67.831221) (xy 188.268828 -67.792512)
			(xy 188.234742 -67.748369) (xy 188.207446 -67.699734) (xy 188.187523 -67.647643) (xy 188.175397 -67.593206)
			(xy 188.171326 -67.537584) (xy 187.63906 -67.537584) (xy 187.634125 -67.571116) (xy 187.618057 -67.624523)
			(xy 187.594385 -67.67502) (xy 187.563612 -67.721533) (xy 187.526395 -67.76307) (xy 187.483527 -67.798745)
			(xy 187.435921 -67.827799) (xy 187.384592 -67.849611) (xy 187.330635 -67.863717) (xy 187.275198 -67.869817)
			(xy 187.219464 -67.86778) (xy 187.164621 -67.85765) (xy 187.111837 -67.839643) (xy 187.062237 -67.814142)
			(xy 187.016879 -67.781691) (xy 186.97673 -67.742982) (xy 186.942644 -67.698839) (xy 186.915348 -67.650204)
			(xy 186.895425 -67.598113) (xy 186.883299 -67.543676) (xy 186.879228 -67.488054) (xy 164.193768 -67.488054)
			(xy 164.200339 -67.509894) (xy 164.208459 -67.56507) (xy 164.208968 -67.592956) (xy 164.208459 -67.620842)
			(xy 164.200339 -67.676018) (xy 164.184271 -67.729425) (xy 164.160599 -67.779922) (xy 164.129826 -67.826435)
			(xy 164.092609 -67.867972) (xy 164.049741 -67.903647) (xy 164.002135 -67.932701) (xy 163.950806 -67.954513)
			(xy 163.896849 -67.968619) (xy 163.841412 -67.974719) (xy 163.785678 -67.972682) (xy 163.730835 -67.962552)
			(xy 163.678051 -67.944545) (xy 163.628451 -67.919044) (xy 163.583093 -67.886593) (xy 163.542944 -67.847884)
			(xy 163.508858 -67.803741) (xy 163.481562 -67.755106) (xy 163.461639 -67.703015) (xy 163.449513 -67.648578)
			(xy 163.445442 -67.592956) (xy 162.93035 -67.592956) (xy 162.926275 -67.620646) (xy 162.910207 -67.674053)
			(xy 162.886535 -67.72455) (xy 162.855762 -67.771063) (xy 162.818545 -67.8126) (xy 162.775677 -67.848275)
			(xy 162.728071 -67.877329) (xy 162.676742 -67.899141) (xy 162.622785 -67.913247) (xy 162.567348 -67.919347)
			(xy 162.511614 -67.91731) (xy 162.456771 -67.90718) (xy 162.403987 -67.889173) (xy 162.354387 -67.863672)
			(xy 162.309029 -67.831221) (xy 162.26888 -67.792512) (xy 162.234794 -67.748369) (xy 162.207498 -67.699734)
			(xy 162.187575 -67.647643) (xy 162.175449 -67.593206) (xy 162.171378 -67.537584) (xy 161.639112 -67.537584)
			(xy 161.634177 -67.571116) (xy 161.618109 -67.624523) (xy 161.594437 -67.67502) (xy 161.563664 -67.721533)
			(xy 161.526447 -67.76307) (xy 161.483579 -67.798745) (xy 161.435973 -67.827799) (xy 161.384644 -67.849611)
			(xy 161.330687 -67.863717) (xy 161.27525 -67.869817) (xy 161.219516 -67.86778) (xy 161.164673 -67.85765)
			(xy 161.111889 -67.839643) (xy 161.062289 -67.814142) (xy 161.016931 -67.781691) (xy 160.976782 -67.742982)
			(xy 160.942696 -67.698839) (xy 160.9154 -67.650204) (xy 160.895477 -67.598113) (xy 160.883351 -67.543676)
			(xy 160.87928 -67.488054) (xy 138.19382 -67.488054) (xy 138.200391 -67.509894) (xy 138.208511 -67.56507)
			(xy 138.20902 -67.592956) (xy 138.208511 -67.620842) (xy 138.200391 -67.676018) (xy 138.184323 -67.729425)
			(xy 138.160651 -67.779922) (xy 138.129878 -67.826435) (xy 138.092661 -67.867972) (xy 138.049793 -67.903647)
			(xy 138.002187 -67.932701) (xy 137.950858 -67.954513) (xy 137.896901 -67.968619) (xy 137.841464 -67.974719)
			(xy 137.78573 -67.972682) (xy 137.730887 -67.962552) (xy 137.678103 -67.944545) (xy 137.628503 -67.919044)
			(xy 137.583145 -67.886593) (xy 137.542996 -67.847884) (xy 137.50891 -67.803741) (xy 137.481614 -67.755106)
			(xy 137.461691 -67.703015) (xy 137.449565 -67.648578) (xy 137.445494 -67.592956) (xy 136.930402 -67.592956)
			(xy 136.926327 -67.620646) (xy 136.910259 -67.674053) (xy 136.886587 -67.72455) (xy 136.855814 -67.771063)
			(xy 136.818597 -67.8126) (xy 136.775729 -67.848275) (xy 136.728123 -67.877329) (xy 136.676794 -67.899141)
			(xy 136.622837 -67.913247) (xy 136.5674 -67.919347) (xy 136.511666 -67.91731) (xy 136.456823 -67.90718)
			(xy 136.404039 -67.889173) (xy 136.354439 -67.863672) (xy 136.309081 -67.831221) (xy 136.268932 -67.792512)
			(xy 136.234846 -67.748369) (xy 136.20755 -67.699734) (xy 136.187627 -67.647643) (xy 136.175501 -67.593206)
			(xy 136.17143 -67.537584) (xy 135.639164 -67.537584) (xy 135.634229 -67.571116) (xy 135.618161 -67.624523)
			(xy 135.594489 -67.67502) (xy 135.563716 -67.721533) (xy 135.526499 -67.76307) (xy 135.483631 -67.798745)
			(xy 135.436025 -67.827799) (xy 135.384696 -67.849611) (xy 135.330739 -67.863717) (xy 135.275302 -67.869817)
			(xy 135.219568 -67.86778) (xy 135.164725 -67.85765) (xy 135.111941 -67.839643) (xy 135.062341 -67.814142)
			(xy 135.016983 -67.781691) (xy 134.976834 -67.742982) (xy 134.942748 -67.698839) (xy 134.915452 -67.650204)
			(xy 134.895529 -67.598113) (xy 134.883403 -67.543676) (xy 134.879332 -67.488054) (xy 118.399461 -67.488054)
			(xy 118.413555 -67.489706) (xy 118.615422 -67.521358) (xy 118.815906 -67.560829) (xy 119.014706 -67.608058)
			(xy 119.211521 -67.662974) (xy 119.406055 -67.725494) (xy 119.598012 -67.795525) (xy 119.787105 -67.872959)
			(xy 119.973046 -67.957681) (xy 120.155556 -68.049562) (xy 120.334359 -68.148464) (xy 120.509185 -68.254237)
			(xy 120.67977 -68.366721) (xy 120.845856 -68.485748) (xy 120.975627 -68.586604) (xy 132.725414 -68.586604)
			(xy 132.725914 -68.559271) (xy 132.733715 -68.505165) (xy 132.749157 -68.452727) (xy 132.771926 -68.403029)
			(xy 132.801553 -68.357088) (xy 132.81914 -68.33616) (xy 132.819394 -68.335906) (xy 132.819648 -68.335652)
			(xy 132.825225 -68.328559) (xy 132.831476 -68.311647) (xy 132.83184 -68.302632) (xy 132.83184 -68.235576)
			(xy 132.831507 -68.226556) (xy 132.825244 -68.209639) (xy 132.819648 -68.202556) (xy 132.819394 -68.202302)
			(xy 132.81914 -68.202048) (xy 132.801563 -68.18111) (xy 132.771921 -68.135177) (xy 132.749141 -68.085482)
			(xy 132.73369 -68.033044) (xy 132.725884 -67.978938) (xy 132.725414 -67.951604) (xy 132.725859 -67.92435)
			(xy 132.733616 -67.870398) (xy 132.748973 -67.818098) (xy 132.771616 -67.768516) (xy 132.801086 -67.722662)
			(xy 132.836782 -67.681469) (xy 132.877977 -67.645775) (xy 132.923832 -67.616308) (xy 132.973415 -67.593666)
			(xy 133.025715 -67.578312) (xy 133.079668 -67.570558) (xy 133.106922 -67.570096) (xy 133.107176 -67.570096)
			(xy 133.13347 -67.570572) (xy 133.185558 -67.577814) (xy 133.236159 -67.592137) (xy 133.284315 -67.613269)
			(xy 133.329115 -67.640811) (xy 133.369711 -67.674241) (xy 133.387846 -67.693286) (xy 133.395403 -67.700744)
			(xy 133.414832 -67.70926) (xy 133.425438 -67.709796) (xy 133.499606 -67.709796) (xy 133.510238 -67.709383)
			(xy 133.529702 -67.700836) (xy 133.537198 -67.693286) (xy 133.555316 -67.67422) (xy 133.5959 -67.640765)
			(xy 133.640699 -67.613207) (xy 133.688861 -67.59207) (xy 133.739472 -67.577754) (xy 133.79157 -67.570533)
			(xy 133.817868 -67.570096) (xy 133.818122 -67.570096) (xy 133.845493 -67.57055) (xy 133.899672 -67.578371)
			(xy 133.952175 -67.593863) (xy 134.001922 -67.616707) (xy 134.047889 -67.646434) (xy 134.06882 -67.664076)
			(xy 134.069074 -67.66433) (xy 134.076161 -67.669915) (xy 134.093078 -67.676162) (xy 134.102094 -67.676522)
			(xy 134.16915 -67.676522) (xy 134.178164 -67.676136) (xy 134.195081 -67.669908) (xy 134.20217 -67.66433)
			(xy 134.202678 -67.663822) (xy 134.223604 -67.64623) (xy 134.269541 -67.616591) (xy 134.319238 -67.593814)
			(xy 134.371679 -67.578366) (xy 134.425788 -67.570564) (xy 134.453122 -67.570096) (xy 134.480374 -67.570557)
			(xy 134.534323 -67.578317) (xy 134.586618 -67.593675) (xy 134.636196 -67.616319) (xy 134.682046 -67.645788)
			(xy 134.723236 -67.681482) (xy 134.758928 -67.722675) (xy 134.788393 -67.768527) (xy 134.811034 -67.818106)
			(xy 134.826389 -67.870403) (xy 134.834145 -67.924352) (xy 134.83463 -67.951604) (xy 134.834148 -67.978937)
			(xy 134.826345 -68.033045) (xy 134.810899 -68.085484) (xy 134.788126 -68.135182) (xy 134.758494 -68.181121)
			(xy 134.740904 -68.202048) (xy 134.74065 -68.202302) (xy 134.740396 -68.202556) (xy 134.734821 -68.209651)
			(xy 134.728568 -68.226561) (xy 134.728204 -68.235576) (xy 134.728204 -68.302632) (xy 134.728545 -68.311651)
			(xy 134.734804 -68.328567) (xy 134.740396 -68.335652) (xy 134.74065 -68.335906) (xy 134.740904 -68.33616)
			(xy 134.758492 -68.357089) (xy 134.788131 -68.403025) (xy 134.810908 -68.452722) (xy 134.826357 -68.505162)
			(xy 134.834161 -68.55927) (xy 134.83463 -68.586604) (xy 158.725362 -68.586604) (xy 158.72585 -68.559271)
			(xy 158.733652 -68.505164) (xy 158.749097 -68.452725) (xy 158.771868 -68.403027) (xy 158.801499 -68.357087)
			(xy 158.819088 -68.33616) (xy 158.819342 -68.335906) (xy 158.819596 -68.335652) (xy 158.825167 -68.328554)
			(xy 158.831423 -68.311646) (xy 158.831788 -68.302632) (xy 158.831788 -68.235576) (xy 158.831445 -68.226558)
			(xy 158.825188 -68.209641) (xy 158.819596 -68.202556) (xy 158.819342 -68.202302) (xy 158.819088 -68.202048)
			(xy 158.801503 -68.181117) (xy 158.771864 -68.135181) (xy 158.749086 -68.085485) (xy 158.733637 -68.033045)
			(xy 158.725832 -67.978938) (xy 158.725362 -67.951604) (xy 158.725881 -67.924354) (xy 158.733637 -67.870409)
			(xy 158.74899 -67.818117) (xy 158.771628 -67.768542) (xy 158.801091 -67.722693) (xy 158.836779 -67.681503)
			(xy 158.877966 -67.645812) (xy 158.923812 -67.616345) (xy 158.973385 -67.593702) (xy 159.025676 -67.578344)
			(xy 159.07962 -67.570584) (xy 159.10687 -67.570096) (xy 159.107124 -67.570096) (xy 159.133419 -67.57054)
			(xy 159.185509 -67.577789) (xy 159.23611 -67.592117) (xy 159.284266 -67.613256) (xy 159.329065 -67.640803)
			(xy 159.36966 -67.674238) (xy 159.387794 -67.693286) (xy 159.395371 -67.700721) (xy 159.414785 -67.70925)
			(xy 159.425386 -67.709796) (xy 159.499554 -67.709796) (xy 159.510189 -67.709409) (xy 159.529653 -67.700844)
			(xy 159.537146 -67.693286) (xy 159.55524 -67.674196) (xy 159.59583 -67.640743) (xy 159.640634 -67.613189)
			(xy 159.6888 -67.592056) (xy 159.739415 -67.577745) (xy 159.791516 -67.57053) (xy 159.817816 -67.570096)
			(xy 159.81807 -67.570096) (xy 159.84544 -67.570581) (xy 159.899618 -67.578394) (xy 159.952121 -67.593879)
			(xy 160.001868 -67.616716) (xy 160.047836 -67.646437) (xy 160.068768 -67.664076) (xy 160.069022 -67.66433)
			(xy 160.076096 -67.669935) (xy 160.093022 -67.67617) (xy 160.102042 -67.676522) (xy 160.169098 -67.676522)
			(xy 160.178114 -67.676159) (xy 160.195031 -67.669915) (xy 160.202118 -67.66433) (xy 160.202626 -67.663822)
			(xy 160.223572 -67.646254) (xy 160.269503 -67.616611) (xy 160.319196 -67.59383) (xy 160.371632 -67.578376)
			(xy 160.425737 -67.570567) (xy 160.45307 -67.570096) (xy 160.480322 -67.570583) (xy 160.534273 -67.578336)
			(xy 160.58657 -67.593689) (xy 160.636151 -67.616328) (xy 160.682004 -67.645793) (xy 160.723197 -67.681484)
			(xy 160.758891 -67.722675) (xy 160.78836 -67.768527) (xy 160.811002 -67.818105) (xy 160.826358 -67.870402)
			(xy 160.834115 -67.924352) (xy 160.834578 -67.951604) (xy 160.834085 -67.978937) (xy 160.826282 -68.033043)
			(xy 160.810839 -68.085482) (xy 160.788069 -68.13518) (xy 160.75844 -68.18112) (xy 160.740852 -68.202048)
			(xy 160.740598 -68.202302) (xy 160.740344 -68.202556) (xy 160.734763 -68.209646) (xy 160.728514 -68.22656)
			(xy 160.728152 -68.235576) (xy 160.728152 -68.302632) (xy 160.728482 -68.311652) (xy 160.734747 -68.328569)
			(xy 160.740344 -68.335652) (xy 160.740598 -68.335906) (xy 160.740852 -68.33616) (xy 160.758432 -68.357096)
			(xy 160.788074 -68.403029) (xy 160.810853 -68.452725) (xy 160.826304 -68.505163) (xy 160.834109 -68.55927)
			(xy 160.834578 -68.586604) (xy 184.72531 -68.586604) (xy 184.725811 -68.559271) (xy 184.733612 -68.505166)
			(xy 184.749054 -68.452727) (xy 184.771822 -68.403029) (xy 184.801449 -68.357088) (xy 184.819036 -68.33616)
			(xy 184.81929 -68.335906) (xy 184.819544 -68.335652) (xy 184.82512 -68.328559) (xy 184.831372 -68.311647)
			(xy 184.831736 -68.302632) (xy 184.831736 -68.235576) (xy 184.831383 -68.226559) (xy 184.825132 -68.209642)
			(xy 184.819544 -68.202556) (xy 184.81929 -68.202302) (xy 184.819036 -68.202048) (xy 184.801458 -68.18111)
			(xy 184.771816 -68.135177) (xy 184.749037 -68.085482) (xy 184.733586 -68.033044) (xy 184.72578 -67.978938)
			(xy 184.72531 -67.951604) (xy 184.725759 -67.92435) (xy 184.733516 -67.870398) (xy 184.748872 -67.818099)
			(xy 184.771516 -67.768518) (xy 184.800985 -67.722664) (xy 184.83668 -67.68147) (xy 184.877875 -67.645777)
			(xy 184.92373 -67.616309) (xy 184.973312 -67.593668) (xy 185.025612 -67.578313) (xy 185.079564 -67.570558)
			(xy 185.106818 -67.570096) (xy 185.107072 -67.570096) (xy 185.133366 -67.570575) (xy 185.185454 -67.577816)
			(xy 185.236055 -67.592138) (xy 185.284211 -67.61327) (xy 185.329011 -67.640811) (xy 185.369607 -67.674241)
			(xy 185.387742 -67.693286) (xy 185.395301 -67.700743) (xy 185.414728 -67.709259) (xy 185.425334 -67.709796)
			(xy 185.499502 -67.709796) (xy 185.510133 -67.70938) (xy 185.529598 -67.700836) (xy 185.537094 -67.693286)
			(xy 185.555214 -67.674222) (xy 185.595798 -67.640766) (xy 185.640596 -67.613208) (xy 185.688758 -67.592071)
			(xy 185.739368 -67.577755) (xy 185.791466 -67.570533) (xy 185.817764 -67.570096) (xy 185.818018 -67.570096)
			(xy 185.845389 -67.570552) (xy 185.899568 -67.578373) (xy 185.952071 -67.593864) (xy 186.001818 -67.616708)
			(xy 186.047784 -67.646434) (xy 186.068716 -67.664076) (xy 186.06897 -67.66433) (xy 186.076059 -67.669913)
			(xy 186.092974 -67.676161) (xy 186.10199 -67.676522) (xy 186.169046 -67.676522) (xy 186.17806 -67.676135)
			(xy 186.194977 -67.669908) (xy 186.202066 -67.66433) (xy 186.202574 -67.663822) (xy 186.223502 -67.646232)
			(xy 186.269438 -67.616592) (xy 186.319135 -67.593815) (xy 186.371575 -67.578367) (xy 186.425684 -67.570564)
			(xy 186.453018 -67.570096) (xy 186.48027 -67.570561) (xy 186.534219 -67.57832) (xy 186.586514 -67.593678)
			(xy 186.636091 -67.616321) (xy 186.681942 -67.64579) (xy 186.723132 -67.681483) (xy 186.758823 -67.722676)
			(xy 186.788289 -67.768528) (xy 186.81093 -67.818107) (xy 186.826285 -67.870403) (xy 186.834041 -67.924352)
			(xy 186.834526 -67.951604) (xy 186.834045 -67.978937) (xy 186.826241 -68.033045) (xy 186.810795 -68.085484)
			(xy 186.788023 -68.135182) (xy 186.758389 -68.181121) (xy 186.7408 -68.202048) (xy 186.740546 -68.202302)
			(xy 186.740292 -68.202556) (xy 186.734717 -68.20965) (xy 186.728464 -68.226561) (xy 186.7281 -68.235576)
			(xy 186.7281 -68.302632) (xy 186.728442 -68.31165) (xy 186.7347 -68.328567) (xy 186.740292 -68.335652)
			(xy 186.740546 -68.335906) (xy 186.7408 -68.33616) (xy 186.758387 -68.35709) (xy 186.788026 -68.403026)
			(xy 186.810804 -68.452723) (xy 186.826253 -68.505162) (xy 186.834057 -68.55927) (xy 186.834526 -68.586604)
			(xy 210.725258 -68.586604) (xy 210.725747 -68.559271) (xy 210.733549 -68.505164) (xy 210.748994 -68.452725)
			(xy 210.771764 -68.403027) (xy 210.801395 -68.357087) (xy 210.818984 -68.33616) (xy 210.819238 -68.335906)
			(xy 210.819492 -68.335652) (xy 210.825062 -68.328554) (xy 210.831319 -68.311646) (xy 210.831684 -68.302632)
			(xy 210.831684 -68.235576) (xy 210.831342 -68.226558) (xy 210.825084 -68.209641) (xy 210.819492 -68.202556)
			(xy 210.819238 -68.202302) (xy 210.818984 -68.202048) (xy 210.801398 -68.181117) (xy 210.771759 -68.135181)
			(xy 210.748982 -68.085485) (xy 210.733533 -68.033045) (xy 210.725728 -67.978938) (xy 210.725258 -67.951604)
			(xy 210.725781 -67.924354) (xy 210.733536 -67.87041) (xy 210.748889 -67.818118) (xy 210.771528 -67.768543)
			(xy 210.80099 -67.722694) (xy 210.836678 -67.681505) (xy 210.877864 -67.645813) (xy 210.923709 -67.616346)
			(xy 210.973282 -67.593703) (xy 211.025573 -67.578345) (xy 211.079516 -67.570584) (xy 211.106766 -67.570096)
			(xy 211.10702 -67.570096) (xy 211.133315 -67.570543) (xy 211.185404 -67.577791) (xy 211.236006 -67.592119)
			(xy 211.284162 -67.613257) (xy 211.328961 -67.640804) (xy 211.369556 -67.674239) (xy 211.38769 -67.693286)
			(xy 211.395268 -67.700719) (xy 211.414681 -67.70925) (xy 211.425282 -67.709796) (xy 211.49945 -67.709796)
			(xy 211.510084 -67.709407) (xy 211.529549 -67.700844) (xy 211.537042 -67.693286) (xy 211.555138 -67.674198)
			(xy 211.595728 -67.640745) (xy 211.640531 -67.61319) (xy 211.688697 -67.592057) (xy 211.739311 -67.577746)
			(xy 211.791413 -67.57053) (xy 211.817712 -67.570096) (xy 211.817966 -67.570096) (xy 211.845335 -67.570583)
			(xy 211.899514 -67.578396) (xy 211.952016 -67.59388) (xy 212.001764 -67.616717) (xy 212.047732 -67.646437)
			(xy 212.068664 -67.664076) (xy 212.068918 -67.66433) (xy 212.075993 -67.669934) (xy 212.092919 -67.676169)
			(xy 212.101938 -67.676522) (xy 212.168994 -67.676522) (xy 212.17801 -67.676157) (xy 212.194927 -67.669914)
			(xy 212.202014 -67.66433) (xy 212.202522 -67.663822) (xy 212.223469 -67.646256) (xy 212.2694 -67.616613)
			(xy 212.319092 -67.593831) (xy 212.371528 -67.578377) (xy 212.425633 -67.570568) (xy 212.452966 -67.570096)
			(xy 212.480218 -67.570587) (xy 212.534168 -67.578339) (xy 212.586466 -67.593691) (xy 212.636046 -67.61633)
			(xy 212.6819 -67.645795) (xy 212.723093 -67.681486) (xy 212.758787 -67.722676) (xy 212.788255 -67.768527)
			(xy 212.810898 -67.818106) (xy 212.826254 -67.870402) (xy 212.834011 -67.924352) (xy 212.834474 -67.951604)
			(xy 212.833982 -67.978937) (xy 212.826179 -68.033043) (xy 212.810735 -68.085482) (xy 212.787965 -68.13518)
			(xy 212.758336 -68.18112) (xy 212.740748 -68.202048) (xy 212.740494 -68.202302) (xy 212.74024 -68.202556)
			(xy 212.734659 -68.209646) (xy 212.72841 -68.22656) (xy 212.728048 -68.235576) (xy 212.728048 -68.302632)
			(xy 212.728379 -68.311652) (xy 212.734643 -68.328569) (xy 212.74024 -68.335652) (xy 212.740494 -68.335906)
			(xy 212.740748 -68.33616) (xy 212.758343 -68.357084) (xy 212.787979 -68.403022) (xy 212.810754 -68.45272)
			(xy 212.826202 -68.505161) (xy 212.834005 -68.55927) (xy 212.834474 -68.586604) (xy 212.834048 -68.613858)
			(xy 212.82629 -68.667813) (xy 212.810932 -68.720113) (xy 212.788286 -68.769696) (xy 212.758815 -68.81555)
			(xy 212.723117 -68.856744) (xy 212.68192 -68.892437) (xy 212.636062 -68.921904) (xy 212.586478 -68.944545)
			(xy 212.534175 -68.959898) (xy 212.480221 -68.967651) (xy 212.452966 -68.968112) (xy 212.425595 -68.967663)
			(xy 212.371416 -68.959841) (xy 212.318912 -68.944347) (xy 212.269166 -68.921502) (xy 212.223199 -68.891774)
			(xy 212.202268 -68.874132) (xy 212.202014 -68.873878) (xy 212.194929 -68.868289) (xy 212.178011 -68.862044)
			(xy 212.168994 -68.861686) (xy 212.101938 -68.861686) (xy 212.092923 -68.862064) (xy 212.076006 -68.868297)
			(xy 212.068918 -68.873878) (xy 212.06841 -68.874386) (xy 212.04749 -68.891985) (xy 212.001551 -68.921623)
			(xy 211.951852 -68.944398) (xy 211.89941 -68.959844) (xy 211.845301 -68.967645) (xy 211.817966 -68.968112)
			(xy 211.817712 -68.968112) (xy 211.791418 -68.967641) (xy 211.73933 -68.960398) (xy 211.688729 -68.946074)
			(xy 211.640573 -68.924941) (xy 211.595773 -68.897398) (xy 211.555177 -68.863967) (xy 211.537042 -68.844922)
			(xy 211.529451 -68.837504) (xy 211.510048 -68.828965) (xy 211.49945 -68.828412) (xy 211.425282 -68.828412)
			(xy 211.414649 -68.828816) (xy 211.395185 -68.837369) (xy 211.38769 -68.844922) (xy 211.36958 -68.863996)
			(xy 211.328993 -68.89745) (xy 211.284193 -68.925006) (xy 211.236029 -68.946142) (xy 211.185418 -68.960456)
			(xy 211.133319 -68.967676) (xy 211.10702 -68.968112) (xy 211.106766 -68.968112) (xy 211.079514 -68.967654)
			(xy 211.025566 -68.959893) (xy 210.973271 -68.944534) (xy 210.923693 -68.921889) (xy 210.877843 -68.892419)
			(xy 210.836654 -68.856725) (xy 210.800963 -68.815532) (xy 210.771497 -68.76968) (xy 210.748856 -68.720101)
			(xy 210.733501 -68.667805) (xy 210.725744 -68.613856) (xy 210.725258 -68.586604) (xy 186.834526 -68.586604)
			(xy 186.834026 -68.613855) (xy 186.826269 -68.667801) (xy 186.810915 -68.720094) (xy 186.788274 -68.76967)
			(xy 186.758809 -68.81552) (xy 186.723119 -68.856709) (xy 186.681931 -68.892401) (xy 186.636083 -68.921868)
			(xy 186.586507 -68.94451) (xy 186.534215 -68.959866) (xy 186.480269 -68.967625) (xy 186.453018 -68.968112)
			(xy 186.425648 -68.967632) (xy 186.37147 -68.959817) (xy 186.318967 -68.944331) (xy 186.26922 -68.921493)
			(xy 186.223252 -68.891772) (xy 186.20232 -68.874132) (xy 186.202066 -68.873878) (xy 186.194966 -68.86831)
			(xy 186.17806 -68.862053) (xy 186.169046 -68.861686) (xy 186.10199 -68.861686) (xy 186.092973 -68.862041)
			(xy 186.076056 -68.868291) (xy 186.06897 -68.873878) (xy 186.068462 -68.874386) (xy 186.047522 -68.891961)
			(xy 186.001589 -68.921602) (xy 185.951895 -68.944382) (xy 185.899458 -68.959834) (xy 185.845351 -68.967641)
			(xy 185.818018 -68.968112) (xy 185.817764 -68.968112) (xy 185.791469 -68.967673) (xy 185.739379 -68.960423)
			(xy 185.688778 -68.946093) (xy 185.640622 -68.924954) (xy 185.595822 -68.897406) (xy 185.555228 -68.86397)
			(xy 185.537094 -68.844922) (xy 185.529521 -68.837483) (xy 185.510104 -68.828956) (xy 185.499502 -68.828412)
			(xy 185.425334 -68.828412) (xy 185.414698 -68.82879) (xy 185.395234 -68.837361) (xy 185.387742 -68.844922)
			(xy 185.369606 -68.863971) (xy 185.329025 -68.897427) (xy 185.28423 -68.924987) (xy 185.236072 -68.946127)
			(xy 185.185464 -68.960446) (xy 185.133369 -68.967672) (xy 185.107072 -68.968112) (xy 185.106818 -68.968112)
			(xy 185.079566 -68.967628) (xy 185.025616 -68.959874) (xy 184.973319 -68.94452) (xy 184.923739 -68.92188)
			(xy 184.877886 -68.892414) (xy 184.836693 -68.856723) (xy 184.800999 -68.815532) (xy 184.771531 -68.769681)
			(xy 184.748888 -68.720102) (xy 184.733531 -68.667806) (xy 184.725774 -68.613856) (xy 184.72531 -68.586604)
			(xy 160.834578 -68.586604) (xy 160.834148 -68.613858) (xy 160.82639 -68.667812) (xy 160.811032 -68.720112)
			(xy 160.788387 -68.769694) (xy 160.758916 -68.815549) (xy 160.723218 -68.856742) (xy 160.682022 -68.892436)
			(xy 160.636165 -68.921903) (xy 160.58658 -68.944544) (xy 160.534279 -68.959897) (xy 160.480324 -68.967651)
			(xy 160.45307 -68.968112) (xy 160.425699 -68.967661) (xy 160.37152 -68.959839) (xy 160.319017 -68.944346)
			(xy 160.26927 -68.921501) (xy 160.223304 -68.891774) (xy 160.202372 -68.874132) (xy 160.202118 -68.873878)
			(xy 160.195032 -68.86829) (xy 160.178115 -68.862045) (xy 160.169098 -68.861686) (xy 160.102042 -68.861686)
			(xy 160.093028 -68.862066) (xy 160.076111 -68.868298) (xy 160.069022 -68.873878) (xy 160.068514 -68.874386)
			(xy 160.047592 -68.891983) (xy 160.001654 -68.921621) (xy 159.951955 -68.944397) (xy 159.899514 -68.959844)
			(xy 159.845405 -68.967645) (xy 159.81807 -68.968112) (xy 159.817816 -68.968112) (xy 159.791522 -68.967639)
			(xy 159.739434 -68.960396) (xy 159.688833 -68.946072) (xy 159.640677 -68.92494) (xy 159.595877 -68.897397)
			(xy 159.555281 -68.863967) (xy 159.537146 -68.844922) (xy 159.529591 -68.837461) (xy 159.51016 -68.828946)
			(xy 159.499554 -68.828412) (xy 159.425386 -68.828412) (xy 159.414754 -68.828819) (xy 159.395289 -68.837369)
			(xy 159.387794 -68.844922) (xy 159.369682 -68.863994) (xy 159.329096 -68.897448) (xy 159.284296 -68.925005)
			(xy 159.236133 -68.946141) (xy 159.185521 -68.960455) (xy 159.133422 -68.967676) (xy 159.107124 -68.968112)
			(xy 159.10687 -68.968112) (xy 159.079618 -68.96765) (xy 159.02567 -68.95989) (xy 158.973375 -68.944531)
			(xy 158.923798 -68.921887) (xy 158.877948 -68.892418) (xy 158.836758 -68.856724) (xy 158.801067 -68.815531)
			(xy 158.771601 -68.769679) (xy 158.74896 -68.720101) (xy 158.733605 -68.667805) (xy 158.725848 -68.613856)
			(xy 158.725362 -68.586604) (xy 134.83463 -68.586604) (xy 134.834126 -68.613854) (xy 134.82637 -68.6678)
			(xy 134.811015 -68.720093) (xy 134.788375 -68.769669) (xy 134.75891 -68.815518) (xy 134.723221 -68.856708)
			(xy 134.682033 -68.8924) (xy 134.636185 -68.921866) (xy 134.58661 -68.944509) (xy 134.534318 -68.959866)
			(xy 134.480372 -68.967625) (xy 134.453122 -68.968112) (xy 134.425752 -68.96763) (xy 134.371574 -68.959816)
			(xy 134.319071 -68.94433) (xy 134.269324 -68.921492) (xy 134.223356 -68.891771) (xy 134.202424 -68.874132)
			(xy 134.20217 -68.873878) (xy 134.195069 -68.868312) (xy 134.178163 -68.862054) (xy 134.16915 -68.861686)
			(xy 134.102094 -68.861686) (xy 134.093077 -68.862043) (xy 134.07616 -68.868291) (xy 134.069074 -68.873878)
			(xy 134.068566 -68.874386) (xy 134.047624 -68.891959) (xy 134.001692 -68.921601) (xy 133.951998 -68.944381)
			(xy 133.899561 -68.959833) (xy 133.845455 -68.967641) (xy 133.818122 -68.968112) (xy 133.817868 -68.968112)
			(xy 133.791573 -68.967671) (xy 133.739483 -68.960421) (xy 133.688882 -68.946092) (xy 133.640726 -68.924953)
			(xy 133.595927 -68.897405) (xy 133.555332 -68.86397) (xy 133.537198 -68.844922) (xy 133.529623 -68.837484)
			(xy 133.510208 -68.828956) (xy 133.499606 -68.828412) (xy 133.425438 -68.828412) (xy 133.414803 -68.828792)
			(xy 133.395338 -68.837362) (xy 133.387846 -68.844922) (xy 133.369708 -68.863969) (xy 133.329128 -68.897425)
			(xy 133.284333 -68.924985) (xy 133.236175 -68.946126) (xy 133.185568 -68.960445) (xy 133.133473 -68.967672)
			(xy 133.107176 -68.968112) (xy 133.106922 -68.968112) (xy 133.07967 -68.967624) (xy 133.02572 -68.95987)
			(xy 132.973423 -68.944517) (xy 132.923843 -68.921878) (xy 132.87799 -68.892412) (xy 132.836797 -68.856721)
			(xy 132.801103 -68.815531) (xy 132.771635 -68.76968) (xy 132.748992 -68.720102) (xy 132.733635 -68.667805)
			(xy 132.725878 -68.613856) (xy 132.725414 -68.586604) (xy 120.975627 -68.586604) (xy 121.007193 -68.611137)
			(xy 121.163538 -68.742698) (xy 121.314653 -68.880234) (xy 121.460312 -69.023536) (xy 121.600294 -69.172389)
			(xy 121.734387 -69.326567) (xy 121.86239 -69.485838) (xy 121.984109 -69.649961) (xy 122.099361 -69.818689)
			(xy 122.207971 -69.991767) (xy 122.309775 -70.168933) (xy 122.357642 -70.259194) (xy 122.357896 -70.259448)
			(xy 122.35815 -70.259956) (xy 122.36158 -70.265814) (xy 122.37097 -70.275609) (xy 122.376692 -70.27926)
			(xy 122.382688 -70.282668) (xy 122.39596 -70.286403) (xy 122.402854 -70.286626) (xy 226.642168 -70.286626)
			(xy 226.651779 -70.286215) (xy 226.669665 -70.279172) (xy 226.676966 -70.27291) (xy 226.683517 -70.266301)
			(xy 226.691727 -70.24962) (xy 226.692968 -70.240398) (xy 226.692968 -70.23989) (xy 226.692968 -70.239636)
			(xy 226.696701 -70.200613) (xy 226.711387 -70.123607) (xy 226.734162 -70.048593) (xy 226.76477 -69.976421)
			(xy 226.802865 -69.907904) (xy 226.848016 -69.843818) (xy 226.899713 -69.784885) (xy 226.957373 -69.731771)
			(xy 227.020344 -69.685077) (xy 227.087915 -69.645329) (xy 227.159323 -69.612977) (xy 227.23376 -69.588385)
			(xy 227.310388 -69.571833) (xy 227.388339 -69.563507) (xy 227.427536 -69.56298) (xy 227.46208 -69.563742)
			(xy 227.462588 -69.563742) (xy 227.464874 -69.563742) (xy 227.467414 -69.563742) (xy 227.467922 -69.563742)
			(xy 227.502466 -69.56298) (xy 227.539497 -69.563438) (xy 227.613187 -69.570863) (xy 227.685763 -69.585632)
			(xy 227.756494 -69.607596) (xy 227.790756 -69.621654) (xy 227.801678 -69.626226) (xy 227.825046 -69.62521)
			(xy 227.898706 -69.584062) (xy 227.908105 -69.578196) (xy 227.921125 -69.5603) (xy 227.925419 -69.53859)
			(xy 227.920192 -69.517085) (xy 227.913692 -69.508116) (xy 227.891848 -69.48043) (xy 227.868734 -69.470524)
			(xy 227.856034 -69.47154) (xy 227.826062 -69.472556) (xy 227.798811 -69.472068) (xy 227.744865 -69.464307)
			(xy 227.692572 -69.448949) (xy 227.642997 -69.426306) (xy 227.597148 -69.39684) (xy 227.555958 -69.361149)
			(xy 227.520266 -69.31996) (xy 227.490798 -69.274112) (xy 227.468154 -69.224537) (xy 227.452795 -69.172245)
			(xy 227.445033 -69.118299) (xy 227.444554 -69.091048) (xy 227.444989 -69.064795) (xy 227.45219 -69.012785)
			(xy 227.466461 -68.962256) (xy 227.487534 -68.914165) (xy 227.515007 -68.86942) (xy 227.548363 -68.828871)
			(xy 227.586969 -68.793284) (xy 227.630094 -68.763333) (xy 227.676923 -68.739585) (xy 227.701602 -68.730622)
			(xy 227.70211 -68.730368) (xy 227.712524 -68.726558) (xy 227.720144 -68.7197) (xy 227.724106 -68.715842)
			(xy 227.730377 -68.706735) (xy 227.73259 -68.701666) (xy 227.765864 -68.621402) (xy 227.765356 -68.600066)
			(xy 227.76053 -68.59016) (xy 227.748615 -68.564194) (xy 227.731767 -68.509605) (xy 227.723237 -68.453116)
			(xy 227.722684 -68.424552) (xy 227.722684 -68.424298) (xy 227.723217 -68.395302) (xy 227.731979 -68.337976)
			(xy 227.749316 -68.282636) (xy 227.774828 -68.230557) (xy 227.807929 -68.182939) (xy 227.847855 -68.14088)
			(xy 227.893686 -68.105347) (xy 227.918772 -68.090796) (xy 227.927408 -68.08597) (xy 227.939346 -68.071492)
			(xy 227.96373 -67.996562) (xy 227.966357 -67.987378) (xy 227.965312 -67.96832) (xy 227.961698 -67.959478)
			(xy 227.950637 -67.934356) (xy 227.935033 -67.88173) (xy 227.927138 -67.827411) (xy 227.926646 -67.799966)
			(xy 227.927057 -67.77471) (xy 227.933724 -67.72464) (xy 227.946939 -67.675888) (xy 227.966468 -67.629304)
			(xy 227.991972 -67.585704) (xy 228.007164 -67.565524) (xy 228.012696 -67.557787) (xy 228.018132 -67.539574)
			(xy 228.016593 -67.520629) (xy 228.012752 -67.51193) (xy 227.990654 -67.466972) (xy 227.98614 -67.458605)
			(xy 227.972154 -67.445747) (xy 227.954435 -67.438893) (xy 227.944934 -67.438524) (xy 227.763832 -67.438524)
			(xy 227.736908 -67.458844) (xy 227.732082 -67.475354) (xy 227.72408 -67.501532) (xy 227.701615 -67.55145)
			(xy 227.672243 -67.597642) (xy 227.636568 -67.639159) (xy 227.595322 -67.675148) (xy 227.549354 -67.704869)
			(xy 227.499608 -67.727712) (xy 227.447107 -67.743206) (xy 227.39293 -67.751034) (xy 227.33819 -67.751034)
			(xy 227.284013 -67.743206) (xy 227.231512 -67.727712) (xy 227.181766 -67.704869) (xy 227.135798 -67.675148)
			(xy 227.094552 -67.639159) (xy 227.058877 -67.597642) (xy 227.029505 -67.55145) (xy 227.00704 -67.501532)
			(xy 226.999038 -67.475354) (xy 226.994212 -67.458844) (xy 226.967288 -67.438524) (xy 226.898708 -67.438524)
			(xy 226.88872 -67.439061) (xy 226.870288 -67.446775) (xy 226.862894 -67.45351) (xy 225.584258 -68.732146)
			(xy 225.56068 -68.755056) (xy 225.509266 -68.79603) (xy 225.453589 -68.830991) (xy 225.394347 -68.859499)
			(xy 225.332287 -68.881197) (xy 225.268188 -68.895811) (xy 225.202856 -68.903157) (xy 225.169984 -68.903596)
			(xy 225.134587 -68.903082) (xy 225.064308 -68.894546) (xy 224.995571 -68.877602) (xy 224.929377 -68.852496)
			(xy 224.866692 -68.819593) (xy 224.80843 -68.779375) (xy 224.755441 -68.732428) (xy 224.708498 -68.679435)
			(xy 224.668284 -68.62117) (xy 224.635386 -68.558483) (xy 224.610285 -68.492287) (xy 224.593346 -68.423549)
			(xy 224.584815 -68.35327) (xy 224.58426 -68.317872) (xy 224.584689 -68.284999) (xy 224.592023 -68.219662)
			(xy 224.60663 -68.155559) (xy 224.628325 -68.093495) (xy 224.656836 -68.034252) (xy 224.691804 -67.978575)
			(xy 224.732788 -67.927166) (xy 224.75571 -67.903598) (xy 226.308158 -66.351404) (xy 226.315778 -66.328544)
			(xy 226.313746 -66.316352) (xy 226.311714 -66.302024) (xy 226.30955 -66.273164) (xy 226.309428 -66.258694)
			(xy 226.309428 -66.25844) (xy 226.309889 -66.231186) (xy 226.317641 -66.177233) (xy 226.332994 -66.124932)
			(xy 226.355635 -66.075349) (xy 226.385102 -66.029494) (xy 226.420797 -65.988299) (xy 226.461991 -65.952605)
			(xy 226.507846 -65.923137) (xy 226.557429 -65.900496) (xy 226.609729 -65.885142) (xy 226.663682 -65.877389)
			(xy 226.690936 -65.876932) (xy 226.718301 -65.877405) (xy 226.772469 -65.88523) (xy 226.824963 -65.900713)
			(xy 226.874706 -65.923538) (xy 226.920678 -65.953236) (xy 226.961935 -65.989197) (xy 226.997631 -66.030684)
			(xy 227.027033 -66.076845) (xy 227.049539 -66.126734) (xy 227.064685 -66.179326) (xy 227.068888 -66.20637)
			(xy 227.070158 -66.215768) (xy 227.078794 -66.231516) (xy 227.085652 -66.237612) (xy 227.092808 -66.24339)
			(xy 227.109992 -66.249909) (xy 227.11918 -66.250312) (xy 227.848414 -66.250312) (xy 227.858592 -66.249805)
			(xy 227.87732 -66.241809) (xy 227.884736 -66.234818) (xy 227.887276 -66.232278) (xy 227.945188 -66.152776)
			(xy 227.948998 -66.129154) (xy 227.945188 -66.117216) (xy 227.936549 -66.088715) (xy 227.927229 -66.029897)
			(xy 227.926646 -66.000122) (xy 227.927028 -65.976831) (xy 227.932764 -65.930601) (xy 227.938076 -65.90792)
			(xy 227.938584 -65.906142) (xy 227.938838 -65.90411) (xy 227.9401 -65.893474) (xy 227.934842 -65.872738)
			(xy 227.928678 -65.863978) (xy 227.879402 -65.800986) (xy 227.87181 -65.792162) (xy 227.850899 -65.781989)
			(xy 227.83927 -65.781428) (xy 227.839016 -65.781428) (xy 227.811761 -65.780966) (xy 227.757805 -65.773211)
			(xy 227.705503 -65.757855) (xy 227.655918 -65.735212) (xy 227.61006 -65.705743) (xy 227.568864 -65.670048)
			(xy 227.533166 -65.628852) (xy 227.503695 -65.582996) (xy 227.48105 -65.533412) (xy 227.465693 -65.48111)
			(xy 227.457935 -65.427155) (xy 227.457935 -65.372645) (xy 227.465693 -65.31869) (xy 227.48105 -65.266388)
			(xy 227.503695 -65.216804) (xy 227.533166 -65.170948) (xy 227.568864 -65.129752) (xy 227.61006 -65.094057)
			(xy 227.655918 -65.064588) (xy 227.705503 -65.041945) (xy 227.757805 -65.026589) (xy 227.811761 -65.018834)
			(xy 227.839016 -65.018412) (xy 227.866268 -65.018876) (xy 227.920216 -65.026635) (xy 227.97251 -65.041993)
			(xy 228.022087 -65.064637) (xy 228.067937 -65.094105) (xy 228.109126 -65.129799) (xy 228.144816 -65.170992)
			(xy 228.174281 -65.216844) (xy 228.19692 -65.266423) (xy 228.212272 -65.31872) (xy 228.220026 -65.372668)
			(xy 228.220524 -65.39992) (xy 231.00614 -65.39992) (xy 231.010211 -65.344298) (xy 231.022337 -65.289861)
			(xy 231.04226 -65.23777) (xy 231.069556 -65.189135) (xy 231.103642 -65.144992) (xy 231.143791 -65.106283)
			(xy 231.189149 -65.073832) (xy 231.238749 -65.048331) (xy 231.291533 -65.030324) (xy 231.346376 -65.020194)
			(xy 231.40211 -65.018157) (xy 231.457547 -65.024257) (xy 231.511504 -65.038363) (xy 231.562833 -65.060175)
			(xy 231.610439 -65.089229) (xy 231.653307 -65.124904) (xy 231.690524 -65.166441) (xy 231.721297 -65.212954)
			(xy 231.744969 -65.263451) (xy 231.761037 -65.316858) (xy 231.769157 -65.372034) (xy 231.769666 -65.39992)
			(xy 231.769157 -65.427806) (xy 231.761037 -65.482982) (xy 231.744969 -65.536389) (xy 231.721297 -65.586886)
			(xy 231.690524 -65.633399) (xy 231.653307 -65.674936) (xy 231.610439 -65.710611) (xy 231.562833 -65.739665)
			(xy 231.511504 -65.761477) (xy 231.457547 -65.775583) (xy 231.40211 -65.781683) (xy 231.346376 -65.779646)
			(xy 231.291533 -65.769516) (xy 231.238749 -65.751509) (xy 231.189149 -65.726008) (xy 231.143791 -65.693557)
			(xy 231.103642 -65.654848) (xy 231.069556 -65.610705) (xy 231.04226 -65.56207) (xy 231.022337 -65.509979)
			(xy 231.010211 -65.455542) (xy 231.00614 -65.39992) (xy 228.220524 -65.39992) (xy 228.220145 -65.423212)
			(xy 228.214416 -65.469443) (xy 228.209094 -65.492122) (xy 228.208586 -65.4939) (xy 228.208332 -65.495932)
			(xy 228.207058 -65.506572) (xy 228.212295 -65.527324) (xy 228.218492 -65.536064) (xy 228.267768 -65.599056)
			(xy 228.275361 -65.60788) (xy 228.296271 -65.618056) (xy 228.3079 -65.618614) (xy 228.308154 -65.618614)
			(xy 228.335408 -65.619074) (xy 228.389363 -65.626826) (xy 228.441665 -65.642178) (xy 228.49125 -65.664818)
			(xy 228.537107 -65.694286) (xy 228.578303 -65.72998) (xy 228.614 -65.771174) (xy 228.64347 -65.817029)
			(xy 228.666113 -65.866612) (xy 228.681469 -65.918913) (xy 228.689224 -65.972868) (xy 228.689662 -66.000122)
			(xy 228.689048 -66.029895) (xy 228.679736 -66.08871) (xy 228.67112 -66.117216) (xy 228.66731 -66.129154)
			(xy 228.67112 -66.152776) (xy 228.726746 -66.22923) (xy 228.731572 -66.234818) (xy 228.738971 -66.241832)
			(xy 228.75771 -66.249819) (xy 228.767894 -66.250312) (xy 230.189024 -66.250312) (xy 230.221291 -66.25078)
			(xy 230.285418 -66.25803) (xy 230.348332 -66.272402) (xy 230.409246 -66.293717) (xy 230.467395 -66.321707)
			(xy 230.522051 -66.356021) (xy 230.572529 -66.39623) (xy 230.595678 -66.418714) (xy 230.72852 -66.55181)
			(xy 230.735915 -66.558663) (xy 230.754514 -66.566405) (xy 230.764588 -66.566796) (xy 230.98252 -66.566796)
			(xy 231.01046 -66.543936) (xy 231.014016 -66.525902) (xy 231.019867 -66.498907) (xy 231.03831 -66.446841)
			(xy 231.064071 -66.397981) (xy 231.09661 -66.353347) (xy 231.135246 -66.313873) (xy 231.179173 -66.280386)
			(xy 231.22747 -66.253584) (xy 231.279128 -66.23403) (xy 231.333067 -66.222131) (xy 231.388158 -66.218137)
			(xy 231.443249 -66.222131) (xy 231.497188 -66.23403) (xy 231.548846 -66.253584) (xy 231.597143 -66.280386)
			(xy 231.64107 -66.313873) (xy 231.679706 -66.353347) (xy 231.712245 -66.397981) (xy 231.738006 -66.446841)
			(xy 231.756449 -66.498907) (xy 231.7623 -66.525902) (xy 231.765856 -66.543936) (xy 231.793796 -66.566796)
			(xy 232.121456 -66.566796) (xy 232.131522 -66.566362) (xy 232.150111 -66.558633) (xy 232.157524 -66.55181)
			(xy 232.546144 -66.162936) (xy 232.569301 -66.140396) (xy 232.619827 -66.100104) (xy 232.674547 -66.065722)
			(xy 232.732772 -66.037683) (xy 232.79377 -66.016339) (xy 232.856775 -66.00196) (xy 232.920994 -65.994725)
			(xy 232.953306 -65.99428) (xy 233.14406 -65.99428) (xy 233.15325 -65.993886) (xy 233.170432 -65.987362)
			(xy 233.177588 -65.98158) (xy 233.1847 -65.975484) (xy 233.193082 -65.959482) (xy 233.194352 -65.950084)
			(xy 233.198429 -65.922917) (xy 233.213371 -65.870054) (xy 233.23574 -65.819881) (xy 233.265074 -65.773435)
			(xy 233.300767 -65.731677) (xy 233.34208 -65.69547) (xy 233.388159 -65.665562) (xy 233.438052 -65.642573)
			(xy 233.490725 -65.626978) (xy 233.545091 -65.619099) (xy 233.600025 -65.619099) (xy 233.654391 -65.626978)
			(xy 233.707064 -65.642573) (xy 233.756957 -65.665562) (xy 233.803036 -65.69547) (xy 233.844349 -65.731677)
			(xy 233.864729 -65.75552) (xy 246.546622 -65.75552) (xy 246.550693 -65.699898) (xy 246.562819 -65.645461)
			(xy 246.582742 -65.59337) (xy 246.610038 -65.544735) (xy 246.644124 -65.500592) (xy 246.684273 -65.461883)
			(xy 246.729631 -65.429432) (xy 246.779231 -65.403931) (xy 246.832015 -65.385924) (xy 246.886858 -65.375794)
			(xy 246.942592 -65.373757) (xy 246.998029 -65.379857) (xy 247.051986 -65.393963) (xy 247.103315 -65.415775)
			(xy 247.150921 -65.444829) (xy 247.193789 -65.480504) (xy 247.231006 -65.522041) (xy 247.261779 -65.568554)
			(xy 247.285451 -65.619051) (xy 247.301519 -65.672458) (xy 247.309639 -65.727634) (xy 247.310148 -65.75552)
			(xy 272.54657 -65.75552) (xy 272.550641 -65.699898) (xy 272.562767 -65.645461) (xy 272.58269 -65.59337)
			(xy 272.609986 -65.544735) (xy 272.644072 -65.500592) (xy 272.684221 -65.461883) (xy 272.729579 -65.429432)
			(xy 272.779179 -65.403931) (xy 272.831963 -65.385924) (xy 272.886806 -65.375794) (xy 272.94254 -65.373757)
			(xy 272.997977 -65.379857) (xy 273.051934 -65.393963) (xy 273.103263 -65.415775) (xy 273.150869 -65.444829)
			(xy 273.193737 -65.480504) (xy 273.230954 -65.522041) (xy 273.261727 -65.568554) (xy 273.285399 -65.619051)
			(xy 273.301467 -65.672458) (xy 273.309587 -65.727634) (xy 273.310096 -65.75552) (xy 273.309587 -65.783406)
			(xy 273.301467 -65.838582) (xy 273.285399 -65.891989) (xy 273.261727 -65.942486) (xy 273.230954 -65.988999)
			(xy 273.193737 -66.030536) (xy 273.150869 -66.066211) (xy 273.103263 -66.095265) (xy 273.051934 -66.117077)
			(xy 272.997977 -66.131183) (xy 272.94254 -66.137283) (xy 272.886806 -66.135246) (xy 272.831963 -66.125116)
			(xy 272.779179 -66.107109) (xy 272.729579 -66.081608) (xy 272.684221 -66.049157) (xy 272.644072 -66.010448)
			(xy 272.609986 -65.966305) (xy 272.58269 -65.91767) (xy 272.562767 -65.865579) (xy 272.550641 -65.811142)
			(xy 272.54657 -65.75552) (xy 247.310148 -65.75552) (xy 247.309639 -65.783406) (xy 247.301519 -65.838582)
			(xy 247.285451 -65.891989) (xy 247.261779 -65.942486) (xy 247.231006 -65.988999) (xy 247.193789 -66.030536)
			(xy 247.150921 -66.066211) (xy 247.103315 -66.095265) (xy 247.051986 -66.117077) (xy 246.998029 -66.131183)
			(xy 246.942592 -66.137283) (xy 246.886858 -66.135246) (xy 246.832015 -66.125116) (xy 246.779231 -66.107109)
			(xy 246.729631 -66.081608) (xy 246.684273 -66.049157) (xy 246.644124 -66.010448) (xy 246.610038 -65.966305)
			(xy 246.582742 -65.91767) (xy 246.562819 -65.865579) (xy 246.550693 -65.811142) (xy 246.546622 -65.75552)
			(xy 233.864729 -65.75552) (xy 233.880042 -65.773435) (xy 233.909376 -65.819881) (xy 233.931745 -65.870054)
			(xy 233.946687 -65.922917) (xy 233.950764 -65.950084) (xy 233.952034 -65.959482) (xy 233.960416 -65.975484)
			(xy 233.967528 -65.98158) (xy 233.974682 -65.987365) (xy 233.991866 -65.993896) (xy 234.001056 -65.99428)
			(xy 234.913932 -65.99428) (xy 234.946243 -65.994735) (xy 235.010459 -66.001974) (xy 235.07346 -66.016357)
			(xy 235.134455 -66.037703) (xy 235.192676 -66.065744) (xy 235.247392 -66.100128) (xy 235.297914 -66.140421)
			(xy 235.321094 -66.162936) (xy 235.917994 -66.759836) (xy 235.940489 -66.782978) (xy 235.980722 -66.833442)
			(xy 236.015053 -66.888094) (xy 236.043051 -66.946244) (xy 236.064364 -67.007164) (xy 236.078723 -67.070086)
			(xy 236.082156 -67.100555) (xy 246.218627 -67.100555) (xy 246.218627 -67.046045) (xy 246.226385 -66.992089)
			(xy 246.241742 -66.939786) (xy 246.264387 -66.890202) (xy 246.293858 -66.844345) (xy 246.329556 -66.803149)
			(xy 246.370753 -66.767452) (xy 246.416611 -66.737983) (xy 246.466196 -66.715339) (xy 246.518499 -66.699983)
			(xy 246.572455 -66.692226) (xy 246.59971 -66.691764) (xy 246.627081 -66.692209) (xy 246.681262 -66.700029)
			(xy 246.733766 -66.715522) (xy 246.783512 -66.738369) (xy 246.829478 -66.7681) (xy 246.850408 -66.785744)
			(xy 246.850662 -66.785998) (xy 246.857755 -66.791575) (xy 246.874667 -66.797827) (xy 246.883682 -66.79819)
			(xy 246.950738 -66.79819) (xy 246.959757 -66.797853) (xy 246.976674 -66.791592) (xy 246.983758 -66.785998)
			(xy 246.984266 -66.78549) (xy 247.005192 -66.767898) (xy 247.051129 -66.73826) (xy 247.100827 -66.715484)
			(xy 247.153267 -66.700036) (xy 247.207376 -66.692233) (xy 247.23471 -66.691764) (xy 247.261959 -66.692307)
			(xy 247.315901 -66.700064) (xy 247.368191 -66.715419) (xy 247.417763 -66.738059) (xy 247.463609 -66.767523)
			(xy 247.504795 -66.803212) (xy 247.540483 -66.844399) (xy 247.569946 -66.890245) (xy 247.592585 -66.939818)
			(xy 247.607938 -66.992108) (xy 247.615694 -67.046051) (xy 247.615694 -67.100549) (xy 247.607938 -67.154492)
			(xy 247.592585 -67.206782) (xy 247.569946 -67.256355) (xy 247.540483 -67.302201) (xy 247.504795 -67.343388)
			(xy 247.463609 -67.379077) (xy 247.417763 -67.408541) (xy 247.368191 -67.431181) (xy 247.315901 -67.446536)
			(xy 247.261959 -67.454293) (xy 247.23471 -67.45478) (xy 247.20734 -67.454313) (xy 247.153161 -67.446496)
			(xy 247.100657 -67.431008) (xy 247.05091 -67.408166) (xy 247.004944 -67.378441) (xy 246.984012 -67.3608)
			(xy 246.983758 -67.360546) (xy 246.976664 -67.354971) (xy 246.959753 -67.348719) (xy 246.950738 -67.348354)
			(xy 246.883682 -67.348354) (xy 246.874663 -67.348691) (xy 246.857746 -67.354951) (xy 246.850662 -67.360546)
			(xy 246.850154 -67.361054) (xy 246.829213 -67.378627) (xy 246.783281 -67.40827) (xy 246.733587 -67.431051)
			(xy 246.68115 -67.446503) (xy 246.627043 -67.45431) (xy 246.59971 -67.45478) (xy 246.572455 -67.454374)
			(xy 246.518499 -67.446617) (xy 246.466196 -67.431261) (xy 246.416611 -67.408617) (xy 246.370753 -67.379148)
			(xy 246.329556 -67.343451) (xy 246.293858 -67.302255) (xy 246.264387 -67.256398) (xy 246.241742 -67.206814)
			(xy 246.226385 -67.154511) (xy 246.218627 -67.100555) (xy 236.082156 -67.100555) (xy 236.085949 -67.13422)
			(xy 236.086396 -67.16649) (xy 236.086396 -67.488054) (xy 250.979176 -67.488054) (xy 250.983247 -67.432432)
			(xy 250.995373 -67.377995) (xy 251.015296 -67.325904) (xy 251.042592 -67.277269) (xy 251.076678 -67.233126)
			(xy 251.116827 -67.194417) (xy 251.162185 -67.161966) (xy 251.211785 -67.136465) (xy 251.264569 -67.118458)
			(xy 251.319412 -67.108328) (xy 251.375146 -67.106291) (xy 251.430583 -67.112391) (xy 251.48454 -67.126497)
			(xy 251.49032 -67.128953) (xy 272.566575 -67.128953) (xy 272.566575 -67.074447) (xy 272.574333 -67.020495)
			(xy 272.58969 -66.968197) (xy 272.612334 -66.918617) (xy 272.641804 -66.872765) (xy 272.6775 -66.831573)
			(xy 272.718695 -66.795881) (xy 272.764551 -66.766416) (xy 272.814133 -66.743777) (xy 272.866433 -66.728425)
			(xy 272.920385 -66.720673) (xy 272.947638 -66.720212) (xy 272.975007 -66.720711) (xy 273.029185 -66.728521)
			(xy 273.081688 -66.744002) (xy 273.131435 -66.766836) (xy 273.177403 -66.796554) (xy 273.198336 -66.814192)
			(xy 273.19859 -66.814446) (xy 273.205671 -66.82004) (xy 273.222592 -66.826281) (xy 273.23161 -66.826638)
			(xy 273.298666 -66.826638) (xy 273.30768 -66.826256) (xy 273.324597 -66.820025) (xy 273.331686 -66.814446)
			(xy 273.332194 -66.813938) (xy 273.353116 -66.796341) (xy 273.399053 -66.766702) (xy 273.448752 -66.743926)
			(xy 273.501194 -66.728479) (xy 273.555303 -66.720679) (xy 273.582638 -66.720212) (xy 273.609889 -66.72066)
			(xy 273.663835 -66.728422) (xy 273.716128 -66.743781) (xy 273.765703 -66.766425) (xy 273.811551 -66.795894)
			(xy 273.852739 -66.831588) (xy 273.888428 -66.872779) (xy 273.917893 -66.91863) (xy 273.940532 -66.968207)
			(xy 273.955886 -67.020502) (xy 273.963642 -67.074449) (xy 273.963642 -67.128951) (xy 273.955886 -67.182898)
			(xy 273.940532 -67.235193) (xy 273.917893 -67.28477) (xy 273.888428 -67.330621) (xy 273.852739 -67.371812)
			(xy 273.811551 -67.407506) (xy 273.765703 -67.436975) (xy 273.716128 -67.459619) (xy 273.663835 -67.474978)
			(xy 273.609889 -67.48274) (xy 273.582638 -67.483228) (xy 273.555268 -67.482757) (xy 273.501088 -67.474943)
			(xy 273.448584 -67.459456) (xy 273.398837 -67.436615) (xy 273.352871 -67.40689) (xy 273.33194 -67.389248)
			(xy 273.331686 -67.388994) (xy 273.324608 -67.383395) (xy 273.307685 -67.377156) (xy 273.298666 -67.376802)
			(xy 273.23161 -67.376802) (xy 273.222594 -67.377163) (xy 273.205677 -67.383408) (xy 273.19859 -67.388994)
			(xy 273.198082 -67.389502) (xy 273.177174 -67.407117) (xy 273.131232 -67.436752) (xy 273.08153 -67.459524)
			(xy 273.029085 -67.474966) (xy 272.974973 -67.482763) (xy 272.947638 -67.483228) (xy 272.920385 -67.482727)
			(xy 272.866433 -67.474975) (xy 272.814133 -67.459623) (xy 272.764551 -67.436984) (xy 272.718695 -67.407519)
			(xy 272.6775 -67.371827) (xy 272.641804 -67.330635) (xy 272.612334 -67.284783) (xy 272.58969 -67.235203)
			(xy 272.574333 -67.182905) (xy 272.566575 -67.128953) (xy 251.49032 -67.128953) (xy 251.535869 -67.148309)
			(xy 251.583475 -67.177363) (xy 251.626343 -67.213038) (xy 251.66356 -67.254575) (xy 251.694333 -67.301088)
			(xy 251.718005 -67.351585) (xy 251.734073 -67.404992) (xy 251.742193 -67.460168) (xy 251.742702 -67.488054)
			(xy 251.742193 -67.51594) (xy 251.739008 -67.537584) (xy 252.271274 -67.537584) (xy 252.275345 -67.481962)
			(xy 252.287471 -67.427525) (xy 252.307394 -67.375434) (xy 252.33469 -67.326799) (xy 252.368776 -67.282656)
			(xy 252.408925 -67.243947) (xy 252.454283 -67.211496) (xy 252.503883 -67.185995) (xy 252.556667 -67.167988)
			(xy 252.61151 -67.157858) (xy 252.667244 -67.155821) (xy 252.722681 -67.161921) (xy 252.776638 -67.176027)
			(xy 252.827967 -67.197839) (xy 252.875573 -67.226893) (xy 252.918441 -67.262568) (xy 252.955658 -67.304105)
			(xy 252.986431 -67.350618) (xy 253.010103 -67.401115) (xy 253.026171 -67.454522) (xy 253.034291 -67.509698)
			(xy 253.0348 -67.537584) (xy 253.034291 -67.56547) (xy 253.030246 -67.592956) (xy 253.545338 -67.592956)
			(xy 253.549409 -67.537334) (xy 253.561535 -67.482897) (xy 253.581458 -67.430806) (xy 253.608754 -67.382171)
			(xy 253.64284 -67.338028) (xy 253.682989 -67.299319) (xy 253.728347 -67.266868) (xy 253.777947 -67.241367)
			(xy 253.830731 -67.22336) (xy 253.885574 -67.21323) (xy 253.941308 -67.211193) (xy 253.996745 -67.217293)
			(xy 254.050702 -67.231399) (xy 254.102031 -67.253211) (xy 254.149637 -67.282265) (xy 254.192505 -67.31794)
			(xy 254.229722 -67.359477) (xy 254.260495 -67.40599) (xy 254.284167 -67.456487) (xy 254.293664 -67.488054)
			(xy 276.979124 -67.488054) (xy 276.983195 -67.432432) (xy 276.995321 -67.377995) (xy 277.015244 -67.325904)
			(xy 277.04254 -67.277269) (xy 277.076626 -67.233126) (xy 277.116775 -67.194417) (xy 277.162133 -67.161966)
			(xy 277.211733 -67.136465) (xy 277.264517 -67.118458) (xy 277.31936 -67.108328) (xy 277.375094 -67.106291)
			(xy 277.430531 -67.112391) (xy 277.484488 -67.126497) (xy 277.490258 -67.128949) (xy 298.566598 -67.128949)
			(xy 298.566598 -67.074451) (xy 298.574354 -67.020507) (xy 298.589708 -66.968216) (xy 298.612346 -66.918643)
			(xy 298.64181 -66.872796) (xy 298.677498 -66.831608) (xy 298.718684 -66.795918) (xy 298.76453 -66.766453)
			(xy 298.814103 -66.743812) (xy 298.866394 -66.728457) (xy 298.920337 -66.720699) (xy 298.947586 -66.720212)
			(xy 298.974956 -66.720683) (xy 299.029135 -66.728499) (xy 299.081638 -66.743987) (xy 299.131385 -66.766828)
			(xy 299.177352 -66.796551) (xy 299.198284 -66.814192) (xy 299.198538 -66.814446) (xy 299.205634 -66.820018)
			(xy 299.222544 -66.826272) (xy 299.231558 -66.826638) (xy 299.298614 -66.826638) (xy 299.307631 -66.82628)
			(xy 299.324547 -66.820032) (xy 299.331634 -66.814446) (xy 299.332142 -66.813938) (xy 299.353084 -66.796365)
			(xy 299.399016 -66.766723) (xy 299.448709 -66.743942) (xy 299.501147 -66.72849) (xy 299.555253 -66.720682)
			(xy 299.582586 -66.720212) (xy 299.609841 -66.720634) (xy 299.663796 -66.72839) (xy 299.716099 -66.743745)
			(xy 299.765683 -66.766388) (xy 299.811541 -66.795857) (xy 299.852737 -66.831553) (xy 299.888434 -66.872748)
			(xy 299.917905 -66.918605) (xy 299.94055 -66.968188) (xy 299.955907 -67.02049) (xy 299.963665 -67.074445)
			(xy 299.963665 -67.128955) (xy 299.955907 -67.18291) (xy 299.94055 -67.235212) (xy 299.917905 -67.284795)
			(xy 299.888434 -67.330652) (xy 299.852737 -67.371847) (xy 299.811541 -67.407543) (xy 299.765683 -67.437012)
			(xy 299.716099 -67.459655) (xy 299.663796 -67.47501) (xy 299.609841 -67.482766) (xy 299.582586 -67.483228)
			(xy 299.555215 -67.482788) (xy 299.501034 -67.474966) (xy 299.44853 -67.459472) (xy 299.398783 -67.436624)
			(xy 299.352818 -67.406893) (xy 299.331888 -67.389248) (xy 299.331634 -67.388994) (xy 299.324542 -67.383415)
			(xy 299.307629 -67.377164) (xy 299.298614 -67.376802) (xy 299.231558 -67.376802) (xy 299.222544 -67.377187)
			(xy 299.205627 -67.383415) (xy 299.198538 -67.388994) (xy 299.19803 -67.389502) (xy 299.177104 -67.407094)
			(xy 299.131167 -67.436732) (xy 299.081469 -67.459509) (xy 299.029029 -67.474957) (xy 298.97492 -67.48276)
			(xy 298.947586 -67.483228) (xy 298.920337 -67.482701) (xy 298.866394 -67.474943) (xy 298.814103 -67.459588)
			(xy 298.76453 -67.436947) (xy 298.718684 -67.407482) (xy 298.677498 -67.371792) (xy 298.64181 -67.330604)
			(xy 298.612346 -67.284757) (xy 298.589708 -67.235184) (xy 298.574354 -67.182893) (xy 298.566598 -67.128949)
			(xy 277.490258 -67.128949) (xy 277.535817 -67.148309) (xy 277.583423 -67.177363) (xy 277.626291 -67.213038)
			(xy 277.663508 -67.254575) (xy 277.694281 -67.301088) (xy 277.717953 -67.351585) (xy 277.734021 -67.404992)
			(xy 277.742141 -67.460168) (xy 277.74265 -67.488054) (xy 277.742141 -67.51594) (xy 277.738956 -67.537584)
			(xy 278.271222 -67.537584) (xy 278.275293 -67.481962) (xy 278.287419 -67.427525) (xy 278.307342 -67.375434)
			(xy 278.334638 -67.326799) (xy 278.368724 -67.282656) (xy 278.408873 -67.243947) (xy 278.454231 -67.211496)
			(xy 278.503831 -67.185995) (xy 278.556615 -67.167988) (xy 278.611458 -67.157858) (xy 278.667192 -67.155821)
			(xy 278.722629 -67.161921) (xy 278.776586 -67.176027) (xy 278.827915 -67.197839) (xy 278.875521 -67.226893)
			(xy 278.918389 -67.262568) (xy 278.955606 -67.304105) (xy 278.986379 -67.350618) (xy 279.010051 -67.401115)
			(xy 279.026119 -67.454522) (xy 279.034239 -67.509698) (xy 279.034748 -67.537584) (xy 279.034239 -67.56547)
			(xy 279.030194 -67.592956) (xy 279.545286 -67.592956) (xy 279.549357 -67.537334) (xy 279.561483 -67.482897)
			(xy 279.581406 -67.430806) (xy 279.608702 -67.382171) (xy 279.642788 -67.338028) (xy 279.682937 -67.299319)
			(xy 279.728295 -67.266868) (xy 279.777895 -67.241367) (xy 279.830679 -67.22336) (xy 279.885522 -67.21323)
			(xy 279.941256 -67.211193) (xy 279.996693 -67.217293) (xy 280.05065 -67.231399) (xy 280.101979 -67.253211)
			(xy 280.149585 -67.282265) (xy 280.192453 -67.31794) (xy 280.22967 -67.359477) (xy 280.260443 -67.40599)
			(xy 280.284115 -67.456487) (xy 280.293612 -67.488054) (xy 302.979072 -67.488054) (xy 302.983143 -67.432432)
			(xy 302.995269 -67.377995) (xy 303.015192 -67.325904) (xy 303.042488 -67.277269) (xy 303.076574 -67.233126)
			(xy 303.116723 -67.194417) (xy 303.162081 -67.161966) (xy 303.211681 -67.136465) (xy 303.264465 -67.118458)
			(xy 303.319308 -67.108328) (xy 303.375042 -67.106291) (xy 303.430479 -67.112391) (xy 303.484436 -67.126497)
			(xy 303.490216 -67.128953) (xy 324.566475 -67.128953) (xy 324.566475 -67.074447) (xy 324.574233 -67.020496)
			(xy 324.58959 -66.968198) (xy 324.612234 -66.918618) (xy 324.641703 -66.872766) (xy 324.677399 -66.831575)
			(xy 324.718593 -66.795883) (xy 324.764448 -66.766417) (xy 324.81403 -66.743778) (xy 324.866329 -66.728426)
			(xy 324.920281 -66.720673) (xy 324.947534 -66.720212) (xy 324.974905 -66.720655) (xy 325.029085 -66.728478)
			(xy 325.081589 -66.743972) (xy 325.131335 -66.766819) (xy 325.177301 -66.796549) (xy 325.198232 -66.814192)
			(xy 325.198486 -66.814446) (xy 325.205568 -66.820038) (xy 325.222489 -66.82628) (xy 325.231506 -66.826638)
			(xy 325.298562 -66.826638) (xy 325.307576 -66.826255) (xy 325.324493 -66.820024) (xy 325.331582 -66.814446)
			(xy 325.33209 -66.813938) (xy 325.353014 -66.796343) (xy 325.398951 -66.766703) (xy 325.448649 -66.743927)
			(xy 325.50109 -66.72848) (xy 325.5552 -66.720679) (xy 325.582534 -66.720212) (xy 325.609785 -66.72066)
			(xy 325.663732 -66.728421) (xy 325.716025 -66.74378) (xy 325.765601 -66.766424) (xy 325.811449 -66.795893)
			(xy 325.852638 -66.831586) (xy 325.888328 -66.872778) (xy 325.917792 -66.918629) (xy 325.940432 -66.968207)
			(xy 325.955786 -67.020501) (xy 325.963542 -67.074449) (xy 325.963542 -67.128951) (xy 325.955786 -67.182899)
			(xy 325.940432 -67.235193) (xy 325.917792 -67.284771) (xy 325.888328 -67.330622) (xy 325.852638 -67.371814)
			(xy 325.811449 -67.407507) (xy 325.765601 -67.436976) (xy 325.716025 -67.45962) (xy 325.663732 -67.474979)
			(xy 325.609785 -67.48274) (xy 325.582534 -67.483228) (xy 325.555164 -67.48276) (xy 325.500984 -67.474945)
			(xy 325.44848 -67.459457) (xy 325.398733 -67.436616) (xy 325.352767 -67.40689) (xy 325.331836 -67.389248)
			(xy 325.331582 -67.388994) (xy 325.324505 -67.383393) (xy 325.307581 -67.377155) (xy 325.298562 -67.376802)
			(xy 325.231506 -67.376802) (xy 325.222489 -67.377161) (xy 325.205572 -67.383407) (xy 325.198486 -67.388994)
			(xy 325.197978 -67.389502) (xy 325.177034 -67.407072) (xy 325.131102 -67.436713) (xy 325.081409 -67.459494)
			(xy 325.028972 -67.474947) (xy 324.974867 -67.482756) (xy 324.947534 -67.483228) (xy 324.920281 -67.482727)
			(xy 324.866329 -67.474974) (xy 324.81403 -67.459622) (xy 324.764448 -67.436983) (xy 324.718593 -67.407517)
			(xy 324.677399 -67.371825) (xy 324.641703 -67.330634) (xy 324.612234 -67.284782) (xy 324.58959 -67.235202)
			(xy 324.574233 -67.182904) (xy 324.566475 -67.128953) (xy 303.490216 -67.128953) (xy 303.535765 -67.148309)
			(xy 303.583371 -67.177363) (xy 303.626239 -67.213038) (xy 303.663456 -67.254575) (xy 303.694229 -67.301088)
			(xy 303.717901 -67.351585) (xy 303.733969 -67.404992) (xy 303.742089 -67.460168) (xy 303.742598 -67.488054)
			(xy 303.742089 -67.51594) (xy 303.738904 -67.537584) (xy 304.27117 -67.537584) (xy 304.275241 -67.481962)
			(xy 304.287367 -67.427525) (xy 304.30729 -67.375434) (xy 304.334586 -67.326799) (xy 304.368672 -67.282656)
			(xy 304.408821 -67.243947) (xy 304.454179 -67.211496) (xy 304.503779 -67.185995) (xy 304.556563 -67.167988)
			(xy 304.611406 -67.157858) (xy 304.66714 -67.155821) (xy 304.722577 -67.161921) (xy 304.776534 -67.176027)
			(xy 304.827863 -67.197839) (xy 304.875469 -67.226893) (xy 304.918337 -67.262568) (xy 304.955554 -67.304105)
			(xy 304.986327 -67.350618) (xy 305.009999 -67.401115) (xy 305.026067 -67.454522) (xy 305.034187 -67.509698)
			(xy 305.034696 -67.537584) (xy 305.034187 -67.56547) (xy 305.030142 -67.592956) (xy 305.545234 -67.592956)
			(xy 305.549305 -67.537334) (xy 305.561431 -67.482897) (xy 305.581354 -67.430806) (xy 305.60865 -67.382171)
			(xy 305.642736 -67.338028) (xy 305.682885 -67.299319) (xy 305.728243 -67.266868) (xy 305.777843 -67.241367)
			(xy 305.830627 -67.22336) (xy 305.88547 -67.21323) (xy 305.941204 -67.211193) (xy 305.996641 -67.217293)
			(xy 306.050598 -67.231399) (xy 306.101927 -67.253211) (xy 306.149533 -67.282265) (xy 306.192401 -67.31794)
			(xy 306.229618 -67.359477) (xy 306.260391 -67.40599) (xy 306.284063 -67.456487) (xy 306.29356 -67.488054)
			(xy 328.97902 -67.488054) (xy 328.983091 -67.432432) (xy 328.995217 -67.377995) (xy 329.01514 -67.325904)
			(xy 329.042436 -67.277269) (xy 329.076522 -67.233126) (xy 329.116671 -67.194417) (xy 329.162029 -67.161966)
			(xy 329.211629 -67.136465) (xy 329.264413 -67.118458) (xy 329.319256 -67.108328) (xy 329.37499 -67.106291)
			(xy 329.430427 -67.112391) (xy 329.484384 -67.126497) (xy 329.535713 -67.148309) (xy 329.583319 -67.177363)
			(xy 329.626187 -67.213038) (xy 329.663404 -67.254575) (xy 329.694177 -67.301088) (xy 329.717849 -67.351585)
			(xy 329.733917 -67.404992) (xy 329.742037 -67.460168) (xy 329.742546 -67.488054) (xy 329.742037 -67.51594)
			(xy 329.738852 -67.537584) (xy 330.271118 -67.537584) (xy 330.275189 -67.481962) (xy 330.287315 -67.427525)
			(xy 330.307238 -67.375434) (xy 330.334534 -67.326799) (xy 330.36862 -67.282656) (xy 330.408769 -67.243947)
			(xy 330.454127 -67.211496) (xy 330.503727 -67.185995) (xy 330.556511 -67.167988) (xy 330.611354 -67.157858)
			(xy 330.667088 -67.155821) (xy 330.722525 -67.161921) (xy 330.776482 -67.176027) (xy 330.827811 -67.197839)
			(xy 330.875417 -67.226893) (xy 330.918285 -67.262568) (xy 330.955502 -67.304105) (xy 330.986275 -67.350618)
			(xy 331.009947 -67.401115) (xy 331.026015 -67.454522) (xy 331.034135 -67.509698) (xy 331.034644 -67.537584)
			(xy 331.034135 -67.56547) (xy 331.03009 -67.592956) (xy 331.545182 -67.592956) (xy 331.549253 -67.537334)
			(xy 331.561379 -67.482897) (xy 331.581302 -67.430806) (xy 331.608598 -67.382171) (xy 331.642684 -67.338028)
			(xy 331.682833 -67.299319) (xy 331.728191 -67.266868) (xy 331.777791 -67.241367) (xy 331.830575 -67.22336)
			(xy 331.885418 -67.21323) (xy 331.941152 -67.211193) (xy 331.996589 -67.217293) (xy 332.050546 -67.231399)
			(xy 332.101875 -67.253211) (xy 332.149481 -67.282265) (xy 332.192349 -67.31794) (xy 332.229566 -67.359477)
			(xy 332.234138 -67.366388) (xy 342.116408 -67.366388) (xy 342.120479 -67.310766) (xy 342.132605 -67.256329)
			(xy 342.152528 -67.204238) (xy 342.179824 -67.155603) (xy 342.21391 -67.11146) (xy 342.254059 -67.072751)
			(xy 342.299417 -67.0403) (xy 342.349017 -67.014799) (xy 342.401801 -66.996792) (xy 342.456644 -66.986662)
			(xy 342.512378 -66.984625) (xy 342.567815 -66.990725) (xy 342.621772 -67.004831) (xy 342.673101 -67.026643)
			(xy 342.720707 -67.055697) (xy 342.763575 -67.091372) (xy 342.797244 -67.128949) (xy 362.666798 -67.128949)
			(xy 362.666798 -67.074451) (xy 362.674554 -67.020507) (xy 362.689908 -66.968216) (xy 362.712547 -66.918642)
			(xy 362.74201 -66.872795) (xy 362.777699 -66.831607) (xy 362.818885 -66.795918) (xy 362.864732 -66.766452)
			(xy 362.914305 -66.743812) (xy 362.966595 -66.728457) (xy 363.020539 -66.720699) (xy 363.047788 -66.720212)
			(xy 363.075158 -66.720682) (xy 363.129337 -66.728499) (xy 363.18184 -66.743987) (xy 363.231587 -66.766827)
			(xy 363.277554 -66.796551) (xy 363.298486 -66.814192) (xy 363.29874 -66.814446) (xy 363.305836 -66.820019)
			(xy 363.322746 -66.826273) (xy 363.33176 -66.826638) (xy 363.398816 -66.826638) (xy 363.407833 -66.826281)
			(xy 363.424749 -66.820032) (xy 363.431836 -66.814446) (xy 363.432344 -66.813938) (xy 363.453285 -66.796364)
			(xy 363.499217 -66.766722) (xy 363.548911 -66.743941) (xy 363.601348 -66.728489) (xy 363.655455 -66.720682)
			(xy 363.682788 -66.720212) (xy 363.710043 -66.720634) (xy 363.763998 -66.72839) (xy 363.8163 -66.743746)
			(xy 363.865884 -66.766389) (xy 363.911741 -66.795858) (xy 363.952938 -66.831554) (xy 363.988635 -66.872749)
			(xy 364.018105 -66.918605) (xy 364.04075 -66.968189) (xy 364.056107 -67.02049) (xy 364.063865 -67.074445)
			(xy 364.063865 -67.128955) (xy 364.056107 -67.18291) (xy 364.04075 -67.235211) (xy 364.018105 -67.284795)
			(xy 363.988635 -67.330651) (xy 363.952938 -67.371846) (xy 363.911741 -67.407542) (xy 363.865884 -67.437011)
			(xy 363.8163 -67.459654) (xy 363.763998 -67.47501) (xy 363.710043 -67.482766) (xy 363.682788 -67.483228)
			(xy 363.655417 -67.482787) (xy 363.601236 -67.474965) (xy 363.548732 -67.459472) (xy 363.498985 -67.436624)
			(xy 363.45302 -67.406893) (xy 363.43209 -67.389248) (xy 363.431836 -67.388994) (xy 363.424744 -67.383416)
			(xy 363.407831 -67.377164) (xy 363.398816 -67.376802) (xy 363.33176 -67.376802) (xy 363.322741 -67.37714)
			(xy 363.305824 -67.383401) (xy 363.29874 -67.388994) (xy 363.298232 -67.389502) (xy 363.277305 -67.407093)
			(xy 363.231369 -67.436732) (xy 363.181671 -67.459508) (xy 363.129231 -67.474956) (xy 363.075122 -67.482759)
			(xy 363.047788 -67.483228) (xy 363.020539 -67.482701) (xy 362.966595 -67.474943) (xy 362.914305 -67.459588)
			(xy 362.864732 -67.436948) (xy 362.818885 -67.407482) (xy 362.777699 -67.371793) (xy 362.74201 -67.330605)
			(xy 362.712547 -67.284758) (xy 362.689908 -67.235184) (xy 362.674554 -67.182893) (xy 362.666798 -67.128949)
			(xy 342.797244 -67.128949) (xy 342.800792 -67.132909) (xy 342.831565 -67.179422) (xy 342.855237 -67.229919)
			(xy 342.871305 -67.283326) (xy 342.879425 -67.338502) (xy 342.879934 -67.366388) (xy 342.879425 -67.394274)
			(xy 342.871305 -67.44945) (xy 342.855237 -67.502857) (xy 342.831565 -67.553354) (xy 342.800792 -67.599867)
			(xy 342.763575 -67.641404) (xy 342.720707 -67.677079) (xy 342.673101 -67.706133) (xy 342.621772 -67.727945)
			(xy 342.567815 -67.742051) (xy 342.512378 -67.748151) (xy 342.456644 -67.746114) (xy 342.401801 -67.735984)
			(xy 342.349017 -67.717977) (xy 342.299417 -67.692476) (xy 342.254059 -67.660025) (xy 342.21391 -67.621316)
			(xy 342.179824 -67.577173) (xy 342.152528 -67.528538) (xy 342.132605 -67.476447) (xy 342.120479 -67.42201)
			(xy 342.116408 -67.366388) (xy 332.234138 -67.366388) (xy 332.260339 -67.40599) (xy 332.284011 -67.456487)
			(xy 332.300079 -67.509894) (xy 332.308199 -67.56507) (xy 332.308708 -67.592956) (xy 332.308199 -67.620842)
			(xy 332.300079 -67.676018) (xy 332.284011 -67.729425) (xy 332.260339 -67.779922) (xy 332.229566 -67.826435)
			(xy 332.192349 -67.867972) (xy 332.149481 -67.903647) (xy 332.101875 -67.932701) (xy 332.050546 -67.954513)
			(xy 331.996589 -67.968619) (xy 331.941152 -67.974719) (xy 331.885418 -67.972682) (xy 331.830575 -67.962552)
			(xy 331.777791 -67.944545) (xy 331.728191 -67.919044) (xy 331.682833 -67.886593) (xy 331.642684 -67.847884)
			(xy 331.608598 -67.803741) (xy 331.581302 -67.755106) (xy 331.561379 -67.703015) (xy 331.549253 -67.648578)
			(xy 331.545182 -67.592956) (xy 331.03009 -67.592956) (xy 331.026015 -67.620646) (xy 331.009947 -67.674053)
			(xy 330.986275 -67.72455) (xy 330.955502 -67.771063) (xy 330.918285 -67.8126) (xy 330.875417 -67.848275)
			(xy 330.827811 -67.877329) (xy 330.776482 -67.899141) (xy 330.722525 -67.913247) (xy 330.667088 -67.919347)
			(xy 330.611354 -67.91731) (xy 330.556511 -67.90718) (xy 330.503727 -67.889173) (xy 330.454127 -67.863672)
			(xy 330.408769 -67.831221) (xy 330.36862 -67.792512) (xy 330.334534 -67.748369) (xy 330.307238 -67.699734)
			(xy 330.287315 -67.647643) (xy 330.275189 -67.593206) (xy 330.271118 -67.537584) (xy 329.738852 -67.537584)
			(xy 329.733917 -67.571116) (xy 329.717849 -67.624523) (xy 329.694177 -67.67502) (xy 329.663404 -67.721533)
			(xy 329.626187 -67.76307) (xy 329.583319 -67.798745) (xy 329.535713 -67.827799) (xy 329.484384 -67.849611)
			(xy 329.430427 -67.863717) (xy 329.37499 -67.869817) (xy 329.319256 -67.86778) (xy 329.264413 -67.85765)
			(xy 329.211629 -67.839643) (xy 329.162029 -67.814142) (xy 329.116671 -67.781691) (xy 329.076522 -67.742982)
			(xy 329.042436 -67.698839) (xy 329.01514 -67.650204) (xy 328.995217 -67.598113) (xy 328.983091 -67.543676)
			(xy 328.97902 -67.488054) (xy 306.29356 -67.488054) (xy 306.300131 -67.509894) (xy 306.308251 -67.56507)
			(xy 306.30876 -67.592956) (xy 306.308251 -67.620842) (xy 306.300131 -67.676018) (xy 306.284063 -67.729425)
			(xy 306.260391 -67.779922) (xy 306.229618 -67.826435) (xy 306.192401 -67.867972) (xy 306.149533 -67.903647)
			(xy 306.101927 -67.932701) (xy 306.050598 -67.954513) (xy 305.996641 -67.968619) (xy 305.941204 -67.974719)
			(xy 305.88547 -67.972682) (xy 305.830627 -67.962552) (xy 305.777843 -67.944545) (xy 305.728243 -67.919044)
			(xy 305.682885 -67.886593) (xy 305.642736 -67.847884) (xy 305.60865 -67.803741) (xy 305.581354 -67.755106)
			(xy 305.561431 -67.703015) (xy 305.549305 -67.648578) (xy 305.545234 -67.592956) (xy 305.030142 -67.592956)
			(xy 305.026067 -67.620646) (xy 305.009999 -67.674053) (xy 304.986327 -67.72455) (xy 304.955554 -67.771063)
			(xy 304.918337 -67.8126) (xy 304.875469 -67.848275) (xy 304.827863 -67.877329) (xy 304.776534 -67.899141)
			(xy 304.722577 -67.913247) (xy 304.66714 -67.919347) (xy 304.611406 -67.91731) (xy 304.556563 -67.90718)
			(xy 304.503779 -67.889173) (xy 304.454179 -67.863672) (xy 304.408821 -67.831221) (xy 304.368672 -67.792512)
			(xy 304.334586 -67.748369) (xy 304.30729 -67.699734) (xy 304.287367 -67.647643) (xy 304.275241 -67.593206)
			(xy 304.27117 -67.537584) (xy 303.738904 -67.537584) (xy 303.733969 -67.571116) (xy 303.717901 -67.624523)
			(xy 303.694229 -67.67502) (xy 303.663456 -67.721533) (xy 303.626239 -67.76307) (xy 303.583371 -67.798745)
			(xy 303.535765 -67.827799) (xy 303.484436 -67.849611) (xy 303.430479 -67.863717) (xy 303.375042 -67.869817)
			(xy 303.319308 -67.86778) (xy 303.264465 -67.85765) (xy 303.211681 -67.839643) (xy 303.162081 -67.814142)
			(xy 303.116723 -67.781691) (xy 303.076574 -67.742982) (xy 303.042488 -67.698839) (xy 303.015192 -67.650204)
			(xy 302.995269 -67.598113) (xy 302.983143 -67.543676) (xy 302.979072 -67.488054) (xy 280.293612 -67.488054)
			(xy 280.300183 -67.509894) (xy 280.308303 -67.56507) (xy 280.308812 -67.592956) (xy 280.308303 -67.620842)
			(xy 280.300183 -67.676018) (xy 280.284115 -67.729425) (xy 280.260443 -67.779922) (xy 280.22967 -67.826435)
			(xy 280.192453 -67.867972) (xy 280.149585 -67.903647) (xy 280.101979 -67.932701) (xy 280.05065 -67.954513)
			(xy 279.996693 -67.968619) (xy 279.941256 -67.974719) (xy 279.885522 -67.972682) (xy 279.830679 -67.962552)
			(xy 279.777895 -67.944545) (xy 279.728295 -67.919044) (xy 279.682937 -67.886593) (xy 279.642788 -67.847884)
			(xy 279.608702 -67.803741) (xy 279.581406 -67.755106) (xy 279.561483 -67.703015) (xy 279.549357 -67.648578)
			(xy 279.545286 -67.592956) (xy 279.030194 -67.592956) (xy 279.026119 -67.620646) (xy 279.010051 -67.674053)
			(xy 278.986379 -67.72455) (xy 278.955606 -67.771063) (xy 278.918389 -67.8126) (xy 278.875521 -67.848275)
			(xy 278.827915 -67.877329) (xy 278.776586 -67.899141) (xy 278.722629 -67.913247) (xy 278.667192 -67.919347)
			(xy 278.611458 -67.91731) (xy 278.556615 -67.90718) (xy 278.503831 -67.889173) (xy 278.454231 -67.863672)
			(xy 278.408873 -67.831221) (xy 278.368724 -67.792512) (xy 278.334638 -67.748369) (xy 278.307342 -67.699734)
			(xy 278.287419 -67.647643) (xy 278.275293 -67.593206) (xy 278.271222 -67.537584) (xy 277.738956 -67.537584)
			(xy 277.734021 -67.571116) (xy 277.717953 -67.624523) (xy 277.694281 -67.67502) (xy 277.663508 -67.721533)
			(xy 277.626291 -67.76307) (xy 277.583423 -67.798745) (xy 277.535817 -67.827799) (xy 277.484488 -67.849611)
			(xy 277.430531 -67.863717) (xy 277.375094 -67.869817) (xy 277.31936 -67.86778) (xy 277.264517 -67.85765)
			(xy 277.211733 -67.839643) (xy 277.162133 -67.814142) (xy 277.116775 -67.781691) (xy 277.076626 -67.742982)
			(xy 277.04254 -67.698839) (xy 277.015244 -67.650204) (xy 276.995321 -67.598113) (xy 276.983195 -67.543676)
			(xy 276.979124 -67.488054) (xy 254.293664 -67.488054) (xy 254.300235 -67.509894) (xy 254.308355 -67.56507)
			(xy 254.308864 -67.592956) (xy 254.308355 -67.620842) (xy 254.300235 -67.676018) (xy 254.284167 -67.729425)
			(xy 254.260495 -67.779922) (xy 254.229722 -67.826435) (xy 254.192505 -67.867972) (xy 254.149637 -67.903647)
			(xy 254.102031 -67.932701) (xy 254.050702 -67.954513) (xy 253.996745 -67.968619) (xy 253.941308 -67.974719)
			(xy 253.885574 -67.972682) (xy 253.830731 -67.962552) (xy 253.777947 -67.944545) (xy 253.728347 -67.919044)
			(xy 253.682989 -67.886593) (xy 253.64284 -67.847884) (xy 253.608754 -67.803741) (xy 253.581458 -67.755106)
			(xy 253.561535 -67.703015) (xy 253.549409 -67.648578) (xy 253.545338 -67.592956) (xy 253.030246 -67.592956)
			(xy 253.026171 -67.620646) (xy 253.010103 -67.674053) (xy 252.986431 -67.72455) (xy 252.955658 -67.771063)
			(xy 252.918441 -67.8126) (xy 252.875573 -67.848275) (xy 252.827967 -67.877329) (xy 252.776638 -67.899141)
			(xy 252.722681 -67.913247) (xy 252.667244 -67.919347) (xy 252.61151 -67.91731) (xy 252.556667 -67.90718)
			(xy 252.503883 -67.889173) (xy 252.454283 -67.863672) (xy 252.408925 -67.831221) (xy 252.368776 -67.792512)
			(xy 252.33469 -67.748369) (xy 252.307394 -67.699734) (xy 252.287471 -67.647643) (xy 252.275345 -67.593206)
			(xy 252.271274 -67.537584) (xy 251.739008 -67.537584) (xy 251.734073 -67.571116) (xy 251.718005 -67.624523)
			(xy 251.694333 -67.67502) (xy 251.66356 -67.721533) (xy 251.626343 -67.76307) (xy 251.583475 -67.798745)
			(xy 251.535869 -67.827799) (xy 251.48454 -67.849611) (xy 251.430583 -67.863717) (xy 251.375146 -67.869817)
			(xy 251.319412 -67.86778) (xy 251.264569 -67.85765) (xy 251.211785 -67.839643) (xy 251.162185 -67.814142)
			(xy 251.116827 -67.781691) (xy 251.076678 -67.742982) (xy 251.042592 -67.698839) (xy 251.015296 -67.650204)
			(xy 250.995373 -67.598113) (xy 250.983247 -67.543676) (xy 250.979176 -67.488054) (xy 236.086396 -67.488054)
			(xy 236.086396 -68.586604) (xy 248.825258 -68.586604) (xy 248.825747 -68.559271) (xy 248.833549 -68.505164)
			(xy 248.848994 -68.452725) (xy 248.871764 -68.403027) (xy 248.901395 -68.357087) (xy 248.918984 -68.33616)
			(xy 248.919238 -68.335906) (xy 248.919492 -68.335652) (xy 248.925062 -68.328554) (xy 248.931319 -68.311646)
			(xy 248.931684 -68.302632) (xy 248.931684 -68.235576) (xy 248.931342 -68.226558) (xy 248.925084 -68.209641)
			(xy 248.919492 -68.202556) (xy 248.919238 -68.202302) (xy 248.918984 -68.202048) (xy 248.901398 -68.181117)
			(xy 248.871759 -68.135181) (xy 248.848982 -68.085485) (xy 248.833533 -68.033045) (xy 248.825728 -67.978938)
			(xy 248.825258 -67.951604) (xy 248.825781 -67.924354) (xy 248.833536 -67.87041) (xy 248.848889 -67.818118)
			(xy 248.871528 -67.768543) (xy 248.90099 -67.722694) (xy 248.936678 -67.681505) (xy 248.977864 -67.645813)
			(xy 249.023709 -67.616346) (xy 249.073282 -67.593703) (xy 249.125573 -67.578345) (xy 249.179516 -67.570584)
			(xy 249.206766 -67.570096) (xy 249.20702 -67.570096) (xy 249.233315 -67.570543) (xy 249.285404 -67.577791)
			(xy 249.336006 -67.592119) (xy 249.384162 -67.613257) (xy 249.428961 -67.640804) (xy 249.469556 -67.674239)
			(xy 249.48769 -67.693286) (xy 249.495268 -67.700719) (xy 249.514681 -67.70925) (xy 249.525282 -67.709796)
			(xy 249.59945 -67.709796) (xy 249.610084 -67.709407) (xy 249.629549 -67.700844) (xy 249.637042 -67.693286)
			(xy 249.655138 -67.674198) (xy 249.695728 -67.640745) (xy 249.740531 -67.61319) (xy 249.788697 -67.592057)
			(xy 249.839311 -67.577746) (xy 249.891413 -67.57053) (xy 249.917712 -67.570096) (xy 249.917966 -67.570096)
			(xy 249.945335 -67.570583) (xy 249.999514 -67.578396) (xy 250.052016 -67.59388) (xy 250.101764 -67.616717)
			(xy 250.147732 -67.646437) (xy 250.168664 -67.664076) (xy 250.168918 -67.66433) (xy 250.175993 -67.669934)
			(xy 250.192919 -67.676169) (xy 250.201938 -67.676522) (xy 250.268994 -67.676522) (xy 250.27801 -67.676157)
			(xy 250.294927 -67.669914) (xy 250.302014 -67.66433) (xy 250.302522 -67.663822) (xy 250.323469 -67.646256)
			(xy 250.3694 -67.616613) (xy 250.419092 -67.593831) (xy 250.471528 -67.578377) (xy 250.525633 -67.570568)
			(xy 250.552966 -67.570096) (xy 250.580218 -67.570587) (xy 250.634168 -67.578339) (xy 250.686466 -67.593691)
			(xy 250.736046 -67.61633) (xy 250.7819 -67.645795) (xy 250.823093 -67.681486) (xy 250.858787 -67.722676)
			(xy 250.888255 -67.768527) (xy 250.910898 -67.818106) (xy 250.926254 -67.870402) (xy 250.934011 -67.924352)
			(xy 250.934474 -67.951604) (xy 250.933982 -67.978937) (xy 250.926179 -68.033043) (xy 250.910735 -68.085482)
			(xy 250.887965 -68.13518) (xy 250.858336 -68.18112) (xy 250.840748 -68.202048) (xy 250.840494 -68.202302)
			(xy 250.84024 -68.202556) (xy 250.834659 -68.209646) (xy 250.82841 -68.22656) (xy 250.828048 -68.235576)
			(xy 250.828048 -68.302632) (xy 250.828379 -68.311652) (xy 250.834643 -68.328569) (xy 250.84024 -68.335652)
			(xy 250.840494 -68.335906) (xy 250.840748 -68.33616) (xy 250.858343 -68.357084) (xy 250.887979 -68.403022)
			(xy 250.910754 -68.45272) (xy 250.926202 -68.505161) (xy 250.934005 -68.55927) (xy 250.934474 -68.586604)
			(xy 274.825206 -68.586604) (xy 274.825708 -68.559271) (xy 274.833509 -68.505166) (xy 274.848951 -68.452727)
			(xy 274.871718 -68.403029) (xy 274.901345 -68.357088) (xy 274.918932 -68.33616) (xy 274.919186 -68.335906)
			(xy 274.91944 -68.335652) (xy 274.925016 -68.328558) (xy 274.931268 -68.311647) (xy 274.931632 -68.302632)
			(xy 274.931632 -68.235576) (xy 274.93128 -68.226559) (xy 274.925028 -68.209642) (xy 274.91944 -68.202556)
			(xy 274.919186 -68.202302) (xy 274.918932 -68.202048) (xy 274.901354 -68.181111) (xy 274.871712 -68.135178)
			(xy 274.848932 -68.085483) (xy 274.833481 -68.033045) (xy 274.825676 -67.978938) (xy 274.825206 -67.951604)
			(xy 274.825659 -67.924351) (xy 274.833416 -67.870399) (xy 274.848772 -67.8181) (xy 274.871415 -67.768519)
			(xy 274.900884 -67.722665) (xy 274.936579 -67.681472) (xy 274.977773 -67.645778) (xy 275.023627 -67.61631)
			(xy 275.073209 -67.593669) (xy 275.125508 -67.578314) (xy 275.179461 -67.570558) (xy 275.206714 -67.570096)
			(xy 275.206968 -67.570096) (xy 275.233262 -67.570577) (xy 275.28535 -67.577818) (xy 275.335951 -67.59214)
			(xy 275.384107 -67.613271) (xy 275.428907 -67.640812) (xy 275.469503 -67.674241) (xy 275.487638 -67.693286)
			(xy 275.495198 -67.700741) (xy 275.514625 -67.709259) (xy 275.52523 -67.709796) (xy 275.599398 -67.709796)
			(xy 275.610029 -67.709378) (xy 275.629494 -67.700835) (xy 275.63699 -67.693286) (xy 275.655112 -67.674223)
			(xy 275.695695 -67.640768) (xy 275.740493 -67.61321) (xy 275.788655 -67.592072) (xy 275.839265 -67.577756)
			(xy 275.891362 -67.570533) (xy 275.91766 -67.570096) (xy 275.917914 -67.570096) (xy 275.945284 -67.570555)
			(xy 275.999464 -67.578375) (xy 276.051967 -67.593865) (xy 276.101714 -67.616709) (xy 276.14768 -67.646434)
			(xy 276.168612 -67.664076) (xy 276.168866 -67.66433) (xy 276.175956 -67.669912) (xy 276.19287 -67.67616)
			(xy 276.201886 -67.676522) (xy 276.268942 -67.676522) (xy 276.277956 -67.676133) (xy 276.294873 -67.669907)
			(xy 276.301962 -67.66433) (xy 276.30247 -67.663822) (xy 276.323399 -67.646234) (xy 276.369335 -67.616594)
			(xy 276.419032 -67.593816) (xy 276.471472 -67.578368) (xy 276.52558 -67.570564) (xy 276.552914 -67.570096)
			(xy 276.580166 -67.570565) (xy 276.634114 -67.578323) (xy 276.68641 -67.59368) (xy 276.735987 -67.616323)
			(xy 276.781838 -67.645792) (xy 276.823028 -67.681485) (xy 276.858719 -67.722677) (xy 276.888185 -67.768529)
			(xy 276.910826 -67.818107) (xy 276.926181 -67.870403) (xy 276.933937 -67.924352) (xy 276.934422 -67.951604)
			(xy 276.933918 -67.978936) (xy 276.926117 -68.033042) (xy 276.910675 -68.08548) (xy 276.887908 -68.135178)
			(xy 276.858282 -68.181119) (xy 276.840696 -68.202048) (xy 276.840442 -68.202302) (xy 276.840188 -68.202556)
			(xy 276.834612 -68.20965) (xy 276.828359 -68.226561) (xy 276.827996 -68.235576) (xy 276.827996 -68.302632)
			(xy 276.828339 -68.31165) (xy 276.834596 -68.328567) (xy 276.840188 -68.335652) (xy 276.840442 -68.335906)
			(xy 276.840696 -68.33616) (xy 276.858283 -68.35709) (xy 276.887922 -68.403026) (xy 276.910699 -68.452723)
			(xy 276.926149 -68.505162) (xy 276.933953 -68.55927) (xy 276.934422 -68.586604) (xy 300.825154 -68.586604)
			(xy 300.825644 -68.559271) (xy 300.833446 -68.505164) (xy 300.84889 -68.452725) (xy 300.871661 -68.403027)
			(xy 300.901291 -68.357088) (xy 300.91888 -68.33616) (xy 300.919134 -68.335906) (xy 300.919388 -68.335652)
			(xy 300.924958 -68.328554) (xy 300.931215 -68.311646) (xy 300.93158 -68.302632) (xy 300.93158 -68.235576)
			(xy 300.931239 -68.226557) (xy 300.924981 -68.20964) (xy 300.919388 -68.202556) (xy 300.919134 -68.202302)
			(xy 300.91888 -68.202048) (xy 300.901293 -68.181118) (xy 300.871655 -68.135182) (xy 300.848878 -68.085485)
			(xy 300.833428 -68.033046) (xy 300.825624 -67.978938) (xy 300.825154 -67.951604) (xy 300.825681 -67.924355)
			(xy 300.833436 -67.87041) (xy 300.848789 -67.818119) (xy 300.871427 -67.768544) (xy 300.900889 -67.722695)
			(xy 300.936576 -67.681506) (xy 300.977762 -67.645815) (xy 301.023607 -67.616347) (xy 301.073179 -67.593704)
			(xy 301.125469 -67.578345) (xy 301.179413 -67.570584) (xy 301.206662 -67.570096) (xy 301.206916 -67.570096)
			(xy 301.233211 -67.570545) (xy 301.2853 -67.577793) (xy 301.335902 -67.592121) (xy 301.384058 -67.613258)
			(xy 301.428857 -67.640804) (xy 301.469452 -67.674239) (xy 301.487586 -67.693286) (xy 301.495166 -67.700718)
			(xy 301.514577 -67.709249) (xy 301.525178 -67.709796) (xy 301.599346 -67.709796) (xy 301.60998 -67.709405)
			(xy 301.629444 -67.700843) (xy 301.636938 -67.693286) (xy 301.655036 -67.6742) (xy 301.695625 -67.640747)
			(xy 301.740428 -67.613192) (xy 301.788594 -67.592058) (xy 301.839208 -67.577747) (xy 301.891309 -67.57053)
			(xy 301.917608 -67.570096) (xy 301.917862 -67.570096) (xy 301.945231 -67.570585) (xy 301.999409 -67.578398)
			(xy 302.051912 -67.593881) (xy 302.101659 -67.616718) (xy 302.147627 -67.646437) (xy 302.16856 -67.664076)
			(xy 302.168814 -67.66433) (xy 302.17589 -67.669932) (xy 302.192815 -67.676168) (xy 302.201834 -67.676522)
			(xy 302.26889 -67.676522) (xy 302.277906 -67.676155) (xy 302.294823 -67.669914) (xy 302.30191 -67.66433)
			(xy 302.302418 -67.663822) (xy 302.323329 -67.646211) (xy 302.36927 -67.616575) (xy 302.418971 -67.593802)
			(xy 302.471415 -67.578358) (xy 302.525527 -67.570561) (xy 302.552862 -67.570096) (xy 302.580114 -67.570591)
			(xy 302.634064 -67.578343) (xy 302.686362 -67.593694) (xy 302.735942 -67.616332) (xy 302.781795 -67.645797)
			(xy 302.822989 -67.681487) (xy 302.858683 -67.722677) (xy 302.888151 -67.768528) (xy 302.910794 -67.818106)
			(xy 302.92615 -67.870403) (xy 302.933907 -67.924352) (xy 302.93437 -67.951604) (xy 302.933879 -67.978937)
			(xy 302.926076 -68.033043) (xy 302.910632 -68.085482) (xy 302.887862 -68.13518) (xy 302.858232 -68.18112)
			(xy 302.840644 -68.202048) (xy 302.84039 -68.202302) (xy 302.840136 -68.202556) (xy 302.834554 -68.209645)
			(xy 302.828306 -68.22656) (xy 302.827944 -68.235576) (xy 302.827944 -68.302632) (xy 302.828276 -68.311652)
			(xy 302.83454 -68.328569) (xy 302.840136 -68.335652) (xy 302.84039 -68.335906) (xy 302.840644 -68.33616)
			(xy 302.858238 -68.357084) (xy 302.887875 -68.403022) (xy 302.91065 -68.452721) (xy 302.926098 -68.505161)
			(xy 302.933901 -68.55927) (xy 302.93437 -68.586604) (xy 326.825102 -68.586604) (xy 326.825605 -68.559271)
			(xy 326.833405 -68.505166) (xy 326.848848 -68.452727) (xy 326.871615 -68.403029) (xy 326.901242 -68.357089)
			(xy 326.918828 -68.33616) (xy 326.919082 -68.335906) (xy 326.919336 -68.335652) (xy 326.924911 -68.328558)
			(xy 326.931164 -68.311647) (xy 326.931528 -68.302632) (xy 326.931528 -68.235576) (xy 326.931177 -68.226559)
			(xy 326.924925 -68.209642) (xy 326.919336 -68.202556) (xy 326.919082 -68.202302) (xy 326.918828 -68.202048)
			(xy 326.901249 -68.181111) (xy 326.871608 -68.135178) (xy 326.848828 -68.085483) (xy 326.833377 -68.033045)
			(xy 326.825572 -67.978938) (xy 326.825102 -67.951604) (xy 326.825559 -67.924351) (xy 326.833316 -67.870399)
			(xy 326.848672 -67.818101) (xy 326.871315 -67.76852) (xy 326.900783 -67.722666) (xy 326.936477 -67.681473)
			(xy 326.977671 -67.645779) (xy 327.023525 -67.616312) (xy 327.073106 -67.59367) (xy 327.125405 -67.578314)
			(xy 327.179357 -67.570559) (xy 327.20661 -67.570096) (xy 327.206864 -67.570096) (xy 327.233158 -67.57058)
			(xy 327.285245 -67.57782) (xy 327.335846 -67.592141) (xy 327.384003 -67.613272) (xy 327.428803 -67.640813)
			(xy 327.469399 -67.674241) (xy 327.487534 -67.693286) (xy 327.495096 -67.700739) (xy 327.514521 -67.709258)
			(xy 327.525126 -67.709796) (xy 327.599294 -67.709796) (xy 327.609925 -67.709376) (xy 327.629389 -67.700834)
			(xy 327.636886 -67.693286) (xy 327.655009 -67.674225) (xy 327.695593 -67.64077) (xy 327.740391 -67.613211)
			(xy 327.788551 -67.592073) (xy 327.839161 -67.577757) (xy 327.891258 -67.570534) (xy 327.917556 -67.570096)
			(xy 327.91781 -67.570096) (xy 327.94518 -67.570557) (xy 327.99936 -67.578376) (xy 328.051863 -67.593867)
			(xy 328.10161 -67.616709) (xy 328.147576 -67.646435) (xy 328.168508 -67.664076) (xy 328.168762 -67.66433)
			(xy 328.175853 -67.66991) (xy 328.192766 -67.67616) (xy 328.201782 -67.676522) (xy 328.268838 -67.676522)
			(xy 328.277856 -67.676179) (xy 328.294773 -67.669921) (xy 328.301858 -67.66433) (xy 328.302366 -67.663822)
			(xy 328.323297 -67.646235) (xy 328.369232 -67.616595) (xy 328.418928 -67.593818) (xy 328.471368 -67.578368)
			(xy 328.525476 -67.570565) (xy 328.55281 -67.570096) (xy 328.580062 -67.570569) (xy 328.63401 -67.578326)
			(xy 328.686305 -67.593683) (xy 328.735883 -67.616326) (xy 328.781733 -67.645793) (xy 328.822924 -67.681486)
			(xy 328.858615 -67.722678) (xy 328.888081 -67.768529) (xy 328.910722 -67.818108) (xy 328.926077 -67.870404)
			(xy 328.933832 -67.924352) (xy 328.934318 -67.951604) (xy 328.933815 -67.978936) (xy 328.926014 -68.033042)
			(xy 328.910571 -68.08548) (xy 328.887804 -68.135178) (xy 328.858178 -68.181119) (xy 328.840592 -68.202048)
			(xy 328.840338 -68.202302) (xy 328.840084 -68.202556) (xy 328.834508 -68.20965) (xy 328.828255 -68.226561)
			(xy 328.827892 -68.235576) (xy 328.827892 -68.302632) (xy 328.828236 -68.31165) (xy 328.834493 -68.328567)
			(xy 328.840084 -68.335652) (xy 328.840338 -68.335906) (xy 328.840592 -68.33616) (xy 328.858178 -68.357091)
			(xy 328.887818 -68.403026) (xy 328.910595 -68.452723) (xy 328.926045 -68.505162) (xy 328.933849 -68.55927)
			(xy 328.934318 -68.586604) (xy 328.933826 -68.613855) (xy 328.926069 -68.667802) (xy 328.910714 -68.720096)
			(xy 328.888073 -68.769672) (xy 328.858607 -68.815522) (xy 328.822917 -68.856712) (xy 328.781727 -68.892404)
			(xy 328.735878 -68.92187) (xy 328.686302 -68.944512) (xy 328.634008 -68.959868) (xy 328.580061 -68.967626)
			(xy 328.55281 -68.968112) (xy 328.52544 -68.967637) (xy 328.471262 -68.959821) (xy 328.418759 -68.944334)
			(xy 328.369012 -68.921494) (xy 328.323044 -68.891772) (xy 328.302112 -68.874132) (xy 328.301858 -68.873878)
			(xy 328.294761 -68.868307) (xy 328.277852 -68.862052) (xy 328.268838 -68.861686) (xy 328.201782 -68.861686)
			(xy 328.192765 -68.862038) (xy 328.175848 -68.868289) (xy 328.168762 -68.873878) (xy 328.168254 -68.874386)
			(xy 328.147317 -68.891964) (xy 328.101383 -68.921605) (xy 328.051688 -68.944385) (xy 327.99925 -68.959836)
			(xy 327.945144 -68.967642) (xy 327.91781 -68.968112) (xy 327.917556 -68.968112) (xy 327.89126 -68.967679)
			(xy 327.839171 -68.960428) (xy 327.788569 -68.946096) (xy 327.740413 -68.924956) (xy 327.695614 -68.897407)
			(xy 327.65502 -68.86397) (xy 327.636886 -68.844922) (xy 327.629316 -68.837479) (xy 327.609897 -68.828954)
			(xy 327.599294 -68.828412) (xy 327.525126 -68.828412) (xy 327.514496 -68.828841) (xy 327.495031 -68.837376)
			(xy 327.487534 -68.844922) (xy 327.469402 -68.863974) (xy 327.42882 -68.89743) (xy 327.384024 -68.92499)
			(xy 327.335865 -68.946129) (xy 327.285257 -68.960448) (xy 327.233161 -68.967673) (xy 327.206864 -68.968112)
			(xy 327.20661 -68.968112) (xy 327.179358 -68.967635) (xy 327.125407 -68.95988) (xy 327.07311 -68.944525)
			(xy 327.02353 -68.921884) (xy 326.977677 -68.892418) (xy 326.936485 -68.856725) (xy 326.900791 -68.815534)
			(xy 326.871322 -68.769682) (xy 326.84868 -68.720103) (xy 326.833323 -68.667806) (xy 326.825566 -68.613856)
			(xy 326.825102 -68.586604) (xy 302.93437 -68.586604) (xy 302.933948 -68.613859) (xy 302.92619 -68.667813)
			(xy 302.910831 -68.720114) (xy 302.888186 -68.769697) (xy 302.858714 -68.815552) (xy 302.823015 -68.856745)
			(xy 302.781818 -68.892439) (xy 302.73596 -68.921906) (xy 302.686375 -68.944546) (xy 302.634072 -68.959899)
			(xy 302.580117 -68.967651) (xy 302.552862 -68.968112) (xy 302.525493 -68.967607) (xy 302.471316 -68.959798)
			(xy 302.418813 -68.944318) (xy 302.369066 -68.921485) (xy 302.323097 -68.891769) (xy 302.302164 -68.874132)
			(xy 302.30191 -68.873878) (xy 302.294827 -68.868287) (xy 302.277907 -68.862044) (xy 302.26889 -68.861686)
			(xy 302.201834 -68.861686) (xy 302.192819 -68.862062) (xy 302.175902 -68.868297) (xy 302.168814 -68.873878)
			(xy 302.168306 -68.874386) (xy 302.147387 -68.891987) (xy 302.101448 -68.921624) (xy 302.051749 -68.944399)
			(xy 301.999307 -68.959845) (xy 301.945197 -68.967645) (xy 301.917862 -68.968112) (xy 301.917608 -68.968112)
			(xy 301.891314 -68.967644) (xy 301.839225 -68.9604) (xy 301.788624 -68.946076) (xy 301.740468 -68.924942)
			(xy 301.695668 -68.897399) (xy 301.655073 -68.863968) (xy 301.636938 -68.844922) (xy 301.629348 -68.837502)
			(xy 301.609944 -68.828964) (xy 301.599346 -68.828412) (xy 301.525178 -68.828412) (xy 301.514545 -68.828814)
			(xy 301.495081 -68.837368) (xy 301.487586 -68.844922) (xy 301.469478 -68.863998) (xy 301.428891 -68.897451)
			(xy 301.38409 -68.925008) (xy 301.335926 -68.946143) (xy 301.285314 -68.960457) (xy 301.233215 -68.967676)
			(xy 301.206916 -68.968112) (xy 301.206662 -68.968112) (xy 301.17941 -68.967658) (xy 301.125461 -68.959896)
			(xy 301.073166 -68.944536) (xy 301.023589 -68.921891) (xy 300.977739 -68.892421) (xy 300.936549 -68.856726)
			(xy 300.900859 -68.815534) (xy 300.871393 -68.769681) (xy 300.848752 -68.720102) (xy 300.833397 -68.667805)
			(xy 300.82564 -68.613856) (xy 300.825154 -68.586604) (xy 276.934422 -68.586604) (xy 276.933926 -68.613855)
			(xy 276.926169 -68.667801) (xy 276.910814 -68.720095) (xy 276.888174 -68.769671) (xy 276.858708 -68.815521)
			(xy 276.823018 -68.856711) (xy 276.781829 -68.892402) (xy 276.73598 -68.921869) (xy 276.686404 -68.944511)
			(xy 276.634111 -68.959867) (xy 276.580165 -68.967625) (xy 276.552914 -68.968112) (xy 276.525544 -68.967635)
			(xy 276.471366 -68.959819) (xy 276.418863 -68.944333) (xy 276.369116 -68.921493) (xy 276.323148 -68.891772)
			(xy 276.302216 -68.874132) (xy 276.301962 -68.873878) (xy 276.294864 -68.868309) (xy 276.277956 -68.862052)
			(xy 276.268942 -68.861686) (xy 276.201886 -68.861686) (xy 276.192869 -68.86204) (xy 276.175952 -68.86829)
			(xy 276.168866 -68.873878) (xy 276.168358 -68.874386) (xy 276.147419 -68.891963) (xy 276.101486 -68.921604)
			(xy 276.051792 -68.944383) (xy 275.999354 -68.959835) (xy 275.945247 -68.967642) (xy 275.917914 -68.968112)
			(xy 275.91766 -68.968112) (xy 275.891364 -68.967676) (xy 275.839275 -68.960426) (xy 275.788673 -68.946095)
			(xy 275.740517 -68.924955) (xy 275.695718 -68.897406) (xy 275.655124 -68.86397) (xy 275.63699 -68.844922)
			(xy 275.629418 -68.837481) (xy 275.610001 -68.828955) (xy 275.599398 -68.828412) (xy 275.52523 -68.828412)
			(xy 275.5146 -68.828843) (xy 275.495136 -68.837377) (xy 275.487638 -68.844922) (xy 275.469504 -68.863972)
			(xy 275.428923 -68.897429) (xy 275.384127 -68.924988) (xy 275.335969 -68.946128) (xy 275.285361 -68.960447)
			(xy 275.233265 -68.967673) (xy 275.206968 -68.968112) (xy 275.206714 -68.968112) (xy 275.179462 -68.967632)
			(xy 275.125512 -68.959877) (xy 275.073214 -68.944523) (xy 275.023634 -68.921882) (xy 274.977781 -68.892416)
			(xy 274.936589 -68.856724) (xy 274.900895 -68.815533) (xy 274.871427 -68.769681) (xy 274.848784 -68.720103)
			(xy 274.833427 -68.667806) (xy 274.82567 -68.613856) (xy 274.825206 -68.586604) (xy 250.934474 -68.586604)
			(xy 250.934048 -68.613858) (xy 250.92629 -68.667813) (xy 250.910932 -68.720113) (xy 250.888286 -68.769696)
			(xy 250.858815 -68.81555) (xy 250.823117 -68.856744) (xy 250.78192 -68.892437) (xy 250.736062 -68.921904)
			(xy 250.686478 -68.944545) (xy 250.634175 -68.959898) (xy 250.580221 -68.967651) (xy 250.552966 -68.968112)
			(xy 250.525595 -68.967663) (xy 250.471416 -68.959841) (xy 250.418912 -68.944347) (xy 250.369166 -68.921502)
			(xy 250.323199 -68.891774) (xy 250.302268 -68.874132) (xy 250.302014 -68.873878) (xy 250.294929 -68.868289)
			(xy 250.278011 -68.862044) (xy 250.268994 -68.861686) (xy 250.201938 -68.861686) (xy 250.192923 -68.862064)
			(xy 250.176006 -68.868297) (xy 250.168918 -68.873878) (xy 250.16841 -68.874386) (xy 250.14749 -68.891985)
			(xy 250.101551 -68.921623) (xy 250.051852 -68.944398) (xy 249.99941 -68.959844) (xy 249.945301 -68.967645)
			(xy 249.917966 -68.968112) (xy 249.917712 -68.968112) (xy 249.891418 -68.967641) (xy 249.83933 -68.960398)
			(xy 249.788729 -68.946074) (xy 249.740573 -68.924941) (xy 249.695773 -68.897398) (xy 249.655177 -68.863967)
			(xy 249.637042 -68.844922) (xy 249.629451 -68.837504) (xy 249.610048 -68.828965) (xy 249.59945 -68.828412)
			(xy 249.525282 -68.828412) (xy 249.514649 -68.828816) (xy 249.495185 -68.837369) (xy 249.48769 -68.844922)
			(xy 249.46958 -68.863996) (xy 249.428993 -68.89745) (xy 249.384193 -68.925006) (xy 249.336029 -68.946142)
			(xy 249.285418 -68.960456) (xy 249.233319 -68.967676) (xy 249.20702 -68.968112) (xy 249.206766 -68.968112)
			(xy 249.179514 -68.967654) (xy 249.125566 -68.959893) (xy 249.073271 -68.944534) (xy 249.023693 -68.921889)
			(xy 248.977843 -68.892419) (xy 248.936654 -68.856725) (xy 248.900963 -68.815532) (xy 248.871497 -68.76968)
			(xy 248.848856 -68.720101) (xy 248.833501 -68.667805) (xy 248.825744 -68.613856) (xy 248.825258 -68.586604)
			(xy 236.086396 -68.586604) (xy 236.086396 -70.235826) (xy 236.086889 -70.24583) (xy 236.094553 -70.264314)
			(xy 236.108704 -70.27846) (xy 236.127191 -70.286116) (xy 236.137196 -70.286626) (xy 239.55629 -70.286626)
			(xy 239.567216 -70.286102) (xy 239.587085 -70.277008) (xy 239.594644 -70.2691) (xy 239.644936 -70.210934)
			(xy 239.651669 -70.202412) (xy 239.657862 -70.181617) (xy 239.656874 -70.170802) (xy 239.656874 -70.170548)
			(xy 239.656874 -70.170294) (xy 239.655105 -70.157093) (xy 239.653197 -70.130526) (xy 239.653064 -70.117208)
			(xy 239.653064 -70.11543) (xy 239.653657 -70.088251) (xy 239.661594 -70.034472) (xy 239.677084 -69.982364)
			(xy 239.699814 -69.932982) (xy 239.729323 -69.887326) (xy 239.765013 -69.846321) (xy 239.806162 -69.810797)
			(xy 239.851936 -69.781473) (xy 239.90141 -69.758943) (xy 239.95358 -69.743663) (xy 240.007391 -69.735943)
			(xy 240.034572 -69.735446) (xy 240.061826 -69.73593) (xy 240.115779 -69.743683) (xy 240.16808 -69.759035)
			(xy 240.217663 -69.781674) (xy 240.263521 -69.811139) (xy 240.304718 -69.84683) (xy 240.340417 -69.88802)
			(xy 240.36989 -69.933872) (xy 240.392539 -69.983451) (xy 240.407901 -70.035749) (xy 240.415665 -70.0897)
			(xy 240.41608 -70.116954) (xy 240.41564 -70.143535) (xy 240.408242 -70.19618) (xy 240.401348 -70.221856)
			(xy 240.399316 -70.228714) (xy 240.399316 -70.235826) (xy 240.399809 -70.245829) (xy 240.407473 -70.264309)
			(xy 240.421626 -70.27845) (xy 240.440113 -70.2861) (xy 240.450116 -70.286626) (xy 240.475516 -70.286626)
			(xy 240.489486 -70.284594) (xy 240.508028 -70.27926) (xy 240.513616 -70.275958) (xy 240.546827 -70.257217)
			(xy 240.617138 -70.22769) (xy 240.69073 -70.207702) (xy 240.766317 -70.197603) (xy 240.804446 -70.196964)
			(xy 253.166626 -70.196964) (xy 253.204756 -70.197597) (xy 253.280345 -70.207693) (xy 253.35394 -70.227677)
			(xy 253.424253 -70.257202) (xy 253.457456 -70.275958) (xy 253.463044 -70.27926) (xy 253.481586 -70.284594)
			(xy 253.495556 -70.286626) (xy 345.182952 -70.286626) (xy 345.189904 -70.28639) (xy 345.2033 -70.282661)
			(xy 345.209368 -70.27926) (xy 345.235784 -70.263258) (xy 345.245182 -70.253352) (xy 345.248484 -70.247002)
			(xy 345.29647 -70.157063) (xy 345.398486 -69.980546) (xy 345.507267 -69.808115) (xy 345.62265 -69.640031)
			(xy 345.74446 -69.476545) (xy 345.872516 -69.317903) (xy 346.006624 -69.164343) (xy 346.146584 -69.016097)
			(xy 346.292184 -68.873387) (xy 346.443206 -68.736427) (xy 346.599423 -68.605424) (xy 346.7606 -68.480574)
			(xy 346.926495 -68.362065) (xy 347.096859 -68.250075) (xy 347.271435 -68.144772) (xy 347.449962 -68.046315)
			(xy 347.632171 -67.954851) (xy 347.817787 -67.870518) (xy 348.006533 -67.793443) (xy 348.198125 -67.723741)
			(xy 348.392274 -67.661518) (xy 348.588688 -67.606867) (xy 348.787074 -67.559869) (xy 348.987132 -67.520596)
			(xy 349.188562 -67.489106) (xy 349.391061 -67.465448) (xy 349.594325 -67.449655) (xy 349.798048 -67.441753)
			(xy 350.001924 -67.441753) (xy 350.205647 -67.449655) (xy 350.408911 -67.465448) (xy 350.602405 -67.488054)
			(xy 367.079274 -67.488054) (xy 367.083345 -67.432432) (xy 367.095471 -67.377995) (xy 367.115394 -67.325904)
			(xy 367.14269 -67.277269) (xy 367.176776 -67.233126) (xy 367.216925 -67.194417) (xy 367.262283 -67.161966)
			(xy 367.311883 -67.136465) (xy 367.364667 -67.118458) (xy 367.41951 -67.108328) (xy 367.475244 -67.106291)
			(xy 367.530681 -67.112391) (xy 367.584638 -67.126497) (xy 367.590418 -67.128953) (xy 388.666675 -67.128953)
			(xy 388.666675 -67.074447) (xy 388.674433 -67.020496) (xy 388.68979 -66.968198) (xy 388.712434 -66.918618)
			(xy 388.741904 -66.872765) (xy 388.777599 -66.831574) (xy 388.818794 -66.795882) (xy 388.864649 -66.766417)
			(xy 388.914231 -66.743777) (xy 388.966531 -66.728425) (xy 389.020483 -66.720673) (xy 389.047736 -66.720212)
			(xy 389.075107 -66.720654) (xy 389.129287 -66.728477) (xy 389.181791 -66.743972) (xy 389.231537 -66.766819)
			(xy 389.277503 -66.796548) (xy 389.298434 -66.814192) (xy 389.298688 -66.814446) (xy 389.30577 -66.820039)
			(xy 389.32269 -66.826281) (xy 389.331708 -66.826638) (xy 389.398764 -66.826638) (xy 389.407778 -66.826255)
			(xy 389.424695 -66.820025) (xy 389.431784 -66.814446) (xy 389.432292 -66.813938) (xy 389.453215 -66.796342)
			(xy 389.499152 -66.766703) (xy 389.54885 -66.743926) (xy 389.601292 -66.72848) (xy 389.655401 -66.720679)
			(xy 389.682736 -66.720212) (xy 389.709987 -66.72066) (xy 389.763934 -66.728421) (xy 389.816227 -66.74378)
			(xy 389.865802 -66.766425) (xy 389.91165 -66.795894) (xy 389.952838 -66.831587) (xy 389.988528 -66.872778)
			(xy 390.017992 -66.91863) (xy 390.040632 -66.968207) (xy 390.055986 -67.020502) (xy 390.063742 -67.074449)
			(xy 390.063742 -67.128951) (xy 390.055986 -67.182898) (xy 390.040632 -67.235193) (xy 390.017992 -67.28477)
			(xy 389.988528 -67.330622) (xy 389.952838 -67.371813) (xy 389.91165 -67.407506) (xy 389.865802 -67.436975)
			(xy 389.816227 -67.45962) (xy 389.763934 -67.474979) (xy 389.709987 -67.48274) (xy 389.682736 -67.483228)
			(xy 389.655366 -67.482758) (xy 389.601186 -67.474944) (xy 389.548682 -67.459457) (xy 389.498935 -67.436615)
			(xy 389.452969 -67.40689) (xy 389.432038 -67.389248) (xy 389.431784 -67.388994) (xy 389.424707 -67.383394)
			(xy 389.407783 -67.377156) (xy 389.398764 -67.376802) (xy 389.331708 -67.376802) (xy 389.322691 -67.377162)
			(xy 389.305774 -67.383408) (xy 389.298688 -67.388994) (xy 389.29818 -67.389502) (xy 389.277273 -67.407118)
			(xy 389.231331 -67.436752) (xy 389.181628 -67.459524) (xy 389.129184 -67.474967) (xy 389.075072 -67.482763)
			(xy 389.047736 -67.483228) (xy 389.020483 -67.482727) (xy 388.966531 -67.474975) (xy 388.914231 -67.459623)
			(xy 388.864649 -67.436983) (xy 388.818794 -67.407518) (xy 388.777599 -67.371826) (xy 388.741904 -67.330635)
			(xy 388.712434 -67.284782) (xy 388.68979 -67.235202) (xy 388.674433 -67.182904) (xy 388.666675 -67.128953)
			(xy 367.590418 -67.128953) (xy 367.635967 -67.148309) (xy 367.683573 -67.177363) (xy 367.726441 -67.213038)
			(xy 367.763658 -67.254575) (xy 367.794431 -67.301088) (xy 367.818103 -67.351585) (xy 367.834171 -67.404992)
			(xy 367.842291 -67.460168) (xy 367.8428 -67.488054) (xy 367.842291 -67.51594) (xy 367.839106 -67.537584)
			(xy 368.371372 -67.537584) (xy 368.375443 -67.481962) (xy 368.387569 -67.427525) (xy 368.407492 -67.375434)
			(xy 368.434788 -67.326799) (xy 368.468874 -67.282656) (xy 368.509023 -67.243947) (xy 368.554381 -67.211496)
			(xy 368.603981 -67.185995) (xy 368.656765 -67.167988) (xy 368.711608 -67.157858) (xy 368.767342 -67.155821)
			(xy 368.822779 -67.161921) (xy 368.876736 -67.176027) (xy 368.928065 -67.197839) (xy 368.975671 -67.226893)
			(xy 369.018539 -67.262568) (xy 369.055756 -67.304105) (xy 369.086529 -67.350618) (xy 369.110201 -67.401115)
			(xy 369.126269 -67.454522) (xy 369.134389 -67.509698) (xy 369.134898 -67.537584) (xy 369.134389 -67.56547)
			(xy 369.130344 -67.592956) (xy 369.645436 -67.592956) (xy 369.649507 -67.537334) (xy 369.661633 -67.482897)
			(xy 369.681556 -67.430806) (xy 369.708852 -67.382171) (xy 369.742938 -67.338028) (xy 369.783087 -67.299319)
			(xy 369.828445 -67.266868) (xy 369.878045 -67.241367) (xy 369.930829 -67.22336) (xy 369.985672 -67.21323)
			(xy 370.041406 -67.211193) (xy 370.096843 -67.217293) (xy 370.1508 -67.231399) (xy 370.202129 -67.253211)
			(xy 370.249735 -67.282265) (xy 370.292603 -67.31794) (xy 370.32982 -67.359477) (xy 370.360593 -67.40599)
			(xy 370.384265 -67.456487) (xy 370.393762 -67.488054) (xy 393.079222 -67.488054) (xy 393.083293 -67.432432)
			(xy 393.095419 -67.377995) (xy 393.115342 -67.325904) (xy 393.142638 -67.277269) (xy 393.176724 -67.233126)
			(xy 393.216873 -67.194417) (xy 393.262231 -67.161966) (xy 393.311831 -67.136465) (xy 393.364615 -67.118458)
			(xy 393.419458 -67.108328) (xy 393.475192 -67.106291) (xy 393.530629 -67.112391) (xy 393.584586 -67.126497)
			(xy 393.590356 -67.128949) (xy 414.666698 -67.128949) (xy 414.666698 -67.074451) (xy 414.674454 -67.020508)
			(xy 414.689807 -66.968217) (xy 414.712446 -66.918643) (xy 414.741909 -66.872796) (xy 414.777597 -66.831609)
			(xy 414.818783 -66.795919) (xy 414.864629 -66.766454) (xy 414.914202 -66.743813) (xy 414.966492 -66.728457)
			(xy 415.020435 -66.720699) (xy 415.047684 -66.720212) (xy 415.075054 -66.720685) (xy 415.129233 -66.7285)
			(xy 415.181736 -66.743988) (xy 415.231483 -66.766828) (xy 415.27745 -66.796551) (xy 415.298382 -66.814192)
			(xy 415.298636 -66.814446) (xy 415.305733 -66.820017) (xy 415.322642 -66.826272) (xy 415.331656 -66.826638)
			(xy 415.398712 -66.826638) (xy 415.407728 -66.826279) (xy 415.424645 -66.820032) (xy 415.431732 -66.814446)
			(xy 415.43224 -66.813938) (xy 415.453182 -66.796366) (xy 415.499114 -66.766723) (xy 415.548808 -66.743942)
			(xy 415.601245 -66.72849) (xy 415.655351 -66.720683) (xy 415.682684 -66.720212) (xy 415.709939 -66.720634)
			(xy 415.763895 -66.728389) (xy 415.816197 -66.743745) (xy 415.865782 -66.766388) (xy 415.91164 -66.795857)
			(xy 415.952836 -66.831552) (xy 415.988534 -66.872748) (xy 416.018005 -66.918604) (xy 416.04065 -66.968188)
			(xy 416.056007 -67.02049) (xy 416.063765 -67.074445) (xy 416.063765 -67.128955) (xy 416.056007 -67.18291)
			(xy 416.04065 -67.235212) (xy 416.018005 -67.284796) (xy 415.988534 -67.330652) (xy 415.952836 -67.371848)
			(xy 415.91164 -67.407543) (xy 415.865782 -67.437012) (xy 415.816197 -67.459655) (xy 415.763895 -67.475011)
			(xy 415.709939 -67.482766) (xy 415.682684 -67.483228) (xy 415.655313 -67.482789) (xy 415.601132 -67.474967)
			(xy 415.548628 -67.459473) (xy 415.498881 -67.436625) (xy 415.452916 -67.406893) (xy 415.431986 -67.389248)
			(xy 415.431732 -67.388994) (xy 415.424641 -67.383414) (xy 415.407728 -67.377164) (xy 415.398712 -67.376802)
			(xy 415.331656 -67.376802) (xy 415.322642 -67.377186) (xy 415.305725 -67.383415) (xy 415.298636 -67.388994)
			(xy 415.298128 -67.389502) (xy 415.277203 -67.407095) (xy 415.231266 -67.436733) (xy 415.181568 -67.459509)
			(xy 415.129127 -67.474957) (xy 415.075018 -67.48276) (xy 415.047684 -67.483228) (xy 415.020435 -67.482701)
			(xy 414.966492 -67.474943) (xy 414.914202 -67.459587) (xy 414.864629 -67.436946) (xy 414.818783 -67.407481)
			(xy 414.777597 -67.371791) (xy 414.741909 -67.330604) (xy 414.712446 -67.284757) (xy 414.689807 -67.235183)
			(xy 414.674454 -67.182892) (xy 414.666698 -67.128949) (xy 393.590356 -67.128949) (xy 393.635915 -67.148309)
			(xy 393.683521 -67.177363) (xy 393.726389 -67.213038) (xy 393.763606 -67.254575) (xy 393.794379 -67.301088)
			(xy 393.818051 -67.351585) (xy 393.834119 -67.404992) (xy 393.842239 -67.460168) (xy 393.842748 -67.488054)
			(xy 393.842239 -67.51594) (xy 393.839054 -67.537584) (xy 394.37132 -67.537584) (xy 394.375391 -67.481962)
			(xy 394.387517 -67.427525) (xy 394.40744 -67.375434) (xy 394.434736 -67.326799) (xy 394.468822 -67.282656)
			(xy 394.508971 -67.243947) (xy 394.554329 -67.211496) (xy 394.603929 -67.185995) (xy 394.656713 -67.167988)
			(xy 394.711556 -67.157858) (xy 394.76729 -67.155821) (xy 394.822727 -67.161921) (xy 394.876684 -67.176027)
			(xy 394.928013 -67.197839) (xy 394.975619 -67.226893) (xy 395.018487 -67.262568) (xy 395.055704 -67.304105)
			(xy 395.086477 -67.350618) (xy 395.110149 -67.401115) (xy 395.126217 -67.454522) (xy 395.134337 -67.509698)
			(xy 395.134846 -67.537584) (xy 395.134337 -67.56547) (xy 395.130292 -67.592956) (xy 395.645384 -67.592956)
			(xy 395.649455 -67.537334) (xy 395.661581 -67.482897) (xy 395.681504 -67.430806) (xy 395.7088 -67.382171)
			(xy 395.742886 -67.338028) (xy 395.783035 -67.299319) (xy 395.828393 -67.266868) (xy 395.877993 -67.241367)
			(xy 395.930777 -67.22336) (xy 395.98562 -67.21323) (xy 396.041354 -67.211193) (xy 396.096791 -67.217293)
			(xy 396.150748 -67.231399) (xy 396.202077 -67.253211) (xy 396.249683 -67.282265) (xy 396.292551 -67.31794)
			(xy 396.329768 -67.359477) (xy 396.360541 -67.40599) (xy 396.384213 -67.456487) (xy 396.39371 -67.488054)
			(xy 419.07917 -67.488054) (xy 419.083241 -67.432432) (xy 419.095367 -67.377995) (xy 419.11529 -67.325904)
			(xy 419.142586 -67.277269) (xy 419.176672 -67.233126) (xy 419.216821 -67.194417) (xy 419.262179 -67.161966)
			(xy 419.311779 -67.136465) (xy 419.364563 -67.118458) (xy 419.419406 -67.108328) (xy 419.47514 -67.106291)
			(xy 419.530577 -67.112391) (xy 419.584534 -67.126497) (xy 419.590314 -67.128953) (xy 440.666575 -67.128953)
			(xy 440.666575 -67.074447) (xy 440.674333 -67.020496) (xy 440.68969 -66.968199) (xy 440.712333 -66.918619)
			(xy 440.741803 -66.872767) (xy 440.777498 -66.831575) (xy 440.818692 -66.795883) (xy 440.864547 -66.766418)
			(xy 440.914129 -66.743778) (xy 440.966428 -66.728426) (xy 441.020379 -66.720673) (xy 441.047632 -66.720212)
			(xy 441.075003 -66.720656) (xy 441.129183 -66.728479) (xy 441.181687 -66.743973) (xy 441.231433 -66.76682)
			(xy 441.277399 -66.796549) (xy 441.29833 -66.814192) (xy 441.298584 -66.814446) (xy 441.305667 -66.820038)
			(xy 441.322587 -66.82628) (xy 441.331604 -66.826638) (xy 441.39866 -66.826638) (xy 441.407674 -66.826254)
			(xy 441.424591 -66.820024) (xy 441.43168 -66.814446) (xy 441.432188 -66.813938) (xy 441.453112 -66.796344)
			(xy 441.499049 -66.766704) (xy 441.548747 -66.743928) (xy 441.601188 -66.72848) (xy 441.655298 -66.720679)
			(xy 441.682632 -66.720212) (xy 441.709883 -66.72066) (xy 441.76383 -66.728421) (xy 441.816124 -66.743779)
			(xy 441.8657 -66.766423) (xy 441.911549 -66.795892) (xy 441.952737 -66.831586) (xy 441.988427 -66.872777)
			(xy 442.017892 -66.918628) (xy 442.040532 -66.968206) (xy 442.055886 -67.020501) (xy 442.063642 -67.074449)
			(xy 442.063642 -67.128951) (xy 442.055886 -67.182899) (xy 442.040532 -67.235194) (xy 442.017892 -67.284772)
			(xy 441.988427 -67.330623) (xy 441.952737 -67.371814) (xy 441.911549 -67.407508) (xy 441.8657 -67.436977)
			(xy 441.816124 -67.459621) (xy 441.76383 -67.474979) (xy 441.709883 -67.48274) (xy 441.682632 -67.483228)
			(xy 441.655262 -67.482761) (xy 441.601082 -67.474946) (xy 441.548578 -67.459458) (xy 441.498831 -67.436616)
			(xy 441.452865 -67.40689) (xy 441.431934 -67.389248) (xy 441.43168 -67.388994) (xy 441.424604 -67.383392)
			(xy 441.407679 -67.377155) (xy 441.39866 -67.376802) (xy 441.331604 -67.376802) (xy 441.322587 -67.37716)
			(xy 441.30567 -67.383407) (xy 441.298584 -67.388994) (xy 441.298076 -67.389502) (xy 441.277133 -67.407073)
			(xy 441.231201 -67.436714) (xy 441.181507 -67.459495) (xy 441.129071 -67.474948) (xy 441.074965 -67.482756)
			(xy 441.047632 -67.483228) (xy 441.020379 -67.482727) (xy 440.966428 -67.474974) (xy 440.914129 -67.459622)
			(xy 440.864547 -67.436982) (xy 440.818692 -67.407516) (xy 440.777498 -67.371825) (xy 440.741803 -67.330633)
			(xy 440.712333 -67.284781) (xy 440.68969 -67.235201) (xy 440.674333 -67.182904) (xy 440.666575 -67.128953)
			(xy 419.590314 -67.128953) (xy 419.635863 -67.148309) (xy 419.683469 -67.177363) (xy 419.726337 -67.213038)
			(xy 419.763554 -67.254575) (xy 419.794327 -67.301088) (xy 419.817999 -67.351585) (xy 419.834067 -67.404992)
			(xy 419.842187 -67.460168) (xy 419.842696 -67.488054) (xy 419.842187 -67.51594) (xy 419.839002 -67.537584)
			(xy 420.371268 -67.537584) (xy 420.375339 -67.481962) (xy 420.387465 -67.427525) (xy 420.407388 -67.375434)
			(xy 420.434684 -67.326799) (xy 420.46877 -67.282656) (xy 420.508919 -67.243947) (xy 420.554277 -67.211496)
			(xy 420.603877 -67.185995) (xy 420.656661 -67.167988) (xy 420.711504 -67.157858) (xy 420.767238 -67.155821)
			(xy 420.822675 -67.161921) (xy 420.876632 -67.176027) (xy 420.927961 -67.197839) (xy 420.975567 -67.226893)
			(xy 421.018435 -67.262568) (xy 421.055652 -67.304105) (xy 421.086425 -67.350618) (xy 421.110097 -67.401115)
			(xy 421.126165 -67.454522) (xy 421.134285 -67.509698) (xy 421.134794 -67.537584) (xy 421.134285 -67.56547)
			(xy 421.13024 -67.592956) (xy 421.645332 -67.592956) (xy 421.649403 -67.537334) (xy 421.661529 -67.482897)
			(xy 421.681452 -67.430806) (xy 421.708748 -67.382171) (xy 421.742834 -67.338028) (xy 421.782983 -67.299319)
			(xy 421.828341 -67.266868) (xy 421.877941 -67.241367) (xy 421.930725 -67.22336) (xy 421.985568 -67.21323)
			(xy 422.041302 -67.211193) (xy 422.096739 -67.217293) (xy 422.150696 -67.231399) (xy 422.202025 -67.253211)
			(xy 422.249631 -67.282265) (xy 422.292499 -67.31794) (xy 422.329716 -67.359477) (xy 422.360489 -67.40599)
			(xy 422.384161 -67.456487) (xy 422.393658 -67.488054) (xy 445.079118 -67.488054) (xy 445.083189 -67.432432)
			(xy 445.095315 -67.377995) (xy 445.115238 -67.325904) (xy 445.142534 -67.277269) (xy 445.17662 -67.233126)
			(xy 445.216769 -67.194417) (xy 445.262127 -67.161966) (xy 445.311727 -67.136465) (xy 445.364511 -67.118458)
			(xy 445.419354 -67.108328) (xy 445.475088 -67.106291) (xy 445.530525 -67.112391) (xy 445.584482 -67.126497)
			(xy 445.635811 -67.148309) (xy 445.683417 -67.177363) (xy 445.726285 -67.213038) (xy 445.763502 -67.254575)
			(xy 445.794275 -67.301088) (xy 445.817947 -67.351585) (xy 445.834015 -67.404992) (xy 445.842135 -67.460168)
			(xy 445.842644 -67.488054) (xy 445.842135 -67.51594) (xy 445.83895 -67.537584) (xy 446.371216 -67.537584)
			(xy 446.375287 -67.481962) (xy 446.387413 -67.427525) (xy 446.407336 -67.375434) (xy 446.434632 -67.326799)
			(xy 446.468718 -67.282656) (xy 446.508867 -67.243947) (xy 446.554225 -67.211496) (xy 446.603825 -67.185995)
			(xy 446.656609 -67.167988) (xy 446.711452 -67.157858) (xy 446.767186 -67.155821) (xy 446.822623 -67.161921)
			(xy 446.87658 -67.176027) (xy 446.927909 -67.197839) (xy 446.975515 -67.226893) (xy 447.018383 -67.262568)
			(xy 447.0556 -67.304105) (xy 447.086373 -67.350618) (xy 447.110045 -67.401115) (xy 447.126113 -67.454522)
			(xy 447.134233 -67.509698) (xy 447.134742 -67.537584) (xy 447.134233 -67.56547) (xy 447.130188 -67.592956)
			(xy 447.64528 -67.592956) (xy 447.649351 -67.537334) (xy 447.661477 -67.482897) (xy 447.6814 -67.430806)
			(xy 447.708696 -67.382171) (xy 447.742782 -67.338028) (xy 447.782931 -67.299319) (xy 447.828289 -67.266868)
			(xy 447.877889 -67.241367) (xy 447.930673 -67.22336) (xy 447.985516 -67.21323) (xy 448.04125 -67.211193)
			(xy 448.096687 -67.217293) (xy 448.150644 -67.231399) (xy 448.201973 -67.253211) (xy 448.249579 -67.282265)
			(xy 448.292447 -67.31794) (xy 448.329664 -67.359477) (xy 448.360437 -67.40599) (xy 448.384109 -67.456487)
			(xy 448.400177 -67.509894) (xy 448.408297 -67.56507) (xy 448.408806 -67.592956) (xy 448.408297 -67.620842)
			(xy 448.400177 -67.676018) (xy 448.384109 -67.729425) (xy 448.360437 -67.779922) (xy 448.329664 -67.826435)
			(xy 448.292447 -67.867972) (xy 448.249579 -67.903647) (xy 448.201973 -67.932701) (xy 448.150644 -67.954513)
			(xy 448.096687 -67.968619) (xy 448.04125 -67.974719) (xy 447.985516 -67.972682) (xy 447.930673 -67.962552)
			(xy 447.877889 -67.944545) (xy 447.828289 -67.919044) (xy 447.782931 -67.886593) (xy 447.742782 -67.847884)
			(xy 447.708696 -67.803741) (xy 447.6814 -67.755106) (xy 447.661477 -67.703015) (xy 447.649351 -67.648578)
			(xy 447.64528 -67.592956) (xy 447.130188 -67.592956) (xy 447.126113 -67.620646) (xy 447.110045 -67.674053)
			(xy 447.086373 -67.72455) (xy 447.0556 -67.771063) (xy 447.018383 -67.8126) (xy 446.975515 -67.848275)
			(xy 446.927909 -67.877329) (xy 446.87658 -67.899141) (xy 446.822623 -67.913247) (xy 446.767186 -67.919347)
			(xy 446.711452 -67.91731) (xy 446.656609 -67.90718) (xy 446.603825 -67.889173) (xy 446.554225 -67.863672)
			(xy 446.508867 -67.831221) (xy 446.468718 -67.792512) (xy 446.434632 -67.748369) (xy 446.407336 -67.699734)
			(xy 446.387413 -67.647643) (xy 446.375287 -67.593206) (xy 446.371216 -67.537584) (xy 445.83895 -67.537584)
			(xy 445.834015 -67.571116) (xy 445.817947 -67.624523) (xy 445.794275 -67.67502) (xy 445.763502 -67.721533)
			(xy 445.726285 -67.76307) (xy 445.683417 -67.798745) (xy 445.635811 -67.827799) (xy 445.584482 -67.849611)
			(xy 445.530525 -67.863717) (xy 445.475088 -67.869817) (xy 445.419354 -67.86778) (xy 445.364511 -67.85765)
			(xy 445.311727 -67.839643) (xy 445.262127 -67.814142) (xy 445.216769 -67.781691) (xy 445.17662 -67.742982)
			(xy 445.142534 -67.698839) (xy 445.115238 -67.650204) (xy 445.095315 -67.598113) (xy 445.083189 -67.543676)
			(xy 445.079118 -67.488054) (xy 422.393658 -67.488054) (xy 422.400229 -67.509894) (xy 422.408349 -67.56507)
			(xy 422.408858 -67.592956) (xy 422.408349 -67.620842) (xy 422.400229 -67.676018) (xy 422.384161 -67.729425)
			(xy 422.360489 -67.779922) (xy 422.329716 -67.826435) (xy 422.292499 -67.867972) (xy 422.249631 -67.903647)
			(xy 422.202025 -67.932701) (xy 422.150696 -67.954513) (xy 422.096739 -67.968619) (xy 422.041302 -67.974719)
			(xy 421.985568 -67.972682) (xy 421.930725 -67.962552) (xy 421.877941 -67.944545) (xy 421.828341 -67.919044)
			(xy 421.782983 -67.886593) (xy 421.742834 -67.847884) (xy 421.708748 -67.803741) (xy 421.681452 -67.755106)
			(xy 421.661529 -67.703015) (xy 421.649403 -67.648578) (xy 421.645332 -67.592956) (xy 421.13024 -67.592956)
			(xy 421.126165 -67.620646) (xy 421.110097 -67.674053) (xy 421.086425 -67.72455) (xy 421.055652 -67.771063)
			(xy 421.018435 -67.8126) (xy 420.975567 -67.848275) (xy 420.927961 -67.877329) (xy 420.876632 -67.899141)
			(xy 420.822675 -67.913247) (xy 420.767238 -67.919347) (xy 420.711504 -67.91731) (xy 420.656661 -67.90718)
			(xy 420.603877 -67.889173) (xy 420.554277 -67.863672) (xy 420.508919 -67.831221) (xy 420.46877 -67.792512)
			(xy 420.434684 -67.748369) (xy 420.407388 -67.699734) (xy 420.387465 -67.647643) (xy 420.375339 -67.593206)
			(xy 420.371268 -67.537584) (xy 419.839002 -67.537584) (xy 419.834067 -67.571116) (xy 419.817999 -67.624523)
			(xy 419.794327 -67.67502) (xy 419.763554 -67.721533) (xy 419.726337 -67.76307) (xy 419.683469 -67.798745)
			(xy 419.635863 -67.827799) (xy 419.584534 -67.849611) (xy 419.530577 -67.863717) (xy 419.47514 -67.869817)
			(xy 419.419406 -67.86778) (xy 419.364563 -67.85765) (xy 419.311779 -67.839643) (xy 419.262179 -67.814142)
			(xy 419.216821 -67.781691) (xy 419.176672 -67.742982) (xy 419.142586 -67.698839) (xy 419.11529 -67.650204)
			(xy 419.095367 -67.598113) (xy 419.083241 -67.543676) (xy 419.07917 -67.488054) (xy 396.39371 -67.488054)
			(xy 396.400281 -67.509894) (xy 396.408401 -67.56507) (xy 396.40891 -67.592956) (xy 396.408401 -67.620842)
			(xy 396.400281 -67.676018) (xy 396.384213 -67.729425) (xy 396.360541 -67.779922) (xy 396.329768 -67.826435)
			(xy 396.292551 -67.867972) (xy 396.249683 -67.903647) (xy 396.202077 -67.932701) (xy 396.150748 -67.954513)
			(xy 396.096791 -67.968619) (xy 396.041354 -67.974719) (xy 395.98562 -67.972682) (xy 395.930777 -67.962552)
			(xy 395.877993 -67.944545) (xy 395.828393 -67.919044) (xy 395.783035 -67.886593) (xy 395.742886 -67.847884)
			(xy 395.7088 -67.803741) (xy 395.681504 -67.755106) (xy 395.661581 -67.703015) (xy 395.649455 -67.648578)
			(xy 395.645384 -67.592956) (xy 395.130292 -67.592956) (xy 395.126217 -67.620646) (xy 395.110149 -67.674053)
			(xy 395.086477 -67.72455) (xy 395.055704 -67.771063) (xy 395.018487 -67.8126) (xy 394.975619 -67.848275)
			(xy 394.928013 -67.877329) (xy 394.876684 -67.899141) (xy 394.822727 -67.913247) (xy 394.76729 -67.919347)
			(xy 394.711556 -67.91731) (xy 394.656713 -67.90718) (xy 394.603929 -67.889173) (xy 394.554329 -67.863672)
			(xy 394.508971 -67.831221) (xy 394.468822 -67.792512) (xy 394.434736 -67.748369) (xy 394.40744 -67.699734)
			(xy 394.387517 -67.647643) (xy 394.375391 -67.593206) (xy 394.37132 -67.537584) (xy 393.839054 -67.537584)
			(xy 393.834119 -67.571116) (xy 393.818051 -67.624523) (xy 393.794379 -67.67502) (xy 393.763606 -67.721533)
			(xy 393.726389 -67.76307) (xy 393.683521 -67.798745) (xy 393.635915 -67.827799) (xy 393.584586 -67.849611)
			(xy 393.530629 -67.863717) (xy 393.475192 -67.869817) (xy 393.419458 -67.86778) (xy 393.364615 -67.85765)
			(xy 393.311831 -67.839643) (xy 393.262231 -67.814142) (xy 393.216873 -67.781691) (xy 393.176724 -67.742982)
			(xy 393.142638 -67.698839) (xy 393.115342 -67.650204) (xy 393.095419 -67.598113) (xy 393.083293 -67.543676)
			(xy 393.079222 -67.488054) (xy 370.393762 -67.488054) (xy 370.400333 -67.509894) (xy 370.408453 -67.56507)
			(xy 370.408962 -67.592956) (xy 370.408453 -67.620842) (xy 370.400333 -67.676018) (xy 370.384265 -67.729425)
			(xy 370.360593 -67.779922) (xy 370.32982 -67.826435) (xy 370.292603 -67.867972) (xy 370.249735 -67.903647)
			(xy 370.202129 -67.932701) (xy 370.1508 -67.954513) (xy 370.096843 -67.968619) (xy 370.041406 -67.974719)
			(xy 369.985672 -67.972682) (xy 369.930829 -67.962552) (xy 369.878045 -67.944545) (xy 369.828445 -67.919044)
			(xy 369.783087 -67.886593) (xy 369.742938 -67.847884) (xy 369.708852 -67.803741) (xy 369.681556 -67.755106)
			(xy 369.661633 -67.703015) (xy 369.649507 -67.648578) (xy 369.645436 -67.592956) (xy 369.130344 -67.592956)
			(xy 369.126269 -67.620646) (xy 369.110201 -67.674053) (xy 369.086529 -67.72455) (xy 369.055756 -67.771063)
			(xy 369.018539 -67.8126) (xy 368.975671 -67.848275) (xy 368.928065 -67.877329) (xy 368.876736 -67.899141)
			(xy 368.822779 -67.913247) (xy 368.767342 -67.919347) (xy 368.711608 -67.91731) (xy 368.656765 -67.90718)
			(xy 368.603981 -67.889173) (xy 368.554381 -67.863672) (xy 368.509023 -67.831221) (xy 368.468874 -67.792512)
			(xy 368.434788 -67.748369) (xy 368.407492 -67.699734) (xy 368.387569 -67.647643) (xy 368.375443 -67.593206)
			(xy 368.371372 -67.537584) (xy 367.839106 -67.537584) (xy 367.834171 -67.571116) (xy 367.818103 -67.624523)
			(xy 367.794431 -67.67502) (xy 367.763658 -67.721533) (xy 367.726441 -67.76307) (xy 367.683573 -67.798745)
			(xy 367.635967 -67.827799) (xy 367.584638 -67.849611) (xy 367.530681 -67.863717) (xy 367.475244 -67.869817)
			(xy 367.41951 -67.86778) (xy 367.364667 -67.85765) (xy 367.311883 -67.839643) (xy 367.262283 -67.814142)
			(xy 367.216925 -67.781691) (xy 367.176776 -67.742982) (xy 367.14269 -67.698839) (xy 367.115394 -67.650204)
			(xy 367.095471 -67.598113) (xy 367.083345 -67.543676) (xy 367.079274 -67.488054) (xy 350.602405 -67.488054)
			(xy 350.61141 -67.489106) (xy 350.81284 -67.520596) (xy 351.012898 -67.559869) (xy 351.211284 -67.606867)
			(xy 351.407698 -67.661518) (xy 351.601847 -67.723741) (xy 351.793439 -67.793443) (xy 351.982185 -67.870518)
			(xy 352.167801 -67.954851) (xy 352.35001 -68.046315) (xy 352.528537 -68.144772) (xy 352.703113 -68.250075)
			(xy 352.873477 -68.362065) (xy 353.039372 -68.480574) (xy 353.176253 -68.586604) (xy 364.925356 -68.586604)
			(xy 364.925846 -68.559271) (xy 364.933648 -68.505164) (xy 364.949092 -68.452725) (xy 364.971863 -68.403027)
			(xy 365.001493 -68.357088) (xy 365.019082 -68.33616) (xy 365.019336 -68.335906) (xy 365.01959 -68.335652)
			(xy 365.02516 -68.328554) (xy 365.031417 -68.311646) (xy 365.031782 -68.302632) (xy 365.031782 -68.235576)
			(xy 365.03144 -68.226557) (xy 365.025183 -68.20964) (xy 365.01959 -68.202556) (xy 365.019336 -68.202302)
			(xy 365.019082 -68.202048) (xy 365.001496 -68.181117) (xy 364.971857 -68.135181) (xy 364.94908 -68.085485)
			(xy 364.93363 -68.033046) (xy 364.925826 -67.978938) (xy 364.925356 -67.951604) (xy 364.925881 -67.924354)
			(xy 364.933636 -67.87041) (xy 364.948989 -67.818118) (xy 364.971627 -67.768543) (xy 365.00109 -67.722695)
			(xy 365.036777 -67.681505) (xy 365.077963 -67.645814) (xy 365.123808 -67.616346) (xy 365.173381 -67.593703)
			(xy 365.225671 -67.578345) (xy 365.279615 -67.570584) (xy 365.306864 -67.570096) (xy 365.307118 -67.570096)
			(xy 365.333413 -67.570544) (xy 365.385502 -67.577792) (xy 365.436104 -67.59212) (xy 365.48426 -67.613257)
			(xy 365.529059 -67.640804) (xy 365.569654 -67.674239) (xy 365.587788 -67.693286) (xy 365.595367 -67.700719)
			(xy 365.614779 -67.709249) (xy 365.62538 -67.709796) (xy 365.699548 -67.709796) (xy 365.710182 -67.709406)
			(xy 365.729647 -67.700843) (xy 365.73714 -67.693286) (xy 365.755237 -67.674199) (xy 365.795826 -67.640746)
			(xy 365.840629 -67.613191) (xy 365.888795 -67.592057) (xy 365.93941 -67.577746) (xy 365.991511 -67.57053)
			(xy 366.01781 -67.570096) (xy 366.018064 -67.570096) (xy 366.045433 -67.570584) (xy 366.099612 -67.578397)
			(xy 366.152114 -67.593881) (xy 366.201862 -67.616718) (xy 366.247829 -67.646437) (xy 366.268762 -67.664076)
			(xy 366.269016 -67.66433) (xy 366.276091 -67.669933) (xy 366.293017 -67.676169) (xy 366.302036 -67.676522)
			(xy 366.369092 -67.676522) (xy 366.378108 -67.676156) (xy 366.395025 -67.669914) (xy 366.402112 -67.66433)
			(xy 366.40262 -67.663822) (xy 366.42353 -67.64621) (xy 366.469471 -67.616574) (xy 366.519173 -67.593801)
			(xy 366.571617 -67.578358) (xy 366.625729 -67.570561) (xy 366.653064 -67.570096) (xy 366.680316 -67.570589)
			(xy 366.734266 -67.578341) (xy 366.786564 -67.593693) (xy 366.836144 -67.616331) (xy 366.881998 -67.645796)
			(xy 366.923191 -67.681487) (xy 366.958885 -67.722677) (xy 366.988353 -67.768528) (xy 367.010996 -67.818106)
			(xy 367.026352 -67.870402) (xy 367.034109 -67.924352) (xy 367.034572 -67.951604) (xy 367.03408 -67.978937)
			(xy 367.026278 -68.033043) (xy 367.010834 -68.085482) (xy 366.988064 -68.13518) (xy 366.958434 -68.18112)
			(xy 366.940846 -68.202048) (xy 366.940592 -68.202302) (xy 366.940338 -68.202556) (xy 366.934756 -68.209646)
			(xy 366.928508 -68.22656) (xy 366.928146 -68.235576) (xy 366.928146 -68.302632) (xy 366.928478 -68.311652)
			(xy 366.934742 -68.328569) (xy 366.940338 -68.335652) (xy 366.940592 -68.335906) (xy 366.940846 -68.33616)
			(xy 366.95844 -68.357084) (xy 366.988077 -68.403022) (xy 367.010852 -68.452721) (xy 367.0263 -68.505161)
			(xy 367.034103 -68.55927) (xy 367.034572 -68.586604) (xy 390.925304 -68.586604) (xy 390.925806 -68.559271)
			(xy 390.933607 -68.505166) (xy 390.949049 -68.452727) (xy 390.971817 -68.403029) (xy 391.001444 -68.357089)
			(xy 391.01903 -68.33616) (xy 391.019284 -68.335906) (xy 391.019538 -68.335652) (xy 391.025113 -68.328558)
			(xy 391.031366 -68.311647) (xy 391.03173 -68.302632) (xy 391.03173 -68.235576) (xy 391.031378 -68.226559)
			(xy 391.025126 -68.209642) (xy 391.019538 -68.202556) (xy 391.019284 -68.202302) (xy 391.01903 -68.202048)
			(xy 391.001451 -68.181111) (xy 390.97181 -68.135178) (xy 390.94903 -68.085483) (xy 390.933579 -68.033045)
			(xy 390.925774 -67.978938) (xy 390.925304 -67.951604) (xy 390.925759 -67.924351) (xy 390.933516 -67.870399)
			(xy 390.948872 -67.8181) (xy 390.971515 -67.768519) (xy 391.000984 -67.722666) (xy 391.036678 -67.681472)
			(xy 391.077872 -67.645779) (xy 391.123726 -67.616311) (xy 391.173308 -67.593669) (xy 391.225607 -67.578314)
			(xy 391.279559 -67.570559) (xy 391.306812 -67.570096) (xy 391.307066 -67.570096) (xy 391.33336 -67.570579)
			(xy 391.385448 -67.577819) (xy 391.436048 -67.592141) (xy 391.484205 -67.613272) (xy 391.529005 -67.640812)
			(xy 391.569601 -67.674241) (xy 391.587736 -67.693286) (xy 391.595297 -67.70074) (xy 391.614723 -67.709258)
			(xy 391.625328 -67.709796) (xy 391.699496 -67.709796) (xy 391.710127 -67.709377) (xy 391.729591 -67.700835)
			(xy 391.737088 -67.693286) (xy 391.75521 -67.674224) (xy 391.795794 -67.640769) (xy 391.840592 -67.613211)
			(xy 391.888753 -67.592073) (xy 391.939363 -67.577756) (xy 391.99146 -67.570534) (xy 392.017758 -67.570096)
			(xy 392.018012 -67.570096) (xy 392.045382 -67.570556) (xy 392.099562 -67.578375) (xy 392.152065 -67.593866)
			(xy 392.201812 -67.616709) (xy 392.247778 -67.646434) (xy 392.26871 -67.664076) (xy 392.268964 -67.66433)
			(xy 392.276054 -67.669911) (xy 392.292968 -67.67616) (xy 392.301984 -67.676522) (xy 392.36904 -67.676522)
			(xy 392.378058 -67.676179) (xy 392.394975 -67.669921) (xy 392.40206 -67.66433) (xy 392.402568 -67.663822)
			(xy 392.423498 -67.646234) (xy 392.469433 -67.616595) (xy 392.51913 -67.593817) (xy 392.57157 -67.578368)
			(xy 392.625678 -67.570565) (xy 392.653012 -67.570096) (xy 392.680264 -67.570567) (xy 392.734212 -67.578325)
			(xy 392.786507 -67.593682) (xy 392.836085 -67.616325) (xy 392.881936 -67.645792) (xy 392.923126 -67.681486)
			(xy 392.958817 -67.722677) (xy 392.988283 -67.768529) (xy 393.010924 -67.818108) (xy 393.026279 -67.870403)
			(xy 393.034035 -67.924352) (xy 393.03452 -67.951604) (xy 393.034016 -67.978936) (xy 393.026215 -68.033042)
			(xy 393.010773 -68.08548) (xy 392.988006 -68.135178) (xy 392.95838 -68.181119) (xy 392.940794 -68.202048)
			(xy 392.94054 -68.202302) (xy 392.940286 -68.202556) (xy 392.93471 -68.20965) (xy 392.928457 -68.226561)
			(xy 392.928094 -68.235576) (xy 392.928094 -68.302632) (xy 392.928437 -68.31165) (xy 392.934695 -68.328567)
			(xy 392.940286 -68.335652) (xy 392.94054 -68.335906) (xy 392.940794 -68.33616) (xy 392.95838 -68.357091)
			(xy 392.98802 -68.403026) (xy 393.010797 -68.452723) (xy 393.026247 -68.505162) (xy 393.034051 -68.55927)
			(xy 393.03452 -68.586604) (xy 416.925252 -68.586604) (xy 416.925743 -68.559271) (xy 416.933544 -68.505164)
			(xy 416.948989 -68.452725) (xy 416.971759 -68.403027) (xy 417.00139 -68.357088) (xy 417.018978 -68.33616)
			(xy 417.019232 -68.335906) (xy 417.019486 -68.335652) (xy 417.025055 -68.328554) (xy 417.031313 -68.311646)
			(xy 417.031678 -68.302632) (xy 417.031678 -68.235576) (xy 417.031337 -68.226557) (xy 417.025079 -68.20964)
			(xy 417.019486 -68.202556) (xy 417.019232 -68.202302) (xy 417.018978 -68.202048) (xy 417.001391 -68.181118)
			(xy 416.971753 -68.135182) (xy 416.948976 -68.085485) (xy 416.933526 -68.033046) (xy 416.925722 -67.978938)
			(xy 416.925252 -67.951604) (xy 416.925781 -67.924355) (xy 416.933536 -67.870411) (xy 416.948889 -67.818119)
			(xy 416.971527 -67.768545) (xy 417.000989 -67.722696) (xy 417.036676 -67.681507) (xy 417.077861 -67.645815)
			(xy 417.123706 -67.616348) (xy 417.173278 -67.593704) (xy 417.225568 -67.578346) (xy 417.279511 -67.570585)
			(xy 417.30676 -67.570096) (xy 417.307014 -67.570096) (xy 417.333309 -67.570547) (xy 417.385398 -67.577794)
			(xy 417.435999 -67.592121) (xy 417.484156 -67.613258) (xy 417.528955 -67.640805) (xy 417.56955 -67.674239)
			(xy 417.587684 -67.693286) (xy 417.595264 -67.700717) (xy 417.614676 -67.709248) (xy 417.625276 -67.709796)
			(xy 417.699444 -67.709796) (xy 417.710078 -67.709404) (xy 417.729542 -67.700843) (xy 417.737036 -67.693286)
			(xy 417.755135 -67.674201) (xy 417.795724 -67.640748) (xy 417.840527 -67.613193) (xy 417.888692 -67.592059)
			(xy 417.939306 -67.577747) (xy 417.991407 -67.57053) (xy 418.017706 -67.570096) (xy 418.01796 -67.570096)
			(xy 418.045329 -67.570586) (xy 418.099507 -67.578399) (xy 418.15201 -67.593882) (xy 418.201757 -67.616718)
			(xy 418.247725 -67.646437) (xy 418.268658 -67.664076) (xy 418.268912 -67.66433) (xy 418.275988 -67.669931)
			(xy 418.292913 -67.676168) (xy 418.301932 -67.676522) (xy 418.368988 -67.676522) (xy 418.378004 -67.676154)
			(xy 418.39492 -67.669914) (xy 418.402008 -67.66433) (xy 418.402516 -67.663822) (xy 418.423428 -67.646212)
			(xy 418.469368 -67.616576) (xy 418.51907 -67.593802) (xy 418.571513 -67.578359) (xy 418.625625 -67.570561)
			(xy 418.65296 -67.570096) (xy 418.680212 -67.570593) (xy 418.734162 -67.578344) (xy 418.786459 -67.593695)
			(xy 418.83604 -67.616333) (xy 418.881893 -67.645798) (xy 418.923086 -67.681488) (xy 418.958781 -67.722678)
			(xy 418.988249 -67.768529) (xy 419.010892 -67.818107) (xy 419.026248 -67.870403) (xy 419.034005 -67.924352)
			(xy 419.034468 -67.951604) (xy 419.033977 -67.978937) (xy 419.026175 -68.033043) (xy 419.01073 -68.085482)
			(xy 418.98796 -68.135181) (xy 418.95833 -68.18112) (xy 418.940742 -68.202048) (xy 418.940488 -68.202302)
			(xy 418.940234 -68.202556) (xy 418.934652 -68.209645) (xy 418.928404 -68.22656) (xy 418.928042 -68.235576)
			(xy 418.928042 -68.302632) (xy 418.928375 -68.311652) (xy 418.934638 -68.328569) (xy 418.940234 -68.335652)
			(xy 418.940488 -68.335906) (xy 418.940742 -68.33616) (xy 418.958336 -68.357085) (xy 418.987972 -68.403023)
			(xy 419.010748 -68.452721) (xy 419.026196 -68.505161) (xy 419.033999 -68.55927) (xy 419.034468 -68.586604)
			(xy 442.9252 -68.586604) (xy 442.925703 -68.559271) (xy 442.933504 -68.505166) (xy 442.948946 -68.452727)
			(xy 442.971713 -68.403029) (xy 443.00134 -68.357089) (xy 443.018926 -68.33616) (xy 443.01918 -68.335906)
			(xy 443.019434 -68.335652) (xy 443.025009 -68.328557) (xy 443.031261 -68.311647) (xy 443.031626 -68.302632)
			(xy 443.031626 -68.235576) (xy 443.031275 -68.226559) (xy 443.025023 -68.209642) (xy 443.019434 -68.202556)
			(xy 443.01918 -68.202302) (xy 443.018926 -68.202048) (xy 443.001347 -68.181112) (xy 442.971705 -68.135178)
			(xy 442.948926 -68.085483) (xy 442.933475 -68.033045) (xy 442.92567 -67.978938) (xy 442.9252 -67.951604)
			(xy 442.925659 -67.924351) (xy 442.933416 -67.870399) (xy 442.948772 -67.818101) (xy 442.971414 -67.76852)
			(xy 443.000883 -67.722667) (xy 443.036577 -67.681474) (xy 443.07777 -67.64578) (xy 443.123624 -67.616312)
			(xy 443.173205 -67.59367) (xy 443.225503 -67.578315) (xy 443.279455 -67.570559) (xy 443.306708 -67.570096)
			(xy 443.306962 -67.570096) (xy 443.333256 -67.570581) (xy 443.385343 -67.577821) (xy 443.435944 -67.592142)
			(xy 443.4841 -67.613273) (xy 443.528901 -67.640813) (xy 443.569497 -67.674242) (xy 443.587632 -67.693286)
			(xy 443.595195 -67.700738) (xy 443.614619 -67.709257) (xy 443.625224 -67.709796) (xy 443.699392 -67.709796)
			(xy 443.710023 -67.709375) (xy 443.729487 -67.700834) (xy 443.736984 -67.693286) (xy 443.755108 -67.674226)
			(xy 443.795692 -67.640771) (xy 443.840489 -67.613212) (xy 443.88865 -67.592074) (xy 443.939259 -67.577757)
			(xy 443.991356 -67.570534) (xy 444.017654 -67.570096) (xy 444.017908 -67.570096) (xy 444.045278 -67.570558)
			(xy 444.099458 -67.578377) (xy 444.151961 -67.593867) (xy 444.201707 -67.61671) (xy 444.247674 -67.646435)
			(xy 444.268606 -67.664076) (xy 444.26886 -67.66433) (xy 444.275951 -67.669909) (xy 444.292865 -67.676159)
			(xy 444.30188 -67.676522) (xy 444.368936 -67.676522) (xy 444.377954 -67.676178) (xy 444.394871 -67.669921)
			(xy 444.401956 -67.66433) (xy 444.402464 -67.663822) (xy 444.423395 -67.646236) (xy 444.46933 -67.616596)
			(xy 444.519027 -67.593818) (xy 444.571466 -67.578369) (xy 444.625574 -67.570565) (xy 444.652908 -67.570096)
			(xy 444.68016 -67.57057) (xy 444.734108 -67.578328) (xy 444.786403 -67.593684) (xy 444.835981 -67.616327)
			(xy 444.881831 -67.645794) (xy 444.923022 -67.681487) (xy 444.958713 -67.722678) (xy 444.988179 -67.76853)
			(xy 445.01082 -67.818108) (xy 445.026174 -67.870404) (xy 445.03393 -67.924352) (xy 445.034416 -67.951604)
			(xy 445.033913 -67.978936) (xy 445.026112 -68.033042) (xy 445.01067 -68.08548) (xy 444.987902 -68.135179)
			(xy 444.958276 -68.181119) (xy 444.94069 -68.202048) (xy 444.940436 -68.202302) (xy 444.940182 -68.202556)
			(xy 444.934606 -68.20965) (xy 444.928353 -68.226561) (xy 444.92799 -68.235576) (xy 444.92799 -68.302632)
			(xy 444.928334 -68.31165) (xy 444.934591 -68.328567) (xy 444.940182 -68.335652) (xy 444.940436 -68.335906)
			(xy 444.94069 -68.33616) (xy 444.958276 -68.357091) (xy 444.987915 -68.403027) (xy 445.010693 -68.452723)
			(xy 445.026143 -68.505162) (xy 445.033947 -68.55927) (xy 445.034416 -68.586604) (xy 445.033926 -68.613855)
			(xy 445.026169 -68.667802) (xy 445.010814 -68.720096) (xy 444.988173 -68.769673) (xy 444.958707 -68.815523)
			(xy 444.923016 -68.856713) (xy 444.881826 -68.892404) (xy 444.835977 -68.921871) (xy 444.7864 -68.944512)
			(xy 444.734106 -68.959868) (xy 444.680159 -68.967626) (xy 444.652908 -68.968112) (xy 444.625538 -68.967638)
			(xy 444.571359 -68.959822) (xy 444.518857 -68.944334) (xy 444.46911 -68.921494) (xy 444.423142 -68.891772)
			(xy 444.40221 -68.874132) (xy 444.401956 -68.873878) (xy 444.394859 -68.868306) (xy 444.37795 -68.862051)
			(xy 444.368936 -68.861686) (xy 444.30188 -68.861686) (xy 444.292863 -68.862037) (xy 444.275946 -68.868289)
			(xy 444.26886 -68.873878) (xy 444.268352 -68.874386) (xy 444.247416 -68.891965) (xy 444.201482 -68.921606)
			(xy 444.151787 -68.944385) (xy 444.099349 -68.959836) (xy 444.045242 -68.967642) (xy 444.017908 -68.968112)
			(xy 444.017654 -68.968112) (xy 443.991358 -68.96768) (xy 443.939269 -68.960429) (xy 443.888667 -68.946097)
			(xy 443.840511 -68.924957) (xy 443.795712 -68.897407) (xy 443.755118 -68.86397) (xy 443.736984 -68.844922)
			(xy 443.729414 -68.837478) (xy 443.709995 -68.828954) (xy 443.699392 -68.828412) (xy 443.625224 -68.828412)
			(xy 443.614594 -68.82884) (xy 443.595129 -68.837376) (xy 443.587632 -68.844922) (xy 443.569501 -68.863975)
			(xy 443.528919 -68.897431) (xy 443.484123 -68.92499) (xy 443.435964 -68.94613) (xy 443.385355 -68.960448)
			(xy 443.333259 -68.967673) (xy 443.306962 -68.968112) (xy 443.306708 -68.968112) (xy 443.279456 -68.967637)
			(xy 443.225505 -68.959881) (xy 443.173208 -68.944527) (xy 443.123628 -68.921885) (xy 443.077775 -68.892419)
			(xy 443.036582 -68.856726) (xy 443.000889 -68.815535) (xy 442.97142 -68.769683) (xy 442.948778 -68.720103)
			(xy 442.933421 -68.667807) (xy 442.925664 -68.613856) (xy 442.9252 -68.586604) (xy 419.034468 -68.586604)
			(xy 419.034048 -68.613859) (xy 419.02629 -68.667813) (xy 419.010931 -68.720114) (xy 418.988285 -68.769697)
			(xy 418.958813 -68.815552) (xy 418.923115 -68.856746) (xy 418.881917 -68.89244) (xy 418.836059 -68.921906)
			(xy 418.786473 -68.944547) (xy 418.73417 -68.959899) (xy 418.680215 -68.967651) (xy 418.65296 -68.968112)
			(xy 418.625591 -68.967608) (xy 418.571414 -68.959799) (xy 418.518911 -68.944318) (xy 418.469164 -68.921485)
			(xy 418.423195 -68.891769) (xy 418.402262 -68.874132) (xy 418.402008 -68.873878) (xy 418.394925 -68.868286)
			(xy 418.378005 -68.862043) (xy 418.368988 -68.861686) (xy 418.301932 -68.861686) (xy 418.292917 -68.862061)
			(xy 418.276 -68.868296) (xy 418.268912 -68.873878) (xy 418.268404 -68.874386) (xy 418.247486 -68.891988)
			(xy 418.201547 -68.921625) (xy 418.151847 -68.9444) (xy 418.099405 -68.959846) (xy 418.045295 -68.967645)
			(xy 418.01796 -68.968112) (xy 418.017706 -68.968112) (xy 417.991411 -68.967645) (xy 417.939323 -68.960401)
			(xy 417.888722 -68.946076) (xy 417.840566 -68.924942) (xy 417.795766 -68.897399) (xy 417.755171 -68.863968)
			(xy 417.737036 -68.844922) (xy 417.729447 -68.837501) (xy 417.710042 -68.828964) (xy 417.699444 -68.828412)
			(xy 417.625276 -68.828412) (xy 417.614643 -68.828813) (xy 417.595179 -68.837368) (xy 417.587684 -68.844922)
			(xy 417.569577 -68.863999) (xy 417.52899 -68.897452) (xy 417.484189 -68.925009) (xy 417.436025 -68.946144)
			(xy 417.385412 -68.960457) (xy 417.333313 -68.967676) (xy 417.307014 -68.968112) (xy 417.30676 -68.968112)
			(xy 417.279508 -68.967659) (xy 417.225559 -68.959898) (xy 417.173264 -68.944538) (xy 417.123687 -68.921892)
			(xy 417.077837 -68.892422) (xy 417.036647 -68.856727) (xy 417.000956 -68.815534) (xy 416.971491 -68.769681)
			(xy 416.94885 -68.720102) (xy 416.933495 -68.667806) (xy 416.925738 -68.613856) (xy 416.925252 -68.586604)
			(xy 393.03452 -68.586604) (xy 393.034026 -68.613855) (xy 393.026269 -68.667802) (xy 393.010914 -68.720095)
			(xy 392.988273 -68.769672) (xy 392.958808 -68.815522) (xy 392.923117 -68.856712) (xy 392.881928 -68.892403)
			(xy 392.836079 -68.92187) (xy 392.786503 -68.944511) (xy 392.734209 -68.959868) (xy 392.680263 -68.967625)
			(xy 392.653012 -68.968112) (xy 392.625642 -68.967636) (xy 392.571464 -68.95982) (xy 392.518961 -68.944333)
			(xy 392.469214 -68.921494) (xy 392.423246 -68.891772) (xy 392.402314 -68.874132) (xy 392.40206 -68.873878)
			(xy 392.394962 -68.868308) (xy 392.378054 -68.862052) (xy 392.36904 -68.861686) (xy 392.301984 -68.861686)
			(xy 392.292967 -68.862039) (xy 392.27605 -68.86829) (xy 392.268964 -68.873878) (xy 392.268456 -68.874386)
			(xy 392.247518 -68.891963) (xy 392.201585 -68.921605) (xy 392.15189 -68.944384) (xy 392.099452 -68.959835)
			(xy 392.045345 -68.967642) (xy 392.018012 -68.968112) (xy 392.017758 -68.968112) (xy 391.991462 -68.967677)
			(xy 391.939373 -68.960427) (xy 391.888771 -68.946096) (xy 391.840615 -68.924956) (xy 391.795816 -68.897407)
			(xy 391.755222 -68.86397) (xy 391.737088 -68.844922) (xy 391.729517 -68.83748) (xy 391.710099 -68.828954)
			(xy 391.699496 -68.828412) (xy 391.625328 -68.828412) (xy 391.614698 -68.828842) (xy 391.595234 -68.837376)
			(xy 391.587736 -68.844922) (xy 391.569603 -68.863973) (xy 391.529022 -68.897429) (xy 391.484226 -68.924989)
			(xy 391.436067 -68.946129) (xy 391.385459 -68.960447) (xy 391.333363 -68.967673) (xy 391.307066 -68.968112)
			(xy 391.306812 -68.968112) (xy 391.27956 -68.967634) (xy 391.225609 -68.959878) (xy 391.173312 -68.944524)
			(xy 391.123732 -68.921883) (xy 391.077879 -68.892417) (xy 391.036687 -68.856725) (xy 391.000993 -68.815533)
			(xy 390.971525 -68.769682) (xy 390.948882 -68.720103) (xy 390.933525 -68.667806) (xy 390.925768 -68.613856)
			(xy 390.925304 -68.586604) (xy 367.034572 -68.586604) (xy 367.034148 -68.613859) (xy 367.02639 -68.667813)
			(xy 367.011031 -68.720114) (xy 366.988386 -68.769696) (xy 366.958914 -68.815551) (xy 366.923216 -68.856745)
			(xy 366.882019 -68.892438) (xy 366.836161 -68.921905) (xy 366.786576 -68.944545) (xy 366.734274 -68.959898)
			(xy 366.680319 -68.967651) (xy 366.653064 -68.968112) (xy 366.625693 -68.967664) (xy 366.571513 -68.959841)
			(xy 366.51901 -68.944348) (xy 366.469264 -68.921502) (xy 366.423297 -68.891775) (xy 366.402366 -68.874132)
			(xy 366.402112 -68.873878) (xy 366.395028 -68.868288) (xy 366.378109 -68.862044) (xy 366.369092 -68.861686)
			(xy 366.302036 -68.861686) (xy 366.293021 -68.862063) (xy 366.276104 -68.868297) (xy 366.269016 -68.873878)
			(xy 366.268508 -68.874386) (xy 366.247588 -68.891986) (xy 366.20165 -68.921624) (xy 366.151951 -68.944399)
			(xy 366.099509 -68.959845) (xy 366.045399 -68.967645) (xy 366.018064 -68.968112) (xy 366.01781 -68.968112)
			(xy 365.991516 -68.967643) (xy 365.939427 -68.960399) (xy 365.888827 -68.946075) (xy 365.84067 -68.924941)
			(xy 365.795871 -68.897398) (xy 365.755275 -68.863967) (xy 365.73714 -68.844922) (xy 365.72955 -68.837503)
			(xy 365.710146 -68.828964) (xy 365.699548 -68.828412) (xy 365.62538 -68.828412) (xy 365.614747 -68.828815)
			(xy 365.595283 -68.837368) (xy 365.587788 -68.844922) (xy 365.569679 -68.863997) (xy 365.529092 -68.897451)
			(xy 365.484291 -68.925007) (xy 365.436128 -68.946143) (xy 365.385516 -68.960456) (xy 365.333417 -68.967676)
			(xy 365.307118 -68.968112) (xy 365.306864 -68.968112) (xy 365.279612 -68.967656) (xy 365.225663 -68.959894)
			(xy 365.173368 -68.944535) (xy 365.123791 -68.92189) (xy 365.077941 -68.89242) (xy 365.036752 -68.856726)
			(xy 365.001061 -68.815533) (xy 364.971595 -68.769681) (xy 364.948954 -68.720102) (xy 364.933599 -68.667805)
			(xy 364.925842 -68.613856) (xy 364.925356 -68.586604) (xy 353.176253 -68.586604) (xy 353.200549 -68.605424)
			(xy 353.356766 -68.736427) (xy 353.507788 -68.873387) (xy 353.653388 -69.016097) (xy 353.793348 -69.164343)
			(xy 353.927456 -69.317903) (xy 354.055512 -69.476545) (xy 354.177322 -69.640031) (xy 354.292705 -69.808115)
			(xy 354.401486 -69.980546) (xy 354.503502 -70.157063) (xy 354.551488 -70.247002) (xy 354.55479 -70.253352)
			(xy 354.564188 -70.263258) (xy 354.590604 -70.27926) (xy 354.596659 -70.282692) (xy 354.610062 -70.286425)
			(xy 354.61702 -70.286626) (xy 454.338182 -70.286626) (xy 454.348232 -70.28612) (xy 454.366792 -70.278398)
			(xy 454.37425 -70.27164) (xy 459.042008 -65.603882) (xy 459.042516 -65.603374) (xy 459.049107 -65.595996)
			(xy 459.056572 -65.577697) (xy 459.056994 -65.567814) (xy 459.056994 -46.840902) (xy 459.056571 -46.830832)
			(xy 459.048856 -46.812227) (xy 459.042008 -46.804834) (xy 457.167996 -44.930822) (xy 457.160884 -44.923456)
			(xy 457.142088 -44.915836) (xy 454.019158 -44.915836) (xy 453.991218 -44.938188) (xy 453.987408 -44.955714)
			(xy 453.981045 -44.982118) (xy 453.961856 -45.032925) (xy 453.935654 -45.080497) (xy 453.90297 -45.123872)
			(xy 453.864464 -45.162173) (xy 453.820915 -45.194625) (xy 453.773204 -45.220572) (xy 453.722295 -45.239489)
			(xy 453.669217 -45.250995) (xy 453.615044 -45.254857) (xy 453.560871 -45.250995) (xy 453.507793 -45.239489)
			(xy 453.456884 -45.220572) (xy 453.409173 -45.194625) (xy 453.365624 -45.162173) (xy 453.327118 -45.123872)
			(xy 453.294434 -45.080497) (xy 453.268232 -45.032925) (xy 453.249043 -44.982118) (xy 453.24268 -44.955714)
			(xy 453.23887 -44.938188) (xy 453.21093 -44.915836) (xy 451.731888 -44.915836) (xy 451.721957 -44.916315)
			(xy 451.703593 -44.923884) (xy 451.689496 -44.937877) (xy 451.685152 -44.946824) (xy 451.649846 -45.030898)
			(xy 451.648001 -45.035579) (xy 451.645955 -45.045428) (xy 451.645782 -45.050456) (xy 451.645782 -45.063918)
			(xy 451.652894 -45.081952) (xy 451.660006 -45.089064) (xy 451.680005 -45.11053) (xy 451.713837 -45.15846)
			(xy 451.739929 -45.211006) (xy 451.757666 -45.266928) (xy 451.766629 -45.324906) (xy 451.767194 -45.35424)
			(xy 451.766705 -45.381489) (xy 451.758944 -45.435432) (xy 451.743585 -45.487721) (xy 451.720941 -45.537292)
			(xy 451.691474 -45.583136) (xy 451.655782 -45.62432) (xy 451.614593 -45.660006) (xy 451.568744 -45.689467)
			(xy 451.51917 -45.712104) (xy 451.466879 -45.727455) (xy 451.412935 -45.735209) (xy 451.385686 -45.735748)
			(xy 451.35884 -45.735283) (xy 451.30568 -45.727742) (xy 451.254102 -45.712824) (xy 451.205123 -45.690825)
			(xy 451.159712 -45.662177) (xy 451.118764 -45.627448) (xy 451.083087 -45.587322) (xy 451.053387 -45.542592)
			(xy 451.03025 -45.494141) (xy 451.014131 -45.442925) (xy 451.00535 -45.389956) (xy 451.004178 -45.36313)
			(xy 451.004178 -45.354748) (xy 451.004672 -45.325229) (xy 451.013648 -45.266881) (xy 451.031504 -45.21061)
			(xy 451.057811 -45.157761) (xy 451.091944 -45.109593) (xy 451.112128 -45.088048) (xy 451.118833 -45.080612)
			(xy 451.1263 -45.06205) (xy 451.126079 -45.042044) (xy 451.122542 -45.032676) (xy 451.08622 -44.946824)
			(xy 451.081905 -44.937865) (xy 451.067783 -44.923893) (xy 451.049416 -44.916324) (xy 451.039484 -44.915836)
			(xy 447.220848 -44.915836) (xy 447.209566 -44.916451) (xy 447.189158 -44.926087) (xy 447.181478 -44.934378)
			(xy 447.13144 -44.995338) (xy 447.128036 -44.99977) (xy 447.123047 -45.009769) (xy 447.121534 -45.01515)
			(xy 447.11874 -45.02658) (xy 447.121026 -45.03801) (xy 447.124694 -45.056911) (xy 447.128636 -45.095212)
			(xy 447.1289 -45.114464) (xy 447.128439 -45.141718) (xy 447.120686 -45.195673) (xy 447.105333 -45.247974)
			(xy 447.082693 -45.297559) (xy 447.053226 -45.343416) (xy 447.017532 -45.384612) (xy 446.976338 -45.420309)
			(xy 446.930483 -45.449779) (xy 446.880901 -45.472423) (xy 446.8286 -45.48778) (xy 446.774646 -45.495537)
			(xy 446.747392 -45.495972) (xy 446.72014 -45.495508) (xy 446.666192 -45.48775) (xy 446.613897 -45.472393)
			(xy 446.564321 -45.449749) (xy 446.518471 -45.420281) (xy 446.477282 -45.384586) (xy 446.441593 -45.343394)
			(xy 446.412129 -45.297541) (xy 446.389492 -45.247961) (xy 446.374141 -45.195665) (xy 446.366389 -45.141716)
			(xy 446.365884 -45.114464) (xy 446.366163 -45.095213) (xy 446.370104 -45.056913) (xy 446.373758 -45.03801)
			(xy 446.376044 -45.02658) (xy 446.37325 -45.01515) (xy 446.371762 -45.009761) (xy 446.366753 -44.99977)
			(xy 446.363344 -44.995338) (xy 446.313306 -44.934378) (xy 446.305684 -44.926016) (xy 446.285238 -44.9164)
			(xy 446.273936 -44.915836) (xy 428.01921 -44.915836) (xy 427.99127 -44.938188) (xy 427.98746 -44.955714)
			(xy 427.981097 -44.982118) (xy 427.961908 -45.032925) (xy 427.935706 -45.080497) (xy 427.903022 -45.123872)
			(xy 427.864516 -45.162173) (xy 427.820967 -45.194625) (xy 427.773256 -45.220572) (xy 427.722347 -45.239489)
			(xy 427.669269 -45.250995) (xy 427.615096 -45.254857) (xy 427.560923 -45.250995) (xy 427.507845 -45.239489)
			(xy 427.456936 -45.220572) (xy 427.409225 -45.194625) (xy 427.365676 -45.162173) (xy 427.32717 -45.123872)
			(xy 427.294486 -45.080497) (xy 427.268284 -45.032925) (xy 427.249095 -44.982118) (xy 427.242732 -44.955714)
			(xy 427.238922 -44.938188) (xy 427.210982 -44.915836) (xy 425.73194 -44.915836) (xy 425.722003 -44.916306)
			(xy 425.703623 -44.923864) (xy 425.68951 -44.937856) (xy 425.685204 -44.946824) (xy 425.649898 -45.030898)
			(xy 425.648055 -45.035579) (xy 425.64601 -45.045428) (xy 425.645834 -45.050456) (xy 425.645834 -45.063918)
			(xy 425.652946 -45.081952) (xy 425.660058 -45.089064) (xy 425.680059 -45.110529) (xy 425.713895 -45.158458)
			(xy 425.73999 -45.211003) (xy 425.75773 -45.266926) (xy 425.766694 -45.324905) (xy 425.767246 -45.35424)
			(xy 425.766758 -45.38149) (xy 425.758997 -45.435436) (xy 425.743638 -45.487728) (xy 425.720995 -45.537303)
			(xy 425.691529 -45.583151) (xy 425.655838 -45.624339) (xy 425.614649 -45.66003) (xy 425.568801 -45.689496)
			(xy 425.519226 -45.712139) (xy 425.466934 -45.727497) (xy 425.412988 -45.735258) (xy 425.385738 -45.735748)
			(xy 425.35889 -45.735287) (xy 425.305724 -45.727751) (xy 425.25414 -45.712838) (xy 425.205155 -45.690842)
			(xy 425.159737 -45.662196) (xy 425.118783 -45.627467) (xy 425.083101 -45.58734) (xy 425.053396 -45.542608)
			(xy 425.030254 -45.494153) (xy 425.014133 -45.442933) (xy 425.005351 -45.389959) (xy 425.00423 -45.36313)
			(xy 425.00423 -45.354748) (xy 425.004724 -45.32523) (xy 425.013702 -45.266882) (xy 425.031559 -45.210613)
			(xy 425.057869 -45.157765) (xy 425.092004 -45.109601) (xy 425.11218 -45.088048) (xy 425.11888 -45.08061)
			(xy 425.126338 -45.062049) (xy 425.126118 -45.042047) (xy 425.122594 -45.032676) (xy 425.086272 -44.946824)
			(xy 425.081959 -44.937859) (xy 425.06784 -44.923873) (xy 425.049472 -44.916286) (xy 425.039536 -44.915836)
			(xy 421.2209 -44.915836) (xy 421.209612 -44.916441) (xy 421.189188 -44.926063) (xy 421.18153 -44.934378)
			(xy 421.131492 -44.995338) (xy 421.128085 -44.999769) (xy 421.123091 -45.009767) (xy 421.121586 -45.01515)
			(xy 421.118792 -45.02658) (xy 421.121078 -45.03801) (xy 421.124746 -45.056911) (xy 421.128687 -45.095212)
			(xy 421.128952 -45.114464) (xy 421.128469 -45.141718) (xy 421.120717 -45.195672) (xy 421.105365 -45.247974)
			(xy 421.082727 -45.297558) (xy 421.053262 -45.343416) (xy 421.017571 -45.384614) (xy 420.97638 -45.420314)
			(xy 420.930528 -45.449788) (xy 420.880949 -45.472437) (xy 420.82865 -45.4878) (xy 420.774698 -45.495563)
			(xy 420.747444 -45.495972) (xy 420.72019 -45.495512) (xy 420.666236 -45.48776) (xy 420.613935 -45.472407)
			(xy 420.564352 -45.449766) (xy 420.518496 -45.420299) (xy 420.477301 -45.384605) (xy 420.441606 -45.343411)
			(xy 420.412137 -45.297555) (xy 420.389496 -45.247972) (xy 420.374142 -45.195672) (xy 420.366389 -45.141718)
			(xy 420.365936 -45.114464) (xy 420.366215 -45.095213) (xy 420.370156 -45.056913) (xy 420.37381 -45.03801)
			(xy 420.376096 -45.02658) (xy 420.373302 -45.01515) (xy 420.371815 -45.00976) (xy 420.366811 -44.999765)
			(xy 420.363396 -44.995338) (xy 420.313358 -44.934378) (xy 420.305739 -44.926007) (xy 420.285293 -44.91637)
			(xy 420.273988 -44.915836) (xy 402.019262 -44.915836) (xy 401.991322 -44.938188) (xy 401.987512 -44.955714)
			(xy 401.981149 -44.982118) (xy 401.96196 -45.032925) (xy 401.935758 -45.080497) (xy 401.903074 -45.123872)
			(xy 401.864568 -45.162173) (xy 401.821019 -45.194625) (xy 401.773308 -45.220572) (xy 401.722399 -45.239489)
			(xy 401.669321 -45.250995) (xy 401.615148 -45.254857) (xy 401.560975 -45.250995) (xy 401.507897 -45.239489)
			(xy 401.456988 -45.220572) (xy 401.409277 -45.194625) (xy 401.365728 -45.162173) (xy 401.327222 -45.123872)
			(xy 401.294538 -45.080497) (xy 401.268336 -45.032925) (xy 401.249147 -44.982118) (xy 401.242784 -44.955714)
			(xy 401.238974 -44.938188) (xy 401.211034 -44.915836) (xy 399.731992 -44.915836) (xy 399.72206 -44.916314)
			(xy 399.703695 -44.923883) (xy 399.689597 -44.937875) (xy 399.685256 -44.946824) (xy 399.64995 -45.030898)
			(xy 399.648105 -45.035579) (xy 399.646059 -45.045428) (xy 399.645886 -45.050456) (xy 399.645886 -45.063918)
			(xy 399.652998 -45.081952) (xy 399.66011 -45.089064) (xy 399.680114 -45.110528) (xy 399.713953 -45.158455)
			(xy 399.740052 -45.211001) (xy 399.757794 -45.266924) (xy 399.76676 -45.324905) (xy 399.767298 -45.35424)
			(xy 399.766809 -45.381489) (xy 399.759048 -45.435432) (xy 399.743689 -45.487721) (xy 399.721046 -45.537293)
			(xy 399.691578 -45.583137) (xy 399.655886 -45.624322) (xy 399.614697 -45.660008) (xy 399.568849 -45.68947)
			(xy 399.519274 -45.712107) (xy 399.466983 -45.727458) (xy 399.413039 -45.735213) (xy 399.38579 -45.735748)
			(xy 399.358944 -45.735284) (xy 399.305783 -45.727743) (xy 399.254204 -45.712825) (xy 399.205226 -45.690826)
			(xy 399.159814 -45.662179) (xy 399.118865 -45.627449) (xy 399.083188 -45.587324) (xy 399.053488 -45.542594)
			(xy 399.03035 -45.494142) (xy 399.014231 -45.442926) (xy 399.00545 -45.389956) (xy 399.004282 -45.36313)
			(xy 399.004282 -45.354748) (xy 399.004776 -45.325229) (xy 399.013753 -45.266881) (xy 399.031608 -45.21061)
			(xy 399.057916 -45.157761) (xy 399.092048 -45.109593) (xy 399.112232 -45.088048) (xy 399.118937 -45.080612)
			(xy 399.126403 -45.06205) (xy 399.126182 -45.042044) (xy 399.122646 -45.032676) (xy 399.086324 -44.946824)
			(xy 399.082009 -44.937865) (xy 399.067888 -44.923891) (xy 399.04952 -44.91632) (xy 399.039588 -44.915836)
			(xy 395.220952 -44.915836) (xy 395.209669 -44.916451) (xy 395.18926 -44.926085) (xy 395.181582 -44.934378)
			(xy 395.131544 -44.995338) (xy 395.128139 -44.99977) (xy 395.12315 -45.009769) (xy 395.121638 -45.01515)
			(xy 395.118844 -45.02658) (xy 395.12113 -45.03801) (xy 395.124798 -45.056911) (xy 395.12874 -45.095212)
			(xy 395.129004 -45.114464) (xy 395.128543 -45.141718) (xy 395.12079 -45.195673) (xy 395.105437 -45.247975)
			(xy 395.082797 -45.297559) (xy 395.05333 -45.343417) (xy 395.017636 -45.384613) (xy 394.976442 -45.420311)
			(xy 394.930587 -45.449781) (xy 394.881005 -45.472426) (xy 394.828704 -45.487783) (xy 394.77475 -45.495541)
			(xy 394.747496 -45.495972) (xy 394.720244 -45.495508) (xy 394.666296 -45.487751) (xy 394.614 -45.472394)
			(xy 394.564423 -45.449751) (xy 394.518573 -45.420282) (xy 394.477384 -45.384588) (xy 394.441694 -45.343395)
			(xy 394.41223 -45.297542) (xy 394.389592 -45.247962) (xy 394.374241 -45.195665) (xy 394.366489 -45.141716)
			(xy 394.365988 -45.114464) (xy 394.366267 -45.095213) (xy 394.370208 -45.056913) (xy 394.373862 -45.03801)
			(xy 394.376148 -45.02658) (xy 394.373354 -45.01515) (xy 394.371866 -45.009761) (xy 394.366858 -44.999769)
			(xy 394.363448 -44.995338) (xy 394.31341 -44.934378) (xy 394.305788 -44.926015) (xy 394.285342 -44.916397)
			(xy 394.27404 -44.915836) (xy 376.019314 -44.915836) (xy 375.991374 -44.938188) (xy 375.987564 -44.955714)
			(xy 375.981201 -44.982118) (xy 375.962012 -45.032925) (xy 375.93581 -45.080497) (xy 375.903126 -45.123872)
			(xy 375.86462 -45.162173) (xy 375.821071 -45.194625) (xy 375.77336 -45.220572) (xy 375.722451 -45.239489)
			(xy 375.669373 -45.250995) (xy 375.6152 -45.254857) (xy 375.561027 -45.250995) (xy 375.507949 -45.239489)
			(xy 375.45704 -45.220572) (xy 375.409329 -45.194625) (xy 375.36578 -45.162173) (xy 375.327274 -45.123872)
			(xy 375.29459 -45.080497) (xy 375.268388 -45.032925) (xy 375.249199 -44.982118) (xy 375.242836 -44.955714)
			(xy 375.239026 -44.938188) (xy 375.211086 -44.915836) (xy 373.732044 -44.915836) (xy 373.722107 -44.916305)
			(xy 373.703726 -44.923863) (xy 373.689611 -44.937854) (xy 373.685308 -44.946824) (xy 373.650002 -45.030898)
			(xy 373.648159 -45.035579) (xy 373.646114 -45.045428) (xy 373.645938 -45.050456) (xy 373.645938 -45.063918)
			(xy 373.65305 -45.081952) (xy 373.660162 -45.089064) (xy 373.680163 -45.110529) (xy 373.713998 -45.158458)
			(xy 373.740093 -45.211003) (xy 373.757833 -45.266926) (xy 373.766797 -45.324906) (xy 373.76735 -45.35424)
			(xy 373.766862 -45.38149) (xy 373.759101 -45.435436) (xy 373.743742 -45.487728) (xy 373.7211 -45.537303)
			(xy 373.691633 -45.583152) (xy 373.655942 -45.624341) (xy 373.614753 -45.660032) (xy 373.568905 -45.689499)
			(xy 373.51933 -45.712142) (xy 373.467038 -45.7275) (xy 373.413092 -45.735261) (xy 373.385842 -45.735748)
			(xy 373.358993 -45.735287) (xy 373.305827 -45.727752) (xy 373.254243 -45.712839) (xy 373.205257 -45.690843)
			(xy 373.159839 -45.662197) (xy 373.118884 -45.627468) (xy 373.083202 -45.587341) (xy 373.053497 -45.542609)
			(xy 373.030355 -45.494154) (xy 373.014233 -45.442934) (xy 373.005451 -45.38996) (xy 373.004334 -45.36313)
			(xy 373.004334 -45.354748) (xy 373.004828 -45.32523) (xy 373.013806 -45.266882) (xy 373.031663 -45.210613)
			(xy 373.057973 -45.157766) (xy 373.092109 -45.109601) (xy 373.112284 -45.088048) (xy 373.123206 -45.076872)
			(xy 373.128794 -45.047154) (xy 373.086376 -44.946824) (xy 373.082063 -44.937859) (xy 373.067945 -44.923871)
			(xy 373.049576 -44.916283) (xy 373.03964 -44.915836) (xy 369.221004 -44.915836) (xy 369.209716 -44.91644)
			(xy 369.18929 -44.926061) (xy 369.181634 -44.934378) (xy 369.131596 -44.995338) (xy 369.128188 -44.999769)
			(xy 369.123194 -45.009766) (xy 369.12169 -45.01515) (xy 369.118896 -45.02658) (xy 369.121182 -45.03801)
			(xy 369.12485 -45.056911) (xy 369.128791 -45.095212) (xy 369.129056 -45.114464) (xy 369.128573 -45.141718)
			(xy 369.120821 -45.195672) (xy 369.105469 -45.247974) (xy 369.082831 -45.297559) (xy 369.053366 -45.343417)
			(xy 369.017675 -45.384616) (xy 368.976485 -45.420316) (xy 368.930633 -45.44979) (xy 368.881053 -45.47244)
			(xy 368.828755 -45.487803) (xy 368.774802 -45.495567) (xy 368.747548 -45.495972) (xy 368.720294 -45.495512)
			(xy 368.66634 -45.48776) (xy 368.614038 -45.472408) (xy 368.564454 -45.449768) (xy 368.518598 -45.420301)
			(xy 368.477402 -45.384606) (xy 368.441707 -45.343412) (xy 368.412238 -45.297556) (xy 368.389596 -45.247973)
			(xy 368.374242 -45.195672) (xy 368.366489 -45.141718) (xy 368.36604 -45.114464) (xy 368.366319 -45.095213)
			(xy 368.37026 -45.056913) (xy 368.373914 -45.03801) (xy 368.3762 -45.02658) (xy 368.373406 -45.01515)
			(xy 368.371919 -45.00976) (xy 368.366915 -44.999765) (xy 368.3635 -44.995338) (xy 368.313462 -44.934378)
			(xy 368.305844 -44.926007) (xy 368.285398 -44.916368) (xy 368.274092 -44.915836) (xy 337.91906 -44.915836)
			(xy 337.89112 -44.938188) (xy 337.88731 -44.955714) (xy 337.880947 -44.982118) (xy 337.861758 -45.032925)
			(xy 337.835556 -45.080497) (xy 337.802872 -45.123872) (xy 337.764366 -45.162173) (xy 337.720817 -45.194625)
			(xy 337.673106 -45.220572) (xy 337.622197 -45.239489) (xy 337.569119 -45.250995) (xy 337.514946 -45.254857)
			(xy 337.460773 -45.250995) (xy 337.407695 -45.239489) (xy 337.356786 -45.220572) (xy 337.309075 -45.194625)
			(xy 337.265526 -45.162173) (xy 337.22702 -45.123872) (xy 337.194336 -45.080497) (xy 337.168134 -45.032925)
			(xy 337.148945 -44.982118) (xy 337.142582 -44.955714) (xy 337.138772 -44.938188) (xy 337.110832 -44.915836)
			(xy 335.63179 -44.915836) (xy 335.621859 -44.916315) (xy 335.603494 -44.923883) (xy 335.589396 -44.937876)
			(xy 335.585054 -44.946824) (xy 335.549748 -45.030898) (xy 335.547903 -45.035579) (xy 335.545857 -45.045428)
			(xy 335.545684 -45.050456) (xy 335.545684 -45.063918) (xy 335.552796 -45.081952) (xy 335.559908 -45.089064)
			(xy 335.579912 -45.110528) (xy 335.613752 -45.158455) (xy 335.63985 -45.211001) (xy 335.657592 -45.266924)
			(xy 335.666558 -45.324905) (xy 335.667096 -45.35424) (xy 335.666607 -45.381489) (xy 335.658846 -45.435432)
			(xy 335.643487 -45.487721) (xy 335.620844 -45.537292) (xy 335.591376 -45.583137) (xy 335.555684 -45.624321)
			(xy 335.514495 -45.660007) (xy 335.468647 -45.689468) (xy 335.419072 -45.712105) (xy 335.366781 -45.727457)
			(xy 335.312837 -45.735211) (xy 335.285588 -45.735748) (xy 335.258742 -45.735283) (xy 335.205582 -45.727742)
			(xy 335.154003 -45.712825) (xy 335.105024 -45.690825) (xy 335.059613 -45.662178) (xy 335.018664 -45.627449)
			(xy 334.982988 -45.587323) (xy 334.953288 -45.542593) (xy 334.93015 -45.494142) (xy 334.914031 -45.442926)
			(xy 334.90525 -45.389956) (xy 334.90408 -45.36313) (xy 334.90408 -45.354748) (xy 334.904574 -45.325229)
			(xy 334.91355 -45.266881) (xy 334.931406 -45.21061) (xy 334.957713 -45.157761) (xy 334.991846 -45.109593)
			(xy 335.01203 -45.088048) (xy 335.022952 -45.076872) (xy 335.02854 -45.047154) (xy 334.986122 -44.946824)
			(xy 334.981807 -44.937865) (xy 334.967686 -44.923891) (xy 334.949318 -44.916322) (xy 334.939386 -44.915836)
			(xy 331.12075 -44.915836) (xy 331.109467 -44.916451) (xy 331.089059 -44.926086) (xy 331.08138 -44.934378)
			(xy 331.031342 -44.995338) (xy 331.027937 -44.99977) (xy 331.022949 -45.009769) (xy 331.021436 -45.01515)
			(xy 331.018642 -45.02658) (xy 331.020928 -45.03801) (xy 331.024596 -45.056911) (xy 331.028538 -45.095212)
			(xy 331.028802 -45.114464) (xy 331.028341 -45.141718) (xy 331.020588 -45.195673) (xy 331.005235 -45.247975)
			(xy 330.982595 -45.297559) (xy 330.953128 -45.343416) (xy 330.917434 -45.384613) (xy 330.87624 -45.42031)
			(xy 330.830385 -45.44978) (xy 330.780803 -45.472425) (xy 330.728502 -45.487782) (xy 330.674548 -45.495539)
			(xy 330.647294 -45.495972) (xy 330.620042 -45.495508) (xy 330.566094 -45.48775) (xy 330.513799 -45.472393)
			(xy 330.464222 -45.44975) (xy 330.418372 -45.420281) (xy 330.377183 -45.384587) (xy 330.341493 -45.343394)
			(xy 330.31203 -45.297541) (xy 330.289392 -45.247962) (xy 330.274041 -45.195665) (xy 330.266289 -45.141716)
			(xy 330.265786 -45.114464) (xy 330.266065 -45.095213) (xy 330.270006 -45.056913) (xy 330.27366 -45.03801)
			(xy 330.275946 -45.02658) (xy 330.273152 -45.01515) (xy 330.271664 -45.009761) (xy 330.266655 -44.999769)
			(xy 330.263246 -44.995338) (xy 330.213208 -44.934378) (xy 330.205586 -44.926016) (xy 330.18514 -44.916398)
			(xy 330.173838 -44.915836) (xy 311.919112 -44.915836) (xy 311.891172 -44.938188) (xy 311.887362 -44.955714)
			(xy 311.880999 -44.982118) (xy 311.86181 -45.032925) (xy 311.835608 -45.080497) (xy 311.802924 -45.123872)
			(xy 311.764418 -45.162173) (xy 311.720869 -45.194625) (xy 311.673158 -45.220572) (xy 311.622249 -45.239489)
			(xy 311.569171 -45.250995) (xy 311.514998 -45.254857) (xy 311.460825 -45.250995) (xy 311.407747 -45.239489)
			(xy 311.356838 -45.220572) (xy 311.309127 -45.194625) (xy 311.265578 -45.162173) (xy 311.227072 -45.123872)
			(xy 311.194388 -45.080497) (xy 311.168186 -45.032925) (xy 311.148997 -44.982118) (xy 311.142634 -44.955714)
			(xy 311.138824 -44.938188) (xy 311.110884 -44.915836) (xy 309.631842 -44.915836) (xy 309.621905 -44.916306)
			(xy 309.603524 -44.923863) (xy 309.589411 -44.937855) (xy 309.585106 -44.946824) (xy 309.5498 -45.030898)
			(xy 309.547957 -45.035579) (xy 309.545912 -45.045428) (xy 309.545736 -45.050456) (xy 309.545736 -45.063918)
			(xy 309.552848 -45.081952) (xy 309.55996 -45.089064) (xy 309.579961 -45.110529) (xy 309.613797 -45.158458)
			(xy 309.639892 -45.211003) (xy 309.657631 -45.266926) (xy 309.666596 -45.324905) (xy 309.667148 -45.35424)
			(xy 309.66666 -45.38149) (xy 309.658899 -45.435436) (xy 309.64354 -45.487728) (xy 309.620898 -45.537303)
			(xy 309.591431 -45.583151) (xy 309.55574 -45.62434) (xy 309.514551 -45.660031) (xy 309.468703 -45.689498)
			(xy 309.419128 -45.71214) (xy 309.366836 -45.727499) (xy 309.31289 -45.73526) (xy 309.28564 -45.735748)
			(xy 309.258792 -45.735287) (xy 309.205626 -45.727752) (xy 309.154041 -45.712839) (xy 309.105056 -45.690842)
			(xy 309.059638 -45.662197) (xy 309.018683 -45.627467) (xy 308.983001 -45.58734) (xy 308.953296 -45.542608)
			(xy 308.930155 -45.494154) (xy 308.914033 -45.442934) (xy 308.905251 -45.38996) (xy 308.904132 -45.36313)
			(xy 308.904132 -45.354748) (xy 308.904626 -45.32523) (xy 308.913604 -45.266882) (xy 308.931461 -45.210613)
			(xy 308.957771 -45.157766) (xy 308.991907 -45.109601) (xy 309.012082 -45.088048) (xy 309.023004 -45.076872)
			(xy 309.028592 -45.047154) (xy 308.986174 -44.946824) (xy 308.981861 -44.937859) (xy 308.967743 -44.923872)
			(xy 308.949374 -44.916284) (xy 308.939438 -44.915836) (xy 305.120802 -44.915836) (xy 305.109514 -44.916441)
			(xy 305.089089 -44.926062) (xy 305.081432 -44.934378) (xy 305.031394 -44.995338) (xy 305.027986 -44.999769)
			(xy 305.022993 -45.009767) (xy 305.021488 -45.01515) (xy 305.018694 -45.02658) (xy 305.02098 -45.03801)
			(xy 305.024648 -45.056911) (xy 305.028589 -45.095212) (xy 305.028854 -45.114464) (xy 305.028371 -45.141718)
			(xy 305.020619 -45.195672) (xy 305.005267 -45.247974) (xy 304.982629 -45.297559) (xy 304.953164 -45.343417)
			(xy 304.917473 -45.384615) (xy 304.876283 -45.420315) (xy 304.830431 -45.449789) (xy 304.780851 -45.472438)
			(xy 304.728552 -45.487801) (xy 304.6746 -45.495565) (xy 304.647346 -45.495972) (xy 304.620092 -45.495512)
			(xy 304.566138 -45.48776) (xy 304.513837 -45.472408) (xy 304.464253 -45.449767) (xy 304.418397 -45.4203)
			(xy 304.377201 -45.384606) (xy 304.341506 -45.343411) (xy 304.312038 -45.297556) (xy 304.289396 -45.247973)
			(xy 304.274042 -45.195672) (xy 304.266289 -45.141718) (xy 304.265838 -45.114464) (xy 304.266117 -45.095213)
			(xy 304.270058 -45.056913) (xy 304.273712 -45.03801) (xy 304.275998 -45.02658) (xy 304.273204 -45.01515)
			(xy 304.271717 -45.00976) (xy 304.266713 -44.999765) (xy 304.263298 -44.995338) (xy 304.21326 -44.934378)
			(xy 304.205641 -44.926007) (xy 304.185195 -44.916369) (xy 304.17389 -44.915836) (xy 285.919164 -44.915836)
			(xy 285.891224 -44.938188) (xy 285.887414 -44.955714) (xy 285.881051 -44.982118) (xy 285.861862 -45.032925)
			(xy 285.83566 -45.080497) (xy 285.802976 -45.123872) (xy 285.76447 -45.162173) (xy 285.720921 -45.194625)
			(xy 285.67321 -45.220572) (xy 285.622301 -45.239489) (xy 285.569223 -45.250995) (xy 285.51505 -45.254857)
			(xy 285.460877 -45.250995) (xy 285.407799 -45.239489) (xy 285.35689 -45.220572) (xy 285.309179 -45.194625)
			(xy 285.26563 -45.162173) (xy 285.227124 -45.123872) (xy 285.19444 -45.080497) (xy 285.168238 -45.032925)
			(xy 285.149049 -44.982118) (xy 285.142686 -44.955714) (xy 285.138876 -44.938188) (xy 285.110936 -44.915836)
			(xy 283.631894 -44.915836) (xy 283.621962 -44.916314) (xy 283.603596 -44.923882) (xy 283.589497 -44.937875)
			(xy 283.585158 -44.946824) (xy 283.549852 -45.030898) (xy 283.548007 -45.035579) (xy 283.545961 -45.045428)
			(xy 283.545788 -45.050456) (xy 283.545788 -45.063918) (xy 283.5529 -45.081952) (xy 283.560012 -45.089064)
			(xy 283.580015 -45.110528) (xy 283.613855 -45.158455) (xy 283.639954 -45.211001) (xy 283.657695 -45.266924)
			(xy 283.666661 -45.324905) (xy 283.6672 -45.35424) (xy 283.666711 -45.381489) (xy 283.65895 -45.435432)
			(xy 283.643592 -45.487722) (xy 283.620948 -45.537293) (xy 283.591481 -45.583138) (xy 283.555789 -45.624323)
			(xy 283.5146 -45.660009) (xy 283.468751 -45.689471) (xy 283.419177 -45.712108) (xy 283.366885 -45.727461)
			(xy 283.312941 -45.735215) (xy 283.285692 -45.735748) (xy 283.258846 -45.735284) (xy 283.205685 -45.727743)
			(xy 283.154106 -45.712826) (xy 283.105127 -45.690827) (xy 283.059715 -45.662179) (xy 283.018766 -45.62745)
			(xy 282.983089 -45.587324) (xy 282.953388 -45.542594) (xy 282.93025 -45.494143) (xy 282.914132 -45.442926)
			(xy 282.90535 -45.389956) (xy 282.904184 -45.36313) (xy 282.904184 -45.354748) (xy 282.904678 -45.325229)
			(xy 282.913655 -45.266881) (xy 282.93151 -45.21061) (xy 282.957818 -45.157761) (xy 282.991951 -45.109594)
			(xy 283.012134 -45.088048) (xy 283.023056 -45.076872) (xy 283.028644 -45.047154) (xy 282.986226 -44.946824)
			(xy 282.981911 -44.937864) (xy 282.96779 -44.92389) (xy 282.949423 -44.916319) (xy 282.93949 -44.915836)
			(xy 279.120854 -44.915836) (xy 279.109571 -44.91645) (xy 279.089161 -44.926084) (xy 279.081484 -44.934378)
			(xy 279.031446 -44.995338) (xy 279.028041 -44.99977) (xy 279.023052 -45.009769) (xy 279.02154 -45.01515)
			(xy 279.018746 -45.02658) (xy 279.021032 -45.03801) (xy 279.0247 -45.056911) (xy 279.028642 -45.095212)
			(xy 279.028906 -45.114464) (xy 279.028445 -45.141718) (xy 279.020692 -45.195673) (xy 279.005339 -45.247975)
			(xy 278.982699 -45.29756) (xy 278.953232 -45.343417) (xy 278.917538 -45.384614) (xy 278.876345 -45.420311)
			(xy 278.83049 -45.449783) (xy 278.780907 -45.472427) (xy 278.728606 -45.487785) (xy 278.674652 -45.495543)
			(xy 278.647398 -45.495972) (xy 278.620146 -45.495509) (xy 278.566197 -45.487751) (xy 278.513902 -45.472395)
			(xy 278.464324 -45.449751) (xy 278.418474 -45.420283) (xy 278.377284 -45.384589) (xy 278.341594 -45.343396)
			(xy 278.31213 -45.297542) (xy 278.289492 -45.247963) (xy 278.274141 -45.195665) (xy 278.266389 -45.141716)
			(xy 278.26589 -45.114464) (xy 278.266169 -45.095213) (xy 278.27011 -45.056913) (xy 278.273764 -45.03801)
			(xy 278.27605 -45.02658) (xy 278.273256 -45.01515) (xy 278.271768 -45.009761) (xy 278.26676 -44.999769)
			(xy 278.26335 -44.995338) (xy 278.213312 -44.934378) (xy 278.20569 -44.926015) (xy 278.185244 -44.916396)
			(xy 278.173942 -44.915836) (xy 259.919216 -44.915836) (xy 259.891276 -44.938188) (xy 259.887466 -44.955714)
			(xy 259.881103 -44.982118) (xy 259.861914 -45.032925) (xy 259.835712 -45.080497) (xy 259.803028 -45.123872)
			(xy 259.764522 -45.162173) (xy 259.720973 -45.194625) (xy 259.673262 -45.220572) (xy 259.622353 -45.239489)
			(xy 259.569275 -45.250995) (xy 259.515102 -45.254857) (xy 259.460929 -45.250995) (xy 259.407851 -45.239489)
			(xy 259.356942 -45.220572) (xy 259.309231 -45.194625) (xy 259.265682 -45.162173) (xy 259.227176 -45.123872)
			(xy 259.194492 -45.080497) (xy 259.16829 -45.032925) (xy 259.149101 -44.982118) (xy 259.142738 -44.955714)
			(xy 259.138928 -44.938188) (xy 259.110988 -44.915836) (xy 257.631946 -44.915836) (xy 257.622008 -44.916305)
			(xy 257.603627 -44.923862) (xy 257.589512 -44.937853) (xy 257.58521 -44.946824) (xy 257.549904 -45.030898)
			(xy 257.548061 -45.035579) (xy 257.546016 -45.045428) (xy 257.54584 -45.050456) (xy 257.54584 -45.063918)
			(xy 257.552952 -45.081952) (xy 257.560064 -45.089064) (xy 257.580065 -45.110529) (xy 257.6139 -45.158458)
			(xy 257.639995 -45.211004) (xy 257.657734 -45.266926) (xy 257.666699 -45.324906) (xy 257.667252 -45.35424)
			(xy 257.666764 -45.381491) (xy 257.659003 -45.435436) (xy 257.643644 -45.487729) (xy 257.621002 -45.537304)
			(xy 257.591535 -45.583152) (xy 257.555844 -45.624341) (xy 257.514655 -45.660033) (xy 257.468807 -45.6895)
			(xy 257.419232 -45.712143) (xy 257.36694 -45.727502) (xy 257.312995 -45.735263) (xy 257.285744 -45.735748)
			(xy 257.258895 -45.735287) (xy 257.205729 -45.727753) (xy 257.154144 -45.71284) (xy 257.105158 -45.690843)
			(xy 257.05974 -45.662198) (xy 257.018785 -45.627469) (xy 256.983102 -45.587342) (xy 256.953397 -45.542609)
			(xy 256.930255 -45.494154) (xy 256.914133 -45.442934) (xy 256.905351 -45.38996) (xy 256.904236 -45.36313)
			(xy 256.904236 -45.354748) (xy 256.90473 -45.32523) (xy 256.913708 -45.266882) (xy 256.931565 -45.210613)
			(xy 256.957876 -45.157766) (xy 256.992011 -45.109602) (xy 257.012186 -45.088048) (xy 257.023108 -45.076872)
			(xy 257.028696 -45.047154) (xy 256.986278 -44.946824) (xy 256.981966 -44.937859) (xy 256.967847 -44.92387)
			(xy 256.949478 -44.916281) (xy 256.939542 -44.915836) (xy 253.120906 -44.915836) (xy 253.109618 -44.91644)
			(xy 253.089192 -44.926061) (xy 253.081536 -44.934378) (xy 253.031498 -44.995338) (xy 253.02809 -44.999769)
			(xy 253.023096 -45.009766) (xy 253.021592 -45.01515) (xy 253.018798 -45.02658) (xy 253.021084 -45.03801)
			(xy 253.024753 -45.056911) (xy 253.028695 -45.095212) (xy 253.028958 -45.114464) (xy 253.028497 -45.141717)
			(xy 253.020744 -45.195669) (xy 253.005391 -45.247969) (xy 252.982749 -45.29755) (xy 252.953282 -45.343404)
			(xy 252.917587 -45.384597) (xy 252.876393 -45.42029) (xy 252.830538 -45.449756) (xy 252.780956 -45.472395)
			(xy 252.728656 -45.487747) (xy 252.674703 -45.495498) (xy 252.64745 -45.495972) (xy 252.620196 -45.495512)
			(xy 252.566241 -45.487761) (xy 252.51394 -45.472409) (xy 252.464355 -45.449768) (xy 252.418499 -45.420301)
			(xy 252.377303 -45.384607) (xy 252.341607 -45.343413) (xy 252.312138 -45.297557) (xy 252.289496 -45.247974)
			(xy 252.274142 -45.195672) (xy 252.266389 -45.141718) (xy 252.265942 -45.114464) (xy 252.266221 -45.095213)
			(xy 252.270162 -45.056913) (xy 252.273816 -45.03801) (xy 252.276102 -45.02658) (xy 252.273308 -45.01515)
			(xy 252.271821 -45.00976) (xy 252.266817 -44.999765) (xy 252.263402 -44.995338) (xy 252.213364 -44.934378)
			(xy 252.205746 -44.926006) (xy 252.1853 -44.916367) (xy 252.173994 -44.915836) (xy 221.819216 -44.915836)
			(xy 221.791276 -44.938188) (xy 221.787466 -44.955714) (xy 221.781103 -44.982118) (xy 221.761914 -45.032925)
			(xy 221.735712 -45.080497) (xy 221.703028 -45.123872) (xy 221.664522 -45.162173) (xy 221.620973 -45.194625)
			(xy 221.573262 -45.220572) (xy 221.522353 -45.239489) (xy 221.469275 -45.250995) (xy 221.415102 -45.254857)
			(xy 221.360929 -45.250995) (xy 221.307851 -45.239489) (xy 221.256942 -45.220572) (xy 221.209231 -45.194625)
			(xy 221.165682 -45.162173) (xy 221.127176 -45.123872) (xy 221.094492 -45.080497) (xy 221.06829 -45.032925)
			(xy 221.049101 -44.982118) (xy 221.042738 -44.955714) (xy 221.038928 -44.938188) (xy 221.010988 -44.915836)
			(xy 219.531946 -44.915836) (xy 219.522008 -44.916305) (xy 219.503627 -44.923862) (xy 219.489512 -44.937853)
			(xy 219.48521 -44.946824) (xy 219.449904 -45.030898) (xy 219.448061 -45.035579) (xy 219.446016 -45.045428)
			(xy 219.44584 -45.050456) (xy 219.44584 -45.063918) (xy 219.452952 -45.081952) (xy 219.460064 -45.089064)
			(xy 219.480065 -45.110529) (xy 219.5139 -45.158458) (xy 219.539995 -45.211004) (xy 219.557734 -45.266926)
			(xy 219.566699 -45.324906) (xy 219.567252 -45.35424) (xy 219.566764 -45.381491) (xy 219.559003 -45.435436)
			(xy 219.543644 -45.487729) (xy 219.521002 -45.537304) (xy 219.491535 -45.583152) (xy 219.455844 -45.624341)
			(xy 219.414655 -45.660033) (xy 219.368807 -45.6895) (xy 219.319232 -45.712143) (xy 219.26694 -45.727502)
			(xy 219.212995 -45.735263) (xy 219.185744 -45.735748) (xy 219.158895 -45.735287) (xy 219.105729 -45.727753)
			(xy 219.054144 -45.71284) (xy 219.005158 -45.690843) (xy 218.95974 -45.662198) (xy 218.918785 -45.627469)
			(xy 218.883102 -45.587342) (xy 218.853397 -45.542609) (xy 218.830255 -45.494154) (xy 218.814133 -45.442934)
			(xy 218.805351 -45.38996) (xy 218.804236 -45.36313) (xy 218.804236 -45.354748) (xy 218.80473 -45.32523)
			(xy 218.813708 -45.266882) (xy 218.831565 -45.210613) (xy 218.857876 -45.157766) (xy 218.892011 -45.109602)
			(xy 218.912186 -45.088048) (xy 218.923108 -45.076872) (xy 218.928696 -45.047154) (xy 218.886278 -44.946824)
			(xy 218.881966 -44.937859) (xy 218.867847 -44.92387) (xy 218.849478 -44.916281) (xy 218.839542 -44.915836)
			(xy 215.020906 -44.915836) (xy 215.009618 -44.91644) (xy 214.989192 -44.926061) (xy 214.981536 -44.934378)
			(xy 214.931498 -44.995338) (xy 214.92809 -44.999769) (xy 214.923096 -45.009766) (xy 214.921592 -45.01515)
			(xy 214.918798 -45.02658) (xy 214.921084 -45.03801) (xy 214.924753 -45.056911) (xy 214.928695 -45.095212)
			(xy 214.928958 -45.114464) (xy 214.928497 -45.141717) (xy 214.920744 -45.195669) (xy 214.905391 -45.247969)
			(xy 214.882749 -45.29755) (xy 214.853282 -45.343404) (xy 214.817587 -45.384597) (xy 214.776393 -45.42029)
			(xy 214.730538 -45.449756) (xy 214.680956 -45.472395) (xy 214.628656 -45.487747) (xy 214.574703 -45.495498)
			(xy 214.54745 -45.495972) (xy 214.520196 -45.495512) (xy 214.466241 -45.487761) (xy 214.41394 -45.472409)
			(xy 214.364355 -45.449768) (xy 214.318499 -45.420301) (xy 214.277303 -45.384607) (xy 214.241607 -45.343413)
			(xy 214.212138 -45.297557) (xy 214.189496 -45.247974) (xy 214.174142 -45.195672) (xy 214.166389 -45.141718)
			(xy 214.165942 -45.114464) (xy 214.166221 -45.095213) (xy 214.170162 -45.056913) (xy 214.173816 -45.03801)
			(xy 214.176102 -45.02658) (xy 214.173308 -45.01515) (xy 214.171821 -45.00976) (xy 214.166817 -44.999765)
			(xy 214.163402 -44.995338) (xy 214.113364 -44.934378) (xy 214.105746 -44.926006) (xy 214.0853 -44.916367)
			(xy 214.073994 -44.915836) (xy 195.837048 -44.915836) (xy 195.825622 -44.916477) (xy 195.805027 -44.926384)
			(xy 195.790743 -44.944224) (xy 195.787518 -44.955206) (xy 195.787518 -44.955714) (xy 195.787518 -44.955968)
			(xy 195.781141 -44.982359) (xy 195.761929 -45.033138) (xy 195.735711 -45.080681) (xy 195.703019 -45.124027)
			(xy 195.664512 -45.1623) (xy 195.620967 -45.194728) (xy 195.573266 -45.220655) (xy 195.52237 -45.239558)
			(xy 195.469309 -45.251054) (xy 195.415154 -45.254912) (xy 195.360999 -45.251054) (xy 195.307938 -45.239558)
			(xy 195.257042 -45.220655) (xy 195.209341 -45.194728) (xy 195.165796 -45.1623) (xy 195.127289 -45.124027)
			(xy 195.094597 -45.080681) (xy 195.068379 -45.033138) (xy 195.049167 -44.982359) (xy 195.04279 -44.955968)
			(xy 195.04279 -44.955714) (xy 195.04279 -44.955206) (xy 195.039606 -44.944203) (xy 195.025317 -44.926342)
			(xy 195.004697 -44.916441) (xy 194.99326 -44.915836) (xy 193.531998 -44.915836) (xy 193.522066 -44.916313)
			(xy 193.503699 -44.92388) (xy 193.489598 -44.937873) (xy 193.485262 -44.946824) (xy 193.449956 -45.030898)
			(xy 193.448114 -45.035579) (xy 193.446071 -45.045428) (xy 193.445892 -45.050456) (xy 193.445892 -45.063918)
			(xy 193.453004 -45.081952) (xy 193.460116 -45.089064) (xy 193.480119 -45.110528) (xy 193.513959 -45.158455)
			(xy 193.540057 -45.211001) (xy 193.557798 -45.266924) (xy 193.566764 -45.324905) (xy 193.567304 -45.35424)
			(xy 193.566815 -45.381489) (xy 193.559054 -45.435432) (xy 193.543696 -45.487722) (xy 193.521052 -45.537294)
			(xy 193.491585 -45.583139) (xy 193.455893 -45.624324) (xy 193.414704 -45.660011) (xy 193.368855 -45.689473)
			(xy 193.319281 -45.712111) (xy 193.266989 -45.727464) (xy 193.213045 -45.735219) (xy 193.185796 -45.735748)
			(xy 193.15895 -45.735284) (xy 193.105788 -45.727744) (xy 193.054209 -45.712827) (xy 193.005229 -45.690828)
			(xy 192.959817 -45.662181) (xy 192.918867 -45.627452) (xy 192.88319 -45.587326) (xy 192.853489 -45.542595)
			(xy 192.830351 -45.494144) (xy 192.814232 -45.442927) (xy 192.80545 -45.389957) (xy 192.804288 -45.36313)
			(xy 192.804288 -45.354748) (xy 192.804782 -45.325229) (xy 192.813759 -45.266881) (xy 192.831614 -45.210611)
			(xy 192.857922 -45.157761) (xy 192.892055 -45.109594) (xy 192.912238 -45.088048) (xy 192.92316 -45.076872)
			(xy 192.928748 -45.047154) (xy 192.88633 -44.946824) (xy 192.882015 -44.937864) (xy 192.867894 -44.923888)
			(xy 192.849527 -44.916316) (xy 192.839594 -44.915836) (xy 189.020958 -44.915836) (xy 189.009675 -44.916449)
			(xy 188.989264 -44.926082) (xy 188.981588 -44.934378) (xy 188.93155 -44.995338) (xy 188.928145 -44.99977)
			(xy 188.923155 -45.009769) (xy 188.921644 -45.01515) (xy 188.91885 -45.02658) (xy 188.921136 -45.03801)
			(xy 188.924804 -45.056911) (xy 188.928746 -45.095212) (xy 188.92901 -45.114464) (xy 188.928549 -45.141719)
			(xy 188.920796 -45.195674) (xy 188.905443 -45.247976) (xy 188.882803 -45.297561) (xy 188.853336 -45.343418)
			(xy 188.817642 -45.384615) (xy 188.776449 -45.420313) (xy 188.730594 -45.449785) (xy 188.681011 -45.47243)
			(xy 188.628711 -45.487788) (xy 188.574757 -45.495546) (xy 188.547502 -45.495972) (xy 188.52025 -45.495509)
			(xy 188.466301 -45.487752) (xy 188.414005 -45.472396) (xy 188.364427 -45.449753) (xy 188.318576 -45.420284)
			(xy 188.277386 -45.38459) (xy 188.241695 -45.343397) (xy 188.212231 -45.297543) (xy 188.189592 -45.247963)
			(xy 188.174241 -45.195666) (xy 188.166489 -45.141716) (xy 188.165994 -45.114464) (xy 188.166273 -45.095213)
			(xy 188.170214 -45.056913) (xy 188.173868 -45.03801) (xy 188.176154 -45.02658) (xy 188.17336 -45.01515)
			(xy 188.171872 -45.009761) (xy 188.166864 -44.999769) (xy 188.163454 -44.995338) (xy 188.113416 -44.934378)
			(xy 188.105795 -44.926014) (xy 188.085348 -44.916394) (xy 188.074046 -44.915836) (xy 169.8371 -44.915836)
			(xy 169.825667 -44.916467) (xy 169.805052 -44.926363) (xy 169.790752 -44.944207) (xy 169.78757 -44.955206)
			(xy 169.78757 -44.955714) (xy 169.78757 -44.955968) (xy 169.781193 -44.982359) (xy 169.761981 -45.033138)
			(xy 169.735763 -45.080681) (xy 169.703071 -45.124027) (xy 169.664564 -45.1623) (xy 169.621019 -45.194728)
			(xy 169.573318 -45.220655) (xy 169.522422 -45.239558) (xy 169.469361 -45.251054) (xy 169.415206 -45.254912)
			(xy 169.361051 -45.251054) (xy 169.30799 -45.239558) (xy 169.257094 -45.220655) (xy 169.209393 -45.194728)
			(xy 169.165848 -45.1623) (xy 169.127341 -45.124027) (xy 169.094649 -45.080681) (xy 169.068431 -45.033138)
			(xy 169.049219 -44.982359) (xy 169.042842 -44.955968) (xy 169.042842 -44.955714) (xy 169.042842 -44.955206)
			(xy 169.039656 -44.944208) (xy 169.025364 -44.92636) (xy 169.004746 -44.916478) (xy 168.993312 -44.915836)
			(xy 167.53205 -44.915836) (xy 167.522112 -44.916304) (xy 167.503729 -44.92386) (xy 167.489613 -44.937852)
			(xy 167.485314 -44.946824) (xy 167.450008 -45.030898) (xy 167.448165 -45.035579) (xy 167.44612 -45.045428)
			(xy 167.445944 -45.050456) (xy 167.445944 -45.063918) (xy 167.453056 -45.081952) (xy 167.460168 -45.089064)
			(xy 167.480169 -45.110529) (xy 167.514004 -45.158458) (xy 167.540098 -45.211004) (xy 167.557837 -45.266926)
			(xy 167.566802 -45.324906) (xy 167.567356 -45.35424) (xy 167.566868 -45.381491) (xy 167.559107 -45.435437)
			(xy 167.543749 -45.487729) (xy 167.521106 -45.537305) (xy 167.491639 -45.583153) (xy 167.455948 -45.624343)
			(xy 167.41476 -45.660034) (xy 167.368912 -45.689502) (xy 167.319337 -45.712146) (xy 167.267044 -45.727505)
			(xy 167.213099 -45.735267) (xy 167.185848 -45.735748) (xy 167.158999 -45.735287) (xy 167.105833 -45.727753)
			(xy 167.054247 -45.712841) (xy 167.005261 -45.690845) (xy 166.959842 -45.662199) (xy 166.918886 -45.62747)
			(xy 166.883203 -45.587343) (xy 166.853498 -45.54261) (xy 166.830355 -45.494155) (xy 166.814234 -45.442935)
			(xy 166.805451 -45.38996) (xy 166.80434 -45.36313) (xy 166.80434 -45.354748) (xy 166.804834 -45.32523)
			(xy 166.813812 -45.266882) (xy 166.831669 -45.210613) (xy 166.85798 -45.157766) (xy 166.892116 -45.109602)
			(xy 166.91229 -45.088048) (xy 166.923212 -45.076872) (xy 166.9288 -45.047154) (xy 166.886382 -44.946824)
			(xy 166.882065 -44.937869) (xy 166.867942 -44.923907) (xy 166.849575 -44.916351) (xy 166.839646 -44.915836)
			(xy 163.02101 -44.915836) (xy 163.009721 -44.916439) (xy 162.989294 -44.926059) (xy 162.98164 -44.934378)
			(xy 162.931602 -44.995338) (xy 162.928194 -44.999769) (xy 162.923199 -45.009766) (xy 162.921696 -45.01515)
			(xy 162.918902 -45.02658) (xy 162.921188 -45.03801) (xy 162.924857 -45.056911) (xy 162.928799 -45.095212)
			(xy 162.929062 -45.114464) (xy 162.928601 -45.141717) (xy 162.920848 -45.19567) (xy 162.905495 -45.247969)
			(xy 162.882854 -45.297551) (xy 162.853386 -45.343405) (xy 162.817691 -45.384599) (xy 162.776497 -45.420292)
			(xy 162.730642 -45.449758) (xy 162.68106 -45.472398) (xy 162.62876 -45.48775) (xy 162.574807 -45.495502)
			(xy 162.547554 -45.495972) (xy 162.520306 -45.495483) (xy 162.466365 -45.487721) (xy 162.414078 -45.472361)
			(xy 162.364509 -45.449717) (xy 162.318667 -45.420249) (xy 162.277485 -45.384557) (xy 162.241802 -45.343367)
			(xy 162.212344 -45.297519) (xy 162.18971 -45.247945) (xy 162.174362 -45.195655) (xy 162.166612 -45.141712)
			(xy 162.166046 -45.114464) (xy 162.166325 -45.095213) (xy 162.170266 -45.056913) (xy 162.17392 -45.03801)
			(xy 162.176206 -45.02658) (xy 162.173412 -45.01515) (xy 162.171925 -45.00976) (xy 162.166922 -44.999765)
			(xy 162.163506 -44.995338) (xy 162.113468 -44.934378) (xy 162.10585 -44.926006) (xy 162.085404 -44.916364)
			(xy 162.074098 -44.915836) (xy 143.837152 -44.915836) (xy 143.825725 -44.916476) (xy 143.805129 -44.926382)
			(xy 143.790844 -44.944223) (xy 143.787622 -44.955206) (xy 143.787622 -44.955714) (xy 143.787622 -44.955968)
			(xy 143.781245 -44.982359) (xy 143.762033 -45.033138) (xy 143.735815 -45.080681) (xy 143.703123 -45.124027)
			(xy 143.664616 -45.1623) (xy 143.621071 -45.194728) (xy 143.57337 -45.220655) (xy 143.522474 -45.239558)
			(xy 143.469413 -45.251054) (xy 143.415258 -45.254912) (xy 143.361103 -45.251054) (xy 143.308042 -45.239558)
			(xy 143.257146 -45.220655) (xy 143.209445 -45.194728) (xy 143.1659 -45.1623) (xy 143.127393 -45.124027)
			(xy 143.094701 -45.080681) (xy 143.068483 -45.033138) (xy 143.049271 -44.982359) (xy 143.042894 -44.955968)
			(xy 143.042894 -44.955714) (xy 143.042894 -44.955206) (xy 143.03971 -44.944203) (xy 143.025421 -44.92634)
			(xy 143.004802 -44.916438) (xy 142.993364 -44.915836) (xy 141.532102 -44.915836) (xy 141.522169 -44.916313)
			(xy 141.503801 -44.923879) (xy 141.4897 -44.937871) (xy 141.485366 -44.946824) (xy 141.45006 -45.030898)
			(xy 141.448218 -45.035579) (xy 141.446175 -45.045428) (xy 141.445996 -45.050456) (xy 141.445996 -45.063918)
			(xy 141.453108 -45.081952) (xy 141.46022 -45.089064) (xy 141.480223 -45.110528) (xy 141.514062 -45.158456)
			(xy 141.54016 -45.211001) (xy 141.557901 -45.266924) (xy 141.566867 -45.324905) (xy 141.567408 -45.35424)
			(xy 141.566919 -45.381489) (xy 141.559158 -45.435433) (xy 141.5438 -45.487723) (xy 141.521156 -45.537295)
			(xy 141.491689 -45.58314) (xy 141.455997 -45.624326) (xy 141.414808 -45.660013) (xy 141.36896 -45.689476)
			(xy 141.319385 -45.712114) (xy 141.267094 -45.727467) (xy 141.213149 -45.735222) (xy 141.1859 -45.735748)
			(xy 141.159053 -45.735284) (xy 141.105892 -45.727745) (xy 141.054312 -45.712828) (xy 141.005332 -45.690829)
			(xy 140.959919 -45.662182) (xy 140.918969 -45.627453) (xy 140.883291 -45.587327) (xy 140.85359 -45.542596)
			(xy 140.830451 -45.494144) (xy 140.814332 -45.442928) (xy 140.80555 -45.389957) (xy 140.804392 -45.36313)
			(xy 140.804392 -45.354748) (xy 140.804886 -45.325229) (xy 140.813863 -45.266881) (xy 140.831718 -45.210611)
			(xy 140.858027 -45.157762) (xy 140.89216 -45.109595) (xy 140.912342 -45.088048) (xy 140.923264 -45.076872)
			(xy 140.928852 -45.047154) (xy 140.886434 -44.946824) (xy 140.882119 -44.937863) (xy 140.867999 -44.923887)
			(xy 140.849631 -44.916313) (xy 140.839698 -44.915836) (xy 137.021062 -44.915836) (xy 137.009778 -44.916449)
			(xy 136.989366 -44.92608) (xy 136.981692 -44.934378) (xy 136.931654 -44.995338) (xy 136.928249 -44.99977)
			(xy 136.923259 -45.009768) (xy 136.921748 -45.01515) (xy 136.918954 -45.02658) (xy 136.92124 -45.03801)
			(xy 136.924908 -45.056911) (xy 136.92885 -45.095212) (xy 136.929114 -45.114464) (xy 136.928653 -45.141719)
			(xy 136.9209 -45.195674) (xy 136.905547 -45.247976) (xy 136.882907 -45.297561) (xy 136.85344 -45.343419)
			(xy 136.817747 -45.384617) (xy 136.776553 -45.420315) (xy 136.730698 -45.449787) (xy 136.681116 -45.472433)
			(xy 136.628815 -45.487791) (xy 136.574861 -45.49555) (xy 136.547606 -45.495972) (xy 136.520354 -45.495509)
			(xy 136.466404 -45.487753) (xy 136.414108 -45.472397) (xy 136.364529 -45.449754) (xy 136.318678 -45.420286)
			(xy 136.277487 -45.384591) (xy 136.241796 -45.343398) (xy 136.212332 -45.297545) (xy 136.189693 -45.247964)
			(xy 136.174341 -45.195666) (xy 136.166589 -45.141716) (xy 136.166098 -45.114464) (xy 136.166377 -45.095213)
			(xy 136.170318 -45.056913) (xy 136.173972 -45.03801) (xy 136.176258 -45.02658) (xy 136.173464 -45.01515)
			(xy 136.171976 -45.009761) (xy 136.166969 -44.999768) (xy 136.163558 -44.995338) (xy 136.11352 -44.934378)
			(xy 136.105899 -44.926014) (xy 136.085453 -44.916392) (xy 136.07415 -44.915836) (xy 105.736898 -44.915836)
			(xy 105.725465 -44.916467) (xy 105.704851 -44.926364) (xy 105.690551 -44.944208) (xy 105.687368 -44.955206)
			(xy 105.687368 -44.955714) (xy 105.687368 -44.955968) (xy 105.680991 -44.982359) (xy 105.661779 -45.033138)
			(xy 105.635561 -45.080681) (xy 105.602869 -45.124027) (xy 105.564362 -45.1623) (xy 105.520817 -45.194728)
			(xy 105.473116 -45.220655) (xy 105.42222 -45.239558) (xy 105.369159 -45.251054) (xy 105.315004 -45.254912)
			(xy 105.260849 -45.251054) (xy 105.207788 -45.239558) (xy 105.156892 -45.220655) (xy 105.109191 -45.194728)
			(xy 105.065646 -45.1623) (xy 105.027139 -45.124027) (xy 104.994447 -45.080681) (xy 104.968229 -45.033138)
			(xy 104.949017 -44.982359) (xy 104.94264 -44.955968) (xy 104.94264 -44.955714) (xy 104.94264 -44.955206)
			(xy 104.939454 -44.944208) (xy 104.925162 -44.926361) (xy 104.904543 -44.916479) (xy 104.89311 -44.915836)
			(xy 103.431848 -44.915836) (xy 103.42191 -44.916304) (xy 103.403528 -44.923861) (xy 103.389412 -44.937852)
			(xy 103.385112 -44.946824) (xy 103.349806 -45.030898) (xy 103.347963 -45.035579) (xy 103.345918 -45.045428)
			(xy 103.345742 -45.050456) (xy 103.345742 -45.063918) (xy 103.352854 -45.081952) (xy 103.359966 -45.089064)
			(xy 103.379967 -45.110529) (xy 103.413802 -45.158458) (xy 103.439897 -45.211004) (xy 103.457636 -45.266926)
			(xy 103.4666 -45.324906) (xy 103.467154 -45.35424) (xy 103.466668 -45.381491) (xy 103.458912 -45.435439)
			(xy 103.443557 -45.487734) (xy 103.420915 -45.537311) (xy 103.391449 -45.583161) (xy 103.355758 -45.624352)
			(xy 103.314567 -45.660043) (xy 103.268717 -45.689509) (xy 103.21914 -45.712151) (xy 103.166845 -45.727506)
			(xy 103.112897 -45.735262) (xy 103.058395 -45.735262) (xy 103.004447 -45.727506) (xy 102.952152 -45.712151)
			(xy 102.902575 -45.689509) (xy 102.856725 -45.660043) (xy 102.815534 -45.624352) (xy 102.779843 -45.583161)
			(xy 102.750377 -45.537311) (xy 102.727735 -45.487734) (xy 102.71238 -45.435439) (xy 102.704624 -45.381491)
			(xy 102.704138 -45.35424) (xy 102.704685 -45.324835) (xy 102.713715 -45.266724) (xy 102.731553 -45.210685)
			(xy 102.757775 -45.158045) (xy 102.791761 -45.110051) (xy 102.811834 -45.088556) (xy 102.812088 -45.088302)
			(xy 102.812596 -45.087794) (xy 102.81734 -45.082403) (xy 102.823908 -45.069639) (xy 102.82555 -45.062648)
			(xy 102.82555 -45.062394) (xy 102.826715 -45.054952) (xy 102.825169 -45.039975) (xy 102.822502 -45.03293)
			(xy 102.78618 -44.946824) (xy 102.781863 -44.937869) (xy 102.76774 -44.923908) (xy 102.749373 -44.916353)
			(xy 102.739444 -44.915836) (xy 98.920808 -44.915836) (xy 98.90952 -44.916439) (xy 98.889093 -44.92606)
			(xy 98.881438 -44.934378) (xy 98.8314 -44.995338) (xy 98.827992 -44.999769) (xy 98.822998 -45.009766)
			(xy 98.821494 -45.01515) (xy 98.8187 -45.02658) (xy 98.820986 -45.03801) (xy 98.824655 -45.056911)
			(xy 98.828597 -45.095212) (xy 98.82886 -45.114464) (xy 98.828399 -45.141717) (xy 98.820646 -45.19567)
			(xy 98.805293 -45.247969) (xy 98.782651 -45.297551) (xy 98.753184 -45.343405) (xy 98.717489 -45.384598)
			(xy 98.676295 -45.420291) (xy 98.63044 -45.449757) (xy 98.580858 -45.472397) (xy 98.528558 -45.487749)
			(xy 98.474605 -45.4955) (xy 98.447352 -45.495972) (xy 98.420104 -45.495482) (xy 98.366163 -45.48772)
			(xy 98.313877 -45.472361) (xy 98.264308 -45.449716) (xy 98.218466 -45.420248) (xy 98.177284 -45.384556)
			(xy 98.141602 -45.343367) (xy 98.112144 -45.297518) (xy 98.08951 -45.247945) (xy 98.074162 -45.195654)
			(xy 98.066412 -45.141712) (xy 98.065844 -45.114464) (xy 98.066123 -45.095213) (xy 98.070064 -45.056913)
			(xy 98.073718 -45.03801) (xy 98.076004 -45.02658) (xy 98.07321 -45.01515) (xy 98.071723 -45.00976)
			(xy 98.06672 -44.999765) (xy 98.063304 -44.995338) (xy 98.013266 -44.934378) (xy 98.005648 -44.926006)
			(xy 97.985202 -44.916366) (xy 97.973896 -44.915836) (xy 79.73695 -44.915836) (xy 79.725524 -44.916477)
			(xy 79.704928 -44.926383) (xy 79.690644 -44.944223) (xy 79.68742 -44.955206) (xy 79.68742 -44.955714)
			(xy 79.68742 -44.955968) (xy 79.681043 -44.982359) (xy 79.661831 -45.033138) (xy 79.635613 -45.080681)
			(xy 79.602921 -45.124027) (xy 79.564414 -45.1623) (xy 79.520869 -45.194728) (xy 79.473168 -45.220655)
			(xy 79.422272 -45.239558) (xy 79.369211 -45.251054) (xy 79.315056 -45.254912) (xy 79.260901 -45.251054)
			(xy 79.20784 -45.239558) (xy 79.156944 -45.220655) (xy 79.109243 -45.194728) (xy 79.065698 -45.1623)
			(xy 79.027191 -45.124027) (xy 78.994499 -45.080681) (xy 78.968281 -45.033138) (xy 78.949069 -44.982359)
			(xy 78.942692 -44.955968) (xy 78.942692 -44.955714) (xy 78.942692 -44.955206) (xy 78.939508 -44.944203)
			(xy 78.925219 -44.926341) (xy 78.904599 -44.916439) (xy 78.893162 -44.915836) (xy 77.4319 -44.915836)
			(xy 77.421967 -44.916313) (xy 77.4036 -44.92388) (xy 77.389499 -44.937872) (xy 77.385164 -44.946824)
			(xy 77.349858 -45.030898) (xy 77.348016 -45.035579) (xy 77.345973 -45.045428) (xy 77.345794 -45.050456)
			(xy 77.345794 -45.063918) (xy 77.352906 -45.081952) (xy 77.360018 -45.089064) (xy 77.380021 -45.110528)
			(xy 77.41386 -45.158456) (xy 77.439958 -45.211001) (xy 77.4577 -45.266924) (xy 77.466665 -45.324905)
			(xy 77.467206 -45.35424) (xy 77.466717 -45.381489) (xy 77.458956 -45.435433) (xy 77.443598 -45.487722)
			(xy 77.420954 -45.537295) (xy 77.391487 -45.58314) (xy 77.355795 -45.624325) (xy 77.314606 -45.660012)
			(xy 77.268758 -45.689474) (xy 77.219183 -45.712112) (xy 77.166892 -45.727465) (xy 77.112947 -45.73522)
			(xy 77.085698 -45.735748) (xy 77.058851 -45.735284) (xy 77.00569 -45.727744) (xy 76.95411 -45.712827)
			(xy 76.90513 -45.690828) (xy 76.859718 -45.662182) (xy 76.818768 -45.627452) (xy 76.783091 -45.587326)
			(xy 76.753389 -45.542596) (xy 76.730251 -45.494144) (xy 76.714132 -45.442927) (xy 76.70535 -45.389957)
			(xy 76.70419 -45.36313) (xy 76.70419 -45.354748) (xy 76.704684 -45.325229) (xy 76.713661 -45.266881)
			(xy 76.731516 -45.210611) (xy 76.757825 -45.157762) (xy 76.791958 -45.109595) (xy 76.81214 -45.088048)
			(xy 76.823062 -45.076872) (xy 76.82865 -45.047154) (xy 76.786232 -44.946824) (xy 76.781917 -44.937864)
			(xy 76.767797 -44.923888) (xy 76.749429 -44.916315) (xy 76.739496 -44.915836) (xy 72.92086 -44.915836)
			(xy 72.909576 -44.916449) (xy 72.889165 -44.926081) (xy 72.88149 -44.934378) (xy 72.831452 -44.995338)
			(xy 72.828047 -44.99977) (xy 72.823057 -45.009769) (xy 72.821546 -45.01515) (xy 72.818752 -45.02658)
			(xy 72.821038 -45.03801) (xy 72.824706 -45.056911) (xy 72.828648 -45.095212) (xy 72.828912 -45.114464)
			(xy 72.828451 -45.141719) (xy 72.820698 -45.195674) (xy 72.805345 -45.247976) (xy 72.782705 -45.297561)
			(xy 72.753238 -45.343419) (xy 72.717545 -45.384616) (xy 72.676351 -45.420314) (xy 72.630496 -45.449786)
			(xy 72.580914 -45.472431) (xy 72.528613 -45.48779) (xy 72.474659 -45.495548) (xy 72.447404 -45.495972)
			(xy 72.420152 -45.495509) (xy 72.366202 -45.487752) (xy 72.313906 -45.472396) (xy 72.264328 -45.449753)
			(xy 72.218477 -45.420285) (xy 72.177287 -45.384591) (xy 72.141596 -45.343398) (xy 72.112131 -45.297544)
			(xy 72.089493 -45.247964) (xy 72.074141 -45.195666) (xy 72.066389 -45.141716) (xy 72.065896 -45.114464)
			(xy 72.066175 -45.095213) (xy 72.070116 -45.056913) (xy 72.07377 -45.03801) (xy 72.076056 -45.02658)
			(xy 72.073262 -45.01515) (xy 72.071774 -45.009761) (xy 72.066766 -44.999769) (xy 72.063356 -44.995338)
			(xy 72.013318 -44.934378) (xy 72.005697 -44.926014) (xy 71.985251 -44.916393) (xy 71.973948 -44.915836)
			(xy 53.737002 -44.915836) (xy 53.725568 -44.916466) (xy 53.704953 -44.926363) (xy 53.690652 -44.944206)
			(xy 53.687472 -44.955206) (xy 53.687472 -44.955714) (xy 53.687472 -44.955968) (xy 53.681095 -44.982359)
			(xy 53.661883 -45.033138) (xy 53.635665 -45.080681) (xy 53.602973 -45.124027) (xy 53.564466 -45.1623)
			(xy 53.520921 -45.194728) (xy 53.47322 -45.220655) (xy 53.422324 -45.239558) (xy 53.369263 -45.251054)
			(xy 53.315108 -45.254912) (xy 53.260953 -45.251054) (xy 53.207892 -45.239558) (xy 53.156996 -45.220655)
			(xy 53.109295 -45.194728) (xy 53.06575 -45.1623) (xy 53.027243 -45.124027) (xy 52.994551 -45.080681)
			(xy 52.968333 -45.033138) (xy 52.949121 -44.982359) (xy 52.942744 -44.955968) (xy 52.942744 -44.955714)
			(xy 52.942744 -44.955206) (xy 52.939558 -44.944208) (xy 52.925267 -44.926359) (xy 52.904648 -44.916476)
			(xy 52.893214 -44.915836) (xy 51.431952 -44.915836) (xy 51.422014 -44.916304) (xy 51.40363 -44.923859)
			(xy 51.389513 -44.937851) (xy 51.385216 -44.946824) (xy 51.34991 -45.030898) (xy 51.348066 -45.035579)
			(xy 51.346022 -45.045428) (xy 51.345846 -45.050456) (xy 51.345846 -45.063918) (xy 51.352958 -45.081952)
			(xy 51.36007 -45.089064) (xy 51.380071 -45.110529) (xy 51.413905 -45.158458) (xy 51.44 -45.211004)
			(xy 51.457739 -45.266926) (xy 51.466703 -45.324906) (xy 51.467258 -45.35424) (xy 51.466772 -45.381491)
			(xy 51.459016 -45.435439) (xy 51.443661 -45.487734) (xy 51.421019 -45.537311) (xy 51.391553 -45.583161)
			(xy 51.355862 -45.624352) (xy 51.314671 -45.660043) (xy 51.268821 -45.689509) (xy 51.219244 -45.712151)
			(xy 51.166949 -45.727506) (xy 51.113001 -45.735262) (xy 51.058499 -45.735262) (xy 51.004551 -45.727506)
			(xy 50.952256 -45.712151) (xy 50.902679 -45.689509) (xy 50.856829 -45.660043) (xy 50.815638 -45.624352)
			(xy 50.779947 -45.583161) (xy 50.750481 -45.537311) (xy 50.727839 -45.487734) (xy 50.712484 -45.435439)
			(xy 50.704728 -45.381491) (xy 50.704242 -45.35424) (xy 50.704789 -45.324835) (xy 50.713819 -45.266724)
			(xy 50.731657 -45.210685) (xy 50.757879 -45.158045) (xy 50.791866 -45.110051) (xy 50.811938 -45.088556)
			(xy 50.812192 -45.088302) (xy 50.8127 -45.087794) (xy 50.817444 -45.082403) (xy 50.824011 -45.069639)
			(xy 50.825654 -45.062648) (xy 50.825654 -45.062394) (xy 50.826819 -45.054952) (xy 50.825273 -45.039975)
			(xy 50.822606 -45.03293) (xy 50.786284 -44.946824) (xy 50.781967 -44.937869) (xy 50.767844 -44.923906)
			(xy 50.749478 -44.91635) (xy 50.739548 -44.915836) (xy 46.920912 -44.915836) (xy 46.909623 -44.916439)
			(xy 46.889195 -44.926058) (xy 46.881542 -44.934378) (xy 46.831504 -44.995338) (xy 46.828096 -44.999769)
			(xy 46.823101 -45.009766) (xy 46.821598 -45.01515) (xy 46.818804 -45.02658) (xy 46.82109 -45.03801)
			(xy 46.824759 -45.056911) (xy 46.828701 -45.095212) (xy 46.828964 -45.114464) (xy 46.828503 -45.141717)
			(xy 46.82075 -45.19567) (xy 46.805397 -45.24797) (xy 46.782756 -45.297551) (xy 46.753288 -45.343406)
			(xy 46.717594 -45.384599) (xy 46.676399 -45.420293) (xy 46.630544 -45.449759) (xy 46.580962 -45.472399)
			(xy 46.528662 -45.487752) (xy 46.474709 -45.495504) (xy 46.447456 -45.495972) (xy 46.420208 -45.495483)
			(xy 46.366267 -45.487721) (xy 46.313979 -45.472362) (xy 46.26441 -45.449717) (xy 46.218568 -45.420249)
			(xy 46.177386 -45.384557) (xy 46.141703 -45.343368) (xy 46.112244 -45.29752) (xy 46.08961 -45.247946)
			(xy 46.074262 -45.195655) (xy 46.066512 -45.141712) (xy 46.065948 -45.114464) (xy 46.066227 -45.095213)
			(xy 46.070168 -45.056913) (xy 46.073822 -45.03801) (xy 46.076108 -45.02658) (xy 46.073314 -45.01515)
			(xy 46.071827 -45.00976) (xy 46.066824 -44.999765) (xy 46.063408 -44.995338) (xy 46.01337 -44.934378)
			(xy 46.005752 -44.926005) (xy 45.985306 -44.916363) (xy 45.974 -44.915836) (xy 27.737054 -44.915836)
			(xy 27.725627 -44.916476) (xy 27.70503 -44.926381) (xy 27.690744 -44.944222) (xy 27.687524 -44.955206)
			(xy 27.687524 -44.955714) (xy 27.687524 -44.955968) (xy 27.681147 -44.982359) (xy 27.661935 -45.033138)
			(xy 27.635717 -45.080681) (xy 27.603025 -45.124027) (xy 27.564518 -45.1623) (xy 27.520973 -45.194728)
			(xy 27.473272 -45.220655) (xy 27.422376 -45.239558) (xy 27.369315 -45.251054) (xy 27.31516 -45.254912)
			(xy 27.261005 -45.251054) (xy 27.207944 -45.239558) (xy 27.157048 -45.220655) (xy 27.109347 -45.194728)
			(xy 27.065802 -45.1623) (xy 27.027295 -45.124027) (xy 26.994603 -45.080681) (xy 26.968385 -45.033138)
			(xy 26.949173 -44.982359) (xy 26.942796 -44.955968) (xy 26.942796 -44.955714) (xy 26.942796 -44.955206)
			(xy 26.939612 -44.944203) (xy 26.925324 -44.926339) (xy 26.904704 -44.916436) (xy 26.893266 -44.915836)
			(xy 25.432004 -44.915836) (xy 25.422071 -44.916312) (xy 25.403702 -44.923878) (xy 25.3896 -44.937871)
			(xy 25.385268 -44.946824) (xy 25.349962 -45.030898) (xy 25.34812 -45.035579) (xy 25.346077 -45.045428)
			(xy 25.345898 -45.050456) (xy 25.345898 -45.063918) (xy 25.35301 -45.081952) (xy 25.360122 -45.089064)
			(xy 25.380125 -45.110528) (xy 25.413964 -45.158456) (xy 25.440062 -45.211001) (xy 25.457803 -45.266924)
			(xy 25.466768 -45.324905) (xy 25.46731 -45.35424) (xy 25.466821 -45.381489) (xy 25.45906 -45.435433)
			(xy 25.443702 -45.487723) (xy 25.421058 -45.537295) (xy 25.391591 -45.583141) (xy 25.3559 -45.624326)
			(xy 25.31471 -45.660014) (xy 25.268862 -45.689477) (xy 25.219287 -45.712115) (xy 25.166996 -45.727468)
			(xy 25.113051 -45.735224) (xy 25.085802 -45.735748) (xy 25.058955 -45.735284) (xy 25.005793 -45.727745)
			(xy 24.954213 -45.712829) (xy 24.905233 -45.69083) (xy 24.859819 -45.662183) (xy 24.81887 -45.627454)
			(xy 24.783192 -45.587328) (xy 24.75349 -45.542597) (xy 24.730351 -45.494145) (xy 24.714232 -45.442928)
			(xy 24.70545 -45.389957) (xy 24.704294 -45.36313) (xy 24.704294 -45.354748) (xy 24.704788 -45.325229)
			(xy 24.713765 -45.266881) (xy 24.731621 -45.210611) (xy 24.757929 -45.157762) (xy 24.792062 -45.109595)
			(xy 24.812244 -45.088048) (xy 24.823166 -45.076872) (xy 24.828754 -45.047154) (xy 24.786336 -44.946824)
			(xy 24.782022 -44.937863) (xy 24.767901 -44.923886) (xy 24.749533 -44.916312) (xy 24.7396 -44.915836)
			(xy 24.536146 -44.915836) (xy 24.526081 -44.91627) (xy 24.507494 -44.924002) (xy 24.500078 -44.930822)
			(xy 23.796498 -45.634402) (xy 23.789447 -45.642072) (xy 23.781704 -45.66139) (xy 23.782326 -45.682193)
			(xy 23.786338 -45.691806) (xy 23.786338 -45.69206) (xy 23.79769 -45.717509) (xy 23.813733 -45.770872)
			(xy 23.821866 -45.825997) (xy 23.822406 -45.853858) (xy 23.821946 -45.881113) (xy 23.820826 -45.88891)
			(xy 26.933142 -45.88891) (xy 26.937213 -45.833288) (xy 26.949339 -45.778851) (xy 26.969262 -45.72676)
			(xy 26.996558 -45.678125) (xy 27.030644 -45.633982) (xy 27.070793 -45.595273) (xy 27.116151 -45.562822)
			(xy 27.165751 -45.537321) (xy 27.218535 -45.519314) (xy 27.273378 -45.509184) (xy 27.329112 -45.507147)
			(xy 27.384549 -45.513247) (xy 27.438506 -45.527353) (xy 27.489835 -45.549165) (xy 27.537441 -45.578219)
			(xy 27.580309 -45.613894) (xy 27.617526 -45.655431) (xy 27.648299 -45.701944) (xy 27.671971 -45.752441)
			(xy 27.688039 -45.805848) (xy 27.696159 -45.861024) (xy 27.696668 -45.88891) (xy 27.696159 -45.916796)
			(xy 27.688039 -45.971972) (xy 27.671971 -46.025379) (xy 27.648299 -46.075876) (xy 27.644112 -46.082204)
			(xy 44.05249 -46.082204) (xy 44.052959 -46.054951) (xy 44.060715 -46.001001) (xy 44.076071 -45.948703)
			(xy 44.098713 -45.899123) (xy 44.12818 -45.85327) (xy 44.163873 -45.812077) (xy 44.205065 -45.776384)
			(xy 44.250918 -45.746916) (xy 44.300497 -45.724273) (xy 44.352795 -45.708917) (xy 44.406745 -45.701159)
			(xy 44.433998 -45.700696) (xy 44.460889 -45.701184) (xy 44.514138 -45.708732) (xy 44.5658 -45.723678)
			(xy 44.614854 -45.745726) (xy 44.660328 -45.774441) (xy 44.701322 -45.809254) (xy 44.737025 -45.849475)
			(xy 44.75226 -45.871638) (xy 44.759372 -45.882814) (xy 44.782232 -45.894752) (xy 44.881292 -45.892974)
			(xy 44.88979 -45.892482) (xy 44.905767 -45.886644) (xy 44.91896 -45.875907) (xy 44.92371 -45.868844)
			(xy 44.92371 -45.86859) (xy 44.938638 -45.844993) (xy 44.974316 -45.802041) (xy 45.015873 -45.764748)
			(xy 45.062422 -45.73391) (xy 45.112969 -45.710186) (xy 45.166433 -45.694082) (xy 45.221674 -45.685943)
			(xy 45.249592 -45.685456) (xy 45.276585 -45.685922) (xy 45.330033 -45.693527) (xy 45.381876 -45.708586)
			(xy 45.431081 -45.730799) (xy 45.476665 -45.759722) (xy 45.497496 -45.776896) (xy 45.505878 -45.784008)
			(xy 45.526198 -45.790104) (xy 45.611288 -45.779182) (xy 45.616649 -45.778447) (xy 45.626898 -45.774987)
			(xy 45.631608 -45.772324) (xy 45.640498 -45.766736) (xy 45.646848 -45.757846) (xy 45.647102 -45.757592)
			(xy 45.662475 -45.736408) (xy 45.698037 -45.698006) (xy 45.738521 -45.664833) (xy 45.783164 -45.637513)
			(xy 45.831126 -45.616561) (xy 45.881505 -45.602371) (xy 45.933352 -45.59521) (xy 45.959522 -45.594778)
			(xy 45.986771 -45.595294) (xy 46.040714 -45.603053) (xy 46.093005 -45.618409) (xy 46.142577 -45.64105)
			(xy 46.188423 -45.670516) (xy 46.229609 -45.706206) (xy 46.265297 -45.747395) (xy 46.29476 -45.793242)
			(xy 46.317399 -45.842816) (xy 46.323997 -45.865288) (xy 47.869346 -45.865288) (xy 47.873417 -45.809666)
			(xy 47.885543 -45.755229) (xy 47.905466 -45.703138) (xy 47.932762 -45.654503) (xy 47.966848 -45.61036)
			(xy 48.006997 -45.571651) (xy 48.052355 -45.5392) (xy 48.101955 -45.513699) (xy 48.154739 -45.495692)
			(xy 48.209582 -45.485562) (xy 48.265316 -45.483525) (xy 48.320753 -45.489625) (xy 48.37471 -45.503731)
			(xy 48.426039 -45.525543) (xy 48.473645 -45.554597) (xy 48.516513 -45.590272) (xy 48.55373 -45.631809)
			(xy 48.584503 -45.678322) (xy 48.608175 -45.728819) (xy 48.624243 -45.782226) (xy 48.632363 -45.837402)
			(xy 48.632663 -45.853858) (xy 49.058828 -45.853858) (xy 49.062899 -45.798236) (xy 49.075025 -45.743799)
			(xy 49.094948 -45.691708) (xy 49.122244 -45.643073) (xy 49.15633 -45.59893) (xy 49.196479 -45.560221)
			(xy 49.241837 -45.52777) (xy 49.291437 -45.502269) (xy 49.344221 -45.484262) (xy 49.399064 -45.474132)
			(xy 49.454798 -45.472095) (xy 49.510235 -45.478195) (xy 49.564192 -45.492301) (xy 49.615521 -45.514113)
			(xy 49.663127 -45.543167) (xy 49.705995 -45.578842) (xy 49.743212 -45.620379) (xy 49.773985 -45.666892)
			(xy 49.797657 -45.717389) (xy 49.813725 -45.770796) (xy 49.821845 -45.825972) (xy 49.822354 -45.853858)
			(xy 49.821845 -45.881744) (xy 49.82079 -45.88891) (xy 52.93309 -45.88891) (xy 52.937161 -45.833288)
			(xy 52.949287 -45.778851) (xy 52.96921 -45.72676) (xy 52.996506 -45.678125) (xy 53.030592 -45.633982)
			(xy 53.070741 -45.595273) (xy 53.116099 -45.562822) (xy 53.165699 -45.537321) (xy 53.218483 -45.519314)
			(xy 53.273326 -45.509184) (xy 53.32906 -45.507147) (xy 53.384497 -45.513247) (xy 53.438454 -45.527353)
			(xy 53.489783 -45.549165) (xy 53.537389 -45.578219) (xy 53.580257 -45.613894) (xy 53.617474 -45.655431)
			(xy 53.648247 -45.701944) (xy 53.671919 -45.752441) (xy 53.687987 -45.805848) (xy 53.696107 -45.861024)
			(xy 53.696616 -45.88891) (xy 53.696107 -45.916796) (xy 53.687987 -45.971972) (xy 53.671919 -46.025379)
			(xy 53.648247 -46.075876) (xy 53.64406 -46.082204) (xy 70.052438 -46.082204) (xy 70.052859 -46.054949)
			(xy 70.060617 -46.000994) (xy 70.075975 -45.948693) (xy 70.09862 -45.89911) (xy 70.128092 -45.853254)
			(xy 70.16379 -45.81206) (xy 70.204988 -45.776367) (xy 70.250847 -45.7469) (xy 70.300432 -45.72426)
			(xy 70.352735 -45.708908) (xy 70.406691 -45.701156) (xy 70.433946 -45.700696) (xy 70.460838 -45.701148)
			(xy 70.514088 -45.708702) (xy 70.565752 -45.723654) (xy 70.614806 -45.745709) (xy 70.660279 -45.774429)
			(xy 70.701272 -45.809247) (xy 70.736974 -45.849473) (xy 70.752208 -45.871638) (xy 70.75932 -45.882814)
			(xy 70.78218 -45.894752) (xy 70.88124 -45.892974) (xy 70.889741 -45.892514) (xy 70.90572 -45.886661)
			(xy 70.918911 -45.875912) (xy 70.923658 -45.868844) (xy 70.923658 -45.86859) (xy 70.938554 -45.844971)
			(xy 70.974237 -45.80202) (xy 71.0158 -45.764728) (xy 71.062354 -45.733892) (xy 71.112906 -45.710172)
			(xy 71.166375 -45.694073) (xy 71.22162 -45.68594) (xy 71.24954 -45.685456) (xy 71.276534 -45.685894)
			(xy 71.329983 -45.693506) (xy 71.381827 -45.708571) (xy 71.431031 -45.73079) (xy 71.476614 -45.75972)
			(xy 71.497444 -45.776896) (xy 71.505826 -45.784008) (xy 71.526146 -45.790104) (xy 71.611236 -45.779182)
			(xy 71.616594 -45.778432) (xy 71.626845 -45.774982) (xy 71.631556 -45.772324) (xy 71.640446 -45.766736)
			(xy 71.646796 -45.757846) (xy 71.64705 -45.757592) (xy 71.662393 -45.736386) (xy 71.69796 -45.697984)
			(xy 71.738449 -45.664813) (xy 71.783097 -45.637496) (xy 71.831065 -45.616547) (xy 71.881448 -45.602362)
			(xy 71.933299 -45.595207) (xy 71.95947 -45.594778) (xy 71.986723 -45.595267) (xy 72.040675 -45.60302)
			(xy 72.092975 -45.618373) (xy 72.142557 -45.641013) (xy 72.188412 -45.670479) (xy 72.229607 -45.706172)
			(xy 72.265303 -45.747364) (xy 72.294772 -45.793217) (xy 72.317416 -45.842797) (xy 72.32402 -45.865288)
			(xy 73.869294 -45.865288) (xy 73.873365 -45.809666) (xy 73.885491 -45.755229) (xy 73.905414 -45.703138)
			(xy 73.93271 -45.654503) (xy 73.966796 -45.61036) (xy 74.006945 -45.571651) (xy 74.052303 -45.5392)
			(xy 74.101903 -45.513699) (xy 74.154687 -45.495692) (xy 74.20953 -45.485562) (xy 74.265264 -45.483525)
			(xy 74.320701 -45.489625) (xy 74.374658 -45.503731) (xy 74.425987 -45.525543) (xy 74.473593 -45.554597)
			(xy 74.516461 -45.590272) (xy 74.553678 -45.631809) (xy 74.584451 -45.678322) (xy 74.608123 -45.728819)
			(xy 74.624191 -45.782226) (xy 74.632311 -45.837402) (xy 74.632611 -45.853858) (xy 75.058776 -45.853858)
			(xy 75.062847 -45.798236) (xy 75.074973 -45.743799) (xy 75.094896 -45.691708) (xy 75.122192 -45.643073)
			(xy 75.156278 -45.59893) (xy 75.196427 -45.560221) (xy 75.241785 -45.52777) (xy 75.291385 -45.502269)
			(xy 75.344169 -45.484262) (xy 75.399012 -45.474132) (xy 75.454746 -45.472095) (xy 75.510183 -45.478195)
			(xy 75.56414 -45.492301) (xy 75.615469 -45.514113) (xy 75.663075 -45.543167) (xy 75.705943 -45.578842)
			(xy 75.74316 -45.620379) (xy 75.773933 -45.666892) (xy 75.797605 -45.717389) (xy 75.813673 -45.770796)
			(xy 75.821793 -45.825972) (xy 75.822302 -45.853858) (xy 75.821793 -45.881744) (xy 75.820738 -45.88891)
			(xy 78.933038 -45.88891) (xy 78.937109 -45.833288) (xy 78.949235 -45.778851) (xy 78.969158 -45.72676)
			(xy 78.996454 -45.678125) (xy 79.03054 -45.633982) (xy 79.070689 -45.595273) (xy 79.116047 -45.562822)
			(xy 79.165647 -45.537321) (xy 79.218431 -45.519314) (xy 79.273274 -45.509184) (xy 79.329008 -45.507147)
			(xy 79.384445 -45.513247) (xy 79.438402 -45.527353) (xy 79.489731 -45.549165) (xy 79.537337 -45.578219)
			(xy 79.580205 -45.613894) (xy 79.617422 -45.655431) (xy 79.648195 -45.701944) (xy 79.671867 -45.752441)
			(xy 79.687935 -45.805848) (xy 79.696055 -45.861024) (xy 79.696564 -45.88891) (xy 79.696055 -45.916796)
			(xy 79.687935 -45.971972) (xy 79.671867 -46.025379) (xy 79.648195 -46.075876) (xy 79.644008 -46.082204)
			(xy 96.052386 -46.082204) (xy 96.052881 -46.054953) (xy 96.060637 -46.001006) (xy 96.075992 -45.948712)
			(xy 96.098632 -45.899135) (xy 96.128097 -45.853285) (xy 96.163788 -45.812095) (xy 96.204977 -45.776403)
			(xy 96.250826 -45.746937) (xy 96.300402 -45.724295) (xy 96.352696 -45.708939) (xy 96.406643 -45.701182)
			(xy 96.433894 -45.700696) (xy 96.460785 -45.701187) (xy 96.514033 -45.708734) (xy 96.565696 -45.72368)
			(xy 96.61475 -45.745728) (xy 96.660224 -45.774442) (xy 96.701218 -45.809254) (xy 96.736921 -45.849475)
			(xy 96.752156 -45.871638) (xy 96.759268 -45.882814) (xy 96.782128 -45.894752) (xy 96.881188 -45.892974)
			(xy 96.889686 -45.892479) (xy 96.905663 -45.886642) (xy 96.918856 -45.875906) (xy 96.923606 -45.868844)
			(xy 96.923606 -45.86859) (xy 96.938537 -45.844995) (xy 96.974214 -45.802043) (xy 97.015771 -45.76475)
			(xy 97.06232 -45.733912) (xy 97.112865 -45.710187) (xy 97.166329 -45.694083) (xy 97.22157 -45.685943)
			(xy 97.249488 -45.685456) (xy 97.276481 -45.685924) (xy 97.329929 -45.693528) (xy 97.381772 -45.708587)
			(xy 97.430977 -45.730799) (xy 97.476561 -45.759723) (xy 97.497392 -45.776896) (xy 97.505774 -45.784008)
			(xy 97.526094 -45.790104) (xy 97.611184 -45.779182) (xy 97.616544 -45.778446) (xy 97.626794 -45.774987)
			(xy 97.631504 -45.772324) (xy 97.640394 -45.766736) (xy 97.646744 -45.757846) (xy 97.646998 -45.757592)
			(xy 97.662373 -45.73641) (xy 97.697935 -45.698008) (xy 97.738418 -45.664835) (xy 97.783061 -45.637515)
			(xy 97.831023 -45.616562) (xy 97.881402 -45.602372) (xy 97.933249 -45.59521) (xy 97.959418 -45.594778)
			(xy 97.986667 -45.595293) (xy 98.040611 -45.603052) (xy 98.092902 -45.618408) (xy 98.142475 -45.641049)
			(xy 98.188321 -45.670515) (xy 98.229508 -45.706205) (xy 98.265196 -45.747393) (xy 98.294659 -45.793241)
			(xy 98.317298 -45.842815) (xy 98.323897 -45.865288) (xy 99.869242 -45.865288) (xy 99.873313 -45.809666)
			(xy 99.885439 -45.755229) (xy 99.905362 -45.703138) (xy 99.932658 -45.654503) (xy 99.966744 -45.61036)
			(xy 100.006893 -45.571651) (xy 100.052251 -45.5392) (xy 100.101851 -45.513699) (xy 100.154635 -45.495692)
			(xy 100.209478 -45.485562) (xy 100.265212 -45.483525) (xy 100.320649 -45.489625) (xy 100.374606 -45.503731)
			(xy 100.425935 -45.525543) (xy 100.473541 -45.554597) (xy 100.516409 -45.590272) (xy 100.553626 -45.631809)
			(xy 100.584399 -45.678322) (xy 100.608071 -45.728819) (xy 100.624139 -45.782226) (xy 100.632259 -45.837402)
			(xy 100.632559 -45.853858) (xy 101.058724 -45.853858) (xy 101.062795 -45.798236) (xy 101.074921 -45.743799)
			(xy 101.094844 -45.691708) (xy 101.12214 -45.643073) (xy 101.156226 -45.59893) (xy 101.196375 -45.560221)
			(xy 101.241733 -45.52777) (xy 101.291333 -45.502269) (xy 101.344117 -45.484262) (xy 101.39896 -45.474132)
			(xy 101.454694 -45.472095) (xy 101.510131 -45.478195) (xy 101.564088 -45.492301) (xy 101.615417 -45.514113)
			(xy 101.663023 -45.543167) (xy 101.705891 -45.578842) (xy 101.743108 -45.620379) (xy 101.773881 -45.666892)
			(xy 101.797553 -45.717389) (xy 101.813621 -45.770796) (xy 101.821741 -45.825972) (xy 101.82225 -45.853858)
			(xy 101.821741 -45.881744) (xy 101.820686 -45.88891) (xy 104.932986 -45.88891) (xy 104.937057 -45.833288)
			(xy 104.949183 -45.778851) (xy 104.969106 -45.72676) (xy 104.996402 -45.678125) (xy 105.030488 -45.633982)
			(xy 105.070637 -45.595273) (xy 105.115995 -45.562822) (xy 105.165595 -45.537321) (xy 105.218379 -45.519314)
			(xy 105.273222 -45.509184) (xy 105.328956 -45.507147) (xy 105.384393 -45.513247) (xy 105.43835 -45.527353)
			(xy 105.489679 -45.549165) (xy 105.537285 -45.578219) (xy 105.580153 -45.613894) (xy 105.61737 -45.655431)
			(xy 105.648143 -45.701944) (xy 105.671815 -45.752441) (xy 105.687883 -45.805848) (xy 105.696003 -45.861024)
			(xy 105.696512 -45.88891) (xy 105.696003 -45.916796) (xy 105.687883 -45.971972) (xy 105.671815 -46.025379)
			(xy 105.648143 -46.075876) (xy 105.643956 -46.082204) (xy 134.15264 -46.082204) (xy 134.153059 -46.054949)
			(xy 134.160817 -46.000994) (xy 134.176175 -45.948692) (xy 134.19882 -45.899109) (xy 134.228292 -45.853254)
			(xy 134.263991 -45.81206) (xy 134.305189 -45.776366) (xy 134.351048 -45.746899) (xy 134.400634 -45.724259)
			(xy 134.452937 -45.708908) (xy 134.506893 -45.701156) (xy 134.534148 -45.700696) (xy 134.56104 -45.701146)
			(xy 134.614291 -45.708701) (xy 134.665954 -45.723653) (xy 134.715008 -45.745708) (xy 134.760482 -45.774429)
			(xy 134.801475 -45.809247) (xy 134.837176 -45.849473) (xy 134.85241 -45.871638) (xy 134.859522 -45.882814)
			(xy 134.882382 -45.894752) (xy 134.981442 -45.892974) (xy 134.989943 -45.892515) (xy 135.005922 -45.886662)
			(xy 135.019113 -45.875912) (xy 135.02386 -45.868844) (xy 135.02386 -45.86859) (xy 135.038754 -45.84497)
			(xy 135.074438 -45.802019) (xy 135.116001 -45.764727) (xy 135.162555 -45.733892) (xy 135.213107 -45.710171)
			(xy 135.266577 -45.694073) (xy 135.321822 -45.685939) (xy 135.349742 -45.685456) (xy 135.376736 -45.685893)
			(xy 135.430185 -45.693505) (xy 135.482029 -45.70857) (xy 135.531233 -45.73079) (xy 135.576816 -45.75972)
			(xy 135.597646 -45.776896) (xy 135.606028 -45.784008) (xy 135.626348 -45.790104) (xy 135.711438 -45.779182)
			(xy 135.716796 -45.778432) (xy 135.727047 -45.774983) (xy 135.731758 -45.772324) (xy 135.740648 -45.766736)
			(xy 135.746998 -45.757846) (xy 135.747252 -45.757592) (xy 135.762594 -45.736385) (xy 135.798161 -45.697983)
			(xy 135.83865 -45.664812) (xy 135.883299 -45.637495) (xy 135.931266 -45.616547) (xy 135.98165 -45.602362)
			(xy 136.033501 -45.595207) (xy 136.059672 -45.594778) (xy 136.086925 -45.595267) (xy 136.140877 -45.603021)
			(xy 136.193176 -45.618374) (xy 136.242758 -45.641014) (xy 136.288613 -45.67048) (xy 136.329808 -45.706172)
			(xy 136.365503 -45.747364) (xy 136.394973 -45.793217) (xy 136.417616 -45.842797) (xy 136.42422 -45.865288)
			(xy 137.969496 -45.865288) (xy 137.973567 -45.809666) (xy 137.985693 -45.755229) (xy 138.005616 -45.703138)
			(xy 138.032912 -45.654503) (xy 138.066998 -45.61036) (xy 138.107147 -45.571651) (xy 138.152505 -45.5392)
			(xy 138.202105 -45.513699) (xy 138.254889 -45.495692) (xy 138.309732 -45.485562) (xy 138.365466 -45.483525)
			(xy 138.420903 -45.489625) (xy 138.47486 -45.503731) (xy 138.526189 -45.525543) (xy 138.573795 -45.554597)
			(xy 138.616663 -45.590272) (xy 138.65388 -45.631809) (xy 138.684653 -45.678322) (xy 138.708325 -45.728819)
			(xy 138.724393 -45.782226) (xy 138.732513 -45.837402) (xy 138.732813 -45.853858) (xy 139.158978 -45.853858)
			(xy 139.163049 -45.798236) (xy 139.175175 -45.743799) (xy 139.195098 -45.691708) (xy 139.222394 -45.643073)
			(xy 139.25648 -45.59893) (xy 139.296629 -45.560221) (xy 139.341987 -45.52777) (xy 139.391587 -45.502269)
			(xy 139.444371 -45.484262) (xy 139.499214 -45.474132) (xy 139.554948 -45.472095) (xy 139.610385 -45.478195)
			(xy 139.664342 -45.492301) (xy 139.715671 -45.514113) (xy 139.763277 -45.543167) (xy 139.806145 -45.578842)
			(xy 139.843362 -45.620379) (xy 139.874135 -45.666892) (xy 139.897807 -45.717389) (xy 139.913875 -45.770796)
			(xy 139.921995 -45.825972) (xy 139.922504 -45.853858) (xy 139.921995 -45.881744) (xy 139.92094 -45.88891)
			(xy 143.03324 -45.88891) (xy 143.037311 -45.833288) (xy 143.049437 -45.778851) (xy 143.06936 -45.72676)
			(xy 143.096656 -45.678125) (xy 143.130742 -45.633982) (xy 143.170891 -45.595273) (xy 143.216249 -45.562822)
			(xy 143.265849 -45.537321) (xy 143.318633 -45.519314) (xy 143.373476 -45.509184) (xy 143.42921 -45.507147)
			(xy 143.484647 -45.513247) (xy 143.538604 -45.527353) (xy 143.589933 -45.549165) (xy 143.637539 -45.578219)
			(xy 143.680407 -45.613894) (xy 143.717624 -45.655431) (xy 143.748397 -45.701944) (xy 143.772069 -45.752441)
			(xy 143.788137 -45.805848) (xy 143.796257 -45.861024) (xy 143.796766 -45.88891) (xy 143.796257 -45.916796)
			(xy 143.788137 -45.971972) (xy 143.772069 -46.025379) (xy 143.748397 -46.075876) (xy 143.74421 -46.082204)
			(xy 160.152588 -46.082204) (xy 160.153081 -46.054953) (xy 160.160837 -46.001006) (xy 160.176192 -45.948711)
			(xy 160.198832 -45.899134) (xy 160.228298 -45.853284) (xy 160.263988 -45.812094) (xy 160.305178 -45.776402)
			(xy 160.351027 -45.746936) (xy 160.400604 -45.724295) (xy 160.452898 -45.708939) (xy 160.506845 -45.701182)
			(xy 160.534096 -45.700696) (xy 160.560987 -45.701186) (xy 160.614235 -45.708733) (xy 160.665898 -45.723679)
			(xy 160.714952 -45.745727) (xy 160.760426 -45.774442) (xy 160.80142 -45.809254) (xy 160.837123 -45.849475)
			(xy 160.852358 -45.871638) (xy 160.85947 -45.882814) (xy 160.88233 -45.894752) (xy 160.98139 -45.892974)
			(xy 160.989888 -45.89248) (xy 161.005865 -45.886643) (xy 161.019058 -45.875906) (xy 161.023808 -45.868844)
			(xy 161.023808 -45.86859) (xy 161.038738 -45.844994) (xy 161.074415 -45.802042) (xy 161.115972 -45.764749)
			(xy 161.162521 -45.733911) (xy 161.213067 -45.710187) (xy 161.266531 -45.694083) (xy 161.321772 -45.685943)
			(xy 161.34969 -45.685456) (xy 161.376683 -45.685923) (xy 161.430131 -45.693527) (xy 161.481974 -45.708586)
			(xy 161.531179 -45.730799) (xy 161.576763 -45.759722) (xy 161.597594 -45.776896) (xy 161.605976 -45.784008)
			(xy 161.626296 -45.790104) (xy 161.711386 -45.779182) (xy 161.716747 -45.778447) (xy 161.726996 -45.774987)
			(xy 161.731706 -45.772324) (xy 161.740596 -45.766736) (xy 161.746946 -45.757846) (xy 161.7472 -45.757592)
			(xy 161.762574 -45.736409) (xy 161.798136 -45.698007) (xy 161.83862 -45.664834) (xy 161.883263 -45.637514)
			(xy 161.931225 -45.616562) (xy 161.981604 -45.602371) (xy 162.03345 -45.59521) (xy 162.05962 -45.594778)
			(xy 162.086869 -45.595294) (xy 162.140813 -45.603052) (xy 162.193103 -45.618408) (xy 162.242676 -45.64105)
			(xy 162.288522 -45.670516) (xy 162.329708 -45.706206) (xy 162.365396 -45.747394) (xy 162.39486 -45.793242)
			(xy 162.417499 -45.842816) (xy 162.424097 -45.865288) (xy 163.969444 -45.865288) (xy 163.973515 -45.809666)
			(xy 163.985641 -45.755229) (xy 164.005564 -45.703138) (xy 164.03286 -45.654503) (xy 164.066946 -45.61036)
			(xy 164.107095 -45.571651) (xy 164.152453 -45.5392) (xy 164.202053 -45.513699) (xy 164.254837 -45.495692)
			(xy 164.30968 -45.485562) (xy 164.365414 -45.483525) (xy 164.420851 -45.489625) (xy 164.474808 -45.503731)
			(xy 164.526137 -45.525543) (xy 164.573743 -45.554597) (xy 164.616611 -45.590272) (xy 164.653828 -45.631809)
			(xy 164.684601 -45.678322) (xy 164.708273 -45.728819) (xy 164.724341 -45.782226) (xy 164.732461 -45.837402)
			(xy 164.732761 -45.853858) (xy 165.158926 -45.853858) (xy 165.162997 -45.798236) (xy 165.175123 -45.743799)
			(xy 165.195046 -45.691708) (xy 165.222342 -45.643073) (xy 165.256428 -45.59893) (xy 165.296577 -45.560221)
			(xy 165.341935 -45.52777) (xy 165.391535 -45.502269) (xy 165.444319 -45.484262) (xy 165.499162 -45.474132)
			(xy 165.554896 -45.472095) (xy 165.610333 -45.478195) (xy 165.66429 -45.492301) (xy 165.715619 -45.514113)
			(xy 165.763225 -45.543167) (xy 165.806093 -45.578842) (xy 165.84331 -45.620379) (xy 165.874083 -45.666892)
			(xy 165.897755 -45.717389) (xy 165.913823 -45.770796) (xy 165.921943 -45.825972) (xy 165.922452 -45.853858)
			(xy 165.921943 -45.881744) (xy 165.920888 -45.88891) (xy 169.033188 -45.88891) (xy 169.037259 -45.833288)
			(xy 169.049385 -45.778851) (xy 169.069308 -45.72676) (xy 169.096604 -45.678125) (xy 169.13069 -45.633982)
			(xy 169.170839 -45.595273) (xy 169.216197 -45.562822) (xy 169.265797 -45.537321) (xy 169.318581 -45.519314)
			(xy 169.373424 -45.509184) (xy 169.429158 -45.507147) (xy 169.484595 -45.513247) (xy 169.538552 -45.527353)
			(xy 169.589881 -45.549165) (xy 169.637487 -45.578219) (xy 169.680355 -45.613894) (xy 169.717572 -45.655431)
			(xy 169.748345 -45.701944) (xy 169.772017 -45.752441) (xy 169.788085 -45.805848) (xy 169.796205 -45.861024)
			(xy 169.796714 -45.88891) (xy 169.796205 -45.916796) (xy 169.788085 -45.971972) (xy 169.772017 -46.025379)
			(xy 169.748345 -46.075876) (xy 169.744158 -46.082204) (xy 186.152536 -46.082204) (xy 186.152959 -46.054949)
			(xy 186.160717 -46.000995) (xy 186.176075 -45.948693) (xy 186.19872 -45.89911) (xy 186.228191 -45.853255)
			(xy 186.263889 -45.812061) (xy 186.305087 -45.776367) (xy 186.350945 -45.746901) (xy 186.400531 -45.724261)
			(xy 186.452834 -45.708908) (xy 186.506789 -45.701156) (xy 186.534044 -45.700696) (xy 186.560936 -45.701149)
			(xy 186.614186 -45.708703) (xy 186.66585 -45.723655) (xy 186.714904 -45.74571) (xy 186.760377 -45.77443)
			(xy 186.80137 -45.809247) (xy 186.837072 -45.849473) (xy 186.852306 -45.871638) (xy 186.859418 -45.882814)
			(xy 186.882278 -45.894752) (xy 186.981338 -45.892974) (xy 186.989839 -45.892513) (xy 187.005817 -45.886661)
			(xy 187.019009 -45.875912) (xy 187.023756 -45.868844) (xy 187.023756 -45.86859) (xy 187.038653 -45.844972)
			(xy 187.074336 -45.802021) (xy 187.115899 -45.764729) (xy 187.162453 -45.733893) (xy 187.213004 -45.710172)
			(xy 187.266473 -45.694073) (xy 187.321718 -45.68594) (xy 187.349638 -45.685456) (xy 187.376632 -45.685895)
			(xy 187.430081 -45.693506) (xy 187.481925 -45.708572) (xy 187.531129 -45.730791) (xy 187.576712 -45.75972)
			(xy 187.597542 -45.776896) (xy 187.605924 -45.784008) (xy 187.626244 -45.790104) (xy 187.711334 -45.779182)
			(xy 187.716692 -45.778431) (xy 187.726943 -45.774982) (xy 187.731654 -45.772324) (xy 187.740544 -45.766736)
			(xy 187.746894 -45.757846) (xy 187.747148 -45.757592) (xy 187.762492 -45.736387) (xy 187.798059 -45.697985)
			(xy 187.838548 -45.664814) (xy 187.883196 -45.637496) (xy 187.931163 -45.616548) (xy 187.981546 -45.602363)
			(xy 188.033397 -45.595207) (xy 188.059568 -45.594778) (xy 188.086821 -45.595267) (xy 188.140774 -45.60302)
			(xy 188.193074 -45.618373) (xy 188.242656 -45.641013) (xy 188.288511 -45.670479) (xy 188.329706 -45.706171)
			(xy 188.365402 -45.747363) (xy 188.394872 -45.793216) (xy 188.417516 -45.842796) (xy 188.424121 -45.865288)
			(xy 189.969392 -45.865288) (xy 189.973463 -45.809666) (xy 189.985589 -45.755229) (xy 190.005512 -45.703138)
			(xy 190.032808 -45.654503) (xy 190.066894 -45.61036) (xy 190.107043 -45.571651) (xy 190.152401 -45.5392)
			(xy 190.202001 -45.513699) (xy 190.254785 -45.495692) (xy 190.309628 -45.485562) (xy 190.365362 -45.483525)
			(xy 190.420799 -45.489625) (xy 190.474756 -45.503731) (xy 190.526085 -45.525543) (xy 190.573691 -45.554597)
			(xy 190.616559 -45.590272) (xy 190.653776 -45.631809) (xy 190.684549 -45.678322) (xy 190.708221 -45.728819)
			(xy 190.724289 -45.782226) (xy 190.732409 -45.837402) (xy 190.732709 -45.853858) (xy 191.158874 -45.853858)
			(xy 191.162945 -45.798236) (xy 191.175071 -45.743799) (xy 191.194994 -45.691708) (xy 191.22229 -45.643073)
			(xy 191.256376 -45.59893) (xy 191.296525 -45.560221) (xy 191.341883 -45.52777) (xy 191.391483 -45.502269)
			(xy 191.444267 -45.484262) (xy 191.49911 -45.474132) (xy 191.554844 -45.472095) (xy 191.610281 -45.478195)
			(xy 191.664238 -45.492301) (xy 191.715567 -45.514113) (xy 191.763173 -45.543167) (xy 191.806041 -45.578842)
			(xy 191.843258 -45.620379) (xy 191.874031 -45.666892) (xy 191.897703 -45.717389) (xy 191.913771 -45.770796)
			(xy 191.921891 -45.825972) (xy 191.9224 -45.853858) (xy 191.921891 -45.881744) (xy 191.920836 -45.88891)
			(xy 195.033136 -45.88891) (xy 195.037207 -45.833288) (xy 195.049333 -45.778851) (xy 195.069256 -45.72676)
			(xy 195.096552 -45.678125) (xy 195.130638 -45.633982) (xy 195.170787 -45.595273) (xy 195.216145 -45.562822)
			(xy 195.265745 -45.537321) (xy 195.318529 -45.519314) (xy 195.373372 -45.509184) (xy 195.429106 -45.507147)
			(xy 195.484543 -45.513247) (xy 195.5385 -45.527353) (xy 195.589829 -45.549165) (xy 195.637435 -45.578219)
			(xy 195.680303 -45.613894) (xy 195.71752 -45.655431) (xy 195.748293 -45.701944) (xy 195.771965 -45.752441)
			(xy 195.788033 -45.805848) (xy 195.796153 -45.861024) (xy 195.796662 -45.88891) (xy 195.796153 -45.916796)
			(xy 195.788033 -45.971972) (xy 195.771965 -46.025379) (xy 195.748293 -46.075876) (xy 195.744106 -46.082204)
			(xy 212.152484 -46.082204) (xy 212.152981 -46.054953) (xy 212.160737 -46.001006) (xy 212.176091 -45.948712)
			(xy 212.198732 -45.899136) (xy 212.228197 -45.853286) (xy 212.263887 -45.812095) (xy 212.305076 -45.776404)
			(xy 212.350925 -45.746937) (xy 212.400501 -45.724296) (xy 212.452795 -45.70894) (xy 212.506741 -45.701182)
			(xy 212.533992 -45.700696) (xy 212.560882 -45.701189) (xy 212.614131 -45.708736) (xy 212.665794 -45.723681)
			(xy 212.714848 -45.745729) (xy 212.760322 -45.774443) (xy 212.801316 -45.809255) (xy 212.837019 -45.849475)
			(xy 212.852254 -45.871638) (xy 212.859366 -45.882814) (xy 212.882226 -45.894752) (xy 212.981286 -45.892974)
			(xy 212.989783 -45.892478) (xy 213.005761 -45.886642) (xy 213.018954 -45.875906) (xy 213.023704 -45.868844)
			(xy 213.023704 -45.86859) (xy 213.038636 -45.844996) (xy 213.074314 -45.802044) (xy 213.11587 -45.764751)
			(xy 213.162418 -45.733912) (xy 213.212964 -45.710188) (xy 213.266428 -45.694083) (xy 213.321668 -45.685943)
			(xy 213.349586 -45.685456) (xy 213.376579 -45.685925) (xy 213.430027 -45.693529) (xy 213.48187 -45.708588)
			(xy 213.531075 -45.7308) (xy 213.576659 -45.759723) (xy 213.59749 -45.776896) (xy 213.605872 -45.784008)
			(xy 213.626192 -45.790104) (xy 213.711282 -45.779182) (xy 213.716642 -45.778445) (xy 213.726892 -45.774987)
			(xy 213.731602 -45.772324) (xy 213.740492 -45.766736) (xy 213.746842 -45.757846) (xy 213.747096 -45.757592)
			(xy 213.762473 -45.736411) (xy 213.798034 -45.698009) (xy 213.838517 -45.664836) (xy 213.88316 -45.637515)
			(xy 213.931122 -45.616563) (xy 213.9815 -45.602372) (xy 214.033347 -45.595211) (xy 214.059516 -45.594778)
			(xy 214.086765 -45.595293) (xy 214.140709 -45.603051) (xy 214.193 -45.618407) (xy 214.242574 -45.641049)
			(xy 214.28842 -45.670514) (xy 214.329607 -45.706204) (xy 214.365295 -45.747393) (xy 214.394759 -45.79324)
			(xy 214.417398 -45.842815) (xy 214.423997 -45.865288) (xy 215.96934 -45.865288) (xy 215.973411 -45.809666)
			(xy 215.985537 -45.755229) (xy 216.00546 -45.703138) (xy 216.032756 -45.654503) (xy 216.066842 -45.61036)
			(xy 216.106991 -45.571651) (xy 216.152349 -45.5392) (xy 216.201949 -45.513699) (xy 216.254733 -45.495692)
			(xy 216.309576 -45.485562) (xy 216.36531 -45.483525) (xy 216.420747 -45.489625) (xy 216.474704 -45.503731)
			(xy 216.526033 -45.525543) (xy 216.573639 -45.554597) (xy 216.616507 -45.590272) (xy 216.653724 -45.631809)
			(xy 216.684497 -45.678322) (xy 216.708169 -45.728819) (xy 216.724237 -45.782226) (xy 216.732357 -45.837402)
			(xy 216.732657 -45.853858) (xy 217.158822 -45.853858) (xy 217.162893 -45.798236) (xy 217.175019 -45.743799)
			(xy 217.194942 -45.691708) (xy 217.222238 -45.643073) (xy 217.256324 -45.59893) (xy 217.296473 -45.560221)
			(xy 217.341831 -45.52777) (xy 217.391431 -45.502269) (xy 217.444215 -45.484262) (xy 217.499058 -45.474132)
			(xy 217.554792 -45.472095) (xy 217.610229 -45.478195) (xy 217.664186 -45.492301) (xy 217.715515 -45.514113)
			(xy 217.763121 -45.543167) (xy 217.805989 -45.578842) (xy 217.843206 -45.620379) (xy 217.873979 -45.666892)
			(xy 217.897651 -45.717389) (xy 217.913719 -45.770796) (xy 217.921839 -45.825972) (xy 217.922348 -45.853858)
			(xy 217.921839 -45.881744) (xy 217.920784 -45.88891) (xy 221.033084 -45.88891) (xy 221.037155 -45.833288)
			(xy 221.049281 -45.778851) (xy 221.069204 -45.72676) (xy 221.0965 -45.678125) (xy 221.130586 -45.633982)
			(xy 221.170735 -45.595273) (xy 221.216093 -45.562822) (xy 221.265693 -45.537321) (xy 221.318477 -45.519314)
			(xy 221.37332 -45.509184) (xy 221.429054 -45.507147) (xy 221.484491 -45.513247) (xy 221.538448 -45.527353)
			(xy 221.589777 -45.549165) (xy 221.637383 -45.578219) (xy 221.680251 -45.613894) (xy 221.717468 -45.655431)
			(xy 221.748241 -45.701944) (xy 221.771913 -45.752441) (xy 221.787981 -45.805848) (xy 221.792322 -45.835348)
			(xy 234.660216 -45.835348) (xy 234.660216 -45.780852) (xy 234.667972 -45.726911) (xy 234.683324 -45.674623)
			(xy 234.705962 -45.625051) (xy 234.735424 -45.579206) (xy 234.771111 -45.538021) (xy 234.812295 -45.502333)
			(xy 234.858139 -45.472869) (xy 234.90771 -45.450229) (xy 234.959997 -45.434874) (xy 235.013938 -45.427117)
			(xy 235.041186 -45.42663) (xy 235.068556 -45.427097) (xy 235.122736 -45.434913) (xy 235.175239 -45.450402)
			(xy 235.224986 -45.473244) (xy 235.270953 -45.502968) (xy 235.291884 -45.52061) (xy 235.292138 -45.520864)
			(xy 235.299233 -45.526438) (xy 235.316143 -45.532691) (xy 235.325158 -45.533056) (xy 235.392214 -45.533056)
			(xy 235.401233 -45.532715) (xy 235.41815 -45.526458) (xy 235.425234 -45.520864) (xy 235.425742 -45.520356)
			(xy 235.446705 -45.502779) (xy 235.492666 -45.473113) (xy 235.542395 -45.45032) (xy 235.594871 -45.434868)
			(xy 235.649017 -45.427074) (xy 235.70372 -45.427098) (xy 235.757859 -45.43494) (xy 235.810321 -45.450439)
			(xy 235.86003 -45.473275) (xy 235.905965 -45.502982) (xy 235.926884 -45.52061) (xy 235.927138 -45.520864)
			(xy 235.934233 -45.526438) (xy 235.951143 -45.532691) (xy 235.960158 -45.533056) (xy 236.027214 -45.533056)
			(xy 236.036233 -45.532715) (xy 236.05315 -45.526458) (xy 236.060234 -45.520864) (xy 236.060742 -45.520356)
			(xy 236.081673 -45.50277) (xy 236.127609 -45.473133) (xy 236.177306 -45.450356) (xy 236.229745 -45.434906)
			(xy 236.283852 -45.4271) (xy 236.311186 -45.42663) (xy 236.31144 -45.42663) (xy 236.337736 -45.427052)
			(xy 236.389827 -45.434304) (xy 236.440429 -45.448636) (xy 236.488585 -45.469779) (xy 236.533384 -45.49733)
			(xy 236.573977 -45.53077) (xy 236.59211 -45.54982) (xy 236.599676 -45.557267) (xy 236.619098 -45.565788)
			(xy 236.629702 -45.56633) (xy 236.70387 -45.56633) (xy 236.714498 -45.565887) (xy 236.733962 -45.55736)
			(xy 236.741462 -45.54982) (xy 236.759604 -45.530778) (xy 236.800183 -45.497319) (xy 236.844976 -45.469757)
			(xy 236.893133 -45.448616) (xy 236.94374 -45.434296) (xy 236.995835 -45.427069) (xy 237.022132 -45.42663)
			(xy 237.022386 -45.42663) (xy 237.049642 -45.427016) (xy 237.1036 -45.434772) (xy 237.155905 -45.450128)
			(xy 237.205492 -45.472772) (xy 237.251351 -45.502243) (xy 237.29255 -45.53794) (xy 237.328249 -45.579137)
			(xy 237.357721 -45.624996) (xy 237.380367 -45.674582) (xy 237.395725 -45.726886) (xy 237.403483 -45.780844)
			(xy 237.403483 -45.835351) (xy 238.482093 -45.835351) (xy 238.482093 -45.780849) (xy 238.48985 -45.726901)
			(xy 238.505206 -45.674607) (xy 238.527848 -45.62503) (xy 238.557315 -45.57918) (xy 238.593008 -45.537991)
			(xy 238.634199 -45.502301) (xy 238.680051 -45.472836) (xy 238.729629 -45.450197) (xy 238.781925 -45.434845)
			(xy 238.835873 -45.427092) (xy 238.863124 -45.42663) (xy 238.890495 -45.427075) (xy 238.944675 -45.434897)
			(xy 238.997179 -45.45039) (xy 239.046926 -45.473237) (xy 239.092891 -45.502966) (xy 239.113822 -45.52061)
			(xy 239.114076 -45.520864) (xy 239.12116 -45.526454) (xy 239.138079 -45.532697) (xy 239.147096 -45.533056)
			(xy 239.214152 -45.533056) (xy 239.223168 -45.532686) (xy 239.240085 -45.526448) (xy 239.247172 -45.520864)
			(xy 239.24768 -45.520356) (xy 239.268612 -45.502741) (xy 239.314579 -45.473077) (xy 239.364313 -45.450287)
			(xy 239.416794 -45.434838) (xy 239.470943 -45.427047) (xy 239.525651 -45.427076) (xy 239.579792 -45.434922)
			(xy 239.632257 -45.450425) (xy 239.681967 -45.473267) (xy 239.727903 -45.502979) (xy 239.748822 -45.52061)
			(xy 239.749076 -45.520864) (xy 239.75616 -45.526454) (xy 239.773079 -45.532697) (xy 239.782096 -45.533056)
			(xy 239.849152 -45.533056) (xy 239.858168 -45.532686) (xy 239.875085 -45.526448) (xy 239.882172 -45.520864)
			(xy 239.88268 -45.520356) (xy 239.903612 -45.502741) (xy 239.949579 -45.473077) (xy 239.999313 -45.450287)
			(xy 240.051794 -45.434838) (xy 240.105943 -45.427047) (xy 240.160651 -45.427076) (xy 240.214792 -45.434922)
			(xy 240.267257 -45.450425) (xy 240.316967 -45.473267) (xy 240.362903 -45.502979) (xy 240.383822 -45.52061)
			(xy 240.384076 -45.520864) (xy 240.39116 -45.526454) (xy 240.408079 -45.532697) (xy 240.417096 -45.533056)
			(xy 240.484152 -45.533056) (xy 240.493168 -45.532686) (xy 240.510085 -45.526448) (xy 240.517172 -45.520864)
			(xy 240.51768 -45.520356) (xy 240.538597 -45.502753) (xy 240.584537 -45.473117) (xy 240.634237 -45.450344)
			(xy 240.686679 -45.434898) (xy 240.740789 -45.427098) (xy 240.768124 -45.42663) (xy 240.795377 -45.427042)
			(xy 240.849327 -45.434802) (xy 240.901624 -45.45016) (xy 240.951204 -45.472805) (xy 240.997056 -45.502275)
			(xy 241.038247 -45.53797) (xy 241.073939 -45.579164) (xy 241.103406 -45.625018) (xy 241.126048 -45.674598)
			(xy 241.141404 -45.726896) (xy 241.14916 -45.780847) (xy 241.14916 -45.835353) (xy 241.141404 -45.889304)
			(xy 241.126048 -45.941602) (xy 241.103406 -45.991182) (xy 241.073939 -46.037036) (xy 241.038247 -46.07823)
			(xy 241.033661 -46.082204) (xy 250.252484 -46.082204) (xy 250.252981 -46.054953) (xy 250.260737 -46.001006)
			(xy 250.276091 -45.948712) (xy 250.298732 -45.899136) (xy 250.328197 -45.853286) (xy 250.363887 -45.812095)
			(xy 250.405076 -45.776404) (xy 250.450925 -45.746937) (xy 250.500501 -45.724296) (xy 250.552795 -45.70894)
			(xy 250.606741 -45.701182) (xy 250.633992 -45.700696) (xy 250.660882 -45.701189) (xy 250.714131 -45.708736)
			(xy 250.765794 -45.723681) (xy 250.814848 -45.745729) (xy 250.860322 -45.774443) (xy 250.901316 -45.809255)
			(xy 250.937019 -45.849475) (xy 250.952254 -45.871638) (xy 250.959366 -45.882814) (xy 250.982226 -45.894752)
			(xy 251.081286 -45.892974) (xy 251.089783 -45.892478) (xy 251.105761 -45.886642) (xy 251.118954 -45.875906)
			(xy 251.123704 -45.868844) (xy 251.123704 -45.86859) (xy 251.138636 -45.844996) (xy 251.174314 -45.802044)
			(xy 251.21587 -45.764751) (xy 251.262418 -45.733912) (xy 251.312964 -45.710188) (xy 251.366428 -45.694083)
			(xy 251.421668 -45.685943) (xy 251.449586 -45.685456) (xy 251.476579 -45.685925) (xy 251.530027 -45.693529)
			(xy 251.58187 -45.708588) (xy 251.631075 -45.7308) (xy 251.676659 -45.759723) (xy 251.69749 -45.776896)
			(xy 251.705872 -45.784008) (xy 251.726192 -45.790104) (xy 251.811282 -45.779182) (xy 251.816642 -45.778445)
			(xy 251.826892 -45.774987) (xy 251.831602 -45.772324) (xy 251.840492 -45.766736) (xy 251.846842 -45.757846)
			(xy 251.847096 -45.757592) (xy 251.862473 -45.736411) (xy 251.898034 -45.698009) (xy 251.938517 -45.664836)
			(xy 251.98316 -45.637515) (xy 252.031122 -45.616563) (xy 252.0815 -45.602372) (xy 252.133347 -45.595211)
			(xy 252.159516 -45.594778) (xy 252.186765 -45.595293) (xy 252.240709 -45.603051) (xy 252.293 -45.618407)
			(xy 252.342574 -45.641049) (xy 252.38842 -45.670514) (xy 252.429607 -45.706204) (xy 252.465295 -45.747393)
			(xy 252.494759 -45.79324) (xy 252.517398 -45.842815) (xy 252.523997 -45.865288) (xy 254.06934 -45.865288)
			(xy 254.073411 -45.809666) (xy 254.085537 -45.755229) (xy 254.10546 -45.703138) (xy 254.132756 -45.654503)
			(xy 254.166842 -45.61036) (xy 254.206991 -45.571651) (xy 254.252349 -45.5392) (xy 254.301949 -45.513699)
			(xy 254.354733 -45.495692) (xy 254.409576 -45.485562) (xy 254.46531 -45.483525) (xy 254.520747 -45.489625)
			(xy 254.574704 -45.503731) (xy 254.626033 -45.525543) (xy 254.673639 -45.554597) (xy 254.716507 -45.590272)
			(xy 254.753724 -45.631809) (xy 254.784497 -45.678322) (xy 254.808169 -45.728819) (xy 254.824237 -45.782226)
			(xy 254.832357 -45.837402) (xy 254.832657 -45.853858) (xy 255.258822 -45.853858) (xy 255.262893 -45.798236)
			(xy 255.275019 -45.743799) (xy 255.294942 -45.691708) (xy 255.322238 -45.643073) (xy 255.356324 -45.59893)
			(xy 255.396473 -45.560221) (xy 255.441831 -45.52777) (xy 255.491431 -45.502269) (xy 255.544215 -45.484262)
			(xy 255.599058 -45.474132) (xy 255.654792 -45.472095) (xy 255.710229 -45.478195) (xy 255.764186 -45.492301)
			(xy 255.815515 -45.514113) (xy 255.863121 -45.543167) (xy 255.905989 -45.578842) (xy 255.943206 -45.620379)
			(xy 255.973979 -45.666892) (xy 255.997651 -45.717389) (xy 256.013719 -45.770796) (xy 256.021839 -45.825972)
			(xy 256.022348 -45.853858) (xy 256.021839 -45.881744) (xy 256.020784 -45.88891) (xy 259.133084 -45.88891)
			(xy 259.137155 -45.833288) (xy 259.149281 -45.778851) (xy 259.169204 -45.72676) (xy 259.1965 -45.678125)
			(xy 259.230586 -45.633982) (xy 259.270735 -45.595273) (xy 259.316093 -45.562822) (xy 259.365693 -45.537321)
			(xy 259.418477 -45.519314) (xy 259.47332 -45.509184) (xy 259.529054 -45.507147) (xy 259.584491 -45.513247)
			(xy 259.638448 -45.527353) (xy 259.689777 -45.549165) (xy 259.737383 -45.578219) (xy 259.780251 -45.613894)
			(xy 259.817468 -45.655431) (xy 259.848241 -45.701944) (xy 259.871913 -45.752441) (xy 259.887981 -45.805848)
			(xy 259.896101 -45.861024) (xy 259.89661 -45.88891) (xy 259.896101 -45.916796) (xy 259.887981 -45.971972)
			(xy 259.871913 -46.025379) (xy 259.848241 -46.075876) (xy 259.844054 -46.082204) (xy 276.252432 -46.082204)
			(xy 276.252859 -46.054949) (xy 276.260617 -46.000995) (xy 276.275974 -45.948694) (xy 276.298619 -45.899111)
			(xy 276.32809 -45.853256) (xy 276.363788 -45.812063) (xy 276.404985 -45.776369) (xy 276.450843 -45.746902)
			(xy 276.500428 -45.724262) (xy 276.55273 -45.708909) (xy 276.606685 -45.701157) (xy 276.63394 -45.700696)
			(xy 276.660832 -45.701152) (xy 276.714082 -45.708706) (xy 276.765746 -45.723657) (xy 276.814799 -45.745711)
			(xy 276.860273 -45.774431) (xy 276.901266 -45.809248) (xy 276.936967 -45.849473) (xy 276.952202 -45.871638)
			(xy 276.959314 -45.882814) (xy 276.982174 -45.894752) (xy 277.081234 -45.892974) (xy 277.089735 -45.89251)
			(xy 277.105713 -45.886659) (xy 277.118905 -45.875911) (xy 277.123652 -45.868844) (xy 277.123652 -45.86859)
			(xy 277.138552 -45.844974) (xy 277.174234 -45.802022) (xy 277.215796 -45.76473) (xy 277.26235 -45.733895)
			(xy 277.312901 -45.710174) (xy 277.36637 -45.694074) (xy 277.421614 -45.68594) (xy 277.449534 -45.685456)
			(xy 277.476528 -45.685897) (xy 277.529977 -45.693508) (xy 277.581821 -45.708573) (xy 277.631025 -45.730791)
			(xy 277.676608 -45.75972) (xy 277.697438 -45.776896) (xy 277.70582 -45.784008) (xy 277.72614 -45.790104)
			(xy 277.81123 -45.779182) (xy 277.816588 -45.77843) (xy 277.826838 -45.774982) (xy 277.83155 -45.772324)
			(xy 277.84044 -45.766736) (xy 277.84679 -45.757846) (xy 277.847044 -45.757592) (xy 277.862391 -45.736389)
			(xy 277.897957 -45.697987) (xy 277.938446 -45.664815) (xy 277.983093 -45.637498) (xy 278.03106 -45.616549)
			(xy 278.081443 -45.602363) (xy 278.133293 -45.595207) (xy 278.159464 -45.594778) (xy 278.186718 -45.595267)
			(xy 278.24067 -45.603019) (xy 278.292971 -45.618372) (xy 278.342553 -45.641011) (xy 278.388409 -45.670477)
			(xy 278.429605 -45.70617) (xy 278.465301 -45.747362) (xy 278.494771 -45.793215) (xy 278.517416 -45.842796)
			(xy 278.524021 -45.865288) (xy 280.069288 -45.865288) (xy 280.073359 -45.809666) (xy 280.085485 -45.755229)
			(xy 280.105408 -45.703138) (xy 280.132704 -45.654503) (xy 280.16679 -45.61036) (xy 280.206939 -45.571651)
			(xy 280.252297 -45.5392) (xy 280.301897 -45.513699) (xy 280.354681 -45.495692) (xy 280.409524 -45.485562)
			(xy 280.465258 -45.483525) (xy 280.520695 -45.489625) (xy 280.574652 -45.503731) (xy 280.625981 -45.525543)
			(xy 280.673587 -45.554597) (xy 280.716455 -45.590272) (xy 280.753672 -45.631809) (xy 280.784445 -45.678322)
			(xy 280.808117 -45.728819) (xy 280.824185 -45.782226) (xy 280.832305 -45.837402) (xy 280.832605 -45.853858)
			(xy 281.25877 -45.853858) (xy 281.262841 -45.798236) (xy 281.274967 -45.743799) (xy 281.29489 -45.691708)
			(xy 281.322186 -45.643073) (xy 281.356272 -45.59893) (xy 281.396421 -45.560221) (xy 281.441779 -45.52777)
			(xy 281.491379 -45.502269) (xy 281.544163 -45.484262) (xy 281.599006 -45.474132) (xy 281.65474 -45.472095)
			(xy 281.710177 -45.478195) (xy 281.764134 -45.492301) (xy 281.815463 -45.514113) (xy 281.863069 -45.543167)
			(xy 281.905937 -45.578842) (xy 281.943154 -45.620379) (xy 281.973927 -45.666892) (xy 281.997599 -45.717389)
			(xy 282.013667 -45.770796) (xy 282.021787 -45.825972) (xy 282.022296 -45.853858) (xy 282.021787 -45.881744)
			(xy 282.020732 -45.88891) (xy 285.133032 -45.88891) (xy 285.137103 -45.833288) (xy 285.149229 -45.778851)
			(xy 285.169152 -45.72676) (xy 285.196448 -45.678125) (xy 285.230534 -45.633982) (xy 285.270683 -45.595273)
			(xy 285.316041 -45.562822) (xy 285.365641 -45.537321) (xy 285.418425 -45.519314) (xy 285.473268 -45.509184)
			(xy 285.529002 -45.507147) (xy 285.584439 -45.513247) (xy 285.638396 -45.527353) (xy 285.689725 -45.549165)
			(xy 285.737331 -45.578219) (xy 285.780199 -45.613894) (xy 285.817416 -45.655431) (xy 285.848189 -45.701944)
			(xy 285.871861 -45.752441) (xy 285.887929 -45.805848) (xy 285.896049 -45.861024) (xy 285.896558 -45.88891)
			(xy 285.896049 -45.916796) (xy 285.887929 -45.971972) (xy 285.871861 -46.025379) (xy 285.848189 -46.075876)
			(xy 285.844002 -46.082204) (xy 302.25238 -46.082204) (xy 302.252881 -46.054953) (xy 302.260637 -46.001007)
			(xy 302.275991 -45.948713) (xy 302.298631 -45.899137) (xy 302.328096 -45.853287) (xy 302.363786 -45.812097)
			(xy 302.404974 -45.776405) (xy 302.450823 -45.746939) (xy 302.500398 -45.724297) (xy 302.552691 -45.708941)
			(xy 302.606637 -45.701183) (xy 302.633888 -45.700696) (xy 302.660778 -45.701192) (xy 302.714027 -45.708738)
			(xy 302.76569 -45.723683) (xy 302.814743 -45.74573) (xy 302.860217 -45.774444) (xy 302.901212 -45.809255)
			(xy 302.936915 -45.849475) (xy 302.95215 -45.871638) (xy 302.959262 -45.882814) (xy 302.982122 -45.894752)
			(xy 303.081182 -45.892974) (xy 303.089679 -45.892475) (xy 303.105656 -45.88664) (xy 303.11885 -45.875906)
			(xy 303.1236 -45.868844) (xy 303.1236 -45.86859) (xy 303.138535 -45.844997) (xy 303.174212 -45.802046)
			(xy 303.215768 -45.764752) (xy 303.262316 -45.733914) (xy 303.312861 -45.710189) (xy 303.366324 -45.694084)
			(xy 303.421564 -45.685944) (xy 303.449482 -45.685456) (xy 303.476475 -45.685928) (xy 303.529923 -45.693531)
			(xy 303.581766 -45.708589) (xy 303.630971 -45.7308) (xy 303.676555 -45.759723) (xy 303.697386 -45.776896)
			(xy 303.705768 -45.784008) (xy 303.726088 -45.790104) (xy 303.811178 -45.779182) (xy 303.816538 -45.778444)
			(xy 303.826788 -45.774986) (xy 303.831498 -45.772324) (xy 303.840388 -45.766736) (xy 303.846738 -45.757846)
			(xy 303.846992 -45.757592) (xy 303.862371 -45.736413) (xy 303.897932 -45.698011) (xy 303.938415 -45.664837)
			(xy 303.983057 -45.637517) (xy 304.031018 -45.616564) (xy 304.081396 -45.602373) (xy 304.133243 -45.595211)
			(xy 304.159412 -45.594778) (xy 304.186662 -45.595293) (xy 304.240606 -45.603051) (xy 304.292897 -45.618406)
			(xy 304.342471 -45.641047) (xy 304.388318 -45.670513) (xy 304.429506 -45.706203) (xy 304.465194 -45.747391)
			(xy 304.494659 -45.793239) (xy 304.517298 -45.842814) (xy 304.523897 -45.865288) (xy 306.069236 -45.865288)
			(xy 306.073307 -45.809666) (xy 306.085433 -45.755229) (xy 306.105356 -45.703138) (xy 306.132652 -45.654503)
			(xy 306.166738 -45.61036) (xy 306.206887 -45.571651) (xy 306.252245 -45.5392) (xy 306.301845 -45.513699)
			(xy 306.354629 -45.495692) (xy 306.409472 -45.485562) (xy 306.465206 -45.483525) (xy 306.520643 -45.489625)
			(xy 306.5746 -45.503731) (xy 306.625929 -45.525543) (xy 306.673535 -45.554597) (xy 306.716403 -45.590272)
			(xy 306.75362 -45.631809) (xy 306.784393 -45.678322) (xy 306.808065 -45.728819) (xy 306.824133 -45.782226)
			(xy 306.832253 -45.837402) (xy 306.832553 -45.853858) (xy 307.258718 -45.853858) (xy 307.262789 -45.798236)
			(xy 307.274915 -45.743799) (xy 307.294838 -45.691708) (xy 307.322134 -45.643073) (xy 307.35622 -45.59893)
			(xy 307.396369 -45.560221) (xy 307.441727 -45.52777) (xy 307.491327 -45.502269) (xy 307.544111 -45.484262)
			(xy 307.598954 -45.474132) (xy 307.654688 -45.472095) (xy 307.710125 -45.478195) (xy 307.764082 -45.492301)
			(xy 307.815411 -45.514113) (xy 307.863017 -45.543167) (xy 307.905885 -45.578842) (xy 307.943102 -45.620379)
			(xy 307.973875 -45.666892) (xy 307.997547 -45.717389) (xy 308.013615 -45.770796) (xy 308.021735 -45.825972)
			(xy 308.022244 -45.853858) (xy 308.021735 -45.881744) (xy 308.02068 -45.88891) (xy 311.13298 -45.88891)
			(xy 311.137051 -45.833288) (xy 311.149177 -45.778851) (xy 311.1691 -45.72676) (xy 311.196396 -45.678125)
			(xy 311.230482 -45.633982) (xy 311.270631 -45.595273) (xy 311.315989 -45.562822) (xy 311.365589 -45.537321)
			(xy 311.418373 -45.519314) (xy 311.473216 -45.509184) (xy 311.52895 -45.507147) (xy 311.584387 -45.513247)
			(xy 311.638344 -45.527353) (xy 311.689673 -45.549165) (xy 311.737279 -45.578219) (xy 311.780147 -45.613894)
			(xy 311.817364 -45.655431) (xy 311.848137 -45.701944) (xy 311.871809 -45.752441) (xy 311.887877 -45.805848)
			(xy 311.895997 -45.861024) (xy 311.896506 -45.88891) (xy 311.895997 -45.916796) (xy 311.887877 -45.971972)
			(xy 311.871809 -46.025379) (xy 311.848137 -46.075876) (xy 311.84395 -46.082204) (xy 328.252328 -46.082204)
			(xy 328.252759 -46.05495) (xy 328.260517 -46.000996) (xy 328.275874 -45.948695) (xy 328.298519 -45.899113)
			(xy 328.327989 -45.853258) (xy 328.363687 -45.812064) (xy 328.404883 -45.77637) (xy 328.450741 -45.746903)
			(xy 328.500325 -45.724263) (xy 328.552627 -45.70891) (xy 328.606582 -45.701157) (xy 328.633836 -45.700696)
			(xy 328.660728 -45.701155) (xy 328.713978 -45.708708) (xy 328.765641 -45.723659) (xy 328.814695 -45.745712)
			(xy 328.860169 -45.774432) (xy 328.901162 -45.809248) (xy 328.936863 -45.849473) (xy 328.952098 -45.871638)
			(xy 328.95921 -45.882814) (xy 328.98207 -45.894752) (xy 329.08113 -45.892974) (xy 329.089631 -45.892507)
			(xy 329.105609 -45.886658) (xy 329.1188 -45.875911) (xy 329.123548 -45.868844) (xy 329.123548 -45.86859)
			(xy 329.13845 -45.844976) (xy 329.174133 -45.802024) (xy 329.215694 -45.764732) (xy 329.262247 -45.733896)
			(xy 329.312798 -45.710175) (xy 329.366266 -45.694075) (xy 329.42151 -45.68594) (xy 329.44943 -45.685456)
			(xy 329.476424 -45.6859) (xy 329.529873 -45.69351) (xy 329.581716 -45.708574) (xy 329.630921 -45.730792)
			(xy 329.676504 -45.75972) (xy 329.697334 -45.776896) (xy 329.705716 -45.784008) (xy 329.726036 -45.790104)
			(xy 329.811126 -45.779182) (xy 329.816483 -45.778429) (xy 329.826734 -45.774981) (xy 329.831446 -45.772324)
			(xy 329.840336 -45.766736) (xy 329.846686 -45.757846) (xy 329.84694 -45.757592) (xy 329.862289 -45.73639)
			(xy 329.897855 -45.697989) (xy 329.938343 -45.664817) (xy 329.98299 -45.637499) (xy 330.030957 -45.61655)
			(xy 330.081339 -45.602364) (xy 330.133189 -45.595208) (xy 330.15936 -45.594778) (xy 330.186614 -45.595267)
			(xy 330.240567 -45.603019) (xy 330.292868 -45.618371) (xy 330.342451 -45.64101) (xy 330.388308 -45.670476)
			(xy 330.429503 -45.706168) (xy 330.4652 -45.74736) (xy 330.494671 -45.793214) (xy 330.517315 -45.842795)
			(xy 330.52392 -45.865288) (xy 332.069184 -45.865288) (xy 332.073255 -45.809666) (xy 332.085381 -45.755229)
			(xy 332.105304 -45.703138) (xy 332.1326 -45.654503) (xy 332.166686 -45.61036) (xy 332.206835 -45.571651)
			(xy 332.252193 -45.5392) (xy 332.301793 -45.513699) (xy 332.354577 -45.495692) (xy 332.40942 -45.485562)
			(xy 332.465154 -45.483525) (xy 332.520591 -45.489625) (xy 332.574548 -45.503731) (xy 332.625877 -45.525543)
			(xy 332.673483 -45.554597) (xy 332.716351 -45.590272) (xy 332.753568 -45.631809) (xy 332.784341 -45.678322)
			(xy 332.808013 -45.728819) (xy 332.824081 -45.782226) (xy 332.832201 -45.837402) (xy 332.832501 -45.853858)
			(xy 333.258666 -45.853858) (xy 333.262737 -45.798236) (xy 333.274863 -45.743799) (xy 333.294786 -45.691708)
			(xy 333.322082 -45.643073) (xy 333.356168 -45.59893) (xy 333.396317 -45.560221) (xy 333.441675 -45.52777)
			(xy 333.491275 -45.502269) (xy 333.544059 -45.484262) (xy 333.598902 -45.474132) (xy 333.654636 -45.472095)
			(xy 333.710073 -45.478195) (xy 333.76403 -45.492301) (xy 333.815359 -45.514113) (xy 333.862965 -45.543167)
			(xy 333.905833 -45.578842) (xy 333.94305 -45.620379) (xy 333.973823 -45.666892) (xy 333.997495 -45.717389)
			(xy 334.013563 -45.770796) (xy 334.021683 -45.825972) (xy 334.022192 -45.853858) (xy 334.021683 -45.881744)
			(xy 334.020628 -45.88891) (xy 337.132928 -45.88891) (xy 337.136999 -45.833288) (xy 337.149125 -45.778851)
			(xy 337.169048 -45.72676) (xy 337.196344 -45.678125) (xy 337.23043 -45.633982) (xy 337.270579 -45.595273)
			(xy 337.315937 -45.562822) (xy 337.365537 -45.537321) (xy 337.418321 -45.519314) (xy 337.473164 -45.509184)
			(xy 337.528898 -45.507147) (xy 337.584335 -45.513247) (xy 337.638292 -45.527353) (xy 337.689621 -45.549165)
			(xy 337.737227 -45.578219) (xy 337.780095 -45.613894) (xy 337.817312 -45.655431) (xy 337.848085 -45.701944)
			(xy 337.871757 -45.752441) (xy 337.887825 -45.805848) (xy 337.895945 -45.861024) (xy 337.896454 -45.88891)
			(xy 337.895945 -45.916796) (xy 337.887825 -45.971972) (xy 337.871757 -46.025379) (xy 337.848085 -46.075876)
			(xy 337.843898 -46.082204) (xy 366.352582 -46.082204) (xy 366.353081 -46.054953) (xy 366.360837 -46.001007)
			(xy 366.376191 -45.948713) (xy 366.398831 -45.899136) (xy 366.428296 -45.853286) (xy 366.463986 -45.812096)
			(xy 366.505175 -45.776405) (xy 366.551024 -45.746938) (xy 366.6006 -45.724296) (xy 366.652893 -45.70894)
			(xy 366.706839 -45.701182) (xy 366.73409 -45.700696) (xy 366.76098 -45.70119) (xy 366.814229 -45.708737)
			(xy 366.865892 -45.723682) (xy 366.914946 -45.745729) (xy 366.96042 -45.774443) (xy 367.001414 -45.809255)
			(xy 367.037117 -45.849475) (xy 367.052352 -45.871638) (xy 367.059464 -45.882814) (xy 367.082324 -45.894752)
			(xy 367.181384 -45.892974) (xy 367.189881 -45.892476) (xy 367.205858 -45.886641) (xy 367.219052 -45.875906)
			(xy 367.223802 -45.868844) (xy 367.223802 -45.86859) (xy 367.238736 -45.844997) (xy 367.274413 -45.802045)
			(xy 367.315969 -45.764751) (xy 367.362517 -45.733913) (xy 367.413062 -45.710188) (xy 367.466526 -45.694084)
			(xy 367.521766 -45.685944) (xy 367.549684 -45.685456) (xy 367.576677 -45.685926) (xy 367.630125 -45.69353)
			(xy 367.681968 -45.708588) (xy 367.731173 -45.7308) (xy 367.776757 -45.759723) (xy 367.797588 -45.776896)
			(xy 367.80597 -45.784008) (xy 367.82629 -45.790104) (xy 367.91138 -45.779182) (xy 367.91674 -45.778445)
			(xy 367.92699 -45.774986) (xy 367.9317 -45.772324) (xy 367.94059 -45.766736) (xy 367.94694 -45.757846)
			(xy 367.947194 -45.757592) (xy 367.962572 -45.736412) (xy 367.998133 -45.69801) (xy 368.038616 -45.664836)
			(xy 368.083258 -45.637516) (xy 368.13122 -45.616563) (xy 368.181598 -45.602373) (xy 368.233445 -45.595211)
			(xy 368.259614 -45.594778) (xy 368.286864 -45.595293) (xy 368.340808 -45.603051) (xy 368.393099 -45.618407)
			(xy 368.442672 -45.641048) (xy 368.488519 -45.670513) (xy 368.529706 -45.706204) (xy 368.565395 -45.747392)
			(xy 368.594859 -45.79324) (xy 368.617498 -45.842814) (xy 368.624097 -45.865288) (xy 370.169438 -45.865288)
			(xy 370.173509 -45.809666) (xy 370.185635 -45.755229) (xy 370.205558 -45.703138) (xy 370.232854 -45.654503)
			(xy 370.26694 -45.61036) (xy 370.307089 -45.571651) (xy 370.352447 -45.5392) (xy 370.402047 -45.513699)
			(xy 370.454831 -45.495692) (xy 370.509674 -45.485562) (xy 370.565408 -45.483525) (xy 370.620845 -45.489625)
			(xy 370.674802 -45.503731) (xy 370.726131 -45.525543) (xy 370.773737 -45.554597) (xy 370.816605 -45.590272)
			(xy 370.853822 -45.631809) (xy 370.884595 -45.678322) (xy 370.908267 -45.728819) (xy 370.924335 -45.782226)
			(xy 370.932455 -45.837402) (xy 370.932755 -45.853858) (xy 371.35892 -45.853858) (xy 371.362991 -45.798236)
			(xy 371.375117 -45.743799) (xy 371.39504 -45.691708) (xy 371.422336 -45.643073) (xy 371.456422 -45.59893)
			(xy 371.496571 -45.560221) (xy 371.541929 -45.52777) (xy 371.591529 -45.502269) (xy 371.644313 -45.484262)
			(xy 371.699156 -45.474132) (xy 371.75489 -45.472095) (xy 371.810327 -45.478195) (xy 371.864284 -45.492301)
			(xy 371.915613 -45.514113) (xy 371.963219 -45.543167) (xy 372.006087 -45.578842) (xy 372.043304 -45.620379)
			(xy 372.074077 -45.666892) (xy 372.097749 -45.717389) (xy 372.113817 -45.770796) (xy 372.121937 -45.825972)
			(xy 372.122446 -45.853858) (xy 372.121937 -45.881744) (xy 372.120882 -45.88891) (xy 375.233182 -45.88891)
			(xy 375.237253 -45.833288) (xy 375.249379 -45.778851) (xy 375.269302 -45.72676) (xy 375.296598 -45.678125)
			(xy 375.330684 -45.633982) (xy 375.370833 -45.595273) (xy 375.416191 -45.562822) (xy 375.465791 -45.537321)
			(xy 375.518575 -45.519314) (xy 375.573418 -45.509184) (xy 375.629152 -45.507147) (xy 375.684589 -45.513247)
			(xy 375.738546 -45.527353) (xy 375.789875 -45.549165) (xy 375.837481 -45.578219) (xy 375.880349 -45.613894)
			(xy 375.917566 -45.655431) (xy 375.948339 -45.701944) (xy 375.972011 -45.752441) (xy 375.988079 -45.805848)
			(xy 375.996199 -45.861024) (xy 375.996708 -45.88891) (xy 375.996199 -45.916796) (xy 375.988079 -45.971972)
			(xy 375.972011 -46.025379) (xy 375.948339 -46.075876) (xy 375.944152 -46.082204) (xy 392.35253 -46.082204)
			(xy 392.352959 -46.05495) (xy 392.360717 -46.000995) (xy 392.376074 -45.948695) (xy 392.398719 -45.899112)
			(xy 392.42819 -45.853257) (xy 392.463887 -45.812063) (xy 392.505084 -45.77637) (xy 392.550942 -45.746903)
			(xy 392.600526 -45.724262) (xy 392.652829 -45.708909) (xy 392.706783 -45.701157) (xy 392.734038 -45.700696)
			(xy 392.76093 -45.701154) (xy 392.81418 -45.708707) (xy 392.865843 -45.723658) (xy 392.914897 -45.745712)
			(xy 392.960371 -45.774431) (xy 393.001364 -45.809248) (xy 393.037065 -45.849473) (xy 393.0523 -45.871638)
			(xy 393.059412 -45.882814) (xy 393.082272 -45.894752) (xy 393.181332 -45.892974) (xy 393.189833 -45.892509)
			(xy 393.205811 -45.886659) (xy 393.219002 -45.875911) (xy 393.22375 -45.868844) (xy 393.22375 -45.86859)
			(xy 393.238651 -45.844975) (xy 393.274333 -45.802023) (xy 393.315895 -45.764731) (xy 393.362449 -45.733895)
			(xy 393.413 -45.710174) (xy 393.466468 -45.694074) (xy 393.521712 -45.68594) (xy 393.549632 -45.685456)
			(xy 393.576626 -45.685899) (xy 393.630075 -45.693509) (xy 393.681919 -45.708574) (xy 393.731123 -45.730792)
			(xy 393.776706 -45.75972) (xy 393.797536 -45.776896) (xy 393.805918 -45.784008) (xy 393.826238 -45.790104)
			(xy 393.911328 -45.779182) (xy 393.916686 -45.778429) (xy 393.926936 -45.774982) (xy 393.931648 -45.772324)
			(xy 393.940538 -45.766736) (xy 393.946888 -45.757846) (xy 393.947142 -45.757592) (xy 393.96249 -45.73639)
			(xy 393.998056 -45.697988) (xy 394.038544 -45.664816) (xy 394.083192 -45.637499) (xy 394.131158 -45.61655)
			(xy 394.181541 -45.602364) (xy 394.233391 -45.595207) (xy 394.259562 -45.594778) (xy 394.286816 -45.595267)
			(xy 394.340769 -45.603019) (xy 394.393069 -45.618371) (xy 394.442652 -45.641011) (xy 394.488508 -45.670477)
			(xy 394.529704 -45.706169) (xy 394.565401 -45.747361) (xy 394.594871 -45.793214) (xy 394.617516 -45.842795)
			(xy 394.624121 -45.865288) (xy 396.169386 -45.865288) (xy 396.173457 -45.809666) (xy 396.185583 -45.755229)
			(xy 396.205506 -45.703138) (xy 396.232802 -45.654503) (xy 396.266888 -45.61036) (xy 396.307037 -45.571651)
			(xy 396.352395 -45.5392) (xy 396.401995 -45.513699) (xy 396.454779 -45.495692) (xy 396.509622 -45.485562)
			(xy 396.565356 -45.483525) (xy 396.620793 -45.489625) (xy 396.67475 -45.503731) (xy 396.726079 -45.525543)
			(xy 396.773685 -45.554597) (xy 396.816553 -45.590272) (xy 396.85377 -45.631809) (xy 396.884543 -45.678322)
			(xy 396.908215 -45.728819) (xy 396.924283 -45.782226) (xy 396.932403 -45.837402) (xy 396.932703 -45.853858)
			(xy 397.358868 -45.853858) (xy 397.362939 -45.798236) (xy 397.375065 -45.743799) (xy 397.394988 -45.691708)
			(xy 397.422284 -45.643073) (xy 397.45637 -45.59893) (xy 397.496519 -45.560221) (xy 397.541877 -45.52777)
			(xy 397.591477 -45.502269) (xy 397.644261 -45.484262) (xy 397.699104 -45.474132) (xy 397.754838 -45.472095)
			(xy 397.810275 -45.478195) (xy 397.864232 -45.492301) (xy 397.915561 -45.514113) (xy 397.963167 -45.543167)
			(xy 398.006035 -45.578842) (xy 398.043252 -45.620379) (xy 398.074025 -45.666892) (xy 398.097697 -45.717389)
			(xy 398.113765 -45.770796) (xy 398.121885 -45.825972) (xy 398.122394 -45.853858) (xy 398.121885 -45.881744)
			(xy 398.12083 -45.88891) (xy 401.23313 -45.88891) (xy 401.237201 -45.833288) (xy 401.249327 -45.778851)
			(xy 401.26925 -45.72676) (xy 401.296546 -45.678125) (xy 401.330632 -45.633982) (xy 401.370781 -45.595273)
			(xy 401.416139 -45.562822) (xy 401.465739 -45.537321) (xy 401.518523 -45.519314) (xy 401.573366 -45.509184)
			(xy 401.6291 -45.507147) (xy 401.684537 -45.513247) (xy 401.738494 -45.527353) (xy 401.789823 -45.549165)
			(xy 401.837429 -45.578219) (xy 401.880297 -45.613894) (xy 401.917514 -45.655431) (xy 401.948287 -45.701944)
			(xy 401.971959 -45.752441) (xy 401.988027 -45.805848) (xy 401.996147 -45.861024) (xy 401.996656 -45.88891)
			(xy 401.996147 -45.916796) (xy 401.988027 -45.971972) (xy 401.971959 -46.025379) (xy 401.948287 -46.075876)
			(xy 401.9441 -46.082204) (xy 418.352478 -46.082204) (xy 418.352981 -46.054953) (xy 418.360737 -46.001007)
			(xy 418.376091 -45.948714) (xy 418.398731 -45.899137) (xy 418.428195 -45.853288) (xy 418.463885 -45.812098)
			(xy 418.505073 -45.776406) (xy 418.550921 -45.746939) (xy 418.600497 -45.724297) (xy 418.65279 -45.708941)
			(xy 418.706736 -45.701183) (xy 418.733986 -45.700696) (xy 418.760876 -45.701193) (xy 418.814125 -45.708739)
			(xy 418.865787 -45.723684) (xy 418.914841 -45.745731) (xy 418.960315 -45.774444) (xy 419.00131 -45.809255)
			(xy 419.037013 -45.849475) (xy 419.052248 -45.871638) (xy 419.05936 -45.882814) (xy 419.08222 -45.894752)
			(xy 419.18128 -45.892974) (xy 419.189777 -45.892474) (xy 419.205754 -45.88664) (xy 419.218948 -45.875905)
			(xy 419.223698 -45.868844) (xy 419.223698 -45.86859) (xy 419.238634 -45.844998) (xy 419.274311 -45.802047)
			(xy 419.315867 -45.764753) (xy 419.362414 -45.733915) (xy 419.412959 -45.71019) (xy 419.466422 -45.694085)
			(xy 419.521662 -45.685944) (xy 419.54958 -45.685456) (xy 419.576573 -45.685929) (xy 419.630021 -45.693532)
			(xy 419.681864 -45.708589) (xy 419.731069 -45.730801) (xy 419.776653 -45.759723) (xy 419.797484 -45.776896)
			(xy 419.805866 -45.784008) (xy 419.826186 -45.790104) (xy 419.911276 -45.779182) (xy 419.916636 -45.778444)
			(xy 419.926886 -45.774986) (xy 419.931596 -45.772324) (xy 419.940486 -45.766736) (xy 419.946836 -45.757846)
			(xy 419.94709 -45.757592) (xy 419.96247 -45.736414) (xy 419.998031 -45.698012) (xy 420.038514 -45.664838)
			(xy 420.083156 -45.637518) (xy 420.131117 -45.616565) (xy 420.181495 -45.602373) (xy 420.233341 -45.595211)
			(xy 420.25951 -45.594778) (xy 420.28676 -45.595293) (xy 420.340704 -45.60305) (xy 420.392996 -45.618406)
			(xy 420.44257 -45.641047) (xy 420.488417 -45.670512) (xy 420.529605 -45.706202) (xy 420.565294 -45.747391)
			(xy 420.594758 -45.793239) (xy 420.617398 -45.842813) (xy 420.623997 -45.865288) (xy 422.169334 -45.865288)
			(xy 422.173405 -45.809666) (xy 422.185531 -45.755229) (xy 422.205454 -45.703138) (xy 422.23275 -45.654503)
			(xy 422.266836 -45.61036) (xy 422.306985 -45.571651) (xy 422.352343 -45.5392) (xy 422.401943 -45.513699)
			(xy 422.454727 -45.495692) (xy 422.50957 -45.485562) (xy 422.565304 -45.483525) (xy 422.620741 -45.489625)
			(xy 422.674698 -45.503731) (xy 422.726027 -45.525543) (xy 422.773633 -45.554597) (xy 422.816501 -45.590272)
			(xy 422.853718 -45.631809) (xy 422.884491 -45.678322) (xy 422.908163 -45.728819) (xy 422.924231 -45.782226)
			(xy 422.932351 -45.837402) (xy 422.932651 -45.853858) (xy 423.358816 -45.853858) (xy 423.362887 -45.798236)
			(xy 423.375013 -45.743799) (xy 423.394936 -45.691708) (xy 423.422232 -45.643073) (xy 423.456318 -45.59893)
			(xy 423.496467 -45.560221) (xy 423.541825 -45.52777) (xy 423.591425 -45.502269) (xy 423.644209 -45.484262)
			(xy 423.699052 -45.474132) (xy 423.754786 -45.472095) (xy 423.810223 -45.478195) (xy 423.86418 -45.492301)
			(xy 423.915509 -45.514113) (xy 423.963115 -45.543167) (xy 424.005983 -45.578842) (xy 424.0432 -45.620379)
			(xy 424.073973 -45.666892) (xy 424.097645 -45.717389) (xy 424.113713 -45.770796) (xy 424.121833 -45.825972)
			(xy 424.122342 -45.853858) (xy 424.121833 -45.881744) (xy 424.120778 -45.88891) (xy 427.233078 -45.88891)
			(xy 427.237149 -45.833288) (xy 427.249275 -45.778851) (xy 427.269198 -45.72676) (xy 427.296494 -45.678125)
			(xy 427.33058 -45.633982) (xy 427.370729 -45.595273) (xy 427.416087 -45.562822) (xy 427.465687 -45.537321)
			(xy 427.518471 -45.519314) (xy 427.573314 -45.509184) (xy 427.629048 -45.507147) (xy 427.684485 -45.513247)
			(xy 427.738442 -45.527353) (xy 427.789771 -45.549165) (xy 427.837377 -45.578219) (xy 427.880245 -45.613894)
			(xy 427.917462 -45.655431) (xy 427.948235 -45.701944) (xy 427.971907 -45.752441) (xy 427.987975 -45.805848)
			(xy 427.996095 -45.861024) (xy 427.996604 -45.88891) (xy 427.996095 -45.916796) (xy 427.987975 -45.971972)
			(xy 427.971907 -46.025379) (xy 427.948235 -46.075876) (xy 427.944048 -46.082204) (xy 444.352426 -46.082204)
			(xy 444.352859 -46.05495) (xy 444.360616 -46.000996) (xy 444.375974 -45.948695) (xy 444.398618 -45.899113)
			(xy 444.428089 -45.853258) (xy 444.463786 -45.812065) (xy 444.504982 -45.776371) (xy 444.550839 -45.746904)
			(xy 444.600424 -45.724263) (xy 444.652725 -45.70891) (xy 444.70668 -45.701157) (xy 444.733934 -45.700696)
			(xy 444.760826 -45.701157) (xy 444.814076 -45.708709) (xy 444.865739 -45.72366) (xy 444.914793 -45.745713)
			(xy 444.960267 -45.774432) (xy 445.00126 -45.809249) (xy 445.036961 -45.849473) (xy 445.052196 -45.871638)
			(xy 445.059308 -45.882814) (xy 445.082168 -45.894752) (xy 445.181228 -45.892974) (xy 445.189728 -45.892506)
			(xy 445.205707 -45.886657) (xy 445.218898 -45.875911) (xy 445.223646 -45.868844) (xy 445.223646 -45.86859)
			(xy 445.23855 -45.844977) (xy 445.274232 -45.802025) (xy 445.315793 -45.764733) (xy 445.362346 -45.733897)
			(xy 445.412896 -45.710175) (xy 445.466364 -45.694075) (xy 445.521608 -45.68594) (xy 445.549528 -45.685456)
			(xy 445.576522 -45.685901) (xy 445.629971 -45.693511) (xy 445.681814 -45.708575) (xy 445.731019 -45.730792)
			(xy 445.776602 -45.75972) (xy 445.797432 -45.776896) (xy 445.805814 -45.784008) (xy 445.826134 -45.790104)
			(xy 445.911224 -45.779182) (xy 445.916581 -45.778428) (xy 445.926832 -45.774981) (xy 445.931544 -45.772324)
			(xy 445.940434 -45.766736) (xy 445.946784 -45.757846) (xy 445.947038 -45.757592) (xy 445.962388 -45.736391)
			(xy 445.997954 -45.69799) (xy 446.038442 -45.664818) (xy 446.083089 -45.6375) (xy 446.131055 -45.616551)
			(xy 446.181437 -45.602364) (xy 446.233287 -45.595208) (xy 446.259458 -45.594778) (xy 446.286712 -45.595266)
			(xy 446.340665 -45.603018) (xy 446.392966 -45.61837) (xy 446.44255 -45.641009) (xy 446.488407 -45.670475)
			(xy 446.529603 -45.706168) (xy 446.5653 -45.74736) (xy 446.59477 -45.793213) (xy 446.617415 -45.842794)
			(xy 446.62402 -45.865288) (xy 448.169282 -45.865288) (xy 448.173353 -45.809666) (xy 448.185479 -45.755229)
			(xy 448.205402 -45.703138) (xy 448.232698 -45.654503) (xy 448.266784 -45.61036) (xy 448.306933 -45.571651)
			(xy 448.352291 -45.5392) (xy 448.401891 -45.513699) (xy 448.454675 -45.495692) (xy 448.509518 -45.485562)
			(xy 448.565252 -45.483525) (xy 448.620689 -45.489625) (xy 448.674646 -45.503731) (xy 448.725975 -45.525543)
			(xy 448.773581 -45.554597) (xy 448.816449 -45.590272) (xy 448.853666 -45.631809) (xy 448.884439 -45.678322)
			(xy 448.908111 -45.728819) (xy 448.924179 -45.782226) (xy 448.932299 -45.837402) (xy 448.932599 -45.853858)
			(xy 449.358764 -45.853858) (xy 449.362835 -45.798236) (xy 449.374961 -45.743799) (xy 449.394884 -45.691708)
			(xy 449.42218 -45.643073) (xy 449.456266 -45.59893) (xy 449.496415 -45.560221) (xy 449.541773 -45.52777)
			(xy 449.591373 -45.502269) (xy 449.644157 -45.484262) (xy 449.699 -45.474132) (xy 449.754734 -45.472095)
			(xy 449.810171 -45.478195) (xy 449.864128 -45.492301) (xy 449.915457 -45.514113) (xy 449.963063 -45.543167)
			(xy 450.005931 -45.578842) (xy 450.043148 -45.620379) (xy 450.073921 -45.666892) (xy 450.097593 -45.717389)
			(xy 450.113661 -45.770796) (xy 450.121781 -45.825972) (xy 450.12229 -45.853858) (xy 450.121781 -45.881744)
			(xy 450.120726 -45.88891) (xy 453.233026 -45.88891) (xy 453.237097 -45.833288) (xy 453.249223 -45.778851)
			(xy 453.269146 -45.72676) (xy 453.296442 -45.678125) (xy 453.330528 -45.633982) (xy 453.370677 -45.595273)
			(xy 453.416035 -45.562822) (xy 453.465635 -45.537321) (xy 453.518419 -45.519314) (xy 453.573262 -45.509184)
			(xy 453.628996 -45.507147) (xy 453.684433 -45.513247) (xy 453.73839 -45.527353) (xy 453.789719 -45.549165)
			(xy 453.837325 -45.578219) (xy 453.880193 -45.613894) (xy 453.91741 -45.655431) (xy 453.948183 -45.701944)
			(xy 453.971855 -45.752441) (xy 453.987923 -45.805848) (xy 453.996043 -45.861024) (xy 453.996552 -45.88891)
			(xy 453.996043 -45.916796) (xy 453.987923 -45.971972) (xy 453.971855 -46.025379) (xy 453.948183 -46.075876)
			(xy 453.91741 -46.122389) (xy 453.880193 -46.163926) (xy 453.837325 -46.199601) (xy 453.789719 -46.228655)
			(xy 453.73839 -46.250467) (xy 453.684433 -46.264573) (xy 453.628996 -46.270673) (xy 453.573262 -46.268636)
			(xy 453.518419 -46.258506) (xy 453.465635 -46.240499) (xy 453.416035 -46.214998) (xy 453.370677 -46.182547)
			(xy 453.330528 -46.143838) (xy 453.296442 -46.099695) (xy 453.269146 -46.05106) (xy 453.249223 -45.998969)
			(xy 453.237097 -45.944532) (xy 453.233026 -45.88891) (xy 450.120726 -45.88891) (xy 450.113661 -45.93692)
			(xy 450.097593 -45.990327) (xy 450.073921 -46.040824) (xy 450.043148 -46.087337) (xy 450.005931 -46.128874)
			(xy 449.963063 -46.164549) (xy 449.915457 -46.193603) (xy 449.864128 -46.215415) (xy 449.810171 -46.229521)
			(xy 449.754734 -46.235621) (xy 449.699 -46.233584) (xy 449.644157 -46.223454) (xy 449.591373 -46.205447)
			(xy 449.541773 -46.179946) (xy 449.496415 -46.147495) (xy 449.456266 -46.108786) (xy 449.42218 -46.064643)
			(xy 449.394884 -46.016008) (xy 449.374961 -45.963917) (xy 449.362835 -45.90948) (xy 449.358764 -45.853858)
			(xy 448.932599 -45.853858) (xy 448.932808 -45.865288) (xy 448.932299 -45.893174) (xy 448.924179 -45.94835)
			(xy 448.908111 -46.001757) (xy 448.884439 -46.052254) (xy 448.853666 -46.098767) (xy 448.816449 -46.140304)
			(xy 448.773581 -46.175979) (xy 448.725975 -46.205033) (xy 448.674646 -46.226845) (xy 448.620689 -46.240951)
			(xy 448.565252 -46.247051) (xy 448.509518 -46.245014) (xy 448.454675 -46.234884) (xy 448.401891 -46.216877)
			(xy 448.352291 -46.191376) (xy 448.306933 -46.158925) (xy 448.266784 -46.120216) (xy 448.232698 -46.076073)
			(xy 448.205402 -46.027438) (xy 448.185479 -45.975347) (xy 448.173353 -45.92091) (xy 448.169282 -45.865288)
			(xy 446.62402 -45.865288) (xy 446.632773 -45.895094) (xy 446.640531 -45.949046) (xy 446.640531 -46.003554)
			(xy 446.632773 -46.057506) (xy 446.617415 -46.109806) (xy 446.59477 -46.159387) (xy 446.5653 -46.20524)
			(xy 446.529603 -46.246432) (xy 446.488407 -46.282125) (xy 446.44255 -46.311591) (xy 446.392966 -46.33423)
			(xy 446.340665 -46.349582) (xy 446.286712 -46.357334) (xy 446.259458 -46.357794) (xy 446.232464 -46.357345)
			(xy 446.179016 -46.349735) (xy 446.127173 -46.334671) (xy 446.077969 -46.312454) (xy 446.032385 -46.283528)
			(xy 446.011554 -46.266354) (xy 446.003172 -46.259242) (xy 445.982852 -46.253146) (xy 445.897762 -46.264068)
			(xy 445.892403 -46.264812) (xy 445.882153 -46.268265) (xy 445.877442 -46.270926) (xy 445.868552 -46.276514)
			(xy 445.862202 -46.285404) (xy 445.861948 -46.285658) (xy 445.844363 -46.309863) (xy 445.80289 -46.352982)
			(xy 445.779398 -46.37151) (xy 445.77127 -46.377606) (xy 445.76111 -46.394624) (xy 445.749426 -46.475396)
			(xy 445.748431 -46.485332) (xy 445.753277 -46.504684) (xy 445.758824 -46.512988) (xy 445.776274 -46.537717)
			(xy 445.803981 -46.591523) (xy 445.822851 -46.649027) (xy 445.832409 -46.708788) (xy 445.832992 -46.739048)
			(xy 445.832567 -46.766301) (xy 445.824803 -46.820252) (xy 445.809441 -46.872549) (xy 445.799995 -46.893226)
			(xy 446.637154 -46.893226) (xy 446.641225 -46.837604) (xy 446.653351 -46.783167) (xy 446.673274 -46.731076)
			(xy 446.70057 -46.682441) (xy 446.734656 -46.638298) (xy 446.774805 -46.599589) (xy 446.820163 -46.567138)
			(xy 446.869763 -46.541637) (xy 446.922547 -46.52363) (xy 446.97739 -46.5135) (xy 447.033124 -46.511463)
			(xy 447.088561 -46.517563) (xy 447.142518 -46.531669) (xy 447.193847 -46.553481) (xy 447.241453 -46.582535)
			(xy 447.284321 -46.61821) (xy 447.321538 -46.659747) (xy 447.352311 -46.70626) (xy 447.375983 -46.756757)
			(xy 447.392051 -46.810164) (xy 447.400171 -46.86534) (xy 447.40068 -46.893226) (xy 447.400171 -46.921112)
			(xy 447.392051 -46.976288) (xy 447.375983 -47.029695) (xy 447.374945 -47.03191) (xy 448.169282 -47.03191)
			(xy 448.173353 -46.976288) (xy 448.185479 -46.921851) (xy 448.205402 -46.86976) (xy 448.232698 -46.821125)
			(xy 448.266784 -46.776982) (xy 448.306933 -46.738273) (xy 448.352291 -46.705822) (xy 448.401891 -46.680321)
			(xy 448.454675 -46.662314) (xy 448.509518 -46.652184) (xy 448.565252 -46.650147) (xy 448.620689 -46.656247)
			(xy 448.674646 -46.670353) (xy 448.725975 -46.692165) (xy 448.773581 -46.721219) (xy 448.816449 -46.756894)
			(xy 448.853666 -46.798431) (xy 448.884439 -46.844944) (xy 448.908111 -46.895441) (xy 448.924179 -46.948848)
			(xy 448.932299 -47.004024) (xy 448.932604 -47.020734) (xy 449.347334 -47.020734) (xy 449.351405 -46.965112)
			(xy 449.363531 -46.910675) (xy 449.383454 -46.858584) (xy 449.41075 -46.809949) (xy 449.444836 -46.765806)
			(xy 449.484985 -46.727097) (xy 449.530343 -46.694646) (xy 449.579943 -46.669145) (xy 449.632727 -46.651138)
			(xy 449.68757 -46.641008) (xy 449.743304 -46.638971) (xy 449.798741 -46.645071) (xy 449.852698 -46.659177)
			(xy 449.904027 -46.680989) (xy 449.925077 -46.693836) (xy 450.976238 -46.693836) (xy 450.976724 -46.666585)
			(xy 450.98448 -46.612637) (xy 450.999835 -46.560342) (xy 451.022477 -46.510765) (xy 451.051943 -46.464915)
			(xy 451.087634 -46.423724) (xy 451.128825 -46.388033) (xy 451.174675 -46.358567) (xy 451.224252 -46.335925)
			(xy 451.276547 -46.32057) (xy 451.330495 -46.312814) (xy 451.384997 -46.312814) (xy 451.438945 -46.32057)
			(xy 451.49124 -46.335925) (xy 451.540817 -46.358567) (xy 451.586667 -46.388033) (xy 451.627858 -46.423724)
			(xy 451.663549 -46.464915) (xy 451.693015 -46.510765) (xy 451.715657 -46.560342) (xy 451.731012 -46.612637)
			(xy 451.738768 -46.666585) (xy 451.739254 -46.693836) (xy 451.738788 -46.720264) (xy 451.731477 -46.772612)
			(xy 451.717002 -46.823447) (xy 451.69564 -46.871793) (xy 451.682104 -46.894496) (xy 451.682104 -46.89475)
			(xy 451.676629 -46.904711) (xy 451.674114 -46.927268) (xy 451.677278 -46.938184) (xy 451.707758 -47.023782)
			(xy 451.724014 -47.040038) (xy 451.734936 -47.043848) (xy 451.759443 -47.052923) (xy 451.805895 -47.076865)
			(xy 451.848648 -47.106919) (xy 451.8869 -47.142526) (xy 451.919937 -47.183018) (xy 451.947141 -47.227638)
			(xy 451.968003 -47.275553) (xy 451.982133 -47.325866) (xy 451.989267 -47.377636) (xy 451.989698 -47.403766)
			(xy 451.989212 -47.431017) (xy 451.987689 -47.441612) (xy 453.261728 -47.441612) (xy 453.265799 -47.38599)
			(xy 453.277925 -47.331553) (xy 453.297848 -47.279462) (xy 453.325144 -47.230827) (xy 453.35923 -47.186684)
			(xy 453.399379 -47.147975) (xy 453.444737 -47.115524) (xy 453.494337 -47.090023) (xy 453.547121 -47.072016)
			(xy 453.601964 -47.061886) (xy 453.657698 -47.059849) (xy 453.713135 -47.065949) (xy 453.767092 -47.080055)
			(xy 453.818421 -47.101867) (xy 453.866027 -47.130921) (xy 453.908895 -47.166596) (xy 453.946112 -47.208133)
			(xy 453.976885 -47.254646) (xy 454.000557 -47.305143) (xy 454.016625 -47.35855) (xy 454.024745 -47.413726)
			(xy 454.025254 -47.441612) (xy 454.024745 -47.469498) (xy 454.016625 -47.524674) (xy 454.000557 -47.578081)
			(xy 453.976885 -47.628578) (xy 453.946112 -47.675091) (xy 453.908895 -47.716628) (xy 453.866027 -47.752303)
			(xy 453.818421 -47.781357) (xy 453.767092 -47.803169) (xy 453.713135 -47.817275) (xy 453.657698 -47.823375)
			(xy 453.601964 -47.821338) (xy 453.547121 -47.811208) (xy 453.494337 -47.793201) (xy 453.444737 -47.7677)
			(xy 453.399379 -47.735249) (xy 453.35923 -47.69654) (xy 453.325144 -47.652397) (xy 453.297848 -47.603762)
			(xy 453.277925 -47.551671) (xy 453.265799 -47.497234) (xy 453.261728 -47.441612) (xy 451.987689 -47.441612)
			(xy 451.981456 -47.484965) (xy 451.966101 -47.53726) (xy 451.943459 -47.586837) (xy 451.913993 -47.632687)
			(xy 451.878302 -47.673878) (xy 451.837111 -47.709569) (xy 451.791261 -47.739035) (xy 451.741684 -47.761677)
			(xy 451.689389 -47.777032) (xy 451.635441 -47.784788) (xy 451.580939 -47.784788) (xy 451.526991 -47.777032)
			(xy 451.474696 -47.761677) (xy 451.425119 -47.739035) (xy 451.379269 -47.709569) (xy 451.338078 -47.673878)
			(xy 451.302387 -47.632687) (xy 451.272921 -47.586837) (xy 451.250279 -47.53726) (xy 451.234924 -47.484965)
			(xy 451.227168 -47.431017) (xy 451.226682 -47.403766) (xy 451.227158 -47.377339) (xy 451.234467 -47.324991)
			(xy 451.248939 -47.274157) (xy 451.270298 -47.225809) (xy 451.283832 -47.203106) (xy 451.283832 -47.202852)
			(xy 451.289405 -47.192924) (xy 451.291929 -47.170322) (xy 451.288658 -47.159418) (xy 451.258178 -47.07382)
			(xy 451.241922 -47.057564) (xy 451.231 -47.053754) (xy 451.206502 -47.044657) (xy 451.160048 -47.02072)
			(xy 451.117295 -46.990669) (xy 451.079041 -46.955066) (xy 451.046003 -46.914576) (xy 451.018798 -46.869958)
			(xy 450.997935 -46.822045) (xy 450.983804 -46.771734) (xy 450.976669 -46.719965) (xy 450.976238 -46.693836)
			(xy 449.925077 -46.693836) (xy 449.951633 -46.710043) (xy 449.994501 -46.745718) (xy 450.031718 -46.787255)
			(xy 450.062491 -46.833768) (xy 450.086163 -46.884265) (xy 450.102231 -46.937672) (xy 450.110351 -46.992848)
			(xy 450.11086 -47.020734) (xy 450.110351 -47.04862) (xy 450.102231 -47.103796) (xy 450.086163 -47.157203)
			(xy 450.062491 -47.2077) (xy 450.031718 -47.254213) (xy 449.994501 -47.29575) (xy 449.951633 -47.331425)
			(xy 449.904027 -47.360479) (xy 449.852698 -47.382291) (xy 449.798741 -47.396397) (xy 449.743304 -47.402497)
			(xy 449.68757 -47.40046) (xy 449.632727 -47.39033) (xy 449.579943 -47.372323) (xy 449.530343 -47.346822)
			(xy 449.484985 -47.314371) (xy 449.444836 -47.275662) (xy 449.41075 -47.231519) (xy 449.383454 -47.182884)
			(xy 449.363531 -47.130793) (xy 449.351405 -47.076356) (xy 449.347334 -47.020734) (xy 448.932604 -47.020734)
			(xy 448.932808 -47.03191) (xy 448.932299 -47.059796) (xy 448.924179 -47.114972) (xy 448.908111 -47.168379)
			(xy 448.884439 -47.218876) (xy 448.853666 -47.265389) (xy 448.816449 -47.306926) (xy 448.773581 -47.342601)
			(xy 448.725975 -47.371655) (xy 448.674646 -47.393467) (xy 448.620689 -47.407573) (xy 448.565252 -47.413673)
			(xy 448.509518 -47.411636) (xy 448.454675 -47.401506) (xy 448.401891 -47.383499) (xy 448.352291 -47.357998)
			(xy 448.306933 -47.325547) (xy 448.266784 -47.286838) (xy 448.232698 -47.242695) (xy 448.205402 -47.19406)
			(xy 448.185479 -47.141969) (xy 448.173353 -47.087532) (xy 448.169282 -47.03191) (xy 447.374945 -47.03191)
			(xy 447.352311 -47.080192) (xy 447.321538 -47.126705) (xy 447.284321 -47.168242) (xy 447.241453 -47.203917)
			(xy 447.193847 -47.232971) (xy 447.142518 -47.254783) (xy 447.088561 -47.268889) (xy 447.033124 -47.274989)
			(xy 446.97739 -47.272952) (xy 446.922547 -47.262822) (xy 446.869763 -47.244815) (xy 446.820163 -47.219314)
			(xy 446.774805 -47.186863) (xy 446.734656 -47.148154) (xy 446.70057 -47.104011) (xy 446.673274 -47.055376)
			(xy 446.653351 -47.003285) (xy 446.641225 -46.948848) (xy 446.637154 -46.893226) (xy 445.799995 -46.893226)
			(xy 445.786793 -46.922127) (xy 445.757321 -46.967978) (xy 445.721623 -47.009168) (xy 445.680427 -47.044859)
			(xy 445.634571 -47.074324) (xy 445.584989 -47.096964) (xy 445.532689 -47.112317) (xy 445.478737 -47.120071)
			(xy 445.451484 -47.120556) (xy 445.42545 -47.120111) (xy 445.373868 -47.113022) (xy 445.323726 -47.098992)
			(xy 445.275955 -47.078281) (xy 445.23144 -47.051272) (xy 445.210946 -47.035212) (xy 445.203326 -47.029116)
			(xy 445.184784 -47.023274) (xy 445.105028 -47.029624) (xy 445.095392 -47.030804) (xy 445.07802 -47.039433)
			(xy 445.071246 -47.046388) (xy 445.053065 -47.066034) (xy 445.012157 -47.100556) (xy 444.966828 -47.129025)
			(xy 444.917967 -47.150882) (xy 444.866531 -47.1657) (xy 444.81353 -47.173187) (xy 444.786766 -47.173642)
			(xy 444.759515 -47.173154) (xy 444.70557 -47.165394) (xy 444.653277 -47.150036) (xy 444.603702 -47.127393)
			(xy 444.557853 -47.097927) (xy 444.516664 -47.062236) (xy 444.480973 -47.021047) (xy 444.451507 -46.975198)
			(xy 444.428864 -46.925623) (xy 444.413506 -46.87333) (xy 444.405746 -46.819385) (xy 444.405258 -46.792134)
			(xy 444.405794 -46.763361) (xy 444.414444 -46.706467) (xy 444.431538 -46.651517) (xy 444.456689 -46.599757)
			(xy 444.489326 -46.55236) (xy 444.508636 -46.531022) (xy 444.515531 -46.522968) (xy 444.522621 -46.503013)
			(xy 444.522352 -46.492414) (xy 444.516764 -46.417992) (xy 444.5155 -46.407519) (xy 444.505638 -46.388891)
			(xy 444.497714 -46.381924) (xy 444.49746 -46.38167) (xy 444.475284 -46.363435) (xy 444.436071 -46.321503)
			(xy 444.403583 -46.27417) (xy 444.378553 -46.222504) (xy 444.361546 -46.167671) (xy 444.352944 -46.110909)
			(xy 444.352426 -46.082204) (xy 427.944048 -46.082204) (xy 427.917462 -46.122389) (xy 427.880245 -46.163926)
			(xy 427.837377 -46.199601) (xy 427.789771 -46.228655) (xy 427.738442 -46.250467) (xy 427.684485 -46.264573)
			(xy 427.629048 -46.270673) (xy 427.573314 -46.268636) (xy 427.518471 -46.258506) (xy 427.465687 -46.240499)
			(xy 427.416087 -46.214998) (xy 427.370729 -46.182547) (xy 427.33058 -46.143838) (xy 427.296494 -46.099695)
			(xy 427.269198 -46.05106) (xy 427.249275 -45.998969) (xy 427.237149 -45.944532) (xy 427.233078 -45.88891)
			(xy 424.120778 -45.88891) (xy 424.113713 -45.93692) (xy 424.097645 -45.990327) (xy 424.073973 -46.040824)
			(xy 424.0432 -46.087337) (xy 424.005983 -46.128874) (xy 423.963115 -46.164549) (xy 423.915509 -46.193603)
			(xy 423.86418 -46.215415) (xy 423.810223 -46.229521) (xy 423.754786 -46.235621) (xy 423.699052 -46.233584)
			(xy 423.644209 -46.223454) (xy 423.591425 -46.205447) (xy 423.541825 -46.179946) (xy 423.496467 -46.147495)
			(xy 423.456318 -46.108786) (xy 423.422232 -46.064643) (xy 423.394936 -46.016008) (xy 423.375013 -45.963917)
			(xy 423.362887 -45.90948) (xy 423.358816 -45.853858) (xy 422.932651 -45.853858) (xy 422.93286 -45.865288)
			(xy 422.932351 -45.893174) (xy 422.924231 -45.94835) (xy 422.908163 -46.001757) (xy 422.884491 -46.052254)
			(xy 422.853718 -46.098767) (xy 422.816501 -46.140304) (xy 422.773633 -46.175979) (xy 422.726027 -46.205033)
			(xy 422.674698 -46.226845) (xy 422.620741 -46.240951) (xy 422.565304 -46.247051) (xy 422.50957 -46.245014)
			(xy 422.454727 -46.234884) (xy 422.401943 -46.216877) (xy 422.352343 -46.191376) (xy 422.306985 -46.158925)
			(xy 422.266836 -46.120216) (xy 422.23275 -46.076073) (xy 422.205454 -46.027438) (xy 422.185531 -45.975347)
			(xy 422.173405 -45.92091) (xy 422.169334 -45.865288) (xy 420.623997 -45.865288) (xy 420.632752 -45.895105)
			(xy 420.640508 -45.94905) (xy 420.640508 -46.00355) (xy 420.632752 -46.057495) (xy 420.617398 -46.109787)
			(xy 420.594758 -46.159361) (xy 420.565294 -46.205209) (xy 420.529605 -46.246398) (xy 420.488417 -46.282088)
			(xy 420.44257 -46.311553) (xy 420.392996 -46.334194) (xy 420.340704 -46.34955) (xy 420.28676 -46.357307)
			(xy 420.25951 -46.357794) (xy 420.232517 -46.357315) (xy 420.179071 -46.349712) (xy 420.127228 -46.334655)
			(xy 420.078023 -46.312445) (xy 420.032437 -46.283526) (xy 420.011606 -46.266354) (xy 420.003224 -46.259242)
			(xy 419.982904 -46.253146) (xy 419.897814 -46.264068) (xy 419.892452 -46.264798) (xy 419.882203 -46.268261)
			(xy 419.877494 -46.270926) (xy 419.868604 -46.276514) (xy 419.862254 -46.285404) (xy 419.862 -46.285658)
			(xy 419.844408 -46.309858) (xy 419.802939 -46.35298) (xy 419.77945 -46.37151) (xy 419.771322 -46.377606)
			(xy 419.761162 -46.394624) (xy 419.749478 -46.475396) (xy 419.748473 -46.485332) (xy 419.753325 -46.504685)
			(xy 419.758876 -46.512988) (xy 419.77632 -46.537721) (xy 419.80403 -46.591525) (xy 419.822902 -46.649028)
			(xy 419.832461 -46.708788) (xy 419.833044 -46.739048) (xy 419.832567 -46.766299) (xy 419.824805 -46.820245)
			(xy 419.809445 -46.872538) (xy 419.799995 -46.893226) (xy 420.637206 -46.893226) (xy 420.641277 -46.837604)
			(xy 420.653403 -46.783167) (xy 420.673326 -46.731076) (xy 420.700622 -46.682441) (xy 420.734708 -46.638298)
			(xy 420.774857 -46.599589) (xy 420.820215 -46.567138) (xy 420.869815 -46.541637) (xy 420.922599 -46.52363)
			(xy 420.977442 -46.5135) (xy 421.033176 -46.511463) (xy 421.088613 -46.517563) (xy 421.14257 -46.531669)
			(xy 421.193899 -46.553481) (xy 421.241505 -46.582535) (xy 421.284373 -46.61821) (xy 421.32159 -46.659747)
			(xy 421.352363 -46.70626) (xy 421.376035 -46.756757) (xy 421.392103 -46.810164) (xy 421.400223 -46.86534)
			(xy 421.400732 -46.893226) (xy 421.400223 -46.921112) (xy 421.392103 -46.976288) (xy 421.376035 -47.029695)
			(xy 421.374997 -47.03191) (xy 422.169334 -47.03191) (xy 422.173405 -46.976288) (xy 422.185531 -46.921851)
			(xy 422.205454 -46.86976) (xy 422.23275 -46.821125) (xy 422.266836 -46.776982) (xy 422.306985 -46.738273)
			(xy 422.352343 -46.705822) (xy 422.401943 -46.680321) (xy 422.454727 -46.662314) (xy 422.50957 -46.652184)
			(xy 422.565304 -46.650147) (xy 422.620741 -46.656247) (xy 422.674698 -46.670353) (xy 422.726027 -46.692165)
			(xy 422.773633 -46.721219) (xy 422.816501 -46.756894) (xy 422.853718 -46.798431) (xy 422.884491 -46.844944)
			(xy 422.908163 -46.895441) (xy 422.924231 -46.948848) (xy 422.932351 -47.004024) (xy 422.932656 -47.020734)
			(xy 423.347386 -47.020734) (xy 423.351457 -46.965112) (xy 423.363583 -46.910675) (xy 423.383506 -46.858584)
			(xy 423.410802 -46.809949) (xy 423.444888 -46.765806) (xy 423.485037 -46.727097) (xy 423.530395 -46.694646)
			(xy 423.579995 -46.669145) (xy 423.632779 -46.651138) (xy 423.687622 -46.641008) (xy 423.743356 -46.638971)
			(xy 423.798793 -46.645071) (xy 423.85275 -46.659177) (xy 423.904079 -46.680989) (xy 423.925129 -46.693836)
			(xy 424.97629 -46.693836) (xy 424.976776 -46.666585) (xy 424.984532 -46.612637) (xy 424.999887 -46.560342)
			(xy 425.022529 -46.510765) (xy 425.051995 -46.464915) (xy 425.087686 -46.423724) (xy 425.128877 -46.388033)
			(xy 425.174727 -46.358567) (xy 425.224304 -46.335925) (xy 425.276599 -46.32057) (xy 425.330547 -46.312814)
			(xy 425.385049 -46.312814) (xy 425.438997 -46.32057) (xy 425.491292 -46.335925) (xy 425.540869 -46.358567)
			(xy 425.586719 -46.388033) (xy 425.62791 -46.423724) (xy 425.663601 -46.464915) (xy 425.693067 -46.510765)
			(xy 425.715709 -46.560342) (xy 425.731064 -46.612637) (xy 425.73882 -46.666585) (xy 425.739306 -46.693836)
			(xy 425.738832 -46.720264) (xy 425.731523 -46.772611) (xy 425.71705 -46.823446) (xy 425.695691 -46.871793)
			(xy 425.682156 -46.894496) (xy 425.682156 -46.89475) (xy 425.676581 -46.904677) (xy 425.674059 -46.92728)
			(xy 425.67733 -46.938184) (xy 425.70781 -47.023782) (xy 425.724066 -47.040038) (xy 425.734988 -47.043848)
			(xy 425.759506 -47.052894) (xy 425.805957 -47.076841) (xy 425.848708 -47.106901) (xy 425.886958 -47.142512)
			(xy 425.919993 -47.183008) (xy 425.947196 -47.227631) (xy 425.968056 -47.275549) (xy 425.982186 -47.325864)
			(xy 425.989319 -47.377635) (xy 425.98975 -47.403766) (xy 425.989264 -47.431017) (xy 425.987741 -47.441612)
			(xy 427.26178 -47.441612) (xy 427.265851 -47.38599) (xy 427.277977 -47.331553) (xy 427.2979 -47.279462)
			(xy 427.325196 -47.230827) (xy 427.359282 -47.186684) (xy 427.399431 -47.147975) (xy 427.444789 -47.115524)
			(xy 427.494389 -47.090023) (xy 427.547173 -47.072016) (xy 427.602016 -47.061886) (xy 427.65775 -47.059849)
			(xy 427.713187 -47.065949) (xy 427.767144 -47.080055) (xy 427.818473 -47.101867) (xy 427.866079 -47.130921)
			(xy 427.908947 -47.166596) (xy 427.946164 -47.208133) (xy 427.976937 -47.254646) (xy 428.000609 -47.305143)
			(xy 428.016677 -47.35855) (xy 428.024797 -47.413726) (xy 428.025306 -47.441612) (xy 428.024797 -47.469498)
			(xy 428.016677 -47.524674) (xy 428.000609 -47.578081) (xy 427.976937 -47.628578) (xy 427.946164 -47.675091)
			(xy 427.908947 -47.716628) (xy 427.866079 -47.752303) (xy 427.818473 -47.781357) (xy 427.767144 -47.803169)
			(xy 427.713187 -47.817275) (xy 427.65775 -47.823375) (xy 427.602016 -47.821338) (xy 427.547173 -47.811208)
			(xy 427.494389 -47.793201) (xy 427.444789 -47.7677) (xy 427.399431 -47.735249) (xy 427.359282 -47.69654)
			(xy 427.325196 -47.652397) (xy 427.2979 -47.603762) (xy 427.277977 -47.551671) (xy 427.265851 -47.497234)
			(xy 427.26178 -47.441612) (xy 425.987741 -47.441612) (xy 425.981508 -47.484965) (xy 425.966153 -47.53726)
			(xy 425.943511 -47.586837) (xy 425.914045 -47.632687) (xy 425.878354 -47.673878) (xy 425.837163 -47.709569)
			(xy 425.791313 -47.739035) (xy 425.741736 -47.761677) (xy 425.689441 -47.777032) (xy 425.635493 -47.784788)
			(xy 425.580991 -47.784788) (xy 425.527043 -47.777032) (xy 425.474748 -47.761677) (xy 425.425171 -47.739035)
			(xy 425.379321 -47.709569) (xy 425.33813 -47.673878) (xy 425.302439 -47.632687) (xy 425.272973 -47.586837)
			(xy 425.250331 -47.53726) (xy 425.234976 -47.484965) (xy 425.22722 -47.431017) (xy 425.226734 -47.403766)
			(xy 425.227203 -47.377338) (xy 425.234513 -47.324991) (xy 425.248987 -47.274156) (xy 425.270349 -47.225809)
			(xy 425.283884 -47.203106) (xy 425.283884 -47.202852) (xy 425.289358 -47.19289) (xy 425.291874 -47.170334)
			(xy 425.28871 -47.159418) (xy 425.25823 -47.07382) (xy 425.241974 -47.057564) (xy 425.231052 -47.053754)
			(xy 425.206544 -47.044684) (xy 425.160091 -47.020741) (xy 425.117339 -46.990685) (xy 425.079087 -46.955078)
			(xy 425.046051 -46.914585) (xy 425.018847 -46.869964) (xy 424.997985 -46.822049) (xy 424.983855 -46.771736)
			(xy 424.976721 -46.719966) (xy 424.97629 -46.693836) (xy 423.925129 -46.693836) (xy 423.951685 -46.710043)
			(xy 423.994553 -46.745718) (xy 424.03177 -46.787255) (xy 424.062543 -46.833768) (xy 424.086215 -46.884265)
			(xy 424.102283 -46.937672) (xy 424.110403 -46.992848) (xy 424.110912 -47.020734) (xy 424.110403 -47.04862)
			(xy 424.102283 -47.103796) (xy 424.086215 -47.157203) (xy 424.062543 -47.2077) (xy 424.03177 -47.254213)
			(xy 423.994553 -47.29575) (xy 423.951685 -47.331425) (xy 423.904079 -47.360479) (xy 423.85275 -47.382291)
			(xy 423.798793 -47.396397) (xy 423.743356 -47.402497) (xy 423.687622 -47.40046) (xy 423.632779 -47.39033)
			(xy 423.579995 -47.372323) (xy 423.530395 -47.346822) (xy 423.485037 -47.314371) (xy 423.444888 -47.275662)
			(xy 423.410802 -47.231519) (xy 423.383506 -47.182884) (xy 423.363583 -47.130793) (xy 423.351457 -47.076356)
			(xy 423.347386 -47.020734) (xy 422.932656 -47.020734) (xy 422.93286 -47.03191) (xy 422.932351 -47.059796)
			(xy 422.924231 -47.114972) (xy 422.908163 -47.168379) (xy 422.884491 -47.218876) (xy 422.853718 -47.265389)
			(xy 422.816501 -47.306926) (xy 422.773633 -47.342601) (xy 422.726027 -47.371655) (xy 422.674698 -47.393467)
			(xy 422.620741 -47.407573) (xy 422.565304 -47.413673) (xy 422.50957 -47.411636) (xy 422.454727 -47.401506)
			(xy 422.401943 -47.383499) (xy 422.352343 -47.357998) (xy 422.306985 -47.325547) (xy 422.266836 -47.286838)
			(xy 422.23275 -47.242695) (xy 422.205454 -47.19406) (xy 422.185531 -47.141969) (xy 422.173405 -47.087532)
			(xy 422.169334 -47.03191) (xy 421.374997 -47.03191) (xy 421.352363 -47.080192) (xy 421.32159 -47.126705)
			(xy 421.284373 -47.168242) (xy 421.241505 -47.203917) (xy 421.193899 -47.232971) (xy 421.14257 -47.254783)
			(xy 421.088613 -47.268889) (xy 421.033176 -47.274989) (xy 420.977442 -47.272952) (xy 420.922599 -47.262822)
			(xy 420.869815 -47.244815) (xy 420.820215 -47.219314) (xy 420.774857 -47.186863) (xy 420.734708 -47.148154)
			(xy 420.700622 -47.104011) (xy 420.673326 -47.055376) (xy 420.653403 -47.003285) (xy 420.641277 -46.948848)
			(xy 420.637206 -46.893226) (xy 419.799995 -46.893226) (xy 419.786801 -46.922113) (xy 419.757333 -46.967961)
			(xy 419.721641 -47.00915) (xy 419.680451 -47.044841) (xy 419.634602 -47.074307) (xy 419.585026 -47.09695)
			(xy 419.532733 -47.112307) (xy 419.478787 -47.120068) (xy 419.451536 -47.120556) (xy 419.425503 -47.120081)
			(xy 419.373922 -47.113) (xy 419.323781 -47.098976) (xy 419.276009 -47.078272) (xy 419.231493 -47.051269)
			(xy 419.210998 -47.035212) (xy 419.203378 -47.029116) (xy 419.184836 -47.023274) (xy 419.10508 -47.029624)
			(xy 419.09544 -47.030781) (xy 419.078069 -47.039426) (xy 419.071298 -47.046388) (xy 419.053141 -47.066057)
			(xy 419.012228 -47.100577) (xy 418.966894 -47.129043) (xy 418.918028 -47.150897) (xy 418.866588 -47.165709)
			(xy 418.813583 -47.17319) (xy 418.786818 -47.173642) (xy 418.759569 -47.173105) (xy 418.705625 -47.165352)
			(xy 418.653333 -47.150001) (xy 418.603758 -47.127364) (xy 418.557909 -47.097903) (xy 418.51672 -47.062217)
			(xy 418.481028 -47.021032) (xy 418.451561 -46.975187) (xy 418.428917 -46.925616) (xy 418.413559 -46.873326)
			(xy 418.405799 -46.819383) (xy 418.40531 -46.792134) (xy 418.405832 -46.76336) (xy 418.414483 -46.706465)
			(xy 418.43158 -46.651515) (xy 418.456734 -46.599755) (xy 418.489375 -46.552359) (xy 418.508688 -46.531022)
			(xy 418.515589 -46.522973) (xy 418.522674 -46.503014) (xy 418.522404 -46.492414) (xy 418.516816 -46.417992)
			(xy 418.515535 -46.407522) (xy 418.505684 -46.388895) (xy 418.497766 -46.381924) (xy 418.497512 -46.38167)
			(xy 418.475326 -46.363447) (xy 418.436116 -46.321511) (xy 418.403631 -46.274175) (xy 418.378603 -46.222507)
			(xy 418.361597 -46.167672) (xy 418.352996 -46.110909) (xy 418.352478 -46.082204) (xy 401.9441 -46.082204)
			(xy 401.917514 -46.122389) (xy 401.880297 -46.163926) (xy 401.837429 -46.199601) (xy 401.789823 -46.228655)
			(xy 401.738494 -46.250467) (xy 401.684537 -46.264573) (xy 401.6291 -46.270673) (xy 401.573366 -46.268636)
			(xy 401.518523 -46.258506) (xy 401.465739 -46.240499) (xy 401.416139 -46.214998) (xy 401.370781 -46.182547)
			(xy 401.330632 -46.143838) (xy 401.296546 -46.099695) (xy 401.26925 -46.05106) (xy 401.249327 -45.998969)
			(xy 401.237201 -45.944532) (xy 401.23313 -45.88891) (xy 398.12083 -45.88891) (xy 398.113765 -45.93692)
			(xy 398.097697 -45.990327) (xy 398.074025 -46.040824) (xy 398.043252 -46.087337) (xy 398.006035 -46.128874)
			(xy 397.963167 -46.164549) (xy 397.915561 -46.193603) (xy 397.864232 -46.215415) (xy 397.810275 -46.229521)
			(xy 397.754838 -46.235621) (xy 397.699104 -46.233584) (xy 397.644261 -46.223454) (xy 397.591477 -46.205447)
			(xy 397.541877 -46.179946) (xy 397.496519 -46.147495) (xy 397.45637 -46.108786) (xy 397.422284 -46.064643)
			(xy 397.394988 -46.016008) (xy 397.375065 -45.963917) (xy 397.362939 -45.90948) (xy 397.358868 -45.853858)
			(xy 396.932703 -45.853858) (xy 396.932912 -45.865288) (xy 396.932403 -45.893174) (xy 396.924283 -45.94835)
			(xy 396.908215 -46.001757) (xy 396.884543 -46.052254) (xy 396.85377 -46.098767) (xy 396.816553 -46.140304)
			(xy 396.773685 -46.175979) (xy 396.726079 -46.205033) (xy 396.67475 -46.226845) (xy 396.620793 -46.240951)
			(xy 396.565356 -46.247051) (xy 396.509622 -46.245014) (xy 396.454779 -46.234884) (xy 396.401995 -46.216877)
			(xy 396.352395 -46.191376) (xy 396.307037 -46.158925) (xy 396.266888 -46.120216) (xy 396.232802 -46.076073)
			(xy 396.205506 -46.027438) (xy 396.185583 -45.975347) (xy 396.173457 -45.92091) (xy 396.169386 -45.865288)
			(xy 394.624121 -45.865288) (xy 394.632873 -45.895094) (xy 394.640631 -45.949046) (xy 394.640631 -46.003554)
			(xy 394.632873 -46.057506) (xy 394.617516 -46.109805) (xy 394.594871 -46.159386) (xy 394.565401 -46.205239)
			(xy 394.529704 -46.246431) (xy 394.488508 -46.282123) (xy 394.442652 -46.311589) (xy 394.393069 -46.334229)
			(xy 394.340769 -46.349581) (xy 394.286816 -46.357333) (xy 394.259562 -46.357794) (xy 394.232568 -46.357343)
			(xy 394.17912 -46.349733) (xy 394.127277 -46.33467) (xy 394.078073 -46.312454) (xy 394.032489 -46.283528)
			(xy 394.011658 -46.266354) (xy 394.003276 -46.259242) (xy 393.982956 -46.253146) (xy 393.897866 -46.264068)
			(xy 393.892507 -46.264813) (xy 393.882257 -46.268265) (xy 393.877546 -46.270926) (xy 393.868656 -46.276514)
			(xy 393.862306 -46.285404) (xy 393.862052 -46.285658) (xy 393.844466 -46.309863) (xy 393.802994 -46.352982)
			(xy 393.779502 -46.37151) (xy 393.771374 -46.377606) (xy 393.761214 -46.394624) (xy 393.74953 -46.475396)
			(xy 393.748534 -46.485332) (xy 393.753381 -46.504684) (xy 393.758928 -46.512988) (xy 393.776379 -46.537717)
			(xy 393.804086 -46.591523) (xy 393.822955 -46.649027) (xy 393.832513 -46.708788) (xy 393.833096 -46.739048)
			(xy 393.832667 -46.766301) (xy 393.824903 -46.820251) (xy 393.809542 -46.872548) (xy 393.800096 -46.893226)
			(xy 394.637258 -46.893226) (xy 394.641329 -46.837604) (xy 394.653455 -46.783167) (xy 394.673378 -46.731076)
			(xy 394.700674 -46.682441) (xy 394.73476 -46.638298) (xy 394.774909 -46.599589) (xy 394.820267 -46.567138)
			(xy 394.869867 -46.541637) (xy 394.922651 -46.52363) (xy 394.977494 -46.5135) (xy 395.033228 -46.511463)
			(xy 395.088665 -46.517563) (xy 395.142622 -46.531669) (xy 395.193951 -46.553481) (xy 395.241557 -46.582535)
			(xy 395.284425 -46.61821) (xy 395.321642 -46.659747) (xy 395.352415 -46.70626) (xy 395.376087 -46.756757)
			(xy 395.392155 -46.810164) (xy 395.400275 -46.86534) (xy 395.400784 -46.893226) (xy 395.400275 -46.921112)
			(xy 395.392155 -46.976288) (xy 395.376087 -47.029695) (xy 395.375049 -47.03191) (xy 396.169386 -47.03191)
			(xy 396.173457 -46.976288) (xy 396.185583 -46.921851) (xy 396.205506 -46.86976) (xy 396.232802 -46.821125)
			(xy 396.266888 -46.776982) (xy 396.307037 -46.738273) (xy 396.352395 -46.705822) (xy 396.401995 -46.680321)
			(xy 396.454779 -46.662314) (xy 396.509622 -46.652184) (xy 396.565356 -46.650147) (xy 396.620793 -46.656247)
			(xy 396.67475 -46.670353) (xy 396.726079 -46.692165) (xy 396.773685 -46.721219) (xy 396.816553 -46.756894)
			(xy 396.85377 -46.798431) (xy 396.884543 -46.844944) (xy 396.908215 -46.895441) (xy 396.924283 -46.948848)
			(xy 396.932403 -47.004024) (xy 396.932708 -47.020734) (xy 397.347438 -47.020734) (xy 397.351509 -46.965112)
			(xy 397.363635 -46.910675) (xy 397.383558 -46.858584) (xy 397.410854 -46.809949) (xy 397.44494 -46.765806)
			(xy 397.485089 -46.727097) (xy 397.530447 -46.694646) (xy 397.580047 -46.669145) (xy 397.632831 -46.651138)
			(xy 397.687674 -46.641008) (xy 397.743408 -46.638971) (xy 397.798845 -46.645071) (xy 397.852802 -46.659177)
			(xy 397.904131 -46.680989) (xy 397.925181 -46.693836) (xy 398.976342 -46.693836) (xy 398.976828 -46.666585)
			(xy 398.984584 -46.612637) (xy 398.999939 -46.560342) (xy 399.022581 -46.510765) (xy 399.052047 -46.464915)
			(xy 399.087738 -46.423724) (xy 399.128929 -46.388033) (xy 399.174779 -46.358567) (xy 399.224356 -46.335925)
			(xy 399.276651 -46.32057) (xy 399.330599 -46.312814) (xy 399.385101 -46.312814) (xy 399.439049 -46.32057)
			(xy 399.491344 -46.335925) (xy 399.540921 -46.358567) (xy 399.586771 -46.388033) (xy 399.627962 -46.423724)
			(xy 399.663653 -46.464915) (xy 399.693119 -46.510765) (xy 399.715761 -46.560342) (xy 399.731116 -46.612637)
			(xy 399.738872 -46.666585) (xy 399.739358 -46.693836) (xy 399.738891 -46.720264) (xy 399.731581 -46.772612)
			(xy 399.717106 -46.823447) (xy 399.695744 -46.871793) (xy 399.682208 -46.894496) (xy 399.682208 -46.89475)
			(xy 399.676733 -46.904711) (xy 399.674218 -46.927268) (xy 399.677382 -46.938184) (xy 399.707862 -47.023782)
			(xy 399.724118 -47.040038) (xy 399.73504 -47.043848) (xy 399.759547 -47.052921) (xy 399.806 -47.076863)
			(xy 399.848752 -47.106918) (xy 399.887004 -47.142525) (xy 399.920041 -47.183017) (xy 399.947245 -47.227638)
			(xy 399.968107 -47.275553) (xy 399.982237 -47.325866) (xy 399.989371 -47.377636) (xy 399.989802 -47.403766)
			(xy 399.989316 -47.431017) (xy 399.987793 -47.441612) (xy 401.261832 -47.441612) (xy 401.265903 -47.38599)
			(xy 401.278029 -47.331553) (xy 401.297952 -47.279462) (xy 401.325248 -47.230827) (xy 401.359334 -47.186684)
			(xy 401.399483 -47.147975) (xy 401.444841 -47.115524) (xy 401.494441 -47.090023) (xy 401.547225 -47.072016)
			(xy 401.602068 -47.061886) (xy 401.657802 -47.059849) (xy 401.713239 -47.065949) (xy 401.767196 -47.080055)
			(xy 401.818525 -47.101867) (xy 401.866131 -47.130921) (xy 401.908999 -47.166596) (xy 401.946216 -47.208133)
			(xy 401.976989 -47.254646) (xy 402.000661 -47.305143) (xy 402.016729 -47.35855) (xy 402.024849 -47.413726)
			(xy 402.025358 -47.441612) (xy 402.024849 -47.469498) (xy 402.016729 -47.524674) (xy 402.000661 -47.578081)
			(xy 401.976989 -47.628578) (xy 401.946216 -47.675091) (xy 401.908999 -47.716628) (xy 401.866131 -47.752303)
			(xy 401.818525 -47.781357) (xy 401.767196 -47.803169) (xy 401.713239 -47.817275) (xy 401.657802 -47.823375)
			(xy 401.602068 -47.821338) (xy 401.547225 -47.811208) (xy 401.494441 -47.793201) (xy 401.444841 -47.7677)
			(xy 401.399483 -47.735249) (xy 401.359334 -47.69654) (xy 401.325248 -47.652397) (xy 401.297952 -47.603762)
			(xy 401.278029 -47.551671) (xy 401.265903 -47.497234) (xy 401.261832 -47.441612) (xy 399.987793 -47.441612)
			(xy 399.98156 -47.484965) (xy 399.966205 -47.53726) (xy 399.943563 -47.586837) (xy 399.914097 -47.632687)
			(xy 399.878406 -47.673878) (xy 399.837215 -47.709569) (xy 399.791365 -47.739035) (xy 399.741788 -47.761677)
			(xy 399.689493 -47.777032) (xy 399.635545 -47.784788) (xy 399.581043 -47.784788) (xy 399.527095 -47.777032)
			(xy 399.4748 -47.761677) (xy 399.425223 -47.739035) (xy 399.379373 -47.709569) (xy 399.338182 -47.673878)
			(xy 399.302491 -47.632687) (xy 399.273025 -47.586837) (xy 399.250383 -47.53726) (xy 399.235028 -47.484965)
			(xy 399.227272 -47.431017) (xy 399.226786 -47.403766) (xy 399.227262 -47.377339) (xy 399.23457 -47.324991)
			(xy 399.249043 -47.274156) (xy 399.270402 -47.225809) (xy 399.283936 -47.203106) (xy 399.283936 -47.202852)
			(xy 399.28951 -47.192925) (xy 399.292033 -47.170322) (xy 399.288762 -47.159418) (xy 399.258282 -47.07382)
			(xy 399.242026 -47.057564) (xy 399.231104 -47.053754) (xy 399.206585 -47.044711) (xy 399.160134 -47.020763)
			(xy 399.117384 -46.990702) (xy 399.079133 -46.955091) (xy 399.046099 -46.914595) (xy 399.018897 -46.869971)
			(xy 398.998036 -46.822054) (xy 398.983907 -46.771739) (xy 398.976773 -46.719967) (xy 398.976342 -46.693836)
			(xy 397.925181 -46.693836) (xy 397.951737 -46.710043) (xy 397.994605 -46.745718) (xy 398.031822 -46.787255)
			(xy 398.062595 -46.833768) (xy 398.086267 -46.884265) (xy 398.102335 -46.937672) (xy 398.110455 -46.992848)
			(xy 398.110964 -47.020734) (xy 398.110455 -47.04862) (xy 398.102335 -47.103796) (xy 398.086267 -47.157203)
			(xy 398.062595 -47.2077) (xy 398.031822 -47.254213) (xy 397.994605 -47.29575) (xy 397.951737 -47.331425)
			(xy 397.904131 -47.360479) (xy 397.852802 -47.382291) (xy 397.798845 -47.396397) (xy 397.743408 -47.402497)
			(xy 397.687674 -47.40046) (xy 397.632831 -47.39033) (xy 397.580047 -47.372323) (xy 397.530447 -47.346822)
			(xy 397.485089 -47.314371) (xy 397.44494 -47.275662) (xy 397.410854 -47.231519) (xy 397.383558 -47.182884)
			(xy 397.363635 -47.130793) (xy 397.351509 -47.076356) (xy 397.347438 -47.020734) (xy 396.932708 -47.020734)
			(xy 396.932912 -47.03191) (xy 396.932403 -47.059796) (xy 396.924283 -47.114972) (xy 396.908215 -47.168379)
			(xy 396.884543 -47.218876) (xy 396.85377 -47.265389) (xy 396.816553 -47.306926) (xy 396.773685 -47.342601)
			(xy 396.726079 -47.371655) (xy 396.67475 -47.393467) (xy 396.620793 -47.407573) (xy 396.565356 -47.413673)
			(xy 396.509622 -47.411636) (xy 396.454779 -47.401506) (xy 396.401995 -47.383499) (xy 396.352395 -47.357998)
			(xy 396.307037 -47.325547) (xy 396.266888 -47.286838) (xy 396.232802 -47.242695) (xy 396.205506 -47.19406)
			(xy 396.185583 -47.141969) (xy 396.173457 -47.087532) (xy 396.169386 -47.03191) (xy 395.375049 -47.03191)
			(xy 395.352415 -47.080192) (xy 395.321642 -47.126705) (xy 395.284425 -47.168242) (xy 395.241557 -47.203917)
			(xy 395.193951 -47.232971) (xy 395.142622 -47.254783) (xy 395.088665 -47.268889) (xy 395.033228 -47.274989)
			(xy 394.977494 -47.272952) (xy 394.922651 -47.262822) (xy 394.869867 -47.244815) (xy 394.820267 -47.219314)
			(xy 394.774909 -47.186863) (xy 394.73476 -47.148154) (xy 394.700674 -47.104011) (xy 394.673378 -47.055376)
			(xy 394.653455 -47.003285) (xy 394.641329 -46.948848) (xy 394.637258 -46.893226) (xy 393.800096 -46.893226)
			(xy 393.786894 -46.922126) (xy 393.757422 -46.967977) (xy 393.721724 -47.009167) (xy 393.680529 -47.044858)
			(xy 393.634673 -47.074323) (xy 393.585092 -47.096963) (xy 393.532793 -47.112316) (xy 393.478841 -47.120071)
			(xy 393.451588 -47.120556) (xy 393.425554 -47.120109) (xy 393.373972 -47.113021) (xy 393.32383 -47.098991)
			(xy 393.276059 -47.07828) (xy 393.231544 -47.051272) (xy 393.21105 -47.035212) (xy 393.20343 -47.029116)
			(xy 393.184888 -47.023274) (xy 393.105132 -47.029624) (xy 393.095497 -47.030806) (xy 393.078124 -47.039434)
			(xy 393.07135 -47.046388) (xy 393.053167 -47.066032) (xy 393.01226 -47.100554) (xy 392.966931 -47.129023)
			(xy 392.91807 -47.150881) (xy 392.866635 -47.165699) (xy 392.813634 -47.173186) (xy 392.78687 -47.173642)
			(xy 392.75962 -47.17315) (xy 392.705674 -47.16539) (xy 392.653381 -47.150033) (xy 392.603806 -47.127391)
			(xy 392.557958 -47.097925) (xy 392.516769 -47.062234) (xy 392.481078 -47.021046) (xy 392.451611 -46.975197)
			(xy 392.428968 -46.925622) (xy 392.41361 -46.87333) (xy 392.40585 -46.819384) (xy 392.405362 -46.792134)
			(xy 392.405897 -46.76336) (xy 392.414547 -46.706467) (xy 392.431641 -46.651517) (xy 392.456792 -46.599757)
			(xy 392.48943 -46.55236) (xy 392.50874 -46.531022) (xy 392.515636 -46.522968) (xy 392.522725 -46.503013)
			(xy 392.522456 -46.492414) (xy 392.516868 -46.417992) (xy 392.515602 -46.407519) (xy 392.505742 -46.388891)
			(xy 392.497818 -46.381924) (xy 392.497564 -46.38167) (xy 392.475388 -46.363434) (xy 392.436176 -46.321503)
			(xy 392.403688 -46.27417) (xy 392.378657 -46.222504) (xy 392.36165 -46.167671) (xy 392.353048 -46.110909)
			(xy 392.35253 -46.082204) (xy 375.944152 -46.082204) (xy 375.917566 -46.122389) (xy 375.880349 -46.163926)
			(xy 375.837481 -46.199601) (xy 375.789875 -46.228655) (xy 375.738546 -46.250467) (xy 375.684589 -46.264573)
			(xy 375.629152 -46.270673) (xy 375.573418 -46.268636) (xy 375.518575 -46.258506) (xy 375.465791 -46.240499)
			(xy 375.416191 -46.214998) (xy 375.370833 -46.182547) (xy 375.330684 -46.143838) (xy 375.296598 -46.099695)
			(xy 375.269302 -46.05106) (xy 375.249379 -45.998969) (xy 375.237253 -45.944532) (xy 375.233182 -45.88891)
			(xy 372.120882 -45.88891) (xy 372.113817 -45.93692) (xy 372.097749 -45.990327) (xy 372.074077 -46.040824)
			(xy 372.043304 -46.087337) (xy 372.006087 -46.128874) (xy 371.963219 -46.164549) (xy 371.915613 -46.193603)
			(xy 371.864284 -46.215415) (xy 371.810327 -46.229521) (xy 371.75489 -46.235621) (xy 371.699156 -46.233584)
			(xy 371.644313 -46.223454) (xy 371.591529 -46.205447) (xy 371.541929 -46.179946) (xy 371.496571 -46.147495)
			(xy 371.456422 -46.108786) (xy 371.422336 -46.064643) (xy 371.39504 -46.016008) (xy 371.375117 -45.963917)
			(xy 371.362991 -45.90948) (xy 371.35892 -45.853858) (xy 370.932755 -45.853858) (xy 370.932964 -45.865288)
			(xy 370.932455 -45.893174) (xy 370.924335 -45.94835) (xy 370.908267 -46.001757) (xy 370.884595 -46.052254)
			(xy 370.853822 -46.098767) (xy 370.816605 -46.140304) (xy 370.773737 -46.175979) (xy 370.726131 -46.205033)
			(xy 370.674802 -46.226845) (xy 370.620845 -46.240951) (xy 370.565408 -46.247051) (xy 370.509674 -46.245014)
			(xy 370.454831 -46.234884) (xy 370.402047 -46.216877) (xy 370.352447 -46.191376) (xy 370.307089 -46.158925)
			(xy 370.26694 -46.120216) (xy 370.232854 -46.076073) (xy 370.205558 -46.027438) (xy 370.185635 -45.975347)
			(xy 370.173509 -45.92091) (xy 370.169438 -45.865288) (xy 368.624097 -45.865288) (xy 368.632852 -45.895106)
			(xy 368.640608 -45.94905) (xy 368.640608 -46.00355) (xy 368.632852 -46.057494) (xy 368.617498 -46.109786)
			(xy 368.594859 -46.15936) (xy 368.565395 -46.205208) (xy 368.529706 -46.246396) (xy 368.488519 -46.282087)
			(xy 368.442672 -46.311552) (xy 368.393099 -46.334193) (xy 368.340808 -46.349549) (xy 368.286864 -46.357307)
			(xy 368.259614 -46.357794) (xy 368.232622 -46.357313) (xy 368.179175 -46.34971) (xy 368.127332 -46.334654)
			(xy 368.078127 -46.312445) (xy 368.032542 -46.283525) (xy 368.01171 -46.266354) (xy 368.003328 -46.259242)
			(xy 367.983008 -46.253146) (xy 367.897918 -46.264068) (xy 367.892557 -46.264799) (xy 367.882307 -46.268261)
			(xy 367.877598 -46.270926) (xy 367.868708 -46.276514) (xy 367.862358 -46.285404) (xy 367.862104 -46.285658)
			(xy 367.844511 -46.309857) (xy 367.803043 -46.35298) (xy 367.779554 -46.37151) (xy 367.771426 -46.377606)
			(xy 367.761266 -46.394624) (xy 367.749582 -46.475396) (xy 367.748577 -46.485332) (xy 367.753428 -46.504685)
			(xy 367.75898 -46.512988) (xy 367.776425 -46.537721) (xy 367.804135 -46.591525) (xy 367.823006 -46.649028)
			(xy 367.832565 -46.708788) (xy 367.833148 -46.739048) (xy 367.832667 -46.766299) (xy 367.824905 -46.820244)
			(xy 367.809546 -46.872537) (xy 367.800096 -46.893226) (xy 368.63731 -46.893226) (xy 368.641381 -46.837604)
			(xy 368.653507 -46.783167) (xy 368.67343 -46.731076) (xy 368.700726 -46.682441) (xy 368.734812 -46.638298)
			(xy 368.774961 -46.599589) (xy 368.820319 -46.567138) (xy 368.869919 -46.541637) (xy 368.922703 -46.52363)
			(xy 368.977546 -46.5135) (xy 369.03328 -46.511463) (xy 369.088717 -46.517563) (xy 369.142674 -46.531669)
			(xy 369.194003 -46.553481) (xy 369.241609 -46.582535) (xy 369.284477 -46.61821) (xy 369.321694 -46.659747)
			(xy 369.352467 -46.70626) (xy 369.376139 -46.756757) (xy 369.392207 -46.810164) (xy 369.400327 -46.86534)
			(xy 369.400836 -46.893226) (xy 369.400327 -46.921112) (xy 369.392207 -46.976288) (xy 369.376139 -47.029695)
			(xy 369.375101 -47.03191) (xy 370.169438 -47.03191) (xy 370.173509 -46.976288) (xy 370.185635 -46.921851)
			(xy 370.205558 -46.86976) (xy 370.232854 -46.821125) (xy 370.26694 -46.776982) (xy 370.307089 -46.738273)
			(xy 370.352447 -46.705822) (xy 370.402047 -46.680321) (xy 370.454831 -46.662314) (xy 370.509674 -46.652184)
			(xy 370.565408 -46.650147) (xy 370.620845 -46.656247) (xy 370.674802 -46.670353) (xy 370.726131 -46.692165)
			(xy 370.773737 -46.721219) (xy 370.816605 -46.756894) (xy 370.853822 -46.798431) (xy 370.884595 -46.844944)
			(xy 370.908267 -46.895441) (xy 370.924335 -46.948848) (xy 370.932455 -47.004024) (xy 370.93276 -47.020734)
			(xy 371.34749 -47.020734) (xy 371.351561 -46.965112) (xy 371.363687 -46.910675) (xy 371.38361 -46.858584)
			(xy 371.410906 -46.809949) (xy 371.444992 -46.765806) (xy 371.485141 -46.727097) (xy 371.530499 -46.694646)
			(xy 371.580099 -46.669145) (xy 371.632883 -46.651138) (xy 371.687726 -46.641008) (xy 371.74346 -46.638971)
			(xy 371.798897 -46.645071) (xy 371.852854 -46.659177) (xy 371.904183 -46.680989) (xy 371.925233 -46.693836)
			(xy 372.976394 -46.693836) (xy 372.97688 -46.666585) (xy 372.984636 -46.612637) (xy 372.999991 -46.560342)
			(xy 373.022633 -46.510765) (xy 373.052099 -46.464915) (xy 373.08779 -46.423724) (xy 373.128981 -46.388033)
			(xy 373.174831 -46.358567) (xy 373.224408 -46.335925) (xy 373.276703 -46.32057) (xy 373.330651 -46.312814)
			(xy 373.385153 -46.312814) (xy 373.439101 -46.32057) (xy 373.491396 -46.335925) (xy 373.540973 -46.358567)
			(xy 373.586823 -46.388033) (xy 373.628014 -46.423724) (xy 373.663705 -46.464915) (xy 373.693171 -46.510765)
			(xy 373.715813 -46.560342) (xy 373.731168 -46.612637) (xy 373.738924 -46.666585) (xy 373.73941 -46.693836)
			(xy 373.738936 -46.720263) (xy 373.731627 -46.772611) (xy 373.717154 -46.823446) (xy 373.695795 -46.871793)
			(xy 373.68226 -46.894496) (xy 373.68226 -46.89475) (xy 373.676685 -46.904677) (xy 373.674162 -46.92728)
			(xy 373.677434 -46.938184) (xy 373.707914 -47.023782) (xy 373.72417 -47.040038) (xy 373.735092 -47.043848)
			(xy 373.759611 -47.052892) (xy 373.806062 -47.07684) (xy 373.848813 -47.1069) (xy 373.887063 -47.142511)
			(xy 373.920098 -47.183007) (xy 373.9473 -47.227631) (xy 373.968161 -47.275548) (xy 373.98229 -47.325863)
			(xy 373.989423 -47.377635) (xy 373.989854 -47.403766) (xy 373.989368 -47.431017) (xy 373.987845 -47.441612)
			(xy 375.261884 -47.441612) (xy 375.265955 -47.38599) (xy 375.278081 -47.331553) (xy 375.298004 -47.279462)
			(xy 375.3253 -47.230827) (xy 375.359386 -47.186684) (xy 375.399535 -47.147975) (xy 375.444893 -47.115524)
			(xy 375.494493 -47.090023) (xy 375.547277 -47.072016) (xy 375.60212 -47.061886) (xy 375.657854 -47.059849)
			(xy 375.713291 -47.065949) (xy 375.767248 -47.080055) (xy 375.818577 -47.101867) (xy 375.866183 -47.130921)
			(xy 375.909051 -47.166596) (xy 375.946268 -47.208133) (xy 375.977041 -47.254646) (xy 376.000713 -47.305143)
			(xy 376.016781 -47.35855) (xy 376.024901 -47.413726) (xy 376.02541 -47.441612) (xy 376.024901 -47.469498)
			(xy 376.016781 -47.524674) (xy 376.000713 -47.578081) (xy 375.977041 -47.628578) (xy 375.946268 -47.675091)
			(xy 375.909051 -47.716628) (xy 375.866183 -47.752303) (xy 375.818577 -47.781357) (xy 375.767248 -47.803169)
			(xy 375.713291 -47.817275) (xy 375.657854 -47.823375) (xy 375.60212 -47.821338) (xy 375.547277 -47.811208)
			(xy 375.494493 -47.793201) (xy 375.444893 -47.7677) (xy 375.399535 -47.735249) (xy 375.359386 -47.69654)
			(xy 375.3253 -47.652397) (xy 375.298004 -47.603762) (xy 375.278081 -47.551671) (xy 375.265955 -47.497234)
			(xy 375.261884 -47.441612) (xy 373.987845 -47.441612) (xy 373.981612 -47.484965) (xy 373.966257 -47.53726)
			(xy 373.943615 -47.586837) (xy 373.914149 -47.632687) (xy 373.878458 -47.673878) (xy 373.837267 -47.709569)
			(xy 373.791417 -47.739035) (xy 373.74184 -47.761677) (xy 373.689545 -47.777032) (xy 373.635597 -47.784788)
			(xy 373.581095 -47.784788) (xy 373.527147 -47.777032) (xy 373.474852 -47.761677) (xy 373.425275 -47.739035)
			(xy 373.379425 -47.709569) (xy 373.338234 -47.673878) (xy 373.302543 -47.632687) (xy 373.273077 -47.586837)
			(xy 373.250435 -47.53726) (xy 373.23508 -47.484965) (xy 373.227324 -47.431017) (xy 373.226838 -47.403766)
			(xy 373.227306 -47.377338) (xy 373.234616 -47.324991) (xy 373.249091 -47.274156) (xy 373.270452 -47.225809)
			(xy 373.283988 -47.203106) (xy 373.283988 -47.202852) (xy 373.289462 -47.19289) (xy 373.291978 -47.170334)
			(xy 373.288814 -47.159418) (xy 373.258334 -47.07382) (xy 373.242078 -47.057564) (xy 373.231156 -47.053754)
			(xy 373.206648 -47.044682) (xy 373.160196 -47.020739) (xy 373.117444 -46.990684) (xy 373.079192 -46.955077)
			(xy 373.046155 -46.914585) (xy 373.018951 -46.869964) (xy 372.998089 -46.822049) (xy 372.983959 -46.771736)
			(xy 372.976825 -46.719966) (xy 372.976394 -46.693836) (xy 371.925233 -46.693836) (xy 371.951789 -46.710043)
			(xy 371.994657 -46.745718) (xy 372.031874 -46.787255) (xy 372.062647 -46.833768) (xy 372.086319 -46.884265)
			(xy 372.102387 -46.937672) (xy 372.110507 -46.992848) (xy 372.111016 -47.020734) (xy 372.110507 -47.04862)
			(xy 372.102387 -47.103796) (xy 372.086319 -47.157203) (xy 372.062647 -47.2077) (xy 372.031874 -47.254213)
			(xy 371.994657 -47.29575) (xy 371.951789 -47.331425) (xy 371.904183 -47.360479) (xy 371.852854 -47.382291)
			(xy 371.798897 -47.396397) (xy 371.74346 -47.402497) (xy 371.687726 -47.40046) (xy 371.632883 -47.39033)
			(xy 371.580099 -47.372323) (xy 371.530499 -47.346822) (xy 371.485141 -47.314371) (xy 371.444992 -47.275662)
			(xy 371.410906 -47.231519) (xy 371.38361 -47.182884) (xy 371.363687 -47.130793) (xy 371.351561 -47.076356)
			(xy 371.34749 -47.020734) (xy 370.93276 -47.020734) (xy 370.932964 -47.03191) (xy 370.932455 -47.059796)
			(xy 370.924335 -47.114972) (xy 370.908267 -47.168379) (xy 370.884595 -47.218876) (xy 370.853822 -47.265389)
			(xy 370.816605 -47.306926) (xy 370.773737 -47.342601) (xy 370.726131 -47.371655) (xy 370.674802 -47.393467)
			(xy 370.620845 -47.407573) (xy 370.565408 -47.413673) (xy 370.509674 -47.411636) (xy 370.454831 -47.401506)
			(xy 370.402047 -47.383499) (xy 370.352447 -47.357998) (xy 370.307089 -47.325547) (xy 370.26694 -47.286838)
			(xy 370.232854 -47.242695) (xy 370.205558 -47.19406) (xy 370.185635 -47.141969) (xy 370.173509 -47.087532)
			(xy 370.169438 -47.03191) (xy 369.375101 -47.03191) (xy 369.352467 -47.080192) (xy 369.321694 -47.126705)
			(xy 369.284477 -47.168242) (xy 369.241609 -47.203917) (xy 369.194003 -47.232971) (xy 369.142674 -47.254783)
			(xy 369.088717 -47.268889) (xy 369.03328 -47.274989) (xy 368.977546 -47.272952) (xy 368.922703 -47.262822)
			(xy 368.869919 -47.244815) (xy 368.820319 -47.219314) (xy 368.774961 -47.186863) (xy 368.734812 -47.148154)
			(xy 368.700726 -47.104011) (xy 368.67343 -47.055376) (xy 368.653507 -47.003285) (xy 368.641381 -46.948848)
			(xy 368.63731 -46.893226) (xy 367.800096 -46.893226) (xy 367.786902 -46.922112) (xy 367.757434 -46.96796)
			(xy 367.721743 -47.009148) (xy 367.680553 -47.044839) (xy 367.634705 -47.074306) (xy 367.585129 -47.096949)
			(xy 367.532837 -47.112307) (xy 367.478891 -47.120068) (xy 367.45164 -47.120556) (xy 367.425606 -47.120136)
			(xy 367.374022 -47.113041) (xy 367.32388 -47.099005) (xy 367.276109 -47.078289) (xy 367.231596 -47.051275)
			(xy 367.211102 -47.035212) (xy 367.203482 -47.029116) (xy 367.18494 -47.023274) (xy 367.105184 -47.029624)
			(xy 367.095544 -47.030783) (xy 367.078173 -47.039427) (xy 367.071402 -47.046388) (xy 367.053243 -47.066055)
			(xy 367.012331 -47.100575) (xy 366.966997 -47.129042) (xy 366.918131 -47.150895) (xy 366.866692 -47.165708)
			(xy 366.813687 -47.17319) (xy 366.786922 -47.173642) (xy 366.759673 -47.173101) (xy 366.705729 -47.165349)
			(xy 366.653437 -47.149998) (xy 366.603863 -47.127362) (xy 366.558014 -47.097901) (xy 366.516824 -47.062216)
			(xy 366.481132 -47.021031) (xy 366.451665 -46.975187) (xy 366.429021 -46.925615) (xy 366.413663 -46.873326)
			(xy 366.405903 -46.819383) (xy 366.405414 -46.792134) (xy 366.405935 -46.76336) (xy 366.414586 -46.706465)
			(xy 366.431683 -46.651515) (xy 366.456838 -46.599755) (xy 366.489479 -46.552359) (xy 366.508792 -46.531022)
			(xy 366.515694 -46.522973) (xy 366.522778 -46.503014) (xy 366.522508 -46.492414) (xy 366.51692 -46.417992)
			(xy 366.515638 -46.407523) (xy 366.505787 -46.388895) (xy 366.49787 -46.381924) (xy 366.497616 -46.38167)
			(xy 366.47543 -46.363446) (xy 366.436221 -46.321511) (xy 366.403735 -46.274175) (xy 366.378707 -46.222507)
			(xy 366.361701 -46.167672) (xy 366.3531 -46.110909) (xy 366.352582 -46.082204) (xy 337.843898 -46.082204)
			(xy 337.817312 -46.122389) (xy 337.780095 -46.163926) (xy 337.737227 -46.199601) (xy 337.689621 -46.228655)
			(xy 337.638292 -46.250467) (xy 337.584335 -46.264573) (xy 337.528898 -46.270673) (xy 337.473164 -46.268636)
			(xy 337.418321 -46.258506) (xy 337.365537 -46.240499) (xy 337.315937 -46.214998) (xy 337.270579 -46.182547)
			(xy 337.23043 -46.143838) (xy 337.196344 -46.099695) (xy 337.169048 -46.05106) (xy 337.149125 -45.998969)
			(xy 337.136999 -45.944532) (xy 337.132928 -45.88891) (xy 334.020628 -45.88891) (xy 334.013563 -45.93692)
			(xy 333.997495 -45.990327) (xy 333.973823 -46.040824) (xy 333.94305 -46.087337) (xy 333.905833 -46.128874)
			(xy 333.862965 -46.164549) (xy 333.815359 -46.193603) (xy 333.76403 -46.215415) (xy 333.710073 -46.229521)
			(xy 333.654636 -46.235621) (xy 333.598902 -46.233584) (xy 333.544059 -46.223454) (xy 333.491275 -46.205447)
			(xy 333.441675 -46.179946) (xy 333.396317 -46.147495) (xy 333.356168 -46.108786) (xy 333.322082 -46.064643)
			(xy 333.294786 -46.016008) (xy 333.274863 -45.963917) (xy 333.262737 -45.90948) (xy 333.258666 -45.853858)
			(xy 332.832501 -45.853858) (xy 332.83271 -45.865288) (xy 332.832201 -45.893174) (xy 332.824081 -45.94835)
			(xy 332.808013 -46.001757) (xy 332.784341 -46.052254) (xy 332.753568 -46.098767) (xy 332.716351 -46.140304)
			(xy 332.673483 -46.175979) (xy 332.625877 -46.205033) (xy 332.574548 -46.226845) (xy 332.520591 -46.240951)
			(xy 332.465154 -46.247051) (xy 332.40942 -46.245014) (xy 332.354577 -46.234884) (xy 332.301793 -46.216877)
			(xy 332.252193 -46.191376) (xy 332.206835 -46.158925) (xy 332.166686 -46.120216) (xy 332.1326 -46.076073)
			(xy 332.105304 -46.027438) (xy 332.085381 -45.975347) (xy 332.073255 -45.92091) (xy 332.069184 -45.865288)
			(xy 330.52392 -45.865288) (xy 330.532673 -45.895094) (xy 330.540431 -45.949046) (xy 330.540431 -46.003554)
			(xy 330.532673 -46.057506) (xy 330.517315 -46.109805) (xy 330.494671 -46.159386) (xy 330.4652 -46.20524)
			(xy 330.429503 -46.246432) (xy 330.388308 -46.282124) (xy 330.342451 -46.31159) (xy 330.292868 -46.334229)
			(xy 330.240567 -46.349581) (xy 330.186614 -46.357333) (xy 330.15936 -46.357794) (xy 330.132366 -46.357344)
			(xy 330.078918 -46.349734) (xy 330.027075 -46.33467) (xy 329.977871 -46.312454) (xy 329.932287 -46.283528)
			(xy 329.911456 -46.266354) (xy 329.903074 -46.259242) (xy 329.882754 -46.253146) (xy 329.797664 -46.264068)
			(xy 329.792305 -46.264812) (xy 329.782055 -46.268265) (xy 329.777344 -46.270926) (xy 329.768454 -46.276514)
			(xy 329.762104 -46.285404) (xy 329.76185 -46.285658) (xy 329.744264 -46.309863) (xy 329.702792 -46.352982)
			(xy 329.6793 -46.37151) (xy 329.671172 -46.377606) (xy 329.661012 -46.394624) (xy 329.649328 -46.475396)
			(xy 329.648333 -46.485332) (xy 329.653179 -46.504684) (xy 329.658726 -46.512988) (xy 329.676176 -46.537717)
			(xy 329.703884 -46.591523) (xy 329.722753 -46.649027) (xy 329.732311 -46.708788) (xy 329.732894 -46.739048)
			(xy 329.732467 -46.766301) (xy 329.724703 -46.820252) (xy 329.709341 -46.872548) (xy 329.699896 -46.893226)
			(xy 330.537056 -46.893226) (xy 330.541127 -46.837604) (xy 330.553253 -46.783167) (xy 330.573176 -46.731076)
			(xy 330.600472 -46.682441) (xy 330.634558 -46.638298) (xy 330.674707 -46.599589) (xy 330.720065 -46.567138)
			(xy 330.769665 -46.541637) (xy 330.822449 -46.52363) (xy 330.877292 -46.5135) (xy 330.933026 -46.511463)
			(xy 330.988463 -46.517563) (xy 331.04242 -46.531669) (xy 331.093749 -46.553481) (xy 331.141355 -46.582535)
			(xy 331.184223 -46.61821) (xy 331.22144 -46.659747) (xy 331.252213 -46.70626) (xy 331.275885 -46.756757)
			(xy 331.291953 -46.810164) (xy 331.300073 -46.86534) (xy 331.300582 -46.893226) (xy 331.300073 -46.921112)
			(xy 331.291953 -46.976288) (xy 331.275885 -47.029695) (xy 331.274847 -47.03191) (xy 332.069184 -47.03191)
			(xy 332.073255 -46.976288) (xy 332.085381 -46.921851) (xy 332.105304 -46.86976) (xy 332.1326 -46.821125)
			(xy 332.166686 -46.776982) (xy 332.206835 -46.738273) (xy 332.252193 -46.705822) (xy 332.301793 -46.680321)
			(xy 332.354577 -46.662314) (xy 332.40942 -46.652184) (xy 332.465154 -46.650147) (xy 332.520591 -46.656247)
			(xy 332.574548 -46.670353) (xy 332.625877 -46.692165) (xy 332.673483 -46.721219) (xy 332.716351 -46.756894)
			(xy 332.753568 -46.798431) (xy 332.784341 -46.844944) (xy 332.808013 -46.895441) (xy 332.824081 -46.948848)
			(xy 332.832201 -47.004024) (xy 332.832506 -47.020734) (xy 333.247236 -47.020734) (xy 333.251307 -46.965112)
			(xy 333.263433 -46.910675) (xy 333.283356 -46.858584) (xy 333.310652 -46.809949) (xy 333.344738 -46.765806)
			(xy 333.384887 -46.727097) (xy 333.430245 -46.694646) (xy 333.479845 -46.669145) (xy 333.532629 -46.651138)
			(xy 333.587472 -46.641008) (xy 333.643206 -46.638971) (xy 333.698643 -46.645071) (xy 333.7526 -46.659177)
			(xy 333.803929 -46.680989) (xy 333.824979 -46.693836) (xy 334.87614 -46.693836) (xy 334.876626 -46.666585)
			(xy 334.884382 -46.612637) (xy 334.899737 -46.560342) (xy 334.922379 -46.510765) (xy 334.951845 -46.464915)
			(xy 334.987536 -46.423724) (xy 335.028727 -46.388033) (xy 335.074577 -46.358567) (xy 335.124154 -46.335925)
			(xy 335.176449 -46.32057) (xy 335.230397 -46.312814) (xy 335.284899 -46.312814) (xy 335.338847 -46.32057)
			(xy 335.391142 -46.335925) (xy 335.440719 -46.358567) (xy 335.486569 -46.388033) (xy 335.52776 -46.423724)
			(xy 335.563451 -46.464915) (xy 335.592917 -46.510765) (xy 335.615559 -46.560342) (xy 335.630914 -46.612637)
			(xy 335.63867 -46.666585) (xy 335.639156 -46.693836) (xy 335.638689 -46.720264) (xy 335.631379 -46.772612)
			(xy 335.616904 -46.823447) (xy 335.595542 -46.871793) (xy 335.582006 -46.894496) (xy 335.582006 -46.89475)
			(xy 335.576531 -46.904711) (xy 335.574016 -46.927268) (xy 335.57718 -46.938184) (xy 335.60766 -47.023782)
			(xy 335.623916 -47.040038) (xy 335.634838 -47.043848) (xy 335.659345 -47.052922) (xy 335.705798 -47.076864)
			(xy 335.74855 -47.106919) (xy 335.786802 -47.142525) (xy 335.819839 -47.183018) (xy 335.847043 -47.227638)
			(xy 335.867905 -47.275553) (xy 335.882035 -47.325866) (xy 335.889169 -47.377636) (xy 335.8896 -47.403766)
			(xy 335.889114 -47.431017) (xy 335.887591 -47.441612) (xy 337.16163 -47.441612) (xy 337.165701 -47.38599)
			(xy 337.177827 -47.331553) (xy 337.19775 -47.279462) (xy 337.225046 -47.230827) (xy 337.259132 -47.186684)
			(xy 337.299281 -47.147975) (xy 337.344639 -47.115524) (xy 337.394239 -47.090023) (xy 337.447023 -47.072016)
			(xy 337.501866 -47.061886) (xy 337.5576 -47.059849) (xy 337.613037 -47.065949) (xy 337.666994 -47.080055)
			(xy 337.718323 -47.101867) (xy 337.765929 -47.130921) (xy 337.808797 -47.166596) (xy 337.846014 -47.208133)
			(xy 337.876787 -47.254646) (xy 337.900459 -47.305143) (xy 337.916527 -47.35855) (xy 337.924647 -47.413726)
			(xy 337.925156 -47.441612) (xy 337.924647 -47.469498) (xy 337.916527 -47.524674) (xy 337.900459 -47.578081)
			(xy 337.876787 -47.628578) (xy 337.846014 -47.675091) (xy 337.808797 -47.716628) (xy 337.765929 -47.752303)
			(xy 337.718323 -47.781357) (xy 337.666994 -47.803169) (xy 337.613037 -47.817275) (xy 337.5576 -47.823375)
			(xy 337.501866 -47.821338) (xy 337.447023 -47.811208) (xy 337.394239 -47.793201) (xy 337.344639 -47.7677)
			(xy 337.299281 -47.735249) (xy 337.259132 -47.69654) (xy 337.225046 -47.652397) (xy 337.19775 -47.603762)
			(xy 337.177827 -47.551671) (xy 337.165701 -47.497234) (xy 337.16163 -47.441612) (xy 335.887591 -47.441612)
			(xy 335.881358 -47.484965) (xy 335.866003 -47.53726) (xy 335.843361 -47.586837) (xy 335.813895 -47.632687)
			(xy 335.778204 -47.673878) (xy 335.737013 -47.709569) (xy 335.691163 -47.739035) (xy 335.641586 -47.761677)
			(xy 335.589291 -47.777032) (xy 335.535343 -47.784788) (xy 335.480841 -47.784788) (xy 335.426893 -47.777032)
			(xy 335.374598 -47.761677) (xy 335.325021 -47.739035) (xy 335.279171 -47.709569) (xy 335.23798 -47.673878)
			(xy 335.202289 -47.632687) (xy 335.172823 -47.586837) (xy 335.150181 -47.53726) (xy 335.134826 -47.484965)
			(xy 335.12707 -47.431017) (xy 335.126584 -47.403766) (xy 335.12706 -47.377339) (xy 335.134369 -47.324991)
			(xy 335.148841 -47.274157) (xy 335.1702 -47.225809) (xy 335.183734 -47.203106) (xy 335.183734 -47.202852)
			(xy 335.189308 -47.192925) (xy 335.191831 -47.170322) (xy 335.18856 -47.159418) (xy 335.15808 -47.07382)
			(xy 335.141824 -47.057564) (xy 335.130902 -47.053754) (xy 335.106383 -47.044712) (xy 335.059932 -47.020764)
			(xy 335.017181 -46.990703) (xy 334.978931 -46.955091) (xy 334.945896 -46.914595) (xy 334.918694 -46.869971)
			(xy 334.897834 -46.822054) (xy 334.883705 -46.771739) (xy 334.876571 -46.719967) (xy 334.87614 -46.693836)
			(xy 333.824979 -46.693836) (xy 333.851535 -46.710043) (xy 333.894403 -46.745718) (xy 333.93162 -46.787255)
			(xy 333.962393 -46.833768) (xy 333.986065 -46.884265) (xy 334.002133 -46.937672) (xy 334.010253 -46.992848)
			(xy 334.010762 -47.020734) (xy 334.010253 -47.04862) (xy 334.002133 -47.103796) (xy 333.986065 -47.157203)
			(xy 333.962393 -47.2077) (xy 333.93162 -47.254213) (xy 333.894403 -47.29575) (xy 333.851535 -47.331425)
			(xy 333.803929 -47.360479) (xy 333.7526 -47.382291) (xy 333.698643 -47.396397) (xy 333.643206 -47.402497)
			(xy 333.587472 -47.40046) (xy 333.532629 -47.39033) (xy 333.479845 -47.372323) (xy 333.430245 -47.346822)
			(xy 333.384887 -47.314371) (xy 333.344738 -47.275662) (xy 333.310652 -47.231519) (xy 333.283356 -47.182884)
			(xy 333.263433 -47.130793) (xy 333.251307 -47.076356) (xy 333.247236 -47.020734) (xy 332.832506 -47.020734)
			(xy 332.83271 -47.03191) (xy 332.832201 -47.059796) (xy 332.824081 -47.114972) (xy 332.808013 -47.168379)
			(xy 332.784341 -47.218876) (xy 332.753568 -47.265389) (xy 332.716351 -47.306926) (xy 332.673483 -47.342601)
			(xy 332.625877 -47.371655) (xy 332.574548 -47.393467) (xy 332.520591 -47.407573) (xy 332.465154 -47.413673)
			(xy 332.40942 -47.411636) (xy 332.354577 -47.401506) (xy 332.301793 -47.383499) (xy 332.252193 -47.357998)
			(xy 332.206835 -47.325547) (xy 332.166686 -47.286838) (xy 332.1326 -47.242695) (xy 332.105304 -47.19406)
			(xy 332.085381 -47.141969) (xy 332.073255 -47.087532) (xy 332.069184 -47.03191) (xy 331.274847 -47.03191)
			(xy 331.252213 -47.080192) (xy 331.22144 -47.126705) (xy 331.184223 -47.168242) (xy 331.141355 -47.203917)
			(xy 331.093749 -47.232971) (xy 331.04242 -47.254783) (xy 330.988463 -47.268889) (xy 330.933026 -47.274989)
			(xy 330.877292 -47.272952) (xy 330.822449 -47.262822) (xy 330.769665 -47.244815) (xy 330.720065 -47.219314)
			(xy 330.674707 -47.186863) (xy 330.634558 -47.148154) (xy 330.600472 -47.104011) (xy 330.573176 -47.055376)
			(xy 330.553253 -47.003285) (xy 330.541127 -46.948848) (xy 330.537056 -46.893226) (xy 329.699896 -46.893226)
			(xy 329.686694 -46.922127) (xy 329.657221 -46.967977) (xy 329.621524 -47.009167) (xy 329.580328 -47.044858)
			(xy 329.534472 -47.074323) (xy 329.48489 -47.096963) (xy 329.432591 -47.112317) (xy 329.378639 -47.120071)
			(xy 329.351386 -47.120556) (xy 329.325352 -47.12011) (xy 329.27377 -47.113021) (xy 329.223628 -47.098992)
			(xy 329.175857 -47.078281) (xy 329.131342 -47.051272) (xy 329.110848 -47.035212) (xy 329.103228 -47.029116)
			(xy 329.084686 -47.023274) (xy 329.00493 -47.029624) (xy 328.995294 -47.030805) (xy 328.977922 -47.039434)
			(xy 328.971148 -47.046388) (xy 328.952966 -47.066033) (xy 328.912059 -47.100555) (xy 328.86673 -47.129024)
			(xy 328.817869 -47.150882) (xy 328.766433 -47.1657) (xy 328.713432 -47.173187) (xy 328.686668 -47.173642)
			(xy 328.659418 -47.173152) (xy 328.605472 -47.165392) (xy 328.553179 -47.150035) (xy 328.503604 -47.127392)
			(xy 328.457755 -47.097926) (xy 328.416566 -47.062235) (xy 328.380875 -47.021046) (xy 328.351409 -46.975198)
			(xy 328.328766 -46.925623) (xy 328.313408 -46.87333) (xy 328.305648 -46.819384) (xy 328.30516 -46.792134)
			(xy 328.305695 -46.76336) (xy 328.314345 -46.706467) (xy 328.33144 -46.651517) (xy 328.35659 -46.599757)
			(xy 328.389228 -46.55236) (xy 328.408538 -46.531022) (xy 328.415433 -46.522968) (xy 328.422523 -46.503013)
			(xy 328.422254 -46.492414) (xy 328.416666 -46.417992) (xy 328.415401 -46.407519) (xy 328.40554 -46.388891)
			(xy 328.397616 -46.381924) (xy 328.397362 -46.38167) (xy 328.375186 -46.363435) (xy 328.335974 -46.321503)
			(xy 328.303486 -46.27417) (xy 328.278455 -46.222504) (xy 328.261448 -46.167671) (xy 328.252846 -46.110909)
			(xy 328.252328 -46.082204) (xy 311.84395 -46.082204) (xy 311.817364 -46.122389) (xy 311.780147 -46.163926)
			(xy 311.737279 -46.199601) (xy 311.689673 -46.228655) (xy 311.638344 -46.250467) (xy 311.584387 -46.264573)
			(xy 311.52895 -46.270673) (xy 311.473216 -46.268636) (xy 311.418373 -46.258506) (xy 311.365589 -46.240499)
			(xy 311.315989 -46.214998) (xy 311.270631 -46.182547) (xy 311.230482 -46.143838) (xy 311.196396 -46.099695)
			(xy 311.1691 -46.05106) (xy 311.149177 -45.998969) (xy 311.137051 -45.944532) (xy 311.13298 -45.88891)
			(xy 308.02068 -45.88891) (xy 308.013615 -45.93692) (xy 307.997547 -45.990327) (xy 307.973875 -46.040824)
			(xy 307.943102 -46.087337) (xy 307.905885 -46.128874) (xy 307.863017 -46.164549) (xy 307.815411 -46.193603)
			(xy 307.764082 -46.215415) (xy 307.710125 -46.229521) (xy 307.654688 -46.235621) (xy 307.598954 -46.233584)
			(xy 307.544111 -46.223454) (xy 307.491327 -46.205447) (xy 307.441727 -46.179946) (xy 307.396369 -46.147495)
			(xy 307.35622 -46.108786) (xy 307.322134 -46.064643) (xy 307.294838 -46.016008) (xy 307.274915 -45.963917)
			(xy 307.262789 -45.90948) (xy 307.258718 -45.853858) (xy 306.832553 -45.853858) (xy 306.832762 -45.865288)
			(xy 306.832253 -45.893174) (xy 306.824133 -45.94835) (xy 306.808065 -46.001757) (xy 306.784393 -46.052254)
			(xy 306.75362 -46.098767) (xy 306.716403 -46.140304) (xy 306.673535 -46.175979) (xy 306.625929 -46.205033)
			(xy 306.5746 -46.226845) (xy 306.520643 -46.240951) (xy 306.465206 -46.247051) (xy 306.409472 -46.245014)
			(xy 306.354629 -46.234884) (xy 306.301845 -46.216877) (xy 306.252245 -46.191376) (xy 306.206887 -46.158925)
			(xy 306.166738 -46.120216) (xy 306.132652 -46.076073) (xy 306.105356 -46.027438) (xy 306.085433 -45.975347)
			(xy 306.073307 -45.92091) (xy 306.069236 -45.865288) (xy 304.523897 -45.865288) (xy 304.532652 -45.895106)
			(xy 304.540408 -45.94905) (xy 304.540408 -46.00355) (xy 304.532652 -46.057494) (xy 304.517298 -46.109786)
			(xy 304.494659 -46.159361) (xy 304.465194 -46.205209) (xy 304.429506 -46.246397) (xy 304.388318 -46.282087)
			(xy 304.342471 -46.311553) (xy 304.292897 -46.334194) (xy 304.240606 -46.349549) (xy 304.186662 -46.357307)
			(xy 304.159412 -46.357794) (xy 304.13242 -46.357314) (xy 304.078973 -46.349711) (xy 304.02713 -46.334654)
			(xy 303.977925 -46.312445) (xy 303.93234 -46.283525) (xy 303.911508 -46.266354) (xy 303.903126 -46.259242)
			(xy 303.882806 -46.253146) (xy 303.797716 -46.264068) (xy 303.792355 -46.264798) (xy 303.782105 -46.268261)
			(xy 303.777396 -46.270926) (xy 303.768506 -46.276514) (xy 303.762156 -46.285404) (xy 303.761902 -46.285658)
			(xy 303.744309 -46.309857) (xy 303.702841 -46.35298) (xy 303.679352 -46.37151) (xy 303.671224 -46.377606)
			(xy 303.661064 -46.394624) (xy 303.64938 -46.475396) (xy 303.648375 -46.485332) (xy 303.653227 -46.504685)
			(xy 303.658778 -46.512988) (xy 303.676222 -46.537721) (xy 303.703932 -46.591525) (xy 303.722804 -46.649028)
			(xy 303.732363 -46.708788) (xy 303.732946 -46.739048) (xy 303.732467 -46.766299) (xy 303.724705 -46.820245)
			(xy 303.709346 -46.872537) (xy 303.699896 -46.893226) (xy 304.537108 -46.893226) (xy 304.541179 -46.837604)
			(xy 304.553305 -46.783167) (xy 304.573228 -46.731076) (xy 304.600524 -46.682441) (xy 304.63461 -46.638298)
			(xy 304.674759 -46.599589) (xy 304.720117 -46.567138) (xy 304.769717 -46.541637) (xy 304.822501 -46.52363)
			(xy 304.877344 -46.5135) (xy 304.933078 -46.511463) (xy 304.988515 -46.517563) (xy 305.042472 -46.531669)
			(xy 305.093801 -46.553481) (xy 305.141407 -46.582535) (xy 305.184275 -46.61821) (xy 305.221492 -46.659747)
			(xy 305.252265 -46.70626) (xy 305.275937 -46.756757) (xy 305.292005 -46.810164) (xy 305.300125 -46.86534)
			(xy 305.300634 -46.893226) (xy 305.300125 -46.921112) (xy 305.292005 -46.976288) (xy 305.275937 -47.029695)
			(xy 305.274899 -47.03191) (xy 306.069236 -47.03191) (xy 306.073307 -46.976288) (xy 306.085433 -46.921851)
			(xy 306.105356 -46.86976) (xy 306.132652 -46.821125) (xy 306.166738 -46.776982) (xy 306.206887 -46.738273)
			(xy 306.252245 -46.705822) (xy 306.301845 -46.680321) (xy 306.354629 -46.662314) (xy 306.409472 -46.652184)
			(xy 306.465206 -46.650147) (xy 306.520643 -46.656247) (xy 306.5746 -46.670353) (xy 306.625929 -46.692165)
			(xy 306.673535 -46.721219) (xy 306.716403 -46.756894) (xy 306.75362 -46.798431) (xy 306.784393 -46.844944)
			(xy 306.808065 -46.895441) (xy 306.824133 -46.948848) (xy 306.832253 -47.004024) (xy 306.832558 -47.020734)
			(xy 307.247288 -47.020734) (xy 307.251359 -46.965112) (xy 307.263485 -46.910675) (xy 307.283408 -46.858584)
			(xy 307.310704 -46.809949) (xy 307.34479 -46.765806) (xy 307.384939 -46.727097) (xy 307.430297 -46.694646)
			(xy 307.479897 -46.669145) (xy 307.532681 -46.651138) (xy 307.587524 -46.641008) (xy 307.643258 -46.638971)
			(xy 307.698695 -46.645071) (xy 307.752652 -46.659177) (xy 307.803981 -46.680989) (xy 307.825031 -46.693836)
			(xy 308.876192 -46.693836) (xy 308.876678 -46.666585) (xy 308.884434 -46.612637) (xy 308.899789 -46.560342)
			(xy 308.922431 -46.510765) (xy 308.951897 -46.464915) (xy 308.987588 -46.423724) (xy 309.028779 -46.388033)
			(xy 309.074629 -46.358567) (xy 309.124206 -46.335925) (xy 309.176501 -46.32057) (xy 309.230449 -46.312814)
			(xy 309.284951 -46.312814) (xy 309.338899 -46.32057) (xy 309.391194 -46.335925) (xy 309.440771 -46.358567)
			(xy 309.486621 -46.388033) (xy 309.527812 -46.423724) (xy 309.563503 -46.464915) (xy 309.592969 -46.510765)
			(xy 309.615611 -46.560342) (xy 309.630966 -46.612637) (xy 309.638722 -46.666585) (xy 309.639208 -46.693836)
			(xy 309.638734 -46.720264) (xy 309.631425 -46.772611) (xy 309.616952 -46.823446) (xy 309.595593 -46.871793)
			(xy 309.582058 -46.894496) (xy 309.582058 -46.89475) (xy 309.576483 -46.904677) (xy 309.57396 -46.92728)
			(xy 309.577232 -46.938184) (xy 309.607712 -47.023782) (xy 309.623968 -47.040038) (xy 309.63489 -47.043848)
			(xy 309.659408 -47.052893) (xy 309.70586 -47.07684) (xy 309.74861 -47.106901) (xy 309.786861 -47.142512)
			(xy 309.819896 -47.183008) (xy 309.847098 -47.227631) (xy 309.867959 -47.275548) (xy 309.882088 -47.325863)
			(xy 309.889221 -47.377635) (xy 309.889652 -47.403766) (xy 309.889166 -47.431017) (xy 309.887643 -47.441612)
			(xy 311.161682 -47.441612) (xy 311.165753 -47.38599) (xy 311.177879 -47.331553) (xy 311.197802 -47.279462)
			(xy 311.225098 -47.230827) (xy 311.259184 -47.186684) (xy 311.299333 -47.147975) (xy 311.344691 -47.115524)
			(xy 311.394291 -47.090023) (xy 311.447075 -47.072016) (xy 311.501918 -47.061886) (xy 311.557652 -47.059849)
			(xy 311.613089 -47.065949) (xy 311.667046 -47.080055) (xy 311.718375 -47.101867) (xy 311.765981 -47.130921)
			(xy 311.808849 -47.166596) (xy 311.846066 -47.208133) (xy 311.876839 -47.254646) (xy 311.900511 -47.305143)
			(xy 311.916579 -47.35855) (xy 311.924699 -47.413726) (xy 311.925208 -47.441612) (xy 311.924699 -47.469498)
			(xy 311.916579 -47.524674) (xy 311.900511 -47.578081) (xy 311.876839 -47.628578) (xy 311.846066 -47.675091)
			(xy 311.808849 -47.716628) (xy 311.765981 -47.752303) (xy 311.718375 -47.781357) (xy 311.667046 -47.803169)
			(xy 311.613089 -47.817275) (xy 311.557652 -47.823375) (xy 311.501918 -47.821338) (xy 311.447075 -47.811208)
			(xy 311.394291 -47.793201) (xy 311.344691 -47.7677) (xy 311.299333 -47.735249) (xy 311.259184 -47.69654)
			(xy 311.225098 -47.652397) (xy 311.197802 -47.603762) (xy 311.177879 -47.551671) (xy 311.165753 -47.497234)
			(xy 311.161682 -47.441612) (xy 309.887643 -47.441612) (xy 309.88141 -47.484965) (xy 309.866055 -47.53726)
			(xy 309.843413 -47.586837) (xy 309.813947 -47.632687) (xy 309.778256 -47.673878) (xy 309.737065 -47.709569)
			(xy 309.691215 -47.739035) (xy 309.641638 -47.761677) (xy 309.589343 -47.777032) (xy 309.535395 -47.784788)
			(xy 309.480893 -47.784788) (xy 309.426945 -47.777032) (xy 309.37465 -47.761677) (xy 309.325073 -47.739035)
			(xy 309.279223 -47.709569) (xy 309.238032 -47.673878) (xy 309.202341 -47.632687) (xy 309.172875 -47.586837)
			(xy 309.150233 -47.53726) (xy 309.134878 -47.484965) (xy 309.127122 -47.431017) (xy 309.126636 -47.403766)
			(xy 309.127105 -47.377338) (xy 309.134415 -47.324991) (xy 309.148889 -47.274156) (xy 309.170251 -47.225809)
			(xy 309.183786 -47.203106) (xy 309.183786 -47.202852) (xy 309.18926 -47.19289) (xy 309.191776 -47.170334)
			(xy 309.188612 -47.159418) (xy 309.158132 -47.07382) (xy 309.141876 -47.057564) (xy 309.130954 -47.053754)
			(xy 309.106446 -47.044683) (xy 309.059994 -47.02074) (xy 309.017242 -46.990685) (xy 308.97899 -46.955078)
			(xy 308.945953 -46.914585) (xy 308.918749 -46.869964) (xy 308.897887 -46.822049) (xy 308.883757 -46.771736)
			(xy 308.876623 -46.719966) (xy 308.876192 -46.693836) (xy 307.825031 -46.693836) (xy 307.851587 -46.710043)
			(xy 307.894455 -46.745718) (xy 307.931672 -46.787255) (xy 307.962445 -46.833768) (xy 307.986117 -46.884265)
			(xy 308.002185 -46.937672) (xy 308.010305 -46.992848) (xy 308.010814 -47.020734) (xy 308.010305 -47.04862)
			(xy 308.002185 -47.103796) (xy 307.986117 -47.157203) (xy 307.962445 -47.2077) (xy 307.931672 -47.254213)
			(xy 307.894455 -47.29575) (xy 307.851587 -47.331425) (xy 307.803981 -47.360479) (xy 307.752652 -47.382291)
			(xy 307.698695 -47.396397) (xy 307.643258 -47.402497) (xy 307.587524 -47.40046) (xy 307.532681 -47.39033)
			(xy 307.479897 -47.372323) (xy 307.430297 -47.346822) (xy 307.384939 -47.314371) (xy 307.34479 -47.275662)
			(xy 307.310704 -47.231519) (xy 307.283408 -47.182884) (xy 307.263485 -47.130793) (xy 307.251359 -47.076356)
			(xy 307.247288 -47.020734) (xy 306.832558 -47.020734) (xy 306.832762 -47.03191) (xy 306.832253 -47.059796)
			(xy 306.824133 -47.114972) (xy 306.808065 -47.168379) (xy 306.784393 -47.218876) (xy 306.75362 -47.265389)
			(xy 306.716403 -47.306926) (xy 306.673535 -47.342601) (xy 306.625929 -47.371655) (xy 306.5746 -47.393467)
			(xy 306.520643 -47.407573) (xy 306.465206 -47.413673) (xy 306.409472 -47.411636) (xy 306.354629 -47.401506)
			(xy 306.301845 -47.383499) (xy 306.252245 -47.357998) (xy 306.206887 -47.325547) (xy 306.166738 -47.286838)
			(xy 306.132652 -47.242695) (xy 306.105356 -47.19406) (xy 306.085433 -47.141969) (xy 306.073307 -47.087532)
			(xy 306.069236 -47.03191) (xy 305.274899 -47.03191) (xy 305.252265 -47.080192) (xy 305.221492 -47.126705)
			(xy 305.184275 -47.168242) (xy 305.141407 -47.203917) (xy 305.093801 -47.232971) (xy 305.042472 -47.254783)
			(xy 304.988515 -47.268889) (xy 304.933078 -47.274989) (xy 304.877344 -47.272952) (xy 304.822501 -47.262822)
			(xy 304.769717 -47.244815) (xy 304.720117 -47.219314) (xy 304.674759 -47.186863) (xy 304.63461 -47.148154)
			(xy 304.600524 -47.104011) (xy 304.573228 -47.055376) (xy 304.553305 -47.003285) (xy 304.541179 -46.948848)
			(xy 304.537108 -46.893226) (xy 303.699896 -46.893226) (xy 303.686702 -46.922112) (xy 303.657234 -46.96796)
			(xy 303.621542 -47.009149) (xy 303.580352 -47.04484) (xy 303.534503 -47.074306) (xy 303.484928 -47.096949)
			(xy 303.432635 -47.112307) (xy 303.378689 -47.120068) (xy 303.351438 -47.120556) (xy 303.325405 -47.12008)
			(xy 303.273824 -47.112999) (xy 303.223683 -47.098976) (xy 303.175911 -47.078271) (xy 303.131395 -47.051269)
			(xy 303.1109 -47.035212) (xy 303.10328 -47.029116) (xy 303.084738 -47.023274) (xy 303.004982 -47.029624)
			(xy 302.995342 -47.030782) (xy 302.977971 -47.039427) (xy 302.9712 -47.046388) (xy 302.953042 -47.066056)
			(xy 302.912129 -47.100576) (xy 302.866796 -47.129042) (xy 302.81793 -47.150896) (xy 302.76649 -47.165709)
			(xy 302.713485 -47.17319) (xy 302.68672 -47.173642) (xy 302.659471 -47.173103) (xy 302.605527 -47.16535)
			(xy 302.553235 -47.149999) (xy 302.50366 -47.127363) (xy 302.457812 -47.097902) (xy 302.416622 -47.062216)
			(xy 302.38093 -47.021032) (xy 302.351463 -46.975187) (xy 302.328819 -46.925615) (xy 302.313461 -46.873326)
			(xy 302.305701 -46.819383) (xy 302.305212 -46.792134) (xy 302.305733 -46.76336) (xy 302.314385 -46.706465)
			(xy 302.331481 -46.651515) (xy 302.356636 -46.599755) (xy 302.389277 -46.552359) (xy 302.40859 -46.531022)
			(xy 302.415492 -46.522973) (xy 302.422576 -46.503014) (xy 302.422306 -46.492414) (xy 302.416718 -46.417992)
			(xy 302.415436 -46.407522) (xy 302.405585 -46.388895) (xy 302.397668 -46.381924) (xy 302.397414 -46.38167)
			(xy 302.375228 -46.363447) (xy 302.336019 -46.321511) (xy 302.303533 -46.274175) (xy 302.278505 -46.222507)
			(xy 302.261499 -46.167672) (xy 302.252898 -46.110909) (xy 302.25238 -46.082204) (xy 285.844002 -46.082204)
			(xy 285.817416 -46.122389) (xy 285.780199 -46.163926) (xy 285.737331 -46.199601) (xy 285.689725 -46.228655)
			(xy 285.638396 -46.250467) (xy 285.584439 -46.264573) (xy 285.529002 -46.270673) (xy 285.473268 -46.268636)
			(xy 285.418425 -46.258506) (xy 285.365641 -46.240499) (xy 285.316041 -46.214998) (xy 285.270683 -46.182547)
			(xy 285.230534 -46.143838) (xy 285.196448 -46.099695) (xy 285.169152 -46.05106) (xy 285.149229 -45.998969)
			(xy 285.137103 -45.944532) (xy 285.133032 -45.88891) (xy 282.020732 -45.88891) (xy 282.013667 -45.93692)
			(xy 281.997599 -45.990327) (xy 281.973927 -46.040824) (xy 281.943154 -46.087337) (xy 281.905937 -46.128874)
			(xy 281.863069 -46.164549) (xy 281.815463 -46.193603) (xy 281.764134 -46.215415) (xy 281.710177 -46.229521)
			(xy 281.65474 -46.235621) (xy 281.599006 -46.233584) (xy 281.544163 -46.223454) (xy 281.491379 -46.205447)
			(xy 281.441779 -46.179946) (xy 281.396421 -46.147495) (xy 281.356272 -46.108786) (xy 281.322186 -46.064643)
			(xy 281.29489 -46.016008) (xy 281.274967 -45.963917) (xy 281.262841 -45.90948) (xy 281.25877 -45.853858)
			(xy 280.832605 -45.853858) (xy 280.832814 -45.865288) (xy 280.832305 -45.893174) (xy 280.824185 -45.94835)
			(xy 280.808117 -46.001757) (xy 280.784445 -46.052254) (xy 280.753672 -46.098767) (xy 280.716455 -46.140304)
			(xy 280.673587 -46.175979) (xy 280.625981 -46.205033) (xy 280.574652 -46.226845) (xy 280.520695 -46.240951)
			(xy 280.465258 -46.247051) (xy 280.409524 -46.245014) (xy 280.354681 -46.234884) (xy 280.301897 -46.216877)
			(xy 280.252297 -46.191376) (xy 280.206939 -46.158925) (xy 280.16679 -46.120216) (xy 280.132704 -46.076073)
			(xy 280.105408 -46.027438) (xy 280.085485 -45.975347) (xy 280.073359 -45.92091) (xy 280.069288 -45.865288)
			(xy 278.524021 -45.865288) (xy 278.532773 -45.895094) (xy 278.540531 -45.949047) (xy 278.540531 -46.003553)
			(xy 278.532773 -46.057506) (xy 278.517416 -46.109804) (xy 278.494771 -46.159385) (xy 278.465301 -46.205238)
			(xy 278.429605 -46.24643) (xy 278.388409 -46.282123) (xy 278.342553 -46.311589) (xy 278.292971 -46.334228)
			(xy 278.24067 -46.349581) (xy 278.186718 -46.357333) (xy 278.159464 -46.357794) (xy 278.132471 -46.357342)
			(xy 278.079022 -46.349732) (xy 278.027179 -46.334669) (xy 277.977975 -46.312453) (xy 277.932391 -46.283528)
			(xy 277.91156 -46.266354) (xy 277.903178 -46.259242) (xy 277.882858 -46.253146) (xy 277.797768 -46.264068)
			(xy 277.792409 -46.264813) (xy 277.782159 -46.268266) (xy 277.777448 -46.270926) (xy 277.768558 -46.276514)
			(xy 277.762208 -46.285404) (xy 277.761954 -46.285658) (xy 277.744368 -46.309862) (xy 277.702895 -46.352982)
			(xy 277.679404 -46.37151) (xy 277.671276 -46.377606) (xy 277.661116 -46.394624) (xy 277.649432 -46.475396)
			(xy 277.648441 -46.485161) (xy 277.653006 -46.50423) (xy 277.658322 -46.51248) (xy 277.658576 -46.512734)
			(xy 277.65883 -46.512988) (xy 277.676281 -46.537717) (xy 277.703988 -46.591523) (xy 277.722857 -46.649027)
			(xy 277.732415 -46.708788) (xy 277.732998 -46.739048) (xy 277.732567 -46.766301) (xy 277.724803 -46.820251)
			(xy 277.709442 -46.872547) (xy 277.699996 -46.893226) (xy 278.53716 -46.893226) (xy 278.541231 -46.837604)
			(xy 278.553357 -46.783167) (xy 278.57328 -46.731076) (xy 278.600576 -46.682441) (xy 278.634662 -46.638298)
			(xy 278.674811 -46.599589) (xy 278.720169 -46.567138) (xy 278.769769 -46.541637) (xy 278.822553 -46.52363)
			(xy 278.877396 -46.5135) (xy 278.93313 -46.511463) (xy 278.988567 -46.517563) (xy 279.042524 -46.531669)
			(xy 279.093853 -46.553481) (xy 279.141459 -46.582535) (xy 279.184327 -46.61821) (xy 279.221544 -46.659747)
			(xy 279.252317 -46.70626) (xy 279.275989 -46.756757) (xy 279.292057 -46.810164) (xy 279.300177 -46.86534)
			(xy 279.300686 -46.893226) (xy 279.300177 -46.921112) (xy 279.292057 -46.976288) (xy 279.275989 -47.029695)
			(xy 279.274951 -47.03191) (xy 280.069288 -47.03191) (xy 280.073359 -46.976288) (xy 280.085485 -46.921851)
			(xy 280.105408 -46.86976) (xy 280.132704 -46.821125) (xy 280.16679 -46.776982) (xy 280.206939 -46.738273)
			(xy 280.252297 -46.705822) (xy 280.301897 -46.680321) (xy 280.354681 -46.662314) (xy 280.409524 -46.652184)
			(xy 280.465258 -46.650147) (xy 280.520695 -46.656247) (xy 280.574652 -46.670353) (xy 280.625981 -46.692165)
			(xy 280.673587 -46.721219) (xy 280.716455 -46.756894) (xy 280.753672 -46.798431) (xy 280.784445 -46.844944)
			(xy 280.808117 -46.895441) (xy 280.824185 -46.948848) (xy 280.832305 -47.004024) (xy 280.83261 -47.020734)
			(xy 281.24734 -47.020734) (xy 281.251411 -46.965112) (xy 281.263537 -46.910675) (xy 281.28346 -46.858584)
			(xy 281.310756 -46.809949) (xy 281.344842 -46.765806) (xy 281.384991 -46.727097) (xy 281.430349 -46.694646)
			(xy 281.479949 -46.669145) (xy 281.532733 -46.651138) (xy 281.587576 -46.641008) (xy 281.64331 -46.638971)
			(xy 281.698747 -46.645071) (xy 281.752704 -46.659177) (xy 281.804033 -46.680989) (xy 281.825083 -46.693836)
			(xy 282.876244 -46.693836) (xy 282.87673 -46.666585) (xy 282.884486 -46.612637) (xy 282.899841 -46.560342)
			(xy 282.922483 -46.510765) (xy 282.951949 -46.464915) (xy 282.98764 -46.423724) (xy 283.028831 -46.388033)
			(xy 283.074681 -46.358567) (xy 283.124258 -46.335925) (xy 283.176553 -46.32057) (xy 283.230501 -46.312814)
			(xy 283.285003 -46.312814) (xy 283.338951 -46.32057) (xy 283.391246 -46.335925) (xy 283.440823 -46.358567)
			(xy 283.486673 -46.388033) (xy 283.527864 -46.423724) (xy 283.563555 -46.464915) (xy 283.593021 -46.510765)
			(xy 283.615663 -46.560342) (xy 283.631018 -46.612637) (xy 283.638774 -46.666585) (xy 283.63926 -46.693836)
			(xy 283.638793 -46.720264) (xy 283.631483 -46.772612) (xy 283.617008 -46.823447) (xy 283.595646 -46.871793)
			(xy 283.58211 -46.894496) (xy 283.58211 -46.89475) (xy 283.576635 -46.904711) (xy 283.57412 -46.927268)
			(xy 283.577284 -46.938184) (xy 283.607764 -47.023782) (xy 283.62402 -47.040038) (xy 283.634942 -47.043848)
			(xy 283.65945 -47.05292) (xy 283.705902 -47.076862) (xy 283.748655 -47.106917) (xy 283.786907 -47.142524)
			(xy 283.819943 -47.183017) (xy 283.847147 -47.227638) (xy 283.868009 -47.275553) (xy 283.882139 -47.325866)
			(xy 283.889273 -47.377636) (xy 283.889704 -47.403766) (xy 283.889218 -47.431017) (xy 283.887695 -47.441612)
			(xy 285.161734 -47.441612) (xy 285.165805 -47.38599) (xy 285.177931 -47.331553) (xy 285.197854 -47.279462)
			(xy 285.22515 -47.230827) (xy 285.259236 -47.186684) (xy 285.299385 -47.147975) (xy 285.344743 -47.115524)
			(xy 285.394343 -47.090023) (xy 285.447127 -47.072016) (xy 285.50197 -47.061886) (xy 285.557704 -47.059849)
			(xy 285.613141 -47.065949) (xy 285.667098 -47.080055) (xy 285.718427 -47.101867) (xy 285.766033 -47.130921)
			(xy 285.808901 -47.166596) (xy 285.846118 -47.208133) (xy 285.876891 -47.254646) (xy 285.900563 -47.305143)
			(xy 285.916631 -47.35855) (xy 285.924751 -47.413726) (xy 285.92526 -47.441612) (xy 285.924751 -47.469498)
			(xy 285.916631 -47.524674) (xy 285.900563 -47.578081) (xy 285.876891 -47.628578) (xy 285.846118 -47.675091)
			(xy 285.808901 -47.716628) (xy 285.766033 -47.752303) (xy 285.718427 -47.781357) (xy 285.667098 -47.803169)
			(xy 285.613141 -47.817275) (xy 285.557704 -47.823375) (xy 285.50197 -47.821338) (xy 285.447127 -47.811208)
			(xy 285.394343 -47.793201) (xy 285.344743 -47.7677) (xy 285.299385 -47.735249) (xy 285.259236 -47.69654)
			(xy 285.22515 -47.652397) (xy 285.197854 -47.603762) (xy 285.177931 -47.551671) (xy 285.165805 -47.497234)
			(xy 285.161734 -47.441612) (xy 283.887695 -47.441612) (xy 283.881462 -47.484965) (xy 283.866107 -47.53726)
			(xy 283.843465 -47.586837) (xy 283.813999 -47.632687) (xy 283.778308 -47.673878) (xy 283.737117 -47.709569)
			(xy 283.691267 -47.739035) (xy 283.64169 -47.761677) (xy 283.589395 -47.777032) (xy 283.535447 -47.784788)
			(xy 283.480945 -47.784788) (xy 283.426997 -47.777032) (xy 283.374702 -47.761677) (xy 283.325125 -47.739035)
			(xy 283.279275 -47.709569) (xy 283.238084 -47.673878) (xy 283.202393 -47.632687) (xy 283.172927 -47.586837)
			(xy 283.150285 -47.53726) (xy 283.13493 -47.484965) (xy 283.127174 -47.431017) (xy 283.126688 -47.403766)
			(xy 283.127163 -47.377339) (xy 283.134472 -47.324991) (xy 283.148945 -47.274156) (xy 283.170304 -47.225809)
			(xy 283.183838 -47.203106) (xy 283.183838 -47.202852) (xy 283.189412 -47.192925) (xy 283.191935 -47.170322)
			(xy 283.188664 -47.159418) (xy 283.158184 -47.07382) (xy 283.141928 -47.057564) (xy 283.131006 -47.053754)
			(xy 283.106488 -47.04471) (xy 283.060036 -47.020762) (xy 283.017286 -46.990701) (xy 282.979036 -46.95509)
			(xy 282.946001 -46.914594) (xy 282.918799 -46.869971) (xy 282.897938 -46.822053) (xy 282.883809 -46.771739)
			(xy 282.876675 -46.719967) (xy 282.876244 -46.693836) (xy 281.825083 -46.693836) (xy 281.851639 -46.710043)
			(xy 281.894507 -46.745718) (xy 281.931724 -46.787255) (xy 281.962497 -46.833768) (xy 281.986169 -46.884265)
			(xy 282.002237 -46.937672) (xy 282.010357 -46.992848) (xy 282.010866 -47.020734) (xy 282.010357 -47.04862)
			(xy 282.002237 -47.103796) (xy 281.986169 -47.157203) (xy 281.962497 -47.2077) (xy 281.931724 -47.254213)
			(xy 281.894507 -47.29575) (xy 281.851639 -47.331425) (xy 281.804033 -47.360479) (xy 281.752704 -47.382291)
			(xy 281.698747 -47.396397) (xy 281.64331 -47.402497) (xy 281.587576 -47.40046) (xy 281.532733 -47.39033)
			(xy 281.479949 -47.372323) (xy 281.430349 -47.346822) (xy 281.384991 -47.314371) (xy 281.344842 -47.275662)
			(xy 281.310756 -47.231519) (xy 281.28346 -47.182884) (xy 281.263537 -47.130793) (xy 281.251411 -47.076356)
			(xy 281.24734 -47.020734) (xy 280.83261 -47.020734) (xy 280.832814 -47.03191) (xy 280.832305 -47.059796)
			(xy 280.824185 -47.114972) (xy 280.808117 -47.168379) (xy 280.784445 -47.218876) (xy 280.753672 -47.265389)
			(xy 280.716455 -47.306926) (xy 280.673587 -47.342601) (xy 280.625981 -47.371655) (xy 280.574652 -47.393467)
			(xy 280.520695 -47.407573) (xy 280.465258 -47.413673) (xy 280.409524 -47.411636) (xy 280.354681 -47.401506)
			(xy 280.301897 -47.383499) (xy 280.252297 -47.357998) (xy 280.206939 -47.325547) (xy 280.16679 -47.286838)
			(xy 280.132704 -47.242695) (xy 280.105408 -47.19406) (xy 280.085485 -47.141969) (xy 280.073359 -47.087532)
			(xy 280.069288 -47.03191) (xy 279.274951 -47.03191) (xy 279.252317 -47.080192) (xy 279.221544 -47.126705)
			(xy 279.184327 -47.168242) (xy 279.141459 -47.203917) (xy 279.093853 -47.232971) (xy 279.042524 -47.254783)
			(xy 278.988567 -47.268889) (xy 278.93313 -47.274989) (xy 278.877396 -47.272952) (xy 278.822553 -47.262822)
			(xy 278.769769 -47.244815) (xy 278.720169 -47.219314) (xy 278.674811 -47.186863) (xy 278.634662 -47.148154)
			(xy 278.600576 -47.104011) (xy 278.57328 -47.055376) (xy 278.553357 -47.003285) (xy 278.541231 -46.948848)
			(xy 278.53716 -46.893226) (xy 277.699996 -46.893226) (xy 277.686794 -46.922126) (xy 277.657322 -46.967976)
			(xy 277.621625 -47.009166) (xy 277.58043 -47.044857) (xy 277.534575 -47.074322) (xy 277.484993 -47.096962)
			(xy 277.432694 -47.112316) (xy 277.378743 -47.120071) (xy 277.35149 -47.120556) (xy 277.325456 -47.120107)
			(xy 277.273874 -47.11302) (xy 277.223732 -47.09899) (xy 277.175961 -47.07828) (xy 277.131446 -47.051272)
			(xy 277.110952 -47.035212) (xy 277.103332 -47.029116) (xy 277.08479 -47.023274) (xy 277.005034 -47.029624)
			(xy 276.995399 -47.030807) (xy 276.978026 -47.039434) (xy 276.971252 -47.046388) (xy 276.953068 -47.066031)
			(xy 276.912161 -47.100553) (xy 276.866833 -47.129023) (xy 276.817972 -47.150881) (xy 276.766536 -47.165699)
			(xy 276.713536 -47.173186) (xy 276.686772 -47.173642) (xy 276.659522 -47.173148) (xy 276.605576 -47.165389)
			(xy 276.553283 -47.150032) (xy 276.503708 -47.12739) (xy 276.45786 -47.097924) (xy 276.416671 -47.062234)
			(xy 276.38098 -47.021045) (xy 276.351513 -46.975197) (xy 276.32887 -46.925622) (xy 276.313512 -46.87333)
			(xy 276.305752 -46.819384) (xy 276.305264 -46.792134) (xy 276.305798 -46.76336) (xy 276.314448 -46.706467)
			(xy 276.331543 -46.651517) (xy 276.356694 -46.599757) (xy 276.389331 -46.55236) (xy 276.408642 -46.531022)
			(xy 276.415538 -46.522968) (xy 276.422627 -46.503013) (xy 276.422358 -46.492414) (xy 276.41677 -46.417992)
			(xy 276.415504 -46.407519) (xy 276.405643 -46.388891) (xy 276.39772 -46.381924) (xy 276.397466 -46.38167)
			(xy 276.375291 -46.363434) (xy 276.336078 -46.321502) (xy 276.30359 -46.274169) (xy 276.27856 -46.222503)
			(xy 276.261552 -46.167671) (xy 276.25295 -46.110909) (xy 276.252432 -46.082204) (xy 259.844054 -46.082204)
			(xy 259.817468 -46.122389) (xy 259.780251 -46.163926) (xy 259.737383 -46.199601) (xy 259.689777 -46.228655)
			(xy 259.638448 -46.250467) (xy 259.584491 -46.264573) (xy 259.529054 -46.270673) (xy 259.47332 -46.268636)
			(xy 259.418477 -46.258506) (xy 259.365693 -46.240499) (xy 259.316093 -46.214998) (xy 259.270735 -46.182547)
			(xy 259.230586 -46.143838) (xy 259.1965 -46.099695) (xy 259.169204 -46.05106) (xy 259.149281 -45.998969)
			(xy 259.137155 -45.944532) (xy 259.133084 -45.88891) (xy 256.020784 -45.88891) (xy 256.013719 -45.93692)
			(xy 255.997651 -45.990327) (xy 255.973979 -46.040824) (xy 255.943206 -46.087337) (xy 255.905989 -46.128874)
			(xy 255.863121 -46.164549) (xy 255.815515 -46.193603) (xy 255.764186 -46.215415) (xy 255.710229 -46.229521)
			(xy 255.654792 -46.235621) (xy 255.599058 -46.233584) (xy 255.544215 -46.223454) (xy 255.491431 -46.205447)
			(xy 255.441831 -46.179946) (xy 255.396473 -46.147495) (xy 255.356324 -46.108786) (xy 255.322238 -46.064643)
			(xy 255.294942 -46.016008) (xy 255.275019 -45.963917) (xy 255.262893 -45.90948) (xy 255.258822 -45.853858)
			(xy 254.832657 -45.853858) (xy 254.832866 -45.865288) (xy 254.832357 -45.893174) (xy 254.824237 -45.94835)
			(xy 254.808169 -46.001757) (xy 254.784497 -46.052254) (xy 254.753724 -46.098767) (xy 254.716507 -46.140304)
			(xy 254.673639 -46.175979) (xy 254.626033 -46.205033) (xy 254.574704 -46.226845) (xy 254.520747 -46.240951)
			(xy 254.46531 -46.247051) (xy 254.409576 -46.245014) (xy 254.354733 -46.234884) (xy 254.301949 -46.216877)
			(xy 254.252349 -46.191376) (xy 254.206991 -46.158925) (xy 254.166842 -46.120216) (xy 254.132756 -46.076073)
			(xy 254.10546 -46.027438) (xy 254.085537 -45.975347) (xy 254.073411 -45.92091) (xy 254.06934 -45.865288)
			(xy 252.523997 -45.865288) (xy 252.532752 -45.895106) (xy 252.540508 -45.949051) (xy 252.540508 -46.003549)
			(xy 252.532752 -46.057494) (xy 252.517398 -46.109785) (xy 252.494759 -46.15936) (xy 252.465295 -46.205207)
			(xy 252.429607 -46.246396) (xy 252.38842 -46.282086) (xy 252.342574 -46.311551) (xy 252.293 -46.334193)
			(xy 252.240709 -46.349549) (xy 252.186765 -46.357307) (xy 252.159516 -46.357794) (xy 252.132524 -46.357312)
			(xy 252.079077 -46.349709) (xy 252.027234 -46.334653) (xy 251.978029 -46.312444) (xy 251.932444 -46.283525)
			(xy 251.911612 -46.266354) (xy 251.90323 -46.259242) (xy 251.88291 -46.253146) (xy 251.79782 -46.264068)
			(xy 251.792459 -46.264799) (xy 251.782209 -46.268261) (xy 251.7775 -46.270926) (xy 251.76861 -46.276514)
			(xy 251.76226 -46.285404) (xy 251.762006 -46.285658) (xy 251.744413 -46.309857) (xy 251.702945 -46.35298)
			(xy 251.679456 -46.37151) (xy 251.671328 -46.377606) (xy 251.661168 -46.394624) (xy 251.649484 -46.475396)
			(xy 251.648501 -46.485161) (xy 251.653062 -46.504229) (xy 251.658374 -46.51248) (xy 251.658628 -46.512734)
			(xy 251.658882 -46.512988) (xy 251.676327 -46.537721) (xy 251.704037 -46.591525) (xy 251.722908 -46.649028)
			(xy 251.732467 -46.708788) (xy 251.73305 -46.739048) (xy 251.732567 -46.766299) (xy 251.724805 -46.820244)
			(xy 251.709446 -46.872536) (xy 251.699996 -46.893226) (xy 252.537212 -46.893226) (xy 252.541283 -46.837604)
			(xy 252.553409 -46.783167) (xy 252.573332 -46.731076) (xy 252.600628 -46.682441) (xy 252.634714 -46.638298)
			(xy 252.674863 -46.599589) (xy 252.720221 -46.567138) (xy 252.769821 -46.541637) (xy 252.822605 -46.52363)
			(xy 252.877448 -46.5135) (xy 252.933182 -46.511463) (xy 252.988619 -46.517563) (xy 253.042576 -46.531669)
			(xy 253.093905 -46.553481) (xy 253.141511 -46.582535) (xy 253.184379 -46.61821) (xy 253.221596 -46.659747)
			(xy 253.252369 -46.70626) (xy 253.276041 -46.756757) (xy 253.292109 -46.810164) (xy 253.300229 -46.86534)
			(xy 253.300738 -46.893226) (xy 253.300229 -46.921112) (xy 253.292109 -46.976288) (xy 253.276041 -47.029695)
			(xy 253.275003 -47.03191) (xy 254.06934 -47.03191) (xy 254.073411 -46.976288) (xy 254.085537 -46.921851)
			(xy 254.10546 -46.86976) (xy 254.132756 -46.821125) (xy 254.166842 -46.776982) (xy 254.206991 -46.738273)
			(xy 254.252349 -46.705822) (xy 254.301949 -46.680321) (xy 254.354733 -46.662314) (xy 254.409576 -46.652184)
			(xy 254.46531 -46.650147) (xy 254.520747 -46.656247) (xy 254.574704 -46.670353) (xy 254.626033 -46.692165)
			(xy 254.673639 -46.721219) (xy 254.716507 -46.756894) (xy 254.753724 -46.798431) (xy 254.784497 -46.844944)
			(xy 254.808169 -46.895441) (xy 254.824237 -46.948848) (xy 254.832357 -47.004024) (xy 254.832662 -47.020734)
			(xy 255.247392 -47.020734) (xy 255.251463 -46.965112) (xy 255.263589 -46.910675) (xy 255.283512 -46.858584)
			(xy 255.310808 -46.809949) (xy 255.344894 -46.765806) (xy 255.385043 -46.727097) (xy 255.430401 -46.694646)
			(xy 255.480001 -46.669145) (xy 255.532785 -46.651138) (xy 255.587628 -46.641008) (xy 255.643362 -46.638971)
			(xy 255.698799 -46.645071) (xy 255.752756 -46.659177) (xy 255.804085 -46.680989) (xy 255.825135 -46.693836)
			(xy 256.876296 -46.693836) (xy 256.876782 -46.666585) (xy 256.884538 -46.612637) (xy 256.899893 -46.560342)
			(xy 256.922535 -46.510765) (xy 256.952001 -46.464915) (xy 256.987692 -46.423724) (xy 257.028883 -46.388033)
			(xy 257.074733 -46.358567) (xy 257.12431 -46.335925) (xy 257.176605 -46.32057) (xy 257.230553 -46.312814)
			(xy 257.285055 -46.312814) (xy 257.339003 -46.32057) (xy 257.391298 -46.335925) (xy 257.440875 -46.358567)
			(xy 257.486725 -46.388033) (xy 257.527916 -46.423724) (xy 257.563607 -46.464915) (xy 257.593073 -46.510765)
			(xy 257.615715 -46.560342) (xy 257.63107 -46.612637) (xy 257.638826 -46.666585) (xy 257.639312 -46.693836)
			(xy 257.638838 -46.720263) (xy 257.631528 -46.772611) (xy 257.617056 -46.823446) (xy 257.595696 -46.871793)
			(xy 257.582162 -46.894496) (xy 257.582162 -46.89475) (xy 257.576587 -46.904677) (xy 257.574064 -46.92728)
			(xy 257.577336 -46.938184) (xy 257.607816 -47.023782) (xy 257.624072 -47.040038) (xy 257.634994 -47.043848)
			(xy 257.659513 -47.052891) (xy 257.705964 -47.076839) (xy 257.748715 -47.106899) (xy 257.786965 -47.142511)
			(xy 257.82 -47.183007) (xy 257.847202 -47.227631) (xy 257.868063 -47.275548) (xy 257.882192 -47.325863)
			(xy 257.889325 -47.377635) (xy 257.889756 -47.403766) (xy 257.88927 -47.431017) (xy 257.887747 -47.441612)
			(xy 259.161786 -47.441612) (xy 259.165857 -47.38599) (xy 259.177983 -47.331553) (xy 259.197906 -47.279462)
			(xy 259.225202 -47.230827) (xy 259.259288 -47.186684) (xy 259.299437 -47.147975) (xy 259.344795 -47.115524)
			(xy 259.394395 -47.090023) (xy 259.447179 -47.072016) (xy 259.502022 -47.061886) (xy 259.557756 -47.059849)
			(xy 259.613193 -47.065949) (xy 259.66715 -47.080055) (xy 259.718479 -47.101867) (xy 259.766085 -47.130921)
			(xy 259.808953 -47.166596) (xy 259.84617 -47.208133) (xy 259.876943 -47.254646) (xy 259.900615 -47.305143)
			(xy 259.916683 -47.35855) (xy 259.924803 -47.413726) (xy 259.925312 -47.441612) (xy 259.924803 -47.469498)
			(xy 259.916683 -47.524674) (xy 259.900615 -47.578081) (xy 259.876943 -47.628578) (xy 259.84617 -47.675091)
			(xy 259.808953 -47.716628) (xy 259.766085 -47.752303) (xy 259.718479 -47.781357) (xy 259.66715 -47.803169)
			(xy 259.613193 -47.817275) (xy 259.557756 -47.823375) (xy 259.502022 -47.821338) (xy 259.447179 -47.811208)
			(xy 259.394395 -47.793201) (xy 259.344795 -47.7677) (xy 259.299437 -47.735249) (xy 259.259288 -47.69654)
			(xy 259.225202 -47.652397) (xy 259.197906 -47.603762) (xy 259.177983 -47.551671) (xy 259.165857 -47.497234)
			(xy 259.161786 -47.441612) (xy 257.887747 -47.441612) (xy 257.881514 -47.484965) (xy 257.866159 -47.53726)
			(xy 257.843517 -47.586837) (xy 257.814051 -47.632687) (xy 257.77836 -47.673878) (xy 257.737169 -47.709569)
			(xy 257.691319 -47.739035) (xy 257.641742 -47.761677) (xy 257.589447 -47.777032) (xy 257.535499 -47.784788)
			(xy 257.480997 -47.784788) (xy 257.427049 -47.777032) (xy 257.374754 -47.761677) (xy 257.325177 -47.739035)
			(xy 257.279327 -47.709569) (xy 257.238136 -47.673878) (xy 257.202445 -47.632687) (xy 257.172979 -47.586837)
			(xy 257.150337 -47.53726) (xy 257.134982 -47.484965) (xy 257.127226 -47.431017) (xy 257.12674 -47.403766)
			(xy 257.127208 -47.377338) (xy 257.134518 -47.324991) (xy 257.148993 -47.274155) (xy 257.170354 -47.225809)
			(xy 257.18389 -47.203106) (xy 257.18389 -47.202852) (xy 257.189364 -47.19289) (xy 257.19188 -47.170334)
			(xy 257.188716 -47.159418) (xy 257.158236 -47.07382) (xy 257.14198 -47.057564) (xy 257.131058 -47.053754)
			(xy 257.106551 -47.04468) (xy 257.060098 -47.020739) (xy 257.017346 -46.990683) (xy 256.979094 -46.955077)
			(xy 256.946057 -46.914584) (xy 256.918854 -46.869964) (xy 256.897991 -46.822049) (xy 256.883861 -46.771736)
			(xy 256.876727 -46.719966) (xy 256.876296 -46.693836) (xy 255.825135 -46.693836) (xy 255.851691 -46.710043)
			(xy 255.894559 -46.745718) (xy 255.931776 -46.787255) (xy 255.962549 -46.833768) (xy 255.986221 -46.884265)
			(xy 256.002289 -46.937672) (xy 256.010409 -46.992848) (xy 256.010918 -47.020734) (xy 256.010409 -47.04862)
			(xy 256.002289 -47.103796) (xy 255.986221 -47.157203) (xy 255.962549 -47.2077) (xy 255.931776 -47.254213)
			(xy 255.894559 -47.29575) (xy 255.851691 -47.331425) (xy 255.804085 -47.360479) (xy 255.752756 -47.382291)
			(xy 255.698799 -47.396397) (xy 255.643362 -47.402497) (xy 255.587628 -47.40046) (xy 255.532785 -47.39033)
			(xy 255.480001 -47.372323) (xy 255.430401 -47.346822) (xy 255.385043 -47.314371) (xy 255.344894 -47.275662)
			(xy 255.310808 -47.231519) (xy 255.283512 -47.182884) (xy 255.263589 -47.130793) (xy 255.251463 -47.076356)
			(xy 255.247392 -47.020734) (xy 254.832662 -47.020734) (xy 254.832866 -47.03191) (xy 254.832357 -47.059796)
			(xy 254.824237 -47.114972) (xy 254.808169 -47.168379) (xy 254.784497 -47.218876) (xy 254.753724 -47.265389)
			(xy 254.716507 -47.306926) (xy 254.673639 -47.342601) (xy 254.626033 -47.371655) (xy 254.574704 -47.393467)
			(xy 254.520747 -47.407573) (xy 254.46531 -47.413673) (xy 254.409576 -47.411636) (xy 254.354733 -47.401506)
			(xy 254.301949 -47.383499) (xy 254.252349 -47.357998) (xy 254.206991 -47.325547) (xy 254.166842 -47.286838)
			(xy 254.132756 -47.242695) (xy 254.10546 -47.19406) (xy 254.085537 -47.141969) (xy 254.073411 -47.087532)
			(xy 254.06934 -47.03191) (xy 253.275003 -47.03191) (xy 253.252369 -47.080192) (xy 253.221596 -47.126705)
			(xy 253.184379 -47.168242) (xy 253.141511 -47.203917) (xy 253.093905 -47.232971) (xy 253.042576 -47.254783)
			(xy 252.988619 -47.268889) (xy 252.933182 -47.274989) (xy 252.877448 -47.272952) (xy 252.822605 -47.262822)
			(xy 252.769821 -47.244815) (xy 252.720221 -47.219314) (xy 252.674863 -47.186863) (xy 252.634714 -47.148154)
			(xy 252.600628 -47.104011) (xy 252.573332 -47.055376) (xy 252.553409 -47.003285) (xy 252.541283 -46.948848)
			(xy 252.537212 -46.893226) (xy 251.699996 -46.893226) (xy 251.686802 -46.922111) (xy 251.657335 -46.967959)
			(xy 251.621643 -47.009148) (xy 251.580454 -47.044838) (xy 251.534606 -47.074305) (xy 251.485031 -47.096948)
			(xy 251.432738 -47.112306) (xy 251.378793 -47.120067) (xy 251.351542 -47.120556) (xy 251.325508 -47.120134)
			(xy 251.273924 -47.11304) (xy 251.223782 -47.099005) (xy 251.176011 -47.078288) (xy 251.131498 -47.051275)
			(xy 251.111004 -47.035212) (xy 251.103384 -47.029116) (xy 251.084842 -47.023274) (xy 251.005086 -47.029624)
			(xy 250.995446 -47.030784) (xy 250.978075 -47.039427) (xy 250.971304 -47.046388) (xy 250.953144 -47.066054)
			(xy 250.912232 -47.100574) (xy 250.866898 -47.129041) (xy 250.818033 -47.150895) (xy 250.766593 -47.165708)
			(xy 250.713589 -47.17319) (xy 250.686824 -47.173642) (xy 250.659575 -47.1731) (xy 250.605631 -47.165347)
			(xy 250.553339 -47.149997) (xy 250.503765 -47.127361) (xy 250.457916 -47.0979) (xy 250.416726 -47.062215)
			(xy 250.381034 -47.021031) (xy 250.351567 -46.975186) (xy 250.328923 -46.925615) (xy 250.313565 -46.873326)
			(xy 250.305805 -46.819383) (xy 250.305316 -46.792134) (xy 250.305836 -46.76336) (xy 250.314488 -46.706465)
			(xy 250.331585 -46.651515) (xy 250.356739 -46.599754) (xy 250.389381 -46.552359) (xy 250.408694 -46.531022)
			(xy 250.415596 -46.522973) (xy 250.42268 -46.503014) (xy 250.42241 -46.492414) (xy 250.416822 -46.417992)
			(xy 250.415539 -46.407523) (xy 250.405689 -46.388895) (xy 250.397772 -46.381924) (xy 250.397518 -46.38167)
			(xy 250.375333 -46.363446) (xy 250.336123 -46.32151) (xy 250.303638 -46.274174) (xy 250.278609 -46.222506)
			(xy 250.261603 -46.167672) (xy 250.253002 -46.110909) (xy 250.252484 -46.082204) (xy 241.033661 -46.082204)
			(xy 240.997056 -46.113925) (xy 240.951204 -46.143395) (xy 240.901624 -46.16604) (xy 240.849327 -46.181398)
			(xy 240.795377 -46.189158) (xy 240.768124 -46.189646) (xy 240.740754 -46.189179) (xy 240.686574 -46.181363)
			(xy 240.63407 -46.165875) (xy 240.584324 -46.143033) (xy 240.538357 -46.113308) (xy 240.517426 -46.095666)
			(xy 240.517172 -46.095412) (xy 240.510068 -46.089851) (xy 240.493165 -46.083588) (xy 240.484152 -46.08322)
			(xy 240.417096 -46.08322) (xy 240.408078 -46.083571) (xy 240.391161 -46.089822) (xy 240.384076 -46.095412)
			(xy 240.383568 -46.09592) (xy 240.362596 -46.113484) (xy 240.316635 -46.143145) (xy 240.266907 -46.165933)
			(xy 240.214433 -46.181383) (xy 240.16029 -46.189176) (xy 240.105589 -46.189153) (xy 240.051452 -46.181314)
			(xy 239.998991 -46.16582) (xy 239.949283 -46.14299) (xy 239.903346 -46.11329) (xy 239.882426 -46.095666)
			(xy 239.882172 -46.095412) (xy 239.875068 -46.089851) (xy 239.858165 -46.083588) (xy 239.849152 -46.08322)
			(xy 239.782096 -46.08322) (xy 239.773078 -46.083571) (xy 239.756161 -46.089822) (xy 239.749076 -46.095412)
			(xy 239.748568 -46.09592) (xy 239.727596 -46.113484) (xy 239.681635 -46.143145) (xy 239.631907 -46.165933)
			(xy 239.579433 -46.181383) (xy 239.52529 -46.189176) (xy 239.470589 -46.189153) (xy 239.416452 -46.181314)
			(xy 239.363991 -46.16582) (xy 239.314283 -46.14299) (xy 239.268346 -46.11329) (xy 239.247426 -46.095666)
			(xy 239.247172 -46.095412) (xy 239.240068 -46.089851) (xy 239.223165 -46.083588) (xy 239.214152 -46.08322)
			(xy 239.147096 -46.08322) (xy 239.138078 -46.083571) (xy 239.121161 -46.089822) (xy 239.114076 -46.095412)
			(xy 239.113568 -46.09592) (xy 239.09263 -46.113497) (xy 239.046696 -46.143137) (xy 238.997001 -46.165916)
			(xy 238.944564 -46.181368) (xy 238.890457 -46.189175) (xy 238.863124 -46.189646) (xy 238.835873 -46.189108)
			(xy 238.781925 -46.181355) (xy 238.729629 -46.166003) (xy 238.680051 -46.143364) (xy 238.634199 -46.113899)
			(xy 238.593008 -46.078209) (xy 238.557315 -46.03702) (xy 238.527848 -45.99117) (xy 238.505206 -45.941593)
			(xy 238.48985 -45.889299) (xy 238.482093 -45.835351) (xy 237.403483 -45.835351) (xy 237.403483 -45.835356)
			(xy 237.395725 -45.889314) (xy 237.380367 -45.941618) (xy 237.357721 -45.991204) (xy 237.328249 -46.037063)
			(xy 237.29255 -46.07826) (xy 237.251351 -46.113957) (xy 237.205492 -46.143428) (xy 237.155905 -46.166072)
			(xy 237.1036 -46.181428) (xy 237.049642 -46.189184) (xy 237.022386 -46.189646) (xy 237.022132 -46.189646)
			(xy 236.995837 -46.189183) (xy 236.943748 -46.181941) (xy 236.893146 -46.167617) (xy 236.844989 -46.146483)
			(xy 236.80019 -46.118937) (xy 236.759596 -46.085503) (xy 236.741462 -46.066456) (xy 236.733896 -46.059007)
			(xy 236.714474 -46.050485) (xy 236.70387 -46.049946) (xy 236.629702 -46.049946) (xy 236.619073 -46.050381)
			(xy 236.59961 -46.058914) (xy 236.59211 -46.066456) (xy 236.573977 -46.085507) (xy 236.533397 -46.118966)
			(xy 236.488602 -46.146527) (xy 236.440443 -46.167667) (xy 236.389834 -46.181985) (xy 236.337738 -46.189208)
			(xy 236.31144 -46.189646) (xy 236.311186 -46.189646) (xy 236.283815 -46.189201) (xy 236.229634 -46.18138)
			(xy 236.17713 -46.165887) (xy 236.127384 -46.14304) (xy 236.081418 -46.11331) (xy 236.060488 -46.095666)
			(xy 236.060234 -46.095412) (xy 236.053141 -46.089835) (xy 236.036229 -46.083582) (xy 236.027214 -46.08322)
			(xy 235.960158 -46.08322) (xy 235.951143 -46.083601) (xy 235.934226 -46.089831) (xy 235.927138 -46.095412)
			(xy 235.92663 -46.09592) (xy 235.905688 -46.113522) (xy 235.859721 -46.14318) (xy 235.809988 -46.165967)
			(xy 235.75751 -46.181413) (xy 235.703363 -46.189203) (xy 235.648658 -46.189176) (xy 235.594519 -46.181332)
			(xy 235.542056 -46.165834) (xy 235.492345 -46.142998) (xy 235.446408 -46.113293) (xy 235.425488 -46.095666)
			(xy 235.425234 -46.095412) (xy 235.418141 -46.089835) (xy 235.401229 -46.083582) (xy 235.392214 -46.08322)
			(xy 235.325158 -46.08322) (xy 235.316143 -46.083601) (xy 235.299226 -46.089831) (xy 235.292138 -46.095412)
			(xy 235.29163 -46.09592) (xy 235.270706 -46.113515) (xy 235.224768 -46.143152) (xy 235.17507 -46.165928)
			(xy 235.122629 -46.181375) (xy 235.06852 -46.189178) (xy 235.041186 -46.189646) (xy 235.013938 -46.189083)
			(xy 234.959997 -46.181326) (xy 234.90771 -46.165971) (xy 234.858139 -46.143331) (xy 234.812295 -46.113867)
			(xy 234.771111 -46.078179) (xy 234.735424 -46.036994) (xy 234.705962 -45.991149) (xy 234.683324 -45.941577)
			(xy 234.667972 -45.889289) (xy 234.660216 -45.835348) (xy 221.792322 -45.835348) (xy 221.796101 -45.861024)
			(xy 221.79661 -45.88891) (xy 221.796101 -45.916796) (xy 221.787981 -45.971972) (xy 221.771913 -46.025379)
			(xy 221.748241 -46.075876) (xy 221.717468 -46.122389) (xy 221.680251 -46.163926) (xy 221.637383 -46.199601)
			(xy 221.589777 -46.228655) (xy 221.538448 -46.250467) (xy 221.484491 -46.264573) (xy 221.429054 -46.270673)
			(xy 221.37332 -46.268636) (xy 221.318477 -46.258506) (xy 221.265693 -46.240499) (xy 221.216093 -46.214998)
			(xy 221.170735 -46.182547) (xy 221.130586 -46.143838) (xy 221.0965 -46.099695) (xy 221.069204 -46.05106)
			(xy 221.049281 -45.998969) (xy 221.037155 -45.944532) (xy 221.033084 -45.88891) (xy 217.920784 -45.88891)
			(xy 217.913719 -45.93692) (xy 217.897651 -45.990327) (xy 217.873979 -46.040824) (xy 217.843206 -46.087337)
			(xy 217.805989 -46.128874) (xy 217.763121 -46.164549) (xy 217.715515 -46.193603) (xy 217.664186 -46.215415)
			(xy 217.610229 -46.229521) (xy 217.554792 -46.235621) (xy 217.499058 -46.233584) (xy 217.444215 -46.223454)
			(xy 217.391431 -46.205447) (xy 217.341831 -46.179946) (xy 217.296473 -46.147495) (xy 217.256324 -46.108786)
			(xy 217.222238 -46.064643) (xy 217.194942 -46.016008) (xy 217.175019 -45.963917) (xy 217.162893 -45.90948)
			(xy 217.158822 -45.853858) (xy 216.732657 -45.853858) (xy 216.732866 -45.865288) (xy 216.732357 -45.893174)
			(xy 216.724237 -45.94835) (xy 216.708169 -46.001757) (xy 216.684497 -46.052254) (xy 216.653724 -46.098767)
			(xy 216.616507 -46.140304) (xy 216.573639 -46.175979) (xy 216.526033 -46.205033) (xy 216.474704 -46.226845)
			(xy 216.420747 -46.240951) (xy 216.36531 -46.247051) (xy 216.309576 -46.245014) (xy 216.254733 -46.234884)
			(xy 216.201949 -46.216877) (xy 216.152349 -46.191376) (xy 216.106991 -46.158925) (xy 216.066842 -46.120216)
			(xy 216.032756 -46.076073) (xy 216.00546 -46.027438) (xy 215.985537 -45.975347) (xy 215.973411 -45.92091)
			(xy 215.96934 -45.865288) (xy 214.423997 -45.865288) (xy 214.432752 -45.895106) (xy 214.440508 -45.949051)
			(xy 214.440508 -46.003549) (xy 214.432752 -46.057494) (xy 214.417398 -46.109785) (xy 214.394759 -46.15936)
			(xy 214.365295 -46.205207) (xy 214.329607 -46.246396) (xy 214.28842 -46.282086) (xy 214.242574 -46.311551)
			(xy 214.193 -46.334193) (xy 214.140709 -46.349549) (xy 214.086765 -46.357307) (xy 214.059516 -46.357794)
			(xy 214.032524 -46.357312) (xy 213.979077 -46.349709) (xy 213.927234 -46.334653) (xy 213.878029 -46.312444)
			(xy 213.832444 -46.283525) (xy 213.811612 -46.266354) (xy 213.80323 -46.259242) (xy 213.78291 -46.253146)
			(xy 213.69782 -46.264068) (xy 213.692459 -46.264799) (xy 213.682209 -46.268261) (xy 213.6775 -46.270926)
			(xy 213.66861 -46.276514) (xy 213.66226 -46.285404) (xy 213.662006 -46.285658) (xy 213.644413 -46.309857)
			(xy 213.602945 -46.35298) (xy 213.579456 -46.37151) (xy 213.571328 -46.377606) (xy 213.561168 -46.394624)
			(xy 213.549484 -46.475396) (xy 213.548501 -46.485161) (xy 213.553062 -46.504229) (xy 213.558374 -46.51248)
			(xy 213.558628 -46.512734) (xy 213.558882 -46.512988) (xy 213.576327 -46.537721) (xy 213.604037 -46.591525)
			(xy 213.622908 -46.649028) (xy 213.632467 -46.708788) (xy 213.63305 -46.739048) (xy 213.632567 -46.766299)
			(xy 213.624805 -46.820244) (xy 213.609446 -46.872536) (xy 213.599996 -46.893226) (xy 214.437212 -46.893226)
			(xy 214.441283 -46.837604) (xy 214.453409 -46.783167) (xy 214.473332 -46.731076) (xy 214.500628 -46.682441)
			(xy 214.534714 -46.638298) (xy 214.574863 -46.599589) (xy 214.620221 -46.567138) (xy 214.669821 -46.541637)
			(xy 214.722605 -46.52363) (xy 214.777448 -46.5135) (xy 214.833182 -46.511463) (xy 214.888619 -46.517563)
			(xy 214.942576 -46.531669) (xy 214.993905 -46.553481) (xy 215.041511 -46.582535) (xy 215.084379 -46.61821)
			(xy 215.121596 -46.659747) (xy 215.152369 -46.70626) (xy 215.176041 -46.756757) (xy 215.192109 -46.810164)
			(xy 215.200229 -46.86534) (xy 215.200738 -46.893226) (xy 215.200229 -46.921112) (xy 215.192109 -46.976288)
			(xy 215.176041 -47.029695) (xy 215.175003 -47.03191) (xy 215.96934 -47.03191) (xy 215.973411 -46.976288)
			(xy 215.985537 -46.921851) (xy 216.00546 -46.86976) (xy 216.032756 -46.821125) (xy 216.066842 -46.776982)
			(xy 216.106991 -46.738273) (xy 216.152349 -46.705822) (xy 216.201949 -46.680321) (xy 216.254733 -46.662314)
			(xy 216.309576 -46.652184) (xy 216.36531 -46.650147) (xy 216.420747 -46.656247) (xy 216.474704 -46.670353)
			(xy 216.526033 -46.692165) (xy 216.573639 -46.721219) (xy 216.616507 -46.756894) (xy 216.653724 -46.798431)
			(xy 216.684497 -46.844944) (xy 216.708169 -46.895441) (xy 216.724237 -46.948848) (xy 216.732357 -47.004024)
			(xy 216.732662 -47.020734) (xy 217.147392 -47.020734) (xy 217.151463 -46.965112) (xy 217.163589 -46.910675)
			(xy 217.183512 -46.858584) (xy 217.210808 -46.809949) (xy 217.244894 -46.765806) (xy 217.285043 -46.727097)
			(xy 217.330401 -46.694646) (xy 217.380001 -46.669145) (xy 217.432785 -46.651138) (xy 217.487628 -46.641008)
			(xy 217.543362 -46.638971) (xy 217.598799 -46.645071) (xy 217.652756 -46.659177) (xy 217.704085 -46.680989)
			(xy 217.725135 -46.693836) (xy 218.776296 -46.693836) (xy 218.776782 -46.666585) (xy 218.784538 -46.612637)
			(xy 218.799893 -46.560342) (xy 218.822535 -46.510765) (xy 218.852001 -46.464915) (xy 218.887692 -46.423724)
			(xy 218.928883 -46.388033) (xy 218.974733 -46.358567) (xy 219.02431 -46.335925) (xy 219.076605 -46.32057)
			(xy 219.130553 -46.312814) (xy 219.185055 -46.312814) (xy 219.239003 -46.32057) (xy 219.291298 -46.335925)
			(xy 219.340875 -46.358567) (xy 219.386725 -46.388033) (xy 219.427916 -46.423724) (xy 219.463607 -46.464915)
			(xy 219.493073 -46.510765) (xy 219.515715 -46.560342) (xy 219.53107 -46.612637) (xy 219.538826 -46.666585)
			(xy 219.539312 -46.693836) (xy 219.538838 -46.720263) (xy 219.531528 -46.772611) (xy 219.517056 -46.823446)
			(xy 219.495696 -46.871793) (xy 219.482162 -46.894496) (xy 219.482162 -46.89475) (xy 219.476587 -46.904677)
			(xy 219.474064 -46.92728) (xy 219.477336 -46.938184) (xy 219.507816 -47.023782) (xy 219.524072 -47.040038)
			(xy 219.534994 -47.043848) (xy 219.559513 -47.052891) (xy 219.605964 -47.076839) (xy 219.648715 -47.106899)
			(xy 219.686965 -47.142511) (xy 219.72 -47.183007) (xy 219.747202 -47.227631) (xy 219.768063 -47.275548)
			(xy 219.782192 -47.325863) (xy 219.789325 -47.377635) (xy 219.789756 -47.403766) (xy 219.78927 -47.431017)
			(xy 219.787747 -47.441612) (xy 221.061786 -47.441612) (xy 221.065857 -47.38599) (xy 221.077983 -47.331553)
			(xy 221.097906 -47.279462) (xy 221.125202 -47.230827) (xy 221.159288 -47.186684) (xy 221.199437 -47.147975)
			(xy 221.244795 -47.115524) (xy 221.294395 -47.090023) (xy 221.347179 -47.072016) (xy 221.402022 -47.061886)
			(xy 221.457756 -47.059849) (xy 221.513193 -47.065949) (xy 221.56715 -47.080055) (xy 221.618479 -47.101867)
			(xy 221.666085 -47.130921) (xy 221.708953 -47.166596) (xy 221.74617 -47.208133) (xy 221.776943 -47.254646)
			(xy 221.800615 -47.305143) (xy 221.816683 -47.35855) (xy 221.824803 -47.413726) (xy 221.825312 -47.441612)
			(xy 221.824803 -47.469498) (xy 221.816683 -47.524674) (xy 221.800615 -47.578081) (xy 221.776943 -47.628578)
			(xy 221.74617 -47.675091) (xy 221.708953 -47.716628) (xy 221.666085 -47.752303) (xy 221.618479 -47.781357)
			(xy 221.56715 -47.803169) (xy 221.513193 -47.817275) (xy 221.457756 -47.823375) (xy 221.402022 -47.821338)
			(xy 221.347179 -47.811208) (xy 221.294395 -47.793201) (xy 221.244795 -47.7677) (xy 221.199437 -47.735249)
			(xy 221.159288 -47.69654) (xy 221.125202 -47.652397) (xy 221.097906 -47.603762) (xy 221.077983 -47.551671)
			(xy 221.065857 -47.497234) (xy 221.061786 -47.441612) (xy 219.787747 -47.441612) (xy 219.781514 -47.484965)
			(xy 219.766159 -47.53726) (xy 219.743517 -47.586837) (xy 219.714051 -47.632687) (xy 219.67836 -47.673878)
			(xy 219.637169 -47.709569) (xy 219.591319 -47.739035) (xy 219.541742 -47.761677) (xy 219.489447 -47.777032)
			(xy 219.435499 -47.784788) (xy 219.380997 -47.784788) (xy 219.327049 -47.777032) (xy 219.274754 -47.761677)
			(xy 219.225177 -47.739035) (xy 219.179327 -47.709569) (xy 219.138136 -47.673878) (xy 219.102445 -47.632687)
			(xy 219.072979 -47.586837) (xy 219.050337 -47.53726) (xy 219.034982 -47.484965) (xy 219.027226 -47.431017)
			(xy 219.02674 -47.403766) (xy 219.027208 -47.377338) (xy 219.034518 -47.324991) (xy 219.048993 -47.274155)
			(xy 219.070354 -47.225809) (xy 219.08389 -47.203106) (xy 219.08389 -47.202852) (xy 219.089364 -47.19289)
			(xy 219.09188 -47.170334) (xy 219.088716 -47.159418) (xy 219.058236 -47.07382) (xy 219.04198 -47.057564)
			(xy 219.031058 -47.053754) (xy 219.006551 -47.04468) (xy 218.960098 -47.020739) (xy 218.917346 -46.990683)
			(xy 218.879094 -46.955077) (xy 218.846057 -46.914584) (xy 218.818854 -46.869964) (xy 218.797991 -46.822049)
			(xy 218.783861 -46.771736) (xy 218.776727 -46.719966) (xy 218.776296 -46.693836) (xy 217.725135 -46.693836)
			(xy 217.751691 -46.710043) (xy 217.794559 -46.745718) (xy 217.831776 -46.787255) (xy 217.862549 -46.833768)
			(xy 217.886221 -46.884265) (xy 217.902289 -46.937672) (xy 217.910409 -46.992848) (xy 217.910918 -47.020734)
			(xy 217.910409 -47.04862) (xy 217.902289 -47.103796) (xy 217.886221 -47.157203) (xy 217.862549 -47.2077)
			(xy 217.831776 -47.254213) (xy 217.794559 -47.29575) (xy 217.751691 -47.331425) (xy 217.704085 -47.360479)
			(xy 217.652756 -47.382291) (xy 217.598799 -47.396397) (xy 217.543362 -47.402497) (xy 217.487628 -47.40046)
			(xy 217.432785 -47.39033) (xy 217.380001 -47.372323) (xy 217.330401 -47.346822) (xy 217.285043 -47.314371)
			(xy 217.244894 -47.275662) (xy 217.210808 -47.231519) (xy 217.183512 -47.182884) (xy 217.163589 -47.130793)
			(xy 217.151463 -47.076356) (xy 217.147392 -47.020734) (xy 216.732662 -47.020734) (xy 216.732866 -47.03191)
			(xy 216.732357 -47.059796) (xy 216.724237 -47.114972) (xy 216.708169 -47.168379) (xy 216.684497 -47.218876)
			(xy 216.653724 -47.265389) (xy 216.616507 -47.306926) (xy 216.573639 -47.342601) (xy 216.526033 -47.371655)
			(xy 216.474704 -47.393467) (xy 216.420747 -47.407573) (xy 216.36531 -47.413673) (xy 216.309576 -47.411636)
			(xy 216.254733 -47.401506) (xy 216.201949 -47.383499) (xy 216.152349 -47.357998) (xy 216.106991 -47.325547)
			(xy 216.066842 -47.286838) (xy 216.032756 -47.242695) (xy 216.00546 -47.19406) (xy 215.985537 -47.141969)
			(xy 215.973411 -47.087532) (xy 215.96934 -47.03191) (xy 215.175003 -47.03191) (xy 215.152369 -47.080192)
			(xy 215.121596 -47.126705) (xy 215.084379 -47.168242) (xy 215.041511 -47.203917) (xy 214.993905 -47.232971)
			(xy 214.942576 -47.254783) (xy 214.888619 -47.268889) (xy 214.833182 -47.274989) (xy 214.777448 -47.272952)
			(xy 214.722605 -47.262822) (xy 214.669821 -47.244815) (xy 214.620221 -47.219314) (xy 214.574863 -47.186863)
			(xy 214.534714 -47.148154) (xy 214.500628 -47.104011) (xy 214.473332 -47.055376) (xy 214.453409 -47.003285)
			(xy 214.441283 -46.948848) (xy 214.437212 -46.893226) (xy 213.599996 -46.893226) (xy 213.586802 -46.922111)
			(xy 213.557335 -46.967959) (xy 213.521643 -47.009148) (xy 213.480454 -47.044838) (xy 213.434606 -47.074305)
			(xy 213.385031 -47.096948) (xy 213.332738 -47.112306) (xy 213.278793 -47.120067) (xy 213.251542 -47.120556)
			(xy 213.225508 -47.120134) (xy 213.173924 -47.11304) (xy 213.123782 -47.099005) (xy 213.076011 -47.078288)
			(xy 213.031498 -47.051275) (xy 213.011004 -47.035212) (xy 213.003384 -47.029116) (xy 212.984842 -47.023274)
			(xy 212.905086 -47.029624) (xy 212.895446 -47.030784) (xy 212.878075 -47.039427) (xy 212.871304 -47.046388)
			(xy 212.853144 -47.066054) (xy 212.812232 -47.100574) (xy 212.766898 -47.129041) (xy 212.718033 -47.150895)
			(xy 212.666593 -47.165708) (xy 212.613589 -47.17319) (xy 212.586824 -47.173642) (xy 212.559575 -47.1731)
			(xy 212.505631 -47.165347) (xy 212.453339 -47.149997) (xy 212.403765 -47.127361) (xy 212.357916 -47.0979)
			(xy 212.316726 -47.062215) (xy 212.281034 -47.021031) (xy 212.251567 -46.975186) (xy 212.228923 -46.925615)
			(xy 212.213565 -46.873326) (xy 212.205805 -46.819383) (xy 212.205316 -46.792134) (xy 212.205836 -46.76336)
			(xy 212.214488 -46.706465) (xy 212.231585 -46.651515) (xy 212.256739 -46.599754) (xy 212.289381 -46.552359)
			(xy 212.308694 -46.531022) (xy 212.315596 -46.522973) (xy 212.32268 -46.503014) (xy 212.32241 -46.492414)
			(xy 212.316822 -46.417992) (xy 212.315539 -46.407523) (xy 212.305689 -46.388895) (xy 212.297772 -46.381924)
			(xy 212.297518 -46.38167) (xy 212.275333 -46.363446) (xy 212.236123 -46.32151) (xy 212.203638 -46.274174)
			(xy 212.178609 -46.222506) (xy 212.161603 -46.167672) (xy 212.153002 -46.110909) (xy 212.152484 -46.082204)
			(xy 195.744106 -46.082204) (xy 195.71752 -46.122389) (xy 195.680303 -46.163926) (xy 195.637435 -46.199601)
			(xy 195.589829 -46.228655) (xy 195.5385 -46.250467) (xy 195.484543 -46.264573) (xy 195.429106 -46.270673)
			(xy 195.373372 -46.268636) (xy 195.318529 -46.258506) (xy 195.265745 -46.240499) (xy 195.216145 -46.214998)
			(xy 195.170787 -46.182547) (xy 195.130638 -46.143838) (xy 195.096552 -46.099695) (xy 195.069256 -46.05106)
			(xy 195.049333 -45.998969) (xy 195.037207 -45.944532) (xy 195.033136 -45.88891) (xy 191.920836 -45.88891)
			(xy 191.913771 -45.93692) (xy 191.897703 -45.990327) (xy 191.874031 -46.040824) (xy 191.843258 -46.087337)
			(xy 191.806041 -46.128874) (xy 191.763173 -46.164549) (xy 191.715567 -46.193603) (xy 191.664238 -46.215415)
			(xy 191.610281 -46.229521) (xy 191.554844 -46.235621) (xy 191.49911 -46.233584) (xy 191.444267 -46.223454)
			(xy 191.391483 -46.205447) (xy 191.341883 -46.179946) (xy 191.296525 -46.147495) (xy 191.256376 -46.108786)
			(xy 191.22229 -46.064643) (xy 191.194994 -46.016008) (xy 191.175071 -45.963917) (xy 191.162945 -45.90948)
			(xy 191.158874 -45.853858) (xy 190.732709 -45.853858) (xy 190.732918 -45.865288) (xy 190.732409 -45.893174)
			(xy 190.724289 -45.94835) (xy 190.708221 -46.001757) (xy 190.684549 -46.052254) (xy 190.653776 -46.098767)
			(xy 190.616559 -46.140304) (xy 190.573691 -46.175979) (xy 190.526085 -46.205033) (xy 190.474756 -46.226845)
			(xy 190.420799 -46.240951) (xy 190.365362 -46.247051) (xy 190.309628 -46.245014) (xy 190.254785 -46.234884)
			(xy 190.202001 -46.216877) (xy 190.152401 -46.191376) (xy 190.107043 -46.158925) (xy 190.066894 -46.120216)
			(xy 190.032808 -46.076073) (xy 190.005512 -46.027438) (xy 189.985589 -45.975347) (xy 189.973463 -45.92091)
			(xy 189.969392 -45.865288) (xy 188.424121 -45.865288) (xy 188.432873 -45.895095) (xy 188.440631 -45.949047)
			(xy 188.440631 -46.003553) (xy 188.432873 -46.057505) (xy 188.417516 -46.109804) (xy 188.394872 -46.159384)
			(xy 188.365402 -46.205237) (xy 188.329706 -46.246429) (xy 188.288511 -46.282121) (xy 188.242656 -46.311587)
			(xy 188.193074 -46.334227) (xy 188.140774 -46.34958) (xy 188.086821 -46.357333) (xy 188.059568 -46.357794)
			(xy 188.032575 -46.35734) (xy 187.979127 -46.34973) (xy 187.927284 -46.334668) (xy 187.878079 -46.312453)
			(xy 187.832495 -46.283528) (xy 187.811664 -46.266354) (xy 187.803282 -46.259242) (xy 187.782962 -46.253146)
			(xy 187.697872 -46.264068) (xy 187.692513 -46.264815) (xy 187.682263 -46.268266) (xy 187.677552 -46.270926)
			(xy 187.668662 -46.276514) (xy 187.662312 -46.285404) (xy 187.662058 -46.285658) (xy 187.644471 -46.309862)
			(xy 187.602999 -46.352982) (xy 187.579508 -46.37151) (xy 187.57138 -46.377606) (xy 187.56122 -46.394624)
			(xy 187.549536 -46.475396) (xy 187.548562 -46.485161) (xy 187.553118 -46.504228) (xy 187.558426 -46.51248)
			(xy 187.55868 -46.512734) (xy 187.558934 -46.512988) (xy 187.576385 -46.537716) (xy 187.604092 -46.591522)
			(xy 187.622961 -46.649027) (xy 187.632519 -46.708788) (xy 187.633102 -46.739048) (xy 187.632667 -46.766301)
			(xy 187.624904 -46.820251) (xy 187.609542 -46.872547) (xy 187.600096 -46.893226) (xy 188.437264 -46.893226)
			(xy 188.441335 -46.837604) (xy 188.453461 -46.783167) (xy 188.473384 -46.731076) (xy 188.50068 -46.682441)
			(xy 188.534766 -46.638298) (xy 188.574915 -46.599589) (xy 188.620273 -46.567138) (xy 188.669873 -46.541637)
			(xy 188.722657 -46.52363) (xy 188.7775 -46.5135) (xy 188.833234 -46.511463) (xy 188.888671 -46.517563)
			(xy 188.942628 -46.531669) (xy 188.993957 -46.553481) (xy 189.041563 -46.582535) (xy 189.084431 -46.61821)
			(xy 189.121648 -46.659747) (xy 189.152421 -46.70626) (xy 189.176093 -46.756757) (xy 189.192161 -46.810164)
			(xy 189.200281 -46.86534) (xy 189.20079 -46.893226) (xy 189.200281 -46.921112) (xy 189.192161 -46.976288)
			(xy 189.176093 -47.029695) (xy 189.175055 -47.03191) (xy 189.969392 -47.03191) (xy 189.973463 -46.976288)
			(xy 189.985589 -46.921851) (xy 190.005512 -46.86976) (xy 190.032808 -46.821125) (xy 190.066894 -46.776982)
			(xy 190.107043 -46.738273) (xy 190.152401 -46.705822) (xy 190.202001 -46.680321) (xy 190.254785 -46.662314)
			(xy 190.309628 -46.652184) (xy 190.365362 -46.650147) (xy 190.420799 -46.656247) (xy 190.474756 -46.670353)
			(xy 190.526085 -46.692165) (xy 190.573691 -46.721219) (xy 190.616559 -46.756894) (xy 190.653776 -46.798431)
			(xy 190.684549 -46.844944) (xy 190.708221 -46.895441) (xy 190.724289 -46.948848) (xy 190.732409 -47.004024)
			(xy 190.732714 -47.020734) (xy 191.147444 -47.020734) (xy 191.151515 -46.965112) (xy 191.163641 -46.910675)
			(xy 191.183564 -46.858584) (xy 191.21086 -46.809949) (xy 191.244946 -46.765806) (xy 191.285095 -46.727097)
			(xy 191.330453 -46.694646) (xy 191.380053 -46.669145) (xy 191.432837 -46.651138) (xy 191.48768 -46.641008)
			(xy 191.543414 -46.638971) (xy 191.598851 -46.645071) (xy 191.652808 -46.659177) (xy 191.704137 -46.680989)
			(xy 191.725187 -46.693836) (xy 192.776348 -46.693836) (xy 192.776912 -46.666588) (xy 192.784662 -46.612645)
			(xy 192.80001 -46.560354) (xy 192.822644 -46.51078) (xy 192.852103 -46.464932) (xy 192.887786 -46.423743)
			(xy 192.928968 -46.388051) (xy 192.97481 -46.358583) (xy 193.024379 -46.335938) (xy 193.076667 -46.320579)
			(xy 193.130608 -46.312817) (xy 193.157856 -46.312328) (xy 193.185109 -46.312796) (xy 193.239062 -46.320548)
			(xy 193.291362 -46.335901) (xy 193.340944 -46.358541) (xy 193.386799 -46.388007) (xy 193.427994 -46.423701)
			(xy 193.463688 -46.464894) (xy 193.493156 -46.510749) (xy 193.515797 -46.56033) (xy 193.53115 -46.61263)
			(xy 193.538903 -46.666583) (xy 193.539364 -46.693836) (xy 193.538896 -46.720264) (xy 193.531586 -46.772611)
			(xy 193.517111 -46.823446) (xy 193.49575 -46.871793) (xy 193.482214 -46.894496) (xy 193.482214 -46.89475)
			(xy 193.476739 -46.904711) (xy 193.474223 -46.927268) (xy 193.477388 -46.938184) (xy 193.507868 -47.023782)
			(xy 193.524124 -47.040038) (xy 193.535046 -47.043848) (xy 193.559555 -47.052918) (xy 193.606007 -47.07686)
			(xy 193.648759 -47.106916) (xy 193.687011 -47.142523) (xy 193.720048 -47.183016) (xy 193.747251 -47.227637)
			(xy 193.768113 -47.275552) (xy 193.782243 -47.325866) (xy 193.789377 -47.377636) (xy 193.789808 -47.403766)
			(xy 193.789313 -47.431018) (xy 193.787791 -47.441612) (xy 195.061838 -47.441612) (xy 195.065909 -47.38599)
			(xy 195.078035 -47.331553) (xy 195.097958 -47.279462) (xy 195.125254 -47.230827) (xy 195.15934 -47.186684)
			(xy 195.199489 -47.147975) (xy 195.244847 -47.115524) (xy 195.294447 -47.090023) (xy 195.347231 -47.072016)
			(xy 195.402074 -47.061886) (xy 195.457808 -47.059849) (xy 195.513245 -47.065949) (xy 195.567202 -47.080055)
			(xy 195.618531 -47.101867) (xy 195.666137 -47.130921) (xy 195.709005 -47.166596) (xy 195.746222 -47.208133)
			(xy 195.776995 -47.254646) (xy 195.800667 -47.305143) (xy 195.816735 -47.35855) (xy 195.824855 -47.413726)
			(xy 195.825364 -47.441612) (xy 195.824855 -47.469498) (xy 195.816735 -47.524674) (xy 195.800667 -47.578081)
			(xy 195.776995 -47.628578) (xy 195.746222 -47.675091) (xy 195.709005 -47.716628) (xy 195.666137 -47.752303)
			(xy 195.618531 -47.781357) (xy 195.567202 -47.803169) (xy 195.513245 -47.817275) (xy 195.457808 -47.823375)
			(xy 195.402074 -47.821338) (xy 195.347231 -47.811208) (xy 195.294447 -47.793201) (xy 195.244847 -47.7677)
			(xy 195.199489 -47.735249) (xy 195.15934 -47.69654) (xy 195.125254 -47.652397) (xy 195.097958 -47.603762)
			(xy 195.078035 -47.551671) (xy 195.065909 -47.497234) (xy 195.061838 -47.441612) (xy 193.787791 -47.441612)
			(xy 193.781561 -47.484968) (xy 193.766209 -47.537265) (xy 193.74357 -47.586845) (xy 193.714106 -47.632698)
			(xy 193.678416 -47.673891) (xy 193.637226 -47.709586) (xy 193.591375 -47.739054) (xy 193.541797 -47.761697)
			(xy 193.489501 -47.777053) (xy 193.435552 -47.784811) (xy 193.4083 -47.785274) (xy 193.381046 -47.784845)
			(xy 193.327092 -47.777087) (xy 193.274791 -47.761729) (xy 193.225209 -47.739084) (xy 193.179354 -47.709613)
			(xy 193.13816 -47.673915) (xy 193.102467 -47.632719) (xy 193.073 -47.586861) (xy 193.050359 -47.537277)
			(xy 193.035006 -47.484975) (xy 193.027253 -47.43102) (xy 193.026792 -47.403766) (xy 193.027267 -47.377339)
			(xy 193.034576 -47.324991) (xy 193.049049 -47.274156) (xy 193.070408 -47.225809) (xy 193.083942 -47.203106)
			(xy 193.083942 -47.202852) (xy 193.089516 -47.192925) (xy 193.092039 -47.170322) (xy 193.088768 -47.159418)
			(xy 193.058288 -47.07382) (xy 193.042032 -47.057564) (xy 193.03111 -47.053754) (xy 193.006593 -47.044708)
			(xy 192.960141 -47.02076) (xy 192.917391 -46.9907) (xy 192.87914 -46.955089) (xy 192.846105 -46.914594)
			(xy 192.818903 -46.86997) (xy 192.798042 -46.822053) (xy 192.783913 -46.771738) (xy 192.776779 -46.719966)
			(xy 192.776348 -46.693836) (xy 191.725187 -46.693836) (xy 191.751743 -46.710043) (xy 191.794611 -46.745718)
			(xy 191.831828 -46.787255) (xy 191.862601 -46.833768) (xy 191.886273 -46.884265) (xy 191.902341 -46.937672)
			(xy 191.910461 -46.992848) (xy 191.91097 -47.020734) (xy 191.910461 -47.04862) (xy 191.902341 -47.103796)
			(xy 191.886273 -47.157203) (xy 191.862601 -47.2077) (xy 191.831828 -47.254213) (xy 191.794611 -47.29575)
			(xy 191.751743 -47.331425) (xy 191.704137 -47.360479) (xy 191.652808 -47.382291) (xy 191.598851 -47.396397)
			(xy 191.543414 -47.402497) (xy 191.48768 -47.40046) (xy 191.432837 -47.39033) (xy 191.380053 -47.372323)
			(xy 191.330453 -47.346822) (xy 191.285095 -47.314371) (xy 191.244946 -47.275662) (xy 191.21086 -47.231519)
			(xy 191.183564 -47.182884) (xy 191.163641 -47.130793) (xy 191.151515 -47.076356) (xy 191.147444 -47.020734)
			(xy 190.732714 -47.020734) (xy 190.732918 -47.03191) (xy 190.732409 -47.059796) (xy 190.724289 -47.114972)
			(xy 190.708221 -47.168379) (xy 190.684549 -47.218876) (xy 190.653776 -47.265389) (xy 190.616559 -47.306926)
			(xy 190.573691 -47.342601) (xy 190.526085 -47.371655) (xy 190.474756 -47.393467) (xy 190.420799 -47.407573)
			(xy 190.365362 -47.413673) (xy 190.309628 -47.411636) (xy 190.254785 -47.401506) (xy 190.202001 -47.383499)
			(xy 190.152401 -47.357998) (xy 190.107043 -47.325547) (xy 190.066894 -47.286838) (xy 190.032808 -47.242695)
			(xy 190.005512 -47.19406) (xy 189.985589 -47.141969) (xy 189.973463 -47.087532) (xy 189.969392 -47.03191)
			(xy 189.175055 -47.03191) (xy 189.152421 -47.080192) (xy 189.121648 -47.126705) (xy 189.084431 -47.168242)
			(xy 189.041563 -47.203917) (xy 188.993957 -47.232971) (xy 188.942628 -47.254783) (xy 188.888671 -47.268889)
			(xy 188.833234 -47.274989) (xy 188.7775 -47.272952) (xy 188.722657 -47.262822) (xy 188.669873 -47.244815)
			(xy 188.620273 -47.219314) (xy 188.574915 -47.186863) (xy 188.534766 -47.148154) (xy 188.50068 -47.104011)
			(xy 188.473384 -47.055376) (xy 188.453461 -47.003285) (xy 188.441335 -46.948848) (xy 188.437264 -46.893226)
			(xy 187.600096 -46.893226) (xy 187.586895 -46.922124) (xy 187.557423 -46.967975) (xy 187.521726 -47.009165)
			(xy 187.480532 -47.044855) (xy 187.434677 -47.074321) (xy 187.385096 -47.096961) (xy 187.332798 -47.112315)
			(xy 187.278847 -47.120071) (xy 187.251594 -47.120556) (xy 187.225561 -47.120105) (xy 187.173978 -47.113018)
			(xy 187.123836 -47.098989) (xy 187.076065 -47.078279) (xy 187.03155 -47.051272) (xy 187.011056 -47.035212)
			(xy 187.003436 -47.029116) (xy 186.984894 -47.023274) (xy 186.905138 -47.029624) (xy 186.895503 -47.030809)
			(xy 186.87813 -47.039435) (xy 186.871356 -47.046388) (xy 186.85317 -47.066029) (xy 186.812263 -47.100551)
			(xy 186.766935 -47.129021) (xy 186.718075 -47.150879) (xy 186.66664 -47.165698) (xy 186.613639 -47.173186)
			(xy 186.586876 -47.173642) (xy 186.559626 -47.173145) (xy 186.50568 -47.165386) (xy 186.453388 -47.150029)
			(xy 186.403813 -47.127388) (xy 186.357964 -47.097922) (xy 186.316775 -47.062232) (xy 186.281084 -47.021044)
			(xy 186.251617 -46.975196) (xy 186.228974 -46.925622) (xy 186.213616 -46.87333) (xy 186.205856 -46.819384)
			(xy 186.205368 -46.792134) (xy 186.205901 -46.76336) (xy 186.214551 -46.706467) (xy 186.231646 -46.651517)
			(xy 186.256797 -46.599757) (xy 186.289435 -46.55236) (xy 186.308746 -46.531022) (xy 186.315642 -46.522969)
			(xy 186.322731 -46.503013) (xy 186.322462 -46.492414) (xy 186.316874 -46.417992) (xy 186.315606 -46.407519)
			(xy 186.305747 -46.388892) (xy 186.297824 -46.381924) (xy 186.29757 -46.38167) (xy 186.275375 -46.363458)
			(xy 186.236168 -46.321518) (xy 186.203685 -46.27418) (xy 186.178659 -46.222509) (xy 186.161654 -46.167674)
			(xy 186.153054 -46.11091) (xy 186.152536 -46.082204) (xy 169.744158 -46.082204) (xy 169.717572 -46.122389)
			(xy 169.680355 -46.163926) (xy 169.637487 -46.199601) (xy 169.589881 -46.228655) (xy 169.538552 -46.250467)
			(xy 169.484595 -46.264573) (xy 169.429158 -46.270673) (xy 169.373424 -46.268636) (xy 169.318581 -46.258506)
			(xy 169.265797 -46.240499) (xy 169.216197 -46.214998) (xy 169.170839 -46.182547) (xy 169.13069 -46.143838)
			(xy 169.096604 -46.099695) (xy 169.069308 -46.05106) (xy 169.049385 -45.998969) (xy 169.037259 -45.944532)
			(xy 169.033188 -45.88891) (xy 165.920888 -45.88891) (xy 165.913823 -45.93692) (xy 165.897755 -45.990327)
			(xy 165.874083 -46.040824) (xy 165.84331 -46.087337) (xy 165.806093 -46.128874) (xy 165.763225 -46.164549)
			(xy 165.715619 -46.193603) (xy 165.66429 -46.215415) (xy 165.610333 -46.229521) (xy 165.554896 -46.235621)
			(xy 165.499162 -46.233584) (xy 165.444319 -46.223454) (xy 165.391535 -46.205447) (xy 165.341935 -46.179946)
			(xy 165.296577 -46.147495) (xy 165.256428 -46.108786) (xy 165.222342 -46.064643) (xy 165.195046 -46.016008)
			(xy 165.175123 -45.963917) (xy 165.162997 -45.90948) (xy 165.158926 -45.853858) (xy 164.732761 -45.853858)
			(xy 164.73297 -45.865288) (xy 164.732461 -45.893174) (xy 164.724341 -45.94835) (xy 164.708273 -46.001757)
			(xy 164.684601 -46.052254) (xy 164.653828 -46.098767) (xy 164.616611 -46.140304) (xy 164.573743 -46.175979)
			(xy 164.526137 -46.205033) (xy 164.474808 -46.226845) (xy 164.420851 -46.240951) (xy 164.365414 -46.247051)
			(xy 164.30968 -46.245014) (xy 164.254837 -46.234884) (xy 164.202053 -46.216877) (xy 164.152453 -46.191376)
			(xy 164.107095 -46.158925) (xy 164.066946 -46.120216) (xy 164.03286 -46.076073) (xy 164.005564 -46.027438)
			(xy 163.985641 -45.975347) (xy 163.973515 -45.92091) (xy 163.969444 -45.865288) (xy 162.424097 -45.865288)
			(xy 162.432852 -45.895107) (xy 162.440608 -45.949051) (xy 162.440608 -46.003549) (xy 162.432852 -46.057493)
			(xy 162.417499 -46.109784) (xy 162.39486 -46.159358) (xy 162.365396 -46.205206) (xy 162.329708 -46.246394)
			(xy 162.288522 -46.282084) (xy 162.242676 -46.31155) (xy 162.193103 -46.334192) (xy 162.140813 -46.349548)
			(xy 162.086869 -46.357306) (xy 162.05962 -46.357794) (xy 162.032628 -46.357309) (xy 161.979181 -46.349707)
			(xy 161.927338 -46.334652) (xy 161.878133 -46.312444) (xy 161.832548 -46.283525) (xy 161.811716 -46.266354)
			(xy 161.803334 -46.259242) (xy 161.783014 -46.253146) (xy 161.697924 -46.264068) (xy 161.692563 -46.2648)
			(xy 161.682313 -46.268262) (xy 161.677604 -46.270926) (xy 161.668714 -46.276514) (xy 161.662364 -46.285404)
			(xy 161.66211 -46.285658) (xy 161.644516 -46.309857) (xy 161.603049 -46.352979) (xy 161.57956 -46.37151)
			(xy 161.571432 -46.377606) (xy 161.561272 -46.394624) (xy 161.549588 -46.475396) (xy 161.548605 -46.485161)
			(xy 161.553165 -46.504229) (xy 161.558478 -46.51248) (xy 161.558732 -46.512734) (xy 161.558986 -46.512988)
			(xy 161.576431 -46.53772) (xy 161.604141 -46.591524) (xy 161.623012 -46.649027) (xy 161.632571 -46.708788)
			(xy 161.633154 -46.739048) (xy 161.632667 -46.766298) (xy 161.624905 -46.820244) (xy 161.609546 -46.872536)
			(xy 161.600096 -46.893226) (xy 162.437316 -46.893226) (xy 162.441387 -46.837604) (xy 162.453513 -46.783167)
			(xy 162.473436 -46.731076) (xy 162.500732 -46.682441) (xy 162.534818 -46.638298) (xy 162.574967 -46.599589)
			(xy 162.620325 -46.567138) (xy 162.669925 -46.541637) (xy 162.722709 -46.52363) (xy 162.777552 -46.5135)
			(xy 162.833286 -46.511463) (xy 162.888723 -46.517563) (xy 162.94268 -46.531669) (xy 162.994009 -46.553481)
			(xy 163.041615 -46.582535) (xy 163.084483 -46.61821) (xy 163.1217 -46.659747) (xy 163.152473 -46.70626)
			(xy 163.176145 -46.756757) (xy 163.192213 -46.810164) (xy 163.200333 -46.86534) (xy 163.200842 -46.893226)
			(xy 163.200333 -46.921112) (xy 163.192213 -46.976288) (xy 163.176145 -47.029695) (xy 163.175107 -47.03191)
			(xy 163.969444 -47.03191) (xy 163.973515 -46.976288) (xy 163.985641 -46.921851) (xy 164.005564 -46.86976)
			(xy 164.03286 -46.821125) (xy 164.066946 -46.776982) (xy 164.107095 -46.738273) (xy 164.152453 -46.705822)
			(xy 164.202053 -46.680321) (xy 164.254837 -46.662314) (xy 164.30968 -46.652184) (xy 164.365414 -46.650147)
			(xy 164.420851 -46.656247) (xy 164.474808 -46.670353) (xy 164.526137 -46.692165) (xy 164.573743 -46.721219)
			(xy 164.616611 -46.756894) (xy 164.653828 -46.798431) (xy 164.684601 -46.844944) (xy 164.708273 -46.895441)
			(xy 164.724341 -46.948848) (xy 164.732461 -47.004024) (xy 164.732766 -47.020734) (xy 165.147496 -47.020734)
			(xy 165.151567 -46.965112) (xy 165.163693 -46.910675) (xy 165.183616 -46.858584) (xy 165.210912 -46.809949)
			(xy 165.244998 -46.765806) (xy 165.285147 -46.727097) (xy 165.330505 -46.694646) (xy 165.380105 -46.669145)
			(xy 165.432889 -46.651138) (xy 165.487732 -46.641008) (xy 165.543466 -46.638971) (xy 165.598903 -46.645071)
			(xy 165.65286 -46.659177) (xy 165.704189 -46.680989) (xy 165.725239 -46.693836) (xy 166.7764 -46.693836)
			(xy 166.776889 -46.666584) (xy 166.784641 -46.612633) (xy 166.799993 -46.560335) (xy 166.822632 -46.510755)
			(xy 166.852097 -46.464901) (xy 166.887788 -46.423708) (xy 166.928979 -46.388014) (xy 166.97483 -46.358545)
			(xy 167.024409 -46.335903) (xy 167.076706 -46.320547) (xy 167.130656 -46.312791) (xy 167.157908 -46.312328)
			(xy 167.185163 -46.312748) (xy 167.239117 -46.320507) (xy 167.291418 -46.335866) (xy 167.341 -46.358512)
			(xy 167.386855 -46.387984) (xy 167.428049 -46.423682) (xy 167.463742 -46.46488) (xy 167.493209 -46.510738)
			(xy 167.51585 -46.560323) (xy 167.531202 -46.612626) (xy 167.538955 -46.666581) (xy 167.539416 -46.693836)
			(xy 167.538941 -46.720263) (xy 167.531632 -46.772611) (xy 167.517159 -46.823446) (xy 167.4958 -46.871793)
			(xy 167.482266 -46.894496) (xy 167.482266 -46.89475) (xy 167.476691 -46.904677) (xy 167.474168 -46.92728)
			(xy 167.47744 -46.938184) (xy 167.50792 -47.023782) (xy 167.524176 -47.040038) (xy 167.535098 -47.043848)
			(xy 167.559618 -47.052888) (xy 167.606069 -47.076837) (xy 167.648819 -47.106898) (xy 167.68707 -47.14251)
			(xy 167.720104 -47.183006) (xy 167.747306 -47.22763) (xy 167.768167 -47.275548) (xy 167.782296 -47.325863)
			(xy 167.789429 -47.377635) (xy 167.78986 -47.403766) (xy 167.789413 -47.43102) (xy 167.787891 -47.441612)
			(xy 169.06189 -47.441612) (xy 169.065961 -47.38599) (xy 169.078087 -47.331553) (xy 169.09801 -47.279462)
			(xy 169.125306 -47.230827) (xy 169.159392 -47.186684) (xy 169.199541 -47.147975) (xy 169.244899 -47.115524)
			(xy 169.294499 -47.090023) (xy 169.347283 -47.072016) (xy 169.402126 -47.061886) (xy 169.45786 -47.059849)
			(xy 169.513297 -47.065949) (xy 169.567254 -47.080055) (xy 169.618583 -47.101867) (xy 169.666189 -47.130921)
			(xy 169.709057 -47.166596) (xy 169.746274 -47.208133) (xy 169.777047 -47.254646) (xy 169.800719 -47.305143)
			(xy 169.816787 -47.35855) (xy 169.824907 -47.413726) (xy 169.825416 -47.441612) (xy 169.824907 -47.469498)
			(xy 169.816787 -47.524674) (xy 169.800719 -47.578081) (xy 169.777047 -47.628578) (xy 169.746274 -47.675091)
			(xy 169.709057 -47.716628) (xy 169.666189 -47.752303) (xy 169.618583 -47.781357) (xy 169.567254 -47.803169)
			(xy 169.513297 -47.817275) (xy 169.45786 -47.823375) (xy 169.402126 -47.821338) (xy 169.347283 -47.811208)
			(xy 169.294499 -47.793201) (xy 169.244899 -47.7677) (xy 169.199541 -47.735249) (xy 169.159392 -47.69654)
			(xy 169.125306 -47.652397) (xy 169.09801 -47.603762) (xy 169.078087 -47.551671) (xy 169.065961 -47.497234)
			(xy 169.06189 -47.441612) (xy 167.787891 -47.441612) (xy 167.781659 -47.484974) (xy 167.766305 -47.537275)
			(xy 167.743663 -47.586858) (xy 167.714194 -47.632714) (xy 167.678499 -47.673908) (xy 167.637303 -47.709603)
			(xy 167.591446 -47.73907) (xy 167.541862 -47.76171) (xy 167.489561 -47.777062) (xy 167.435606 -47.784814)
			(xy 167.408352 -47.785274) (xy 167.381098 -47.784867) (xy 167.327146 -47.777103) (xy 167.274847 -47.76174)
			(xy 167.225268 -47.739091) (xy 167.179416 -47.709616) (xy 167.138225 -47.673917) (xy 167.102535 -47.632718)
			(xy 167.07307 -47.58686) (xy 167.050431 -47.537276) (xy 167.03508 -47.484974) (xy 167.027327 -47.43102)
			(xy 167.026844 -47.403766) (xy 167.027312 -47.377338) (xy 167.034622 -47.32499) (xy 167.049096 -47.274155)
			(xy 167.070458 -47.225809) (xy 167.083994 -47.203106) (xy 167.083994 -47.202852) (xy 167.089468 -47.19289)
			(xy 167.091984 -47.170334) (xy 167.08882 -47.159418) (xy 167.05834 -47.07382) (xy 167.042084 -47.057564)
			(xy 167.031162 -47.053754) (xy 167.006656 -47.044678) (xy 166.960203 -47.020737) (xy 166.917451 -46.990682)
			(xy 166.879199 -46.955076) (xy 166.846162 -46.914584) (xy 166.818958 -46.869963) (xy 166.798096 -46.822048)
			(xy 166.783965 -46.771736) (xy 166.776831 -46.719966) (xy 166.7764 -46.693836) (xy 165.725239 -46.693836)
			(xy 165.751795 -46.710043) (xy 165.794663 -46.745718) (xy 165.83188 -46.787255) (xy 165.862653 -46.833768)
			(xy 165.886325 -46.884265) (xy 165.902393 -46.937672) (xy 165.910513 -46.992848) (xy 165.911022 -47.020734)
			(xy 165.910513 -47.04862) (xy 165.902393 -47.103796) (xy 165.886325 -47.157203) (xy 165.862653 -47.2077)
			(xy 165.83188 -47.254213) (xy 165.794663 -47.29575) (xy 165.751795 -47.331425) (xy 165.704189 -47.360479)
			(xy 165.65286 -47.382291) (xy 165.598903 -47.396397) (xy 165.543466 -47.402497) (xy 165.487732 -47.40046)
			(xy 165.432889 -47.39033) (xy 165.380105 -47.372323) (xy 165.330505 -47.346822) (xy 165.285147 -47.314371)
			(xy 165.244998 -47.275662) (xy 165.210912 -47.231519) (xy 165.183616 -47.182884) (xy 165.163693 -47.130793)
			(xy 165.151567 -47.076356) (xy 165.147496 -47.020734) (xy 164.732766 -47.020734) (xy 164.73297 -47.03191)
			(xy 164.732461 -47.059796) (xy 164.724341 -47.114972) (xy 164.708273 -47.168379) (xy 164.684601 -47.218876)
			(xy 164.653828 -47.265389) (xy 164.616611 -47.306926) (xy 164.573743 -47.342601) (xy 164.526137 -47.371655)
			(xy 164.474808 -47.393467) (xy 164.420851 -47.407573) (xy 164.365414 -47.413673) (xy 164.30968 -47.411636)
			(xy 164.254837 -47.401506) (xy 164.202053 -47.383499) (xy 164.152453 -47.357998) (xy 164.107095 -47.325547)
			(xy 164.066946 -47.286838) (xy 164.03286 -47.242695) (xy 164.005564 -47.19406) (xy 163.985641 -47.141969)
			(xy 163.973515 -47.087532) (xy 163.969444 -47.03191) (xy 163.175107 -47.03191) (xy 163.152473 -47.080192)
			(xy 163.1217 -47.126705) (xy 163.084483 -47.168242) (xy 163.041615 -47.203917) (xy 162.994009 -47.232971)
			(xy 162.94268 -47.254783) (xy 162.888723 -47.268889) (xy 162.833286 -47.274989) (xy 162.777552 -47.272952)
			(xy 162.722709 -47.262822) (xy 162.669925 -47.244815) (xy 162.620325 -47.219314) (xy 162.574967 -47.186863)
			(xy 162.534818 -47.148154) (xy 162.500732 -47.104011) (xy 162.473436 -47.055376) (xy 162.453513 -47.003285)
			(xy 162.441387 -46.948848) (xy 162.437316 -46.893226) (xy 161.600096 -46.893226) (xy 161.586903 -46.92211)
			(xy 161.557436 -46.967958) (xy 161.521745 -47.009146) (xy 161.480556 -47.044837) (xy 161.434708 -47.074304)
			(xy 161.385134 -47.096947) (xy 161.332842 -47.112306) (xy 161.278896 -47.120067) (xy 161.251646 -47.120556)
			(xy 161.225612 -47.120132) (xy 161.174028 -47.113038) (xy 161.123886 -47.099003) (xy 161.076116 -47.078287)
			(xy 161.031602 -47.051274) (xy 161.011108 -47.035212) (xy 161.003488 -47.029116) (xy 160.984946 -47.023274)
			(xy 160.90519 -47.029624) (xy 160.895551 -47.030786) (xy 160.87818 -47.039428) (xy 160.871408 -47.046388)
			(xy 160.853246 -47.066052) (xy 160.812334 -47.100573) (xy 160.767001 -47.129039) (xy 160.718136 -47.150894)
			(xy 160.666697 -47.165707) (xy 160.613693 -47.173189) (xy 160.586928 -47.173642) (xy 160.559679 -47.173096)
			(xy 160.505735 -47.165344) (xy 160.453444 -47.149994) (xy 160.403869 -47.127359) (xy 160.35802 -47.097899)
			(xy 160.31683 -47.062213) (xy 160.281139 -47.02103) (xy 160.251671 -46.975185) (xy 160.229028 -46.925614)
			(xy 160.213669 -46.873325) (xy 160.205909 -46.819383) (xy 160.20542 -46.792134) (xy 160.205939 -46.76336)
			(xy 160.214591 -46.706465) (xy 160.231688 -46.651514) (xy 160.256843 -46.599754) (xy 160.289485 -46.552359)
			(xy 160.308798 -46.531022) (xy 160.315701 -46.522974) (xy 160.322784 -46.503014) (xy 160.322514 -46.492414)
			(xy 160.316926 -46.417992) (xy 160.315642 -46.407523) (xy 160.305792 -46.388895) (xy 160.297876 -46.381924)
			(xy 160.297622 -46.38167) (xy 160.275438 -46.363445) (xy 160.236228 -46.32151) (xy 160.203742 -46.274174)
			(xy 160.178713 -46.222506) (xy 160.161707 -46.167672) (xy 160.153106 -46.110909) (xy 160.152588 -46.082204)
			(xy 143.74421 -46.082204) (xy 143.717624 -46.122389) (xy 143.680407 -46.163926) (xy 143.637539 -46.199601)
			(xy 143.589933 -46.228655) (xy 143.538604 -46.250467) (xy 143.484647 -46.264573) (xy 143.42921 -46.270673)
			(xy 143.373476 -46.268636) (xy 143.318633 -46.258506) (xy 143.265849 -46.240499) (xy 143.216249 -46.214998)
			(xy 143.170891 -46.182547) (xy 143.130742 -46.143838) (xy 143.096656 -46.099695) (xy 143.06936 -46.05106)
			(xy 143.049437 -45.998969) (xy 143.037311 -45.944532) (xy 143.03324 -45.88891) (xy 139.92094 -45.88891)
			(xy 139.913875 -45.93692) (xy 139.897807 -45.990327) (xy 139.874135 -46.040824) (xy 139.843362 -46.087337)
			(xy 139.806145 -46.128874) (xy 139.763277 -46.164549) (xy 139.715671 -46.193603) (xy 139.664342 -46.215415)
			(xy 139.610385 -46.229521) (xy 139.554948 -46.235621) (xy 139.499214 -46.233584) (xy 139.444371 -46.223454)
			(xy 139.391587 -46.205447) (xy 139.341987 -46.179946) (xy 139.296629 -46.147495) (xy 139.25648 -46.108786)
			(xy 139.222394 -46.064643) (xy 139.195098 -46.016008) (xy 139.175175 -45.963917) (xy 139.163049 -45.90948)
			(xy 139.158978 -45.853858) (xy 138.732813 -45.853858) (xy 138.733022 -45.865288) (xy 138.732513 -45.893174)
			(xy 138.724393 -45.94835) (xy 138.708325 -46.001757) (xy 138.684653 -46.052254) (xy 138.65388 -46.098767)
			(xy 138.616663 -46.140304) (xy 138.573795 -46.175979) (xy 138.526189 -46.205033) (xy 138.47486 -46.226845)
			(xy 138.420903 -46.240951) (xy 138.365466 -46.247051) (xy 138.309732 -46.245014) (xy 138.254889 -46.234884)
			(xy 138.202105 -46.216877) (xy 138.152505 -46.191376) (xy 138.107147 -46.158925) (xy 138.066998 -46.120216)
			(xy 138.032912 -46.076073) (xy 138.005616 -46.027438) (xy 137.985693 -45.975347) (xy 137.973567 -45.92091)
			(xy 137.969496 -45.865288) (xy 136.42422 -45.865288) (xy 136.432973 -45.895095) (xy 136.440731 -45.949047)
			(xy 136.440731 -46.003553) (xy 136.432973 -46.057505) (xy 136.417616 -46.109803) (xy 136.394973 -46.159383)
			(xy 136.365503 -46.205236) (xy 136.329808 -46.246428) (xy 136.288613 -46.28212) (xy 136.242758 -46.311586)
			(xy 136.193176 -46.334226) (xy 136.140877 -46.349579) (xy 136.086925 -46.357333) (xy 136.059672 -46.357794)
			(xy 136.032679 -46.357337) (xy 135.979231 -46.349728) (xy 135.927388 -46.334667) (xy 135.878183 -46.312452)
			(xy 135.832599 -46.283528) (xy 135.811768 -46.266354) (xy 135.803386 -46.259242) (xy 135.783066 -46.253146)
			(xy 135.697976 -46.264068) (xy 135.692618 -46.264816) (xy 135.682367 -46.268266) (xy 135.677656 -46.270926)
			(xy 135.668766 -46.276514) (xy 135.662416 -46.285404) (xy 135.662162 -46.285658) (xy 135.644575 -46.309862)
			(xy 135.603103 -46.352981) (xy 135.579612 -46.37151) (xy 135.571484 -46.377606) (xy 135.561324 -46.394624)
			(xy 135.54964 -46.475396) (xy 135.548665 -46.485161) (xy 135.553221 -46.504228) (xy 135.55853 -46.51248)
			(xy 135.558784 -46.512734) (xy 135.559038 -46.512988) (xy 135.57649 -46.537716) (xy 135.604196 -46.591522)
			(xy 135.623065 -46.649026) (xy 135.632623 -46.708788) (xy 135.633206 -46.739048) (xy 135.632767 -46.766301)
			(xy 135.625004 -46.82025) (xy 135.609642 -46.872546) (xy 135.600196 -46.893226) (xy 136.437368 -46.893226)
			(xy 136.441439 -46.837604) (xy 136.453565 -46.783167) (xy 136.473488 -46.731076) (xy 136.500784 -46.682441)
			(xy 136.53487 -46.638298) (xy 136.575019 -46.599589) (xy 136.620377 -46.567138) (xy 136.669977 -46.541637)
			(xy 136.722761 -46.52363) (xy 136.777604 -46.5135) (xy 136.833338 -46.511463) (xy 136.888775 -46.517563)
			(xy 136.942732 -46.531669) (xy 136.994061 -46.553481) (xy 137.041667 -46.582535) (xy 137.084535 -46.61821)
			(xy 137.121752 -46.659747) (xy 137.152525 -46.70626) (xy 137.176197 -46.756757) (xy 137.192265 -46.810164)
			(xy 137.200385 -46.86534) (xy 137.200894 -46.893226) (xy 137.200385 -46.921112) (xy 137.192265 -46.976288)
			(xy 137.176197 -47.029695) (xy 137.175159 -47.03191) (xy 137.969496 -47.03191) (xy 137.973567 -46.976288)
			(xy 137.985693 -46.921851) (xy 138.005616 -46.86976) (xy 138.032912 -46.821125) (xy 138.066998 -46.776982)
			(xy 138.107147 -46.738273) (xy 138.152505 -46.705822) (xy 138.202105 -46.680321) (xy 138.254889 -46.662314)
			(xy 138.309732 -46.652184) (xy 138.365466 -46.650147) (xy 138.420903 -46.656247) (xy 138.47486 -46.670353)
			(xy 138.526189 -46.692165) (xy 138.573795 -46.721219) (xy 138.616663 -46.756894) (xy 138.65388 -46.798431)
			(xy 138.684653 -46.844944) (xy 138.708325 -46.895441) (xy 138.724393 -46.948848) (xy 138.732513 -47.004024)
			(xy 138.732818 -47.020734) (xy 139.147548 -47.020734) (xy 139.151619 -46.965112) (xy 139.163745 -46.910675)
			(xy 139.183668 -46.858584) (xy 139.210964 -46.809949) (xy 139.24505 -46.765806) (xy 139.285199 -46.727097)
			(xy 139.330557 -46.694646) (xy 139.380157 -46.669145) (xy 139.432941 -46.651138) (xy 139.487784 -46.641008)
			(xy 139.543518 -46.638971) (xy 139.598955 -46.645071) (xy 139.652912 -46.659177) (xy 139.704241 -46.680989)
			(xy 139.725291 -46.693836) (xy 140.776452 -46.693836) (xy 140.777012 -46.666587) (xy 140.784762 -46.612645)
			(xy 140.800111 -46.560354) (xy 140.822745 -46.510779) (xy 140.852203 -46.464931) (xy 140.887887 -46.423741)
			(xy 140.92907 -46.388049) (xy 140.974913 -46.358581) (xy 141.024482 -46.335937) (xy 141.07677 -46.320578)
			(xy 141.130712 -46.312817) (xy 141.15796 -46.312328) (xy 141.185213 -46.312793) (xy 141.239166 -46.320545)
			(xy 141.291466 -46.335898) (xy 141.341049 -46.358538) (xy 141.386904 -46.388006) (xy 141.428098 -46.423699)
			(xy 141.463792 -46.464893) (xy 141.49326 -46.510748) (xy 141.515901 -46.56033) (xy 141.531254 -46.61263)
			(xy 141.539007 -46.666583) (xy 141.539468 -46.693836) (xy 141.539 -46.720264) (xy 141.53169 -46.772611)
			(xy 141.517215 -46.823446) (xy 141.495853 -46.871793) (xy 141.482318 -46.894496) (xy 141.482318 -46.89475)
			(xy 141.476843 -46.904711) (xy 141.474327 -46.927268) (xy 141.477492 -46.938184) (xy 141.507972 -47.023782)
			(xy 141.524228 -47.040038) (xy 141.53515 -47.043848) (xy 141.55966 -47.052915) (xy 141.606112 -47.076858)
			(xy 141.648864 -47.106915) (xy 141.687116 -47.142522) (xy 141.720152 -47.183015) (xy 141.747356 -47.227637)
			(xy 141.768217 -47.275552) (xy 141.782347 -47.325865) (xy 141.789481 -47.377636) (xy 141.789912 -47.403766)
			(xy 141.789413 -47.431018) (xy 141.787891 -47.441612) (xy 143.061942 -47.441612) (xy 143.066013 -47.38599)
			(xy 143.078139 -47.331553) (xy 143.098062 -47.279462) (xy 143.125358 -47.230827) (xy 143.159444 -47.186684)
			(xy 143.199593 -47.147975) (xy 143.244951 -47.115524) (xy 143.294551 -47.090023) (xy 143.347335 -47.072016)
			(xy 143.402178 -47.061886) (xy 143.457912 -47.059849) (xy 143.513349 -47.065949) (xy 143.567306 -47.080055)
			(xy 143.618635 -47.101867) (xy 143.666241 -47.130921) (xy 143.709109 -47.166596) (xy 143.746326 -47.208133)
			(xy 143.777099 -47.254646) (xy 143.800771 -47.305143) (xy 143.816839 -47.35855) (xy 143.824959 -47.413726)
			(xy 143.825468 -47.441612) (xy 143.824959 -47.469498) (xy 143.816839 -47.524674) (xy 143.800771 -47.578081)
			(xy 143.777099 -47.628578) (xy 143.746326 -47.675091) (xy 143.709109 -47.716628) (xy 143.666241 -47.752303)
			(xy 143.618635 -47.781357) (xy 143.567306 -47.803169) (xy 143.513349 -47.817275) (xy 143.457912 -47.823375)
			(xy 143.402178 -47.821338) (xy 143.347335 -47.811208) (xy 143.294551 -47.793201) (xy 143.244951 -47.7677)
			(xy 143.199593 -47.735249) (xy 143.159444 -47.69654) (xy 143.125358 -47.652397) (xy 143.098062 -47.603762)
			(xy 143.078139 -47.551671) (xy 143.066013 -47.497234) (xy 143.061942 -47.441612) (xy 141.787891 -47.441612)
			(xy 141.781661 -47.484967) (xy 141.766309 -47.537264) (xy 141.743671 -47.586844) (xy 141.714207 -47.632697)
			(xy 141.678517 -47.67389) (xy 141.637328 -47.709584) (xy 141.591477 -47.739053) (xy 141.5419 -47.761696)
			(xy 141.489604 -47.777053) (xy 141.435656 -47.78481) (xy 141.408404 -47.785274) (xy 141.38115 -47.784841)
			(xy 141.327196 -47.777084) (xy 141.274895 -47.761726) (xy 141.225313 -47.739082) (xy 141.179458 -47.709611)
			(xy 141.138265 -47.673914) (xy 141.102571 -47.632718) (xy 141.073104 -47.586861) (xy 141.050463 -47.537276)
			(xy 141.03511 -47.484975) (xy 141.027357 -47.43102) (xy 141.026896 -47.403766) (xy 141.02737 -47.377338)
			(xy 141.034679 -47.324991) (xy 141.049152 -47.274156) (xy 141.070511 -47.225809) (xy 141.084046 -47.203106)
			(xy 141.084046 -47.202852) (xy 141.08962 -47.192925) (xy 141.092143 -47.170322) (xy 141.088872 -47.159418)
			(xy 141.058392 -47.07382) (xy 141.042136 -47.057564) (xy 141.031214 -47.053754) (xy 141.006697 -47.044705)
			(xy 140.960246 -47.020758) (xy 140.917495 -46.990699) (xy 140.879245 -46.955088) (xy 140.846209 -46.914593)
			(xy 140.819007 -46.86997) (xy 140.798146 -46.822053) (xy 140.784017 -46.771738) (xy 140.776883 -46.719966)
			(xy 140.776452 -46.693836) (xy 139.725291 -46.693836) (xy 139.751847 -46.710043) (xy 139.794715 -46.745718)
			(xy 139.831932 -46.787255) (xy 139.862705 -46.833768) (xy 139.886377 -46.884265) (xy 139.902445 -46.937672)
			(xy 139.910565 -46.992848) (xy 139.911074 -47.020734) (xy 139.910565 -47.04862) (xy 139.902445 -47.103796)
			(xy 139.886377 -47.157203) (xy 139.862705 -47.2077) (xy 139.831932 -47.254213) (xy 139.794715 -47.29575)
			(xy 139.751847 -47.331425) (xy 139.704241 -47.360479) (xy 139.652912 -47.382291) (xy 139.598955 -47.396397)
			(xy 139.543518 -47.402497) (xy 139.487784 -47.40046) (xy 139.432941 -47.39033) (xy 139.380157 -47.372323)
			(xy 139.330557 -47.346822) (xy 139.285199 -47.314371) (xy 139.24505 -47.275662) (xy 139.210964 -47.231519)
			(xy 139.183668 -47.182884) (xy 139.163745 -47.130793) (xy 139.151619 -47.076356) (xy 139.147548 -47.020734)
			(xy 138.732818 -47.020734) (xy 138.733022 -47.03191) (xy 138.732513 -47.059796) (xy 138.724393 -47.114972)
			(xy 138.708325 -47.168379) (xy 138.684653 -47.218876) (xy 138.65388 -47.265389) (xy 138.616663 -47.306926)
			(xy 138.573795 -47.342601) (xy 138.526189 -47.371655) (xy 138.47486 -47.393467) (xy 138.420903 -47.407573)
			(xy 138.365466 -47.413673) (xy 138.309732 -47.411636) (xy 138.254889 -47.401506) (xy 138.202105 -47.383499)
			(xy 138.152505 -47.357998) (xy 138.107147 -47.325547) (xy 138.066998 -47.286838) (xy 138.032912 -47.242695)
			(xy 138.005616 -47.19406) (xy 137.985693 -47.141969) (xy 137.973567 -47.087532) (xy 137.969496 -47.03191)
			(xy 137.175159 -47.03191) (xy 137.152525 -47.080192) (xy 137.121752 -47.126705) (xy 137.084535 -47.168242)
			(xy 137.041667 -47.203917) (xy 136.994061 -47.232971) (xy 136.942732 -47.254783) (xy 136.888775 -47.268889)
			(xy 136.833338 -47.274989) (xy 136.777604 -47.272952) (xy 136.722761 -47.262822) (xy 136.669977 -47.244815)
			(xy 136.620377 -47.219314) (xy 136.575019 -47.186863) (xy 136.53487 -47.148154) (xy 136.500784 -47.104011)
			(xy 136.473488 -47.055376) (xy 136.453565 -47.003285) (xy 136.441439 -46.948848) (xy 136.437368 -46.893226)
			(xy 135.600196 -46.893226) (xy 135.586996 -46.922123) (xy 135.557524 -46.967974) (xy 135.521828 -47.009163)
			(xy 135.480633 -47.044854) (xy 135.434779 -47.07432) (xy 135.385199 -47.09696) (xy 135.332901 -47.112314)
			(xy 135.278951 -47.12007) (xy 135.251698 -47.120556) (xy 135.225665 -47.120102) (xy 135.174082 -47.113016)
			(xy 135.123941 -47.098988) (xy 135.07617 -47.078278) (xy 135.031655 -47.051271) (xy 135.01116 -47.035212)
			(xy 135.00354 -47.029116) (xy 134.984998 -47.023274) (xy 134.905242 -47.029624) (xy 134.895607 -47.030811)
			(xy 134.878235 -47.039435) (xy 134.87146 -47.046388) (xy 134.853272 -47.066027) (xy 134.812366 -47.10055)
			(xy 134.767038 -47.12902) (xy 134.718178 -47.150878) (xy 134.666744 -47.165697) (xy 134.613743 -47.173186)
			(xy 134.58698 -47.173642) (xy 134.55973 -47.173141) (xy 134.505784 -47.165383) (xy 134.453492 -47.150027)
			(xy 134.403917 -47.127386) (xy 134.358068 -47.09792) (xy 134.316879 -47.062231) (xy 134.281188 -47.021043)
			(xy 134.251721 -46.975195) (xy 134.229078 -46.925621) (xy 134.21372 -46.873329) (xy 134.20596 -46.819384)
			(xy 134.205472 -46.792134) (xy 134.206004 -46.76336) (xy 134.214654 -46.706467) (xy 134.231749 -46.651517)
			(xy 134.256901 -46.599757) (xy 134.289539 -46.55236) (xy 134.30885 -46.531022) (xy 134.315747 -46.522969)
			(xy 134.322835 -46.503013) (xy 134.322566 -46.492414) (xy 134.316978 -46.417992) (xy 134.315709 -46.40752)
			(xy 134.30585 -46.388892) (xy 134.297928 -46.381924) (xy 134.297674 -46.38167) (xy 134.27548 -46.363457)
			(xy 134.236273 -46.321518) (xy 134.203789 -46.274179) (xy 134.178763 -46.222509) (xy 134.161758 -46.167674)
			(xy 134.153158 -46.11091) (xy 134.15264 -46.082204) (xy 105.643956 -46.082204) (xy 105.61737 -46.122389)
			(xy 105.580153 -46.163926) (xy 105.537285 -46.199601) (xy 105.489679 -46.228655) (xy 105.43835 -46.250467)
			(xy 105.384393 -46.264573) (xy 105.328956 -46.270673) (xy 105.273222 -46.268636) (xy 105.218379 -46.258506)
			(xy 105.165595 -46.240499) (xy 105.115995 -46.214998) (xy 105.070637 -46.182547) (xy 105.030488 -46.143838)
			(xy 104.996402 -46.099695) (xy 104.969106 -46.05106) (xy 104.949183 -45.998969) (xy 104.937057 -45.944532)
			(xy 104.932986 -45.88891) (xy 101.820686 -45.88891) (xy 101.813621 -45.93692) (xy 101.797553 -45.990327)
			(xy 101.773881 -46.040824) (xy 101.743108 -46.087337) (xy 101.705891 -46.128874) (xy 101.663023 -46.164549)
			(xy 101.615417 -46.193603) (xy 101.564088 -46.215415) (xy 101.510131 -46.229521) (xy 101.454694 -46.235621)
			(xy 101.39896 -46.233584) (xy 101.344117 -46.223454) (xy 101.291333 -46.205447) (xy 101.241733 -46.179946)
			(xy 101.196375 -46.147495) (xy 101.156226 -46.108786) (xy 101.12214 -46.064643) (xy 101.094844 -46.016008)
			(xy 101.074921 -45.963917) (xy 101.062795 -45.90948) (xy 101.058724 -45.853858) (xy 100.632559 -45.853858)
			(xy 100.632768 -45.865288) (xy 100.632259 -45.893174) (xy 100.624139 -45.94835) (xy 100.608071 -46.001757)
			(xy 100.584399 -46.052254) (xy 100.553626 -46.098767) (xy 100.516409 -46.140304) (xy 100.473541 -46.175979)
			(xy 100.425935 -46.205033) (xy 100.374606 -46.226845) (xy 100.320649 -46.240951) (xy 100.265212 -46.247051)
			(xy 100.209478 -46.245014) (xy 100.154635 -46.234884) (xy 100.101851 -46.216877) (xy 100.052251 -46.191376)
			(xy 100.006893 -46.158925) (xy 99.966744 -46.120216) (xy 99.932658 -46.076073) (xy 99.905362 -46.027438)
			(xy 99.885439 -45.975347) (xy 99.873313 -45.92091) (xy 99.869242 -45.865288) (xy 98.323897 -45.865288)
			(xy 98.332652 -45.895106) (xy 98.340408 -45.949051) (xy 98.340408 -46.003549) (xy 98.332652 -46.057493)
			(xy 98.317298 -46.109785) (xy 98.294659 -46.159359) (xy 98.265196 -46.205207) (xy 98.229508 -46.246395)
			(xy 98.188321 -46.282085) (xy 98.142475 -46.311551) (xy 98.092902 -46.334192) (xy 98.040611 -46.349548)
			(xy 97.986667 -46.357307) (xy 97.959418 -46.357794) (xy 97.932426 -46.357311) (xy 97.878979 -46.349708)
			(xy 97.827136 -46.334653) (xy 97.777931 -46.312444) (xy 97.732346 -46.283525) (xy 97.711514 -46.266354)
			(xy 97.703132 -46.259242) (xy 97.682812 -46.253146) (xy 97.597722 -46.264068) (xy 97.592361 -46.2648)
			(xy 97.582111 -46.268261) (xy 97.577402 -46.270926) (xy 97.568512 -46.276514) (xy 97.562162 -46.285404)
			(xy 97.561908 -46.285658) (xy 97.544315 -46.309857) (xy 97.502847 -46.35298) (xy 97.479358 -46.37151)
			(xy 97.47123 -46.377606) (xy 97.46107 -46.394624) (xy 97.449386 -46.475396) (xy 97.448403 -46.485161)
			(xy 97.452964 -46.504229) (xy 97.458276 -46.51248) (xy 97.45853 -46.512734) (xy 97.458784 -46.512988)
			(xy 97.476229 -46.537721) (xy 97.503939 -46.591525) (xy 97.52281 -46.649027) (xy 97.532369 -46.708788)
			(xy 97.532952 -46.739048) (xy 97.532467 -46.766298) (xy 97.524705 -46.820244) (xy 97.509346 -46.872536)
			(xy 97.499896 -46.893226) (xy 98.337114 -46.893226) (xy 98.341185 -46.837604) (xy 98.353311 -46.783167)
			(xy 98.373234 -46.731076) (xy 98.40053 -46.682441) (xy 98.434616 -46.638298) (xy 98.474765 -46.599589)
			(xy 98.520123 -46.567138) (xy 98.569723 -46.541637) (xy 98.622507 -46.52363) (xy 98.67735 -46.5135)
			(xy 98.733084 -46.511463) (xy 98.788521 -46.517563) (xy 98.842478 -46.531669) (xy 98.893807 -46.553481)
			(xy 98.941413 -46.582535) (xy 98.984281 -46.61821) (xy 99.021498 -46.659747) (xy 99.052271 -46.70626)
			(xy 99.075943 -46.756757) (xy 99.092011 -46.810164) (xy 99.100131 -46.86534) (xy 99.10064 -46.893226)
			(xy 99.100131 -46.921112) (xy 99.092011 -46.976288) (xy 99.075943 -47.029695) (xy 99.074905 -47.03191)
			(xy 99.869242 -47.03191) (xy 99.873313 -46.976288) (xy 99.885439 -46.921851) (xy 99.905362 -46.86976)
			(xy 99.932658 -46.821125) (xy 99.966744 -46.776982) (xy 100.006893 -46.738273) (xy 100.052251 -46.705822)
			(xy 100.101851 -46.680321) (xy 100.154635 -46.662314) (xy 100.209478 -46.652184) (xy 100.265212 -46.650147)
			(xy 100.320649 -46.656247) (xy 100.374606 -46.670353) (xy 100.425935 -46.692165) (xy 100.473541 -46.721219)
			(xy 100.516409 -46.756894) (xy 100.553626 -46.798431) (xy 100.584399 -46.844944) (xy 100.608071 -46.895441)
			(xy 100.624139 -46.948848) (xy 100.632259 -47.004024) (xy 100.632564 -47.020734) (xy 101.047294 -47.020734)
			(xy 101.051365 -46.965112) (xy 101.063491 -46.910675) (xy 101.083414 -46.858584) (xy 101.11071 -46.809949)
			(xy 101.144796 -46.765806) (xy 101.184945 -46.727097) (xy 101.230303 -46.694646) (xy 101.279903 -46.669145)
			(xy 101.332687 -46.651138) (xy 101.38753 -46.641008) (xy 101.443264 -46.638971) (xy 101.498701 -46.645071)
			(xy 101.552658 -46.659177) (xy 101.603987 -46.680989) (xy 101.625037 -46.693836) (xy 102.676198 -46.693836)
			(xy 102.676689 -46.666584) (xy 102.684441 -46.612634) (xy 102.699793 -46.560336) (xy 102.722432 -46.510755)
			(xy 102.751896 -46.464902) (xy 102.787587 -46.423709) (xy 102.828778 -46.388014) (xy 102.874629 -46.358546)
			(xy 102.924208 -46.335903) (xy 102.976504 -46.320547) (xy 103.030454 -46.312791) (xy 103.057706 -46.312328)
			(xy 103.084961 -46.31275) (xy 103.138915 -46.320509) (xy 103.191216 -46.335867) (xy 103.240798 -46.358513)
			(xy 103.286653 -46.387985) (xy 103.327847 -46.423683) (xy 103.36354 -46.464881) (xy 103.393007 -46.510739)
			(xy 103.415647 -46.560324) (xy 103.431 -46.612626) (xy 103.438753 -46.666581) (xy 103.439214 -46.693836)
			(xy 103.438739 -46.720263) (xy 103.43143 -46.772611) (xy 103.416957 -46.823446) (xy 103.395598 -46.871793)
			(xy 103.382064 -46.894496) (xy 103.382064 -46.89475) (xy 103.376489 -46.904677) (xy 103.373966 -46.92728)
			(xy 103.377238 -46.938184) (xy 103.407718 -47.023782) (xy 103.423974 -47.040038) (xy 103.434896 -47.043848)
			(xy 103.459415 -47.052889) (xy 103.505867 -47.076838) (xy 103.548617 -47.106899) (xy 103.586867 -47.14251)
			(xy 103.619902 -47.183006) (xy 103.647104 -47.22763) (xy 103.667965 -47.275548) (xy 103.682094 -47.325863)
			(xy 103.689227 -47.377635) (xy 103.689658 -47.403766) (xy 103.689213 -47.43102) (xy 103.687691 -47.441612)
			(xy 104.961688 -47.441612) (xy 104.965759 -47.38599) (xy 104.977885 -47.331553) (xy 104.997808 -47.279462)
			(xy 105.025104 -47.230827) (xy 105.05919 -47.186684) (xy 105.099339 -47.147975) (xy 105.144697 -47.115524)
			(xy 105.194297 -47.090023) (xy 105.247081 -47.072016) (xy 105.301924 -47.061886) (xy 105.357658 -47.059849)
			(xy 105.413095 -47.065949) (xy 105.467052 -47.080055) (xy 105.518381 -47.101867) (xy 105.565987 -47.130921)
			(xy 105.608855 -47.166596) (xy 105.646072 -47.208133) (xy 105.676845 -47.254646) (xy 105.700517 -47.305143)
			(xy 105.716585 -47.35855) (xy 105.724705 -47.413726) (xy 105.725214 -47.441612) (xy 105.724705 -47.469498)
			(xy 105.716585 -47.524674) (xy 105.700517 -47.578081) (xy 105.676845 -47.628578) (xy 105.646072 -47.675091)
			(xy 105.608855 -47.716628) (xy 105.565987 -47.752303) (xy 105.518381 -47.781357) (xy 105.467052 -47.803169)
			(xy 105.413095 -47.817275) (xy 105.357658 -47.823375) (xy 105.301924 -47.821338) (xy 105.247081 -47.811208)
			(xy 105.194297 -47.793201) (xy 105.144697 -47.7677) (xy 105.099339 -47.735249) (xy 105.05919 -47.69654)
			(xy 105.025104 -47.652397) (xy 104.997808 -47.603762) (xy 104.977885 -47.551671) (xy 104.965759 -47.497234)
			(xy 104.961688 -47.441612) (xy 103.687691 -47.441612) (xy 103.681459 -47.484974) (xy 103.666105 -47.537276)
			(xy 103.643463 -47.586859) (xy 103.613994 -47.632715) (xy 103.578298 -47.673909) (xy 103.537102 -47.709603)
			(xy 103.491245 -47.739071) (xy 103.441661 -47.761711) (xy 103.389359 -47.777063) (xy 103.335404 -47.784814)
			(xy 103.30815 -47.785274) (xy 103.280897 -47.784798) (xy 103.226945 -47.777047) (xy 103.174645 -47.761696)
			(xy 103.125063 -47.739056) (xy 103.079208 -47.709591) (xy 103.038013 -47.673898) (xy 103.002319 -47.632705)
			(xy 102.972851 -47.586851) (xy 102.95021 -47.53727) (xy 102.934856 -47.484971) (xy 102.927103 -47.431019)
			(xy 102.926642 -47.403766) (xy 102.92711 -47.377338) (xy 102.93442 -47.32499) (xy 102.948895 -47.274155)
			(xy 102.970256 -47.225809) (xy 102.983792 -47.203106) (xy 102.983792 -47.202852) (xy 102.989266 -47.19289)
			(xy 102.991782 -47.170334) (xy 102.988618 -47.159418) (xy 102.958138 -47.07382) (xy 102.941882 -47.057564)
			(xy 102.93096 -47.053754) (xy 102.906453 -47.044679) (xy 102.860001 -47.020738) (xy 102.817249 -46.990683)
			(xy 102.778996 -46.955076) (xy 102.74596 -46.914584) (xy 102.718756 -46.869963) (xy 102.697894 -46.822049)
			(xy 102.683763 -46.771736) (xy 102.676629 -46.719966) (xy 102.676198 -46.693836) (xy 101.625037 -46.693836)
			(xy 101.651593 -46.710043) (xy 101.694461 -46.745718) (xy 101.731678 -46.787255) (xy 101.762451 -46.833768)
			(xy 101.786123 -46.884265) (xy 101.802191 -46.937672) (xy 101.810311 -46.992848) (xy 101.81082 -47.020734)
			(xy 101.810311 -47.04862) (xy 101.802191 -47.103796) (xy 101.786123 -47.157203) (xy 101.762451 -47.2077)
			(xy 101.731678 -47.254213) (xy 101.694461 -47.29575) (xy 101.651593 -47.331425) (xy 101.603987 -47.360479)
			(xy 101.552658 -47.382291) (xy 101.498701 -47.396397) (xy 101.443264 -47.402497) (xy 101.38753 -47.40046)
			(xy 101.332687 -47.39033) (xy 101.279903 -47.372323) (xy 101.230303 -47.346822) (xy 101.184945 -47.314371)
			(xy 101.144796 -47.275662) (xy 101.11071 -47.231519) (xy 101.083414 -47.182884) (xy 101.063491 -47.130793)
			(xy 101.051365 -47.076356) (xy 101.047294 -47.020734) (xy 100.632564 -47.020734) (xy 100.632768 -47.03191)
			(xy 100.632259 -47.059796) (xy 100.624139 -47.114972) (xy 100.608071 -47.168379) (xy 100.584399 -47.218876)
			(xy 100.553626 -47.265389) (xy 100.516409 -47.306926) (xy 100.473541 -47.342601) (xy 100.425935 -47.371655)
			(xy 100.374606 -47.393467) (xy 100.320649 -47.407573) (xy 100.265212 -47.413673) (xy 100.209478 -47.411636)
			(xy 100.154635 -47.401506) (xy 100.101851 -47.383499) (xy 100.052251 -47.357998) (xy 100.006893 -47.325547)
			(xy 99.966744 -47.286838) (xy 99.932658 -47.242695) (xy 99.905362 -47.19406) (xy 99.885439 -47.141969)
			(xy 99.873313 -47.087532) (xy 99.869242 -47.03191) (xy 99.074905 -47.03191) (xy 99.052271 -47.080192)
			(xy 99.021498 -47.126705) (xy 98.984281 -47.168242) (xy 98.941413 -47.203917) (xy 98.893807 -47.232971)
			(xy 98.842478 -47.254783) (xy 98.788521 -47.268889) (xy 98.733084 -47.274989) (xy 98.67735 -47.272952)
			(xy 98.622507 -47.262822) (xy 98.569723 -47.244815) (xy 98.520123 -47.219314) (xy 98.474765 -47.186863)
			(xy 98.434616 -47.148154) (xy 98.40053 -47.104011) (xy 98.373234 -47.055376) (xy 98.353311 -47.003285)
			(xy 98.341185 -46.948848) (xy 98.337114 -46.893226) (xy 97.499896 -46.893226) (xy 97.486703 -46.92211)
			(xy 97.457235 -46.967958) (xy 97.421544 -47.009147) (xy 97.380355 -47.044838) (xy 97.334507 -47.074304)
			(xy 97.284932 -47.096947) (xy 97.23264 -47.112306) (xy 97.178694 -47.120067) (xy 97.151444 -47.120556)
			(xy 97.12541 -47.120133) (xy 97.073826 -47.113039) (xy 97.023684 -47.099004) (xy 96.975913 -47.078288)
			(xy 96.9314 -47.051275) (xy 96.910906 -47.035212) (xy 96.903286 -47.029116) (xy 96.884744 -47.023274)
			(xy 96.804988 -47.029624) (xy 96.795349 -47.030785) (xy 96.777978 -47.039428) (xy 96.771206 -47.046388)
			(xy 96.753045 -47.066053) (xy 96.712133 -47.100573) (xy 96.6668 -47.12904) (xy 96.617935 -47.150894)
			(xy 96.566495 -47.165708) (xy 96.513491 -47.173189) (xy 96.486726 -47.173642) (xy 96.459477 -47.173098)
			(xy 96.405533 -47.165346) (xy 96.353242 -47.149995) (xy 96.303667 -47.12736) (xy 96.257818 -47.0979)
			(xy 96.216628 -47.062214) (xy 96.180936 -47.02103) (xy 96.151469 -46.975186) (xy 96.128826 -46.925615)
			(xy 96.113467 -46.873326) (xy 96.105707 -46.819383) (xy 96.105218 -46.792134) (xy 96.105738 -46.76336)
			(xy 96.114389 -46.706465) (xy 96.131486 -46.651514) (xy 96.156641 -46.599754) (xy 96.189283 -46.552359)
			(xy 96.208596 -46.531022) (xy 96.215498 -46.522974) (xy 96.222582 -46.503014) (xy 96.222312 -46.492414)
			(xy 96.216724 -46.417992) (xy 96.21544 -46.407523) (xy 96.205591 -46.388895) (xy 96.197674 -46.381924)
			(xy 96.19742 -46.38167) (xy 96.175235 -46.363445) (xy 96.136025 -46.32151) (xy 96.10354 -46.274174)
			(xy 96.078511 -46.222506) (xy 96.061505 -46.167672) (xy 96.052904 -46.110909) (xy 96.052386 -46.082204)
			(xy 79.644008 -46.082204) (xy 79.617422 -46.122389) (xy 79.580205 -46.163926) (xy 79.537337 -46.199601)
			(xy 79.489731 -46.228655) (xy 79.438402 -46.250467) (xy 79.384445 -46.264573) (xy 79.329008 -46.270673)
			(xy 79.273274 -46.268636) (xy 79.218431 -46.258506) (xy 79.165647 -46.240499) (xy 79.116047 -46.214998)
			(xy 79.070689 -46.182547) (xy 79.03054 -46.143838) (xy 78.996454 -46.099695) (xy 78.969158 -46.05106)
			(xy 78.949235 -45.998969) (xy 78.937109 -45.944532) (xy 78.933038 -45.88891) (xy 75.820738 -45.88891)
			(xy 75.813673 -45.93692) (xy 75.797605 -45.990327) (xy 75.773933 -46.040824) (xy 75.74316 -46.087337)
			(xy 75.705943 -46.128874) (xy 75.663075 -46.164549) (xy 75.615469 -46.193603) (xy 75.56414 -46.215415)
			(xy 75.510183 -46.229521) (xy 75.454746 -46.235621) (xy 75.399012 -46.233584) (xy 75.344169 -46.223454)
			(xy 75.291385 -46.205447) (xy 75.241785 -46.179946) (xy 75.196427 -46.147495) (xy 75.156278 -46.108786)
			(xy 75.122192 -46.064643) (xy 75.094896 -46.016008) (xy 75.074973 -45.963917) (xy 75.062847 -45.90948)
			(xy 75.058776 -45.853858) (xy 74.632611 -45.853858) (xy 74.63282 -45.865288) (xy 74.632311 -45.893174)
			(xy 74.624191 -45.94835) (xy 74.608123 -46.001757) (xy 74.584451 -46.052254) (xy 74.553678 -46.098767)
			(xy 74.516461 -46.140304) (xy 74.473593 -46.175979) (xy 74.425987 -46.205033) (xy 74.374658 -46.226845)
			(xy 74.320701 -46.240951) (xy 74.265264 -46.247051) (xy 74.20953 -46.245014) (xy 74.154687 -46.234884)
			(xy 74.101903 -46.216877) (xy 74.052303 -46.191376) (xy 74.006945 -46.158925) (xy 73.966796 -46.120216)
			(xy 73.93271 -46.076073) (xy 73.905414 -46.027438) (xy 73.885491 -45.975347) (xy 73.873365 -45.92091)
			(xy 73.869294 -45.865288) (xy 72.32402 -45.865288) (xy 72.332773 -45.895095) (xy 72.340531 -45.949047)
			(xy 72.340531 -46.003553) (xy 72.332773 -46.057505) (xy 72.317416 -46.109803) (xy 72.294772 -46.159383)
			(xy 72.265303 -46.205236) (xy 72.229607 -46.246428) (xy 72.188412 -46.282121) (xy 72.142557 -46.311587)
			(xy 72.092975 -46.334227) (xy 72.040675 -46.34958) (xy 71.986723 -46.357333) (xy 71.95947 -46.357794)
			(xy 71.932477 -46.357338) (xy 71.879029 -46.349729) (xy 71.827186 -46.334667) (xy 71.777981 -46.312452)
			(xy 71.732397 -46.283528) (xy 71.711566 -46.266354) (xy 71.703184 -46.259242) (xy 71.682864 -46.253146)
			(xy 71.597774 -46.264068) (xy 71.592415 -46.264815) (xy 71.582165 -46.268266) (xy 71.577454 -46.270926)
			(xy 71.568564 -46.276514) (xy 71.562214 -46.285404) (xy 71.56196 -46.285658) (xy 71.544373 -46.309862)
			(xy 71.502901 -46.352982) (xy 71.47941 -46.37151) (xy 71.471282 -46.377606) (xy 71.461122 -46.394624)
			(xy 71.449438 -46.475396) (xy 71.448463 -46.485161) (xy 71.453019 -46.504228) (xy 71.458328 -46.51248)
			(xy 71.458582 -46.512734) (xy 71.458836 -46.512988) (xy 71.476288 -46.537716) (xy 71.503994 -46.591522)
			(xy 71.522863 -46.649026) (xy 71.532421 -46.708788) (xy 71.533004 -46.739048) (xy 71.532567 -46.766301)
			(xy 71.524804 -46.82025) (xy 71.509442 -46.872546) (xy 71.499995 -46.893226) (xy 72.337166 -46.893226)
			(xy 72.341237 -46.837604) (xy 72.353363 -46.783167) (xy 72.373286 -46.731076) (xy 72.400582 -46.682441)
			(xy 72.434668 -46.638298) (xy 72.474817 -46.599589) (xy 72.520175 -46.567138) (xy 72.569775 -46.541637)
			(xy 72.622559 -46.52363) (xy 72.677402 -46.5135) (xy 72.733136 -46.511463) (xy 72.788573 -46.517563)
			(xy 72.84253 -46.531669) (xy 72.893859 -46.553481) (xy 72.941465 -46.582535) (xy 72.984333 -46.61821)
			(xy 73.02155 -46.659747) (xy 73.052323 -46.70626) (xy 73.075995 -46.756757) (xy 73.092063 -46.810164)
			(xy 73.100183 -46.86534) (xy 73.100692 -46.893226) (xy 73.100183 -46.921112) (xy 73.092063 -46.976288)
			(xy 73.075995 -47.029695) (xy 73.074957 -47.03191) (xy 73.869294 -47.03191) (xy 73.873365 -46.976288)
			(xy 73.885491 -46.921851) (xy 73.905414 -46.86976) (xy 73.93271 -46.821125) (xy 73.966796 -46.776982)
			(xy 74.006945 -46.738273) (xy 74.052303 -46.705822) (xy 74.101903 -46.680321) (xy 74.154687 -46.662314)
			(xy 74.20953 -46.652184) (xy 74.265264 -46.650147) (xy 74.320701 -46.656247) (xy 74.374658 -46.670353)
			(xy 74.425987 -46.692165) (xy 74.473593 -46.721219) (xy 74.516461 -46.756894) (xy 74.553678 -46.798431)
			(xy 74.584451 -46.844944) (xy 74.608123 -46.895441) (xy 74.624191 -46.948848) (xy 74.632311 -47.004024)
			(xy 74.632616 -47.020734) (xy 75.047346 -47.020734) (xy 75.051417 -46.965112) (xy 75.063543 -46.910675)
			(xy 75.083466 -46.858584) (xy 75.110762 -46.809949) (xy 75.144848 -46.765806) (xy 75.184997 -46.727097)
			(xy 75.230355 -46.694646) (xy 75.279955 -46.669145) (xy 75.332739 -46.651138) (xy 75.387582 -46.641008)
			(xy 75.443316 -46.638971) (xy 75.498753 -46.645071) (xy 75.55271 -46.659177) (xy 75.604039 -46.680989)
			(xy 75.625089 -46.693836) (xy 76.67625 -46.693836) (xy 76.676812 -46.666588) (xy 76.684562 -46.612645)
			(xy 76.699911 -46.560354) (xy 76.722544 -46.51078) (xy 76.752003 -46.464931) (xy 76.787687 -46.423742)
			(xy 76.828869 -46.38805) (xy 76.874711 -46.358582) (xy 76.924281 -46.335938) (xy 76.976568 -46.320579)
			(xy 77.03051 -46.312817) (xy 77.057758 -46.312328) (xy 77.085011 -46.312794) (xy 77.138964 -46.320547)
			(xy 77.191264 -46.335899) (xy 77.240847 -46.358539) (xy 77.286702 -46.388006) (xy 77.327896 -46.4237)
			(xy 77.36359 -46.464894) (xy 77.393058 -46.510748) (xy 77.415699 -46.56033) (xy 77.431052 -46.61263)
			(xy 77.438805 -46.666583) (xy 77.439266 -46.693836) (xy 77.438798 -46.720264) (xy 77.431488 -46.772611)
			(xy 77.417013 -46.823446) (xy 77.395652 -46.871793) (xy 77.382116 -46.894496) (xy 77.382116 -46.89475)
			(xy 77.376641 -46.904711) (xy 77.374125 -46.927268) (xy 77.37729 -46.938184) (xy 77.40777 -47.023782)
			(xy 77.424026 -47.040038) (xy 77.434948 -47.043848) (xy 77.459457 -47.052916) (xy 77.50591 -47.076859)
			(xy 77.548661 -47.106915) (xy 77.586913 -47.142523) (xy 77.61995 -47.183016) (xy 77.647153 -47.227637)
			(xy 77.668015 -47.275552) (xy 77.682145 -47.325866) (xy 77.689279 -47.377636) (xy 77.68971 -47.403766)
			(xy 77.689213 -47.431018) (xy 77.687691 -47.441612) (xy 78.96174 -47.441612) (xy 78.965811 -47.38599)
			(xy 78.977937 -47.331553) (xy 78.99786 -47.279462) (xy 79.025156 -47.230827) (xy 79.059242 -47.186684)
			(xy 79.099391 -47.147975) (xy 79.144749 -47.115524) (xy 79.194349 -47.090023) (xy 79.247133 -47.072016)
			(xy 79.301976 -47.061886) (xy 79.35771 -47.059849) (xy 79.413147 -47.065949) (xy 79.467104 -47.080055)
			(xy 79.518433 -47.101867) (xy 79.566039 -47.130921) (xy 79.608907 -47.166596) (xy 79.646124 -47.208133)
			(xy 79.676897 -47.254646) (xy 79.700569 -47.305143) (xy 79.716637 -47.35855) (xy 79.724757 -47.413726)
			(xy 79.725266 -47.441612) (xy 79.724757 -47.469498) (xy 79.716637 -47.524674) (xy 79.700569 -47.578081)
			(xy 79.676897 -47.628578) (xy 79.646124 -47.675091) (xy 79.608907 -47.716628) (xy 79.566039 -47.752303)
			(xy 79.518433 -47.781357) (xy 79.467104 -47.803169) (xy 79.413147 -47.817275) (xy 79.35771 -47.823375)
			(xy 79.301976 -47.821338) (xy 79.247133 -47.811208) (xy 79.194349 -47.793201) (xy 79.144749 -47.7677)
			(xy 79.099391 -47.735249) (xy 79.059242 -47.69654) (xy 79.025156 -47.652397) (xy 78.99786 -47.603762)
			(xy 78.977937 -47.551671) (xy 78.965811 -47.497234) (xy 78.96174 -47.441612) (xy 77.687691 -47.441612)
			(xy 77.681461 -47.484968) (xy 77.666109 -47.537265) (xy 77.643471 -47.586845) (xy 77.614006 -47.632698)
			(xy 77.578316 -47.673891) (xy 77.537127 -47.709585) (xy 77.491276 -47.739053) (xy 77.441698 -47.761697)
			(xy 77.389403 -47.777053) (xy 77.335454 -47.784811) (xy 77.308202 -47.785274) (xy 77.280948 -47.784843)
			(xy 77.226994 -47.777085) (xy 77.174693 -47.761728) (xy 77.125111 -47.739083) (xy 77.079256 -47.709612)
			(xy 77.038063 -47.673915) (xy 77.002369 -47.632718) (xy 76.972902 -47.586861) (xy 76.950261 -47.537277)
			(xy 76.934908 -47.484975) (xy 76.927155 -47.43102) (xy 76.926694 -47.403766) (xy 76.927168 -47.377339)
			(xy 76.934477 -47.324991) (xy 76.94895 -47.274156) (xy 76.970309 -47.225809) (xy 76.983844 -47.203106)
			(xy 76.983844 -47.202852) (xy 76.989418 -47.192925) (xy 76.991941 -47.170322) (xy 76.98867 -47.159418)
			(xy 76.95819 -47.07382) (xy 76.941934 -47.057564) (xy 76.931012 -47.053754) (xy 76.906495 -47.044706)
			(xy 76.860044 -47.020759) (xy 76.817293 -46.990699) (xy 76.779042 -46.955089) (xy 76.746007 -46.914593)
			(xy 76.718805 -46.86997) (xy 76.697944 -46.822053) (xy 76.683815 -46.771738) (xy 76.676681 -46.719966)
			(xy 76.67625 -46.693836) (xy 75.625089 -46.693836) (xy 75.651645 -46.710043) (xy 75.694513 -46.745718)
			(xy 75.73173 -46.787255) (xy 75.762503 -46.833768) (xy 75.786175 -46.884265) (xy 75.802243 -46.937672)
			(xy 75.810363 -46.992848) (xy 75.810872 -47.020734) (xy 75.810363 -47.04862) (xy 75.802243 -47.103796)
			(xy 75.786175 -47.157203) (xy 75.762503 -47.2077) (xy 75.73173 -47.254213) (xy 75.694513 -47.29575)
			(xy 75.651645 -47.331425) (xy 75.604039 -47.360479) (xy 75.55271 -47.382291) (xy 75.498753 -47.396397)
			(xy 75.443316 -47.402497) (xy 75.387582 -47.40046) (xy 75.332739 -47.39033) (xy 75.279955 -47.372323)
			(xy 75.230355 -47.346822) (xy 75.184997 -47.314371) (xy 75.144848 -47.275662) (xy 75.110762 -47.231519)
			(xy 75.083466 -47.182884) (xy 75.063543 -47.130793) (xy 75.051417 -47.076356) (xy 75.047346 -47.020734)
			(xy 74.632616 -47.020734) (xy 74.63282 -47.03191) (xy 74.632311 -47.059796) (xy 74.624191 -47.114972)
			(xy 74.608123 -47.168379) (xy 74.584451 -47.218876) (xy 74.553678 -47.265389) (xy 74.516461 -47.306926)
			(xy 74.473593 -47.342601) (xy 74.425987 -47.371655) (xy 74.374658 -47.393467) (xy 74.320701 -47.407573)
			(xy 74.265264 -47.413673) (xy 74.20953 -47.411636) (xy 74.154687 -47.401506) (xy 74.101903 -47.383499)
			(xy 74.052303 -47.357998) (xy 74.006945 -47.325547) (xy 73.966796 -47.286838) (xy 73.93271 -47.242695)
			(xy 73.905414 -47.19406) (xy 73.885491 -47.141969) (xy 73.873365 -47.087532) (xy 73.869294 -47.03191)
			(xy 73.074957 -47.03191) (xy 73.052323 -47.080192) (xy 73.02155 -47.126705) (xy 72.984333 -47.168242)
			(xy 72.941465 -47.203917) (xy 72.893859 -47.232971) (xy 72.84253 -47.254783) (xy 72.788573 -47.268889)
			(xy 72.733136 -47.274989) (xy 72.677402 -47.272952) (xy 72.622559 -47.262822) (xy 72.569775 -47.244815)
			(xy 72.520175 -47.219314) (xy 72.474817 -47.186863) (xy 72.434668 -47.148154) (xy 72.400582 -47.104011)
			(xy 72.373286 -47.055376) (xy 72.353363 -47.003285) (xy 72.341237 -46.948848) (xy 72.337166 -46.893226)
			(xy 71.499995 -46.893226) (xy 71.486795 -46.922124) (xy 71.457324 -46.967974) (xy 71.421627 -47.009164)
			(xy 71.380433 -47.044855) (xy 71.334578 -47.07432) (xy 71.284997 -47.09696) (xy 71.232699 -47.112315)
			(xy 71.178749 -47.120071) (xy 71.151496 -47.120556) (xy 71.125463 -47.120104) (xy 71.07388 -47.113017)
			(xy 71.023739 -47.098988) (xy 70.975968 -47.078278) (xy 70.931453 -47.051271) (xy 70.910958 -47.035212)
			(xy 70.903338 -47.029116) (xy 70.884796 -47.023274) (xy 70.80504 -47.029624) (xy 70.795405 -47.03081)
			(xy 70.778033 -47.039435) (xy 70.771258 -47.046388) (xy 70.753071 -47.066028) (xy 70.712165 -47.10055)
			(xy 70.666837 -47.12902) (xy 70.617977 -47.150879) (xy 70.566542 -47.165698) (xy 70.513541 -47.173186)
			(xy 70.486778 -47.173642) (xy 70.459528 -47.173143) (xy 70.405582 -47.165384) (xy 70.35329 -47.150028)
			(xy 70.303715 -47.127387) (xy 70.257866 -47.097921) (xy 70.216677 -47.062231) (xy 70.180986 -47.021043)
			(xy 70.151519 -46.975196) (xy 70.128876 -46.925621) (xy 70.113518 -46.873329) (xy 70.105758 -46.819384)
			(xy 70.10527 -46.792134) (xy 70.105803 -46.76336) (xy 70.114453 -46.706467) (xy 70.131548 -46.651517)
			(xy 70.156699 -46.599757) (xy 70.189337 -46.55236) (xy 70.208648 -46.531022) (xy 70.215545 -46.522969)
			(xy 70.222633 -46.503013) (xy 70.222364 -46.492414) (xy 70.216776 -46.417992) (xy 70.215508 -46.40752)
			(xy 70.205649 -46.388892) (xy 70.197726 -46.381924) (xy 70.197472 -46.38167) (xy 70.175277 -46.363457)
			(xy 70.13607 -46.321518) (xy 70.103587 -46.274179) (xy 70.078561 -46.222509) (xy 70.061556 -46.167674)
			(xy 70.052956 -46.11091) (xy 70.052438 -46.082204) (xy 53.64406 -46.082204) (xy 53.617474 -46.122389)
			(xy 53.580257 -46.163926) (xy 53.537389 -46.199601) (xy 53.489783 -46.228655) (xy 53.438454 -46.250467)
			(xy 53.384497 -46.264573) (xy 53.32906 -46.270673) (xy 53.273326 -46.268636) (xy 53.218483 -46.258506)
			(xy 53.165699 -46.240499) (xy 53.116099 -46.214998) (xy 53.070741 -46.182547) (xy 53.030592 -46.143838)
			(xy 52.996506 -46.099695) (xy 52.96921 -46.05106) (xy 52.949287 -45.998969) (xy 52.937161 -45.944532)
			(xy 52.93309 -45.88891) (xy 49.82079 -45.88891) (xy 49.813725 -45.93692) (xy 49.797657 -45.990327)
			(xy 49.773985 -46.040824) (xy 49.743212 -46.087337) (xy 49.705995 -46.128874) (xy 49.663127 -46.164549)
			(xy 49.615521 -46.193603) (xy 49.564192 -46.215415) (xy 49.510235 -46.229521) (xy 49.454798 -46.235621)
			(xy 49.399064 -46.233584) (xy 49.344221 -46.223454) (xy 49.291437 -46.205447) (xy 49.241837 -46.179946)
			(xy 49.196479 -46.147495) (xy 49.15633 -46.108786) (xy 49.122244 -46.064643) (xy 49.094948 -46.016008)
			(xy 49.075025 -45.963917) (xy 49.062899 -45.90948) (xy 49.058828 -45.853858) (xy 48.632663 -45.853858)
			(xy 48.632872 -45.865288) (xy 48.632363 -45.893174) (xy 48.624243 -45.94835) (xy 48.608175 -46.001757)
			(xy 48.584503 -46.052254) (xy 48.55373 -46.098767) (xy 48.516513 -46.140304) (xy 48.473645 -46.175979)
			(xy 48.426039 -46.205033) (xy 48.37471 -46.226845) (xy 48.320753 -46.240951) (xy 48.265316 -46.247051)
			(xy 48.209582 -46.245014) (xy 48.154739 -46.234884) (xy 48.101955 -46.216877) (xy 48.052355 -46.191376)
			(xy 48.006997 -46.158925) (xy 47.966848 -46.120216) (xy 47.932762 -46.076073) (xy 47.905466 -46.027438)
			(xy 47.885543 -45.975347) (xy 47.873417 -45.92091) (xy 47.869346 -45.865288) (xy 46.323997 -45.865288)
			(xy 46.332752 -45.895107) (xy 46.340508 -45.949051) (xy 46.340508 -46.003549) (xy 46.332752 -46.057493)
			(xy 46.317399 -46.109784) (xy 46.29476 -46.159358) (xy 46.265297 -46.205205) (xy 46.229609 -46.246394)
			(xy 46.188423 -46.282084) (xy 46.142577 -46.31155) (xy 46.093005 -46.334191) (xy 46.040714 -46.349547)
			(xy 45.986771 -46.357306) (xy 45.959522 -46.357794) (xy 45.93253 -46.357308) (xy 45.879083 -46.349706)
			(xy 45.82724 -46.334651) (xy 45.778035 -46.312443) (xy 45.73245 -46.283525) (xy 45.711618 -46.266354)
			(xy 45.703236 -46.259242) (xy 45.682916 -46.253146) (xy 45.597826 -46.264068) (xy 45.592465 -46.264801)
			(xy 45.582216 -46.268262) (xy 45.577506 -46.270926) (xy 45.568616 -46.276514) (xy 45.562266 -46.285404)
			(xy 45.562012 -46.285658) (xy 45.544418 -46.309856) (xy 45.502951 -46.352979) (xy 45.479462 -46.37151)
			(xy 45.471334 -46.377606) (xy 45.461174 -46.394624) (xy 45.44949 -46.475396) (xy 45.448506 -46.485161)
			(xy 45.453067 -46.504229) (xy 45.45838 -46.51248) (xy 45.458634 -46.512734) (xy 45.458888 -46.512988)
			(xy 45.476334 -46.53772) (xy 45.504043 -46.591524) (xy 45.522914 -46.649027) (xy 45.532473 -46.708788)
			(xy 45.533056 -46.739048) (xy 45.532567 -46.766298) (xy 45.524805 -46.820243) (xy 45.509446 -46.872535)
			(xy 45.499995 -46.893226) (xy 46.337218 -46.893226) (xy 46.341289 -46.837604) (xy 46.353415 -46.783167)
			(xy 46.373338 -46.731076) (xy 46.400634 -46.682441) (xy 46.43472 -46.638298) (xy 46.474869 -46.599589)
			(xy 46.520227 -46.567138) (xy 46.569827 -46.541637) (xy 46.622611 -46.52363) (xy 46.677454 -46.5135)
			(xy 46.733188 -46.511463) (xy 46.788625 -46.517563) (xy 46.842582 -46.531669) (xy 46.893911 -46.553481)
			(xy 46.941517 -46.582535) (xy 46.984385 -46.61821) (xy 47.021602 -46.659747) (xy 47.052375 -46.70626)
			(xy 47.076047 -46.756757) (xy 47.092115 -46.810164) (xy 47.100235 -46.86534) (xy 47.100744 -46.893226)
			(xy 47.100235 -46.921112) (xy 47.092115 -46.976288) (xy 47.076047 -47.029695) (xy 47.075009 -47.03191)
			(xy 47.869346 -47.03191) (xy 47.873417 -46.976288) (xy 47.885543 -46.921851) (xy 47.905466 -46.86976)
			(xy 47.932762 -46.821125) (xy 47.966848 -46.776982) (xy 48.006997 -46.738273) (xy 48.052355 -46.705822)
			(xy 48.101955 -46.680321) (xy 48.154739 -46.662314) (xy 48.209582 -46.652184) (xy 48.265316 -46.650147)
			(xy 48.320753 -46.656247) (xy 48.37471 -46.670353) (xy 48.426039 -46.692165) (xy 48.473645 -46.721219)
			(xy 48.516513 -46.756894) (xy 48.55373 -46.798431) (xy 48.584503 -46.844944) (xy 48.608175 -46.895441)
			(xy 48.624243 -46.948848) (xy 48.632363 -47.004024) (xy 48.632668 -47.020734) (xy 49.047398 -47.020734)
			(xy 49.051469 -46.965112) (xy 49.063595 -46.910675) (xy 49.083518 -46.858584) (xy 49.110814 -46.809949)
			(xy 49.1449 -46.765806) (xy 49.185049 -46.727097) (xy 49.230407 -46.694646) (xy 49.280007 -46.669145)
			(xy 49.332791 -46.651138) (xy 49.387634 -46.641008) (xy 49.443368 -46.638971) (xy 49.498805 -46.645071)
			(xy 49.552762 -46.659177) (xy 49.604091 -46.680989) (xy 49.625141 -46.693836) (xy 50.676302 -46.693836)
			(xy 50.676789 -46.666584) (xy 50.684541 -46.612633) (xy 50.699893 -46.560335) (xy 50.722532 -46.510754)
			(xy 50.751997 -46.4649) (xy 50.787689 -46.423707) (xy 50.82888 -46.388013) (xy 50.874731 -46.358545)
			(xy 50.924311 -46.335902) (xy 50.976608 -46.320547) (xy 51.030558 -46.312791) (xy 51.05781 -46.312328)
			(xy 51.085065 -46.312746) (xy 51.139019 -46.320505) (xy 51.19132 -46.335864) (xy 51.240903 -46.35851)
			(xy 51.286758 -46.387983) (xy 51.327951 -46.423681) (xy 51.363645 -46.464879) (xy 51.393112 -46.510738)
			(xy 51.415752 -46.560323) (xy 51.431105 -46.612626) (xy 51.438858 -46.666581) (xy 51.439318 -46.693836)
			(xy 51.438843 -46.720263) (xy 51.431534 -46.772611) (xy 51.417061 -46.823446) (xy 51.395702 -46.871793)
			(xy 51.382168 -46.894496) (xy 51.382168 -46.89475) (xy 51.376593 -46.904677) (xy 51.37407 -46.92728)
			(xy 51.377342 -46.938184) (xy 51.407822 -47.023782) (xy 51.424078 -47.040038) (xy 51.435 -47.043848)
			(xy 51.459499 -47.052944) (xy 51.505952 -47.076881) (xy 51.548706 -47.106932) (xy 51.586959 -47.142535)
			(xy 51.619998 -47.183025) (xy 51.647203 -47.227643) (xy 51.668066 -47.275556) (xy 51.682197 -47.325868)
			(xy 51.689331 -47.377637) (xy 51.689762 -47.403766) (xy 51.689313 -47.43102) (xy 51.687791 -47.441612)
			(xy 52.961792 -47.441612) (xy 52.965863 -47.38599) (xy 52.977989 -47.331553) (xy 52.997912 -47.279462)
			(xy 53.025208 -47.230827) (xy 53.059294 -47.186684) (xy 53.099443 -47.147975) (xy 53.144801 -47.115524)
			(xy 53.194401 -47.090023) (xy 53.247185 -47.072016) (xy 53.302028 -47.061886) (xy 53.357762 -47.059849)
			(xy 53.413199 -47.065949) (xy 53.467156 -47.080055) (xy 53.518485 -47.101867) (xy 53.566091 -47.130921)
			(xy 53.608959 -47.166596) (xy 53.646176 -47.208133) (xy 53.676949 -47.254646) (xy 53.700621 -47.305143)
			(xy 53.716689 -47.35855) (xy 53.724809 -47.413726) (xy 53.725318 -47.441612) (xy 53.724809 -47.469498)
			(xy 53.716689 -47.524674) (xy 53.700621 -47.578081) (xy 53.676949 -47.628578) (xy 53.646176 -47.675091)
			(xy 53.608959 -47.716628) (xy 53.566091 -47.752303) (xy 53.518485 -47.781357) (xy 53.467156 -47.803169)
			(xy 53.413199 -47.817275) (xy 53.357762 -47.823375) (xy 53.302028 -47.821338) (xy 53.247185 -47.811208)
			(xy 53.194401 -47.793201) (xy 53.144801 -47.7677) (xy 53.099443 -47.735249) (xy 53.059294 -47.69654)
			(xy 53.025208 -47.652397) (xy 52.997912 -47.603762) (xy 52.977989 -47.551671) (xy 52.965863 -47.497234)
			(xy 52.961792 -47.441612) (xy 51.687791 -47.441612) (xy 51.681559 -47.484974) (xy 51.666205 -47.537275)
			(xy 51.643563 -47.586858) (xy 51.614095 -47.632713) (xy 51.578399 -47.673908) (xy 51.537204 -47.709602)
			(xy 51.491347 -47.739069) (xy 51.441764 -47.76171) (xy 51.389462 -47.777062) (xy 51.335508 -47.784814)
			(xy 51.308254 -47.785274) (xy 51.281 -47.784865) (xy 51.227048 -47.777101) (xy 51.17475 -47.761739)
			(xy 51.12517 -47.73909) (xy 51.079318 -47.709615) (xy 51.038128 -47.673916) (xy 51.002437 -47.632718)
			(xy 50.972972 -47.58686) (xy 50.950333 -47.537275) (xy 50.934982 -47.484974) (xy 50.927229 -47.43102)
			(xy 50.926746 -47.403766) (xy 50.927213 -47.377338) (xy 50.934523 -47.32499) (xy 50.948998 -47.274155)
			(xy 50.97036 -47.225809) (xy 50.983896 -47.203106) (xy 50.983896 -47.202852) (xy 50.98937 -47.19289)
			(xy 50.991886 -47.170334) (xy 50.988722 -47.159418) (xy 50.958242 -47.07382) (xy 50.941986 -47.057564)
			(xy 50.931064 -47.053754) (xy 50.906558 -47.044677) (xy 50.860105 -47.020736) (xy 50.817353 -46.990681)
			(xy 50.779101 -46.955075) (xy 50.746064 -46.914583) (xy 50.71886 -46.869963) (xy 50.697998 -46.822048)
			(xy 50.683867 -46.771736) (xy 50.676733 -46.719966) (xy 50.676302 -46.693836) (xy 49.625141 -46.693836)
			(xy 49.651697 -46.710043) (xy 49.694565 -46.745718) (xy 49.731782 -46.787255) (xy 49.762555 -46.833768)
			(xy 49.786227 -46.884265) (xy 49.802295 -46.937672) (xy 49.810415 -46.992848) (xy 49.810924 -47.020734)
			(xy 49.810415 -47.04862) (xy 49.802295 -47.103796) (xy 49.786227 -47.157203) (xy 49.762555 -47.2077)
			(xy 49.731782 -47.254213) (xy 49.694565 -47.29575) (xy 49.651697 -47.331425) (xy 49.604091 -47.360479)
			(xy 49.552762 -47.382291) (xy 49.498805 -47.396397) (xy 49.443368 -47.402497) (xy 49.387634 -47.40046)
			(xy 49.332791 -47.39033) (xy 49.280007 -47.372323) (xy 49.230407 -47.346822) (xy 49.185049 -47.314371)
			(xy 49.1449 -47.275662) (xy 49.110814 -47.231519) (xy 49.083518 -47.182884) (xy 49.063595 -47.130793)
			(xy 49.051469 -47.076356) (xy 49.047398 -47.020734) (xy 48.632668 -47.020734) (xy 48.632872 -47.03191)
			(xy 48.632363 -47.059796) (xy 48.624243 -47.114972) (xy 48.608175 -47.168379) (xy 48.584503 -47.218876)
			(xy 48.55373 -47.265389) (xy 48.516513 -47.306926) (xy 48.473645 -47.342601) (xy 48.426039 -47.371655)
			(xy 48.37471 -47.393467) (xy 48.320753 -47.407573) (xy 48.265316 -47.413673) (xy 48.209582 -47.411636)
			(xy 48.154739 -47.401506) (xy 48.101955 -47.383499) (xy 48.052355 -47.357998) (xy 48.006997 -47.325547)
			(xy 47.966848 -47.286838) (xy 47.932762 -47.242695) (xy 47.905466 -47.19406) (xy 47.885543 -47.141969)
			(xy 47.873417 -47.087532) (xy 47.869346 -47.03191) (xy 47.075009 -47.03191) (xy 47.052375 -47.080192)
			(xy 47.021602 -47.126705) (xy 46.984385 -47.168242) (xy 46.941517 -47.203917) (xy 46.893911 -47.232971)
			(xy 46.842582 -47.254783) (xy 46.788625 -47.268889) (xy 46.733188 -47.274989) (xy 46.677454 -47.272952)
			(xy 46.622611 -47.262822) (xy 46.569827 -47.244815) (xy 46.520227 -47.219314) (xy 46.474869 -47.186863)
			(xy 46.43472 -47.148154) (xy 46.400634 -47.104011) (xy 46.373338 -47.055376) (xy 46.353415 -47.003285)
			(xy 46.341289 -46.948848) (xy 46.337218 -46.893226) (xy 45.499995 -46.893226) (xy 45.486803 -46.922109)
			(xy 45.457336 -46.967957) (xy 45.421646 -47.009146) (xy 45.380457 -47.044836) (xy 45.334609 -47.074303)
			(xy 45.285035 -47.096946) (xy 45.232743 -47.112305) (xy 45.178798 -47.120067) (xy 45.151548 -47.120556)
			(xy 45.125514 -47.120131) (xy 45.07393 -47.113038) (xy 45.023788 -47.099003) (xy 44.976018 -47.078287)
			(xy 44.931504 -47.051274) (xy 44.91101 -47.035212) (xy 44.90339 -47.029116) (xy 44.884848 -47.023274)
			(xy 44.805092 -47.029624) (xy 44.795453 -47.030786) (xy 44.778082 -47.039428) (xy 44.77131 -47.046388)
			(xy 44.753147 -47.066051) (xy 44.712235 -47.100572) (xy 44.666903 -47.129039) (xy 44.618038 -47.150893)
			(xy 44.566599 -47.165707) (xy 44.513595 -47.173189) (xy 44.48683 -47.173642) (xy 44.459581 -47.173094)
			(xy 44.405637 -47.165342) (xy 44.353346 -47.149993) (xy 44.303771 -47.127358) (xy 44.257922 -47.097898)
			(xy 44.216733 -47.062213) (xy 44.181041 -47.021029) (xy 44.151573 -46.975185) (xy 44.12893 -46.925614)
			(xy 44.113571 -46.873325) (xy 44.105811 -46.819383) (xy 44.105322 -46.792134) (xy 44.105841 -46.76336)
			(xy 44.114492 -46.706465) (xy 44.13159 -46.651514) (xy 44.156745 -46.599754) (xy 44.189387 -46.552358)
			(xy 44.2087 -46.531022) (xy 44.215603 -46.522974) (xy 44.222686 -46.503014) (xy 44.222416 -46.492414)
			(xy 44.216828 -46.417992) (xy 44.215543 -46.407523) (xy 44.205694 -46.388895) (xy 44.197778 -46.381924)
			(xy 44.197524 -46.38167) (xy 44.17534 -46.363444) (xy 44.13613 -46.321509) (xy 44.103644 -46.274174)
			(xy 44.078615 -46.222506) (xy 44.061609 -46.167672) (xy 44.053008 -46.110909) (xy 44.05249 -46.082204)
			(xy 27.644112 -46.082204) (xy 27.617526 -46.122389) (xy 27.580309 -46.163926) (xy 27.537441 -46.199601)
			(xy 27.489835 -46.228655) (xy 27.438506 -46.250467) (xy 27.384549 -46.264573) (xy 27.329112 -46.270673)
			(xy 27.273378 -46.268636) (xy 27.218535 -46.258506) (xy 27.165751 -46.240499) (xy 27.116151 -46.214998)
			(xy 27.070793 -46.182547) (xy 27.030644 -46.143838) (xy 26.996558 -46.099695) (xy 26.969262 -46.05106)
			(xy 26.949339 -45.998969) (xy 26.937213 -45.944532) (xy 26.933142 -45.88891) (xy 23.820826 -45.88891)
			(xy 23.814193 -45.935068) (xy 23.798841 -45.987371) (xy 23.776201 -46.036956) (xy 23.746734 -46.082814)
			(xy 23.71104 -46.124012) (xy 23.669846 -46.15971) (xy 23.623991 -46.189182) (xy 23.574408 -46.211827)
			(xy 23.522107 -46.227185) (xy 23.468153 -46.234943) (xy 23.440898 -46.235366) (xy 23.413033 -46.234886)
			(xy 23.357896 -46.226768) (xy 23.304535 -46.210691) (xy 23.2791 -46.199298) (xy 23.278846 -46.199298)
			(xy 23.269215 -46.195399) (xy 23.248465 -46.19485) (xy 23.229174 -46.202514) (xy 23.221442 -46.209458)
			(xy 22.610572 -46.820328) (xy 22.605387 -46.825965) (xy 22.598284 -46.839526) (xy 22.596602 -46.846998)
			(xy 22.595078 -46.854872) (xy 22.596602 -46.869858) (xy 22.599904 -46.877224) (xy 22.610291 -46.901679)
			(xy 22.624965 -46.952742) (xy 22.632422 -47.005346) (xy 22.632713 -47.020734) (xy 23.04745 -47.020734)
			(xy 23.051521 -46.965112) (xy 23.063647 -46.910675) (xy 23.08357 -46.858584) (xy 23.110866 -46.809949)
			(xy 23.144952 -46.765806) (xy 23.185101 -46.727097) (xy 23.230459 -46.694646) (xy 23.280059 -46.669145)
			(xy 23.332843 -46.651138) (xy 23.387686 -46.641008) (xy 23.44342 -46.638971) (xy 23.498857 -46.645071)
			(xy 23.552814 -46.659177) (xy 23.604143 -46.680989) (xy 23.625193 -46.693836) (xy 24.676354 -46.693836)
			(xy 24.676912 -46.666587) (xy 24.684662 -46.612644) (xy 24.700011 -46.560353) (xy 24.722645 -46.510779)
			(xy 24.752104 -46.46493) (xy 24.787788 -46.42374) (xy 24.828971 -46.388048) (xy 24.874814 -46.358581)
			(xy 24.924384 -46.335937) (xy 24.976672 -46.320578) (xy 25.030613 -46.312817) (xy 25.057862 -46.312328)
			(xy 25.085116 -46.312791) (xy 25.139068 -46.320543) (xy 25.191368 -46.335897) (xy 25.240951 -46.358537)
			(xy 25.286806 -46.388005) (xy 25.328 -46.423699) (xy 25.363694 -46.464893) (xy 25.393162 -46.510747)
			(xy 25.415803 -46.56033) (xy 25.431156 -46.61263) (xy 25.438909 -46.666582) (xy 25.43937 -46.693836)
			(xy 25.438901 -46.720264) (xy 25.431591 -46.772611) (xy 25.417117 -46.823446) (xy 25.395755 -46.871793)
			(xy 25.38222 -46.894496) (xy 25.38222 -46.89475) (xy 25.376645 -46.904676) (xy 25.374124 -46.92728)
			(xy 25.377394 -46.938184) (xy 25.407874 -47.023782) (xy 25.42413 -47.040038) (xy 25.435052 -47.043848)
			(xy 25.459562 -47.052914) (xy 25.506014 -47.076857) (xy 25.548766 -47.106914) (xy 25.587018 -47.142522)
			(xy 25.620054 -47.183015) (xy 25.647258 -47.227636) (xy 25.668119 -47.275552) (xy 25.682249 -47.325865)
			(xy 25.689383 -47.377636) (xy 25.689814 -47.403766) (xy 25.689313 -47.431018) (xy 25.687791 -47.441612)
			(xy 26.961844 -47.441612) (xy 26.965915 -47.38599) (xy 26.978041 -47.331553) (xy 26.997964 -47.279462)
			(xy 27.02526 -47.230827) (xy 27.059346 -47.186684) (xy 27.099495 -47.147975) (xy 27.144853 -47.115524)
			(xy 27.194453 -47.090023) (xy 27.247237 -47.072016) (xy 27.30208 -47.061886) (xy 27.357814 -47.059849)
			(xy 27.413251 -47.065949) (xy 27.467208 -47.080055) (xy 27.518537 -47.101867) (xy 27.566143 -47.130921)
			(xy 27.609011 -47.166596) (xy 27.646228 -47.208133) (xy 27.677001 -47.254646) (xy 27.700673 -47.305143)
			(xy 27.716741 -47.35855) (xy 27.724861 -47.413726) (xy 27.72537 -47.441612) (xy 27.724861 -47.469498)
			(xy 27.716741 -47.524674) (xy 27.700673 -47.578081) (xy 27.677001 -47.628578) (xy 27.646228 -47.675091)
			(xy 27.609011 -47.716628) (xy 27.566143 -47.752303) (xy 27.518537 -47.781357) (xy 27.467208 -47.803169)
			(xy 27.413251 -47.817275) (xy 27.357814 -47.823375) (xy 27.30208 -47.821338) (xy 27.247237 -47.811208)
			(xy 27.194453 -47.793201) (xy 27.144853 -47.7677) (xy 27.099495 -47.735249) (xy 27.059346 -47.69654)
			(xy 27.02526 -47.652397) (xy 26.997964 -47.603762) (xy 26.978041 -47.551671) (xy 26.965915 -47.497234)
			(xy 26.961844 -47.441612) (xy 25.687791 -47.441612) (xy 25.681561 -47.484967) (xy 25.666209 -47.537264)
			(xy 25.643571 -47.586843) (xy 25.614107 -47.632696) (xy 25.578418 -47.673889) (xy 25.537228 -47.709583)
			(xy 25.491379 -47.739052) (xy 25.441801 -47.761695) (xy 25.389506 -47.777052) (xy 25.335558 -47.78481)
			(xy 25.308306 -47.785274) (xy 25.281052 -47.784839) (xy 25.227098 -47.777082) (xy 25.174798 -47.761725)
			(xy 25.125215 -47.739081) (xy 25.07936 -47.70961) (xy 25.038167 -47.673913) (xy 25.002473 -47.632717)
			(xy 24.973006 -47.58686) (xy 24.950365 -47.537276) (xy 24.935012 -47.484975) (xy 24.927259 -47.43102)
			(xy 24.926798 -47.403766) (xy 24.927272 -47.377338) (xy 24.934581 -47.324991) (xy 24.949054 -47.274156)
			(xy 24.970413 -47.225809) (xy 24.983948 -47.203106) (xy 24.983948 -47.202852) (xy 24.989522 -47.192925)
			(xy 24.992045 -47.170322) (xy 24.988774 -47.159418) (xy 24.958294 -47.07382) (xy 24.942038 -47.057564)
			(xy 24.931116 -47.053754) (xy 24.9066 -47.044704) (xy 24.860148 -47.020757) (xy 24.817398 -46.990698)
			(xy 24.779147 -46.955088) (xy 24.746112 -46.914592) (xy 24.718909 -46.869969) (xy 24.698048 -46.822053)
			(xy 24.683919 -46.771738) (xy 24.676785 -46.719966) (xy 24.676354 -46.693836) (xy 23.625193 -46.693836)
			(xy 23.651749 -46.710043) (xy 23.694617 -46.745718) (xy 23.731834 -46.787255) (xy 23.762607 -46.833768)
			(xy 23.786279 -46.884265) (xy 23.802347 -46.937672) (xy 23.810467 -46.992848) (xy 23.810976 -47.020734)
			(xy 23.810467 -47.04862) (xy 23.802347 -47.103796) (xy 23.786279 -47.157203) (xy 23.762607 -47.2077)
			(xy 23.731834 -47.254213) (xy 23.694617 -47.29575) (xy 23.651749 -47.331425) (xy 23.604143 -47.360479)
			(xy 23.552814 -47.382291) (xy 23.498857 -47.396397) (xy 23.44342 -47.402497) (xy 23.387686 -47.40046)
			(xy 23.332843 -47.39033) (xy 23.280059 -47.372323) (xy 23.230459 -47.346822) (xy 23.185101 -47.314371)
			(xy 23.144952 -47.275662) (xy 23.110866 -47.231519) (xy 23.08357 -47.182884) (xy 23.063647 -47.130793)
			(xy 23.051521 -47.076356) (xy 23.04745 -47.020734) (xy 22.632713 -47.020734) (xy 22.632924 -47.03191)
			(xy 22.632438 -47.059161) (xy 22.62468 -47.113109) (xy 22.609324 -47.165403) (xy 22.586683 -47.21498)
			(xy 22.557216 -47.26083) (xy 22.521525 -47.302021) (xy 22.480335 -47.337713) (xy 22.434485 -47.36718)
			(xy 22.384909 -47.389822) (xy 22.332615 -47.405179) (xy 22.278667 -47.412937) (xy 22.251416 -47.413418)
			(xy 22.224851 -47.412923) (xy 22.172246 -47.405472) (xy 22.121186 -47.390783) (xy 22.09673 -47.380398)
			(xy 22.089551 -47.37748) (xy 22.074166 -47.375678) (xy 22.066504 -47.376842) (xy 22.066504 -47.377096)
			(xy 22.059013 -47.378727) (xy 22.045441 -47.385838) (xy 22.039834 -47.391066) (xy 20.677886 -48.753014)
			(xy 21.168358 -48.753014) (xy 21.172429 -48.697392) (xy 21.184555 -48.642955) (xy 21.204478 -48.590864)
			(xy 21.231774 -48.542229) (xy 21.26586 -48.498086) (xy 21.306009 -48.459377) (xy 21.351367 -48.426926)
			(xy 21.400967 -48.401425) (xy 21.453751 -48.383418) (xy 21.508594 -48.373288) (xy 21.564328 -48.371251)
			(xy 21.619765 -48.377351) (xy 21.673722 -48.391457) (xy 21.725051 -48.413269) (xy 21.772657 -48.442323)
			(xy 21.815525 -48.477998) (xy 21.852742 -48.519535) (xy 21.883515 -48.566048) (xy 21.907187 -48.616545)
			(xy 21.923255 -48.669952) (xy 21.931375 -48.725128) (xy 21.931884 -48.753014) (xy 21.931375 -48.7809)
			(xy 21.923255 -48.836076) (xy 21.907187 -48.889483) (xy 21.892997 -48.919754) (xy 23.215038 -48.919754)
			(xy 23.215038 -48.865246) (xy 23.222795 -48.811294) (xy 23.238151 -48.758994) (xy 23.260794 -48.709412)
			(xy 23.290263 -48.663557) (xy 23.325957 -48.622363) (xy 23.367151 -48.586668) (xy 23.413005 -48.557198)
			(xy 23.462586 -48.534554) (xy 23.514886 -48.519197) (xy 23.568838 -48.511438) (xy 23.596092 -48.510952)
			(xy 23.625887 -48.51149) (xy 23.684753 -48.520755) (xy 23.741463 -48.53906) (xy 23.794636 -48.56596)
			(xy 23.84298 -48.600801) (xy 23.885318 -48.642736) (xy 23.903432 -48.6664) (xy 23.910798 -48.67656)
			(xy 23.932642 -48.687228) (xy 24.040846 -48.684942) (xy 24.062436 -48.673004) (xy 24.069548 -48.66259)
			(xy 24.084813 -48.640639) (xy 24.120489 -48.600815) (xy 24.161374 -48.56636) (xy 24.206667 -48.537948)
			(xy 24.255482 -48.516135) (xy 24.306864 -48.501349) (xy 24.359807 -48.493879) (xy 24.38654 -48.493426)
			(xy 24.387048 -48.493426) (xy 24.401841 -48.493565) (xy 24.431339 -48.495852) (xy 24.445976 -48.497998)
			(xy 24.458168 -48.50003) (xy 24.481536 -48.492156) (xy 24.54783 -48.423322) (xy 24.55192 -48.418871)
			(xy 24.558074 -48.408471) (xy 24.560022 -48.402748) (xy 24.563578 -48.39081) (xy 24.561292 -48.378364)
			(xy 24.558118 -48.36069) (xy 24.554684 -48.324945) (xy 24.554434 -48.30699) (xy 24.554846 -48.279735)
			(xy 24.562605 -48.22578) (xy 24.577965 -48.173479) (xy 24.600611 -48.123895) (xy 24.630084 -48.07804)
			(xy 24.665783 -48.036847) (xy 24.706982 -48.001153) (xy 24.752841 -47.971686) (xy 24.802427 -47.949046)
			(xy 24.854731 -47.933694) (xy 24.908687 -47.925942) (xy 24.935942 -47.925482) (xy 24.963191 -47.925991)
			(xy 25.017132 -47.933752) (xy 25.027025 -47.936658) (xy 44.652946 -47.936658) (xy 44.653432 -47.909407)
			(xy 44.661188 -47.855459) (xy 44.676543 -47.803164) (xy 44.699185 -47.753587) (xy 44.728651 -47.707737)
			(xy 44.764342 -47.666546) (xy 44.805533 -47.630855) (xy 44.851383 -47.601389) (xy 44.90096 -47.578747)
			(xy 44.953255 -47.563392) (xy 45.007203 -47.555636) (xy 45.061705 -47.555636) (xy 45.115653 -47.563392)
			(xy 45.167948 -47.578747) (xy 45.217525 -47.601389) (xy 45.263375 -47.630855) (xy 45.304566 -47.666546)
			(xy 45.340257 -47.707737) (xy 45.369723 -47.753587) (xy 45.392365 -47.803164) (xy 45.40772 -47.855459)
			(xy 45.415476 -47.909407) (xy 45.415962 -47.936658) (xy 45.415496 -47.962999) (xy 45.408246 -48.015179)
			(xy 45.393891 -48.065866) (xy 45.372705 -48.1141) (xy 45.345089 -48.158963) (xy 45.311569 -48.199603)
			(xy 45.272779 -48.23525) (xy 45.25137 -48.250602) (xy 45.239542 -48.259295) (xy 45.2211 -48.282119)
			(xy 45.209912 -48.309246) (xy 45.206903 -48.338435) (xy 45.212321 -48.367274) (xy 45.225719 -48.39338)
			(xy 45.245989 -48.414597) (xy 45.258482 -48.422306) (xy 45.28302 -48.436998) (xy 45.327778 -48.4726)
			(xy 45.366721 -48.514484) (xy 45.398977 -48.561711) (xy 45.423822 -48.613224) (xy 45.440701 -48.667868)
			(xy 45.449235 -48.724418) (xy 45.449744 -48.753014) (xy 47.168306 -48.753014) (xy 47.172377 -48.697392)
			(xy 47.184503 -48.642955) (xy 47.204426 -48.590864) (xy 47.231722 -48.542229) (xy 47.265808 -48.498086)
			(xy 47.305957 -48.459377) (xy 47.351315 -48.426926) (xy 47.400915 -48.401425) (xy 47.453699 -48.383418)
			(xy 47.508542 -48.373288) (xy 47.564276 -48.371251) (xy 47.619713 -48.377351) (xy 47.67367 -48.391457)
			(xy 47.724999 -48.413269) (xy 47.772605 -48.442323) (xy 47.815473 -48.477998) (xy 47.85269 -48.519535)
			(xy 47.883463 -48.566048) (xy 47.907135 -48.616545) (xy 47.923203 -48.669952) (xy 47.931323 -48.725128)
			(xy 47.931832 -48.753014) (xy 47.931323 -48.7809) (xy 47.923203 -48.836076) (xy 47.907135 -48.889483)
			(xy 47.892943 -48.919758) (xy 49.214915 -48.919758) (xy 49.214915 -48.865242) (xy 49.222674 -48.811282)
			(xy 49.238034 -48.758976) (xy 49.260681 -48.709388) (xy 49.290156 -48.663528) (xy 49.325858 -48.62233)
			(xy 49.36706 -48.586632) (xy 49.412923 -48.557162) (xy 49.462513 -48.53452) (xy 49.514821 -48.519165)
			(xy 49.568782 -48.511412) (xy 49.59604 -48.510952) (xy 49.625834 -48.511529) (xy 49.684698 -48.520785)
			(xy 49.741407 -48.539083) (xy 49.79458 -48.565976) (xy 49.842925 -48.60081) (xy 49.885265 -48.642739)
			(xy 49.90338 -48.6664) (xy 49.910746 -48.67656) (xy 49.93259 -48.687228) (xy 50.040794 -48.684942)
			(xy 50.062384 -48.673004) (xy 50.069496 -48.66259) (xy 50.084731 -48.640616) (xy 50.120412 -48.600793)
			(xy 50.161302 -48.566339) (xy 50.2066 -48.53793) (xy 50.25542 -48.516122) (xy 50.306807 -48.50134)
			(xy 50.359753 -48.493876) (xy 50.386488 -48.493426) (xy 50.386996 -48.493426) (xy 50.401789 -48.49356)
			(xy 50.431287 -48.49585) (xy 50.445924 -48.497998) (xy 50.458116 -48.50003) (xy 50.481484 -48.492156)
			(xy 50.547778 -48.423322) (xy 50.551874 -48.418876) (xy 50.558024 -48.408472) (xy 50.55997 -48.402748)
			(xy 50.563526 -48.39081) (xy 50.56124 -48.378364) (xy 50.558066 -48.36069) (xy 50.554632 -48.324945)
			(xy 50.554382 -48.30699) (xy 50.554868 -48.279739) (xy 50.562626 -48.225792) (xy 50.577982 -48.173498)
			(xy 50.600624 -48.123921) (xy 50.63009 -48.078071) (xy 50.665781 -48.036881) (xy 50.706971 -48.00119)
			(xy 50.752821 -47.971724) (xy 50.802398 -47.949082) (xy 50.854692 -47.933726) (xy 50.908639 -47.925968)
			(xy 50.93589 -47.925482) (xy 50.963143 -47.925965) (xy 51.017093 -47.93372) (xy 51.0271 -47.936658)
			(xy 70.652894 -47.936658) (xy 70.65338 -47.909407) (xy 70.661136 -47.855459) (xy 70.676491 -47.803164)
			(xy 70.699133 -47.753587) (xy 70.728599 -47.707737) (xy 70.76429 -47.666546) (xy 70.805481 -47.630855)
			(xy 70.851331 -47.601389) (xy 70.900908 -47.578747) (xy 70.953203 -47.563392) (xy 71.007151 -47.555636)
			(xy 71.061653 -47.555636) (xy 71.115601 -47.563392) (xy 71.167896 -47.578747) (xy 71.217473 -47.601389)
			(xy 71.263323 -47.630855) (xy 71.304514 -47.666546) (xy 71.340205 -47.707737) (xy 71.369671 -47.753587)
			(xy 71.392313 -47.803164) (xy 71.407668 -47.855459) (xy 71.415424 -47.909407) (xy 71.41591 -47.936658)
			(xy 71.415466 -47.963) (xy 71.408215 -48.015181) (xy 71.393858 -48.065871) (xy 71.372669 -48.114105)
			(xy 71.345049 -48.158968) (xy 71.311524 -48.199608) (xy 71.272729 -48.235252) (xy 71.251318 -48.250602)
			(xy 71.239497 -48.259301) (xy 71.221065 -48.282126) (xy 71.209884 -48.30925) (xy 71.206877 -48.338435)
			(xy 71.212292 -48.367269) (xy 71.225682 -48.393373) (xy 71.245943 -48.414593) (xy 71.25843 -48.422306)
			(xy 71.282979 -48.43698) (xy 71.327735 -48.472587) (xy 71.366675 -48.514475) (xy 71.398929 -48.561705)
			(xy 71.423772 -48.61322) (xy 71.44065 -48.667866) (xy 71.449183 -48.724418) (xy 71.449692 -48.753014)
			(xy 73.168254 -48.753014) (xy 73.172325 -48.697392) (xy 73.184451 -48.642955) (xy 73.204374 -48.590864)
			(xy 73.23167 -48.542229) (xy 73.265756 -48.498086) (xy 73.305905 -48.459377) (xy 73.351263 -48.426926)
			(xy 73.400863 -48.401425) (xy 73.453647 -48.383418) (xy 73.50849 -48.373288) (xy 73.564224 -48.371251)
			(xy 73.619661 -48.377351) (xy 73.673618 -48.391457) (xy 73.724947 -48.413269) (xy 73.772553 -48.442323)
			(xy 73.815421 -48.477998) (xy 73.852638 -48.519535) (xy 73.883411 -48.566048) (xy 73.907083 -48.616545)
			(xy 73.923151 -48.669952) (xy 73.931271 -48.725128) (xy 73.93178 -48.753014) (xy 73.931271 -48.7809)
			(xy 73.923151 -48.836076) (xy 73.907083 -48.889483) (xy 73.905687 -48.89246) (xy 75.21448 -48.89246)
			(xy 75.214941 -48.865208) (xy 75.222702 -48.81126) (xy 75.238062 -48.758966) (xy 75.260707 -48.709389)
			(xy 75.290176 -48.66354) (xy 75.32587 -48.62235) (xy 75.367062 -48.586659) (xy 75.412914 -48.557193)
			(xy 75.462492 -48.534552) (xy 75.514788 -48.519196) (xy 75.568736 -48.511439) (xy 75.595988 -48.510952)
			(xy 75.609175 -48.511039) (xy 75.635488 -48.512818) (xy 75.648566 -48.514508) (xy 75.660504 -48.516286)
			(xy 75.683618 -48.508412) (xy 75.757786 -48.431958) (xy 75.764898 -48.408844) (xy 75.762866 -48.396652)
			(xy 75.760274 -48.380712) (xy 75.757478 -48.348538) (xy 75.757278 -48.33239) (xy 75.757768 -48.305139)
			(xy 75.765526 -48.251192) (xy 75.780882 -48.198898) (xy 75.803523 -48.149322) (xy 75.832989 -48.103472)
			(xy 75.86868 -48.062283) (xy 75.909869 -48.026591) (xy 75.955719 -47.997125) (xy 76.005295 -47.974483)
			(xy 76.057588 -47.959127) (xy 76.111535 -47.951369) (xy 76.138786 -47.950882) (xy 76.168653 -47.951468)
			(xy 76.227656 -47.960788) (xy 76.284487 -47.979188) (xy 76.337756 -48.006219) (xy 76.386163 -48.041219)
			(xy 76.428525 -48.083333) (xy 76.446634 -48.107092) (xy 76.454 -48.117252) (xy 76.476352 -48.128174)
			(xy 76.572872 -48.12538) (xy 76.585326 -48.124467) (xy 76.607044 -48.112195) (xy 76.614274 -48.102012)
			(xy 76.614274 -48.101758) (xy 76.629355 -48.078951) (xy 76.665045 -48.037529) (xy 76.706284 -48.001627)
			(xy 76.752227 -47.971982) (xy 76.801933 -47.949201) (xy 76.854382 -47.933751) (xy 76.908499 -47.925949)
			(xy 76.935838 -47.925482) (xy 76.963087 -47.925991) (xy 77.017029 -47.933752) (xy 77.026923 -47.936658)
			(xy 96.652842 -47.936658) (xy 96.653328 -47.909407) (xy 96.661084 -47.855459) (xy 96.676439 -47.803164)
			(xy 96.699081 -47.753587) (xy 96.728547 -47.707737) (xy 96.764238 -47.666546) (xy 96.805429 -47.630855)
			(xy 96.851279 -47.601389) (xy 96.900856 -47.578747) (xy 96.953151 -47.563392) (xy 97.007099 -47.555636)
			(xy 97.061601 -47.555636) (xy 97.115549 -47.563392) (xy 97.167844 -47.578747) (xy 97.217421 -47.601389)
			(xy 97.263271 -47.630855) (xy 97.304462 -47.666546) (xy 97.340153 -47.707737) (xy 97.369619 -47.753587)
			(xy 97.392261 -47.803164) (xy 97.407616 -47.855459) (xy 97.415372 -47.909407) (xy 97.415858 -47.936658)
			(xy 97.415393 -47.962999) (xy 97.408143 -48.015179) (xy 97.393789 -48.065867) (xy 97.372602 -48.1141)
			(xy 97.344986 -48.158963) (xy 97.311465 -48.199604) (xy 97.272675 -48.23525) (xy 97.251266 -48.250602)
			(xy 97.239438 -48.259295) (xy 97.220997 -48.282119) (xy 97.20981 -48.309246) (xy 97.206801 -48.338435)
			(xy 97.212219 -48.367273) (xy 97.225616 -48.39338) (xy 97.245886 -48.414597) (xy 97.258378 -48.422306)
			(xy 97.282915 -48.437) (xy 97.327673 -48.472602) (xy 97.366617 -48.514485) (xy 97.398872 -48.561712)
			(xy 97.423718 -48.613224) (xy 97.440597 -48.667868) (xy 97.449131 -48.724418) (xy 97.44964 -48.753014)
			(xy 99.168202 -48.753014) (xy 99.172273 -48.697392) (xy 99.184399 -48.642955) (xy 99.204322 -48.590864)
			(xy 99.231618 -48.542229) (xy 99.265704 -48.498086) (xy 99.305853 -48.459377) (xy 99.351211 -48.426926)
			(xy 99.400811 -48.401425) (xy 99.453595 -48.383418) (xy 99.508438 -48.373288) (xy 99.564172 -48.371251)
			(xy 99.619609 -48.377351) (xy 99.673566 -48.391457) (xy 99.724895 -48.413269) (xy 99.772501 -48.442323)
			(xy 99.815369 -48.477998) (xy 99.852586 -48.519535) (xy 99.883359 -48.566048) (xy 99.907031 -48.616545)
			(xy 99.923099 -48.669952) (xy 99.931219 -48.725128) (xy 99.931728 -48.753014) (xy 99.931219 -48.7809)
			(xy 99.923099 -48.836076) (xy 99.920655 -48.8442) (xy 100.18725 -48.8442) (xy 100.191321 -48.788578)
			(xy 100.203447 -48.734141) (xy 100.22337 -48.68205) (xy 100.250666 -48.633415) (xy 100.284752 -48.589272)
			(xy 100.324901 -48.550563) (xy 100.370259 -48.518112) (xy 100.419859 -48.492611) (xy 100.472643 -48.474604)
			(xy 100.527486 -48.464474) (xy 100.58322 -48.462437) (xy 100.638657 -48.468537) (xy 100.692614 -48.482643)
			(xy 100.743943 -48.504455) (xy 100.791549 -48.533509) (xy 100.834417 -48.569184) (xy 100.871634 -48.610721)
			(xy 100.902407 -48.657234) (xy 100.926079 -48.707731) (xy 100.942147 -48.761138) (xy 100.950267 -48.816314)
			(xy 100.950776 -48.8442) (xy 100.950267 -48.872086) (xy 100.943251 -48.919757) (xy 101.214815 -48.919757)
			(xy 101.214815 -48.865243) (xy 101.222574 -48.811283) (xy 101.237933 -48.758977) (xy 101.260581 -48.709389)
			(xy 101.290055 -48.663529) (xy 101.325757 -48.622331) (xy 101.366958 -48.586634) (xy 101.41282 -48.557164)
			(xy 101.46241 -48.534521) (xy 101.514718 -48.519166) (xy 101.568679 -48.511412) (xy 101.595936 -48.510952)
			(xy 101.62573 -48.511532) (xy 101.684594 -48.520788) (xy 101.741302 -48.539085) (xy 101.794476 -48.565977)
			(xy 101.842821 -48.600811) (xy 101.885161 -48.642739) (xy 101.903276 -48.6664) (xy 101.910642 -48.67656)
			(xy 101.932486 -48.687228) (xy 102.04069 -48.684942) (xy 102.06228 -48.673004) (xy 102.069392 -48.66259)
			(xy 102.084629 -48.640618) (xy 102.12031 -48.600795) (xy 102.161199 -48.566341) (xy 102.206497 -48.537932)
			(xy 102.255317 -48.516123) (xy 102.306703 -48.501341) (xy 102.359649 -48.493876) (xy 102.386384 -48.493426)
			(xy 102.386892 -48.493426) (xy 102.401685 -48.49356) (xy 102.431183 -48.49585) (xy 102.44582 -48.497998)
			(xy 102.458012 -48.50003) (xy 102.48138 -48.492156) (xy 102.547674 -48.423322) (xy 102.551769 -48.418876)
			(xy 102.55792 -48.408472) (xy 102.559866 -48.402748) (xy 102.563422 -48.39081) (xy 102.561136 -48.378364)
			(xy 102.557962 -48.36069) (xy 102.554528 -48.324945) (xy 102.554278 -48.30699) (xy 102.554768 -48.279739)
			(xy 102.562526 -48.225792) (xy 102.577882 -48.173498) (xy 102.600523 -48.123922) (xy 102.629989 -48.078072)
			(xy 102.66568 -48.036883) (xy 102.706869 -48.001191) (xy 102.752719 -47.971725) (xy 102.802295 -47.949083)
			(xy 102.854588 -47.933727) (xy 102.908535 -47.925969) (xy 102.935786 -47.925482) (xy 102.963039 -47.925964)
			(xy 103.01699 -47.93372) (xy 103.026997 -47.936658) (xy 134.753096 -47.936658) (xy 134.753582 -47.909407)
			(xy 134.761338 -47.855459) (xy 134.776693 -47.803164) (xy 134.799335 -47.753587) (xy 134.828801 -47.707737)
			(xy 134.864492 -47.666546) (xy 134.905683 -47.630855) (xy 134.951533 -47.601389) (xy 135.00111 -47.578747)
			(xy 135.053405 -47.563392) (xy 135.107353 -47.555636) (xy 135.161855 -47.555636) (xy 135.215803 -47.563392)
			(xy 135.268098 -47.578747) (xy 135.317675 -47.601389) (xy 135.363525 -47.630855) (xy 135.404716 -47.666546)
			(xy 135.440407 -47.707737) (xy 135.469873 -47.753587) (xy 135.492515 -47.803164) (xy 135.50787 -47.855459)
			(xy 135.515626 -47.909407) (xy 135.516112 -47.936658) (xy 135.515667 -47.963) (xy 135.508416 -48.015181)
			(xy 135.49406 -48.065871) (xy 135.47287 -48.114105) (xy 135.445251 -48.158968) (xy 135.411726 -48.199607)
			(xy 135.372931 -48.235252) (xy 135.35152 -48.250602) (xy 135.339699 -48.2593) (xy 135.321266 -48.282126)
			(xy 135.310085 -48.30925) (xy 135.307078 -48.338435) (xy 135.312493 -48.367269) (xy 135.325884 -48.393374)
			(xy 135.346144 -48.414593) (xy 135.358632 -48.422306) (xy 135.383181 -48.436979) (xy 135.427937 -48.472587)
			(xy 135.466878 -48.514475) (xy 135.499131 -48.561705) (xy 135.523975 -48.61322) (xy 135.540852 -48.667865)
			(xy 135.549385 -48.724418) (xy 135.549894 -48.753014) (xy 137.268456 -48.753014) (xy 137.272527 -48.697392)
			(xy 137.284653 -48.642955) (xy 137.304576 -48.590864) (xy 137.331872 -48.542229) (xy 137.365958 -48.498086)
			(xy 137.406107 -48.459377) (xy 137.451465 -48.426926) (xy 137.501065 -48.401425) (xy 137.553849 -48.383418)
			(xy 137.608692 -48.373288) (xy 137.664426 -48.371251) (xy 137.719863 -48.377351) (xy 137.77382 -48.391457)
			(xy 137.825149 -48.413269) (xy 137.872755 -48.442323) (xy 137.915623 -48.477998) (xy 137.95284 -48.519535)
			(xy 137.983613 -48.566048) (xy 138.007285 -48.616545) (xy 138.023353 -48.669952) (xy 138.031473 -48.725128)
			(xy 138.031982 -48.753014) (xy 138.031473 -48.7809) (xy 138.023353 -48.836076) (xy 138.007285 -48.889483)
			(xy 137.993095 -48.919754) (xy 139.315138 -48.919754) (xy 139.315138 -48.865246) (xy 139.322895 -48.811294)
			(xy 139.338251 -48.758994) (xy 139.360894 -48.709413) (xy 139.390362 -48.663558) (xy 139.426057 -48.622364)
			(xy 139.46725 -48.586668) (xy 139.513104 -48.557199) (xy 139.562685 -48.534555) (xy 139.614984 -48.519197)
			(xy 139.668936 -48.511439) (xy 139.69619 -48.510952) (xy 139.725985 -48.511492) (xy 139.784851 -48.520756)
			(xy 139.841561 -48.539061) (xy 139.894734 -48.565961) (xy 139.943078 -48.600802) (xy 139.985416 -48.642736)
			(xy 140.00353 -48.6664) (xy 140.010896 -48.67656) (xy 140.03274 -48.687228) (xy 140.140944 -48.684942)
			(xy 140.162534 -48.673004) (xy 140.169646 -48.66259) (xy 140.184912 -48.64064) (xy 140.220588 -48.600816)
			(xy 140.261473 -48.566361) (xy 140.306766 -48.537949) (xy 140.355581 -48.516136) (xy 140.406962 -48.50135)
			(xy 140.459905 -48.493879) (xy 140.486638 -48.493426) (xy 140.487146 -48.493426) (xy 140.501939 -48.493566)
			(xy 140.531437 -48.495852) (xy 140.546074 -48.497998) (xy 140.558266 -48.50003) (xy 140.581634 -48.492156)
			(xy 140.647928 -48.423322) (xy 140.656077 -48.414095) (xy 140.663146 -48.390546) (xy 140.66139 -48.378364)
			(xy 140.658216 -48.36069) (xy 140.654782 -48.324945) (xy 140.654532 -48.30699) (xy 140.654946 -48.279735)
			(xy 140.662705 -48.22578) (xy 140.678064 -48.173479) (xy 140.700711 -48.123896) (xy 140.730184 -48.078041)
			(xy 140.765883 -48.036847) (xy 140.807081 -48.001154) (xy 140.85294 -47.971687) (xy 140.902526 -47.949047)
			(xy 140.954829 -47.933694) (xy 141.008785 -47.925942) (xy 141.03604 -47.925482) (xy 141.063289 -47.925991)
			(xy 141.117231 -47.933752) (xy 141.127125 -47.936658) (xy 160.753044 -47.936658) (xy 160.75353 -47.909407)
			(xy 160.761286 -47.855459) (xy 160.776641 -47.803164) (xy 160.799283 -47.753587) (xy 160.828749 -47.707737)
			(xy 160.86444 -47.666546) (xy 160.905631 -47.630855) (xy 160.951481 -47.601389) (xy 161.001058 -47.578747)
			(xy 161.053353 -47.563392) (xy 161.107301 -47.555636) (xy 161.161803 -47.555636) (xy 161.215751 -47.563392)
			(xy 161.268046 -47.578747) (xy 161.317623 -47.601389) (xy 161.363473 -47.630855) (xy 161.404664 -47.666546)
			(xy 161.440355 -47.707737) (xy 161.469821 -47.753587) (xy 161.492463 -47.803164) (xy 161.507818 -47.855459)
			(xy 161.515574 -47.909407) (xy 161.51606 -47.936658) (xy 161.515595 -47.962999) (xy 161.508345 -48.015179)
			(xy 161.49399 -48.065867) (xy 161.472804 -48.1141) (xy 161.445188 -48.158963) (xy 161.411667 -48.199604)
			(xy 161.372877 -48.23525) (xy 161.351468 -48.250602) (xy 161.33964 -48.259295) (xy 161.321198 -48.282119)
			(xy 161.310011 -48.309246) (xy 161.307002 -48.338435) (xy 161.31242 -48.367273) (xy 161.325817 -48.39338)
			(xy 161.346088 -48.414597) (xy 161.35858 -48.422306) (xy 161.383117 -48.436999) (xy 161.427876 -48.472601)
			(xy 161.466819 -48.514485) (xy 161.499075 -48.561712) (xy 161.52392 -48.613224) (xy 161.540799 -48.667868)
			(xy 161.549333 -48.724418) (xy 161.549842 -48.753014) (xy 163.268404 -48.753014) (xy 163.272475 -48.697392)
			(xy 163.284601 -48.642955) (xy 163.304524 -48.590864) (xy 163.33182 -48.542229) (xy 163.365906 -48.498086)
			(xy 163.406055 -48.459377) (xy 163.451413 -48.426926) (xy 163.501013 -48.401425) (xy 163.553797 -48.383418)
			(xy 163.60864 -48.373288) (xy 163.664374 -48.371251) (xy 163.719811 -48.377351) (xy 163.773768 -48.391457)
			(xy 163.825097 -48.413269) (xy 163.872703 -48.442323) (xy 163.915571 -48.477998) (xy 163.952788 -48.519535)
			(xy 163.983561 -48.566048) (xy 164.007233 -48.616545) (xy 164.023301 -48.669952) (xy 164.031421 -48.725128)
			(xy 164.03193 -48.753014) (xy 164.031421 -48.7809) (xy 164.023301 -48.836076) (xy 164.007233 -48.889483)
			(xy 163.993041 -48.919757) (xy 165.315015 -48.919757) (xy 165.315015 -48.865243) (xy 165.322774 -48.811283)
			(xy 165.338133 -48.758976) (xy 165.360781 -48.709388) (xy 165.390256 -48.663528) (xy 165.425957 -48.62233)
			(xy 165.467159 -48.586633) (xy 165.513022 -48.557163) (xy 165.562612 -48.53452) (xy 165.61492 -48.519166)
			(xy 165.66888 -48.511412) (xy 165.696138 -48.510952) (xy 165.725932 -48.51153) (xy 165.784796 -48.520786)
			(xy 165.841504 -48.539084) (xy 165.894678 -48.565977) (xy 165.943023 -48.600811) (xy 165.985363 -48.642739)
			(xy 166.003478 -48.6664) (xy 166.010844 -48.67656) (xy 166.032688 -48.687228) (xy 166.140892 -48.684942)
			(xy 166.162482 -48.673004) (xy 166.169594 -48.66259) (xy 166.18483 -48.640617) (xy 166.220511 -48.600794)
			(xy 166.2614 -48.56634) (xy 166.306699 -48.537931) (xy 166.355519 -48.516122) (xy 166.406905 -48.501341)
			(xy 166.459851 -48.493876) (xy 166.486586 -48.493426) (xy 166.487094 -48.493426) (xy 166.501887 -48.49356)
			(xy 166.531385 -48.49585) (xy 166.546022 -48.497998) (xy 166.558214 -48.50003) (xy 166.581582 -48.492156)
			(xy 166.647876 -48.423322) (xy 166.65603 -48.4141) (xy 166.663093 -48.390547) (xy 166.661338 -48.378364)
			(xy 166.658164 -48.36069) (xy 166.65473 -48.324945) (xy 166.65448 -48.30699) (xy 166.654968 -48.279739)
			(xy 166.662726 -48.225792) (xy 166.678082 -48.173498) (xy 166.700723 -48.123922) (xy 166.730189 -48.078072)
			(xy 166.765881 -48.036882) (xy 166.80707 -48.001191) (xy 166.85292 -47.971724) (xy 166.902496 -47.949083)
			(xy 166.95479 -47.933726) (xy 167.008737 -47.925969) (xy 167.035988 -47.925482) (xy 167.063241 -47.925964)
			(xy 167.117192 -47.93372) (xy 167.127199 -47.936658) (xy 186.752992 -47.936658) (xy 186.753478 -47.909407)
			(xy 186.761234 -47.855459) (xy 186.776589 -47.803164) (xy 186.799231 -47.753587) (xy 186.828697 -47.707737)
			(xy 186.864388 -47.666546) (xy 186.905579 -47.630855) (xy 186.951429 -47.601389) (xy 187.001006 -47.578747)
			(xy 187.053301 -47.563392) (xy 187.107249 -47.555636) (xy 187.161751 -47.555636) (xy 187.215699 -47.563392)
			(xy 187.267994 -47.578747) (xy 187.317571 -47.601389) (xy 187.363421 -47.630855) (xy 187.404612 -47.666546)
			(xy 187.440303 -47.707737) (xy 187.469769 -47.753587) (xy 187.492411 -47.803164) (xy 187.507766 -47.855459)
			(xy 187.515522 -47.909407) (xy 187.516008 -47.936658) (xy 187.515565 -47.963) (xy 187.508314 -48.015182)
			(xy 187.493957 -48.065871) (xy 187.472768 -48.114105) (xy 187.445148 -48.158968) (xy 187.411622 -48.199608)
			(xy 187.372828 -48.235252) (xy 187.351416 -48.250602) (xy 187.339595 -48.259301) (xy 187.321164 -48.282126)
			(xy 187.309983 -48.309251) (xy 187.306976 -48.338435) (xy 187.312391 -48.367269) (xy 187.325781 -48.393373)
			(xy 187.346041 -48.414593) (xy 187.358528 -48.422306) (xy 187.383076 -48.436981) (xy 187.427832 -48.472588)
			(xy 187.466773 -48.514476) (xy 187.499027 -48.561706) (xy 187.52387 -48.61322) (xy 187.540748 -48.667866)
			(xy 187.549281 -48.724418) (xy 187.54979 -48.753014) (xy 189.268352 -48.753014) (xy 189.272423 -48.697392)
			(xy 189.284549 -48.642955) (xy 189.304472 -48.590864) (xy 189.331768 -48.542229) (xy 189.365854 -48.498086)
			(xy 189.406003 -48.459377) (xy 189.451361 -48.426926) (xy 189.500961 -48.401425) (xy 189.553745 -48.383418)
			(xy 189.608588 -48.373288) (xy 189.664322 -48.371251) (xy 189.719759 -48.377351) (xy 189.773716 -48.391457)
			(xy 189.825045 -48.413269) (xy 189.872651 -48.442323) (xy 189.915519 -48.477998) (xy 189.952736 -48.519535)
			(xy 189.983509 -48.566048) (xy 190.007181 -48.616545) (xy 190.023249 -48.669952) (xy 190.031369 -48.725128)
			(xy 190.031878 -48.753014) (xy 190.031369 -48.7809) (xy 190.023249 -48.836076) (xy 190.020805 -48.8442)
			(xy 190.2874 -48.8442) (xy 190.291471 -48.788578) (xy 190.303597 -48.734141) (xy 190.32352 -48.68205)
			(xy 190.350816 -48.633415) (xy 190.384902 -48.589272) (xy 190.425051 -48.550563) (xy 190.470409 -48.518112)
			(xy 190.520009 -48.492611) (xy 190.572793 -48.474604) (xy 190.627636 -48.464474) (xy 190.68337 -48.462437)
			(xy 190.738807 -48.468537) (xy 190.792764 -48.482643) (xy 190.844093 -48.504455) (xy 190.891699 -48.533509)
			(xy 190.934567 -48.569184) (xy 190.971784 -48.610721) (xy 191.002557 -48.657234) (xy 191.026229 -48.707731)
			(xy 191.042297 -48.761138) (xy 191.050417 -48.816314) (xy 191.050926 -48.8442) (xy 191.050417 -48.872086)
			(xy 191.043402 -48.919753) (xy 191.315038 -48.919753) (xy 191.315038 -48.865247) (xy 191.322795 -48.811294)
			(xy 191.338151 -48.758995) (xy 191.360793 -48.709414) (xy 191.390261 -48.663559) (xy 191.425955 -48.622365)
			(xy 191.467148 -48.58667) (xy 191.513001 -48.5572) (xy 191.562582 -48.534556) (xy 191.614881 -48.519198)
			(xy 191.668833 -48.511439) (xy 191.696086 -48.510952) (xy 191.725881 -48.511495) (xy 191.784747 -48.520758)
			(xy 191.841456 -48.539063) (xy 191.89463 -48.565962) (xy 191.942974 -48.600802) (xy 191.985312 -48.642736)
			(xy 192.003426 -48.6664) (xy 192.010792 -48.67656) (xy 192.032636 -48.687228) (xy 192.14084 -48.684942)
			(xy 192.16243 -48.673004) (xy 192.169542 -48.66259) (xy 192.184811 -48.640641) (xy 192.220486 -48.600817)
			(xy 192.26137 -48.566362) (xy 192.306663 -48.53795) (xy 192.355478 -48.516137) (xy 192.406859 -48.50135)
			(xy 192.459801 -48.493879) (xy 192.486534 -48.493426) (xy 192.487042 -48.493426) (xy 192.501835 -48.493566)
			(xy 192.531333 -48.495852) (xy 192.54597 -48.497998) (xy 192.558162 -48.50003) (xy 192.58153 -48.492156)
			(xy 192.647824 -48.423322) (xy 192.655972 -48.414095) (xy 192.663041 -48.390546) (xy 192.661286 -48.378364)
			(xy 192.658112 -48.36069) (xy 192.654678 -48.324945) (xy 192.654428 -48.30699) (xy 192.654846 -48.279735)
			(xy 192.662605 -48.225781) (xy 192.677964 -48.17348) (xy 192.70061 -48.123897) (xy 192.730083 -48.078042)
			(xy 192.765781 -48.036849) (xy 192.806979 -48.001155) (xy 192.852838 -47.971688) (xy 192.902423 -47.949048)
			(xy 192.954726 -47.933695) (xy 193.008681 -47.925942) (xy 193.035936 -47.925482) (xy 193.063185 -47.925991)
			(xy 193.117127 -47.933751) (xy 193.127024 -47.936658) (xy 212.75294 -47.936658) (xy 212.753426 -47.909407)
			(xy 212.761182 -47.855459) (xy 212.776537 -47.803164) (xy 212.799179 -47.753587) (xy 212.828645 -47.707737)
			(xy 212.864336 -47.666546) (xy 212.905527 -47.630855) (xy 212.951377 -47.601389) (xy 213.000954 -47.578747)
			(xy 213.053249 -47.563392) (xy 213.107197 -47.555636) (xy 213.161699 -47.555636) (xy 213.215647 -47.563392)
			(xy 213.267942 -47.578747) (xy 213.317519 -47.601389) (xy 213.363369 -47.630855) (xy 213.40456 -47.666546)
			(xy 213.440251 -47.707737) (xy 213.469717 -47.753587) (xy 213.492359 -47.803164) (xy 213.507714 -47.855459)
			(xy 213.51547 -47.909407) (xy 213.515705 -47.922557) (xy 234.624511 -47.922557) (xy 234.624511 -47.868043)
			(xy 234.63227 -47.814083) (xy 234.647629 -47.761777) (xy 234.670276 -47.71219) (xy 234.69975 -47.66633)
			(xy 234.73545 -47.625132) (xy 234.776651 -47.589434) (xy 234.822513 -47.559963) (xy 234.872102 -47.53732)
			(xy 234.924409 -47.521964) (xy 234.978369 -47.514209) (xy 235.005626 -47.513748) (xy 235.032997 -47.514187)
			(xy 235.087178 -47.52201) (xy 235.139682 -47.537504) (xy 235.189428 -47.560352) (xy 235.235394 -47.590083)
			(xy 235.256324 -47.607728) (xy 235.256578 -47.607982) (xy 235.263668 -47.613563) (xy 235.280582 -47.619813)
			(xy 235.289598 -47.620174) (xy 235.356654 -47.620174) (xy 235.365669 -47.619801) (xy 235.382587 -47.613565)
			(xy 235.389674 -47.607982) (xy 235.390182 -47.607474) (xy 235.4111 -47.589872) (xy 235.45704 -47.560236)
			(xy 235.50674 -47.537462) (xy 235.559181 -47.522016) (xy 235.613291 -47.514215) (xy 235.640626 -47.513748)
			(xy 235.658969 -47.513987) (xy 235.695482 -47.517546) (xy 235.713524 -47.52086) (xy 235.713778 -47.52086)
			(xy 235.724281 -47.522257) (xy 235.744881 -47.517401) (xy 235.753656 -47.511462) (xy 235.822998 -47.459138)
			(xy 235.833158 -47.440342) (xy 235.834174 -47.42942) (xy 235.837018 -47.40113) (xy 235.850067 -47.345791)
			(xy 235.871174 -47.292997) (xy 235.899874 -47.243916) (xy 235.935533 -47.199631) (xy 235.956094 -47.179992)
			(xy 235.963537 -47.172422) (xy 235.972061 -47.153003) (xy 235.972604 -47.1424) (xy 235.972604 -47.068232)
			(xy 235.972222 -47.057597) (xy 235.963653 -47.038133) (xy 235.956094 -47.03064) (xy 235.937048 -47.012502)
			(xy 235.903591 -46.971922) (xy 235.87603 -46.927127) (xy 235.854889 -46.878969) (xy 235.84057 -46.828362)
			(xy 235.833343 -46.776267) (xy 235.832904 -46.74997) (xy 235.832904 -46.749716) (xy 235.83339 -46.722465)
			(xy 235.841146 -46.668517) (xy 235.856501 -46.616222) (xy 235.879143 -46.566645) (xy 235.908609 -46.520795)
			(xy 235.9443 -46.479604) (xy 235.985491 -46.443913) (xy 236.031341 -46.414447) (xy 236.080918 -46.391805)
			(xy 236.133213 -46.37645) (xy 236.187161 -46.368694) (xy 236.241663 -46.368694) (xy 236.295611 -46.37645)
			(xy 236.347906 -46.391805) (xy 236.397483 -46.414447) (xy 236.443333 -46.443913) (xy 236.484524 -46.479604)
			(xy 236.520215 -46.520795) (xy 236.549681 -46.566645) (xy 236.572323 -46.616222) (xy 236.587678 -46.668517)
			(xy 236.595434 -46.722465) (xy 236.59592 -46.749716) (xy 236.59592 -46.74997) (xy 236.595435 -46.776264)
			(xy 236.588194 -46.828351) (xy 236.573873 -46.878952) (xy 236.552742 -46.927108) (xy 236.525202 -46.971908)
			(xy 236.491774 -47.012505) (xy 236.47273 -47.03064) (xy 236.465277 -47.038202) (xy 236.456757 -47.057627)
			(xy 236.45622 -47.068232) (xy 236.45622 -47.1424) (xy 236.456632 -47.153032) (xy 236.465179 -47.172497)
			(xy 236.47273 -47.179992) (xy 236.491777 -47.198129) (xy 236.525237 -47.238708) (xy 236.5528 -47.283502)
			(xy 236.573941 -47.33166) (xy 236.588259 -47.382268) (xy 236.595483 -47.434365) (xy 236.59592 -47.460662)
			(xy 236.59592 -47.460916) (xy 236.595627 -47.477426) (xy 239.502188 -47.477426) (xy 239.502649 -47.450092)
			(xy 239.51046 -47.395985) (xy 239.525912 -47.343546) (xy 239.548689 -47.293848) (xy 239.578324 -47.247909)
			(xy 239.595914 -47.226982) (xy 239.596168 -47.226728) (xy 239.596422 -47.226474) (xy 239.601986 -47.219372)
			(xy 239.608246 -47.202467) (xy 239.608614 -47.193454) (xy 239.608614 -47.126398) (xy 239.608255 -47.117381)
			(xy 239.602008 -47.100465) (xy 239.596422 -47.093378) (xy 239.596168 -47.093124) (xy 239.595914 -47.09287)
			(xy 239.578343 -47.071927) (xy 239.548701 -47.025995) (xy 239.52592 -46.976302) (xy 239.510467 -46.923865)
			(xy 239.502659 -46.869759) (xy 239.502188 -46.842426) (xy 239.502679 -46.815174) (xy 239.510433 -46.761224)
			(xy 239.525785 -46.708927) (xy 239.548425 -46.659347) (xy 239.577889 -46.613494) (xy 239.61358 -46.572301)
			(xy 239.65477 -46.536607) (xy 239.700621 -46.507139) (xy 239.750199 -46.484496) (xy 239.802495 -46.469139)
			(xy 239.856444 -46.461382) (xy 239.883696 -46.460918) (xy 239.912613 -46.461433) (xy 239.969785 -46.470161)
			(xy 240.024984 -46.48742) (xy 240.076946 -46.512812) (xy 240.12448 -46.545756) (xy 240.166496 -46.585498)
			(xy 240.184686 -46.607984) (xy 240.190969 -46.615369) (xy 240.207684 -46.625164) (xy 240.217198 -46.627034)
			(xy 240.224818 -46.627542) (xy 240.304574 -46.627542) (xy 240.312194 -46.627034) (xy 240.321711 -46.625178)
			(xy 240.338424 -46.615372) (xy 240.344706 -46.607984) (xy 240.36289 -46.585494) (xy 240.404911 -46.54576)
			(xy 240.452448 -46.512822) (xy 240.504411 -46.487435) (xy 240.559609 -46.47018) (xy 240.61678 -46.461452)
			(xy 240.645696 -46.460918) (xy 240.67295 -46.461359) (xy 240.726903 -46.469116) (xy 240.779203 -46.484473)
			(xy 240.828785 -46.507117) (xy 240.874639 -46.536587) (xy 240.915832 -46.572283) (xy 240.951526 -46.613479)
			(xy 240.980994 -46.659335) (xy 241.003635 -46.708918) (xy 241.018988 -46.761219) (xy 241.026742 -46.815172)
			(xy 241.027204 -46.842426) (xy 241.027204 -46.84268) (xy 241.026731 -46.868974) (xy 241.019488 -46.921062)
			(xy 241.005165 -46.971663) (xy 240.984032 -47.01982) (xy 240.95649 -47.064619) (xy 240.923059 -47.105215)
			(xy 240.904014 -47.12335) (xy 240.896554 -47.130906) (xy 240.888039 -47.150336) (xy 240.887504 -47.160942)
			(xy 240.887504 -47.23511) (xy 240.887915 -47.245742) (xy 240.896463 -47.265206) (xy 240.904014 -47.272702)
			(xy 240.923082 -47.290818) (xy 240.956537 -47.331403) (xy 240.984095 -47.376202) (xy 241.005231 -47.424364)
			(xy 241.019546 -47.474975) (xy 241.026767 -47.527074) (xy 241.027204 -47.553372) (xy 241.027204 -47.553626)
			(xy 241.026746 -47.580878) (xy 241.018986 -47.634827) (xy 241.003628 -47.687123) (xy 240.980983 -47.7367)
			(xy 240.951514 -47.782551) (xy 240.915819 -47.823741) (xy 240.874627 -47.859432) (xy 240.828774 -47.888898)
			(xy 240.779194 -47.911538) (xy 240.726898 -47.926893) (xy 240.672948 -47.934649) (xy 240.645696 -47.935134)
			(xy 240.618029 -47.934655) (xy 240.563277 -47.926654) (xy 240.510254 -47.910834) (xy 240.460068 -47.887526)
			(xy 240.413773 -47.857219) (xy 240.372336 -47.820547) (xy 240.336627 -47.778278) (xy 240.321592 -47.755048)
			(xy 240.321338 -47.754794) (xy 240.314706 -47.74524) (xy 240.294987 -47.732947) (xy 240.283492 -47.731172)
			(xy 240.203482 -47.723298) (xy 240.191782 -47.72265) (xy 240.169811 -47.730719) (xy 240.161318 -47.738792)
			(xy 240.161318 -47.739046) (xy 240.143201 -47.757591) (xy 240.102878 -47.790175) (xy 240.058511 -47.816994)
			(xy 240.01092 -47.837553) (xy 239.960982 -47.851474) (xy 239.909617 -47.858499) (xy 239.883696 -47.858934)
			(xy 239.856446 -47.858426) (xy 239.8025 -47.85067) (xy 239.750208 -47.835315) (xy 239.700632 -47.812676)
			(xy 239.654783 -47.783211) (xy 239.613593 -47.747522) (xy 239.577902 -47.706335) (xy 239.548435 -47.660487)
			(xy 239.525792 -47.610913) (xy 239.510435 -47.558621) (xy 239.502676 -47.504676) (xy 239.502188 -47.477426)
			(xy 236.595627 -47.477426) (xy 236.595437 -47.488167) (xy 236.587679 -47.542114) (xy 236.572322 -47.594408)
			(xy 236.54968 -47.643985) (xy 236.520213 -47.689835) (xy 236.484522 -47.731024) (xy 236.443331 -47.766716)
			(xy 236.397481 -47.796182) (xy 236.347905 -47.818824) (xy 236.29561 -47.83418) (xy 236.241663 -47.841937)
			(xy 236.214412 -47.842424) (xy 236.196069 -47.842193) (xy 236.159556 -47.838629) (xy 236.141514 -47.835312)
			(xy 236.14126 -47.835312) (xy 236.130755 -47.833943) (xy 236.110159 -47.838781) (xy 236.101382 -47.84471)
			(xy 236.03204 -47.897034) (xy 236.02188 -47.91583) (xy 236.020864 -47.926752) (xy 236.019856 -47.936658)
			(xy 250.85294 -47.936658) (xy 250.853426 -47.909407) (xy 250.861182 -47.855459) (xy 250.876537 -47.803164)
			(xy 250.899179 -47.753587) (xy 250.928645 -47.707737) (xy 250.964336 -47.666546) (xy 251.005527 -47.630855)
			(xy 251.051377 -47.601389) (xy 251.100954 -47.578747) (xy 251.153249 -47.563392) (xy 251.207197 -47.555636)
			(xy 251.261699 -47.555636) (xy 251.315647 -47.563392) (xy 251.367942 -47.578747) (xy 251.417519 -47.601389)
			(xy 251.463369 -47.630855) (xy 251.50456 -47.666546) (xy 251.540251 -47.707737) (xy 251.569717 -47.753587)
			(xy 251.592359 -47.803164) (xy 251.607714 -47.855459) (xy 251.61547 -47.909407) (xy 251.615956 -47.936658)
			(xy 251.615492 -47.962999) (xy 251.608242 -48.015179) (xy 251.593888 -48.065867) (xy 251.572701 -48.1141)
			(xy 251.545085 -48.158963) (xy 251.511563 -48.199604) (xy 251.472773 -48.23525) (xy 251.451364 -48.250602)
			(xy 251.439537 -48.259295) (xy 251.421096 -48.282119) (xy 251.409908 -48.309246) (xy 251.4069 -48.338435)
			(xy 251.412317 -48.367273) (xy 251.425715 -48.393379) (xy 251.445984 -48.414596) (xy 251.458476 -48.422306)
			(xy 251.483012 -48.437) (xy 251.527771 -48.472602) (xy 251.566714 -48.514485) (xy 251.59897 -48.561712)
			(xy 251.623816 -48.613224) (xy 251.640695 -48.667868) (xy 251.649229 -48.724418) (xy 251.649738 -48.753014)
			(xy 253.3683 -48.753014) (xy 253.372371 -48.697392) (xy 253.384497 -48.642955) (xy 253.40442 -48.590864)
			(xy 253.431716 -48.542229) (xy 253.465802 -48.498086) (xy 253.505951 -48.459377) (xy 253.551309 -48.426926)
			(xy 253.600909 -48.401425) (xy 253.653693 -48.383418) (xy 253.708536 -48.373288) (xy 253.76427 -48.371251)
			(xy 253.819707 -48.377351) (xy 253.873664 -48.391457) (xy 253.924993 -48.413269) (xy 253.972599 -48.442323)
			(xy 254.015467 -48.477998) (xy 254.052684 -48.519535) (xy 254.083457 -48.566048) (xy 254.107129 -48.616545)
			(xy 254.123197 -48.669952) (xy 254.131317 -48.725128) (xy 254.131826 -48.753014) (xy 254.131317 -48.7809)
			(xy 254.123197 -48.836076) (xy 254.120753 -48.8442) (xy 254.387348 -48.8442) (xy 254.391419 -48.788578)
			(xy 254.403545 -48.734141) (xy 254.423468 -48.68205) (xy 254.450764 -48.633415) (xy 254.48485 -48.589272)
			(xy 254.524999 -48.550563) (xy 254.570357 -48.518112) (xy 254.619957 -48.492611) (xy 254.672741 -48.474604)
			(xy 254.727584 -48.464474) (xy 254.783318 -48.462437) (xy 254.838755 -48.468537) (xy 254.892712 -48.482643)
			(xy 254.944041 -48.504455) (xy 254.991647 -48.533509) (xy 255.034515 -48.569184) (xy 255.071732 -48.610721)
			(xy 255.102505 -48.657234) (xy 255.126177 -48.707731) (xy 255.142245 -48.761138) (xy 255.150365 -48.816314)
			(xy 255.150874 -48.8442) (xy 255.150365 -48.872086) (xy 255.143349 -48.919757) (xy 255.414915 -48.919757)
			(xy 255.414915 -48.865243) (xy 255.422674 -48.811283) (xy 255.438033 -48.758977) (xy 255.46068 -48.709389)
			(xy 255.490155 -48.66353) (xy 255.525856 -48.622332) (xy 255.567057 -48.586634) (xy 255.612919 -48.557164)
			(xy 255.662509 -48.534521) (xy 255.714816 -48.519166) (xy 255.768777 -48.511413) (xy 255.796034 -48.510952)
			(xy 255.825828 -48.511533) (xy 255.884692 -48.520789) (xy 255.9414 -48.539085) (xy 255.994574 -48.565978)
			(xy 256.042919 -48.600811) (xy 256.085259 -48.642739) (xy 256.103374 -48.6664) (xy 256.11074 -48.67656)
			(xy 256.132584 -48.687228) (xy 256.240788 -48.684942) (xy 256.262378 -48.673004) (xy 256.26949 -48.66259)
			(xy 256.284728 -48.640619) (xy 256.320409 -48.600796) (xy 256.361298 -48.566342) (xy 256.406596 -48.537932)
			(xy 256.455416 -48.516123) (xy 256.506801 -48.501341) (xy 256.559747 -48.493876) (xy 256.586482 -48.493426)
			(xy 256.58699 -48.493426) (xy 256.601783 -48.49356) (xy 256.631281 -48.49585) (xy 256.645918 -48.497998)
			(xy 256.65811 -48.50003) (xy 256.681478 -48.492156) (xy 256.747772 -48.423322) (xy 256.755926 -48.414099)
			(xy 256.762989 -48.390547) (xy 256.761234 -48.378364) (xy 256.75806 -48.36069) (xy 256.754626 -48.324945)
			(xy 256.754376 -48.30699) (xy 256.754868 -48.279739) (xy 256.762626 -48.225793) (xy 256.777981 -48.173499)
			(xy 256.800623 -48.123923) (xy 256.830088 -48.078073) (xy 256.865779 -48.036883) (xy 256.906968 -48.001192)
			(xy 256.952817 -47.971726) (xy 257.002393 -47.949084) (xy 257.054687 -47.933727) (xy 257.108633 -47.925969)
			(xy 257.135884 -47.925482) (xy 257.163137 -47.925964) (xy 257.217088 -47.933719) (xy 257.227099 -47.936658)
			(xy 276.852888 -47.936658) (xy 276.853374 -47.909407) (xy 276.86113 -47.855459) (xy 276.876485 -47.803164)
			(xy 276.899127 -47.753587) (xy 276.928593 -47.707737) (xy 276.964284 -47.666546) (xy 277.005475 -47.630855)
			(xy 277.051325 -47.601389) (xy 277.100902 -47.578747) (xy 277.153197 -47.563392) (xy 277.207145 -47.555636)
			(xy 277.261647 -47.555636) (xy 277.315595 -47.563392) (xy 277.36789 -47.578747) (xy 277.417467 -47.601389)
			(xy 277.463317 -47.630855) (xy 277.504508 -47.666546) (xy 277.540199 -47.707737) (xy 277.569665 -47.753587)
			(xy 277.592307 -47.803164) (xy 277.607662 -47.855459) (xy 277.615418 -47.909407) (xy 277.615904 -47.936658)
			(xy 277.615463 -47.963) (xy 277.608211 -48.015182) (xy 277.593854 -48.065871) (xy 277.572665 -48.114106)
			(xy 277.545045 -48.158969) (xy 277.511519 -48.199608) (xy 277.472724 -48.235252) (xy 277.451312 -48.250602)
			(xy 277.439492 -48.259301) (xy 277.421061 -48.282127) (xy 277.409881 -48.309251) (xy 277.406874 -48.338435)
			(xy 277.412289 -48.367268) (xy 277.425678 -48.393373) (xy 277.445937 -48.414593) (xy 277.458424 -48.422306)
			(xy 277.482971 -48.436982) (xy 277.527727 -48.472589) (xy 277.566669 -48.514476) (xy 277.598922 -48.561706)
			(xy 277.623766 -48.613221) (xy 277.640644 -48.667866) (xy 277.649177 -48.724418) (xy 277.649686 -48.753014)
			(xy 279.368248 -48.753014) (xy 279.372319 -48.697392) (xy 279.384445 -48.642955) (xy 279.404368 -48.590864)
			(xy 279.431664 -48.542229) (xy 279.46575 -48.498086) (xy 279.505899 -48.459377) (xy 279.551257 -48.426926)
			(xy 279.600857 -48.401425) (xy 279.653641 -48.383418) (xy 279.708484 -48.373288) (xy 279.764218 -48.371251)
			(xy 279.819655 -48.377351) (xy 279.873612 -48.391457) (xy 279.924941 -48.413269) (xy 279.972547 -48.442323)
			(xy 280.015415 -48.477998) (xy 280.052632 -48.519535) (xy 280.083405 -48.566048) (xy 280.107077 -48.616545)
			(xy 280.123145 -48.669952) (xy 280.131265 -48.725128) (xy 280.131774 -48.753014) (xy 280.131265 -48.7809)
			(xy 280.123145 -48.836076) (xy 280.107077 -48.889483) (xy 280.092887 -48.919753) (xy 281.414938 -48.919753)
			(xy 281.414938 -48.865247) (xy 281.422695 -48.811295) (xy 281.438051 -48.758996) (xy 281.460693 -48.709415)
			(xy 281.49016 -48.663561) (xy 281.525854 -48.622366) (xy 281.567046 -48.586671) (xy 281.612899 -48.557201)
			(xy 281.662479 -48.534557) (xy 281.714777 -48.519199) (xy 281.768729 -48.511439) (xy 281.795982 -48.510952)
			(xy 281.825777 -48.511498) (xy 281.884643 -48.520761) (xy 281.941352 -48.539064) (xy 281.994525 -48.565963)
			(xy 282.04287 -48.600803) (xy 282.085208 -48.642736) (xy 282.103322 -48.6664) (xy 282.110688 -48.67656)
			(xy 282.132532 -48.687228) (xy 282.240736 -48.684942) (xy 282.262326 -48.673004) (xy 282.269438 -48.66259)
			(xy 282.28471 -48.640643) (xy 282.320384 -48.600819) (xy 282.361268 -48.566364) (xy 282.40656 -48.537952)
			(xy 282.455374 -48.516138) (xy 282.506755 -48.501351) (xy 282.559697 -48.49388) (xy 282.58643 -48.493426)
			(xy 282.586938 -48.493426) (xy 282.601731 -48.493567) (xy 282.631229 -48.495852) (xy 282.645866 -48.497998)
			(xy 282.658058 -48.50003) (xy 282.681426 -48.492156) (xy 282.74772 -48.423322) (xy 282.755868 -48.414095)
			(xy 282.762937 -48.390546) (xy 282.761182 -48.378364) (xy 282.758008 -48.36069) (xy 282.754574 -48.324945)
			(xy 282.754324 -48.30699) (xy 282.754746 -48.279735) (xy 282.762505 -48.225781) (xy 282.777864 -48.173481)
			(xy 282.80051 -48.123898) (xy 282.829982 -48.078044) (xy 282.86568 -48.03685) (xy 282.906877 -48.001157)
			(xy 282.952735 -47.97169) (xy 283.00232 -47.949049) (xy 283.054622 -47.933696) (xy 283.108577 -47.925943)
			(xy 283.135832 -47.925482) (xy 283.163081 -47.92599) (xy 283.217024 -47.93375) (xy 283.226925 -47.936658)
			(xy 302.852836 -47.936658) (xy 302.853322 -47.909407) (xy 302.861078 -47.855459) (xy 302.876433 -47.803164)
			(xy 302.899075 -47.753587) (xy 302.928541 -47.707737) (xy 302.964232 -47.666546) (xy 303.005423 -47.630855)
			(xy 303.051273 -47.601389) (xy 303.10085 -47.578747) (xy 303.153145 -47.563392) (xy 303.207093 -47.555636)
			(xy 303.261595 -47.555636) (xy 303.315543 -47.563392) (xy 303.367838 -47.578747) (xy 303.417415 -47.601389)
			(xy 303.463265 -47.630855) (xy 303.504456 -47.666546) (xy 303.540147 -47.707737) (xy 303.569613 -47.753587)
			(xy 303.592255 -47.803164) (xy 303.60761 -47.855459) (xy 303.615366 -47.909407) (xy 303.615852 -47.936658)
			(xy 303.61539 -47.962999) (xy 303.60814 -48.015179) (xy 303.593785 -48.065867) (xy 303.572598 -48.114101)
			(xy 303.544982 -48.158964) (xy 303.51146 -48.199604) (xy 303.472669 -48.235251) (xy 303.45126 -48.250602)
			(xy 303.439433 -48.259296) (xy 303.420993 -48.28212) (xy 303.409806 -48.309247) (xy 303.406798 -48.338435)
			(xy 303.412215 -48.367273) (xy 303.425612 -48.393379) (xy 303.44588 -48.414596) (xy 303.458372 -48.422306)
			(xy 303.482907 -48.437002) (xy 303.527666 -48.472603) (xy 303.56661 -48.514486) (xy 303.598866 -48.561713)
			(xy 303.623712 -48.613225) (xy 303.640591 -48.667868) (xy 303.649125 -48.724419) (xy 303.649634 -48.753014)
			(xy 305.368196 -48.753014) (xy 305.372267 -48.697392) (xy 305.384393 -48.642955) (xy 305.404316 -48.590864)
			(xy 305.431612 -48.542229) (xy 305.465698 -48.498086) (xy 305.505847 -48.459377) (xy 305.551205 -48.426926)
			(xy 305.600805 -48.401425) (xy 305.653589 -48.383418) (xy 305.708432 -48.373288) (xy 305.764166 -48.371251)
			(xy 305.819603 -48.377351) (xy 305.87356 -48.391457) (xy 305.924889 -48.413269) (xy 305.972495 -48.442323)
			(xy 306.015363 -48.477998) (xy 306.05258 -48.519535) (xy 306.083353 -48.566048) (xy 306.107025 -48.616545)
			(xy 306.123093 -48.669952) (xy 306.131213 -48.725128) (xy 306.131722 -48.753014) (xy 306.131213 -48.7809)
			(xy 306.123093 -48.836076) (xy 306.120649 -48.8442) (xy 306.387244 -48.8442) (xy 306.391315 -48.788578)
			(xy 306.403441 -48.734141) (xy 306.423364 -48.68205) (xy 306.45066 -48.633415) (xy 306.484746 -48.589272)
			(xy 306.524895 -48.550563) (xy 306.570253 -48.518112) (xy 306.619853 -48.492611) (xy 306.672637 -48.474604)
			(xy 306.72748 -48.464474) (xy 306.783214 -48.462437) (xy 306.838651 -48.468537) (xy 306.892608 -48.482643)
			(xy 306.943937 -48.504455) (xy 306.991543 -48.533509) (xy 307.034411 -48.569184) (xy 307.071628 -48.610721)
			(xy 307.102401 -48.657234) (xy 307.126073 -48.707731) (xy 307.142141 -48.761138) (xy 307.150261 -48.816314)
			(xy 307.15077 -48.8442) (xy 307.150261 -48.872086) (xy 307.143245 -48.919757) (xy 307.414815 -48.919757)
			(xy 307.414815 -48.865243) (xy 307.422574 -48.811284) (xy 307.437933 -48.758978) (xy 307.46058 -48.70939)
			(xy 307.490054 -48.663531) (xy 307.525754 -48.622333) (xy 307.566955 -48.586636) (xy 307.612817 -48.557165)
			(xy 307.662406 -48.534522) (xy 307.714713 -48.519167) (xy 307.768673 -48.511413) (xy 307.79593 -48.510952)
			(xy 307.825724 -48.511536) (xy 307.884587 -48.520791) (xy 307.941296 -48.539087) (xy 307.99447 -48.565979)
			(xy 308.042815 -48.600812) (xy 308.085155 -48.642739) (xy 308.10327 -48.6664) (xy 308.110636 -48.67656)
			(xy 308.13248 -48.687228) (xy 308.240684 -48.684942) (xy 308.262274 -48.673004) (xy 308.269386 -48.66259)
			(xy 308.284627 -48.640621) (xy 308.320307 -48.600797) (xy 308.361196 -48.566344) (xy 308.406493 -48.537934)
			(xy 308.455312 -48.516124) (xy 308.506698 -48.501342) (xy 308.559643 -48.493876) (xy 308.586378 -48.493426)
			(xy 308.586886 -48.493426) (xy 308.601679 -48.493561) (xy 308.631177 -48.49585) (xy 308.645814 -48.497998)
			(xy 308.658006 -48.50003) (xy 308.681374 -48.492156) (xy 308.747668 -48.423322) (xy 308.755821 -48.414099)
			(xy 308.762885 -48.390547) (xy 308.76113 -48.378364) (xy 308.757956 -48.36069) (xy 308.754522 -48.324945)
			(xy 308.754272 -48.30699) (xy 308.754768 -48.279739) (xy 308.762526 -48.225793) (xy 308.777881 -48.1735)
			(xy 308.800522 -48.123924) (xy 308.829987 -48.078074) (xy 308.865678 -48.036885) (xy 308.906866 -48.001193)
			(xy 308.952715 -47.971727) (xy 309.00229 -47.949085) (xy 309.054583 -47.933728) (xy 309.108529 -47.925969)
			(xy 309.13578 -47.925482) (xy 309.163033 -47.925964) (xy 309.216985 -47.933718) (xy 309.226999 -47.936658)
			(xy 328.852784 -47.936658) (xy 328.85327 -47.909407) (xy 328.861026 -47.855459) (xy 328.876381 -47.803164)
			(xy 328.899023 -47.753587) (xy 328.928489 -47.707737) (xy 328.96418 -47.666546) (xy 329.005371 -47.630855)
			(xy 329.051221 -47.601389) (xy 329.100798 -47.578747) (xy 329.153093 -47.563392) (xy 329.207041 -47.555636)
			(xy 329.261543 -47.555636) (xy 329.315491 -47.563392) (xy 329.367786 -47.578747) (xy 329.417363 -47.601389)
			(xy 329.463213 -47.630855) (xy 329.504404 -47.666546) (xy 329.540095 -47.707737) (xy 329.569561 -47.753587)
			(xy 329.592203 -47.803164) (xy 329.607558 -47.855459) (xy 329.615314 -47.909407) (xy 329.6158 -47.936658)
			(xy 329.61536 -47.963) (xy 329.608109 -48.015182) (xy 329.593752 -48.065872) (xy 329.572562 -48.114106)
			(xy 329.544942 -48.158969) (xy 329.511415 -48.199608) (xy 329.47262 -48.235252) (xy 329.451208 -48.250602)
			(xy 329.439389 -48.259302) (xy 329.420958 -48.282128) (xy 329.409778 -48.309251) (xy 329.406772 -48.338434)
			(xy 329.412186 -48.367268) (xy 329.425575 -48.393372) (xy 329.445834 -48.414592) (xy 329.45832 -48.422306)
			(xy 329.482866 -48.436984) (xy 329.527623 -48.47259) (xy 329.566564 -48.514477) (xy 329.598818 -48.561707)
			(xy 329.623662 -48.613221) (xy 329.64054 -48.667866) (xy 329.649073 -48.724418) (xy 329.649582 -48.753014)
			(xy 331.368144 -48.753014) (xy 331.372215 -48.697392) (xy 331.384341 -48.642955) (xy 331.404264 -48.590864)
			(xy 331.43156 -48.542229) (xy 331.465646 -48.498086) (xy 331.505795 -48.459377) (xy 331.551153 -48.426926)
			(xy 331.600753 -48.401425) (xy 331.653537 -48.383418) (xy 331.70838 -48.373288) (xy 331.764114 -48.371251)
			(xy 331.819551 -48.377351) (xy 331.873508 -48.391457) (xy 331.924837 -48.413269) (xy 331.972443 -48.442323)
			(xy 332.015311 -48.477998) (xy 332.052528 -48.519535) (xy 332.083301 -48.566048) (xy 332.106973 -48.616545)
			(xy 332.123041 -48.669952) (xy 332.131161 -48.725128) (xy 332.13167 -48.753014) (xy 332.131161 -48.7809)
			(xy 332.123041 -48.836076) (xy 332.120597 -48.8442) (xy 332.387192 -48.8442) (xy 332.391263 -48.788578)
			(xy 332.403389 -48.734141) (xy 332.423312 -48.68205) (xy 332.450608 -48.633415) (xy 332.484694 -48.589272)
			(xy 332.524843 -48.550563) (xy 332.570201 -48.518112) (xy 332.619801 -48.492611) (xy 332.672585 -48.474604)
			(xy 332.727428 -48.464474) (xy 332.783162 -48.462437) (xy 332.838599 -48.468537) (xy 332.892556 -48.482643)
			(xy 332.943885 -48.504455) (xy 332.991491 -48.533509) (xy 333.034359 -48.569184) (xy 333.071576 -48.610721)
			(xy 333.102349 -48.657234) (xy 333.126021 -48.707731) (xy 333.142089 -48.761138) (xy 333.150209 -48.816314)
			(xy 333.150718 -48.8442) (xy 333.150209 -48.872086) (xy 333.143194 -48.919753) (xy 333.414838 -48.919753)
			(xy 333.414838 -48.865247) (xy 333.422595 -48.811295) (xy 333.43795 -48.758997) (xy 333.460592 -48.709416)
			(xy 333.490059 -48.663562) (xy 333.525752 -48.622368) (xy 333.566944 -48.586673) (xy 333.612797 -48.557203)
			(xy 333.662376 -48.534558) (xy 333.714674 -48.519199) (xy 333.768625 -48.511439) (xy 333.795878 -48.510952)
			(xy 333.825673 -48.511501) (xy 333.884538 -48.520763) (xy 333.941248 -48.539066) (xy 333.994421 -48.565964)
			(xy 334.042765 -48.600804) (xy 334.085104 -48.642737) (xy 334.103218 -48.6664) (xy 334.110584 -48.67656)
			(xy 334.132428 -48.687228) (xy 334.240632 -48.684942) (xy 334.262222 -48.673004) (xy 334.269334 -48.66259)
			(xy 334.284608 -48.640645) (xy 334.320283 -48.600821) (xy 334.361166 -48.566366) (xy 334.406457 -48.537953)
			(xy 334.455271 -48.516139) (xy 334.506652 -48.501352) (xy 334.559593 -48.49388) (xy 334.586326 -48.493426)
			(xy 334.586834 -48.493426) (xy 334.601627 -48.493567) (xy 334.631125 -48.495852) (xy 334.645762 -48.497998)
			(xy 334.657954 -48.50003) (xy 334.681322 -48.492156) (xy 334.747616 -48.423322) (xy 334.755764 -48.414094)
			(xy 334.762833 -48.390546) (xy 334.761078 -48.378364) (xy 334.757904 -48.36069) (xy 334.75447 -48.324945)
			(xy 334.75422 -48.30699) (xy 334.754646 -48.279736) (xy 334.762405 -48.225782) (xy 334.777763 -48.173482)
			(xy 334.800409 -48.123899) (xy 334.829881 -48.078045) (xy 334.865579 -48.036852) (xy 334.906775 -48.001158)
			(xy 334.952633 -47.971691) (xy 335.002217 -47.94905) (xy 335.054519 -47.933697) (xy 335.108474 -47.925943)
			(xy 335.135728 -47.925482) (xy 335.162977 -47.92599) (xy 335.21692 -47.93375) (xy 335.226822 -47.936658)
			(xy 366.953038 -47.936658) (xy 366.953524 -47.909407) (xy 366.96128 -47.855459) (xy 366.976635 -47.803164)
			(xy 366.999277 -47.753587) (xy 367.028743 -47.707737) (xy 367.064434 -47.666546) (xy 367.105625 -47.630855)
			(xy 367.151475 -47.601389) (xy 367.201052 -47.578747) (xy 367.253347 -47.563392) (xy 367.307295 -47.555636)
			(xy 367.361797 -47.555636) (xy 367.415745 -47.563392) (xy 367.46804 -47.578747) (xy 367.517617 -47.601389)
			(xy 367.563467 -47.630855) (xy 367.604658 -47.666546) (xy 367.640349 -47.707737) (xy 367.669815 -47.753587)
			(xy 367.692457 -47.803164) (xy 367.707812 -47.855459) (xy 367.715568 -47.909407) (xy 367.716054 -47.936658)
			(xy 367.715591 -47.962999) (xy 367.708341 -48.015179) (xy 367.693986 -48.065867) (xy 367.6728 -48.114101)
			(xy 367.645183 -48.158964) (xy 367.611662 -48.199604) (xy 367.572871 -48.23525) (xy 367.551462 -48.250602)
			(xy 367.539635 -48.259295) (xy 367.521194 -48.28212) (xy 367.510007 -48.309246) (xy 367.506999 -48.338435)
			(xy 367.512416 -48.367273) (xy 367.525813 -48.393379) (xy 367.546082 -48.414596) (xy 367.558574 -48.422306)
			(xy 367.58311 -48.437001) (xy 367.627868 -48.472603) (xy 367.666812 -48.514486) (xy 367.699068 -48.561712)
			(xy 367.723914 -48.613224) (xy 367.740793 -48.667868) (xy 367.749327 -48.724419) (xy 367.749836 -48.753014)
			(xy 369.468398 -48.753014) (xy 369.472469 -48.697392) (xy 369.484595 -48.642955) (xy 369.504518 -48.590864)
			(xy 369.531814 -48.542229) (xy 369.5659 -48.498086) (xy 369.606049 -48.459377) (xy 369.651407 -48.426926)
			(xy 369.701007 -48.401425) (xy 369.753791 -48.383418) (xy 369.808634 -48.373288) (xy 369.864368 -48.371251)
			(xy 369.919805 -48.377351) (xy 369.973762 -48.391457) (xy 370.025091 -48.413269) (xy 370.072697 -48.442323)
			(xy 370.115565 -48.477998) (xy 370.152782 -48.519535) (xy 370.183555 -48.566048) (xy 370.207227 -48.616545)
			(xy 370.223295 -48.669952) (xy 370.231415 -48.725128) (xy 370.231924 -48.753014) (xy 370.231415 -48.7809)
			(xy 370.223295 -48.836076) (xy 370.207227 -48.889483) (xy 370.193035 -48.919757) (xy 371.515015 -48.919757)
			(xy 371.515015 -48.865243) (xy 371.522774 -48.811283) (xy 371.538133 -48.758977) (xy 371.56078 -48.70939)
			(xy 371.590254 -48.66353) (xy 371.625955 -48.622333) (xy 371.667156 -48.586635) (xy 371.713018 -48.557165)
			(xy 371.762607 -48.534522) (xy 371.814915 -48.519167) (xy 371.868875 -48.511413) (xy 371.896132 -48.510952)
			(xy 371.925926 -48.511535) (xy 371.984789 -48.52079) (xy 372.041498 -48.539086) (xy 372.094672 -48.565978)
			(xy 372.143017 -48.600812) (xy 372.185357 -48.642739) (xy 372.203472 -48.6664) (xy 372.210838 -48.67656)
			(xy 372.232682 -48.687228) (xy 372.340886 -48.684942) (xy 372.362476 -48.673004) (xy 372.369588 -48.66259)
			(xy 372.384828 -48.64062) (xy 372.420508 -48.600797) (xy 372.461397 -48.566343) (xy 372.506695 -48.537933)
			(xy 372.555514 -48.516124) (xy 372.6069 -48.501342) (xy 372.659845 -48.493876) (xy 372.68658 -48.493426)
			(xy 372.687088 -48.493426) (xy 372.701881 -48.493561) (xy 372.731379 -48.49585) (xy 372.746016 -48.497998)
			(xy 372.758208 -48.50003) (xy 372.781576 -48.492156) (xy 372.84787 -48.423322) (xy 372.856024 -48.414099)
			(xy 372.863087 -48.390547) (xy 372.861332 -48.378364) (xy 372.858158 -48.36069) (xy 372.854724 -48.324945)
			(xy 372.854474 -48.30699) (xy 372.854968 -48.279739) (xy 372.862726 -48.225793) (xy 372.878081 -48.173499)
			(xy 372.900722 -48.123923) (xy 372.930188 -48.078074) (xy 372.965878 -48.036884) (xy 373.007067 -48.001193)
			(xy 373.052916 -47.971726) (xy 373.102492 -47.949084) (xy 373.154785 -47.933728) (xy 373.208731 -47.925969)
			(xy 373.235982 -47.925482) (xy 373.263235 -47.925964) (xy 373.317186 -47.933719) (xy 373.327197 -47.936658)
			(xy 392.952986 -47.936658) (xy 392.953472 -47.909407) (xy 392.961228 -47.855459) (xy 392.976583 -47.803164)
			(xy 392.999225 -47.753587) (xy 393.028691 -47.707737) (xy 393.064382 -47.666546) (xy 393.105573 -47.630855)
			(xy 393.151423 -47.601389) (xy 393.201 -47.578747) (xy 393.253295 -47.563392) (xy 393.307243 -47.555636)
			(xy 393.361745 -47.555636) (xy 393.415693 -47.563392) (xy 393.467988 -47.578747) (xy 393.517565 -47.601389)
			(xy 393.563415 -47.630855) (xy 393.604606 -47.666546) (xy 393.640297 -47.707737) (xy 393.669763 -47.753587)
			(xy 393.692405 -47.803164) (xy 393.70776 -47.855459) (xy 393.715516 -47.909407) (xy 393.716002 -47.936658)
			(xy 393.715561 -47.963) (xy 393.70831 -48.015182) (xy 393.693953 -48.065872) (xy 393.672763 -48.114106)
			(xy 393.645143 -48.158969) (xy 393.611617 -48.199608) (xy 393.572822 -48.235252) (xy 393.55141 -48.250602)
			(xy 393.53959 -48.259301) (xy 393.52116 -48.282127) (xy 393.50998 -48.309251) (xy 393.506973 -48.338435)
			(xy 393.512387 -48.367268) (xy 393.525777 -48.393372) (xy 393.546035 -48.414593) (xy 393.558522 -48.422306)
			(xy 393.583069 -48.436983) (xy 393.627825 -48.47259) (xy 393.666766 -48.514477) (xy 393.69902 -48.561706)
			(xy 393.723864 -48.613221) (xy 393.740742 -48.667866) (xy 393.749275 -48.724418) (xy 393.749784 -48.753014)
			(xy 395.468346 -48.753014) (xy 395.472417 -48.697392) (xy 395.484543 -48.642955) (xy 395.504466 -48.590864)
			(xy 395.531762 -48.542229) (xy 395.565848 -48.498086) (xy 395.605997 -48.459377) (xy 395.651355 -48.426926)
			(xy 395.700955 -48.401425) (xy 395.753739 -48.383418) (xy 395.808582 -48.373288) (xy 395.864316 -48.371251)
			(xy 395.919753 -48.377351) (xy 395.97371 -48.391457) (xy 396.025039 -48.413269) (xy 396.072645 -48.442323)
			(xy 396.115513 -48.477998) (xy 396.15273 -48.519535) (xy 396.183503 -48.566048) (xy 396.207175 -48.616545)
			(xy 396.223243 -48.669952) (xy 396.231363 -48.725128) (xy 396.231872 -48.753014) (xy 396.231363 -48.7809)
			(xy 396.223243 -48.836076) (xy 396.207175 -48.889483) (xy 396.192985 -48.919753) (xy 397.515038 -48.919753)
			(xy 397.515038 -48.865247) (xy 397.522795 -48.811295) (xy 397.53815 -48.758997) (xy 397.560792 -48.709415)
			(xy 397.59026 -48.663561) (xy 397.625953 -48.622367) (xy 397.667145 -48.586672) (xy 397.712998 -48.557202)
			(xy 397.762578 -48.534557) (xy 397.814876 -48.519199) (xy 397.868827 -48.511439) (xy 397.89608 -48.510952)
			(xy 397.925875 -48.511499) (xy 397.984741 -48.520762) (xy 398.04145 -48.539065) (xy 398.094623 -48.565964)
			(xy 398.142967 -48.600803) (xy 398.185306 -48.642737) (xy 398.20342 -48.6664) (xy 398.210786 -48.67656)
			(xy 398.23263 -48.687228) (xy 398.340834 -48.684942) (xy 398.362424 -48.673004) (xy 398.369536 -48.66259)
			(xy 398.384809 -48.640644) (xy 398.420483 -48.60082) (xy 398.461367 -48.566365) (xy 398.506659 -48.537952)
			(xy 398.555473 -48.516139) (xy 398.606853 -48.501352) (xy 398.659795 -48.49388) (xy 398.686528 -48.493426)
			(xy 398.687036 -48.493426) (xy 398.701829 -48.493567) (xy 398.731327 -48.495852) (xy 398.745964 -48.497998)
			(xy 398.758156 -48.50003) (xy 398.781524 -48.492156) (xy 398.847818 -48.423322) (xy 398.855966 -48.414094)
			(xy 398.863035 -48.390546) (xy 398.86128 -48.378364) (xy 398.858106 -48.36069) (xy 398.854672 -48.324945)
			(xy 398.854422 -48.30699) (xy 398.854846 -48.279736) (xy 398.862605 -48.225782) (xy 398.877964 -48.173481)
			(xy 398.900609 -48.123899) (xy 398.930081 -48.078044) (xy 398.965779 -48.036851) (xy 399.006976 -48.001157)
			(xy 399.052834 -47.97169) (xy 399.102419 -47.94905) (xy 399.154721 -47.933696) (xy 399.208675 -47.925943)
			(xy 399.23593 -47.925482) (xy 399.263179 -47.92599) (xy 399.317122 -47.93375) (xy 399.327024 -47.936658)
			(xy 418.952934 -47.936658) (xy 418.95342 -47.909407) (xy 418.961176 -47.855459) (xy 418.976531 -47.803164)
			(xy 418.999173 -47.753587) (xy 419.028639 -47.707737) (xy 419.06433 -47.666546) (xy 419.105521 -47.630855)
			(xy 419.151371 -47.601389) (xy 419.200948 -47.578747) (xy 419.253243 -47.563392) (xy 419.307191 -47.555636)
			(xy 419.361693 -47.555636) (xy 419.415641 -47.563392) (xy 419.467936 -47.578747) (xy 419.517513 -47.601389)
			(xy 419.563363 -47.630855) (xy 419.604554 -47.666546) (xy 419.640245 -47.707737) (xy 419.669711 -47.753587)
			(xy 419.692353 -47.803164) (xy 419.707708 -47.855459) (xy 419.715464 -47.909407) (xy 419.71595 -47.936658)
			(xy 419.715489 -47.962999) (xy 419.708239 -48.015179) (xy 419.693884 -48.065867) (xy 419.672697 -48.114101)
			(xy 419.64508 -48.158964) (xy 419.611558 -48.199604) (xy 419.572768 -48.235251) (xy 419.551358 -48.250602)
			(xy 419.539531 -48.259296) (xy 419.521092 -48.28212) (xy 419.509905 -48.309247) (xy 419.506897 -48.338435)
			(xy 419.512314 -48.367273) (xy 419.52571 -48.393379) (xy 419.545979 -48.414596) (xy 419.55847 -48.422306)
			(xy 419.583005 -48.437003) (xy 419.627764 -48.472604) (xy 419.666708 -48.514487) (xy 419.698964 -48.561713)
			(xy 419.72381 -48.613225) (xy 419.740689 -48.667868) (xy 419.749223 -48.724419) (xy 419.749732 -48.753014)
			(xy 421.468294 -48.753014) (xy 421.472365 -48.697392) (xy 421.484491 -48.642955) (xy 421.504414 -48.590864)
			(xy 421.53171 -48.542229) (xy 421.565796 -48.498086) (xy 421.605945 -48.459377) (xy 421.651303 -48.426926)
			(xy 421.700903 -48.401425) (xy 421.753687 -48.383418) (xy 421.80853 -48.373288) (xy 421.864264 -48.371251)
			(xy 421.919701 -48.377351) (xy 421.973658 -48.391457) (xy 422.024987 -48.413269) (xy 422.072593 -48.442323)
			(xy 422.115461 -48.477998) (xy 422.152678 -48.519535) (xy 422.183451 -48.566048) (xy 422.207123 -48.616545)
			(xy 422.223191 -48.669952) (xy 422.231311 -48.725128) (xy 422.23182 -48.753014) (xy 422.231311 -48.7809)
			(xy 422.223191 -48.836076) (xy 422.220747 -48.8442) (xy 422.487342 -48.8442) (xy 422.491413 -48.788578)
			(xy 422.503539 -48.734141) (xy 422.523462 -48.68205) (xy 422.550758 -48.633415) (xy 422.584844 -48.589272)
			(xy 422.624993 -48.550563) (xy 422.670351 -48.518112) (xy 422.719951 -48.492611) (xy 422.772735 -48.474604)
			(xy 422.827578 -48.464474) (xy 422.883312 -48.462437) (xy 422.938749 -48.468537) (xy 422.992706 -48.482643)
			(xy 423.044035 -48.504455) (xy 423.091641 -48.533509) (xy 423.134509 -48.569184) (xy 423.171726 -48.610721)
			(xy 423.202499 -48.657234) (xy 423.226171 -48.707731) (xy 423.242239 -48.761138) (xy 423.250359 -48.816314)
			(xy 423.250868 -48.8442) (xy 423.250359 -48.872086) (xy 423.243343 -48.919757) (xy 423.514915 -48.919757)
			(xy 423.514915 -48.865243) (xy 423.522674 -48.811284) (xy 423.538033 -48.758978) (xy 423.56068 -48.709391)
			(xy 423.590153 -48.663532) (xy 423.625854 -48.622334) (xy 423.667054 -48.586636) (xy 423.712916 -48.557166)
			(xy 423.762505 -48.534523) (xy 423.814811 -48.519168) (xy 423.868771 -48.511413) (xy 423.896028 -48.510952)
			(xy 423.925822 -48.511537) (xy 423.984685 -48.520792) (xy 424.041394 -48.539088) (xy 424.094567 -48.565979)
			(xy 424.142912 -48.600812) (xy 424.185253 -48.64274) (xy 424.203368 -48.6664) (xy 424.210734 -48.67656)
			(xy 424.232578 -48.687228) (xy 424.340782 -48.684942) (xy 424.362372 -48.673004) (xy 424.369484 -48.66259)
			(xy 424.384726 -48.640622) (xy 424.420406 -48.600798) (xy 424.461295 -48.566344) (xy 424.506592 -48.537935)
			(xy 424.555411 -48.516125) (xy 424.606796 -48.501342) (xy 424.659741 -48.493876) (xy 424.686476 -48.493426)
			(xy 424.686984 -48.493426) (xy 424.701777 -48.493561) (xy 424.731275 -48.49585) (xy 424.745912 -48.497998)
			(xy 424.758104 -48.50003) (xy 424.781472 -48.492156) (xy 424.847766 -48.423322) (xy 424.855919 -48.414099)
			(xy 424.862983 -48.390547) (xy 424.861228 -48.378364) (xy 424.858054 -48.36069) (xy 424.85462 -48.324945)
			(xy 424.85437 -48.30699) (xy 424.854868 -48.27974) (xy 424.862626 -48.225793) (xy 424.877981 -48.1735)
			(xy 424.900622 -48.123924) (xy 424.930087 -48.078075) (xy 424.965777 -48.036886) (xy 425.006965 -48.001194)
			(xy 425.052814 -47.971727) (xy 425.102389 -47.949085) (xy 425.154682 -47.933728) (xy 425.208628 -47.925969)
			(xy 425.235878 -47.925482) (xy 425.263131 -47.925964) (xy 425.317083 -47.933718) (xy 425.327097 -47.936658)
			(xy 444.952882 -47.936658) (xy 444.953368 -47.909407) (xy 444.961124 -47.855459) (xy 444.976479 -47.803164)
			(xy 444.999121 -47.753587) (xy 445.028587 -47.707737) (xy 445.064278 -47.666546) (xy 445.105469 -47.630855)
			(xy 445.151319 -47.601389) (xy 445.200896 -47.578747) (xy 445.253191 -47.563392) (xy 445.307139 -47.555636)
			(xy 445.361641 -47.555636) (xy 445.415589 -47.563392) (xy 445.467884 -47.578747) (xy 445.517461 -47.601389)
			(xy 445.563311 -47.630855) (xy 445.604502 -47.666546) (xy 445.640193 -47.707737) (xy 445.669659 -47.753587)
			(xy 445.692301 -47.803164) (xy 445.707656 -47.855459) (xy 445.715412 -47.909407) (xy 445.715898 -47.936658)
			(xy 445.715459 -47.963) (xy 445.708208 -48.015182) (xy 445.693851 -48.065872) (xy 445.672661 -48.114106)
			(xy 445.64504 -48.158969) (xy 445.611514 -48.199608) (xy 445.572718 -48.235252) (xy 445.551306 -48.250602)
			(xy 445.539487 -48.259302) (xy 445.521057 -48.282128) (xy 445.509877 -48.309252) (xy 445.506871 -48.338434)
			(xy 445.512285 -48.367268) (xy 445.525674 -48.393372) (xy 445.545932 -48.414592) (xy 445.558418 -48.422306)
			(xy 445.582964 -48.436985) (xy 445.62772 -48.472591) (xy 445.666662 -48.514478) (xy 445.698916 -48.561707)
			(xy 445.72376 -48.613221) (xy 445.740638 -48.667866) (xy 445.749171 -48.724418) (xy 445.74968 -48.753014)
			(xy 447.468242 -48.753014) (xy 447.472313 -48.697392) (xy 447.484439 -48.642955) (xy 447.504362 -48.590864)
			(xy 447.531658 -48.542229) (xy 447.565744 -48.498086) (xy 447.605893 -48.459377) (xy 447.651251 -48.426926)
			(xy 447.700851 -48.401425) (xy 447.753635 -48.383418) (xy 447.808478 -48.373288) (xy 447.864212 -48.371251)
			(xy 447.919649 -48.377351) (xy 447.973606 -48.391457) (xy 448.024935 -48.413269) (xy 448.072541 -48.442323)
			(xy 448.115409 -48.477998) (xy 448.152626 -48.519535) (xy 448.183399 -48.566048) (xy 448.207071 -48.616545)
			(xy 448.223139 -48.669952) (xy 448.231259 -48.725128) (xy 448.231768 -48.753014) (xy 448.231259 -48.7809)
			(xy 448.223139 -48.836076) (xy 448.220695 -48.8442) (xy 448.48729 -48.8442) (xy 448.491361 -48.788578)
			(xy 448.503487 -48.734141) (xy 448.52341 -48.68205) (xy 448.550706 -48.633415) (xy 448.584792 -48.589272)
			(xy 448.624941 -48.550563) (xy 448.670299 -48.518112) (xy 448.719899 -48.492611) (xy 448.772683 -48.474604)
			(xy 448.827526 -48.464474) (xy 448.88326 -48.462437) (xy 448.938697 -48.468537) (xy 448.992654 -48.482643)
			(xy 449.043983 -48.504455) (xy 449.091589 -48.533509) (xy 449.134457 -48.569184) (xy 449.171674 -48.610721)
			(xy 449.202447 -48.657234) (xy 449.226119 -48.707731) (xy 449.242187 -48.761138) (xy 449.250307 -48.816314)
			(xy 449.250816 -48.8442) (xy 449.250307 -48.872086) (xy 449.243292 -48.919753) (xy 449.514938 -48.919753)
			(xy 449.514938 -48.865247) (xy 449.522695 -48.811296) (xy 449.53805 -48.758997) (xy 449.560692 -48.709417)
			(xy 449.590159 -48.663563) (xy 449.625852 -48.622369) (xy 449.667043 -48.586673) (xy 449.712895 -48.557203)
			(xy 449.762475 -48.534558) (xy 449.814772 -48.5192) (xy 449.868723 -48.51144) (xy 449.895976 -48.510952)
			(xy 449.925771 -48.511502) (xy 449.984636 -48.520764) (xy 450.041346 -48.539067) (xy 450.094519 -48.565965)
			(xy 450.142863 -48.600804) (xy 450.185202 -48.642737) (xy 450.203316 -48.6664) (xy 450.210682 -48.67656)
			(xy 450.232526 -48.687228) (xy 450.34073 -48.684942) (xy 450.36232 -48.673004) (xy 450.369432 -48.66259)
			(xy 450.384707 -48.640646) (xy 450.420382 -48.600822) (xy 450.461265 -48.566366) (xy 450.506556 -48.537954)
			(xy 450.55537 -48.51614) (xy 450.60675 -48.501352) (xy 450.659691 -48.49388) (xy 450.686424 -48.493426)
			(xy 450.686932 -48.493426) (xy 450.701725 -48.493567) (xy 450.731223 -48.495852) (xy 450.74586 -48.497998)
			(xy 450.758052 -48.50003) (xy 450.78142 -48.492156) (xy 450.847714 -48.423322) (xy 450.855862 -48.414094)
			(xy 450.862931 -48.390546) (xy 450.861176 -48.378364) (xy 450.858002 -48.36069) (xy 450.854568 -48.324945)
			(xy 450.854318 -48.30699) (xy 450.854746 -48.279736) (xy 450.862505 -48.225782) (xy 450.877863 -48.173482)
			(xy 450.900509 -48.1239) (xy 450.92998 -48.078046) (xy 450.965678 -48.036852) (xy 451.006874 -48.001159)
			(xy 451.052732 -47.971692) (xy 451.102316 -47.949051) (xy 451.154617 -47.933697) (xy 451.208572 -47.925943)
			(xy 451.235826 -47.925482) (xy 451.263075 -47.92599) (xy 451.317019 -47.933749) (xy 451.369309 -47.949106)
			(xy 451.418882 -47.971748) (xy 451.464727 -48.001214) (xy 451.505913 -48.036905) (xy 451.541601 -48.078093)
			(xy 451.571064 -48.123941) (xy 451.593703 -48.173515) (xy 451.609056 -48.225807) (xy 451.616812 -48.279751)
			(xy 451.616812 -48.334249) (xy 451.609056 -48.388193) (xy 451.593703 -48.440485) (xy 451.571064 -48.490059)
			(xy 451.541601 -48.535907) (xy 451.505913 -48.577095) (xy 451.464727 -48.612786) (xy 451.418882 -48.642252)
			(xy 451.369309 -48.664894) (xy 451.317019 -48.680251) (xy 451.263075 -48.68801) (xy 451.235826 -48.688498)
			(xy 451.235318 -48.688498) (xy 451.220525 -48.688362) (xy 451.191027 -48.686074) (xy 451.17639 -48.683926)
			(xy 451.164198 -48.681894) (xy 451.14083 -48.689768) (xy 451.074536 -48.758602) (xy 451.066369 -48.767815)
			(xy 451.059313 -48.791375) (xy 451.061074 -48.80356) (xy 451.064251 -48.821233) (xy 451.067683 -48.856979)
			(xy 451.067932 -48.874934) (xy 451.067454 -48.902185) (xy 451.062458 -48.93691) (xy 453.205848 -48.93691)
			(xy 453.209919 -48.881288) (xy 453.222045 -48.826851) (xy 453.241968 -48.77476) (xy 453.269264 -48.726125)
			(xy 453.30335 -48.681982) (xy 453.343499 -48.643273) (xy 453.388857 -48.610822) (xy 453.438457 -48.585321)
			(xy 453.491241 -48.567314) (xy 453.546084 -48.557184) (xy 453.601818 -48.555147) (xy 453.657255 -48.561247)
			(xy 453.711212 -48.575353) (xy 453.762541 -48.597165) (xy 453.810147 -48.626219) (xy 453.853015 -48.661894)
			(xy 453.890232 -48.703431) (xy 453.921005 -48.749944) (xy 453.944677 -48.800441) (xy 453.960745 -48.853848)
			(xy 453.968865 -48.909024) (xy 453.969374 -48.93691) (xy 453.968865 -48.964796) (xy 453.960745 -49.019972)
			(xy 453.944677 -49.073379) (xy 453.921005 -49.123876) (xy 453.890232 -49.170389) (xy 453.853015 -49.211926)
			(xy 453.810147 -49.247601) (xy 453.762541 -49.276655) (xy 453.711212 -49.298467) (xy 453.657255 -49.312573)
			(xy 453.601818 -49.318673) (xy 453.546084 -49.316636) (xy 453.491241 -49.306506) (xy 453.438457 -49.288499)
			(xy 453.388857 -49.262998) (xy 453.343499 -49.230547) (xy 453.30335 -49.191838) (xy 453.269264 -49.147695)
			(xy 453.241968 -49.09906) (xy 453.222045 -49.046969) (xy 453.209919 -48.992532) (xy 453.205848 -48.93691)
			(xy 451.062458 -48.93691) (xy 451.059693 -48.956132) (xy 451.044335 -49.008425) (xy 451.021692 -49.058001)
			(xy 450.992224 -49.10385) (xy 450.956532 -49.145039) (xy 450.915342 -49.18073) (xy 450.869492 -49.210197)
			(xy 450.819916 -49.232839) (xy 450.767622 -49.248196) (xy 450.713675 -49.255955) (xy 450.686424 -49.256442)
			(xy 450.656629 -49.255894) (xy 450.597763 -49.246632) (xy 450.541054 -49.228329) (xy 450.48788 -49.20143)
			(xy 450.439536 -49.166591) (xy 450.397198 -49.124658) (xy 450.379084 -49.100994) (xy 450.371718 -49.090834)
			(xy 450.349874 -49.080166) (xy 450.24167 -49.082452) (xy 450.22008 -49.09439) (xy 450.212968 -49.104804)
			(xy 450.197691 -49.126747) (xy 450.162017 -49.166571) (xy 450.121134 -49.201027) (xy 450.075843 -49.22944)
			(xy 450.02703 -49.251254) (xy 449.97565 -49.266042) (xy 449.922709 -49.273514) (xy 449.895976 -49.273968)
			(xy 449.868723 -49.27356) (xy 449.814772 -49.2658) (xy 449.762475 -49.250442) (xy 449.712895 -49.227797)
			(xy 449.667043 -49.198327) (xy 449.625852 -49.162631) (xy 449.590159 -49.121437) (xy 449.560692 -49.075583)
			(xy 449.53805 -49.026003) (xy 449.522695 -48.973704) (xy 449.514938 -48.919753) (xy 449.243292 -48.919753)
			(xy 449.242187 -48.927262) (xy 449.226119 -48.980669) (xy 449.202447 -49.031166) (xy 449.171674 -49.077679)
			(xy 449.134457 -49.119216) (xy 449.091589 -49.154891) (xy 449.043983 -49.183945) (xy 448.992654 -49.205757)
			(xy 448.938697 -49.219863) (xy 448.88326 -49.225963) (xy 448.827526 -49.223926) (xy 448.772683 -49.213796)
			(xy 448.719899 -49.195789) (xy 448.670299 -49.170288) (xy 448.624941 -49.137837) (xy 448.584792 -49.099128)
			(xy 448.550706 -49.054985) (xy 448.52341 -49.00635) (xy 448.503487 -48.954259) (xy 448.491361 -48.899822)
			(xy 448.48729 -48.8442) (xy 448.220695 -48.8442) (xy 448.207071 -48.889483) (xy 448.183399 -48.93998)
			(xy 448.152626 -48.986493) (xy 448.115409 -49.02803) (xy 448.072541 -49.063705) (xy 448.024935 -49.092759)
			(xy 447.973606 -49.114571) (xy 447.919649 -49.128677) (xy 447.864212 -49.134777) (xy 447.808478 -49.13274)
			(xy 447.753635 -49.12261) (xy 447.700851 -49.104603) (xy 447.651251 -49.079102) (xy 447.605893 -49.046651)
			(xy 447.565744 -49.007942) (xy 447.531658 -48.963799) (xy 447.504362 -48.915164) (xy 447.484439 -48.863073)
			(xy 447.472313 -48.808636) (xy 447.468242 -48.753014) (xy 445.74968 -48.753014) (xy 445.749194 -48.780265)
			(xy 445.741438 -48.834213) (xy 445.726083 -48.886508) (xy 445.703441 -48.936085) (xy 445.673975 -48.981935)
			(xy 445.638284 -49.023126) (xy 445.597093 -49.058817) (xy 445.551243 -49.088283) (xy 445.501666 -49.110925)
			(xy 445.449371 -49.12628) (xy 445.395423 -49.134036) (xy 445.340921 -49.134036) (xy 445.286973 -49.12628)
			(xy 445.234678 -49.110925) (xy 445.185101 -49.088283) (xy 445.139251 -49.058817) (xy 445.09806 -49.023126)
			(xy 445.062369 -48.981935) (xy 445.032903 -48.936085) (xy 445.010261 -48.886508) (xy 444.994906 -48.834213)
			(xy 444.98715 -48.780265) (xy 444.986664 -48.753014) (xy 444.987098 -48.726672) (xy 444.994352 -48.67449)
			(xy 445.008712 -48.623801) (xy 445.029903 -48.575567) (xy 445.057524 -48.530705) (xy 445.09105 -48.490065)
			(xy 445.129845 -48.45442) (xy 445.151256 -48.43907) (xy 445.163109 -48.43041) (xy 445.181547 -48.407577)
			(xy 445.19273 -48.380443) (xy 445.195734 -48.351249) (xy 445.190312 -48.322407) (xy 445.176911 -48.296297)
			(xy 445.156638 -48.275077) (xy 445.144144 -48.267366) (xy 445.119621 -48.252651) (xy 445.074867 -48.217049)
			(xy 445.035926 -48.175168) (xy 445.00367 -48.127945) (xy 444.978822 -48.076437) (xy 444.961938 -48.021798)
			(xy 444.953396 -47.965252) (xy 444.952882 -47.936658) (xy 425.327097 -47.936658) (xy 425.369382 -47.949072)
			(xy 425.418964 -47.971712) (xy 425.464818 -48.001179) (xy 425.506013 -48.036872) (xy 425.541708 -48.078064)
			(xy 425.571177 -48.123917) (xy 425.593821 -48.173497) (xy 425.609177 -48.225795) (xy 425.616935 -48.279747)
			(xy 425.616935 -48.334253) (xy 425.609177 -48.388205) (xy 425.593821 -48.440503) (xy 425.571177 -48.490083)
			(xy 425.541708 -48.535936) (xy 425.506013 -48.577128) (xy 425.464818 -48.612821) (xy 425.418964 -48.642288)
			(xy 425.369382 -48.664928) (xy 425.317083 -48.680282) (xy 425.263131 -48.688036) (xy 425.235878 -48.688498)
			(xy 425.23537 -48.688498) (xy 425.220577 -48.688356) (xy 425.191079 -48.686072) (xy 425.176442 -48.683926)
			(xy 425.16425 -48.681894) (xy 425.140882 -48.689768) (xy 425.074588 -48.758602) (xy 425.066427 -48.76782)
			(xy 425.059365 -48.791376) (xy 425.061126 -48.80356) (xy 425.064304 -48.821233) (xy 425.067735 -48.856979)
			(xy 425.067984 -48.874934) (xy 425.067554 -48.902187) (xy 425.062558 -48.93691) (xy 427.233078 -48.93691)
			(xy 427.237149 -48.881288) (xy 427.249275 -48.826851) (xy 427.269198 -48.77476) (xy 427.296494 -48.726125)
			(xy 427.33058 -48.681982) (xy 427.370729 -48.643273) (xy 427.416087 -48.610822) (xy 427.465687 -48.585321)
			(xy 427.518471 -48.567314) (xy 427.573314 -48.557184) (xy 427.629048 -48.555147) (xy 427.684485 -48.561247)
			(xy 427.738442 -48.575353) (xy 427.789771 -48.597165) (xy 427.837377 -48.626219) (xy 427.880245 -48.661894)
			(xy 427.917462 -48.703431) (xy 427.948235 -48.749944) (xy 427.971907 -48.800441) (xy 427.987975 -48.853848)
			(xy 427.996095 -48.909024) (xy 427.996604 -48.93691) (xy 427.996095 -48.964796) (xy 427.987975 -49.019972)
			(xy 427.971907 -49.073379) (xy 427.948235 -49.123876) (xy 427.917462 -49.170389) (xy 427.880245 -49.211926)
			(xy 427.837377 -49.247601) (xy 427.789771 -49.276655) (xy 427.738442 -49.298467) (xy 427.684485 -49.312573)
			(xy 427.629048 -49.318673) (xy 427.573314 -49.316636) (xy 427.518471 -49.306506) (xy 427.465687 -49.288499)
			(xy 427.416087 -49.262998) (xy 427.370729 -49.230547) (xy 427.33058 -49.191838) (xy 427.296494 -49.147695)
			(xy 427.269198 -49.09906) (xy 427.249275 -49.046969) (xy 427.237149 -48.992532) (xy 427.233078 -48.93691)
			(xy 425.062558 -48.93691) (xy 425.059792 -48.956138) (xy 425.044431 -49.008435) (xy 425.021784 -49.058014)
			(xy 424.992312 -49.103866) (xy 424.956615 -49.145056) (xy 424.915419 -49.180747) (xy 424.869563 -49.210212)
			(xy 424.819981 -49.232852) (xy 424.767681 -49.248204) (xy 424.713729 -49.255958) (xy 424.686476 -49.256442)
			(xy 424.656682 -49.255856) (xy 424.597819 -49.246602) (xy 424.54111 -49.228306) (xy 424.487936 -49.201415)
			(xy 424.439591 -49.166582) (xy 424.397251 -49.124655) (xy 424.379136 -49.100994) (xy 424.37177 -49.090834)
			(xy 424.349926 -49.080166) (xy 424.241722 -49.082452) (xy 424.220132 -49.09439) (xy 424.21302 -49.104804)
			(xy 424.197773 -49.126769) (xy 424.162095 -49.166593) (xy 424.121207 -49.201047) (xy 424.07591 -49.229457)
			(xy 424.027092 -49.251268) (xy 423.975707 -49.266051) (xy 423.922762 -49.273517) (xy 423.896028 -49.273968)
			(xy 423.868771 -49.273587) (xy 423.814811 -49.265832) (xy 423.762505 -49.250477) (xy 423.712916 -49.227834)
			(xy 423.667054 -49.198364) (xy 423.625854 -49.162666) (xy 423.590153 -49.121468) (xy 423.56068 -49.075609)
			(xy 423.538033 -49.026022) (xy 423.522674 -48.973716) (xy 423.514915 -48.919757) (xy 423.243343 -48.919757)
			(xy 423.242239 -48.927262) (xy 423.226171 -48.980669) (xy 423.202499 -49.031166) (xy 423.171726 -49.077679)
			(xy 423.134509 -49.119216) (xy 423.091641 -49.154891) (xy 423.044035 -49.183945) (xy 422.992706 -49.205757)
			(xy 422.938749 -49.219863) (xy 422.883312 -49.225963) (xy 422.827578 -49.223926) (xy 422.772735 -49.213796)
			(xy 422.719951 -49.195789) (xy 422.670351 -49.170288) (xy 422.624993 -49.137837) (xy 422.584844 -49.099128)
			(xy 422.550758 -49.054985) (xy 422.523462 -49.00635) (xy 422.503539 -48.954259) (xy 422.491413 -48.899822)
			(xy 422.487342 -48.8442) (xy 422.220747 -48.8442) (xy 422.207123 -48.889483) (xy 422.183451 -48.93998)
			(xy 422.152678 -48.986493) (xy 422.115461 -49.02803) (xy 422.072593 -49.063705) (xy 422.024987 -49.092759)
			(xy 421.973658 -49.114571) (xy 421.919701 -49.128677) (xy 421.864264 -49.134777) (xy 421.80853 -49.13274)
			(xy 421.753687 -49.12261) (xy 421.700903 -49.104603) (xy 421.651303 -49.079102) (xy 421.605945 -49.046651)
			(xy 421.565796 -49.007942) (xy 421.53171 -48.963799) (xy 421.504414 -48.915164) (xy 421.484491 -48.863073)
			(xy 421.472365 -48.808636) (xy 421.468294 -48.753014) (xy 419.749732 -48.753014) (xy 419.749246 -48.780265)
			(xy 419.74149 -48.834213) (xy 419.726135 -48.886508) (xy 419.703493 -48.936085) (xy 419.674027 -48.981935)
			(xy 419.638336 -49.023126) (xy 419.597145 -49.058817) (xy 419.551295 -49.088283) (xy 419.501718 -49.110925)
			(xy 419.449423 -49.12628) (xy 419.395475 -49.134036) (xy 419.340973 -49.134036) (xy 419.287025 -49.12628)
			(xy 419.23473 -49.110925) (xy 419.185153 -49.088283) (xy 419.139303 -49.058817) (xy 419.098112 -49.023126)
			(xy 419.062421 -48.981935) (xy 419.032955 -48.936085) (xy 419.010313 -48.886508) (xy 418.994958 -48.834213)
			(xy 418.987202 -48.780265) (xy 418.986716 -48.753014) (xy 418.98717 -48.726673) (xy 418.994423 -48.674493)
			(xy 419.008781 -48.623805) (xy 419.029969 -48.575572) (xy 419.057586 -48.530709) (xy 419.091108 -48.490069)
			(xy 419.129898 -48.454422) (xy 419.151308 -48.43907) (xy 419.163153 -48.430403) (xy 419.181581 -48.407569)
			(xy 419.192757 -48.380438) (xy 419.19576 -48.35125) (xy 419.190341 -48.322412) (xy 419.176947 -48.296304)
			(xy 419.156685 -48.275081) (xy 419.144196 -48.267366) (xy 419.119685 -48.252632) (xy 419.074928 -48.217035)
			(xy 419.035985 -48.175158) (xy 419.003726 -48.127938) (xy 418.978876 -48.076433) (xy 418.961991 -48.021796)
			(xy 418.953448 -47.965251) (xy 418.952934 -47.936658) (xy 399.327024 -47.936658) (xy 399.369412 -47.949107)
			(xy 399.418984 -47.97175) (xy 399.464829 -48.001216) (xy 399.506015 -48.036906) (xy 399.541702 -48.078095)
			(xy 399.571165 -48.123942) (xy 399.593803 -48.173516) (xy 399.609156 -48.225807) (xy 399.616912 -48.279751)
			(xy 399.616912 -48.334249) (xy 399.609156 -48.388193) (xy 399.593803 -48.440484) (xy 399.571165 -48.490058)
			(xy 399.541702 -48.535905) (xy 399.506015 -48.577094) (xy 399.464829 -48.612784) (xy 399.418984 -48.64225)
			(xy 399.369412 -48.664893) (xy 399.317122 -48.68025) (xy 399.263179 -48.68801) (xy 399.23593 -48.688498)
			(xy 399.235422 -48.688498) (xy 399.220629 -48.688362) (xy 399.191131 -48.686073) (xy 399.176494 -48.683926)
			(xy 399.164302 -48.681894) (xy 399.140934 -48.689768) (xy 399.07464 -48.758602) (xy 399.066474 -48.767816)
			(xy 399.059417 -48.791375) (xy 399.061178 -48.80356) (xy 399.064355 -48.821233) (xy 399.067787 -48.856979)
			(xy 399.068036 -48.874934) (xy 399.067554 -48.902185) (xy 399.062558 -48.93691) (xy 401.23313 -48.93691)
			(xy 401.237201 -48.881288) (xy 401.249327 -48.826851) (xy 401.26925 -48.77476) (xy 401.296546 -48.726125)
			(xy 401.330632 -48.681982) (xy 401.370781 -48.643273) (xy 401.416139 -48.610822) (xy 401.465739 -48.585321)
			(xy 401.518523 -48.567314) (xy 401.573366 -48.557184) (xy 401.6291 -48.555147) (xy 401.684537 -48.561247)
			(xy 401.738494 -48.575353) (xy 401.789823 -48.597165) (xy 401.837429 -48.626219) (xy 401.880297 -48.661894)
			(xy 401.917514 -48.703431) (xy 401.948287 -48.749944) (xy 401.971959 -48.800441) (xy 401.988027 -48.853848)
			(xy 401.996147 -48.909024) (xy 401.996656 -48.93691) (xy 401.996147 -48.964796) (xy 401.988027 -49.019972)
			(xy 401.971959 -49.073379) (xy 401.948287 -49.123876) (xy 401.917514 -49.170389) (xy 401.880297 -49.211926)
			(xy 401.837429 -49.247601) (xy 401.789823 -49.276655) (xy 401.738494 -49.298467) (xy 401.684537 -49.312573)
			(xy 401.6291 -49.318673) (xy 401.573366 -49.316636) (xy 401.518523 -49.306506) (xy 401.465739 -49.288499)
			(xy 401.416139 -49.262998) (xy 401.370781 -49.230547) (xy 401.330632 -49.191838) (xy 401.296546 -49.147695)
			(xy 401.26925 -49.09906) (xy 401.249327 -49.046969) (xy 401.237201 -48.992532) (xy 401.23313 -48.93691)
			(xy 399.062558 -48.93691) (xy 399.059793 -48.956131) (xy 399.044435 -49.008424) (xy 399.021792 -49.058)
			(xy 398.992325 -49.103849) (xy 398.956634 -49.145038) (xy 398.915444 -49.180729) (xy 398.869595 -49.210195)
			(xy 398.820019 -49.232838) (xy 398.767725 -49.248195) (xy 398.713779 -49.255954) (xy 398.686528 -49.256442)
			(xy 398.656733 -49.255892) (xy 398.597868 -49.24663) (xy 398.541158 -49.228327) (xy 398.487985 -49.201429)
			(xy 398.43964 -49.16659) (xy 398.397302 -49.124657) (xy 398.379188 -49.100994) (xy 398.371822 -49.090834)
			(xy 398.349978 -49.080166) (xy 398.241774 -49.082452) (xy 398.220184 -49.09439) (xy 398.213072 -49.104804)
			(xy 398.197792 -49.126745) (xy 398.162119 -49.166569) (xy 398.121237 -49.201025) (xy 398.075946 -49.229438)
			(xy 398.027133 -49.251253) (xy 397.975753 -49.266041) (xy 397.922813 -49.273514) (xy 397.89608 -49.273968)
			(xy 397.868827 -49.273561) (xy 397.814876 -49.265801) (xy 397.762578 -49.250443) (xy 397.712998 -49.227798)
			(xy 397.667145 -49.198328) (xy 397.625953 -49.162633) (xy 397.59026 -49.121439) (xy 397.560792 -49.075585)
			(xy 397.53815 -49.026003) (xy 397.522795 -48.973705) (xy 397.515038 -48.919753) (xy 396.192985 -48.919753)
			(xy 396.183503 -48.93998) (xy 396.15273 -48.986493) (xy 396.115513 -49.02803) (xy 396.072645 -49.063705)
			(xy 396.025039 -49.092759) (xy 395.97371 -49.114571) (xy 395.919753 -49.128677) (xy 395.864316 -49.134777)
			(xy 395.808582 -49.13274) (xy 395.753739 -49.12261) (xy 395.700955 -49.104603) (xy 395.651355 -49.079102)
			(xy 395.605997 -49.046651) (xy 395.565848 -49.007942) (xy 395.531762 -48.963799) (xy 395.504466 -48.915164)
			(xy 395.484543 -48.863073) (xy 395.472417 -48.808636) (xy 395.468346 -48.753014) (xy 393.749784 -48.753014)
			(xy 393.749298 -48.780265) (xy 393.741542 -48.834213) (xy 393.726187 -48.886508) (xy 393.703545 -48.936085)
			(xy 393.674079 -48.981935) (xy 393.638388 -49.023126) (xy 393.597197 -49.058817) (xy 393.551347 -49.088283)
			(xy 393.50177 -49.110925) (xy 393.449475 -49.12628) (xy 393.395527 -49.134036) (xy 393.341025 -49.134036)
			(xy 393.287077 -49.12628) (xy 393.234782 -49.110925) (xy 393.185205 -49.088283) (xy 393.139355 -49.058817)
			(xy 393.098164 -49.023126) (xy 393.062473 -48.981935) (xy 393.033007 -48.936085) (xy 393.010365 -48.886508)
			(xy 392.99501 -48.834213) (xy 392.987254 -48.780265) (xy 392.986768 -48.753014) (xy 392.9872 -48.726672)
			(xy 392.994455 -48.67449) (xy 393.008814 -48.623801) (xy 393.030006 -48.575567) (xy 393.057627 -48.530704)
			(xy 393.091153 -48.490065) (xy 393.129948 -48.45442) (xy 393.15136 -48.43907) (xy 393.163212 -48.430409)
			(xy 393.181649 -48.407576) (xy 393.192832 -48.380443) (xy 393.195836 -48.351249) (xy 393.190414 -48.322407)
			(xy 393.177014 -48.296298) (xy 393.156741 -48.275077) (xy 393.144248 -48.267366) (xy 393.119726 -48.25265)
			(xy 393.074972 -48.217048) (xy 393.03603 -48.175167) (xy 393.003774 -48.127944) (xy 392.978926 -48.076437)
			(xy 392.962042 -48.021798) (xy 392.9535 -47.965252) (xy 392.952986 -47.936658) (xy 373.327197 -47.936658)
			(xy 373.369485 -47.949073) (xy 373.419066 -47.971714) (xy 373.46492 -48.00118) (xy 373.506114 -48.036873)
			(xy 373.541809 -48.078065) (xy 373.571278 -48.123918) (xy 373.593921 -48.173498) (xy 373.609277 -48.225796)
			(xy 373.617035 -48.279747) (xy 373.617035 -48.334253) (xy 373.609277 -48.388204) (xy 373.593921 -48.440502)
			(xy 373.571278 -48.490082) (xy 373.541809 -48.535935) (xy 373.506114 -48.577127) (xy 373.46492 -48.61282)
			(xy 373.419066 -48.642286) (xy 373.369485 -48.664927) (xy 373.317186 -48.680281) (xy 373.263235 -48.688036)
			(xy 373.235982 -48.688498) (xy 373.235474 -48.688498) (xy 373.220681 -48.688367) (xy 373.191183 -48.686075)
			(xy 373.176546 -48.683926) (xy 373.164354 -48.681894) (xy 373.140986 -48.689768) (xy 373.074692 -48.758602)
			(xy 373.066637 -48.76788) (xy 373.059604 -48.791381) (xy 373.06123 -48.80356) (xy 373.064407 -48.821233)
			(xy 373.067839 -48.856979) (xy 373.068088 -48.874934) (xy 373.067654 -48.902187) (xy 373.062658 -48.93691)
			(xy 375.233182 -48.93691) (xy 375.237253 -48.881288) (xy 375.249379 -48.826851) (xy 375.269302 -48.77476)
			(xy 375.296598 -48.726125) (xy 375.330684 -48.681982) (xy 375.370833 -48.643273) (xy 375.416191 -48.610822)
			(xy 375.465791 -48.585321) (xy 375.518575 -48.567314) (xy 375.573418 -48.557184) (xy 375.629152 -48.555147)
			(xy 375.684589 -48.561247) (xy 375.738546 -48.575353) (xy 375.789875 -48.597165) (xy 375.837481 -48.626219)
			(xy 375.880349 -48.661894) (xy 375.917566 -48.703431) (xy 375.948339 -48.749944) (xy 375.972011 -48.800441)
			(xy 375.988079 -48.853848) (xy 375.996199 -48.909024) (xy 375.996708 -48.93691) (xy 375.996199 -48.964796)
			(xy 375.988079 -49.019972) (xy 375.972011 -49.073379) (xy 375.948339 -49.123876) (xy 375.917566 -49.170389)
			(xy 375.880349 -49.211926) (xy 375.837481 -49.247601) (xy 375.789875 -49.276655) (xy 375.738546 -49.298467)
			(xy 375.684589 -49.312573) (xy 375.629152 -49.318673) (xy 375.573418 -49.316636) (xy 375.518575 -49.306506)
			(xy 375.465791 -49.288499) (xy 375.416191 -49.262998) (xy 375.370833 -49.230547) (xy 375.330684 -49.191838)
			(xy 375.296598 -49.147695) (xy 375.269302 -49.09906) (xy 375.249379 -49.046969) (xy 375.237253 -48.992532)
			(xy 375.233182 -48.93691) (xy 373.062658 -48.93691) (xy 373.059892 -48.956138) (xy 373.044532 -49.008435)
			(xy 373.021885 -49.058013) (xy 372.992413 -49.103864) (xy 372.956717 -49.145055) (xy 372.915521 -49.180746)
			(xy 372.869666 -49.210211) (xy 372.820084 -49.232851) (xy 372.767785 -49.248204) (xy 372.713833 -49.255958)
			(xy 372.68658 -49.256442) (xy 372.656787 -49.255853) (xy 372.597923 -49.246599) (xy 372.541214 -49.228305)
			(xy 372.488041 -49.201414) (xy 372.439695 -49.166581) (xy 372.397355 -49.124654) (xy 372.37924 -49.100994)
			(xy 372.371874 -49.090834) (xy 372.35003 -49.080166) (xy 372.241826 -49.082452) (xy 372.220236 -49.09439)
			(xy 372.213124 -49.104804) (xy 372.197875 -49.126767) (xy 372.162196 -49.166591) (xy 372.121309 -49.201045)
			(xy 372.076013 -49.229456) (xy 372.027195 -49.251266) (xy 371.975811 -49.26605) (xy 371.922866 -49.273517)
			(xy 371.896132 -49.273968) (xy 371.868875 -49.273587) (xy 371.814915 -49.265833) (xy 371.762607 -49.250478)
			(xy 371.713018 -49.227835) (xy 371.667156 -49.198365) (xy 371.625955 -49.162667) (xy 371.590254 -49.12147)
			(xy 371.56078 -49.07561) (xy 371.538133 -49.026023) (xy 371.522774 -48.973717) (xy 371.515015 -48.919757)
			(xy 370.193035 -48.919757) (xy 370.183555 -48.93998) (xy 370.152782 -48.986493) (xy 370.115565 -49.02803)
			(xy 370.072697 -49.063705) (xy 370.025091 -49.092759) (xy 369.973762 -49.114571) (xy 369.919805 -49.128677)
			(xy 369.864368 -49.134777) (xy 369.808634 -49.13274) (xy 369.753791 -49.12261) (xy 369.701007 -49.104603)
			(xy 369.651407 -49.079102) (xy 369.606049 -49.046651) (xy 369.5659 -49.007942) (xy 369.531814 -48.963799)
			(xy 369.504518 -48.915164) (xy 369.484595 -48.863073) (xy 369.472469 -48.808636) (xy 369.468398 -48.753014)
			(xy 367.749836 -48.753014) (xy 367.74935 -48.780265) (xy 367.741594 -48.834213) (xy 367.726239 -48.886508)
			(xy 367.703597 -48.936085) (xy 367.674131 -48.981935) (xy 367.63844 -49.023126) (xy 367.597249 -49.058817)
			(xy 367.551399 -49.088283) (xy 367.501822 -49.110925) (xy 367.449527 -49.12628) (xy 367.395579 -49.134036)
			(xy 367.341077 -49.134036) (xy 367.287129 -49.12628) (xy 367.234834 -49.110925) (xy 367.185257 -49.088283)
			(xy 367.139407 -49.058817) (xy 367.098216 -49.023126) (xy 367.062525 -48.981935) (xy 367.033059 -48.936085)
			(xy 367.010417 -48.886508) (xy 366.995062 -48.834213) (xy 366.987306 -48.780265) (xy 366.98682 -48.753014)
			(xy 366.987273 -48.726673) (xy 366.994526 -48.674493) (xy 367.008884 -48.623805) (xy 367.030072 -48.575572)
			(xy 367.05769 -48.530709) (xy 367.091212 -48.490069) (xy 367.130003 -48.454422) (xy 367.151412 -48.43907)
			(xy 367.163257 -48.430403) (xy 367.181684 -48.407569) (xy 367.19286 -48.380438) (xy 367.195862 -48.35125)
			(xy 367.190443 -48.322412) (xy 367.17705 -48.296304) (xy 367.156788 -48.275081) (xy 367.1443 -48.267366)
			(xy 367.11979 -48.25263) (xy 367.075033 -48.217034) (xy 367.036089 -48.175157) (xy 367.003831 -48.127938)
			(xy 366.978981 -48.076433) (xy 366.962095 -48.021796) (xy 366.953552 -47.965251) (xy 366.953038 -47.936658)
			(xy 335.226822 -47.936658) (xy 335.26921 -47.949107) (xy 335.318783 -47.971749) (xy 335.364628 -48.001215)
			(xy 335.405814 -48.036906) (xy 335.441502 -48.078094) (xy 335.470964 -48.123942) (xy 335.493603 -48.173516)
			(xy 335.508956 -48.225807) (xy 335.516712 -48.279751) (xy 335.516712 -48.334249) (xy 335.508956 -48.388193)
			(xy 335.493603 -48.440484) (xy 335.470964 -48.490058) (xy 335.441502 -48.535906) (xy 335.405814 -48.577094)
			(xy 335.364628 -48.612785) (xy 335.318783 -48.642251) (xy 335.26921 -48.664893) (xy 335.21692 -48.68025)
			(xy 335.162977 -48.68801) (xy 335.135728 -48.688498) (xy 335.13522 -48.688498) (xy 335.120427 -48.688362)
			(xy 335.090929 -48.686073) (xy 335.076292 -48.683926) (xy 335.0641 -48.681894) (xy 335.040732 -48.689768)
			(xy 334.974438 -48.758602) (xy 334.966272 -48.767816) (xy 334.959215 -48.791375) (xy 334.960976 -48.80356)
			(xy 334.964153 -48.821233) (xy 334.967585 -48.856979) (xy 334.967834 -48.874934) (xy 334.967354 -48.902185)
			(xy 334.962358 -48.93691) (xy 337.132928 -48.93691) (xy 337.136999 -48.881288) (xy 337.149125 -48.826851)
			(xy 337.169048 -48.77476) (xy 337.196344 -48.726125) (xy 337.23043 -48.681982) (xy 337.270579 -48.643273)
			(xy 337.315937 -48.610822) (xy 337.365537 -48.585321) (xy 337.418321 -48.567314) (xy 337.473164 -48.557184)
			(xy 337.528898 -48.555147) (xy 337.584335 -48.561247) (xy 337.638292 -48.575353) (xy 337.689621 -48.597165)
			(xy 337.737227 -48.626219) (xy 337.780095 -48.661894) (xy 337.817312 -48.703431) (xy 337.848085 -48.749944)
			(xy 337.871757 -48.800441) (xy 337.887825 -48.853848) (xy 337.895945 -48.909024) (xy 337.896454 -48.93691)
			(xy 337.895945 -48.964796) (xy 337.887825 -49.019972) (xy 337.871757 -49.073379) (xy 337.848085 -49.123876)
			(xy 337.817312 -49.170389) (xy 337.780095 -49.211926) (xy 337.737227 -49.247601) (xy 337.689621 -49.276655)
			(xy 337.638292 -49.298467) (xy 337.584335 -49.312573) (xy 337.528898 -49.318673) (xy 337.473164 -49.316636)
			(xy 337.418321 -49.306506) (xy 337.365537 -49.288499) (xy 337.315937 -49.262998) (xy 337.270579 -49.230547)
			(xy 337.23043 -49.191838) (xy 337.196344 -49.147695) (xy 337.169048 -49.09906) (xy 337.149125 -49.046969)
			(xy 337.136999 -48.992532) (xy 337.132928 -48.93691) (xy 334.962358 -48.93691) (xy 334.959593 -48.956131)
			(xy 334.944235 -49.008425) (xy 334.921592 -49.058) (xy 334.892125 -49.103849) (xy 334.856433 -49.145038)
			(xy 334.815243 -49.180729) (xy 334.769393 -49.210196) (xy 334.719817 -49.232838) (xy 334.667524 -49.248195)
			(xy 334.613577 -49.255954) (xy 334.586326 -49.256442) (xy 334.556531 -49.255893) (xy 334.497665 -49.246631)
			(xy 334.440956 -49.228328) (xy 334.387783 -49.20143) (xy 334.339438 -49.16659) (xy 334.2971 -49.124657)
			(xy 334.278986 -49.100994) (xy 334.27162 -49.090834) (xy 334.249776 -49.080166) (xy 334.141572 -49.082452)
			(xy 334.119982 -49.09439) (xy 334.11287 -49.104804) (xy 334.097591 -49.126746) (xy 334.061918 -49.16657)
			(xy 334.021036 -49.201026) (xy 333.975745 -49.229439) (xy 333.926931 -49.251253) (xy 333.875552 -49.266041)
			(xy 333.822611 -49.273514) (xy 333.795878 -49.273968) (xy 333.768625 -49.273561) (xy 333.714674 -49.265801)
			(xy 333.662376 -49.250442) (xy 333.612797 -49.227797) (xy 333.566944 -49.198327) (xy 333.525752 -49.162632)
			(xy 333.490059 -49.121438) (xy 333.460592 -49.075584) (xy 333.43795 -49.026003) (xy 333.422595 -48.973705)
			(xy 333.414838 -48.919753) (xy 333.143194 -48.919753) (xy 333.142089 -48.927262) (xy 333.126021 -48.980669)
			(xy 333.102349 -49.031166) (xy 333.071576 -49.077679) (xy 333.034359 -49.119216) (xy 332.991491 -49.154891)
			(xy 332.943885 -49.183945) (xy 332.892556 -49.205757) (xy 332.838599 -49.219863) (xy 332.783162 -49.225963)
			(xy 332.727428 -49.223926) (xy 332.672585 -49.213796) (xy 332.619801 -49.195789) (xy 332.570201 -49.170288)
			(xy 332.524843 -49.137837) (xy 332.484694 -49.099128) (xy 332.450608 -49.054985) (xy 332.423312 -49.00635)
			(xy 332.403389 -48.954259) (xy 332.391263 -48.899822) (xy 332.387192 -48.8442) (xy 332.120597 -48.8442)
			(xy 332.106973 -48.889483) (xy 332.083301 -48.93998) (xy 332.052528 -48.986493) (xy 332.015311 -49.02803)
			(xy 331.972443 -49.063705) (xy 331.924837 -49.092759) (xy 331.873508 -49.114571) (xy 331.819551 -49.128677)
			(xy 331.764114 -49.134777) (xy 331.70838 -49.13274) (xy 331.653537 -49.12261) (xy 331.600753 -49.104603)
			(xy 331.551153 -49.079102) (xy 331.505795 -49.046651) (xy 331.465646 -49.007942) (xy 331.43156 -48.963799)
			(xy 331.404264 -48.915164) (xy 331.384341 -48.863073) (xy 331.372215 -48.808636) (xy 331.368144 -48.753014)
			(xy 329.649582 -48.753014) (xy 329.649096 -48.780265) (xy 329.64134 -48.834213) (xy 329.625985 -48.886508)
			(xy 329.603343 -48.936085) (xy 329.573877 -48.981935) (xy 329.538186 -49.023126) (xy 329.496995 -49.058817)
			(xy 329.451145 -49.088283) (xy 329.401568 -49.110925) (xy 329.349273 -49.12628) (xy 329.295325 -49.134036)
			(xy 329.240823 -49.134036) (xy 329.186875 -49.12628) (xy 329.13458 -49.110925) (xy 329.085003 -49.088283)
			(xy 329.039153 -49.058817) (xy 328.997962 -49.023126) (xy 328.962271 -48.981935) (xy 328.932805 -48.936085)
			(xy 328.910163 -48.886508) (xy 328.894808 -48.834213) (xy 328.887052 -48.780265) (xy 328.886566 -48.753014)
			(xy 328.886999 -48.726672) (xy 328.894254 -48.67449) (xy 328.908613 -48.623801) (xy 328.929804 -48.575567)
			(xy 328.957425 -48.530705) (xy 328.990952 -48.490065) (xy 329.029746 -48.45442) (xy 329.051158 -48.43907)
			(xy 329.06301 -48.430409) (xy 329.081448 -48.407576) (xy 329.092631 -48.380443) (xy 329.095635 -48.351249)
			(xy 329.090213 -48.322407) (xy 329.076812 -48.296298) (xy 329.05654 -48.275077) (xy 329.044046 -48.267366)
			(xy 329.019524 -48.25265) (xy 328.974769 -48.217049) (xy 328.935828 -48.175167) (xy 328.903572 -48.127944)
			(xy 328.878724 -48.076437) (xy 328.86184 -48.021798) (xy 328.853298 -47.965252) (xy 328.852784 -47.936658)
			(xy 309.226999 -47.936658) (xy 309.269284 -47.949072) (xy 309.318865 -47.971713) (xy 309.364719 -48.00118)
			(xy 309.405913 -48.036872) (xy 309.441608 -48.078065) (xy 309.471077 -48.123917) (xy 309.493721 -48.173498)
			(xy 309.509077 -48.225796) (xy 309.516835 -48.279747) (xy 309.516835 -48.334253) (xy 309.509077 -48.388204)
			(xy 309.493721 -48.440502) (xy 309.471077 -48.490083) (xy 309.441608 -48.535935) (xy 309.405913 -48.577128)
			(xy 309.364719 -48.61282) (xy 309.318865 -48.642287) (xy 309.269284 -48.664928) (xy 309.216985 -48.680282)
			(xy 309.163033 -48.688036) (xy 309.13578 -48.688498) (xy 309.135272 -48.688498) (xy 309.120479 -48.688368)
			(xy 309.090981 -48.686075) (xy 309.076344 -48.683926) (xy 309.064152 -48.681894) (xy 309.040784 -48.689768)
			(xy 308.97449 -48.758602) (xy 308.966435 -48.76788) (xy 308.959402 -48.791381) (xy 308.961028 -48.80356)
			(xy 308.964206 -48.821233) (xy 308.967637 -48.856979) (xy 308.967886 -48.874934) (xy 308.967454 -48.902187)
			(xy 308.962458 -48.93691) (xy 311.13298 -48.93691) (xy 311.137051 -48.881288) (xy 311.149177 -48.826851)
			(xy 311.1691 -48.77476) (xy 311.196396 -48.726125) (xy 311.230482 -48.681982) (xy 311.270631 -48.643273)
			(xy 311.315989 -48.610822) (xy 311.365589 -48.585321) (xy 311.418373 -48.567314) (xy 311.473216 -48.557184)
			(xy 311.52895 -48.555147) (xy 311.584387 -48.561247) (xy 311.638344 -48.575353) (xy 311.689673 -48.597165)
			(xy 311.737279 -48.626219) (xy 311.780147 -48.661894) (xy 311.817364 -48.703431) (xy 311.848137 -48.749944)
			(xy 311.871809 -48.800441) (xy 311.887877 -48.853848) (xy 311.895997 -48.909024) (xy 311.896506 -48.93691)
			(xy 311.895997 -48.964796) (xy 311.887877 -49.019972) (xy 311.871809 -49.073379) (xy 311.848137 -49.123876)
			(xy 311.817364 -49.170389) (xy 311.780147 -49.211926) (xy 311.737279 -49.247601) (xy 311.689673 -49.276655)
			(xy 311.638344 -49.298467) (xy 311.584387 -49.312573) (xy 311.52895 -49.318673) (xy 311.473216 -49.316636)
			(xy 311.418373 -49.306506) (xy 311.365589 -49.288499) (xy 311.315989 -49.262998) (xy 311.270631 -49.230547)
			(xy 311.230482 -49.191838) (xy 311.196396 -49.147695) (xy 311.1691 -49.09906) (xy 311.149177 -49.046969)
			(xy 311.137051 -48.992532) (xy 311.13298 -48.93691) (xy 308.962458 -48.93691) (xy 308.959692 -48.956138)
			(xy 308.944331 -49.008435) (xy 308.921685 -49.058014) (xy 308.892213 -49.103865) (xy 308.856516 -49.145055)
			(xy 308.81532 -49.180747) (xy 308.769465 -49.210212) (xy 308.719882 -49.232851) (xy 308.667583 -49.248204)
			(xy 308.613631 -49.255958) (xy 308.586378 -49.256442) (xy 308.556585 -49.255855) (xy 308.497721 -49.246601)
			(xy 308.441012 -49.228305) (xy 308.387838 -49.201414) (xy 308.339493 -49.166581) (xy 308.297153 -49.124654)
			(xy 308.279038 -49.100994) (xy 308.271672 -49.090834) (xy 308.249828 -49.080166) (xy 308.141624 -49.082452)
			(xy 308.120034 -49.09439) (xy 308.112922 -49.104804) (xy 308.097674 -49.126768) (xy 308.061995 -49.166592)
			(xy 308.021108 -49.201046) (xy 307.975812 -49.229457) (xy 307.926993 -49.251267) (xy 307.875609 -49.26605)
			(xy 307.822664 -49.273517) (xy 307.79593 -49.273968) (xy 307.768673 -49.273587) (xy 307.714713 -49.265833)
			(xy 307.662406 -49.250478) (xy 307.612817 -49.227835) (xy 307.566955 -49.198364) (xy 307.525754 -49.162667)
			(xy 307.490054 -49.121469) (xy 307.46058 -49.07561) (xy 307.437933 -49.026022) (xy 307.422574 -48.973716)
			(xy 307.414815 -48.919757) (xy 307.143245 -48.919757) (xy 307.142141 -48.927262) (xy 307.126073 -48.980669)
			(xy 307.102401 -49.031166) (xy 307.071628 -49.077679) (xy 307.034411 -49.119216) (xy 306.991543 -49.154891)
			(xy 306.943937 -49.183945) (xy 306.892608 -49.205757) (xy 306.838651 -49.219863) (xy 306.783214 -49.225963)
			(xy 306.72748 -49.223926) (xy 306.672637 -49.213796) (xy 306.619853 -49.195789) (xy 306.570253 -49.170288)
			(xy 306.524895 -49.137837) (xy 306.484746 -49.099128) (xy 306.45066 -49.054985) (xy 306.423364 -49.00635)
			(xy 306.403441 -48.954259) (xy 306.391315 -48.899822) (xy 306.387244 -48.8442) (xy 306.120649 -48.8442)
			(xy 306.107025 -48.889483) (xy 306.083353 -48.93998) (xy 306.05258 -48.986493) (xy 306.015363 -49.02803)
			(xy 305.972495 -49.063705) (xy 305.924889 -49.092759) (xy 305.87356 -49.114571) (xy 305.819603 -49.128677)
			(xy 305.764166 -49.134777) (xy 305.708432 -49.13274) (xy 305.653589 -49.12261) (xy 305.600805 -49.104603)
			(xy 305.551205 -49.079102) (xy 305.505847 -49.046651) (xy 305.465698 -49.007942) (xy 305.431612 -48.963799)
			(xy 305.404316 -48.915164) (xy 305.384393 -48.863073) (xy 305.372267 -48.808636) (xy 305.368196 -48.753014)
			(xy 303.649634 -48.753014) (xy 303.649148 -48.780265) (xy 303.641392 -48.834213) (xy 303.626037 -48.886508)
			(xy 303.603395 -48.936085) (xy 303.573929 -48.981935) (xy 303.538238 -49.023126) (xy 303.497047 -49.058817)
			(xy 303.451197 -49.088283) (xy 303.40162 -49.110925) (xy 303.349325 -49.12628) (xy 303.295377 -49.134036)
			(xy 303.240875 -49.134036) (xy 303.186927 -49.12628) (xy 303.134632 -49.110925) (xy 303.085055 -49.088283)
			(xy 303.039205 -49.058817) (xy 302.998014 -49.023126) (xy 302.962323 -48.981935) (xy 302.932857 -48.936085)
			(xy 302.910215 -48.886508) (xy 302.89486 -48.834213) (xy 302.887104 -48.780265) (xy 302.886618 -48.753014)
			(xy 302.887071 -48.726673) (xy 302.894325 -48.674493) (xy 302.908682 -48.623805) (xy 302.92987 -48.575572)
			(xy 302.957488 -48.530709) (xy 302.99101 -48.490068) (xy 303.0298 -48.454422) (xy 303.05121 -48.43907)
			(xy 303.063055 -48.430403) (xy 303.081482 -48.407569) (xy 303.092658 -48.380438) (xy 303.095661 -48.35125)
			(xy 303.090242 -48.322412) (xy 303.076849 -48.296304) (xy 303.056586 -48.275081) (xy 303.044098 -48.267366)
			(xy 303.019588 -48.252631) (xy 302.974831 -48.217035) (xy 302.935887 -48.175158) (xy 302.903629 -48.127938)
			(xy 302.878778 -48.076433) (xy 302.861893 -48.021796) (xy 302.85335 -47.965251) (xy 302.852836 -47.936658)
			(xy 283.226925 -47.936658) (xy 283.269313 -47.949108) (xy 283.318885 -47.97175) (xy 283.36473 -48.001217)
			(xy 283.405916 -48.036907) (xy 283.441603 -48.078095) (xy 283.471065 -48.123943) (xy 283.493703 -48.173517)
			(xy 283.509056 -48.225808) (xy 283.516812 -48.279751) (xy 283.516812 -48.334249) (xy 283.509056 -48.388192)
			(xy 283.493703 -48.440483) (xy 283.471065 -48.490057) (xy 283.441603 -48.535905) (xy 283.405916 -48.577093)
			(xy 283.36473 -48.612783) (xy 283.318885 -48.64225) (xy 283.269313 -48.664892) (xy 283.217024 -48.68025)
			(xy 283.163081 -48.68801) (xy 283.135832 -48.688498) (xy 283.135324 -48.688498) (xy 283.120531 -48.688362)
			(xy 283.091033 -48.686073) (xy 283.076396 -48.683926) (xy 283.064204 -48.681894) (xy 283.040836 -48.689768)
			(xy 282.974542 -48.758602) (xy 282.966376 -48.767816) (xy 282.959319 -48.791375) (xy 282.96108 -48.80356)
			(xy 282.964257 -48.821233) (xy 282.967689 -48.856979) (xy 282.967938 -48.874934) (xy 282.967454 -48.902185)
			(xy 282.962459 -48.93691) (xy 285.133032 -48.93691) (xy 285.137103 -48.881288) (xy 285.149229 -48.826851)
			(xy 285.169152 -48.77476) (xy 285.196448 -48.726125) (xy 285.230534 -48.681982) (xy 285.270683 -48.643273)
			(xy 285.316041 -48.610822) (xy 285.365641 -48.585321) (xy 285.418425 -48.567314) (xy 285.473268 -48.557184)
			(xy 285.529002 -48.555147) (xy 285.584439 -48.561247) (xy 285.638396 -48.575353) (xy 285.689725 -48.597165)
			(xy 285.737331 -48.626219) (xy 285.780199 -48.661894) (xy 285.817416 -48.703431) (xy 285.848189 -48.749944)
			(xy 285.871861 -48.800441) (xy 285.887929 -48.853848) (xy 285.896049 -48.909024) (xy 285.896558 -48.93691)
			(xy 285.896049 -48.964796) (xy 285.887929 -49.019972) (xy 285.871861 -49.073379) (xy 285.848189 -49.123876)
			(xy 285.817416 -49.170389) (xy 285.780199 -49.211926) (xy 285.737331 -49.247601) (xy 285.689725 -49.276655)
			(xy 285.638396 -49.298467) (xy 285.584439 -49.312573) (xy 285.529002 -49.318673) (xy 285.473268 -49.316636)
			(xy 285.418425 -49.306506) (xy 285.365641 -49.288499) (xy 285.316041 -49.262998) (xy 285.270683 -49.230547)
			(xy 285.230534 -49.191838) (xy 285.196448 -49.147695) (xy 285.169152 -49.09906) (xy 285.149229 -49.046969)
			(xy 285.137103 -48.992532) (xy 285.133032 -48.93691) (xy 282.962459 -48.93691) (xy 282.959694 -48.956131)
			(xy 282.944336 -49.008424) (xy 282.921693 -49.057999) (xy 282.892226 -49.103848) (xy 282.856534 -49.145037)
			(xy 282.815345 -49.180728) (xy 282.769496 -49.210195) (xy 282.71992 -49.232837) (xy 282.667627 -49.248194)
			(xy 282.613681 -49.255954) (xy 282.58643 -49.256442) (xy 282.556635 -49.25589) (xy 282.49777 -49.246629)
			(xy 282.44106 -49.228326) (xy 282.387887 -49.201429) (xy 282.339543 -49.16659) (xy 282.297204 -49.124657)
			(xy 282.27909 -49.100994) (xy 282.271724 -49.090834) (xy 282.24988 -49.080166) (xy 282.141676 -49.082452)
			(xy 282.120086 -49.09439) (xy 282.112974 -49.104804) (xy 282.097693 -49.126744) (xy 282.06202 -49.166568)
			(xy 282.021138 -49.201024) (xy 281.975847 -49.229438) (xy 281.927035 -49.251252) (xy 281.875655 -49.26604)
			(xy 281.822715 -49.273514) (xy 281.795982 -49.273968) (xy 281.768729 -49.273561) (xy 281.714777 -49.265801)
			(xy 281.662479 -49.250443) (xy 281.612899 -49.227799) (xy 281.567046 -49.198329) (xy 281.525854 -49.162634)
			(xy 281.49016 -49.121439) (xy 281.460693 -49.075585) (xy 281.438051 -49.026004) (xy 281.422695 -48.973705)
			(xy 281.414938 -48.919753) (xy 280.092887 -48.919753) (xy 280.083405 -48.93998) (xy 280.052632 -48.986493)
			(xy 280.015415 -49.02803) (xy 279.972547 -49.063705) (xy 279.924941 -49.092759) (xy 279.873612 -49.114571)
			(xy 279.819655 -49.128677) (xy 279.764218 -49.134777) (xy 279.708484 -49.13274) (xy 279.653641 -49.12261)
			(xy 279.600857 -49.104603) (xy 279.551257 -49.079102) (xy 279.505899 -49.046651) (xy 279.46575 -49.007942)
			(xy 279.431664 -48.963799) (xy 279.404368 -48.915164) (xy 279.384445 -48.863073) (xy 279.372319 -48.808636)
			(xy 279.368248 -48.753014) (xy 277.649686 -48.753014) (xy 277.6492 -48.780265) (xy 277.641444 -48.834213)
			(xy 277.626089 -48.886508) (xy 277.603447 -48.936085) (xy 277.573981 -48.981935) (xy 277.53829 -49.023126)
			(xy 277.497099 -49.058817) (xy 277.451249 -49.088283) (xy 277.401672 -49.110925) (xy 277.349377 -49.12628)
			(xy 277.295429 -49.134036) (xy 277.240927 -49.134036) (xy 277.186979 -49.12628) (xy 277.134684 -49.110925)
			(xy 277.085107 -49.088283) (xy 277.039257 -49.058817) (xy 276.998066 -49.023126) (xy 276.962375 -48.981935)
			(xy 276.932909 -48.936085) (xy 276.910267 -48.886508) (xy 276.894912 -48.834213) (xy 276.887156 -48.780265)
			(xy 276.88667 -48.753014) (xy 276.887101 -48.726672) (xy 276.894356 -48.67449) (xy 276.908715 -48.623801)
			(xy 276.929907 -48.575567) (xy 276.957528 -48.530704) (xy 276.991055 -48.490065) (xy 277.02985 -48.45442)
			(xy 277.051262 -48.43907) (xy 277.063114 -48.430409) (xy 277.081551 -48.407576) (xy 277.092733 -48.380442)
			(xy 277.095737 -48.351249) (xy 277.090315 -48.322407) (xy 277.076915 -48.296298) (xy 277.056643 -48.275078)
			(xy 277.04415 -48.267366) (xy 277.019629 -48.252649) (xy 276.974874 -48.217048) (xy 276.935933 -48.175167)
			(xy 276.903677 -48.127944) (xy 276.878828 -48.076437) (xy 276.861944 -48.021798) (xy 276.853402 -47.965252)
			(xy 276.852888 -47.936658) (xy 257.227099 -47.936658) (xy 257.269387 -47.949073) (xy 257.318967 -47.971714)
			(xy 257.364821 -48.001181) (xy 257.406015 -48.036874) (xy 257.441709 -48.078066) (xy 257.471178 -48.123919)
			(xy 257.493821 -48.173498) (xy 257.509177 -48.225796) (xy 257.516935 -48.279747) (xy 257.516935 -48.334253)
			(xy 257.509177 -48.388204) (xy 257.493821 -48.440502) (xy 257.471178 -48.490081) (xy 257.441709 -48.535934)
			(xy 257.406015 -48.577126) (xy 257.364821 -48.612819) (xy 257.318967 -48.642286) (xy 257.269387 -48.664927)
			(xy 257.217088 -48.680281) (xy 257.163137 -48.688036) (xy 257.135884 -48.688498) (xy 257.135376 -48.688498)
			(xy 257.120583 -48.688367) (xy 257.091085 -48.686075) (xy 257.076448 -48.683926) (xy 257.064256 -48.681894)
			(xy 257.040888 -48.689768) (xy 256.974594 -48.758602) (xy 256.966539 -48.76788) (xy 256.959506 -48.791381)
			(xy 256.961132 -48.80356) (xy 256.964309 -48.821233) (xy 256.967741 -48.856979) (xy 256.96799 -48.874934)
			(xy 256.967554 -48.902187) (xy 256.962558 -48.93691) (xy 259.133084 -48.93691) (xy 259.137155 -48.881288)
			(xy 259.149281 -48.826851) (xy 259.169204 -48.77476) (xy 259.1965 -48.726125) (xy 259.230586 -48.681982)
			(xy 259.270735 -48.643273) (xy 259.316093 -48.610822) (xy 259.365693 -48.585321) (xy 259.418477 -48.567314)
			(xy 259.47332 -48.557184) (xy 259.529054 -48.555147) (xy 259.584491 -48.561247) (xy 259.638448 -48.575353)
			(xy 259.689777 -48.597165) (xy 259.737383 -48.626219) (xy 259.780251 -48.661894) (xy 259.817468 -48.703431)
			(xy 259.848241 -48.749944) (xy 259.871913 -48.800441) (xy 259.887981 -48.853848) (xy 259.896101 -48.909024)
			(xy 259.89661 -48.93691) (xy 259.896101 -48.964796) (xy 259.887981 -49.019972) (xy 259.871913 -49.073379)
			(xy 259.848241 -49.123876) (xy 259.817468 -49.170389) (xy 259.780251 -49.211926) (xy 259.737383 -49.247601)
			(xy 259.689777 -49.276655) (xy 259.638448 -49.298467) (xy 259.584491 -49.312573) (xy 259.529054 -49.318673)
			(xy 259.47332 -49.316636) (xy 259.418477 -49.306506) (xy 259.365693 -49.288499) (xy 259.316093 -49.262998)
			(xy 259.270735 -49.230547) (xy 259.230586 -49.191838) (xy 259.1965 -49.147695) (xy 259.169204 -49.09906)
			(xy 259.149281 -49.046969) (xy 259.137155 -48.992532) (xy 259.133084 -48.93691) (xy 256.962558 -48.93691)
			(xy 256.959792 -48.956137) (xy 256.944432 -49.008434) (xy 256.921785 -49.058013) (xy 256.892314 -49.103864)
			(xy 256.856617 -49.145054) (xy 256.815422 -49.180745) (xy 256.769567 -49.21021) (xy 256.719985 -49.23285)
			(xy 256.667686 -49.248203) (xy 256.613735 -49.255957) (xy 256.586482 -49.256442) (xy 256.556689 -49.255852)
			(xy 256.497825 -49.246598) (xy 256.441117 -49.228304) (xy 256.387943 -49.201413) (xy 256.339598 -49.166581)
			(xy 256.297257 -49.124654) (xy 256.279142 -49.100994) (xy 256.271776 -49.090834) (xy 256.249932 -49.080166)
			(xy 256.141728 -49.082452) (xy 256.120138 -49.09439) (xy 256.113026 -49.104804) (xy 256.097776 -49.126766)
			(xy 256.062097 -49.16659) (xy 256.02121 -49.201045) (xy 255.975914 -49.229455) (xy 255.927097 -49.251266)
			(xy 255.875713 -49.26605) (xy 255.822768 -49.273517) (xy 255.796034 -49.273968) (xy 255.768777 -49.273587)
			(xy 255.714816 -49.265834) (xy 255.662509 -49.250479) (xy 255.612919 -49.227836) (xy 255.567057 -49.198366)
			(xy 255.525856 -49.162668) (xy 255.490155 -49.12147) (xy 255.46068 -49.075611) (xy 255.438033 -49.026023)
			(xy 255.422674 -48.973717) (xy 255.414915 -48.919757) (xy 255.143349 -48.919757) (xy 255.142245 -48.927262)
			(xy 255.126177 -48.980669) (xy 255.102505 -49.031166) (xy 255.071732 -49.077679) (xy 255.034515 -49.119216)
			(xy 254.991647 -49.154891) (xy 254.944041 -49.183945) (xy 254.892712 -49.205757) (xy 254.838755 -49.219863)
			(xy 254.783318 -49.225963) (xy 254.727584 -49.223926) (xy 254.672741 -49.213796) (xy 254.619957 -49.195789)
			(xy 254.570357 -49.170288) (xy 254.524999 -49.137837) (xy 254.48485 -49.099128) (xy 254.450764 -49.054985)
			(xy 254.423468 -49.00635) (xy 254.403545 -48.954259) (xy 254.391419 -48.899822) (xy 254.387348 -48.8442)
			(xy 254.120753 -48.8442) (xy 254.107129 -48.889483) (xy 254.083457 -48.93998) (xy 254.052684 -48.986493)
			(xy 254.015467 -49.02803) (xy 253.972599 -49.063705) (xy 253.924993 -49.092759) (xy 253.873664 -49.114571)
			(xy 253.819707 -49.128677) (xy 253.76427 -49.134777) (xy 253.708536 -49.13274) (xy 253.653693 -49.12261)
			(xy 253.600909 -49.104603) (xy 253.551309 -49.079102) (xy 253.505951 -49.046651) (xy 253.465802 -49.007942)
			(xy 253.431716 -48.963799) (xy 253.40442 -48.915164) (xy 253.384497 -48.863073) (xy 253.372371 -48.808636)
			(xy 253.3683 -48.753014) (xy 251.649738 -48.753014) (xy 251.649252 -48.780265) (xy 251.641496 -48.834213)
			(xy 251.626141 -48.886508) (xy 251.603499 -48.936085) (xy 251.574033 -48.981935) (xy 251.538342 -49.023126)
			(xy 251.497151 -49.058817) (xy 251.451301 -49.088283) (xy 251.401724 -49.110925) (xy 251.349429 -49.12628)
			(xy 251.295481 -49.134036) (xy 251.240979 -49.134036) (xy 251.187031 -49.12628) (xy 251.134736 -49.110925)
			(xy 251.085159 -49.088283) (xy 251.039309 -49.058817) (xy 250.998118 -49.023126) (xy 250.962427 -48.981935)
			(xy 250.932961 -48.936085) (xy 250.910319 -48.886508) (xy 250.894964 -48.834213) (xy 250.887208 -48.780265)
			(xy 250.886722 -48.753014) (xy 250.887174 -48.726673) (xy 250.894427 -48.674493) (xy 250.908785 -48.623805)
			(xy 250.929974 -48.575572) (xy 250.957591 -48.530709) (xy 250.991114 -48.490068) (xy 251.029905 -48.454422)
			(xy 251.051314 -48.43907) (xy 251.063158 -48.430403) (xy 251.081585 -48.407568) (xy 251.092761 -48.380438)
			(xy 251.095763 -48.35125) (xy 251.090344 -48.322412) (xy 251.076951 -48.296305) (xy 251.05669 -48.275081)
			(xy 251.044202 -48.267366) (xy 251.019693 -48.252629) (xy 250.974935 -48.217034) (xy 250.935991 -48.175157)
			(xy 250.903733 -48.127937) (xy 250.878883 -48.076433) (xy 250.861997 -48.021796) (xy 250.853454 -47.965251)
			(xy 250.85294 -47.936658) (xy 236.019856 -47.936658) (xy 236.017989 -47.955012) (xy 236.004952 -48.010297)
			(xy 235.983863 -48.063039) (xy 235.955189 -48.112072) (xy 235.919562 -48.156312) (xy 235.877771 -48.194782)
			(xy 235.830739 -48.226632) (xy 235.779504 -48.251157) (xy 235.7252 -48.267816) (xy 235.669027 -48.27624)
			(xy 235.640626 -48.276764) (xy 235.613256 -48.276291) (xy 235.559077 -48.268477) (xy 235.506573 -48.252989)
			(xy 235.456826 -48.230149) (xy 235.41086 -48.200425) (xy 235.389928 -48.182784) (xy 235.389674 -48.18253)
			(xy 235.382576 -48.17696) (xy 235.365668 -48.170705) (xy 235.356654 -48.170338) (xy 235.289598 -48.170338)
			(xy 235.28058 -48.170686) (xy 235.263663 -48.176939) (xy 235.256578 -48.18253) (xy 235.25607 -48.183038)
			(xy 235.235134 -48.200617) (xy 235.189199 -48.230256) (xy 235.139504 -48.253034) (xy 235.087066 -48.268486)
			(xy 235.032959 -48.276293) (xy 235.005626 -48.276764) (xy 234.978369 -48.276391) (xy 234.924409 -48.268636)
			(xy 234.872102 -48.25328) (xy 234.822513 -48.230637) (xy 234.776651 -48.201166) (xy 234.73545 -48.165468)
			(xy 234.69975 -48.12427) (xy 234.670276 -48.07841) (xy 234.647629 -48.028823) (xy 234.63227 -47.976517)
			(xy 234.624511 -47.922557) (xy 213.515705 -47.922557) (xy 213.515956 -47.936658) (xy 213.515492 -47.962999)
			(xy 213.508242 -48.015179) (xy 213.493888 -48.065867) (xy 213.472701 -48.1141) (xy 213.445085 -48.158963)
			(xy 213.411563 -48.199604) (xy 213.372773 -48.23525) (xy 213.351364 -48.250602) (xy 213.339537 -48.259295)
			(xy 213.321096 -48.282119) (xy 213.309908 -48.309246) (xy 213.3069 -48.338435) (xy 213.312317 -48.367273)
			(xy 213.325715 -48.393379) (xy 213.345984 -48.414596) (xy 213.358476 -48.422306) (xy 213.383012 -48.437)
			(xy 213.427771 -48.472602) (xy 213.466714 -48.514485) (xy 213.49897 -48.561712) (xy 213.523816 -48.613224)
			(xy 213.540695 -48.667868) (xy 213.549229 -48.724418) (xy 213.549738 -48.753014) (xy 215.2683 -48.753014)
			(xy 215.272371 -48.697392) (xy 215.284497 -48.642955) (xy 215.30442 -48.590864) (xy 215.331716 -48.542229)
			(xy 215.365802 -48.498086) (xy 215.405951 -48.459377) (xy 215.451309 -48.426926) (xy 215.500909 -48.401425)
			(xy 215.553693 -48.383418) (xy 215.608536 -48.373288) (xy 215.66427 -48.371251) (xy 215.719707 -48.377351)
			(xy 215.773664 -48.391457) (xy 215.824993 -48.413269) (xy 215.872599 -48.442323) (xy 215.915467 -48.477998)
			(xy 215.952684 -48.519535) (xy 215.983457 -48.566048) (xy 216.007129 -48.616545) (xy 216.023197 -48.669952)
			(xy 216.031317 -48.725128) (xy 216.031826 -48.753014) (xy 216.031317 -48.7809) (xy 216.023197 -48.836076)
			(xy 216.020753 -48.8442) (xy 216.287348 -48.8442) (xy 216.291419 -48.788578) (xy 216.303545 -48.734141)
			(xy 216.323468 -48.68205) (xy 216.350764 -48.633415) (xy 216.38485 -48.589272) (xy 216.424999 -48.550563)
			(xy 216.470357 -48.518112) (xy 216.519957 -48.492611) (xy 216.572741 -48.474604) (xy 216.627584 -48.464474)
			(xy 216.683318 -48.462437) (xy 216.738755 -48.468537) (xy 216.792712 -48.482643) (xy 216.844041 -48.504455)
			(xy 216.891647 -48.533509) (xy 216.934515 -48.569184) (xy 216.971732 -48.610721) (xy 217.002505 -48.657234)
			(xy 217.026177 -48.707731) (xy 217.042245 -48.761138) (xy 217.050365 -48.816314) (xy 217.050874 -48.8442)
			(xy 217.050365 -48.872086) (xy 217.043349 -48.919757) (xy 217.314915 -48.919757) (xy 217.314915 -48.865243)
			(xy 217.322674 -48.811283) (xy 217.338033 -48.758977) (xy 217.36068 -48.709389) (xy 217.390155 -48.66353)
			(xy 217.425856 -48.622332) (xy 217.467057 -48.586634) (xy 217.512919 -48.557164) (xy 217.562509 -48.534521)
			(xy 217.614816 -48.519166) (xy 217.668777 -48.511413) (xy 217.696034 -48.510952) (xy 217.725828 -48.511533)
			(xy 217.784692 -48.520789) (xy 217.8414 -48.539085) (xy 217.894574 -48.565978) (xy 217.942919 -48.600811)
			(xy 217.985259 -48.642739) (xy 218.003374 -48.6664) (xy 218.01074 -48.67656) (xy 218.032584 -48.687228)
			(xy 218.140788 -48.684942) (xy 218.162378 -48.673004) (xy 218.16949 -48.66259) (xy 218.184728 -48.640619)
			(xy 218.220409 -48.600796) (xy 218.261298 -48.566342) (xy 218.306596 -48.537932) (xy 218.355416 -48.516123)
			(xy 218.406801 -48.501341) (xy 218.459747 -48.493876) (xy 218.486482 -48.493426) (xy 218.48699 -48.493426)
			(xy 218.501783 -48.49356) (xy 218.531281 -48.49585) (xy 218.545918 -48.497998) (xy 218.55811 -48.50003)
			(xy 218.581478 -48.492156) (xy 218.647772 -48.423322) (xy 218.655926 -48.414099) (xy 218.662989 -48.390547)
			(xy 218.661234 -48.378364) (xy 218.65806 -48.36069) (xy 218.654626 -48.324945) (xy 218.654376 -48.30699)
			(xy 218.654868 -48.279739) (xy 218.662626 -48.225793) (xy 218.677981 -48.173499) (xy 218.700623 -48.123923)
			(xy 218.730088 -48.078073) (xy 218.765779 -48.036883) (xy 218.806968 -48.001192) (xy 218.852817 -47.971726)
			(xy 218.902393 -47.949084) (xy 218.954687 -47.933727) (xy 219.008633 -47.925969) (xy 219.035884 -47.925482)
			(xy 219.063137 -47.925964) (xy 219.117088 -47.933719) (xy 219.169387 -47.949073) (xy 219.218967 -47.971714)
			(xy 219.264821 -48.001181) (xy 219.306015 -48.036874) (xy 219.341709 -48.078066) (xy 219.371178 -48.123919)
			(xy 219.393821 -48.173498) (xy 219.409177 -48.225796) (xy 219.416935 -48.279747) (xy 219.416935 -48.334253)
			(xy 219.409177 -48.388204) (xy 219.393821 -48.440502) (xy 219.371178 -48.490081) (xy 219.341709 -48.535934)
			(xy 219.306015 -48.577126) (xy 219.264821 -48.612819) (xy 219.218967 -48.642286) (xy 219.169387 -48.664927)
			(xy 219.117088 -48.680281) (xy 219.063137 -48.688036) (xy 219.035884 -48.688498) (xy 219.035376 -48.688498)
			(xy 219.020583 -48.688367) (xy 218.991085 -48.686075) (xy 218.976448 -48.683926) (xy 218.964256 -48.681894)
			(xy 218.940888 -48.689768) (xy 218.874594 -48.758602) (xy 218.866539 -48.76788) (xy 218.859506 -48.791381)
			(xy 218.861132 -48.80356) (xy 218.864309 -48.821233) (xy 218.867741 -48.856979) (xy 218.86799 -48.874934)
			(xy 218.867554 -48.902187) (xy 218.862558 -48.93691) (xy 221.033084 -48.93691) (xy 221.037155 -48.881288)
			(xy 221.049281 -48.826851) (xy 221.069204 -48.77476) (xy 221.0965 -48.726125) (xy 221.130586 -48.681982)
			(xy 221.170735 -48.643273) (xy 221.216093 -48.610822) (xy 221.265693 -48.585321) (xy 221.318477 -48.567314)
			(xy 221.37332 -48.557184) (xy 221.429054 -48.555147) (xy 221.484491 -48.561247) (xy 221.538448 -48.575353)
			(xy 221.589777 -48.597165) (xy 221.637383 -48.626219) (xy 221.680251 -48.661894) (xy 221.717468 -48.703431)
			(xy 221.748241 -48.749944) (xy 221.770558 -48.797551) (xy 236.196364 -48.797551) (xy 236.196364 -48.743049)
			(xy 236.20412 -48.689101) (xy 236.219475 -48.636806) (xy 236.242115 -48.587228) (xy 236.27158 -48.541377)
			(xy 236.307271 -48.500186) (xy 236.34846 -48.464493) (xy 236.394309 -48.435025) (xy 236.443885 -48.412382)
			(xy 236.496179 -48.397025) (xy 236.550127 -48.389265) (xy 236.577378 -48.388778) (xy 236.604749 -48.389238)
			(xy 236.658929 -48.397054) (xy 236.711433 -48.412544) (xy 236.76118 -48.435387) (xy 236.807145 -48.465115)
			(xy 236.828076 -48.482758) (xy 236.82833 -48.483012) (xy 236.835431 -48.488577) (xy 236.852337 -48.494836)
			(xy 236.86135 -48.495204) (xy 236.928406 -48.495204) (xy 236.937423 -48.494849) (xy 236.95434 -48.4886)
			(xy 236.961426 -48.483012) (xy 236.961934 -48.482504) (xy 236.982874 -48.46493) (xy 237.028807 -48.435288)
			(xy 237.078501 -48.412509) (xy 237.130939 -48.397056) (xy 237.185045 -48.389249) (xy 237.212378 -48.388778)
			(xy 237.239631 -48.389268) (xy 237.293582 -48.397022) (xy 237.345881 -48.412376) (xy 237.395462 -48.435016)
			(xy 237.441316 -48.464482) (xy 237.48251 -48.500175) (xy 237.518205 -48.541366) (xy 237.547674 -48.587219)
			(xy 237.570317 -48.636799) (xy 237.585673 -48.689096) (xy 237.593431 -48.743047) (xy 237.593431 -48.789458)
			(xy 238.952913 -48.789458) (xy 238.952913 -48.734942) (xy 238.960672 -48.680982) (xy 238.976032 -48.628675)
			(xy 238.99868 -48.579087) (xy 239.028155 -48.533227) (xy 239.063857 -48.492028) (xy 239.105059 -48.456331)
			(xy 239.150922 -48.42686) (xy 239.200513 -48.404218) (xy 239.252821 -48.388863) (xy 239.306782 -48.38111)
			(xy 239.33404 -48.38065) (xy 239.36141 -48.381139) (xy 239.415588 -48.388949) (xy 239.468091 -48.404432)
			(xy 239.517839 -48.427269) (xy 239.563806 -48.45699) (xy 239.584738 -48.47463) (xy 239.584992 -48.474884)
			(xy 239.592078 -48.480472) (xy 239.608995 -48.486718) (xy 239.618012 -48.487076) (xy 239.685068 -48.487076)
			(xy 239.694084 -48.486709) (xy 239.711001 -48.480469) (xy 239.718088 -48.474884) (xy 239.718596 -48.474376)
			(xy 239.739509 -48.456768) (xy 239.78545 -48.427133) (xy 239.835151 -48.40436) (xy 239.887594 -48.388916)
			(xy 239.941705 -48.381117) (xy 239.96904 -48.38065) (xy 239.996286 -48.381223) (xy 240.050224 -48.388983)
			(xy 240.102508 -48.40434) (xy 240.152075 -48.426981) (xy 240.197915 -48.456445) (xy 240.239096 -48.492133)
			(xy 240.274779 -48.533317) (xy 240.304238 -48.579161) (xy 240.326874 -48.62873) (xy 240.342225 -48.681015)
			(xy 240.34998 -48.734954) (xy 240.34998 -48.789446) (xy 240.342225 -48.843385) (xy 240.326874 -48.89567)
			(xy 240.304238 -48.945239) (xy 240.274779 -48.991083) (xy 240.239096 -49.032267) (xy 240.197915 -49.067955)
			(xy 240.152075 -49.097419) (xy 240.102508 -49.12006) (xy 240.050224 -49.135417) (xy 239.996286 -49.143177)
			(xy 239.96904 -49.143666) (xy 239.94167 -49.143185) (xy 239.887491 -49.135372) (xy 239.834988 -49.119887)
			(xy 239.785241 -49.097048) (xy 239.739274 -49.067326) (xy 239.718342 -49.049686) (xy 239.718088 -49.049432)
			(xy 239.711015 -49.043826) (xy 239.694088 -49.037593) (xy 239.685068 -49.03724) (xy 239.618012 -49.03724)
			(xy 239.608995 -49.037594) (xy 239.592077 -49.043843) (xy 239.584992 -49.049432) (xy 239.584484 -49.04994)
			(xy 239.56358 -49.06756) (xy 239.517637 -49.097193) (xy 239.467933 -49.119963) (xy 239.415488 -49.135405)
			(xy 239.361376 -49.143201) (xy 239.33404 -49.143666) (xy 239.306782 -49.14329) (xy 239.252821 -49.135537)
			(xy 239.200513 -49.120182) (xy 239.150922 -49.09754) (xy 239.105059 -49.068069) (xy 239.063857 -49.032372)
			(xy 239.028155 -48.991173) (xy 238.99868 -48.945313) (xy 238.976032 -48.895725) (xy 238.960672 -48.843418)
			(xy 238.952913 -48.789458) (xy 237.593431 -48.789458) (xy 237.593431 -48.797553) (xy 237.585673 -48.851504)
			(xy 237.570317 -48.903801) (xy 237.547674 -48.953381) (xy 237.518205 -48.999234) (xy 237.48251 -49.040425)
			(xy 237.441316 -49.076118) (xy 237.395462 -49.105584) (xy 237.345881 -49.128224) (xy 237.293582 -49.143578)
			(xy 237.239631 -49.151332) (xy 237.212378 -49.151794) (xy 237.185007 -49.151342) (xy 237.130827 -49.143521)
			(xy 237.078324 -49.128029) (xy 237.028578 -49.105184) (xy 236.982611 -49.075457) (xy 236.96168 -49.057814)
			(xy 236.961426 -49.05756) (xy 236.95434 -49.051973) (xy 236.937423 -49.045728) (xy 236.928406 -49.045368)
			(xy 236.86135 -49.045368) (xy 236.852336 -49.045756) (xy 236.83542 -49.051983) (xy 236.82833 -49.05756)
			(xy 236.827822 -49.058068) (xy 236.806895 -49.075659) (xy 236.760959 -49.105298) (xy 236.711261 -49.128076)
			(xy 236.658821 -49.143524) (xy 236.604712 -49.151326) (xy 236.577378 -49.151794) (xy 236.550127 -49.151335)
			(xy 236.496179 -49.143575) (xy 236.443885 -49.128218) (xy 236.394309 -49.105575) (xy 236.34846 -49.076107)
			(xy 236.307271 -49.040414) (xy 236.27158 -48.999223) (xy 236.242115 -48.953372) (xy 236.219475 -48.903794)
			(xy 236.20412 -48.851499) (xy 236.196364 -48.797551) (xy 221.770558 -48.797551) (xy 221.771913 -48.800441)
			(xy 221.787981 -48.853848) (xy 221.796101 -48.909024) (xy 221.79661 -48.93691) (xy 221.796101 -48.964796)
			(xy 221.787981 -49.019972) (xy 221.771913 -49.073379) (xy 221.748241 -49.123876) (xy 221.717468 -49.170389)
			(xy 221.680251 -49.211926) (xy 221.637383 -49.247601) (xy 221.589777 -49.276655) (xy 221.538448 -49.298467)
			(xy 221.484491 -49.312573) (xy 221.429054 -49.318673) (xy 221.37332 -49.316636) (xy 221.318477 -49.306506)
			(xy 221.265693 -49.288499) (xy 221.216093 -49.262998) (xy 221.170735 -49.230547) (xy 221.130586 -49.191838)
			(xy 221.0965 -49.147695) (xy 221.069204 -49.09906) (xy 221.049281 -49.046969) (xy 221.037155 -48.992532)
			(xy 221.033084 -48.93691) (xy 218.862558 -48.93691) (xy 218.859792 -48.956137) (xy 218.844432 -49.008434)
			(xy 218.821785 -49.058013) (xy 218.792314 -49.103864) (xy 218.756617 -49.145054) (xy 218.715422 -49.180745)
			(xy 218.669567 -49.21021) (xy 218.619985 -49.23285) (xy 218.567686 -49.248203) (xy 218.513735 -49.255957)
			(xy 218.486482 -49.256442) (xy 218.456689 -49.255852) (xy 218.397825 -49.246598) (xy 218.341117 -49.228304)
			(xy 218.287943 -49.201413) (xy 218.239598 -49.166581) (xy 218.197257 -49.124654) (xy 218.179142 -49.100994)
			(xy 218.171776 -49.090834) (xy 218.149932 -49.080166) (xy 218.041728 -49.082452) (xy 218.020138 -49.09439)
			(xy 218.013026 -49.104804) (xy 217.997776 -49.126766) (xy 217.962097 -49.16659) (xy 217.92121 -49.201045)
			(xy 217.875914 -49.229455) (xy 217.827097 -49.251266) (xy 217.775713 -49.26605) (xy 217.722768 -49.273517)
			(xy 217.696034 -49.273968) (xy 217.668777 -49.273587) (xy 217.614816 -49.265834) (xy 217.562509 -49.250479)
			(xy 217.512919 -49.227836) (xy 217.467057 -49.198366) (xy 217.425856 -49.162668) (xy 217.390155 -49.12147)
			(xy 217.36068 -49.075611) (xy 217.338033 -49.026023) (xy 217.322674 -48.973717) (xy 217.314915 -48.919757)
			(xy 217.043349 -48.919757) (xy 217.042245 -48.927262) (xy 217.026177 -48.980669) (xy 217.002505 -49.031166)
			(xy 216.971732 -49.077679) (xy 216.934515 -49.119216) (xy 216.891647 -49.154891) (xy 216.844041 -49.183945)
			(xy 216.792712 -49.205757) (xy 216.738755 -49.219863) (xy 216.683318 -49.225963) (xy 216.627584 -49.223926)
			(xy 216.572741 -49.213796) (xy 216.519957 -49.195789) (xy 216.470357 -49.170288) (xy 216.424999 -49.137837)
			(xy 216.38485 -49.099128) (xy 216.350764 -49.054985) (xy 216.323468 -49.00635) (xy 216.303545 -48.954259)
			(xy 216.291419 -48.899822) (xy 216.287348 -48.8442) (xy 216.020753 -48.8442) (xy 216.007129 -48.889483)
			(xy 215.983457 -48.93998) (xy 215.952684 -48.986493) (xy 215.915467 -49.02803) (xy 215.872599 -49.063705)
			(xy 215.824993 -49.092759) (xy 215.773664 -49.114571) (xy 215.719707 -49.128677) (xy 215.66427 -49.134777)
			(xy 215.608536 -49.13274) (xy 215.553693 -49.12261) (xy 215.500909 -49.104603) (xy 215.451309 -49.079102)
			(xy 215.405951 -49.046651) (xy 215.365802 -49.007942) (xy 215.331716 -48.963799) (xy 215.30442 -48.915164)
			(xy 215.284497 -48.863073) (xy 215.272371 -48.808636) (xy 215.2683 -48.753014) (xy 213.549738 -48.753014)
			(xy 213.549252 -48.780265) (xy 213.541496 -48.834213) (xy 213.526141 -48.886508) (xy 213.503499 -48.936085)
			(xy 213.474033 -48.981935) (xy 213.438342 -49.023126) (xy 213.397151 -49.058817) (xy 213.351301 -49.088283)
			(xy 213.301724 -49.110925) (xy 213.249429 -49.12628) (xy 213.195481 -49.134036) (xy 213.140979 -49.134036)
			(xy 213.087031 -49.12628) (xy 213.034736 -49.110925) (xy 212.985159 -49.088283) (xy 212.939309 -49.058817)
			(xy 212.898118 -49.023126) (xy 212.862427 -48.981935) (xy 212.832961 -48.936085) (xy 212.810319 -48.886508)
			(xy 212.794964 -48.834213) (xy 212.787208 -48.780265) (xy 212.786722 -48.753014) (xy 212.787174 -48.726673)
			(xy 212.794427 -48.674493) (xy 212.808785 -48.623805) (xy 212.829974 -48.575572) (xy 212.857591 -48.530709)
			(xy 212.891114 -48.490068) (xy 212.929905 -48.454422) (xy 212.951314 -48.43907) (xy 212.963158 -48.430403)
			(xy 212.981585 -48.407568) (xy 212.992761 -48.380438) (xy 212.995763 -48.35125) (xy 212.990344 -48.322412)
			(xy 212.976951 -48.296305) (xy 212.95669 -48.275081) (xy 212.944202 -48.267366) (xy 212.919693 -48.252629)
			(xy 212.874935 -48.217034) (xy 212.835991 -48.175157) (xy 212.803733 -48.127937) (xy 212.778883 -48.076433)
			(xy 212.761997 -48.021796) (xy 212.753454 -47.965251) (xy 212.75294 -47.936658) (xy 193.127024 -47.936658)
			(xy 193.169416 -47.949109) (xy 193.218987 -47.971752) (xy 193.264832 -48.001218) (xy 193.306017 -48.036909)
			(xy 193.341704 -48.078097) (xy 193.371166 -48.123944) (xy 193.393804 -48.173518) (xy 193.409156 -48.225808)
			(xy 193.416912 -48.279751) (xy 193.416912 -48.334249) (xy 193.409156 -48.388192) (xy 193.393804 -48.440482)
			(xy 193.371166 -48.490056) (xy 193.341704 -48.535903) (xy 193.306017 -48.577091) (xy 193.264832 -48.612782)
			(xy 193.218987 -48.642248) (xy 193.169416 -48.664891) (xy 193.117127 -48.680249) (xy 193.063185 -48.688009)
			(xy 193.035936 -48.688498) (xy 193.035428 -48.688498) (xy 193.020635 -48.688361) (xy 192.991137 -48.686073)
			(xy 192.9765 -48.683926) (xy 192.964308 -48.681894) (xy 192.94094 -48.689768) (xy 192.874646 -48.758602)
			(xy 192.86648 -48.767816) (xy 192.859423 -48.791375) (xy 192.861184 -48.80356) (xy 192.864361 -48.821233)
			(xy 192.867793 -48.856979) (xy 192.868042 -48.874934) (xy 192.867554 -48.902185) (xy 192.862559 -48.93691)
			(xy 195.033136 -48.93691) (xy 195.037207 -48.881288) (xy 195.049333 -48.826851) (xy 195.069256 -48.77476)
			(xy 195.096552 -48.726125) (xy 195.130638 -48.681982) (xy 195.170787 -48.643273) (xy 195.216145 -48.610822)
			(xy 195.265745 -48.585321) (xy 195.318529 -48.567314) (xy 195.373372 -48.557184) (xy 195.429106 -48.555147)
			(xy 195.484543 -48.561247) (xy 195.5385 -48.575353) (xy 195.589829 -48.597165) (xy 195.637435 -48.626219)
			(xy 195.680303 -48.661894) (xy 195.71752 -48.703431) (xy 195.748293 -48.749944) (xy 195.771965 -48.800441)
			(xy 195.788033 -48.853848) (xy 195.796153 -48.909024) (xy 195.796662 -48.93691) (xy 195.796153 -48.964796)
			(xy 195.788033 -49.019972) (xy 195.771965 -49.073379) (xy 195.748293 -49.123876) (xy 195.71752 -49.170389)
			(xy 195.680303 -49.211926) (xy 195.637435 -49.247601) (xy 195.589829 -49.276655) (xy 195.5385 -49.298467)
			(xy 195.484543 -49.312573) (xy 195.429106 -49.318673) (xy 195.373372 -49.316636) (xy 195.318529 -49.306506)
			(xy 195.265745 -49.288499) (xy 195.216145 -49.262998) (xy 195.170787 -49.230547) (xy 195.130638 -49.191838)
			(xy 195.096552 -49.147695) (xy 195.069256 -49.09906) (xy 195.049333 -49.046969) (xy 195.037207 -48.992532)
			(xy 195.033136 -48.93691) (xy 192.862559 -48.93691) (xy 192.859794 -48.95613) (xy 192.844436 -49.008423)
			(xy 192.821793 -49.057998) (xy 192.792327 -49.103847) (xy 192.756636 -49.145036) (xy 192.715447 -49.180727)
			(xy 192.669598 -49.210193) (xy 192.620023 -49.232836) (xy 192.56773 -49.248194) (xy 192.513785 -49.255954)
			(xy 192.486534 -49.256442) (xy 192.456739 -49.255887) (xy 192.397874 -49.246626) (xy 192.341165 -49.228325)
			(xy 192.287991 -49.201428) (xy 192.239647 -49.166589) (xy 192.197308 -49.124657) (xy 192.179194 -49.100994)
			(xy 192.171828 -49.090834) (xy 192.149984 -49.080166) (xy 192.04178 -49.082452) (xy 192.02019 -49.09439)
			(xy 192.013078 -49.104804) (xy 191.997858 -49.126788) (xy 191.962175 -49.166612) (xy 191.921282 -49.201065)
			(xy 191.875981 -49.229473) (xy 191.827159 -49.25128) (xy 191.77577 -49.266059) (xy 191.722822 -49.27352)
			(xy 191.696086 -49.273968) (xy 191.668833 -49.273561) (xy 191.614881 -49.265802) (xy 191.562582 -49.250444)
			(xy 191.513001 -49.2278) (xy 191.467148 -49.19833) (xy 191.425955 -49.162635) (xy 191.390261 -49.121441)
			(xy 191.360793 -49.075586) (xy 191.338151 -49.026005) (xy 191.322795 -48.973706) (xy 191.315038 -48.919753)
			(xy 191.043402 -48.919753) (xy 191.042297 -48.927262) (xy 191.026229 -48.980669) (xy 191.002557 -49.031166)
			(xy 190.971784 -49.077679) (xy 190.934567 -49.119216) (xy 190.891699 -49.154891) (xy 190.844093 -49.183945)
			(xy 190.792764 -49.205757) (xy 190.738807 -49.219863) (xy 190.68337 -49.225963) (xy 190.627636 -49.223926)
			(xy 190.572793 -49.213796) (xy 190.520009 -49.195789) (xy 190.470409 -49.170288) (xy 190.425051 -49.137837)
			(xy 190.384902 -49.099128) (xy 190.350816 -49.054985) (xy 190.32352 -49.00635) (xy 190.303597 -48.954259)
			(xy 190.291471 -48.899822) (xy 190.2874 -48.8442) (xy 190.020805 -48.8442) (xy 190.007181 -48.889483)
			(xy 189.983509 -48.93998) (xy 189.952736 -48.986493) (xy 189.915519 -49.02803) (xy 189.872651 -49.063705)
			(xy 189.825045 -49.092759) (xy 189.773716 -49.114571) (xy 189.719759 -49.128677) (xy 189.664322 -49.134777)
			(xy 189.608588 -49.13274) (xy 189.553745 -49.12261) (xy 189.500961 -49.104603) (xy 189.451361 -49.079102)
			(xy 189.406003 -49.046651) (xy 189.365854 -49.007942) (xy 189.331768 -48.963799) (xy 189.304472 -48.915164)
			(xy 189.284549 -48.863073) (xy 189.272423 -48.808636) (xy 189.268352 -48.753014) (xy 187.54979 -48.753014)
			(xy 187.549304 -48.780265) (xy 187.541548 -48.834213) (xy 187.526193 -48.886508) (xy 187.503551 -48.936085)
			(xy 187.474085 -48.981935) (xy 187.438394 -49.023126) (xy 187.397203 -49.058817) (xy 187.351353 -49.088283)
			(xy 187.301776 -49.110925) (xy 187.249481 -49.12628) (xy 187.195533 -49.134036) (xy 187.141031 -49.134036)
			(xy 187.087083 -49.12628) (xy 187.034788 -49.110925) (xy 186.985211 -49.088283) (xy 186.939361 -49.058817)
			(xy 186.89817 -49.023126) (xy 186.862479 -48.981935) (xy 186.833013 -48.936085) (xy 186.810371 -48.886508)
			(xy 186.795016 -48.834213) (xy 186.78726 -48.780265) (xy 186.786774 -48.753014) (xy 186.787204 -48.726672)
			(xy 186.794458 -48.67449) (xy 186.808818 -48.6238) (xy 186.83001 -48.575566) (xy 186.857631 -48.530704)
			(xy 186.891158 -48.490064) (xy 186.929954 -48.45442) (xy 186.951366 -48.43907) (xy 186.963217 -48.430408)
			(xy 186.981653 -48.407575) (xy 186.992835 -48.380442) (xy 186.995839 -48.351249) (xy 186.990417 -48.322408)
			(xy 186.977018 -48.296299) (xy 186.956747 -48.275078) (xy 186.944254 -48.267366) (xy 186.919734 -48.252647)
			(xy 186.874979 -48.217047) (xy 186.836037 -48.175166) (xy 186.803781 -48.127943) (xy 186.778933 -48.076436)
			(xy 186.762048 -48.021798) (xy 186.753506 -47.965252) (xy 186.752992 -47.936658) (xy 167.127199 -47.936658)
			(xy 167.169489 -47.949074) (xy 167.21907 -47.971716) (xy 167.264923 -48.001183) (xy 167.306116 -48.036875)
			(xy 167.34181 -48.078067) (xy 167.371279 -48.12392) (xy 167.393921 -48.173499) (xy 167.409278 -48.225797)
			(xy 167.417035 -48.279747) (xy 167.417035 -48.334253) (xy 167.409278 -48.388203) (xy 167.393921 -48.440501)
			(xy 167.371279 -48.49008) (xy 167.34181 -48.535933) (xy 167.306116 -48.577125) (xy 167.264923 -48.612817)
			(xy 167.21907 -48.642284) (xy 167.169489 -48.664926) (xy 167.117192 -48.68028) (xy 167.063241 -48.688036)
			(xy 167.035988 -48.688498) (xy 167.03548 -48.688498) (xy 167.020687 -48.688367) (xy 166.991189 -48.686075)
			(xy 166.976552 -48.683926) (xy 166.96436 -48.681894) (xy 166.940992 -48.689768) (xy 166.874698 -48.758602)
			(xy 166.866644 -48.767881) (xy 166.85961 -48.791381) (xy 166.861236 -48.80356) (xy 166.864413 -48.821233)
			(xy 166.867845 -48.856979) (xy 166.868094 -48.874934) (xy 166.867654 -48.902187) (xy 166.862658 -48.93691)
			(xy 169.033188 -48.93691) (xy 169.037259 -48.881288) (xy 169.049385 -48.826851) (xy 169.069308 -48.77476)
			(xy 169.096604 -48.726125) (xy 169.13069 -48.681982) (xy 169.170839 -48.643273) (xy 169.216197 -48.610822)
			(xy 169.265797 -48.585321) (xy 169.318581 -48.567314) (xy 169.373424 -48.557184) (xy 169.429158 -48.555147)
			(xy 169.484595 -48.561247) (xy 169.538552 -48.575353) (xy 169.589881 -48.597165) (xy 169.637487 -48.626219)
			(xy 169.680355 -48.661894) (xy 169.717572 -48.703431) (xy 169.748345 -48.749944) (xy 169.772017 -48.800441)
			(xy 169.788085 -48.853848) (xy 169.796205 -48.909024) (xy 169.796714 -48.93691) (xy 169.796205 -48.964796)
			(xy 169.788085 -49.019972) (xy 169.772017 -49.073379) (xy 169.748345 -49.123876) (xy 169.717572 -49.170389)
			(xy 169.680355 -49.211926) (xy 169.637487 -49.247601) (xy 169.589881 -49.276655) (xy 169.538552 -49.298467)
			(xy 169.484595 -49.312573) (xy 169.429158 -49.318673) (xy 169.373424 -49.316636) (xy 169.318581 -49.306506)
			(xy 169.265797 -49.288499) (xy 169.216197 -49.262998) (xy 169.170839 -49.230547) (xy 169.13069 -49.191838)
			(xy 169.096604 -49.147695) (xy 169.069308 -49.09906) (xy 169.049385 -49.046969) (xy 169.037259 -48.992532)
			(xy 169.033188 -48.93691) (xy 166.862658 -48.93691) (xy 166.859892 -48.956137) (xy 166.844532 -49.008433)
			(xy 166.821886 -49.058012) (xy 166.792415 -49.103862) (xy 166.756719 -49.145053) (xy 166.715524 -49.180744)
			(xy 166.669669 -49.210209) (xy 166.620088 -49.232849) (xy 166.56779 -49.248202) (xy 166.513839 -49.255957)
			(xy 166.486586 -49.256442) (xy 166.456793 -49.255849) (xy 166.397929 -49.246596) (xy 166.341221 -49.228302)
			(xy 166.288047 -49.201412) (xy 166.239702 -49.16658) (xy 166.197361 -49.124654) (xy 166.179246 -49.100994)
			(xy 166.17188 -49.090834) (xy 166.150036 -49.080166) (xy 166.041832 -49.082452) (xy 166.020242 -49.09439)
			(xy 166.01313 -49.104804) (xy 165.997877 -49.126764) (xy 165.962199 -49.166588) (xy 165.921312 -49.201043)
			(xy 165.876017 -49.229454) (xy 165.8272 -49.251265) (xy 165.775816 -49.266049) (xy 165.722872 -49.273517)
			(xy 165.696138 -49.273968) (xy 165.66888 -49.273588) (xy 165.61492 -49.265834) (xy 165.562612 -49.25048)
			(xy 165.513022 -49.227837) (xy 165.467159 -49.198367) (xy 165.425957 -49.16267) (xy 165.390256 -49.121472)
			(xy 165.360781 -49.075612) (xy 165.338133 -49.026024) (xy 165.322774 -48.973717) (xy 165.315015 -48.919757)
			(xy 163.993041 -48.919757) (xy 163.983561 -48.93998) (xy 163.952788 -48.986493) (xy 163.915571 -49.02803)
			(xy 163.872703 -49.063705) (xy 163.825097 -49.092759) (xy 163.773768 -49.114571) (xy 163.719811 -49.128677)
			(xy 163.664374 -49.134777) (xy 163.60864 -49.13274) (xy 163.553797 -49.12261) (xy 163.501013 -49.104603)
			(xy 163.451413 -49.079102) (xy 163.406055 -49.046651) (xy 163.365906 -49.007942) (xy 163.33182 -48.963799)
			(xy 163.304524 -48.915164) (xy 163.284601 -48.863073) (xy 163.272475 -48.808636) (xy 163.268404 -48.753014)
			(xy 161.549842 -48.753014) (xy 161.549356 -48.780265) (xy 161.5416 -48.834213) (xy 161.526245 -48.886508)
			(xy 161.503603 -48.936085) (xy 161.474137 -48.981935) (xy 161.438446 -49.023126) (xy 161.397255 -49.058817)
			(xy 161.351405 -49.088283) (xy 161.301828 -49.110925) (xy 161.249533 -49.12628) (xy 161.195585 -49.134036)
			(xy 161.141083 -49.134036) (xy 161.087135 -49.12628) (xy 161.03484 -49.110925) (xy 160.985263 -49.088283)
			(xy 160.939413 -49.058817) (xy 160.898222 -49.023126) (xy 160.862531 -48.981935) (xy 160.833065 -48.936085)
			(xy 160.810423 -48.886508) (xy 160.795068 -48.834213) (xy 160.787312 -48.780265) (xy 160.786826 -48.753014)
			(xy 160.787276 -48.726673) (xy 160.79453 -48.674493) (xy 160.808887 -48.623804) (xy 160.830076 -48.575571)
			(xy 160.857694 -48.530709) (xy 160.891217 -48.490068) (xy 160.930008 -48.454422) (xy 160.951418 -48.43907)
			(xy 160.963262 -48.430402) (xy 160.981688 -48.407568) (xy 160.992863 -48.380437) (xy 160.995865 -48.35125)
			(xy 160.990446 -48.322412) (xy 160.977054 -48.296305) (xy 160.956794 -48.275082) (xy 160.944306 -48.267366)
			(xy 160.919798 -48.252628) (xy 160.87504 -48.217032) (xy 160.836096 -48.175156) (xy 160.803837 -48.127937)
			(xy 160.778987 -48.076432) (xy 160.762101 -48.021796) (xy 160.753558 -47.965251) (xy 160.753044 -47.936658)
			(xy 141.127125 -47.936658) (xy 141.169519 -47.94911) (xy 141.21909 -47.971753) (xy 141.264934 -48.001219)
			(xy 141.306118 -48.03691) (xy 141.341805 -48.078098) (xy 141.371266 -48.123945) (xy 141.393904 -48.173518)
			(xy 141.409257 -48.225809) (xy 141.417012 -48.279751) (xy 141.417012 -48.334249) (xy 141.409257 -48.388191)
			(xy 141.393904 -48.440482) (xy 141.371266 -48.490055) (xy 141.341805 -48.535902) (xy 141.306118 -48.57709)
			(xy 141.264934 -48.612781) (xy 141.21909 -48.642247) (xy 141.169519 -48.66489) (xy 141.117231 -48.680248)
			(xy 141.063289 -48.688009) (xy 141.03604 -48.688498) (xy 141.035532 -48.688498) (xy 141.020739 -48.688361)
			(xy 140.991241 -48.686073) (xy 140.976604 -48.683926) (xy 140.964412 -48.681894) (xy 140.941044 -48.689768)
			(xy 140.87475 -48.758602) (xy 140.866585 -48.767817) (xy 140.859527 -48.791375) (xy 140.861288 -48.80356)
			(xy 140.864465 -48.821233) (xy 140.867897 -48.856979) (xy 140.868146 -48.874934) (xy 140.867654 -48.902184)
			(xy 140.862659 -48.93691) (xy 143.03324 -48.93691) (xy 143.037311 -48.881288) (xy 143.049437 -48.826851)
			(xy 143.06936 -48.77476) (xy 143.096656 -48.726125) (xy 143.130742 -48.681982) (xy 143.170891 -48.643273)
			(xy 143.216249 -48.610822) (xy 143.265849 -48.585321) (xy 143.318633 -48.567314) (xy 143.373476 -48.557184)
			(xy 143.42921 -48.555147) (xy 143.484647 -48.561247) (xy 143.538604 -48.575353) (xy 143.589933 -48.597165)
			(xy 143.637539 -48.626219) (xy 143.680407 -48.661894) (xy 143.717624 -48.703431) (xy 143.748397 -48.749944)
			(xy 143.772069 -48.800441) (xy 143.788137 -48.853848) (xy 143.796257 -48.909024) (xy 143.796766 -48.93691)
			(xy 143.796257 -48.964796) (xy 143.788137 -49.019972) (xy 143.772069 -49.073379) (xy 143.748397 -49.123876)
			(xy 143.717624 -49.170389) (xy 143.680407 -49.211926) (xy 143.637539 -49.247601) (xy 143.589933 -49.276655)
			(xy 143.538604 -49.298467) (xy 143.484647 -49.312573) (xy 143.42921 -49.318673) (xy 143.373476 -49.316636)
			(xy 143.318633 -49.306506) (xy 143.265849 -49.288499) (xy 143.216249 -49.262998) (xy 143.170891 -49.230547)
			(xy 143.130742 -49.191838) (xy 143.096656 -49.147695) (xy 143.06936 -49.09906) (xy 143.049437 -49.046969)
			(xy 143.037311 -48.992532) (xy 143.03324 -48.93691) (xy 140.862659 -48.93691) (xy 140.859894 -48.95613)
			(xy 140.844536 -49.008422) (xy 140.821894 -49.057997) (xy 140.792428 -49.103845) (xy 140.756737 -49.145034)
			(xy 140.715549 -49.180725) (xy 140.669701 -49.210192) (xy 140.620126 -49.232835) (xy 140.567834 -49.248193)
			(xy 140.513888 -49.255954) (xy 140.486638 -49.256442) (xy 140.456843 -49.255884) (xy 140.397978 -49.246624)
			(xy 140.341269 -49.228323) (xy 140.288095 -49.201426) (xy 140.239751 -49.166588) (xy 140.197412 -49.124657)
			(xy 140.179298 -49.100994) (xy 140.171932 -49.090834) (xy 140.150088 -49.080166) (xy 140.041884 -49.082452)
			(xy 140.020294 -49.09439) (xy 140.013182 -49.104804) (xy 139.99796 -49.126787) (xy 139.962277 -49.16661)
			(xy 139.921385 -49.201063) (xy 139.876084 -49.229471) (xy 139.827262 -49.251279) (xy 139.775874 -49.266058)
			(xy 139.722926 -49.27352) (xy 139.69619 -49.273968) (xy 139.668936 -49.273561) (xy 139.614984 -49.265803)
			(xy 139.562685 -49.250445) (xy 139.513104 -49.227801) (xy 139.46725 -49.198332) (xy 139.426057 -49.162636)
			(xy 139.390362 -49.121442) (xy 139.360894 -49.075587) (xy 139.338251 -49.026006) (xy 139.322895 -48.973706)
			(xy 139.315138 -48.919754) (xy 137.993095 -48.919754) (xy 137.983613 -48.93998) (xy 137.95284 -48.986493)
			(xy 137.915623 -49.02803) (xy 137.872755 -49.063705) (xy 137.825149 -49.092759) (xy 137.77382 -49.114571)
			(xy 137.719863 -49.128677) (xy 137.664426 -49.134777) (xy 137.608692 -49.13274) (xy 137.553849 -49.12261)
			(xy 137.501065 -49.104603) (xy 137.451465 -49.079102) (xy 137.406107 -49.046651) (xy 137.365958 -49.007942)
			(xy 137.331872 -48.963799) (xy 137.304576 -48.915164) (xy 137.284653 -48.863073) (xy 137.272527 -48.808636)
			(xy 137.268456 -48.753014) (xy 135.549894 -48.753014) (xy 135.549408 -48.780265) (xy 135.541652 -48.834213)
			(xy 135.526297 -48.886508) (xy 135.503655 -48.936085) (xy 135.474189 -48.981935) (xy 135.438498 -49.023126)
			(xy 135.397307 -49.058817) (xy 135.351457 -49.088283) (xy 135.30188 -49.110925) (xy 135.249585 -49.12628)
			(xy 135.195637 -49.134036) (xy 135.141135 -49.134036) (xy 135.087187 -49.12628) (xy 135.034892 -49.110925)
			(xy 134.985315 -49.088283) (xy 134.939465 -49.058817) (xy 134.898274 -49.023126) (xy 134.862583 -48.981935)
			(xy 134.833117 -48.936085) (xy 134.810475 -48.886508) (xy 134.79512 -48.834213) (xy 134.787364 -48.780265)
			(xy 134.786878 -48.753014) (xy 134.787306 -48.726672) (xy 134.794561 -48.67449) (xy 134.80892 -48.6238)
			(xy 134.830113 -48.575566) (xy 134.857735 -48.530703) (xy 134.891262 -48.490064) (xy 134.930058 -48.45442)
			(xy 134.95147 -48.43907) (xy 134.963321 -48.430408) (xy 134.981756 -48.407575) (xy 134.992937 -48.380442)
			(xy 134.995941 -48.351249) (xy 134.99052 -48.322408) (xy 134.977121 -48.296299) (xy 134.95685 -48.275078)
			(xy 134.944358 -48.267366) (xy 134.919839 -48.252646) (xy 134.875083 -48.217045) (xy 134.836142 -48.175165)
			(xy 134.803885 -48.127943) (xy 134.779037 -48.076436) (xy 134.762152 -48.021798) (xy 134.75361 -47.965252)
			(xy 134.753096 -47.936658) (xy 103.026997 -47.936658) (xy 103.069288 -47.949074) (xy 103.118869 -47.971715)
			(xy 103.164722 -48.001182) (xy 103.205915 -48.036875) (xy 103.24161 -48.078067) (xy 103.271078 -48.123919)
			(xy 103.293721 -48.173499) (xy 103.309078 -48.225796) (xy 103.316835 -48.279747) (xy 103.316835 -48.334253)
			(xy 103.309078 -48.388204) (xy 103.293721 -48.440501) (xy 103.271078 -48.490081) (xy 103.24161 -48.535933)
			(xy 103.205915 -48.577125) (xy 103.164722 -48.612818) (xy 103.118869 -48.642285) (xy 103.069288 -48.664926)
			(xy 103.01699 -48.68028) (xy 102.963039 -48.688036) (xy 102.935786 -48.688498) (xy 102.935278 -48.688498)
			(xy 102.920485 -48.688367) (xy 102.890987 -48.686075) (xy 102.87635 -48.683926) (xy 102.864158 -48.681894)
			(xy 102.84079 -48.689768) (xy 102.774496 -48.758602) (xy 102.770427 -48.76307) (xy 102.76426 -48.773458)
			(xy 102.762304 -48.779176) (xy 102.758748 -48.791114) (xy 102.761034 -48.80356) (xy 102.764211 -48.821233)
			(xy 102.767643 -48.856979) (xy 102.767892 -48.874934) (xy 102.767454 -48.902187) (xy 102.762458 -48.93691)
			(xy 104.932986 -48.93691) (xy 104.937057 -48.881288) (xy 104.949183 -48.826851) (xy 104.969106 -48.77476)
			(xy 104.996402 -48.726125) (xy 105.030488 -48.681982) (xy 105.070637 -48.643273) (xy 105.115995 -48.610822)
			(xy 105.165595 -48.585321) (xy 105.218379 -48.567314) (xy 105.273222 -48.557184) (xy 105.328956 -48.555147)
			(xy 105.384393 -48.561247) (xy 105.43835 -48.575353) (xy 105.489679 -48.597165) (xy 105.537285 -48.626219)
			(xy 105.580153 -48.661894) (xy 105.61737 -48.703431) (xy 105.648143 -48.749944) (xy 105.671815 -48.800441)
			(xy 105.687883 -48.853848) (xy 105.696003 -48.909024) (xy 105.696512 -48.93691) (xy 105.696003 -48.964796)
			(xy 105.687883 -49.019972) (xy 105.671815 -49.073379) (xy 105.648143 -49.123876) (xy 105.61737 -49.170389)
			(xy 105.580153 -49.211926) (xy 105.537285 -49.247601) (xy 105.489679 -49.276655) (xy 105.43835 -49.298467)
			(xy 105.384393 -49.312573) (xy 105.328956 -49.318673) (xy 105.273222 -49.316636) (xy 105.218379 -49.306506)
			(xy 105.165595 -49.288499) (xy 105.115995 -49.262998) (xy 105.070637 -49.230547) (xy 105.030488 -49.191838)
			(xy 104.996402 -49.147695) (xy 104.969106 -49.09906) (xy 104.949183 -49.046969) (xy 104.937057 -48.992532)
			(xy 104.932986 -48.93691) (xy 102.762458 -48.93691) (xy 102.759692 -48.956137) (xy 102.744332 -49.008434)
			(xy 102.721686 -49.058012) (xy 102.692214 -49.103863) (xy 102.656518 -49.145053) (xy 102.615323 -49.180744)
			(xy 102.569468 -49.21021) (xy 102.519887 -49.232849) (xy 102.467588 -49.248203) (xy 102.413637 -49.255957)
			(xy 102.386384 -49.256442) (xy 102.356591 -49.25585) (xy 102.297727 -49.246597) (xy 102.241019 -49.228303)
			(xy 102.187845 -49.201413) (xy 102.1395 -49.16658) (xy 102.097159 -49.124654) (xy 102.079044 -49.100994)
			(xy 102.071678 -49.090834) (xy 102.049834 -49.080166) (xy 101.94163 -49.082452) (xy 101.92004 -49.09439)
			(xy 101.912928 -49.104804) (xy 101.897676 -49.126765) (xy 101.861998 -49.166589) (xy 101.821111 -49.201044)
			(xy 101.775816 -49.229454) (xy 101.726998 -49.251265) (xy 101.675614 -49.266049) (xy 101.62267 -49.273517)
			(xy 101.595936 -49.273968) (xy 101.568679 -49.273588) (xy 101.514718 -49.265834) (xy 101.46241 -49.250479)
			(xy 101.41282 -49.227837) (xy 101.366958 -49.198366) (xy 101.325757 -49.162669) (xy 101.290055 -49.121471)
			(xy 101.260581 -49.075611) (xy 101.237933 -49.026023) (xy 101.222574 -48.973717) (xy 101.214815 -48.919757)
			(xy 100.943251 -48.919757) (xy 100.942147 -48.927262) (xy 100.926079 -48.980669) (xy 100.902407 -49.031166)
			(xy 100.871634 -49.077679) (xy 100.834417 -49.119216) (xy 100.791549 -49.154891) (xy 100.743943 -49.183945)
			(xy 100.692614 -49.205757) (xy 100.638657 -49.219863) (xy 100.58322 -49.225963) (xy 100.527486 -49.223926)
			(xy 100.472643 -49.213796) (xy 100.419859 -49.195789) (xy 100.370259 -49.170288) (xy 100.324901 -49.137837)
			(xy 100.284752 -49.099128) (xy 100.250666 -49.054985) (xy 100.22337 -49.00635) (xy 100.203447 -48.954259)
			(xy 100.191321 -48.899822) (xy 100.18725 -48.8442) (xy 99.920655 -48.8442) (xy 99.907031 -48.889483)
			(xy 99.883359 -48.93998) (xy 99.852586 -48.986493) (xy 99.815369 -49.02803) (xy 99.772501 -49.063705)
			(xy 99.724895 -49.092759) (xy 99.673566 -49.114571) (xy 99.619609 -49.128677) (xy 99.564172 -49.134777)
			(xy 99.508438 -49.13274) (xy 99.453595 -49.12261) (xy 99.400811 -49.104603) (xy 99.351211 -49.079102)
			(xy 99.305853 -49.046651) (xy 99.265704 -49.007942) (xy 99.231618 -48.963799) (xy 99.204322 -48.915164)
			(xy 99.184399 -48.863073) (xy 99.172273 -48.808636) (xy 99.168202 -48.753014) (xy 97.44964 -48.753014)
			(xy 97.449154 -48.780265) (xy 97.441398 -48.834213) (xy 97.426043 -48.886508) (xy 97.403401 -48.936085)
			(xy 97.373935 -48.981935) (xy 97.338244 -49.023126) (xy 97.297053 -49.058817) (xy 97.251203 -49.088283)
			(xy 97.201626 -49.110925) (xy 97.149331 -49.12628) (xy 97.095383 -49.134036) (xy 97.040881 -49.134036)
			(xy 96.986933 -49.12628) (xy 96.934638 -49.110925) (xy 96.885061 -49.088283) (xy 96.839211 -49.058817)
			(xy 96.79802 -49.023126) (xy 96.762329 -48.981935) (xy 96.732863 -48.936085) (xy 96.710221 -48.886508)
			(xy 96.694866 -48.834213) (xy 96.68711 -48.780265) (xy 96.686624 -48.753014) (xy 96.687075 -48.726673)
			(xy 96.694329 -48.674493) (xy 96.708686 -48.623805) (xy 96.729875 -48.575571) (xy 96.757493 -48.530709)
			(xy 96.791016 -48.490068) (xy 96.829806 -48.454422) (xy 96.851216 -48.43907) (xy 96.86306 -48.430403)
			(xy 96.881486 -48.407568) (xy 96.892662 -48.380437) (xy 96.895664 -48.35125) (xy 96.890245 -48.322412)
			(xy 96.876853 -48.296305) (xy 96.856592 -48.275081) (xy 96.844104 -48.267366) (xy 96.819595 -48.252629)
			(xy 96.774838 -48.217033) (xy 96.735894 -48.175157) (xy 96.703635 -48.127937) (xy 96.678785 -48.076432)
			(xy 96.661899 -48.021796) (xy 96.653356 -47.965251) (xy 96.652842 -47.936658) (xy 77.026923 -47.936658)
			(xy 77.069318 -47.94911) (xy 77.118889 -47.971752) (xy 77.164733 -48.001219) (xy 77.205918 -48.036909)
			(xy 77.241604 -48.078097) (xy 77.271066 -48.123945) (xy 77.293704 -48.173518) (xy 77.309057 -48.225808)
			(xy 77.316812 -48.279751) (xy 77.316812 -48.334249) (xy 77.309057 -48.388192) (xy 77.293704 -48.440482)
			(xy 77.271066 -48.490055) (xy 77.241604 -48.535903) (xy 77.205918 -48.577091) (xy 77.164733 -48.612781)
			(xy 77.118889 -48.642248) (xy 77.069318 -48.66489) (xy 77.017029 -48.680248) (xy 76.963087 -48.688009)
			(xy 76.935838 -48.688498) (xy 76.935076 -48.688498) (xy 76.917057 -48.688277) (xy 76.881182 -48.684843)
			(xy 76.863448 -48.68164) (xy 76.849224 -48.678846) (xy 76.822554 -48.689006) (xy 76.749402 -48.782986)
			(xy 76.7461 -48.811434) (xy 76.752196 -48.824388) (xy 76.763585 -48.849824) (xy 76.779663 -48.903185)
			(xy 76.78463 -48.93691) (xy 78.933038 -48.93691) (xy 78.937109 -48.881288) (xy 78.949235 -48.826851)
			(xy 78.969158 -48.77476) (xy 78.996454 -48.726125) (xy 79.03054 -48.681982) (xy 79.070689 -48.643273)
			(xy 79.116047 -48.610822) (xy 79.165647 -48.585321) (xy 79.218431 -48.567314) (xy 79.273274 -48.557184)
			(xy 79.329008 -48.555147) (xy 79.384445 -48.561247) (xy 79.438402 -48.575353) (xy 79.489731 -48.597165)
			(xy 79.537337 -48.626219) (xy 79.580205 -48.661894) (xy 79.617422 -48.703431) (xy 79.648195 -48.749944)
			(xy 79.671867 -48.800441) (xy 79.687935 -48.853848) (xy 79.696055 -48.909024) (xy 79.696564 -48.93691)
			(xy 79.696055 -48.964796) (xy 79.687935 -49.019972) (xy 79.671867 -49.073379) (xy 79.648195 -49.123876)
			(xy 79.617422 -49.170389) (xy 79.580205 -49.211926) (xy 79.537337 -49.247601) (xy 79.489731 -49.276655)
			(xy 79.438402 -49.298467) (xy 79.384445 -49.312573) (xy 79.329008 -49.318673) (xy 79.273274 -49.316636)
			(xy 79.218431 -49.306506) (xy 79.165647 -49.288499) (xy 79.116047 -49.262998) (xy 79.070689 -49.230547)
			(xy 79.03054 -49.191838) (xy 78.996454 -49.147695) (xy 78.969158 -49.09906) (xy 78.949235 -49.046969)
			(xy 78.937109 -48.992532) (xy 78.933038 -48.93691) (xy 76.78463 -48.93691) (xy 76.787783 -48.958321)
			(xy 76.788264 -48.986186) (xy 76.787832 -49.013441) (xy 76.780075 -49.067395) (xy 76.764719 -49.119696)
			(xy 76.742075 -49.169279) (xy 76.712604 -49.215134) (xy 76.676907 -49.256328) (xy 76.63571 -49.292022)
			(xy 76.589853 -49.321489) (xy 76.540268 -49.344129) (xy 76.487965 -49.359482) (xy 76.434011 -49.367234)
			(xy 76.406756 -49.367694) (xy 76.380011 -49.367232) (xy 76.327047 -49.359748) (xy 76.275646 -49.344946)
			(xy 76.226813 -49.323116) (xy 76.181504 -49.294686) (xy 76.140606 -49.26021) (xy 76.104919 -49.220365)
			(xy 76.075141 -49.17593) (xy 76.063094 -49.152048) (xy 76.057252 -49.14011) (xy 76.03617 -49.125124)
			(xy 75.938126 -49.113694) (xy 75.929666 -49.112972) (xy 75.913084 -49.116589) (xy 75.898579 -49.125402)
			(xy 75.892914 -49.131728) (xy 75.89266 -49.132236) (xy 75.892406 -49.13249) (xy 75.874208 -49.154183)
			(xy 75.832477 -49.192453) (xy 75.785545 -49.22413) (xy 75.734444 -49.248518) (xy 75.680299 -49.26508)
			(xy 75.624299 -49.273452) (xy 75.595988 -49.273968) (xy 75.568733 -49.273556) (xy 75.514778 -49.265797)
			(xy 75.462477 -49.250437) (xy 75.412894 -49.22779) (xy 75.367039 -49.198317) (xy 75.325845 -49.162618)
			(xy 75.290152 -49.121419) (xy 75.260685 -49.07556) (xy 75.238045 -49.025974) (xy 75.222692 -48.973671)
			(xy 75.21494 -48.919715) (xy 75.21448 -48.89246) (xy 73.905687 -48.89246) (xy 73.883411 -48.93998)
			(xy 73.852638 -48.986493) (xy 73.815421 -49.02803) (xy 73.772553 -49.063705) (xy 73.724947 -49.092759)
			(xy 73.673618 -49.114571) (xy 73.619661 -49.128677) (xy 73.564224 -49.134777) (xy 73.50849 -49.13274)
			(xy 73.453647 -49.12261) (xy 73.400863 -49.104603) (xy 73.351263 -49.079102) (xy 73.305905 -49.046651)
			(xy 73.265756 -49.007942) (xy 73.23167 -48.963799) (xy 73.204374 -48.915164) (xy 73.184451 -48.863073)
			(xy 73.172325 -48.808636) (xy 73.168254 -48.753014) (xy 71.449692 -48.753014) (xy 71.449206 -48.780265)
			(xy 71.44145 -48.834213) (xy 71.426095 -48.886508) (xy 71.403453 -48.936085) (xy 71.373987 -48.981935)
			(xy 71.338296 -49.023126) (xy 71.297105 -49.058817) (xy 71.251255 -49.088283) (xy 71.201678 -49.110925)
			(xy 71.149383 -49.12628) (xy 71.095435 -49.134036) (xy 71.040933 -49.134036) (xy 70.986985 -49.12628)
			(xy 70.93469 -49.110925) (xy 70.885113 -49.088283) (xy 70.839263 -49.058817) (xy 70.798072 -49.023126)
			(xy 70.762381 -48.981935) (xy 70.732915 -48.936085) (xy 70.710273 -48.886508) (xy 70.694918 -48.834213)
			(xy 70.687162 -48.780265) (xy 70.686676 -48.753014) (xy 70.687105 -48.726672) (xy 70.69436 -48.67449)
			(xy 70.708719 -48.6238) (xy 70.729911 -48.575566) (xy 70.757533 -48.530704) (xy 70.79106 -48.490064)
			(xy 70.829856 -48.45442) (xy 70.851268 -48.43907) (xy 70.863119 -48.430408) (xy 70.881555 -48.407575)
			(xy 70.892736 -48.380442) (xy 70.89574 -48.351249) (xy 70.890319 -48.322408) (xy 70.876919 -48.296299)
			(xy 70.856649 -48.275078) (xy 70.844156 -48.267366) (xy 70.819636 -48.252647) (xy 70.774881 -48.217046)
			(xy 70.735939 -48.175166) (xy 70.703683 -48.127943) (xy 70.678835 -48.076436) (xy 70.66195 -48.021798)
			(xy 70.653408 -47.965252) (xy 70.652894 -47.936658) (xy 51.0271 -47.936658) (xy 51.069391 -47.949075)
			(xy 51.118971 -47.971716) (xy 51.164824 -48.001183) (xy 51.206017 -48.036876) (xy 51.241711 -48.078068)
			(xy 51.271179 -48.12392) (xy 51.293821 -48.1735) (xy 51.309178 -48.225797) (xy 51.316935 -48.279747)
			(xy 51.316935 -48.334253) (xy 51.309178 -48.388203) (xy 51.293821 -48.4405) (xy 51.271179 -48.49008)
			(xy 51.241711 -48.535932) (xy 51.206017 -48.577124) (xy 51.164824 -48.612817) (xy 51.118971 -48.642284)
			(xy 51.069391 -48.664925) (xy 51.017093 -48.68028) (xy 50.963143 -48.688035) (xy 50.93589 -48.688498)
			(xy 50.935382 -48.688498) (xy 50.920589 -48.688367) (xy 50.891091 -48.686075) (xy 50.876454 -48.683926)
			(xy 50.864262 -48.681894) (xy 50.840894 -48.689768) (xy 50.7746 -48.758602) (xy 50.770532 -48.763071)
			(xy 50.764364 -48.773459) (xy 50.762408 -48.779176) (xy 50.758852 -48.791114) (xy 50.761138 -48.80356)
			(xy 50.764315 -48.821233) (xy 50.767747 -48.856979) (xy 50.767996 -48.874934) (xy 50.767554 -48.902187)
			(xy 50.762558 -48.93691) (xy 52.93309 -48.93691) (xy 52.937161 -48.881288) (xy 52.949287 -48.826851)
			(xy 52.96921 -48.77476) (xy 52.996506 -48.726125) (xy 53.030592 -48.681982) (xy 53.070741 -48.643273)
			(xy 53.116099 -48.610822) (xy 53.165699 -48.585321) (xy 53.218483 -48.567314) (xy 53.273326 -48.557184)
			(xy 53.32906 -48.555147) (xy 53.384497 -48.561247) (xy 53.438454 -48.575353) (xy 53.489783 -48.597165)
			(xy 53.537389 -48.626219) (xy 53.580257 -48.661894) (xy 53.617474 -48.703431) (xy 53.648247 -48.749944)
			(xy 53.671919 -48.800441) (xy 53.687987 -48.853848) (xy 53.696107 -48.909024) (xy 53.696616 -48.93691)
			(xy 53.696107 -48.964796) (xy 53.687987 -49.019972) (xy 53.671919 -49.073379) (xy 53.648247 -49.123876)
			(xy 53.617474 -49.170389) (xy 53.580257 -49.211926) (xy 53.537389 -49.247601) (xy 53.489783 -49.276655)
			(xy 53.438454 -49.298467) (xy 53.384497 -49.312573) (xy 53.32906 -49.318673) (xy 53.273326 -49.316636)
			(xy 53.218483 -49.306506) (xy 53.165699 -49.288499) (xy 53.116099 -49.262998) (xy 53.070741 -49.230547)
			(xy 53.030592 -49.191838) (xy 52.996506 -49.147695) (xy 52.96921 -49.09906) (xy 52.949287 -49.046969)
			(xy 52.937161 -48.992532) (xy 52.93309 -48.93691) (xy 50.762558 -48.93691) (xy 50.759792 -48.956137)
			(xy 50.744432 -49.008433) (xy 50.721786 -49.058011) (xy 50.692315 -49.103862) (xy 50.656619 -49.145052)
			(xy 50.615425 -49.180743) (xy 50.569571 -49.210208) (xy 50.51999 -49.232848) (xy 50.467692 -49.248202)
			(xy 50.413741 -49.255957) (xy 50.386488 -49.256442) (xy 50.356695 -49.255847) (xy 50.297831 -49.246595)
			(xy 50.241123 -49.228301) (xy 50.187949 -49.201411) (xy 50.139604 -49.16658) (xy 50.097263 -49.124654)
			(xy 50.079148 -49.100994) (xy 50.071782 -49.090834) (xy 50.049938 -49.080166) (xy 49.941734 -49.082452)
			(xy 49.920144 -49.09439) (xy 49.913032 -49.104804) (xy 49.897778 -49.126763) (xy 49.8621 -49.166587)
			(xy 49.821214 -49.201042) (xy 49.775919 -49.229453) (xy 49.727101 -49.251264) (xy 49.675718 -49.266048)
			(xy 49.622774 -49.273516) (xy 49.59604 -49.273968) (xy 49.568782 -49.273588) (xy 49.514821 -49.265835)
			(xy 49.462513 -49.25048) (xy 49.412923 -49.227838) (xy 49.36706 -49.198368) (xy 49.325858 -49.16267)
			(xy 49.290156 -49.121472) (xy 49.260681 -49.075612) (xy 49.238034 -49.026024) (xy 49.222674 -48.973718)
			(xy 49.214915 -48.919758) (xy 47.892943 -48.919758) (xy 47.883463 -48.93998) (xy 47.85269 -48.986493)
			(xy 47.815473 -49.02803) (xy 47.772605 -49.063705) (xy 47.724999 -49.092759) (xy 47.67367 -49.114571)
			(xy 47.619713 -49.128677) (xy 47.564276 -49.134777) (xy 47.508542 -49.13274) (xy 47.453699 -49.12261)
			(xy 47.400915 -49.104603) (xy 47.351315 -49.079102) (xy 47.305957 -49.046651) (xy 47.265808 -49.007942)
			(xy 47.231722 -48.963799) (xy 47.204426 -48.915164) (xy 47.184503 -48.863073) (xy 47.172377 -48.808636)
			(xy 47.168306 -48.753014) (xy 45.449744 -48.753014) (xy 45.449258 -48.780265) (xy 45.441502 -48.834213)
			(xy 45.426147 -48.886508) (xy 45.403505 -48.936085) (xy 45.374039 -48.981935) (xy 45.338348 -49.023126)
			(xy 45.297157 -49.058817) (xy 45.251307 -49.088283) (xy 45.20173 -49.110925) (xy 45.149435 -49.12628)
			(xy 45.095487 -49.134036) (xy 45.040985 -49.134036) (xy 44.987037 -49.12628) (xy 44.934742 -49.110925)
			(xy 44.885165 -49.088283) (xy 44.839315 -49.058817) (xy 44.798124 -49.023126) (xy 44.762433 -48.981935)
			(xy 44.732967 -48.936085) (xy 44.710325 -48.886508) (xy 44.69497 -48.834213) (xy 44.687214 -48.780265)
			(xy 44.686728 -48.753014) (xy 44.687177 -48.726673) (xy 44.694431 -48.674492) (xy 44.708789 -48.623804)
			(xy 44.729978 -48.575571) (xy 44.757596 -48.530708) (xy 44.791119 -48.490068) (xy 44.82991 -48.454422)
			(xy 44.85132 -48.43907) (xy 44.863164 -48.430402) (xy 44.881589 -48.407567) (xy 44.892764 -48.380437)
			(xy 44.895766 -48.35125) (xy 44.890347 -48.322413) (xy 44.876956 -48.296305) (xy 44.856695 -48.275082)
			(xy 44.844208 -48.267366) (xy 44.8197 -48.252627) (xy 44.774942 -48.217032) (xy 44.735998 -48.175156)
			(xy 44.703739 -48.127937) (xy 44.678889 -48.076432) (xy 44.662003 -48.021796) (xy 44.65346 -47.965251)
			(xy 44.652946 -47.936658) (xy 25.027025 -47.936658) (xy 25.069421 -47.949111) (xy 25.118991 -47.971754)
			(xy 25.164835 -48.00122) (xy 25.206019 -48.036911) (xy 25.241705 -48.078099) (xy 25.271167 -48.123946)
			(xy 25.293804 -48.173519) (xy 25.309157 -48.225809) (xy 25.316912 -48.279751) (xy 25.316912 -48.334249)
			(xy 25.309157 -48.388191) (xy 25.293804 -48.440481) (xy 25.271167 -48.490054) (xy 25.241705 -48.535901)
			(xy 25.206019 -48.577089) (xy 25.164835 -48.61278) (xy 25.118991 -48.642246) (xy 25.069421 -48.664889)
			(xy 25.017132 -48.680248) (xy 24.963191 -48.688009) (xy 24.935942 -48.688498) (xy 24.935434 -48.688498)
			(xy 24.920641 -48.68836) (xy 24.891143 -48.686073) (xy 24.876506 -48.683926) (xy 24.864314 -48.681894)
			(xy 24.840946 -48.689768) (xy 24.774652 -48.758602) (xy 24.770578 -48.763066) (xy 24.764414 -48.773457)
			(xy 24.76246 -48.779176) (xy 24.758904 -48.791114) (xy 24.76119 -48.80356) (xy 24.764367 -48.821233)
			(xy 24.767799 -48.856979) (xy 24.768048 -48.874934) (xy 24.767554 -48.902184) (xy 24.762559 -48.93691)
			(xy 26.933142 -48.93691) (xy 26.937213 -48.881288) (xy 26.949339 -48.826851) (xy 26.969262 -48.77476)
			(xy 26.996558 -48.726125) (xy 27.030644 -48.681982) (xy 27.070793 -48.643273) (xy 27.116151 -48.610822)
			(xy 27.165751 -48.585321) (xy 27.218535 -48.567314) (xy 27.273378 -48.557184) (xy 27.329112 -48.555147)
			(xy 27.384549 -48.561247) (xy 27.438506 -48.575353) (xy 27.489835 -48.597165) (xy 27.537441 -48.626219)
			(xy 27.580309 -48.661894) (xy 27.617526 -48.703431) (xy 27.648299 -48.749944) (xy 27.671971 -48.800441)
			(xy 27.688039 -48.853848) (xy 27.696159 -48.909024) (xy 27.696668 -48.93691) (xy 27.696159 -48.964796)
			(xy 27.688039 -49.019972) (xy 27.671971 -49.073379) (xy 27.648299 -49.123876) (xy 27.617526 -49.170389)
			(xy 27.580309 -49.211926) (xy 27.537441 -49.247601) (xy 27.489835 -49.276655) (xy 27.438506 -49.298467)
			(xy 27.384549 -49.312573) (xy 27.329112 -49.318673) (xy 27.273378 -49.316636) (xy 27.218535 -49.306506)
			(xy 27.165751 -49.288499) (xy 27.116151 -49.262998) (xy 27.070793 -49.230547) (xy 27.030644 -49.191838)
			(xy 26.996558 -49.147695) (xy 26.969262 -49.09906) (xy 26.949339 -49.046969) (xy 26.937213 -48.992532)
			(xy 26.933142 -48.93691) (xy 24.762559 -48.93691) (xy 24.759794 -48.95613) (xy 24.744436 -49.008422)
			(xy 24.721794 -49.057996) (xy 24.692328 -49.103845) (xy 24.656638 -49.145034) (xy 24.61545 -49.180725)
			(xy 24.569602 -49.210191) (xy 24.520027 -49.232834) (xy 24.467735 -49.248193) (xy 24.41379 -49.255954)
			(xy 24.38654 -49.256442) (xy 24.356745 -49.255883) (xy 24.29788 -49.246623) (xy 24.241171 -49.228322)
			(xy 24.187998 -49.201426) (xy 24.139653 -49.166588) (xy 24.097314 -49.124657) (xy 24.0792 -49.100994)
			(xy 24.071834 -49.090834) (xy 24.04999 -49.080166) (xy 23.941786 -49.082452) (xy 23.920196 -49.09439)
			(xy 23.913084 -49.104804) (xy 23.89786 -49.126786) (xy 23.862178 -49.166609) (xy 23.821286 -49.201062)
			(xy 23.775986 -49.229471) (xy 23.727163 -49.251278) (xy 23.675775 -49.266057) (xy 23.622828 -49.27352)
			(xy 23.596092 -49.273968) (xy 23.568838 -49.273562) (xy 23.514886 -49.265803) (xy 23.462586 -49.250446)
			(xy 23.413005 -49.227802) (xy 23.367151 -49.198332) (xy 23.325957 -49.162637) (xy 23.290263 -49.121443)
			(xy 23.260794 -49.075588) (xy 23.238151 -49.026006) (xy 23.222795 -48.973706) (xy 23.215038 -48.919754)
			(xy 21.892997 -48.919754) (xy 21.883515 -48.93998) (xy 21.852742 -48.986493) (xy 21.815525 -49.02803)
			(xy 21.772657 -49.063705) (xy 21.725051 -49.092759) (xy 21.673722 -49.114571) (xy 21.619765 -49.128677)
			(xy 21.564328 -49.134777) (xy 21.508594 -49.13274) (xy 21.453751 -49.12261) (xy 21.400967 -49.104603)
			(xy 21.351367 -49.079102) (xy 21.306009 -49.046651) (xy 21.26586 -49.007942) (xy 21.231774 -48.963799)
			(xy 21.204478 -48.915164) (xy 21.184555 -48.863073) (xy 21.172429 -48.808636) (xy 21.168358 -48.753014)
			(xy 20.677886 -48.753014) (xy 20.395438 -49.035462) (xy 20.388072 -49.042574) (xy 20.380452 -49.06137)
			(xy 20.380452 -49.95291) (xy 26.933142 -49.95291) (xy 26.937213 -49.897288) (xy 26.949339 -49.842851)
			(xy 26.969262 -49.79076) (xy 26.996558 -49.742125) (xy 27.030644 -49.697982) (xy 27.070793 -49.659273)
			(xy 27.116151 -49.626822) (xy 27.165751 -49.601321) (xy 27.218535 -49.583314) (xy 27.273378 -49.573184)
			(xy 27.329112 -49.571147) (xy 27.384549 -49.577247) (xy 27.438506 -49.591353) (xy 27.463453 -49.601954)
			(xy 28.290959 -49.601954) (xy 28.290959 -49.547446) (xy 28.298717 -49.493493) (xy 28.314074 -49.441194)
			(xy 28.336719 -49.391612) (xy 28.366189 -49.345758) (xy 28.401885 -49.304565) (xy 28.443081 -49.268872)
			(xy 28.488937 -49.239405) (xy 28.53852 -49.216765) (xy 28.590821 -49.201411) (xy 28.644774 -49.193657)
			(xy 28.672028 -49.193196) (xy 28.699399 -49.193647) (xy 28.753578 -49.201468) (xy 28.806082 -49.216961)
			(xy 28.855828 -49.239806) (xy 28.901795 -49.269534) (xy 28.922726 -49.287176) (xy 28.92298 -49.28743)
			(xy 28.930066 -49.293018) (xy 28.946983 -49.299263) (xy 28.956 -49.299622) (xy 29.023056 -49.299622)
			(xy 29.03207 -49.299239) (xy 29.048987 -49.293009) (xy 29.056076 -49.28743) (xy 29.056584 -49.286922)
			(xy 29.077514 -49.269305) (xy 29.123482 -49.239643) (xy 29.173216 -49.216855) (xy 29.225697 -49.201408)
			(xy 29.279847 -49.193619) (xy 29.334553 -49.193647) (xy 29.388695 -49.201494) (xy 29.441159 -49.216996)
			(xy 29.49087 -49.239836) (xy 29.536807 -49.269546) (xy 29.557726 -49.287176) (xy 29.55798 -49.28743)
			(xy 29.565066 -49.293018) (xy 29.581983 -49.299263) (xy 29.591 -49.299622) (xy 29.658056 -49.299622)
			(xy 29.66707 -49.299239) (xy 29.683987 -49.293009) (xy 29.691076 -49.28743) (xy 29.691584 -49.286922)
			(xy 29.712508 -49.269327) (xy 29.758445 -49.239688) (xy 29.808143 -49.216912) (xy 29.860584 -49.201465)
			(xy 29.914694 -49.193663) (xy 29.942028 -49.193196) (xy 29.942282 -49.193196) (xy 29.968576 -49.193668)
			(xy 30.020664 -49.200911) (xy 30.071265 -49.215234) (xy 30.119422 -49.236367) (xy 30.164222 -49.26391)
			(xy 30.204817 -49.297341) (xy 30.222952 -49.316386) (xy 30.230507 -49.323847) (xy 30.249938 -49.332361)
			(xy 30.260544 -49.332896) (xy 30.334712 -49.332896) (xy 30.345344 -49.332486) (xy 30.364808 -49.323937)
			(xy 30.372304 -49.316386) (xy 30.390419 -49.297317) (xy 30.431004 -49.263862) (xy 30.475804 -49.236305)
			(xy 30.523966 -49.215168) (xy 30.574577 -49.200853) (xy 30.626676 -49.193632) (xy 30.652974 -49.193196)
			(xy 30.653228 -49.193196) (xy 30.680478 -49.193676) (xy 30.734423 -49.201436) (xy 30.786715 -49.216793)
			(xy 30.83629 -49.239436) (xy 30.882137 -49.268904) (xy 30.923324 -49.304595) (xy 30.959013 -49.345785)
			(xy 30.988477 -49.391635) (xy 31.011117 -49.441211) (xy 31.02647 -49.493504) (xy 31.034226 -49.54745)
			(xy 31.034226 -49.601949) (xy 32.112982 -49.601949) (xy 32.112982 -49.547451) (xy 32.120737 -49.493506)
			(xy 32.13609 -49.441215) (xy 32.158729 -49.39164) (xy 32.188192 -49.345792) (xy 32.223879 -49.304603)
			(xy 32.265065 -49.268912) (xy 32.310911 -49.239445) (xy 32.360483 -49.216802) (xy 32.412773 -49.201444)
			(xy 32.466717 -49.193684) (xy 32.493966 -49.193196) (xy 32.521335 -49.193683) (xy 32.575514 -49.201496)
			(xy 32.628016 -49.21698) (xy 32.677764 -49.239817) (xy 32.723732 -49.269537) (xy 32.744664 -49.287176)
			(xy 32.744918 -49.28743) (xy 32.751993 -49.293034) (xy 32.768919 -49.299269) (xy 32.777938 -49.299622)
			(xy 32.844994 -49.299622) (xy 32.85401 -49.299257) (xy 32.870927 -49.293014) (xy 32.878014 -49.28743)
			(xy 32.878522 -49.286922) (xy 32.899422 -49.269268) (xy 32.945395 -49.239608) (xy 32.995135 -49.216822)
			(xy 33.04762 -49.201377) (xy 33.101773 -49.193592) (xy 33.156484 -49.193625) (xy 33.210628 -49.201475)
			(xy 33.263095 -49.216983) (xy 33.312807 -49.239828) (xy 33.358744 -49.269544) (xy 33.379664 -49.287176)
			(xy 33.379918 -49.28743) (xy 33.386993 -49.293034) (xy 33.403919 -49.299269) (xy 33.412938 -49.299622)
			(xy 33.479994 -49.299622) (xy 33.48901 -49.299257) (xy 33.505927 -49.293014) (xy 33.513014 -49.28743)
			(xy 33.513522 -49.286922) (xy 33.534422 -49.269268) (xy 33.580395 -49.239608) (xy 33.630135 -49.216822)
			(xy 33.68262 -49.201377) (xy 33.736773 -49.193592) (xy 33.791484 -49.193625) (xy 33.845628 -49.201475)
			(xy 33.898095 -49.216983) (xy 33.947807 -49.239828) (xy 33.993744 -49.269544) (xy 34.014664 -49.287176)
			(xy 34.014918 -49.28743) (xy 34.021993 -49.293034) (xy 34.038919 -49.299269) (xy 34.047938 -49.299622)
			(xy 34.114994 -49.299622) (xy 34.12401 -49.299257) (xy 34.140927 -49.293014) (xy 34.148014 -49.28743)
			(xy 34.148522 -49.286922) (xy 34.169469 -49.269356) (xy 34.2154 -49.239713) (xy 34.265092 -49.216931)
			(xy 34.317528 -49.201477) (xy 34.371633 -49.193668) (xy 34.398966 -49.193196) (xy 34.426221 -49.193649)
			(xy 34.480176 -49.201402) (xy 34.532478 -49.216755) (xy 34.582063 -49.239396) (xy 34.627921 -49.268864)
			(xy 34.669118 -49.304558) (xy 34.704816 -49.345752) (xy 34.734287 -49.391607) (xy 34.756933 -49.44119)
			(xy 34.772291 -49.493491) (xy 34.780049 -49.547445) (xy 34.780049 -49.601955) (xy 34.772291 -49.655909)
			(xy 34.756933 -49.70821) (xy 34.734287 -49.757793) (xy 34.704816 -49.803648) (xy 34.669118 -49.844842)
			(xy 34.627921 -49.880536) (xy 34.582063 -49.910004) (xy 34.532478 -49.932645) (xy 34.480176 -49.947998)
			(xy 34.445992 -49.95291) (xy 52.93309 -49.95291) (xy 52.937161 -49.897288) (xy 52.949287 -49.842851)
			(xy 52.96921 -49.79076) (xy 52.996506 -49.742125) (xy 53.030592 -49.697982) (xy 53.070741 -49.659273)
			(xy 53.116099 -49.626822) (xy 53.165699 -49.601321) (xy 53.218483 -49.583314) (xy 53.273326 -49.573184)
			(xy 53.32906 -49.571147) (xy 53.384497 -49.577247) (xy 53.438454 -49.591353) (xy 53.463391 -49.60195)
			(xy 54.290982 -49.60195) (xy 54.290982 -49.54745) (xy 54.298738 -49.493505) (xy 54.314091 -49.441213)
			(xy 54.33673 -49.391638) (xy 54.366194 -49.345789) (xy 54.401883 -49.3046) (xy 54.44307 -49.268909)
			(xy 54.488917 -49.239442) (xy 54.53849 -49.2168) (xy 54.590782 -49.201443) (xy 54.644726 -49.193683)
			(xy 54.671976 -49.193196) (xy 54.699346 -49.193677) (xy 54.753524 -49.201491) (xy 54.806027 -49.216977)
			(xy 54.855774 -49.239815) (xy 54.901742 -49.269536) (xy 54.922674 -49.287176) (xy 54.922928 -49.28743)
			(xy 54.930029 -49.292996) (xy 54.946935 -49.299254) (xy 54.955948 -49.299622) (xy 55.023004 -49.299622)
			(xy 55.03202 -49.299262) (xy 55.048937 -49.293016) (xy 55.056024 -49.28743) (xy 55.056532 -49.286922)
			(xy 55.077503 -49.269356) (xy 55.123464 -49.239692) (xy 55.173192 -49.216901) (xy 55.225666 -49.20145)
			(xy 55.27981 -49.193656) (xy 55.334512 -49.193679) (xy 55.388649 -49.201519) (xy 55.44111 -49.217014)
			(xy 55.490819 -49.239848) (xy 55.536755 -49.26955) (xy 55.557674 -49.287176) (xy 55.557928 -49.28743)
			(xy 55.565029 -49.292996) (xy 55.581935 -49.299254) (xy 55.590948 -49.299622) (xy 55.658004 -49.299622)
			(xy 55.66702 -49.299262) (xy 55.683937 -49.293016) (xy 55.691024 -49.28743) (xy 55.691532 -49.286922)
			(xy 55.712475 -49.269351) (xy 55.758407 -49.239709) (xy 55.8081 -49.216928) (xy 55.860537 -49.201475)
			(xy 55.914643 -49.193667) (xy 55.941976 -49.193196) (xy 55.94223 -49.193196) (xy 55.968525 -49.193636)
			(xy 56.020615 -49.200885) (xy 56.071217 -49.215215) (xy 56.119373 -49.236354) (xy 56.164172 -49.263902)
			(xy 56.204766 -49.297338) (xy 56.2229 -49.316386) (xy 56.230474 -49.323824) (xy 56.24989 -49.332351)
			(xy 56.260492 -49.332896) (xy 56.33466 -49.332896) (xy 56.345295 -49.332512) (xy 56.364759 -49.323945)
			(xy 56.372252 -49.316386) (xy 56.390392 -49.297342) (xy 56.430972 -49.263885) (xy 56.475766 -49.236324)
			(xy 56.523924 -49.215183) (xy 56.57453 -49.200863) (xy 56.626625 -49.193636) (xy 56.652922 -49.193196)
			(xy 56.653176 -49.193196) (xy 56.68043 -49.19365) (xy 56.734384 -49.201404) (xy 56.786686 -49.216758)
			(xy 56.836269 -49.239399) (xy 56.882126 -49.268867) (xy 56.923322 -49.304561) (xy 56.959018 -49.345755)
			(xy 56.988489 -49.39161) (xy 57.011133 -49.441192) (xy 57.026491 -49.493492) (xy 57.034249 -49.547446)
			(xy 57.034249 -49.601953) (xy 58.112859 -49.601953) (xy 58.112859 -49.547447) (xy 58.120617 -49.493495)
			(xy 58.135973 -49.441197) (xy 58.158616 -49.391616) (xy 58.188085 -49.345763) (xy 58.22378 -49.30457)
			(xy 58.264974 -49.268877) (xy 58.310829 -49.23941) (xy 58.36041 -49.216768) (xy 58.412709 -49.201414)
			(xy 58.466661 -49.193658) (xy 58.493914 -49.193196) (xy 58.521284 -49.193655) (xy 58.575464 -49.201475)
			(xy 58.627967 -49.216965) (xy 58.677714 -49.239809) (xy 58.72368 -49.269534) (xy 58.744612 -49.287176)
			(xy 58.744866 -49.28743) (xy 58.751956 -49.293012) (xy 58.76887 -49.29926) (xy 58.777886 -49.299622)
			(xy 58.844942 -49.299622) (xy 58.853956 -49.299233) (xy 58.870873 -49.293007) (xy 58.877962 -49.28743)
			(xy 58.87847 -49.286922) (xy 58.899411 -49.269319) (xy 58.945377 -49.239657) (xy 58.99511 -49.216868)
			(xy 59.047589 -49.201419) (xy 59.101737 -49.193629) (xy 59.156442 -49.193656) (xy 59.210582 -49.2015)
			(xy 59.263046 -49.217001) (xy 59.312756 -49.239839) (xy 59.358693 -49.269547) (xy 59.379612 -49.287176)
			(xy 59.379866 -49.28743) (xy 59.386956 -49.293012) (xy 59.40387 -49.29926) (xy 59.412886 -49.299622)
			(xy 59.479942 -49.299622) (xy 59.488956 -49.299233) (xy 59.505873 -49.293007) (xy 59.512962 -49.28743)
			(xy 59.51347 -49.286922) (xy 59.534411 -49.269319) (xy 59.580377 -49.239657) (xy 59.63011 -49.216868)
			(xy 59.682589 -49.201419) (xy 59.736737 -49.193629) (xy 59.791442 -49.193656) (xy 59.845582 -49.2015)
			(xy 59.898046 -49.217001) (xy 59.947756 -49.239839) (xy 59.993693 -49.269547) (xy 60.014612 -49.287176)
			(xy 60.014866 -49.28743) (xy 60.021956 -49.293012) (xy 60.03887 -49.29926) (xy 60.047886 -49.299622)
			(xy 60.114942 -49.299622) (xy 60.123956 -49.299233) (xy 60.140873 -49.293007) (xy 60.147962 -49.28743)
			(xy 60.14847 -49.286922) (xy 60.169399 -49.269334) (xy 60.215335 -49.239694) (xy 60.265032 -49.216916)
			(xy 60.317472 -49.201468) (xy 60.37158 -49.193664) (xy 60.398914 -49.193196) (xy 60.426165 -49.193675)
			(xy 60.480112 -49.201433) (xy 60.532405 -49.216789) (xy 60.581981 -49.239432) (xy 60.62783 -49.268899)
			(xy 60.669019 -49.304591) (xy 60.70471 -49.345781) (xy 60.734175 -49.391631) (xy 60.756815 -49.441208)
			(xy 60.77217 -49.493502) (xy 60.779926 -49.547449) (xy 60.779926 -49.601951) (xy 60.77217 -49.655898)
			(xy 60.756815 -49.708192) (xy 60.734175 -49.757769) (xy 60.70471 -49.803619) (xy 60.669019 -49.844809)
			(xy 60.62783 -49.880501) (xy 60.581981 -49.909968) (xy 60.532405 -49.932611) (xy 60.480112 -49.947967)
			(xy 60.44574 -49.95291) (xy 78.933038 -49.95291) (xy 78.937109 -49.897288) (xy 78.949235 -49.842851)
			(xy 78.969158 -49.79076) (xy 78.996454 -49.742125) (xy 79.03054 -49.697982) (xy 79.070689 -49.659273)
			(xy 79.116047 -49.626822) (xy 79.165647 -49.601321) (xy 79.218431 -49.583314) (xy 79.273274 -49.573184)
			(xy 79.329008 -49.571147) (xy 79.384445 -49.577247) (xy 79.438402 -49.591353) (xy 79.463349 -49.601954)
			(xy 80.290859 -49.601954) (xy 80.290859 -49.547446) (xy 80.298617 -49.493494) (xy 80.313974 -49.441195)
			(xy 80.336618 -49.391613) (xy 80.366088 -49.34576) (xy 80.401784 -49.304567) (xy 80.442979 -49.268874)
			(xy 80.488835 -49.239406) (xy 80.538417 -49.216766) (xy 80.590717 -49.201412) (xy 80.64467 -49.193658)
			(xy 80.671924 -49.193196) (xy 80.699295 -49.193649) (xy 80.753474 -49.20147) (xy 80.805978 -49.216962)
			(xy 80.855724 -49.239807) (xy 80.901691 -49.269534) (xy 80.922622 -49.287176) (xy 80.922876 -49.28743)
			(xy 80.929963 -49.293016) (xy 80.94688 -49.299262) (xy 80.955896 -49.299622) (xy 81.022952 -49.299622)
			(xy 81.031966 -49.299237) (xy 81.048883 -49.293008) (xy 81.055972 -49.28743) (xy 81.05648 -49.286922)
			(xy 81.077413 -49.269309) (xy 81.12338 -49.239647) (xy 81.173114 -49.216859) (xy 81.225595 -49.201411)
			(xy 81.279744 -49.193622) (xy 81.33445 -49.19365) (xy 81.388591 -49.201495) (xy 81.441055 -49.216997)
			(xy 81.490766 -49.239837) (xy 81.536703 -49.269547) (xy 81.557622 -49.287176) (xy 81.557876 -49.28743)
			(xy 81.564963 -49.293016) (xy 81.58188 -49.299262) (xy 81.590896 -49.299622) (xy 81.657952 -49.299622)
			(xy 81.666966 -49.299237) (xy 81.683883 -49.293008) (xy 81.690972 -49.28743) (xy 81.69148 -49.286922)
			(xy 81.712405 -49.269329) (xy 81.758342 -49.23969) (xy 81.80804 -49.216913) (xy 81.860481 -49.201466)
			(xy 81.91459 -49.193664) (xy 81.941924 -49.193196) (xy 81.942178 -49.193196) (xy 81.968472 -49.193671)
			(xy 82.02056 -49.200913) (xy 82.071161 -49.215236) (xy 82.119317 -49.236368) (xy 82.164117 -49.26391)
			(xy 82.204713 -49.297341) (xy 82.222848 -49.316386) (xy 82.230405 -49.323845) (xy 82.249834 -49.332361)
			(xy 82.26044 -49.332896) (xy 82.334608 -49.332896) (xy 82.34524 -49.332484) (xy 82.364704 -49.323937)
			(xy 82.3722 -49.316386) (xy 82.390317 -49.297319) (xy 82.430902 -49.263864) (xy 82.475701 -49.236306)
			(xy 82.523863 -49.215169) (xy 82.574474 -49.200854) (xy 82.626572 -49.193633) (xy 82.65287 -49.193196)
			(xy 82.653124 -49.193196) (xy 82.680374 -49.193675) (xy 82.73432 -49.201435) (xy 82.786613 -49.216792)
			(xy 82.836187 -49.239435) (xy 82.882035 -49.268902) (xy 82.923223 -49.304594) (xy 82.958912 -49.345784)
			(xy 82.988377 -49.391634) (xy 83.011016 -49.44121) (xy 83.02637 -49.493503) (xy 83.034126 -49.54745)
			(xy 83.034126 -49.601949) (xy 84.112882 -49.601949) (xy 84.112882 -49.547451) (xy 84.120637 -49.493507)
			(xy 84.13599 -49.441216) (xy 84.158628 -49.391642) (xy 84.188091 -49.345793) (xy 84.223778 -49.304605)
			(xy 84.264963 -49.268914) (xy 84.310808 -49.239447) (xy 84.36038 -49.216803) (xy 84.41267 -49.201445)
			(xy 84.466613 -49.193684) (xy 84.493862 -49.193196) (xy 84.521231 -49.193685) (xy 84.575409 -49.201498)
			(xy 84.627912 -49.216981) (xy 84.677659 -49.239818) (xy 84.723627 -49.269537) (xy 84.74456 -49.287176)
			(xy 84.744814 -49.28743) (xy 84.75189 -49.293032) (xy 84.768815 -49.299268) (xy 84.777834 -49.299622)
			(xy 84.84489 -49.299622) (xy 84.853906 -49.299255) (xy 84.870823 -49.293014) (xy 84.87791 -49.28743)
			(xy 84.878418 -49.286922) (xy 84.899321 -49.269272) (xy 84.945293 -49.239612) (xy 84.995033 -49.216825)
			(xy 85.047517 -49.201381) (xy 85.101671 -49.193595) (xy 85.156381 -49.193627) (xy 85.210525 -49.201477)
			(xy 85.262991 -49.216984) (xy 85.312703 -49.239829) (xy 85.35864 -49.269544) (xy 85.37956 -49.287176)
			(xy 85.379814 -49.28743) (xy 85.38689 -49.293032) (xy 85.403815 -49.299268) (xy 85.412834 -49.299622)
			(xy 85.47989 -49.299622) (xy 85.488906 -49.299255) (xy 85.505823 -49.293014) (xy 85.51291 -49.28743)
			(xy 85.513418 -49.286922) (xy 85.534321 -49.269272) (xy 85.580293 -49.239612) (xy 85.630033 -49.216825)
			(xy 85.682517 -49.201381) (xy 85.736671 -49.193595) (xy 85.791381 -49.193627) (xy 85.845525 -49.201477)
			(xy 85.897991 -49.216984) (xy 85.947703 -49.239829) (xy 85.99364 -49.269544) (xy 86.01456 -49.287176)
			(xy 86.014814 -49.28743) (xy 86.02189 -49.293032) (xy 86.038815 -49.299268) (xy 86.047834 -49.299622)
			(xy 86.11489 -49.299622) (xy 86.123906 -49.299255) (xy 86.140823 -49.293014) (xy 86.14791 -49.28743)
			(xy 86.148418 -49.286922) (xy 86.169329 -49.269311) (xy 86.21527 -49.239675) (xy 86.264971 -49.216902)
			(xy 86.317415 -49.201458) (xy 86.371527 -49.193661) (xy 86.398862 -49.193196) (xy 86.426117 -49.193649)
			(xy 86.480073 -49.201401) (xy 86.532375 -49.216754) (xy 86.581961 -49.239395) (xy 86.627819 -49.268862)
			(xy 86.669017 -49.304556) (xy 86.704715 -49.34575) (xy 86.734187 -49.391606) (xy 86.756832 -49.441189)
			(xy 86.77219 -49.49349) (xy 86.779949 -49.547445) (xy 86.779949 -49.601955) (xy 86.77219 -49.65591)
			(xy 86.756832 -49.708211) (xy 86.734187 -49.757794) (xy 86.704715 -49.80365) (xy 86.669017 -49.844844)
			(xy 86.627819 -49.880538) (xy 86.581961 -49.910005) (xy 86.532375 -49.932646) (xy 86.480073 -49.947999)
			(xy 86.445891 -49.95291) (xy 104.932986 -49.95291) (xy 104.937057 -49.897288) (xy 104.949183 -49.842851)
			(xy 104.969106 -49.79076) (xy 104.996402 -49.742125) (xy 105.030488 -49.697982) (xy 105.070637 -49.659273)
			(xy 105.115995 -49.626822) (xy 105.165595 -49.601321) (xy 105.218379 -49.583314) (xy 105.273222 -49.573184)
			(xy 105.328956 -49.571147) (xy 105.384393 -49.577247) (xy 105.43835 -49.591353) (xy 105.463287 -49.60195)
			(xy 118.391182 -49.60195) (xy 118.391182 -49.54745) (xy 118.398938 -49.493505) (xy 118.414291 -49.441212)
			(xy 118.436931 -49.391637) (xy 118.466395 -49.345788) (xy 118.502083 -49.304599) (xy 118.543271 -49.268908)
			(xy 118.589118 -49.239441) (xy 118.638692 -49.216799) (xy 118.690983 -49.201442) (xy 118.744928 -49.193683)
			(xy 118.772178 -49.193196) (xy 118.799548 -49.193676) (xy 118.853726 -49.201491) (xy 118.906229 -49.216976)
			(xy 118.955976 -49.239815) (xy 119.001944 -49.269536) (xy 119.022876 -49.287176) (xy 119.02313 -49.28743)
			(xy 119.03023 -49.292997) (xy 119.047137 -49.299254) (xy 119.05615 -49.299622) (xy 119.123206 -49.299622)
			(xy 119.132223 -49.299263) (xy 119.149139 -49.293016) (xy 119.156226 -49.28743) (xy 119.156734 -49.286922)
			(xy 119.177704 -49.269354) (xy 119.223664 -49.23969) (xy 119.273393 -49.216899) (xy 119.325867 -49.201448)
			(xy 119.380011 -49.193654) (xy 119.434713 -49.193678) (xy 119.488851 -49.201518) (xy 119.541312 -49.217013)
			(xy 119.591021 -49.239847) (xy 119.636957 -49.26955) (xy 119.657876 -49.287176) (xy 119.65813 -49.28743)
			(xy 119.66523 -49.292997) (xy 119.682137 -49.299254) (xy 119.69115 -49.299622) (xy 119.758206 -49.299622)
			(xy 119.767223 -49.299263) (xy 119.784139 -49.293016) (xy 119.791226 -49.28743) (xy 119.791734 -49.286922)
			(xy 119.812677 -49.26935) (xy 119.858609 -49.239708) (xy 119.908302 -49.216927) (xy 119.960739 -49.201475)
			(xy 120.014845 -49.193667) (xy 120.042178 -49.193196) (xy 120.042432 -49.193196) (xy 120.068728 -49.193635)
			(xy 120.120817 -49.200884) (xy 120.171419 -49.215214) (xy 120.219575 -49.236354) (xy 120.264374 -49.263902)
			(xy 120.304968 -49.297338) (xy 120.323102 -49.316386) (xy 120.330676 -49.323825) (xy 120.350092 -49.332352)
			(xy 120.360694 -49.332896) (xy 120.434862 -49.332896) (xy 120.445497 -49.332513) (xy 120.464961 -49.323945)
			(xy 120.472454 -49.316386) (xy 120.490593 -49.297341) (xy 120.531173 -49.263884) (xy 120.575968 -49.236324)
			(xy 120.624125 -49.215183) (xy 120.674732 -49.200863) (xy 120.726827 -49.193636) (xy 120.753124 -49.193196)
			(xy 120.753378 -49.193196) (xy 120.780632 -49.19365) (xy 120.834586 -49.201404) (xy 120.886887 -49.216759)
			(xy 120.93647 -49.2394) (xy 120.982327 -49.268868) (xy 121.023523 -49.304562) (xy 121.059219 -49.345756)
			(xy 121.088689 -49.39161) (xy 121.111334 -49.441192) (xy 121.126691 -49.493492) (xy 121.134449 -49.547446)
			(xy 121.134449 -49.601953) (xy 122.213059 -49.601953) (xy 122.213059 -49.547447) (xy 122.220817 -49.493495)
			(xy 122.236173 -49.441196) (xy 122.258817 -49.391616) (xy 122.288286 -49.345762) (xy 122.323981 -49.30457)
			(xy 122.365175 -49.268876) (xy 122.41103 -49.239409) (xy 122.460611 -49.216768) (xy 122.512911 -49.201413)
			(xy 122.566863 -49.193658) (xy 122.594116 -49.193196) (xy 122.621487 -49.193654) (xy 122.675666 -49.201474)
			(xy 122.728169 -49.216965) (xy 122.777916 -49.239808) (xy 122.823882 -49.269534) (xy 122.844814 -49.287176)
			(xy 122.845068 -49.28743) (xy 122.852157 -49.293013) (xy 122.869072 -49.299261) (xy 122.878088 -49.299622)
			(xy 122.945144 -49.299622) (xy 122.954158 -49.299234) (xy 122.971075 -49.293007) (xy 122.978164 -49.28743)
			(xy 122.978672 -49.286922) (xy 122.999611 -49.269317) (xy 123.045578 -49.239655) (xy 123.095311 -49.216866)
			(xy 123.14779 -49.201418) (xy 123.201938 -49.193627) (xy 123.256644 -49.193655) (xy 123.310784 -49.201499)
			(xy 123.363248 -49.217) (xy 123.412958 -49.239839) (xy 123.458895 -49.269547) (xy 123.479814 -49.287176)
			(xy 123.480068 -49.28743) (xy 123.487157 -49.293013) (xy 123.504072 -49.299261) (xy 123.513088 -49.299622)
			(xy 123.580144 -49.299622) (xy 123.589158 -49.299234) (xy 123.606075 -49.293007) (xy 123.613164 -49.28743)
			(xy 123.613672 -49.286922) (xy 123.634611 -49.269317) (xy 123.680578 -49.239655) (xy 123.730311 -49.216866)
			(xy 123.78279 -49.201418) (xy 123.836938 -49.193627) (xy 123.891644 -49.193655) (xy 123.945784 -49.201499)
			(xy 123.998248 -49.217) (xy 124.047958 -49.239839) (xy 124.093895 -49.269547) (xy 124.114814 -49.287176)
			(xy 124.115068 -49.28743) (xy 124.122157 -49.293013) (xy 124.139072 -49.299261) (xy 124.148088 -49.299622)
			(xy 124.215144 -49.299622) (xy 124.224158 -49.299234) (xy 124.241075 -49.293007) (xy 124.248164 -49.28743)
			(xy 124.248672 -49.286922) (xy 124.2696 -49.269333) (xy 124.315536 -49.239693) (xy 124.365233 -49.216916)
			(xy 124.417673 -49.201467) (xy 124.471782 -49.193664) (xy 124.499116 -49.193196) (xy 124.526367 -49.193675)
			(xy 124.580313 -49.201433) (xy 124.632607 -49.21679) (xy 124.682182 -49.239432) (xy 124.728031 -49.268899)
			(xy 124.76922 -49.304591) (xy 124.80491 -49.345781) (xy 124.834375 -49.391632) (xy 124.857016 -49.441208)
			(xy 124.87237 -49.493502) (xy 124.880126 -49.547449) (xy 124.880126 -49.601951) (xy 124.87237 -49.655898)
			(xy 124.857016 -49.708192) (xy 124.834375 -49.757768) (xy 124.80491 -49.803619) (xy 124.76922 -49.844809)
			(xy 124.728031 -49.880501) (xy 124.682182 -49.909968) (xy 124.632607 -49.93261) (xy 124.580313 -49.947967)
			(xy 124.545941 -49.95291) (xy 143.03324 -49.95291) (xy 143.037311 -49.897288) (xy 143.049437 -49.842851)
			(xy 143.06936 -49.79076) (xy 143.096656 -49.742125) (xy 143.130742 -49.697982) (xy 143.170891 -49.659273)
			(xy 143.216249 -49.626822) (xy 143.265849 -49.601321) (xy 143.318633 -49.583314) (xy 143.373476 -49.573184)
			(xy 143.42921 -49.571147) (xy 143.484647 -49.577247) (xy 143.538604 -49.591353) (xy 143.563551 -49.601954)
			(xy 144.391059 -49.601954) (xy 144.391059 -49.547446) (xy 144.398817 -49.493494) (xy 144.414174 -49.441194)
			(xy 144.436818 -49.391613) (xy 144.466288 -49.345759) (xy 144.501985 -49.304566) (xy 144.54318 -49.268873)
			(xy 144.589036 -49.239406) (xy 144.638619 -49.216765) (xy 144.690919 -49.201411) (xy 144.744872 -49.193658)
			(xy 144.772126 -49.193196) (xy 144.799497 -49.193648) (xy 144.853676 -49.201469) (xy 144.90618 -49.216962)
			(xy 144.955926 -49.239807) (xy 145.001893 -49.269534) (xy 145.022824 -49.287176) (xy 145.023078 -49.28743)
			(xy 145.030164 -49.293017) (xy 145.047081 -49.299262) (xy 145.056098 -49.299622) (xy 145.123154 -49.299622)
			(xy 145.132168 -49.299238) (xy 145.149085 -49.293009) (xy 145.156174 -49.28743) (xy 145.156682 -49.286922)
			(xy 145.177614 -49.269307) (xy 145.223581 -49.239645) (xy 145.273315 -49.216857) (xy 145.325796 -49.20141)
			(xy 145.379945 -49.19362) (xy 145.434652 -49.193649) (xy 145.488793 -49.201495) (xy 145.541257 -49.216997)
			(xy 145.590968 -49.239837) (xy 145.636905 -49.269546) (xy 145.657824 -49.287176) (xy 145.658078 -49.28743)
			(xy 145.665164 -49.293017) (xy 145.682081 -49.299262) (xy 145.691098 -49.299622) (xy 145.758154 -49.299622)
			(xy 145.767168 -49.299238) (xy 145.784085 -49.293009) (xy 145.791174 -49.28743) (xy 145.791682 -49.286922)
			(xy 145.812606 -49.269328) (xy 145.858543 -49.239689) (xy 145.908242 -49.216913) (xy 145.960682 -49.201465)
			(xy 146.014792 -49.193664) (xy 146.042126 -49.193196) (xy 146.04238 -49.193196) (xy 146.068674 -49.193669)
			(xy 146.120762 -49.200912) (xy 146.171363 -49.215235) (xy 146.21952 -49.236368) (xy 146.264319 -49.26391)
			(xy 146.304915 -49.297341) (xy 146.32305 -49.316386) (xy 146.330606 -49.323846) (xy 146.350036 -49.332361)
			(xy 146.360642 -49.332896) (xy 146.43481 -49.332896) (xy 146.445442 -49.332485) (xy 146.464906 -49.323937)
			(xy 146.472402 -49.316386) (xy 146.490518 -49.297318) (xy 146.531103 -49.263863) (xy 146.575902 -49.236305)
			(xy 146.624064 -49.215169) (xy 146.674675 -49.200854) (xy 146.726774 -49.193633) (xy 146.753072 -49.193196)
			(xy 146.753326 -49.193196) (xy 146.780576 -49.193676) (xy 146.834522 -49.201435) (xy 146.886814 -49.216793)
			(xy 146.936388 -49.239436) (xy 146.982236 -49.268903) (xy 147.023424 -49.304595) (xy 147.059113 -49.345785)
			(xy 147.088577 -49.391634) (xy 147.111216 -49.44121) (xy 147.12657 -49.493504) (xy 147.134326 -49.54745)
			(xy 147.134326 -49.601949) (xy 148.213082 -49.601949) (xy 148.213082 -49.547451) (xy 148.220837 -49.493507)
			(xy 148.23619 -49.441215) (xy 148.258829 -49.391641) (xy 148.288291 -49.345793) (xy 148.323978 -49.304604)
			(xy 148.365164 -49.268913) (xy 148.411009 -49.239446) (xy 148.460582 -49.216803) (xy 148.512871 -49.201445)
			(xy 148.566815 -49.193684) (xy 148.594064 -49.193196) (xy 148.621433 -49.193684) (xy 148.675612 -49.201497)
			(xy 148.728114 -49.216981) (xy 148.777862 -49.239818) (xy 148.823829 -49.269537) (xy 148.844762 -49.287176)
			(xy 148.845016 -49.28743) (xy 148.852091 -49.293033) (xy 148.869017 -49.299269) (xy 148.878036 -49.299622)
			(xy 148.945092 -49.299622) (xy 148.954108 -49.299256) (xy 148.971025 -49.293014) (xy 148.978112 -49.28743)
			(xy 148.97862 -49.286922) (xy 148.999521 -49.26927) (xy 149.045494 -49.23961) (xy 149.095234 -49.216824)
			(xy 149.147719 -49.201379) (xy 149.201872 -49.193593) (xy 149.256582 -49.193626) (xy 149.310726 -49.201476)
			(xy 149.363193 -49.216983) (xy 149.412905 -49.239829) (xy 149.458842 -49.269544) (xy 149.479762 -49.287176)
			(xy 149.480016 -49.28743) (xy 149.487091 -49.293033) (xy 149.504017 -49.299269) (xy 149.513036 -49.299622)
			(xy 149.580092 -49.299622) (xy 149.589108 -49.299256) (xy 149.606025 -49.293014) (xy 149.613112 -49.28743)
			(xy 149.61362 -49.286922) (xy 149.634521 -49.26927) (xy 149.680494 -49.23961) (xy 149.730234 -49.216824)
			(xy 149.782719 -49.201379) (xy 149.836872 -49.193593) (xy 149.891582 -49.193626) (xy 149.945726 -49.201476)
			(xy 149.998193 -49.216983) (xy 150.047905 -49.239829) (xy 150.093842 -49.269544) (xy 150.114762 -49.287176)
			(xy 150.115016 -49.28743) (xy 150.122091 -49.293033) (xy 150.139017 -49.299269) (xy 150.148036 -49.299622)
			(xy 150.215092 -49.299622) (xy 150.224108 -49.299256) (xy 150.241025 -49.293014) (xy 150.248112 -49.28743)
			(xy 150.24862 -49.286922) (xy 150.26953 -49.26931) (xy 150.315471 -49.239674) (xy 150.365173 -49.216901)
			(xy 150.417617 -49.201458) (xy 150.471729 -49.193661) (xy 150.499064 -49.193196) (xy 150.526319 -49.193649)
			(xy 150.580274 -49.201402) (xy 150.632577 -49.216755) (xy 150.682162 -49.239396) (xy 150.72802 -49.268863)
			(xy 150.769218 -49.304557) (xy 150.804916 -49.345751) (xy 150.834387 -49.391606) (xy 150.857033 -49.441189)
			(xy 150.872391 -49.493491) (xy 150.880149 -49.547445) (xy 150.880149 -49.601955) (xy 150.872391 -49.655909)
			(xy 150.857033 -49.708211) (xy 150.834387 -49.757794) (xy 150.804916 -49.803649) (xy 150.769218 -49.844843)
			(xy 150.72802 -49.880537) (xy 150.682162 -49.910004) (xy 150.632577 -49.932645) (xy 150.580274 -49.947998)
			(xy 150.54609 -49.95291) (xy 169.033188 -49.95291) (xy 169.037259 -49.897288) (xy 169.049385 -49.842851)
			(xy 169.069308 -49.79076) (xy 169.096604 -49.742125) (xy 169.13069 -49.697982) (xy 169.170839 -49.659273)
			(xy 169.216197 -49.626822) (xy 169.265797 -49.601321) (xy 169.318581 -49.583314) (xy 169.373424 -49.573184)
			(xy 169.429158 -49.571147) (xy 169.484595 -49.577247) (xy 169.538552 -49.591353) (xy 169.563489 -49.60195)
			(xy 170.391082 -49.60195) (xy 170.391082 -49.54745) (xy 170.398837 -49.493505) (xy 170.414191 -49.441213)
			(xy 170.43683 -49.391638) (xy 170.466294 -49.34579) (xy 170.501982 -49.3046) (xy 170.543169 -49.268909)
			(xy 170.589015 -49.239443) (xy 170.638589 -49.2168) (xy 170.69088 -49.201443) (xy 170.744824 -49.193684)
			(xy 170.772074 -49.193196) (xy 170.799444 -49.193678) (xy 170.853622 -49.201492) (xy 170.906125 -49.216978)
			(xy 170.955872 -49.239816) (xy 171.00184 -49.269537) (xy 171.022772 -49.287176) (xy 171.023026 -49.28743)
			(xy 171.030127 -49.292995) (xy 171.047033 -49.299254) (xy 171.056046 -49.299622) (xy 171.123102 -49.299622)
			(xy 171.132118 -49.299261) (xy 171.149035 -49.293016) (xy 171.156122 -49.28743) (xy 171.15663 -49.286922)
			(xy 171.177603 -49.269358) (xy 171.223563 -49.239694) (xy 171.273291 -49.216903) (xy 171.325765 -49.201451)
			(xy 171.379908 -49.193657) (xy 171.43461 -49.19368) (xy 171.488747 -49.20152) (xy 171.541209 -49.217015)
			(xy 171.590917 -49.239848) (xy 171.636853 -49.26955) (xy 171.657772 -49.287176) (xy 171.658026 -49.28743)
			(xy 171.665127 -49.292995) (xy 171.682033 -49.299254) (xy 171.691046 -49.299622) (xy 171.758102 -49.299622)
			(xy 171.767118 -49.299261) (xy 171.784035 -49.293016) (xy 171.791122 -49.28743) (xy 171.79163 -49.286922)
			(xy 171.812574 -49.269352) (xy 171.858506 -49.23971) (xy 171.908199 -49.216929) (xy 171.960635 -49.201476)
			(xy 172.014741 -49.193667) (xy 172.042074 -49.193196) (xy 172.042328 -49.193196) (xy 172.068623 -49.193637)
			(xy 172.120713 -49.200886) (xy 172.171314 -49.215216) (xy 172.21947 -49.236355) (xy 172.26427 -49.263903)
			(xy 172.304864 -49.297338) (xy 172.322998 -49.316386) (xy 172.330573 -49.323823) (xy 172.349988 -49.332351)
			(xy 172.36059 -49.332896) (xy 172.434758 -49.332896) (xy 172.445393 -49.332511) (xy 172.464857 -49.323945)
			(xy 172.47235 -49.316386) (xy 172.490442 -49.297294) (xy 172.531033 -49.263842) (xy 172.575837 -49.236287)
			(xy 172.624004 -49.215154) (xy 172.674619 -49.200845) (xy 172.72672 -49.193629) (xy 172.75302 -49.193196)
			(xy 172.753274 -49.193196) (xy 172.780528 -49.19365) (xy 172.834483 -49.201404) (xy 172.886784 -49.216758)
			(xy 172.936368 -49.239399) (xy 172.982225 -49.268866) (xy 173.023421 -49.30456) (xy 173.059118 -49.345754)
			(xy 173.088589 -49.391609) (xy 173.111233 -49.441191) (xy 173.126591 -49.493492) (xy 173.134349 -49.547446)
			(xy 173.134349 -49.601953) (xy 174.212959 -49.601953) (xy 174.212959 -49.547447) (xy 174.220717 -49.493495)
			(xy 174.236073 -49.441197) (xy 174.258716 -49.391617) (xy 174.288185 -49.345764) (xy 174.32388 -49.304571)
			(xy 174.365073 -49.268878) (xy 174.410927 -49.23941) (xy 174.460508 -49.216769) (xy 174.512807 -49.201414)
			(xy 174.566759 -49.193659) (xy 174.594012 -49.193196) (xy 174.621382 -49.193656) (xy 174.675562 -49.201475)
			(xy 174.728065 -49.216966) (xy 174.777812 -49.239809) (xy 174.823778 -49.269534) (xy 174.84471 -49.287176)
			(xy 174.844964 -49.28743) (xy 174.852054 -49.293011) (xy 174.868968 -49.29926) (xy 174.877984 -49.299622)
			(xy 174.94504 -49.299622) (xy 174.954058 -49.299279) (xy 174.970975 -49.293021) (xy 174.97806 -49.28743)
			(xy 174.978568 -49.286922) (xy 174.999511 -49.269321) (xy 175.045476 -49.239659) (xy 175.095209 -49.216869)
			(xy 175.147688 -49.201421) (xy 175.201835 -49.19363) (xy 175.256541 -49.193657) (xy 175.310681 -49.201501)
			(xy 175.363144 -49.217002) (xy 175.412854 -49.23984) (xy 175.458791 -49.269547) (xy 175.47971 -49.287176)
			(xy 175.479964 -49.28743) (xy 175.487054 -49.293011) (xy 175.503968 -49.29926) (xy 175.512984 -49.299622)
			(xy 175.58004 -49.299622) (xy 175.589058 -49.299279) (xy 175.605975 -49.293021) (xy 175.61306 -49.28743)
			(xy 175.613568 -49.286922) (xy 175.634511 -49.269321) (xy 175.680476 -49.239659) (xy 175.730209 -49.216869)
			(xy 175.782688 -49.201421) (xy 175.836835 -49.19363) (xy 175.891541 -49.193657) (xy 175.945681 -49.201501)
			(xy 175.998144 -49.217002) (xy 176.047854 -49.23984) (xy 176.093791 -49.269547) (xy 176.11471 -49.287176)
			(xy 176.114964 -49.28743) (xy 176.122054 -49.293011) (xy 176.138968 -49.29926) (xy 176.147984 -49.299622)
			(xy 176.21504 -49.299622) (xy 176.224058 -49.299279) (xy 176.240975 -49.293021) (xy 176.24806 -49.28743)
			(xy 176.248568 -49.286922) (xy 176.269498 -49.269334) (xy 176.315433 -49.239695) (xy 176.36513 -49.216917)
			(xy 176.41757 -49.201468) (xy 176.471678 -49.193665) (xy 176.499012 -49.193196) (xy 176.526263 -49.193675)
			(xy 176.58021 -49.201433) (xy 176.632504 -49.216789) (xy 176.68208 -49.239431) (xy 176.727929 -49.268898)
			(xy 176.769119 -49.30459) (xy 176.804809 -49.34578) (xy 176.834275 -49.39163) (xy 176.856915 -49.441207)
			(xy 176.87227 -49.493502) (xy 176.880026 -49.547449) (xy 176.880026 -49.601951) (xy 176.880026 -49.601954)
			(xy 196.390959 -49.601954) (xy 196.390959 -49.547446) (xy 196.398717 -49.493494) (xy 196.414074 -49.441195)
			(xy 196.436718 -49.391614) (xy 196.466187 -49.34576) (xy 196.501883 -49.304568) (xy 196.543078 -49.268874)
			(xy 196.588933 -49.239407) (xy 196.638516 -49.216766) (xy 196.690816 -49.201412) (xy 196.744768 -49.193658)
			(xy 196.772022 -49.193196) (xy 196.799393 -49.19365) (xy 196.853572 -49.201471) (xy 196.906075 -49.216963)
			(xy 196.955822 -49.239807) (xy 197.001789 -49.269534) (xy 197.02272 -49.287176) (xy 197.022974 -49.28743)
			(xy 197.030061 -49.293015) (xy 197.046978 -49.299262) (xy 197.055994 -49.299622) (xy 197.12305 -49.299622)
			(xy 197.132064 -49.299236) (xy 197.148981 -49.293008) (xy 197.15607 -49.28743) (xy 197.156578 -49.286922)
			(xy 197.177513 -49.269311) (xy 197.22348 -49.239649) (xy 197.273214 -49.216861) (xy 197.325694 -49.201413)
			(xy 197.379842 -49.193623) (xy 197.434549 -49.193651) (xy 197.48869 -49.201496) (xy 197.541154 -49.216998)
			(xy 197.590864 -49.239838) (xy 197.636801 -49.269547) (xy 197.65772 -49.287176) (xy 197.657974 -49.28743)
			(xy 197.665061 -49.293015) (xy 197.681978 -49.299262) (xy 197.690994 -49.299622) (xy 197.75805 -49.299622)
			(xy 197.767064 -49.299236) (xy 197.783981 -49.293008) (xy 197.79107 -49.28743) (xy 197.791578 -49.286922)
			(xy 197.812504 -49.26933) (xy 197.858441 -49.239691) (xy 197.908138 -49.216914) (xy 197.960579 -49.201466)
			(xy 198.014688 -49.193664) (xy 198.042022 -49.193196) (xy 198.042276 -49.193196) (xy 198.06857 -49.193672)
			(xy 198.120658 -49.200914) (xy 198.171259 -49.215237) (xy 198.219415 -49.236369) (xy 198.264215 -49.263911)
			(xy 198.304811 -49.297341) (xy 198.322946 -49.316386) (xy 198.330503 -49.323844) (xy 198.349932 -49.33236)
			(xy 198.360538 -49.332896) (xy 198.434706 -49.332896) (xy 198.445338 -49.332483) (xy 198.464802 -49.323936)
			(xy 198.472298 -49.316386) (xy 198.490416 -49.29732) (xy 198.531 -49.263865) (xy 198.575799 -49.236307)
			(xy 198.623961 -49.21517) (xy 198.674572 -49.200854) (xy 198.72667 -49.193633) (xy 198.752968 -49.193196)
			(xy 198.753222 -49.193196) (xy 198.780473 -49.193675) (xy 198.834418 -49.201434) (xy 198.886711 -49.216792)
			(xy 198.936286 -49.239434) (xy 198.982134 -49.268901) (xy 199.023322 -49.304593) (xy 199.059012 -49.345783)
			(xy 199.088476 -49.391633) (xy 199.111116 -49.44121) (xy 199.12647 -49.493503) (xy 199.134226 -49.547449)
			(xy 199.134226 -49.601949) (xy 200.212982 -49.601949) (xy 200.212982 -49.547451) (xy 200.220737 -49.493507)
			(xy 200.23609 -49.441216) (xy 200.258728 -49.391642) (xy 200.28819 -49.345794) (xy 200.323877 -49.304605)
			(xy 200.365062 -49.268914) (xy 200.410907 -49.239447) (xy 200.460479 -49.216804) (xy 200.512768 -49.201446)
			(xy 200.566711 -49.193684) (xy 200.59396 -49.193196) (xy 200.621329 -49.193686) (xy 200.675507 -49.201499)
			(xy 200.72801 -49.216982) (xy 200.777757 -49.239818) (xy 200.823725 -49.269537) (xy 200.844658 -49.287176)
			(xy 200.844912 -49.28743) (xy 200.851988 -49.293031) (xy 200.868913 -49.299268) (xy 200.877932 -49.299622)
			(xy 200.944988 -49.299622) (xy 200.954004 -49.299254) (xy 200.97092 -49.293014) (xy 200.978008 -49.28743)
			(xy 200.978516 -49.286922) (xy 200.999421 -49.269274) (xy 201.045393 -49.239613) (xy 201.095132 -49.216827)
			(xy 201.147616 -49.201382) (xy 201.201769 -49.193596) (xy 201.256479 -49.193628) (xy 201.310623 -49.201478)
			(xy 201.363089 -49.216985) (xy 201.412801 -49.23983) (xy 201.458738 -49.269544) (xy 201.479658 -49.287176)
			(xy 201.479912 -49.28743) (xy 201.486988 -49.293031) (xy 201.503913 -49.299268) (xy 201.512932 -49.299622)
			(xy 201.579988 -49.299622) (xy 201.589004 -49.299254) (xy 201.60592 -49.293014) (xy 201.613008 -49.28743)
			(xy 201.613516 -49.286922) (xy 201.634421 -49.269274) (xy 201.680393 -49.239613) (xy 201.730132 -49.216827)
			(xy 201.782616 -49.201382) (xy 201.836769 -49.193596) (xy 201.891479 -49.193628) (xy 201.945623 -49.201478)
			(xy 201.998089 -49.216985) (xy 202.047801 -49.23983) (xy 202.093738 -49.269544) (xy 202.114658 -49.287176)
			(xy 202.114912 -49.28743) (xy 202.121988 -49.293031) (xy 202.138913 -49.299268) (xy 202.147932 -49.299622)
			(xy 202.214988 -49.299622) (xy 202.224004 -49.299254) (xy 202.24092 -49.293014) (xy 202.248008 -49.28743)
			(xy 202.248516 -49.286922) (xy 202.269428 -49.269312) (xy 202.315368 -49.239676) (xy 202.36507 -49.216902)
			(xy 202.417513 -49.201459) (xy 202.471625 -49.193661) (xy 202.49896 -49.193196) (xy 202.526215 -49.193649)
			(xy 202.580171 -49.201401) (xy 202.632474 -49.216754) (xy 202.68206 -49.239394) (xy 202.727918 -49.268861)
			(xy 202.769116 -49.304555) (xy 202.804815 -49.34575) (xy 202.834287 -49.391605) (xy 202.856932 -49.441188)
			(xy 202.87229 -49.49349) (xy 202.880049 -49.547445) (xy 202.880049 -49.601955) (xy 202.87229 -49.65591)
			(xy 202.856932 -49.708212) (xy 202.834287 -49.757795) (xy 202.804815 -49.80365) (xy 202.769116 -49.844845)
			(xy 202.727918 -49.880539) (xy 202.68206 -49.910006) (xy 202.632474 -49.932646) (xy 202.580171 -49.947999)
			(xy 202.545989 -49.95291) (xy 221.033084 -49.95291) (xy 221.037155 -49.897288) (xy 221.049281 -49.842851)
			(xy 221.069204 -49.79076) (xy 221.0965 -49.742125) (xy 221.130586 -49.697982) (xy 221.170735 -49.659273)
			(xy 221.216093 -49.626822) (xy 221.265693 -49.601321) (xy 221.318477 -49.583314) (xy 221.37332 -49.573184)
			(xy 221.429054 -49.571147) (xy 221.484491 -49.577247) (xy 221.538448 -49.591353) (xy 221.589777 -49.613165)
			(xy 221.637383 -49.642219) (xy 221.680251 -49.677894) (xy 221.717468 -49.719431) (xy 221.724427 -49.72995)
			(xy 238.502698 -49.72995) (xy 238.502698 -49.67545) (xy 238.510454 -49.621506) (xy 238.525808 -49.569214)
			(xy 238.548448 -49.519639) (xy 238.577913 -49.473792) (xy 238.613602 -49.432604) (xy 238.65479 -49.396914)
			(xy 238.700638 -49.367449) (xy 238.750212 -49.344809) (xy 238.802504 -49.329455) (xy 238.856448 -49.321698)
			(xy 238.883698 -49.321212) (xy 238.911068 -49.321676) (xy 238.965248 -49.329494) (xy 239.017751 -49.344983)
			(xy 239.067498 -49.367826) (xy 239.113464 -49.397551) (xy 239.134396 -49.415192) (xy 239.13465 -49.415446)
			(xy 239.141743 -49.421023) (xy 239.158655 -49.427274) (xy 239.16767 -49.427638) (xy 239.234726 -49.427638)
			(xy 239.243743 -49.427285) (xy 239.26066 -49.421034) (xy 239.267746 -49.415446) (xy 239.268254 -49.414938)
			(xy 239.289191 -49.39736) (xy 239.335124 -49.367718) (xy 239.384819 -49.344938) (xy 239.437257 -49.329487)
			(xy 239.491364 -49.321682) (xy 239.518698 -49.321212) (xy 239.545952 -49.321635) (xy 239.599906 -49.329392)
			(xy 239.652207 -49.344749) (xy 239.70179 -49.367392) (xy 239.747646 -49.396862) (xy 239.788841 -49.432557)
			(xy 239.824537 -49.473752) (xy 239.854007 -49.519608) (xy 239.876651 -49.569191) (xy 239.892008 -49.621492)
			(xy 239.899765 -49.675446) (xy 239.899765 -49.729954) (xy 239.892008 -49.783908) (xy 239.876651 -49.836209)
			(xy 239.854007 -49.885792) (xy 239.824537 -49.931648) (xy 239.806113 -49.95291) (xy 259.133084 -49.95291)
			(xy 259.137155 -49.897288) (xy 259.149281 -49.842851) (xy 259.169204 -49.79076) (xy 259.1965 -49.742125)
			(xy 259.230586 -49.697982) (xy 259.270735 -49.659273) (xy 259.316093 -49.626822) (xy 259.365693 -49.601321)
			(xy 259.418477 -49.583314) (xy 259.47332 -49.573184) (xy 259.529054 -49.571147) (xy 259.584491 -49.577247)
			(xy 259.638448 -49.591353) (xy 259.663385 -49.60195) (xy 260.490982 -49.60195) (xy 260.490982 -49.54745)
			(xy 260.498737 -49.493506) (xy 260.514091 -49.441214) (xy 260.53673 -49.391639) (xy 260.566193 -49.345791)
			(xy 260.601881 -49.304602) (xy 260.643067 -49.268911) (xy 260.688913 -49.239444) (xy 260.738486 -49.216801)
			(xy 260.790777 -49.201444) (xy 260.84472 -49.193684) (xy 260.87197 -49.193196) (xy 260.89934 -49.193681)
			(xy 260.953518 -49.201494) (xy 261.006021 -49.216979) (xy 261.055768 -49.239816) (xy 261.101736 -49.269537)
			(xy 261.122668 -49.287176) (xy 261.122922 -49.28743) (xy 261.129996 -49.293035) (xy 261.146922 -49.29927)
			(xy 261.155942 -49.299622) (xy 261.222998 -49.299622) (xy 261.232014 -49.299259) (xy 261.248931 -49.293015)
			(xy 261.256018 -49.28743) (xy 261.256526 -49.286922) (xy 261.277502 -49.269362) (xy 261.323462 -49.239698)
			(xy 261.373189 -49.216906) (xy 261.425662 -49.201455) (xy 261.479806 -49.19366) (xy 261.534507 -49.193682)
			(xy 261.588644 -49.201521) (xy 261.641105 -49.217016) (xy 261.690813 -49.239849) (xy 261.736749 -49.26955)
			(xy 261.757668 -49.287176) (xy 261.757922 -49.28743) (xy 261.764996 -49.293035) (xy 261.781922 -49.29927)
			(xy 261.790942 -49.299622) (xy 261.857998 -49.299622) (xy 261.867014 -49.299259) (xy 261.883931 -49.293015)
			(xy 261.891018 -49.28743) (xy 261.891526 -49.286922) (xy 261.912472 -49.269354) (xy 261.958403 -49.239711)
			(xy 262.008096 -49.21693) (xy 262.060532 -49.201476) (xy 262.114637 -49.193667) (xy 262.14197 -49.193196)
			(xy 262.142224 -49.193196) (xy 262.168519 -49.19364) (xy 262.220609 -49.200889) (xy 262.27121 -49.215217)
			(xy 262.319366 -49.236356) (xy 262.364165 -49.263903) (xy 262.40476 -49.297338) (xy 262.422894 -49.316386)
			(xy 262.430471 -49.323821) (xy 262.449885 -49.33235) (xy 262.460486 -49.332896) (xy 262.534654 -49.332896)
			(xy 262.545289 -49.332509) (xy 262.564753 -49.323944) (xy 262.572246 -49.316386) (xy 262.59034 -49.297296)
			(xy 262.63093 -49.263843) (xy 262.675734 -49.236289) (xy 262.7239 -49.215156) (xy 262.774515 -49.200845)
			(xy 262.826616 -49.19363) (xy 262.852916 -49.193196) (xy 262.85317 -49.193196) (xy 262.880425 -49.193649)
			(xy 262.934379 -49.201403) (xy 262.986681 -49.216756) (xy 263.036266 -49.239398) (xy 263.082123 -49.268865)
			(xy 263.12332 -49.304559) (xy 263.159017 -49.345753) (xy 263.188488 -49.391608) (xy 263.211133 -49.441191)
			(xy 263.226491 -49.493491) (xy 263.234249 -49.547446) (xy 263.234249 -49.601953) (xy 264.312859 -49.601953)
			(xy 264.312859 -49.547447) (xy 264.320616 -49.493496) (xy 264.335973 -49.441198) (xy 264.358616 -49.391618)
			(xy 264.388084 -49.345765) (xy 264.423778 -49.304572) (xy 264.464971 -49.268879) (xy 264.510825 -49.239412)
			(xy 264.560406 -49.21677) (xy 264.612704 -49.201415) (xy 264.666655 -49.193659) (xy 264.693908 -49.193196)
			(xy 264.721278 -49.193658) (xy 264.775458 -49.201477) (xy 264.827961 -49.216967) (xy 264.877707 -49.23981)
			(xy 264.923674 -49.269535) (xy 264.944606 -49.287176) (xy 264.94486 -49.28743) (xy 264.951951 -49.293009)
			(xy 264.968865 -49.299259) (xy 264.97788 -49.299622) (xy 265.044936 -49.299622) (xy 265.053954 -49.299278)
			(xy 265.070871 -49.293021) (xy 265.077956 -49.28743) (xy 265.078464 -49.286922) (xy 265.09941 -49.269325)
			(xy 265.145375 -49.239662) (xy 265.195107 -49.216873) (xy 265.247585 -49.201424) (xy 265.301732 -49.193633)
			(xy 265.356437 -49.19366) (xy 265.410577 -49.201503) (xy 265.46304 -49.217003) (xy 265.51275 -49.239841)
			(xy 265.558687 -49.269548) (xy 265.579606 -49.287176) (xy 265.57986 -49.28743) (xy 265.586951 -49.293009)
			(xy 265.603865 -49.299259) (xy 265.61288 -49.299622) (xy 265.679936 -49.299622) (xy 265.688954 -49.299278)
			(xy 265.705871 -49.293021) (xy 265.712956 -49.28743) (xy 265.713464 -49.286922) (xy 265.73441 -49.269325)
			(xy 265.780375 -49.239662) (xy 265.830107 -49.216873) (xy 265.882585 -49.201424) (xy 265.936732 -49.193633)
			(xy 265.991437 -49.19366) (xy 266.045577 -49.201503) (xy 266.09804 -49.217003) (xy 266.14775 -49.239841)
			(xy 266.193687 -49.269548) (xy 266.214606 -49.287176) (xy 266.21486 -49.28743) (xy 266.221951 -49.293009)
			(xy 266.238865 -49.299259) (xy 266.24788 -49.299622) (xy 266.314936 -49.299622) (xy 266.323954 -49.299278)
			(xy 266.340871 -49.293021) (xy 266.347956 -49.28743) (xy 266.348464 -49.286922) (xy 266.369395 -49.269336)
			(xy 266.41533 -49.239696) (xy 266.465027 -49.216918) (xy 266.517466 -49.201469) (xy 266.571574 -49.193665)
			(xy 266.598908 -49.193196) (xy 266.626159 -49.193674) (xy 266.680107 -49.201432) (xy 266.732401 -49.216788)
			(xy 266.781978 -49.23943) (xy 266.827828 -49.268896) (xy 266.869017 -49.304588) (xy 266.904708 -49.345779)
			(xy 266.934174 -49.391629) (xy 266.956815 -49.441207) (xy 266.97217 -49.493501) (xy 266.979926 -49.547449)
			(xy 266.979926 -49.601951) (xy 266.97217 -49.655899) (xy 266.956815 -49.708193) (xy 266.934174 -49.757771)
			(xy 266.904708 -49.803621) (xy 266.869017 -49.844812) (xy 266.827828 -49.880504) (xy 266.781978 -49.90997)
			(xy 266.732401 -49.932612) (xy 266.680107 -49.947968) (xy 266.645741 -49.95291) (xy 285.133032 -49.95291)
			(xy 285.137103 -49.897288) (xy 285.149229 -49.842851) (xy 285.169152 -49.79076) (xy 285.196448 -49.742125)
			(xy 285.230534 -49.697982) (xy 285.270683 -49.659273) (xy 285.316041 -49.626822) (xy 285.365641 -49.601321)
			(xy 285.418425 -49.583314) (xy 285.473268 -49.573184) (xy 285.529002 -49.571147) (xy 285.584439 -49.577247)
			(xy 285.638396 -49.591353) (xy 285.66334 -49.601953) (xy 286.490859 -49.601953) (xy 286.490859 -49.547447)
			(xy 286.498617 -49.493495) (xy 286.513974 -49.441196) (xy 286.536617 -49.391615) (xy 286.566086 -49.345762)
			(xy 286.601782 -49.304569) (xy 286.642976 -49.268876) (xy 286.688831 -49.239408) (xy 286.738413 -49.216767)
			(xy 286.790712 -49.201413) (xy 286.844665 -49.193658) (xy 286.871918 -49.193196) (xy 286.899289 -49.193652)
			(xy 286.953468 -49.201473) (xy 287.005971 -49.216964) (xy 287.055718 -49.239808) (xy 287.101684 -49.269534)
			(xy 287.122616 -49.287176) (xy 287.12287 -49.28743) (xy 287.129959 -49.293013) (xy 287.146874 -49.299261)
			(xy 287.15589 -49.299622) (xy 287.222946 -49.299622) (xy 287.23196 -49.299235) (xy 287.248877 -49.293008)
			(xy 287.255966 -49.28743) (xy 287.256474 -49.286922) (xy 287.277412 -49.269315) (xy 287.323378 -49.239653)
			(xy 287.373112 -49.216864) (xy 287.425591 -49.201416) (xy 287.47974 -49.193626) (xy 287.534445 -49.193653)
			(xy 287.588586 -49.201498) (xy 287.64105 -49.216999) (xy 287.69076 -49.239839) (xy 287.736697 -49.269547)
			(xy 287.757616 -49.287176) (xy 287.75787 -49.28743) (xy 287.764959 -49.293013) (xy 287.781874 -49.299261)
			(xy 287.79089 -49.299622) (xy 287.857946 -49.299622) (xy 287.86696 -49.299235) (xy 287.883877 -49.293008)
			(xy 287.890966 -49.28743) (xy 287.891474 -49.286922) (xy 287.912402 -49.269332) (xy 287.958338 -49.239692)
			(xy 288.008035 -49.216915) (xy 288.060475 -49.201467) (xy 288.114584 -49.193664) (xy 288.141918 -49.193196)
			(xy 288.142172 -49.193196) (xy 288.168466 -49.193675) (xy 288.220554 -49.200916) (xy 288.271155 -49.215238)
			(xy 288.319311 -49.23637) (xy 288.364111 -49.263911) (xy 288.404707 -49.297341) (xy 288.422842 -49.316386)
			(xy 288.430401 -49.323843) (xy 288.449828 -49.332359) (xy 288.460434 -49.332896) (xy 288.534602 -49.332896)
			(xy 288.545233 -49.33248) (xy 288.564698 -49.323936) (xy 288.572194 -49.316386) (xy 288.590314 -49.297322)
			(xy 288.630898 -49.263866) (xy 288.675696 -49.236308) (xy 288.723858 -49.215171) (xy 288.774468 -49.200855)
			(xy 288.826566 -49.193633) (xy 288.852864 -49.193196) (xy 288.853118 -49.193196) (xy 288.880369 -49.193675)
			(xy 288.934315 -49.201434) (xy 288.986608 -49.216791) (xy 289.036184 -49.239433) (xy 289.082032 -49.2689)
			(xy 289.123221 -49.304592) (xy 289.158911 -49.345782) (xy 289.188376 -49.391632) (xy 289.211016 -49.441209)
			(xy 289.22637 -49.493503) (xy 289.234126 -49.547449) (xy 289.234126 -49.601949) (xy 290.312882 -49.601949)
			(xy 290.312882 -49.547451) (xy 290.320637 -49.493508) (xy 290.33599 -49.441217) (xy 290.358627 -49.391643)
			(xy 290.388089 -49.345795) (xy 290.423776 -49.304607) (xy 290.46496 -49.268916) (xy 290.510805 -49.239448)
			(xy 290.560376 -49.216805) (xy 290.612665 -49.201446) (xy 290.666607 -49.193685) (xy 290.693856 -49.193196)
			(xy 290.721225 -49.193689) (xy 290.775403 -49.2015) (xy 290.827906 -49.216983) (xy 290.877653 -49.239819)
			(xy 290.923621 -49.269538) (xy 290.944554 -49.287176) (xy 290.944808 -49.28743) (xy 290.951886 -49.293029)
			(xy 290.968809 -49.299267) (xy 290.977828 -49.299622) (xy 291.044884 -49.299622) (xy 291.053899 -49.299253)
			(xy 291.070816 -49.293013) (xy 291.077904 -49.28743) (xy 291.078412 -49.286922) (xy 291.09932 -49.269278)
			(xy 291.145291 -49.239617) (xy 291.19503 -49.216831) (xy 291.247514 -49.201385) (xy 291.301666 -49.193599)
			(xy 291.356376 -49.193631) (xy 291.410519 -49.20148) (xy 291.462985 -49.216986) (xy 291.512697 -49.239831)
			(xy 291.558634 -49.269544) (xy 291.579554 -49.287176) (xy 291.579808 -49.28743) (xy 291.586886 -49.293029)
			(xy 291.603809 -49.299267) (xy 291.612828 -49.299622) (xy 291.679884 -49.299622) (xy 291.688899 -49.299253)
			(xy 291.705816 -49.293013) (xy 291.712904 -49.28743) (xy 291.713412 -49.286922) (xy 291.73432 -49.269278)
			(xy 291.780291 -49.239617) (xy 291.83003 -49.216831) (xy 291.882514 -49.201385) (xy 291.936666 -49.193599)
			(xy 291.991376 -49.193631) (xy 292.045519 -49.20148) (xy 292.097985 -49.216986) (xy 292.147697 -49.239831)
			(xy 292.193634 -49.269544) (xy 292.214554 -49.287176) (xy 292.214808 -49.28743) (xy 292.221886 -49.293029)
			(xy 292.238809 -49.299267) (xy 292.247828 -49.299622) (xy 292.314884 -49.299622) (xy 292.323899 -49.299253)
			(xy 292.340816 -49.293013) (xy 292.347904 -49.28743) (xy 292.348412 -49.286922) (xy 292.369325 -49.269314)
			(xy 292.415265 -49.239677) (xy 292.464966 -49.216903) (xy 292.51741 -49.201459) (xy 292.571521 -49.193661)
			(xy 292.598856 -49.193196) (xy 292.626111 -49.193648) (xy 292.680067 -49.2014) (xy 292.732371 -49.216753)
			(xy 292.781957 -49.239393) (xy 292.827816 -49.26886) (xy 292.869015 -49.304554) (xy 292.904714 -49.345748)
			(xy 292.934186 -49.391604) (xy 292.956832 -49.441188) (xy 292.97219 -49.49349) (xy 292.979949 -49.547445)
			(xy 292.979949 -49.601949) (xy 312.490882 -49.601949) (xy 312.490882 -49.547451) (xy 312.498637 -49.493506)
			(xy 312.51399 -49.441215) (xy 312.536629 -49.39164) (xy 312.566092 -49.345792) (xy 312.601779 -49.304603)
			(xy 312.642965 -49.268912) (xy 312.688811 -49.239445) (xy 312.738383 -49.216802) (xy 312.790673 -49.201444)
			(xy 312.844617 -49.193684) (xy 312.871866 -49.193196) (xy 312.899235 -49.193683) (xy 312.953414 -49.201496)
			(xy 313.005916 -49.21698) (xy 313.055664 -49.239817) (xy 313.101632 -49.269537) (xy 313.122564 -49.287176)
			(xy 313.122818 -49.28743) (xy 313.129893 -49.293034) (xy 313.146819 -49.299269) (xy 313.155838 -49.299622)
			(xy 313.222894 -49.299622) (xy 313.23191 -49.299257) (xy 313.248827 -49.293014) (xy 313.255914 -49.28743)
			(xy 313.256422 -49.286922) (xy 313.277322 -49.269268) (xy 313.323295 -49.239608) (xy 313.373035 -49.216822)
			(xy 313.42552 -49.201377) (xy 313.479673 -49.193592) (xy 313.534384 -49.193625) (xy 313.588528 -49.201475)
			(xy 313.640995 -49.216983) (xy 313.690707 -49.239828) (xy 313.736644 -49.269544) (xy 313.757564 -49.287176)
			(xy 313.757818 -49.28743) (xy 313.764893 -49.293034) (xy 313.781819 -49.299269) (xy 313.790838 -49.299622)
			(xy 313.857894 -49.299622) (xy 313.86691 -49.299257) (xy 313.883827 -49.293014) (xy 313.890914 -49.28743)
			(xy 313.891422 -49.286922) (xy 313.912369 -49.269356) (xy 313.9583 -49.239713) (xy 314.007992 -49.216931)
			(xy 314.060428 -49.201477) (xy 314.114533 -49.193668) (xy 314.141866 -49.193196) (xy 314.14212 -49.193196)
			(xy 314.168415 -49.193643) (xy 314.220504 -49.200891) (xy 314.271106 -49.215219) (xy 314.319262 -49.236357)
			(xy 314.364061 -49.263904) (xy 314.404656 -49.297339) (xy 314.42279 -49.316386) (xy 314.430368 -49.323819)
			(xy 314.449781 -49.33235) (xy 314.460382 -49.332896) (xy 314.53455 -49.332896) (xy 314.545184 -49.332507)
			(xy 314.564649 -49.323944) (xy 314.572142 -49.316386) (xy 314.590238 -49.297298) (xy 314.630828 -49.263845)
			(xy 314.675631 -49.23629) (xy 314.723797 -49.215157) (xy 314.774411 -49.200846) (xy 314.826513 -49.19363)
			(xy 314.852812 -49.193196) (xy 314.853066 -49.193196) (xy 314.880321 -49.193649) (xy 314.934276 -49.201402)
			(xy 314.986578 -49.216755) (xy 315.036163 -49.239396) (xy 315.082021 -49.268864) (xy 315.123218 -49.304558)
			(xy 315.158916 -49.345752) (xy 315.188387 -49.391607) (xy 315.211033 -49.44119) (xy 315.226391 -49.493491)
			(xy 315.234149 -49.547445) (xy 315.234149 -49.601953) (xy 316.312759 -49.601953) (xy 316.312759 -49.547447)
			(xy 316.320516 -49.493497) (xy 316.335872 -49.441199) (xy 316.358515 -49.391619) (xy 316.387983 -49.345766)
			(xy 316.423677 -49.304574) (xy 316.464869 -49.268881) (xy 316.510723 -49.239413) (xy 316.560303 -49.216771)
			(xy 316.6126 -49.201415) (xy 316.666551 -49.193659) (xy 316.693804 -49.193196) (xy 316.721174 -49.193661)
			(xy 316.775353 -49.201479) (xy 316.827856 -49.216968) (xy 316.877603 -49.23981) (xy 316.92357 -49.269535)
			(xy 316.944502 -49.287176) (xy 316.944756 -49.28743) (xy 316.951849 -49.293008) (xy 316.968761 -49.299259)
			(xy 316.977776 -49.299622) (xy 317.044832 -49.299622) (xy 317.05385 -49.299276) (xy 317.070767 -49.29302)
			(xy 317.077852 -49.28743) (xy 317.07836 -49.286922) (xy 317.099309 -49.269329) (xy 317.145273 -49.239666)
			(xy 317.195005 -49.216876) (xy 317.247483 -49.201427) (xy 317.30163 -49.193636) (xy 317.356334 -49.193662)
			(xy 317.410474 -49.201505) (xy 317.462937 -49.217004) (xy 317.512646 -49.239842) (xy 317.558583 -49.269548)
			(xy 317.579502 -49.287176) (xy 317.579756 -49.28743) (xy 317.586849 -49.293008) (xy 317.603761 -49.299259)
			(xy 317.612776 -49.299622) (xy 317.679832 -49.299622) (xy 317.68885 -49.299276) (xy 317.705767 -49.29302)
			(xy 317.712852 -49.28743) (xy 317.71336 -49.286922) (xy 317.734309 -49.269329) (xy 317.780273 -49.239666)
			(xy 317.830005 -49.216876) (xy 317.882483 -49.201427) (xy 317.93663 -49.193636) (xy 317.991334 -49.193662)
			(xy 318.045474 -49.201505) (xy 318.097937 -49.217004) (xy 318.147646 -49.239842) (xy 318.193583 -49.269548)
			(xy 318.214502 -49.287176) (xy 318.214756 -49.28743) (xy 318.221849 -49.293008) (xy 318.238761 -49.299259)
			(xy 318.247776 -49.299622) (xy 318.314832 -49.299622) (xy 318.32385 -49.299276) (xy 318.340767 -49.29302)
			(xy 318.347852 -49.28743) (xy 318.34836 -49.286922) (xy 318.369293 -49.269338) (xy 318.415227 -49.239698)
			(xy 318.464923 -49.216919) (xy 318.517363 -49.20147) (xy 318.57147 -49.193665) (xy 318.598804 -49.193196)
			(xy 318.626055 -49.193674) (xy 318.680003 -49.201431) (xy 318.732298 -49.216787) (xy 318.781875 -49.239428)
			(xy 318.827726 -49.268895) (xy 318.868916 -49.304587) (xy 318.904607 -49.345778) (xy 318.934074 -49.391628)
			(xy 318.956715 -49.441206) (xy 318.97207 -49.493501) (xy 318.979826 -49.547449) (xy 318.979826 -49.601951)
			(xy 318.97207 -49.655899) (xy 318.956715 -49.708194) (xy 318.934074 -49.757772) (xy 318.904607 -49.803622)
			(xy 318.868916 -49.844813) (xy 318.827726 -49.880505) (xy 318.781875 -49.909972) (xy 318.732298 -49.932613)
			(xy 318.680003 -49.947969) (xy 318.64564 -49.95291) (xy 337.132928 -49.95291) (xy 337.136999 -49.897288)
			(xy 337.149125 -49.842851) (xy 337.169048 -49.79076) (xy 337.196344 -49.742125) (xy 337.23043 -49.697982)
			(xy 337.270579 -49.659273) (xy 337.315937 -49.626822) (xy 337.365537 -49.601321) (xy 337.418321 -49.583314)
			(xy 337.473164 -49.573184) (xy 337.528898 -49.571147) (xy 337.584335 -49.577247) (xy 337.638292 -49.591353)
			(xy 337.663236 -49.601953) (xy 350.591059 -49.601953) (xy 350.591059 -49.547447) (xy 350.598817 -49.493494)
			(xy 350.614174 -49.441196) (xy 350.636817 -49.391615) (xy 350.666287 -49.345761) (xy 350.701982 -49.304568)
			(xy 350.743177 -49.268875) (xy 350.789032 -49.239408) (xy 350.838614 -49.216767) (xy 350.890914 -49.201413)
			(xy 350.944867 -49.193658) (xy 350.97212 -49.193196) (xy 350.999491 -49.193651) (xy 351.05367 -49.201472)
			(xy 351.106173 -49.216964) (xy 351.15592 -49.239808) (xy 351.201886 -49.269534) (xy 351.222818 -49.287176)
			(xy 351.223072 -49.28743) (xy 351.23016 -49.293014) (xy 351.247076 -49.299261) (xy 351.256092 -49.299622)
			(xy 351.323148 -49.299622) (xy 351.332162 -49.299235) (xy 351.349079 -49.293008) (xy 351.356168 -49.28743)
			(xy 351.356676 -49.286922) (xy 351.377612 -49.269313) (xy 351.423579 -49.239651) (xy 351.473313 -49.216862)
			(xy 351.525792 -49.201414) (xy 351.579941 -49.193624) (xy 351.634647 -49.193652) (xy 351.688788 -49.201497)
			(xy 351.741252 -49.216999) (xy 351.790962 -49.239838) (xy 351.836899 -49.269547) (xy 351.857818 -49.287176)
			(xy 351.858072 -49.28743) (xy 351.86516 -49.293014) (xy 351.882076 -49.299261) (xy 351.891092 -49.299622)
			(xy 351.958148 -49.299622) (xy 351.967162 -49.299235) (xy 351.984079 -49.293008) (xy 351.991168 -49.28743)
			(xy 351.991676 -49.286922) (xy 352.012603 -49.269331) (xy 352.058539 -49.239691) (xy 352.108237 -49.216915)
			(xy 352.160677 -49.201467) (xy 352.214786 -49.193664) (xy 352.24212 -49.193196) (xy 352.242374 -49.193196)
			(xy 352.268668 -49.193673) (xy 352.320756 -49.200915) (xy 352.371357 -49.215237) (xy 352.419513 -49.236369)
			(xy 352.464313 -49.263911) (xy 352.504909 -49.297341) (xy 352.523044 -49.316386) (xy 352.530602 -49.323843)
			(xy 352.55003 -49.33236) (xy 352.560636 -49.332896) (xy 352.634804 -49.332896) (xy 352.645435 -49.332482)
			(xy 352.6649 -49.323936) (xy 352.672396 -49.316386) (xy 352.690515 -49.297321) (xy 352.731099 -49.263866)
			(xy 352.775898 -49.236308) (xy 352.82406 -49.21517) (xy 352.87467 -49.200855) (xy 352.926768 -49.193633)
			(xy 352.953066 -49.193196) (xy 352.95332 -49.193196) (xy 352.980571 -49.193675) (xy 353.034517 -49.201434)
			(xy 353.08681 -49.216791) (xy 353.136385 -49.239434) (xy 353.182233 -49.268901) (xy 353.223422 -49.304593)
			(xy 353.259111 -49.345783) (xy 353.288576 -49.391633) (xy 353.311216 -49.441209) (xy 353.32657 -49.493503)
			(xy 353.334326 -49.547449) (xy 353.334326 -49.601949) (xy 354.413082 -49.601949) (xy 354.413082 -49.547451)
			(xy 354.420837 -49.493507) (xy 354.43619 -49.441217) (xy 354.458828 -49.391643) (xy 354.48829 -49.345795)
			(xy 354.523976 -49.304606) (xy 354.565161 -49.268915) (xy 354.611006 -49.239448) (xy 354.660577 -49.216805)
			(xy 354.712866 -49.201446) (xy 354.766809 -49.193685) (xy 354.794058 -49.193196) (xy 354.821427 -49.193688)
			(xy 354.875605 -49.201499) (xy 354.928108 -49.216983) (xy 354.977855 -49.239819) (xy 355.023823 -49.269537)
			(xy 355.044756 -49.287176) (xy 355.04501 -49.28743) (xy 355.052087 -49.29303) (xy 355.069011 -49.299268)
			(xy 355.07803 -49.299622) (xy 355.145086 -49.299622) (xy 355.154102 -49.299253) (xy 355.171018 -49.293013)
			(xy 355.178106 -49.28743) (xy 355.178614 -49.286922) (xy 355.19952 -49.269276) (xy 355.245492 -49.239615)
			(xy 355.295231 -49.216829) (xy 355.347715 -49.201384) (xy 355.401868 -49.193597) (xy 355.456577 -49.193629)
			(xy 355.510721 -49.201479) (xy 355.563187 -49.216985) (xy 355.612899 -49.23983) (xy 355.658836 -49.269544)
			(xy 355.679756 -49.287176) (xy 355.68001 -49.28743) (xy 355.687087 -49.29303) (xy 355.704011 -49.299268)
			(xy 355.71303 -49.299622) (xy 355.780086 -49.299622) (xy 355.789102 -49.299253) (xy 355.806018 -49.293013)
			(xy 355.813106 -49.28743) (xy 355.813614 -49.286922) (xy 355.83452 -49.269276) (xy 355.880492 -49.239615)
			(xy 355.930231 -49.216829) (xy 355.982715 -49.201384) (xy 356.036868 -49.193597) (xy 356.091577 -49.193629)
			(xy 356.145721 -49.201479) (xy 356.198187 -49.216985) (xy 356.247899 -49.23983) (xy 356.293836 -49.269544)
			(xy 356.314756 -49.287176) (xy 356.31501 -49.28743) (xy 356.322087 -49.29303) (xy 356.339011 -49.299268)
			(xy 356.34803 -49.299622) (xy 356.415086 -49.299622) (xy 356.424102 -49.299253) (xy 356.441018 -49.293013)
			(xy 356.448106 -49.28743) (xy 356.448614 -49.286922) (xy 356.469526 -49.269313) (xy 356.515467 -49.239676)
			(xy 356.565168 -49.216903) (xy 356.617611 -49.201459) (xy 356.671723 -49.193661) (xy 356.699058 -49.193196)
			(xy 356.726313 -49.193648) (xy 356.780269 -49.201401) (xy 356.832573 -49.216753) (xy 356.882158 -49.239394)
			(xy 356.928017 -49.268861) (xy 356.969215 -49.304555) (xy 357.004914 -49.345749) (xy 357.034386 -49.391605)
			(xy 357.057032 -49.441188) (xy 357.07239 -49.49349) (xy 357.080149 -49.547445) (xy 357.080149 -49.601955)
			(xy 357.07239 -49.65591) (xy 357.057032 -49.708212) (xy 357.034386 -49.757795) (xy 357.004914 -49.803651)
			(xy 356.969215 -49.844845) (xy 356.928017 -49.880539) (xy 356.882158 -49.910006) (xy 356.832573 -49.932647)
			(xy 356.780269 -49.947999) (xy 356.746092 -49.95291) (xy 375.233182 -49.95291) (xy 375.237253 -49.897288)
			(xy 375.249379 -49.842851) (xy 375.269302 -49.79076) (xy 375.296598 -49.742125) (xy 375.330684 -49.697982)
			(xy 375.370833 -49.659273) (xy 375.416191 -49.626822) (xy 375.465791 -49.601321) (xy 375.518575 -49.583314)
			(xy 375.573418 -49.573184) (xy 375.629152 -49.571147) (xy 375.684589 -49.577247) (xy 375.738546 -49.591353)
			(xy 375.763483 -49.60195) (xy 376.591082 -49.60195) (xy 376.591082 -49.54745) (xy 376.598837 -49.493506)
			(xy 376.614191 -49.441214) (xy 376.636829 -49.39164) (xy 376.666292 -49.345792) (xy 376.70198 -49.304603)
			(xy 376.743166 -49.268911) (xy 376.789012 -49.239445) (xy 376.838584 -49.216802) (xy 376.890875 -49.201444)
			(xy 376.944819 -49.193684) (xy 376.972068 -49.193196) (xy 376.999438 -49.193682) (xy 377.053616 -49.201495)
			(xy 377.106119 -49.21698) (xy 377.155866 -49.239817) (xy 377.201834 -49.269537) (xy 377.222766 -49.287176)
			(xy 377.22302 -49.28743) (xy 377.230094 -49.293034) (xy 377.247021 -49.299269) (xy 377.25604 -49.299622)
			(xy 377.323096 -49.299622) (xy 377.332112 -49.299258) (xy 377.349029 -49.293015) (xy 377.356116 -49.28743)
			(xy 377.356624 -49.286922) (xy 377.377522 -49.269266) (xy 377.423496 -49.239606) (xy 377.473235 -49.21682)
			(xy 377.525721 -49.201376) (xy 377.579875 -49.19359) (xy 377.634585 -49.193623) (xy 377.68873 -49.201474)
			(xy 377.741197 -49.216982) (xy 377.790909 -49.239828) (xy 377.836846 -49.269543) (xy 377.857766 -49.287176)
			(xy 377.85802 -49.28743) (xy 377.865094 -49.293034) (xy 377.882021 -49.299269) (xy 377.89104 -49.299622)
			(xy 377.958096 -49.299622) (xy 377.967112 -49.299258) (xy 377.984029 -49.293015) (xy 377.991116 -49.28743)
			(xy 377.991624 -49.286922) (xy 378.01257 -49.269355) (xy 378.058501 -49.239712) (xy 378.108194 -49.216931)
			(xy 378.16063 -49.201477) (xy 378.214735 -49.193668) (xy 378.242068 -49.193196) (xy 378.242322 -49.193196)
			(xy 378.268617 -49.193641) (xy 378.320707 -49.20089) (xy 378.371308 -49.215218) (xy 378.419464 -49.236356)
			(xy 378.464263 -49.263904) (xy 378.504858 -49.297339) (xy 378.522992 -49.316386) (xy 378.530569 -49.32382)
			(xy 378.549983 -49.33235) (xy 378.560584 -49.332896) (xy 378.634752 -49.332896) (xy 378.645386 -49.332508)
			(xy 378.664851 -49.323944) (xy 378.672344 -49.316386) (xy 378.690439 -49.297297) (xy 378.731029 -49.263844)
			(xy 378.775832 -49.23629) (xy 378.823999 -49.215156) (xy 378.874613 -49.200846) (xy 378.926715 -49.19363)
			(xy 378.953014 -49.193196) (xy 378.953268 -49.193196) (xy 378.980523 -49.193649) (xy 379.034478 -49.201403)
			(xy 379.08678 -49.216756) (xy 379.136364 -49.239397) (xy 379.182222 -49.268864) (xy 379.223419 -49.304558)
			(xy 379.259117 -49.345752) (xy 379.288588 -49.391607) (xy 379.311233 -49.44119) (xy 379.326591 -49.493491)
			(xy 379.334349 -49.547445) (xy 379.334349 -49.601953) (xy 380.412959 -49.601953) (xy 380.412959 -49.547447)
			(xy 380.420716 -49.493496) (xy 380.436073 -49.441199) (xy 380.458715 -49.391618) (xy 380.488184 -49.345766)
			(xy 380.523877 -49.304573) (xy 380.56507 -49.26888) (xy 380.610924 -49.239412) (xy 380.660504 -49.21677)
			(xy 380.712802 -49.201415) (xy 380.766753 -49.193659) (xy 380.794006 -49.193196) (xy 380.821376 -49.19366)
			(xy 380.875555 -49.201478) (xy 380.928059 -49.216968) (xy 380.977805 -49.23981) (xy 381.023772 -49.269535)
			(xy 381.044704 -49.287176) (xy 381.044958 -49.28743) (xy 381.05205 -49.293008) (xy 381.068963 -49.299259)
			(xy 381.077978 -49.299622) (xy 381.145034 -49.299622) (xy 381.154052 -49.299277) (xy 381.170969 -49.293021)
			(xy 381.178054 -49.28743) (xy 381.178562 -49.286922) (xy 381.199509 -49.269327) (xy 381.245474 -49.239664)
			(xy 381.295206 -49.216875) (xy 381.347684 -49.201426) (xy 381.401831 -49.193634) (xy 381.456536 -49.193661)
			(xy 381.510675 -49.201504) (xy 381.563139 -49.217004) (xy 381.612848 -49.239841) (xy 381.658785 -49.269548)
			(xy 381.679704 -49.287176) (xy 381.679958 -49.28743) (xy 381.68705 -49.293008) (xy 381.703963 -49.299259)
			(xy 381.712978 -49.299622) (xy 381.780034 -49.299622) (xy 381.789052 -49.299277) (xy 381.805969 -49.293021)
			(xy 381.813054 -49.28743) (xy 381.813562 -49.286922) (xy 381.834509 -49.269327) (xy 381.880474 -49.239664)
			(xy 381.930206 -49.216875) (xy 381.982684 -49.201426) (xy 382.036831 -49.193634) (xy 382.091536 -49.193661)
			(xy 382.145675 -49.201504) (xy 382.198139 -49.217004) (xy 382.247848 -49.239841) (xy 382.293785 -49.269548)
			(xy 382.314704 -49.287176) (xy 382.314958 -49.28743) (xy 382.32205 -49.293008) (xy 382.338963 -49.299259)
			(xy 382.347978 -49.299622) (xy 382.415034 -49.299622) (xy 382.424052 -49.299277) (xy 382.440969 -49.293021)
			(xy 382.448054 -49.28743) (xy 382.448562 -49.286922) (xy 382.469494 -49.269337) (xy 382.515429 -49.239697)
			(xy 382.565125 -49.216919) (xy 382.617564 -49.201469) (xy 382.671672 -49.193665) (xy 382.699006 -49.193196)
			(xy 382.726257 -49.193674) (xy 382.780205 -49.201431) (xy 382.832499 -49.216787) (xy 382.882076 -49.239429)
			(xy 382.927927 -49.268896) (xy 382.969117 -49.304588) (xy 383.004808 -49.345778) (xy 383.034274 -49.391629)
			(xy 383.056915 -49.441206) (xy 383.07227 -49.493501) (xy 383.080026 -49.547449) (xy 383.080026 -49.601951)
			(xy 383.07227 -49.655899) (xy 383.056915 -49.708194) (xy 383.034274 -49.757771) (xy 383.004808 -49.803622)
			(xy 382.969117 -49.844812) (xy 382.927927 -49.880504) (xy 382.882076 -49.909971) (xy 382.832499 -49.932613)
			(xy 382.780205 -49.947969) (xy 382.745842 -49.95291) (xy 401.23313 -49.95291) (xy 401.237201 -49.897288)
			(xy 401.249327 -49.842851) (xy 401.26925 -49.79076) (xy 401.296546 -49.742125) (xy 401.330632 -49.697982)
			(xy 401.370781 -49.659273) (xy 401.416139 -49.626822) (xy 401.465739 -49.601321) (xy 401.518523 -49.583314)
			(xy 401.573366 -49.573184) (xy 401.6291 -49.571147) (xy 401.684537 -49.577247) (xy 401.738494 -49.591353)
			(xy 401.763438 -49.601953) (xy 402.590959 -49.601953) (xy 402.590959 -49.547447) (xy 402.598717 -49.493495)
			(xy 402.614073 -49.441196) (xy 402.636717 -49.391616) (xy 402.666186 -49.345762) (xy 402.701881 -49.30457)
			(xy 402.743075 -49.268876) (xy 402.78893 -49.239409) (xy 402.838511 -49.216768) (xy 402.890811 -49.201413)
			(xy 402.944763 -49.193658) (xy 402.972016 -49.193196) (xy 402.999387 -49.193654) (xy 403.053566 -49.201474)
			(xy 403.106069 -49.216965) (xy 403.155816 -49.239808) (xy 403.201782 -49.269534) (xy 403.222714 -49.287176)
			(xy 403.222968 -49.28743) (xy 403.230057 -49.293013) (xy 403.246972 -49.299261) (xy 403.255988 -49.299622)
			(xy 403.323044 -49.299622) (xy 403.332058 -49.299234) (xy 403.348975 -49.293007) (xy 403.356064 -49.28743)
			(xy 403.356572 -49.286922) (xy 403.377511 -49.269317) (xy 403.423478 -49.239655) (xy 403.473211 -49.216866)
			(xy 403.52569 -49.201418) (xy 403.579838 -49.193627) (xy 403.634544 -49.193655) (xy 403.688684 -49.201499)
			(xy 403.741148 -49.217) (xy 403.790858 -49.239839) (xy 403.836795 -49.269547) (xy 403.857714 -49.287176)
			(xy 403.857968 -49.28743) (xy 403.865057 -49.293013) (xy 403.881972 -49.299261) (xy 403.890988 -49.299622)
			(xy 403.958044 -49.299622) (xy 403.967058 -49.299234) (xy 403.983975 -49.293007) (xy 403.991064 -49.28743)
			(xy 403.991572 -49.286922) (xy 404.0125 -49.269333) (xy 404.058436 -49.239693) (xy 404.108133 -49.216916)
			(xy 404.160573 -49.201467) (xy 404.214682 -49.193664) (xy 404.242016 -49.193196) (xy 404.24227 -49.193196)
			(xy 404.268564 -49.193676) (xy 404.320652 -49.200917) (xy 404.371253 -49.215239) (xy 404.419409 -49.236371)
			(xy 404.464209 -49.263912) (xy 404.504805 -49.297341) (xy 404.52294 -49.316386) (xy 404.5305 -49.323842)
			(xy 404.549927 -49.332359) (xy 404.560532 -49.332896) (xy 404.6347 -49.332896) (xy 404.645331 -49.332479)
			(xy 404.664796 -49.323935) (xy 404.672292 -49.316386) (xy 404.690413 -49.297322) (xy 404.730997 -49.263867)
			(xy 404.775795 -49.236309) (xy 404.823956 -49.215171) (xy 404.874566 -49.200856) (xy 404.926664 -49.193633)
			(xy 404.952962 -49.193196) (xy 404.953216 -49.193196) (xy 404.980467 -49.193675) (xy 405.034413 -49.201433)
			(xy 405.086707 -49.21679) (xy 405.136282 -49.239432) (xy 405.182131 -49.268899) (xy 405.22332 -49.304591)
			(xy 405.25901 -49.345781) (xy 405.288475 -49.391632) (xy 405.311116 -49.441208) (xy 405.32647 -49.493502)
			(xy 405.334226 -49.547449) (xy 405.334226 -49.601949) (xy 406.412982 -49.601949) (xy 406.412982 -49.547451)
			(xy 406.420737 -49.493508) (xy 406.43609 -49.441217) (xy 406.458727 -49.391644) (xy 406.488189 -49.345796)
			(xy 406.523875 -49.304608) (xy 406.565059 -49.268916) (xy 406.610903 -49.239449) (xy 406.660474 -49.216806)
			(xy 406.712763 -49.201447) (xy 406.766705 -49.193685) (xy 406.793954 -49.193196) (xy 406.821323 -49.19369)
			(xy 406.875501 -49.201501) (xy 406.928004 -49.216984) (xy 406.977751 -49.239819) (xy 407.023719 -49.269538)
			(xy 407.044652 -49.287176) (xy 407.044906 -49.28743) (xy 407.051984 -49.293029) (xy 407.068908 -49.299267)
			(xy 407.077926 -49.299622) (xy 407.144982 -49.299622) (xy 407.153997 -49.299252) (xy 407.170914 -49.293013)
			(xy 407.178002 -49.28743) (xy 407.17851 -49.286922) (xy 407.199419 -49.26928) (xy 407.245391 -49.239619)
			(xy 407.295129 -49.216832) (xy 407.347613 -49.201387) (xy 407.401765 -49.1936) (xy 407.456474 -49.193632)
			(xy 407.510618 -49.201481) (xy 407.563084 -49.216987) (xy 407.612795 -49.239831) (xy 407.658732 -49.269544)
			(xy 407.679652 -49.287176) (xy 407.679906 -49.28743) (xy 407.686984 -49.293029) (xy 407.703908 -49.299267)
			(xy 407.712926 -49.299622) (xy 407.779982 -49.299622) (xy 407.788997 -49.299252) (xy 407.805914 -49.293013)
			(xy 407.813002 -49.28743) (xy 407.81351 -49.286922) (xy 407.834419 -49.26928) (xy 407.880391 -49.239619)
			(xy 407.930129 -49.216832) (xy 407.982613 -49.201387) (xy 408.036765 -49.1936) (xy 408.091474 -49.193632)
			(xy 408.145618 -49.201481) (xy 408.198084 -49.216987) (xy 408.247795 -49.239831) (xy 408.293732 -49.269544)
			(xy 408.314652 -49.287176) (xy 408.314906 -49.28743) (xy 408.321984 -49.293029) (xy 408.338908 -49.299267)
			(xy 408.347926 -49.299622) (xy 408.414982 -49.299622) (xy 408.423997 -49.299252) (xy 408.440914 -49.293013)
			(xy 408.448002 -49.28743) (xy 408.44851 -49.286922) (xy 408.469424 -49.269315) (xy 408.515364 -49.239678)
			(xy 408.565065 -49.216904) (xy 408.617508 -49.20146) (xy 408.671619 -49.193662) (xy 408.698954 -49.193196)
			(xy 408.726209 -49.193648) (xy 408.780166 -49.2014) (xy 408.83247 -49.216752) (xy 408.882056 -49.239392)
			(xy 408.927915 -49.268859) (xy 408.969114 -49.304553) (xy 409.004813 -49.345748) (xy 409.034286 -49.391603)
			(xy 409.056932 -49.441187) (xy 409.07229 -49.493489) (xy 409.080049 -49.547445) (xy 409.080049 -49.601949)
			(xy 428.590982 -49.601949) (xy 428.590982 -49.547451) (xy 428.598737 -49.493507) (xy 428.61409 -49.441215)
			(xy 428.636729 -49.391641) (xy 428.666191 -49.345793) (xy 428.701878 -49.304604) (xy 428.743064 -49.268913)
			(xy 428.788909 -49.239446) (xy 428.838482 -49.216803) (xy 428.890771 -49.201445) (xy 428.944715 -49.193684)
			(xy 428.971964 -49.193196) (xy 428.999333 -49.193684) (xy 429.053512 -49.201497) (xy 429.106014 -49.216981)
			(xy 429.155762 -49.239818) (xy 429.201729 -49.269537) (xy 429.222662 -49.287176) (xy 429.222916 -49.28743)
			(xy 429.229991 -49.293033) (xy 429.246917 -49.299269) (xy 429.255936 -49.299622) (xy 429.322992 -49.299622)
			(xy 429.332008 -49.299256) (xy 429.348925 -49.293014) (xy 429.356012 -49.28743) (xy 429.35652 -49.286922)
			(xy 429.377421 -49.26927) (xy 429.423394 -49.23961) (xy 429.473134 -49.216824) (xy 429.525619 -49.201379)
			(xy 429.579772 -49.193593) (xy 429.634482 -49.193626) (xy 429.688626 -49.201476) (xy 429.741093 -49.216983)
			(xy 429.790805 -49.239829) (xy 429.836742 -49.269544) (xy 429.857662 -49.287176) (xy 429.857916 -49.28743)
			(xy 429.864991 -49.293033) (xy 429.881917 -49.299269) (xy 429.890936 -49.299622) (xy 429.957992 -49.299622)
			(xy 429.967008 -49.299256) (xy 429.983925 -49.293014) (xy 429.991012 -49.28743) (xy 429.99152 -49.286922)
			(xy 430.01243 -49.26931) (xy 430.058371 -49.239674) (xy 430.108073 -49.216901) (xy 430.160517 -49.201458)
			(xy 430.214629 -49.193661) (xy 430.241964 -49.193196) (xy 430.242218 -49.193196) (xy 430.268513 -49.193644)
			(xy 430.320602 -49.200892) (xy 430.371204 -49.21522) (xy 430.41936 -49.236357) (xy 430.464159 -49.263904)
			(xy 430.504754 -49.297339) (xy 430.522888 -49.316386) (xy 430.530467 -49.323819) (xy 430.549879 -49.332349)
			(xy 430.56048 -49.332896) (xy 430.634648 -49.332896) (xy 430.645282 -49.332506) (xy 430.664747 -49.323943)
			(xy 430.67224 -49.316386) (xy 430.690337 -49.297299) (xy 430.730926 -49.263846) (xy 430.775729 -49.236291)
			(xy 430.823895 -49.215157) (xy 430.87451 -49.200846) (xy 430.926611 -49.19363) (xy 430.95291 -49.193196)
			(xy 430.953164 -49.193196) (xy 430.980419 -49.193649) (xy 431.034374 -49.201402) (xy 431.086677 -49.216755)
			(xy 431.136262 -49.239396) (xy 431.18212 -49.268863) (xy 431.223318 -49.304557) (xy 431.259016 -49.345751)
			(xy 431.288487 -49.391606) (xy 431.311133 -49.441189) (xy 431.326491 -49.493491) (xy 431.334249 -49.547445)
			(xy 431.334249 -49.601953) (xy 432.412859 -49.601953) (xy 432.412859 -49.547447) (xy 432.420616 -49.493497)
			(xy 432.435972 -49.441199) (xy 432.458615 -49.39162) (xy 432.488083 -49.345767) (xy 432.523776 -49.304575)
			(xy 432.564968 -49.268881) (xy 432.610821 -49.239414) (xy 432.660401 -49.216772) (xy 432.712699 -49.201416)
			(xy 432.766649 -49.193659) (xy 432.793902 -49.193196) (xy 432.821272 -49.193662) (xy 432.875451 -49.20148)
			(xy 432.927954 -49.216969) (xy 432.977701 -49.239811) (xy 433.023668 -49.269535) (xy 433.0446 -49.287176)
			(xy 433.044854 -49.28743) (xy 433.051947 -49.293007) (xy 433.068859 -49.299258) (xy 433.077874 -49.299622)
			(xy 433.14493 -49.299622) (xy 433.153948 -49.299275) (xy 433.170864 -49.29302) (xy 433.17795 -49.28743)
			(xy 433.178458 -49.286922) (xy 433.199409 -49.26933) (xy 433.245373 -49.239668) (xy 433.295104 -49.216878)
			(xy 433.347582 -49.201429) (xy 433.401728 -49.193637) (xy 433.456433 -49.193663) (xy 433.510572 -49.201506)
			(xy 433.563035 -49.217005) (xy 433.612745 -49.239842) (xy 433.658681 -49.269548) (xy 433.6796 -49.287176)
			(xy 433.679854 -49.28743) (xy 433.686947 -49.293007) (xy 433.703859 -49.299258) (xy 433.712874 -49.299622)
			(xy 433.77993 -49.299622) (xy 433.788948 -49.299275) (xy 433.805864 -49.29302) (xy 433.81295 -49.28743)
			(xy 433.813458 -49.286922) (xy 433.834409 -49.26933) (xy 433.880373 -49.239668) (xy 433.930104 -49.216878)
			(xy 433.982582 -49.201429) (xy 434.036728 -49.193637) (xy 434.091433 -49.193663) (xy 434.145572 -49.201506)
			(xy 434.198035 -49.217005) (xy 434.247745 -49.239842) (xy 434.293681 -49.269548) (xy 434.3146 -49.287176)
			(xy 434.314854 -49.28743) (xy 434.321947 -49.293007) (xy 434.338859 -49.299258) (xy 434.347874 -49.299622)
			(xy 434.41493 -49.299622) (xy 434.423948 -49.299275) (xy 434.440864 -49.29302) (xy 434.44795 -49.28743)
			(xy 434.448458 -49.286922) (xy 434.469392 -49.269339) (xy 434.515326 -49.239699) (xy 434.565022 -49.21692)
			(xy 434.617461 -49.20147) (xy 434.671568 -49.193665) (xy 434.698902 -49.193196) (xy 434.726153 -49.193674)
			(xy 434.780102 -49.201431) (xy 434.832397 -49.216786) (xy 434.881974 -49.239428) (xy 434.927825 -49.268894)
			(xy 434.969015 -49.304586) (xy 435.004707 -49.345777) (xy 435.034173 -49.391628) (xy 435.056814 -49.441205)
			(xy 435.07217 -49.4935) (xy 435.079926 -49.547449) (xy 435.079926 -49.601951) (xy 435.07217 -49.6559)
			(xy 435.056814 -49.708195) (xy 435.034173 -49.757772) (xy 435.004707 -49.803623) (xy 434.969015 -49.844814)
			(xy 434.927825 -49.880506) (xy 434.881974 -49.909972) (xy 434.832397 -49.932614) (xy 434.780102 -49.947969)
			(xy 434.745738 -49.95291) (xy 453.233026 -49.95291) (xy 453.237097 -49.897288) (xy 453.249223 -49.842851)
			(xy 453.269146 -49.79076) (xy 453.296442 -49.742125) (xy 453.330528 -49.697982) (xy 453.370677 -49.659273)
			(xy 453.416035 -49.626822) (xy 453.465635 -49.601321) (xy 453.518419 -49.583314) (xy 453.573262 -49.573184)
			(xy 453.628996 -49.571147) (xy 453.684433 -49.577247) (xy 453.73839 -49.591353) (xy 453.789719 -49.613165)
			(xy 453.837325 -49.642219) (xy 453.880193 -49.677894) (xy 453.91741 -49.719431) (xy 453.948183 -49.765944)
			(xy 453.971855 -49.816441) (xy 453.987923 -49.869848) (xy 453.996043 -49.925024) (xy 453.996552 -49.95291)
			(xy 453.996043 -49.980796) (xy 453.987923 -50.035972) (xy 453.971855 -50.089379) (xy 453.948183 -50.139876)
			(xy 453.91741 -50.186389) (xy 453.880193 -50.227926) (xy 453.837325 -50.263601) (xy 453.789719 -50.292655)
			(xy 453.73839 -50.314467) (xy 453.684433 -50.328573) (xy 453.628996 -50.334673) (xy 453.573262 -50.332636)
			(xy 453.518419 -50.322506) (xy 453.465635 -50.304499) (xy 453.416035 -50.278998) (xy 453.370677 -50.246547)
			(xy 453.330528 -50.207838) (xy 453.296442 -50.163695) (xy 453.269146 -50.11506) (xy 453.249223 -50.062969)
			(xy 453.237097 -50.008532) (xy 453.233026 -49.95291) (xy 434.745738 -49.95291) (xy 434.726153 -49.955726)
			(xy 434.698902 -49.956212) (xy 434.671532 -49.955742) (xy 434.617353 -49.947925) (xy 434.56485 -49.932436)
			(xy 434.515103 -49.909596) (xy 434.469136 -49.879872) (xy 434.448204 -49.862232) (xy 434.44795 -49.861978)
			(xy 434.440855 -49.856404) (xy 434.423945 -49.85015) (xy 434.41493 -49.849786) (xy 434.347874 -49.849786)
			(xy 434.338856 -49.850134) (xy 434.32194 -49.856388) (xy 434.314854 -49.861978) (xy 434.314346 -49.862486)
			(xy 434.293392 -49.880073) (xy 434.247428 -49.909735) (xy 434.197698 -49.932525) (xy 434.145221 -49.947974)
			(xy 434.091074 -49.955766) (xy 434.036371 -49.955741) (xy 433.982232 -49.947898) (xy 433.929769 -49.9324)
			(xy 433.88006 -49.909564) (xy 433.834124 -49.879859) (xy 433.813204 -49.862232) (xy 433.81295 -49.861978)
			(xy 433.805855 -49.856404) (xy 433.788945 -49.85015) (xy 433.77993 -49.849786) (xy 433.712874 -49.849786)
			(xy 433.703856 -49.850134) (xy 433.68694 -49.856388) (xy 433.679854 -49.861978) (xy 433.679346 -49.862486)
			(xy 433.658392 -49.880073) (xy 433.612428 -49.909735) (xy 433.562698 -49.932525) (xy 433.510221 -49.947974)
			(xy 433.456074 -49.955766) (xy 433.401371 -49.955741) (xy 433.347232 -49.947898) (xy 433.294769 -49.9324)
			(xy 433.24506 -49.909564) (xy 433.199124 -49.879859) (xy 433.178204 -49.862232) (xy 433.17795 -49.861978)
			(xy 433.170855 -49.856404) (xy 433.153945 -49.85015) (xy 433.14493 -49.849786) (xy 433.077874 -49.849786)
			(xy 433.068856 -49.850134) (xy 433.05194 -49.856388) (xy 433.044854 -49.861978) (xy 433.044346 -49.862486)
			(xy 433.023412 -49.880068) (xy 432.977477 -49.909709) (xy 432.927782 -49.932487) (xy 432.875343 -49.947937)
			(xy 432.821236 -49.955742) (xy 432.793902 -49.956212) (xy 432.766649 -49.955741) (xy 432.712699 -49.947984)
			(xy 432.660401 -49.932628) (xy 432.610821 -49.909986) (xy 432.564968 -49.880519) (xy 432.523776 -49.844825)
			(xy 432.488083 -49.803633) (xy 432.458615 -49.75778) (xy 432.435972 -49.708201) (xy 432.420616 -49.655903)
			(xy 432.412859 -49.601953) (xy 431.334249 -49.601953) (xy 431.334249 -49.601955) (xy 431.326491 -49.655909)
			(xy 431.311133 -49.708211) (xy 431.288487 -49.757794) (xy 431.259016 -49.803649) (xy 431.223318 -49.844843)
			(xy 431.18212 -49.880537) (xy 431.136262 -49.910004) (xy 431.086677 -49.932645) (xy 431.034374 -49.947998)
			(xy 430.980419 -49.955751) (xy 430.953164 -49.956212) (xy 430.95291 -49.956212) (xy 430.926616 -49.955743)
			(xy 430.874527 -49.948499) (xy 430.823927 -49.934175) (xy 430.77577 -49.913041) (xy 430.730971 -49.885498)
			(xy 430.690375 -49.852067) (xy 430.67224 -49.833022) (xy 430.66465 -49.825603) (xy 430.645246 -49.817064)
			(xy 430.634648 -49.816512) (xy 430.56048 -49.816512) (xy 430.549847 -49.816915) (xy 430.530383 -49.825468)
			(xy 430.522888 -49.833022) (xy 430.504779 -49.852097) (xy 430.464192 -49.885551) (xy 430.419391 -49.913107)
			(xy 430.371228 -49.934243) (xy 430.320616 -49.948556) (xy 430.268517 -49.955776) (xy 430.242218 -49.956212)
			(xy 430.241964 -49.956212) (xy 430.214593 -49.955764) (xy 430.160413 -49.947941) (xy 430.10791 -49.932448)
			(xy 430.058164 -49.909602) (xy 430.012197 -49.879875) (xy 429.991266 -49.862232) (xy 429.991012 -49.861978)
			(xy 429.983928 -49.856388) (xy 429.967009 -49.850144) (xy 429.957992 -49.849786) (xy 429.890936 -49.849786)
			(xy 429.881921 -49.850163) (xy 429.865004 -49.856397) (xy 429.857916 -49.861978) (xy 429.857408 -49.862486)
			(xy 429.836484 -49.88011) (xy 429.790515 -49.909771) (xy 429.740779 -49.932558) (xy 429.688298 -49.948005)
			(xy 429.634148 -49.955793) (xy 429.57944 -49.955763) (xy 429.525298 -49.947916) (xy 429.472834 -49.932413)
			(xy 429.423123 -49.909572) (xy 429.377186 -49.879862) (xy 429.356266 -49.862232) (xy 429.356012 -49.861978)
			(xy 429.348928 -49.856388) (xy 429.332009 -49.850144) (xy 429.322992 -49.849786) (xy 429.255936 -49.849786)
			(xy 429.246921 -49.850163) (xy 429.230004 -49.856397) (xy 429.222916 -49.861978) (xy 429.222408 -49.862486)
			(xy 429.201488 -49.880086) (xy 429.15555 -49.909724) (xy 429.105851 -49.932499) (xy 429.053409 -49.947945)
			(xy 428.999299 -49.955745) (xy 428.971964 -49.956212) (xy 428.944715 -49.955716) (xy 428.890771 -49.947955)
			(xy 428.838482 -49.932597) (xy 428.788909 -49.909954) (xy 428.743064 -49.880487) (xy 428.701878 -49.844796)
			(xy 428.666191 -49.803607) (xy 428.636729 -49.757759) (xy 428.61409 -49.708185) (xy 428.598737 -49.655893)
			(xy 428.590982 -49.601949) (xy 409.080049 -49.601949) (xy 409.080049 -49.601955) (xy 409.07229 -49.655911)
			(xy 409.056932 -49.708213) (xy 409.034286 -49.757797) (xy 409.004813 -49.803652) (xy 408.969114 -49.844847)
			(xy 408.927915 -49.880541) (xy 408.882056 -49.910008) (xy 408.83247 -49.932648) (xy 408.780166 -49.948)
			(xy 408.726209 -49.955752) (xy 408.698954 -49.956212) (xy 408.671585 -49.955711) (xy 408.617408 -49.947901)
			(xy 408.564905 -49.93242) (xy 408.515158 -49.909586) (xy 408.469189 -49.87987) (xy 408.448256 -49.862232)
			(xy 408.448002 -49.861978) (xy 408.440921 -49.856384) (xy 408.424 -49.850142) (xy 408.414982 -49.849786)
			(xy 408.347926 -49.849786) (xy 408.338911 -49.850158) (xy 408.321994 -49.856396) (xy 408.314906 -49.861978)
			(xy 408.314398 -49.862486) (xy 408.293482 -49.88012) (xy 408.247512 -49.90978) (xy 408.197775 -49.932567)
			(xy 408.145292 -49.948013) (xy 408.091141 -49.9558) (xy 408.036432 -49.955769) (xy 407.98229 -49.947921)
			(xy 407.929824 -49.932417) (xy 407.880113 -49.909574) (xy 407.834176 -49.879863) (xy 407.813256 -49.862232)
			(xy 407.813002 -49.861978) (xy 407.805921 -49.856384) (xy 407.789 -49.850142) (xy 407.779982 -49.849786)
			(xy 407.712926 -49.849786) (xy 407.703911 -49.850158) (xy 407.686994 -49.856396) (xy 407.679906 -49.861978)
			(xy 407.679398 -49.862486) (xy 407.658482 -49.88012) (xy 407.612512 -49.90978) (xy 407.562775 -49.932567)
			(xy 407.510292 -49.948013) (xy 407.456141 -49.9558) (xy 407.401432 -49.955769) (xy 407.34729 -49.947921)
			(xy 407.294824 -49.932417) (xy 407.245113 -49.909574) (xy 407.199176 -49.879863) (xy 407.178256 -49.862232)
			(xy 407.178002 -49.861978) (xy 407.170921 -49.856384) (xy 407.154 -49.850142) (xy 407.144982 -49.849786)
			(xy 407.077926 -49.849786) (xy 407.068911 -49.850158) (xy 407.051994 -49.856396) (xy 407.044906 -49.861978)
			(xy 407.044398 -49.862486) (xy 407.023482 -49.880091) (xy 406.977543 -49.909728) (xy 406.927842 -49.932502)
			(xy 406.8754 -49.947947) (xy 406.821289 -49.955746) (xy 406.793954 -49.956212) (xy 406.766705 -49.955715)
			(xy 406.712763 -49.947953) (xy 406.660474 -49.932594) (xy 406.610903 -49.909951) (xy 406.565059 -49.880484)
			(xy 406.523875 -49.844792) (xy 406.488189 -49.803604) (xy 406.458727 -49.757756) (xy 406.43609 -49.708183)
			(xy 406.420737 -49.655892) (xy 406.412982 -49.601949) (xy 405.334226 -49.601949) (xy 405.334226 -49.601951)
			(xy 405.32647 -49.655898) (xy 405.311116 -49.708192) (xy 405.288475 -49.757768) (xy 405.25901 -49.803619)
			(xy 405.22332 -49.844809) (xy 405.182131 -49.880501) (xy 405.136282 -49.909968) (xy 405.086707 -49.93261)
			(xy 405.034413 -49.947967) (xy 404.980467 -49.955725) (xy 404.953216 -49.956212) (xy 404.952962 -49.956212)
			(xy 404.926666 -49.955775) (xy 404.874577 -49.948525) (xy 404.823975 -49.934194) (xy 404.775819 -49.913055)
			(xy 404.73102 -49.885506) (xy 404.690426 -49.85207) (xy 404.672292 -49.833022) (xy 404.664719 -49.825582)
			(xy 404.645302 -49.817055) (xy 404.6347 -49.816512) (xy 404.560532 -49.816512) (xy 404.549896 -49.816889)
			(xy 404.530432 -49.825461) (xy 404.52294 -49.833022) (xy 404.504805 -49.852072) (xy 404.464224 -49.885528)
			(xy 404.419429 -49.913087) (xy 404.37127 -49.934228) (xy 404.320663 -49.948547) (xy 404.268567 -49.955773)
			(xy 404.24227 -49.956212) (xy 404.242016 -49.956212) (xy 404.214646 -49.955734) (xy 404.160468 -49.947918)
			(xy 404.107965 -49.932432) (xy 404.058218 -49.909593) (xy 404.01225 -49.879872) (xy 403.991318 -49.862232)
			(xy 403.991064 -49.861978) (xy 403.983965 -49.85641) (xy 403.967058 -49.850153) (xy 403.958044 -49.849786)
			(xy 403.890988 -49.849786) (xy 403.881971 -49.85014) (xy 403.865054 -49.85639) (xy 403.857968 -49.861978)
			(xy 403.85746 -49.862486) (xy 403.836495 -49.88006) (xy 403.790533 -49.909722) (xy 403.740804 -49.932513)
			(xy 403.688329 -49.947963) (xy 403.634184 -49.955756) (xy 403.579482 -49.955732) (xy 403.525344 -49.947891)
			(xy 403.472882 -49.932395) (xy 403.423173 -49.909561) (xy 403.377238 -49.879858) (xy 403.356318 -49.862232)
			(xy 403.356064 -49.861978) (xy 403.348965 -49.85641) (xy 403.332058 -49.850153) (xy 403.323044 -49.849786)
			(xy 403.255988 -49.849786) (xy 403.246971 -49.85014) (xy 403.230054 -49.85639) (xy 403.222968 -49.861978)
			(xy 403.22246 -49.862486) (xy 403.201521 -49.880062) (xy 403.155588 -49.909703) (xy 403.105893 -49.932483)
			(xy 403.053456 -49.947935) (xy 402.999349 -49.955742) (xy 402.972016 -49.956212) (xy 402.944763 -49.955742)
			(xy 402.890811 -49.947987) (xy 402.838511 -49.932632) (xy 402.78893 -49.909991) (xy 402.743075 -49.880524)
			(xy 402.701881 -49.84483) (xy 402.666186 -49.803638) (xy 402.636717 -49.757784) (xy 402.614073 -49.708204)
			(xy 402.598717 -49.655905) (xy 402.590959 -49.601953) (xy 401.763438 -49.601953) (xy 401.789823 -49.613165)
			(xy 401.837429 -49.642219) (xy 401.880297 -49.677894) (xy 401.917514 -49.719431) (xy 401.948287 -49.765944)
			(xy 401.971959 -49.816441) (xy 401.988027 -49.869848) (xy 401.996147 -49.925024) (xy 401.996656 -49.95291)
			(xy 401.996147 -49.980796) (xy 401.988027 -50.035972) (xy 401.971959 -50.089379) (xy 401.948287 -50.139876)
			(xy 401.917514 -50.186389) (xy 401.880297 -50.227926) (xy 401.837429 -50.263601) (xy 401.789823 -50.292655)
			(xy 401.738494 -50.314467) (xy 401.684537 -50.328573) (xy 401.6291 -50.334673) (xy 401.573366 -50.332636)
			(xy 401.518523 -50.322506) (xy 401.465739 -50.304499) (xy 401.416139 -50.278998) (xy 401.370781 -50.246547)
			(xy 401.330632 -50.207838) (xy 401.296546 -50.163695) (xy 401.26925 -50.11506) (xy 401.249327 -50.062969)
			(xy 401.237201 -50.008532) (xy 401.23313 -49.95291) (xy 382.745842 -49.95291) (xy 382.726257 -49.955726)
			(xy 382.699006 -49.956212) (xy 382.671636 -49.955739) (xy 382.617457 -49.947923) (xy 382.564954 -49.932435)
			(xy 382.515207 -49.909595) (xy 382.46924 -49.879872) (xy 382.448308 -49.862232) (xy 382.448054 -49.861978)
			(xy 382.440958 -49.856405) (xy 382.424048 -49.850151) (xy 382.415034 -49.849786) (xy 382.347978 -49.849786)
			(xy 382.33896 -49.850136) (xy 382.322044 -49.856389) (xy 382.314958 -49.861978) (xy 382.31445 -49.862486)
			(xy 382.293493 -49.880069) (xy 382.24753 -49.909732) (xy 382.197799 -49.932521) (xy 382.145323 -49.947971)
			(xy 382.091177 -49.955763) (xy 382.036474 -49.955738) (xy 381.982335 -49.947896) (xy 381.929873 -49.932399)
			(xy 381.880164 -49.909563) (xy 381.834228 -49.879859) (xy 381.813308 -49.862232) (xy 381.813054 -49.861978)
			(xy 381.805958 -49.856405) (xy 381.789048 -49.850151) (xy 381.780034 -49.849786) (xy 381.712978 -49.849786)
			(xy 381.70396 -49.850136) (xy 381.687044 -49.856389) (xy 381.679958 -49.861978) (xy 381.67945 -49.862486)
			(xy 381.658493 -49.880069) (xy 381.61253 -49.909732) (xy 381.562799 -49.932521) (xy 381.510323 -49.947971)
			(xy 381.456177 -49.955763) (xy 381.401474 -49.955738) (xy 381.347335 -49.947896) (xy 381.294873 -49.932399)
			(xy 381.245164 -49.909563) (xy 381.199228 -49.879859) (xy 381.178308 -49.862232) (xy 381.178054 -49.861978)
			(xy 381.170958 -49.856405) (xy 381.154048 -49.850151) (xy 381.145034 -49.849786) (xy 381.077978 -49.849786)
			(xy 381.06896 -49.850136) (xy 381.052044 -49.856389) (xy 381.044958 -49.861978) (xy 381.04445 -49.862486)
			(xy 381.023514 -49.880066) (xy 380.97758 -49.909707) (xy 380.927885 -49.932486) (xy 380.875447 -49.947937)
			(xy 380.82134 -49.955742) (xy 380.794006 -49.956212) (xy 380.766753 -49.955741) (xy 380.712802 -49.947985)
			(xy 380.660504 -49.93263) (xy 380.610924 -49.909988) (xy 380.56507 -49.88052) (xy 380.523877 -49.844827)
			(xy 380.488184 -49.803634) (xy 380.458715 -49.757782) (xy 380.436073 -49.708201) (xy 380.420716 -49.655904)
			(xy 380.412959 -49.601953) (xy 379.334349 -49.601953) (xy 379.334349 -49.601955) (xy 379.326591 -49.655909)
			(xy 379.311233 -49.70821) (xy 379.288588 -49.757793) (xy 379.259117 -49.803648) (xy 379.223419 -49.844842)
			(xy 379.182222 -49.880536) (xy 379.136364 -49.910003) (xy 379.08678 -49.932644) (xy 379.034478 -49.947997)
			(xy 378.980523 -49.955751) (xy 378.953268 -49.956212) (xy 378.953014 -49.956212) (xy 378.92672 -49.95574)
			(xy 378.874632 -49.948497) (xy 378.824031 -49.934173) (xy 378.775875 -49.91304) (xy 378.731075 -49.885498)
			(xy 378.690479 -49.852067) (xy 378.672344 -49.833022) (xy 378.664789 -49.82556) (xy 378.645359 -49.817046)
			(xy 378.634752 -49.816512) (xy 378.560584 -49.816512) (xy 378.549951 -49.816918) (xy 378.530487 -49.825469)
			(xy 378.522992 -49.833022) (xy 378.504881 -49.852095) (xy 378.464294 -49.885549) (xy 378.419494 -49.913106)
			(xy 378.371331 -49.934242) (xy 378.320719 -49.948556) (xy 378.268621 -49.955776) (xy 378.242322 -49.956212)
			(xy 378.242068 -49.956212) (xy 378.214697 -49.955762) (xy 378.160518 -49.94794) (xy 378.108014 -49.932447)
			(xy 378.058268 -49.909602) (xy 378.012301 -49.879874) (xy 377.99137 -49.862232) (xy 377.991116 -49.861978)
			(xy 377.984031 -49.85639) (xy 377.967113 -49.850145) (xy 377.958096 -49.849786) (xy 377.89104 -49.849786)
			(xy 377.882025 -49.850165) (xy 377.865108 -49.856398) (xy 377.85802 -49.861978) (xy 377.857512 -49.862486)
			(xy 377.836585 -49.880107) (xy 377.790617 -49.909767) (xy 377.740881 -49.932555) (xy 377.6884 -49.948001)
			(xy 377.63425 -49.95579) (xy 377.579543 -49.955761) (xy 377.525402 -49.947915) (xy 377.472937 -49.932412)
			(xy 377.423226 -49.909571) (xy 377.37729 -49.879862) (xy 377.35637 -49.862232) (xy 377.356116 -49.861978)
			(xy 377.349031 -49.85639) (xy 377.332113 -49.850145) (xy 377.323096 -49.849786) (xy 377.25604 -49.849786)
			(xy 377.247025 -49.850165) (xy 377.230108 -49.856398) (xy 377.22302 -49.861978) (xy 377.222512 -49.862486)
			(xy 377.201591 -49.880084) (xy 377.155653 -49.909722) (xy 377.105954 -49.932498) (xy 377.053512 -49.947944)
			(xy 376.999403 -49.955745) (xy 376.972068 -49.956212) (xy 376.944819 -49.955716) (xy 376.890875 -49.947956)
			(xy 376.838584 -49.932598) (xy 376.789012 -49.909955) (xy 376.743166 -49.880489) (xy 376.70198 -49.844797)
			(xy 376.666292 -49.803608) (xy 376.636829 -49.75776) (xy 376.614191 -49.708186) (xy 376.598837 -49.655894)
			(xy 376.591082 -49.60195) (xy 375.763483 -49.60195) (xy 375.789875 -49.613165) (xy 375.837481 -49.642219)
			(xy 375.880349 -49.677894) (xy 375.917566 -49.719431) (xy 375.948339 -49.765944) (xy 375.972011 -49.816441)
			(xy 375.988079 -49.869848) (xy 375.996199 -49.925024) (xy 375.996708 -49.95291) (xy 375.996199 -49.980796)
			(xy 375.988079 -50.035972) (xy 375.972011 -50.089379) (xy 375.948339 -50.139876) (xy 375.917566 -50.186389)
			(xy 375.880349 -50.227926) (xy 375.837481 -50.263601) (xy 375.789875 -50.292655) (xy 375.738546 -50.314467)
			(xy 375.684589 -50.328573) (xy 375.629152 -50.334673) (xy 375.573418 -50.332636) (xy 375.518575 -50.322506)
			(xy 375.465791 -50.304499) (xy 375.416191 -50.278998) (xy 375.370833 -50.246547) (xy 375.330684 -50.207838)
			(xy 375.296598 -50.163695) (xy 375.269302 -50.11506) (xy 375.249379 -50.062969) (xy 375.237253 -50.008532)
			(xy 375.233182 -49.95291) (xy 356.746092 -49.95291) (xy 356.726313 -49.955752) (xy 356.699058 -49.956212)
			(xy 356.671689 -49.955709) (xy 356.617512 -49.9479) (xy 356.565009 -49.932419) (xy 356.515262 -49.909586)
			(xy 356.469293 -49.879869) (xy 356.44836 -49.862232) (xy 356.448106 -49.861978) (xy 356.441024 -49.856385)
			(xy 356.424104 -49.850143) (xy 356.415086 -49.849786) (xy 356.34803 -49.849786) (xy 356.339015 -49.85016)
			(xy 356.322098 -49.856396) (xy 356.31501 -49.861978) (xy 356.314502 -49.862486) (xy 356.293583 -49.880116)
			(xy 356.247613 -49.909777) (xy 356.197877 -49.932564) (xy 356.145394 -49.94801) (xy 356.091243 -49.955797)
			(xy 356.036535 -49.955767) (xy 355.982393 -49.947919) (xy 355.929928 -49.932416) (xy 355.880217 -49.909574)
			(xy 355.83428 -49.879862) (xy 355.81336 -49.862232) (xy 355.813106 -49.861978) (xy 355.806024 -49.856385)
			(xy 355.789104 -49.850143) (xy 355.780086 -49.849786) (xy 355.71303 -49.849786) (xy 355.704015 -49.85016)
			(xy 355.687098 -49.856396) (xy 355.68001 -49.861978) (xy 355.679502 -49.862486) (xy 355.658583 -49.880116)
			(xy 355.612613 -49.909777) (xy 355.562877 -49.932564) (xy 355.510394 -49.94801) (xy 355.456243 -49.955797)
			(xy 355.401535 -49.955767) (xy 355.347393 -49.947919) (xy 355.294928 -49.932416) (xy 355.245217 -49.909574)
			(xy 355.19928 -49.879862) (xy 355.17836 -49.862232) (xy 355.178106 -49.861978) (xy 355.171024 -49.856385)
			(xy 355.154104 -49.850143) (xy 355.145086 -49.849786) (xy 355.07803 -49.849786) (xy 355.069015 -49.85016)
			(xy 355.052098 -49.856396) (xy 355.04501 -49.861978) (xy 355.044502 -49.862486) (xy 355.023585 -49.880089)
			(xy 354.977646 -49.909726) (xy 354.927946 -49.932501) (xy 354.875503 -49.947946) (xy 354.821393 -49.955746)
			(xy 354.794058 -49.956212) (xy 354.766809 -49.955715) (xy 354.712866 -49.947954) (xy 354.660577 -49.932595)
			(xy 354.611006 -49.909952) (xy 354.565161 -49.880485) (xy 354.523976 -49.844794) (xy 354.48829 -49.803605)
			(xy 354.458828 -49.757757) (xy 354.43619 -49.708183) (xy 354.420837 -49.655893) (xy 354.413082 -49.601949)
			(xy 353.334326 -49.601949) (xy 353.334326 -49.601951) (xy 353.32657 -49.655897) (xy 353.311216 -49.708191)
			(xy 353.288576 -49.757767) (xy 353.259111 -49.803617) (xy 353.223422 -49.844807) (xy 353.182233 -49.880499)
			(xy 353.136385 -49.909966) (xy 353.08681 -49.932609) (xy 353.034517 -49.947966) (xy 352.980571 -49.955725)
			(xy 352.95332 -49.956212) (xy 352.953066 -49.956212) (xy 352.926771 -49.955772) (xy 352.874681 -49.948522)
			(xy 352.82408 -49.934192) (xy 352.775924 -49.913053) (xy 352.731125 -49.885505) (xy 352.69053 -49.85207)
			(xy 352.672396 -49.833022) (xy 352.664822 -49.825583) (xy 352.645406 -49.817056) (xy 352.634804 -49.816512)
			(xy 352.560636 -49.816512) (xy 352.55 -49.816891) (xy 352.530536 -49.825461) (xy 352.523044 -49.833022)
			(xy 352.504907 -49.85207) (xy 352.464327 -49.885526) (xy 352.419532 -49.913086) (xy 352.371373 -49.934226)
			(xy 352.320766 -49.948546) (xy 352.268671 -49.955772) (xy 352.242374 -49.956212) (xy 352.24212 -49.956212)
			(xy 352.21475 -49.955731) (xy 352.160572 -49.947917) (xy 352.108069 -49.932431) (xy 352.058322 -49.909592)
			(xy 352.012354 -49.879871) (xy 351.991422 -49.862232) (xy 351.991168 -49.861978) (xy 351.984068 -49.856411)
			(xy 351.967161 -49.850153) (xy 351.958148 -49.849786) (xy 351.891092 -49.849786) (xy 351.882075 -49.850142)
			(xy 351.865158 -49.856391) (xy 351.858072 -49.861978) (xy 351.857564 -49.862486) (xy 351.836596 -49.880056)
			(xy 351.790635 -49.909718) (xy 351.740906 -49.932509) (xy 351.688431 -49.94796) (xy 351.634287 -49.955753)
			(xy 351.579585 -49.95573) (xy 351.525448 -49.94789) (xy 351.472986 -49.932394) (xy 351.423277 -49.90956)
			(xy 351.377342 -49.879858) (xy 351.356422 -49.862232) (xy 351.356168 -49.861978) (xy 351.349068 -49.856411)
			(xy 351.332161 -49.850153) (xy 351.323148 -49.849786) (xy 351.256092 -49.849786) (xy 351.247075 -49.850142)
			(xy 351.230158 -49.856391) (xy 351.223072 -49.861978) (xy 351.222564 -49.862486) (xy 351.201623 -49.88006)
			(xy 351.155691 -49.909701) (xy 351.105997 -49.932482) (xy 351.053559 -49.947934) (xy 350.999453 -49.955741)
			(xy 350.97212 -49.956212) (xy 350.944867 -49.955742) (xy 350.890914 -49.947987) (xy 350.838614 -49.932633)
			(xy 350.789032 -49.909992) (xy 350.743177 -49.880525) (xy 350.701982 -49.844832) (xy 350.666287 -49.803639)
			(xy 350.636817 -49.757785) (xy 350.614174 -49.708204) (xy 350.598817 -49.655906) (xy 350.591059 -49.601953)
			(xy 337.663236 -49.601953) (xy 337.689621 -49.613165) (xy 337.737227 -49.642219) (xy 337.780095 -49.677894)
			(xy 337.817312 -49.719431) (xy 337.848085 -49.765944) (xy 337.871757 -49.816441) (xy 337.887825 -49.869848)
			(xy 337.895945 -49.925024) (xy 337.896454 -49.95291) (xy 337.895945 -49.980796) (xy 337.887825 -50.035972)
			(xy 337.871757 -50.089379) (xy 337.848085 -50.139876) (xy 337.817312 -50.186389) (xy 337.780095 -50.227926)
			(xy 337.737227 -50.263601) (xy 337.689621 -50.292655) (xy 337.638292 -50.314467) (xy 337.584335 -50.328573)
			(xy 337.528898 -50.334673) (xy 337.473164 -50.332636) (xy 337.418321 -50.322506) (xy 337.365537 -50.304499)
			(xy 337.315937 -50.278998) (xy 337.270579 -50.246547) (xy 337.23043 -50.207838) (xy 337.196344 -50.163695)
			(xy 337.169048 -50.11506) (xy 337.149125 -50.062969) (xy 337.136999 -50.008532) (xy 337.132928 -49.95291)
			(xy 318.64564 -49.95291) (xy 318.626055 -49.955726) (xy 318.598804 -49.956212) (xy 318.571434 -49.955741)
			(xy 318.517255 -49.947924) (xy 318.464752 -49.932436) (xy 318.415005 -49.909595) (xy 318.369038 -49.879872)
			(xy 318.348106 -49.862232) (xy 318.347852 -49.861978) (xy 318.340757 -49.856405) (xy 318.323846 -49.850151)
			(xy 318.314832 -49.849786) (xy 318.247776 -49.849786) (xy 318.238758 -49.850135) (xy 318.221842 -49.856389)
			(xy 318.214756 -49.861978) (xy 318.214248 -49.862486) (xy 318.193293 -49.880071) (xy 318.147329 -49.909733)
			(xy 318.097599 -49.932523) (xy 318.045122 -49.947973) (xy 317.990976 -49.955765) (xy 317.936272 -49.955739)
			(xy 317.882134 -49.947897) (xy 317.829671 -49.932399) (xy 317.779962 -49.909564) (xy 317.734026 -49.879859)
			(xy 317.713106 -49.862232) (xy 317.712852 -49.861978) (xy 317.705757 -49.856405) (xy 317.688846 -49.850151)
			(xy 317.679832 -49.849786) (xy 317.612776 -49.849786) (xy 317.603758 -49.850135) (xy 317.586842 -49.856389)
			(xy 317.579756 -49.861978) (xy 317.579248 -49.862486) (xy 317.558293 -49.880071) (xy 317.512329 -49.909733)
			(xy 317.462599 -49.932523) (xy 317.410122 -49.947973) (xy 317.355976 -49.955765) (xy 317.301272 -49.955739)
			(xy 317.247134 -49.947897) (xy 317.194671 -49.932399) (xy 317.144962 -49.909564) (xy 317.099026 -49.879859)
			(xy 317.078106 -49.862232) (xy 317.077852 -49.861978) (xy 317.070757 -49.856405) (xy 317.053846 -49.850151)
			(xy 317.044832 -49.849786) (xy 316.977776 -49.849786) (xy 316.968758 -49.850135) (xy 316.951842 -49.856389)
			(xy 316.944756 -49.861978) (xy 316.944248 -49.862486) (xy 316.923313 -49.880067) (xy 316.877379 -49.909708)
			(xy 316.827683 -49.932487) (xy 316.775245 -49.947937) (xy 316.721138 -49.955742) (xy 316.693804 -49.956212)
			(xy 316.666551 -49.955741) (xy 316.6126 -49.947985) (xy 316.560303 -49.932629) (xy 316.510723 -49.909987)
			(xy 316.464869 -49.880519) (xy 316.423677 -49.844826) (xy 316.387983 -49.803634) (xy 316.358515 -49.757781)
			(xy 316.335872 -49.708201) (xy 316.320516 -49.655903) (xy 316.312759 -49.601953) (xy 315.234149 -49.601953)
			(xy 315.234149 -49.601955) (xy 315.226391 -49.655909) (xy 315.211033 -49.70821) (xy 315.188387 -49.757793)
			(xy 315.158916 -49.803648) (xy 315.123218 -49.844842) (xy 315.082021 -49.880536) (xy 315.036163 -49.910004)
			(xy 314.986578 -49.932645) (xy 314.934276 -49.947998) (xy 314.880321 -49.955751) (xy 314.853066 -49.956212)
			(xy 314.852812 -49.956212) (xy 314.826518 -49.955741) (xy 314.77443 -49.948498) (xy 314.723829 -49.934174)
			(xy 314.675673 -49.913041) (xy 314.630873 -49.885498) (xy 314.590277 -49.852067) (xy 314.572142 -49.833022)
			(xy 314.564551 -49.825604) (xy 314.545148 -49.817065) (xy 314.53455 -49.816512) (xy 314.460382 -49.816512)
			(xy 314.449749 -49.816916) (xy 314.430285 -49.825469) (xy 314.42279 -49.833022) (xy 314.40468 -49.852096)
			(xy 314.364093 -49.88555) (xy 314.319293 -49.913106) (xy 314.271129 -49.934242) (xy 314.220518 -49.948556)
			(xy 314.168419 -49.955776) (xy 314.14212 -49.956212) (xy 314.141866 -49.956212) (xy 314.114495 -49.955763)
			(xy 314.060316 -49.947941) (xy 314.007812 -49.932447) (xy 313.958066 -49.909602) (xy 313.912099 -49.879874)
			(xy 313.891168 -49.862232) (xy 313.890914 -49.861978) (xy 313.883829 -49.856389) (xy 313.866911 -49.850144)
			(xy 313.857894 -49.849786) (xy 313.790838 -49.849786) (xy 313.781823 -49.850164) (xy 313.764906 -49.856397)
			(xy 313.757818 -49.861978) (xy 313.75731 -49.862486) (xy 313.736385 -49.880109) (xy 313.690416 -49.909769)
			(xy 313.64068 -49.932557) (xy 313.588199 -49.948003) (xy 313.534049 -49.955792) (xy 313.479342 -49.955762)
			(xy 313.4252 -49.947916) (xy 313.372735 -49.932413) (xy 313.323025 -49.909572) (xy 313.277088 -49.879862)
			(xy 313.256168 -49.862232) (xy 313.255914 -49.861978) (xy 313.248829 -49.856389) (xy 313.231911 -49.850144)
			(xy 313.222894 -49.849786) (xy 313.155838 -49.849786) (xy 313.146823 -49.850164) (xy 313.129906 -49.856397)
			(xy 313.122818 -49.861978) (xy 313.12231 -49.862486) (xy 313.10139 -49.880085) (xy 313.055451 -49.909723)
			(xy 313.005752 -49.932498) (xy 312.95331 -49.947944) (xy 312.899201 -49.955745) (xy 312.871866 -49.956212)
			(xy 312.844617 -49.955716) (xy 312.790673 -49.947956) (xy 312.738383 -49.932598) (xy 312.688811 -49.909955)
			(xy 312.642965 -49.880488) (xy 312.601779 -49.844797) (xy 312.566092 -49.803608) (xy 312.536629 -49.75776)
			(xy 312.51399 -49.708185) (xy 312.498637 -49.655894) (xy 312.490882 -49.601949) (xy 292.979949 -49.601949)
			(xy 292.979949 -49.601955) (xy 292.97219 -49.65591) (xy 292.956832 -49.708212) (xy 292.934186 -49.757796)
			(xy 292.904714 -49.803652) (xy 292.869015 -49.844846) (xy 292.827816 -49.88054) (xy 292.781957 -49.910007)
			(xy 292.732371 -49.932647) (xy 292.680067 -49.948) (xy 292.626111 -49.955752) (xy 292.598856 -49.956212)
			(xy 292.571487 -49.95571) (xy 292.51731 -49.947901) (xy 292.464807 -49.93242) (xy 292.41506 -49.909586)
			(xy 292.369091 -49.879869) (xy 292.348158 -49.862232) (xy 292.347904 -49.861978) (xy 292.340822 -49.856385)
			(xy 292.323902 -49.850143) (xy 292.314884 -49.849786) (xy 292.247828 -49.849786) (xy 292.238813 -49.850159)
			(xy 292.221896 -49.856396) (xy 292.214808 -49.861978) (xy 292.2143 -49.862486) (xy 292.193383 -49.880118)
			(xy 292.147412 -49.909779) (xy 292.097676 -49.932565) (xy 292.045193 -49.948011) (xy 291.991042 -49.955799)
			(xy 291.936334 -49.955768) (xy 291.882191 -49.94792) (xy 291.829726 -49.932416) (xy 291.780015 -49.909574)
			(xy 291.734078 -49.879863) (xy 291.713158 -49.862232) (xy 291.712904 -49.861978) (xy 291.705822 -49.856385)
			(xy 291.688902 -49.850143) (xy 291.679884 -49.849786) (xy 291.612828 -49.849786) (xy 291.603813 -49.850159)
			(xy 291.586896 -49.856396) (xy 291.579808 -49.861978) (xy 291.5793 -49.862486) (xy 291.558383 -49.880118)
			(xy 291.512412 -49.909779) (xy 291.462676 -49.932565) (xy 291.410193 -49.948011) (xy 291.356042 -49.955799)
			(xy 291.301334 -49.955768) (xy 291.247191 -49.94792) (xy 291.194726 -49.932416) (xy 291.145015 -49.909574)
			(xy 291.099078 -49.879863) (xy 291.078158 -49.862232) (xy 291.077904 -49.861978) (xy 291.070822 -49.856385)
			(xy 291.053902 -49.850143) (xy 291.044884 -49.849786) (xy 290.977828 -49.849786) (xy 290.968813 -49.850159)
			(xy 290.951896 -49.856396) (xy 290.944808 -49.861978) (xy 290.9443 -49.862486) (xy 290.923383 -49.88009)
			(xy 290.877444 -49.909727) (xy 290.827744 -49.932501) (xy 290.775301 -49.947946) (xy 290.721191 -49.955746)
			(xy 290.693856 -49.956212) (xy 290.666607 -49.955715) (xy 290.612665 -49.947954) (xy 290.560376 -49.932595)
			(xy 290.510805 -49.909952) (xy 290.46496 -49.880484) (xy 290.423776 -49.844793) (xy 290.388089 -49.803605)
			(xy 290.358627 -49.757757) (xy 290.33599 -49.708183) (xy 290.320637 -49.655892) (xy 290.312882 -49.601949)
			(xy 289.234126 -49.601949) (xy 289.234126 -49.601951) (xy 289.22637 -49.655897) (xy 289.211016 -49.708191)
			(xy 289.188376 -49.757768) (xy 289.158911 -49.803618) (xy 289.123221 -49.844808) (xy 289.082032 -49.8805)
			(xy 289.036184 -49.909967) (xy 288.986608 -49.932609) (xy 288.934315 -49.947966) (xy 288.880369 -49.955725)
			(xy 288.853118 -49.956212) (xy 288.852864 -49.956212) (xy 288.826569 -49.955773) (xy 288.774479 -49.948523)
			(xy 288.723878 -49.934193) (xy 288.675722 -49.913054) (xy 288.630922 -49.885506) (xy 288.590328 -49.85207)
			(xy 288.572194 -49.833022) (xy 288.564621 -49.825583) (xy 288.545204 -49.817056) (xy 288.534602 -49.816512)
			(xy 288.460434 -49.816512) (xy 288.449798 -49.81689) (xy 288.430334 -49.825461) (xy 288.422842 -49.833022)
			(xy 288.404706 -49.852071) (xy 288.364125 -49.885527) (xy 288.31933 -49.913087) (xy 288.271172 -49.934227)
			(xy 288.220564 -49.948546) (xy 288.168469 -49.955772) (xy 288.142172 -49.956212) (xy 288.141918 -49.956212)
			(xy 288.114548 -49.955732) (xy 288.06037 -49.947917) (xy 288.007867 -49.932431) (xy 287.95812 -49.909593)
			(xy 287.912152 -49.879872) (xy 287.89122 -49.862232) (xy 287.890966 -49.861978) (xy 287.883866 -49.85641)
			(xy 287.86696 -49.850153) (xy 287.857946 -49.849786) (xy 287.79089 -49.849786) (xy 287.781873 -49.850141)
			(xy 287.764956 -49.856391) (xy 287.75787 -49.861978) (xy 287.757362 -49.862486) (xy 287.736395 -49.880058)
			(xy 287.690434 -49.90972) (xy 287.640705 -49.932511) (xy 287.58823 -49.947961) (xy 287.534086 -49.955755)
			(xy 287.479383 -49.955731) (xy 287.425246 -49.947891) (xy 287.372784 -49.932394) (xy 287.323075 -49.909561)
			(xy 287.27714 -49.879858) (xy 287.25622 -49.862232) (xy 287.255966 -49.861978) (xy 287.248866 -49.85641)
			(xy 287.23196 -49.850153) (xy 287.222946 -49.849786) (xy 287.15589 -49.849786) (xy 287.146873 -49.850141)
			(xy 287.129956 -49.856391) (xy 287.12287 -49.861978) (xy 287.122362 -49.862486) (xy 287.101422 -49.880061)
			(xy 287.055489 -49.909702) (xy 287.005795 -49.932482) (xy 286.953358 -49.947934) (xy 286.899251 -49.955741)
			(xy 286.871918 -49.956212) (xy 286.844665 -49.955742) (xy 286.790712 -49.947987) (xy 286.738413 -49.932633)
			(xy 286.688831 -49.909992) (xy 286.642976 -49.880524) (xy 286.601782 -49.844831) (xy 286.566086 -49.803638)
			(xy 286.536617 -49.757785) (xy 286.513974 -49.708204) (xy 286.498617 -49.655905) (xy 286.490859 -49.601953)
			(xy 285.66334 -49.601953) (xy 285.689725 -49.613165) (xy 285.737331 -49.642219) (xy 285.780199 -49.677894)
			(xy 285.817416 -49.719431) (xy 285.848189 -49.765944) (xy 285.871861 -49.816441) (xy 285.887929 -49.869848)
			(xy 285.896049 -49.925024) (xy 285.896558 -49.95291) (xy 285.896049 -49.980796) (xy 285.887929 -50.035972)
			(xy 285.871861 -50.089379) (xy 285.848189 -50.139876) (xy 285.817416 -50.186389) (xy 285.780199 -50.227926)
			(xy 285.737331 -50.263601) (xy 285.689725 -50.292655) (xy 285.638396 -50.314467) (xy 285.584439 -50.328573)
			(xy 285.529002 -50.334673) (xy 285.473268 -50.332636) (xy 285.418425 -50.322506) (xy 285.365641 -50.304499)
			(xy 285.316041 -50.278998) (xy 285.270683 -50.246547) (xy 285.230534 -50.207838) (xy 285.196448 -50.163695)
			(xy 285.169152 -50.11506) (xy 285.149229 -50.062969) (xy 285.137103 -50.008532) (xy 285.133032 -49.95291)
			(xy 266.645741 -49.95291) (xy 266.626159 -49.955726) (xy 266.598908 -49.956212) (xy 266.571538 -49.955738)
			(xy 266.517359 -49.947922) (xy 266.464857 -49.932434) (xy 266.41511 -49.909594) (xy 266.369142 -49.879872)
			(xy 266.34821 -49.862232) (xy 266.347956 -49.861978) (xy 266.340859 -49.856406) (xy 266.32395 -49.850151)
			(xy 266.314936 -49.849786) (xy 266.24788 -49.849786) (xy 266.238863 -49.850137) (xy 266.221946 -49.856389)
			(xy 266.21486 -49.861978) (xy 266.214352 -49.862486) (xy 266.193393 -49.880067) (xy 266.14743 -49.90973)
			(xy 266.0977 -49.93252) (xy 266.045224 -49.947969) (xy 265.991079 -49.955762) (xy 265.936375 -49.955737)
			(xy 265.882237 -49.947895) (xy 265.829775 -49.932398) (xy 265.780066 -49.909563) (xy 265.73413 -49.879859)
			(xy 265.71321 -49.862232) (xy 265.712956 -49.861978) (xy 265.705859 -49.856406) (xy 265.68895 -49.850151)
			(xy 265.679936 -49.849786) (xy 265.61288 -49.849786) (xy 265.603863 -49.850137) (xy 265.586946 -49.856389)
			(xy 265.57986 -49.861978) (xy 265.579352 -49.862486) (xy 265.558393 -49.880067) (xy 265.51243 -49.90973)
			(xy 265.4627 -49.93252) (xy 265.410224 -49.947969) (xy 265.356079 -49.955762) (xy 265.301375 -49.955737)
			(xy 265.247237 -49.947895) (xy 265.194775 -49.932398) (xy 265.145066 -49.909563) (xy 265.09913 -49.879859)
			(xy 265.07821 -49.862232) (xy 265.077956 -49.861978) (xy 265.070859 -49.856406) (xy 265.05395 -49.850151)
			(xy 265.044936 -49.849786) (xy 264.97788 -49.849786) (xy 264.968863 -49.850137) (xy 264.951946 -49.856389)
			(xy 264.94486 -49.861978) (xy 264.944352 -49.862486) (xy 264.923416 -49.880065) (xy 264.877482 -49.909706)
			(xy 264.827787 -49.932485) (xy 264.775349 -49.947936) (xy 264.721242 -49.955742) (xy 264.693908 -49.956212)
			(xy 264.666655 -49.955741) (xy 264.612704 -49.947985) (xy 264.560406 -49.93263) (xy 264.510825 -49.909988)
			(xy 264.464971 -49.880521) (xy 264.423778 -49.844828) (xy 264.388084 -49.803635) (xy 264.358616 -49.757782)
			(xy 264.335973 -49.708202) (xy 264.320616 -49.655904) (xy 264.312859 -49.601953) (xy 263.234249 -49.601953)
			(xy 263.234249 -49.601954) (xy 263.226491 -49.655909) (xy 263.211133 -49.708209) (xy 263.188488 -49.757792)
			(xy 263.159017 -49.803647) (xy 263.12332 -49.844841) (xy 263.082123 -49.880535) (xy 263.036266 -49.910002)
			(xy 262.986681 -49.932644) (xy 262.934379 -49.947997) (xy 262.880425 -49.955751) (xy 262.85317 -49.956212)
			(xy 262.852916 -49.956212) (xy 262.826622 -49.955739) (xy 262.774534 -49.948496) (xy 262.723933 -49.934172)
			(xy 262.675777 -49.91304) (xy 262.630977 -49.885497) (xy 262.590381 -49.852067) (xy 262.572246 -49.833022)
			(xy 262.564691 -49.825561) (xy 262.54526 -49.817046) (xy 262.534654 -49.816512) (xy 262.460486 -49.816512)
			(xy 262.449854 -49.816919) (xy 262.430389 -49.825469) (xy 262.422894 -49.833022) (xy 262.404782 -49.852094)
			(xy 262.364196 -49.885548) (xy 262.319396 -49.913105) (xy 262.271233 -49.934241) (xy 262.220621 -49.948555)
			(xy 262.168522 -49.955776) (xy 262.142224 -49.956212) (xy 262.14197 -49.956212) (xy 262.114599 -49.955761)
			(xy 262.06042 -49.947939) (xy 262.007917 -49.932446) (xy 261.95817 -49.909601) (xy 261.912204 -49.879874)
			(xy 261.891272 -49.862232) (xy 261.891018 -49.861978) (xy 261.883932 -49.85639) (xy 261.867015 -49.850145)
			(xy 261.857998 -49.849786) (xy 261.790942 -49.849786) (xy 261.781928 -49.850166) (xy 261.765011 -49.856398)
			(xy 261.757922 -49.861978) (xy 261.757414 -49.862486) (xy 261.736485 -49.880105) (xy 261.690517 -49.909765)
			(xy 261.640782 -49.932553) (xy 261.588301 -49.948) (xy 261.534152 -49.955789) (xy 261.479445 -49.95576)
			(xy 261.425304 -49.947914) (xy 261.372839 -49.932411) (xy 261.323128 -49.909571) (xy 261.277192 -49.879862)
			(xy 261.256272 -49.862232) (xy 261.256018 -49.861978) (xy 261.248932 -49.85639) (xy 261.232015 -49.850145)
			(xy 261.222998 -49.849786) (xy 261.155942 -49.849786) (xy 261.146928 -49.850166) (xy 261.130011 -49.856398)
			(xy 261.122922 -49.861978) (xy 261.122414 -49.862486) (xy 261.101492 -49.880083) (xy 261.055554 -49.909721)
			(xy 261.005855 -49.932497) (xy 260.953414 -49.947944) (xy 260.899305 -49.955745) (xy 260.87197 -49.956212)
			(xy 260.84472 -49.955716) (xy 260.790777 -49.947956) (xy 260.738486 -49.932599) (xy 260.688913 -49.909956)
			(xy 260.643067 -49.880489) (xy 260.601881 -49.844798) (xy 260.566193 -49.803609) (xy 260.53673 -49.757761)
			(xy 260.514091 -49.708186) (xy 260.498737 -49.655894) (xy 260.490982 -49.60195) (xy 259.663385 -49.60195)
			(xy 259.689777 -49.613165) (xy 259.737383 -49.642219) (xy 259.780251 -49.677894) (xy 259.817468 -49.719431)
			(xy 259.848241 -49.765944) (xy 259.871913 -49.816441) (xy 259.887981 -49.869848) (xy 259.896101 -49.925024)
			(xy 259.89661 -49.95291) (xy 259.896101 -49.980796) (xy 259.887981 -50.035972) (xy 259.871913 -50.089379)
			(xy 259.848241 -50.139876) (xy 259.817468 -50.186389) (xy 259.780251 -50.227926) (xy 259.737383 -50.263601)
			(xy 259.689777 -50.292655) (xy 259.638448 -50.314467) (xy 259.584491 -50.328573) (xy 259.529054 -50.334673)
			(xy 259.47332 -50.332636) (xy 259.418477 -50.322506) (xy 259.365693 -50.304499) (xy 259.316093 -50.278998)
			(xy 259.270735 -50.246547) (xy 259.230586 -50.207838) (xy 259.1965 -50.163695) (xy 259.169204 -50.11506)
			(xy 259.149281 -50.062969) (xy 259.137155 -50.008532) (xy 259.133084 -49.95291) (xy 239.806113 -49.95291)
			(xy 239.788841 -49.972843) (xy 239.747646 -50.008538) (xy 239.70179 -50.038008) (xy 239.652207 -50.060651)
			(xy 239.599906 -50.076008) (xy 239.545952 -50.083765) (xy 239.518698 -50.084228) (xy 239.491327 -50.083781)
			(xy 239.437146 -50.075961) (xy 239.384642 -50.060469) (xy 239.334896 -50.037622) (xy 239.28893 -50.007892)
			(xy 239.268 -49.990248) (xy 239.267746 -49.989994) (xy 239.260651 -49.98442) (xy 239.243741 -49.978166)
			(xy 239.234726 -49.977802) (xy 239.16767 -49.977802) (xy 239.158652 -49.978144) (xy 239.141735 -49.984402)
			(xy 239.13465 -49.989994) (xy 239.134142 -49.990502) (xy 239.113212 -50.008089) (xy 239.067276 -50.037728)
			(xy 239.017579 -50.060505) (xy 238.96514 -50.075954) (xy 238.911032 -50.083759) (xy 238.883698 -50.084228)
			(xy 238.856448 -50.083702) (xy 238.802504 -50.075945) (xy 238.750212 -50.060591) (xy 238.700638 -50.037951)
			(xy 238.65479 -50.008486) (xy 238.613602 -49.972796) (xy 238.577913 -49.931608) (xy 238.548448 -49.885761)
			(xy 238.525808 -49.836186) (xy 238.510454 -49.783894) (xy 238.502698 -49.72995) (xy 221.724427 -49.72995)
			(xy 221.748241 -49.765944) (xy 221.771913 -49.816441) (xy 221.787981 -49.869848) (xy 221.796101 -49.925024)
			(xy 221.79661 -49.95291) (xy 221.796101 -49.980796) (xy 221.787981 -50.035972) (xy 221.771913 -50.089379)
			(xy 221.748241 -50.139876) (xy 221.717468 -50.186389) (xy 221.680251 -50.227926) (xy 221.637383 -50.263601)
			(xy 221.589777 -50.292655) (xy 221.538448 -50.314467) (xy 221.484491 -50.328573) (xy 221.429054 -50.334673)
			(xy 221.37332 -50.332636) (xy 221.318477 -50.322506) (xy 221.265693 -50.304499) (xy 221.216093 -50.278998)
			(xy 221.170735 -50.246547) (xy 221.130586 -50.207838) (xy 221.0965 -50.163695) (xy 221.069204 -50.11506)
			(xy 221.049281 -50.062969) (xy 221.037155 -50.008532) (xy 221.033084 -49.95291) (xy 202.545989 -49.95291)
			(xy 202.526215 -49.955751) (xy 202.49896 -49.956212) (xy 202.471591 -49.955708) (xy 202.417414 -49.947899)
			(xy 202.364911 -49.932418) (xy 202.315164 -49.909585) (xy 202.269195 -49.879869) (xy 202.248262 -49.862232)
			(xy 202.248008 -49.861978) (xy 202.240925 -49.856386) (xy 202.224005 -49.850143) (xy 202.214988 -49.849786)
			(xy 202.147932 -49.849786) (xy 202.138917 -49.850161) (xy 202.122 -49.856396) (xy 202.114912 -49.861978)
			(xy 202.114404 -49.862486) (xy 202.093483 -49.880114) (xy 202.047514 -49.909775) (xy 201.997778 -49.932562)
			(xy 201.945295 -49.948008) (xy 201.891145 -49.955796) (xy 201.836437 -49.955766) (xy 201.782295 -49.947918)
			(xy 201.72983 -49.932415) (xy 201.680119 -49.909573) (xy 201.634182 -49.879862) (xy 201.613262 -49.862232)
			(xy 201.613008 -49.861978) (xy 201.605925 -49.856386) (xy 201.589005 -49.850143) (xy 201.579988 -49.849786)
			(xy 201.512932 -49.849786) (xy 201.503917 -49.850161) (xy 201.487 -49.856396) (xy 201.479912 -49.861978)
			(xy 201.479404 -49.862486) (xy 201.458483 -49.880114) (xy 201.412514 -49.909775) (xy 201.362778 -49.932562)
			(xy 201.310295 -49.948008) (xy 201.256145 -49.955796) (xy 201.201437 -49.955766) (xy 201.147295 -49.947918)
			(xy 201.09483 -49.932415) (xy 201.045119 -49.909573) (xy 200.999182 -49.879862) (xy 200.978262 -49.862232)
			(xy 200.978008 -49.861978) (xy 200.970925 -49.856386) (xy 200.954005 -49.850143) (xy 200.944988 -49.849786)
			(xy 200.877932 -49.849786) (xy 200.868917 -49.850161) (xy 200.852 -49.856396) (xy 200.844912 -49.861978)
			(xy 200.844404 -49.862486) (xy 200.823486 -49.880088) (xy 200.777547 -49.909725) (xy 200.727847 -49.9325)
			(xy 200.675405 -49.947946) (xy 200.621295 -49.955745) (xy 200.59396 -49.956212) (xy 200.566711 -49.955716)
			(xy 200.512768 -49.947954) (xy 200.460479 -49.932596) (xy 200.410907 -49.909953) (xy 200.365062 -49.880486)
			(xy 200.323877 -49.844795) (xy 200.28819 -49.803606) (xy 200.258728 -49.757758) (xy 200.23609 -49.708184)
			(xy 200.220737 -49.655893) (xy 200.212982 -49.601949) (xy 199.134226 -49.601949) (xy 199.134226 -49.601951)
			(xy 199.12647 -49.655897) (xy 199.111116 -49.70819) (xy 199.088476 -49.757767) (xy 199.059012 -49.803617)
			(xy 199.023322 -49.844807) (xy 198.982134 -49.880499) (xy 198.936286 -49.909966) (xy 198.886711 -49.932608)
			(xy 198.834418 -49.947966) (xy 198.780473 -49.955725) (xy 198.753222 -49.956212) (xy 198.752968 -49.956212)
			(xy 198.726673 -49.955771) (xy 198.674583 -49.948521) (xy 198.623982 -49.934192) (xy 198.575826 -49.913053)
			(xy 198.531027 -49.885505) (xy 198.490432 -49.85207) (xy 198.472298 -49.833022) (xy 198.464723 -49.825584)
			(xy 198.445308 -49.817056) (xy 198.434706 -49.816512) (xy 198.360538 -49.816512) (xy 198.349903 -49.816892)
			(xy 198.330438 -49.825462) (xy 198.322946 -49.833022) (xy 198.304808 -49.852069) (xy 198.264228 -49.885525)
			(xy 198.219433 -49.913085) (xy 198.171275 -49.934226) (xy 198.120668 -49.948545) (xy 198.068573 -49.955772)
			(xy 198.042276 -49.956212) (xy 198.042022 -49.956212) (xy 198.014652 -49.95573) (xy 197.960474 -49.947916)
			(xy 197.907971 -49.93243) (xy 197.858224 -49.909592) (xy 197.812256 -49.879871) (xy 197.791324 -49.862232)
			(xy 197.79107 -49.861978) (xy 197.783969 -49.856412) (xy 197.767063 -49.850154) (xy 197.75805 -49.849786)
			(xy 197.690994 -49.849786) (xy 197.681977 -49.850143) (xy 197.66506 -49.856391) (xy 197.657974 -49.861978)
			(xy 197.657466 -49.862486) (xy 197.636496 -49.880054) (xy 197.590535 -49.909717) (xy 197.540807 -49.932507)
			(xy 197.488333 -49.947958) (xy 197.434189 -49.955752) (xy 197.379487 -49.955729) (xy 197.325349 -49.947889)
			(xy 197.272888 -49.932393) (xy 197.223179 -49.90956) (xy 197.177244 -49.879858) (xy 197.156324 -49.862232)
			(xy 197.15607 -49.861978) (xy 197.148969 -49.856412) (xy 197.132063 -49.850154) (xy 197.12305 -49.849786)
			(xy 197.055994 -49.849786) (xy 197.046977 -49.850143) (xy 197.03006 -49.856391) (xy 197.022974 -49.861978)
			(xy 197.022466 -49.862486) (xy 197.001524 -49.880059) (xy 196.955592 -49.909701) (xy 196.905898 -49.932481)
			(xy 196.853461 -49.947933) (xy 196.799355 -49.955741) (xy 196.772022 -49.956212) (xy 196.744768 -49.955742)
			(xy 196.690816 -49.947988) (xy 196.638516 -49.932634) (xy 196.588933 -49.909993) (xy 196.543078 -49.880526)
			(xy 196.501883 -49.844832) (xy 196.466187 -49.80364) (xy 196.436718 -49.757786) (xy 196.414074 -49.708205)
			(xy 196.398717 -49.655906) (xy 196.390959 -49.601954) (xy 176.880026 -49.601954) (xy 176.87227 -49.655898)
			(xy 176.856915 -49.708193) (xy 176.834275 -49.75777) (xy 176.804809 -49.80362) (xy 176.769119 -49.84481)
			(xy 176.727929 -49.880502) (xy 176.68208 -49.909969) (xy 176.632504 -49.932611) (xy 176.58021 -49.947967)
			(xy 176.526263 -49.955725) (xy 176.499012 -49.956212) (xy 176.471642 -49.955736) (xy 176.417464 -49.94792)
			(xy 176.364961 -49.932433) (xy 176.315214 -49.909594) (xy 176.269246 -49.879872) (xy 176.248314 -49.862232)
			(xy 176.24806 -49.861978) (xy 176.240962 -49.856408) (xy 176.224054 -49.850152) (xy 176.21504 -49.849786)
			(xy 176.147984 -49.849786) (xy 176.138967 -49.850139) (xy 176.12205 -49.85639) (xy 176.114964 -49.861978)
			(xy 176.114456 -49.862486) (xy 176.093494 -49.880063) (xy 176.047532 -49.909726) (xy 175.997802 -49.932516)
			(xy 175.945327 -49.947966) (xy 175.891182 -49.955759) (xy 175.836479 -49.955735) (xy 175.782341 -49.947893)
			(xy 175.729879 -49.932397) (xy 175.68017 -49.909562) (xy 175.634234 -49.879859) (xy 175.613314 -49.862232)
			(xy 175.61306 -49.861978) (xy 175.605962 -49.856408) (xy 175.589054 -49.850152) (xy 175.58004 -49.849786)
			(xy 175.512984 -49.849786) (xy 175.503967 -49.850139) (xy 175.48705 -49.85639) (xy 175.479964 -49.861978)
			(xy 175.479456 -49.862486) (xy 175.458494 -49.880063) (xy 175.412532 -49.909726) (xy 175.362802 -49.932516)
			(xy 175.310327 -49.947966) (xy 175.256182 -49.955759) (xy 175.201479 -49.955735) (xy 175.147341 -49.947893)
			(xy 175.094879 -49.932397) (xy 175.04517 -49.909562) (xy 174.999234 -49.879859) (xy 174.978314 -49.862232)
			(xy 174.97806 -49.861978) (xy 174.970962 -49.856408) (xy 174.954054 -49.850152) (xy 174.94504 -49.849786)
			(xy 174.877984 -49.849786) (xy 174.868967 -49.850139) (xy 174.85205 -49.85639) (xy 174.844964 -49.861978)
			(xy 174.844456 -49.862486) (xy 174.823518 -49.880063) (xy 174.777585 -49.909705) (xy 174.72789 -49.932484)
			(xy 174.675452 -49.947935) (xy 174.621345 -49.955742) (xy 174.594012 -49.956212) (xy 174.566759 -49.955741)
			(xy 174.512807 -49.947986) (xy 174.460508 -49.932631) (xy 174.410927 -49.90999) (xy 174.365073 -49.880522)
			(xy 174.32388 -49.844829) (xy 174.288185 -49.803636) (xy 174.258716 -49.757783) (xy 174.236073 -49.708203)
			(xy 174.220717 -49.655905) (xy 174.212959 -49.601953) (xy 173.134349 -49.601953) (xy 173.134349 -49.601954)
			(xy 173.126591 -49.655908) (xy 173.111233 -49.708209) (xy 173.088589 -49.757791) (xy 173.059118 -49.803646)
			(xy 173.023421 -49.84484) (xy 172.982225 -49.880534) (xy 172.936368 -49.910001) (xy 172.886784 -49.932642)
			(xy 172.834483 -49.947996) (xy 172.780528 -49.95575) (xy 172.753274 -49.956212) (xy 172.75302 -49.956212)
			(xy 172.726726 -49.955736) (xy 172.674638 -49.948494) (xy 172.624037 -49.934171) (xy 172.575881 -49.913039)
			(xy 172.531081 -49.885497) (xy 172.490485 -49.852067) (xy 172.47235 -49.833022) (xy 172.464793 -49.825563)
			(xy 172.445364 -49.817047) (xy 172.434758 -49.816512) (xy 172.36059 -49.816512) (xy 172.349958 -49.816921)
			(xy 172.330493 -49.82547) (xy 172.322998 -49.833022) (xy 172.304884 -49.852092) (xy 172.264298 -49.885546)
			(xy 172.219499 -49.913103) (xy 172.171336 -49.93424) (xy 172.120725 -49.948554) (xy 172.068626 -49.955775)
			(xy 172.042328 -49.956212) (xy 172.042074 -49.956212) (xy 172.014703 -49.955758) (xy 171.960524 -49.947937)
			(xy 171.908021 -49.932445) (xy 171.858274 -49.909601) (xy 171.812308 -49.879874) (xy 171.791376 -49.862232)
			(xy 171.791122 -49.861978) (xy 171.784035 -49.856392) (xy 171.767118 -49.850146) (xy 171.758102 -49.849786)
			(xy 171.691046 -49.849786) (xy 171.682032 -49.850168) (xy 171.665115 -49.856398) (xy 171.658026 -49.861978)
			(xy 171.657518 -49.862486) (xy 171.636586 -49.880101) (xy 171.590619 -49.909762) (xy 171.540884 -49.93255)
			(xy 171.488404 -49.947997) (xy 171.434255 -49.955786) (xy 171.379548 -49.955757) (xy 171.325407 -49.947912)
			(xy 171.272943 -49.93241) (xy 171.223232 -49.90957) (xy 171.177296 -49.879861) (xy 171.156376 -49.862232)
			(xy 171.156122 -49.861978) (xy 171.149035 -49.856392) (xy 171.132118 -49.850146) (xy 171.123102 -49.849786)
			(xy 171.056046 -49.849786) (xy 171.047032 -49.850168) (xy 171.030115 -49.856398) (xy 171.023026 -49.861978)
			(xy 171.022518 -49.862486) (xy 171.001595 -49.880081) (xy 170.955657 -49.90972) (xy 170.905959 -49.932496)
			(xy 170.853518 -49.947943) (xy 170.799408 -49.955744) (xy 170.772074 -49.956212) (xy 170.744824 -49.955716)
			(xy 170.69088 -49.947957) (xy 170.638589 -49.9326) (xy 170.589015 -49.909957) (xy 170.543169 -49.880491)
			(xy 170.501982 -49.8448) (xy 170.466294 -49.80361) (xy 170.43683 -49.757762) (xy 170.414191 -49.708187)
			(xy 170.398837 -49.655895) (xy 170.391082 -49.60195) (xy 169.563489 -49.60195) (xy 169.589881 -49.613165)
			(xy 169.637487 -49.642219) (xy 169.680355 -49.677894) (xy 169.717572 -49.719431) (xy 169.748345 -49.765944)
			(xy 169.772017 -49.816441) (xy 169.788085 -49.869848) (xy 169.796205 -49.925024) (xy 169.796714 -49.95291)
			(xy 169.796205 -49.980796) (xy 169.788085 -50.035972) (xy 169.772017 -50.089379) (xy 169.748345 -50.139876)
			(xy 169.717572 -50.186389) (xy 169.680355 -50.227926) (xy 169.637487 -50.263601) (xy 169.589881 -50.292655)
			(xy 169.538552 -50.314467) (xy 169.484595 -50.328573) (xy 169.429158 -50.334673) (xy 169.373424 -50.332636)
			(xy 169.318581 -50.322506) (xy 169.265797 -50.304499) (xy 169.216197 -50.278998) (xy 169.170839 -50.246547)
			(xy 169.13069 -50.207838) (xy 169.096604 -50.163695) (xy 169.069308 -50.11506) (xy 169.049385 -50.062969)
			(xy 169.037259 -50.008532) (xy 169.033188 -49.95291) (xy 150.54609 -49.95291) (xy 150.526319 -49.955751)
			(xy 150.499064 -49.956212) (xy 150.471693 -49.955764) (xy 150.417513 -49.947941) (xy 150.36501 -49.932448)
			(xy 150.315264 -49.909602) (xy 150.269297 -49.879875) (xy 150.248366 -49.862232) (xy 150.248112 -49.861978)
			(xy 150.241028 -49.856388) (xy 150.224109 -49.850144) (xy 150.215092 -49.849786) (xy 150.148036 -49.849786)
			(xy 150.139021 -49.850163) (xy 150.122104 -49.856397) (xy 150.115016 -49.861978) (xy 150.114508 -49.862486)
			(xy 150.093584 -49.88011) (xy 150.047615 -49.909771) (xy 149.997879 -49.932558) (xy 149.945398 -49.948005)
			(xy 149.891248 -49.955793) (xy 149.83654 -49.955763) (xy 149.782398 -49.947916) (xy 149.729934 -49.932413)
			(xy 149.680223 -49.909572) (xy 149.634286 -49.879862) (xy 149.613366 -49.862232) (xy 149.613112 -49.861978)
			(xy 149.606028 -49.856388) (xy 149.589109 -49.850144) (xy 149.580092 -49.849786) (xy 149.513036 -49.849786)
			(xy 149.504021 -49.850163) (xy 149.487104 -49.856397) (xy 149.480016 -49.861978) (xy 149.479508 -49.862486)
			(xy 149.458584 -49.88011) (xy 149.412615 -49.909771) (xy 149.362879 -49.932558) (xy 149.310398 -49.948005)
			(xy 149.256248 -49.955793) (xy 149.20154 -49.955763) (xy 149.147398 -49.947916) (xy 149.094934 -49.932413)
			(xy 149.045223 -49.909572) (xy 148.999286 -49.879862) (xy 148.978366 -49.862232) (xy 148.978112 -49.861978)
			(xy 148.971028 -49.856388) (xy 148.954109 -49.850144) (xy 148.945092 -49.849786) (xy 148.878036 -49.849786)
			(xy 148.869021 -49.850163) (xy 148.852104 -49.856397) (xy 148.845016 -49.861978) (xy 148.844508 -49.862486)
			(xy 148.823588 -49.880086) (xy 148.77765 -49.909724) (xy 148.727951 -49.932499) (xy 148.675509 -49.947945)
			(xy 148.621399 -49.955745) (xy 148.594064 -49.956212) (xy 148.566815 -49.955716) (xy 148.512871 -49.947955)
			(xy 148.460582 -49.932597) (xy 148.411009 -49.909954) (xy 148.365164 -49.880487) (xy 148.323978 -49.844796)
			(xy 148.288291 -49.803607) (xy 148.258829 -49.757759) (xy 148.23619 -49.708185) (xy 148.220837 -49.655893)
			(xy 148.213082 -49.601949) (xy 147.134326 -49.601949) (xy 147.134326 -49.60195) (xy 147.12657 -49.655896)
			(xy 147.111216 -49.70819) (xy 147.088577 -49.757766) (xy 147.059113 -49.803615) (xy 147.023424 -49.844805)
			(xy 146.982236 -49.880497) (xy 146.936388 -49.909964) (xy 146.886814 -49.932607) (xy 146.834522 -49.947965)
			(xy 146.780576 -49.955724) (xy 146.753326 -49.956212) (xy 146.753072 -49.956212) (xy 146.726777 -49.955768)
			(xy 146.674688 -49.948519) (xy 146.624086 -49.93419) (xy 146.57593 -49.913052) (xy 146.531131 -49.885504)
			(xy 146.490536 -49.852069) (xy 146.472402 -49.833022) (xy 146.464826 -49.825586) (xy 146.445411 -49.817057)
			(xy 146.43481 -49.816512) (xy 146.360642 -49.816512) (xy 146.350007 -49.816895) (xy 146.330542 -49.825462)
			(xy 146.32305 -49.833022) (xy 146.304959 -49.852115) (xy 146.264369 -49.885567) (xy 146.219564 -49.913121)
			(xy 146.171397 -49.934254) (xy 146.120782 -49.948564) (xy 146.06868 -49.955779) (xy 146.04238 -49.956212)
			(xy 146.042126 -49.956212) (xy 146.014756 -49.955728) (xy 145.960578 -49.947914) (xy 145.908075 -49.932429)
			(xy 145.858328 -49.909591) (xy 145.812361 -49.879871) (xy 145.791428 -49.862232) (xy 145.791174 -49.861978)
			(xy 145.784072 -49.856414) (xy 145.767167 -49.850154) (xy 145.758154 -49.849786) (xy 145.691098 -49.849786)
			(xy 145.682081 -49.850145) (xy 145.665165 -49.856392) (xy 145.658078 -49.861978) (xy 145.65757 -49.862486)
			(xy 145.636597 -49.88005) (xy 145.590637 -49.909713) (xy 145.540909 -49.932504) (xy 145.488435 -49.947955)
			(xy 145.434291 -49.955749) (xy 145.37959 -49.955726) (xy 145.325453 -49.947887) (xy 145.272992 -49.932392)
			(xy 145.223283 -49.909559) (xy 145.177348 -49.879858) (xy 145.156428 -49.862232) (xy 145.156174 -49.861978)
			(xy 145.149072 -49.856414) (xy 145.132167 -49.850154) (xy 145.123154 -49.849786) (xy 145.056098 -49.849786)
			(xy 145.047081 -49.850145) (xy 145.030165 -49.856392) (xy 145.023078 -49.861978) (xy 145.02257 -49.862486)
			(xy 145.001627 -49.880057) (xy 144.955695 -49.909699) (xy 144.906002 -49.93248) (xy 144.853565 -49.947933)
			(xy 144.799459 -49.955741) (xy 144.772126 -49.956212) (xy 144.744872 -49.955742) (xy 144.690919 -49.947989)
			(xy 144.638619 -49.932635) (xy 144.589036 -49.909994) (xy 144.54318 -49.880527) (xy 144.501985 -49.844834)
			(xy 144.466288 -49.803641) (xy 144.436818 -49.757787) (xy 144.414174 -49.708206) (xy 144.398817 -49.655906)
			(xy 144.391059 -49.601954) (xy 143.563551 -49.601954) (xy 143.589933 -49.613165) (xy 143.637539 -49.642219)
			(xy 143.680407 -49.677894) (xy 143.717624 -49.719431) (xy 143.748397 -49.765944) (xy 143.772069 -49.816441)
			(xy 143.788137 -49.869848) (xy 143.796257 -49.925024) (xy 143.796766 -49.95291) (xy 143.796257 -49.980796)
			(xy 143.788137 -50.035972) (xy 143.772069 -50.089379) (xy 143.748397 -50.139876) (xy 143.717624 -50.186389)
			(xy 143.680407 -50.227926) (xy 143.637539 -50.263601) (xy 143.589933 -50.292655) (xy 143.538604 -50.314467)
			(xy 143.484647 -50.328573) (xy 143.42921 -50.334673) (xy 143.373476 -50.332636) (xy 143.318633 -50.322506)
			(xy 143.265849 -50.304499) (xy 143.216249 -50.278998) (xy 143.170891 -50.246547) (xy 143.130742 -50.207838)
			(xy 143.096656 -50.163695) (xy 143.06936 -50.11506) (xy 143.049437 -50.062969) (xy 143.037311 -50.008532)
			(xy 143.03324 -49.95291) (xy 124.545941 -49.95291) (xy 124.526367 -49.955725) (xy 124.499116 -49.956212)
			(xy 124.471746 -49.955734) (xy 124.417568 -49.947918) (xy 124.365065 -49.932432) (xy 124.315318 -49.909593)
			(xy 124.26935 -49.879872) (xy 124.248418 -49.862232) (xy 124.248164 -49.861978) (xy 124.241065 -49.85641)
			(xy 124.224158 -49.850153) (xy 124.215144 -49.849786) (xy 124.148088 -49.849786) (xy 124.139071 -49.85014)
			(xy 124.122154 -49.85639) (xy 124.115068 -49.861978) (xy 124.11456 -49.862486) (xy 124.093595 -49.88006)
			(xy 124.047633 -49.909722) (xy 123.997904 -49.932513) (xy 123.945429 -49.947963) (xy 123.891284 -49.955756)
			(xy 123.836582 -49.955732) (xy 123.782444 -49.947891) (xy 123.729982 -49.932395) (xy 123.680273 -49.909561)
			(xy 123.634338 -49.879858) (xy 123.613418 -49.862232) (xy 123.613164 -49.861978) (xy 123.606065 -49.85641)
			(xy 123.589158 -49.850153) (xy 123.580144 -49.849786) (xy 123.513088 -49.849786) (xy 123.504071 -49.85014)
			(xy 123.487154 -49.85639) (xy 123.480068 -49.861978) (xy 123.47956 -49.862486) (xy 123.458595 -49.88006)
			(xy 123.412633 -49.909722) (xy 123.362904 -49.932513) (xy 123.310429 -49.947963) (xy 123.256284 -49.955756)
			(xy 123.201582 -49.955732) (xy 123.147444 -49.947891) (xy 123.094982 -49.932395) (xy 123.045273 -49.909561)
			(xy 122.999338 -49.879858) (xy 122.978418 -49.862232) (xy 122.978164 -49.861978) (xy 122.971065 -49.85641)
			(xy 122.954158 -49.850153) (xy 122.945144 -49.849786) (xy 122.878088 -49.849786) (xy 122.869071 -49.85014)
			(xy 122.852154 -49.85639) (xy 122.845068 -49.861978) (xy 122.84456 -49.862486) (xy 122.823621 -49.880062)
			(xy 122.777688 -49.909703) (xy 122.727993 -49.932483) (xy 122.675556 -49.947935) (xy 122.621449 -49.955742)
			(xy 122.594116 -49.956212) (xy 122.566863 -49.955742) (xy 122.512911 -49.947987) (xy 122.460611 -49.932632)
			(xy 122.41103 -49.909991) (xy 122.365175 -49.880524) (xy 122.323981 -49.84483) (xy 122.288286 -49.803638)
			(xy 122.258817 -49.757784) (xy 122.236173 -49.708204) (xy 122.220817 -49.655905) (xy 122.213059 -49.601953)
			(xy 121.134449 -49.601953) (xy 121.134449 -49.601954) (xy 121.126691 -49.655908) (xy 121.111334 -49.708208)
			(xy 121.088689 -49.75779) (xy 121.059219 -49.803644) (xy 121.023523 -49.844838) (xy 120.982327 -49.880532)
			(xy 120.93647 -49.91) (xy 120.886887 -49.932641) (xy 120.834586 -49.947996) (xy 120.780632 -49.95575)
			(xy 120.753378 -49.956212) (xy 120.753124 -49.956212) (xy 120.72683 -49.955733) (xy 120.674742 -49.948492)
			(xy 120.624141 -49.934169) (xy 120.575985 -49.913037) (xy 120.531185 -49.885496) (xy 120.490589 -49.852067)
			(xy 120.472454 -49.833022) (xy 120.464896 -49.825565) (xy 120.445468 -49.817048) (xy 120.434862 -49.816512)
			(xy 120.360694 -49.816512) (xy 120.350062 -49.816923) (xy 120.330597 -49.825471) (xy 120.323102 -49.833022)
			(xy 120.304986 -49.85209) (xy 120.264401 -49.885544) (xy 120.219601 -49.913102) (xy 120.171439 -49.934239)
			(xy 120.120828 -49.948554) (xy 120.06873 -49.955775) (xy 120.042432 -49.956212) (xy 120.042178 -49.956212)
			(xy 120.014807 -49.955756) (xy 119.960628 -49.947935) (xy 119.908125 -49.932444) (xy 119.858378 -49.9096)
			(xy 119.812412 -49.879874) (xy 119.79148 -49.862232) (xy 119.791226 -49.861978) (xy 119.784138 -49.856394)
			(xy 119.767222 -49.850146) (xy 119.758206 -49.849786) (xy 119.69115 -49.849786) (xy 119.682136 -49.85017)
			(xy 119.665219 -49.856399) (xy 119.65813 -49.861978) (xy 119.657622 -49.862486) (xy 119.636687 -49.880097)
			(xy 119.59072 -49.909758) (xy 119.540986 -49.932546) (xy 119.488506 -49.947993) (xy 119.434358 -49.955783)
			(xy 119.379651 -49.955755) (xy 119.325511 -49.94791) (xy 119.273047 -49.932408) (xy 119.223336 -49.909569)
			(xy 119.1774 -49.879861) (xy 119.15648 -49.862232) (xy 119.156226 -49.861978) (xy 119.149138 -49.856394)
			(xy 119.132222 -49.850146) (xy 119.123206 -49.849786) (xy 119.05615 -49.849786) (xy 119.047136 -49.85017)
			(xy 119.030219 -49.856399) (xy 119.02313 -49.861978) (xy 119.022622 -49.862486) (xy 119.001697 -49.880079)
			(xy 118.95576 -49.909718) (xy 118.906062 -49.932495) (xy 118.853621 -49.947942) (xy 118.799512 -49.955744)
			(xy 118.772178 -49.956212) (xy 118.744928 -49.955717) (xy 118.690983 -49.947958) (xy 118.638692 -49.932601)
			(xy 118.589118 -49.909959) (xy 118.543271 -49.880492) (xy 118.502083 -49.844801) (xy 118.466395 -49.803612)
			(xy 118.436931 -49.757763) (xy 118.414291 -49.708188) (xy 118.398938 -49.655895) (xy 118.391182 -49.60195)
			(xy 105.463287 -49.60195) (xy 105.489679 -49.613165) (xy 105.537285 -49.642219) (xy 105.580153 -49.677894)
			(xy 105.61737 -49.719431) (xy 105.648143 -49.765944) (xy 105.671815 -49.816441) (xy 105.687883 -49.869848)
			(xy 105.696003 -49.925024) (xy 105.696512 -49.95291) (xy 105.696003 -49.980796) (xy 105.687883 -50.035972)
			(xy 105.671815 -50.089379) (xy 105.648143 -50.139876) (xy 105.61737 -50.186389) (xy 105.580153 -50.227926)
			(xy 105.537285 -50.263601) (xy 105.489679 -50.292655) (xy 105.43835 -50.314467) (xy 105.384393 -50.328573)
			(xy 105.328956 -50.334673) (xy 105.273222 -50.332636) (xy 105.218379 -50.322506) (xy 105.165595 -50.304499)
			(xy 105.115995 -50.278998) (xy 105.070637 -50.246547) (xy 105.030488 -50.207838) (xy 104.996402 -50.163695)
			(xy 104.969106 -50.11506) (xy 104.949183 -50.062969) (xy 104.937057 -50.008532) (xy 104.932986 -49.95291)
			(xy 86.445891 -49.95291) (xy 86.426117 -49.955751) (xy 86.398862 -49.956212) (xy 86.371493 -49.955707)
			(xy 86.317316 -49.947898) (xy 86.264813 -49.932418) (xy 86.215066 -49.909585) (xy 86.169097 -49.879869)
			(xy 86.148164 -49.862232) (xy 86.14791 -49.861978) (xy 86.140827 -49.856387) (xy 86.123907 -49.850144)
			(xy 86.11489 -49.849786) (xy 86.047834 -49.849786) (xy 86.038819 -49.850162) (xy 86.021902 -49.856397)
			(xy 86.014814 -49.861978) (xy 86.014306 -49.862486) (xy 85.993384 -49.880112) (xy 85.947414 -49.909773)
			(xy 85.897678 -49.93256) (xy 85.845197 -49.948006) (xy 85.791046 -49.955794) (xy 85.736339 -49.955765)
			(xy 85.682197 -49.947917) (xy 85.629732 -49.932414) (xy 85.580021 -49.909573) (xy 85.534084 -49.879862)
			(xy 85.513164 -49.862232) (xy 85.51291 -49.861978) (xy 85.505827 -49.856387) (xy 85.488907 -49.850144)
			(xy 85.47989 -49.849786) (xy 85.412834 -49.849786) (xy 85.403819 -49.850162) (xy 85.386902 -49.856397)
			(xy 85.379814 -49.861978) (xy 85.379306 -49.862486) (xy 85.358384 -49.880112) (xy 85.312414 -49.909773)
			(xy 85.262678 -49.93256) (xy 85.210197 -49.948006) (xy 85.156046 -49.955794) (xy 85.101339 -49.955765)
			(xy 85.047197 -49.947917) (xy 84.994732 -49.932414) (xy 84.945021 -49.909573) (xy 84.899084 -49.879862)
			(xy 84.878164 -49.862232) (xy 84.87791 -49.861978) (xy 84.870827 -49.856387) (xy 84.853907 -49.850144)
			(xy 84.84489 -49.849786) (xy 84.777834 -49.849786) (xy 84.768819 -49.850162) (xy 84.751902 -49.856397)
			(xy 84.744814 -49.861978) (xy 84.744306 -49.862486) (xy 84.723387 -49.880087) (xy 84.677448 -49.909724)
			(xy 84.627749 -49.932499) (xy 84.575307 -49.947945) (xy 84.521197 -49.955745) (xy 84.493862 -49.956212)
			(xy 84.466613 -49.955716) (xy 84.41267 -49.947955) (xy 84.36038 -49.932597) (xy 84.310808 -49.909953)
			(xy 84.264963 -49.880486) (xy 84.223778 -49.844795) (xy 84.188091 -49.803607) (xy 84.158628 -49.757758)
			(xy 84.13599 -49.708184) (xy 84.120637 -49.655893) (xy 84.112882 -49.601949) (xy 83.034126 -49.601949)
			(xy 83.034126 -49.60195) (xy 83.02637 -49.655897) (xy 83.011016 -49.70819) (xy 82.988377 -49.757766)
			(xy 82.958912 -49.803616) (xy 82.923223 -49.844806) (xy 82.882035 -49.880498) (xy 82.836187 -49.909965)
			(xy 82.786613 -49.932608) (xy 82.73432 -49.947965) (xy 82.680374 -49.955725) (xy 82.653124 -49.956212)
			(xy 82.65287 -49.956212) (xy 82.626575 -49.955769) (xy 82.574485 -49.94852) (xy 82.523884 -49.934191)
			(xy 82.475728 -49.913052) (xy 82.430929 -49.885505) (xy 82.390334 -49.852069) (xy 82.3722 -49.833022)
			(xy 82.364624 -49.825585) (xy 82.34521 -49.817057) (xy 82.334608 -49.816512) (xy 82.26044 -49.816512)
			(xy 82.249805 -49.816893) (xy 82.23034 -49.825462) (xy 82.222848 -49.833022) (xy 82.204709 -49.852068)
			(xy 82.164129 -49.885524) (xy 82.119335 -49.913084) (xy 82.071177 -49.934225) (xy 82.02057 -49.948545)
			(xy 81.968475 -49.955772) (xy 81.942178 -49.956212) (xy 81.941924 -49.956212) (xy 81.914554 -49.955729)
			(xy 81.860376 -49.947915) (xy 81.807873 -49.932429) (xy 81.758126 -49.909592) (xy 81.712158 -49.879871)
			(xy 81.691226 -49.862232) (xy 81.690972 -49.861978) (xy 81.683871 -49.856413) (xy 81.666965 -49.850154)
			(xy 81.657952 -49.849786) (xy 81.590896 -49.849786) (xy 81.581879 -49.850144) (xy 81.564963 -49.856391)
			(xy 81.557876 -49.861978) (xy 81.557368 -49.862486) (xy 81.536397 -49.880052) (xy 81.490436 -49.909715)
			(xy 81.440708 -49.932506) (xy 81.388234 -49.947957) (xy 81.33409 -49.95575) (xy 81.279388 -49.955727)
			(xy 81.225251 -49.947888) (xy 81.17279 -49.932392) (xy 81.123081 -49.90956) (xy 81.077146 -49.879858)
			(xy 81.056226 -49.862232) (xy 81.055972 -49.861978) (xy 81.048871 -49.856413) (xy 81.031965 -49.850154)
			(xy 81.022952 -49.849786) (xy 80.955896 -49.849786) (xy 80.946879 -49.850144) (xy 80.929963 -49.856391)
			(xy 80.922876 -49.861978) (xy 80.922368 -49.862486) (xy 80.901426 -49.880058) (xy 80.855493 -49.9097)
			(xy 80.8058 -49.93248) (xy 80.753363 -49.947933) (xy 80.699257 -49.955741) (xy 80.671924 -49.956212)
			(xy 80.64467 -49.955742) (xy 80.590717 -49.947988) (xy 80.538417 -49.932634) (xy 80.488835 -49.909994)
			(xy 80.442979 -49.880526) (xy 80.401784 -49.844833) (xy 80.366088 -49.80364) (xy 80.336618 -49.757787)
			(xy 80.313974 -49.708205) (xy 80.298617 -49.655906) (xy 80.290859 -49.601954) (xy 79.463349 -49.601954)
			(xy 79.489731 -49.613165) (xy 79.537337 -49.642219) (xy 79.580205 -49.677894) (xy 79.617422 -49.719431)
			(xy 79.648195 -49.765944) (xy 79.671867 -49.816441) (xy 79.687935 -49.869848) (xy 79.696055 -49.925024)
			(xy 79.696564 -49.95291) (xy 79.696055 -49.980796) (xy 79.687935 -50.035972) (xy 79.671867 -50.089379)
			(xy 79.648195 -50.139876) (xy 79.617422 -50.186389) (xy 79.580205 -50.227926) (xy 79.537337 -50.263601)
			(xy 79.489731 -50.292655) (xy 79.438402 -50.314467) (xy 79.384445 -50.328573) (xy 79.329008 -50.334673)
			(xy 79.273274 -50.332636) (xy 79.218431 -50.322506) (xy 79.165647 -50.304499) (xy 79.116047 -50.278998)
			(xy 79.070689 -50.246547) (xy 79.03054 -50.207838) (xy 78.996454 -50.163695) (xy 78.969158 -50.11506)
			(xy 78.949235 -50.062969) (xy 78.937109 -50.008532) (xy 78.933038 -49.95291) (xy 60.44574 -49.95291)
			(xy 60.426165 -49.955725) (xy 60.398914 -49.956212) (xy 60.371544 -49.955735) (xy 60.317366 -49.947919)
			(xy 60.264863 -49.932433) (xy 60.215116 -49.909593) (xy 60.169148 -49.879872) (xy 60.148216 -49.862232)
			(xy 60.147962 -49.861978) (xy 60.140864 -49.856409) (xy 60.123956 -49.850152) (xy 60.114942 -49.849786)
			(xy 60.047886 -49.849786) (xy 60.038869 -49.85014) (xy 60.021952 -49.85639) (xy 60.014866 -49.861978)
			(xy 60.014358 -49.862486) (xy 59.993395 -49.880062) (xy 59.947432 -49.909724) (xy 59.897703 -49.932514)
			(xy 59.845228 -49.947965) (xy 59.791083 -49.955758) (xy 59.73638 -49.955733) (xy 59.682242 -49.947892)
			(xy 59.62978 -49.932396) (xy 59.580071 -49.909562) (xy 59.534136 -49.879858) (xy 59.513216 -49.862232)
			(xy 59.512962 -49.861978) (xy 59.505864 -49.856409) (xy 59.488956 -49.850152) (xy 59.479942 -49.849786)
			(xy 59.412886 -49.849786) (xy 59.403869 -49.85014) (xy 59.386952 -49.85639) (xy 59.379866 -49.861978)
			(xy 59.379358 -49.862486) (xy 59.358395 -49.880062) (xy 59.312432 -49.909724) (xy 59.262703 -49.932514)
			(xy 59.210228 -49.947965) (xy 59.156083 -49.955758) (xy 59.10138 -49.955733) (xy 59.047242 -49.947892)
			(xy 58.99478 -49.932396) (xy 58.945071 -49.909562) (xy 58.899136 -49.879858) (xy 58.878216 -49.862232)
			(xy 58.877962 -49.861978) (xy 58.870864 -49.856409) (xy 58.853956 -49.850152) (xy 58.844942 -49.849786)
			(xy 58.777886 -49.849786) (xy 58.768869 -49.85014) (xy 58.751952 -49.85639) (xy 58.744866 -49.861978)
			(xy 58.744358 -49.862486) (xy 58.723419 -49.880063) (xy 58.677486 -49.909704) (xy 58.627792 -49.932483)
			(xy 58.575354 -49.947935) (xy 58.521247 -49.955742) (xy 58.493914 -49.956212) (xy 58.466661 -49.955742)
			(xy 58.412709 -49.947986) (xy 58.36041 -49.932632) (xy 58.310829 -49.90999) (xy 58.264974 -49.880523)
			(xy 58.22378 -49.84483) (xy 58.188085 -49.803637) (xy 58.158616 -49.757784) (xy 58.135973 -49.708203)
			(xy 58.120617 -49.655905) (xy 58.112859 -49.601953) (xy 57.034249 -49.601953) (xy 57.034249 -49.601954)
			(xy 57.026491 -49.655908) (xy 57.011133 -49.708208) (xy 56.988489 -49.75779) (xy 56.959018 -49.803645)
			(xy 56.923322 -49.844839) (xy 56.882126 -49.880533) (xy 56.836269 -49.910001) (xy 56.786686 -49.932642)
			(xy 56.734384 -49.947996) (xy 56.68043 -49.95575) (xy 56.653176 -49.956212) (xy 56.652922 -49.956212)
			(xy 56.626628 -49.955735) (xy 56.57454 -49.948493) (xy 56.523939 -49.93417) (xy 56.475783 -49.913038)
			(xy 56.430983 -49.885497) (xy 56.390387 -49.852067) (xy 56.372252 -49.833022) (xy 56.364694 -49.825564)
			(xy 56.345266 -49.817048) (xy 56.33466 -49.816512) (xy 56.260492 -49.816512) (xy 56.24986 -49.816922)
			(xy 56.230395 -49.82547) (xy 56.2229 -49.833022) (xy 56.204785 -49.852091) (xy 56.164199 -49.885545)
			(xy 56.1194 -49.913102) (xy 56.071238 -49.934239) (xy 56.020627 -49.948554) (xy 55.968528 -49.955775)
			(xy 55.94223 -49.956212) (xy 55.941976 -49.956212) (xy 55.914605 -49.955757) (xy 55.860426 -49.947936)
			(xy 55.807923 -49.932444) (xy 55.758176 -49.9096) (xy 55.71221 -49.879874) (xy 55.691278 -49.862232)
			(xy 55.691024 -49.861978) (xy 55.683937 -49.856393) (xy 55.66702 -49.850146) (xy 55.658004 -49.849786)
			(xy 55.590948 -49.849786) (xy 55.581934 -49.850169) (xy 55.565017 -49.856399) (xy 55.557928 -49.861978)
			(xy 55.55742 -49.862486) (xy 55.536487 -49.880099) (xy 55.490519 -49.90976) (xy 55.440785 -49.932548)
			(xy 55.388305 -49.947995) (xy 55.334156 -49.955784) (xy 55.27945 -49.955756) (xy 55.225309 -49.947911)
			(xy 55.172845 -49.932409) (xy 55.123134 -49.90957) (xy 55.077198 -49.879861) (xy 55.056278 -49.862232)
			(xy 55.056024 -49.861978) (xy 55.048937 -49.856393) (xy 55.03202 -49.850146) (xy 55.023004 -49.849786)
			(xy 54.955948 -49.849786) (xy 54.946934 -49.850169) (xy 54.930017 -49.856399) (xy 54.922928 -49.861978)
			(xy 54.92242 -49.862486) (xy 54.901496 -49.88008) (xy 54.855559 -49.909719) (xy 54.80586 -49.932495)
			(xy 54.75342 -49.947942) (xy 54.69931 -49.955744) (xy 54.671976 -49.956212) (xy 54.644726 -49.955717)
			(xy 54.590782 -49.947957) (xy 54.53849 -49.9326) (xy 54.488917 -49.909958) (xy 54.44307 -49.880491)
			(xy 54.401883 -49.8448) (xy 54.366194 -49.803611) (xy 54.33673 -49.757762) (xy 54.314091 -49.708187)
			(xy 54.298738 -49.655895) (xy 54.290982 -49.60195) (xy 53.463391 -49.60195) (xy 53.489783 -49.613165)
			(xy 53.537389 -49.642219) (xy 53.580257 -49.677894) (xy 53.617474 -49.719431) (xy 53.648247 -49.765944)
			(xy 53.671919 -49.816441) (xy 53.687987 -49.869848) (xy 53.696107 -49.925024) (xy 53.696616 -49.95291)
			(xy 53.696107 -49.980796) (xy 53.687987 -50.035972) (xy 53.671919 -50.089379) (xy 53.648247 -50.139876)
			(xy 53.617474 -50.186389) (xy 53.580257 -50.227926) (xy 53.537389 -50.263601) (xy 53.489783 -50.292655)
			(xy 53.438454 -50.314467) (xy 53.384497 -50.328573) (xy 53.32906 -50.334673) (xy 53.273326 -50.332636)
			(xy 53.218483 -50.322506) (xy 53.165699 -50.304499) (xy 53.116099 -50.278998) (xy 53.070741 -50.246547)
			(xy 53.030592 -50.207838) (xy 52.996506 -50.163695) (xy 52.96921 -50.11506) (xy 52.949287 -50.062969)
			(xy 52.937161 -50.008532) (xy 52.93309 -49.95291) (xy 34.445992 -49.95291) (xy 34.426221 -49.955751)
			(xy 34.398966 -49.956212) (xy 34.371595 -49.955763) (xy 34.317416 -49.947941) (xy 34.264912 -49.932447)
			(xy 34.215166 -49.909602) (xy 34.169199 -49.879874) (xy 34.148268 -49.862232) (xy 34.148014 -49.861978)
			(xy 34.140929 -49.856389) (xy 34.124011 -49.850144) (xy 34.114994 -49.849786) (xy 34.047938 -49.849786)
			(xy 34.038923 -49.850164) (xy 34.022006 -49.856397) (xy 34.014918 -49.861978) (xy 34.01441 -49.862486)
			(xy 33.993485 -49.880109) (xy 33.947516 -49.909769) (xy 33.89778 -49.932557) (xy 33.845299 -49.948003)
			(xy 33.791149 -49.955792) (xy 33.736442 -49.955762) (xy 33.6823 -49.947916) (xy 33.629835 -49.932413)
			(xy 33.580125 -49.909572) (xy 33.534188 -49.879862) (xy 33.513268 -49.862232) (xy 33.513014 -49.861978)
			(xy 33.505929 -49.856389) (xy 33.489011 -49.850144) (xy 33.479994 -49.849786) (xy 33.412938 -49.849786)
			(xy 33.403923 -49.850164) (xy 33.387006 -49.856397) (xy 33.379918 -49.861978) (xy 33.37941 -49.862486)
			(xy 33.358485 -49.880109) (xy 33.312516 -49.909769) (xy 33.26278 -49.932557) (xy 33.210299 -49.948003)
			(xy 33.156149 -49.955792) (xy 33.101442 -49.955762) (xy 33.0473 -49.947916) (xy 32.994835 -49.932413)
			(xy 32.945125 -49.909572) (xy 32.899188 -49.879862) (xy 32.878268 -49.862232) (xy 32.878014 -49.861978)
			(xy 32.870929 -49.856389) (xy 32.854011 -49.850144) (xy 32.844994 -49.849786) (xy 32.777938 -49.849786)
			(xy 32.768923 -49.850164) (xy 32.752006 -49.856397) (xy 32.744918 -49.861978) (xy 32.74441 -49.862486)
			(xy 32.72349 -49.880085) (xy 32.677551 -49.909723) (xy 32.627852 -49.932498) (xy 32.57541 -49.947944)
			(xy 32.521301 -49.955745) (xy 32.493966 -49.956212) (xy 32.466717 -49.955716) (xy 32.412773 -49.947956)
			(xy 32.360483 -49.932598) (xy 32.310911 -49.909955) (xy 32.265065 -49.880488) (xy 32.223879 -49.844797)
			(xy 32.188192 -49.803608) (xy 32.158729 -49.75776) (xy 32.13609 -49.708185) (xy 32.120737 -49.655894)
			(xy 32.112982 -49.601949) (xy 31.034226 -49.601949) (xy 31.034226 -49.60195) (xy 31.02647 -49.655896)
			(xy 31.011117 -49.708189) (xy 30.988477 -49.757765) (xy 30.959013 -49.803615) (xy 30.923324 -49.844805)
			(xy 30.882137 -49.880496) (xy 30.83629 -49.909964) (xy 30.786715 -49.932607) (xy 30.734423 -49.947964)
			(xy 30.680478 -49.955724) (xy 30.653228 -49.956212) (xy 30.652974 -49.956212) (xy 30.626679 -49.955767)
			(xy 30.57459 -49.948518) (xy 30.523988 -49.934189) (xy 30.475832 -49.913051) (xy 30.431033 -49.885504)
			(xy 30.390438 -49.852069) (xy 30.372304 -49.833022) (xy 30.364727 -49.825587) (xy 30.345313 -49.817057)
			(xy 30.334712 -49.816512) (xy 30.260544 -49.816512) (xy 30.249909 -49.816896) (xy 30.230445 -49.825463)
			(xy 30.222952 -49.833022) (xy 30.20486 -49.852114) (xy 30.16427 -49.885566) (xy 30.119465 -49.913121)
			(xy 30.071298 -49.934253) (xy 30.020683 -49.948563) (xy 29.968582 -49.955778) (xy 29.942282 -49.956212)
			(xy 29.942028 -49.956212) (xy 29.914659 -49.955727) (xy 29.86048 -49.947913) (xy 29.807978 -49.932428)
			(xy 29.75823 -49.909591) (xy 29.712263 -49.879871) (xy 29.69133 -49.862232) (xy 29.691076 -49.861978)
			(xy 29.684002 -49.856373) (xy 29.667076 -49.850138) (xy 29.658056 -49.849786) (xy 29.591 -49.849786)
			(xy 29.581984 -49.850146) (xy 29.565067 -49.856392) (xy 29.55798 -49.861978) (xy 29.557472 -49.862486)
			(xy 29.536498 -49.880048) (xy 29.490537 -49.909711) (xy 29.44081 -49.932502) (xy 29.388336 -49.947953)
			(xy 29.334193 -49.955748) (xy 29.279491 -49.955725) (xy 29.225355 -49.947886) (xy 29.172894 -49.932391)
			(xy 29.123185 -49.909559) (xy 29.07725 -49.879857) (xy 29.05633 -49.862232) (xy 29.056076 -49.861978)
			(xy 29.049002 -49.856373) (xy 29.032076 -49.850138) (xy 29.023056 -49.849786) (xy 28.956 -49.849786)
			(xy 28.946984 -49.850146) (xy 28.930067 -49.856392) (xy 28.92298 -49.861978) (xy 28.922472 -49.862486)
			(xy 28.901528 -49.880056) (xy 28.855596 -49.909698) (xy 28.805903 -49.932479) (xy 28.753467 -49.947932)
			(xy 28.699361 -49.955741) (xy 28.672028 -49.956212) (xy 28.644774 -49.955743) (xy 28.590821 -49.947989)
			(xy 28.53852 -49.932635) (xy 28.488937 -49.909995) (xy 28.443081 -49.880528) (xy 28.401885 -49.844835)
			(xy 28.366189 -49.803642) (xy 28.336719 -49.757788) (xy 28.314074 -49.708206) (xy 28.298717 -49.655907)
			(xy 28.290959 -49.601954) (xy 27.463453 -49.601954) (xy 27.489835 -49.613165) (xy 27.537441 -49.642219)
			(xy 27.580309 -49.677894) (xy 27.617526 -49.719431) (xy 27.648299 -49.765944) (xy 27.671971 -49.816441)
			(xy 27.688039 -49.869848) (xy 27.696159 -49.925024) (xy 27.696668 -49.95291) (xy 27.696159 -49.980796)
			(xy 27.688039 -50.035972) (xy 27.671971 -50.089379) (xy 27.648299 -50.139876) (xy 27.617526 -50.186389)
			(xy 27.580309 -50.227926) (xy 27.537441 -50.263601) (xy 27.489835 -50.292655) (xy 27.438506 -50.314467)
			(xy 27.384549 -50.328573) (xy 27.329112 -50.334673) (xy 27.273378 -50.332636) (xy 27.218535 -50.322506)
			(xy 27.165751 -50.304499) (xy 27.116151 -50.278998) (xy 27.070793 -50.246547) (xy 27.030644 -50.207838)
			(xy 26.996558 -50.163695) (xy 26.969262 -50.11506) (xy 26.949339 -50.062969) (xy 26.937213 -50.008532)
			(xy 26.933142 -49.95291) (xy 20.380452 -49.95291) (xy 20.380452 -51.019456) (xy 24.749504 -51.019456)
			(xy 24.753575 -50.963834) (xy 24.765701 -50.909397) (xy 24.785624 -50.857306) (xy 24.81292 -50.808671)
			(xy 24.847006 -50.764528) (xy 24.887155 -50.725819) (xy 24.932513 -50.693368) (xy 24.982113 -50.667867)
			(xy 25.034897 -50.64986) (xy 25.08974 -50.63973) (xy 25.145474 -50.637693) (xy 25.200911 -50.643793)
			(xy 25.254868 -50.657899) (xy 25.306197 -50.679711) (xy 25.353803 -50.708765) (xy 25.396671 -50.74444)
			(xy 25.433888 -50.785977) (xy 25.464661 -50.83249) (xy 25.488333 -50.882987) (xy 25.504401 -50.936394)
			(xy 25.512521 -50.99157) (xy 25.51303 -51.019456) (xy 26.94127 -51.019456) (xy 26.945341 -50.963834)
			(xy 26.957467 -50.909397) (xy 26.97739 -50.857306) (xy 27.004686 -50.808671) (xy 27.038772 -50.764528)
			(xy 27.078921 -50.725819) (xy 27.124279 -50.693368) (xy 27.173879 -50.667867) (xy 27.226663 -50.64986)
			(xy 27.281506 -50.63973) (xy 27.33724 -50.637693) (xy 27.392677 -50.643793) (xy 27.446634 -50.657899)
			(xy 27.497963 -50.679711) (xy 27.545569 -50.708765) (xy 27.588437 -50.74444) (xy 27.625654 -50.785977)
			(xy 27.656427 -50.83249) (xy 27.680099 -50.882987) (xy 27.696167 -50.936394) (xy 27.704287 -50.99157)
			(xy 27.704796 -51.019456) (xy 27.704287 -51.047342) (xy 27.696167 -51.102518) (xy 27.680099 -51.155925)
			(xy 27.656427 -51.206422) (xy 27.625654 -51.252935) (xy 27.588437 -51.294472) (xy 27.545569 -51.330147)
			(xy 27.497963 -51.359201) (xy 27.446634 -51.381013) (xy 27.392677 -51.395119) (xy 27.33724 -51.401219)
			(xy 27.281506 -51.399182) (xy 27.226663 -51.389052) (xy 27.173879 -51.371045) (xy 27.124279 -51.345544)
			(xy 27.078921 -51.313093) (xy 27.038772 -51.274384) (xy 27.004686 -51.230241) (xy 26.97739 -51.181606)
			(xy 26.957467 -51.129515) (xy 26.945341 -51.075078) (xy 26.94127 -51.019456) (xy 25.51303 -51.019456)
			(xy 25.512521 -51.047342) (xy 25.504401 -51.102518) (xy 25.488333 -51.155925) (xy 25.464661 -51.206422)
			(xy 25.433888 -51.252935) (xy 25.396671 -51.294472) (xy 25.353803 -51.330147) (xy 25.306197 -51.359201)
			(xy 25.254868 -51.381013) (xy 25.200911 -51.395119) (xy 25.145474 -51.401219) (xy 25.08974 -51.399182)
			(xy 25.034897 -51.389052) (xy 24.982113 -51.371045) (xy 24.932513 -51.345544) (xy 24.887155 -51.313093)
			(xy 24.847006 -51.274384) (xy 24.81292 -51.230241) (xy 24.785624 -51.181606) (xy 24.765701 -51.129515)
			(xy 24.753575 -51.075078) (xy 24.749504 -51.019456) (xy 20.380452 -51.019456) (xy 20.380452 -52.035456)
			(xy 26.94127 -52.035456) (xy 26.945341 -51.979834) (xy 26.957467 -51.925397) (xy 26.97739 -51.873306)
			(xy 27.004686 -51.824671) (xy 27.038772 -51.780528) (xy 27.078921 -51.741819) (xy 27.124279 -51.709368)
			(xy 27.173879 -51.683867) (xy 27.226663 -51.66586) (xy 27.281506 -51.65573) (xy 27.33724 -51.653693)
			(xy 27.392677 -51.659793) (xy 27.446634 -51.673899) (xy 27.482283 -51.689048) (xy 28.2555 -51.689048)
			(xy 28.2555 -51.634552) (xy 28.263255 -51.58061) (xy 28.278608 -51.528321) (xy 28.301245 -51.478749)
			(xy 28.330707 -51.432903) (xy 28.366393 -51.391716) (xy 28.407577 -51.356026) (xy 28.453421 -51.326561)
			(xy 28.502991 -51.303919) (xy 28.555279 -51.288562) (xy 28.60922 -51.280802) (xy 28.636468 -51.280314)
			(xy 28.663838 -51.280795) (xy 28.718016 -51.288609) (xy 28.770519 -51.304094) (xy 28.820266 -51.326933)
			(xy 28.866234 -51.356654) (xy 28.887166 -51.374294) (xy 28.88742 -51.374548) (xy 28.894492 -51.380155)
			(xy 28.91142 -51.386388) (xy 28.92044 -51.38674) (xy 28.987496 -51.38674) (xy 28.996514 -51.386394)
			(xy 29.013432 -51.38014) (xy 29.020516 -51.374548) (xy 29.021024 -51.37404) (xy 29.041973 -51.356476)
			(xy 29.087903 -51.326832) (xy 29.137595 -51.304049) (xy 29.19003 -51.288595) (xy 29.244135 -51.280786)
			(xy 29.271468 -51.280314) (xy 29.289811 -51.280547) (xy 29.326324 -51.28411) (xy 29.344366 -51.287426)
			(xy 29.34462 -51.287426) (xy 29.355121 -51.288854) (xy 29.375726 -51.283978) (xy 29.384498 -51.278028)
			(xy 29.45384 -51.225704) (xy 29.464 -51.206908) (xy 29.465016 -51.195986) (xy 29.467916 -51.167703)
			(xy 29.480953 -51.112366) (xy 29.502048 -51.059572) (xy 29.530735 -51.010489) (xy 29.566381 -50.9662)
			(xy 29.586936 -50.946558) (xy 29.594385 -50.938993) (xy 29.602908 -50.91957) (xy 29.603446 -50.908966)
			(xy 29.603446 -50.834798) (xy 29.603016 -50.824169) (xy 29.59448 -50.804705) (xy 29.586936 -50.797206)
			(xy 29.567881 -50.779077) (xy 29.534423 -50.738495) (xy 29.506863 -50.6937) (xy 29.485723 -50.64554)
			(xy 29.471406 -50.594931) (xy 29.464183 -50.542834) (xy 29.463746 -50.516536) (xy 29.463746 -50.516282)
			(xy 29.464232 -50.489031) (xy 29.471988 -50.435083) (xy 29.487343 -50.382788) (xy 29.509985 -50.333211)
			(xy 29.539451 -50.287361) (xy 29.575142 -50.24617) (xy 29.616333 -50.210479) (xy 29.662183 -50.181013)
			(xy 29.71176 -50.158371) (xy 29.764055 -50.143016) (xy 29.818003 -50.13526) (xy 29.872505 -50.13526)
			(xy 29.926453 -50.143016) (xy 29.978748 -50.158371) (xy 30.028325 -50.181013) (xy 30.074175 -50.210479)
			(xy 30.115366 -50.24617) (xy 30.151057 -50.287361) (xy 30.180523 -50.333211) (xy 30.203165 -50.382788)
			(xy 30.21852 -50.435083) (xy 30.226276 -50.489031) (xy 30.226762 -50.516282) (xy 30.226762 -50.516536)
			(xy 30.226339 -50.542832) (xy 30.219088 -50.594923) (xy 30.204756 -50.645525) (xy 30.183614 -50.693682)
			(xy 30.156062 -50.73848) (xy 30.122622 -50.779073) (xy 30.103572 -50.797206) (xy 30.09614 -50.804786)
			(xy 30.087607 -50.824197) (xy 30.087062 -50.834798) (xy 30.087062 -50.908966) (xy 30.087455 -50.9196)
			(xy 30.096017 -50.939063) (xy 30.103572 -50.946558) (xy 30.122611 -50.964703) (xy 30.15607 -51.005281)
			(xy 30.183632 -51.050074) (xy 30.204775 -51.098231) (xy 30.219095 -51.148837) (xy 30.226322 -51.200931)
			(xy 30.226762 -51.227228) (xy 30.226762 -51.227482) (xy 30.226499 -51.243992) (xy 33.13303 -51.243992)
			(xy 33.133519 -51.216659) (xy 33.141322 -51.162552) (xy 33.156767 -51.110113) (xy 33.179538 -51.060415)
			(xy 33.209168 -51.014476) (xy 33.226756 -50.993548) (xy 33.22701 -50.993294) (xy 33.227264 -50.99304)
			(xy 33.232848 -50.985952) (xy 33.239094 -50.969036) (xy 33.239456 -50.96002) (xy 33.239456 -50.892964)
			(xy 33.239126 -50.883944) (xy 33.232861 -50.867027) (xy 33.227264 -50.859944) (xy 33.22701 -50.85969)
			(xy 33.226756 -50.859436) (xy 33.20916 -50.838513) (xy 33.179524 -50.792575) (xy 33.156749 -50.742876)
			(xy 33.141302 -50.690435) (xy 33.133499 -50.636326) (xy 33.13303 -50.608992) (xy 33.133448 -50.581737)
			(xy 33.141207 -50.527783) (xy 33.156566 -50.475482) (xy 33.179212 -50.425899) (xy 33.208685 -50.380044)
			(xy 33.244383 -50.338851) (xy 33.285581 -50.303157) (xy 33.331439 -50.27369) (xy 33.381025 -50.25105)
			(xy 33.433328 -50.235697) (xy 33.487283 -50.227945) (xy 33.514538 -50.227484) (xy 33.543455 -50.228015)
			(xy 33.600627 -50.236737) (xy 33.655827 -50.25399) (xy 33.707789 -50.27938) (xy 33.755323 -50.312322)
			(xy 33.797339 -50.352064) (xy 33.815528 -50.37455) (xy 33.821802 -50.381944) (xy 33.838523 -50.391736)
			(xy 33.84804 -50.3936) (xy 33.85566 -50.394108) (xy 33.935416 -50.394108) (xy 33.943036 -50.3936)
			(xy 33.952549 -50.391728) (xy 33.969264 -50.381934) (xy 33.975548 -50.37455) (xy 33.993756 -50.352081)
			(xy 34.035774 -50.312347) (xy 34.083305 -50.279408) (xy 34.135263 -50.254018) (xy 34.190457 -50.236757)
			(xy 34.247623 -50.228023) (xy 34.276538 -50.227484) (xy 34.30379 -50.227942) (xy 34.357738 -50.235704)
			(xy 34.410033 -50.251063) (xy 34.45961 -50.273708) (xy 34.50546 -50.303178) (xy 34.546649 -50.338872)
			(xy 34.58234 -50.380065) (xy 34.611806 -50.425917) (xy 34.634447 -50.475495) (xy 34.649802 -50.527791)
			(xy 34.65756 -50.58174) (xy 34.658046 -50.608992) (xy 34.658046 -50.609246) (xy 34.657635 -50.635543)
			(xy 34.650383 -50.687634) (xy 34.636048 -50.738237) (xy 34.614904 -50.786393) (xy 34.58735 -50.831192)
			(xy 34.553907 -50.871784) (xy 34.534856 -50.889916) (xy 34.527417 -50.89749) (xy 34.518889 -50.916906)
			(xy 34.518346 -50.927508) (xy 34.518346 -51.001676) (xy 34.518793 -51.012303) (xy 34.521926 -51.019456)
			(xy 50.749452 -51.019456) (xy 50.753523 -50.963834) (xy 50.765649 -50.909397) (xy 50.785572 -50.857306)
			(xy 50.812868 -50.808671) (xy 50.846954 -50.764528) (xy 50.887103 -50.725819) (xy 50.932461 -50.693368)
			(xy 50.982061 -50.667867) (xy 51.034845 -50.64986) (xy 51.089688 -50.63973) (xy 51.145422 -50.637693)
			(xy 51.200859 -50.643793) (xy 51.254816 -50.657899) (xy 51.306145 -50.679711) (xy 51.353751 -50.708765)
			(xy 51.396619 -50.74444) (xy 51.433836 -50.785977) (xy 51.464609 -50.83249) (xy 51.488281 -50.882987)
			(xy 51.504349 -50.936394) (xy 51.512469 -50.99157) (xy 51.512978 -51.019456) (xy 52.941218 -51.019456)
			(xy 52.945289 -50.963834) (xy 52.957415 -50.909397) (xy 52.977338 -50.857306) (xy 53.004634 -50.808671)
			(xy 53.03872 -50.764528) (xy 53.078869 -50.725819) (xy 53.124227 -50.693368) (xy 53.173827 -50.667867)
			(xy 53.226611 -50.64986) (xy 53.281454 -50.63973) (xy 53.337188 -50.637693) (xy 53.392625 -50.643793)
			(xy 53.446582 -50.657899) (xy 53.497911 -50.679711) (xy 53.545517 -50.708765) (xy 53.588385 -50.74444)
			(xy 53.625602 -50.785977) (xy 53.656375 -50.83249) (xy 53.680047 -50.882987) (xy 53.696115 -50.936394)
			(xy 53.704235 -50.99157) (xy 53.704744 -51.019456) (xy 53.704235 -51.047342) (xy 53.696115 -51.102518)
			(xy 53.680047 -51.155925) (xy 53.656375 -51.206422) (xy 53.625602 -51.252935) (xy 53.588385 -51.294472)
			(xy 53.545517 -51.330147) (xy 53.497911 -51.359201) (xy 53.446582 -51.381013) (xy 53.392625 -51.395119)
			(xy 53.337188 -51.401219) (xy 53.281454 -51.399182) (xy 53.226611 -51.389052) (xy 53.173827 -51.371045)
			(xy 53.124227 -51.345544) (xy 53.078869 -51.313093) (xy 53.03872 -51.274384) (xy 53.004634 -51.230241)
			(xy 52.977338 -51.181606) (xy 52.957415 -51.129515) (xy 52.945289 -51.075078) (xy 52.941218 -51.019456)
			(xy 51.512978 -51.019456) (xy 51.512469 -51.047342) (xy 51.504349 -51.102518) (xy 51.488281 -51.155925)
			(xy 51.464609 -51.206422) (xy 51.433836 -51.252935) (xy 51.396619 -51.294472) (xy 51.353751 -51.330147)
			(xy 51.306145 -51.359201) (xy 51.254816 -51.381013) (xy 51.200859 -51.395119) (xy 51.145422 -51.401219)
			(xy 51.089688 -51.399182) (xy 51.034845 -51.389052) (xy 50.982061 -51.371045) (xy 50.932461 -51.345544)
			(xy 50.887103 -51.313093) (xy 50.846954 -51.274384) (xy 50.812868 -51.230241) (xy 50.785572 -51.181606)
			(xy 50.765649 -51.129515) (xy 50.753523 -51.075078) (xy 50.749452 -51.019456) (xy 34.521926 -51.019456)
			(xy 34.527318 -51.031767) (xy 34.534856 -51.039268) (xy 34.553897 -51.057412) (xy 34.587356 -51.09799)
			(xy 34.614919 -51.142782) (xy 34.636061 -51.19094) (xy 34.650381 -51.241546) (xy 34.657607 -51.293641)
			(xy 34.658046 -51.319938) (xy 34.658046 -51.320192) (xy 34.657515 -51.347441) (xy 34.64976 -51.401385)
			(xy 34.634408 -51.453677) (xy 34.611771 -51.503252) (xy 34.582309 -51.5491) (xy 34.546622 -51.59029)
			(xy 34.505437 -51.625981) (xy 34.459592 -51.655449) (xy 34.41002 -51.678092) (xy 34.35773 -51.693451)
			(xy 34.303787 -51.701212) (xy 34.276538 -51.7017) (xy 34.248874 -51.701158) (xy 34.194126 -51.693164)
			(xy 34.141105 -51.677353) (xy 34.090921 -51.654055) (xy 34.044625 -51.623758) (xy 34.003186 -51.587097)
			(xy 33.967472 -51.544839) (xy 33.952434 -51.521614) (xy 33.95218 -51.52136) (xy 33.945537 -51.511816)
			(xy 33.925826 -51.49952) (xy 33.914334 -51.497738) (xy 33.834324 -51.489864) (xy 33.822623 -51.489223)
			(xy 33.800652 -51.497285) (xy 33.79216 -51.505358) (xy 33.79216 -51.505612) (xy 33.774083 -51.524197)
			(xy 33.73375 -51.556775) (xy 33.689375 -51.583587) (xy 33.641776 -51.604139) (xy 33.591831 -51.618052)
			(xy 33.540461 -51.625069) (xy 33.514538 -51.6255) (xy 33.487286 -51.625009) (xy 33.433335 -51.617257)
			(xy 33.381038 -51.601906) (xy 33.331457 -51.579267) (xy 33.285603 -51.549802) (xy 33.24441 -51.514111)
			(xy 33.208716 -51.472921) (xy 33.179247 -51.427069) (xy 33.156605 -51.377491) (xy 33.141249 -51.325194)
			(xy 33.133493 -51.271244) (xy 33.13303 -51.243992) (xy 30.226499 -51.243992) (xy 30.226328 -51.254736)
			(xy 30.218572 -51.308691) (xy 30.203216 -51.360992) (xy 30.180572 -51.410575) (xy 30.151102 -51.456431)
			(xy 30.115405 -51.497625) (xy 30.074208 -51.533319) (xy 30.028351 -51.562786) (xy 29.978766 -51.585426)
			(xy 29.926463 -51.600778) (xy 29.872509 -51.60853) (xy 29.845254 -51.60899) (xy 29.826911 -51.608753)
			(xy 29.790398 -51.605193) (xy 29.772356 -51.601878) (xy 29.772102 -51.601878) (xy 29.7616 -51.600462)
			(xy 29.740997 -51.60533) (xy 29.732224 -51.611276) (xy 29.662882 -51.6636) (xy 29.652722 -51.682396)
			(xy 29.651706 -51.693318) (xy 29.648761 -51.721569) (xy 29.635731 -51.776851) (xy 29.61465 -51.82959)
			(xy 29.585983 -51.878621) (xy 29.550365 -51.92286) (xy 29.508581 -51.961331) (xy 29.461557 -51.993182)
			(xy 29.41033 -52.01771) (xy 29.356033 -52.034373) (xy 29.348817 -52.035456) (xy 52.941218 -52.035456)
			(xy 52.945289 -51.979834) (xy 52.957415 -51.925397) (xy 52.977338 -51.873306) (xy 53.004634 -51.824671)
			(xy 53.03872 -51.780528) (xy 53.078869 -51.741819) (xy 53.124227 -51.709368) (xy 53.173827 -51.683867)
			(xy 53.226611 -51.66586) (xy 53.281454 -51.65573) (xy 53.337188 -51.653693) (xy 53.392625 -51.659793)
			(xy 53.446582 -51.673899) (xy 53.482241 -51.689052) (xy 54.255377 -51.689052) (xy 54.255377 -51.634548)
			(xy 54.263134 -51.580599) (xy 54.27849 -51.528303) (xy 54.301133 -51.478724) (xy 54.3306 -51.432873)
			(xy 54.366294 -51.391682) (xy 54.407486 -51.355991) (xy 54.453338 -51.326525) (xy 54.502918 -51.303885)
			(xy 54.555214 -51.288531) (xy 54.609164 -51.280776) (xy 54.636416 -51.280314) (xy 54.663787 -51.280767)
			(xy 54.717966 -51.288588) (xy 54.77047 -51.30408) (xy 54.820217 -51.326924) (xy 54.866183 -51.356651)
			(xy 54.887114 -51.374294) (xy 54.887368 -51.374548) (xy 54.894455 -51.380133) (xy 54.911372 -51.386379)
			(xy 54.920388 -51.38674) (xy 54.987444 -51.38674) (xy 54.99646 -51.386369) (xy 55.013378 -51.380133)
			(xy 55.020464 -51.374548) (xy 55.020972 -51.37404) (xy 55.041903 -51.356453) (xy 55.087838 -51.326813)
			(xy 55.137534 -51.304035) (xy 55.189974 -51.288586) (xy 55.244082 -51.280782) (xy 55.271416 -51.280314)
			(xy 55.289759 -51.280541) (xy 55.326272 -51.284108) (xy 55.344314 -51.287426) (xy 55.344568 -51.287426)
			(xy 55.355071 -51.288824) (xy 55.375672 -51.283968) (xy 55.384446 -51.278028) (xy 55.453788 -51.225704)
			(xy 55.463948 -51.206908) (xy 55.464964 -51.195986) (xy 55.467849 -51.167701) (xy 55.480888 -51.112363)
			(xy 55.501986 -51.059569) (xy 55.530677 -51.010486) (xy 55.566327 -50.966199) (xy 55.586884 -50.946558)
			(xy 55.59434 -50.938999) (xy 55.602857 -50.919572) (xy 55.603394 -50.908966) (xy 55.603394 -50.834798)
			(xy 55.602979 -50.824167) (xy 55.594434 -50.804702) (xy 55.586884 -50.797206) (xy 55.567819 -50.779087)
			(xy 55.534364 -50.738502) (xy 55.506806 -50.693704) (xy 55.485669 -50.645542) (xy 55.471353 -50.594932)
			(xy 55.464131 -50.542834) (xy 55.463694 -50.516536) (xy 55.463694 -50.516282) (xy 55.46418 -50.489031)
			(xy 55.471936 -50.435083) (xy 55.487291 -50.382788) (xy 55.509933 -50.333211) (xy 55.539399 -50.287361)
			(xy 55.57509 -50.24617) (xy 55.616281 -50.210479) (xy 55.662131 -50.181013) (xy 55.711708 -50.158371)
			(xy 55.764003 -50.143016) (xy 55.817951 -50.13526) (xy 55.872453 -50.13526) (xy 55.926401 -50.143016)
			(xy 55.978696 -50.158371) (xy 56.028273 -50.181013) (xy 56.074123 -50.210479) (xy 56.115314 -50.24617)
			(xy 56.151005 -50.287361) (xy 56.180471 -50.333211) (xy 56.203113 -50.382788) (xy 56.218468 -50.435083)
			(xy 56.226224 -50.489031) (xy 56.22671 -50.516282) (xy 56.22671 -50.516536) (xy 56.226272 -50.542832)
			(xy 56.219022 -50.594921) (xy 56.204692 -50.645523) (xy 56.183552 -50.693679) (xy 56.156004 -50.738478)
			(xy 56.122568 -50.779072) (xy 56.10352 -50.797206) (xy 56.09608 -50.804779) (xy 56.087554 -50.824196)
			(xy 56.08701 -50.834798) (xy 56.08701 -50.908966) (xy 56.087389 -50.919602) (xy 56.095959 -50.939066)
			(xy 56.10352 -50.946558) (xy 56.122568 -50.964694) (xy 56.156024 -51.005275) (xy 56.183584 -51.05007)
			(xy 56.204725 -51.098228) (xy 56.219044 -51.148836) (xy 56.22627 -51.200931) (xy 56.22671 -51.227228)
			(xy 56.22671 -51.227482) (xy 56.226418 -51.243992) (xy 59.132978 -51.243992) (xy 59.13348 -51.21666)
			(xy 59.141281 -51.162554) (xy 59.156724 -51.110116) (xy 59.179492 -51.060417) (xy 59.209118 -51.014477)
			(xy 59.226704 -50.993548) (xy 59.226958 -50.993294) (xy 59.227212 -50.99304) (xy 59.232789 -50.985947)
			(xy 59.239041 -50.969035) (xy 59.239404 -50.96002) (xy 59.239404 -50.892964) (xy 59.239063 -50.883946)
			(xy 59.232804 -50.867029) (xy 59.227212 -50.859944) (xy 59.226958 -50.85969) (xy 59.226704 -50.859436)
			(xy 59.209116 -50.838507) (xy 59.179477 -50.792571) (xy 59.156699 -50.742874) (xy 59.141251 -50.690434)
			(xy 59.133447 -50.636326) (xy 59.132978 -50.608992) (xy 59.13347 -50.581741) (xy 59.141228 -50.527794)
			(xy 59.156583 -50.475501) (xy 59.179224 -50.425924) (xy 59.20869 -50.380075) (xy 59.244381 -50.338885)
			(xy 59.28557 -50.303193) (xy 59.331419 -50.273727) (xy 59.380995 -50.251085) (xy 59.433289 -50.235729)
			(xy 59.487235 -50.227971) (xy 59.514486 -50.227484) (xy 59.543404 -50.22798) (xy 59.600578 -50.236709)
			(xy 59.655778 -50.25397) (xy 59.707741 -50.279365) (xy 59.755274 -50.312314) (xy 59.797288 -50.352061)
			(xy 59.815476 -50.37455) (xy 59.821769 -50.381926) (xy 59.838476 -50.391727) (xy 59.847988 -50.3936)
			(xy 59.855608 -50.394108) (xy 59.935364 -50.394108) (xy 59.942984 -50.3936) (xy 59.952503 -50.391749)
			(xy 59.969215 -50.38194) (xy 59.975496 -50.37455) (xy 59.993677 -50.352058) (xy 60.0357 -50.312326)
			(xy 60.083238 -50.279389) (xy 60.135201 -50.254003) (xy 60.190399 -50.236748) (xy 60.24757 -50.228019)
			(xy 60.276486 -50.227484) (xy 60.303738 -50.227968) (xy 60.357688 -50.235723) (xy 60.409985 -50.251077)
			(xy 60.459564 -50.273717) (xy 60.505417 -50.303183) (xy 60.54661 -50.338875) (xy 60.582304 -50.380065)
			(xy 60.611772 -50.425916) (xy 60.634415 -50.475495) (xy 60.649772 -50.527791) (xy 60.65753 -50.58174)
			(xy 60.657994 -50.608992) (xy 60.657994 -50.609246) (xy 60.657568 -50.635542) (xy 60.650316 -50.687632)
			(xy 60.635984 -50.738234) (xy 60.614842 -50.78639) (xy 60.587292 -50.831189) (xy 60.553853 -50.871783)
			(xy 60.534804 -50.889916) (xy 60.527358 -50.897483) (xy 60.518835 -50.916905) (xy 60.518294 -50.927508)
			(xy 60.518294 -51.001676) (xy 60.518727 -51.012305) (xy 60.521862 -51.019456) (xy 76.7494 -51.019456)
			(xy 76.753471 -50.963834) (xy 76.765597 -50.909397) (xy 76.78552 -50.857306) (xy 76.812816 -50.808671)
			(xy 76.846902 -50.764528) (xy 76.887051 -50.725819) (xy 76.932409 -50.693368) (xy 76.982009 -50.667867)
			(xy 77.034793 -50.64986) (xy 77.089636 -50.63973) (xy 77.14537 -50.637693) (xy 77.200807 -50.643793)
			(xy 77.254764 -50.657899) (xy 77.306093 -50.679711) (xy 77.353699 -50.708765) (xy 77.396567 -50.74444)
			(xy 77.433784 -50.785977) (xy 77.464557 -50.83249) (xy 77.488229 -50.882987) (xy 77.504297 -50.936394)
			(xy 77.512417 -50.99157) (xy 77.512926 -51.019456) (xy 78.941166 -51.019456) (xy 78.945237 -50.963834)
			(xy 78.957363 -50.909397) (xy 78.977286 -50.857306) (xy 79.004582 -50.808671) (xy 79.038668 -50.764528)
			(xy 79.078817 -50.725819) (xy 79.124175 -50.693368) (xy 79.173775 -50.667867) (xy 79.226559 -50.64986)
			(xy 79.281402 -50.63973) (xy 79.337136 -50.637693) (xy 79.392573 -50.643793) (xy 79.44653 -50.657899)
			(xy 79.497859 -50.679711) (xy 79.545465 -50.708765) (xy 79.588333 -50.74444) (xy 79.62555 -50.785977)
			(xy 79.656323 -50.83249) (xy 79.679995 -50.882987) (xy 79.696063 -50.936394) (xy 79.704183 -50.99157)
			(xy 79.704692 -51.019456) (xy 79.704183 -51.047342) (xy 79.696063 -51.102518) (xy 79.679995 -51.155925)
			(xy 79.656323 -51.206422) (xy 79.62555 -51.252935) (xy 79.588333 -51.294472) (xy 79.545465 -51.330147)
			(xy 79.497859 -51.359201) (xy 79.44653 -51.381013) (xy 79.392573 -51.395119) (xy 79.337136 -51.401219)
			(xy 79.281402 -51.399182) (xy 79.226559 -51.389052) (xy 79.173775 -51.371045) (xy 79.124175 -51.345544)
			(xy 79.078817 -51.313093) (xy 79.038668 -51.274384) (xy 79.004582 -51.230241) (xy 78.977286 -51.181606)
			(xy 78.957363 -51.129515) (xy 78.945237 -51.075078) (xy 78.941166 -51.019456) (xy 77.512926 -51.019456)
			(xy 77.512417 -51.047342) (xy 77.504297 -51.102518) (xy 77.488229 -51.155925) (xy 77.464557 -51.206422)
			(xy 77.433784 -51.252935) (xy 77.396567 -51.294472) (xy 77.353699 -51.330147) (xy 77.306093 -51.359201)
			(xy 77.254764 -51.381013) (xy 77.200807 -51.395119) (xy 77.14537 -51.401219) (xy 77.089636 -51.399182)
			(xy 77.034793 -51.389052) (xy 76.982009 -51.371045) (xy 76.932409 -51.345544) (xy 76.887051 -51.313093)
			(xy 76.846902 -51.274384) (xy 76.812816 -51.230241) (xy 76.78552 -51.181606) (xy 76.765597 -51.129515)
			(xy 76.753471 -51.075078) (xy 76.7494 -51.019456) (xy 60.521862 -51.019456) (xy 60.52726 -51.03177)
			(xy 60.534804 -51.039268) (xy 60.553854 -51.057402) (xy 60.587311 -51.097983) (xy 60.614871 -51.142778)
			(xy 60.636011 -51.190937) (xy 60.65033 -51.241545) (xy 60.657555 -51.293641) (xy 60.657994 -51.319938)
			(xy 60.657994 -51.320192) (xy 60.657537 -51.347445) (xy 60.649781 -51.401397) (xy 60.634425 -51.453696)
			(xy 60.611783 -51.503277) (xy 60.582314 -51.549131) (xy 60.54662 -51.590324) (xy 60.505426 -51.626018)
			(xy 60.459572 -51.655486) (xy 60.40999 -51.678127) (xy 60.357691 -51.693482) (xy 60.303739 -51.701238)
			(xy 60.276486 -51.7017) (xy 60.248821 -51.701199) (xy 60.194071 -51.693198) (xy 60.141049 -51.677379)
			(xy 60.090865 -51.654074) (xy 60.044569 -51.623771) (xy 60.003131 -51.587105) (xy 59.967419 -51.544842)
			(xy 59.952382 -51.521614) (xy 59.952128 -51.52136) (xy 59.945509 -51.511795) (xy 59.92578 -51.49951)
			(xy 59.914282 -51.497738) (xy 59.834272 -51.489864) (xy 59.822571 -51.48919) (xy 59.800597 -51.497275)
			(xy 59.792108 -51.505358) (xy 59.792108 -51.505612) (xy 59.774008 -51.524174) (xy 59.73368 -51.556754)
			(xy 59.68931 -51.583569) (xy 59.641715 -51.604125) (xy 59.591774 -51.618043) (xy 59.540408 -51.625065)
			(xy 59.514486 -51.6255) (xy 59.487234 -51.625035) (xy 59.433285 -51.617277) (xy 59.38099 -51.601919)
			(xy 59.331412 -51.579276) (xy 59.285561 -51.549807) (xy 59.244371 -51.514114) (xy 59.208679 -51.472921)
			(xy 59.179214 -51.427069) (xy 59.156573 -51.37749) (xy 59.141219 -51.325193) (xy 59.133463 -51.271244)
			(xy 59.132978 -51.243992) (xy 56.226418 -51.243992) (xy 56.226228 -51.254734) (xy 56.218473 -51.308684)
			(xy 56.20312 -51.360982) (xy 56.18048 -51.410562) (xy 56.151014 -51.456415) (xy 56.115322 -51.497608)
			(xy 56.074131 -51.533302) (xy 56.028279 -51.56277) (xy 55.978701 -51.585413) (xy 55.926404 -51.600769)
			(xy 55.872454 -51.608527) (xy 55.845202 -51.60899) (xy 55.826859 -51.608761) (xy 55.790346 -51.605196)
			(xy 55.772304 -51.601878) (xy 55.77205 -51.601878) (xy 55.761546 -51.60049) (xy 55.740947 -51.605339)
			(xy 55.732172 -51.611276) (xy 55.66283 -51.6636) (xy 55.65267 -51.682396) (xy 55.651654 -51.693318)
			(xy 55.64876 -51.721576) (xy 55.635727 -51.776862) (xy 55.614642 -51.829604) (xy 55.585971 -51.878638)
			(xy 55.550347 -51.922879) (xy 55.508557 -51.96135) (xy 55.461526 -51.9932) (xy 55.410293 -52.017725)
			(xy 55.355989 -52.034383) (xy 55.348834 -52.035456) (xy 78.941166 -52.035456) (xy 78.945237 -51.979834)
			(xy 78.957363 -51.925397) (xy 78.977286 -51.873306) (xy 79.004582 -51.824671) (xy 79.038668 -51.780528)
			(xy 79.078817 -51.741819) (xy 79.124175 -51.709368) (xy 79.173775 -51.683867) (xy 79.226559 -51.66586)
			(xy 79.281402 -51.65573) (xy 79.337136 -51.653693) (xy 79.392573 -51.659793) (xy 79.44653 -51.673899)
			(xy 79.482179 -51.689048) (xy 80.2554 -51.689048) (xy 80.2554 -51.634552) (xy 80.263155 -51.580611)
			(xy 80.278508 -51.528322) (xy 80.301145 -51.47875) (xy 80.330606 -51.432904) (xy 80.366292 -51.391717)
			(xy 80.407475 -51.356028) (xy 80.453318 -51.326562) (xy 80.502888 -51.30392) (xy 80.555175 -51.288563)
			(xy 80.609116 -51.280803) (xy 80.636364 -51.280314) (xy 80.663734 -51.280798) (xy 80.717912 -51.288611)
			(xy 80.770415 -51.304096) (xy 80.820162 -51.326933) (xy 80.86613 -51.356654) (xy 80.887062 -51.374294)
			(xy 80.887316 -51.374548) (xy 80.89439 -51.380153) (xy 80.911317 -51.386388) (xy 80.920336 -51.38674)
			(xy 80.987392 -51.38674) (xy 80.99641 -51.386392) (xy 81.013328 -51.38014) (xy 81.020412 -51.374548)
			(xy 81.02092 -51.37404) (xy 81.041832 -51.356431) (xy 81.087772 -51.326794) (xy 81.137474 -51.30402)
			(xy 81.189917 -51.288576) (xy 81.244029 -51.280779) (xy 81.271364 -51.280314) (xy 81.289707 -51.280548)
			(xy 81.32622 -51.28411) (xy 81.344262 -51.287426) (xy 81.344516 -51.287426) (xy 81.355017 -51.288852)
			(xy 81.375621 -51.283977) (xy 81.384394 -51.278028) (xy 81.453736 -51.225704) (xy 81.463896 -51.206908)
			(xy 81.464912 -51.195986) (xy 81.467813 -51.167703) (xy 81.48085 -51.112366) (xy 81.501945 -51.059573)
			(xy 81.530632 -51.010489) (xy 81.566277 -50.9662) (xy 81.586832 -50.946558) (xy 81.594281 -50.938992)
			(xy 81.602804 -50.91957) (xy 81.603342 -50.908966) (xy 81.603342 -50.834798) (xy 81.602913 -50.824169)
			(xy 81.594376 -50.804705) (xy 81.586832 -50.797206) (xy 81.567776 -50.779077) (xy 81.534319 -50.738496)
			(xy 81.506758 -50.6937) (xy 81.485619 -50.64554) (xy 81.471302 -50.594931) (xy 81.464079 -50.542834)
			(xy 81.463642 -50.516536) (xy 81.463642 -50.516282) (xy 81.464128 -50.489031) (xy 81.471884 -50.435083)
			(xy 81.487239 -50.382788) (xy 81.509881 -50.333211) (xy 81.539347 -50.287361) (xy 81.575038 -50.24617)
			(xy 81.616229 -50.210479) (xy 81.662079 -50.181013) (xy 81.711656 -50.158371) (xy 81.763951 -50.143016)
			(xy 81.817899 -50.13526) (xy 81.872401 -50.13526) (xy 81.926349 -50.143016) (xy 81.978644 -50.158371)
			(xy 82.028221 -50.181013) (xy 82.074071 -50.210479) (xy 82.115262 -50.24617) (xy 82.150953 -50.287361)
			(xy 82.180419 -50.333211) (xy 82.203061 -50.382788) (xy 82.218416 -50.435083) (xy 82.226172 -50.489031)
			(xy 82.226658 -50.516282) (xy 82.226658 -50.516536) (xy 82.226237 -50.542832) (xy 82.218986 -50.594923)
			(xy 82.204653 -50.645526) (xy 82.183511 -50.693682) (xy 82.155959 -50.738481) (xy 82.122518 -50.779073)
			(xy 82.103468 -50.797206) (xy 82.096035 -50.804785) (xy 82.087503 -50.824197) (xy 82.086958 -50.834798)
			(xy 82.086958 -50.908966) (xy 82.087352 -50.919599) (xy 82.095913 -50.939063) (xy 82.103468 -50.946558)
			(xy 82.122506 -50.964704) (xy 82.155965 -51.005282) (xy 82.183528 -51.050074) (xy 82.20467 -51.098231)
			(xy 82.218991 -51.148837) (xy 82.226218 -51.200931) (xy 82.226658 -51.227228) (xy 82.226658 -51.227482)
			(xy 82.226398 -51.243992) (xy 85.132926 -51.243992) (xy 85.133416 -51.216659) (xy 85.141219 -51.162553)
			(xy 85.156664 -51.110114) (xy 85.179434 -51.060416) (xy 85.209064 -51.014476) (xy 85.226652 -50.993548)
			(xy 85.226906 -50.993294) (xy 85.22716 -50.99304) (xy 85.232743 -50.985951) (xy 85.23899 -50.969036)
			(xy 85.239352 -50.96002) (xy 85.239352 -50.892964) (xy 85.239023 -50.883944) (xy 85.232757 -50.867027)
			(xy 85.22716 -50.859944) (xy 85.226906 -50.85969) (xy 85.226652 -50.859436) (xy 85.209056 -50.838514)
			(xy 85.179419 -50.792575) (xy 85.156645 -50.742876) (xy 85.141198 -50.690435) (xy 85.133395 -50.636326)
			(xy 85.132926 -50.608992) (xy 85.133348 -50.581737) (xy 85.141107 -50.527783) (xy 85.156466 -50.475483)
			(xy 85.179112 -50.4259) (xy 85.208584 -50.380045) (xy 85.244282 -50.338852) (xy 85.285479 -50.303158)
			(xy 85.331337 -50.273691) (xy 85.380922 -50.251051) (xy 85.433224 -50.235698) (xy 85.487179 -50.227945)
			(xy 85.514434 -50.227484) (xy 85.543351 -50.228018) (xy 85.600523 -50.236739) (xy 85.655722 -50.253992)
			(xy 85.707685 -50.279381) (xy 85.755219 -50.312323) (xy 85.797235 -50.352064) (xy 85.815424 -50.37455)
			(xy 85.8217 -50.381943) (xy 85.838419 -50.391735) (xy 85.847936 -50.3936) (xy 85.855556 -50.394108)
			(xy 85.935312 -50.394108) (xy 85.942932 -50.3936) (xy 85.952445 -50.391726) (xy 85.96916 -50.381934)
			(xy 85.975444 -50.37455) (xy 85.993598 -50.352035) (xy 86.035627 -50.312304) (xy 86.08317 -50.27937)
			(xy 86.135138 -50.253988) (xy 86.190342 -50.236738) (xy 86.247516 -50.228016) (xy 86.276434 -50.227484)
			(xy 86.303686 -50.227946) (xy 86.357634 -50.235707) (xy 86.409929 -50.251066) (xy 86.459505 -50.273711)
			(xy 86.505355 -50.30318) (xy 86.546545 -50.338874) (xy 86.582236 -50.380066) (xy 86.611702 -50.425917)
			(xy 86.634343 -50.475496) (xy 86.649698 -50.527792) (xy 86.657456 -50.58174) (xy 86.657942 -50.608992)
			(xy 86.657942 -50.609246) (xy 86.6575 -50.635541) (xy 86.65025 -50.68763) (xy 86.635919 -50.738231)
			(xy 86.614781 -50.786387) (xy 86.587233 -50.831186) (xy 86.553799 -50.871781) (xy 86.534752 -50.889916)
			(xy 86.527313 -50.89749) (xy 86.518785 -50.916906) (xy 86.518242 -50.927508) (xy 86.518242 -51.001676)
			(xy 86.51869 -51.012303) (xy 86.521823 -51.019456) (xy 102.749348 -51.019456) (xy 102.753419 -50.963834)
			(xy 102.765545 -50.909397) (xy 102.785468 -50.857306) (xy 102.812764 -50.808671) (xy 102.84685 -50.764528)
			(xy 102.886999 -50.725819) (xy 102.932357 -50.693368) (xy 102.981957 -50.667867) (xy 103.034741 -50.64986)
			(xy 103.089584 -50.63973) (xy 103.145318 -50.637693) (xy 103.200755 -50.643793) (xy 103.254712 -50.657899)
			(xy 103.306041 -50.679711) (xy 103.353647 -50.708765) (xy 103.396515 -50.74444) (xy 103.433732 -50.785977)
			(xy 103.464505 -50.83249) (xy 103.488177 -50.882987) (xy 103.504245 -50.936394) (xy 103.512365 -50.99157)
			(xy 103.512874 -51.019456) (xy 104.941114 -51.019456) (xy 104.945185 -50.963834) (xy 104.957311 -50.909397)
			(xy 104.977234 -50.857306) (xy 105.00453 -50.808671) (xy 105.038616 -50.764528) (xy 105.078765 -50.725819)
			(xy 105.124123 -50.693368) (xy 105.173723 -50.667867) (xy 105.226507 -50.64986) (xy 105.28135 -50.63973)
			(xy 105.337084 -50.637693) (xy 105.392521 -50.643793) (xy 105.446478 -50.657899) (xy 105.497807 -50.679711)
			(xy 105.545413 -50.708765) (xy 105.588281 -50.74444) (xy 105.625498 -50.785977) (xy 105.656271 -50.83249)
			(xy 105.679943 -50.882987) (xy 105.696011 -50.936394) (xy 105.704131 -50.99157) (xy 105.70464 -51.019456)
			(xy 105.704131 -51.047342) (xy 105.696011 -51.102518) (xy 105.679943 -51.155925) (xy 105.656271 -51.206422)
			(xy 105.625498 -51.252935) (xy 105.588281 -51.294472) (xy 105.545413 -51.330147) (xy 105.497807 -51.359201)
			(xy 105.446478 -51.381013) (xy 105.392521 -51.395119) (xy 105.337084 -51.401219) (xy 105.28135 -51.399182)
			(xy 105.226507 -51.389052) (xy 105.173723 -51.371045) (xy 105.124123 -51.345544) (xy 105.078765 -51.313093)
			(xy 105.038616 -51.274384) (xy 105.00453 -51.230241) (xy 104.977234 -51.181606) (xy 104.957311 -51.129515)
			(xy 104.945185 -51.075078) (xy 104.941114 -51.019456) (xy 103.512874 -51.019456) (xy 103.512365 -51.047342)
			(xy 103.504245 -51.102518) (xy 103.488177 -51.155925) (xy 103.464505 -51.206422) (xy 103.433732 -51.252935)
			(xy 103.396515 -51.294472) (xy 103.353647 -51.330147) (xy 103.306041 -51.359201) (xy 103.254712 -51.381013)
			(xy 103.200755 -51.395119) (xy 103.145318 -51.401219) (xy 103.089584 -51.399182) (xy 103.034741 -51.389052)
			(xy 102.981957 -51.371045) (xy 102.932357 -51.345544) (xy 102.886999 -51.313093) (xy 102.84685 -51.274384)
			(xy 102.812764 -51.230241) (xy 102.785468 -51.181606) (xy 102.765545 -51.129515) (xy 102.753419 -51.075078)
			(xy 102.749348 -51.019456) (xy 86.521823 -51.019456) (xy 86.527214 -51.031767) (xy 86.534752 -51.039268)
			(xy 86.553792 -51.057413) (xy 86.587252 -51.09799) (xy 86.614814 -51.142783) (xy 86.635957 -51.19094)
			(xy 86.650277 -51.241546) (xy 86.657503 -51.293641) (xy 86.657942 -51.319938) (xy 86.657942 -51.320192)
			(xy 86.657415 -51.347442) (xy 86.64966 -51.401386) (xy 86.634308 -51.453678) (xy 86.61167 -51.503253)
			(xy 86.582208 -51.549102) (xy 86.546521 -51.590291) (xy 86.505335 -51.625983) (xy 86.45949 -51.65545)
			(xy 86.409917 -51.678093) (xy 86.357627 -51.693451) (xy 86.303683 -51.701212) (xy 86.276434 -51.7017)
			(xy 86.24877 -51.701161) (xy 86.194022 -51.693167) (xy 86.141001 -51.677355) (xy 86.090817 -51.654056)
			(xy 86.044521 -51.623759) (xy 86.003082 -51.587097) (xy 85.967368 -51.544839) (xy 85.95233 -51.521614)
			(xy 85.952076 -51.52136) (xy 85.945435 -51.511814) (xy 85.925722 -51.499519) (xy 85.91423 -51.497738)
			(xy 85.83422 -51.489864) (xy 85.822519 -51.489221) (xy 85.800548 -51.497284) (xy 85.792056 -51.505358)
			(xy 85.792056 -51.505612) (xy 85.773981 -51.524199) (xy 85.733647 -51.556776) (xy 85.689272 -51.583588)
			(xy 85.641672 -51.60414) (xy 85.591727 -51.618052) (xy 85.540357 -51.625069) (xy 85.514434 -51.6255)
			(xy 85.487182 -51.625013) (xy 85.433231 -51.61726) (xy 85.380933 -51.601908) (xy 85.331353 -51.579269)
			(xy 85.285499 -51.549804) (xy 85.244306 -51.514113) (xy 85.208612 -51.472922) (xy 85.179143 -51.42707)
			(xy 85.156501 -51.377491) (xy 85.141145 -51.325194) (xy 85.133389 -51.271244) (xy 85.132926 -51.243992)
			(xy 82.226398 -51.243992) (xy 82.226228 -51.254737) (xy 82.218472 -51.308691) (xy 82.203116 -51.360993)
			(xy 82.180472 -51.410576) (xy 82.151001 -51.456432) (xy 82.115303 -51.497626) (xy 82.074106 -51.53332)
			(xy 82.028248 -51.562787) (xy 81.978663 -51.585427) (xy 81.92636 -51.600779) (xy 81.872405 -51.60853)
			(xy 81.84515 -51.60899) (xy 81.826807 -51.608754) (xy 81.790294 -51.605193) (xy 81.772252 -51.601878)
			(xy 81.771998 -51.601878) (xy 81.761496 -51.60046) (xy 81.740893 -51.605329) (xy 81.73212 -51.611276)
			(xy 81.662778 -51.6636) (xy 81.652618 -51.682396) (xy 81.651602 -51.693318) (xy 81.648661 -51.72157)
			(xy 81.635631 -51.776852) (xy 81.614549 -51.829591) (xy 81.585882 -51.878622) (xy 81.550263 -51.922862)
			(xy 81.50848 -51.961332) (xy 81.461454 -51.993183) (xy 81.410227 -52.017711) (xy 81.35593 -52.034374)
			(xy 81.34872 -52.035456) (xy 104.941114 -52.035456) (xy 104.945185 -51.979834) (xy 104.957311 -51.925397)
			(xy 104.977234 -51.873306) (xy 105.00453 -51.824671) (xy 105.038616 -51.780528) (xy 105.078765 -51.741819)
			(xy 105.124123 -51.709368) (xy 105.173723 -51.683867) (xy 105.226507 -51.66586) (xy 105.28135 -51.65573)
			(xy 105.337084 -51.653693) (xy 105.392521 -51.659793) (xy 105.446478 -51.673899) (xy 105.482137 -51.689052)
			(xy 118.355577 -51.689052) (xy 118.355577 -51.634548) (xy 118.363334 -51.580599) (xy 118.37869 -51.528302)
			(xy 118.401333 -51.478724) (xy 118.430801 -51.432872) (xy 118.466494 -51.391682) (xy 118.507687 -51.35599)
			(xy 118.55354 -51.326524) (xy 118.603119 -51.303884) (xy 118.655416 -51.28853) (xy 118.709366 -51.280776)
			(xy 118.736618 -51.280314) (xy 118.763989 -51.280766) (xy 118.818169 -51.288587) (xy 118.870672 -51.304079)
			(xy 118.920419 -51.326924) (xy 118.966385 -51.356651) (xy 118.987316 -51.374294) (xy 118.98757 -51.374548)
			(xy 118.994657 -51.380134) (xy 119.011574 -51.38638) (xy 119.02059 -51.38674) (xy 119.087646 -51.38674)
			(xy 119.096662 -51.38637) (xy 119.11358 -51.380133) (xy 119.120666 -51.374548) (xy 119.121174 -51.37404)
			(xy 119.142104 -51.356452) (xy 119.188039 -51.326812) (xy 119.237736 -51.304034) (xy 119.290176 -51.288585)
			(xy 119.344284 -51.280782) (xy 119.371618 -51.280314) (xy 119.389961 -51.280555) (xy 119.426474 -51.284112)
			(xy 119.444516 -51.287426) (xy 119.44477 -51.287426) (xy 119.455273 -51.288825) (xy 119.475874 -51.283969)
			(xy 119.484648 -51.278028) (xy 119.55399 -51.225704) (xy 119.56415 -51.206908) (xy 119.565166 -51.195986)
			(xy 119.56805 -51.167701) (xy 119.581089 -51.112363) (xy 119.602187 -51.059569) (xy 119.630878 -51.010486)
			(xy 119.666529 -50.966199) (xy 119.687086 -50.946558) (xy 119.694543 -50.938999) (xy 119.703059 -50.919572)
			(xy 119.703596 -50.908966) (xy 119.703596 -50.834798) (xy 119.70318 -50.824167) (xy 119.694636 -50.804702)
			(xy 119.687086 -50.797206) (xy 119.668022 -50.779086) (xy 119.634566 -50.738502) (xy 119.607008 -50.693704)
			(xy 119.585871 -50.645542) (xy 119.571555 -50.594932) (xy 119.564333 -50.542834) (xy 119.563896 -50.516536)
			(xy 119.563896 -50.516282) (xy 119.564382 -50.489031) (xy 119.572138 -50.435083) (xy 119.587493 -50.382788)
			(xy 119.610135 -50.333211) (xy 119.639601 -50.287361) (xy 119.675292 -50.24617) (xy 119.716483 -50.210479)
			(xy 119.762333 -50.181013) (xy 119.81191 -50.158371) (xy 119.864205 -50.143016) (xy 119.918153 -50.13526)
			(xy 119.972655 -50.13526) (xy 120.026603 -50.143016) (xy 120.078898 -50.158371) (xy 120.128475 -50.181013)
			(xy 120.174325 -50.210479) (xy 120.215516 -50.24617) (xy 120.251207 -50.287361) (xy 120.280673 -50.333211)
			(xy 120.303315 -50.382788) (xy 120.31867 -50.435083) (xy 120.326426 -50.489031) (xy 120.326912 -50.516282)
			(xy 120.326912 -50.516536) (xy 120.326473 -50.542831) (xy 120.319223 -50.594921) (xy 120.304893 -50.645522)
			(xy 120.283754 -50.693678) (xy 120.256206 -50.738478) (xy 120.22277 -50.779072) (xy 120.203722 -50.797206)
			(xy 120.196283 -50.804779) (xy 120.187756 -50.824196) (xy 120.187212 -50.834798) (xy 120.187212 -50.908966)
			(xy 120.18759 -50.919602) (xy 120.196161 -50.939066) (xy 120.203722 -50.946558) (xy 120.222771 -50.964694)
			(xy 120.256227 -51.005275) (xy 120.283787 -51.05007) (xy 120.304927 -51.098228) (xy 120.319246 -51.148836)
			(xy 120.326472 -51.200931) (xy 120.326912 -51.227228) (xy 120.326912 -51.227482) (xy 120.326619 -51.243992)
			(xy 123.23318 -51.243992) (xy 123.233681 -51.216659) (xy 123.241483 -51.162554) (xy 123.256926 -51.110116)
			(xy 123.279693 -51.060417) (xy 123.30932 -51.014477) (xy 123.326906 -50.993548) (xy 123.32716 -50.993294)
			(xy 123.327414 -50.99304) (xy 123.332992 -50.985947) (xy 123.339243 -50.969035) (xy 123.339606 -50.96002)
			(xy 123.339606 -50.892964) (xy 123.339265 -50.883946) (xy 123.333006 -50.867029) (xy 123.327414 -50.859944)
			(xy 123.32716 -50.85969) (xy 123.326906 -50.859436) (xy 123.309318 -50.838507) (xy 123.279679 -50.792571)
			(xy 123.256901 -50.742874) (xy 123.241453 -50.690434) (xy 123.233649 -50.636326) (xy 123.23318 -50.608992)
			(xy 123.23367 -50.581741) (xy 123.241428 -50.527794) (xy 123.256783 -50.4755) (xy 123.279424 -50.425924)
			(xy 123.30889 -50.380074) (xy 123.344581 -50.338884) (xy 123.385771 -50.303193) (xy 123.43162 -50.273726)
			(xy 123.481196 -50.251085) (xy 123.53349 -50.235728) (xy 123.587437 -50.227971) (xy 123.614688 -50.227484)
			(xy 123.643606 -50.227979) (xy 123.70078 -50.236708) (xy 123.755981 -50.253969) (xy 123.807943 -50.279365)
			(xy 123.855476 -50.312314) (xy 123.89749 -50.352061) (xy 123.915678 -50.37455) (xy 123.92197 -50.381926)
			(xy 123.938678 -50.391728) (xy 123.94819 -50.3936) (xy 123.95581 -50.394108) (xy 124.035566 -50.394108)
			(xy 124.043186 -50.3936) (xy 124.052705 -50.391751) (xy 124.069418 -50.381941) (xy 124.075698 -50.37455)
			(xy 124.093877 -50.352057) (xy 124.135901 -50.312325) (xy 124.183439 -50.279388) (xy 124.235402 -50.254002)
			(xy 124.290601 -50.236747) (xy 124.347772 -50.228019) (xy 124.376688 -50.227484) (xy 124.40394 -50.227966)
			(xy 124.45789 -50.235722) (xy 124.510187 -50.251076) (xy 124.559767 -50.273716) (xy 124.605619 -50.303182)
			(xy 124.646812 -50.338874) (xy 124.682506 -50.380065) (xy 124.711974 -50.425916) (xy 124.734617 -50.475494)
			(xy 124.749974 -50.52779) (xy 124.757732 -50.58174) (xy 124.758196 -50.608992) (xy 124.758196 -50.609246)
			(xy 124.757769 -50.635542) (xy 124.750518 -50.687632) (xy 124.736185 -50.738234) (xy 124.715044 -50.78639)
			(xy 124.687493 -50.831189) (xy 124.654055 -50.871783) (xy 124.635006 -50.889916) (xy 124.62756 -50.897483)
			(xy 124.619037 -50.916905) (xy 124.618496 -50.927508) (xy 124.618496 -51.001676) (xy 124.618928 -51.012305)
			(xy 124.622063 -51.019456) (xy 140.849602 -51.019456) (xy 140.853673 -50.963834) (xy 140.865799 -50.909397)
			(xy 140.885722 -50.857306) (xy 140.913018 -50.808671) (xy 140.947104 -50.764528) (xy 140.987253 -50.725819)
			(xy 141.032611 -50.693368) (xy 141.082211 -50.667867) (xy 141.134995 -50.64986) (xy 141.189838 -50.63973)
			(xy 141.245572 -50.637693) (xy 141.301009 -50.643793) (xy 141.354966 -50.657899) (xy 141.406295 -50.679711)
			(xy 141.453901 -50.708765) (xy 141.496769 -50.74444) (xy 141.533986 -50.785977) (xy 141.564759 -50.83249)
			(xy 141.588431 -50.882987) (xy 141.604499 -50.936394) (xy 141.612619 -50.99157) (xy 141.613128 -51.019456)
			(xy 143.041368 -51.019456) (xy 143.045439 -50.963834) (xy 143.057565 -50.909397) (xy 143.077488 -50.857306)
			(xy 143.104784 -50.808671) (xy 143.13887 -50.764528) (xy 143.179019 -50.725819) (xy 143.224377 -50.693368)
			(xy 143.273977 -50.667867) (xy 143.326761 -50.64986) (xy 143.381604 -50.63973) (xy 143.437338 -50.637693)
			(xy 143.492775 -50.643793) (xy 143.546732 -50.657899) (xy 143.598061 -50.679711) (xy 143.645667 -50.708765)
			(xy 143.688535 -50.74444) (xy 143.725752 -50.785977) (xy 143.756525 -50.83249) (xy 143.780197 -50.882987)
			(xy 143.796265 -50.936394) (xy 143.804385 -50.99157) (xy 143.804894 -51.019456) (xy 143.804385 -51.047342)
			(xy 143.796265 -51.102518) (xy 143.780197 -51.155925) (xy 143.756525 -51.206422) (xy 143.725752 -51.252935)
			(xy 143.688535 -51.294472) (xy 143.645667 -51.330147) (xy 143.598061 -51.359201) (xy 143.546732 -51.381013)
			(xy 143.492775 -51.395119) (xy 143.437338 -51.401219) (xy 143.381604 -51.399182) (xy 143.326761 -51.389052)
			(xy 143.273977 -51.371045) (xy 143.224377 -51.345544) (xy 143.179019 -51.313093) (xy 143.13887 -51.274384)
			(xy 143.104784 -51.230241) (xy 143.077488 -51.181606) (xy 143.057565 -51.129515) (xy 143.045439 -51.075078)
			(xy 143.041368 -51.019456) (xy 141.613128 -51.019456) (xy 141.612619 -51.047342) (xy 141.604499 -51.102518)
			(xy 141.588431 -51.155925) (xy 141.564759 -51.206422) (xy 141.533986 -51.252935) (xy 141.496769 -51.294472)
			(xy 141.453901 -51.330147) (xy 141.406295 -51.359201) (xy 141.354966 -51.381013) (xy 141.301009 -51.395119)
			(xy 141.245572 -51.401219) (xy 141.189838 -51.399182) (xy 141.134995 -51.389052) (xy 141.082211 -51.371045)
			(xy 141.032611 -51.345544) (xy 140.987253 -51.313093) (xy 140.947104 -51.274384) (xy 140.913018 -51.230241)
			(xy 140.885722 -51.181606) (xy 140.865799 -51.129515) (xy 140.853673 -51.075078) (xy 140.849602 -51.019456)
			(xy 124.622063 -51.019456) (xy 124.627462 -51.03177) (xy 124.635006 -51.039268) (xy 124.654056 -51.057402)
			(xy 124.687513 -51.097983) (xy 124.715073 -51.142778) (xy 124.736213 -51.190937) (xy 124.750532 -51.241545)
			(xy 124.757757 -51.293641) (xy 124.758196 -51.319938) (xy 124.758196 -51.320192) (xy 124.757737 -51.347445)
			(xy 124.749981 -51.401397) (xy 124.734625 -51.453696) (xy 124.711983 -51.503276) (xy 124.682515 -51.54913)
			(xy 124.64682 -51.590323) (xy 124.605627 -51.626017) (xy 124.559773 -51.655485) (xy 124.510192 -51.678127)
			(xy 124.457893 -51.693482) (xy 124.403941 -51.701237) (xy 124.376688 -51.7017) (xy 124.349023 -51.701197)
			(xy 124.294273 -51.693196) (xy 124.241251 -51.677378) (xy 124.191067 -51.654073) (xy 124.144771 -51.623771)
			(xy 124.103334 -51.587104) (xy 124.067621 -51.544842) (xy 124.052584 -51.521614) (xy 124.05233 -51.52136)
			(xy 124.04571 -51.511796) (xy 124.025982 -51.49951) (xy 124.014484 -51.497738) (xy 123.934474 -51.489864)
			(xy 123.922773 -51.489192) (xy 123.900799 -51.497275) (xy 123.89231 -51.505358) (xy 123.89231 -51.505612)
			(xy 123.874209 -51.524173) (xy 123.833881 -51.556753) (xy 123.789511 -51.583568) (xy 123.741917 -51.604124)
			(xy 123.691976 -51.618042) (xy 123.64061 -51.625065) (xy 123.614688 -51.6255) (xy 123.587436 -51.625033)
			(xy 123.533487 -51.617275) (xy 123.481192 -51.601918) (xy 123.431614 -51.579275) (xy 123.385763 -51.549807)
			(xy 123.344573 -51.514113) (xy 123.308881 -51.472921) (xy 123.279416 -51.427069) (xy 123.256775 -51.37749)
			(xy 123.241421 -51.325193) (xy 123.233665 -51.271244) (xy 123.23318 -51.243992) (xy 120.326619 -51.243992)
			(xy 120.326428 -51.254734) (xy 120.318674 -51.308684) (xy 120.30332 -51.360981) (xy 120.28068 -51.410561)
			(xy 120.251214 -51.456414) (xy 120.215523 -51.497607) (xy 120.174332 -51.533301) (xy 120.128481 -51.562769)
			(xy 120.078902 -51.585412) (xy 120.026606 -51.600769) (xy 119.972656 -51.608526) (xy 119.945404 -51.60899)
			(xy 119.927061 -51.608761) (xy 119.890548 -51.605195) (xy 119.872506 -51.601878) (xy 119.872252 -51.601878)
			(xy 119.861748 -51.600491) (xy 119.841149 -51.605339) (xy 119.832374 -51.611276) (xy 119.763032 -51.6636)
			(xy 119.752872 -51.682396) (xy 119.751856 -51.693318) (xy 119.74896 -51.721576) (xy 119.735928 -51.776861)
			(xy 119.714843 -51.829604) (xy 119.686172 -51.878637) (xy 119.650548 -51.922878) (xy 119.608758 -51.961349)
			(xy 119.561727 -51.993199) (xy 119.510494 -52.017724) (xy 119.456191 -52.034383) (xy 119.449036 -52.035456)
			(xy 143.041368 -52.035456) (xy 143.045439 -51.979834) (xy 143.057565 -51.925397) (xy 143.077488 -51.873306)
			(xy 143.104784 -51.824671) (xy 143.13887 -51.780528) (xy 143.179019 -51.741819) (xy 143.224377 -51.709368)
			(xy 143.273977 -51.683867) (xy 143.326761 -51.66586) (xy 143.381604 -51.65573) (xy 143.437338 -51.653693)
			(xy 143.492775 -51.659793) (xy 143.546732 -51.673899) (xy 143.582381 -51.689048) (xy 144.3556 -51.689048)
			(xy 144.3556 -51.634552) (xy 144.363355 -51.58061) (xy 144.378708 -51.528321) (xy 144.401345 -51.478749)
			(xy 144.430807 -51.432903) (xy 144.466492 -51.391716) (xy 144.507676 -51.356027) (xy 144.553519 -51.326561)
			(xy 144.603089 -51.30392) (xy 144.655377 -51.288563) (xy 144.709318 -51.280803) (xy 144.736566 -51.280314)
			(xy 144.763936 -51.280797) (xy 144.818114 -51.28861) (xy 144.870617 -51.304095) (xy 144.920364 -51.326933)
			(xy 144.966332 -51.356654) (xy 144.987264 -51.374294) (xy 144.987518 -51.374548) (xy 144.994591 -51.380154)
			(xy 145.011518 -51.386388) (xy 145.020538 -51.38674) (xy 145.087594 -51.38674) (xy 145.096612 -51.386393)
			(xy 145.11353 -51.38014) (xy 145.120614 -51.374548) (xy 145.121122 -51.37404) (xy 145.142071 -51.356477)
			(xy 145.188001 -51.326833) (xy 145.237693 -51.30405) (xy 145.290128 -51.288596) (xy 145.344233 -51.280786)
			(xy 145.371566 -51.280314) (xy 145.389909 -51.280548) (xy 145.426422 -51.28411) (xy 145.444464 -51.287426)
			(xy 145.444718 -51.287426) (xy 145.455219 -51.288853) (xy 145.475823 -51.283978) (xy 145.484596 -51.278028)
			(xy 145.553938 -51.225704) (xy 145.564098 -51.206908) (xy 145.565114 -51.195986) (xy 145.568014 -51.167703)
			(xy 145.581051 -51.112366) (xy 145.602146 -51.059573) (xy 145.630833 -51.010489) (xy 145.666479 -50.9662)
			(xy 145.687034 -50.946558) (xy 145.694483 -50.938992) (xy 145.703006 -50.91957) (xy 145.703544 -50.908966)
			(xy 145.703544 -50.834798) (xy 145.703114 -50.824169) (xy 145.694578 -50.804705) (xy 145.687034 -50.797206)
			(xy 145.667979 -50.779077) (xy 145.634521 -50.738496) (xy 145.606961 -50.6937) (xy 145.585821 -50.64554)
			(xy 145.571504 -50.594931) (xy 145.564281 -50.542834) (xy 145.563844 -50.516536) (xy 145.563844 -50.516282)
			(xy 145.56433 -50.489031) (xy 145.572086 -50.435083) (xy 145.587441 -50.382788) (xy 145.610083 -50.333211)
			(xy 145.639549 -50.287361) (xy 145.67524 -50.24617) (xy 145.716431 -50.210479) (xy 145.762281 -50.181013)
			(xy 145.811858 -50.158371) (xy 145.864153 -50.143016) (xy 145.918101 -50.13526) (xy 145.972603 -50.13526)
			(xy 146.026551 -50.143016) (xy 146.078846 -50.158371) (xy 146.128423 -50.181013) (xy 146.174273 -50.210479)
			(xy 146.215464 -50.24617) (xy 146.251155 -50.287361) (xy 146.280621 -50.333211) (xy 146.303263 -50.382788)
			(xy 146.318618 -50.435083) (xy 146.326374 -50.489031) (xy 146.32686 -50.516282) (xy 146.32686 -50.516536)
			(xy 146.326438 -50.542832) (xy 146.319187 -50.594923) (xy 146.304855 -50.645526) (xy 146.283712 -50.693682)
			(xy 146.25616 -50.73848) (xy 146.22272 -50.779073) (xy 146.20367 -50.797206) (xy 146.196238 -50.804786)
			(xy 146.187705 -50.824197) (xy 146.18716 -50.834798) (xy 146.18716 -50.908966) (xy 146.187554 -50.9196)
			(xy 146.196115 -50.939063) (xy 146.20367 -50.946558) (xy 146.222709 -50.964704) (xy 146.256168 -51.005282)
			(xy 146.28373 -51.050074) (xy 146.304873 -51.098231) (xy 146.319193 -51.148837) (xy 146.32642 -51.200931)
			(xy 146.32686 -51.227228) (xy 146.32686 -51.227482) (xy 146.326598 -51.243992) (xy 149.233128 -51.243992)
			(xy 149.233618 -51.216659) (xy 149.24142 -51.162552) (xy 149.256865 -51.110113) (xy 149.279636 -51.060415)
			(xy 149.309266 -51.014476) (xy 149.326854 -50.993548) (xy 149.327108 -50.993294) (xy 149.327362 -50.99304)
			(xy 149.332945 -50.985951) (xy 149.339192 -50.969036) (xy 149.339554 -50.96002) (xy 149.339554 -50.892964)
			(xy 149.339224 -50.883944) (xy 149.332959 -50.867027) (xy 149.327362 -50.859944) (xy 149.327108 -50.85969)
			(xy 149.326854 -50.859436) (xy 149.309258 -50.838513) (xy 149.279622 -50.792575) (xy 149.256847 -50.742876)
			(xy 149.2414 -50.690435) (xy 149.233597 -50.636326) (xy 149.233128 -50.608992) (xy 149.233548 -50.581737)
			(xy 149.241307 -50.527783) (xy 149.256666 -50.475482) (xy 149.279312 -50.4259) (xy 149.308784 -50.380045)
			(xy 149.344482 -50.338851) (xy 149.38568 -50.303158) (xy 149.431538 -50.273691) (xy 149.481123 -50.25105)
			(xy 149.533426 -50.235698) (xy 149.587381 -50.227945) (xy 149.614636 -50.227484) (xy 149.643553 -50.228017)
			(xy 149.700725 -50.236738) (xy 149.755925 -50.253991) (xy 149.807887 -50.27938) (xy 149.855421 -50.312323)
			(xy 149.897437 -50.352064) (xy 149.915626 -50.37455) (xy 149.921901 -50.381943) (xy 149.938621 -50.391735)
			(xy 149.948138 -50.3936) (xy 149.955758 -50.394108) (xy 150.035514 -50.394108) (xy 150.043134 -50.3936)
			(xy 150.052647 -50.391727) (xy 150.069362 -50.381934) (xy 150.075646 -50.37455) (xy 150.093855 -50.352082)
			(xy 150.135872 -50.312348) (xy 150.183404 -50.279409) (xy 150.235362 -50.254018) (xy 150.290555 -50.236758)
			(xy 150.347721 -50.228023) (xy 150.376636 -50.227484) (xy 150.403888 -50.227944) (xy 150.457836 -50.235706)
			(xy 150.510131 -50.251065) (xy 150.559708 -50.27371) (xy 150.605557 -50.303179) (xy 150.646747 -50.338873)
			(xy 150.682438 -50.380065) (xy 150.711904 -50.425917) (xy 150.734545 -50.475496) (xy 150.7499 -50.527791)
			(xy 150.757658 -50.58174) (xy 150.758144 -50.608992) (xy 150.758144 -50.609246) (xy 150.757702 -50.635541)
			(xy 150.750451 -50.68763) (xy 150.736121 -50.738231) (xy 150.714982 -50.786387) (xy 150.687435 -50.831186)
			(xy 150.654001 -50.871781) (xy 150.634954 -50.889916) (xy 150.627515 -50.89749) (xy 150.618987 -50.916906)
			(xy 150.618444 -50.927508) (xy 150.618444 -51.001676) (xy 150.618892 -51.012303) (xy 150.622025 -51.019456)
			(xy 166.84955 -51.019456) (xy 166.853621 -50.963834) (xy 166.865747 -50.909397) (xy 166.88567 -50.857306)
			(xy 166.912966 -50.808671) (xy 166.947052 -50.764528) (xy 166.987201 -50.725819) (xy 167.032559 -50.693368)
			(xy 167.082159 -50.667867) (xy 167.134943 -50.64986) (xy 167.189786 -50.63973) (xy 167.24552 -50.637693)
			(xy 167.300957 -50.643793) (xy 167.354914 -50.657899) (xy 167.406243 -50.679711) (xy 167.453849 -50.708765)
			(xy 167.496717 -50.74444) (xy 167.533934 -50.785977) (xy 167.564707 -50.83249) (xy 167.588379 -50.882987)
			(xy 167.604447 -50.936394) (xy 167.612567 -50.99157) (xy 167.613076 -51.019456) (xy 169.041316 -51.019456)
			(xy 169.045387 -50.963834) (xy 169.057513 -50.909397) (xy 169.077436 -50.857306) (xy 169.104732 -50.808671)
			(xy 169.138818 -50.764528) (xy 169.178967 -50.725819) (xy 169.224325 -50.693368) (xy 169.273925 -50.667867)
			(xy 169.326709 -50.64986) (xy 169.381552 -50.63973) (xy 169.437286 -50.637693) (xy 169.492723 -50.643793)
			(xy 169.54668 -50.657899) (xy 169.598009 -50.679711) (xy 169.645615 -50.708765) (xy 169.688483 -50.74444)
			(xy 169.7257 -50.785977) (xy 169.756473 -50.83249) (xy 169.780145 -50.882987) (xy 169.796213 -50.936394)
			(xy 169.804333 -50.99157) (xy 169.804842 -51.019456) (xy 169.804333 -51.047342) (xy 169.796213 -51.102518)
			(xy 169.780145 -51.155925) (xy 169.756473 -51.206422) (xy 169.7257 -51.252935) (xy 169.688483 -51.294472)
			(xy 169.645615 -51.330147) (xy 169.598009 -51.359201) (xy 169.54668 -51.381013) (xy 169.492723 -51.395119)
			(xy 169.437286 -51.401219) (xy 169.381552 -51.399182) (xy 169.326709 -51.389052) (xy 169.273925 -51.371045)
			(xy 169.224325 -51.345544) (xy 169.178967 -51.313093) (xy 169.138818 -51.274384) (xy 169.104732 -51.230241)
			(xy 169.077436 -51.181606) (xy 169.057513 -51.129515) (xy 169.045387 -51.075078) (xy 169.041316 -51.019456)
			(xy 167.613076 -51.019456) (xy 167.612567 -51.047342) (xy 167.604447 -51.102518) (xy 167.588379 -51.155925)
			(xy 167.564707 -51.206422) (xy 167.533934 -51.252935) (xy 167.496717 -51.294472) (xy 167.453849 -51.330147)
			(xy 167.406243 -51.359201) (xy 167.354914 -51.381013) (xy 167.300957 -51.395119) (xy 167.24552 -51.401219)
			(xy 167.189786 -51.399182) (xy 167.134943 -51.389052) (xy 167.082159 -51.371045) (xy 167.032559 -51.345544)
			(xy 166.987201 -51.313093) (xy 166.947052 -51.274384) (xy 166.912966 -51.230241) (xy 166.88567 -51.181606)
			(xy 166.865747 -51.129515) (xy 166.853621 -51.075078) (xy 166.84955 -51.019456) (xy 150.622025 -51.019456)
			(xy 150.627416 -51.031767) (xy 150.634954 -51.039268) (xy 150.653994 -51.057412) (xy 150.687454 -51.09799)
			(xy 150.715017 -51.142783) (xy 150.736159 -51.19094) (xy 150.750479 -51.241546) (xy 150.757705 -51.293641)
			(xy 150.758144 -51.319938) (xy 150.758144 -51.320192) (xy 150.757615 -51.347441) (xy 150.74986 -51.401386)
			(xy 150.734508 -51.453677) (xy 150.711871 -51.503252) (xy 150.682408 -51.549101) (xy 150.646722 -51.59029)
			(xy 150.605536 -51.625982) (xy 150.559691 -51.655449) (xy 150.510119 -51.678093) (xy 150.457829 -51.693451)
			(xy 150.403885 -51.701212) (xy 150.376636 -51.7017) (xy 150.348972 -51.70116) (xy 150.294224 -51.693165)
			(xy 150.241203 -51.677354) (xy 150.191019 -51.654055) (xy 150.144723 -51.623758) (xy 150.103284 -51.587097)
			(xy 150.06757 -51.544839) (xy 150.052532 -51.521614) (xy 150.052278 -51.52136) (xy 150.045636 -51.511815)
			(xy 150.025924 -51.499519) (xy 150.014432 -51.497738) (xy 149.934422 -51.489864) (xy 149.922721 -51.489222)
			(xy 149.90075 -51.497285) (xy 149.892258 -51.505358) (xy 149.892258 -51.505612) (xy 149.874182 -51.524198)
			(xy 149.833849 -51.556776) (xy 149.789473 -51.583588) (xy 149.741874 -51.604139) (xy 149.691929 -51.618052)
			(xy 149.640559 -51.625069) (xy 149.614636 -51.6255) (xy 149.587384 -51.625011) (xy 149.533433 -51.617259)
			(xy 149.481135 -51.601907) (xy 149.431555 -51.579268) (xy 149.385701 -51.549803) (xy 149.344508 -51.514112)
			(xy 149.308814 -51.472921) (xy 149.279345 -51.42707) (xy 149.256703 -51.377491) (xy 149.241347 -51.325194)
			(xy 149.233591 -51.271244) (xy 149.233128 -51.243992) (xy 146.326598 -51.243992) (xy 146.326428 -51.254737)
			(xy 146.318672 -51.308691) (xy 146.303316 -51.360993) (xy 146.280672 -51.410576) (xy 146.251201 -51.456431)
			(xy 146.215504 -51.497625) (xy 146.174307 -51.533319) (xy 146.128449 -51.562786) (xy 146.078864 -51.585426)
			(xy 146.026562 -51.600778) (xy 145.972607 -51.60853) (xy 145.945352 -51.60899) (xy 145.927009 -51.608754)
			(xy 145.890496 -51.605193) (xy 145.872454 -51.601878) (xy 145.8722 -51.601878) (xy 145.861698 -51.600461)
			(xy 145.841095 -51.605329) (xy 145.832322 -51.611276) (xy 145.76298 -51.6636) (xy 145.75282 -51.682396)
			(xy 145.751804 -51.693318) (xy 145.748861 -51.72157) (xy 145.735831 -51.776851) (xy 145.714749 -51.82959)
			(xy 145.686083 -51.878621) (xy 145.650464 -51.922861) (xy 145.60868 -51.961331) (xy 145.561656 -51.993183)
			(xy 145.510429 -52.017711) (xy 145.456132 -52.034374) (xy 145.448922 -52.035456) (xy 169.041316 -52.035456)
			(xy 169.045387 -51.979834) (xy 169.057513 -51.925397) (xy 169.077436 -51.873306) (xy 169.104732 -51.824671)
			(xy 169.138818 -51.780528) (xy 169.178967 -51.741819) (xy 169.224325 -51.709368) (xy 169.273925 -51.683867)
			(xy 169.326709 -51.66586) (xy 169.381552 -51.65573) (xy 169.437286 -51.653693) (xy 169.492723 -51.659793)
			(xy 169.54668 -51.673899) (xy 169.582339 -51.689052) (xy 170.355477 -51.689052) (xy 170.355477 -51.634548)
			(xy 170.363234 -51.580599) (xy 170.37859 -51.528303) (xy 170.401232 -51.478725) (xy 170.4307 -51.432874)
			(xy 170.466393 -51.391683) (xy 170.507585 -51.355991) (xy 170.553437 -51.326526) (xy 170.603016 -51.303885)
			(xy 170.655313 -51.288531) (xy 170.709262 -51.280776) (xy 170.736514 -51.280314) (xy 170.763885 -51.280768)
			(xy 170.818064 -51.288589) (xy 170.870568 -51.30408) (xy 170.920314 -51.326925) (xy 170.966281 -51.356652)
			(xy 170.987212 -51.374294) (xy 170.987466 -51.374548) (xy 170.994554 -51.380132) (xy 171.01147 -51.386379)
			(xy 171.020486 -51.38674) (xy 171.087542 -51.38674) (xy 171.096558 -51.386368) (xy 171.113475 -51.380132)
			(xy 171.120562 -51.374548) (xy 171.12107 -51.37404) (xy 171.142001 -51.356454) (xy 171.187936 -51.326814)
			(xy 171.237632 -51.304035) (xy 171.290072 -51.288586) (xy 171.34418 -51.280782) (xy 171.371514 -51.280314)
			(xy 171.389857 -51.280541) (xy 171.42637 -51.284108) (xy 171.444412 -51.287426) (xy 171.444666 -51.287426)
			(xy 171.455169 -51.288823) (xy 171.47577 -51.283968) (xy 171.484544 -51.278028) (xy 171.553886 -51.225704)
			(xy 171.564046 -51.206908) (xy 171.565062 -51.195986) (xy 171.567948 -51.167701) (xy 171.580986 -51.112363)
			(xy 171.602084 -51.059569) (xy 171.630775 -51.010486) (xy 171.666425 -50.966199) (xy 171.686982 -50.946558)
			(xy 171.694438 -50.938999) (xy 171.702955 -50.919571) (xy 171.703492 -50.908966) (xy 171.703492 -50.834798)
			(xy 171.703078 -50.824166) (xy 171.694532 -50.804702) (xy 171.686982 -50.797206) (xy 171.667917 -50.779087)
			(xy 171.634462 -50.738503) (xy 171.606904 -50.693704) (xy 171.585767 -50.645542) (xy 171.571451 -50.594932)
			(xy 171.564229 -50.542834) (xy 171.563792 -50.516536) (xy 171.563792 -50.516282) (xy 171.564278 -50.489031)
			(xy 171.572034 -50.435083) (xy 171.587389 -50.382788) (xy 171.610031 -50.333211) (xy 171.639497 -50.287361)
			(xy 171.675188 -50.24617) (xy 171.716379 -50.210479) (xy 171.762229 -50.181013) (xy 171.811806 -50.158371)
			(xy 171.864101 -50.143016) (xy 171.918049 -50.13526) (xy 171.972551 -50.13526) (xy 172.026499 -50.143016)
			(xy 172.078794 -50.158371) (xy 172.128371 -50.181013) (xy 172.174221 -50.210479) (xy 172.215412 -50.24617)
			(xy 172.251103 -50.287361) (xy 172.280569 -50.333211) (xy 172.303211 -50.382788) (xy 172.318566 -50.435083)
			(xy 172.326322 -50.489031) (xy 172.326808 -50.516282) (xy 172.326808 -50.516536) (xy 172.326371 -50.542832)
			(xy 172.319121 -50.594921) (xy 172.30479 -50.645523) (xy 172.283651 -50.693679) (xy 172.256102 -50.738478)
			(xy 172.222666 -50.779072) (xy 172.203618 -50.797206) (xy 172.196178 -50.804779) (xy 172.187652 -50.824196)
			(xy 172.187108 -50.834798) (xy 172.187108 -50.908966) (xy 172.187487 -50.919602) (xy 172.196057 -50.939066)
			(xy 172.203618 -50.946558) (xy 172.222666 -50.964694) (xy 172.256122 -51.005275) (xy 172.283682 -51.05007)
			(xy 172.304823 -51.098228) (xy 172.319142 -51.148836) (xy 172.326368 -51.200931) (xy 172.326808 -51.227228)
			(xy 172.326808 -51.227482) (xy 172.326517 -51.243992) (xy 175.233076 -51.243992) (xy 175.233554 -51.216658)
			(xy 175.241358 -51.162551) (xy 175.256805 -51.110112) (xy 175.279579 -51.060414) (xy 175.309212 -51.014475)
			(xy 175.326802 -50.993548) (xy 175.327056 -50.993294) (xy 175.32731 -50.99304) (xy 175.332887 -50.985947)
			(xy 175.339139 -50.969035) (xy 175.339502 -50.96002) (xy 175.339502 -50.892964) (xy 175.339162 -50.883945)
			(xy 175.332902 -50.867029) (xy 175.32731 -50.859944) (xy 175.327056 -50.85969) (xy 175.326802 -50.859436)
			(xy 175.309213 -50.838507) (xy 175.279574 -50.792571) (xy 175.256797 -50.742874) (xy 175.241348 -50.690434)
			(xy 175.233545 -50.636326) (xy 175.233076 -50.608992) (xy 175.23357 -50.581741) (xy 175.241327 -50.527795)
			(xy 175.256683 -50.475501) (xy 175.279324 -50.425925) (xy 175.308789 -50.380075) (xy 175.34448 -50.338886)
			(xy 175.385669 -50.303194) (xy 175.431518 -50.273728) (xy 175.481094 -50.251086) (xy 175.533387 -50.235729)
			(xy 175.587333 -50.227971) (xy 175.614584 -50.227484) (xy 175.643502 -50.227982) (xy 175.700676 -50.236711)
			(xy 175.755876 -50.25397) (xy 175.807839 -50.279366) (xy 175.855372 -50.312315) (xy 175.897386 -50.352061)
			(xy 175.915574 -50.37455) (xy 175.921868 -50.381925) (xy 175.938574 -50.391727) (xy 175.948086 -50.3936)
			(xy 175.955706 -50.394108) (xy 176.035462 -50.394108) (xy 176.043082 -50.3936) (xy 176.052601 -50.391749)
			(xy 176.069313 -50.38194) (xy 176.075594 -50.37455) (xy 176.093776 -50.352059) (xy 176.135799 -50.312327)
			(xy 176.183336 -50.27939) (xy 176.235299 -50.254003) (xy 176.290498 -50.236748) (xy 176.347668 -50.228019)
			(xy 176.376584 -50.227484) (xy 176.403836 -50.22797) (xy 176.457786 -50.235725) (xy 176.510083 -50.251078)
			(xy 176.559662 -50.273718) (xy 176.605515 -50.303184) (xy 176.646708 -50.338875) (xy 176.682402 -50.380066)
			(xy 176.71187 -50.425917) (xy 176.728548 -50.462434) (xy 190.92621 -50.462434) (xy 190.930281 -50.406812)
			(xy 190.942407 -50.352375) (xy 190.96233 -50.300284) (xy 190.989626 -50.251649) (xy 191.023712 -50.207506)
			(xy 191.063861 -50.168797) (xy 191.109219 -50.136346) (xy 191.158819 -50.110845) (xy 191.211603 -50.092838)
			(xy 191.266446 -50.082708) (xy 191.32218 -50.080671) (xy 191.377617 -50.086771) (xy 191.431574 -50.100877)
			(xy 191.482903 -50.122689) (xy 191.530509 -50.151743) (xy 191.573377 -50.187418) (xy 191.610594 -50.228955)
			(xy 191.641367 -50.275468) (xy 191.665039 -50.325965) (xy 191.681107 -50.379372) (xy 191.689227 -50.434548)
			(xy 191.689736 -50.462434) (xy 191.689227 -50.49032) (xy 191.681107 -50.545496) (xy 191.665039 -50.598903)
			(xy 191.641367 -50.6494) (xy 191.610594 -50.695913) (xy 191.573377 -50.73745) (xy 191.530509 -50.773125)
			(xy 191.482903 -50.802179) (xy 191.431574 -50.823991) (xy 191.377617 -50.838097) (xy 191.32218 -50.844197)
			(xy 191.266446 -50.84216) (xy 191.211603 -50.83203) (xy 191.158819 -50.814023) (xy 191.109219 -50.788522)
			(xy 191.063861 -50.756071) (xy 191.023712 -50.717362) (xy 190.989626 -50.673219) (xy 190.96233 -50.624584)
			(xy 190.942407 -50.572493) (xy 190.930281 -50.518056) (xy 190.92621 -50.462434) (xy 176.728548 -50.462434)
			(xy 176.734513 -50.475495) (xy 176.74987 -50.527791) (xy 176.757628 -50.58174) (xy 176.758092 -50.608992)
			(xy 176.758092 -50.609246) (xy 176.757666 -50.635542) (xy 176.750415 -50.687632) (xy 176.736082 -50.738234)
			(xy 176.714941 -50.78639) (xy 176.68739 -50.831189) (xy 176.653951 -50.871783) (xy 176.634902 -50.889916)
			(xy 176.627455 -50.897483) (xy 176.618933 -50.916904) (xy 176.618392 -50.927508) (xy 176.618392 -51.001676)
			(xy 176.618825 -51.012305) (xy 176.62196 -51.019456) (xy 192.849498 -51.019456) (xy 192.853569 -50.963834)
			(xy 192.865695 -50.909397) (xy 192.885618 -50.857306) (xy 192.912914 -50.808671) (xy 192.947 -50.764528)
			(xy 192.987149 -50.725819) (xy 193.032507 -50.693368) (xy 193.082107 -50.667867) (xy 193.134891 -50.64986)
			(xy 193.189734 -50.63973) (xy 193.245468 -50.637693) (xy 193.300905 -50.643793) (xy 193.354862 -50.657899)
			(xy 193.406191 -50.679711) (xy 193.453797 -50.708765) (xy 193.496665 -50.74444) (xy 193.533882 -50.785977)
			(xy 193.564655 -50.83249) (xy 193.588327 -50.882987) (xy 193.604395 -50.936394) (xy 193.612515 -50.99157)
			(xy 193.613024 -51.019456) (xy 195.041264 -51.019456) (xy 195.045335 -50.963834) (xy 195.057461 -50.909397)
			(xy 195.077384 -50.857306) (xy 195.10468 -50.808671) (xy 195.138766 -50.764528) (xy 195.178915 -50.725819)
			(xy 195.224273 -50.693368) (xy 195.273873 -50.667867) (xy 195.326657 -50.64986) (xy 195.3815 -50.63973)
			(xy 195.437234 -50.637693) (xy 195.492671 -50.643793) (xy 195.546628 -50.657899) (xy 195.597957 -50.679711)
			(xy 195.645563 -50.708765) (xy 195.688431 -50.74444) (xy 195.725648 -50.785977) (xy 195.756421 -50.83249)
			(xy 195.780093 -50.882987) (xy 195.796161 -50.936394) (xy 195.804281 -50.99157) (xy 195.80479 -51.019456)
			(xy 195.804281 -51.047342) (xy 195.796161 -51.102518) (xy 195.780093 -51.155925) (xy 195.756421 -51.206422)
			(xy 195.725648 -51.252935) (xy 195.688431 -51.294472) (xy 195.645563 -51.330147) (xy 195.597957 -51.359201)
			(xy 195.546628 -51.381013) (xy 195.492671 -51.395119) (xy 195.437234 -51.401219) (xy 195.3815 -51.399182)
			(xy 195.326657 -51.389052) (xy 195.273873 -51.371045) (xy 195.224273 -51.345544) (xy 195.178915 -51.313093)
			(xy 195.138766 -51.274384) (xy 195.10468 -51.230241) (xy 195.077384 -51.181606) (xy 195.057461 -51.129515)
			(xy 195.045335 -51.075078) (xy 195.041264 -51.019456) (xy 193.613024 -51.019456) (xy 193.612515 -51.047342)
			(xy 193.604395 -51.102518) (xy 193.588327 -51.155925) (xy 193.564655 -51.206422) (xy 193.533882 -51.252935)
			(xy 193.496665 -51.294472) (xy 193.453797 -51.330147) (xy 193.406191 -51.359201) (xy 193.354862 -51.381013)
			(xy 193.300905 -51.395119) (xy 193.245468 -51.401219) (xy 193.189734 -51.399182) (xy 193.134891 -51.389052)
			(xy 193.082107 -51.371045) (xy 193.032507 -51.345544) (xy 192.987149 -51.313093) (xy 192.947 -51.274384)
			(xy 192.912914 -51.230241) (xy 192.885618 -51.181606) (xy 192.865695 -51.129515) (xy 192.853569 -51.075078)
			(xy 192.849498 -51.019456) (xy 176.62196 -51.019456) (xy 176.627358 -51.03177) (xy 176.634902 -51.039268)
			(xy 176.653952 -51.057403) (xy 176.687408 -51.097983) (xy 176.714969 -51.142779) (xy 176.736109 -51.190937)
			(xy 176.750428 -51.241545) (xy 176.757653 -51.293641) (xy 176.758092 -51.319938) (xy 176.758092 -51.320192)
			(xy 176.757637 -51.347445) (xy 176.749881 -51.401397) (xy 176.734525 -51.453696) (xy 176.711882 -51.503278)
			(xy 176.682414 -51.549132) (xy 176.646719 -51.590325) (xy 176.605525 -51.626018) (xy 176.559671 -51.655486)
			(xy 176.510089 -51.678128) (xy 176.45779 -51.693483) (xy 176.403837 -51.701238) (xy 176.376584 -51.7017)
			(xy 176.348918 -51.7012) (xy 176.294169 -51.693199) (xy 176.241147 -51.67738) (xy 176.190963 -51.654075)
			(xy 176.144667 -51.623772) (xy 176.103229 -51.587105) (xy 176.067517 -51.544842) (xy 176.05248 -51.521614)
			(xy 176.052226 -51.52136) (xy 176.045562 -51.511834) (xy 176.025866 -51.499528) (xy 176.01438 -51.497738)
			(xy 175.93437 -51.489864) (xy 175.922669 -51.489189) (xy 175.900695 -51.497274) (xy 175.892206 -51.505358)
			(xy 175.892206 -51.505612) (xy 175.874107 -51.524175) (xy 175.833779 -51.556755) (xy 175.789408 -51.58357)
			(xy 175.741813 -51.604126) (xy 175.691872 -51.618043) (xy 175.640506 -51.625065) (xy 175.614584 -51.6255)
			(xy 175.587332 -51.625037) (xy 175.533383 -51.617278) (xy 175.481087 -51.601921) (xy 175.43151 -51.579277)
			(xy 175.385659 -51.549808) (xy 175.344469 -51.514114) (xy 175.308777 -51.472922) (xy 175.279311 -51.427069)
			(xy 175.256671 -51.37749) (xy 175.241317 -51.325193) (xy 175.233561 -51.271244) (xy 175.233076 -51.243992)
			(xy 172.326517 -51.243992) (xy 172.326328 -51.254734) (xy 172.318573 -51.308685) (xy 172.30322 -51.360982)
			(xy 172.280579 -51.410562) (xy 172.251113 -51.456416) (xy 172.215421 -51.497608) (xy 172.17423 -51.533302)
			(xy 172.128378 -51.562771) (xy 172.078799 -51.585413) (xy 172.026502 -51.60077) (xy 171.972552 -51.608527)
			(xy 171.9453 -51.60899) (xy 171.926957 -51.608761) (xy 171.890444 -51.605196) (xy 171.872402 -51.601878)
			(xy 171.872148 -51.601878) (xy 171.861644 -51.600489) (xy 171.841045 -51.605339) (xy 171.83227 -51.611276)
			(xy 171.762928 -51.6636) (xy 171.752768 -51.682396) (xy 171.751752 -51.693318) (xy 171.74886 -51.721576)
			(xy 171.735827 -51.776862) (xy 171.714742 -51.829605) (xy 171.686071 -51.878639) (xy 171.650446 -51.92288)
			(xy 171.608656 -51.96135) (xy 171.561625 -51.9932) (xy 171.510391 -52.017725) (xy 171.456088 -52.034384)
			(xy 171.448939 -52.035456) (xy 195.041264 -52.035456) (xy 195.045335 -51.979834) (xy 195.057461 -51.925397)
			(xy 195.077384 -51.873306) (xy 195.10468 -51.824671) (xy 195.138766 -51.780528) (xy 195.178915 -51.741819)
			(xy 195.224273 -51.709368) (xy 195.273873 -51.683867) (xy 195.326657 -51.66586) (xy 195.3815 -51.65573)
			(xy 195.437234 -51.653693) (xy 195.492671 -51.659793) (xy 195.546628 -51.673899) (xy 195.582277 -51.689048)
			(xy 196.3555 -51.689048) (xy 196.3555 -51.634552) (xy 196.363255 -51.580611) (xy 196.378607 -51.528322)
			(xy 196.401245 -51.47875) (xy 196.430706 -51.432905) (xy 196.466391 -51.391718) (xy 196.507574 -51.356028)
			(xy 196.553417 -51.326563) (xy 196.602987 -51.303921) (xy 196.655274 -51.288563) (xy 196.709214 -51.280803)
			(xy 196.736462 -51.280314) (xy 196.763832 -51.280799) (xy 196.81801 -51.288612) (xy 196.870513 -51.304096)
			(xy 196.92026 -51.326934) (xy 196.966228 -51.356655) (xy 196.98716 -51.374294) (xy 196.987414 -51.374548)
			(xy 196.994488 -51.380152) (xy 197.011415 -51.386387) (xy 197.020434 -51.38674) (xy 197.08749 -51.38674)
			(xy 197.096508 -51.386391) (xy 197.113426 -51.380139) (xy 197.12051 -51.374548) (xy 197.121018 -51.37404)
			(xy 197.141931 -51.356432) (xy 197.187871 -51.326795) (xy 197.237572 -51.304021) (xy 197.290015 -51.288577)
			(xy 197.344127 -51.280779) (xy 197.371462 -51.280314) (xy 197.389805 -51.280548) (xy 197.426318 -51.28411)
			(xy 197.44436 -51.287426) (xy 197.444614 -51.287426) (xy 197.455115 -51.28885) (xy 197.475719 -51.283977)
			(xy 197.484492 -51.278028) (xy 197.553834 -51.225704) (xy 197.563994 -51.206908) (xy 197.56501 -51.195986)
			(xy 197.567912 -51.167703) (xy 197.580948 -51.112366) (xy 197.602043 -51.059573) (xy 197.63073 -51.010489)
			(xy 197.666376 -50.9662) (xy 197.68693 -50.946558) (xy 197.694378 -50.938992) (xy 197.702902 -50.91957)
			(xy 197.70344 -50.908966) (xy 197.70344 -50.834798) (xy 197.703012 -50.824168) (xy 197.694475 -50.804705)
			(xy 197.68693 -50.797206) (xy 197.667874 -50.779078) (xy 197.634416 -50.738496) (xy 197.606856 -50.6937)
			(xy 197.585717 -50.64554) (xy 197.5714 -50.594931) (xy 197.564177 -50.542834) (xy 197.56374 -50.516536)
			(xy 197.56374 -50.516282) (xy 197.564226 -50.489031) (xy 197.571982 -50.435083) (xy 197.587337 -50.382788)
			(xy 197.609979 -50.333211) (xy 197.639445 -50.287361) (xy 197.675136 -50.24617) (xy 197.716327 -50.210479)
			(xy 197.762177 -50.181013) (xy 197.811754 -50.158371) (xy 197.864049 -50.143016) (xy 197.917997 -50.13526)
			(xy 197.972499 -50.13526) (xy 198.026447 -50.143016) (xy 198.078742 -50.158371) (xy 198.128319 -50.181013)
			(xy 198.174169 -50.210479) (xy 198.21536 -50.24617) (xy 198.251051 -50.287361) (xy 198.280517 -50.333211)
			(xy 198.303159 -50.382788) (xy 198.318514 -50.435083) (xy 198.32627 -50.489031) (xy 198.326756 -50.516282)
			(xy 198.326756 -50.516536) (xy 198.326335 -50.542832) (xy 198.319084 -50.594923) (xy 198.304752 -50.645526)
			(xy 198.283609 -50.693682) (xy 198.256057 -50.738481) (xy 198.222616 -50.779073) (xy 198.203566 -50.797206)
			(xy 198.196133 -50.804785) (xy 198.187601 -50.824197) (xy 198.187056 -50.834798) (xy 198.187056 -50.908966)
			(xy 198.187451 -50.919599) (xy 198.196012 -50.939063) (xy 198.203566 -50.946558) (xy 198.222604 -50.964705)
			(xy 198.256063 -51.005282) (xy 198.283626 -51.050074) (xy 198.304768 -51.098231) (xy 198.319089 -51.148837)
			(xy 198.326316 -51.200931) (xy 198.326756 -51.227228) (xy 198.326756 -51.227482) (xy 198.326422 -51.243992)
			(xy 201.233024 -51.243992) (xy 201.233515 -51.216659) (xy 201.241317 -51.162553) (xy 201.256762 -51.110114)
			(xy 201.279532 -51.060416) (xy 201.309162 -51.014476) (xy 201.32675 -50.993548) (xy 201.327004 -50.993294)
			(xy 201.327258 -50.99304) (xy 201.332841 -50.985951) (xy 201.339088 -50.969036) (xy 201.33945 -50.96002)
			(xy 201.33945 -50.892964) (xy 201.339121 -50.883944) (xy 201.332855 -50.867027) (xy 201.327258 -50.859944)
			(xy 201.327004 -50.85969) (xy 201.32675 -50.859436) (xy 201.309153 -50.838514) (xy 201.279517 -50.792575)
			(xy 201.256742 -50.742876) (xy 201.241296 -50.690435) (xy 201.233493 -50.636326) (xy 201.233024 -50.608992)
			(xy 201.233448 -50.581737) (xy 201.241207 -50.527784) (xy 201.256566 -50.475483) (xy 201.279211 -50.425901)
			(xy 201.308683 -50.380046) (xy 201.344381 -50.338853) (xy 201.385578 -50.303159) (xy 201.431436 -50.273692)
			(xy 201.481021 -50.251052) (xy 201.533323 -50.235698) (xy 201.587277 -50.227945) (xy 201.614532 -50.227484)
			(xy 201.643449 -50.228019) (xy 201.70062 -50.23674) (xy 201.75582 -50.253993) (xy 201.807783 -50.279381)
			(xy 201.855317 -50.312323) (xy 201.897333 -50.352064) (xy 201.915522 -50.37455) (xy 201.921798 -50.381942)
			(xy 201.938518 -50.391735) (xy 201.948034 -50.3936) (xy 201.955654 -50.394108) (xy 202.03541 -50.394108)
			(xy 202.04303 -50.3936) (xy 202.052543 -50.391726) (xy 202.069258 -50.381933) (xy 202.075542 -50.37455)
			(xy 202.093697 -50.352036) (xy 202.135725 -50.312305) (xy 202.183268 -50.279371) (xy 202.235237 -50.253988)
			(xy 202.29044 -50.236738) (xy 202.347614 -50.228016) (xy 202.376532 -50.227484) (xy 202.403784 -50.227948)
			(xy 202.457732 -50.235709) (xy 202.510026 -50.251067) (xy 202.559603 -50.273712) (xy 202.605453 -50.303181)
			(xy 202.646643 -50.338874) (xy 202.682334 -50.380066) (xy 202.7118 -50.425918) (xy 202.733 -50.47234)
			(xy 240.755168 -50.47234) (xy 240.759239 -50.416718) (xy 240.771365 -50.362281) (xy 240.791288 -50.31019)
			(xy 240.818584 -50.261555) (xy 240.85267 -50.217412) (xy 240.892819 -50.178703) (xy 240.938177 -50.146252)
			(xy 240.987777 -50.120751) (xy 241.040561 -50.102744) (xy 241.095404 -50.092614) (xy 241.151138 -50.090577)
			(xy 241.206575 -50.096677) (xy 241.260532 -50.110783) (xy 241.311861 -50.132595) (xy 241.359467 -50.161649)
			(xy 241.402335 -50.197324) (xy 241.439552 -50.238861) (xy 241.470325 -50.285374) (xy 241.493997 -50.335871)
			(xy 241.510065 -50.389278) (xy 241.518185 -50.444454) (xy 241.518694 -50.47234) (xy 241.518185 -50.500226)
			(xy 241.510065 -50.555402) (xy 241.493997 -50.608809) (xy 241.470325 -50.659306) (xy 241.439552 -50.705819)
			(xy 241.425904 -50.721051) (xy 256.232883 -50.721051) (xy 256.232883 -50.666549) (xy 256.24064 -50.6126)
			(xy 256.255996 -50.560305) (xy 256.278638 -50.510728) (xy 256.308105 -50.464877) (xy 256.343797 -50.423687)
			(xy 256.384989 -50.387996) (xy 256.43084 -50.358531) (xy 256.480418 -50.335891) (xy 256.532714 -50.320537)
			(xy 256.586662 -50.312782) (xy 256.613914 -50.31232) (xy 256.640253 -50.312759) (xy 256.692432 -50.319983)
			(xy 256.74312 -50.33432) (xy 256.791353 -50.355496) (xy 256.836212 -50.383109) (xy 256.876844 -50.416633)
			(xy 256.912476 -50.45543) (xy 256.942429 -50.498762) (xy 256.966133 -50.545804) (xy 256.983138 -50.595661)
			(xy 256.988564 -50.621438) (xy 256.991588 -50.634981) (xy 257.003979 -50.6598) (xy 257.022604 -50.680357)
			(xy 257.046084 -50.695129) (xy 257.072678 -50.703021) (xy 257.100415 -50.703448) (xy 257.127239 -50.696378)
			(xy 257.13944 -50.689764) (xy 257.161399 -50.677474) (xy 257.207836 -50.658087) (xy 257.256419 -50.644971)
			(xy 257.306303 -50.638353) (xy 257.331464 -50.637948) (xy 257.358715 -50.638497) (xy 257.412664 -50.646249)
			(xy 257.46496 -50.6616) (xy 257.514539 -50.684238) (xy 257.560391 -50.713701) (xy 257.601584 -50.749391)
			(xy 257.637277 -50.79058) (xy 257.666745 -50.836429) (xy 257.689388 -50.886006) (xy 257.704744 -50.938301)
			(xy 257.712501 -50.992249) (xy 257.712501 -51.019456) (xy 259.141212 -51.019456) (xy 259.145283 -50.963834)
			(xy 259.157409 -50.909397) (xy 259.177332 -50.857306) (xy 259.204628 -50.808671) (xy 259.238714 -50.764528)
			(xy 259.278863 -50.725819) (xy 259.324221 -50.693368) (xy 259.373821 -50.667867) (xy 259.426605 -50.64986)
			(xy 259.481448 -50.63973) (xy 259.537182 -50.637693) (xy 259.592619 -50.643793) (xy 259.646576 -50.657899)
			(xy 259.697905 -50.679711) (xy 259.745511 -50.708765) (xy 259.788379 -50.74444) (xy 259.825596 -50.785977)
			(xy 259.856369 -50.83249) (xy 259.880041 -50.882987) (xy 259.896109 -50.936394) (xy 259.904229 -50.99157)
			(xy 259.904738 -51.019456) (xy 259.904229 -51.047342) (xy 259.896109 -51.102518) (xy 259.880041 -51.155925)
			(xy 259.856369 -51.206422) (xy 259.825596 -51.252935) (xy 259.788379 -51.294472) (xy 259.745511 -51.330147)
			(xy 259.697905 -51.359201) (xy 259.646576 -51.381013) (xy 259.592619 -51.395119) (xy 259.537182 -51.401219)
			(xy 259.481448 -51.399182) (xy 259.426605 -51.389052) (xy 259.373821 -51.371045) (xy 259.324221 -51.345544)
			(xy 259.278863 -51.313093) (xy 259.238714 -51.274384) (xy 259.204628 -51.230241) (xy 259.177332 -51.181606)
			(xy 259.157409 -51.129515) (xy 259.145283 -51.075078) (xy 259.141212 -51.019456) (xy 257.712501 -51.019456)
			(xy 257.712501 -51.046751) (xy 257.704744 -51.100699) (xy 257.689388 -51.152994) (xy 257.666745 -51.202571)
			(xy 257.637277 -51.24842) (xy 257.601584 -51.289609) (xy 257.560391 -51.325299) (xy 257.514539 -51.354762)
			(xy 257.46496 -51.3774) (xy 257.412664 -51.392751) (xy 257.358715 -51.400503) (xy 257.331464 -51.400964)
			(xy 257.305128 -51.400478) (xy 257.252954 -51.393252) (xy 257.20227 -51.378917) (xy 257.154042 -51.357743)
			(xy 257.109185 -51.330135) (xy 257.068554 -51.296617) (xy 257.032922 -51.257827) (xy 257.002966 -51.214503)
			(xy 256.979257 -51.167469) (xy 256.962245 -51.11762) (xy 256.956814 -51.091846) (xy 256.953689 -51.078332)
			(xy 256.941309 -51.053527) (xy 256.922699 -51.032979) (xy 256.899239 -51.018209) (xy 256.872666 -51.010311)
			(xy 256.844947 -51.00987) (xy 256.818135 -51.016918) (xy 256.805938 -51.02352) (xy 256.783983 -51.035817)
			(xy 256.737544 -51.055203) (xy 256.688961 -51.068317) (xy 256.639075 -51.074933) (xy 256.613914 -51.075336)
			(xy 256.586662 -51.074818) (xy 256.532714 -51.067063) (xy 256.480418 -51.051709) (xy 256.43084 -51.029069)
			(xy 256.384989 -50.999604) (xy 256.343797 -50.963913) (xy 256.308105 -50.922723) (xy 256.278638 -50.876872)
			(xy 256.255996 -50.827295) (xy 256.24064 -50.775) (xy 256.232883 -50.721051) (xy 241.425904 -50.721051)
			(xy 241.402335 -50.747356) (xy 241.359467 -50.783031) (xy 241.311861 -50.812085) (xy 241.260532 -50.833897)
			(xy 241.206575 -50.848003) (xy 241.151138 -50.854103) (xy 241.095404 -50.852066) (xy 241.040561 -50.841936)
			(xy 240.987777 -50.823929) (xy 240.938177 -50.798428) (xy 240.892819 -50.765977) (xy 240.85267 -50.727268)
			(xy 240.818584 -50.683125) (xy 240.791288 -50.63449) (xy 240.771365 -50.582399) (xy 240.759239 -50.527962)
			(xy 240.755168 -50.47234) (xy 202.733 -50.47234) (xy 202.734441 -50.475496) (xy 202.749796 -50.527792)
			(xy 202.757554 -50.58174) (xy 202.75804 -50.608992) (xy 202.75804 -50.609246) (xy 202.757599 -50.635541)
			(xy 202.750348 -50.68763) (xy 202.736018 -50.738231) (xy 202.714879 -50.786387) (xy 202.687332 -50.831186)
			(xy 202.653897 -50.871781) (xy 202.63485 -50.889916) (xy 202.62741 -50.897489) (xy 202.618883 -50.916906)
			(xy 202.61834 -50.927508) (xy 202.61834 -51.001676) (xy 202.618789 -51.012303) (xy 202.621921 -51.019456)
			(xy 218.849446 -51.019456) (xy 218.853517 -50.963834) (xy 218.865643 -50.909397) (xy 218.885566 -50.857306)
			(xy 218.912862 -50.808671) (xy 218.946948 -50.764528) (xy 218.987097 -50.725819) (xy 219.032455 -50.693368)
			(xy 219.082055 -50.667867) (xy 219.134839 -50.64986) (xy 219.189682 -50.63973) (xy 219.245416 -50.637693)
			(xy 219.300853 -50.643793) (xy 219.35481 -50.657899) (xy 219.406139 -50.679711) (xy 219.453745 -50.708765)
			(xy 219.496613 -50.74444) (xy 219.53383 -50.785977) (xy 219.564603 -50.83249) (xy 219.588275 -50.882987)
			(xy 219.604343 -50.936394) (xy 219.612463 -50.99157) (xy 219.612972 -51.019456) (xy 221.041212 -51.019456)
			(xy 221.045283 -50.963834) (xy 221.057409 -50.909397) (xy 221.077332 -50.857306) (xy 221.104628 -50.808671)
			(xy 221.138714 -50.764528) (xy 221.178863 -50.725819) (xy 221.224221 -50.693368) (xy 221.273821 -50.667867)
			(xy 221.326605 -50.64986) (xy 221.381448 -50.63973) (xy 221.437182 -50.637693) (xy 221.492619 -50.643793)
			(xy 221.546576 -50.657899) (xy 221.597905 -50.679711) (xy 221.645511 -50.708765) (xy 221.688379 -50.74444)
			(xy 221.725596 -50.785977) (xy 221.756369 -50.83249) (xy 221.780041 -50.882987) (xy 221.796109 -50.936394)
			(xy 221.804229 -50.99157) (xy 221.804738 -51.019456) (xy 221.804229 -51.047342) (xy 221.796109 -51.102518)
			(xy 221.780041 -51.155925) (xy 221.756369 -51.206422) (xy 221.745766 -51.222449) (xy 236.270302 -51.222449)
			(xy 236.270302 -51.167951) (xy 236.278058 -51.114007) (xy 236.293412 -51.061717) (xy 236.316051 -51.012143)
			(xy 236.345514 -50.966296) (xy 236.381203 -50.925109) (xy 236.42239 -50.889419) (xy 236.468236 -50.859955)
			(xy 236.517809 -50.837315) (xy 236.570099 -50.82196) (xy 236.624043 -50.814203) (xy 236.651292 -50.813716)
			(xy 236.679384 -50.814201) (xy 236.734962 -50.822428) (xy 236.788732 -50.838719) (xy 236.83953 -50.862723)
			(xy 236.886257 -50.89392) (xy 236.927902 -50.931634) (xy 236.963562 -50.97505) (xy 236.978444 -50.998882)
			(xy 236.984032 -51.008026) (xy 237.00105 -51.020218) (xy 237.094014 -51.040284) (xy 237.114588 -51.03622)
			(xy 237.123224 -51.030124) (xy 237.147282 -51.014114) (xy 237.199215 -50.988773) (xy 237.254375 -50.97155)
			(xy 237.311501 -50.962838) (xy 237.340394 -50.962306) (xy 237.367647 -50.962761) (xy 237.421599 -50.970517)
			(xy 237.473898 -50.985873) (xy 237.523479 -51.008516) (xy 237.569333 -51.037985) (xy 237.610526 -51.07368)
			(xy 237.64622 -51.114873) (xy 237.675688 -51.160728) (xy 237.698329 -51.210309) (xy 237.713684 -51.262609)
			(xy 237.72144 -51.316561) (xy 237.721902 -51.343814) (xy 237.721409 -51.371147) (xy 237.713606 -51.425253)
			(xy 237.698161 -51.477692) (xy 237.675392 -51.52739) (xy 237.645763 -51.57333) (xy 237.628176 -51.594258)
			(xy 237.627922 -51.594512) (xy 237.627668 -51.594766) (xy 237.622086 -51.601856) (xy 237.615838 -51.61877)
			(xy 237.615476 -51.627786) (xy 237.615476 -51.694842) (xy 237.615866 -51.703855) (xy 237.622091 -51.720772)
			(xy 237.627668 -51.727862) (xy 237.627922 -51.728116) (xy 237.628176 -51.72837) (xy 237.645788 -51.749282)
			(xy 237.675437 -51.795218) (xy 237.698222 -51.844917) (xy 237.713676 -51.897361) (xy 237.721483 -51.951474)
			(xy 237.721481 -52.006147) (xy 237.717251 -52.035456) (xy 259.141212 -52.035456) (xy 259.145283 -51.979834)
			(xy 259.157409 -51.925397) (xy 259.177332 -51.873306) (xy 259.204628 -51.824671) (xy 259.238714 -51.780528)
			(xy 259.278863 -51.741819) (xy 259.324221 -51.709368) (xy 259.373821 -51.683867) (xy 259.426605 -51.66586)
			(xy 259.481448 -51.65573) (xy 259.537182 -51.653693) (xy 259.592619 -51.659793) (xy 259.646576 -51.673899)
			(xy 259.682235 -51.689052) (xy 260.455377 -51.689052) (xy 260.455377 -51.634548) (xy 260.463134 -51.5806)
			(xy 260.47849 -51.528304) (xy 260.501132 -51.478726) (xy 260.530599 -51.432875) (xy 260.566292 -51.391684)
			(xy 260.607483 -51.355993) (xy 260.653335 -51.326527) (xy 260.702913 -51.303886) (xy 260.755209 -51.288532)
			(xy 260.809158 -51.280777) (xy 260.83641 -51.280314) (xy 260.863781 -51.280771) (xy 260.91796 -51.28859)
			(xy 260.970464 -51.304081) (xy 261.02021 -51.326925) (xy 261.066177 -51.356652) (xy 261.087108 -51.374294)
			(xy 261.087362 -51.374548) (xy 261.094451 -51.380131) (xy 261.111366 -51.386378) (xy 261.120382 -51.38674)
			(xy 261.187438 -51.38674) (xy 261.196458 -51.386414) (xy 261.213376 -51.380147) (xy 261.220458 -51.374548)
			(xy 261.220966 -51.37404) (xy 261.241899 -51.356456) (xy 261.287833 -51.326815) (xy 261.337529 -51.304037)
			(xy 261.389968 -51.288587) (xy 261.444076 -51.280783) (xy 261.47141 -51.280314) (xy 261.489753 -51.280541)
			(xy 261.526266 -51.284108) (xy 261.544308 -51.287426) (xy 261.544562 -51.287426) (xy 261.555065 -51.28882)
			(xy 261.575666 -51.283967) (xy 261.58444 -51.278028) (xy 261.653782 -51.225704) (xy 261.663942 -51.206908)
			(xy 261.664958 -51.195986) (xy 261.667845 -51.167701) (xy 261.680883 -51.112363) (xy 261.701981 -51.059569)
			(xy 261.730672 -51.010486) (xy 261.766321 -50.966199) (xy 261.786878 -50.946558) (xy 261.794333 -50.938998)
			(xy 261.802851 -50.919571) (xy 261.803388 -50.908966) (xy 261.803388 -50.834798) (xy 261.802975 -50.824166)
			(xy 261.794429 -50.804702) (xy 261.786878 -50.797206) (xy 261.767812 -50.779088) (xy 261.734357 -50.738503)
			(xy 261.7068 -50.693704) (xy 261.685663 -50.645542) (xy 261.671347 -50.594932) (xy 261.664125 -50.542834)
			(xy 261.663688 -50.516536) (xy 261.663688 -50.516282) (xy 261.664174 -50.489031) (xy 261.67193 -50.435083)
			(xy 261.687285 -50.382788) (xy 261.709927 -50.333211) (xy 261.739393 -50.287361) (xy 261.775084 -50.24617)
			(xy 261.816275 -50.210479) (xy 261.862125 -50.181013) (xy 261.911702 -50.158371) (xy 261.963997 -50.143016)
			(xy 262.017945 -50.13526) (xy 262.072447 -50.13526) (xy 262.126395 -50.143016) (xy 262.17869 -50.158371)
			(xy 262.228267 -50.181013) (xy 262.274117 -50.210479) (xy 262.315308 -50.24617) (xy 262.350999 -50.287361)
			(xy 262.380465 -50.333211) (xy 262.403107 -50.382788) (xy 262.418462 -50.435083) (xy 262.426218 -50.489031)
			(xy 262.426704 -50.516282) (xy 262.426704 -50.516536) (xy 262.426268 -50.542832) (xy 262.419018 -50.594921)
			(xy 262.404687 -50.645523) (xy 262.383548 -50.693679) (xy 262.355999 -50.738478) (xy 262.322562 -50.779072)
			(xy 262.303514 -50.797206) (xy 262.296073 -50.804778) (xy 262.287547 -50.824196) (xy 262.287004 -50.834798)
			(xy 262.287004 -50.908966) (xy 262.287385 -50.919601) (xy 262.295954 -50.939065) (xy 262.303514 -50.946558)
			(xy 262.322561 -50.964695) (xy 262.356018 -51.005276) (xy 262.383578 -51.05007) (xy 262.404719 -51.098229)
			(xy 262.419038 -51.148836) (xy 262.426264 -51.200931) (xy 262.426704 -51.227228) (xy 262.426704 -51.227482)
			(xy 262.426416 -51.243992) (xy 265.332972 -51.243992) (xy 265.333451 -51.216658) (xy 265.341255 -51.162551)
			(xy 265.356701 -51.110112) (xy 265.379475 -51.060414) (xy 265.409108 -51.014475) (xy 265.426698 -50.993548)
			(xy 265.426952 -50.993294) (xy 265.427206 -50.99304) (xy 265.432783 -50.985947) (xy 265.439035 -50.969035)
			(xy 265.439398 -50.96002) (xy 265.439398 -50.892964) (xy 265.439058 -50.883945) (xy 265.432799 -50.867029)
			(xy 265.427206 -50.859944) (xy 265.426952 -50.85969) (xy 265.426698 -50.859436) (xy 265.409109 -50.838508)
			(xy 265.37947 -50.792571) (xy 265.356693 -50.742874) (xy 265.341244 -50.690434) (xy 265.333441 -50.636326)
			(xy 265.332972 -50.608992) (xy 265.33347 -50.581741) (xy 265.341227 -50.527795) (xy 265.356582 -50.475502)
			(xy 265.379223 -50.425926) (xy 265.408688 -50.380077) (xy 265.444378 -50.338887) (xy 265.485567 -50.303196)
			(xy 265.531415 -50.273729) (xy 265.580991 -50.251087) (xy 265.633283 -50.23573) (xy 265.687229 -50.227971)
			(xy 265.71448 -50.227484) (xy 265.743398 -50.227985) (xy 265.800571 -50.236713) (xy 265.855772 -50.253972)
			(xy 265.907734 -50.279367) (xy 265.955268 -50.312315) (xy 265.997282 -50.352062) (xy 266.01547 -50.37455)
			(xy 266.021765 -50.381923) (xy 266.038471 -50.391726) (xy 266.047982 -50.3936) (xy 266.055602 -50.394108)
			(xy 266.135358 -50.394108) (xy 266.142978 -50.3936) (xy 266.152496 -50.391747) (xy 266.169209 -50.381939)
			(xy 266.17549 -50.37455) (xy 266.193674 -50.352061) (xy 266.235697 -50.312328) (xy 266.283234 -50.279391)
			(xy 266.335196 -50.254005) (xy 266.390394 -50.236749) (xy 266.447564 -50.22802) (xy 266.47648 -50.227484)
			(xy 266.503732 -50.227974) (xy 266.557682 -50.235728) (xy 266.609978 -50.251081) (xy 266.659558 -50.273721)
			(xy 266.705411 -50.303186) (xy 266.746603 -50.338877) (xy 266.782297 -50.380067) (xy 266.811766 -50.425917)
			(xy 266.834409 -50.475495) (xy 266.849766 -50.527791) (xy 266.857524 -50.58174) (xy 266.857988 -50.608992)
			(xy 266.857988 -50.609246) (xy 266.857564 -50.635542) (xy 266.850312 -50.687632) (xy 266.835979 -50.738235)
			(xy 266.814838 -50.786391) (xy 266.787286 -50.831189) (xy 266.753847 -50.871783) (xy 266.734798 -50.889916)
			(xy 266.727351 -50.897482) (xy 266.718829 -50.916904) (xy 266.718288 -50.927508) (xy 266.718288 -51.001676)
			(xy 266.718722 -51.012305) (xy 266.721857 -51.019456) (xy 282.949394 -51.019456) (xy 282.953465 -50.963834)
			(xy 282.965591 -50.909397) (xy 282.985514 -50.857306) (xy 283.01281 -50.808671) (xy 283.046896 -50.764528)
			(xy 283.087045 -50.725819) (xy 283.132403 -50.693368) (xy 283.182003 -50.667867) (xy 283.234787 -50.64986)
			(xy 283.28963 -50.63973) (xy 283.345364 -50.637693) (xy 283.400801 -50.643793) (xy 283.454758 -50.657899)
			(xy 283.506087 -50.679711) (xy 283.553693 -50.708765) (xy 283.596561 -50.74444) (xy 283.633778 -50.785977)
			(xy 283.664551 -50.83249) (xy 283.688223 -50.882987) (xy 283.704291 -50.936394) (xy 283.712411 -50.99157)
			(xy 283.71292 -51.019456) (xy 285.14116 -51.019456) (xy 285.145231 -50.963834) (xy 285.157357 -50.909397)
			(xy 285.17728 -50.857306) (xy 285.204576 -50.808671) (xy 285.238662 -50.764528) (xy 285.278811 -50.725819)
			(xy 285.324169 -50.693368) (xy 285.373769 -50.667867) (xy 285.426553 -50.64986) (xy 285.481396 -50.63973)
			(xy 285.53713 -50.637693) (xy 285.592567 -50.643793) (xy 285.646524 -50.657899) (xy 285.697853 -50.679711)
			(xy 285.745459 -50.708765) (xy 285.788327 -50.74444) (xy 285.825544 -50.785977) (xy 285.856317 -50.83249)
			(xy 285.879989 -50.882987) (xy 285.896057 -50.936394) (xy 285.904177 -50.99157) (xy 285.904686 -51.019456)
			(xy 285.904177 -51.047342) (xy 285.896057 -51.102518) (xy 285.879989 -51.155925) (xy 285.856317 -51.206422)
			(xy 285.825544 -51.252935) (xy 285.788327 -51.294472) (xy 285.745459 -51.330147) (xy 285.697853 -51.359201)
			(xy 285.646524 -51.381013) (xy 285.592567 -51.395119) (xy 285.53713 -51.401219) (xy 285.481396 -51.399182)
			(xy 285.426553 -51.389052) (xy 285.373769 -51.371045) (xy 285.324169 -51.345544) (xy 285.278811 -51.313093)
			(xy 285.238662 -51.274384) (xy 285.204576 -51.230241) (xy 285.17728 -51.181606) (xy 285.157357 -51.129515)
			(xy 285.145231 -51.075078) (xy 285.14116 -51.019456) (xy 283.71292 -51.019456) (xy 283.712411 -51.047342)
			(xy 283.704291 -51.102518) (xy 283.688223 -51.155925) (xy 283.664551 -51.206422) (xy 283.633778 -51.252935)
			(xy 283.596561 -51.294472) (xy 283.553693 -51.330147) (xy 283.506087 -51.359201) (xy 283.454758 -51.381013)
			(xy 283.400801 -51.395119) (xy 283.345364 -51.401219) (xy 283.28963 -51.399182) (xy 283.234787 -51.389052)
			(xy 283.182003 -51.371045) (xy 283.132403 -51.345544) (xy 283.087045 -51.313093) (xy 283.046896 -51.274384)
			(xy 283.01281 -51.230241) (xy 282.985514 -51.181606) (xy 282.965591 -51.129515) (xy 282.953465 -51.075078)
			(xy 282.949394 -51.019456) (xy 266.721857 -51.019456) (xy 266.727254 -51.031769) (xy 266.734798 -51.039268)
			(xy 266.753847 -51.057403) (xy 266.787304 -51.097984) (xy 266.814864 -51.142779) (xy 266.836005 -51.190938)
			(xy 266.850324 -51.241545) (xy 266.857549 -51.293641) (xy 266.857988 -51.319938) (xy 266.857988 -51.320192)
			(xy 266.857537 -51.347446) (xy 266.849781 -51.401398) (xy 266.834425 -51.453697) (xy 266.811782 -51.503279)
			(xy 266.782313 -51.549133) (xy 266.746618 -51.590326) (xy 266.705423 -51.62602) (xy 266.659568 -51.655487)
			(xy 266.609986 -51.678129) (xy 266.557686 -51.693483) (xy 266.503734 -51.701238) (xy 266.47648 -51.7017)
			(xy 266.448814 -51.701203) (xy 266.394064 -51.693201) (xy 266.341042 -51.677382) (xy 266.290858 -51.654076)
			(xy 266.244563 -51.623773) (xy 266.203125 -51.587105) (xy 266.167413 -51.544842) (xy 266.152376 -51.521614)
			(xy 266.152122 -51.52136) (xy 266.14546 -51.511832) (xy 266.125763 -51.499528) (xy 266.114276 -51.497738)
			(xy 266.034266 -51.489864) (xy 266.022565 -51.489187) (xy 266.00059 -51.497274) (xy 265.992102 -51.505358)
			(xy 265.992102 -51.505612) (xy 265.974005 -51.524177) (xy 265.933676 -51.556756) (xy 265.889305 -51.583571)
			(xy 265.84171 -51.604127) (xy 265.791769 -51.618044) (xy 265.740402 -51.625066) (xy 265.71448 -51.6255)
			(xy 265.687228 -51.625041) (xy 265.633279 -51.617281) (xy 265.580983 -51.601923) (xy 265.531405 -51.579279)
			(xy 265.485555 -51.54981) (xy 265.444364 -51.514116) (xy 265.408673 -51.472923) (xy 265.379207 -51.42707)
			(xy 265.356567 -51.377491) (xy 265.341213 -51.325194) (xy 265.333457 -51.271244) (xy 265.332972 -51.243992)
			(xy 262.426416 -51.243992) (xy 262.426228 -51.254735) (xy 262.418473 -51.308685) (xy 262.403119 -51.360983)
			(xy 262.380479 -51.410563) (xy 262.351012 -51.456417) (xy 262.31532 -51.49761) (xy 262.274128 -51.533304)
			(xy 262.228276 -51.562772) (xy 262.178696 -51.585414) (xy 262.126399 -51.60077) (xy 262.072449 -51.608527)
			(xy 262.045196 -51.60899) (xy 262.026853 -51.608762) (xy 261.99034 -51.605196) (xy 261.972298 -51.601878)
			(xy 261.972044 -51.601878) (xy 261.96154 -51.600487) (xy 261.94094 -51.605338) (xy 261.932166 -51.611276)
			(xy 261.862824 -51.6636) (xy 261.852664 -51.682396) (xy 261.851648 -51.693318) (xy 261.84876 -51.721577)
			(xy 261.835727 -51.776863) (xy 261.814642 -51.829606) (xy 261.78597 -51.87864) (xy 261.750345 -51.922881)
			(xy 261.708555 -51.961352) (xy 261.661523 -51.993202) (xy 261.610288 -52.017727) (xy 261.555984 -52.034384)
			(xy 261.548835 -52.035456) (xy 285.14116 -52.035456) (xy 285.145231 -51.979834) (xy 285.157357 -51.925397)
			(xy 285.17728 -51.873306) (xy 285.204576 -51.824671) (xy 285.238662 -51.780528) (xy 285.278811 -51.741819)
			(xy 285.324169 -51.709368) (xy 285.373769 -51.683867) (xy 285.426553 -51.66586) (xy 285.481396 -51.65573)
			(xy 285.53713 -51.653693) (xy 285.592567 -51.659793) (xy 285.646524 -51.673899) (xy 285.682173 -51.689048)
			(xy 286.4554 -51.689048) (xy 286.4554 -51.634552) (xy 286.463155 -51.580611) (xy 286.478507 -51.528323)
			(xy 286.501144 -51.478752) (xy 286.530605 -51.432906) (xy 286.566289 -51.391719) (xy 286.607472 -51.35603)
			(xy 286.653315 -51.326564) (xy 286.702884 -51.303922) (xy 286.75517 -51.288564) (xy 286.80911 -51.280803)
			(xy 286.836358 -51.280314) (xy 286.863728 -51.280801) (xy 286.917906 -51.288613) (xy 286.970409 -51.304097)
			(xy 287.020156 -51.326934) (xy 287.066124 -51.356655) (xy 287.087056 -51.374294) (xy 287.08731 -51.374548)
			(xy 287.094385 -51.380151) (xy 287.111311 -51.386387) (xy 287.12033 -51.38674) (xy 287.187386 -51.38674)
			(xy 287.196404 -51.386389) (xy 287.213321 -51.380139) (xy 287.220406 -51.374548) (xy 287.220914 -51.37404)
			(xy 287.241829 -51.356434) (xy 287.287768 -51.326796) (xy 287.337469 -51.304022) (xy 287.389912 -51.288577)
			(xy 287.444023 -51.280779) (xy 287.471358 -51.280314) (xy 287.489701 -51.280549) (xy 287.526214 -51.28411)
			(xy 287.544256 -51.287426) (xy 287.54451 -51.287426) (xy 287.555012 -51.288848) (xy 287.575615 -51.283976)
			(xy 287.584388 -51.278028) (xy 287.65373 -51.225704) (xy 287.66389 -51.206908) (xy 287.664906 -51.195986)
			(xy 287.667809 -51.167703) (xy 287.680845 -51.112366) (xy 287.70194 -51.059573) (xy 287.730627 -51.01049)
			(xy 287.766272 -50.9662) (xy 287.786826 -50.946558) (xy 287.794274 -50.938991) (xy 287.802798 -50.91957)
			(xy 287.803336 -50.908966) (xy 287.803336 -50.834798) (xy 287.802909 -50.824168) (xy 287.794371 -50.804704)
			(xy 287.786826 -50.797206) (xy 287.767769 -50.779079) (xy 287.734312 -50.738497) (xy 287.706752 -50.6937)
			(xy 287.685613 -50.64554) (xy 287.671296 -50.594931) (xy 287.664073 -50.542834) (xy 287.663636 -50.516536)
			(xy 287.663636 -50.516282) (xy 287.664122 -50.489031) (xy 287.671878 -50.435083) (xy 287.687233 -50.382788)
			(xy 287.709875 -50.333211) (xy 287.739341 -50.287361) (xy 287.775032 -50.24617) (xy 287.816223 -50.210479)
			(xy 287.862073 -50.181013) (xy 287.91165 -50.158371) (xy 287.963945 -50.143016) (xy 288.017893 -50.13526)
			(xy 288.072395 -50.13526) (xy 288.126343 -50.143016) (xy 288.178638 -50.158371) (xy 288.228215 -50.181013)
			(xy 288.274065 -50.210479) (xy 288.315256 -50.24617) (xy 288.350947 -50.287361) (xy 288.380413 -50.333211)
			(xy 288.403055 -50.382788) (xy 288.41841 -50.435083) (xy 288.426166 -50.489031) (xy 288.426652 -50.516282)
			(xy 288.426652 -50.516536) (xy 288.426233 -50.542832) (xy 288.418981 -50.594923) (xy 288.404649 -50.645526)
			(xy 288.383506 -50.693682) (xy 288.355953 -50.738481) (xy 288.322512 -50.779073) (xy 288.303462 -50.797206)
			(xy 288.296028 -50.804785) (xy 288.287497 -50.824197) (xy 288.286952 -50.834798) (xy 288.286952 -50.908966)
			(xy 288.287348 -50.919599) (xy 288.295908 -50.939062) (xy 288.303462 -50.946558) (xy 288.322499 -50.964705)
			(xy 288.355959 -51.005283) (xy 288.383522 -51.050075) (xy 288.404664 -51.098231) (xy 288.418985 -51.148837)
			(xy 288.426212 -51.200931) (xy 288.426652 -51.227228) (xy 288.426652 -51.227482) (xy 288.426321 -51.243992)
			(xy 291.33292 -51.243992) (xy 291.333412 -51.216659) (xy 291.341214 -51.162553) (xy 291.356659 -51.110114)
			(xy 291.379429 -51.060416) (xy 291.409058 -51.014476) (xy 291.426646 -50.993548) (xy 291.4269 -50.993294)
			(xy 291.427154 -50.99304) (xy 291.432736 -50.985951) (xy 291.438984 -50.969036) (xy 291.439346 -50.96002)
			(xy 291.439346 -50.892964) (xy 291.439018 -50.883944) (xy 291.432752 -50.867027) (xy 291.427154 -50.859944)
			(xy 291.4269 -50.85969) (xy 291.426646 -50.859436) (xy 291.409064 -50.838502) (xy 291.379423 -50.792568)
			(xy 291.356643 -50.742872) (xy 291.341193 -50.690433) (xy 291.333389 -50.636326) (xy 291.33292 -50.608992)
			(xy 291.333348 -50.581738) (xy 291.341107 -50.527784) (xy 291.356465 -50.475484) (xy 291.379111 -50.425902)
			(xy 291.408582 -50.380047) (xy 291.44428 -50.338854) (xy 291.485476 -50.303161) (xy 291.531333 -50.273693)
			(xy 291.580918 -50.251053) (xy 291.633219 -50.235699) (xy 291.687174 -50.227945) (xy 291.714428 -50.227484)
			(xy 291.743345 -50.228022) (xy 291.800516 -50.236743) (xy 291.855716 -50.253995) (xy 291.907679 -50.279382)
			(xy 291.955213 -50.312324) (xy 291.997229 -50.352065) (xy 292.015418 -50.37455) (xy 292.021696 -50.381941)
			(xy 292.038414 -50.391734) (xy 292.04793 -50.3936) (xy 292.05555 -50.394108) (xy 292.135306 -50.394108)
			(xy 292.142926 -50.3936) (xy 292.152438 -50.391724) (xy 292.169154 -50.381933) (xy 292.175438 -50.37455)
			(xy 292.193595 -50.352038) (xy 292.235623 -50.312307) (xy 292.283166 -50.279373) (xy 292.335133 -50.25399)
			(xy 292.390336 -50.236739) (xy 292.44751 -50.228016) (xy 292.476428 -50.227484) (xy 292.50368 -50.227952)
			(xy 292.557628 -50.235712) (xy 292.609922 -50.25107) (xy 292.659499 -50.273714) (xy 292.705349 -50.303182)
			(xy 292.746538 -50.338876) (xy 292.78223 -50.380067) (xy 292.811696 -50.425919) (xy 292.828371 -50.462434)
			(xy 307.026054 -50.462434) (xy 307.030125 -50.406812) (xy 307.042251 -50.352375) (xy 307.062174 -50.300284)
			(xy 307.08947 -50.251649) (xy 307.123556 -50.207506) (xy 307.163705 -50.168797) (xy 307.209063 -50.136346)
			(xy 307.258663 -50.110845) (xy 307.311447 -50.092838) (xy 307.36629 -50.082708) (xy 307.422024 -50.080671)
			(xy 307.477461 -50.086771) (xy 307.531418 -50.100877) (xy 307.582747 -50.122689) (xy 307.630353 -50.151743)
			(xy 307.673221 -50.187418) (xy 307.710438 -50.228955) (xy 307.741211 -50.275468) (xy 307.764883 -50.325965)
			(xy 307.780951 -50.379372) (xy 307.789071 -50.434548) (xy 307.78958 -50.462434) (xy 307.789071 -50.49032)
			(xy 307.780951 -50.545496) (xy 307.764883 -50.598903) (xy 307.741211 -50.6494) (xy 307.710438 -50.695913)
			(xy 307.673221 -50.73745) (xy 307.630353 -50.773125) (xy 307.582747 -50.802179) (xy 307.531418 -50.823991)
			(xy 307.477461 -50.838097) (xy 307.422024 -50.844197) (xy 307.36629 -50.84216) (xy 307.311447 -50.83203)
			(xy 307.258663 -50.814023) (xy 307.209063 -50.788522) (xy 307.163705 -50.756071) (xy 307.123556 -50.717362)
			(xy 307.08947 -50.673219) (xy 307.062174 -50.624584) (xy 307.042251 -50.572493) (xy 307.030125 -50.518056)
			(xy 307.026054 -50.462434) (xy 292.828371 -50.462434) (xy 292.834337 -50.475497) (xy 292.849692 -50.527792)
			(xy 292.85745 -50.58174) (xy 292.857936 -50.608992) (xy 292.857936 -50.609246) (xy 292.857496 -50.635541)
			(xy 292.850246 -50.68763) (xy 292.835915 -50.738232) (xy 292.814776 -50.786387) (xy 292.787228 -50.831187)
			(xy 292.753793 -50.871782) (xy 292.734746 -50.889916) (xy 292.727306 -50.897489) (xy 292.718779 -50.916906)
			(xy 292.718236 -50.927508) (xy 292.718236 -51.001676) (xy 292.718656 -51.012307) (xy 292.721793 -51.019456)
			(xy 308.949342 -51.019456) (xy 308.953413 -50.963834) (xy 308.965539 -50.909397) (xy 308.985462 -50.857306)
			(xy 309.012758 -50.808671) (xy 309.046844 -50.764528) (xy 309.086993 -50.725819) (xy 309.132351 -50.693368)
			(xy 309.181951 -50.667867) (xy 309.234735 -50.64986) (xy 309.289578 -50.63973) (xy 309.345312 -50.637693)
			(xy 309.400749 -50.643793) (xy 309.454706 -50.657899) (xy 309.506035 -50.679711) (xy 309.553641 -50.708765)
			(xy 309.596509 -50.74444) (xy 309.633726 -50.785977) (xy 309.664499 -50.83249) (xy 309.688171 -50.882987)
			(xy 309.704239 -50.936394) (xy 309.712359 -50.99157) (xy 309.712868 -51.019456) (xy 311.141108 -51.019456)
			(xy 311.145179 -50.963834) (xy 311.157305 -50.909397) (xy 311.177228 -50.857306) (xy 311.204524 -50.808671)
			(xy 311.23861 -50.764528) (xy 311.278759 -50.725819) (xy 311.324117 -50.693368) (xy 311.373717 -50.667867)
			(xy 311.426501 -50.64986) (xy 311.481344 -50.63973) (xy 311.537078 -50.637693) (xy 311.592515 -50.643793)
			(xy 311.646472 -50.657899) (xy 311.697801 -50.679711) (xy 311.745407 -50.708765) (xy 311.788275 -50.74444)
			(xy 311.825492 -50.785977) (xy 311.856265 -50.83249) (xy 311.879937 -50.882987) (xy 311.896005 -50.936394)
			(xy 311.904125 -50.99157) (xy 311.904634 -51.019456) (xy 311.904125 -51.047342) (xy 311.896005 -51.102518)
			(xy 311.879937 -51.155925) (xy 311.856265 -51.206422) (xy 311.825492 -51.252935) (xy 311.788275 -51.294472)
			(xy 311.745407 -51.330147) (xy 311.697801 -51.359201) (xy 311.646472 -51.381013) (xy 311.592515 -51.395119)
			(xy 311.537078 -51.401219) (xy 311.481344 -51.399182) (xy 311.426501 -51.389052) (xy 311.373717 -51.371045)
			(xy 311.324117 -51.345544) (xy 311.278759 -51.313093) (xy 311.23861 -51.274384) (xy 311.204524 -51.230241)
			(xy 311.177228 -51.181606) (xy 311.157305 -51.129515) (xy 311.145179 -51.075078) (xy 311.141108 -51.019456)
			(xy 309.712868 -51.019456) (xy 309.712359 -51.047342) (xy 309.704239 -51.102518) (xy 309.688171 -51.155925)
			(xy 309.664499 -51.206422) (xy 309.633726 -51.252935) (xy 309.596509 -51.294472) (xy 309.553641 -51.330147)
			(xy 309.506035 -51.359201) (xy 309.454706 -51.381013) (xy 309.400749 -51.395119) (xy 309.345312 -51.401219)
			(xy 309.289578 -51.399182) (xy 309.234735 -51.389052) (xy 309.181951 -51.371045) (xy 309.132351 -51.345544)
			(xy 309.086993 -51.313093) (xy 309.046844 -51.274384) (xy 309.012758 -51.230241) (xy 308.985462 -51.181606)
			(xy 308.965539 -51.129515) (xy 308.953413 -51.075078) (xy 308.949342 -51.019456) (xy 292.721793 -51.019456)
			(xy 292.727197 -51.031772) (xy 292.734746 -51.039268) (xy 292.753785 -51.057414) (xy 292.787245 -51.097991)
			(xy 292.814808 -51.142783) (xy 292.83595 -51.19094) (xy 292.850271 -51.241546) (xy 292.857497 -51.293641)
			(xy 292.857936 -51.319938) (xy 292.857936 -51.320192) (xy 292.857415 -51.347442) (xy 292.84966 -51.401387)
			(xy 292.834307 -51.453679) (xy 292.811669 -51.503255) (xy 292.782206 -51.549104) (xy 292.746519 -51.590293)
			(xy 292.705332 -51.625985) (xy 292.659486 -51.655452) (xy 292.609913 -51.678095) (xy 292.557622 -51.693453)
			(xy 292.503678 -51.701212) (xy 292.476428 -51.7017) (xy 292.448764 -51.701166) (xy 292.394016 -51.69317)
			(xy 292.340994 -51.677358) (xy 292.290811 -51.654058) (xy 292.244515 -51.62376) (xy 292.203076 -51.587098)
			(xy 292.167362 -51.544839) (xy 292.152324 -51.521614) (xy 292.15207 -51.52136) (xy 292.145432 -51.511812)
			(xy 292.125717 -51.499518) (xy 292.114224 -51.497738) (xy 292.034214 -51.489864) (xy 292.022513 -51.489216)
			(xy 292.000541 -51.497283) (xy 291.99205 -51.505358) (xy 291.99205 -51.505612) (xy 291.973978 -51.524202)
			(xy 291.933644 -51.556779) (xy 291.889267 -51.583591) (xy 291.841667 -51.604142) (xy 291.791722 -51.618054)
			(xy 291.740352 -51.625069) (xy 291.714428 -51.6255) (xy 291.687175 -51.625019) (xy 291.633225 -51.617265)
			(xy 291.580927 -51.601912) (xy 291.531346 -51.579273) (xy 291.485493 -51.549807) (xy 291.444299 -51.514115)
			(xy 291.408605 -51.472923) (xy 291.379137 -51.427071) (xy 291.356495 -51.377492) (xy 291.341139 -51.325195)
			(xy 291.333383 -51.271244) (xy 291.33292 -51.243992) (xy 288.426321 -51.243992) (xy 288.426105 -51.254731)
			(xy 288.418352 -51.308674) (xy 288.403002 -51.360965) (xy 288.380366 -51.410539) (xy 288.350906 -51.456387)
			(xy 288.31522 -51.497577) (xy 288.274037 -51.533268) (xy 288.228193 -51.562736) (xy 288.178623 -51.58538)
			(xy 288.126335 -51.600739) (xy 288.072393 -51.608501) (xy 288.045144 -51.60899) (xy 288.026801 -51.608755)
			(xy 287.990288 -51.605194) (xy 287.972246 -51.601878) (xy 287.971992 -51.601878) (xy 287.96149 -51.600456)
			(xy 287.940887 -51.605328) (xy 287.932114 -51.611276) (xy 287.862772 -51.6636) (xy 287.852612 -51.682396)
			(xy 287.851596 -51.693318) (xy 287.848661 -51.721571) (xy 287.83563 -51.776853) (xy 287.814548 -51.829592)
			(xy 287.785881 -51.878624) (xy 287.750261 -51.922864) (xy 287.708477 -51.961334) (xy 287.661451 -51.993185)
			(xy 287.610223 -52.017713) (xy 287.555925 -52.034375) (xy 287.548721 -52.035456) (xy 311.141108 -52.035456)
			(xy 311.145179 -51.979834) (xy 311.157305 -51.925397) (xy 311.177228 -51.873306) (xy 311.204524 -51.824671)
			(xy 311.23861 -51.780528) (xy 311.278759 -51.741819) (xy 311.324117 -51.709368) (xy 311.373717 -51.683867)
			(xy 311.426501 -51.66586) (xy 311.481344 -51.65573) (xy 311.537078 -51.653693) (xy 311.592515 -51.659793)
			(xy 311.646472 -51.673899) (xy 311.682131 -51.689052) (xy 312.455277 -51.689052) (xy 312.455277 -51.634548)
			(xy 312.463034 -51.5806) (xy 312.478389 -51.528305) (xy 312.501031 -51.478727) (xy 312.530498 -51.432876)
			(xy 312.56619 -51.391686) (xy 312.607381 -51.355994) (xy 312.653232 -51.326528) (xy 312.70281 -51.303887)
			(xy 312.755106 -51.288533) (xy 312.809054 -51.280777) (xy 312.836306 -51.280314) (xy 312.863677 -51.280773)
			(xy 312.917856 -51.288592) (xy 312.970359 -51.304083) (xy 313.020106 -51.326926) (xy 313.066073 -51.356652)
			(xy 313.087004 -51.374294) (xy 313.087258 -51.374548) (xy 313.094348 -51.380129) (xy 313.111262 -51.386378)
			(xy 313.120278 -51.38674) (xy 313.187334 -51.38674) (xy 313.196354 -51.386412) (xy 313.213272 -51.380146)
			(xy 313.220354 -51.374548) (xy 313.220862 -51.37404) (xy 313.241796 -51.356458) (xy 313.28773 -51.326817)
			(xy 313.337426 -51.304038) (xy 313.389865 -51.288588) (xy 313.443972 -51.280783) (xy 313.471306 -51.280314)
			(xy 313.489649 -51.280542) (xy 313.526162 -51.284108) (xy 313.544204 -51.287426) (xy 313.544458 -51.287426)
			(xy 313.554962 -51.288818) (xy 313.575562 -51.283967) (xy 313.584336 -51.278028) (xy 313.653678 -51.225704)
			(xy 313.663838 -51.206908) (xy 313.664854 -51.195986) (xy 313.667742 -51.167701) (xy 313.68078 -51.112363)
			(xy 313.701878 -51.05957) (xy 313.730568 -51.010487) (xy 313.766218 -50.966199) (xy 313.786774 -50.946558)
			(xy 313.794229 -50.938998) (xy 313.802747 -50.919571) (xy 313.803284 -50.908966) (xy 313.803284 -50.834798)
			(xy 313.802872 -50.824166) (xy 313.794325 -50.804701) (xy 313.786774 -50.797206) (xy 313.767707 -50.779089)
			(xy 313.734253 -50.738504) (xy 313.706695 -50.693705) (xy 313.685558 -50.645543) (xy 313.671243 -50.594932)
			(xy 313.664021 -50.542834) (xy 313.663584 -50.516536) (xy 313.663584 -50.516282) (xy 313.66407 -50.489031)
			(xy 313.671826 -50.435083) (xy 313.687181 -50.382788) (xy 313.709823 -50.333211) (xy 313.739289 -50.287361)
			(xy 313.77498 -50.24617) (xy 313.816171 -50.210479) (xy 313.862021 -50.181013) (xy 313.911598 -50.158371)
			(xy 313.963893 -50.143016) (xy 314.017841 -50.13526) (xy 314.072343 -50.13526) (xy 314.126291 -50.143016)
			(xy 314.178586 -50.158371) (xy 314.228163 -50.181013) (xy 314.274013 -50.210479) (xy 314.315204 -50.24617)
			(xy 314.350895 -50.287361) (xy 314.380361 -50.333211) (xy 314.403003 -50.382788) (xy 314.418358 -50.435083)
			(xy 314.426114 -50.489031) (xy 314.4266 -50.516282) (xy 314.4266 -50.516536) (xy 314.426165 -50.542832)
			(xy 314.418915 -50.594921) (xy 314.404584 -50.645523) (xy 314.383444 -50.693679) (xy 314.355895 -50.738478)
			(xy 314.322458 -50.779072) (xy 314.30341 -50.797206) (xy 314.295969 -50.804778) (xy 314.287443 -50.824196)
			(xy 314.2869 -50.834798) (xy 314.2869 -50.908966) (xy 314.287282 -50.919601) (xy 314.29585 -50.939065)
			(xy 314.30341 -50.946558) (xy 314.322456 -50.964696) (xy 314.355913 -51.005276) (xy 314.383474 -51.050071)
			(xy 314.404614 -51.098229) (xy 314.418934 -51.148836) (xy 314.42616 -51.200931) (xy 314.4266 -51.227228)
			(xy 314.4266 -51.227482) (xy 314.426314 -51.243992) (xy 317.332868 -51.243992) (xy 317.333348 -51.216658)
			(xy 317.341152 -51.162551) (xy 317.356598 -51.110112) (xy 317.379371 -51.060414) (xy 317.409004 -51.014475)
			(xy 317.426594 -50.993548) (xy 317.426848 -50.993294) (xy 317.427102 -50.99304) (xy 317.432678 -50.985946)
			(xy 317.438931 -50.969035) (xy 317.439294 -50.96002) (xy 317.439294 -50.892964) (xy 317.438955 -50.883945)
			(xy 317.432695 -50.867028) (xy 317.427102 -50.859944) (xy 317.426848 -50.85969) (xy 317.426594 -50.859436)
			(xy 317.409004 -50.838508) (xy 317.379366 -50.792572) (xy 317.356589 -50.742874) (xy 317.34114 -50.690434)
			(xy 317.333337 -50.636326) (xy 317.332868 -50.608992) (xy 317.33337 -50.581742) (xy 317.341127 -50.527796)
			(xy 317.356482 -50.475503) (xy 317.379123 -50.425927) (xy 317.408587 -50.380078) (xy 317.444277 -50.338888)
			(xy 317.485465 -50.303197) (xy 317.531313 -50.27373) (xy 317.580888 -50.251088) (xy 317.63318 -50.235731)
			(xy 317.687126 -50.227971) (xy 317.714376 -50.227484) (xy 317.743294 -50.227988) (xy 317.800467 -50.236715)
			(xy 317.855668 -50.253974) (xy 317.90763 -50.279368) (xy 317.955163 -50.312316) (xy 317.997178 -50.352062)
			(xy 318.015366 -50.37455) (xy 318.021663 -50.381922) (xy 318.038367 -50.391726) (xy 318.047878 -50.3936)
			(xy 318.055498 -50.394108) (xy 318.135254 -50.394108) (xy 318.142874 -50.3936) (xy 318.152392 -50.391745)
			(xy 318.169105 -50.381939) (xy 318.175386 -50.37455) (xy 318.193572 -50.352063) (xy 318.235595 -50.31233)
			(xy 318.283131 -50.279393) (xy 318.335093 -50.254006) (xy 318.39029 -50.23675) (xy 318.44746 -50.22802)
			(xy 318.476376 -50.227484) (xy 318.503628 -50.227978) (xy 318.557577 -50.235731) (xy 318.609874 -50.251084)
			(xy 318.659454 -50.273723) (xy 318.705306 -50.303188) (xy 318.746499 -50.338878) (xy 318.782193 -50.380068)
			(xy 318.811662 -50.425918) (xy 318.834305 -50.475496) (xy 318.849662 -50.527791) (xy 318.85742 -50.58174)
			(xy 318.857884 -50.608992) (xy 318.857884 -50.609246) (xy 318.857461 -50.635542) (xy 318.850209 -50.687633)
			(xy 318.835876 -50.738235) (xy 318.814734 -50.786391) (xy 318.787183 -50.83119) (xy 318.753743 -50.871783)
			(xy 318.734694 -50.889916) (xy 318.727246 -50.897482) (xy 318.718725 -50.916904) (xy 318.718184 -50.927508)
			(xy 318.718184 -51.001676) (xy 318.71862 -51.012305) (xy 318.721754 -51.019456) (xy 334.94929 -51.019456)
			(xy 334.953361 -50.963834) (xy 334.965487 -50.909397) (xy 334.98541 -50.857306) (xy 335.012706 -50.808671)
			(xy 335.046792 -50.764528) (xy 335.086941 -50.725819) (xy 335.132299 -50.693368) (xy 335.181899 -50.667867)
			(xy 335.234683 -50.64986) (xy 335.289526 -50.63973) (xy 335.34526 -50.637693) (xy 335.400697 -50.643793)
			(xy 335.454654 -50.657899) (xy 335.505983 -50.679711) (xy 335.553589 -50.708765) (xy 335.596457 -50.74444)
			(xy 335.633674 -50.785977) (xy 335.664447 -50.83249) (xy 335.688119 -50.882987) (xy 335.704187 -50.936394)
			(xy 335.712307 -50.99157) (xy 335.712816 -51.019456) (xy 337.141056 -51.019456) (xy 337.145127 -50.963834)
			(xy 337.157253 -50.909397) (xy 337.177176 -50.857306) (xy 337.204472 -50.808671) (xy 337.238558 -50.764528)
			(xy 337.278707 -50.725819) (xy 337.324065 -50.693368) (xy 337.373665 -50.667867) (xy 337.426449 -50.64986)
			(xy 337.481292 -50.63973) (xy 337.537026 -50.637693) (xy 337.592463 -50.643793) (xy 337.64642 -50.657899)
			(xy 337.697749 -50.679711) (xy 337.745355 -50.708765) (xy 337.788223 -50.74444) (xy 337.82544 -50.785977)
			(xy 337.856213 -50.83249) (xy 337.879885 -50.882987) (xy 337.895953 -50.936394) (xy 337.904073 -50.99157)
			(xy 337.904582 -51.019456) (xy 337.904073 -51.047342) (xy 337.895953 -51.102518) (xy 337.879885 -51.155925)
			(xy 337.856213 -51.206422) (xy 337.82544 -51.252935) (xy 337.788223 -51.294472) (xy 337.745355 -51.330147)
			(xy 337.697749 -51.359201) (xy 337.64642 -51.381013) (xy 337.592463 -51.395119) (xy 337.537026 -51.401219)
			(xy 337.481292 -51.399182) (xy 337.426449 -51.389052) (xy 337.373665 -51.371045) (xy 337.324065 -51.345544)
			(xy 337.278707 -51.313093) (xy 337.238558 -51.274384) (xy 337.204472 -51.230241) (xy 337.177176 -51.181606)
			(xy 337.157253 -51.129515) (xy 337.145127 -51.075078) (xy 337.141056 -51.019456) (xy 335.712816 -51.019456)
			(xy 335.712307 -51.047342) (xy 335.704187 -51.102518) (xy 335.688119 -51.155925) (xy 335.664447 -51.206422)
			(xy 335.633674 -51.252935) (xy 335.596457 -51.294472) (xy 335.553589 -51.330147) (xy 335.505983 -51.359201)
			(xy 335.454654 -51.381013) (xy 335.400697 -51.395119) (xy 335.34526 -51.401219) (xy 335.289526 -51.399182)
			(xy 335.234683 -51.389052) (xy 335.181899 -51.371045) (xy 335.132299 -51.345544) (xy 335.086941 -51.313093)
			(xy 335.046792 -51.274384) (xy 335.012706 -51.230241) (xy 334.98541 -51.181606) (xy 334.965487 -51.129515)
			(xy 334.953361 -51.075078) (xy 334.94929 -51.019456) (xy 318.721754 -51.019456) (xy 318.727151 -51.031769)
			(xy 318.734694 -51.039268) (xy 318.753742 -51.057404) (xy 318.787199 -51.097985) (xy 318.81476 -51.142779)
			(xy 318.835901 -51.190938) (xy 318.85022 -51.241545) (xy 318.857445 -51.293641) (xy 318.857884 -51.319938)
			(xy 318.857884 -51.320192) (xy 318.857437 -51.347446) (xy 318.849681 -51.401399) (xy 318.834324 -51.453698)
			(xy 318.811681 -51.50328) (xy 318.782212 -51.549134) (xy 318.746516 -51.590328) (xy 318.705321 -51.626021)
			(xy 318.659466 -51.655489) (xy 318.609883 -51.67813) (xy 318.557583 -51.693484) (xy 318.50363 -51.701238)
			(xy 318.476376 -51.7017) (xy 318.44871 -51.701207) (xy 318.39396 -51.693204) (xy 318.340938 -51.677384)
			(xy 318.290754 -51.654078) (xy 318.244459 -51.623774) (xy 318.203021 -51.587106) (xy 318.167309 -51.544842)
			(xy 318.152272 -51.521614) (xy 318.152018 -51.52136) (xy 318.145358 -51.51183) (xy 318.125659 -51.499527)
			(xy 318.114172 -51.497738) (xy 318.034162 -51.489864) (xy 318.02246 -51.489184) (xy 318.000486 -51.497273)
			(xy 317.991998 -51.505358) (xy 317.991998 -51.505612) (xy 317.973903 -51.524179) (xy 317.933574 -51.556758)
			(xy 317.889202 -51.583573) (xy 317.841607 -51.604128) (xy 317.791665 -51.618045) (xy 317.740298 -51.625066)
			(xy 317.714376 -51.6255) (xy 317.687124 -51.625044) (xy 317.633175 -51.617285) (xy 317.580879 -51.601926)
			(xy 317.531301 -51.579281) (xy 317.48545 -51.549812) (xy 317.44426 -51.514117) (xy 317.408569 -51.472924)
			(xy 317.379103 -51.427071) (xy 317.356463 -51.377491) (xy 317.341109 -51.325194) (xy 317.333353 -51.271244)
			(xy 317.332868 -51.243992) (xy 314.426314 -51.243992) (xy 314.426128 -51.254735) (xy 314.418373 -51.308686)
			(xy 314.403019 -51.360984) (xy 314.380378 -51.410565) (xy 314.350911 -51.456418) (xy 314.315218 -51.497611)
			(xy 314.274026 -51.533305) (xy 314.228173 -51.562773) (xy 314.178593 -51.585416) (xy 314.126296 -51.600771)
			(xy 314.072345 -51.608527) (xy 314.045092 -51.60899) (xy 314.026749 -51.608762) (xy 313.990236 -51.605196)
			(xy 313.972194 -51.601878) (xy 313.97194 -51.601878) (xy 313.961437 -51.600484) (xy 313.940836 -51.605337)
			(xy 313.932062 -51.611276) (xy 313.86272 -51.6636) (xy 313.85256 -51.682396) (xy 313.851544 -51.693318)
			(xy 313.84866 -51.721577) (xy 313.835627 -51.776864) (xy 313.814541 -51.829607) (xy 313.785869 -51.878641)
			(xy 313.750244 -51.922883) (xy 313.708453 -51.961353) (xy 313.66142 -51.993203) (xy 313.610186 -52.017728)
			(xy 313.555881 -52.034385) (xy 313.548738 -52.035456) (xy 337.141056 -52.035456) (xy 337.145127 -51.979834)
			(xy 337.157253 -51.925397) (xy 337.177176 -51.873306) (xy 337.204472 -51.824671) (xy 337.238558 -51.780528)
			(xy 337.278707 -51.741819) (xy 337.324065 -51.709368) (xy 337.373665 -51.683867) (xy 337.426449 -51.66586)
			(xy 337.481292 -51.65573) (xy 337.537026 -51.653693) (xy 337.592463 -51.659793) (xy 337.64642 -51.673899)
			(xy 337.682069 -51.689048) (xy 350.5556 -51.689048) (xy 350.5556 -51.634552) (xy 350.563355 -51.580611)
			(xy 350.578707 -51.528323) (xy 350.601344 -51.478751) (xy 350.630805 -51.432905) (xy 350.66649 -51.391718)
			(xy 350.707673 -51.356029) (xy 350.753516 -51.326563) (xy 350.803085 -51.303921) (xy 350.855372 -51.288564)
			(xy 350.909312 -51.280803) (xy 350.93656 -51.280314) (xy 350.96393 -51.2808) (xy 351.018108 -51.288613)
			(xy 351.070611 -51.304097) (xy 351.120358 -51.326934) (xy 351.166326 -51.356655) (xy 351.187258 -51.374294)
			(xy 351.187512 -51.374548) (xy 351.194587 -51.380152) (xy 351.211513 -51.386387) (xy 351.220532 -51.38674)
			(xy 351.287588 -51.38674) (xy 351.296606 -51.38639) (xy 351.313523 -51.380139) (xy 351.320608 -51.374548)
			(xy 351.321116 -51.37404) (xy 351.34203 -51.356433) (xy 351.38797 -51.326795) (xy 351.43767 -51.304021)
			(xy 351.490114 -51.288577) (xy 351.544225 -51.280779) (xy 351.57156 -51.280314) (xy 351.589903 -51.280549)
			(xy 351.626416 -51.28411) (xy 351.644458 -51.287426) (xy 351.644712 -51.287426) (xy 351.655214 -51.288849)
			(xy 351.675817 -51.283976) (xy 351.68459 -51.278028) (xy 351.753932 -51.225704) (xy 351.764092 -51.206908)
			(xy 351.765108 -51.195986) (xy 351.76801 -51.167703) (xy 351.781047 -51.112366) (xy 351.802141 -51.059573)
			(xy 351.830828 -51.01049) (xy 351.866474 -50.9662) (xy 351.887028 -50.946558) (xy 351.894476 -50.938992)
			(xy 351.903 -50.91957) (xy 351.903538 -50.908966) (xy 351.903538 -50.834798) (xy 351.90311 -50.824168)
			(xy 351.894573 -50.804705) (xy 351.887028 -50.797206) (xy 351.867972 -50.779078) (xy 351.834514 -50.738497)
			(xy 351.806954 -50.6937) (xy 351.785815 -50.64554) (xy 351.771498 -50.594931) (xy 351.764275 -50.542834)
			(xy 351.763838 -50.516536) (xy 351.763838 -50.516282) (xy 351.764324 -50.489031) (xy 351.77208 -50.435083)
			(xy 351.787435 -50.382788) (xy 351.810077 -50.333211) (xy 351.839543 -50.287361) (xy 351.875234 -50.24617)
			(xy 351.916425 -50.210479) (xy 351.962275 -50.181013) (xy 352.011852 -50.158371) (xy 352.064147 -50.143016)
			(xy 352.118095 -50.13526) (xy 352.172597 -50.13526) (xy 352.226545 -50.143016) (xy 352.27884 -50.158371)
			(xy 352.328417 -50.181013) (xy 352.374267 -50.210479) (xy 352.415458 -50.24617) (xy 352.451149 -50.287361)
			(xy 352.480615 -50.333211) (xy 352.503257 -50.382788) (xy 352.518612 -50.435083) (xy 352.526368 -50.489031)
			(xy 352.526854 -50.516282) (xy 352.526854 -50.516536) (xy 352.526434 -50.542832) (xy 352.519183 -50.594923)
			(xy 352.50485 -50.645526) (xy 352.483708 -50.693682) (xy 352.456155 -50.738481) (xy 352.422714 -50.779073)
			(xy 352.403664 -50.797206) (xy 352.396231 -50.804785) (xy 352.387699 -50.824197) (xy 352.387154 -50.834798)
			(xy 352.387154 -50.908966) (xy 352.387549 -50.919599) (xy 352.39611 -50.939063) (xy 352.403664 -50.946558)
			(xy 352.422701 -50.964705) (xy 352.456161 -51.005282) (xy 352.483724 -51.050075) (xy 352.504866 -51.098231)
			(xy 352.519187 -51.148837) (xy 352.526414 -51.200931) (xy 352.526854 -51.227228) (xy 352.526854 -51.227482)
			(xy 352.526521 -51.243992) (xy 355.433122 -51.243992) (xy 355.433613 -51.216659) (xy 355.441416 -51.162553)
			(xy 355.45686 -51.110114) (xy 355.47963 -51.060416) (xy 355.50926 -51.014476) (xy 355.526848 -50.993548)
			(xy 355.527102 -50.993294) (xy 355.527356 -50.99304) (xy 355.532939 -50.985951) (xy 355.539186 -50.969036)
			(xy 355.539548 -50.96002) (xy 355.539548 -50.892964) (xy 355.53922 -50.883944) (xy 355.532954 -50.867027)
			(xy 355.527356 -50.859944) (xy 355.527102 -50.85969) (xy 355.526848 -50.859436) (xy 355.509266 -50.838501)
			(xy 355.479625 -50.792568) (xy 355.456846 -50.742872) (xy 355.441395 -50.690433) (xy 355.433591 -50.636326)
			(xy 355.433122 -50.608992) (xy 355.433548 -50.581738) (xy 355.441307 -50.527784) (xy 355.456665 -50.475483)
			(xy 355.479311 -50.425901) (xy 355.508783 -50.380047) (xy 355.54448 -50.338853) (xy 355.585677 -50.30316)
			(xy 355.631535 -50.273693) (xy 355.681119 -50.251052) (xy 355.733421 -50.235699) (xy 355.787376 -50.227945)
			(xy 355.81463 -50.227484) (xy 355.843547 -50.228021) (xy 355.900718 -50.236742) (xy 355.955918 -50.253994)
			(xy 356.007881 -50.279382) (xy 356.055415 -50.312324) (xy 356.097431 -50.352065) (xy 356.11562 -50.37455)
			(xy 356.121897 -50.381941) (xy 356.138616 -50.391734) (xy 356.148132 -50.3936) (xy 356.155752 -50.394108)
			(xy 356.235508 -50.394108) (xy 356.243128 -50.3936) (xy 356.25264 -50.391725) (xy 356.269356 -50.381933)
			(xy 356.27564 -50.37455) (xy 356.293796 -50.352037) (xy 356.335824 -50.312306) (xy 356.383367 -50.279372)
			(xy 356.435335 -50.253989) (xy 356.490538 -50.236739) (xy 356.547712 -50.228016) (xy 356.57663 -50.227484)
			(xy 356.603882 -50.22795) (xy 356.65783 -50.23571) (xy 356.710124 -50.251069) (xy 356.759701 -50.273713)
			(xy 356.805551 -50.303182) (xy 356.846741 -50.338875) (xy 356.882432 -50.380067) (xy 356.911898 -50.425918)
			(xy 356.934539 -50.475496) (xy 356.949894 -50.527792) (xy 356.957652 -50.58174) (xy 356.958138 -50.608992)
			(xy 356.958138 -50.609246) (xy 356.957698 -50.635541) (xy 356.950447 -50.68763) (xy 356.936116 -50.738231)
			(xy 356.914977 -50.786387) (xy 356.88743 -50.831187) (xy 356.853995 -50.871781) (xy 356.834948 -50.889916)
			(xy 356.827508 -50.897489) (xy 356.818981 -50.916906) (xy 356.818438 -50.927508) (xy 356.818438 -51.001676)
			(xy 356.818858 -51.012307) (xy 356.821995 -51.019456) (xy 373.049544 -51.019456) (xy 373.053615 -50.963834)
			(xy 373.065741 -50.909397) (xy 373.085664 -50.857306) (xy 373.11296 -50.808671) (xy 373.147046 -50.764528)
			(xy 373.187195 -50.725819) (xy 373.232553 -50.693368) (xy 373.282153 -50.667867) (xy 373.334937 -50.64986)
			(xy 373.38978 -50.63973) (xy 373.445514 -50.637693) (xy 373.500951 -50.643793) (xy 373.554908 -50.657899)
			(xy 373.606237 -50.679711) (xy 373.653843 -50.708765) (xy 373.696711 -50.74444) (xy 373.733928 -50.785977)
			(xy 373.764701 -50.83249) (xy 373.788373 -50.882987) (xy 373.804441 -50.936394) (xy 373.812561 -50.99157)
			(xy 373.81307 -51.019456) (xy 375.24131 -51.019456) (xy 375.245381 -50.963834) (xy 375.257507 -50.909397)
			(xy 375.27743 -50.857306) (xy 375.304726 -50.808671) (xy 375.338812 -50.764528) (xy 375.378961 -50.725819)
			(xy 375.424319 -50.693368) (xy 375.473919 -50.667867) (xy 375.526703 -50.64986) (xy 375.581546 -50.63973)
			(xy 375.63728 -50.637693) (xy 375.692717 -50.643793) (xy 375.746674 -50.657899) (xy 375.798003 -50.679711)
			(xy 375.845609 -50.708765) (xy 375.888477 -50.74444) (xy 375.925694 -50.785977) (xy 375.956467 -50.83249)
			(xy 375.980139 -50.882987) (xy 375.996207 -50.936394) (xy 376.004327 -50.99157) (xy 376.004836 -51.019456)
			(xy 376.004327 -51.047342) (xy 375.996207 -51.102518) (xy 375.980139 -51.155925) (xy 375.956467 -51.206422)
			(xy 375.925694 -51.252935) (xy 375.888477 -51.294472) (xy 375.845609 -51.330147) (xy 375.798003 -51.359201)
			(xy 375.746674 -51.381013) (xy 375.692717 -51.395119) (xy 375.63728 -51.401219) (xy 375.581546 -51.399182)
			(xy 375.526703 -51.389052) (xy 375.473919 -51.371045) (xy 375.424319 -51.345544) (xy 375.378961 -51.313093)
			(xy 375.338812 -51.274384) (xy 375.304726 -51.230241) (xy 375.27743 -51.181606) (xy 375.257507 -51.129515)
			(xy 375.245381 -51.075078) (xy 375.24131 -51.019456) (xy 373.81307 -51.019456) (xy 373.812561 -51.047342)
			(xy 373.804441 -51.102518) (xy 373.788373 -51.155925) (xy 373.764701 -51.206422) (xy 373.733928 -51.252935)
			(xy 373.696711 -51.294472) (xy 373.653843 -51.330147) (xy 373.606237 -51.359201) (xy 373.554908 -51.381013)
			(xy 373.500951 -51.395119) (xy 373.445514 -51.401219) (xy 373.38978 -51.399182) (xy 373.334937 -51.389052)
			(xy 373.282153 -51.371045) (xy 373.232553 -51.345544) (xy 373.187195 -51.313093) (xy 373.147046 -51.274384)
			(xy 373.11296 -51.230241) (xy 373.085664 -51.181606) (xy 373.065741 -51.129515) (xy 373.053615 -51.075078)
			(xy 373.049544 -51.019456) (xy 356.821995 -51.019456) (xy 356.827398 -51.031772) (xy 356.834948 -51.039268)
			(xy 356.853987 -51.057413) (xy 356.887447 -51.097991) (xy 356.91501 -51.142783) (xy 356.936153 -51.19094)
			(xy 356.950473 -51.241546) (xy 356.957699 -51.293641) (xy 356.958138 -51.319938) (xy 356.958138 -51.320192)
			(xy 356.957615 -51.347442) (xy 356.94986 -51.401387) (xy 356.934508 -51.453679) (xy 356.91187 -51.503254)
			(xy 356.882407 -51.549103) (xy 356.846719 -51.590293) (xy 356.805533 -51.625984) (xy 356.759687 -51.655451)
			(xy 356.710114 -51.678094) (xy 356.657824 -51.693452) (xy 356.60388 -51.701212) (xy 356.57663 -51.7017)
			(xy 356.548966 -51.701164) (xy 356.494218 -51.693169) (xy 356.441197 -51.677357) (xy 356.391013 -51.654057)
			(xy 356.344717 -51.62376) (xy 356.303278 -51.587098) (xy 356.267564 -51.544839) (xy 356.252526 -51.521614)
			(xy 356.252272 -51.52136) (xy 356.245633 -51.511813) (xy 356.225919 -51.499518) (xy 356.214426 -51.497738)
			(xy 356.134416 -51.489864) (xy 356.122715 -51.489218) (xy 356.100743 -51.497283) (xy 356.092252 -51.505358)
			(xy 356.092252 -51.505612) (xy 356.074179 -51.524201) (xy 356.033845 -51.556778) (xy 355.989469 -51.58359)
			(xy 355.941869 -51.604141) (xy 355.891923 -51.618053) (xy 355.840554 -51.625069) (xy 355.81463 -51.6255)
			(xy 355.787378 -51.625017) (xy 355.733427 -51.617264) (xy 355.681129 -51.601911) (xy 355.631548 -51.579271)
			(xy 355.585695 -51.549806) (xy 355.544501 -51.514114) (xy 355.508807 -51.472923) (xy 355.479339 -51.427071)
			(xy 355.456697 -51.377492) (xy 355.441341 -51.325195) (xy 355.433585 -51.271244) (xy 355.433122 -51.243992)
			(xy 352.526521 -51.243992) (xy 352.526305 -51.254731) (xy 352.518552 -51.308674) (xy 352.503202 -51.360964)
			(xy 352.480566 -51.410538) (xy 352.451106 -51.456387) (xy 352.415421 -51.497576) (xy 352.374238 -51.533268)
			(xy 352.328395 -51.562735) (xy 352.278824 -51.585379) (xy 352.226536 -51.600739) (xy 352.172595 -51.608501)
			(xy 352.145346 -51.60899) (xy 352.127003 -51.608754) (xy 352.09049 -51.605193) (xy 352.072448 -51.601878)
			(xy 352.072194 -51.601878) (xy 352.061692 -51.600457) (xy 352.041089 -51.605328) (xy 352.032316 -51.611276)
			(xy 351.962974 -51.6636) (xy 351.952814 -51.682396) (xy 351.951798 -51.693318) (xy 351.948861 -51.72157)
			(xy 351.93583 -51.776852) (xy 351.914749 -51.829592) (xy 351.886081 -51.878623) (xy 351.850462 -51.922863)
			(xy 351.808678 -51.961334) (xy 351.761652 -51.993185) (xy 351.710424 -52.017712) (xy 351.656126 -52.034375)
			(xy 351.648923 -52.035456) (xy 375.24131 -52.035456) (xy 375.245381 -51.979834) (xy 375.257507 -51.925397)
			(xy 375.27743 -51.873306) (xy 375.304726 -51.824671) (xy 375.338812 -51.780528) (xy 375.378961 -51.741819)
			(xy 375.424319 -51.709368) (xy 375.473919 -51.683867) (xy 375.526703 -51.66586) (xy 375.581546 -51.65573)
			(xy 375.63728 -51.653693) (xy 375.692717 -51.659793) (xy 375.746674 -51.673899) (xy 375.782333 -51.689052)
			(xy 376.555477 -51.689052) (xy 376.555477 -51.634548) (xy 376.563234 -51.5806) (xy 376.57859 -51.528304)
			(xy 376.601231 -51.478727) (xy 376.630698 -51.432876) (xy 376.666391 -51.391685) (xy 376.707582 -51.355994)
			(xy 376.753434 -51.326528) (xy 376.803012 -51.303887) (xy 376.855308 -51.288532) (xy 376.909256 -51.280777)
			(xy 376.936508 -51.280314) (xy 376.963879 -51.280772) (xy 377.018058 -51.288591) (xy 377.070561 -51.304082)
			(xy 377.120308 -51.326926) (xy 377.166275 -51.356652) (xy 377.187206 -51.374294) (xy 377.18746 -51.374548)
			(xy 377.19455 -51.38013) (xy 377.211464 -51.386378) (xy 377.22048 -51.38674) (xy 377.287536 -51.38674)
			(xy 377.296556 -51.386413) (xy 377.313474 -51.380146) (xy 377.320556 -51.374548) (xy 377.321064 -51.37404)
			(xy 377.341998 -51.356457) (xy 377.387932 -51.326816) (xy 377.437628 -51.304037) (xy 377.490067 -51.288587)
			(xy 377.544174 -51.280783) (xy 377.571508 -51.280314) (xy 377.589851 -51.280542) (xy 377.626364 -51.284108)
			(xy 377.644406 -51.287426) (xy 377.64466 -51.287426) (xy 377.655163 -51.288819) (xy 377.675764 -51.283967)
			(xy 377.684538 -51.278028) (xy 377.75388 -51.225704) (xy 377.76404 -51.206908) (xy 377.765056 -51.195986)
			(xy 377.767944 -51.167701) (xy 377.780982 -51.112363) (xy 377.802079 -51.05957) (xy 377.83077 -51.010487)
			(xy 377.866419 -50.966199) (xy 377.886976 -50.946558) (xy 377.894431 -50.938998) (xy 377.902949 -50.919571)
			(xy 377.903486 -50.908966) (xy 377.903486 -50.834798) (xy 377.903074 -50.824166) (xy 377.894527 -50.804702)
			(xy 377.886976 -50.797206) (xy 377.86791 -50.779088) (xy 377.834455 -50.738503) (xy 377.806898 -50.693705)
			(xy 377.78576 -50.645543) (xy 377.771445 -50.594932) (xy 377.764223 -50.542834) (xy 377.763786 -50.516536)
			(xy 377.763786 -50.516282) (xy 377.764272 -50.489031) (xy 377.772028 -50.435083) (xy 377.787383 -50.382788)
			(xy 377.810025 -50.333211) (xy 377.839491 -50.287361) (xy 377.875182 -50.24617) (xy 377.916373 -50.210479)
			(xy 377.962223 -50.181013) (xy 378.0118 -50.158371) (xy 378.064095 -50.143016) (xy 378.118043 -50.13526)
			(xy 378.172545 -50.13526) (xy 378.226493 -50.143016) (xy 378.278788 -50.158371) (xy 378.328365 -50.181013)
			(xy 378.374215 -50.210479) (xy 378.415406 -50.24617) (xy 378.451097 -50.287361) (xy 378.480563 -50.333211)
			(xy 378.503205 -50.382788) (xy 378.51856 -50.435083) (xy 378.526316 -50.489031) (xy 378.526802 -50.516282)
			(xy 378.526802 -50.516536) (xy 378.526367 -50.542832) (xy 378.519116 -50.594921) (xy 378.504786 -50.645523)
			(xy 378.483646 -50.693679) (xy 378.456097 -50.738478) (xy 378.42266 -50.779072) (xy 378.403612 -50.797206)
			(xy 378.396171 -50.804778) (xy 378.387645 -50.824196) (xy 378.387102 -50.834798) (xy 378.387102 -50.908966)
			(xy 378.387483 -50.919601) (xy 378.396052 -50.939065) (xy 378.403612 -50.946558) (xy 378.422659 -50.964696)
			(xy 378.456115 -51.005276) (xy 378.483676 -51.050071) (xy 378.504816 -51.098229) (xy 378.519136 -51.148836)
			(xy 378.526362 -51.200931) (xy 378.526802 -51.227228) (xy 378.526802 -51.227482) (xy 378.526515 -51.243992)
			(xy 381.43307 -51.243992) (xy 381.433549 -51.216658) (xy 381.441353 -51.162551) (xy 381.4568 -51.110112)
			(xy 381.479573 -51.060414) (xy 381.509206 -51.014475) (xy 381.526796 -50.993548) (xy 381.52705 -50.993294)
			(xy 381.527304 -50.99304) (xy 381.53288 -50.985946) (xy 381.539133 -50.969035) (xy 381.539496 -50.96002)
			(xy 381.539496 -50.892964) (xy 381.539157 -50.883945) (xy 381.532897 -50.867028) (xy 381.527304 -50.859944)
			(xy 381.52705 -50.85969) (xy 381.526796 -50.859436) (xy 381.509206 -50.838508) (xy 381.479568 -50.792572)
			(xy 381.456791 -50.742874) (xy 381.441342 -50.690434) (xy 381.433539 -50.636326) (xy 381.43307 -50.608992)
			(xy 381.43357 -50.581742) (xy 381.441327 -50.527795) (xy 381.456682 -50.475502) (xy 381.479323 -50.425927)
			(xy 381.508788 -50.380077) (xy 381.544478 -50.338888) (xy 381.585666 -50.303196) (xy 381.631514 -50.27373)
			(xy 381.681089 -50.251087) (xy 381.733382 -50.23573) (xy 381.787328 -50.227971) (xy 381.814578 -50.227484)
			(xy 381.843496 -50.227986) (xy 381.900669 -50.236714) (xy 381.95587 -50.253973) (xy 382.007832 -50.279368)
			(xy 382.055365 -50.312316) (xy 382.09738 -50.352062) (xy 382.115568 -50.37455) (xy 382.121864 -50.381923)
			(xy 382.138569 -50.391726) (xy 382.14808 -50.3936) (xy 382.1557 -50.394108) (xy 382.235456 -50.394108)
			(xy 382.243076 -50.3936) (xy 382.252594 -50.391746) (xy 382.269307 -50.381939) (xy 382.275588 -50.37455)
			(xy 382.293773 -50.352062) (xy 382.335796 -50.312329) (xy 382.383332 -50.279392) (xy 382.435294 -50.254005)
			(xy 382.490492 -50.236749) (xy 382.547662 -50.22802) (xy 382.576578 -50.227484) (xy 382.60383 -50.227976)
			(xy 382.657779 -50.23573) (xy 382.710076 -50.251082) (xy 382.759656 -50.273722) (xy 382.805509 -50.303187)
			(xy 382.846701 -50.338877) (xy 382.882395 -50.380067) (xy 382.911864 -50.425918) (xy 382.934507 -50.475496)
			(xy 382.949864 -50.527791) (xy 382.957622 -50.58174) (xy 382.958086 -50.608992) (xy 382.958086 -50.609246)
			(xy 382.957662 -50.635542) (xy 382.950411 -50.687633) (xy 382.936078 -50.738235) (xy 382.914936 -50.786391)
			(xy 382.887385 -50.831189) (xy 382.853945 -50.871783) (xy 382.834896 -50.889916) (xy 382.827449 -50.897482)
			(xy 382.818927 -50.916904) (xy 382.818386 -50.927508) (xy 382.818386 -51.001676) (xy 382.818821 -51.012305)
			(xy 382.821956 -51.019456) (xy 399.049492 -51.019456) (xy 399.053563 -50.963834) (xy 399.065689 -50.909397)
			(xy 399.085612 -50.857306) (xy 399.112908 -50.808671) (xy 399.146994 -50.764528) (xy 399.187143 -50.725819)
			(xy 399.232501 -50.693368) (xy 399.282101 -50.667867) (xy 399.334885 -50.64986) (xy 399.389728 -50.63973)
			(xy 399.445462 -50.637693) (xy 399.500899 -50.643793) (xy 399.554856 -50.657899) (xy 399.606185 -50.679711)
			(xy 399.653791 -50.708765) (xy 399.696659 -50.74444) (xy 399.733876 -50.785977) (xy 399.764649 -50.83249)
			(xy 399.788321 -50.882987) (xy 399.804389 -50.936394) (xy 399.812509 -50.99157) (xy 399.813018 -51.019456)
			(xy 401.241258 -51.019456) (xy 401.245329 -50.963834) (xy 401.257455 -50.909397) (xy 401.277378 -50.857306)
			(xy 401.304674 -50.808671) (xy 401.33876 -50.764528) (xy 401.378909 -50.725819) (xy 401.424267 -50.693368)
			(xy 401.473867 -50.667867) (xy 401.526651 -50.64986) (xy 401.581494 -50.63973) (xy 401.637228 -50.637693)
			(xy 401.692665 -50.643793) (xy 401.746622 -50.657899) (xy 401.797951 -50.679711) (xy 401.845557 -50.708765)
			(xy 401.888425 -50.74444) (xy 401.925642 -50.785977) (xy 401.956415 -50.83249) (xy 401.980087 -50.882987)
			(xy 401.996155 -50.936394) (xy 402.004275 -50.99157) (xy 402.004784 -51.019456) (xy 402.004275 -51.047342)
			(xy 401.996155 -51.102518) (xy 401.980087 -51.155925) (xy 401.956415 -51.206422) (xy 401.925642 -51.252935)
			(xy 401.888425 -51.294472) (xy 401.845557 -51.330147) (xy 401.797951 -51.359201) (xy 401.746622 -51.381013)
			(xy 401.692665 -51.395119) (xy 401.637228 -51.401219) (xy 401.581494 -51.399182) (xy 401.526651 -51.389052)
			(xy 401.473867 -51.371045) (xy 401.424267 -51.345544) (xy 401.378909 -51.313093) (xy 401.33876 -51.274384)
			(xy 401.304674 -51.230241) (xy 401.277378 -51.181606) (xy 401.257455 -51.129515) (xy 401.245329 -51.075078)
			(xy 401.241258 -51.019456) (xy 399.813018 -51.019456) (xy 399.812509 -51.047342) (xy 399.804389 -51.102518)
			(xy 399.788321 -51.155925) (xy 399.764649 -51.206422) (xy 399.733876 -51.252935) (xy 399.696659 -51.294472)
			(xy 399.653791 -51.330147) (xy 399.606185 -51.359201) (xy 399.554856 -51.381013) (xy 399.500899 -51.395119)
			(xy 399.445462 -51.401219) (xy 399.389728 -51.399182) (xy 399.334885 -51.389052) (xy 399.282101 -51.371045)
			(xy 399.232501 -51.345544) (xy 399.187143 -51.313093) (xy 399.146994 -51.274384) (xy 399.112908 -51.230241)
			(xy 399.085612 -51.181606) (xy 399.065689 -51.129515) (xy 399.053563 -51.075078) (xy 399.049492 -51.019456)
			(xy 382.821956 -51.019456) (xy 382.827353 -51.031769) (xy 382.834896 -51.039268) (xy 382.853944 -51.057404)
			(xy 382.887402 -51.097984) (xy 382.914962 -51.142779) (xy 382.936103 -51.190938) (xy 382.950422 -51.241545)
			(xy 382.957647 -51.293641) (xy 382.958086 -51.319938) (xy 382.958086 -51.320192) (xy 382.957637 -51.347446)
			(xy 382.949881 -51.401398) (xy 382.934525 -51.453698) (xy 382.911881 -51.503279) (xy 382.882412 -51.549133)
			(xy 382.846717 -51.590327) (xy 382.805522 -51.626021) (xy 382.759667 -51.655488) (xy 382.710085 -51.678129)
			(xy 382.657785 -51.693484) (xy 382.603832 -51.701238) (xy 382.576578 -51.7017) (xy 382.548912 -51.701205)
			(xy 382.494162 -51.693203) (xy 382.44114 -51.677383) (xy 382.390956 -51.654077) (xy 382.344661 -51.623773)
			(xy 382.303223 -51.587106) (xy 382.267511 -51.544842) (xy 382.252474 -51.521614) (xy 382.25222 -51.52136)
			(xy 382.245559 -51.511831) (xy 382.225861 -51.499527) (xy 382.214374 -51.497738) (xy 382.134364 -51.489864)
			(xy 382.122663 -51.489186) (xy 382.100688 -51.497273) (xy 382.0922 -51.505358) (xy 382.0922 -51.505612)
			(xy 382.074104 -51.524178) (xy 382.033775 -51.556757) (xy 381.989404 -51.583572) (xy 381.941808 -51.604127)
			(xy 381.891867 -51.618044) (xy 381.8405 -51.625066) (xy 381.814578 -51.6255) (xy 381.787326 -51.625043)
			(xy 381.733377 -51.617283) (xy 381.681081 -51.601925) (xy 381.631503 -51.57928) (xy 381.585652 -51.549811)
			(xy 381.544462 -51.514117) (xy 381.508771 -51.472924) (xy 381.479305 -51.427071) (xy 381.456665 -51.377491)
			(xy 381.441311 -51.325194) (xy 381.433555 -51.271244) (xy 381.43307 -51.243992) (xy 378.526515 -51.243992)
			(xy 378.526328 -51.254735) (xy 378.518573 -51.308686) (xy 378.503219 -51.360984) (xy 378.480578 -51.410564)
			(xy 378.451112 -51.456418) (xy 378.415419 -51.497611) (xy 378.374227 -51.533304) (xy 378.328375 -51.562773)
			(xy 378.278795 -51.585415) (xy 378.226497 -51.600771) (xy 378.172547 -51.608527) (xy 378.145294 -51.60899)
			(xy 378.126951 -51.608762) (xy 378.090438 -51.605196) (xy 378.072396 -51.601878) (xy 378.072142 -51.601878)
			(xy 378.061638 -51.600486) (xy 378.041038 -51.605337) (xy 378.032264 -51.611276) (xy 377.962922 -51.6636)
			(xy 377.952762 -51.682396) (xy 377.951746 -51.693318) (xy 377.94886 -51.721577) (xy 377.935827 -51.776863)
			(xy 377.914741 -51.829607) (xy 377.886069 -51.878641) (xy 377.850444 -51.922882) (xy 377.808654 -51.961353)
			(xy 377.761621 -51.993202) (xy 377.710387 -52.017727) (xy 377.656083 -52.034385) (xy 377.64894 -52.035456)
			(xy 401.241258 -52.035456) (xy 401.245329 -51.979834) (xy 401.257455 -51.925397) (xy 401.277378 -51.873306)
			(xy 401.304674 -51.824671) (xy 401.33876 -51.780528) (xy 401.378909 -51.741819) (xy 401.424267 -51.709368)
			(xy 401.473867 -51.683867) (xy 401.526651 -51.66586) (xy 401.581494 -51.65573) (xy 401.637228 -51.653693)
			(xy 401.692665 -51.659793) (xy 401.746622 -51.673899) (xy 401.782271 -51.689048) (xy 402.5555 -51.689048)
			(xy 402.5555 -51.634552) (xy 402.563255 -51.580612) (xy 402.578607 -51.528324) (xy 402.601244 -51.478752)
			(xy 402.630704 -51.432907) (xy 402.666389 -51.39172) (xy 402.707571 -51.35603) (xy 402.753413 -51.326565)
			(xy 402.802982 -51.303922) (xy 402.855269 -51.288564) (xy 402.909208 -51.280803) (xy 402.936456 -51.280314)
			(xy 402.963825 -51.280802) (xy 403.018004 -51.288614) (xy 403.070507 -51.304098) (xy 403.120254 -51.326935)
			(xy 403.166222 -51.356655) (xy 403.187154 -51.374294) (xy 403.187408 -51.374548) (xy 403.194484 -51.38015)
			(xy 403.211409 -51.386386) (xy 403.220428 -51.38674) (xy 403.287484 -51.38674) (xy 403.296502 -51.386388)
			(xy 403.313419 -51.380138) (xy 403.320504 -51.374548) (xy 403.321012 -51.37404) (xy 403.341927 -51.356435)
			(xy 403.387867 -51.326797) (xy 403.437567 -51.304022) (xy 403.49001 -51.288578) (xy 403.544121 -51.28078)
			(xy 403.571456 -51.280314) (xy 403.589799 -51.280549) (xy 403.626312 -51.28411) (xy 403.644354 -51.287426)
			(xy 403.644608 -51.287426) (xy 403.65511 -51.288847) (xy 403.675713 -51.283976) (xy 403.684486 -51.278028)
			(xy 403.753828 -51.225704) (xy 403.763988 -51.206908) (xy 403.765004 -51.195986) (xy 403.767908 -51.167703)
			(xy 403.780944 -51.112367) (xy 403.802038 -51.059573) (xy 403.830725 -51.01049) (xy 403.86637 -50.9662)
			(xy 403.886924 -50.946558) (xy 403.894372 -50.938991) (xy 403.902896 -50.91957) (xy 403.903434 -50.908966)
			(xy 403.903434 -50.834798) (xy 403.903007 -50.824168) (xy 403.894469 -50.804704) (xy 403.886924 -50.797206)
			(xy 403.867867 -50.779079) (xy 403.83441 -50.738497) (xy 403.80685 -50.693701) (xy 403.785711 -50.64554)
			(xy 403.771394 -50.594931) (xy 403.764171 -50.542834) (xy 403.763734 -50.516536) (xy 403.763734 -50.516282)
			(xy 403.76422 -50.489031) (xy 403.771976 -50.435083) (xy 403.787331 -50.382788) (xy 403.809973 -50.333211)
			(xy 403.839439 -50.287361) (xy 403.87513 -50.24617) (xy 403.916321 -50.210479) (xy 403.962171 -50.181013)
			(xy 404.011748 -50.158371) (xy 404.064043 -50.143016) (xy 404.117991 -50.13526) (xy 404.172493 -50.13526)
			(xy 404.226441 -50.143016) (xy 404.278736 -50.158371) (xy 404.328313 -50.181013) (xy 404.374163 -50.210479)
			(xy 404.415354 -50.24617) (xy 404.451045 -50.287361) (xy 404.480511 -50.333211) (xy 404.503153 -50.382788)
			(xy 404.518508 -50.435083) (xy 404.526264 -50.489031) (xy 404.52675 -50.516282) (xy 404.52675 -50.516536)
			(xy 404.526331 -50.542832) (xy 404.51908 -50.594923) (xy 404.504747 -50.645526) (xy 404.483604 -50.693683)
			(xy 404.456052 -50.738481) (xy 404.42261 -50.779074) (xy 404.40356 -50.797206) (xy 404.396126 -50.804784)
			(xy 404.387595 -50.824197) (xy 404.38705 -50.834798) (xy 404.38705 -50.908966) (xy 404.387447 -50.919599)
			(xy 404.396006 -50.939062) (xy 404.40356 -50.946558) (xy 404.422597 -50.964706) (xy 404.456056 -51.005283)
			(xy 404.483619 -51.050075) (xy 404.504762 -51.098231) (xy 404.519083 -51.148837) (xy 404.52631 -51.200931)
			(xy 404.52675 -51.227228) (xy 404.52675 -51.227482) (xy 404.52642 -51.243992) (xy 407.433018 -51.243992)
			(xy 407.43351 -51.216659) (xy 407.441313 -51.162553) (xy 407.456757 -51.110114) (xy 407.479527 -51.060416)
			(xy 407.509156 -51.014476) (xy 407.526744 -50.993548) (xy 407.526998 -50.993294) (xy 407.527252 -50.99304)
			(xy 407.532834 -50.985951) (xy 407.539082 -50.969036) (xy 407.539444 -50.96002) (xy 407.539444 -50.892964)
			(xy 407.539117 -50.883944) (xy 407.53285 -50.867026) (xy 407.527252 -50.859944) (xy 407.526998 -50.85969)
			(xy 407.526744 -50.859436) (xy 407.509162 -50.838502) (xy 407.47952 -50.792568) (xy 407.456741 -50.742872)
			(xy 407.441291 -50.690433) (xy 407.433487 -50.636326) (xy 407.433018 -50.608992) (xy 407.433448 -50.581738)
			(xy 407.441207 -50.527784) (xy 407.456565 -50.475484) (xy 407.47921 -50.425902) (xy 407.508682 -50.380048)
			(xy 407.544379 -50.338855) (xy 407.585575 -50.303161) (xy 407.631432 -50.273694) (xy 407.681016 -50.251053)
			(xy 407.733318 -50.235699) (xy 407.787272 -50.227946) (xy 407.814526 -50.227484) (xy 407.843443 -50.228024)
			(xy 407.900614 -50.236744) (xy 407.955814 -50.253995) (xy 408.007776 -50.279383) (xy 408.055311 -50.312324)
			(xy 408.097326 -50.352065) (xy 408.115516 -50.37455) (xy 408.121794 -50.38194) (xy 408.138512 -50.391734)
			(xy 408.148028 -50.3936) (xy 408.155648 -50.394108) (xy 408.235404 -50.394108) (xy 408.243024 -50.3936)
			(xy 408.252536 -50.391723) (xy 408.269252 -50.381933) (xy 408.275536 -50.37455) (xy 408.293694 -50.352039)
			(xy 408.335722 -50.312308) (xy 408.383264 -50.279373) (xy 408.435232 -50.25399) (xy 408.490435 -50.236739)
			(xy 408.547608 -50.228016) (xy 408.576526 -50.227484) (xy 408.603778 -50.227954) (xy 408.657725 -50.235713)
			(xy 408.71002 -50.251071) (xy 408.759597 -50.273715) (xy 408.805447 -50.303183) (xy 408.846636 -50.338876)
			(xy 408.882328 -50.380068) (xy 408.911794 -50.425919) (xy 408.934435 -50.475497) (xy 408.942308 -50.502312)
			(xy 423.116754 -50.502312) (xy 423.120825 -50.44669) (xy 423.132951 -50.392253) (xy 423.152874 -50.340162)
			(xy 423.18017 -50.291527) (xy 423.214256 -50.247384) (xy 423.254405 -50.208675) (xy 423.299763 -50.176224)
			(xy 423.349363 -50.150723) (xy 423.402147 -50.132716) (xy 423.45699 -50.122586) (xy 423.512724 -50.120549)
			(xy 423.568161 -50.126649) (xy 423.622118 -50.140755) (xy 423.673447 -50.162567) (xy 423.721053 -50.191621)
			(xy 423.763921 -50.227296) (xy 423.801138 -50.268833) (xy 423.831911 -50.315346) (xy 423.855583 -50.365843)
			(xy 423.871651 -50.41925) (xy 423.879771 -50.474426) (xy 423.88028 -50.502312) (xy 423.879771 -50.530198)
			(xy 423.871651 -50.585374) (xy 423.855583 -50.638781) (xy 423.831911 -50.689278) (xy 423.801138 -50.735791)
			(xy 423.763921 -50.777328) (xy 423.721053 -50.813003) (xy 423.673447 -50.842057) (xy 423.622118 -50.863869)
			(xy 423.568161 -50.877975) (xy 423.512724 -50.884075) (xy 423.45699 -50.882038) (xy 423.402147 -50.871908)
			(xy 423.349363 -50.853901) (xy 423.299763 -50.8284) (xy 423.254405 -50.795949) (xy 423.214256 -50.75724)
			(xy 423.18017 -50.713097) (xy 423.152874 -50.664462) (xy 423.132951 -50.612371) (xy 423.120825 -50.557934)
			(xy 423.116754 -50.502312) (xy 408.942308 -50.502312) (xy 408.94979 -50.527792) (xy 408.957548 -50.58174)
			(xy 408.958034 -50.608992) (xy 408.958034 -50.609246) (xy 408.957595 -50.635541) (xy 408.950344 -50.687631)
			(xy 408.936014 -50.738232) (xy 408.914874 -50.786388) (xy 408.887326 -50.831187) (xy 408.853891 -50.871782)
			(xy 408.834844 -50.889916) (xy 408.827404 -50.897489) (xy 408.818877 -50.916906) (xy 408.818334 -50.927508)
			(xy 408.818334 -51.001676) (xy 408.818755 -51.012307) (xy 408.821892 -51.019456) (xy 425.04944 -51.019456)
			(xy 425.053511 -50.963834) (xy 425.065637 -50.909397) (xy 425.08556 -50.857306) (xy 425.112856 -50.808671)
			(xy 425.146942 -50.764528) (xy 425.187091 -50.725819) (xy 425.232449 -50.693368) (xy 425.282049 -50.667867)
			(xy 425.334833 -50.64986) (xy 425.389676 -50.63973) (xy 425.44541 -50.637693) (xy 425.500847 -50.643793)
			(xy 425.554804 -50.657899) (xy 425.606133 -50.679711) (xy 425.653739 -50.708765) (xy 425.696607 -50.74444)
			(xy 425.733824 -50.785977) (xy 425.764597 -50.83249) (xy 425.788269 -50.882987) (xy 425.804337 -50.936394)
			(xy 425.812457 -50.99157) (xy 425.812966 -51.019456) (xy 427.241206 -51.019456) (xy 427.245277 -50.963834)
			(xy 427.257403 -50.909397) (xy 427.277326 -50.857306) (xy 427.304622 -50.808671) (xy 427.338708 -50.764528)
			(xy 427.378857 -50.725819) (xy 427.424215 -50.693368) (xy 427.473815 -50.667867) (xy 427.526599 -50.64986)
			(xy 427.581442 -50.63973) (xy 427.637176 -50.637693) (xy 427.692613 -50.643793) (xy 427.74657 -50.657899)
			(xy 427.797899 -50.679711) (xy 427.845505 -50.708765) (xy 427.888373 -50.74444) (xy 427.92559 -50.785977)
			(xy 427.956363 -50.83249) (xy 427.980035 -50.882987) (xy 427.996103 -50.936394) (xy 428.004223 -50.99157)
			(xy 428.004732 -51.019456) (xy 428.004223 -51.047342) (xy 427.996103 -51.102518) (xy 427.980035 -51.155925)
			(xy 427.956363 -51.206422) (xy 427.92559 -51.252935) (xy 427.888373 -51.294472) (xy 427.845505 -51.330147)
			(xy 427.797899 -51.359201) (xy 427.74657 -51.381013) (xy 427.692613 -51.395119) (xy 427.637176 -51.401219)
			(xy 427.581442 -51.399182) (xy 427.526599 -51.389052) (xy 427.473815 -51.371045) (xy 427.424215 -51.345544)
			(xy 427.378857 -51.313093) (xy 427.338708 -51.274384) (xy 427.304622 -51.230241) (xy 427.277326 -51.181606)
			(xy 427.257403 -51.129515) (xy 427.245277 -51.075078) (xy 427.241206 -51.019456) (xy 425.812966 -51.019456)
			(xy 425.812457 -51.047342) (xy 425.804337 -51.102518) (xy 425.788269 -51.155925) (xy 425.764597 -51.206422)
			(xy 425.733824 -51.252935) (xy 425.696607 -51.294472) (xy 425.653739 -51.330147) (xy 425.606133 -51.359201)
			(xy 425.554804 -51.381013) (xy 425.500847 -51.395119) (xy 425.44541 -51.401219) (xy 425.389676 -51.399182)
			(xy 425.334833 -51.389052) (xy 425.282049 -51.371045) (xy 425.232449 -51.345544) (xy 425.187091 -51.313093)
			(xy 425.146942 -51.274384) (xy 425.112856 -51.230241) (xy 425.08556 -51.181606) (xy 425.065637 -51.129515)
			(xy 425.053511 -51.075078) (xy 425.04944 -51.019456) (xy 408.821892 -51.019456) (xy 408.827295 -51.031772)
			(xy 408.834844 -51.039268) (xy 408.853883 -51.057414) (xy 408.887343 -51.097991) (xy 408.914906 -51.142783)
			(xy 408.936048 -51.19094) (xy 408.950369 -51.241546) (xy 408.957595 -51.293641) (xy 408.958034 -51.319938)
			(xy 408.958034 -51.320192) (xy 408.957515 -51.347442) (xy 408.94976 -51.401387) (xy 408.934407 -51.45368)
			(xy 408.911769 -51.503255) (xy 408.882306 -51.549104) (xy 408.846618 -51.590294) (xy 408.805432 -51.625986)
			(xy 408.759585 -51.655453) (xy 408.710012 -51.678095) (xy 408.65772 -51.693453) (xy 408.603776 -51.701212)
			(xy 408.576526 -51.7017) (xy 408.548862 -51.701167) (xy 408.494113 -51.693172) (xy 408.441092 -51.677358)
			(xy 408.390908 -51.654059) (xy 408.344612 -51.623761) (xy 408.303174 -51.587098) (xy 408.26746 -51.54484)
			(xy 408.252422 -51.521614) (xy 408.252168 -51.52136) (xy 408.245531 -51.511811) (xy 408.225815 -51.499517)
			(xy 408.214322 -51.497738) (xy 408.134312 -51.489864) (xy 408.122611 -51.489215) (xy 408.100639 -51.497282)
			(xy 408.092148 -51.505358) (xy 408.092148 -51.505612) (xy 408.074077 -51.524203) (xy 408.033742 -51.55678)
			(xy 407.989366 -51.583591) (xy 407.941766 -51.604142) (xy 407.89182 -51.618054) (xy 407.84045 -51.625069)
			(xy 407.814526 -51.6255) (xy 407.787273 -51.62502) (xy 407.733323 -51.617267) (xy 407.681025 -51.601914)
			(xy 407.631444 -51.579274) (xy 407.58559 -51.549808) (xy 407.544397 -51.514116) (xy 407.508703 -51.472924)
			(xy 407.479235 -51.427072) (xy 407.456593 -51.377492) (xy 407.441237 -51.325195) (xy 407.433481 -51.271245)
			(xy 407.433018 -51.243992) (xy 404.52642 -51.243992) (xy 404.526205 -51.254731) (xy 404.518452 -51.308674)
			(xy 404.503101 -51.360965) (xy 404.480465 -51.41054) (xy 404.451005 -51.456388) (xy 404.41532 -51.497577)
			(xy 404.374136 -51.533269) (xy 404.328292 -51.562737) (xy 404.278722 -51.58538) (xy 404.226433 -51.600739)
			(xy 404.172491 -51.608501) (xy 404.145242 -51.60899) (xy 404.126899 -51.608755) (xy 404.090386 -51.605194)
			(xy 404.072344 -51.601878) (xy 404.07209 -51.601878) (xy 404.061588 -51.600455) (xy 404.040985 -51.605328)
			(xy 404.032212 -51.611276) (xy 403.96287 -51.6636) (xy 403.95271 -51.682396) (xy 403.951694 -51.693318)
			(xy 403.948761 -51.721571) (xy 403.93573 -51.776853) (xy 403.914648 -51.829593) (xy 403.88598 -51.878625)
			(xy 403.85036 -51.922865) (xy 403.808576 -51.961335) (xy 403.76155 -51.993186) (xy 403.710321 -52.017714)
			(xy 403.656023 -52.034376) (xy 403.648825 -52.035456) (xy 427.241206 -52.035456) (xy 427.245277 -51.979834)
			(xy 427.257403 -51.925397) (xy 427.277326 -51.873306) (xy 427.304622 -51.824671) (xy 427.338708 -51.780528)
			(xy 427.378857 -51.741819) (xy 427.424215 -51.709368) (xy 427.473815 -51.683867) (xy 427.526599 -51.66586)
			(xy 427.581442 -51.65573) (xy 427.637176 -51.653693) (xy 427.692613 -51.659793) (xy 427.74657 -51.673899)
			(xy 427.782226 -51.689051) (xy 428.555377 -51.689051) (xy 428.555377 -51.634549) (xy 428.563134 -51.5806)
			(xy 428.578489 -51.528305) (xy 428.601131 -51.478728) (xy 428.630597 -51.432877) (xy 428.666289 -51.391687)
			(xy 428.70748 -51.355995) (xy 428.753331 -51.326529) (xy 428.802909 -51.303888) (xy 428.855204 -51.288533)
			(xy 428.909153 -51.280777) (xy 428.936404 -51.280314) (xy 428.963774 -51.280774) (xy 429.017954 -51.288593)
			(xy 429.070457 -51.304083) (xy 429.120204 -51.326926) (xy 429.166171 -51.356652) (xy 429.187102 -51.374294)
			(xy 429.187356 -51.374548) (xy 429.194447 -51.380128) (xy 429.211361 -51.386377) (xy 429.220376 -51.38674)
			(xy 429.287432 -51.38674) (xy 429.296452 -51.386412) (xy 429.31337 -51.380146) (xy 429.320452 -51.374548)
			(xy 429.32096 -51.37404) (xy 429.341895 -51.356459) (xy 429.387829 -51.326818) (xy 429.437524 -51.304038)
			(xy 429.489963 -51.288588) (xy 429.54407 -51.280783) (xy 429.571404 -51.280314) (xy 429.589747 -51.280542)
			(xy 429.62626 -51.284108) (xy 429.644302 -51.287426) (xy 429.644556 -51.287426) (xy 429.65506 -51.288817)
			(xy 429.67566 -51.283966) (xy 429.684434 -51.278028) (xy 429.753776 -51.225704) (xy 429.763936 -51.206908)
			(xy 429.764952 -51.195986) (xy 429.767841 -51.167701) (xy 429.780879 -51.112364) (xy 429.801976 -51.05957)
			(xy 429.830666 -51.010487) (xy 429.866316 -50.966199) (xy 429.886872 -50.946558) (xy 429.894327 -50.938997)
			(xy 429.902845 -50.919571) (xy 429.903382 -50.908966) (xy 429.903382 -50.834798) (xy 429.902971 -50.824166)
			(xy 429.894423 -50.804701) (xy 429.886872 -50.797206) (xy 429.867824 -50.779069) (xy 429.834364 -50.738491)
			(xy 429.806802 -50.693697) (xy 429.785661 -50.645538) (xy 429.771343 -50.59493) (xy 429.764119 -50.542833)
			(xy 429.763682 -50.516536) (xy 429.763682 -50.516282) (xy 429.764168 -50.489031) (xy 429.771924 -50.435083)
			(xy 429.787279 -50.382788) (xy 429.809921 -50.333211) (xy 429.839387 -50.287361) (xy 429.875078 -50.24617)
			(xy 429.916269 -50.210479) (xy 429.962119 -50.181013) (xy 430.011696 -50.158371) (xy 430.063991 -50.143016)
			(xy 430.117939 -50.13526) (xy 430.172441 -50.13526) (xy 430.226389 -50.143016) (xy 430.278684 -50.158371)
			(xy 430.328261 -50.181013) (xy 430.374111 -50.210479) (xy 430.415302 -50.24617) (xy 430.450993 -50.287361)
			(xy 430.480459 -50.333211) (xy 430.503101 -50.382788) (xy 430.518456 -50.435083) (xy 430.526212 -50.489031)
			(xy 430.526698 -50.516282) (xy 430.526698 -50.516536) (xy 430.526264 -50.542832) (xy 430.519014 -50.594921)
			(xy 430.504683 -50.645523) (xy 430.483543 -50.693679) (xy 430.455993 -50.738478) (xy 430.422556 -50.779072)
			(xy 430.403508 -50.797206) (xy 430.396067 -50.804777) (xy 430.387541 -50.824196) (xy 430.386998 -50.834798)
			(xy 430.386998 -50.908966) (xy 430.387381 -50.919601) (xy 430.395949 -50.939065) (xy 430.403508 -50.946558)
			(xy 430.422554 -50.964696) (xy 430.456011 -51.005277) (xy 430.483571 -51.050071) (xy 430.504712 -51.098229)
			(xy 430.519032 -51.148836) (xy 430.526258 -51.200931) (xy 430.526698 -51.227228) (xy 430.526698 -51.227482)
			(xy 430.526413 -51.243992) (xy 433.432966 -51.243992) (xy 433.433446 -51.216658) (xy 433.44125 -51.162551)
			(xy 433.456696 -51.110112) (xy 433.479469 -51.060414) (xy 433.509102 -51.014475) (xy 433.526692 -50.993548)
			(xy 433.526946 -50.993294) (xy 433.5272 -50.99304) (xy 433.532776 -50.985946) (xy 433.539029 -50.969035)
			(xy 433.539392 -50.96002) (xy 433.539392 -50.892964) (xy 433.539054 -50.883945) (xy 433.532793 -50.867028)
			(xy 433.5272 -50.859944) (xy 433.526946 -50.85969) (xy 433.526692 -50.859436) (xy 433.509102 -50.838509)
			(xy 433.479463 -50.792572) (xy 433.456687 -50.742875) (xy 433.441238 -50.690434) (xy 433.433435 -50.636326)
			(xy 433.432966 -50.608992) (xy 433.43347 -50.581742) (xy 433.441227 -50.527796) (xy 433.456582 -50.475503)
			(xy 433.479222 -50.425928) (xy 433.508687 -50.380079) (xy 433.544376 -50.338889) (xy 433.585564 -50.303198)
			(xy 433.631412 -50.273731) (xy 433.680986 -50.251088) (xy 433.733278 -50.235731) (xy 433.787224 -50.227972)
			(xy 433.814474 -50.227484) (xy 433.843392 -50.227989) (xy 433.900565 -50.236716) (xy 433.955766 -50.253975)
			(xy 434.007728 -50.279369) (xy 434.055261 -50.312316) (xy 434.097276 -50.352062) (xy 434.115464 -50.37455)
			(xy 434.121761 -50.381921) (xy 434.138465 -50.391725) (xy 434.147976 -50.3936) (xy 434.155596 -50.394108)
			(xy 434.235352 -50.394108) (xy 434.242972 -50.3936) (xy 434.25249 -50.391744) (xy 434.269203 -50.381939)
			(xy 434.275484 -50.37455) (xy 434.293671 -50.352064) (xy 434.335693 -50.312331) (xy 434.38323 -50.279394)
			(xy 434.435191 -50.254006) (xy 434.490389 -50.23675) (xy 434.547558 -50.22802) (xy 434.576474 -50.227484)
			(xy 434.603726 -50.227979) (xy 434.657675 -50.235733) (xy 434.709972 -50.251085) (xy 434.759551 -50.273724)
			(xy 434.805404 -50.303188) (xy 434.846597 -50.338879) (xy 434.882291 -50.380068) (xy 434.91176 -50.425919)
			(xy 434.934403 -50.475496) (xy 434.94976 -50.527792) (xy 434.957518 -50.58174) (xy 434.957982 -50.608992)
			(xy 434.957982 -50.609246) (xy 434.95756 -50.635542) (xy 434.950308 -50.687633) (xy 434.935975 -50.738235)
			(xy 434.914833 -50.786391) (xy 434.887281 -50.83119) (xy 434.853842 -50.871783) (xy 434.834792 -50.889916)
			(xy 434.827344 -50.897482) (xy 434.818823 -50.916904) (xy 434.818282 -50.927508) (xy 434.818282 -51.001676)
			(xy 434.818718 -51.012305) (xy 434.821852 -51.019456) (xy 451.049388 -51.019456) (xy 451.053459 -50.963834)
			(xy 451.065585 -50.909397) (xy 451.085508 -50.857306) (xy 451.112804 -50.808671) (xy 451.14689 -50.764528)
			(xy 451.187039 -50.725819) (xy 451.232397 -50.693368) (xy 451.281997 -50.667867) (xy 451.334781 -50.64986)
			(xy 451.389624 -50.63973) (xy 451.445358 -50.637693) (xy 451.500795 -50.643793) (xy 451.554752 -50.657899)
			(xy 451.606081 -50.679711) (xy 451.653687 -50.708765) (xy 451.696555 -50.74444) (xy 451.733772 -50.785977)
			(xy 451.764545 -50.83249) (xy 451.788217 -50.882987) (xy 451.804285 -50.936394) (xy 451.812405 -50.99157)
			(xy 451.812914 -51.019456) (xy 453.241154 -51.019456) (xy 453.245225 -50.963834) (xy 453.257351 -50.909397)
			(xy 453.277274 -50.857306) (xy 453.30457 -50.808671) (xy 453.338656 -50.764528) (xy 453.378805 -50.725819)
			(xy 453.424163 -50.693368) (xy 453.473763 -50.667867) (xy 453.526547 -50.64986) (xy 453.58139 -50.63973)
			(xy 453.637124 -50.637693) (xy 453.692561 -50.643793) (xy 453.746518 -50.657899) (xy 453.797847 -50.679711)
			(xy 453.845453 -50.708765) (xy 453.888321 -50.74444) (xy 453.925538 -50.785977) (xy 453.956311 -50.83249)
			(xy 453.979983 -50.882987) (xy 453.996051 -50.936394) (xy 454.004171 -50.99157) (xy 454.00468 -51.019456)
			(xy 454.004171 -51.047342) (xy 453.996051 -51.102518) (xy 453.979983 -51.155925) (xy 453.956311 -51.206422)
			(xy 453.925538 -51.252935) (xy 453.888321 -51.294472) (xy 453.845453 -51.330147) (xy 453.797847 -51.359201)
			(xy 453.746518 -51.381013) (xy 453.692561 -51.395119) (xy 453.637124 -51.401219) (xy 453.58139 -51.399182)
			(xy 453.526547 -51.389052) (xy 453.473763 -51.371045) (xy 453.424163 -51.345544) (xy 453.378805 -51.313093)
			(xy 453.338656 -51.274384) (xy 453.30457 -51.230241) (xy 453.277274 -51.181606) (xy 453.257351 -51.129515)
			(xy 453.245225 -51.075078) (xy 453.241154 -51.019456) (xy 451.812914 -51.019456) (xy 451.812405 -51.047342)
			(xy 451.804285 -51.102518) (xy 451.788217 -51.155925) (xy 451.764545 -51.206422) (xy 451.733772 -51.252935)
			(xy 451.696555 -51.294472) (xy 451.653687 -51.330147) (xy 451.606081 -51.359201) (xy 451.554752 -51.381013)
			(xy 451.500795 -51.395119) (xy 451.445358 -51.401219) (xy 451.389624 -51.399182) (xy 451.334781 -51.389052)
			(xy 451.281997 -51.371045) (xy 451.232397 -51.345544) (xy 451.187039 -51.313093) (xy 451.14689 -51.274384)
			(xy 451.112804 -51.230241) (xy 451.085508 -51.181606) (xy 451.065585 -51.129515) (xy 451.053459 -51.075078)
			(xy 451.049388 -51.019456) (xy 434.821852 -51.019456) (xy 434.827249 -51.031769) (xy 434.834792 -51.039268)
			(xy 434.85384 -51.057405) (xy 434.887297 -51.097985) (xy 434.914858 -51.142779) (xy 434.935999 -51.190938)
			(xy 434.950318 -51.241545) (xy 434.957543 -51.293641) (xy 434.957982 -51.319938) (xy 434.957982 -51.320192)
			(xy 434.957537 -51.347446) (xy 434.949781 -51.401399) (xy 434.934424 -51.453699) (xy 434.911781 -51.50328)
			(xy 434.882311 -51.549135) (xy 434.846615 -51.590328) (xy 434.80542 -51.626022) (xy 434.759565 -51.655489)
			(xy 434.709982 -51.678131) (xy 434.657681 -51.693484) (xy 434.603728 -51.701238) (xy 434.576474 -51.7017)
			(xy 434.548808 -51.701208) (xy 434.494058 -51.693205) (xy 434.441036 -51.677385) (xy 434.390852 -51.654079)
			(xy 434.344557 -51.623774) (xy 434.303119 -51.587106) (xy 434.267407 -51.544842) (xy 434.25237 -51.521614)
			(xy 434.252116 -51.52136) (xy 434.245457 -51.51183) (xy 434.225757 -51.499526) (xy 434.21427 -51.497738)
			(xy 434.13426 -51.489864) (xy 434.122558 -51.489183) (xy 434.100584 -51.497273) (xy 434.092096 -51.505358)
			(xy 434.092096 -51.505612) (xy 434.074002 -51.52418) (xy 434.033672 -51.556759) (xy 433.989301 -51.583573)
			(xy 433.941705 -51.604128) (xy 433.891763 -51.618045) (xy 433.840396 -51.625066) (xy 433.814474 -51.6255)
			(xy 433.787222 -51.625046) (xy 433.733272 -51.617286) (xy 433.680977 -51.601927) (xy 433.631399 -51.579283)
			(xy 433.585548 -51.549813) (xy 433.544358 -51.514118) (xy 433.508667 -51.472925) (xy 433.479201 -51.427071)
			(xy 433.456561 -51.377491) (xy 433.441207 -51.325194) (xy 433.433451 -51.271244) (xy 433.432966 -51.243992)
			(xy 430.526413 -51.243992) (xy 430.526228 -51.254735) (xy 430.518473 -51.308686) (xy 430.503119 -51.360984)
			(xy 430.480478 -51.410565) (xy 430.451011 -51.456419) (xy 430.415318 -51.497612) (xy 430.374125 -51.533306)
			(xy 430.328272 -51.562774) (xy 430.278692 -51.585416) (xy 430.226394 -51.600771) (xy 430.172443 -51.608527)
			(xy 430.14519 -51.60899) (xy 430.126847 -51.608763) (xy 430.090334 -51.605196) (xy 430.072292 -51.601878)
			(xy 430.072038 -51.601878) (xy 430.061535 -51.600483) (xy 430.040934 -51.605336) (xy 430.03216 -51.611276)
			(xy 429.962818 -51.6636) (xy 429.952658 -51.682396) (xy 429.951642 -51.693318) (xy 429.94876 -51.721578)
			(xy 429.935727 -51.776864) (xy 429.914641 -51.829608) (xy 429.885968 -51.878642) (xy 429.850343 -51.922883)
			(xy 429.808552 -51.961354) (xy 429.761519 -51.993204) (xy 429.710284 -52.017728) (xy 429.655979 -52.034386)
			(xy 429.648842 -52.035456) (xy 453.241154 -52.035456) (xy 453.245225 -51.979834) (xy 453.257351 -51.925397)
			(xy 453.277274 -51.873306) (xy 453.30457 -51.824671) (xy 453.338656 -51.780528) (xy 453.378805 -51.741819)
			(xy 453.424163 -51.709368) (xy 453.473763 -51.683867) (xy 453.526547 -51.66586) (xy 453.58139 -51.65573)
			(xy 453.637124 -51.653693) (xy 453.692561 -51.659793) (xy 453.746518 -51.673899) (xy 453.797847 -51.695711)
			(xy 453.845453 -51.724765) (xy 453.888321 -51.76044) (xy 453.925538 -51.801977) (xy 453.956311 -51.84849)
			(xy 453.979983 -51.898987) (xy 453.996051 -51.952394) (xy 454.004171 -52.00757) (xy 454.00468 -52.035456)
			(xy 454.004171 -52.063342) (xy 453.996051 -52.118518) (xy 453.979983 -52.171925) (xy 453.956311 -52.222422)
			(xy 453.925538 -52.268935) (xy 453.888321 -52.310472) (xy 453.845453 -52.346147) (xy 453.797847 -52.375201)
			(xy 453.746518 -52.397013) (xy 453.692561 -52.411119) (xy 453.637124 -52.417219) (xy 453.58139 -52.415182)
			(xy 453.526547 -52.405052) (xy 453.473763 -52.387045) (xy 453.424163 -52.361544) (xy 453.378805 -52.329093)
			(xy 453.338656 -52.290384) (xy 453.30457 -52.246241) (xy 453.277274 -52.197606) (xy 453.257351 -52.145515)
			(xy 453.245225 -52.091078) (xy 453.241154 -52.035456) (xy 429.648842 -52.035456) (xy 429.599805 -52.042808)
			(xy 429.571404 -52.04333) (xy 429.544033 -52.042879) (xy 429.489853 -52.03506) (xy 429.437349 -52.019568)
			(xy 429.387602 -51.996723) (xy 429.341636 -51.966994) (xy 429.320706 -51.94935) (xy 429.320452 -51.949096)
			(xy 429.313355 -51.943525) (xy 429.296446 -51.937269) (xy 429.287432 -51.936904) (xy 429.220376 -51.936904)
			(xy 429.211358 -51.937249) (xy 429.194441 -51.943505) (xy 429.187356 -51.949096) (xy 429.186848 -51.949604)
			(xy 429.165916 -51.967188) (xy 429.11998 -51.996827) (xy 429.070284 -52.019605) (xy 429.017845 -52.035055)
			(xy 428.963738 -52.04286) (xy 428.936404 -52.04333) (xy 428.909153 -52.042823) (xy 428.855204 -52.035067)
			(xy 428.802909 -52.019712) (xy 428.753331 -51.997071) (xy 428.70748 -51.967605) (xy 428.666289 -51.931913)
			(xy 428.630597 -51.890723) (xy 428.601131 -51.844872) (xy 428.578489 -51.795295) (xy 428.563134 -51.743)
			(xy 428.555377 -51.689051) (xy 427.782226 -51.689051) (xy 427.797899 -51.695711) (xy 427.845505 -51.724765)
			(xy 427.888373 -51.76044) (xy 427.92559 -51.801977) (xy 427.956363 -51.84849) (xy 427.980035 -51.898987)
			(xy 427.996103 -51.952394) (xy 428.004223 -52.00757) (xy 428.004732 -52.035456) (xy 428.004223 -52.063342)
			(xy 427.996103 -52.118518) (xy 427.980035 -52.171925) (xy 427.956363 -52.222422) (xy 427.92559 -52.268935)
			(xy 427.888373 -52.310472) (xy 427.845505 -52.346147) (xy 427.797899 -52.375201) (xy 427.74657 -52.397013)
			(xy 427.692613 -52.411119) (xy 427.637176 -52.417219) (xy 427.581442 -52.415182) (xy 427.526599 -52.405052)
			(xy 427.473815 -52.387045) (xy 427.424215 -52.361544) (xy 427.378857 -52.329093) (xy 427.338708 -52.290384)
			(xy 427.304622 -52.246241) (xy 427.277326 -52.197606) (xy 427.257403 -52.145515) (xy 427.245277 -52.091078)
			(xy 427.241206 -52.035456) (xy 403.648825 -52.035456) (xy 403.599855 -52.042804) (xy 403.571456 -52.04333)
			(xy 403.544086 -52.042848) (xy 403.489907 -52.035037) (xy 403.437403 -52.019552) (xy 403.387656 -51.996714)
			(xy 403.341689 -51.966991) (xy 403.320758 -51.94935) (xy 403.320504 -51.949096) (xy 403.313421 -51.943505)
			(xy 403.296501 -51.937261) (xy 403.287484 -51.936904) (xy 403.220428 -51.936904) (xy 403.211412 -51.937273)
			(xy 403.194495 -51.943512) (xy 403.187408 -51.949096) (xy 403.1869 -51.949604) (xy 403.165986 -51.967211)
			(xy 403.120045 -51.996847) (xy 403.070345 -52.01962) (xy 403.017902 -52.035065) (xy 402.963791 -52.042864)
			(xy 402.936456 -52.04333) (xy 402.909208 -52.042797) (xy 402.855269 -52.035036) (xy 402.802982 -52.019678)
			(xy 402.753413 -51.997035) (xy 402.707571 -51.96757) (xy 402.666389 -51.93188) (xy 402.630704 -51.890693)
			(xy 402.601244 -51.844848) (xy 402.578607 -51.795277) (xy 402.563255 -51.742988) (xy 402.5555 -51.689048)
			(xy 401.782271 -51.689048) (xy 401.797951 -51.695711) (xy 401.845557 -51.724765) (xy 401.888425 -51.76044)
			(xy 401.925642 -51.801977) (xy 401.956415 -51.84849) (xy 401.980087 -51.898987) (xy 401.996155 -51.952394)
			(xy 402.004275 -52.00757) (xy 402.004784 -52.035456) (xy 402.004275 -52.063342) (xy 401.996155 -52.118518)
			(xy 401.980087 -52.171925) (xy 401.956415 -52.222422) (xy 401.925642 -52.268935) (xy 401.888425 -52.310472)
			(xy 401.845557 -52.346147) (xy 401.797951 -52.375201) (xy 401.746622 -52.397013) (xy 401.692665 -52.411119)
			(xy 401.637228 -52.417219) (xy 401.581494 -52.415182) (xy 401.526651 -52.405052) (xy 401.473867 -52.387045)
			(xy 401.424267 -52.361544) (xy 401.378909 -52.329093) (xy 401.33876 -52.290384) (xy 401.304674 -52.246241)
			(xy 401.277378 -52.197606) (xy 401.257455 -52.145515) (xy 401.245329 -52.091078) (xy 401.241258 -52.035456)
			(xy 377.64894 -52.035456) (xy 377.599909 -52.042807) (xy 377.571508 -52.04333) (xy 377.544137 -52.042876)
			(xy 377.489957 -52.035058) (xy 377.437453 -52.019567) (xy 377.387706 -51.996722) (xy 377.341741 -51.966994)
			(xy 377.32081 -51.94935) (xy 377.320556 -51.949096) (xy 377.313458 -51.943526) (xy 377.29655 -51.93727)
			(xy 377.287536 -51.936904) (xy 377.22048 -51.936904) (xy 377.211462 -51.937251) (xy 377.194545 -51.943505)
			(xy 377.18746 -51.949096) (xy 377.186952 -51.949604) (xy 377.166018 -51.967186) (xy 377.120083 -51.996826)
			(xy 377.070387 -52.019604) (xy 377.017949 -52.035054) (xy 376.963842 -52.04286) (xy 376.936508 -52.04333)
			(xy 376.909256 -52.042823) (xy 376.855308 -52.035068) (xy 376.803012 -52.019713) (xy 376.753434 -51.997072)
			(xy 376.707582 -51.967606) (xy 376.666391 -51.931915) (xy 376.630698 -51.890724) (xy 376.601231 -51.844873)
			(xy 376.57859 -51.795296) (xy 376.563234 -51.743) (xy 376.555477 -51.689052) (xy 375.782333 -51.689052)
			(xy 375.798003 -51.695711) (xy 375.845609 -51.724765) (xy 375.888477 -51.76044) (xy 375.925694 -51.801977)
			(xy 375.956467 -51.84849) (xy 375.980139 -51.898987) (xy 375.996207 -51.952394) (xy 376.004327 -52.00757)
			(xy 376.004836 -52.035456) (xy 376.004327 -52.063342) (xy 375.996207 -52.118518) (xy 375.980139 -52.171925)
			(xy 375.956467 -52.222422) (xy 375.925694 -52.268935) (xy 375.888477 -52.310472) (xy 375.845609 -52.346147)
			(xy 375.798003 -52.375201) (xy 375.746674 -52.397013) (xy 375.692717 -52.411119) (xy 375.63728 -52.417219)
			(xy 375.581546 -52.415182) (xy 375.526703 -52.405052) (xy 375.473919 -52.387045) (xy 375.424319 -52.361544)
			(xy 375.378961 -52.329093) (xy 375.338812 -52.290384) (xy 375.304726 -52.246241) (xy 375.27743 -52.197606)
			(xy 375.257507 -52.145515) (xy 375.245381 -52.091078) (xy 375.24131 -52.035456) (xy 351.648923 -52.035456)
			(xy 351.599958 -52.042804) (xy 351.57156 -52.04333) (xy 351.54419 -52.042846) (xy 351.490011 -52.035035)
			(xy 351.437508 -52.019551) (xy 351.38776 -51.996713) (xy 351.341793 -51.966991) (xy 351.320862 -51.94935)
			(xy 351.320608 -51.949096) (xy 351.313524 -51.943506) (xy 351.296605 -51.937262) (xy 351.287588 -51.936904)
			(xy 351.220532 -51.936904) (xy 351.211517 -51.937275) (xy 351.194599 -51.943513) (xy 351.187512 -51.949096)
			(xy 351.187004 -51.949604) (xy 351.166088 -51.967209) (xy 351.120148 -51.996845) (xy 351.070448 -52.019619)
			(xy 351.018005 -52.035064) (xy 350.963895 -52.042863) (xy 350.93656 -52.04333) (xy 350.909312 -52.042797)
			(xy 350.855372 -52.035036) (xy 350.803085 -52.019679) (xy 350.753516 -51.997037) (xy 350.707673 -51.967571)
			(xy 350.66649 -51.931882) (xy 350.630805 -51.890695) (xy 350.601344 -51.844849) (xy 350.578707 -51.795277)
			(xy 350.563355 -51.742989) (xy 350.5556 -51.689048) (xy 337.682069 -51.689048) (xy 337.697749 -51.695711)
			(xy 337.745355 -51.724765) (xy 337.788223 -51.76044) (xy 337.82544 -51.801977) (xy 337.856213 -51.84849)
			(xy 337.879885 -51.898987) (xy 337.895953 -51.952394) (xy 337.904073 -52.00757) (xy 337.904582 -52.035456)
			(xy 337.904073 -52.063342) (xy 337.895953 -52.118518) (xy 337.879885 -52.171925) (xy 337.856213 -52.222422)
			(xy 337.82544 -52.268935) (xy 337.788223 -52.310472) (xy 337.745355 -52.346147) (xy 337.697749 -52.375201)
			(xy 337.64642 -52.397013) (xy 337.592463 -52.411119) (xy 337.537026 -52.417219) (xy 337.481292 -52.415182)
			(xy 337.426449 -52.405052) (xy 337.373665 -52.387045) (xy 337.324065 -52.361544) (xy 337.278707 -52.329093)
			(xy 337.238558 -52.290384) (xy 337.204472 -52.246241) (xy 337.177176 -52.197606) (xy 337.157253 -52.145515)
			(xy 337.145127 -52.091078) (xy 337.141056 -52.035456) (xy 313.548738 -52.035456) (xy 313.499707 -52.042807)
			(xy 313.471306 -52.04333) (xy 313.443935 -52.042877) (xy 313.389755 -52.035059) (xy 313.337251 -52.019568)
			(xy 313.287504 -51.996723) (xy 313.241539 -51.966994) (xy 313.220608 -51.94935) (xy 313.220354 -51.949096)
			(xy 313.213256 -51.943525) (xy 313.196348 -51.937269) (xy 313.187334 -51.936904) (xy 313.120278 -51.936904)
			(xy 313.11126 -51.93725) (xy 313.094343 -51.943505) (xy 313.087258 -51.949096) (xy 313.08675 -51.949604)
			(xy 313.065817 -51.967187) (xy 313.019882 -51.996827) (xy 312.970186 -52.019605) (xy 312.917747 -52.035055)
			(xy 312.86364 -52.04286) (xy 312.836306 -52.04333) (xy 312.809054 -52.042823) (xy 312.755106 -52.035067)
			(xy 312.70281 -52.019713) (xy 312.653232 -51.997072) (xy 312.607381 -51.967606) (xy 312.56619 -51.931914)
			(xy 312.530498 -51.890724) (xy 312.501031 -51.844873) (xy 312.478389 -51.795295) (xy 312.463034 -51.743)
			(xy 312.455277 -51.689052) (xy 311.682131 -51.689052) (xy 311.697801 -51.695711) (xy 311.745407 -51.724765)
			(xy 311.788275 -51.76044) (xy 311.825492 -51.801977) (xy 311.856265 -51.84849) (xy 311.879937 -51.898987)
			(xy 311.896005 -51.952394) (xy 311.904125 -52.00757) (xy 311.904634 -52.035456) (xy 311.904125 -52.063342)
			(xy 311.896005 -52.118518) (xy 311.879937 -52.171925) (xy 311.856265 -52.222422) (xy 311.825492 -52.268935)
			(xy 311.788275 -52.310472) (xy 311.745407 -52.346147) (xy 311.697801 -52.375201) (xy 311.646472 -52.397013)
			(xy 311.592515 -52.411119) (xy 311.537078 -52.417219) (xy 311.481344 -52.415182) (xy 311.426501 -52.405052)
			(xy 311.373717 -52.387045) (xy 311.324117 -52.361544) (xy 311.278759 -52.329093) (xy 311.23861 -52.290384)
			(xy 311.204524 -52.246241) (xy 311.177228 -52.197606) (xy 311.157305 -52.145515) (xy 311.145179 -52.091078)
			(xy 311.141108 -52.035456) (xy 287.548721 -52.035456) (xy 287.499756 -52.042804) (xy 287.471358 -52.04333)
			(xy 287.443988 -52.042847) (xy 287.389809 -52.035036) (xy 287.337306 -52.019552) (xy 287.287558 -51.996713)
			(xy 287.241591 -51.966991) (xy 287.22066 -51.94935) (xy 287.220406 -51.949096) (xy 287.213322 -51.943505)
			(xy 287.196403 -51.937261) (xy 287.187386 -51.936904) (xy 287.12033 -51.936904) (xy 287.111314 -51.937274)
			(xy 287.094397 -51.943512) (xy 287.08731 -51.949096) (xy 287.086802 -51.949604) (xy 287.065887 -51.96721)
			(xy 287.019947 -51.996846) (xy 286.970246 -52.01962) (xy 286.917804 -52.035064) (xy 286.863693 -52.042864)
			(xy 286.836358 -52.04333) (xy 286.80911 -52.042797) (xy 286.75517 -52.035036) (xy 286.702884 -52.019678)
			(xy 286.653315 -51.997036) (xy 286.607472 -51.96757) (xy 286.566289 -51.931881) (xy 286.530605 -51.890694)
			(xy 286.501144 -51.844848) (xy 286.478507 -51.795277) (xy 286.463155 -51.742989) (xy 286.4554 -51.689048)
			(xy 285.682173 -51.689048) (xy 285.697853 -51.695711) (xy 285.745459 -51.724765) (xy 285.788327 -51.76044)
			(xy 285.825544 -51.801977) (xy 285.856317 -51.84849) (xy 285.879989 -51.898987) (xy 285.896057 -51.952394)
			(xy 285.904177 -52.00757) (xy 285.904686 -52.035456) (xy 285.904177 -52.063342) (xy 285.896057 -52.118518)
			(xy 285.879989 -52.171925) (xy 285.856317 -52.222422) (xy 285.825544 -52.268935) (xy 285.788327 -52.310472)
			(xy 285.745459 -52.346147) (xy 285.697853 -52.375201) (xy 285.646524 -52.397013) (xy 285.592567 -52.411119)
			(xy 285.53713 -52.417219) (xy 285.481396 -52.415182) (xy 285.426553 -52.405052) (xy 285.373769 -52.387045)
			(xy 285.324169 -52.361544) (xy 285.278811 -52.329093) (xy 285.238662 -52.290384) (xy 285.204576 -52.246241)
			(xy 285.17728 -52.197606) (xy 285.157357 -52.145515) (xy 285.145231 -52.091078) (xy 285.14116 -52.035456)
			(xy 261.548835 -52.035456) (xy 261.499811 -52.042807) (xy 261.47141 -52.04333) (xy 261.444039 -52.042875)
			(xy 261.389859 -52.035057) (xy 261.337355 -52.019566) (xy 261.287608 -51.996722) (xy 261.241643 -51.966993)
			(xy 261.220712 -51.94935) (xy 261.220458 -51.949096) (xy 261.213359 -51.943527) (xy 261.196452 -51.93727)
			(xy 261.187438 -51.936904) (xy 261.120382 -51.936904) (xy 261.111364 -51.937252) (xy 261.094447 -51.943506)
			(xy 261.087362 -51.949096) (xy 261.086854 -51.949604) (xy 261.065919 -51.967185) (xy 261.019985 -51.996825)
			(xy 260.970289 -52.019604) (xy 260.917851 -52.035054) (xy 260.863744 -52.04286) (xy 260.83641 -52.04333)
			(xy 260.809158 -52.042823) (xy 260.755209 -52.035068) (xy 260.702913 -52.019714) (xy 260.653335 -51.997073)
			(xy 260.607483 -51.967607) (xy 260.566292 -51.931916) (xy 260.530599 -51.890725) (xy 260.501132 -51.844874)
			(xy 260.47849 -51.795296) (xy 260.463134 -51.743) (xy 260.455377 -51.689052) (xy 259.682235 -51.689052)
			(xy 259.697905 -51.695711) (xy 259.745511 -51.724765) (xy 259.788379 -51.76044) (xy 259.825596 -51.801977)
			(xy 259.856369 -51.84849) (xy 259.880041 -51.898987) (xy 259.896109 -51.952394) (xy 259.904229 -52.00757)
			(xy 259.904738 -52.035456) (xy 259.904229 -52.063342) (xy 259.896109 -52.118518) (xy 259.880041 -52.171925)
			(xy 259.856369 -52.222422) (xy 259.825596 -52.268935) (xy 259.788379 -52.310472) (xy 259.745511 -52.346147)
			(xy 259.697905 -52.375201) (xy 259.646576 -52.397013) (xy 259.592619 -52.411119) (xy 259.537182 -52.417219)
			(xy 259.481448 -52.415182) (xy 259.426605 -52.405052) (xy 259.373821 -52.387045) (xy 259.324221 -52.361544)
			(xy 259.278863 -52.329093) (xy 259.238714 -52.290384) (xy 259.204628 -52.246241) (xy 259.177332 -52.197606)
			(xy 259.157409 -52.145515) (xy 259.145283 -52.091078) (xy 259.141212 -52.035456) (xy 237.717251 -52.035456)
			(xy 237.713672 -52.06026) (xy 237.698215 -52.112703) (xy 237.675427 -52.162401) (xy 237.645775 -52.208335)
			(xy 237.628176 -52.229258) (xy 237.627922 -52.229512) (xy 237.627668 -52.229766) (xy 237.622086 -52.236856)
			(xy 237.615838 -52.25377) (xy 237.615476 -52.262786) (xy 237.615476 -52.329842) (xy 237.615866 -52.338855)
			(xy 237.622091 -52.355772) (xy 237.627668 -52.362862) (xy 237.627922 -52.363116) (xy 237.628176 -52.36337)
			(xy 237.645764 -52.384299) (xy 237.675404 -52.430235) (xy 237.698182 -52.479932) (xy 237.71363 -52.532372)
			(xy 237.721434 -52.58648) (xy 237.721902 -52.613814) (xy 237.721416 -52.641065) (xy 237.71366 -52.695013)
			(xy 237.698305 -52.747308) (xy 237.675663 -52.796885) (xy 237.646197 -52.842735) (xy 237.610506 -52.883926)
			(xy 237.610047 -52.884324) (xy 240.776504 -52.884324) (xy 240.780575 -52.828702) (xy 240.792701 -52.774265)
			(xy 240.812624 -52.722174) (xy 240.83992 -52.673539) (xy 240.874006 -52.629396) (xy 240.914155 -52.590687)
			(xy 240.959513 -52.558236) (xy 241.009113 -52.532735) (xy 241.061897 -52.514728) (xy 241.11674 -52.504598)
			(xy 241.172474 -52.502561) (xy 241.227911 -52.508661) (xy 241.281868 -52.522767) (xy 241.333197 -52.544579)
			(xy 241.380803 -52.573633) (xy 241.423671 -52.609308) (xy 241.460888 -52.650845) (xy 241.491661 -52.697358)
			(xy 241.515333 -52.747855) (xy 241.531401 -52.801262) (xy 241.539521 -52.856438) (xy 241.54003 -52.884324)
			(xy 241.539521 -52.91221) (xy 241.531401 -52.967386) (xy 241.515333 -53.020793) (xy 241.491661 -53.07129)
			(xy 241.460888 -53.117803) (xy 241.423671 -53.15934) (xy 241.380803 -53.195015) (xy 241.333197 -53.224069)
			(xy 241.281868 -53.245881) (xy 241.227911 -53.259987) (xy 241.172474 -53.266087) (xy 241.11674 -53.26405)
			(xy 241.061897 -53.25392) (xy 241.009113 -53.235913) (xy 240.959513 -53.210412) (xy 240.914155 -53.177961)
			(xy 240.874006 -53.139252) (xy 240.83992 -53.095109) (xy 240.812624 -53.046474) (xy 240.792701 -52.994383)
			(xy 240.780575 -52.939946) (xy 240.776504 -52.884324) (xy 237.610047 -52.884324) (xy 237.569315 -52.919617)
			(xy 237.523465 -52.949083) (xy 237.473888 -52.971725) (xy 237.421593 -52.98708) (xy 237.367645 -52.994836)
			(xy 237.313143 -52.994836) (xy 237.259195 -52.98708) (xy 237.2069 -52.971725) (xy 237.157323 -52.949083)
			(xy 237.111473 -52.919617) (xy 237.070282 -52.883926) (xy 237.034591 -52.842735) (xy 237.005125 -52.796885)
			(xy 236.982483 -52.747308) (xy 236.967128 -52.695013) (xy 236.959372 -52.641065) (xy 236.958886 -52.613814)
			(xy 236.95934 -52.58648) (xy 236.967153 -52.532372) (xy 236.982607 -52.479933) (xy 237.005385 -52.430236)
			(xy 237.035021 -52.384297) (xy 237.052612 -52.36337) (xy 237.052866 -52.363116) (xy 237.05312 -52.362862)
			(xy 237.058689 -52.355763) (xy 237.064946 -52.338856) (xy 237.065312 -52.329842) (xy 237.065312 -52.262786)
			(xy 237.064959 -52.253769) (xy 237.058708 -52.236852) (xy 237.05312 -52.229766) (xy 237.052866 -52.229512)
			(xy 237.052612 -52.229258) (xy 237.035024 -52.208326) (xy 237.005367 -52.162396) (xy 236.982575 -52.1127)
			(xy 236.967115 -52.060259) (xy 236.959304 -52.006147) (xy 236.959302 -51.951474) (xy 236.96711 -51.897362)
			(xy 236.982567 -51.84492) (xy 237.005357 -51.795223) (xy 237.035011 -51.749291) (xy 237.052612 -51.72837)
			(xy 237.052866 -51.728116) (xy 237.05312 -51.727862) (xy 237.058689 -51.720763) (xy 237.064946 -51.703856)
			(xy 237.065312 -51.694842) (xy 237.065312 -51.627786) (xy 237.064959 -51.618769) (xy 237.058708 -51.601852)
			(xy 237.05312 -51.594766) (xy 237.052866 -51.594512) (xy 237.052612 -51.594258) (xy 237.041747 -51.581506)
			(xy 237.022032 -51.554417) (xy 237.013242 -51.540156) (xy 237.007654 -51.531012) (xy 236.990636 -51.51882)
			(xy 236.897672 -51.498754) (xy 236.877098 -51.502818) (xy 236.868462 -51.508914) (xy 236.844411 -51.524934)
			(xy 236.792475 -51.550272) (xy 236.737313 -51.567492) (xy 236.680186 -51.576201) (xy 236.651292 -51.576732)
			(xy 236.624043 -51.576197) (xy 236.570099 -51.56844) (xy 236.517809 -51.553085) (xy 236.468236 -51.530445)
			(xy 236.42239 -51.500981) (xy 236.381203 -51.465291) (xy 236.345514 -51.424104) (xy 236.316051 -51.378257)
			(xy 236.293412 -51.328683) (xy 236.278058 -51.276393) (xy 236.270302 -51.222449) (xy 221.745766 -51.222449)
			(xy 221.725596 -51.252935) (xy 221.688379 -51.294472) (xy 221.645511 -51.330147) (xy 221.597905 -51.359201)
			(xy 221.546576 -51.381013) (xy 221.492619 -51.395119) (xy 221.437182 -51.401219) (xy 221.381448 -51.399182)
			(xy 221.326605 -51.389052) (xy 221.273821 -51.371045) (xy 221.224221 -51.345544) (xy 221.178863 -51.313093)
			(xy 221.138714 -51.274384) (xy 221.104628 -51.230241) (xy 221.077332 -51.181606) (xy 221.057409 -51.129515)
			(xy 221.045283 -51.075078) (xy 221.041212 -51.019456) (xy 219.612972 -51.019456) (xy 219.612463 -51.047342)
			(xy 219.604343 -51.102518) (xy 219.588275 -51.155925) (xy 219.564603 -51.206422) (xy 219.53383 -51.252935)
			(xy 219.496613 -51.294472) (xy 219.453745 -51.330147) (xy 219.406139 -51.359201) (xy 219.35481 -51.381013)
			(xy 219.300853 -51.395119) (xy 219.245416 -51.401219) (xy 219.189682 -51.399182) (xy 219.134839 -51.389052)
			(xy 219.082055 -51.371045) (xy 219.032455 -51.345544) (xy 218.987097 -51.313093) (xy 218.946948 -51.274384)
			(xy 218.912862 -51.230241) (xy 218.885566 -51.181606) (xy 218.865643 -51.129515) (xy 218.853517 -51.075078)
			(xy 218.849446 -51.019456) (xy 202.621921 -51.019456) (xy 202.627312 -51.031766) (xy 202.63485 -51.039268)
			(xy 202.65389 -51.057413) (xy 202.687349 -51.09799) (xy 202.714912 -51.142783) (xy 202.736055 -51.19094)
			(xy 202.750375 -51.241546) (xy 202.757601 -51.293641) (xy 202.75804 -51.319938) (xy 202.75804 -51.320192)
			(xy 202.757515 -51.347442) (xy 202.74976 -51.401386) (xy 202.734408 -51.453678) (xy 202.71177 -51.503253)
			(xy 202.682307 -51.549102) (xy 202.64662 -51.590292) (xy 202.605434 -51.625983) (xy 202.559589 -51.655451)
			(xy 202.510016 -51.678094) (xy 202.457725 -51.693452) (xy 202.403782 -51.701212) (xy 202.376532 -51.7017)
			(xy 202.348868 -51.701163) (xy 202.29412 -51.693168) (xy 202.241099 -51.677356) (xy 202.190915 -51.654057)
			(xy 202.144619 -51.623759) (xy 202.10318 -51.587098) (xy 202.067466 -51.544839) (xy 202.052428 -51.521614)
			(xy 202.052174 -51.52136) (xy 202.045534 -51.511813) (xy 202.025821 -51.499518) (xy 202.014328 -51.497738)
			(xy 201.934318 -51.489864) (xy 201.922617 -51.489219) (xy 201.900645 -51.497283) (xy 201.892154 -51.505358)
			(xy 201.892154 -51.505612) (xy 201.87408 -51.5242) (xy 201.833746 -51.556777) (xy 201.78937 -51.583589)
			(xy 201.741771 -51.604141) (xy 201.691825 -51.618053) (xy 201.640455 -51.625069) (xy 201.614532 -51.6255)
			(xy 201.58728 -51.625015) (xy 201.533329 -51.617262) (xy 201.481031 -51.60191) (xy 201.431451 -51.57927)
			(xy 201.385597 -51.549805) (xy 201.344404 -51.514113) (xy 201.308709 -51.472922) (xy 201.279241 -51.427071)
			(xy 201.256599 -51.377491) (xy 201.241243 -51.325194) (xy 201.233487 -51.271244) (xy 201.233024 -51.243992)
			(xy 198.326422 -51.243992) (xy 198.326205 -51.254731) (xy 198.318452 -51.308673) (xy 198.303102 -51.360964)
			(xy 198.280466 -51.410538) (xy 198.251007 -51.456386) (xy 198.215322 -51.497575) (xy 198.174139 -51.533267)
			(xy 198.128296 -51.562735) (xy 198.078726 -51.585379) (xy 198.026438 -51.600738) (xy 197.972497 -51.6085)
			(xy 197.945248 -51.60899) (xy 197.926905 -51.608754) (xy 197.890392 -51.605193) (xy 197.87235 -51.601878)
			(xy 197.872096 -51.601878) (xy 197.861594 -51.600459) (xy 197.840991 -51.605329) (xy 197.832218 -51.611276)
			(xy 197.762876 -51.6636) (xy 197.752716 -51.682396) (xy 197.7517 -51.693318) (xy 197.748761 -51.72157)
			(xy 197.73573 -51.776852) (xy 197.714649 -51.829591) (xy 197.685982 -51.878623) (xy 197.650363 -51.922862)
			(xy 197.608579 -51.961333) (xy 197.561553 -51.993184) (xy 197.510326 -52.017712) (xy 197.456028 -52.034374)
			(xy 197.448819 -52.035456) (xy 221.041212 -52.035456) (xy 221.045283 -51.979834) (xy 221.057409 -51.925397)
			(xy 221.077332 -51.873306) (xy 221.104628 -51.824671) (xy 221.138714 -51.780528) (xy 221.178863 -51.741819)
			(xy 221.224221 -51.709368) (xy 221.273821 -51.683867) (xy 221.326605 -51.66586) (xy 221.381448 -51.65573)
			(xy 221.437182 -51.653693) (xy 221.442235 -51.654249) (xy 234.593902 -51.654249) (xy 234.593902 -51.599751)
			(xy 234.601658 -51.545807) (xy 234.617012 -51.493517) (xy 234.639651 -51.443943) (xy 234.669114 -51.398096)
			(xy 234.704803 -51.356909) (xy 234.74599 -51.321219) (xy 234.791836 -51.291755) (xy 234.841409 -51.269115)
			(xy 234.893699 -51.25376) (xy 234.947643 -51.246003) (xy 234.974892 -51.245516) (xy 234.975146 -51.245516)
			(xy 235.001442 -51.245939) (xy 235.053533 -51.253191) (xy 235.104135 -51.267524) (xy 235.152291 -51.288666)
			(xy 235.19709 -51.316217) (xy 235.237683 -51.349657) (xy 235.255816 -51.368706) (xy 235.263382 -51.376154)
			(xy 235.282804 -51.384675) (xy 235.293408 -51.385216) (xy 235.367576 -51.385216) (xy 235.378205 -51.38478)
			(xy 235.397669 -51.376249) (xy 235.405168 -51.368706) (xy 235.423304 -51.349658) (xy 235.463885 -51.316201)
			(xy 235.508679 -51.28864) (xy 235.556838 -51.267499) (xy 235.607445 -51.25318) (xy 235.659541 -51.245955)
			(xy 235.685838 -51.245516) (xy 235.686092 -51.245516) (xy 235.713347 -51.24593) (xy 235.767302 -51.253687)
			(xy 235.819604 -51.269043) (xy 235.869189 -51.291687) (xy 235.915046 -51.321156) (xy 235.956242 -51.356852)
			(xy 235.991939 -51.398048) (xy 236.021409 -51.443904) (xy 236.044054 -51.493488) (xy 236.059411 -51.54579)
			(xy 236.067169 -51.599745) (xy 236.067169 -51.654255) (xy 236.059411 -51.70821) (xy 236.044054 -51.760512)
			(xy 236.021409 -51.810096) (xy 235.991939 -51.855952) (xy 235.956242 -51.897148) (xy 235.915046 -51.932844)
			(xy 235.869189 -51.962313) (xy 235.819604 -51.984957) (xy 235.767302 -52.000313) (xy 235.713347 -52.00807)
			(xy 235.686092 -52.008532) (xy 235.685838 -52.008532) (xy 235.659544 -52.008038) (xy 235.607458 -52.000798)
			(xy 235.556858 -51.986478) (xy 235.508701 -51.96535) (xy 235.463901 -51.937811) (xy 235.423304 -51.904385)
			(xy 235.405168 -51.885342) (xy 235.397602 -51.877894) (xy 235.37818 -51.869371) (xy 235.367576 -51.868832)
			(xy 235.293408 -51.868832) (xy 235.282776 -51.869245) (xy 235.263311 -51.877791) (xy 235.255816 -51.885342)
			(xy 235.237677 -51.904388) (xy 235.197099 -51.937847) (xy 235.152305 -51.96541) (xy 235.104147 -51.986551)
			(xy 235.053539 -52.00087) (xy 235.001443 -52.008094) (xy 234.975146 -52.008532) (xy 234.974892 -52.008532)
			(xy 234.947643 -52.007997) (xy 234.893699 -52.00024) (xy 234.841409 -51.984885) (xy 234.791836 -51.962245)
			(xy 234.74599 -51.932781) (xy 234.704803 -51.897091) (xy 234.669114 -51.855904) (xy 234.639651 -51.810057)
			(xy 234.617012 -51.760483) (xy 234.601658 -51.708193) (xy 234.593902 -51.654249) (xy 221.442235 -51.654249)
			(xy 221.492619 -51.659793) (xy 221.546576 -51.673899) (xy 221.597905 -51.695711) (xy 221.645511 -51.724765)
			(xy 221.688379 -51.76044) (xy 221.725596 -51.801977) (xy 221.756369 -51.84849) (xy 221.780041 -51.898987)
			(xy 221.796109 -51.952394) (xy 221.804229 -52.00757) (xy 221.804738 -52.035456) (xy 221.804229 -52.063342)
			(xy 221.796109 -52.118518) (xy 221.780041 -52.171925) (xy 221.756369 -52.222422) (xy 221.725596 -52.268935)
			(xy 221.688379 -52.310472) (xy 221.645511 -52.346147) (xy 221.597905 -52.375201) (xy 221.546576 -52.397013)
			(xy 221.492619 -52.411119) (xy 221.437182 -52.417219) (xy 221.381448 -52.415182) (xy 221.326605 -52.405052)
			(xy 221.273821 -52.387045) (xy 221.224221 -52.361544) (xy 221.178863 -52.329093) (xy 221.138714 -52.290384)
			(xy 221.104628 -52.246241) (xy 221.077332 -52.197606) (xy 221.057409 -52.145515) (xy 221.045283 -52.091078)
			(xy 221.041212 -52.035456) (xy 197.448819 -52.035456) (xy 197.39986 -52.042804) (xy 197.371462 -52.04333)
			(xy 197.344092 -52.042845) (xy 197.289913 -52.035034) (xy 197.23741 -52.01955) (xy 197.187662 -51.996713)
			(xy 197.141696 -51.96699) (xy 197.120764 -51.94935) (xy 197.12051 -51.949096) (xy 197.113425 -51.943507)
			(xy 197.096507 -51.937262) (xy 197.08749 -51.936904) (xy 197.020434 -51.936904) (xy 197.011419 -51.937276)
			(xy 196.994501 -51.943513) (xy 196.987414 -51.949096) (xy 196.986906 -51.949604) (xy 196.965989 -51.967208)
			(xy 196.92005 -51.996844) (xy 196.87035 -52.019618) (xy 196.817907 -52.035064) (xy 196.763797 -52.042863)
			(xy 196.736462 -52.04333) (xy 196.709214 -52.042797) (xy 196.655274 -52.035037) (xy 196.602987 -52.019679)
			(xy 196.553417 -51.997037) (xy 196.507574 -51.967572) (xy 196.466391 -51.931882) (xy 196.430706 -51.890695)
			(xy 196.401245 -51.84485) (xy 196.378607 -51.795278) (xy 196.363255 -51.742989) (xy 196.3555 -51.689048)
			(xy 195.582277 -51.689048) (xy 195.597957 -51.695711) (xy 195.645563 -51.724765) (xy 195.688431 -51.76044)
			(xy 195.725648 -51.801977) (xy 195.756421 -51.84849) (xy 195.780093 -51.898987) (xy 195.796161 -51.952394)
			(xy 195.804281 -52.00757) (xy 195.80479 -52.035456) (xy 195.804281 -52.063342) (xy 195.796161 -52.118518)
			(xy 195.780093 -52.171925) (xy 195.756421 -52.222422) (xy 195.725648 -52.268935) (xy 195.688431 -52.310472)
			(xy 195.645563 -52.346147) (xy 195.597957 -52.375201) (xy 195.546628 -52.397013) (xy 195.492671 -52.411119)
			(xy 195.437234 -52.417219) (xy 195.3815 -52.415182) (xy 195.326657 -52.405052) (xy 195.273873 -52.387045)
			(xy 195.224273 -52.361544) (xy 195.178915 -52.329093) (xy 195.138766 -52.290384) (xy 195.10468 -52.246241)
			(xy 195.077384 -52.197606) (xy 195.057461 -52.145515) (xy 195.045335 -52.091078) (xy 195.041264 -52.035456)
			(xy 171.448939 -52.035456) (xy 171.399915 -52.042807) (xy 171.371514 -52.04333) (xy 171.344143 -52.042873)
			(xy 171.289963 -52.035055) (xy 171.237459 -52.019565) (xy 171.187712 -51.996721) (xy 171.141747 -51.966993)
			(xy 171.120816 -51.94935) (xy 171.120562 -51.949096) (xy 171.113462 -51.943529) (xy 171.096556 -51.937271)
			(xy 171.087542 -51.936904) (xy 171.020486 -51.936904) (xy 171.011468 -51.937254) (xy 170.994551 -51.943506)
			(xy 170.987466 -51.949096) (xy 170.986958 -51.949604) (xy 170.966022 -51.967183) (xy 170.920088 -51.996824)
			(xy 170.870392 -52.019602) (xy 170.817954 -52.035053) (xy 170.763848 -52.04286) (xy 170.736514 -52.04333)
			(xy 170.709262 -52.042824) (xy 170.655313 -52.035069) (xy 170.603016 -52.019715) (xy 170.553437 -51.997074)
			(xy 170.507585 -51.967609) (xy 170.466393 -51.931917) (xy 170.4307 -51.890726) (xy 170.401232 -51.844875)
			(xy 170.37859 -51.795297) (xy 170.363234 -51.743001) (xy 170.355477 -51.689052) (xy 169.582339 -51.689052)
			(xy 169.598009 -51.695711) (xy 169.645615 -51.724765) (xy 169.688483 -51.76044) (xy 169.7257 -51.801977)
			(xy 169.756473 -51.84849) (xy 169.780145 -51.898987) (xy 169.796213 -51.952394) (xy 169.804333 -52.00757)
			(xy 169.804842 -52.035456) (xy 169.804333 -52.063342) (xy 169.796213 -52.118518) (xy 169.780145 -52.171925)
			(xy 169.756473 -52.222422) (xy 169.7257 -52.268935) (xy 169.688483 -52.310472) (xy 169.645615 -52.346147)
			(xy 169.598009 -52.375201) (xy 169.54668 -52.397013) (xy 169.492723 -52.411119) (xy 169.437286 -52.417219)
			(xy 169.381552 -52.415182) (xy 169.326709 -52.405052) (xy 169.273925 -52.387045) (xy 169.224325 -52.361544)
			(xy 169.178967 -52.329093) (xy 169.138818 -52.290384) (xy 169.104732 -52.246241) (xy 169.077436 -52.197606)
			(xy 169.057513 -52.145515) (xy 169.045387 -52.091078) (xy 169.041316 -52.035456) (xy 145.448922 -52.035456)
			(xy 145.399964 -52.042803) (xy 145.371566 -52.04333) (xy 145.344194 -52.042901) (xy 145.290013 -52.035077)
			(xy 145.237509 -52.01958) (xy 145.187762 -51.99673) (xy 145.141798 -51.966996) (xy 145.120868 -51.94935)
			(xy 145.120614 -51.949096) (xy 145.113528 -51.943509) (xy 145.096611 -51.937263) (xy 145.087594 -51.936904)
			(xy 145.020538 -51.936904) (xy 145.011523 -51.937279) (xy 144.994606 -51.943514) (xy 144.987518 -51.949096)
			(xy 144.98701 -51.949604) (xy 144.966092 -51.967206) (xy 144.920153 -51.996843) (xy 144.870453 -52.019617)
			(xy 144.818011 -52.035063) (xy 144.763901 -52.042863) (xy 144.736566 -52.04333) (xy 144.709318 -52.042797)
			(xy 144.655377 -52.035037) (xy 144.603089 -52.01968) (xy 144.553519 -51.997039) (xy 144.507676 -51.967573)
			(xy 144.466492 -51.931884) (xy 144.430807 -51.890697) (xy 144.401345 -51.844851) (xy 144.378708 -51.795279)
			(xy 144.363355 -51.74299) (xy 144.3556 -51.689048) (xy 143.582381 -51.689048) (xy 143.598061 -51.695711)
			(xy 143.645667 -51.724765) (xy 143.688535 -51.76044) (xy 143.725752 -51.801977) (xy 143.756525 -51.84849)
			(xy 143.780197 -51.898987) (xy 143.796265 -51.952394) (xy 143.804385 -52.00757) (xy 143.804894 -52.035456)
			(xy 143.804385 -52.063342) (xy 143.796265 -52.118518) (xy 143.780197 -52.171925) (xy 143.756525 -52.222422)
			(xy 143.725752 -52.268935) (xy 143.688535 -52.310472) (xy 143.645667 -52.346147) (xy 143.598061 -52.375201)
			(xy 143.546732 -52.397013) (xy 143.492775 -52.411119) (xy 143.437338 -52.417219) (xy 143.381604 -52.415182)
			(xy 143.326761 -52.405052) (xy 143.273977 -52.387045) (xy 143.224377 -52.361544) (xy 143.179019 -52.329093)
			(xy 143.13887 -52.290384) (xy 143.104784 -52.246241) (xy 143.077488 -52.197606) (xy 143.057565 -52.145515)
			(xy 143.045439 -52.091078) (xy 143.041368 -52.035456) (xy 119.449036 -52.035456) (xy 119.400018 -52.042807)
			(xy 119.371618 -52.04333) (xy 119.344247 -52.04287) (xy 119.290067 -52.035054) (xy 119.237563 -52.019564)
			(xy 119.187817 -51.99672) (xy 119.141851 -51.966993) (xy 119.12092 -51.94935) (xy 119.120666 -51.949096)
			(xy 119.113565 -51.94353) (xy 119.096659 -51.937271) (xy 119.087646 -51.936904) (xy 119.02059 -51.936904)
			(xy 119.011573 -51.937255) (xy 118.994656 -51.943507) (xy 118.98757 -51.949096) (xy 118.987062 -51.949604)
			(xy 118.966124 -51.967181) (xy 118.920191 -51.996822) (xy 118.870496 -52.019601) (xy 118.818058 -52.035052)
			(xy 118.763951 -52.042859) (xy 118.736618 -52.04333) (xy 118.709366 -52.042824) (xy 118.655416 -52.03507)
			(xy 118.603119 -52.019716) (xy 118.55354 -51.997076) (xy 118.507687 -51.96761) (xy 118.466494 -51.931918)
			(xy 118.430801 -51.890728) (xy 118.401333 -51.844876) (xy 118.37869 -51.795298) (xy 118.363334 -51.743001)
			(xy 118.355577 -51.689052) (xy 105.482137 -51.689052) (xy 105.497807 -51.695711) (xy 105.545413 -51.724765)
			(xy 105.588281 -51.76044) (xy 105.625498 -51.801977) (xy 105.656271 -51.84849) (xy 105.679943 -51.898987)
			(xy 105.696011 -51.952394) (xy 105.704131 -52.00757) (xy 105.70464 -52.035456) (xy 105.704131 -52.063342)
			(xy 105.696011 -52.118518) (xy 105.679943 -52.171925) (xy 105.656271 -52.222422) (xy 105.625498 -52.268935)
			(xy 105.588281 -52.310472) (xy 105.545413 -52.346147) (xy 105.497807 -52.375201) (xy 105.446478 -52.397013)
			(xy 105.392521 -52.411119) (xy 105.337084 -52.417219) (xy 105.28135 -52.415182) (xy 105.226507 -52.405052)
			(xy 105.173723 -52.387045) (xy 105.124123 -52.361544) (xy 105.078765 -52.329093) (xy 105.038616 -52.290384)
			(xy 105.00453 -52.246241) (xy 104.977234 -52.197606) (xy 104.957311 -52.145515) (xy 104.945185 -52.091078)
			(xy 104.941114 -52.035456) (xy 81.34872 -52.035456) (xy 81.299762 -52.042803) (xy 81.271364 -52.04333)
			(xy 81.243992 -52.042902) (xy 81.189811 -52.035078) (xy 81.137307 -52.019581) (xy 81.08756 -51.99673)
			(xy 81.041596 -51.966996) (xy 81.020666 -51.94935) (xy 81.020412 -51.949096) (xy 81.013327 -51.943508)
			(xy 80.996409 -51.937262) (xy 80.987392 -51.936904) (xy 80.920336 -51.936904) (xy 80.911321 -51.937277)
			(xy 80.894404 -51.943513) (xy 80.887316 -51.949096) (xy 80.886808 -51.949604) (xy 80.865891 -51.967207)
			(xy 80.819951 -51.996843) (xy 80.770251 -52.019618) (xy 80.717809 -52.035063) (xy 80.663699 -52.042863)
			(xy 80.636364 -52.04333) (xy 80.609116 -52.042797) (xy 80.555175 -52.035037) (xy 80.502888 -52.01968)
			(xy 80.453318 -51.997038) (xy 80.407475 -51.967572) (xy 80.366292 -51.931883) (xy 80.330606 -51.890696)
			(xy 80.301145 -51.84485) (xy 80.278508 -51.795278) (xy 80.263155 -51.742989) (xy 80.2554 -51.689048)
			(xy 79.482179 -51.689048) (xy 79.497859 -51.695711) (xy 79.545465 -51.724765) (xy 79.588333 -51.76044)
			(xy 79.62555 -51.801977) (xy 79.656323 -51.84849) (xy 79.679995 -51.898987) (xy 79.696063 -51.952394)
			(xy 79.704183 -52.00757) (xy 79.704692 -52.035456) (xy 79.704183 -52.063342) (xy 79.696063 -52.118518)
			(xy 79.679995 -52.171925) (xy 79.656323 -52.222422) (xy 79.62555 -52.268935) (xy 79.588333 -52.310472)
			(xy 79.545465 -52.346147) (xy 79.497859 -52.375201) (xy 79.44653 -52.397013) (xy 79.392573 -52.411119)
			(xy 79.337136 -52.417219) (xy 79.281402 -52.415182) (xy 79.226559 -52.405052) (xy 79.173775 -52.387045)
			(xy 79.124175 -52.361544) (xy 79.078817 -52.329093) (xy 79.038668 -52.290384) (xy 79.004582 -52.246241)
			(xy 78.977286 -52.197606) (xy 78.957363 -52.145515) (xy 78.945237 -52.091078) (xy 78.941166 -52.035456)
			(xy 55.348834 -52.035456) (xy 55.299816 -52.042807) (xy 55.271416 -52.04333) (xy 55.244045 -52.042872)
			(xy 55.189865 -52.035055) (xy 55.137361 -52.019565) (xy 55.087615 -51.996721) (xy 55.041649 -51.966993)
			(xy 55.020718 -51.94935) (xy 55.020464 -51.949096) (xy 55.013364 -51.94353) (xy 54.996457 -51.937271)
			(xy 54.987444 -51.936904) (xy 54.920388 -51.936904) (xy 54.91137 -51.937254) (xy 54.894454 -51.943506)
			(xy 54.887368 -51.949096) (xy 54.88686 -51.949604) (xy 54.865923 -51.967182) (xy 54.819989 -51.996823)
			(xy 54.770294 -52.019602) (xy 54.717856 -52.035053) (xy 54.663749 -52.04286) (xy 54.636416 -52.04333)
			(xy 54.609164 -52.042824) (xy 54.555214 -52.035069) (xy 54.502918 -52.019715) (xy 54.453338 -51.997075)
			(xy 54.407486 -51.967609) (xy 54.366294 -51.931918) (xy 54.3306 -51.890727) (xy 54.301133 -51.844876)
			(xy 54.27849 -51.795297) (xy 54.263134 -51.743001) (xy 54.255377 -51.689052) (xy 53.482241 -51.689052)
			(xy 53.497911 -51.695711) (xy 53.545517 -51.724765) (xy 53.588385 -51.76044) (xy 53.625602 -51.801977)
			(xy 53.656375 -51.84849) (xy 53.680047 -51.898987) (xy 53.696115 -51.952394) (xy 53.704235 -52.00757)
			(xy 53.704744 -52.035456) (xy 53.704235 -52.063342) (xy 53.696115 -52.118518) (xy 53.680047 -52.171925)
			(xy 53.656375 -52.222422) (xy 53.625602 -52.268935) (xy 53.588385 -52.310472) (xy 53.545517 -52.346147)
			(xy 53.497911 -52.375201) (xy 53.446582 -52.397013) (xy 53.392625 -52.411119) (xy 53.337188 -52.417219)
			(xy 53.281454 -52.415182) (xy 53.226611 -52.405052) (xy 53.173827 -52.387045) (xy 53.124227 -52.361544)
			(xy 53.078869 -52.329093) (xy 53.03872 -52.290384) (xy 53.004634 -52.246241) (xy 52.977338 -52.197606)
			(xy 52.957415 -52.145515) (xy 52.945289 -52.091078) (xy 52.941218 -52.035456) (xy 29.348817 -52.035456)
			(xy 29.299866 -52.042803) (xy 29.271468 -52.04333) (xy 29.244096 -52.0429) (xy 29.189915 -52.035076)
			(xy 29.137411 -52.019579) (xy 29.087664 -51.996729) (xy 29.0417 -51.966996) (xy 29.02077 -51.94935)
			(xy 29.020516 -51.949096) (xy 29.013429 -51.94351) (xy 28.996513 -51.937263) (xy 28.987496 -51.936904)
			(xy 28.92044 -51.936904) (xy 28.911425 -51.93728) (xy 28.894508 -51.943514) (xy 28.88742 -51.949096)
			(xy 28.886912 -51.949604) (xy 28.865993 -51.967205) (xy 28.820054 -51.996842) (xy 28.770355 -52.019617)
			(xy 28.717913 -52.035062) (xy 28.663803 -52.042863) (xy 28.636468 -52.04333) (xy 28.60922 -52.042798)
			(xy 28.555279 -52.035038) (xy 28.502991 -52.019681) (xy 28.453421 -51.997039) (xy 28.407577 -51.967574)
			(xy 28.366393 -51.931884) (xy 28.330707 -51.890697) (xy 28.301245 -51.844851) (xy 28.278608 -51.795279)
			(xy 28.263255 -51.74299) (xy 28.2555 -51.689048) (xy 27.482283 -51.689048) (xy 27.497963 -51.695711)
			(xy 27.545569 -51.724765) (xy 27.588437 -51.76044) (xy 27.625654 -51.801977) (xy 27.656427 -51.84849)
			(xy 27.680099 -51.898987) (xy 27.696167 -51.952394) (xy 27.704287 -52.00757) (xy 27.704796 -52.035456)
			(xy 27.704287 -52.063342) (xy 27.696167 -52.118518) (xy 27.680099 -52.171925) (xy 27.656427 -52.222422)
			(xy 27.625654 -52.268935) (xy 27.588437 -52.310472) (xy 27.545569 -52.346147) (xy 27.497963 -52.375201)
			(xy 27.446634 -52.397013) (xy 27.392677 -52.411119) (xy 27.33724 -52.417219) (xy 27.281506 -52.415182)
			(xy 27.226663 -52.405052) (xy 27.173879 -52.387045) (xy 27.124279 -52.361544) (xy 27.078921 -52.329093)
			(xy 27.038772 -52.290384) (xy 27.004686 -52.246241) (xy 26.97739 -52.197606) (xy 26.957467 -52.145515)
			(xy 26.945341 -52.091078) (xy 26.94127 -52.035456) (xy 20.380452 -52.035456) (xy 20.380452 -52.51704)
			(xy 20.84019 -52.51704) (xy 20.844261 -52.461418) (xy 20.856387 -52.406981) (xy 20.87631 -52.35489)
			(xy 20.903606 -52.306255) (xy 20.937692 -52.262112) (xy 20.977841 -52.223403) (xy 21.023199 -52.190952)
			(xy 21.072799 -52.165451) (xy 21.125583 -52.147444) (xy 21.180426 -52.137314) (xy 21.23616 -52.135277)
			(xy 21.291597 -52.141377) (xy 21.345554 -52.155483) (xy 21.396883 -52.177295) (xy 21.444489 -52.206349)
			(xy 21.487357 -52.242024) (xy 21.524574 -52.283561) (xy 21.555347 -52.330074) (xy 21.579019 -52.380571)
			(xy 21.595087 -52.433978) (xy 21.603207 -52.489154) (xy 21.603716 -52.51704) (xy 21.603207 -52.544926)
			(xy 21.596957 -52.587398) (xy 24.755346 -52.587398) (xy 24.759417 -52.531776) (xy 24.771543 -52.477339)
			(xy 24.791466 -52.425248) (xy 24.818762 -52.376613) (xy 24.852848 -52.33247) (xy 24.892997 -52.293761)
			(xy 24.938355 -52.26131) (xy 24.987955 -52.235809) (xy 25.040739 -52.217802) (xy 25.095582 -52.207672)
			(xy 25.151316 -52.205635) (xy 25.206753 -52.211735) (xy 25.26071 -52.225841) (xy 25.312039 -52.247653)
			(xy 25.359645 -52.276707) (xy 25.402513 -52.312382) (xy 25.43973 -52.353919) (xy 25.470503 -52.400432)
			(xy 25.494175 -52.450929) (xy 25.510243 -52.504336) (xy 25.518363 -52.559512) (xy 25.518448 -52.564157)
			(xy 29.827107 -52.564157) (xy 29.827107 -52.509643) (xy 29.834865 -52.455683) (xy 29.850224 -52.403377)
			(xy 29.872871 -52.353789) (xy 29.902345 -52.30793) (xy 29.938045 -52.266731) (xy 29.979246 -52.231033)
			(xy 30.025107 -52.201562) (xy 30.074696 -52.178917) (xy 30.127003 -52.163561) (xy 30.180963 -52.155806)
			(xy 30.20822 -52.155344) (xy 30.235591 -52.155788) (xy 30.289772 -52.163609) (xy 30.342275 -52.179103)
			(xy 30.392022 -52.20195) (xy 30.437987 -52.23168) (xy 30.458918 -52.249324) (xy 30.459172 -52.249578)
			(xy 30.466256 -52.255168) (xy 30.483175 -52.261411) (xy 30.492192 -52.26177) (xy 30.559248 -52.26177)
			(xy 30.568263 -52.261395) (xy 30.585181 -52.25516) (xy 30.592268 -52.249578) (xy 30.592776 -52.24907)
			(xy 30.613696 -52.231471) (xy 30.659635 -52.201834) (xy 30.709334 -52.17906) (xy 30.761776 -52.163614)
			(xy 30.815885 -52.155812) (xy 30.84322 -52.155344) (xy 30.870467 -52.155928) (xy 30.924406 -52.163685)
			(xy 30.976691 -52.17904) (xy 31.02626 -52.20168) (xy 31.072102 -52.231143) (xy 31.113284 -52.26683)
			(xy 31.148969 -52.308014) (xy 31.17843 -52.353858) (xy 31.201067 -52.403427) (xy 31.216419 -52.455714)
			(xy 31.224174 -52.509653) (xy 31.224174 -52.555949) (xy 32.583902 -52.555949) (xy 32.583902 -52.501451)
			(xy 32.591658 -52.447509) (xy 32.607011 -52.395219) (xy 32.629649 -52.345646) (xy 32.659112 -52.299799)
			(xy 32.694799 -52.258612) (xy 32.735985 -52.222923) (xy 32.78183 -52.193458) (xy 32.831402 -52.170817)
			(xy 32.883691 -52.155462) (xy 32.937633 -52.147703) (xy 32.964882 -52.147216) (xy 32.992252 -52.147689)
			(xy 33.046431 -52.155504) (xy 33.098934 -52.170992) (xy 33.148681 -52.193832) (xy 33.194648 -52.223555)
			(xy 33.21558 -52.241196) (xy 33.215834 -52.24145) (xy 33.222931 -52.247021) (xy 33.23984 -52.253276)
			(xy 33.248854 -52.253642) (xy 33.31591 -52.253642) (xy 33.324929 -52.253302) (xy 33.341846 -52.247044)
			(xy 33.34893 -52.24145) (xy 33.349438 -52.240942) (xy 33.370382 -52.223372) (xy 33.416313 -52.193729)
			(xy 33.466006 -52.170947) (xy 33.518443 -52.155494) (xy 33.572549 -52.147687) (xy 33.599882 -52.147216)
			(xy 33.627137 -52.14763) (xy 33.681094 -52.155385) (xy 33.733397 -52.170741) (xy 33.782983 -52.193383)
			(xy 33.828841 -52.222853) (xy 33.870038 -52.258549) (xy 33.905736 -52.299745) (xy 33.935208 -52.345601)
			(xy 33.957853 -52.395186) (xy 33.973211 -52.447489) (xy 33.980969 -52.501445) (xy 33.980969 -52.555955)
			(xy 33.973211 -52.609911) (xy 33.957853 -52.662214) (xy 33.935208 -52.711799) (xy 33.905736 -52.757655)
			(xy 33.870038 -52.798851) (xy 33.828841 -52.834547) (xy 33.782983 -52.864017) (xy 33.733397 -52.886659)
			(xy 33.681094 -52.902015) (xy 33.627137 -52.90977) (xy 33.599882 -52.910232) (xy 33.572511 -52.909793)
			(xy 33.51833 -52.901971) (xy 33.465826 -52.886477) (xy 33.416079 -52.863629) (xy 33.370114 -52.833897)
			(xy 33.349184 -52.816252) (xy 33.34893 -52.815998) (xy 33.341839 -52.810418) (xy 33.324926 -52.804167)
			(xy 33.31591 -52.803806) (xy 33.248854 -52.803806) (xy 33.23984 -52.804188) (xy 33.222922 -52.810418)
			(xy 33.215834 -52.815998) (xy 33.215326 -52.816506) (xy 33.194402 -52.834101) (xy 33.148464 -52.863738)
			(xy 33.098766 -52.886514) (xy 33.046325 -52.901962) (xy 32.992216 -52.909764) (xy 32.964882 -52.910232)
			(xy 32.937633 -52.909697) (xy 32.883691 -52.901938) (xy 32.831402 -52.886583) (xy 32.78183 -52.863942)
			(xy 32.735985 -52.834477) (xy 32.694799 -52.798788) (xy 32.659112 -52.757601) (xy 32.629649 -52.711754)
			(xy 32.607011 -52.662181) (xy 32.591658 -52.609891) (xy 32.583902 -52.555949) (xy 31.224174 -52.555949)
			(xy 31.224174 -52.564147) (xy 31.216419 -52.618086) (xy 31.201067 -52.670373) (xy 31.17843 -52.719942)
			(xy 31.148969 -52.765786) (xy 31.113284 -52.80697) (xy 31.072102 -52.842657) (xy 31.02626 -52.87212)
			(xy 30.976691 -52.89476) (xy 30.924406 -52.910115) (xy 30.870467 -52.917872) (xy 30.84322 -52.91836)
			(xy 30.81585 -52.917892) (xy 30.76167 -52.910076) (xy 30.709167 -52.894588) (xy 30.65942 -52.871746)
			(xy 30.613453 -52.842022) (xy 30.592522 -52.82438) (xy 30.592268 -52.824126) (xy 30.585172 -52.818553)
			(xy 30.568262 -52.8123) (xy 30.559248 -52.811934) (xy 30.492192 -52.811934) (xy 30.483174 -52.81228)
			(xy 30.466256 -52.818534) (xy 30.459172 -52.824126) (xy 30.458664 -52.824634) (xy 30.437729 -52.842215)
			(xy 30.391794 -52.871854) (xy 30.342099 -52.894632) (xy 30.28966 -52.910083) (xy 30.235554 -52.917889)
			(xy 30.20822 -52.91836) (xy 30.180963 -52.917994) (xy 30.127003 -52.910239) (xy 30.074696 -52.894883)
			(xy 30.025107 -52.872238) (xy 29.979246 -52.842767) (xy 29.938045 -52.807069) (xy 29.902345 -52.76587)
			(xy 29.872871 -52.720011) (xy 29.850224 -52.670423) (xy 29.834865 -52.618117) (xy 29.827107 -52.564157)
			(xy 25.518448 -52.564157) (xy 25.518872 -52.587398) (xy 25.518363 -52.615284) (xy 25.510243 -52.67046)
			(xy 25.494175 -52.723867) (xy 25.470503 -52.774364) (xy 25.43973 -52.820877) (xy 25.402513 -52.862414)
			(xy 25.359645 -52.898089) (xy 25.312039 -52.927143) (xy 25.26071 -52.948955) (xy 25.206753 -52.963061)
			(xy 25.151316 -52.969161) (xy 25.095582 -52.967124) (xy 25.040739 -52.956994) (xy 24.987955 -52.938987)
			(xy 24.938355 -52.913486) (xy 24.892997 -52.881035) (xy 24.852848 -52.842326) (xy 24.818762 -52.798183)
			(xy 24.791466 -52.749548) (xy 24.771543 -52.697457) (xy 24.759417 -52.64302) (xy 24.755346 -52.587398)
			(xy 21.596957 -52.587398) (xy 21.595087 -52.600102) (xy 21.579019 -52.653509) (xy 21.555347 -52.704006)
			(xy 21.524574 -52.750519) (xy 21.487357 -52.792056) (xy 21.444489 -52.827731) (xy 21.396883 -52.856785)
			(xy 21.345554 -52.878597) (xy 21.291597 -52.892703) (xy 21.23616 -52.898803) (xy 21.180426 -52.896766)
			(xy 21.125583 -52.886636) (xy 21.072799 -52.868629) (xy 21.023199 -52.843128) (xy 20.977841 -52.810677)
			(xy 20.937692 -52.771968) (xy 20.903606 -52.727825) (xy 20.87631 -52.67919) (xy 20.856387 -52.627099)
			(xy 20.844261 -52.572662) (xy 20.84019 -52.51704) (xy 20.380452 -52.51704) (xy 20.380452 -53.051456)
			(xy 26.94127 -53.051456) (xy 26.945341 -52.995834) (xy 26.957467 -52.941397) (xy 26.97739 -52.889306)
			(xy 27.004686 -52.840671) (xy 27.038772 -52.796528) (xy 27.078921 -52.757819) (xy 27.124279 -52.725368)
			(xy 27.173879 -52.699867) (xy 27.226663 -52.68186) (xy 27.281506 -52.67173) (xy 27.33724 -52.669693)
			(xy 27.392677 -52.675793) (xy 27.446634 -52.689899) (xy 27.497963 -52.711711) (xy 27.545569 -52.740765)
			(xy 27.588437 -52.77644) (xy 27.625654 -52.817977) (xy 27.656427 -52.86449) (xy 27.680099 -52.914987)
			(xy 27.696167 -52.968394) (xy 27.704287 -53.02357) (xy 27.704796 -53.051456) (xy 27.704287 -53.079342)
			(xy 27.696167 -53.134518) (xy 27.680099 -53.187925) (xy 27.656427 -53.238422) (xy 27.625654 -53.284935)
			(xy 27.588437 -53.326472) (xy 27.545569 -53.362147) (xy 27.497963 -53.391201) (xy 27.446634 -53.413013)
			(xy 27.392677 -53.427119) (xy 27.33724 -53.433219) (xy 27.281506 -53.431182) (xy 27.226663 -53.421052)
			(xy 27.173879 -53.403045) (xy 27.124279 -53.377544) (xy 27.078921 -53.345093) (xy 27.038772 -53.306384)
			(xy 27.004686 -53.262241) (xy 26.97739 -53.213606) (xy 26.957467 -53.161515) (xy 26.945341 -53.107078)
			(xy 26.94127 -53.051456) (xy 20.380452 -53.051456) (xy 20.380452 -53.496556) (xy 32.133441 -53.496556)
			(xy 32.133441 -53.442044) (xy 32.141199 -53.388088) (xy 32.156558 -53.335785) (xy 32.179204 -53.2862)
			(xy 32.208677 -53.240343) (xy 32.244376 -53.199148) (xy 32.285575 -53.163453) (xy 32.331435 -53.133985)
			(xy 32.381022 -53.111344) (xy 32.433327 -53.095991) (xy 32.487284 -53.088238) (xy 32.51454 -53.087778)
			(xy 32.54191 -53.08826) (xy 32.596089 -53.096071) (xy 32.648593 -53.111555) (xy 32.69834 -53.134394)
			(xy 32.744307 -53.164117) (xy 32.765238 -53.181758) (xy 32.765492 -53.182012) (xy 32.772576 -53.187603)
			(xy 32.789495 -53.193847) (xy 32.798512 -53.194204) (xy 32.865568 -53.194204) (xy 32.874583 -53.193831)
			(xy 32.8915 -53.187594) (xy 32.898588 -53.182012) (xy 32.899096 -53.181504) (xy 32.920013 -53.163901)
			(xy 32.965952 -53.134264) (xy 33.015652 -53.111489) (xy 33.068095 -53.096044) (xy 33.122205 -53.088245)
			(xy 33.14954 -53.087778) (xy 33.176788 -53.088295) (xy 33.23073 -53.096056) (xy 33.283018 -53.111414)
			(xy 33.332588 -53.134056) (xy 33.378432 -53.163523) (xy 33.419616 -53.199213) (xy 33.455301 -53.2404)
			(xy 33.484763 -53.286247) (xy 33.5074 -53.33582) (xy 33.522753 -53.388109) (xy 33.530508 -53.442052)
			(xy 33.530508 -53.496548) (xy 33.522753 -53.550491) (xy 33.5074 -53.60278) (xy 33.484763 -53.652353)
			(xy 33.455301 -53.6982) (xy 33.419616 -53.739387) (xy 33.378432 -53.775077) (xy 33.332588 -53.804544)
			(xy 33.283018 -53.827186) (xy 33.23073 -53.842544) (xy 33.176788 -53.850305) (xy 33.14954 -53.850794)
			(xy 33.122171 -53.850306) (xy 33.067992 -53.842494) (xy 33.015489 -53.82701) (xy 32.965742 -53.804173)
			(xy 32.919774 -53.774453) (xy 32.898842 -53.756814) (xy 32.898588 -53.75656) (xy 32.891513 -53.750957)
			(xy 32.874587 -53.744721) (xy 32.865568 -53.744368) (xy 32.798512 -53.744368) (xy 32.789497 -53.744738)
			(xy 32.77258 -53.750977) (xy 32.765492 -53.75656) (xy 32.764984 -53.757068) (xy 32.744071 -53.774676)
			(xy 32.698131 -53.804313) (xy 32.64843 -53.827087) (xy 32.595987 -53.842531) (xy 32.541875 -53.850329)
			(xy 32.51454 -53.850794) (xy 32.487284 -53.850362) (xy 32.433327 -53.842609) (xy 32.381022 -53.827256)
			(xy 32.331435 -53.804615) (xy 32.285575 -53.775147) (xy 32.244376 -53.739452) (xy 32.208677 -53.698257)
			(xy 32.179204 -53.6524) (xy 32.156558 -53.602815) (xy 32.141199 -53.550512) (xy 32.133441 -53.496556)
			(xy 20.380452 -53.496556) (xy 20.380452 -53.653436) (xy 20.380858 -53.662953) (xy 20.387788 -53.680683)
			(xy 20.393914 -53.68798) (xy 20.394168 -53.688234) (xy 20.44192 -53.73878) (xy 20.448524 -53.745892)
			(xy 20.46605 -53.754274) (xy 20.475956 -53.754782) (xy 20.504673 -53.757078) (xy 20.560986 -53.769223)
			(xy 20.614833 -53.789696) (xy 20.66499 -53.818032) (xy 20.710318 -53.853587) (xy 20.749784 -53.895551)
			(xy 20.782494 -53.942972) (xy 20.792518 -53.96357) (xy 24.77211 -53.96357) (xy 24.776181 -53.907948)
			(xy 24.788307 -53.853511) (xy 24.80823 -53.80142) (xy 24.835526 -53.752785) (xy 24.869612 -53.708642)
			(xy 24.909761 -53.669933) (xy 24.955119 -53.637482) (xy 25.004719 -53.611981) (xy 25.057503 -53.593974)
			(xy 25.112346 -53.583844) (xy 25.16808 -53.581807) (xy 25.223517 -53.587907) (xy 25.277474 -53.602013)
			(xy 25.328803 -53.623825) (xy 25.376409 -53.652879) (xy 25.419277 -53.688554) (xy 25.456494 -53.730091)
			(xy 25.487267 -53.776604) (xy 25.510939 -53.827101) (xy 25.527007 -53.880508) (xy 25.535127 -53.935684)
			(xy 25.535636 -53.96357) (xy 25.535127 -53.991456) (xy 25.527007 -54.046632) (xy 25.520742 -54.067456)
			(xy 26.94127 -54.067456) (xy 26.945341 -54.011834) (xy 26.957467 -53.957397) (xy 26.97739 -53.905306)
			(xy 27.004686 -53.856671) (xy 27.038772 -53.812528) (xy 27.078921 -53.773819) (xy 27.124279 -53.741368)
			(xy 27.173879 -53.715867) (xy 27.226663 -53.69786) (xy 27.281506 -53.68773) (xy 27.33724 -53.685693)
			(xy 27.392677 -53.691793) (xy 27.446634 -53.705899) (xy 27.497963 -53.727711) (xy 27.545569 -53.756765)
			(xy 27.588437 -53.79244) (xy 27.625654 -53.833977) (xy 27.656427 -53.88049) (xy 27.680099 -53.930987)
			(xy 27.696167 -53.984394) (xy 27.704287 -54.03957) (xy 27.704796 -54.067456) (xy 27.704287 -54.095342)
			(xy 27.696167 -54.150518) (xy 27.680099 -54.203925) (xy 27.663701 -54.238906) (xy 34.38601 -54.238906)
			(xy 34.390081 -54.183284) (xy 34.402207 -54.128847) (xy 34.42213 -54.076756) (xy 34.449426 -54.028121)
			(xy 34.483512 -53.983978) (xy 34.523661 -53.945269) (xy 34.569019 -53.912818) (xy 34.618619 -53.887317)
			(xy 34.671403 -53.86931) (xy 34.726246 -53.85918) (xy 34.78198 -53.857143) (xy 34.837417 -53.863243)
			(xy 34.891374 -53.877349) (xy 34.942703 -53.899161) (xy 34.990309 -53.928215) (xy 35.033177 -53.96389)
			(xy 35.070394 -54.005427) (xy 35.101167 -54.05194) (xy 35.124839 -54.102437) (xy 35.140907 -54.155844)
			(xy 35.149027 -54.21102) (xy 35.149536 -54.238906) (xy 35.149027 -54.266792) (xy 35.140907 -54.321968)
			(xy 35.124839 -54.375375) (xy 35.101167 -54.425872) (xy 35.070394 -54.472385) (xy 35.033177 -54.513922)
			(xy 34.990309 -54.549597) (xy 34.942703 -54.578651) (xy 34.891374 -54.600463) (xy 34.837417 -54.614569)
			(xy 34.78198 -54.620669) (xy 34.726246 -54.618632) (xy 34.671403 -54.608502) (xy 34.618619 -54.590495)
			(xy 34.569019 -54.564994) (xy 34.523661 -54.532543) (xy 34.483512 -54.493834) (xy 34.449426 -54.449691)
			(xy 34.42213 -54.401056) (xy 34.402207 -54.348965) (xy 34.390081 -54.294528) (xy 34.38601 -54.238906)
			(xy 27.663701 -54.238906) (xy 27.656427 -54.254422) (xy 27.625654 -54.300935) (xy 27.588437 -54.342472)
			(xy 27.545569 -54.378147) (xy 27.497963 -54.407201) (xy 27.446634 -54.429013) (xy 27.392677 -54.443119)
			(xy 27.33724 -54.449219) (xy 27.281506 -54.447182) (xy 27.226663 -54.437052) (xy 27.173879 -54.419045)
			(xy 27.124279 -54.393544) (xy 27.078921 -54.361093) (xy 27.038772 -54.322384) (xy 27.004686 -54.278241)
			(xy 26.97739 -54.229606) (xy 26.957467 -54.177515) (xy 26.945341 -54.123078) (xy 26.94127 -54.067456)
			(xy 25.520742 -54.067456) (xy 25.510939 -54.100039) (xy 25.487267 -54.150536) (xy 25.456494 -54.197049)
			(xy 25.419277 -54.238586) (xy 25.376409 -54.274261) (xy 25.328803 -54.303315) (xy 25.277474 -54.325127)
			(xy 25.223517 -54.339233) (xy 25.16808 -54.345333) (xy 25.112346 -54.343296) (xy 25.057503 -54.333166)
			(xy 25.004719 -54.315159) (xy 24.955119 -54.289658) (xy 24.909761 -54.257207) (xy 24.869612 -54.218498)
			(xy 24.835526 -54.174355) (xy 24.80823 -54.12572) (xy 24.788307 -54.073629) (xy 24.776181 -54.019192)
			(xy 24.77211 -53.96357) (xy 20.792518 -53.96357) (xy 20.807702 -53.994772) (xy 20.824837 -54.049773)
			(xy 20.833509 -54.106724) (xy 20.834096 -54.135528) (xy 20.833625 -54.162861) (xy 20.825816 -54.216966)
			(xy 20.810362 -54.269402) (xy 20.787581 -54.319095) (xy 20.757938 -54.365026) (xy 20.74037 -54.385972)
			(xy 20.740116 -54.386226) (xy 20.739862 -54.38648) (xy 20.734277 -54.393567) (xy 20.728034 -54.410484)
			(xy 20.72767 -54.4195) (xy 20.72767 -54.486556) (xy 20.728022 -54.495576) (xy 20.734255 -54.512504)
			(xy 20.739862 -54.519576) (xy 20.740116 -54.51983) (xy 20.74037 -54.520084) (xy 20.757961 -54.541011)
			(xy 20.787597 -54.58695) (xy 20.810374 -54.636647) (xy 20.825827 -54.689086) (xy 20.833638 -54.743194)
			(xy 20.834096 -54.770528) (xy 20.833574 -54.799338) (xy 20.824918 -54.856303) (xy 20.807791 -54.911319)
			(xy 20.782583 -54.963132) (xy 20.749868 -55.010563) (xy 20.710391 -55.052534) (xy 20.670957 -55.083456)
			(xy 26.94127 -55.083456) (xy 26.945341 -55.027834) (xy 26.957467 -54.973397) (xy 26.97739 -54.921306)
			(xy 27.004686 -54.872671) (xy 27.038772 -54.828528) (xy 27.078921 -54.789819) (xy 27.124279 -54.757368)
			(xy 27.173879 -54.731867) (xy 27.226663 -54.71386) (xy 27.281506 -54.70373) (xy 27.33724 -54.701693)
			(xy 27.392677 -54.707793) (xy 27.446634 -54.721899) (xy 27.497963 -54.743711) (xy 27.545569 -54.772765)
			(xy 27.588437 -54.80844) (xy 27.625654 -54.849977) (xy 27.656427 -54.89649) (xy 27.680099 -54.946987)
			(xy 27.692756 -54.989055) (xy 29.901045 -54.989055) (xy 29.901045 -54.934545) (xy 29.908803 -54.880589)
			(xy 29.924161 -54.828287) (xy 29.946807 -54.778704) (xy 29.976279 -54.732848) (xy 30.011977 -54.691653)
			(xy 30.053175 -54.655958) (xy 30.099034 -54.62649) (xy 30.148619 -54.603849) (xy 30.200923 -54.588496)
			(xy 30.254879 -54.580743) (xy 30.282134 -54.580282) (xy 30.310226 -54.58075) (xy 30.365805 -54.588982)
			(xy 30.419575 -54.605278) (xy 30.470372 -54.629285) (xy 30.517098 -54.660484) (xy 30.558743 -54.698199)
			(xy 30.594404 -54.741616) (xy 30.609286 -54.765448) (xy 30.614874 -54.774592) (xy 30.631892 -54.786784)
			(xy 30.724856 -54.80685) (xy 30.74543 -54.802786) (xy 30.754066 -54.79669) (xy 30.778137 -54.780701)
			(xy 30.830066 -54.755356) (xy 30.885222 -54.738127) (xy 30.942344 -54.729409) (xy 30.971236 -54.728872)
			(xy 30.998487 -54.729344) (xy 31.012862 -54.731412) (xy 39.520622 -54.731412) (xy 39.521066 -54.704077)
			(xy 39.52888 -54.649969) (xy 39.544336 -54.59753) (xy 39.567116 -54.547832) (xy 39.596756 -54.501895)
			(xy 39.614348 -54.480968) (xy 39.614602 -54.480714) (xy 39.614856 -54.48046) (xy 39.62043 -54.473365)
			(xy 39.626683 -54.456455) (xy 39.627048 -54.44744) (xy 39.627048 -54.380384) (xy 39.62671 -54.371365)
			(xy 39.62045 -54.354448) (xy 39.614856 -54.347364) (xy 39.614602 -54.34711) (xy 39.614348 -54.346856)
			(xy 39.59676 -54.325924) (xy 39.567108 -54.279992) (xy 39.54432 -54.230296) (xy 39.528863 -54.177856)
			(xy 39.521054 -54.123745) (xy 39.521053 -54.069073) (xy 39.528859 -54.014962) (xy 39.544314 -53.962521)
			(xy 39.5671 -53.912824) (xy 39.596749 -53.86689) (xy 39.614348 -53.845968) (xy 39.614602 -53.845714)
			(xy 39.614856 -53.84546) (xy 39.62043 -53.838365) (xy 39.626683 -53.821455) (xy 39.627048 -53.81244)
			(xy 39.627048 -53.745384) (xy 39.62671 -53.736365) (xy 39.62045 -53.719448) (xy 39.614856 -53.712364)
			(xy 39.614602 -53.71211) (xy 39.614348 -53.711856) (xy 39.59676 -53.690924) (xy 39.567108 -53.644992)
			(xy 39.54432 -53.595296) (xy 39.528863 -53.542856) (xy 39.521054 -53.488745) (xy 39.521053 -53.434073)
			(xy 39.528859 -53.379962) (xy 39.544314 -53.327521) (xy 39.5671 -53.277824) (xy 39.596749 -53.23189)
			(xy 39.614348 -53.210968) (xy 39.614602 -53.210714) (xy 39.614856 -53.21046) (xy 39.62043 -53.203365)
			(xy 39.626683 -53.186455) (xy 39.627048 -53.17744) (xy 39.627048 -53.110384) (xy 39.62671 -53.101365)
			(xy 39.62045 -53.084448) (xy 39.614856 -53.077364) (xy 39.614602 -53.07711) (xy 39.614348 -53.076856)
			(xy 39.596776 -53.055914) (xy 39.567133 -53.009982) (xy 39.544352 -52.960289) (xy 39.528899 -52.907851)
			(xy 39.521092 -52.853745) (xy 39.520622 -52.826412) (xy 39.521108 -52.799161) (xy 39.528864 -52.745213)
			(xy 39.544219 -52.692918) (xy 39.566861 -52.643341) (xy 39.596327 -52.597491) (xy 39.632018 -52.5563)
			(xy 39.673209 -52.520609) (xy 39.719059 -52.491143) (xy 39.768636 -52.468501) (xy 39.820931 -52.453146)
			(xy 39.874879 -52.44539) (xy 39.929381 -52.44539) (xy 39.983329 -52.453146) (xy 40.035624 -52.468501)
			(xy 40.085201 -52.491143) (xy 40.131051 -52.520609) (xy 40.172242 -52.5563) (xy 40.207933 -52.597491)
			(xy 40.237399 -52.643341) (xy 40.260041 -52.692918) (xy 40.275396 -52.745213) (xy 40.283152 -52.799161)
			(xy 40.283638 -52.826412) (xy 40.283159 -52.853746) (xy 40.275355 -52.907853) (xy 40.259908 -52.960292)
			(xy 40.237135 -53.00999) (xy 40.207502 -53.055929) (xy 40.189912 -53.076856) (xy 40.189658 -53.07711)
			(xy 40.189404 -53.077364) (xy 40.183827 -53.084457) (xy 40.177574 -53.101369) (xy 40.177212 -53.110384)
			(xy 40.177212 -53.17744) (xy 40.177547 -53.186459) (xy 40.18381 -53.203376) (xy 40.189404 -53.21046)
			(xy 40.189658 -53.210714) (xy 40.189912 -53.210968) (xy 40.207525 -53.23188) (xy 40.237179 -53.277814)
			(xy 40.259968 -53.327513) (xy 40.275425 -53.379957) (xy 40.283233 -53.434072) (xy 40.283232 -53.488746)
			(xy 40.275421 -53.54286) (xy 40.259962 -53.595304) (xy 40.23717 -53.645001) (xy 40.207514 -53.690934)
			(xy 40.189912 -53.711856) (xy 40.189658 -53.71211) (xy 40.189404 -53.712364) (xy 40.183827 -53.719457)
			(xy 40.177574 -53.736369) (xy 40.177212 -53.745384) (xy 40.177212 -53.81244) (xy 40.177547 -53.821459)
			(xy 40.18381 -53.838376) (xy 40.189404 -53.84546) (xy 40.189658 -53.845714) (xy 40.189912 -53.845968)
			(xy 40.207525 -53.86688) (xy 40.237179 -53.912814) (xy 40.259968 -53.962513) (xy 40.275425 -54.014957)
			(xy 40.283233 -54.069072) (xy 40.283232 -54.123746) (xy 40.275421 -54.17786) (xy 40.259962 -54.230304)
			(xy 40.23717 -54.280001) (xy 40.207514 -54.325934) (xy 40.189912 -54.346856) (xy 40.189658 -54.34711)
			(xy 40.189404 -54.347364) (xy 40.183827 -54.354457) (xy 40.177574 -54.371369) (xy 40.177212 -54.380384)
			(xy 40.177212 -54.44744) (xy 40.177547 -54.456459) (xy 40.18381 -54.473376) (xy 40.189404 -54.48046)
			(xy 40.189658 -54.480714) (xy 40.189912 -54.480968) (xy 40.207505 -54.501893) (xy 40.237143 -54.547831)
			(xy 40.259919 -54.597529) (xy 40.275367 -54.649969) (xy 40.28317 -54.704078) (xy 40.283638 -54.731412)
			(xy 40.283152 -54.758663) (xy 40.278488 -54.791102) (xy 42.176446 -54.791102) (xy 42.176937 -54.763769)
			(xy 42.184739 -54.709662) (xy 42.200183 -54.657223) (xy 42.222953 -54.607525) (xy 42.252584 -54.561586)
			(xy 42.270172 -54.540658) (xy 42.270426 -54.540404) (xy 42.27068 -54.54015) (xy 42.276261 -54.53306)
			(xy 42.282509 -54.516146) (xy 42.282872 -54.50713) (xy 42.282872 -54.440074) (xy 42.282534 -54.431055)
			(xy 42.276274 -54.414138) (xy 42.27068 -54.407054) (xy 42.270426 -54.4068) (xy 42.270172 -54.406546)
			(xy 42.252573 -54.385622) (xy 42.22292 -54.33969) (xy 42.200131 -54.289993) (xy 42.184674 -54.23755)
			(xy 42.176865 -54.183438) (xy 42.176865 -54.128765) (xy 42.184673 -54.074653) (xy 42.20013 -54.02221)
			(xy 42.222919 -53.972513) (xy 42.252572 -53.92658) (xy 42.270172 -53.905658) (xy 42.270426 -53.905404)
			(xy 42.27068 -53.90515) (xy 42.276261 -53.89806) (xy 42.282509 -53.881146) (xy 42.282872 -53.87213)
			(xy 42.282872 -53.805074) (xy 42.282534 -53.796055) (xy 42.276274 -53.779138) (xy 42.27068 -53.772054)
			(xy 42.270426 -53.7718) (xy 42.270172 -53.771546) (xy 42.252573 -53.750622) (xy 42.22292 -53.70469)
			(xy 42.200131 -53.654993) (xy 42.184674 -53.60255) (xy 42.176865 -53.548438) (xy 42.176865 -53.493765)
			(xy 42.184673 -53.439653) (xy 42.20013 -53.38721) (xy 42.222919 -53.337513) (xy 42.252572 -53.29158)
			(xy 42.270172 -53.270658) (xy 42.270426 -53.270404) (xy 42.27068 -53.27015) (xy 42.276261 -53.26306)
			(xy 42.282509 -53.246146) (xy 42.282872 -53.23713) (xy 42.282872 -53.170074) (xy 42.282534 -53.161055)
			(xy 42.276274 -53.144138) (xy 42.27068 -53.137054) (xy 42.270426 -53.1368) (xy 42.270172 -53.136546)
			(xy 42.252583 -53.115617) (xy 42.222945 -53.069681) (xy 42.200169 -53.019984) (xy 42.18472 -52.967544)
			(xy 42.176915 -52.913436) (xy 42.176446 -52.886102) (xy 42.176932 -52.858851) (xy 42.184688 -52.804903)
			(xy 42.200043 -52.752608) (xy 42.222685 -52.703031) (xy 42.252151 -52.657181) (xy 42.287842 -52.61599)
			(xy 42.329033 -52.580299) (xy 42.374883 -52.550833) (xy 42.42446 -52.528191) (xy 42.476755 -52.512836)
			(xy 42.530703 -52.50508) (xy 42.585205 -52.50508) (xy 42.639153 -52.512836) (xy 42.653471 -52.51704)
			(xy 46.840138 -52.51704) (xy 46.844209 -52.461418) (xy 46.856335 -52.406981) (xy 46.876258 -52.35489)
			(xy 46.903554 -52.306255) (xy 46.93764 -52.262112) (xy 46.977789 -52.223403) (xy 47.023147 -52.190952)
			(xy 47.072747 -52.165451) (xy 47.125531 -52.147444) (xy 47.180374 -52.137314) (xy 47.236108 -52.135277)
			(xy 47.291545 -52.141377) (xy 47.345502 -52.155483) (xy 47.396831 -52.177295) (xy 47.444437 -52.206349)
			(xy 47.487305 -52.242024) (xy 47.524522 -52.283561) (xy 47.555295 -52.330074) (xy 47.578967 -52.380571)
			(xy 47.595035 -52.433978) (xy 47.603155 -52.489154) (xy 47.603664 -52.51704) (xy 47.603155 -52.544926)
			(xy 47.596905 -52.587398) (xy 50.755294 -52.587398) (xy 50.759365 -52.531776) (xy 50.771491 -52.477339)
			(xy 50.791414 -52.425248) (xy 50.81871 -52.376613) (xy 50.852796 -52.33247) (xy 50.892945 -52.293761)
			(xy 50.938303 -52.26131) (xy 50.987903 -52.235809) (xy 51.040687 -52.217802) (xy 51.09553 -52.207672)
			(xy 51.151264 -52.205635) (xy 51.206701 -52.211735) (xy 51.260658 -52.225841) (xy 51.311987 -52.247653)
			(xy 51.359593 -52.276707) (xy 51.402461 -52.312382) (xy 51.439678 -52.353919) (xy 51.470451 -52.400432)
			(xy 51.494123 -52.450929) (xy 51.510191 -52.504336) (xy 51.518311 -52.559512) (xy 51.518396 -52.564153)
			(xy 55.82713 -52.564153) (xy 55.82713 -52.509647) (xy 55.834886 -52.455695) (xy 55.850242 -52.403396)
			(xy 55.872884 -52.353815) (xy 55.902351 -52.30796) (xy 55.938043 -52.266766) (xy 55.979235 -52.23107)
			(xy 56.025087 -52.201599) (xy 56.074666 -52.178953) (xy 56.126964 -52.163593) (xy 56.180915 -52.155832)
			(xy 56.208168 -52.155344) (xy 56.235538 -52.155818) (xy 56.289717 -52.163632) (xy 56.342221 -52.179119)
			(xy 56.391968 -52.201959) (xy 56.437934 -52.231683) (xy 56.458866 -52.249324) (xy 56.45912 -52.249578)
			(xy 56.46619 -52.255188) (xy 56.48312 -52.261419) (xy 56.49214 -52.26177) (xy 56.559196 -52.26177)
			(xy 56.568214 -52.261418) (xy 56.585131 -52.255168) (xy 56.592216 -52.249578) (xy 56.592724 -52.24907)
			(xy 56.613664 -52.231495) (xy 56.659597 -52.201855) (xy 56.709292 -52.179076) (xy 56.761729 -52.163624)
			(xy 56.815835 -52.155816) (xy 56.843168 -52.155344) (xy 56.870419 -52.155901) (xy 56.924367 -52.163653)
			(xy 56.976662 -52.179005) (xy 57.02624 -52.201642) (xy 57.072091 -52.231106) (xy 57.113282 -52.266795)
			(xy 57.148975 -52.307983) (xy 57.178442 -52.353832) (xy 57.201084 -52.403408) (xy 57.21644 -52.455702)
			(xy 57.224197 -52.509649) (xy 57.224197 -52.555953) (xy 58.583779 -52.555953) (xy 58.583779 -52.501447)
			(xy 58.591537 -52.447497) (xy 58.606893 -52.3952) (xy 58.629536 -52.345621) (xy 58.659005 -52.29977)
			(xy 58.6947 -52.258579) (xy 58.735894 -52.222887) (xy 58.781748 -52.193422) (xy 58.831329 -52.170783)
			(xy 58.883627 -52.15543) (xy 58.937577 -52.147677) (xy 58.96483 -52.147216) (xy 58.992201 -52.147661)
			(xy 59.046381 -52.155483) (xy 59.098885 -52.170977) (xy 59.148631 -52.193823) (xy 59.194597 -52.223553)
			(xy 59.215528 -52.241196) (xy 59.215782 -52.24145) (xy 59.222865 -52.247041) (xy 59.239785 -52.253284)
			(xy 59.248802 -52.253642) (xy 59.315858 -52.253642) (xy 59.324874 -52.253278) (xy 59.341792 -52.247037)
			(xy 59.348878 -52.24145) (xy 59.349386 -52.240942) (xy 59.370312 -52.223349) (xy 59.416248 -52.193709)
			(xy 59.465946 -52.170932) (xy 59.518387 -52.155485) (xy 59.572496 -52.147683) (xy 59.59983 -52.147216)
			(xy 59.627082 -52.147656) (xy 59.681029 -52.155416) (xy 59.733324 -52.170775) (xy 59.7829 -52.193419)
			(xy 59.82875 -52.222888) (xy 59.869939 -52.258582) (xy 59.90563 -52.299774) (xy 59.935095 -52.345626)
			(xy 59.957735 -52.395204) (xy 59.97309 -52.4475) (xy 59.980846 -52.501448) (xy 59.980846 -52.555952)
			(xy 59.97309 -52.6099) (xy 59.957735 -52.662196) (xy 59.935095 -52.711774) (xy 59.90563 -52.757626)
			(xy 59.869939 -52.798818) (xy 59.82875 -52.834512) (xy 59.7829 -52.863981) (xy 59.733324 -52.886625)
			(xy 59.681029 -52.901984) (xy 59.627082 -52.909744) (xy 59.59983 -52.910232) (xy 59.57246 -52.909765)
			(xy 59.51828 -52.90195) (xy 59.465776 -52.886462) (xy 59.416029 -52.86362) (xy 59.370063 -52.833894)
			(xy 59.349132 -52.816252) (xy 59.348878 -52.815998) (xy 59.341802 -52.810396) (xy 59.324877 -52.804159)
			(xy 59.315858 -52.803806) (xy 59.248802 -52.803806) (xy 59.239785 -52.804163) (xy 59.222868 -52.81041)
			(xy 59.215782 -52.815998) (xy 59.215274 -52.816506) (xy 59.194332 -52.834078) (xy 59.148399 -52.863719)
			(xy 59.098706 -52.8865) (xy 59.046269 -52.901952) (xy 58.992163 -52.909761) (xy 58.96483 -52.910232)
			(xy 58.937577 -52.909723) (xy 58.883627 -52.90197) (xy 58.831329 -52.886617) (xy 58.781748 -52.863978)
			(xy 58.735894 -52.834513) (xy 58.6947 -52.798821) (xy 58.659005 -52.75763) (xy 58.629536 -52.711779)
			(xy 58.606893 -52.6622) (xy 58.591537 -52.609903) (xy 58.583779 -52.555953) (xy 57.224197 -52.555953)
			(xy 57.224197 -52.564151) (xy 57.21644 -52.618098) (xy 57.201084 -52.670392) (xy 57.178442 -52.719968)
			(xy 57.148975 -52.765817) (xy 57.113282 -52.807005) (xy 57.072091 -52.842694) (xy 57.02624 -52.872158)
			(xy 56.976662 -52.894795) (xy 56.924367 -52.910147) (xy 56.870419 -52.917899) (xy 56.843168 -52.91836)
			(xy 56.815797 -52.917922) (xy 56.761616 -52.910099) (xy 56.709112 -52.894604) (xy 56.659366 -52.871756)
			(xy 56.6134 -52.842025) (xy 56.59247 -52.82438) (xy 56.592216 -52.824126) (xy 56.585135 -52.818531)
			(xy 56.568214 -52.812291) (xy 56.559196 -52.811934) (xy 56.49214 -52.811934) (xy 56.483124 -52.812303)
			(xy 56.466207 -52.818541) (xy 56.45912 -52.824126) (xy 56.458612 -52.824634) (xy 56.437697 -52.84224)
			(xy 56.391756 -52.871875) (xy 56.342056 -52.894648) (xy 56.289613 -52.910093) (xy 56.235503 -52.917893)
			(xy 56.208168 -52.91836) (xy 56.180915 -52.917968) (xy 56.126964 -52.910207) (xy 56.074666 -52.894847)
			(xy 56.025087 -52.872201) (xy 55.979235 -52.84273) (xy 55.938043 -52.807034) (xy 55.902351 -52.76584)
			(xy 55.872884 -52.719985) (xy 55.850242 -52.670404) (xy 55.834886 -52.618105) (xy 55.82713 -52.564153)
			(xy 51.518396 -52.564153) (xy 51.51882 -52.587398) (xy 51.518311 -52.615284) (xy 51.510191 -52.67046)
			(xy 51.494123 -52.723867) (xy 51.470451 -52.774364) (xy 51.439678 -52.820877) (xy 51.402461 -52.862414)
			(xy 51.359593 -52.898089) (xy 51.311987 -52.927143) (xy 51.260658 -52.948955) (xy 51.206701 -52.963061)
			(xy 51.151264 -52.969161) (xy 51.09553 -52.967124) (xy 51.040687 -52.956994) (xy 50.987903 -52.938987)
			(xy 50.938303 -52.913486) (xy 50.892945 -52.881035) (xy 50.852796 -52.842326) (xy 50.81871 -52.798183)
			(xy 50.791414 -52.749548) (xy 50.771491 -52.697457) (xy 50.759365 -52.64302) (xy 50.755294 -52.587398)
			(xy 47.596905 -52.587398) (xy 47.595035 -52.600102) (xy 47.578967 -52.653509) (xy 47.555295 -52.704006)
			(xy 47.524522 -52.750519) (xy 47.487305 -52.792056) (xy 47.444437 -52.827731) (xy 47.396831 -52.856785)
			(xy 47.345502 -52.878597) (xy 47.291545 -52.892703) (xy 47.236108 -52.898803) (xy 47.180374 -52.896766)
			(xy 47.125531 -52.886636) (xy 47.072747 -52.868629) (xy 47.023147 -52.843128) (xy 46.977789 -52.810677)
			(xy 46.93764 -52.771968) (xy 46.903554 -52.727825) (xy 46.876258 -52.67919) (xy 46.856335 -52.627099)
			(xy 46.844209 -52.572662) (xy 46.840138 -52.51704) (xy 42.653471 -52.51704) (xy 42.691448 -52.528191)
			(xy 42.741025 -52.550833) (xy 42.786875 -52.580299) (xy 42.828066 -52.61599) (xy 42.863757 -52.657181)
			(xy 42.893223 -52.703031) (xy 42.915865 -52.752608) (xy 42.93122 -52.804903) (xy 42.938976 -52.858851)
			(xy 42.939462 -52.886102) (xy 42.938971 -52.913435) (xy 42.931169 -52.967542) (xy 42.915725 -53.019981)
			(xy 42.892954 -53.069679) (xy 42.863324 -53.115618) (xy 42.845736 -53.136546) (xy 42.845482 -53.1368)
			(xy 42.845228 -53.137054) (xy 42.839646 -53.144143) (xy 42.833399 -53.161058) (xy 42.833036 -53.170074)
			(xy 42.833036 -53.23713) (xy 42.833371 -53.246149) (xy 42.839633 -53.263067) (xy 42.845228 -53.27015)
			(xy 42.845482 -53.270404) (xy 42.845736 -53.270658) (xy 42.863338 -53.291579) (xy 42.892991 -53.337512)
			(xy 42.915779 -53.38721) (xy 42.931236 -53.439652) (xy 42.939044 -53.493765) (xy 42.939044 -53.548438)
			(xy 42.931235 -53.602551) (xy 42.915778 -53.654993) (xy 42.892989 -53.704691) (xy 42.863336 -53.750624)
			(xy 42.846591 -53.77053) (xy 43.210734 -53.77053) (xy 43.211261 -53.741613) (xy 43.219986 -53.684442)
			(xy 43.237242 -53.629243) (xy 43.262632 -53.577281) (xy 43.295574 -53.529747) (xy 43.335315 -53.48773)
			(xy 43.3578 -53.46954) (xy 43.365178 -53.46325) (xy 43.374977 -53.44654) (xy 43.37685 -53.437028)
			(xy 43.377358 -53.429408) (xy 43.377358 -53.349652) (xy 43.37685 -53.342032) (xy 43.374977 -53.332519)
			(xy 43.365182 -53.315805) (xy 43.3578 -53.30952) (xy 43.335326 -53.291318) (xy 43.29559 -53.2493)
			(xy 43.26265 -53.201768) (xy 43.23726 -53.149809) (xy 43.220002 -53.094613) (xy 43.21127 -53.037445)
			(xy 43.210734 -53.00853) (xy 43.211183 -52.981276) (xy 43.218937 -52.927322) (xy 43.234292 -52.875022)
			(xy 43.256934 -52.825439) (xy 43.286403 -52.779584) (xy 43.322098 -52.738389) (xy 43.363293 -52.702695)
			(xy 43.409149 -52.673228) (xy 43.458733 -52.650587) (xy 43.511034 -52.635235) (xy 43.564988 -52.627482)
			(xy 43.592242 -52.627022) (xy 43.592496 -52.627022) (xy 43.618791 -52.627476) (xy 43.67088 -52.634722)
			(xy 43.721482 -52.649048) (xy 43.769638 -52.670184) (xy 43.814438 -52.69773) (xy 43.855032 -52.731165)
			(xy 43.873166 -52.750212) (xy 43.88075 -52.757639) (xy 43.900159 -52.766172) (xy 43.910758 -52.766722)
			(xy 43.984926 -52.766722) (xy 43.995558 -52.766312) (xy 44.015022 -52.757763) (xy 44.022518 -52.750212)
			(xy 44.040631 -52.731141) (xy 44.081216 -52.697685) (xy 44.126016 -52.670128) (xy 44.174179 -52.648991)
			(xy 44.22479 -52.634677) (xy 44.276889 -52.627458) (xy 44.303188 -52.627022) (xy 44.303442 -52.627022)
			(xy 44.330696 -52.627439) (xy 44.384647 -52.635202) (xy 44.436945 -52.650564) (xy 44.486525 -52.673212)
			(xy 44.532376 -52.702685) (xy 44.573567 -52.738384) (xy 44.609258 -52.779581) (xy 44.638723 -52.825439)
			(xy 44.661361 -52.875022) (xy 44.676713 -52.927323) (xy 44.684466 -52.981276) (xy 44.68495 -53.00853)
			(xy 44.684484 -53.036197) (xy 44.682253 -53.051456) (xy 52.941218 -53.051456) (xy 52.945289 -52.995834)
			(xy 52.957415 -52.941397) (xy 52.977338 -52.889306) (xy 53.004634 -52.840671) (xy 53.03872 -52.796528)
			(xy 53.078869 -52.757819) (xy 53.124227 -52.725368) (xy 53.173827 -52.699867) (xy 53.226611 -52.68186)
			(xy 53.281454 -52.67173) (xy 53.337188 -52.669693) (xy 53.392625 -52.675793) (xy 53.446582 -52.689899)
			(xy 53.497911 -52.711711) (xy 53.545517 -52.740765) (xy 53.588385 -52.77644) (xy 53.625602 -52.817977)
			(xy 53.656375 -52.86449) (xy 53.680047 -52.914987) (xy 53.696115 -52.968394) (xy 53.704235 -53.02357)
			(xy 53.704744 -53.051456) (xy 53.704235 -53.079342) (xy 53.696115 -53.134518) (xy 53.680047 -53.187925)
			(xy 53.656375 -53.238422) (xy 53.625602 -53.284935) (xy 53.588385 -53.326472) (xy 53.545517 -53.362147)
			(xy 53.497911 -53.391201) (xy 53.446582 -53.413013) (xy 53.392625 -53.427119) (xy 53.337188 -53.433219)
			(xy 53.281454 -53.431182) (xy 53.226611 -53.421052) (xy 53.173827 -53.403045) (xy 53.124227 -53.377544)
			(xy 53.078869 -53.345093) (xy 53.03872 -53.306384) (xy 53.004634 -53.262241) (xy 52.977338 -53.213606)
			(xy 52.957415 -53.161515) (xy 52.945289 -53.107078) (xy 52.941218 -53.051456) (xy 44.682253 -53.051456)
			(xy 44.676479 -53.090949) (xy 44.660656 -53.143973) (xy 44.637346 -53.194158) (xy 44.607037 -53.240453)
			(xy 44.570364 -53.281889) (xy 44.528095 -53.317599) (xy 44.504864 -53.332634) (xy 44.50461 -53.332888)
			(xy 44.495088 -53.339558) (xy 44.482778 -53.359249) (xy 44.480988 -53.370734) (xy 44.473114 -53.450744)
			(xy 44.472445 -53.462445) (xy 44.480528 -53.484417) (xy 44.488608 -53.492908) (xy 44.488862 -53.492908)
			(xy 44.507422 -53.51101) (xy 44.540004 -53.551336) (xy 44.566821 -53.595706) (xy 44.587377 -53.643301)
			(xy 44.601295 -53.693242) (xy 44.608316 -53.744608) (xy 44.60875 -53.77053) (xy 44.60825 -53.79778)
			(xy 44.600491 -53.851725) (xy 44.585134 -53.904017) (xy 44.562492 -53.953592) (xy 44.533027 -53.99944)
			(xy 44.497337 -54.040629) (xy 44.456149 -54.07632) (xy 44.410302 -54.105787) (xy 44.360728 -54.12843)
			(xy 44.308437 -54.143788) (xy 44.254492 -54.151549) (xy 44.227242 -54.152038) (xy 44.199872 -54.151562)
			(xy 44.145693 -54.143749) (xy 44.093189 -54.128263) (xy 44.043442 -54.105423) (xy 43.997475 -54.075699)
			(xy 43.976544 -54.058058) (xy 43.97629 -54.057804) (xy 43.96921 -54.052208) (xy 43.952288 -54.045967)
			(xy 43.94327 -54.045612) (xy 43.876214 -54.045612) (xy 43.867197 -54.045973) (xy 43.85028 -54.052217)
			(xy 43.843194 -54.057804) (xy 43.842686 -54.058312) (xy 43.821778 -54.075926) (xy 43.775836 -54.105561)
			(xy 43.726134 -54.128333) (xy 43.673689 -54.143776) (xy 43.619577 -54.151573) (xy 43.592242 -54.152038)
			(xy 43.564992 -54.151506) (xy 43.511045 -54.143755) (xy 43.45875 -54.128406) (xy 43.409172 -54.105771)
			(xy 43.36332 -54.07631) (xy 43.322128 -54.040623) (xy 43.286433 -53.999438) (xy 43.256964 -53.953591)
			(xy 43.234319 -53.904018) (xy 43.21896 -53.851726) (xy 43.211199 -53.79778) (xy 43.210734 -53.77053)
			(xy 42.846591 -53.77053) (xy 42.845736 -53.771546) (xy 42.845482 -53.7718) (xy 42.845228 -53.772054)
			(xy 42.839646 -53.779143) (xy 42.833399 -53.796058) (xy 42.833036 -53.805074) (xy 42.833036 -53.87213)
			(xy 42.833371 -53.881149) (xy 42.839633 -53.898067) (xy 42.845228 -53.90515) (xy 42.845482 -53.905404)
			(xy 42.845736 -53.905658) (xy 42.863338 -53.926579) (xy 42.892991 -53.972512) (xy 42.915779 -54.02221)
			(xy 42.931236 -54.074652) (xy 42.939044 -54.128765) (xy 42.939044 -54.183438) (xy 42.931235 -54.237551)
			(xy 42.915778 -54.289993) (xy 42.901933 -54.320186) (xy 45.130466 -54.320186) (xy 45.130943 -54.292852)
			(xy 45.138747 -54.238745) (xy 45.154195 -54.186306) (xy 45.176968 -54.136608) (xy 45.206602 -54.090669)
			(xy 45.224192 -54.069742) (xy 45.224446 -54.069488) (xy 45.2247 -54.069234) (xy 45.230278 -54.062142)
			(xy 45.23653 -54.045229) (xy 45.236892 -54.036214) (xy 45.236892 -53.969158) (xy 45.236509 -53.960144)
			(xy 45.23028 -53.943227) (xy 45.2247 -53.936138) (xy 45.224446 -53.935884) (xy 45.224192 -53.93563)
			(xy 45.206599 -53.914705) (xy 45.176961 -53.868768) (xy 45.154185 -53.81907) (xy 45.138737 -53.766629)
			(xy 45.130934 -53.71252) (xy 45.130466 -53.685186) (xy 45.130952 -53.657935) (xy 45.138708 -53.603987)
			(xy 45.154063 -53.551692) (xy 45.176705 -53.502115) (xy 45.206171 -53.456265) (xy 45.241862 -53.415074)
			(xy 45.283053 -53.379383) (xy 45.328903 -53.349917) (xy 45.37848 -53.327275) (xy 45.430775 -53.31192)
			(xy 45.484723 -53.304164) (xy 45.539225 -53.304164) (xy 45.593173 -53.31192) (xy 45.645468 -53.327275)
			(xy 45.695045 -53.349917) (xy 45.740895 -53.379383) (xy 45.782086 -53.415074) (xy 45.817777 -53.456265)
			(xy 45.843668 -53.496552) (xy 58.133464 -53.496552) (xy 58.133464 -53.442048) (xy 58.14122 -53.3881)
			(xy 58.156575 -53.335804) (xy 58.179216 -53.286226) (xy 58.208683 -53.240374) (xy 58.244374 -53.199183)
			(xy 58.285565 -53.16349) (xy 58.331415 -53.134022) (xy 58.380993 -53.11138) (xy 58.433288 -53.096023)
			(xy 58.487236 -53.088265) (xy 58.514488 -53.087778) (xy 58.541859 -53.088232) (xy 58.596039 -53.09605)
			(xy 58.648543 -53.111541) (xy 58.69829 -53.134386) (xy 58.744256 -53.164114) (xy 58.765186 -53.181758)
			(xy 58.76544 -53.182012) (xy 58.772539 -53.187581) (xy 58.789446 -53.193838) (xy 58.79846 -53.194204)
			(xy 58.865516 -53.194204) (xy 58.874534 -53.193854) (xy 58.89145 -53.187601) (xy 58.898536 -53.182012)
			(xy 58.899044 -53.181504) (xy 58.919981 -53.163925) (xy 58.965914 -53.134284) (xy 59.01561 -53.111505)
			(xy 59.068048 -53.096054) (xy 59.122154 -53.088248) (xy 59.149488 -53.087778) (xy 59.17674 -53.088268)
			(xy 59.230691 -53.096024) (xy 59.282988 -53.111378) (xy 59.332568 -53.134019) (xy 59.378421 -53.163486)
			(xy 59.419613 -53.199178) (xy 59.455307 -53.24037) (xy 59.484775 -53.286222) (xy 59.507418 -53.335801)
			(xy 59.522774 -53.388098) (xy 59.530531 -53.442048) (xy 59.530531 -53.496552) (xy 59.522774 -53.550502)
			(xy 59.507418 -53.602799) (xy 59.484775 -53.652378) (xy 59.455307 -53.69823) (xy 59.419613 -53.739422)
			(xy 59.378421 -53.775114) (xy 59.332568 -53.804581) (xy 59.282988 -53.827222) (xy 59.230691 -53.842576)
			(xy 59.17674 -53.850332) (xy 59.149488 -53.850794) (xy 59.122117 -53.850336) (xy 59.067938 -53.842517)
			(xy 59.015435 -53.827026) (xy 58.965688 -53.804182) (xy 58.919721 -53.774456) (xy 58.89879 -53.756814)
			(xy 58.898536 -53.75656) (xy 58.891447 -53.750977) (xy 58.874532 -53.744729) (xy 58.865516 -53.744368)
			(xy 58.79846 -53.744368) (xy 58.789442 -53.744713) (xy 58.772525 -53.75097) (xy 58.76544 -53.75656)
			(xy 58.764932 -53.757068) (xy 58.744001 -53.774654) (xy 58.698066 -53.804294) (xy 58.64837 -53.827073)
			(xy 58.59593 -53.842522) (xy 58.541822 -53.850325) (xy 58.514488 -53.850794) (xy 58.487236 -53.850335)
			(xy 58.433288 -53.842577) (xy 58.380993 -53.82722) (xy 58.331415 -53.804578) (xy 58.285565 -53.77511)
			(xy 58.244374 -53.739417) (xy 58.208683 -53.698226) (xy 58.179216 -53.652374) (xy 58.156575 -53.602796)
			(xy 58.14122 -53.5505) (xy 58.133464 -53.496552) (xy 45.843668 -53.496552) (xy 45.847243 -53.502115)
			(xy 45.869885 -53.551692) (xy 45.88524 -53.603987) (xy 45.892996 -53.657935) (xy 45.893482 -53.685186)
			(xy 45.893036 -53.712521) (xy 45.885222 -53.766629) (xy 45.869767 -53.819068) (xy 45.846987 -53.868765)
			(xy 45.817348 -53.914703) (xy 45.799756 -53.93563) (xy 45.799502 -53.935884) (xy 45.799248 -53.936138)
			(xy 45.793675 -53.943234) (xy 45.787421 -53.960144) (xy 45.787056 -53.969158) (xy 45.787056 -54.036214)
			(xy 45.787394 -54.045233) (xy 45.793654 -54.06215) (xy 45.799248 -54.069234) (xy 45.799502 -54.069488)
			(xy 45.799756 -54.069742) (xy 45.817328 -54.090684) (xy 45.846971 -54.136616) (xy 45.869752 -54.18631)
			(xy 45.885204 -54.238747) (xy 45.893012 -54.292853) (xy 45.893482 -54.320186) (xy 45.892996 -54.347437)
			(xy 45.88524 -54.401385) (xy 45.869885 -54.45368) (xy 45.847243 -54.503257) (xy 45.817777 -54.549107)
			(xy 45.782086 -54.590298) (xy 45.740895 -54.625989) (xy 45.695045 -54.655455) (xy 45.645468 -54.678097)
			(xy 45.593173 -54.693452) (xy 45.539225 -54.701208) (xy 45.484723 -54.701208) (xy 45.430775 -54.693452)
			(xy 45.37848 -54.678097) (xy 45.328903 -54.655455) (xy 45.283053 -54.625989) (xy 45.241862 -54.590298)
			(xy 45.206171 -54.549107) (xy 45.176705 -54.503257) (xy 45.154063 -54.45368) (xy 45.138708 -54.401385)
			(xy 45.130952 -54.347437) (xy 45.130466 -54.320186) (xy 42.901933 -54.320186) (xy 42.892989 -54.339691)
			(xy 42.863336 -54.385624) (xy 42.845736 -54.406546) (xy 42.845482 -54.4068) (xy 42.845228 -54.407054)
			(xy 42.839646 -54.414143) (xy 42.833399 -54.431058) (xy 42.833036 -54.440074) (xy 42.833036 -54.50713)
			(xy 42.833371 -54.516149) (xy 42.839633 -54.533067) (xy 42.845228 -54.54015) (xy 42.845482 -54.540404)
			(xy 42.845736 -54.540658) (xy 42.863328 -54.561584) (xy 42.892965 -54.607522) (xy 42.915741 -54.657219)
			(xy 42.931189 -54.70966) (xy 42.938993 -54.763768) (xy 42.939109 -54.770528) (xy 46.071028 -54.770528)
			(xy 46.07148 -54.743194) (xy 46.079292 -54.689086) (xy 46.094746 -54.636646) (xy 46.117524 -54.586949)
			(xy 46.147162 -54.541011) (xy 46.164754 -54.520084) (xy 46.165008 -54.51983) (xy 46.165262 -54.519576)
			(xy 46.170872 -54.512506) (xy 46.177103 -54.495576) (xy 46.177454 -54.486556) (xy 46.177454 -54.4195)
			(xy 46.177107 -54.410482) (xy 46.170853 -54.393565) (xy 46.165262 -54.38648) (xy 46.165008 -54.386226)
			(xy 46.164754 -54.385972) (xy 46.147175 -54.365036) (xy 46.117536 -54.319101) (xy 46.094758 -54.269406)
			(xy 46.079307 -54.216968) (xy 46.071499 -54.162861) (xy 46.071028 -54.135528) (xy 46.071514 -54.108277)
			(xy 46.07927 -54.054329) (xy 46.094625 -54.002034) (xy 46.117267 -53.952457) (xy 46.146733 -53.906607)
			(xy 46.182424 -53.865416) (xy 46.223615 -53.829725) (xy 46.269465 -53.800259) (xy 46.319042 -53.777617)
			(xy 46.371337 -53.762262) (xy 46.425285 -53.754506) (xy 46.479787 -53.754506) (xy 46.533735 -53.762262)
			(xy 46.58603 -53.777617) (xy 46.635607 -53.800259) (xy 46.681457 -53.829725) (xy 46.722648 -53.865416)
			(xy 46.758339 -53.906607) (xy 46.787805 -53.952457) (xy 46.79288 -53.96357) (xy 50.772058 -53.96357)
			(xy 50.776129 -53.907948) (xy 50.788255 -53.853511) (xy 50.808178 -53.80142) (xy 50.835474 -53.752785)
			(xy 50.86956 -53.708642) (xy 50.909709 -53.669933) (xy 50.955067 -53.637482) (xy 51.004667 -53.611981)
			(xy 51.057451 -53.593974) (xy 51.112294 -53.583844) (xy 51.168028 -53.581807) (xy 51.223465 -53.587907)
			(xy 51.277422 -53.602013) (xy 51.328751 -53.623825) (xy 51.376357 -53.652879) (xy 51.419225 -53.688554)
			(xy 51.456442 -53.730091) (xy 51.487215 -53.776604) (xy 51.510887 -53.827101) (xy 51.526955 -53.880508)
			(xy 51.535075 -53.935684) (xy 51.535584 -53.96357) (xy 51.535075 -53.991456) (xy 51.526955 -54.046632)
			(xy 51.52069 -54.067456) (xy 52.941218 -54.067456) (xy 52.945289 -54.011834) (xy 52.957415 -53.957397)
			(xy 52.977338 -53.905306) (xy 53.004634 -53.856671) (xy 53.03872 -53.812528) (xy 53.078869 -53.773819)
			(xy 53.124227 -53.741368) (xy 53.173827 -53.715867) (xy 53.226611 -53.69786) (xy 53.281454 -53.68773)
			(xy 53.337188 -53.685693) (xy 53.392625 -53.691793) (xy 53.446582 -53.705899) (xy 53.497911 -53.727711)
			(xy 53.545517 -53.756765) (xy 53.588385 -53.79244) (xy 53.625602 -53.833977) (xy 53.656375 -53.88049)
			(xy 53.680047 -53.930987) (xy 53.696115 -53.984394) (xy 53.704235 -54.03957) (xy 53.704744 -54.067456)
			(xy 53.704235 -54.095342) (xy 53.696115 -54.150518) (xy 53.680047 -54.203925) (xy 53.663649 -54.238906)
			(xy 60.385958 -54.238906) (xy 60.390029 -54.183284) (xy 60.402155 -54.128847) (xy 60.422078 -54.076756)
			(xy 60.449374 -54.028121) (xy 60.48346 -53.983978) (xy 60.523609 -53.945269) (xy 60.568967 -53.912818)
			(xy 60.618567 -53.887317) (xy 60.671351 -53.86931) (xy 60.726194 -53.85918) (xy 60.781928 -53.857143)
			(xy 60.837365 -53.863243) (xy 60.891322 -53.877349) (xy 60.942651 -53.899161) (xy 60.990257 -53.928215)
			(xy 61.033125 -53.96389) (xy 61.070342 -54.005427) (xy 61.101115 -54.05194) (xy 61.124787 -54.102437)
			(xy 61.140855 -54.155844) (xy 61.148975 -54.21102) (xy 61.149484 -54.238906) (xy 61.148975 -54.266792)
			(xy 61.140855 -54.321968) (xy 61.124787 -54.375375) (xy 61.101115 -54.425872) (xy 61.070342 -54.472385)
			(xy 61.033125 -54.513922) (xy 60.990257 -54.549597) (xy 60.942651 -54.578651) (xy 60.891322 -54.600463)
			(xy 60.837365 -54.614569) (xy 60.781928 -54.620669) (xy 60.726194 -54.618632) (xy 60.671351 -54.608502)
			(xy 60.618567 -54.590495) (xy 60.568967 -54.564994) (xy 60.523609 -54.532543) (xy 60.48346 -54.493834)
			(xy 60.449374 -54.449691) (xy 60.422078 -54.401056) (xy 60.402155 -54.348965) (xy 60.390029 -54.294528)
			(xy 60.385958 -54.238906) (xy 53.663649 -54.238906) (xy 53.656375 -54.254422) (xy 53.625602 -54.300935)
			(xy 53.588385 -54.342472) (xy 53.545517 -54.378147) (xy 53.497911 -54.407201) (xy 53.446582 -54.429013)
			(xy 53.392625 -54.443119) (xy 53.337188 -54.449219) (xy 53.281454 -54.447182) (xy 53.226611 -54.437052)
			(xy 53.173827 -54.419045) (xy 53.124227 -54.393544) (xy 53.078869 -54.361093) (xy 53.03872 -54.322384)
			(xy 53.004634 -54.278241) (xy 52.977338 -54.229606) (xy 52.957415 -54.177515) (xy 52.945289 -54.123078)
			(xy 52.941218 -54.067456) (xy 51.52069 -54.067456) (xy 51.510887 -54.100039) (xy 51.487215 -54.150536)
			(xy 51.456442 -54.197049) (xy 51.419225 -54.238586) (xy 51.376357 -54.274261) (xy 51.328751 -54.303315)
			(xy 51.277422 -54.325127) (xy 51.223465 -54.339233) (xy 51.168028 -54.345333) (xy 51.112294 -54.343296)
			(xy 51.057451 -54.333166) (xy 51.004667 -54.315159) (xy 50.955067 -54.289658) (xy 50.909709 -54.257207)
			(xy 50.86956 -54.218498) (xy 50.835474 -54.174355) (xy 50.808178 -54.12572) (xy 50.788255 -54.073629)
			(xy 50.776129 -54.019192) (xy 50.772058 -53.96357) (xy 46.79288 -53.96357) (xy 46.810447 -54.002034)
			(xy 46.825802 -54.054329) (xy 46.833558 -54.108277) (xy 46.834044 -54.135528) (xy 46.833573 -54.162862)
			(xy 46.825767 -54.216969) (xy 46.810318 -54.269409) (xy 46.787543 -54.319107) (xy 46.757908 -54.365045)
			(xy 46.740318 -54.385972) (xy 46.740064 -54.386226) (xy 46.73981 -54.38648) (xy 46.734227 -54.393569)
			(xy 46.727978 -54.410484) (xy 46.727618 -54.4195) (xy 46.727618 -54.486556) (xy 46.727992 -54.495571)
			(xy 46.734228 -54.512488) (xy 46.73981 -54.519576) (xy 46.740064 -54.51983) (xy 46.740318 -54.520084)
			(xy 46.757919 -54.541003) (xy 46.787556 -54.586942) (xy 46.81033 -54.636642) (xy 46.825776 -54.689083)
			(xy 46.833577 -54.743193) (xy 46.834044 -54.770528) (xy 46.833558 -54.797779) (xy 46.825802 -54.851727)
			(xy 46.810447 -54.904022) (xy 46.787805 -54.953599) (xy 46.758339 -54.999449) (xy 46.722648 -55.04064)
			(xy 46.681457 -55.076331) (xy 46.67037 -55.083456) (xy 52.941218 -55.083456) (xy 52.945289 -55.027834)
			(xy 52.957415 -54.973397) (xy 52.977338 -54.921306) (xy 53.004634 -54.872671) (xy 53.03872 -54.828528)
			(xy 53.078869 -54.789819) (xy 53.124227 -54.757368) (xy 53.173827 -54.731867) (xy 53.226611 -54.71386)
			(xy 53.281454 -54.70373) (xy 53.337188 -54.701693) (xy 53.392625 -54.707793) (xy 53.446582 -54.721899)
			(xy 53.497911 -54.743711) (xy 53.545517 -54.772765) (xy 53.588385 -54.80844) (xy 53.625602 -54.849977)
			(xy 53.656375 -54.89649) (xy 53.680047 -54.946987) (xy 53.692702 -54.989051) (xy 55.901068 -54.989051)
			(xy 55.901068 -54.934549) (xy 55.908824 -54.880601) (xy 55.924179 -54.828307) (xy 55.946819 -54.778729)
			(xy 55.976284 -54.732879) (xy 56.011975 -54.691688) (xy 56.053164 -54.655995) (xy 56.099013 -54.626528)
			(xy 56.14859 -54.603885) (xy 56.200884 -54.588528) (xy 56.254831 -54.580769) (xy 56.282082 -54.580282)
			(xy 56.310173 -54.580791) (xy 56.36575 -54.589016) (xy 56.419518 -54.605304) (xy 56.470316 -54.629305)
			(xy 56.517043 -54.660497) (xy 56.558688 -54.698207) (xy 56.594351 -54.741619) (xy 56.609234 -54.765448)
			(xy 56.614822 -54.774592) (xy 56.63184 -54.786784) (xy 56.724804 -54.80685) (xy 56.745378 -54.802786)
			(xy 56.754014 -54.79669) (xy 56.778072 -54.780681) (xy 56.830006 -54.75534) (xy 56.885165 -54.738117)
			(xy 56.942291 -54.729405) (xy 56.971184 -54.728872) (xy 56.998434 -54.729393) (xy 57.01248 -54.731412)
			(xy 65.52057 -54.731412) (xy 65.521003 -54.704077) (xy 65.528818 -54.649967) (xy 65.544275 -54.597527)
			(xy 65.567059 -54.54783) (xy 65.596702 -54.501894) (xy 65.614296 -54.480968) (xy 65.61455 -54.480714)
			(xy 65.614804 -54.48046) (xy 65.620372 -54.473361) (xy 65.62663 -54.456454) (xy 65.626996 -54.44744)
			(xy 65.626996 -54.380384) (xy 65.626647 -54.371366) (xy 65.620394 -54.354449) (xy 65.614804 -54.347364)
			(xy 65.61455 -54.34711) (xy 65.614296 -54.346856) (xy 65.596706 -54.325925) (xy 65.567051 -54.279994)
			(xy 65.54426 -54.230299) (xy 65.5288 -54.177857) (xy 65.52099 -54.123745) (xy 65.520989 -54.069073)
			(xy 65.528797 -54.014961) (xy 65.544253 -53.962518) (xy 65.567042 -53.912822) (xy 65.596695 -53.86689)
			(xy 65.614296 -53.845968) (xy 65.61455 -53.845714) (xy 65.614804 -53.84546) (xy 65.620372 -53.838361)
			(xy 65.62663 -53.821454) (xy 65.626996 -53.81244) (xy 65.626996 -53.745384) (xy 65.626647 -53.736366)
			(xy 65.620394 -53.719449) (xy 65.614804 -53.712364) (xy 65.61455 -53.71211) (xy 65.614296 -53.711856)
			(xy 65.596706 -53.690925) (xy 65.567051 -53.644994) (xy 65.54426 -53.595299) (xy 65.5288 -53.542857)
			(xy 65.52099 -53.488745) (xy 65.520989 -53.434073) (xy 65.528797 -53.379961) (xy 65.544253 -53.327518)
			(xy 65.567042 -53.277822) (xy 65.596695 -53.23189) (xy 65.614296 -53.210968) (xy 65.61455 -53.210714)
			(xy 65.614804 -53.21046) (xy 65.620372 -53.203361) (xy 65.62663 -53.186454) (xy 65.626996 -53.17744)
			(xy 65.626996 -53.110384) (xy 65.626647 -53.101366) (xy 65.620394 -53.084449) (xy 65.614804 -53.077364)
			(xy 65.61455 -53.07711) (xy 65.614296 -53.076856) (xy 65.596716 -53.055921) (xy 65.567076 -53.009986)
			(xy 65.544297 -52.960291) (xy 65.528846 -52.907853) (xy 65.52104 -52.853746) (xy 65.52057 -52.826412)
			(xy 65.521056 -52.799161) (xy 65.528812 -52.745213) (xy 65.544167 -52.692918) (xy 65.566809 -52.643341)
			(xy 65.596275 -52.597491) (xy 65.631966 -52.5563) (xy 65.673157 -52.520609) (xy 65.719007 -52.491143)
			(xy 65.768584 -52.468501) (xy 65.820879 -52.453146) (xy 65.874827 -52.44539) (xy 65.929329 -52.44539)
			(xy 65.983277 -52.453146) (xy 66.035572 -52.468501) (xy 66.085149 -52.491143) (xy 66.130999 -52.520609)
			(xy 66.17219 -52.5563) (xy 66.207881 -52.597491) (xy 66.237347 -52.643341) (xy 66.259989 -52.692918)
			(xy 66.275344 -52.745213) (xy 66.2831 -52.799161) (xy 66.283586 -52.826412) (xy 66.283095 -52.853745)
			(xy 66.275292 -52.907851) (xy 66.259848 -52.96029) (xy 66.237077 -53.009988) (xy 66.207448 -53.055928)
			(xy 66.18986 -53.076856) (xy 66.189606 -53.07711) (xy 66.189352 -53.077364) (xy 66.183769 -53.084453)
			(xy 66.177521 -53.101368) (xy 66.17716 -53.110384) (xy 66.17716 -53.17744) (xy 66.177485 -53.18646)
			(xy 66.183753 -53.203378) (xy 66.189352 -53.21046) (xy 66.189606 -53.210714) (xy 66.18986 -53.210968)
			(xy 66.207471 -53.231881) (xy 66.237121 -53.277816) (xy 66.259907 -53.327515) (xy 66.275362 -53.379959)
			(xy 66.283169 -53.434072) (xy 66.283168 -53.488746) (xy 66.275359 -53.542859) (xy 66.259901 -53.595302)
			(xy 66.237113 -53.644999) (xy 66.20746 -53.690933) (xy 66.18986 -53.711856) (xy 66.189606 -53.71211)
			(xy 66.189352 -53.712364) (xy 66.183769 -53.719453) (xy 66.177521 -53.736368) (xy 66.17716 -53.745384)
			(xy 66.17716 -53.81244) (xy 66.177485 -53.82146) (xy 66.183753 -53.838378) (xy 66.189352 -53.84546)
			(xy 66.189606 -53.845714) (xy 66.18986 -53.845968) (xy 66.207471 -53.866881) (xy 66.237121 -53.912816)
			(xy 66.259907 -53.962515) (xy 66.275362 -54.014959) (xy 66.283169 -54.069072) (xy 66.283168 -54.123746)
			(xy 66.275359 -54.177859) (xy 66.259901 -54.230302) (xy 66.237113 -54.279999) (xy 66.20746 -54.325933)
			(xy 66.18986 -54.346856) (xy 66.189606 -54.34711) (xy 66.189352 -54.347364) (xy 66.183769 -54.354453)
			(xy 66.177521 -54.371368) (xy 66.17716 -54.380384) (xy 66.17716 -54.44744) (xy 66.177485 -54.45646)
			(xy 66.183753 -54.473378) (xy 66.189352 -54.48046) (xy 66.189606 -54.480714) (xy 66.18986 -54.480968)
			(xy 66.207445 -54.5019) (xy 66.237086 -54.547835) (xy 66.259864 -54.597531) (xy 66.275314 -54.64997)
			(xy 66.283117 -54.704078) (xy 66.283586 -54.731412) (xy 66.2831 -54.758663) (xy 66.278436 -54.791102)
			(xy 68.176394 -54.791102) (xy 68.176898 -54.76377) (xy 68.184698 -54.709664) (xy 68.20014 -54.657225)
			(xy 68.222907 -54.607527) (xy 68.252534 -54.561587) (xy 68.27012 -54.540658) (xy 68.270374 -54.540404)
			(xy 68.270628 -54.54015) (xy 68.276203 -54.533056) (xy 68.282456 -54.516145) (xy 68.28282 -54.50713)
			(xy 68.28282 -54.440074) (xy 68.282471 -54.431056) (xy 68.276218 -54.41414) (xy 68.270628 -54.407054)
			(xy 68.270374 -54.4068) (xy 68.27012 -54.406546) (xy 68.252519 -54.385623) (xy 68.222863 -54.339692)
			(xy 68.200071 -54.289995) (xy 68.184611 -54.237552) (xy 68.176801 -54.183439) (xy 68.176801 -54.128764)
			(xy 68.18461 -54.074651) (xy 68.20007 -54.022208) (xy 68.222861 -53.972511) (xy 68.252518 -53.926579)
			(xy 68.27012 -53.905658) (xy 68.270374 -53.905404) (xy 68.270628 -53.90515) (xy 68.276203 -53.898056)
			(xy 68.282456 -53.881145) (xy 68.28282 -53.87213) (xy 68.28282 -53.805074) (xy 68.282471 -53.796056)
			(xy 68.276218 -53.77914) (xy 68.270628 -53.772054) (xy 68.270374 -53.7718) (xy 68.27012 -53.771546)
			(xy 68.252519 -53.750623) (xy 68.222863 -53.704692) (xy 68.200071 -53.654995) (xy 68.184611 -53.602552)
			(xy 68.176801 -53.548439) (xy 68.176801 -53.493764) (xy 68.18461 -53.439651) (xy 68.20007 -53.387208)
			(xy 68.222861 -53.337511) (xy 68.252518 -53.291579) (xy 68.27012 -53.270658) (xy 68.270374 -53.270404)
			(xy 68.270628 -53.27015) (xy 68.276203 -53.263056) (xy 68.282456 -53.246145) (xy 68.28282 -53.23713)
			(xy 68.28282 -53.170074) (xy 68.282471 -53.161056) (xy 68.276218 -53.14414) (xy 68.270628 -53.137054)
			(xy 68.270374 -53.1368) (xy 68.27012 -53.136546) (xy 68.252539 -53.115611) (xy 68.222898 -53.069677)
			(xy 68.200119 -53.019982) (xy 68.184669 -52.967543) (xy 68.176864 -52.913436) (xy 68.176394 -52.886102)
			(xy 68.17688 -52.858851) (xy 68.184636 -52.804903) (xy 68.199991 -52.752608) (xy 68.222633 -52.703031)
			(xy 68.252099 -52.657181) (xy 68.28779 -52.61599) (xy 68.328981 -52.580299) (xy 68.374831 -52.550833)
			(xy 68.424408 -52.528191) (xy 68.476703 -52.512836) (xy 68.530651 -52.50508) (xy 68.585153 -52.50508)
			(xy 68.639101 -52.512836) (xy 68.653419 -52.51704) (xy 72.840086 -52.51704) (xy 72.844157 -52.461418)
			(xy 72.856283 -52.406981) (xy 72.876206 -52.35489) (xy 72.903502 -52.306255) (xy 72.937588 -52.262112)
			(xy 72.977737 -52.223403) (xy 73.023095 -52.190952) (xy 73.072695 -52.165451) (xy 73.125479 -52.147444)
			(xy 73.180322 -52.137314) (xy 73.236056 -52.135277) (xy 73.291493 -52.141377) (xy 73.34545 -52.155483)
			(xy 73.396779 -52.177295) (xy 73.444385 -52.206349) (xy 73.487253 -52.242024) (xy 73.52447 -52.283561)
			(xy 73.555243 -52.330074) (xy 73.578915 -52.380571) (xy 73.594983 -52.433978) (xy 73.603103 -52.489154)
			(xy 73.603612 -52.51704) (xy 73.603103 -52.544926) (xy 73.596853 -52.587398) (xy 76.755242 -52.587398)
			(xy 76.759313 -52.531776) (xy 76.771439 -52.477339) (xy 76.791362 -52.425248) (xy 76.818658 -52.376613)
			(xy 76.852744 -52.33247) (xy 76.892893 -52.293761) (xy 76.938251 -52.26131) (xy 76.987851 -52.235809)
			(xy 77.040635 -52.217802) (xy 77.095478 -52.207672) (xy 77.151212 -52.205635) (xy 77.206649 -52.211735)
			(xy 77.260606 -52.225841) (xy 77.311935 -52.247653) (xy 77.359541 -52.276707) (xy 77.402409 -52.312382)
			(xy 77.439626 -52.353919) (xy 77.470399 -52.400432) (xy 77.494071 -52.450929) (xy 77.510139 -52.504336)
			(xy 77.518259 -52.559512) (xy 77.518344 -52.564157) (xy 81.827007 -52.564157) (xy 81.827007 -52.509643)
			(xy 81.834765 -52.455684) (xy 81.850124 -52.403378) (xy 81.872771 -52.353791) (xy 81.902244 -52.307931)
			(xy 81.937944 -52.266733) (xy 81.979144 -52.231034) (xy 82.025005 -52.201563) (xy 82.074593 -52.178919)
			(xy 82.126899 -52.163562) (xy 82.180859 -52.155806) (xy 82.208116 -52.155344) (xy 82.235487 -52.15579)
			(xy 82.289667 -52.163611) (xy 82.342171 -52.179104) (xy 82.391918 -52.201951) (xy 82.437883 -52.23168)
			(xy 82.458814 -52.249324) (xy 82.459068 -52.249578) (xy 82.466153 -52.255166) (xy 82.483071 -52.26141)
			(xy 82.492088 -52.26177) (xy 82.559144 -52.26177) (xy 82.568159 -52.261393) (xy 82.585076 -52.25516)
			(xy 82.592164 -52.249578) (xy 82.592672 -52.24907) (xy 82.613594 -52.231473) (xy 82.659532 -52.201836)
			(xy 82.709231 -52.179061) (xy 82.761672 -52.163614) (xy 82.815782 -52.155812) (xy 82.843116 -52.155344)
			(xy 82.870363 -52.155927) (xy 82.924302 -52.163685) (xy 82.976588 -52.179039) (xy 83.026157 -52.201678)
			(xy 83.072 -52.231141) (xy 83.113183 -52.266828) (xy 83.148868 -52.308013) (xy 83.178329 -52.353857)
			(xy 83.200966 -52.403427) (xy 83.216319 -52.455713) (xy 83.224074 -52.509653) (xy 83.224074 -52.555949)
			(xy 84.583802 -52.555949) (xy 84.583802 -52.501452) (xy 84.591558 -52.447509) (xy 84.606911 -52.39522)
			(xy 84.629549 -52.345647) (xy 84.659011 -52.299801) (xy 84.694698 -52.258614) (xy 84.735883 -52.222924)
			(xy 84.781728 -52.193459) (xy 84.831299 -52.170818) (xy 84.883588 -52.155462) (xy 84.93753 -52.147704)
			(xy 84.964778 -52.147216) (xy 84.992148 -52.147691) (xy 85.046327 -52.155506) (xy 85.09883 -52.170993)
			(xy 85.148577 -52.193833) (xy 85.194544 -52.223556) (xy 85.215476 -52.241196) (xy 85.21573 -52.24145)
			(xy 85.222828 -52.247019) (xy 85.239736 -52.253275) (xy 85.24875 -52.253642) (xy 85.315806 -52.253642)
			(xy 85.324825 -52.2533) (xy 85.341742 -52.247043) (xy 85.348826 -52.24145) (xy 85.349334 -52.240942)
			(xy 85.370279 -52.223374) (xy 85.41621 -52.19373) (xy 85.465903 -52.170948) (xy 85.518339 -52.155495)
			(xy 85.572445 -52.147687) (xy 85.599778 -52.147216) (xy 85.627034 -52.147629) (xy 85.68099 -52.155384)
			(xy 85.733294 -52.170739) (xy 85.78288 -52.193382) (xy 85.828739 -52.222851) (xy 85.869937 -52.258547)
			(xy 85.905635 -52.299743) (xy 85.935107 -52.3456) (xy 85.957753 -52.395185) (xy 85.973111 -52.447488)
			(xy 85.980869 -52.501444) (xy 85.980869 -52.555956) (xy 85.973111 -52.609912) (xy 85.957753 -52.662215)
			(xy 85.935107 -52.7118) (xy 85.905635 -52.757657) (xy 85.869937 -52.798853) (xy 85.828739 -52.834549)
			(xy 85.78288 -52.864018) (xy 85.733294 -52.886661) (xy 85.68099 -52.902016) (xy 85.627034 -52.909771)
			(xy 85.599778 -52.910232) (xy 85.572407 -52.909795) (xy 85.518225 -52.901973) (xy 85.465721 -52.886478)
			(xy 85.415975 -52.863629) (xy 85.37001 -52.833897) (xy 85.34908 -52.816252) (xy 85.348826 -52.815998)
			(xy 85.341736 -52.810416) (xy 85.324822 -52.804167) (xy 85.315806 -52.803806) (xy 85.24875 -52.803806)
			(xy 85.239735 -52.804186) (xy 85.222818 -52.810418) (xy 85.21573 -52.815998) (xy 85.215222 -52.816506)
			(xy 85.1943 -52.834103) (xy 85.148362 -52.86374) (xy 85.098663 -52.886516) (xy 85.046222 -52.901962)
			(xy 84.992112 -52.909764) (xy 84.964778 -52.910232) (xy 84.93753 -52.909696) (xy 84.883588 -52.901938)
			(xy 84.831299 -52.886582) (xy 84.781728 -52.863941) (xy 84.735883 -52.834476) (xy 84.694698 -52.798786)
			(xy 84.659011 -52.757599) (xy 84.629549 -52.711753) (xy 84.606911 -52.66218) (xy 84.591558 -52.609891)
			(xy 84.583802 -52.555949) (xy 83.224074 -52.555949) (xy 83.224074 -52.564147) (xy 83.216319 -52.618087)
			(xy 83.200966 -52.670373) (xy 83.178329 -52.719943) (xy 83.148868 -52.765787) (xy 83.113183 -52.806972)
			(xy 83.072 -52.842659) (xy 83.026157 -52.872122) (xy 82.976588 -52.894761) (xy 82.924302 -52.910115)
			(xy 82.870363 -52.917873) (xy 82.843116 -52.91836) (xy 82.815746 -52.917894) (xy 82.761566 -52.910078)
			(xy 82.709063 -52.894589) (xy 82.659316 -52.871747) (xy 82.613349 -52.842022) (xy 82.592418 -52.82438)
			(xy 82.592164 -52.824126) (xy 82.58507 -52.818551) (xy 82.568159 -52.812299) (xy 82.559144 -52.811934)
			(xy 82.492088 -52.811934) (xy 82.48307 -52.812278) (xy 82.466152 -52.818534) (xy 82.459068 -52.824126)
			(xy 82.45856 -52.824634) (xy 82.437627 -52.842217) (xy 82.391691 -52.871856) (xy 82.341995 -52.894633)
			(xy 82.289557 -52.910083) (xy 82.23545 -52.91789) (xy 82.208116 -52.91836) (xy 82.180859 -52.917994)
			(xy 82.126899 -52.910238) (xy 82.074593 -52.894881) (xy 82.025005 -52.872237) (xy 81.979144 -52.842766)
			(xy 81.937944 -52.807067) (xy 81.902244 -52.765869) (xy 81.872771 -52.720009) (xy 81.850124 -52.670422)
			(xy 81.834765 -52.618116) (xy 81.827007 -52.564157) (xy 77.518344 -52.564157) (xy 77.518768 -52.587398)
			(xy 77.518259 -52.615284) (xy 77.510139 -52.67046) (xy 77.494071 -52.723867) (xy 77.470399 -52.774364)
			(xy 77.439626 -52.820877) (xy 77.402409 -52.862414) (xy 77.359541 -52.898089) (xy 77.311935 -52.927143)
			(xy 77.260606 -52.948955) (xy 77.206649 -52.963061) (xy 77.151212 -52.969161) (xy 77.095478 -52.967124)
			(xy 77.040635 -52.956994) (xy 76.987851 -52.938987) (xy 76.938251 -52.913486) (xy 76.892893 -52.881035)
			(xy 76.852744 -52.842326) (xy 76.818658 -52.798183) (xy 76.791362 -52.749548) (xy 76.771439 -52.697457)
			(xy 76.759313 -52.64302) (xy 76.755242 -52.587398) (xy 73.596853 -52.587398) (xy 73.594983 -52.600102)
			(xy 73.578915 -52.653509) (xy 73.555243 -52.704006) (xy 73.52447 -52.750519) (xy 73.487253 -52.792056)
			(xy 73.444385 -52.827731) (xy 73.396779 -52.856785) (xy 73.34545 -52.878597) (xy 73.291493 -52.892703)
			(xy 73.236056 -52.898803) (xy 73.180322 -52.896766) (xy 73.125479 -52.886636) (xy 73.072695 -52.868629)
			(xy 73.023095 -52.843128) (xy 72.977737 -52.810677) (xy 72.937588 -52.771968) (xy 72.903502 -52.727825)
			(xy 72.876206 -52.67919) (xy 72.856283 -52.627099) (xy 72.844157 -52.572662) (xy 72.840086 -52.51704)
			(xy 68.653419 -52.51704) (xy 68.691396 -52.528191) (xy 68.740973 -52.550833) (xy 68.786823 -52.580299)
			(xy 68.828014 -52.61599) (xy 68.863705 -52.657181) (xy 68.893171 -52.703031) (xy 68.915813 -52.752608)
			(xy 68.931168 -52.804903) (xy 68.938924 -52.858851) (xy 68.93941 -52.886102) (xy 68.938908 -52.913435)
			(xy 68.931107 -52.96754) (xy 68.915664 -53.019979) (xy 68.892897 -53.069677) (xy 68.86327 -53.115617)
			(xy 68.845684 -53.136546) (xy 68.84543 -53.1368) (xy 68.845176 -53.137054) (xy 68.8396 -53.144148)
			(xy 68.833348 -53.161059) (xy 68.832984 -53.170074) (xy 68.832984 -53.23713) (xy 68.83333 -53.246148)
			(xy 68.839585 -53.263065) (xy 68.845176 -53.27015) (xy 68.84543 -53.270404) (xy 68.845684 -53.270658)
			(xy 68.863288 -53.291578) (xy 68.892945 -53.33751) (xy 68.915736 -53.387207) (xy 68.931195 -53.439651)
			(xy 68.939005 -53.493764) (xy 68.939004 -53.548439) (xy 68.931195 -53.602552) (xy 68.915735 -53.654996)
			(xy 68.892943 -53.704693) (xy 68.863286 -53.750625) (xy 68.846539 -53.77053) (xy 69.210682 -53.77053)
			(xy 69.211191 -53.741612) (xy 69.219917 -53.684439) (xy 69.237175 -53.629239) (xy 69.262568 -53.577276)
			(xy 69.295515 -53.529743) (xy 69.33526 -53.487728) (xy 69.357748 -53.46954) (xy 69.365117 -53.463241)
			(xy 69.374923 -53.446538) (xy 69.376798 -53.437028) (xy 69.377306 -53.429408) (xy 69.377306 -53.349652)
			(xy 69.376798 -53.342032) (xy 69.374941 -53.332515) (xy 69.365136 -53.315802) (xy 69.357748 -53.30952)
			(xy 69.335263 -53.291331) (xy 69.295531 -53.249309) (xy 69.262593 -53.201773) (xy 69.237206 -53.149812)
			(xy 69.219949 -53.094615) (xy 69.211218 -53.037446) (xy 69.210682 -53.00853) (xy 69.211183 -52.981278)
			(xy 69.218936 -52.927329) (xy 69.234288 -52.875033) (xy 69.256926 -52.825453) (xy 69.28639 -52.779601)
			(xy 69.32208 -52.738408) (xy 69.363269 -52.702714) (xy 69.409118 -52.673245) (xy 69.458695 -52.650602)
			(xy 69.51099 -52.635244) (xy 69.564938 -52.627486) (xy 69.59219 -52.627022) (xy 69.592444 -52.627022)
			(xy 69.61874 -52.627444) (xy 69.670831 -52.634696) (xy 69.721433 -52.649029) (xy 69.769589 -52.670171)
			(xy 69.814388 -52.697723) (xy 69.854981 -52.731162) (xy 69.873114 -52.750212) (xy 69.88068 -52.75766)
			(xy 69.900102 -52.766181) (xy 69.910706 -52.766722) (xy 69.984874 -52.766722) (xy 69.995503 -52.766284)
			(xy 70.014967 -52.757754) (xy 70.022466 -52.750212) (xy 70.040604 -52.731166) (xy 70.081184 -52.697708)
			(xy 70.125978 -52.670147) (xy 70.174136 -52.649006) (xy 70.224744 -52.634687) (xy 70.276839 -52.627461)
			(xy 70.303136 -52.627022) (xy 70.30339 -52.627022) (xy 70.330644 -52.627465) (xy 70.384597 -52.635221)
			(xy 70.436897 -52.650577) (xy 70.486479 -52.673221) (xy 70.532334 -52.702691) (xy 70.573528 -52.738387)
			(xy 70.609221 -52.779582) (xy 70.638689 -52.825438) (xy 70.66133 -52.875022) (xy 70.676683 -52.927322)
			(xy 70.684437 -52.981276) (xy 70.684898 -53.00853) (xy 70.68441 -53.036196) (xy 70.682179 -53.051456)
			(xy 78.941166 -53.051456) (xy 78.945237 -52.995834) (xy 78.957363 -52.941397) (xy 78.977286 -52.889306)
			(xy 79.004582 -52.840671) (xy 79.038668 -52.796528) (xy 79.078817 -52.757819) (xy 79.124175 -52.725368)
			(xy 79.173775 -52.699867) (xy 79.226559 -52.68186) (xy 79.281402 -52.67173) (xy 79.337136 -52.669693)
			(xy 79.392573 -52.675793) (xy 79.44653 -52.689899) (xy 79.497859 -52.711711) (xy 79.545465 -52.740765)
			(xy 79.588333 -52.77644) (xy 79.62555 -52.817977) (xy 79.656323 -52.86449) (xy 79.679995 -52.914987)
			(xy 79.696063 -52.968394) (xy 79.704183 -53.02357) (xy 79.704692 -53.051456) (xy 79.704183 -53.079342)
			(xy 79.696063 -53.134518) (xy 79.679995 -53.187925) (xy 79.656323 -53.238422) (xy 79.62555 -53.284935)
			(xy 79.588333 -53.326472) (xy 79.545465 -53.362147) (xy 79.497859 -53.391201) (xy 79.44653 -53.413013)
			(xy 79.392573 -53.427119) (xy 79.337136 -53.433219) (xy 79.281402 -53.431182) (xy 79.226559 -53.421052)
			(xy 79.173775 -53.403045) (xy 79.124175 -53.377544) (xy 79.078817 -53.345093) (xy 79.038668 -53.306384)
			(xy 79.004582 -53.262241) (xy 78.977286 -53.213606) (xy 78.957363 -53.161515) (xy 78.945237 -53.107078)
			(xy 78.941166 -53.051456) (xy 70.682179 -53.051456) (xy 70.676407 -53.090946) (xy 70.660586 -53.143969)
			(xy 70.637279 -53.194153) (xy 70.606974 -53.240448) (xy 70.570305 -53.281885) (xy 70.52804 -53.317598)
			(xy 70.504812 -53.332634) (xy 70.504558 -53.332888) (xy 70.495026 -53.339545) (xy 70.482724 -53.359246)
			(xy 70.480936 -53.370734) (xy 70.473062 -53.450744) (xy 70.472379 -53.462446) (xy 70.48047 -53.48442)
			(xy 70.488556 -53.492908) (xy 70.48881 -53.492908) (xy 70.507379 -53.511001) (xy 70.539958 -53.55133)
			(xy 70.566773 -53.595702) (xy 70.587328 -53.643298) (xy 70.601244 -53.69324) (xy 70.608264 -53.744608)
			(xy 70.608698 -53.77053) (xy 70.60825 -53.797782) (xy 70.600489 -53.851732) (xy 70.58513 -53.904028)
			(xy 70.562484 -53.953606) (xy 70.533014 -53.999457) (xy 70.497319 -54.040647) (xy 70.456125 -54.076338)
			(xy 70.410271 -54.105804) (xy 70.360691 -54.128444) (xy 70.308393 -54.143798) (xy 70.254442 -54.151553)
			(xy 70.22719 -54.152038) (xy 70.199819 -54.151593) (xy 70.145638 -54.143772) (xy 70.093134 -54.128279)
			(xy 70.043388 -54.105432) (xy 69.997422 -54.075702) (xy 69.976492 -54.058058) (xy 69.976238 -54.057804)
			(xy 69.969144 -54.052228) (xy 69.952233 -54.045975) (xy 69.943218 -54.045612) (xy 69.876162 -54.045612)
			(xy 69.867143 -54.045948) (xy 69.850226 -54.05221) (xy 69.843142 -54.057804) (xy 69.842634 -54.058312)
			(xy 69.821708 -54.075904) (xy 69.775771 -54.105542) (xy 69.726073 -54.128318) (xy 69.673633 -54.143766)
			(xy 69.619524 -54.151569) (xy 69.59219 -54.152038) (xy 69.56494 -54.151532) (xy 69.510994 -54.143775)
			(xy 69.458702 -54.12842) (xy 69.409127 -54.10578) (xy 69.363278 -54.076315) (xy 69.322088 -54.040626)
			(xy 69.286397 -53.999438) (xy 69.25693 -53.953591) (xy 69.234287 -53.904017) (xy 69.21893 -53.851725)
			(xy 69.21117 -53.79778) (xy 69.210682 -53.77053) (xy 68.846539 -53.77053) (xy 68.845684 -53.771546)
			(xy 68.84543 -53.7718) (xy 68.845176 -53.772054) (xy 68.8396 -53.779148) (xy 68.833348 -53.796059)
			(xy 68.832984 -53.805074) (xy 68.832984 -53.87213) (xy 68.83333 -53.881148) (xy 68.839585 -53.898065)
			(xy 68.845176 -53.90515) (xy 68.84543 -53.905404) (xy 68.845684 -53.905658) (xy 68.863288 -53.926578)
			(xy 68.892945 -53.97251) (xy 68.915736 -54.022207) (xy 68.931195 -54.074651) (xy 68.939005 -54.128764)
			(xy 68.939004 -54.183439) (xy 68.931195 -54.237552) (xy 68.915735 -54.289996) (xy 68.901889 -54.320186)
			(xy 71.130414 -54.320186) (xy 71.130903 -54.292853) (xy 71.138707 -54.238747) (xy 71.154152 -54.186308)
			(xy 71.176922 -54.13661) (xy 71.206552 -54.09067) (xy 71.22414 -54.069742) (xy 71.224394 -54.069488)
			(xy 71.224648 -54.069234) (xy 71.230232 -54.062146) (xy 71.236479 -54.04523) (xy 71.23684 -54.036214)
			(xy 71.23684 -53.969158) (xy 71.236468 -53.960142) (xy 71.230232 -53.943225) (xy 71.224648 -53.936138)
			(xy 71.224394 -53.935884) (xy 71.22414 -53.93563) (xy 71.206554 -53.914699) (xy 71.176914 -53.868764)
			(xy 71.154135 -53.819068) (xy 71.138686 -53.766628) (xy 71.130882 -53.71252) (xy 71.130414 -53.685186)
			(xy 71.1309 -53.657935) (xy 71.138656 -53.603987) (xy 71.154011 -53.551692) (xy 71.176653 -53.502115)
			(xy 71.206119 -53.456265) (xy 71.24181 -53.415074) (xy 71.283001 -53.379383) (xy 71.328851 -53.349917)
			(xy 71.378428 -53.327275) (xy 71.430723 -53.31192) (xy 71.484671 -53.304164) (xy 71.539173 -53.304164)
			(xy 71.593121 -53.31192) (xy 71.645416 -53.327275) (xy 71.694993 -53.349917) (xy 71.740843 -53.379383)
			(xy 71.782034 -53.415074) (xy 71.817725 -53.456265) (xy 71.843618 -53.496556) (xy 84.133341 -53.496556)
			(xy 84.133341 -53.442044) (xy 84.141099 -53.388088) (xy 84.156458 -53.335786) (xy 84.179104 -53.286201)
			(xy 84.208576 -53.240345) (xy 84.244275 -53.199149) (xy 84.285474 -53.163454) (xy 84.331333 -53.133986)
			(xy 84.380919 -53.111345) (xy 84.433224 -53.095992) (xy 84.48718 -53.088238) (xy 84.514436 -53.087778)
			(xy 84.541808 -53.088204) (xy 84.595989 -53.096029) (xy 84.648494 -53.111526) (xy 84.69824 -53.134377)
			(xy 84.744204 -53.164112) (xy 84.765134 -53.181758) (xy 84.765388 -53.182012) (xy 84.772473 -53.187601)
			(xy 84.789391 -53.193846) (xy 84.798408 -53.194204) (xy 84.865464 -53.194204) (xy 84.874479 -53.193829)
			(xy 84.891396 -53.187594) (xy 84.898484 -53.182012) (xy 84.898992 -53.181504) (xy 84.91991 -53.163902)
			(xy 84.965849 -53.134265) (xy 85.015549 -53.111491) (xy 85.067991 -53.096045) (xy 85.122101 -53.088245)
			(xy 85.149436 -53.087778) (xy 85.176685 -53.088295) (xy 85.230626 -53.096055) (xy 85.282915 -53.111413)
			(xy 85.332486 -53.134055) (xy 85.37833 -53.163521) (xy 85.419514 -53.199211) (xy 85.4552 -53.240399)
			(xy 85.484662 -53.286246) (xy 85.5073 -53.335819) (xy 85.522653 -53.388109) (xy 85.530408 -53.442051)
			(xy 85.530408 -53.496549) (xy 85.522653 -53.550491) (xy 85.5073 -53.602781) (xy 85.484662 -53.652354)
			(xy 85.4552 -53.698201) (xy 85.419514 -53.739389) (xy 85.37833 -53.775079) (xy 85.332486 -53.804545)
			(xy 85.282915 -53.827187) (xy 85.230626 -53.842545) (xy 85.176685 -53.850305) (xy 85.149436 -53.850794)
			(xy 85.122066 -53.850308) (xy 85.067888 -53.842495) (xy 85.015385 -53.827011) (xy 84.965638 -53.804174)
			(xy 84.91967 -53.774453) (xy 84.898738 -53.756814) (xy 84.898484 -53.75656) (xy 84.89141 -53.750956)
			(xy 84.874483 -53.744721) (xy 84.865464 -53.744368) (xy 84.798408 -53.744368) (xy 84.789392 -53.744736)
			(xy 84.772476 -53.750977) (xy 84.765388 -53.75656) (xy 84.76488 -53.757068) (xy 84.743969 -53.774678)
			(xy 84.698028 -53.804315) (xy 84.648327 -53.827089) (xy 84.595883 -53.842532) (xy 84.541771 -53.850329)
			(xy 84.514436 -53.850794) (xy 84.48718 -53.850362) (xy 84.433224 -53.842608) (xy 84.380919 -53.827255)
			(xy 84.331333 -53.804614) (xy 84.285474 -53.775146) (xy 84.244275 -53.739451) (xy 84.208576 -53.698255)
			(xy 84.179104 -53.652399) (xy 84.156458 -53.602814) (xy 84.141099 -53.550512) (xy 84.133341 -53.496556)
			(xy 71.843618 -53.496556) (xy 71.847191 -53.502115) (xy 71.869833 -53.551692) (xy 71.885188 -53.603987)
			(xy 71.892944 -53.657935) (xy 71.89343 -53.685186) (xy 71.892996 -53.712521) (xy 71.885181 -53.76663)
			(xy 71.869724 -53.81907) (xy 71.846941 -53.868768) (xy 71.817298 -53.914704) (xy 71.799704 -53.93563)
			(xy 71.79945 -53.935884) (xy 71.799196 -53.936138) (xy 71.793629 -53.943238) (xy 71.787371 -53.960144)
			(xy 71.787004 -53.969158) (xy 71.787004 -54.036214) (xy 71.787354 -54.045232) (xy 71.793606 -54.062149)
			(xy 71.799196 -54.069234) (xy 71.79945 -54.069488) (xy 71.799704 -54.069742) (xy 71.817283 -54.090678)
			(xy 71.846924 -54.136612) (xy 71.869702 -54.186308) (xy 71.885153 -54.238746) (xy 71.89296 -54.292852)
			(xy 71.89343 -54.320186) (xy 71.892944 -54.347437) (xy 71.885188 -54.401385) (xy 71.869833 -54.45368)
			(xy 71.847191 -54.503257) (xy 71.817725 -54.549107) (xy 71.782034 -54.590298) (xy 71.740843 -54.625989)
			(xy 71.694993 -54.655455) (xy 71.645416 -54.678097) (xy 71.593121 -54.693452) (xy 71.539173 -54.701208)
			(xy 71.484671 -54.701208) (xy 71.430723 -54.693452) (xy 71.378428 -54.678097) (xy 71.328851 -54.655455)
			(xy 71.283001 -54.625989) (xy 71.24181 -54.590298) (xy 71.206119 -54.549107) (xy 71.176653 -54.503257)
			(xy 71.154011 -54.45368) (xy 71.138656 -54.401385) (xy 71.1309 -54.347437) (xy 71.130414 -54.320186)
			(xy 68.901889 -54.320186) (xy 68.892943 -54.339693) (xy 68.863286 -54.385625) (xy 68.845684 -54.406546)
			(xy 68.84543 -54.4068) (xy 68.845176 -54.407054) (xy 68.8396 -54.414148) (xy 68.833348 -54.431059)
			(xy 68.832984 -54.440074) (xy 68.832984 -54.50713) (xy 68.83333 -54.516148) (xy 68.839585 -54.533065)
			(xy 68.845176 -54.54015) (xy 68.84543 -54.540404) (xy 68.845684 -54.540658) (xy 68.863268 -54.561591)
			(xy 68.892908 -54.607526) (xy 68.915686 -54.657222) (xy 68.931136 -54.709661) (xy 68.938941 -54.763768)
			(xy 68.939057 -54.770528) (xy 72.070976 -54.770528) (xy 72.071416 -54.743193) (xy 72.079229 -54.689084)
			(xy 72.094685 -54.636644) (xy 72.117467 -54.586947) (xy 72.147108 -54.54101) (xy 72.164702 -54.520084)
			(xy 72.164956 -54.51983) (xy 72.16521 -54.519576) (xy 72.170814 -54.512501) (xy 72.17705 -54.495575)
			(xy 72.177402 -54.486556) (xy 72.177402 -54.4195) (xy 72.177045 -54.410483) (xy 72.170797 -54.393566)
			(xy 72.16521 -54.38648) (xy 72.164956 -54.386226) (xy 72.164702 -54.385972) (xy 72.14713 -54.36503)
			(xy 72.117489 -54.319097) (xy 72.094708 -54.269404) (xy 72.079256 -54.216967) (xy 72.071447 -54.162861)
			(xy 72.070976 -54.135528) (xy 72.071462 -54.108277) (xy 72.079218 -54.054329) (xy 72.094573 -54.002034)
			(xy 72.117215 -53.952457) (xy 72.146681 -53.906607) (xy 72.182372 -53.865416) (xy 72.223563 -53.829725)
			(xy 72.269413 -53.800259) (xy 72.31899 -53.777617) (xy 72.371285 -53.762262) (xy 72.425233 -53.754506)
			(xy 72.479735 -53.754506) (xy 72.533683 -53.762262) (xy 72.585978 -53.777617) (xy 72.635555 -53.800259)
			(xy 72.681405 -53.829725) (xy 72.722596 -53.865416) (xy 72.758287 -53.906607) (xy 72.787753 -53.952457)
			(xy 72.792828 -53.96357) (xy 76.772006 -53.96357) (xy 76.776077 -53.907948) (xy 76.788203 -53.853511)
			(xy 76.808126 -53.80142) (xy 76.835422 -53.752785) (xy 76.869508 -53.708642) (xy 76.909657 -53.669933)
			(xy 76.955015 -53.637482) (xy 77.004615 -53.611981) (xy 77.057399 -53.593974) (xy 77.112242 -53.583844)
			(xy 77.167976 -53.581807) (xy 77.223413 -53.587907) (xy 77.27737 -53.602013) (xy 77.328699 -53.623825)
			(xy 77.376305 -53.652879) (xy 77.419173 -53.688554) (xy 77.45639 -53.730091) (xy 77.487163 -53.776604)
			(xy 77.510835 -53.827101) (xy 77.526903 -53.880508) (xy 77.535023 -53.935684) (xy 77.535532 -53.96357)
			(xy 77.535023 -53.991456) (xy 77.526903 -54.046632) (xy 77.520638 -54.067456) (xy 78.941166 -54.067456)
			(xy 78.945237 -54.011834) (xy 78.957363 -53.957397) (xy 78.977286 -53.905306) (xy 79.004582 -53.856671)
			(xy 79.038668 -53.812528) (xy 79.078817 -53.773819) (xy 79.124175 -53.741368) (xy 79.173775 -53.715867)
			(xy 79.226559 -53.69786) (xy 79.281402 -53.68773) (xy 79.337136 -53.685693) (xy 79.392573 -53.691793)
			(xy 79.44653 -53.705899) (xy 79.497859 -53.727711) (xy 79.545465 -53.756765) (xy 79.588333 -53.79244)
			(xy 79.62555 -53.833977) (xy 79.656323 -53.88049) (xy 79.679995 -53.930987) (xy 79.696063 -53.984394)
			(xy 79.704183 -54.03957) (xy 79.704692 -54.067456) (xy 79.704183 -54.095342) (xy 79.696063 -54.150518)
			(xy 79.679995 -54.203925) (xy 79.663597 -54.238906) (xy 86.385906 -54.238906) (xy 86.389977 -54.183284)
			(xy 86.402103 -54.128847) (xy 86.422026 -54.076756) (xy 86.449322 -54.028121) (xy 86.483408 -53.983978)
			(xy 86.523557 -53.945269) (xy 86.568915 -53.912818) (xy 86.618515 -53.887317) (xy 86.671299 -53.86931)
			(xy 86.726142 -53.85918) (xy 86.781876 -53.857143) (xy 86.837313 -53.863243) (xy 86.89127 -53.877349)
			(xy 86.942599 -53.899161) (xy 86.990205 -53.928215) (xy 87.033073 -53.96389) (xy 87.07029 -54.005427)
			(xy 87.101063 -54.05194) (xy 87.124735 -54.102437) (xy 87.140803 -54.155844) (xy 87.148923 -54.21102)
			(xy 87.149432 -54.238906) (xy 87.148923 -54.266792) (xy 87.140803 -54.321968) (xy 87.124735 -54.375375)
			(xy 87.101063 -54.425872) (xy 87.07029 -54.472385) (xy 87.033073 -54.513922) (xy 86.990205 -54.549597)
			(xy 86.942599 -54.578651) (xy 86.89127 -54.600463) (xy 86.837313 -54.614569) (xy 86.781876 -54.620669)
			(xy 86.726142 -54.618632) (xy 86.671299 -54.608502) (xy 86.618515 -54.590495) (xy 86.568915 -54.564994)
			(xy 86.523557 -54.532543) (xy 86.483408 -54.493834) (xy 86.449322 -54.449691) (xy 86.422026 -54.401056)
			(xy 86.402103 -54.348965) (xy 86.389977 -54.294528) (xy 86.385906 -54.238906) (xy 79.663597 -54.238906)
			(xy 79.656323 -54.254422) (xy 79.62555 -54.300935) (xy 79.588333 -54.342472) (xy 79.545465 -54.378147)
			(xy 79.497859 -54.407201) (xy 79.44653 -54.429013) (xy 79.392573 -54.443119) (xy 79.337136 -54.449219)
			(xy 79.281402 -54.447182) (xy 79.226559 -54.437052) (xy 79.173775 -54.419045) (xy 79.124175 -54.393544)
			(xy 79.078817 -54.361093) (xy 79.038668 -54.322384) (xy 79.004582 -54.278241) (xy 78.977286 -54.229606)
			(xy 78.957363 -54.177515) (xy 78.945237 -54.123078) (xy 78.941166 -54.067456) (xy 77.520638 -54.067456)
			(xy 77.510835 -54.100039) (xy 77.487163 -54.150536) (xy 77.45639 -54.197049) (xy 77.419173 -54.238586)
			(xy 77.376305 -54.274261) (xy 77.328699 -54.303315) (xy 77.27737 -54.325127) (xy 77.223413 -54.339233)
			(xy 77.167976 -54.345333) (xy 77.112242 -54.343296) (xy 77.057399 -54.333166) (xy 77.004615 -54.315159)
			(xy 76.955015 -54.289658) (xy 76.909657 -54.257207) (xy 76.869508 -54.218498) (xy 76.835422 -54.174355)
			(xy 76.808126 -54.12572) (xy 76.788203 -54.073629) (xy 76.776077 -54.019192) (xy 76.772006 -53.96357)
			(xy 72.792828 -53.96357) (xy 72.810395 -54.002034) (xy 72.82575 -54.054329) (xy 72.833506 -54.108277)
			(xy 72.833992 -54.135528) (xy 72.833509 -54.162861) (xy 72.825704 -54.216968) (xy 72.810257 -54.269407)
			(xy 72.787485 -54.319105) (xy 72.757854 -54.365044) (xy 72.740266 -54.385972) (xy 72.740012 -54.386226)
			(xy 72.739758 -54.38648) (xy 72.734169 -54.393564) (xy 72.727925 -54.410483) (xy 72.727566 -54.4195)
			(xy 72.727566 -54.486556) (xy 72.727951 -54.49557) (xy 72.73418 -54.512487) (xy 72.739758 -54.519576)
			(xy 72.740012 -54.51983) (xy 72.740266 -54.520084) (xy 72.757859 -54.541009) (xy 72.787499 -54.586946)
			(xy 72.810275 -54.636644) (xy 72.825723 -54.689085) (xy 72.833525 -54.743194) (xy 72.833992 -54.770528)
			(xy 72.833506 -54.797779) (xy 72.82575 -54.851727) (xy 72.810395 -54.904022) (xy 72.787753 -54.953599)
			(xy 72.758287 -54.999449) (xy 72.722596 -55.04064) (xy 72.681405 -55.076331) (xy 72.670318 -55.083456)
			(xy 78.941166 -55.083456) (xy 78.945237 -55.027834) (xy 78.957363 -54.973397) (xy 78.977286 -54.921306)
			(xy 79.004582 -54.872671) (xy 79.038668 -54.828528) (xy 79.078817 -54.789819) (xy 79.124175 -54.757368)
			(xy 79.173775 -54.731867) (xy 79.226559 -54.71386) (xy 79.281402 -54.70373) (xy 79.337136 -54.701693)
			(xy 79.392573 -54.707793) (xy 79.44653 -54.721899) (xy 79.497859 -54.743711) (xy 79.545465 -54.772765)
			(xy 79.588333 -54.80844) (xy 79.62555 -54.849977) (xy 79.656323 -54.89649) (xy 79.679995 -54.946987)
			(xy 79.692652 -54.989055) (xy 81.900945 -54.989055) (xy 81.900945 -54.934545) (xy 81.908703 -54.88059)
			(xy 81.924061 -54.828288) (xy 81.946706 -54.778705) (xy 81.976178 -54.732849) (xy 82.011876 -54.691654)
			(xy 82.053073 -54.65596) (xy 82.098931 -54.626492) (xy 82.148516 -54.60385) (xy 82.200819 -54.588497)
			(xy 82.254775 -54.580743) (xy 82.28203 -54.580282) (xy 82.310122 -54.580753) (xy 82.365701 -54.588985)
			(xy 82.41947 -54.60528) (xy 82.470268 -54.629286) (xy 82.516994 -54.660485) (xy 82.558639 -54.6982)
			(xy 82.5943 -54.741616) (xy 82.609182 -54.765448) (xy 82.61477 -54.774592) (xy 82.631788 -54.786784)
			(xy 82.724752 -54.80685) (xy 82.745326 -54.802786) (xy 82.753962 -54.79669) (xy 82.778034 -54.780703)
			(xy 82.829963 -54.755357) (xy 82.885118 -54.738128) (xy 82.94224 -54.729409) (xy 82.971132 -54.728872)
			(xy 82.998383 -54.729348) (xy 83.012732 -54.731412) (xy 91.520518 -54.731412) (xy 91.520963 -54.704077)
			(xy 91.528777 -54.649969) (xy 91.544232 -54.59753) (xy 91.567013 -54.547832) (xy 91.596652 -54.501895)
			(xy 91.614244 -54.480968) (xy 91.614498 -54.480714) (xy 91.614752 -54.48046) (xy 91.620326 -54.473365)
			(xy 91.626579 -54.456454) (xy 91.626944 -54.44744) (xy 91.626944 -54.380384) (xy 91.626607 -54.371365)
			(xy 91.620347 -54.354448) (xy 91.614752 -54.347364) (xy 91.614498 -54.34711) (xy 91.614244 -54.346856)
			(xy 91.596656 -54.325924) (xy 91.567005 -54.279992) (xy 91.544217 -54.230296) (xy 91.52876 -54.177855)
			(xy 91.520951 -54.123745) (xy 91.52095 -54.069073) (xy 91.528756 -54.014962) (xy 91.544211 -53.962521)
			(xy 91.566996 -53.912824) (xy 91.596646 -53.866891) (xy 91.614244 -53.845968) (xy 91.614498 -53.845714)
			(xy 91.614752 -53.84546) (xy 91.620326 -53.838365) (xy 91.626579 -53.821454) (xy 91.626944 -53.81244)
			(xy 91.626944 -53.745384) (xy 91.626607 -53.736365) (xy 91.620347 -53.719448) (xy 91.614752 -53.712364)
			(xy 91.614498 -53.71211) (xy 91.614244 -53.711856) (xy 91.596656 -53.690924) (xy 91.567005 -53.644992)
			(xy 91.544217 -53.595296) (xy 91.52876 -53.542855) (xy 91.520951 -53.488745) (xy 91.52095 -53.434073)
			(xy 91.528756 -53.379962) (xy 91.544211 -53.327521) (xy 91.566996 -53.277824) (xy 91.596646 -53.231891)
			(xy 91.614244 -53.210968) (xy 91.614498 -53.210714) (xy 91.614752 -53.21046) (xy 91.620326 -53.203365)
			(xy 91.626579 -53.186454) (xy 91.626944 -53.17744) (xy 91.626944 -53.110384) (xy 91.626607 -53.101365)
			(xy 91.620347 -53.084448) (xy 91.614752 -53.077364) (xy 91.614498 -53.07711) (xy 91.614244 -53.076856)
			(xy 91.596671 -53.055914) (xy 91.567028 -53.009982) (xy 91.544248 -52.960289) (xy 91.528795 -52.907852)
			(xy 91.520988 -52.853745) (xy 91.520518 -52.826412) (xy 91.521004 -52.799161) (xy 91.52876 -52.745213)
			(xy 91.544115 -52.692918) (xy 91.566757 -52.643341) (xy 91.596223 -52.597491) (xy 91.631914 -52.5563)
			(xy 91.673105 -52.520609) (xy 91.718955 -52.491143) (xy 91.768532 -52.468501) (xy 91.820827 -52.453146)
			(xy 91.874775 -52.44539) (xy 91.929277 -52.44539) (xy 91.983225 -52.453146) (xy 92.03552 -52.468501)
			(xy 92.085097 -52.491143) (xy 92.130947 -52.520609) (xy 92.172138 -52.5563) (xy 92.207829 -52.597491)
			(xy 92.237295 -52.643341) (xy 92.259937 -52.692918) (xy 92.275292 -52.745213) (xy 92.283048 -52.799161)
			(xy 92.283534 -52.826412) (xy 92.283056 -52.853746) (xy 92.275252 -52.907853) (xy 92.259805 -52.960292)
			(xy 92.237031 -53.00999) (xy 92.207398 -53.055929) (xy 92.189808 -53.076856) (xy 92.189554 -53.07711)
			(xy 92.1893 -53.077364) (xy 92.183722 -53.084457) (xy 92.17747 -53.101369) (xy 92.177108 -53.110384)
			(xy 92.177108 -53.17744) (xy 92.177444 -53.186459) (xy 92.183706 -53.203376) (xy 92.1893 -53.21046)
			(xy 92.189554 -53.210714) (xy 92.189808 -53.210968) (xy 92.207421 -53.23188) (xy 92.237075 -53.277814)
			(xy 92.259865 -53.327513) (xy 92.275322 -53.379957) (xy 92.28313 -53.434072) (xy 92.283129 -53.488746)
			(xy 92.275318 -53.54286) (xy 92.259858 -53.595304) (xy 92.237067 -53.645002) (xy 92.20741 -53.690934)
			(xy 92.189808 -53.711856) (xy 92.189554 -53.71211) (xy 92.1893 -53.712364) (xy 92.183722 -53.719457)
			(xy 92.17747 -53.736369) (xy 92.177108 -53.745384) (xy 92.177108 -53.81244) (xy 92.177444 -53.821459)
			(xy 92.183706 -53.838376) (xy 92.1893 -53.84546) (xy 92.189554 -53.845714) (xy 92.189808 -53.845968)
			(xy 92.207421 -53.86688) (xy 92.237075 -53.912814) (xy 92.259865 -53.962513) (xy 92.275322 -54.014957)
			(xy 92.28313 -54.069072) (xy 92.283129 -54.123746) (xy 92.275318 -54.17786) (xy 92.259858 -54.230304)
			(xy 92.237067 -54.280002) (xy 92.20741 -54.325934) (xy 92.189808 -54.346856) (xy 92.189554 -54.34711)
			(xy 92.1893 -54.347364) (xy 92.183722 -54.354457) (xy 92.17747 -54.371369) (xy 92.177108 -54.380384)
			(xy 92.177108 -54.44744) (xy 92.177444 -54.456459) (xy 92.183706 -54.473376) (xy 92.1893 -54.48046)
			(xy 92.189554 -54.480714) (xy 92.189808 -54.480968) (xy 92.2074 -54.501894) (xy 92.237038 -54.547831)
			(xy 92.259815 -54.597529) (xy 92.275262 -54.649969) (xy 92.283066 -54.704078) (xy 92.283534 -54.731412)
			(xy 92.283048 -54.758663) (xy 92.278384 -54.791102) (xy 94.176342 -54.791102) (xy 94.176834 -54.763769)
			(xy 94.184636 -54.709662) (xy 94.20008 -54.657223) (xy 94.22285 -54.607525) (xy 94.25248 -54.561586)
			(xy 94.270068 -54.540658) (xy 94.270322 -54.540404) (xy 94.270576 -54.54015) (xy 94.276157 -54.53306)
			(xy 94.282405 -54.516146) (xy 94.282768 -54.50713) (xy 94.282768 -54.440074) (xy 94.28243 -54.431055)
			(xy 94.27617 -54.414138) (xy 94.270576 -54.407054) (xy 94.270322 -54.4068) (xy 94.270068 -54.406546)
			(xy 94.25247 -54.385622) (xy 94.222817 -54.33969) (xy 94.200028 -54.289993) (xy 94.184571 -54.23755)
			(xy 94.176762 -54.183438) (xy 94.176762 -54.128765) (xy 94.18457 -54.074653) (xy 94.200027 -54.02221)
			(xy 94.222815 -53.972513) (xy 94.252468 -53.92658) (xy 94.270068 -53.905658) (xy 94.270322 -53.905404)
			(xy 94.270576 -53.90515) (xy 94.276157 -53.89806) (xy 94.282405 -53.881146) (xy 94.282768 -53.87213)
			(xy 94.282768 -53.805074) (xy 94.28243 -53.796055) (xy 94.27617 -53.779138) (xy 94.270576 -53.772054)
			(xy 94.270322 -53.7718) (xy 94.270068 -53.771546) (xy 94.25247 -53.750622) (xy 94.222817 -53.70469)
			(xy 94.200028 -53.654993) (xy 94.184571 -53.60255) (xy 94.176762 -53.548438) (xy 94.176762 -53.493765)
			(xy 94.18457 -53.439653) (xy 94.200027 -53.38721) (xy 94.222815 -53.337513) (xy 94.252468 -53.29158)
			(xy 94.270068 -53.270658) (xy 94.270322 -53.270404) (xy 94.270576 -53.27015) (xy 94.276157 -53.26306)
			(xy 94.282405 -53.246146) (xy 94.282768 -53.23713) (xy 94.282768 -53.170074) (xy 94.28243 -53.161055)
			(xy 94.27617 -53.144138) (xy 94.270576 -53.137054) (xy 94.270322 -53.1368) (xy 94.270068 -53.136546)
			(xy 94.252479 -53.115618) (xy 94.222841 -53.069681) (xy 94.200064 -53.019984) (xy 94.184616 -52.967544)
			(xy 94.176811 -52.913436) (xy 94.176342 -52.886102) (xy 94.176828 -52.858851) (xy 94.184584 -52.804903)
			(xy 94.199939 -52.752608) (xy 94.222581 -52.703031) (xy 94.252047 -52.657181) (xy 94.287738 -52.61599)
			(xy 94.328929 -52.580299) (xy 94.374779 -52.550833) (xy 94.424356 -52.528191) (xy 94.476651 -52.512836)
			(xy 94.530599 -52.50508) (xy 94.585101 -52.50508) (xy 94.639049 -52.512836) (xy 94.653367 -52.51704)
			(xy 98.840034 -52.51704) (xy 98.844105 -52.461418) (xy 98.856231 -52.406981) (xy 98.876154 -52.35489)
			(xy 98.90345 -52.306255) (xy 98.937536 -52.262112) (xy 98.977685 -52.223403) (xy 99.023043 -52.190952)
			(xy 99.072643 -52.165451) (xy 99.125427 -52.147444) (xy 99.18027 -52.137314) (xy 99.236004 -52.135277)
			(xy 99.291441 -52.141377) (xy 99.345398 -52.155483) (xy 99.396727 -52.177295) (xy 99.444333 -52.206349)
			(xy 99.487201 -52.242024) (xy 99.524418 -52.283561) (xy 99.555191 -52.330074) (xy 99.578863 -52.380571)
			(xy 99.594931 -52.433978) (xy 99.603051 -52.489154) (xy 99.60356 -52.51704) (xy 99.603051 -52.544926)
			(xy 99.596801 -52.587398) (xy 102.75519 -52.587398) (xy 102.759261 -52.531776) (xy 102.771387 -52.477339)
			(xy 102.79131 -52.425248) (xy 102.818606 -52.376613) (xy 102.852692 -52.33247) (xy 102.892841 -52.293761)
			(xy 102.938199 -52.26131) (xy 102.987799 -52.235809) (xy 103.040583 -52.217802) (xy 103.095426 -52.207672)
			(xy 103.15116 -52.205635) (xy 103.206597 -52.211735) (xy 103.260554 -52.225841) (xy 103.311883 -52.247653)
			(xy 103.359489 -52.276707) (xy 103.402357 -52.312382) (xy 103.439574 -52.353919) (xy 103.470347 -52.400432)
			(xy 103.494019 -52.450929) (xy 103.510087 -52.504336) (xy 103.518207 -52.559512) (xy 103.518292 -52.564153)
			(xy 119.92733 -52.564153) (xy 119.92733 -52.509647) (xy 119.935087 -52.455695) (xy 119.950442 -52.403396)
			(xy 119.973084 -52.353814) (xy 120.002551 -52.30796) (xy 120.038244 -52.266765) (xy 120.079436 -52.231069)
			(xy 120.125288 -52.201598) (xy 120.174868 -52.178953) (xy 120.227165 -52.163593) (xy 120.281117 -52.155832)
			(xy 120.30837 -52.155344) (xy 120.33574 -52.155817) (xy 120.389919 -52.163631) (xy 120.442423 -52.179118)
			(xy 120.49217 -52.201959) (xy 120.538137 -52.231683) (xy 120.559068 -52.249324) (xy 120.559322 -52.249578)
			(xy 120.566391 -52.255189) (xy 120.583322 -52.261419) (xy 120.592342 -52.26177) (xy 120.659398 -52.26177)
			(xy 120.668416 -52.261419) (xy 120.685333 -52.255168) (xy 120.692418 -52.249578) (xy 120.692926 -52.24907)
			(xy 120.713865 -52.231494) (xy 120.759799 -52.201854) (xy 120.809493 -52.179075) (xy 120.861931 -52.163623)
			(xy 120.916037 -52.155815) (xy 120.94337 -52.155344) (xy 120.970621 -52.155901) (xy 121.024568 -52.163654)
			(xy 121.076863 -52.179005) (xy 121.126441 -52.201643) (xy 121.172292 -52.231107) (xy 121.213483 -52.266796)
			(xy 121.249175 -52.307984) (xy 121.278642 -52.353833) (xy 121.301284 -52.403409) (xy 121.31664 -52.455702)
			(xy 121.324397 -52.509649) (xy 121.324397 -52.555953) (xy 122.683979 -52.555953) (xy 122.683979 -52.501447)
			(xy 122.691737 -52.447497) (xy 122.707093 -52.3952) (xy 122.729737 -52.345621) (xy 122.759206 -52.299769)
			(xy 122.794901 -52.258578) (xy 122.836095 -52.222887) (xy 122.881949 -52.193421) (xy 122.93153 -52.170782)
			(xy 122.983828 -52.15543) (xy 123.037779 -52.147677) (xy 123.065032 -52.147216) (xy 123.092403 -52.147659)
			(xy 123.146583 -52.155482) (xy 123.199087 -52.170976) (xy 123.248833 -52.193823) (xy 123.294799 -52.223552)
			(xy 123.31573 -52.241196) (xy 123.315984 -52.24145) (xy 123.323067 -52.247042) (xy 123.339987 -52.253284)
			(xy 123.349004 -52.253642) (xy 123.41606 -52.253642) (xy 123.425076 -52.253278) (xy 123.441994 -52.247037)
			(xy 123.44908 -52.24145) (xy 123.449588 -52.240942) (xy 123.470513 -52.223348) (xy 123.516449 -52.193709)
			(xy 123.566147 -52.170932) (xy 123.618588 -52.155485) (xy 123.672698 -52.147683) (xy 123.700032 -52.147216)
			(xy 123.727283 -52.147656) (xy 123.781231 -52.155417) (xy 123.833525 -52.170776) (xy 123.883102 -52.19342)
			(xy 123.928951 -52.222889) (xy 123.97014 -52.258583) (xy 124.00583 -52.299775) (xy 124.035295 -52.345626)
			(xy 124.057936 -52.395205) (xy 124.07329 -52.4475) (xy 124.081046 -52.501448) (xy 124.081046 -52.555952)
			(xy 124.07329 -52.6099) (xy 124.057936 -52.662195) (xy 124.035295 -52.711774) (xy 124.00583 -52.757625)
			(xy 123.97014 -52.798817) (xy 123.928951 -52.834511) (xy 123.883102 -52.86398) (xy 123.833525 -52.886624)
			(xy 123.781231 -52.901983) (xy 123.727283 -52.909744) (xy 123.700032 -52.910232) (xy 123.672662 -52.909764)
			(xy 123.618482 -52.901949) (xy 123.565978 -52.886461) (xy 123.516231 -52.86362) (xy 123.470265 -52.833894)
			(xy 123.449334 -52.816252) (xy 123.44908 -52.815998) (xy 123.442004 -52.810397) (xy 123.425079 -52.804159)
			(xy 123.41606 -52.803806) (xy 123.349004 -52.803806) (xy 123.339987 -52.804164) (xy 123.32307 -52.810411)
			(xy 123.315984 -52.815998) (xy 123.315476 -52.816506) (xy 123.294533 -52.834077) (xy 123.248601 -52.863719)
			(xy 123.198907 -52.886499) (xy 123.146471 -52.901952) (xy 123.092365 -52.90976) (xy 123.065032 -52.910232)
			(xy 123.037779 -52.909723) (xy 122.983828 -52.90197) (xy 122.93153 -52.886618) (xy 122.881949 -52.863979)
			(xy 122.836095 -52.834513) (xy 122.794901 -52.798822) (xy 122.759206 -52.757631) (xy 122.729737 -52.711779)
			(xy 122.707093 -52.6622) (xy 122.691737 -52.609903) (xy 122.683979 -52.555953) (xy 121.324397 -52.555953)
			(xy 121.324397 -52.564151) (xy 121.31664 -52.618098) (xy 121.301284 -52.670391) (xy 121.278642 -52.719967)
			(xy 121.249175 -52.765816) (xy 121.213483 -52.807004) (xy 121.172292 -52.842693) (xy 121.126441 -52.872157)
			(xy 121.076863 -52.894795) (xy 121.024568 -52.910146) (xy 120.970621 -52.917899) (xy 120.94337 -52.91836)
			(xy 120.915999 -52.917921) (xy 120.861818 -52.910098) (xy 120.809314 -52.894603) (xy 120.759568 -52.871755)
			(xy 120.713602 -52.842024) (xy 120.692672 -52.82438) (xy 120.692418 -52.824126) (xy 120.685337 -52.818532)
			(xy 120.668416 -52.812292) (xy 120.659398 -52.811934) (xy 120.592342 -52.811934) (xy 120.583326 -52.812304)
			(xy 120.566409 -52.818542) (xy 120.559322 -52.824126) (xy 120.558814 -52.824634) (xy 120.537898 -52.842239)
			(xy 120.491958 -52.871874) (xy 120.442258 -52.894647) (xy 120.389815 -52.910093) (xy 120.335705 -52.917893)
			(xy 120.30837 -52.91836) (xy 120.281117 -52.917968) (xy 120.227165 -52.910207) (xy 120.174868 -52.894847)
			(xy 120.125288 -52.872202) (xy 120.079436 -52.842731) (xy 120.038244 -52.807035) (xy 120.002551 -52.76584)
			(xy 119.973084 -52.719986) (xy 119.950442 -52.670404) (xy 119.935087 -52.618105) (xy 119.92733 -52.564153)
			(xy 103.518292 -52.564153) (xy 103.518716 -52.587398) (xy 103.518207 -52.615284) (xy 103.510087 -52.67046)
			(xy 103.494019 -52.723867) (xy 103.470347 -52.774364) (xy 103.439574 -52.820877) (xy 103.402357 -52.862414)
			(xy 103.359489 -52.898089) (xy 103.311883 -52.927143) (xy 103.260554 -52.948955) (xy 103.206597 -52.963061)
			(xy 103.15116 -52.969161) (xy 103.095426 -52.967124) (xy 103.040583 -52.956994) (xy 102.987799 -52.938987)
			(xy 102.938199 -52.913486) (xy 102.892841 -52.881035) (xy 102.852692 -52.842326) (xy 102.818606 -52.798183)
			(xy 102.79131 -52.749548) (xy 102.771387 -52.697457) (xy 102.759261 -52.64302) (xy 102.75519 -52.587398)
			(xy 99.596801 -52.587398) (xy 99.594931 -52.600102) (xy 99.578863 -52.653509) (xy 99.555191 -52.704006)
			(xy 99.524418 -52.750519) (xy 99.487201 -52.792056) (xy 99.444333 -52.827731) (xy 99.396727 -52.856785)
			(xy 99.345398 -52.878597) (xy 99.291441 -52.892703) (xy 99.236004 -52.898803) (xy 99.18027 -52.896766)
			(xy 99.125427 -52.886636) (xy 99.072643 -52.868629) (xy 99.023043 -52.843128) (xy 98.977685 -52.810677)
			(xy 98.937536 -52.771968) (xy 98.90345 -52.727825) (xy 98.876154 -52.67919) (xy 98.856231 -52.627099)
			(xy 98.844105 -52.572662) (xy 98.840034 -52.51704) (xy 94.653367 -52.51704) (xy 94.691344 -52.528191)
			(xy 94.740921 -52.550833) (xy 94.786771 -52.580299) (xy 94.827962 -52.61599) (xy 94.863653 -52.657181)
			(xy 94.893119 -52.703031) (xy 94.915761 -52.752608) (xy 94.931116 -52.804903) (xy 94.938872 -52.858851)
			(xy 94.939358 -52.886102) (xy 94.938868 -52.913435) (xy 94.931066 -52.967542) (xy 94.915621 -53.019981)
			(xy 94.892851 -53.069679) (xy 94.86322 -53.115618) (xy 94.845632 -53.136546) (xy 94.845378 -53.1368)
			(xy 94.845124 -53.137054) (xy 94.839542 -53.144143) (xy 94.833294 -53.161058) (xy 94.832932 -53.170074)
			(xy 94.832932 -53.23713) (xy 94.833268 -53.246149) (xy 94.839529 -53.263066) (xy 94.845124 -53.27015)
			(xy 94.845378 -53.270404) (xy 94.845632 -53.270658) (xy 94.863234 -53.291579) (xy 94.892887 -53.337512)
			(xy 94.915676 -53.387209) (xy 94.931133 -53.439652) (xy 94.938941 -53.493765) (xy 94.938941 -53.548438)
			(xy 94.931132 -53.602551) (xy 94.915675 -53.654993) (xy 94.892886 -53.704691) (xy 94.863232 -53.750624)
			(xy 94.846487 -53.77053) (xy 95.21063 -53.77053) (xy 95.211158 -53.741613) (xy 95.219884 -53.684442)
			(xy 95.237139 -53.629243) (xy 95.262529 -53.577281) (xy 95.295471 -53.529747) (xy 95.335211 -53.48773)
			(xy 95.357696 -53.46954) (xy 95.365074 -53.463249) (xy 95.374873 -53.44654) (xy 95.376746 -53.437028)
			(xy 95.377254 -53.429408) (xy 95.377254 -53.349652) (xy 95.376746 -53.342032) (xy 95.374874 -53.332519)
			(xy 95.365079 -53.315805) (xy 95.357696 -53.30952) (xy 95.335221 -53.291319) (xy 95.295486 -53.249301)
			(xy 95.262546 -53.201768) (xy 95.237156 -53.149809) (xy 95.219898 -53.094613) (xy 95.211166 -53.037445)
			(xy 95.21063 -53.00853) (xy 95.211083 -52.981276) (xy 95.218837 -52.927323) (xy 95.234191 -52.875023)
			(xy 95.256833 -52.82544) (xy 95.286302 -52.779585) (xy 95.321997 -52.738391) (xy 95.363191 -52.702697)
			(xy 95.409047 -52.673229) (xy 95.45863 -52.650589) (xy 95.510931 -52.635236) (xy 95.564884 -52.627483)
			(xy 95.592138 -52.627022) (xy 95.592392 -52.627022) (xy 95.618687 -52.627479) (xy 95.670776 -52.634724)
			(xy 95.721378 -52.64905) (xy 95.769534 -52.670185) (xy 95.814333 -52.697731) (xy 95.854928 -52.731165)
			(xy 95.873062 -52.750212) (xy 95.880647 -52.757637) (xy 95.900055 -52.766171) (xy 95.910654 -52.766722)
			(xy 95.984822 -52.766722) (xy 95.995454 -52.76631) (xy 96.014918 -52.757762) (xy 96.022414 -52.750212)
			(xy 96.040529 -52.731143) (xy 96.081114 -52.697687) (xy 96.125913 -52.670129) (xy 96.174076 -52.648992)
			(xy 96.224687 -52.634678) (xy 96.276786 -52.627458) (xy 96.303084 -52.627022) (xy 96.303338 -52.627022)
			(xy 96.330592 -52.627443) (xy 96.384543 -52.635205) (xy 96.436841 -52.650566) (xy 96.48642 -52.673214)
			(xy 96.532272 -52.702687) (xy 96.573463 -52.738386) (xy 96.609154 -52.779583) (xy 96.638618 -52.825439)
			(xy 96.661257 -52.875023) (xy 96.676609 -52.927323) (xy 96.684362 -52.981276) (xy 96.684846 -53.00853)
			(xy 96.684382 -53.036197) (xy 96.682151 -53.051456) (xy 104.941114 -53.051456) (xy 104.945185 -52.995834)
			(xy 104.957311 -52.941397) (xy 104.977234 -52.889306) (xy 105.00453 -52.840671) (xy 105.038616 -52.796528)
			(xy 105.078765 -52.757819) (xy 105.124123 -52.725368) (xy 105.173723 -52.699867) (xy 105.226507 -52.68186)
			(xy 105.28135 -52.67173) (xy 105.337084 -52.669693) (xy 105.392521 -52.675793) (xy 105.446478 -52.689899)
			(xy 105.497807 -52.711711) (xy 105.545413 -52.740765) (xy 105.588281 -52.77644) (xy 105.625498 -52.817977)
			(xy 105.656271 -52.86449) (xy 105.679943 -52.914987) (xy 105.696011 -52.968394) (xy 105.704131 -53.02357)
			(xy 105.70464 -53.051456) (xy 105.704131 -53.079342) (xy 105.696011 -53.134518) (xy 105.679943 -53.187925)
			(xy 105.656271 -53.238422) (xy 105.625498 -53.284935) (xy 105.588281 -53.326472) (xy 105.545413 -53.362147)
			(xy 105.497807 -53.391201) (xy 105.446478 -53.413013) (xy 105.392521 -53.427119) (xy 105.337084 -53.433219)
			(xy 105.28135 -53.431182) (xy 105.226507 -53.421052) (xy 105.173723 -53.403045) (xy 105.124123 -53.377544)
			(xy 105.078765 -53.345093) (xy 105.038616 -53.306384) (xy 105.00453 -53.262241) (xy 104.977234 -53.213606)
			(xy 104.957311 -53.161515) (xy 104.945185 -53.107078) (xy 104.941114 -53.051456) (xy 96.682151 -53.051456)
			(xy 96.676377 -53.09095) (xy 96.660554 -53.143973) (xy 96.637244 -53.194158) (xy 96.606934 -53.240454)
			(xy 96.570261 -53.28189) (xy 96.527991 -53.317599) (xy 96.50476 -53.332634) (xy 96.504506 -53.332888)
			(xy 96.494983 -53.339556) (xy 96.482674 -53.359248) (xy 96.480884 -53.370734) (xy 96.47301 -53.450744)
			(xy 96.472343 -53.462445) (xy 96.480425 -53.484417) (xy 96.488504 -53.492908) (xy 96.488758 -53.492908)
			(xy 96.507317 -53.511011) (xy 96.5399 -53.551337) (xy 96.566716 -53.595706) (xy 96.587273 -53.643301)
			(xy 96.601191 -53.693242) (xy 96.608212 -53.744608) (xy 96.608646 -53.77053) (xy 96.60815 -53.79778)
			(xy 96.600391 -53.851726) (xy 96.585034 -53.904018) (xy 96.562392 -53.953593) (xy 96.532926 -53.999441)
			(xy 96.497236 -54.04063) (xy 96.456048 -54.076321) (xy 96.4102 -54.105788) (xy 96.360625 -54.128431)
			(xy 96.308333 -54.143789) (xy 96.254388 -54.15155) (xy 96.227138 -54.152038) (xy 96.199768 -54.151565)
			(xy 96.145588 -54.143751) (xy 96.093085 -54.128264) (xy 96.043338 -54.105424) (xy 95.997371 -54.075699)
			(xy 95.97644 -54.058058) (xy 95.976186 -54.057804) (xy 95.969107 -54.052206) (xy 95.952185 -54.045966)
			(xy 95.943166 -54.045612) (xy 95.87611 -54.045612) (xy 95.867093 -54.045971) (xy 95.850176 -54.052217)
			(xy 95.84309 -54.057804) (xy 95.842582 -54.058312) (xy 95.821675 -54.075928) (xy 95.775733 -54.105563)
			(xy 95.72603 -54.128334) (xy 95.673586 -54.143776) (xy 95.619474 -54.151573) (xy 95.592138 -54.152038)
			(xy 95.564887 -54.151509) (xy 95.51094 -54.143758) (xy 95.458646 -54.128409) (xy 95.409068 -54.105773)
			(xy 95.363216 -54.076312) (xy 95.322023 -54.040625) (xy 95.286329 -53.999439) (xy 95.25686 -53.953592)
			(xy 95.234215 -53.904018) (xy 95.218856 -53.851726) (xy 95.211095 -53.79778) (xy 95.21063 -53.77053)
			(xy 94.846487 -53.77053) (xy 94.845632 -53.771546) (xy 94.845378 -53.7718) (xy 94.845124 -53.772054)
			(xy 94.839542 -53.779143) (xy 94.833294 -53.796058) (xy 94.832932 -53.805074) (xy 94.832932 -53.87213)
			(xy 94.833268 -53.881149) (xy 94.839529 -53.898066) (xy 94.845124 -53.90515) (xy 94.845378 -53.905404)
			(xy 94.845632 -53.905658) (xy 94.863234 -53.926579) (xy 94.892887 -53.972512) (xy 94.915676 -54.022209)
			(xy 94.931133 -54.074652) (xy 94.938941 -54.128765) (xy 94.938941 -54.183438) (xy 94.931132 -54.237551)
			(xy 94.915675 -54.289993) (xy 94.90183 -54.320186) (xy 97.130362 -54.320186) (xy 97.13084 -54.292852)
			(xy 97.138644 -54.238745) (xy 97.154091 -54.186306) (xy 97.176865 -54.136608) (xy 97.206498 -54.090669)
			(xy 97.224088 -54.069742) (xy 97.224342 -54.069488) (xy 97.224596 -54.069234) (xy 97.230174 -54.062142)
			(xy 97.236426 -54.045229) (xy 97.236788 -54.036214) (xy 97.236788 -53.969158) (xy 97.236406 -53.960144)
			(xy 97.230176 -53.943226) (xy 97.224596 -53.936138) (xy 97.224342 -53.935884) (xy 97.224088 -53.93563)
			(xy 97.206494 -53.914705) (xy 97.176857 -53.868768) (xy 97.154081 -53.81907) (xy 97.138633 -53.766629)
			(xy 97.13083 -53.71252) (xy 97.130362 -53.685186) (xy 97.130848 -53.657935) (xy 97.138604 -53.603987)
			(xy 97.153959 -53.551692) (xy 97.176601 -53.502115) (xy 97.206067 -53.456265) (xy 97.241758 -53.415074)
			(xy 97.282949 -53.379383) (xy 97.328799 -53.349917) (xy 97.378376 -53.327275) (xy 97.430671 -53.31192)
			(xy 97.484619 -53.304164) (xy 97.539121 -53.304164) (xy 97.593069 -53.31192) (xy 97.645364 -53.327275)
			(xy 97.694941 -53.349917) (xy 97.740791 -53.379383) (xy 97.781982 -53.415074) (xy 97.817673 -53.456265)
			(xy 97.843564 -53.496552) (xy 122.233664 -53.496552) (xy 122.233664 -53.442048) (xy 122.24142 -53.388099)
			(xy 122.256776 -53.335803) (xy 122.279417 -53.286225) (xy 122.308883 -53.240374) (xy 122.344575 -53.199182)
			(xy 122.385766 -53.163489) (xy 122.431616 -53.134022) (xy 122.481194 -53.111379) (xy 122.53349 -53.096022)
			(xy 122.587438 -53.088264) (xy 122.61469 -53.087778) (xy 122.642061 -53.088231) (xy 122.696241 -53.096049)
			(xy 122.748745 -53.11154) (xy 122.798492 -53.134385) (xy 122.844458 -53.164114) (xy 122.865388 -53.181758)
			(xy 122.865642 -53.182012) (xy 122.87274 -53.187582) (xy 122.889648 -53.193838) (xy 122.898662 -53.194204)
			(xy 122.965718 -53.194204) (xy 122.974736 -53.193855) (xy 122.991652 -53.187602) (xy 122.998738 -53.182012)
			(xy 122.999246 -53.181504) (xy 123.020182 -53.163924) (xy 123.066116 -53.134284) (xy 123.115811 -53.111505)
			(xy 123.168249 -53.096054) (xy 123.222356 -53.088248) (xy 123.24969 -53.087778) (xy 123.276942 -53.088269)
			(xy 123.330892 -53.096024) (xy 123.383189 -53.111379) (xy 123.432769 -53.13402) (xy 123.478622 -53.163486)
			(xy 123.519814 -53.199179) (xy 123.555508 -53.24037) (xy 123.584975 -53.286222) (xy 123.607618 -53.335801)
			(xy 123.622974 -53.388098) (xy 123.630731 -53.442048) (xy 123.630731 -53.496552) (xy 123.622974 -53.550502)
			(xy 123.607618 -53.602799) (xy 123.584975 -53.652378) (xy 123.555508 -53.69823) (xy 123.519814 -53.739421)
			(xy 123.478622 -53.775114) (xy 123.432769 -53.80458) (xy 123.383189 -53.827221) (xy 123.330892 -53.842576)
			(xy 123.276942 -53.850331) (xy 123.24969 -53.850794) (xy 123.222319 -53.850335) (xy 123.16814 -53.842516)
			(xy 123.115637 -53.827025) (xy 123.06589 -53.804182) (xy 123.019924 -53.774456) (xy 122.998992 -53.756814)
			(xy 122.998738 -53.75656) (xy 122.991648 -53.750978) (xy 122.974734 -53.74473) (xy 122.965718 -53.744368)
			(xy 122.898662 -53.744368) (xy 122.889644 -53.744714) (xy 122.872728 -53.75097) (xy 122.865642 -53.75656)
			(xy 122.865134 -53.757068) (xy 122.844202 -53.774653) (xy 122.798267 -53.804294) (xy 122.748571 -53.827072)
			(xy 122.696132 -53.842521) (xy 122.642024 -53.850325) (xy 122.61469 -53.850794) (xy 122.587438 -53.850336)
			(xy 122.53349 -53.842578) (xy 122.481194 -53.827221) (xy 122.431616 -53.804578) (xy 122.385766 -53.775111)
			(xy 122.344575 -53.739418) (xy 122.308883 -53.698226) (xy 122.279417 -53.652375) (xy 122.256776 -53.602797)
			(xy 122.24142 -53.550501) (xy 122.233664 -53.496552) (xy 97.843564 -53.496552) (xy 97.847139 -53.502115)
			(xy 97.869781 -53.551692) (xy 97.885136 -53.603987) (xy 97.892892 -53.657935) (xy 97.893378 -53.685186)
			(xy 97.892933 -53.712521) (xy 97.885119 -53.766629) (xy 97.869664 -53.819068) (xy 97.846883 -53.868766)
			(xy 97.817244 -53.914703) (xy 97.799652 -53.93563) (xy 97.799398 -53.935884) (xy 97.799144 -53.936138)
			(xy 97.793571 -53.943233) (xy 97.787317 -53.960144) (xy 97.786952 -53.969158) (xy 97.786952 -54.036214)
			(xy 97.787291 -54.045233) (xy 97.79355 -54.06215) (xy 97.799144 -54.069234) (xy 97.799398 -54.069488)
			(xy 97.799652 -54.069742) (xy 97.817223 -54.090685) (xy 97.846866 -54.136616) (xy 97.869648 -54.18631)
			(xy 97.8851 -54.238747) (xy 97.892908 -54.292853) (xy 97.893378 -54.320186) (xy 97.892892 -54.347437)
			(xy 97.885136 -54.401385) (xy 97.869781 -54.45368) (xy 97.847139 -54.503257) (xy 97.817673 -54.549107)
			(xy 97.781982 -54.590298) (xy 97.740791 -54.625989) (xy 97.694941 -54.655455) (xy 97.645364 -54.678097)
			(xy 97.593069 -54.693452) (xy 97.539121 -54.701208) (xy 97.484619 -54.701208) (xy 97.430671 -54.693452)
			(xy 97.378376 -54.678097) (xy 97.328799 -54.655455) (xy 97.282949 -54.625989) (xy 97.241758 -54.590298)
			(xy 97.206067 -54.549107) (xy 97.176601 -54.503257) (xy 97.153959 -54.45368) (xy 97.138604 -54.401385)
			(xy 97.130848 -54.347437) (xy 97.130362 -54.320186) (xy 94.90183 -54.320186) (xy 94.892886 -54.339691)
			(xy 94.863232 -54.385624) (xy 94.845632 -54.406546) (xy 94.845378 -54.4068) (xy 94.845124 -54.407054)
			(xy 94.839542 -54.414143) (xy 94.833294 -54.431058) (xy 94.832932 -54.440074) (xy 94.832932 -54.50713)
			(xy 94.833268 -54.516149) (xy 94.839529 -54.533066) (xy 94.845124 -54.54015) (xy 94.845378 -54.540404)
			(xy 94.845632 -54.540658) (xy 94.863223 -54.561585) (xy 94.892861 -54.607522) (xy 94.915637 -54.65722)
			(xy 94.931085 -54.70966) (xy 94.938889 -54.763768) (xy 94.939005 -54.770528) (xy 98.070924 -54.770528)
			(xy 98.071377 -54.743194) (xy 98.079189 -54.689086) (xy 98.094642 -54.636646) (xy 98.117421 -54.586949)
			(xy 98.147058 -54.541011) (xy 98.16465 -54.520084) (xy 98.164904 -54.51983) (xy 98.165158 -54.519576)
			(xy 98.170768 -54.512505) (xy 98.176999 -54.495576) (xy 98.17735 -54.486556) (xy 98.17735 -54.4195)
			(xy 98.177004 -54.410482) (xy 98.17075 -54.393564) (xy 98.165158 -54.38648) (xy 98.164904 -54.386226)
			(xy 98.16465 -54.385972) (xy 98.14707 -54.365036) (xy 98.117432 -54.319101) (xy 98.094654 -54.269406)
			(xy 98.079203 -54.216968) (xy 98.071395 -54.162861) (xy 98.070924 -54.135528) (xy 98.07141 -54.108277)
			(xy 98.079166 -54.054329) (xy 98.094521 -54.002034) (xy 98.117163 -53.952457) (xy 98.146629 -53.906607)
			(xy 98.18232 -53.865416) (xy 98.223511 -53.829725) (xy 98.269361 -53.800259) (xy 98.318938 -53.777617)
			(xy 98.371233 -53.762262) (xy 98.425181 -53.754506) (xy 98.479683 -53.754506) (xy 98.533631 -53.762262)
			(xy 98.585926 -53.777617) (xy 98.635503 -53.800259) (xy 98.681353 -53.829725) (xy 98.722544 -53.865416)
			(xy 98.758235 -53.906607) (xy 98.787701 -53.952457) (xy 98.792776 -53.96357) (xy 102.771954 -53.96357)
			(xy 102.776025 -53.907948) (xy 102.788151 -53.853511) (xy 102.808074 -53.80142) (xy 102.83537 -53.752785)
			(xy 102.869456 -53.708642) (xy 102.909605 -53.669933) (xy 102.954963 -53.637482) (xy 103.004563 -53.611981)
			(xy 103.057347 -53.593974) (xy 103.11219 -53.583844) (xy 103.167924 -53.581807) (xy 103.223361 -53.587907)
			(xy 103.277318 -53.602013) (xy 103.328647 -53.623825) (xy 103.376253 -53.652879) (xy 103.419121 -53.688554)
			(xy 103.456338 -53.730091) (xy 103.487111 -53.776604) (xy 103.510783 -53.827101) (xy 103.526851 -53.880508)
			(xy 103.534971 -53.935684) (xy 103.53548 -53.96357) (xy 103.534971 -53.991456) (xy 103.526851 -54.046632)
			(xy 103.520586 -54.067456) (xy 104.941114 -54.067456) (xy 104.945185 -54.011834) (xy 104.957311 -53.957397)
			(xy 104.977234 -53.905306) (xy 105.00453 -53.856671) (xy 105.038616 -53.812528) (xy 105.078765 -53.773819)
			(xy 105.124123 -53.741368) (xy 105.173723 -53.715867) (xy 105.226507 -53.69786) (xy 105.28135 -53.68773)
			(xy 105.337084 -53.685693) (xy 105.392521 -53.691793) (xy 105.446478 -53.705899) (xy 105.497807 -53.727711)
			(xy 105.545413 -53.756765) (xy 105.588281 -53.79244) (xy 105.625498 -53.833977) (xy 105.656271 -53.88049)
			(xy 105.679943 -53.930987) (xy 105.696011 -53.984394) (xy 105.704131 -54.03957) (xy 105.70464 -54.067456)
			(xy 105.704131 -54.095342) (xy 105.696011 -54.150518) (xy 105.679943 -54.203925) (xy 105.663545 -54.238906)
			(xy 124.48616 -54.238906) (xy 124.490231 -54.183284) (xy 124.502357 -54.128847) (xy 124.52228 -54.076756)
			(xy 124.549576 -54.028121) (xy 124.583662 -53.983978) (xy 124.623811 -53.945269) (xy 124.669169 -53.912818)
			(xy 124.718769 -53.887317) (xy 124.771553 -53.86931) (xy 124.826396 -53.85918) (xy 124.88213 -53.857143)
			(xy 124.937567 -53.863243) (xy 124.991524 -53.877349) (xy 125.042853 -53.899161) (xy 125.090459 -53.928215)
			(xy 125.133327 -53.96389) (xy 125.170544 -54.005427) (xy 125.201317 -54.05194) (xy 125.224989 -54.102437)
			(xy 125.241057 -54.155844) (xy 125.249177 -54.21102) (xy 125.249686 -54.238906) (xy 125.249177 -54.266792)
			(xy 125.241057 -54.321968) (xy 125.224989 -54.375375) (xy 125.201317 -54.425872) (xy 125.170544 -54.472385)
			(xy 125.133327 -54.513922) (xy 125.090459 -54.549597) (xy 125.042853 -54.578651) (xy 124.991524 -54.600463)
			(xy 124.937567 -54.614569) (xy 124.88213 -54.620669) (xy 124.826396 -54.618632) (xy 124.771553 -54.608502)
			(xy 124.718769 -54.590495) (xy 124.669169 -54.564994) (xy 124.623811 -54.532543) (xy 124.583662 -54.493834)
			(xy 124.549576 -54.449691) (xy 124.52228 -54.401056) (xy 124.502357 -54.348965) (xy 124.490231 -54.294528)
			(xy 124.48616 -54.238906) (xy 105.663545 -54.238906) (xy 105.656271 -54.254422) (xy 105.625498 -54.300935)
			(xy 105.588281 -54.342472) (xy 105.545413 -54.378147) (xy 105.497807 -54.407201) (xy 105.446478 -54.429013)
			(xy 105.392521 -54.443119) (xy 105.337084 -54.449219) (xy 105.28135 -54.447182) (xy 105.226507 -54.437052)
			(xy 105.173723 -54.419045) (xy 105.124123 -54.393544) (xy 105.078765 -54.361093) (xy 105.038616 -54.322384)
			(xy 105.00453 -54.278241) (xy 104.977234 -54.229606) (xy 104.957311 -54.177515) (xy 104.945185 -54.123078)
			(xy 104.941114 -54.067456) (xy 103.520586 -54.067456) (xy 103.510783 -54.100039) (xy 103.487111 -54.150536)
			(xy 103.456338 -54.197049) (xy 103.419121 -54.238586) (xy 103.376253 -54.274261) (xy 103.328647 -54.303315)
			(xy 103.277318 -54.325127) (xy 103.223361 -54.339233) (xy 103.167924 -54.345333) (xy 103.11219 -54.343296)
			(xy 103.057347 -54.333166) (xy 103.004563 -54.315159) (xy 102.954963 -54.289658) (xy 102.909605 -54.257207)
			(xy 102.869456 -54.218498) (xy 102.83537 -54.174355) (xy 102.808074 -54.12572) (xy 102.788151 -54.073629)
			(xy 102.776025 -54.019192) (xy 102.771954 -53.96357) (xy 98.792776 -53.96357) (xy 98.810343 -54.002034)
			(xy 98.825698 -54.054329) (xy 98.833454 -54.108277) (xy 98.83394 -54.135528) (xy 98.83347 -54.162862)
			(xy 98.825664 -54.216969) (xy 98.810215 -54.269409) (xy 98.78744 -54.319107) (xy 98.757805 -54.365045)
			(xy 98.740214 -54.385972) (xy 98.73996 -54.386226) (xy 98.739706 -54.38648) (xy 98.734122 -54.393569)
			(xy 98.727874 -54.410484) (xy 98.727514 -54.4195) (xy 98.727514 -54.486556) (xy 98.727889 -54.495571)
			(xy 98.734124 -54.512488) (xy 98.739706 -54.519576) (xy 98.73996 -54.51983) (xy 98.740214 -54.520084)
			(xy 98.757815 -54.541003) (xy 98.787451 -54.586942) (xy 98.810226 -54.636642) (xy 98.825672 -54.689084)
			(xy 98.833473 -54.743193) (xy 98.83394 -54.770528) (xy 98.833454 -54.797779) (xy 98.825698 -54.851727)
			(xy 98.810343 -54.904022) (xy 98.787701 -54.953599) (xy 98.758235 -54.999449) (xy 98.722544 -55.04064)
			(xy 98.681353 -55.076331) (xy 98.670266 -55.083456) (xy 104.941114 -55.083456) (xy 104.945185 -55.027834)
			(xy 104.957311 -54.973397) (xy 104.977234 -54.921306) (xy 105.00453 -54.872671) (xy 105.038616 -54.828528)
			(xy 105.078765 -54.789819) (xy 105.124123 -54.757368) (xy 105.173723 -54.731867) (xy 105.226507 -54.71386)
			(xy 105.28135 -54.70373) (xy 105.337084 -54.701693) (xy 105.392521 -54.707793) (xy 105.446478 -54.721899)
			(xy 105.497807 -54.743711) (xy 105.545413 -54.772765) (xy 105.588281 -54.80844) (xy 105.625498 -54.849977)
			(xy 105.656271 -54.89649) (xy 105.679943 -54.946987) (xy 105.692598 -54.989051) (xy 120.001268 -54.989051)
			(xy 120.001268 -54.934549) (xy 120.009024 -54.880601) (xy 120.024379 -54.828306) (xy 120.047019 -54.778729)
			(xy 120.076485 -54.732878) (xy 120.112176 -54.691687) (xy 120.153365 -54.655995) (xy 120.199215 -54.626527)
			(xy 120.248791 -54.603884) (xy 120.301085 -54.588527) (xy 120.355033 -54.580769) (xy 120.382284 -54.580282)
			(xy 120.410375 -54.58079) (xy 120.465952 -54.589014) (xy 120.51972 -54.605303) (xy 120.570518 -54.629304)
			(xy 120.617245 -54.660497) (xy 120.65889 -54.698207) (xy 120.694553 -54.741618) (xy 120.709436 -54.765448)
			(xy 120.715024 -54.774592) (xy 120.732042 -54.786784) (xy 120.825006 -54.80685) (xy 120.84558 -54.802786)
			(xy 120.854216 -54.79669) (xy 120.878273 -54.78068) (xy 120.930207 -54.75534) (xy 120.985367 -54.738117)
			(xy 121.042493 -54.729405) (xy 121.071386 -54.728872) (xy 121.098636 -54.729391) (xy 121.112696 -54.731412)
			(xy 129.620772 -54.731412) (xy 129.621204 -54.704077) (xy 129.629019 -54.649967) (xy 129.644477 -54.597527)
			(xy 129.66726 -54.54783) (xy 129.696904 -54.501894) (xy 129.714498 -54.480968) (xy 129.714752 -54.480714)
			(xy 129.715006 -54.48046) (xy 129.720574 -54.473361) (xy 129.726832 -54.456454) (xy 129.727198 -54.44744)
			(xy 129.727198 -54.380384) (xy 129.726849 -54.371366) (xy 129.720596 -54.354449) (xy 129.715006 -54.347364)
			(xy 129.714752 -54.34711) (xy 129.714498 -54.346856) (xy 129.696908 -54.325925) (xy 129.667252 -54.279994)
			(xy 129.644461 -54.230299) (xy 129.629002 -54.177857) (xy 129.621192 -54.123745) (xy 129.62119 -54.069073)
			(xy 129.628998 -54.014961) (xy 129.644455 -53.962518) (xy 129.667244 -53.912822) (xy 129.696897 -53.866889)
			(xy 129.714498 -53.845968) (xy 129.714752 -53.845714) (xy 129.715006 -53.84546) (xy 129.720574 -53.838361)
			(xy 129.726832 -53.821454) (xy 129.727198 -53.81244) (xy 129.727198 -53.745384) (xy 129.726849 -53.736366)
			(xy 129.720596 -53.719449) (xy 129.715006 -53.712364) (xy 129.714752 -53.71211) (xy 129.714498 -53.711856)
			(xy 129.696908 -53.690925) (xy 129.667252 -53.644994) (xy 129.644461 -53.595299) (xy 129.629002 -53.542857)
			(xy 129.621192 -53.488745) (xy 129.62119 -53.434073) (xy 129.628998 -53.379961) (xy 129.644455 -53.327518)
			(xy 129.667244 -53.277822) (xy 129.696897 -53.231889) (xy 129.714498 -53.210968) (xy 129.714752 -53.210714)
			(xy 129.715006 -53.21046) (xy 129.720574 -53.203361) (xy 129.726832 -53.186454) (xy 129.727198 -53.17744)
			(xy 129.727198 -53.110384) (xy 129.726849 -53.101366) (xy 129.720596 -53.084449) (xy 129.715006 -53.077364)
			(xy 129.714752 -53.07711) (xy 129.714498 -53.076856) (xy 129.696918 -53.05592) (xy 129.667278 -53.009986)
			(xy 129.644499 -52.960291) (xy 129.629048 -52.907852) (xy 129.621242 -52.853746) (xy 129.620772 -52.826412)
			(xy 129.621258 -52.799161) (xy 129.629014 -52.745213) (xy 129.644369 -52.692918) (xy 129.667011 -52.643341)
			(xy 129.696477 -52.597491) (xy 129.732168 -52.5563) (xy 129.773359 -52.520609) (xy 129.819209 -52.491143)
			(xy 129.868786 -52.468501) (xy 129.921081 -52.453146) (xy 129.975029 -52.44539) (xy 130.029531 -52.44539)
			(xy 130.083479 -52.453146) (xy 130.135774 -52.468501) (xy 130.185351 -52.491143) (xy 130.231201 -52.520609)
			(xy 130.272392 -52.5563) (xy 130.308083 -52.597491) (xy 130.337549 -52.643341) (xy 130.360191 -52.692918)
			(xy 130.375546 -52.745213) (xy 130.383302 -52.799161) (xy 130.383788 -52.826412) (xy 130.383297 -52.853745)
			(xy 130.375494 -52.907851) (xy 130.360049 -52.96029) (xy 130.337279 -53.009988) (xy 130.30765 -53.055928)
			(xy 130.290062 -53.076856) (xy 130.289808 -53.07711) (xy 130.289554 -53.077364) (xy 130.283971 -53.084453)
			(xy 130.277723 -53.101368) (xy 130.277362 -53.110384) (xy 130.277362 -53.17744) (xy 130.277708 -53.186458)
			(xy 130.283964 -53.203374) (xy 130.289554 -53.21046) (xy 130.289808 -53.210714) (xy 130.290062 -53.210968)
			(xy 130.307673 -53.231881) (xy 130.337323 -53.277817) (xy 130.360109 -53.327515) (xy 130.375564 -53.379959)
			(xy 130.383371 -53.434072) (xy 130.383369 -53.488746) (xy 130.37556 -53.542859) (xy 130.360103 -53.595302)
			(xy 130.337314 -53.644999) (xy 130.307662 -53.690933) (xy 130.290062 -53.711856) (xy 130.289808 -53.71211)
			(xy 130.289554 -53.712364) (xy 130.283971 -53.719453) (xy 130.277723 -53.736368) (xy 130.277362 -53.745384)
			(xy 130.277362 -53.81244) (xy 130.277708 -53.821458) (xy 130.283964 -53.838374) (xy 130.289554 -53.84546)
			(xy 130.289808 -53.845714) (xy 130.290062 -53.845968) (xy 130.307673 -53.866881) (xy 130.337323 -53.912817)
			(xy 130.360109 -53.962515) (xy 130.375564 -54.014959) (xy 130.383371 -54.069072) (xy 130.383369 -54.123746)
			(xy 130.37556 -54.177859) (xy 130.360103 -54.230302) (xy 130.337314 -54.279999) (xy 130.307662 -54.325933)
			(xy 130.290062 -54.346856) (xy 130.289808 -54.34711) (xy 130.289554 -54.347364) (xy 130.283971 -54.354453)
			(xy 130.277723 -54.371368) (xy 130.277362 -54.380384) (xy 130.277362 -54.44744) (xy 130.277708 -54.456458)
			(xy 130.283964 -54.473374) (xy 130.289554 -54.48046) (xy 130.289808 -54.480714) (xy 130.290062 -54.480968)
			(xy 130.307647 -54.5019) (xy 130.337288 -54.547835) (xy 130.360066 -54.597531) (xy 130.375516 -54.64997)
			(xy 130.383319 -54.704078) (xy 130.383788 -54.731412) (xy 130.383302 -54.758663) (xy 130.378638 -54.791102)
			(xy 132.276596 -54.791102) (xy 132.277099 -54.76377) (xy 132.2849 -54.709664) (xy 132.300342 -54.657225)
			(xy 132.323109 -54.607527) (xy 132.352736 -54.561587) (xy 132.370322 -54.540658) (xy 132.370576 -54.540404)
			(xy 132.37083 -54.54015) (xy 132.376405 -54.533056) (xy 132.382658 -54.516145) (xy 132.383022 -54.50713)
			(xy 132.383022 -54.440074) (xy 132.382673 -54.431056) (xy 132.376419 -54.41414) (xy 132.37083 -54.407054)
			(xy 132.370576 -54.4068) (xy 132.370322 -54.406546) (xy 132.352726 -54.385621) (xy 132.323076 -54.339688)
			(xy 132.30029 -54.289991) (xy 132.284835 -54.237549) (xy 132.277027 -54.183437) (xy 132.277027 -54.128766)
			(xy 132.284834 -54.074654) (xy 132.300289 -54.022212) (xy 132.323075 -53.972515) (xy 132.352724 -53.926581)
			(xy 132.370322 -53.905658) (xy 132.370576 -53.905404) (xy 132.37083 -53.90515) (xy 132.376405 -53.898056)
			(xy 132.382658 -53.881145) (xy 132.383022 -53.87213) (xy 132.383022 -53.805074) (xy 132.382673 -53.796056)
			(xy 132.376419 -53.77914) (xy 132.37083 -53.772054) (xy 132.370576 -53.7718) (xy 132.370322 -53.771546)
			(xy 132.352726 -53.750621) (xy 132.323076 -53.704688) (xy 132.30029 -53.654991) (xy 132.284835 -53.602549)
			(xy 132.277027 -53.548437) (xy 132.277027 -53.493766) (xy 132.284834 -53.439654) (xy 132.300289 -53.387212)
			(xy 132.323075 -53.337515) (xy 132.352724 -53.291581) (xy 132.370322 -53.270658) (xy 132.370576 -53.270404)
			(xy 132.37083 -53.27015) (xy 132.376405 -53.263056) (xy 132.382658 -53.246145) (xy 132.383022 -53.23713)
			(xy 132.383022 -53.170074) (xy 132.382673 -53.161056) (xy 132.376419 -53.14414) (xy 132.37083 -53.137054)
			(xy 132.370576 -53.1368) (xy 132.370322 -53.136546) (xy 132.352741 -53.115611) (xy 132.3231 -53.069677)
			(xy 132.300321 -53.019981) (xy 132.284871 -52.967543) (xy 132.277066 -52.913436) (xy 132.276596 -52.886102)
			(xy 132.277082 -52.858851) (xy 132.284838 -52.804903) (xy 132.300193 -52.752608) (xy 132.322835 -52.703031)
			(xy 132.352301 -52.657181) (xy 132.387992 -52.61599) (xy 132.429183 -52.580299) (xy 132.475033 -52.550833)
			(xy 132.52461 -52.528191) (xy 132.576905 -52.512836) (xy 132.630853 -52.50508) (xy 132.685355 -52.50508)
			(xy 132.739303 -52.512836) (xy 132.753621 -52.51704) (xy 136.940288 -52.51704) (xy 136.944359 -52.461418)
			(xy 136.956485 -52.406981) (xy 136.976408 -52.35489) (xy 137.003704 -52.306255) (xy 137.03779 -52.262112)
			(xy 137.077939 -52.223403) (xy 137.123297 -52.190952) (xy 137.172897 -52.165451) (xy 137.225681 -52.147444)
			(xy 137.280524 -52.137314) (xy 137.336258 -52.135277) (xy 137.391695 -52.141377) (xy 137.445652 -52.155483)
			(xy 137.496981 -52.177295) (xy 137.544587 -52.206349) (xy 137.587455 -52.242024) (xy 137.624672 -52.283561)
			(xy 137.655445 -52.330074) (xy 137.679117 -52.380571) (xy 137.695185 -52.433978) (xy 137.703305 -52.489154)
			(xy 137.703814 -52.51704) (xy 137.703305 -52.544926) (xy 137.697055 -52.587398) (xy 140.855444 -52.587398)
			(xy 140.859515 -52.531776) (xy 140.871641 -52.477339) (xy 140.891564 -52.425248) (xy 140.91886 -52.376613)
			(xy 140.952946 -52.33247) (xy 140.993095 -52.293761) (xy 141.038453 -52.26131) (xy 141.088053 -52.235809)
			(xy 141.140837 -52.217802) (xy 141.19568 -52.207672) (xy 141.251414 -52.205635) (xy 141.306851 -52.211735)
			(xy 141.360808 -52.225841) (xy 141.412137 -52.247653) (xy 141.459743 -52.276707) (xy 141.502611 -52.312382)
			(xy 141.539828 -52.353919) (xy 141.570601 -52.400432) (xy 141.594273 -52.450929) (xy 141.610341 -52.504336)
			(xy 141.618461 -52.559512) (xy 141.618546 -52.564157) (xy 145.927207 -52.564157) (xy 145.927207 -52.509643)
			(xy 145.934965 -52.455684) (xy 145.950324 -52.403378) (xy 145.972971 -52.35379) (xy 146.002444 -52.30793)
			(xy 146.038145 -52.266732) (xy 146.079345 -52.231034) (xy 146.125206 -52.201562) (xy 146.174794 -52.178918)
			(xy 146.227101 -52.163562) (xy 146.281061 -52.155806) (xy 146.308318 -52.155344) (xy 146.335689 -52.155789)
			(xy 146.38987 -52.16361) (xy 146.442373 -52.179104) (xy 146.49212 -52.20195) (xy 146.538085 -52.23168)
			(xy 146.559016 -52.249324) (xy 146.55927 -52.249578) (xy 146.566354 -52.255167) (xy 146.583273 -52.26141)
			(xy 146.59229 -52.26177) (xy 146.659346 -52.26177) (xy 146.668361 -52.261394) (xy 146.685278 -52.25516)
			(xy 146.692366 -52.249578) (xy 146.692874 -52.24907) (xy 146.713795 -52.231472) (xy 146.759734 -52.201835)
			(xy 146.809433 -52.17906) (xy 146.861874 -52.163614) (xy 146.915984 -52.155812) (xy 146.943318 -52.155344)
			(xy 146.970565 -52.155927) (xy 147.024504 -52.163685) (xy 147.07679 -52.17904) (xy 147.126358 -52.201679)
			(xy 147.172201 -52.231142) (xy 147.213384 -52.266829) (xy 147.249069 -52.308014) (xy 147.27853 -52.353857)
			(xy 147.301167 -52.403427) (xy 147.316519 -52.455714) (xy 147.324274 -52.509653) (xy 147.324274 -52.555949)
			(xy 148.684002 -52.555949) (xy 148.684002 -52.501451) (xy 148.691758 -52.447509) (xy 148.707111 -52.395219)
			(xy 148.729749 -52.345646) (xy 148.759212 -52.2998) (xy 148.794899 -52.258613) (xy 148.836084 -52.222924)
			(xy 148.881929 -52.193459) (xy 148.9315 -52.170818) (xy 148.983789 -52.155462) (xy 149.037731 -52.147704)
			(xy 149.06498 -52.147216) (xy 149.09235 -52.14769) (xy 149.146529 -52.155505) (xy 149.199032 -52.170992)
			(xy 149.248779 -52.193832) (xy 149.294746 -52.223555) (xy 149.315678 -52.241196) (xy 149.315932 -52.24145)
			(xy 149.32303 -52.24702) (xy 149.339938 -52.253276) (xy 149.348952 -52.253642) (xy 149.416008 -52.253642)
			(xy 149.425027 -52.253301) (xy 149.441944 -52.247044) (xy 149.449028 -52.24145) (xy 149.449536 -52.240942)
			(xy 149.47048 -52.223373) (xy 149.516412 -52.193729) (xy 149.566105 -52.170948) (xy 149.618541 -52.155495)
			(xy 149.672647 -52.147687) (xy 149.69998 -52.147216) (xy 149.727236 -52.14763) (xy 149.781192 -52.155385)
			(xy 149.833496 -52.17074) (xy 149.883081 -52.193383) (xy 149.92894 -52.222852) (xy 149.970138 -52.258548)
			(xy 150.005836 -52.299744) (xy 150.035308 -52.345601) (xy 150.057953 -52.395186) (xy 150.073311 -52.447488)
			(xy 150.081069 -52.501444) (xy 150.081069 -52.555956) (xy 150.073311 -52.609912) (xy 150.057953 -52.662214)
			(xy 150.035308 -52.711799) (xy 150.005836 -52.757656) (xy 149.970138 -52.798852) (xy 149.92894 -52.834548)
			(xy 149.883081 -52.864017) (xy 149.833496 -52.88666) (xy 149.781192 -52.902015) (xy 149.727236 -52.90977)
			(xy 149.69998 -52.910232) (xy 149.672609 -52.909794) (xy 149.618428 -52.901972) (xy 149.565924 -52.886477)
			(xy 149.516177 -52.863629) (xy 149.470212 -52.833897) (xy 149.449282 -52.816252) (xy 149.449028 -52.815998)
			(xy 149.441938 -52.810417) (xy 149.425024 -52.804167) (xy 149.416008 -52.803806) (xy 149.348952 -52.803806)
			(xy 149.339938 -52.804187) (xy 149.32302 -52.810418) (xy 149.315932 -52.815998) (xy 149.315424 -52.816506)
			(xy 149.294501 -52.834102) (xy 149.248563 -52.863739) (xy 149.198865 -52.886515) (xy 149.146424 -52.901962)
			(xy 149.092314 -52.909764) (xy 149.06498 -52.910232) (xy 149.037731 -52.909696) (xy 148.983789 -52.901938)
			(xy 148.9315 -52.886582) (xy 148.881929 -52.863941) (xy 148.836084 -52.834476) (xy 148.794899 -52.798787)
			(xy 148.759212 -52.7576) (xy 148.729749 -52.711754) (xy 148.707111 -52.662181) (xy 148.691758 -52.609891)
			(xy 148.684002 -52.555949) (xy 147.324274 -52.555949) (xy 147.324274 -52.564147) (xy 147.316519 -52.618086)
			(xy 147.301167 -52.670373) (xy 147.27853 -52.719943) (xy 147.249069 -52.765786) (xy 147.213384 -52.806971)
			(xy 147.172201 -52.842658) (xy 147.126358 -52.872121) (xy 147.07679 -52.89476) (xy 147.024504 -52.910115)
			(xy 146.970565 -52.917873) (xy 146.943318 -52.91836) (xy 146.915948 -52.917893) (xy 146.861768 -52.910077)
			(xy 146.809265 -52.894589) (xy 146.759518 -52.871747) (xy 146.713551 -52.842022) (xy 146.69262 -52.82438)
			(xy 146.692366 -52.824126) (xy 146.685271 -52.818552) (xy 146.66836 -52.8123) (xy 146.659346 -52.811934)
			(xy 146.59229 -52.811934) (xy 146.583272 -52.812279) (xy 146.566354 -52.818534) (xy 146.55927 -52.824126)
			(xy 146.558762 -52.824634) (xy 146.537828 -52.842216) (xy 146.491893 -52.871855) (xy 146.442197 -52.894633)
			(xy 146.389759 -52.910083) (xy 146.335652 -52.917889) (xy 146.308318 -52.91836) (xy 146.281061 -52.917994)
			(xy 146.227101 -52.910238) (xy 146.174794 -52.894882) (xy 146.125206 -52.872238) (xy 146.079345 -52.842766)
			(xy 146.038145 -52.807068) (xy 146.002444 -52.76587) (xy 145.972971 -52.72001) (xy 145.950324 -52.670422)
			(xy 145.934965 -52.618116) (xy 145.927207 -52.564157) (xy 141.618546 -52.564157) (xy 141.61897 -52.587398)
			(xy 141.618461 -52.615284) (xy 141.610341 -52.67046) (xy 141.594273 -52.723867) (xy 141.570601 -52.774364)
			(xy 141.539828 -52.820877) (xy 141.502611 -52.862414) (xy 141.459743 -52.898089) (xy 141.412137 -52.927143)
			(xy 141.360808 -52.948955) (xy 141.306851 -52.963061) (xy 141.251414 -52.969161) (xy 141.19568 -52.967124)
			(xy 141.140837 -52.956994) (xy 141.088053 -52.938987) (xy 141.038453 -52.913486) (xy 140.993095 -52.881035)
			(xy 140.952946 -52.842326) (xy 140.91886 -52.798183) (xy 140.891564 -52.749548) (xy 140.871641 -52.697457)
			(xy 140.859515 -52.64302) (xy 140.855444 -52.587398) (xy 137.697055 -52.587398) (xy 137.695185 -52.600102)
			(xy 137.679117 -52.653509) (xy 137.655445 -52.704006) (xy 137.624672 -52.750519) (xy 137.587455 -52.792056)
			(xy 137.544587 -52.827731) (xy 137.496981 -52.856785) (xy 137.445652 -52.878597) (xy 137.391695 -52.892703)
			(xy 137.336258 -52.898803) (xy 137.280524 -52.896766) (xy 137.225681 -52.886636) (xy 137.172897 -52.868629)
			(xy 137.123297 -52.843128) (xy 137.077939 -52.810677) (xy 137.03779 -52.771968) (xy 137.003704 -52.727825)
			(xy 136.976408 -52.67919) (xy 136.956485 -52.627099) (xy 136.944359 -52.572662) (xy 136.940288 -52.51704)
			(xy 132.753621 -52.51704) (xy 132.791598 -52.528191) (xy 132.841175 -52.550833) (xy 132.887025 -52.580299)
			(xy 132.928216 -52.61599) (xy 132.963907 -52.657181) (xy 132.993373 -52.703031) (xy 133.016015 -52.752608)
			(xy 133.03137 -52.804903) (xy 133.039126 -52.858851) (xy 133.039612 -52.886102) (xy 133.039109 -52.913434)
			(xy 133.031308 -52.96754) (xy 133.015866 -53.019978) (xy 132.993099 -53.069677) (xy 132.963472 -53.115617)
			(xy 132.945886 -53.136546) (xy 132.945632 -53.1368) (xy 132.945378 -53.137054) (xy 132.939802 -53.144148)
			(xy 132.93355 -53.161059) (xy 132.933186 -53.170074) (xy 132.933186 -53.23713) (xy 132.933531 -53.246148)
			(xy 132.939787 -53.263065) (xy 132.945378 -53.27015) (xy 132.945632 -53.270404) (xy 132.945886 -53.270658)
			(xy 132.96349 -53.291578) (xy 132.993147 -53.33751) (xy 133.015938 -53.387207) (xy 133.031397 -53.439651)
			(xy 133.039206 -53.493764) (xy 133.039206 -53.548439) (xy 133.031396 -53.602552) (xy 133.015937 -53.654995)
			(xy 132.993145 -53.704693) (xy 132.963488 -53.750625) (xy 132.946741 -53.77053) (xy 133.310884 -53.77053)
			(xy 133.311392 -53.741612) (xy 133.320119 -53.684439) (xy 133.337376 -53.629239) (xy 133.36277 -53.577276)
			(xy 133.395717 -53.529743) (xy 133.435462 -53.487728) (xy 133.45795 -53.46954) (xy 133.46532 -53.463241)
			(xy 133.475125 -53.446538) (xy 133.477 -53.437028) (xy 133.477508 -53.429408) (xy 133.477508 -53.349652)
			(xy 133.477 -53.342032) (xy 133.475142 -53.332515) (xy 133.465338 -53.315802) (xy 133.45795 -53.30952)
			(xy 133.435466 -53.29133) (xy 133.395733 -53.249309) (xy 133.362795 -53.201773) (xy 133.337408 -53.149812)
			(xy 133.320151 -53.094615) (xy 133.31142 -53.037446) (xy 133.310884 -53.00853) (xy 133.311383 -52.981278)
			(xy 133.319136 -52.927329) (xy 133.334488 -52.875032) (xy 133.357126 -52.825453) (xy 133.38659 -52.7796)
			(xy 133.42228 -52.738407) (xy 133.463469 -52.702713) (xy 133.509319 -52.673244) (xy 133.558897 -52.650601)
			(xy 133.611192 -52.635244) (xy 133.66514 -52.627486) (xy 133.692392 -52.627022) (xy 133.692646 -52.627022)
			(xy 133.718942 -52.627443) (xy 133.771033 -52.634695) (xy 133.821635 -52.649028) (xy 133.869791 -52.67017)
			(xy 133.91459 -52.697722) (xy 133.955183 -52.731162) (xy 133.973316 -52.750212) (xy 133.980881 -52.757661)
			(xy 134.000304 -52.766181) (xy 134.010908 -52.766722) (xy 134.085076 -52.766722) (xy 134.095705 -52.766285)
			(xy 134.115169 -52.757754) (xy 134.122668 -52.750212) (xy 134.140805 -52.731165) (xy 134.181385 -52.697707)
			(xy 134.22618 -52.670146) (xy 134.274338 -52.649006) (xy 134.324945 -52.634687) (xy 134.377041 -52.627461)
			(xy 134.403338 -52.627022) (xy 134.403592 -52.627022) (xy 134.430846 -52.627463) (xy 134.484799 -52.63522)
			(xy 134.537099 -52.650576) (xy 134.586682 -52.67322) (xy 134.632536 -52.70269) (xy 134.67373 -52.738386)
			(xy 134.709423 -52.779582) (xy 134.738891 -52.825438) (xy 134.761532 -52.875021) (xy 134.776885 -52.927322)
			(xy 134.784639 -52.981276) (xy 134.7851 -53.00853) (xy 134.784611 -53.036196) (xy 134.78238 -53.051456)
			(xy 143.041368 -53.051456) (xy 143.045439 -52.995834) (xy 143.057565 -52.941397) (xy 143.077488 -52.889306)
			(xy 143.104784 -52.840671) (xy 143.13887 -52.796528) (xy 143.179019 -52.757819) (xy 143.224377 -52.725368)
			(xy 143.273977 -52.699867) (xy 143.326761 -52.68186) (xy 143.381604 -52.67173) (xy 143.437338 -52.669693)
			(xy 143.492775 -52.675793) (xy 143.546732 -52.689899) (xy 143.598061 -52.711711) (xy 143.645667 -52.740765)
			(xy 143.688535 -52.77644) (xy 143.725752 -52.817977) (xy 143.756525 -52.86449) (xy 143.780197 -52.914987)
			(xy 143.796265 -52.968394) (xy 143.804385 -53.02357) (xy 143.804894 -53.051456) (xy 143.804385 -53.079342)
			(xy 143.796265 -53.134518) (xy 143.780197 -53.187925) (xy 143.756525 -53.238422) (xy 143.725752 -53.284935)
			(xy 143.688535 -53.326472) (xy 143.645667 -53.362147) (xy 143.598061 -53.391201) (xy 143.546732 -53.413013)
			(xy 143.492775 -53.427119) (xy 143.437338 -53.433219) (xy 143.381604 -53.431182) (xy 143.326761 -53.421052)
			(xy 143.273977 -53.403045) (xy 143.224377 -53.377544) (xy 143.179019 -53.345093) (xy 143.13887 -53.306384)
			(xy 143.104784 -53.262241) (xy 143.077488 -53.213606) (xy 143.057565 -53.161515) (xy 143.045439 -53.107078)
			(xy 143.041368 -53.051456) (xy 134.78238 -53.051456) (xy 134.776608 -53.090946) (xy 134.760787 -53.143968)
			(xy 134.73748 -53.194152) (xy 134.707175 -53.240448) (xy 134.670507 -53.281885) (xy 134.628242 -53.317597)
			(xy 134.605014 -53.332634) (xy 134.60476 -53.332888) (xy 134.595228 -53.339546) (xy 134.582926 -53.359246)
			(xy 134.581138 -53.370734) (xy 134.573264 -53.450744) (xy 134.572581 -53.462446) (xy 134.580672 -53.48442)
			(xy 134.588758 -53.492908) (xy 134.589012 -53.492908) (xy 134.607581 -53.511) (xy 134.640161 -53.55133)
			(xy 134.666975 -53.595702) (xy 134.68753 -53.643298) (xy 134.701446 -53.69324) (xy 134.708466 -53.744608)
			(xy 134.7089 -53.77053) (xy 134.70845 -53.797782) (xy 134.700689 -53.851732) (xy 134.68533 -53.904028)
			(xy 134.662685 -53.953606) (xy 134.633215 -53.999456) (xy 134.597519 -54.040646) (xy 134.556326 -54.076337)
			(xy 134.510472 -54.105803) (xy 134.460892 -54.128443) (xy 134.408595 -54.143797) (xy 134.354644 -54.151553)
			(xy 134.327392 -54.152038) (xy 134.300021 -54.151592) (xy 134.24584 -54.143771) (xy 134.193336 -54.128279)
			(xy 134.14359 -54.105432) (xy 134.097624 -54.075702) (xy 134.076694 -54.058058) (xy 134.07644 -54.057804)
			(xy 134.069346 -54.052228) (xy 134.052435 -54.045975) (xy 134.04342 -54.045612) (xy 133.976364 -54.045612)
			(xy 133.967345 -54.045949) (xy 133.950428 -54.05221) (xy 133.943344 -54.057804) (xy 133.942836 -54.058312)
			(xy 133.921909 -54.075903) (xy 133.875972 -54.105541) (xy 133.826275 -54.128318) (xy 133.773835 -54.143766)
			(xy 133.719726 -54.151569) (xy 133.692392 -54.152038) (xy 133.665142 -54.15153) (xy 133.611197 -54.143773)
			(xy 133.558904 -54.128418) (xy 133.509329 -54.105778) (xy 133.46348 -54.076314) (xy 133.422291 -54.040625)
			(xy 133.386599 -53.999438) (xy 133.357132 -53.953591) (xy 133.334489 -53.904017) (xy 133.319132 -53.851725)
			(xy 133.311372 -53.79778) (xy 133.310884 -53.77053) (xy 132.946741 -53.77053) (xy 132.945886 -53.771546)
			(xy 132.945632 -53.7718) (xy 132.945378 -53.772054) (xy 132.939802 -53.779148) (xy 132.93355 -53.796059)
			(xy 132.933186 -53.805074) (xy 132.933186 -53.87213) (xy 132.933531 -53.881148) (xy 132.939787 -53.898065)
			(xy 132.945378 -53.90515) (xy 132.945632 -53.905404) (xy 132.945886 -53.905658) (xy 132.96349 -53.926578)
			(xy 132.993147 -53.97251) (xy 133.015938 -54.022207) (xy 133.031397 -54.074651) (xy 133.039206 -54.128764)
			(xy 133.039206 -54.183439) (xy 133.031396 -54.237552) (xy 133.015937 -54.289995) (xy 133.002091 -54.320186)
			(xy 135.230616 -54.320186) (xy 135.231105 -54.292853) (xy 135.238908 -54.238747) (xy 135.254353 -54.186308)
			(xy 135.277124 -54.13661) (xy 135.306754 -54.09067) (xy 135.324342 -54.069742) (xy 135.324596 -54.069488)
			(xy 135.32485 -54.069234) (xy 135.330434 -54.062146) (xy 135.336681 -54.04523) (xy 135.337042 -54.036214)
			(xy 135.337042 -53.969158) (xy 135.33667 -53.960142) (xy 135.330434 -53.943225) (xy 135.32485 -53.936138)
			(xy 135.324596 -53.935884) (xy 135.324342 -53.93563) (xy 135.306757 -53.914698) (xy 135.277116 -53.868764)
			(xy 135.254337 -53.819067) (xy 135.238888 -53.766628) (xy 135.231084 -53.71252) (xy 135.230616 -53.685186)
			(xy 135.231102 -53.657935) (xy 135.238858 -53.603987) (xy 135.254213 -53.551692) (xy 135.276855 -53.502115)
			(xy 135.306321 -53.456265) (xy 135.342012 -53.415074) (xy 135.383203 -53.379383) (xy 135.429053 -53.349917)
			(xy 135.47863 -53.327275) (xy 135.530925 -53.31192) (xy 135.584873 -53.304164) (xy 135.639375 -53.304164)
			(xy 135.693323 -53.31192) (xy 135.745618 -53.327275) (xy 135.795195 -53.349917) (xy 135.841045 -53.379383)
			(xy 135.882236 -53.415074) (xy 135.917927 -53.456265) (xy 135.94382 -53.496556) (xy 148.233541 -53.496556)
			(xy 148.233541 -53.442044) (xy 148.241299 -53.388088) (xy 148.256658 -53.335785) (xy 148.279304 -53.286201)
			(xy 148.308777 -53.240344) (xy 148.344476 -53.199149) (xy 148.385674 -53.163454) (xy 148.431534 -53.133986)
			(xy 148.481121 -53.111344) (xy 148.533425 -53.095991) (xy 148.587382 -53.088238) (xy 148.614638 -53.087778)
			(xy 148.642008 -53.088261) (xy 148.696187 -53.096072) (xy 148.748691 -53.111556) (xy 148.798438 -53.134394)
			(xy 148.844405 -53.164117) (xy 148.865336 -53.181758) (xy 148.86559 -53.182012) (xy 148.872674 -53.187602)
			(xy 148.889593 -53.193846) (xy 148.89861 -53.194204) (xy 148.965666 -53.194204) (xy 148.974681 -53.19383)
			(xy 148.991598 -53.187594) (xy 148.998686 -53.182012) (xy 148.999194 -53.181504) (xy 149.020112 -53.163902)
			(xy 149.066051 -53.134265) (xy 149.115751 -53.11149) (xy 149.168193 -53.096045) (xy 149.222303 -53.088245)
			(xy 149.249638 -53.087778) (xy 149.276886 -53.088295) (xy 149.330828 -53.096055) (xy 149.383116 -53.111413)
			(xy 149.432687 -53.134056) (xy 149.478531 -53.163522) (xy 149.519715 -53.199212) (xy 149.555401 -53.2404)
			(xy 149.584863 -53.286247) (xy 149.6075 -53.335819) (xy 149.622853 -53.388109) (xy 149.630608 -53.442052)
			(xy 149.630608 -53.496548) (xy 149.622853 -53.550491) (xy 149.6075 -53.602781) (xy 149.584863 -53.652353)
			(xy 149.555401 -53.6982) (xy 149.519715 -53.739388) (xy 149.478531 -53.775078) (xy 149.432687 -53.804544)
			(xy 149.383116 -53.827187) (xy 149.330828 -53.842545) (xy 149.276886 -53.850305) (xy 149.249638 -53.850794)
			(xy 149.222269 -53.850307) (xy 149.16809 -53.842495) (xy 149.115587 -53.82701) (xy 149.06584 -53.804173)
			(xy 149.019872 -53.774453) (xy 148.99894 -53.756814) (xy 148.998686 -53.75656) (xy 148.991611 -53.750957)
			(xy 148.974685 -53.744721) (xy 148.965666 -53.744368) (xy 148.89861 -53.744368) (xy 148.889594 -53.744737)
			(xy 148.872678 -53.750977) (xy 148.86559 -53.75656) (xy 148.865082 -53.757068) (xy 148.84417 -53.774677)
			(xy 148.79823 -53.804314) (xy 148.748528 -53.827088) (xy 148.696085 -53.842532) (xy 148.641973 -53.850329)
			(xy 148.614638 -53.850794) (xy 148.587382 -53.850362) (xy 148.533425 -53.842609) (xy 148.481121 -53.827256)
			(xy 148.431534 -53.804614) (xy 148.385674 -53.775146) (xy 148.344476 -53.739451) (xy 148.308777 -53.698256)
			(xy 148.279304 -53.652399) (xy 148.256658 -53.602815) (xy 148.241299 -53.550512) (xy 148.233541 -53.496556)
			(xy 135.94382 -53.496556) (xy 135.947393 -53.502115) (xy 135.970035 -53.551692) (xy 135.98539 -53.603987)
			(xy 135.993146 -53.657935) (xy 135.993632 -53.685186) (xy 135.993198 -53.712521) (xy 135.985383 -53.76663)
			(xy 135.969926 -53.81907) (xy 135.947143 -53.868768) (xy 135.9175 -53.914704) (xy 135.899906 -53.93563)
			(xy 135.899652 -53.935884) (xy 135.899398 -53.936138) (xy 135.893831 -53.943238) (xy 135.887573 -53.960144)
			(xy 135.887206 -53.969158) (xy 135.887206 -54.036214) (xy 135.887555 -54.045232) (xy 135.893808 -54.062149)
			(xy 135.899398 -54.069234) (xy 135.899652 -54.069488) (xy 135.899906 -54.069742) (xy 135.917486 -54.090678)
			(xy 135.947126 -54.136612) (xy 135.969904 -54.186307) (xy 135.985355 -54.238746) (xy 135.993162 -54.292852)
			(xy 135.993632 -54.320186) (xy 135.993146 -54.347437) (xy 135.98539 -54.401385) (xy 135.970035 -54.45368)
			(xy 135.947393 -54.503257) (xy 135.917927 -54.549107) (xy 135.882236 -54.590298) (xy 135.841045 -54.625989)
			(xy 135.795195 -54.655455) (xy 135.745618 -54.678097) (xy 135.693323 -54.693452) (xy 135.639375 -54.701208)
			(xy 135.584873 -54.701208) (xy 135.530925 -54.693452) (xy 135.47863 -54.678097) (xy 135.429053 -54.655455)
			(xy 135.383203 -54.625989) (xy 135.342012 -54.590298) (xy 135.306321 -54.549107) (xy 135.276855 -54.503257)
			(xy 135.254213 -54.45368) (xy 135.238858 -54.401385) (xy 135.231102 -54.347437) (xy 135.230616 -54.320186)
			(xy 133.002091 -54.320186) (xy 132.993145 -54.339693) (xy 132.963488 -54.385625) (xy 132.945886 -54.406546)
			(xy 132.945632 -54.4068) (xy 132.945378 -54.407054) (xy 132.939802 -54.414148) (xy 132.93355 -54.431059)
			(xy 132.933186 -54.440074) (xy 132.933186 -54.50713) (xy 132.933531 -54.516148) (xy 132.939787 -54.533065)
			(xy 132.945378 -54.54015) (xy 132.945632 -54.540404) (xy 132.945886 -54.540658) (xy 132.96347 -54.561591)
			(xy 132.99311 -54.607525) (xy 133.015888 -54.657221) (xy 133.031338 -54.709661) (xy 133.039143 -54.763768)
			(xy 133.039259 -54.770528) (xy 136.171178 -54.770528) (xy 136.171642 -54.743194) (xy 136.179453 -54.689087)
			(xy 136.194904 -54.636648) (xy 136.21768 -54.586951) (xy 136.247314 -54.541012) (xy 136.264904 -54.520084)
			(xy 136.265158 -54.51983) (xy 136.265412 -54.519576) (xy 136.271016 -54.512501) (xy 136.277252 -54.495575)
			(xy 136.277604 -54.486556) (xy 136.277604 -54.4195) (xy 136.277246 -54.410483) (xy 136.270999 -54.393566)
			(xy 136.265412 -54.38648) (xy 136.265158 -54.386226) (xy 136.264904 -54.385972) (xy 136.247332 -54.365029)
			(xy 136.217691 -54.319097) (xy 136.19491 -54.269404) (xy 136.179458 -54.216967) (xy 136.171649 -54.162861)
			(xy 136.171178 -54.135528) (xy 136.171664 -54.108277) (xy 136.17942 -54.054329) (xy 136.194775 -54.002034)
			(xy 136.217417 -53.952457) (xy 136.246883 -53.906607) (xy 136.282574 -53.865416) (xy 136.323765 -53.829725)
			(xy 136.369615 -53.800259) (xy 136.419192 -53.777617) (xy 136.471487 -53.762262) (xy 136.525435 -53.754506)
			(xy 136.579937 -53.754506) (xy 136.633885 -53.762262) (xy 136.68618 -53.777617) (xy 136.735757 -53.800259)
			(xy 136.781607 -53.829725) (xy 136.822798 -53.865416) (xy 136.858489 -53.906607) (xy 136.887955 -53.952457)
			(xy 136.89303 -53.96357) (xy 140.872208 -53.96357) (xy 140.876279 -53.907948) (xy 140.888405 -53.853511)
			(xy 140.908328 -53.80142) (xy 140.935624 -53.752785) (xy 140.96971 -53.708642) (xy 141.009859 -53.669933)
			(xy 141.055217 -53.637482) (xy 141.104817 -53.611981) (xy 141.157601 -53.593974) (xy 141.212444 -53.583844)
			(xy 141.268178 -53.581807) (xy 141.323615 -53.587907) (xy 141.377572 -53.602013) (xy 141.428901 -53.623825)
			(xy 141.476507 -53.652879) (xy 141.519375 -53.688554) (xy 141.556592 -53.730091) (xy 141.587365 -53.776604)
			(xy 141.611037 -53.827101) (xy 141.627105 -53.880508) (xy 141.635225 -53.935684) (xy 141.635734 -53.96357)
			(xy 141.635225 -53.991456) (xy 141.627105 -54.046632) (xy 141.62084 -54.067456) (xy 143.041368 -54.067456)
			(xy 143.045439 -54.011834) (xy 143.057565 -53.957397) (xy 143.077488 -53.905306) (xy 143.104784 -53.856671)
			(xy 143.13887 -53.812528) (xy 143.179019 -53.773819) (xy 143.224377 -53.741368) (xy 143.273977 -53.715867)
			(xy 143.326761 -53.69786) (xy 143.381604 -53.68773) (xy 143.437338 -53.685693) (xy 143.492775 -53.691793)
			(xy 143.546732 -53.705899) (xy 143.598061 -53.727711) (xy 143.645667 -53.756765) (xy 143.688535 -53.79244)
			(xy 143.725752 -53.833977) (xy 143.756525 -53.88049) (xy 143.780197 -53.930987) (xy 143.796265 -53.984394)
			(xy 143.804385 -54.03957) (xy 143.804894 -54.067456) (xy 143.804385 -54.095342) (xy 143.796265 -54.150518)
			(xy 143.780197 -54.203925) (xy 143.763799 -54.238906) (xy 150.486108 -54.238906) (xy 150.490179 -54.183284)
			(xy 150.502305 -54.128847) (xy 150.522228 -54.076756) (xy 150.549524 -54.028121) (xy 150.58361 -53.983978)
			(xy 150.623759 -53.945269) (xy 150.669117 -53.912818) (xy 150.718717 -53.887317) (xy 150.771501 -53.86931)
			(xy 150.826344 -53.85918) (xy 150.882078 -53.857143) (xy 150.937515 -53.863243) (xy 150.991472 -53.877349)
			(xy 151.042801 -53.899161) (xy 151.090407 -53.928215) (xy 151.133275 -53.96389) (xy 151.170492 -54.005427)
			(xy 151.201265 -54.05194) (xy 151.224937 -54.102437) (xy 151.241005 -54.155844) (xy 151.249125 -54.21102)
			(xy 151.249634 -54.238906) (xy 151.249125 -54.266792) (xy 151.241005 -54.321968) (xy 151.224937 -54.375375)
			(xy 151.201265 -54.425872) (xy 151.170492 -54.472385) (xy 151.133275 -54.513922) (xy 151.090407 -54.549597)
			(xy 151.042801 -54.578651) (xy 150.991472 -54.600463) (xy 150.937515 -54.614569) (xy 150.882078 -54.620669)
			(xy 150.826344 -54.618632) (xy 150.771501 -54.608502) (xy 150.718717 -54.590495) (xy 150.669117 -54.564994)
			(xy 150.623759 -54.532543) (xy 150.58361 -54.493834) (xy 150.549524 -54.449691) (xy 150.522228 -54.401056)
			(xy 150.502305 -54.348965) (xy 150.490179 -54.294528) (xy 150.486108 -54.238906) (xy 143.763799 -54.238906)
			(xy 143.756525 -54.254422) (xy 143.725752 -54.300935) (xy 143.688535 -54.342472) (xy 143.645667 -54.378147)
			(xy 143.598061 -54.407201) (xy 143.546732 -54.429013) (xy 143.492775 -54.443119) (xy 143.437338 -54.449219)
			(xy 143.381604 -54.447182) (xy 143.326761 -54.437052) (xy 143.273977 -54.419045) (xy 143.224377 -54.393544)
			(xy 143.179019 -54.361093) (xy 143.13887 -54.322384) (xy 143.104784 -54.278241) (xy 143.077488 -54.229606)
			(xy 143.057565 -54.177515) (xy 143.045439 -54.123078) (xy 143.041368 -54.067456) (xy 141.62084 -54.067456)
			(xy 141.611037 -54.100039) (xy 141.587365 -54.150536) (xy 141.556592 -54.197049) (xy 141.519375 -54.238586)
			(xy 141.476507 -54.274261) (xy 141.428901 -54.303315) (xy 141.377572 -54.325127) (xy 141.323615 -54.339233)
			(xy 141.268178 -54.345333) (xy 141.212444 -54.343296) (xy 141.157601 -54.333166) (xy 141.104817 -54.315159)
			(xy 141.055217 -54.289658) (xy 141.009859 -54.257207) (xy 140.96971 -54.218498) (xy 140.935624 -54.174355)
			(xy 140.908328 -54.12572) (xy 140.888405 -54.073629) (xy 140.876279 -54.019192) (xy 140.872208 -53.96357)
			(xy 136.89303 -53.96357) (xy 136.910597 -54.002034) (xy 136.925952 -54.054329) (xy 136.933708 -54.108277)
			(xy 136.934194 -54.135528) (xy 136.933711 -54.162861) (xy 136.925906 -54.216968) (xy 136.910459 -54.269407)
			(xy 136.887687 -54.319105) (xy 136.858056 -54.365044) (xy 136.840468 -54.385972) (xy 136.840214 -54.386226)
			(xy 136.83996 -54.38648) (xy 136.834371 -54.393565) (xy 136.828127 -54.410483) (xy 136.827768 -54.4195)
			(xy 136.827768 -54.486556) (xy 136.828153 -54.49557) (xy 136.834382 -54.512487) (xy 136.83996 -54.519576)
			(xy 136.840214 -54.51983) (xy 136.840468 -54.520084) (xy 136.858061 -54.541009) (xy 136.887701 -54.586946)
			(xy 136.910477 -54.636644) (xy 136.925925 -54.689084) (xy 136.933727 -54.743194) (xy 136.934194 -54.770528)
			(xy 136.933708 -54.797779) (xy 136.925952 -54.851727) (xy 136.910597 -54.904022) (xy 136.887955 -54.953599)
			(xy 136.858489 -54.999449) (xy 136.822798 -55.04064) (xy 136.781607 -55.076331) (xy 136.77052 -55.083456)
			(xy 143.041368 -55.083456) (xy 143.045439 -55.027834) (xy 143.057565 -54.973397) (xy 143.077488 -54.921306)
			(xy 143.104784 -54.872671) (xy 143.13887 -54.828528) (xy 143.179019 -54.789819) (xy 143.224377 -54.757368)
			(xy 143.273977 -54.731867) (xy 143.326761 -54.71386) (xy 143.381604 -54.70373) (xy 143.437338 -54.701693)
			(xy 143.492775 -54.707793) (xy 143.546732 -54.721899) (xy 143.598061 -54.743711) (xy 143.645667 -54.772765)
			(xy 143.688535 -54.80844) (xy 143.725752 -54.849977) (xy 143.756525 -54.89649) (xy 143.780197 -54.946987)
			(xy 143.792854 -54.989055) (xy 146.001145 -54.989055) (xy 146.001145 -54.934545) (xy 146.008903 -54.88059)
			(xy 146.024261 -54.828288) (xy 146.046906 -54.778704) (xy 146.076378 -54.732848) (xy 146.112076 -54.691654)
			(xy 146.153274 -54.655959) (xy 146.199132 -54.626491) (xy 146.248718 -54.60385) (xy 146.301021 -54.588496)
			(xy 146.354977 -54.580743) (xy 146.382232 -54.580282) (xy 146.410324 -54.580751) (xy 146.465903 -54.588983)
			(xy 146.519672 -54.605279) (xy 146.57047 -54.629286) (xy 146.617196 -54.660484) (xy 146.658841 -54.6982)
			(xy 146.694502 -54.741616) (xy 146.709384 -54.765448) (xy 146.714972 -54.774592) (xy 146.73199 -54.786784)
			(xy 146.824954 -54.80685) (xy 146.845528 -54.802786) (xy 146.854164 -54.79669) (xy 146.878235 -54.780702)
			(xy 146.930164 -54.755357) (xy 146.98532 -54.738128) (xy 147.042442 -54.729409) (xy 147.071334 -54.728872)
			(xy 147.098585 -54.729346) (xy 147.112946 -54.731412) (xy 155.62072 -54.731412) (xy 155.621165 -54.704077)
			(xy 155.628979 -54.649969) (xy 155.644434 -54.59753) (xy 155.667215 -54.547832) (xy 155.696854 -54.501895)
			(xy 155.714446 -54.480968) (xy 155.7147 -54.480714) (xy 155.714954 -54.48046) (xy 155.720528 -54.473365)
			(xy 155.726781 -54.456455) (xy 155.727146 -54.44744) (xy 155.727146 -54.380384) (xy 155.726808 -54.371365)
			(xy 155.720548 -54.354448) (xy 155.714954 -54.347364) (xy 155.7147 -54.34711) (xy 155.714446 -54.346856)
			(xy 155.696858 -54.325924) (xy 155.667207 -54.279992) (xy 155.644419 -54.230296) (xy 155.628962 -54.177856)
			(xy 155.621152 -54.123745) (xy 155.621151 -54.069073) (xy 155.628958 -54.014962) (xy 155.644412 -53.962521)
			(xy 155.667198 -53.912824) (xy 155.696847 -53.866891) (xy 155.714446 -53.845968) (xy 155.7147 -53.845714)
			(xy 155.714954 -53.84546) (xy 155.720528 -53.838365) (xy 155.726781 -53.821455) (xy 155.727146 -53.81244)
			(xy 155.727146 -53.745384) (xy 155.726808 -53.736365) (xy 155.720548 -53.719448) (xy 155.714954 -53.712364)
			(xy 155.7147 -53.71211) (xy 155.714446 -53.711856) (xy 155.696858 -53.690924) (xy 155.667207 -53.644992)
			(xy 155.644419 -53.595296) (xy 155.628962 -53.542856) (xy 155.621152 -53.488745) (xy 155.621151 -53.434073)
			(xy 155.628958 -53.379962) (xy 155.644412 -53.327521) (xy 155.667198 -53.277824) (xy 155.696847 -53.231891)
			(xy 155.714446 -53.210968) (xy 155.7147 -53.210714) (xy 155.714954 -53.21046) (xy 155.720528 -53.203365)
			(xy 155.726781 -53.186455) (xy 155.727146 -53.17744) (xy 155.727146 -53.110384) (xy 155.726808 -53.101365)
			(xy 155.720548 -53.084448) (xy 155.714954 -53.077364) (xy 155.7147 -53.07711) (xy 155.714446 -53.076856)
			(xy 155.696873 -53.055914) (xy 155.667231 -53.009982) (xy 155.64445 -52.960289) (xy 155.628997 -52.907851)
			(xy 155.62119 -52.853745) (xy 155.62072 -52.826412) (xy 155.621206 -52.799161) (xy 155.628962 -52.745213)
			(xy 155.644317 -52.692918) (xy 155.666959 -52.643341) (xy 155.696425 -52.597491) (xy 155.732116 -52.5563)
			(xy 155.773307 -52.520609) (xy 155.819157 -52.491143) (xy 155.868734 -52.468501) (xy 155.921029 -52.453146)
			(xy 155.974977 -52.44539) (xy 156.029479 -52.44539) (xy 156.083427 -52.453146) (xy 156.135722 -52.468501)
			(xy 156.185299 -52.491143) (xy 156.231149 -52.520609) (xy 156.27234 -52.5563) (xy 156.308031 -52.597491)
			(xy 156.337497 -52.643341) (xy 156.360139 -52.692918) (xy 156.375494 -52.745213) (xy 156.38325 -52.799161)
			(xy 156.383736 -52.826412) (xy 156.383258 -52.853746) (xy 156.375453 -52.907853) (xy 156.360006 -52.960292)
			(xy 156.337233 -53.00999) (xy 156.3076 -53.055929) (xy 156.29001 -53.076856) (xy 156.289756 -53.07711)
			(xy 156.289502 -53.077364) (xy 156.283925 -53.084457) (xy 156.277672 -53.101369) (xy 156.27731 -53.110384)
			(xy 156.27731 -53.17744) (xy 156.277646 -53.186459) (xy 156.283908 -53.203376) (xy 156.289502 -53.21046)
			(xy 156.289756 -53.210714) (xy 156.29001 -53.210968) (xy 156.307623 -53.23188) (xy 156.337277 -53.277814)
			(xy 156.360066 -53.327513) (xy 156.375523 -53.379957) (xy 156.383331 -53.434072) (xy 156.38333 -53.488746)
			(xy 156.37552 -53.54286) (xy 156.36006 -53.595304) (xy 156.337268 -53.645002) (xy 156.307612 -53.690934)
			(xy 156.29001 -53.711856) (xy 156.289756 -53.71211) (xy 156.289502 -53.712364) (xy 156.283925 -53.719457)
			(xy 156.277672 -53.736369) (xy 156.27731 -53.745384) (xy 156.27731 -53.81244) (xy 156.277646 -53.821459)
			(xy 156.283908 -53.838376) (xy 156.289502 -53.84546) (xy 156.289756 -53.845714) (xy 156.29001 -53.845968)
			(xy 156.307623 -53.86688) (xy 156.337277 -53.912814) (xy 156.360066 -53.962513) (xy 156.375523 -54.014957)
			(xy 156.383331 -54.069072) (xy 156.38333 -54.123746) (xy 156.37552 -54.17786) (xy 156.36006 -54.230304)
			(xy 156.337268 -54.280002) (xy 156.307612 -54.325934) (xy 156.29001 -54.346856) (xy 156.289756 -54.34711)
			(xy 156.289502 -54.347364) (xy 156.283925 -54.354457) (xy 156.277672 -54.371369) (xy 156.27731 -54.380384)
			(xy 156.27731 -54.44744) (xy 156.277646 -54.456459) (xy 156.283908 -54.473376) (xy 156.289502 -54.48046)
			(xy 156.289756 -54.480714) (xy 156.29001 -54.480968) (xy 156.307602 -54.501894) (xy 156.33724 -54.547831)
			(xy 156.360017 -54.597529) (xy 156.375465 -54.649969) (xy 156.383268 -54.704078) (xy 156.383736 -54.731412)
			(xy 156.38325 -54.758663) (xy 156.378586 -54.791102) (xy 158.276544 -54.791102) (xy 158.277036 -54.763769)
			(xy 158.284837 -54.709662) (xy 158.300281 -54.657223) (xy 158.323052 -54.607525) (xy 158.352682 -54.561586)
			(xy 158.37027 -54.540658) (xy 158.370524 -54.540404) (xy 158.370778 -54.54015) (xy 158.376359 -54.53306)
			(xy 158.382607 -54.516146) (xy 158.38297 -54.50713) (xy 158.38297 -54.440074) (xy 158.382632 -54.431055)
			(xy 158.376372 -54.414138) (xy 158.370778 -54.407054) (xy 158.370524 -54.4068) (xy 158.37027 -54.406546)
			(xy 158.352672 -54.385622) (xy 158.323018 -54.33969) (xy 158.30023 -54.289993) (xy 158.284772 -54.23755)
			(xy 158.276963 -54.183438) (xy 158.276963 -54.128765) (xy 158.284772 -54.074653) (xy 158.300228 -54.02221)
			(xy 158.323017 -53.972513) (xy 158.35267 -53.92658) (xy 158.37027 -53.905658) (xy 158.370524 -53.905404)
			(xy 158.370778 -53.90515) (xy 158.376359 -53.89806) (xy 158.382607 -53.881146) (xy 158.38297 -53.87213)
			(xy 158.38297 -53.805074) (xy 158.382632 -53.796055) (xy 158.376372 -53.779138) (xy 158.370778 -53.772054)
			(xy 158.370524 -53.7718) (xy 158.37027 -53.771546) (xy 158.352672 -53.750622) (xy 158.323018 -53.70469)
			(xy 158.30023 -53.654993) (xy 158.284772 -53.60255) (xy 158.276963 -53.548438) (xy 158.276963 -53.493765)
			(xy 158.284772 -53.439653) (xy 158.300228 -53.38721) (xy 158.323017 -53.337513) (xy 158.35267 -53.29158)
			(xy 158.37027 -53.270658) (xy 158.370524 -53.270404) (xy 158.370778 -53.27015) (xy 158.376359 -53.26306)
			(xy 158.382607 -53.246146) (xy 158.38297 -53.23713) (xy 158.38297 -53.170074) (xy 158.382632 -53.161055)
			(xy 158.376372 -53.144138) (xy 158.370778 -53.137054) (xy 158.370524 -53.1368) (xy 158.37027 -53.136546)
			(xy 158.352681 -53.115618) (xy 158.323043 -53.069681) (xy 158.300267 -53.019984) (xy 158.284818 -52.967544)
			(xy 158.277013 -52.913436) (xy 158.276544 -52.886102) (xy 158.27703 -52.858851) (xy 158.284786 -52.804903)
			(xy 158.300141 -52.752608) (xy 158.322783 -52.703031) (xy 158.352249 -52.657181) (xy 158.38794 -52.61599)
			(xy 158.429131 -52.580299) (xy 158.474981 -52.550833) (xy 158.524558 -52.528191) (xy 158.576853 -52.512836)
			(xy 158.630801 -52.50508) (xy 158.685303 -52.50508) (xy 158.739251 -52.512836) (xy 158.753569 -52.51704)
			(xy 162.940236 -52.51704) (xy 162.944307 -52.461418) (xy 162.956433 -52.406981) (xy 162.976356 -52.35489)
			(xy 163.003652 -52.306255) (xy 163.037738 -52.262112) (xy 163.077887 -52.223403) (xy 163.123245 -52.190952)
			(xy 163.172845 -52.165451) (xy 163.225629 -52.147444) (xy 163.280472 -52.137314) (xy 163.336206 -52.135277)
			(xy 163.391643 -52.141377) (xy 163.4456 -52.155483) (xy 163.496929 -52.177295) (xy 163.544535 -52.206349)
			(xy 163.587403 -52.242024) (xy 163.62462 -52.283561) (xy 163.655393 -52.330074) (xy 163.679065 -52.380571)
			(xy 163.695133 -52.433978) (xy 163.703253 -52.489154) (xy 163.703762 -52.51704) (xy 163.703253 -52.544926)
			(xy 163.697003 -52.587398) (xy 166.855392 -52.587398) (xy 166.859463 -52.531776) (xy 166.871589 -52.477339)
			(xy 166.891512 -52.425248) (xy 166.918808 -52.376613) (xy 166.952894 -52.33247) (xy 166.993043 -52.293761)
			(xy 167.038401 -52.26131) (xy 167.088001 -52.235809) (xy 167.140785 -52.217802) (xy 167.195628 -52.207672)
			(xy 167.251362 -52.205635) (xy 167.306799 -52.211735) (xy 167.360756 -52.225841) (xy 167.412085 -52.247653)
			(xy 167.459691 -52.276707) (xy 167.502559 -52.312382) (xy 167.539776 -52.353919) (xy 167.570549 -52.400432)
			(xy 167.594221 -52.450929) (xy 167.610289 -52.504336) (xy 167.618409 -52.559512) (xy 167.618494 -52.564153)
			(xy 171.92723 -52.564153) (xy 171.92723 -52.509647) (xy 171.934986 -52.455695) (xy 171.950342 -52.403397)
			(xy 171.972983 -52.353816) (xy 172.00245 -52.307961) (xy 172.038142 -52.266766) (xy 172.079334 -52.23107)
			(xy 172.125186 -52.2016) (xy 172.174765 -52.178954) (xy 172.227062 -52.163594) (xy 172.281013 -52.155832)
			(xy 172.308266 -52.155344) (xy 172.335636 -52.155819) (xy 172.389815 -52.163633) (xy 172.442319 -52.17912)
			(xy 172.492066 -52.20196) (xy 172.538032 -52.231683) (xy 172.558964 -52.249324) (xy 172.559218 -52.249578)
			(xy 172.566289 -52.255187) (xy 172.583218 -52.261418) (xy 172.592238 -52.26177) (xy 172.659294 -52.26177)
			(xy 172.668311 -52.261417) (xy 172.685229 -52.255167) (xy 172.692314 -52.249578) (xy 172.692822 -52.24907)
			(xy 172.713762 -52.231496) (xy 172.759696 -52.201856) (xy 172.80939 -52.179076) (xy 172.861827 -52.163624)
			(xy 172.915933 -52.155816) (xy 172.943266 -52.155344) (xy 172.970517 -52.155901) (xy 173.024465 -52.163653)
			(xy 173.07676 -52.179004) (xy 173.126338 -52.201642) (xy 173.17219 -52.231105) (xy 173.213382 -52.266794)
			(xy 173.249074 -52.307983) (xy 173.278542 -52.353832) (xy 173.301184 -52.403408) (xy 173.31654 -52.455702)
			(xy 173.324297 -52.509649) (xy 173.324297 -52.555952) (xy 174.683879 -52.555952) (xy 174.683879 -52.501448)
			(xy 174.691637 -52.447498) (xy 174.706993 -52.395201) (xy 174.729636 -52.345622) (xy 174.759105 -52.29977)
			(xy 174.794799 -52.25858) (xy 174.835993 -52.222888) (xy 174.881847 -52.193423) (xy 174.931427 -52.170783)
			(xy 174.983725 -52.155431) (xy 175.037676 -52.147677) (xy 175.064928 -52.147216) (xy 175.092299 -52.147662)
			(xy 175.146479 -52.155484) (xy 175.198983 -52.170978) (xy 175.248729 -52.193824) (xy 175.294695 -52.223553)
			(xy 175.315626 -52.241196) (xy 175.31588 -52.24145) (xy 175.322964 -52.24704) (xy 175.339883 -52.253284)
			(xy 175.3489 -52.253642) (xy 175.415956 -52.253642) (xy 175.424972 -52.253277) (xy 175.44189 -52.247036)
			(xy 175.448976 -52.24145) (xy 175.449484 -52.240942) (xy 175.47041 -52.22335) (xy 175.516346 -52.19371)
			(xy 175.566044 -52.170933) (xy 175.618485 -52.155485) (xy 175.672594 -52.147683) (xy 175.699928 -52.147216)
			(xy 175.72718 -52.147656) (xy 175.781128 -52.155416) (xy 175.833422 -52.170775) (xy 175.882999 -52.193419)
			(xy 175.928849 -52.222888) (xy 175.970038 -52.258581) (xy 176.005729 -52.299773) (xy 176.035195 -52.345625)
			(xy 176.057835 -52.395204) (xy 176.07319 -52.4475) (xy 176.080946 -52.501448) (xy 176.080946 -52.555952)
			(xy 176.07319 -52.6099) (xy 176.057835 -52.662196) (xy 176.035195 -52.711775) (xy 176.005729 -52.757627)
			(xy 175.970038 -52.798819) (xy 175.928849 -52.834512) (xy 175.882999 -52.863981) (xy 175.833422 -52.886625)
			(xy 175.781128 -52.901984) (xy 175.72718 -52.909744) (xy 175.699928 -52.910232) (xy 175.672558 -52.909766)
			(xy 175.618378 -52.901951) (xy 175.565874 -52.886463) (xy 175.516127 -52.86362) (xy 175.470161 -52.833894)
			(xy 175.44923 -52.816252) (xy 175.448976 -52.815998) (xy 175.441901 -52.810395) (xy 175.424975 -52.804158)
			(xy 175.415956 -52.803806) (xy 175.3489 -52.803806) (xy 175.339883 -52.804162) (xy 175.322966 -52.81041)
			(xy 175.31588 -52.815998) (xy 175.315372 -52.816506) (xy 175.294431 -52.834079) (xy 175.248498 -52.86372)
			(xy 175.198804 -52.8865) (xy 175.146367 -52.901953) (xy 175.092261 -52.909761) (xy 175.064928 -52.910232)
			(xy 175.037676 -52.909723) (xy 174.983725 -52.901969) (xy 174.931427 -52.886617) (xy 174.881847 -52.863977)
			(xy 174.835993 -52.834512) (xy 174.794799 -52.79882) (xy 174.759105 -52.75763) (xy 174.729636 -52.711778)
			(xy 174.706993 -52.662199) (xy 174.691637 -52.609902) (xy 174.683879 -52.555952) (xy 173.324297 -52.555952)
			(xy 173.324297 -52.564151) (xy 173.31654 -52.618098) (xy 173.301184 -52.670392) (xy 173.278542 -52.719968)
			(xy 173.249074 -52.765817) (xy 173.213382 -52.807006) (xy 173.17219 -52.842695) (xy 173.126338 -52.872158)
			(xy 173.07676 -52.894796) (xy 173.024465 -52.910147) (xy 172.970517 -52.917899) (xy 172.943266 -52.91836)
			(xy 172.915895 -52.917924) (xy 172.861714 -52.9101) (xy 172.80921 -52.894605) (xy 172.759464 -52.871756)
			(xy 172.713498 -52.842025) (xy 172.692568 -52.82438) (xy 172.692314 -52.824126) (xy 172.685234 -52.81853)
			(xy 172.668312 -52.812291) (xy 172.659294 -52.811934) (xy 172.592238 -52.811934) (xy 172.583222 -52.812302)
			(xy 172.566305 -52.818541) (xy 172.559218 -52.824126) (xy 172.55871 -52.824634) (xy 172.537796 -52.84224)
			(xy 172.491855 -52.871876) (xy 172.442154 -52.894649) (xy 172.389711 -52.910093) (xy 172.335601 -52.917893)
			(xy 172.308266 -52.91836) (xy 172.281013 -52.917968) (xy 172.227062 -52.910206) (xy 172.174765 -52.894846)
			(xy 172.125186 -52.8722) (xy 172.079334 -52.84273) (xy 172.038142 -52.807034) (xy 172.00245 -52.765839)
			(xy 171.972983 -52.719984) (xy 171.950342 -52.670403) (xy 171.934986 -52.618105) (xy 171.92723 -52.564153)
			(xy 167.618494 -52.564153) (xy 167.618918 -52.587398) (xy 167.618409 -52.615284) (xy 167.610289 -52.67046)
			(xy 167.594221 -52.723867) (xy 167.570549 -52.774364) (xy 167.539776 -52.820877) (xy 167.502559 -52.862414)
			(xy 167.459691 -52.898089) (xy 167.412085 -52.927143) (xy 167.360756 -52.948955) (xy 167.306799 -52.963061)
			(xy 167.251362 -52.969161) (xy 167.195628 -52.967124) (xy 167.140785 -52.956994) (xy 167.088001 -52.938987)
			(xy 167.038401 -52.913486) (xy 166.993043 -52.881035) (xy 166.952894 -52.842326) (xy 166.918808 -52.798183)
			(xy 166.891512 -52.749548) (xy 166.871589 -52.697457) (xy 166.859463 -52.64302) (xy 166.855392 -52.587398)
			(xy 163.697003 -52.587398) (xy 163.695133 -52.600102) (xy 163.679065 -52.653509) (xy 163.655393 -52.704006)
			(xy 163.62462 -52.750519) (xy 163.587403 -52.792056) (xy 163.544535 -52.827731) (xy 163.496929 -52.856785)
			(xy 163.4456 -52.878597) (xy 163.391643 -52.892703) (xy 163.336206 -52.898803) (xy 163.280472 -52.896766)
			(xy 163.225629 -52.886636) (xy 163.172845 -52.868629) (xy 163.123245 -52.843128) (xy 163.077887 -52.810677)
			(xy 163.037738 -52.771968) (xy 163.003652 -52.727825) (xy 162.976356 -52.67919) (xy 162.956433 -52.627099)
			(xy 162.944307 -52.572662) (xy 162.940236 -52.51704) (xy 158.753569 -52.51704) (xy 158.791546 -52.528191)
			(xy 158.841123 -52.550833) (xy 158.886973 -52.580299) (xy 158.928164 -52.61599) (xy 158.963855 -52.657181)
			(xy 158.993321 -52.703031) (xy 159.015963 -52.752608) (xy 159.031318 -52.804903) (xy 159.039074 -52.858851)
			(xy 159.03956 -52.886102) (xy 159.03907 -52.913435) (xy 159.031268 -52.967542) (xy 159.015823 -53.019981)
			(xy 158.993053 -53.069679) (xy 158.963422 -53.115618) (xy 158.945834 -53.136546) (xy 158.94558 -53.1368)
			(xy 158.945326 -53.137054) (xy 158.939744 -53.144143) (xy 158.933496 -53.161058) (xy 158.933134 -53.170074)
			(xy 158.933134 -53.23713) (xy 158.933469 -53.246149) (xy 158.939731 -53.263066) (xy 158.945326 -53.27015)
			(xy 158.94558 -53.270404) (xy 158.945834 -53.270658) (xy 158.963436 -53.291579) (xy 158.993089 -53.337512)
			(xy 159.015877 -53.387209) (xy 159.031334 -53.439652) (xy 159.039142 -53.493765) (xy 159.039142 -53.548438)
			(xy 159.031333 -53.602551) (xy 159.015876 -53.654993) (xy 158.993087 -53.704691) (xy 158.963434 -53.750624)
			(xy 158.946689 -53.77053) (xy 159.310832 -53.77053) (xy 159.31136 -53.741613) (xy 159.320085 -53.684442)
			(xy 159.33734 -53.629243) (xy 159.36273 -53.577281) (xy 159.395673 -53.529747) (xy 159.435413 -53.48773)
			(xy 159.457898 -53.46954) (xy 159.465276 -53.46325) (xy 159.475075 -53.44654) (xy 159.476948 -53.437028)
			(xy 159.477456 -53.429408) (xy 159.477456 -53.349652) (xy 159.476948 -53.342032) (xy 159.475076 -53.332519)
			(xy 159.465281 -53.315805) (xy 159.457898 -53.30952) (xy 159.435424 -53.291318) (xy 159.395688 -53.249301)
			(xy 159.362748 -53.201768) (xy 159.337358 -53.149809) (xy 159.3201 -53.094613) (xy 159.311368 -53.037445)
			(xy 159.310832 -53.00853) (xy 159.311283 -52.981276) (xy 159.319037 -52.927323) (xy 159.334392 -52.875022)
			(xy 159.357033 -52.825439) (xy 159.386502 -52.779584) (xy 159.422197 -52.73839) (xy 159.463392 -52.702696)
			(xy 159.509248 -52.673229) (xy 159.558831 -52.650588) (xy 159.611132 -52.635235) (xy 159.665086 -52.627483)
			(xy 159.69234 -52.627022) (xy 159.692594 -52.627022) (xy 159.718889 -52.627478) (xy 159.770978 -52.634723)
			(xy 159.82158 -52.649049) (xy 159.869736 -52.670185) (xy 159.914536 -52.697731) (xy 159.95513 -52.731165)
			(xy 159.973264 -52.750212) (xy 159.980848 -52.757638) (xy 160.000257 -52.766172) (xy 160.010856 -52.766722)
			(xy 160.085024 -52.766722) (xy 160.095656 -52.766311) (xy 160.11512 -52.757762) (xy 160.122616 -52.750212)
			(xy 160.14073 -52.731142) (xy 160.181315 -52.697686) (xy 160.226114 -52.670128) (xy 160.274277 -52.648992)
			(xy 160.324889 -52.634677) (xy 160.376988 -52.627458) (xy 160.403286 -52.627022) (xy 160.40354 -52.627022)
			(xy 160.430794 -52.627441) (xy 160.484745 -52.635203) (xy 160.537043 -52.650565) (xy 160.586622 -52.673213)
			(xy 160.632474 -52.702686) (xy 160.673665 -52.738385) (xy 160.709356 -52.779582) (xy 160.73882 -52.825439)
			(xy 160.761459 -52.875023) (xy 160.776811 -52.927323) (xy 160.784564 -52.981276) (xy 160.785048 -53.00853)
			(xy 160.784583 -53.036197) (xy 160.782352 -53.051456) (xy 169.041316 -53.051456) (xy 169.045387 -52.995834)
			(xy 169.057513 -52.941397) (xy 169.077436 -52.889306) (xy 169.104732 -52.840671) (xy 169.138818 -52.796528)
			(xy 169.178967 -52.757819) (xy 169.224325 -52.725368) (xy 169.273925 -52.699867) (xy 169.326709 -52.68186)
			(xy 169.381552 -52.67173) (xy 169.437286 -52.669693) (xy 169.492723 -52.675793) (xy 169.54668 -52.689899)
			(xy 169.598009 -52.711711) (xy 169.645615 -52.740765) (xy 169.688483 -52.77644) (xy 169.7257 -52.817977)
			(xy 169.756473 -52.86449) (xy 169.780145 -52.914987) (xy 169.796213 -52.968394) (xy 169.804333 -53.02357)
			(xy 169.804842 -53.051456) (xy 169.804333 -53.079342) (xy 169.796213 -53.134518) (xy 169.780145 -53.187925)
			(xy 169.756473 -53.238422) (xy 169.7257 -53.284935) (xy 169.688483 -53.326472) (xy 169.645615 -53.362147)
			(xy 169.598009 -53.391201) (xy 169.54668 -53.413013) (xy 169.492723 -53.427119) (xy 169.437286 -53.433219)
			(xy 169.381552 -53.431182) (xy 169.326709 -53.421052) (xy 169.273925 -53.403045) (xy 169.224325 -53.377544)
			(xy 169.178967 -53.345093) (xy 169.138818 -53.306384) (xy 169.104732 -53.262241) (xy 169.077436 -53.213606)
			(xy 169.057513 -53.161515) (xy 169.045387 -53.107078) (xy 169.041316 -53.051456) (xy 160.782352 -53.051456)
			(xy 160.776578 -53.090949) (xy 160.760755 -53.143973) (xy 160.737445 -53.194158) (xy 160.707136 -53.240453)
			(xy 160.670462 -53.28189) (xy 160.628193 -53.317599) (xy 160.604962 -53.332634) (xy 160.604708 -53.332888)
			(xy 160.595185 -53.339557) (xy 160.582876 -53.359248) (xy 160.581086 -53.370734) (xy 160.573212 -53.450744)
			(xy 160.572544 -53.462445) (xy 160.580627 -53.484417) (xy 160.588706 -53.492908) (xy 160.58896 -53.492908)
			(xy 160.60752 -53.51101) (xy 160.640102 -53.551337) (xy 160.666919 -53.595706) (xy 160.687475 -53.643301)
			(xy 160.701393 -53.693242) (xy 160.708414 -53.744608) (xy 160.708848 -53.77053) (xy 160.70835 -53.79778)
			(xy 160.700591 -53.851725) (xy 160.685234 -53.904017) (xy 160.662592 -53.953592) (xy 160.633126 -53.99944)
			(xy 160.597436 -54.040629) (xy 160.556248 -54.07632) (xy 160.510401 -54.105787) (xy 160.460827 -54.12843)
			(xy 160.408535 -54.143789) (xy 160.35459 -54.15155) (xy 160.32734 -54.152038) (xy 160.29997 -54.151564)
			(xy 160.245791 -54.14375) (xy 160.193287 -54.128264) (xy 160.14354 -54.105424) (xy 160.097573 -54.075699)
			(xy 160.076642 -54.058058) (xy 160.076388 -54.057804) (xy 160.069309 -54.052207) (xy 160.052386 -54.045966)
			(xy 160.043368 -54.045612) (xy 159.976312 -54.045612) (xy 159.967295 -54.045972) (xy 159.950378 -54.052217)
			(xy 159.943292 -54.057804) (xy 159.942784 -54.058312) (xy 159.921877 -54.075927) (xy 159.875934 -54.105562)
			(xy 159.826232 -54.128334) (xy 159.773787 -54.143776) (xy 159.719675 -54.151573) (xy 159.69234 -54.152038)
			(xy 159.665089 -54.151508) (xy 159.611143 -54.143757) (xy 159.558848 -54.128407) (xy 159.50927 -54.105772)
			(xy 159.463418 -54.076311) (xy 159.422226 -54.040624) (xy 159.386531 -53.999438) (xy 159.357062 -53.953592)
			(xy 159.334417 -53.904018) (xy 159.319058 -53.851726) (xy 159.311297 -53.79778) (xy 159.310832 -53.77053)
			(xy 158.946689 -53.77053) (xy 158.945834 -53.771546) (xy 158.94558 -53.7718) (xy 158.945326 -53.772054)
			(xy 158.939744 -53.779143) (xy 158.933496 -53.796058) (xy 158.933134 -53.805074) (xy 158.933134 -53.87213)
			(xy 158.933469 -53.881149) (xy 158.939731 -53.898066) (xy 158.945326 -53.90515) (xy 158.94558 -53.905404)
			(xy 158.945834 -53.905658) (xy 158.963436 -53.926579) (xy 158.993089 -53.972512) (xy 159.015877 -54.022209)
			(xy 159.031334 -54.074652) (xy 159.039142 -54.128765) (xy 159.039142 -54.183438) (xy 159.031333 -54.237551)
			(xy 159.015876 -54.289993) (xy 159.002031 -54.320186) (xy 161.230564 -54.320186) (xy 161.231041 -54.292852)
			(xy 161.238846 -54.238745) (xy 161.254293 -54.186306) (xy 161.277066 -54.136608) (xy 161.3067 -54.090669)
			(xy 161.32429 -54.069742) (xy 161.324544 -54.069488) (xy 161.324798 -54.069234) (xy 161.330376 -54.062142)
			(xy 161.336628 -54.045229) (xy 161.33699 -54.036214) (xy 161.33699 -53.969158) (xy 161.336607 -53.960144)
			(xy 161.330378 -53.943226) (xy 161.324798 -53.936138) (xy 161.324544 -53.935884) (xy 161.32429 -53.93563)
			(xy 161.306697 -53.914705) (xy 161.277059 -53.868768) (xy 161.254283 -53.81907) (xy 161.238835 -53.766629)
			(xy 161.231032 -53.71252) (xy 161.230564 -53.685186) (xy 161.23105 -53.657935) (xy 161.238806 -53.603987)
			(xy 161.254161 -53.551692) (xy 161.276803 -53.502115) (xy 161.306269 -53.456265) (xy 161.34196 -53.415074)
			(xy 161.383151 -53.379383) (xy 161.429001 -53.349917) (xy 161.478578 -53.327275) (xy 161.530873 -53.31192)
			(xy 161.584821 -53.304164) (xy 161.639323 -53.304164) (xy 161.693271 -53.31192) (xy 161.745566 -53.327275)
			(xy 161.795143 -53.349917) (xy 161.840993 -53.379383) (xy 161.882184 -53.415074) (xy 161.917875 -53.456265)
			(xy 161.943766 -53.496552) (xy 174.233564 -53.496552) (xy 174.233564 -53.442048) (xy 174.24132 -53.3881)
			(xy 174.256675 -53.335804) (xy 174.279316 -53.286226) (xy 174.308782 -53.240375) (xy 174.344474 -53.199183)
			(xy 174.385664 -53.163491) (xy 174.431514 -53.134023) (xy 174.481091 -53.11138) (xy 174.533386 -53.096023)
			(xy 174.587334 -53.088265) (xy 174.614586 -53.087778) (xy 174.641957 -53.088233) (xy 174.696137 -53.096051)
			(xy 174.748641 -53.111541) (xy 174.798388 -53.134386) (xy 174.844353 -53.164114) (xy 174.865284 -53.181758)
			(xy 174.865538 -53.182012) (xy 174.872637 -53.18758) (xy 174.889544 -53.193838) (xy 174.898558 -53.194204)
			(xy 174.965614 -53.194204) (xy 174.974631 -53.193853) (xy 174.991548 -53.187601) (xy 174.998634 -53.182012)
			(xy 174.999142 -53.181504) (xy 175.020079 -53.163926) (xy 175.066013 -53.134285) (xy 175.115708 -53.111506)
			(xy 175.168146 -53.096055) (xy 175.222253 -53.088248) (xy 175.249586 -53.087778) (xy 175.276839 -53.088268)
			(xy 175.330789 -53.096023) (xy 175.383087 -53.111378) (xy 175.432667 -53.134019) (xy 175.47852 -53.163485)
			(xy 175.519713 -53.199177) (xy 175.555407 -53.240369) (xy 175.584875 -53.286221) (xy 175.607517 -53.3358)
			(xy 175.622874 -53.388097) (xy 175.630631 -53.442048) (xy 175.630631 -53.496552) (xy 175.622874 -53.550503)
			(xy 175.607517 -53.6028) (xy 175.584875 -53.652379) (xy 175.555407 -53.698231) (xy 175.519713 -53.739423)
			(xy 175.47852 -53.775115) (xy 175.432667 -53.804581) (xy 175.383087 -53.827222) (xy 175.330789 -53.842577)
			(xy 175.276839 -53.850332) (xy 175.249586 -53.850794) (xy 175.222215 -53.850338) (xy 175.168036 -53.842518)
			(xy 175.115533 -53.827026) (xy 175.065786 -53.804183) (xy 175.019819 -53.774456) (xy 174.998888 -53.756814)
			(xy 174.998634 -53.75656) (xy 174.991545 -53.750977) (xy 174.97463 -53.744729) (xy 174.965614 -53.744368)
			(xy 174.898558 -53.744368) (xy 174.889545 -53.74476) (xy 174.872628 -53.750984) (xy 174.865538 -53.75656)
			(xy 174.86503 -53.757068) (xy 174.8441 -53.774655) (xy 174.798164 -53.804295) (xy 174.748468 -53.827073)
			(xy 174.696028 -53.842522) (xy 174.64192 -53.850326) (xy 174.614586 -53.850794) (xy 174.587334 -53.850335)
			(xy 174.533386 -53.842577) (xy 174.481091 -53.82722) (xy 174.431514 -53.804577) (xy 174.385664 -53.775109)
			(xy 174.344474 -53.739417) (xy 174.308782 -53.698225) (xy 174.279316 -53.652374) (xy 174.256675 -53.602796)
			(xy 174.24132 -53.5505) (xy 174.233564 -53.496552) (xy 161.943766 -53.496552) (xy 161.947341 -53.502115)
			(xy 161.969983 -53.551692) (xy 161.985338 -53.603987) (xy 161.993094 -53.657935) (xy 161.99358 -53.685186)
			(xy 161.993134 -53.712521) (xy 161.98532 -53.766629) (xy 161.969865 -53.819068) (xy 161.947085 -53.868766)
			(xy 161.917446 -53.914703) (xy 161.899854 -53.93563) (xy 161.8996 -53.935884) (xy 161.899346 -53.936138)
			(xy 161.893773 -53.943233) (xy 161.887519 -53.960144) (xy 161.887154 -53.969158) (xy 161.887154 -54.036214)
			(xy 161.887493 -54.045233) (xy 161.893752 -54.06215) (xy 161.899346 -54.069234) (xy 161.8996 -54.069488)
			(xy 161.899854 -54.069742) (xy 161.917426 -54.090685) (xy 161.947069 -54.136616) (xy 161.96985 -54.18631)
			(xy 161.985302 -54.238747) (xy 161.99311 -54.292853) (xy 161.99358 -54.320186) (xy 161.993094 -54.347437)
			(xy 161.985338 -54.401385) (xy 161.969983 -54.45368) (xy 161.947341 -54.503257) (xy 161.917875 -54.549107)
			(xy 161.882184 -54.590298) (xy 161.840993 -54.625989) (xy 161.795143 -54.655455) (xy 161.745566 -54.678097)
			(xy 161.693271 -54.693452) (xy 161.639323 -54.701208) (xy 161.584821 -54.701208) (xy 161.530873 -54.693452)
			(xy 161.478578 -54.678097) (xy 161.429001 -54.655455) (xy 161.383151 -54.625989) (xy 161.34196 -54.590298)
			(xy 161.306269 -54.549107) (xy 161.276803 -54.503257) (xy 161.254161 -54.45368) (xy 161.238806 -54.401385)
			(xy 161.23105 -54.347437) (xy 161.230564 -54.320186) (xy 159.002031 -54.320186) (xy 158.993087 -54.339691)
			(xy 158.963434 -54.385624) (xy 158.945834 -54.406546) (xy 158.94558 -54.4068) (xy 158.945326 -54.407054)
			(xy 158.939744 -54.414143) (xy 158.933496 -54.431058) (xy 158.933134 -54.440074) (xy 158.933134 -54.50713)
			(xy 158.933469 -54.516149) (xy 158.939731 -54.533066) (xy 158.945326 -54.54015) (xy 158.94558 -54.540404)
			(xy 158.945834 -54.540658) (xy 158.963425 -54.561584) (xy 158.993063 -54.607522) (xy 159.015839 -54.657219)
			(xy 159.031287 -54.70966) (xy 159.039091 -54.763768) (xy 159.039207 -54.770528) (xy 162.171126 -54.770528)
			(xy 162.171579 -54.743194) (xy 162.17939 -54.689086) (xy 162.194844 -54.636646) (xy 162.217623 -54.586949)
			(xy 162.24726 -54.541011) (xy 162.264852 -54.520084) (xy 162.265106 -54.51983) (xy 162.26536 -54.519576)
			(xy 162.27097 -54.512506) (xy 162.277201 -54.495576) (xy 162.277552 -54.486556) (xy 162.277552 -54.4195)
			(xy 162.277205 -54.410482) (xy 162.270952 -54.393565) (xy 162.26536 -54.38648) (xy 162.265106 -54.386226)
			(xy 162.264852 -54.385972) (xy 162.247272 -54.365036) (xy 162.217634 -54.319101) (xy 162.194856 -54.269406)
			(xy 162.179405 -54.216968) (xy 162.171597 -54.162861) (xy 162.171126 -54.135528) (xy 162.171612 -54.108277)
			(xy 162.179368 -54.054329) (xy 162.194723 -54.002034) (xy 162.217365 -53.952457) (xy 162.246831 -53.906607)
			(xy 162.282522 -53.865416) (xy 162.323713 -53.829725) (xy 162.369563 -53.800259) (xy 162.41914 -53.777617)
			(xy 162.471435 -53.762262) (xy 162.525383 -53.754506) (xy 162.579885 -53.754506) (xy 162.633833 -53.762262)
			(xy 162.686128 -53.777617) (xy 162.735705 -53.800259) (xy 162.781555 -53.829725) (xy 162.822746 -53.865416)
			(xy 162.858437 -53.906607) (xy 162.887903 -53.952457) (xy 162.892978 -53.96357) (xy 166.872156 -53.96357)
			(xy 166.876227 -53.907948) (xy 166.888353 -53.853511) (xy 166.908276 -53.80142) (xy 166.935572 -53.752785)
			(xy 166.969658 -53.708642) (xy 167.009807 -53.669933) (xy 167.055165 -53.637482) (xy 167.104765 -53.611981)
			(xy 167.157549 -53.593974) (xy 167.212392 -53.583844) (xy 167.268126 -53.581807) (xy 167.323563 -53.587907)
			(xy 167.37752 -53.602013) (xy 167.428849 -53.623825) (xy 167.476455 -53.652879) (xy 167.519323 -53.688554)
			(xy 167.55654 -53.730091) (xy 167.587313 -53.776604) (xy 167.610985 -53.827101) (xy 167.627053 -53.880508)
			(xy 167.635173 -53.935684) (xy 167.635682 -53.96357) (xy 167.635173 -53.991456) (xy 167.627053 -54.046632)
			(xy 167.620788 -54.067456) (xy 169.041316 -54.067456) (xy 169.045387 -54.011834) (xy 169.057513 -53.957397)
			(xy 169.077436 -53.905306) (xy 169.104732 -53.856671) (xy 169.138818 -53.812528) (xy 169.178967 -53.773819)
			(xy 169.224325 -53.741368) (xy 169.273925 -53.715867) (xy 169.326709 -53.69786) (xy 169.381552 -53.68773)
			(xy 169.437286 -53.685693) (xy 169.492723 -53.691793) (xy 169.54668 -53.705899) (xy 169.598009 -53.727711)
			(xy 169.645615 -53.756765) (xy 169.688483 -53.79244) (xy 169.7257 -53.833977) (xy 169.756473 -53.88049)
			(xy 169.780145 -53.930987) (xy 169.796213 -53.984394) (xy 169.804333 -54.03957) (xy 169.804842 -54.067456)
			(xy 169.804333 -54.095342) (xy 169.796213 -54.150518) (xy 169.780145 -54.203925) (xy 169.763747 -54.238906)
			(xy 176.486056 -54.238906) (xy 176.490127 -54.183284) (xy 176.502253 -54.128847) (xy 176.522176 -54.076756)
			(xy 176.549472 -54.028121) (xy 176.583558 -53.983978) (xy 176.623707 -53.945269) (xy 176.669065 -53.912818)
			(xy 176.718665 -53.887317) (xy 176.771449 -53.86931) (xy 176.826292 -53.85918) (xy 176.882026 -53.857143)
			(xy 176.937463 -53.863243) (xy 176.99142 -53.877349) (xy 177.042749 -53.899161) (xy 177.090355 -53.928215)
			(xy 177.133223 -53.96389) (xy 177.17044 -54.005427) (xy 177.201213 -54.05194) (xy 177.224885 -54.102437)
			(xy 177.240953 -54.155844) (xy 177.249073 -54.21102) (xy 177.249582 -54.238906) (xy 177.249073 -54.266792)
			(xy 177.240953 -54.321968) (xy 177.224885 -54.375375) (xy 177.201213 -54.425872) (xy 177.17044 -54.472385)
			(xy 177.133223 -54.513922) (xy 177.090355 -54.549597) (xy 177.042749 -54.578651) (xy 176.99142 -54.600463)
			(xy 176.937463 -54.614569) (xy 176.882026 -54.620669) (xy 176.826292 -54.618632) (xy 176.771449 -54.608502)
			(xy 176.718665 -54.590495) (xy 176.669065 -54.564994) (xy 176.623707 -54.532543) (xy 176.583558 -54.493834)
			(xy 176.549472 -54.449691) (xy 176.522176 -54.401056) (xy 176.502253 -54.348965) (xy 176.490127 -54.294528)
			(xy 176.486056 -54.238906) (xy 169.763747 -54.238906) (xy 169.756473 -54.254422) (xy 169.7257 -54.300935)
			(xy 169.688483 -54.342472) (xy 169.645615 -54.378147) (xy 169.598009 -54.407201) (xy 169.54668 -54.429013)
			(xy 169.492723 -54.443119) (xy 169.437286 -54.449219) (xy 169.381552 -54.447182) (xy 169.326709 -54.437052)
			(xy 169.273925 -54.419045) (xy 169.224325 -54.393544) (xy 169.178967 -54.361093) (xy 169.138818 -54.322384)
			(xy 169.104732 -54.278241) (xy 169.077436 -54.229606) (xy 169.057513 -54.177515) (xy 169.045387 -54.123078)
			(xy 169.041316 -54.067456) (xy 167.620788 -54.067456) (xy 167.610985 -54.100039) (xy 167.587313 -54.150536)
			(xy 167.55654 -54.197049) (xy 167.519323 -54.238586) (xy 167.476455 -54.274261) (xy 167.428849 -54.303315)
			(xy 167.37752 -54.325127) (xy 167.323563 -54.339233) (xy 167.268126 -54.345333) (xy 167.212392 -54.343296)
			(xy 167.157549 -54.333166) (xy 167.104765 -54.315159) (xy 167.055165 -54.289658) (xy 167.009807 -54.257207)
			(xy 166.969658 -54.218498) (xy 166.935572 -54.174355) (xy 166.908276 -54.12572) (xy 166.888353 -54.073629)
			(xy 166.876227 -54.019192) (xy 166.872156 -53.96357) (xy 162.892978 -53.96357) (xy 162.910545 -54.002034)
			(xy 162.9259 -54.054329) (xy 162.933656 -54.108277) (xy 162.934142 -54.135528) (xy 162.933671 -54.162862)
			(xy 162.925865 -54.216969) (xy 162.910416 -54.269409) (xy 162.887641 -54.319107) (xy 162.858007 -54.365045)
			(xy 162.840416 -54.385972) (xy 162.840162 -54.386226) (xy 162.839908 -54.38648) (xy 162.834325 -54.393569)
			(xy 162.828076 -54.410484) (xy 162.827716 -54.4195) (xy 162.827716 -54.486556) (xy 162.828091 -54.495571)
			(xy 162.834326 -54.512488) (xy 162.839908 -54.519576) (xy 162.840162 -54.51983) (xy 162.840416 -54.520084)
			(xy 162.858017 -54.541003) (xy 162.887653 -54.586942) (xy 162.910428 -54.636642) (xy 162.925874 -54.689084)
			(xy 162.933675 -54.743193) (xy 162.934142 -54.770528) (xy 162.933656 -54.797779) (xy 162.9259 -54.851727)
			(xy 162.910545 -54.904022) (xy 162.887903 -54.953599) (xy 162.858437 -54.999449) (xy 162.822746 -55.04064)
			(xy 162.781555 -55.076331) (xy 162.770468 -55.083456) (xy 169.041316 -55.083456) (xy 169.045387 -55.027834)
			(xy 169.057513 -54.973397) (xy 169.077436 -54.921306) (xy 169.104732 -54.872671) (xy 169.138818 -54.828528)
			(xy 169.178967 -54.789819) (xy 169.224325 -54.757368) (xy 169.273925 -54.731867) (xy 169.326709 -54.71386)
			(xy 169.381552 -54.70373) (xy 169.437286 -54.701693) (xy 169.492723 -54.707793) (xy 169.54668 -54.721899)
			(xy 169.598009 -54.743711) (xy 169.645615 -54.772765) (xy 169.688483 -54.80844) (xy 169.7257 -54.849977)
			(xy 169.756473 -54.89649) (xy 169.780145 -54.946987) (xy 169.7928 -54.989051) (xy 172.001168 -54.989051)
			(xy 172.001168 -54.934549) (xy 172.008924 -54.880602) (xy 172.024278 -54.828307) (xy 172.046919 -54.77873)
			(xy 172.076384 -54.732879) (xy 172.112074 -54.691688) (xy 172.153263 -54.655996) (xy 172.199112 -54.626528)
			(xy 172.248688 -54.603885) (xy 172.300982 -54.588528) (xy 172.354929 -54.580769) (xy 172.38218 -54.580282)
			(xy 172.410271 -54.580793) (xy 172.465847 -54.589017) (xy 172.519616 -54.605305) (xy 172.570413 -54.629305)
			(xy 172.61714 -54.660498) (xy 172.658786 -54.698208) (xy 172.694449 -54.741619) (xy 172.709332 -54.765448)
			(xy 172.71492 -54.774592) (xy 172.731938 -54.786784) (xy 172.824902 -54.80685) (xy 172.845476 -54.802786)
			(xy 172.854112 -54.79669) (xy 172.87817 -54.780681) (xy 172.930104 -54.755341) (xy 172.985264 -54.738118)
			(xy 173.042389 -54.729405) (xy 173.071282 -54.728872) (xy 173.098532 -54.729395) (xy 173.112566 -54.731412)
			(xy 181.620668 -54.731412) (xy 181.621101 -54.704077) (xy 181.628916 -54.649968) (xy 181.644374 -54.597528)
			(xy 181.667157 -54.54783) (xy 181.6968 -54.501894) (xy 181.714394 -54.480968) (xy 181.714648 -54.480714)
			(xy 181.714902 -54.48046) (xy 181.72047 -54.473361) (xy 181.726728 -54.456454) (xy 181.727094 -54.44744)
			(xy 181.727094 -54.380384) (xy 181.726746 -54.371366) (xy 181.720492 -54.354449) (xy 181.714902 -54.347364)
			(xy 181.714648 -54.34711) (xy 181.714394 -54.346856) (xy 181.696804 -54.325925) (xy 181.667149 -54.279994)
			(xy 181.644358 -54.230298) (xy 181.628899 -54.177857) (xy 181.621089 -54.123745) (xy 181.621087 -54.069073)
			(xy 181.628895 -54.014961) (xy 181.644352 -53.962519) (xy 181.66714 -53.912822) (xy 181.696793 -53.86689)
			(xy 181.714394 -53.845968) (xy 181.714648 -53.845714) (xy 181.714902 -53.84546) (xy 181.72047 -53.838361)
			(xy 181.726728 -53.821454) (xy 181.727094 -53.81244) (xy 181.727094 -53.745384) (xy 181.726746 -53.736366)
			(xy 181.720492 -53.719449) (xy 181.714902 -53.712364) (xy 181.714648 -53.71211) (xy 181.714394 -53.711856)
			(xy 181.696804 -53.690925) (xy 181.667149 -53.644994) (xy 181.644358 -53.595298) (xy 181.628899 -53.542857)
			(xy 181.621089 -53.488745) (xy 181.621087 -53.434073) (xy 181.628895 -53.379961) (xy 181.644352 -53.327519)
			(xy 181.66714 -53.277822) (xy 181.696793 -53.23189) (xy 181.714394 -53.210968) (xy 181.714648 -53.210714)
			(xy 181.714902 -53.21046) (xy 181.72047 -53.203361) (xy 181.726728 -53.186454) (xy 181.727094 -53.17744)
			(xy 181.727094 -53.110384) (xy 181.726746 -53.101366) (xy 181.720492 -53.084449) (xy 181.714902 -53.077364)
			(xy 181.714648 -53.07711) (xy 181.714394 -53.076856) (xy 181.696813 -53.055921) (xy 181.667173 -53.009986)
			(xy 181.644395 -52.960291) (xy 181.628944 -52.907853) (xy 181.621138 -52.853746) (xy 181.620668 -52.826412)
			(xy 181.621154 -52.799161) (xy 181.62891 -52.745213) (xy 181.644265 -52.692918) (xy 181.666907 -52.643341)
			(xy 181.696373 -52.597491) (xy 181.732064 -52.5563) (xy 181.773255 -52.520609) (xy 181.819105 -52.491143)
			(xy 181.868682 -52.468501) (xy 181.920977 -52.453146) (xy 181.974925 -52.44539) (xy 182.029427 -52.44539)
			(xy 182.083375 -52.453146) (xy 182.13567 -52.468501) (xy 182.185247 -52.491143) (xy 182.231097 -52.520609)
			(xy 182.272288 -52.5563) (xy 182.307979 -52.597491) (xy 182.337445 -52.643341) (xy 182.360087 -52.692918)
			(xy 182.375442 -52.745213) (xy 182.383198 -52.799161) (xy 182.383684 -52.826412) (xy 182.383194 -52.853745)
			(xy 182.375391 -52.907851) (xy 182.359946 -52.96029) (xy 182.337176 -53.009988) (xy 182.307546 -53.055928)
			(xy 182.289958 -53.076856) (xy 182.289704 -53.07711) (xy 182.28945 -53.077364) (xy 182.283866 -53.084452)
			(xy 182.277619 -53.101368) (xy 182.277258 -53.110384) (xy 182.277258 -53.17744) (xy 182.277583 -53.18646)
			(xy 182.283851 -53.203378) (xy 182.28945 -53.21046) (xy 182.289704 -53.210714) (xy 182.289958 -53.210968)
			(xy 182.307569 -53.231881) (xy 182.337219 -53.277816) (xy 182.360006 -53.327515) (xy 182.375461 -53.379959)
			(xy 182.383268 -53.434072) (xy 182.383266 -53.488746) (xy 182.375457 -53.542859) (xy 182.359999 -53.595302)
			(xy 182.337211 -53.645) (xy 182.307558 -53.690933) (xy 182.289958 -53.711856) (xy 182.289704 -53.71211)
			(xy 182.28945 -53.712364) (xy 182.283866 -53.719452) (xy 182.277619 -53.736368) (xy 182.277258 -53.745384)
			(xy 182.277258 -53.81244) (xy 182.277583 -53.82146) (xy 182.283851 -53.838378) (xy 182.28945 -53.84546)
			(xy 182.289704 -53.845714) (xy 182.289958 -53.845968) (xy 182.307569 -53.866881) (xy 182.337219 -53.912816)
			(xy 182.360006 -53.962515) (xy 182.375461 -54.014959) (xy 182.383268 -54.069072) (xy 182.383266 -54.123746)
			(xy 182.375457 -54.177859) (xy 182.359999 -54.230302) (xy 182.337211 -54.28) (xy 182.307558 -54.325933)
			(xy 182.289958 -54.346856) (xy 182.289704 -54.34711) (xy 182.28945 -54.347364) (xy 182.283866 -54.354452)
			(xy 182.277619 -54.371368) (xy 182.277258 -54.380384) (xy 182.277258 -54.44744) (xy 182.277583 -54.45646)
			(xy 182.283851 -54.473378) (xy 182.28945 -54.48046) (xy 182.289704 -54.480714) (xy 182.289958 -54.480968)
			(xy 182.307542 -54.5019) (xy 182.337183 -54.547835) (xy 182.359962 -54.597531) (xy 182.375412 -54.64997)
			(xy 182.383215 -54.704078) (xy 182.383684 -54.731412) (xy 182.383198 -54.758663) (xy 182.378534 -54.791102)
			(xy 184.276492 -54.791102) (xy 184.276996 -54.76377) (xy 184.284797 -54.709664) (xy 184.300239 -54.657226)
			(xy 184.323006 -54.607527) (xy 184.352632 -54.561587) (xy 184.370218 -54.540658) (xy 184.370472 -54.540404)
			(xy 184.370726 -54.54015) (xy 184.376301 -54.533055) (xy 184.382554 -54.516145) (xy 184.382918 -54.50713)
			(xy 184.382918 -54.440074) (xy 184.38257 -54.431056) (xy 184.376316 -54.41414) (xy 184.370726 -54.407054)
			(xy 184.370472 -54.4068) (xy 184.370218 -54.406546) (xy 184.352618 -54.385623) (xy 184.322961 -54.339692)
			(xy 184.300169 -54.289995) (xy 184.28471 -54.237552) (xy 184.2769 -54.183439) (xy 184.276899 -54.128765)
			(xy 184.284709 -54.074651) (xy 184.300168 -54.022208) (xy 184.322959 -53.972511) (xy 184.352616 -53.926579)
			(xy 184.370218 -53.905658) (xy 184.370472 -53.905404) (xy 184.370726 -53.90515) (xy 184.376301 -53.898055)
			(xy 184.382554 -53.881145) (xy 184.382918 -53.87213) (xy 184.382918 -53.805074) (xy 184.38257 -53.796056)
			(xy 184.376316 -53.77914) (xy 184.370726 -53.772054) (xy 184.370472 -53.7718) (xy 184.370218 -53.771546)
			(xy 184.352618 -53.750623) (xy 184.322961 -53.704692) (xy 184.300169 -53.654995) (xy 184.28471 -53.602552)
			(xy 184.2769 -53.548439) (xy 184.276899 -53.493765) (xy 184.284709 -53.439651) (xy 184.300168 -53.387208)
			(xy 184.322959 -53.337511) (xy 184.352616 -53.291579) (xy 184.370218 -53.270658) (xy 184.370472 -53.270404)
			(xy 184.370726 -53.27015) (xy 184.376301 -53.263055) (xy 184.382554 -53.246145) (xy 184.382918 -53.23713)
			(xy 184.382918 -53.170074) (xy 184.38257 -53.161056) (xy 184.376316 -53.14414) (xy 184.370726 -53.137054)
			(xy 184.370472 -53.1368) (xy 184.370218 -53.136546) (xy 184.352636 -53.115611) (xy 184.322996 -53.069677)
			(xy 184.300217 -53.019982) (xy 184.284767 -52.967543) (xy 184.276962 -52.913436) (xy 184.276492 -52.886102)
			(xy 184.276978 -52.858851) (xy 184.284734 -52.804903) (xy 184.300089 -52.752608) (xy 184.322731 -52.703031)
			(xy 184.352197 -52.657181) (xy 184.387888 -52.61599) (xy 184.429079 -52.580299) (xy 184.474929 -52.550833)
			(xy 184.524506 -52.528191) (xy 184.576801 -52.512836) (xy 184.630749 -52.50508) (xy 184.685251 -52.50508)
			(xy 184.739199 -52.512836) (xy 184.753517 -52.51704) (xy 188.940184 -52.51704) (xy 188.944255 -52.461418)
			(xy 188.956381 -52.406981) (xy 188.976304 -52.35489) (xy 189.0036 -52.306255) (xy 189.037686 -52.262112)
			(xy 189.077835 -52.223403) (xy 189.123193 -52.190952) (xy 189.172793 -52.165451) (xy 189.225577 -52.147444)
			(xy 189.28042 -52.137314) (xy 189.336154 -52.135277) (xy 189.391591 -52.141377) (xy 189.445548 -52.155483)
			(xy 189.496877 -52.177295) (xy 189.544483 -52.206349) (xy 189.587351 -52.242024) (xy 189.624568 -52.283561)
			(xy 189.655341 -52.330074) (xy 189.679013 -52.380571) (xy 189.695081 -52.433978) (xy 189.703201 -52.489154)
			(xy 189.70371 -52.51704) (xy 189.703201 -52.544926) (xy 189.696951 -52.587398) (xy 192.85534 -52.587398)
			(xy 192.859411 -52.531776) (xy 192.871537 -52.477339) (xy 192.89146 -52.425248) (xy 192.918756 -52.376613)
			(xy 192.952842 -52.33247) (xy 192.992991 -52.293761) (xy 193.038349 -52.26131) (xy 193.087949 -52.235809)
			(xy 193.140733 -52.217802) (xy 193.195576 -52.207672) (xy 193.25131 -52.205635) (xy 193.306747 -52.211735)
			(xy 193.360704 -52.225841) (xy 193.412033 -52.247653) (xy 193.459639 -52.276707) (xy 193.502507 -52.312382)
			(xy 193.539724 -52.353919) (xy 193.570497 -52.400432) (xy 193.594169 -52.450929) (xy 193.610237 -52.504336)
			(xy 193.618357 -52.559512) (xy 193.618442 -52.564157) (xy 197.927107 -52.564157) (xy 197.927107 -52.509643)
			(xy 197.934865 -52.455684) (xy 197.950224 -52.403378) (xy 197.97287 -52.353791) (xy 198.002343 -52.307931)
			(xy 198.038043 -52.266733) (xy 198.079243 -52.231035) (xy 198.125103 -52.201564) (xy 198.174692 -52.178919)
			(xy 198.226998 -52.163562) (xy 198.280957 -52.155806) (xy 198.308214 -52.155344) (xy 198.335585 -52.155791)
			(xy 198.389765 -52.163612) (xy 198.442269 -52.179105) (xy 198.492016 -52.201951) (xy 198.537981 -52.23168)
			(xy 198.558912 -52.249324) (xy 198.559166 -52.249578) (xy 198.566251 -52.255166) (xy 198.583169 -52.26141)
			(xy 198.592186 -52.26177) (xy 198.659242 -52.26177) (xy 198.668257 -52.261392) (xy 198.685174 -52.25516)
			(xy 198.692262 -52.249578) (xy 198.69277 -52.24907) (xy 198.713692 -52.231474) (xy 198.759631 -52.201837)
			(xy 198.809329 -52.179062) (xy 198.861771 -52.163615) (xy 198.91588 -52.155812) (xy 198.943214 -52.155344)
			(xy 198.970461 -52.155927) (xy 199.024401 -52.163684) (xy 199.076687 -52.179039) (xy 199.126256 -52.201678)
			(xy 199.172099 -52.231141) (xy 199.213282 -52.266828) (xy 199.248968 -52.308012) (xy 199.278429 -52.353856)
			(xy 199.301066 -52.403426) (xy 199.316419 -52.455713) (xy 199.324174 -52.509653) (xy 199.324174 -52.555948)
			(xy 200.683902 -52.555948) (xy 200.683902 -52.501452) (xy 200.691658 -52.447509) (xy 200.70701 -52.39522)
			(xy 200.729648 -52.345647) (xy 200.759111 -52.299801) (xy 200.794797 -52.258614) (xy 200.835982 -52.222925)
			(xy 200.881826 -52.19346) (xy 200.931397 -52.170819) (xy 200.983686 -52.155463) (xy 201.037628 -52.147704)
			(xy 201.064876 -52.147216) (xy 201.092246 -52.147692) (xy 201.146425 -52.155507) (xy 201.198928 -52.170994)
			(xy 201.248675 -52.193833) (xy 201.294642 -52.223556) (xy 201.315574 -52.241196) (xy 201.315828 -52.24145)
			(xy 201.322927 -52.247019) (xy 201.339834 -52.253275) (xy 201.348848 -52.253642) (xy 201.415904 -52.253642)
			(xy 201.424923 -52.253299) (xy 201.44184 -52.247043) (xy 201.448924 -52.24145) (xy 201.449432 -52.240942)
			(xy 201.470378 -52.223374) (xy 201.516309 -52.193731) (xy 201.566001 -52.170949) (xy 201.618438 -52.155496)
			(xy 201.672543 -52.147687) (xy 201.699876 -52.147216) (xy 201.727132 -52.147629) (xy 201.781089 -52.155384)
			(xy 201.833393 -52.170739) (xy 201.882979 -52.193381) (xy 201.928838 -52.222851) (xy 201.970036 -52.258547)
			(xy 202.005735 -52.299743) (xy 202.035207 -52.3456) (xy 202.057853 -52.395185) (xy 202.073211 -52.447488)
			(xy 202.080969 -52.501444) (xy 202.080969 -52.555956) (xy 202.073211 -52.609912) (xy 202.057853 -52.662215)
			(xy 202.035207 -52.7118) (xy 202.005735 -52.757657) (xy 201.970036 -52.798853) (xy 201.928838 -52.834549)
			(xy 201.882979 -52.864019) (xy 201.833393 -52.886661) (xy 201.781089 -52.902016) (xy 201.727132 -52.909771)
			(xy 201.699876 -52.910232) (xy 201.672504 -52.909797) (xy 201.618323 -52.901974) (xy 201.565819 -52.886479)
			(xy 201.516073 -52.86363) (xy 201.470108 -52.833897) (xy 201.449178 -52.816252) (xy 201.448924 -52.815998)
			(xy 201.441835 -52.810415) (xy 201.42492 -52.804166) (xy 201.415904 -52.803806) (xy 201.348848 -52.803806)
			(xy 201.339833 -52.804185) (xy 201.322916 -52.810417) (xy 201.315828 -52.815998) (xy 201.31532 -52.816506)
			(xy 201.294398 -52.834103) (xy 201.24846 -52.863741) (xy 201.198761 -52.886516) (xy 201.14632 -52.901963)
			(xy 201.09221 -52.909764) (xy 201.064876 -52.910232) (xy 201.037628 -52.909696) (xy 200.983686 -52.901937)
			(xy 200.931397 -52.886581) (xy 200.881826 -52.86394) (xy 200.835982 -52.834475) (xy 200.794797 -52.798786)
			(xy 200.759111 -52.757599) (xy 200.729648 -52.711753) (xy 200.70701 -52.66218) (xy 200.691658 -52.609891)
			(xy 200.683902 -52.555948) (xy 199.324174 -52.555948) (xy 199.324174 -52.564147) (xy 199.316419 -52.618087)
			(xy 199.301066 -52.670374) (xy 199.278429 -52.719944) (xy 199.248968 -52.765788) (xy 199.213282 -52.806972)
			(xy 199.172099 -52.842659) (xy 199.126256 -52.872122) (xy 199.076687 -52.894761) (xy 199.024401 -52.910116)
			(xy 198.970461 -52.917873) (xy 198.943214 -52.91836) (xy 198.915844 -52.917895) (xy 198.861664 -52.910079)
			(xy 198.809161 -52.89459) (xy 198.759414 -52.871748) (xy 198.713447 -52.842022) (xy 198.692516 -52.82438)
			(xy 198.692262 -52.824126) (xy 198.685168 -52.818551) (xy 198.668257 -52.812299) (xy 198.659242 -52.811934)
			(xy 198.592186 -52.811934) (xy 198.583168 -52.812277) (xy 198.56625 -52.818533) (xy 198.559166 -52.824126)
			(xy 198.558658 -52.824634) (xy 198.537726 -52.842218) (xy 198.49179 -52.871856) (xy 198.442094 -52.894634)
			(xy 198.389655 -52.910084) (xy 198.335548 -52.91789) (xy 198.308214 -52.91836) (xy 198.280957 -52.917994)
			(xy 198.226998 -52.910238) (xy 198.174692 -52.894881) (xy 198.125103 -52.872236) (xy 198.079243 -52.842765)
			(xy 198.038043 -52.807067) (xy 198.002343 -52.765869) (xy 197.97287 -52.720009) (xy 197.950224 -52.670422)
			(xy 197.934865 -52.618116) (xy 197.927107 -52.564157) (xy 193.618442 -52.564157) (xy 193.618866 -52.587398)
			(xy 193.618357 -52.615284) (xy 193.610237 -52.67046) (xy 193.594169 -52.723867) (xy 193.570497 -52.774364)
			(xy 193.539724 -52.820877) (xy 193.502507 -52.862414) (xy 193.459639 -52.898089) (xy 193.412033 -52.927143)
			(xy 193.360704 -52.948955) (xy 193.306747 -52.963061) (xy 193.25131 -52.969161) (xy 193.195576 -52.967124)
			(xy 193.140733 -52.956994) (xy 193.087949 -52.938987) (xy 193.038349 -52.913486) (xy 192.992991 -52.881035)
			(xy 192.952842 -52.842326) (xy 192.918756 -52.798183) (xy 192.89146 -52.749548) (xy 192.871537 -52.697457)
			(xy 192.859411 -52.64302) (xy 192.85534 -52.587398) (xy 189.696951 -52.587398) (xy 189.695081 -52.600102)
			(xy 189.679013 -52.653509) (xy 189.655341 -52.704006) (xy 189.624568 -52.750519) (xy 189.587351 -52.792056)
			(xy 189.544483 -52.827731) (xy 189.496877 -52.856785) (xy 189.445548 -52.878597) (xy 189.391591 -52.892703)
			(xy 189.336154 -52.898803) (xy 189.28042 -52.896766) (xy 189.225577 -52.886636) (xy 189.172793 -52.868629)
			(xy 189.123193 -52.843128) (xy 189.077835 -52.810677) (xy 189.037686 -52.771968) (xy 189.0036 -52.727825)
			(xy 188.976304 -52.67919) (xy 188.956381 -52.627099) (xy 188.944255 -52.572662) (xy 188.940184 -52.51704)
			(xy 184.753517 -52.51704) (xy 184.791494 -52.528191) (xy 184.841071 -52.550833) (xy 184.886921 -52.580299)
			(xy 184.928112 -52.61599) (xy 184.963803 -52.657181) (xy 184.993269 -52.703031) (xy 185.015911 -52.752608)
			(xy 185.031266 -52.804903) (xy 185.039022 -52.858851) (xy 185.039508 -52.886102) (xy 185.039006 -52.913435)
			(xy 185.031205 -52.96754) (xy 185.015763 -53.019979) (xy 184.992995 -53.069677) (xy 184.963368 -53.115617)
			(xy 184.945782 -53.136546) (xy 184.945528 -53.1368) (xy 184.945274 -53.137054) (xy 184.939698 -53.144147)
			(xy 184.933446 -53.161059) (xy 184.933082 -53.170074) (xy 184.933082 -53.23713) (xy 184.933428 -53.246148)
			(xy 184.939684 -53.263065) (xy 184.945274 -53.27015) (xy 184.945528 -53.270404) (xy 184.945782 -53.270658)
			(xy 184.963386 -53.291578) (xy 184.993043 -53.33751) (xy 185.015835 -53.387207) (xy 185.031294 -53.439651)
			(xy 185.039103 -53.493764) (xy 185.039103 -53.548439) (xy 185.031293 -53.602552) (xy 185.015834 -53.654996)
			(xy 184.993042 -53.704693) (xy 184.963385 -53.750625) (xy 184.946637 -53.77053) (xy 185.31078 -53.77053)
			(xy 185.311289 -53.741612) (xy 185.320016 -53.684439) (xy 185.337274 -53.629239) (xy 185.362667 -53.577277)
			(xy 185.395613 -53.529743) (xy 185.435358 -53.487728) (xy 185.457846 -53.46954) (xy 185.465215 -53.46324)
			(xy 185.475021 -53.446538) (xy 185.476896 -53.437028) (xy 185.477404 -53.429408) (xy 185.477404 -53.349652)
			(xy 185.476896 -53.342032) (xy 185.47504 -53.332515) (xy 185.465235 -53.315801) (xy 185.457846 -53.30952)
			(xy 185.435361 -53.291331) (xy 185.395628 -53.249309) (xy 185.362691 -53.201774) (xy 185.337303 -53.149812)
			(xy 185.320047 -53.094615) (xy 185.311316 -53.037446) (xy 185.31078 -53.00853) (xy 185.311283 -52.981278)
			(xy 185.319036 -52.92733) (xy 185.334387 -52.875033) (xy 185.357026 -52.825454) (xy 185.386489 -52.779601)
			(xy 185.422179 -52.738409) (xy 185.463368 -52.702714) (xy 185.509217 -52.673246) (xy 185.558794 -52.650602)
			(xy 185.611088 -52.635245) (xy 185.665036 -52.627486) (xy 185.692288 -52.627022) (xy 185.692542 -52.627022)
			(xy 185.718838 -52.627446) (xy 185.770929 -52.634697) (xy 185.821531 -52.64903) (xy 185.869687 -52.670172)
			(xy 185.914486 -52.697723) (xy 185.955079 -52.731162) (xy 185.973212 -52.750212) (xy 185.980778 -52.757659)
			(xy 186.0002 -52.766181) (xy 186.010804 -52.766722) (xy 186.084972 -52.766722) (xy 186.0956 -52.766282)
			(xy 186.115065 -52.757754) (xy 186.122564 -52.750212) (xy 186.140703 -52.731167) (xy 186.181283 -52.697709)
			(xy 186.226077 -52.670148) (xy 186.274235 -52.649007) (xy 186.324842 -52.634687) (xy 186.376937 -52.627461)
			(xy 186.403234 -52.627022) (xy 186.403488 -52.627022) (xy 186.430742 -52.627467) (xy 186.484695 -52.635223)
			(xy 186.536995 -52.650579) (xy 186.586577 -52.673222) (xy 186.632432 -52.702692) (xy 186.673625 -52.738387)
			(xy 186.709319 -52.779583) (xy 186.738787 -52.825439) (xy 186.761428 -52.875022) (xy 186.776781 -52.927323)
			(xy 186.784535 -52.981276) (xy 186.784996 -53.00853) (xy 186.784509 -53.036196) (xy 186.782278 -53.051456)
			(xy 195.041264 -53.051456) (xy 195.045335 -52.995834) (xy 195.057461 -52.941397) (xy 195.077384 -52.889306)
			(xy 195.10468 -52.840671) (xy 195.138766 -52.796528) (xy 195.178915 -52.757819) (xy 195.224273 -52.725368)
			(xy 195.273873 -52.699867) (xy 195.326657 -52.68186) (xy 195.3815 -52.67173) (xy 195.437234 -52.669693)
			(xy 195.492671 -52.675793) (xy 195.546628 -52.689899) (xy 195.597957 -52.711711) (xy 195.645563 -52.740765)
			(xy 195.688431 -52.77644) (xy 195.725648 -52.817977) (xy 195.756421 -52.86449) (xy 195.780093 -52.914987)
			(xy 195.796161 -52.968394) (xy 195.804281 -53.02357) (xy 195.80479 -53.051456) (xy 195.804281 -53.079342)
			(xy 195.796161 -53.134518) (xy 195.780093 -53.187925) (xy 195.756421 -53.238422) (xy 195.725648 -53.284935)
			(xy 195.688431 -53.326472) (xy 195.645563 -53.362147) (xy 195.597957 -53.391201) (xy 195.546628 -53.413013)
			(xy 195.492671 -53.427119) (xy 195.437234 -53.433219) (xy 195.3815 -53.431182) (xy 195.326657 -53.421052)
			(xy 195.273873 -53.403045) (xy 195.224273 -53.377544) (xy 195.178915 -53.345093) (xy 195.138766 -53.306384)
			(xy 195.10468 -53.262241) (xy 195.077384 -53.213606) (xy 195.057461 -53.161515) (xy 195.045335 -53.107078)
			(xy 195.041264 -53.051456) (xy 186.782278 -53.051456) (xy 186.776505 -53.090946) (xy 186.760684 -53.143969)
			(xy 186.737377 -53.194153) (xy 186.707072 -53.240448) (xy 186.670403 -53.281886) (xy 186.628139 -53.317598)
			(xy 186.60491 -53.332634) (xy 186.604656 -53.332888) (xy 186.595123 -53.339545) (xy 186.582822 -53.359246)
			(xy 186.581034 -53.370734) (xy 186.57316 -53.450744) (xy 186.572478 -53.462446) (xy 186.580568 -53.48442)
			(xy 186.588654 -53.492908) (xy 186.588908 -53.492908) (xy 186.607477 -53.511001) (xy 186.640056 -53.551331)
			(xy 186.666871 -53.595702) (xy 186.687425 -53.643298) (xy 186.701342 -53.69324) (xy 186.708362 -53.744608)
			(xy 186.708796 -53.77053) (xy 186.70835 -53.797783) (xy 186.700589 -53.851732) (xy 186.68523 -53.904029)
			(xy 186.662584 -53.953607) (xy 186.633114 -53.999457) (xy 186.597418 -54.040648) (xy 186.556224 -54.076339)
			(xy 186.51037 -54.105804) (xy 186.460789 -54.128444) (xy 186.408491 -54.143798) (xy 186.354541 -54.151553)
			(xy 186.327288 -54.152038) (xy 186.299917 -54.151594) (xy 186.245736 -54.143773) (xy 186.193232 -54.12828)
			(xy 186.143486 -54.105433) (xy 186.09752 -54.075702) (xy 186.07659 -54.058058) (xy 186.076336 -54.057804)
			(xy 186.069243 -54.052227) (xy 186.052331 -54.045974) (xy 186.043316 -54.045612) (xy 185.97626 -54.045612)
			(xy 185.967241 -54.045947) (xy 185.950324 -54.05221) (xy 185.94324 -54.057804) (xy 185.942732 -54.058312)
			(xy 185.921807 -54.075905) (xy 185.875869 -54.105543) (xy 185.826171 -54.128319) (xy 185.773731 -54.143767)
			(xy 185.719622 -54.15157) (xy 185.692288 -54.152038) (xy 185.665038 -54.151533) (xy 185.611092 -54.143776)
			(xy 185.5588 -54.128421) (xy 185.509224 -54.105781) (xy 185.463376 -54.076316) (xy 185.422186 -54.040626)
			(xy 185.386495 -53.999439) (xy 185.357028 -53.953591) (xy 185.334385 -53.904017) (xy 185.319028 -53.851725)
			(xy 185.311268 -53.79778) (xy 185.31078 -53.77053) (xy 184.946637 -53.77053) (xy 184.945782 -53.771546)
			(xy 184.945528 -53.7718) (xy 184.945274 -53.772054) (xy 184.939698 -53.779147) (xy 184.933446 -53.796059)
			(xy 184.933082 -53.805074) (xy 184.933082 -53.87213) (xy 184.933428 -53.881148) (xy 184.939684 -53.898065)
			(xy 184.945274 -53.90515) (xy 184.945528 -53.905404) (xy 184.945782 -53.905658) (xy 184.963386 -53.926578)
			(xy 184.993043 -53.97251) (xy 185.015835 -54.022207) (xy 185.031294 -54.074651) (xy 185.039103 -54.128764)
			(xy 185.039103 -54.183439) (xy 185.031293 -54.237552) (xy 185.015834 -54.289996) (xy 185.001988 -54.320186)
			(xy 187.230512 -54.320186) (xy 187.231002 -54.292853) (xy 187.238805 -54.238747) (xy 187.25425 -54.186308)
			(xy 187.277021 -54.13661) (xy 187.30665 -54.09067) (xy 187.324238 -54.069742) (xy 187.324492 -54.069488)
			(xy 187.324746 -54.069234) (xy 187.33033 -54.062146) (xy 187.336577 -54.04523) (xy 187.336938 -54.036214)
			(xy 187.336938 -53.969158) (xy 187.336545 -53.960145) (xy 187.330322 -53.943228) (xy 187.324746 -53.936138)
			(xy 187.324492 -53.935884) (xy 187.324238 -53.93563) (xy 187.306652 -53.914699) (xy 187.277011 -53.868764)
			(xy 187.254233 -53.819068) (xy 187.238784 -53.766628) (xy 187.23098 -53.71252) (xy 187.230512 -53.685186)
			(xy 187.230998 -53.657935) (xy 187.238754 -53.603987) (xy 187.254109 -53.551692) (xy 187.276751 -53.502115)
			(xy 187.306217 -53.456265) (xy 187.341908 -53.415074) (xy 187.383099 -53.379383) (xy 187.428949 -53.349917)
			(xy 187.478526 -53.327275) (xy 187.530821 -53.31192) (xy 187.584769 -53.304164) (xy 187.639271 -53.304164)
			(xy 187.693219 -53.31192) (xy 187.745514 -53.327275) (xy 187.795091 -53.349917) (xy 187.840941 -53.379383)
			(xy 187.882132 -53.415074) (xy 187.917823 -53.456265) (xy 187.943716 -53.496555) (xy 200.233441 -53.496555)
			(xy 200.233441 -53.442045) (xy 200.241199 -53.388089) (xy 200.256557 -53.335786) (xy 200.279203 -53.286202)
			(xy 200.308676 -53.240345) (xy 200.344374 -53.19915) (xy 200.385573 -53.163455) (xy 200.431432 -53.133987)
			(xy 200.481018 -53.111346) (xy 200.533322 -53.095992) (xy 200.587279 -53.088239) (xy 200.614534 -53.087778)
			(xy 200.641906 -53.088205) (xy 200.696087 -53.096029) (xy 200.748592 -53.111527) (xy 200.798338 -53.134377)
			(xy 200.844302 -53.164112) (xy 200.865232 -53.181758) (xy 200.865486 -53.182012) (xy 200.872571 -53.1876)
			(xy 200.889489 -53.193846) (xy 200.898506 -53.194204) (xy 200.965562 -53.194204) (xy 200.974577 -53.193828)
			(xy 200.991494 -53.187594) (xy 200.998582 -53.182012) (xy 200.99909 -53.181504) (xy 201.020009 -53.163903)
			(xy 201.065948 -53.134266) (xy 201.115647 -53.111491) (xy 201.168089 -53.096045) (xy 201.222199 -53.088245)
			(xy 201.249534 -53.087778) (xy 201.276783 -53.088295) (xy 201.330725 -53.096055) (xy 201.383013 -53.111412)
			(xy 201.432584 -53.134054) (xy 201.478429 -53.163521) (xy 201.519613 -53.199211) (xy 201.5553 -53.240398)
			(xy 201.584762 -53.286245) (xy 201.6074 -53.335819) (xy 201.622753 -53.388109) (xy 201.630508 -53.442051)
			(xy 201.630508 -53.496549) (xy 201.622753 -53.550491) (xy 201.6074 -53.602781) (xy 201.584762 -53.652355)
			(xy 201.5553 -53.698202) (xy 201.519613 -53.739389) (xy 201.478429 -53.775079) (xy 201.432584 -53.804546)
			(xy 201.383013 -53.827188) (xy 201.330725 -53.842545) (xy 201.276783 -53.850305) (xy 201.249534 -53.850794)
			(xy 201.222164 -53.850309) (xy 201.167986 -53.842496) (xy 201.115483 -53.827012) (xy 201.065736 -53.804174)
			(xy 201.019768 -53.774453) (xy 200.998836 -53.756814) (xy 200.998582 -53.75656) (xy 200.991508 -53.750955)
			(xy 200.974581 -53.74472) (xy 200.965562 -53.744368) (xy 200.898506 -53.744368) (xy 200.88949 -53.744735)
			(xy 200.872574 -53.750976) (xy 200.865486 -53.75656) (xy 200.864978 -53.757068) (xy 200.84403 -53.774632)
			(xy 200.798099 -53.804276) (xy 200.748407 -53.827058) (xy 200.695972 -53.842513) (xy 200.641867 -53.850322)
			(xy 200.614534 -53.850794) (xy 200.587279 -53.850361) (xy 200.533322 -53.842608) (xy 200.481018 -53.827254)
			(xy 200.431432 -53.804613) (xy 200.385573 -53.775145) (xy 200.344374 -53.73945) (xy 200.308676 -53.698255)
			(xy 200.279203 -53.652398) (xy 200.256557 -53.602814) (xy 200.241199 -53.550511) (xy 200.233441 -53.496555)
			(xy 187.943716 -53.496555) (xy 187.947289 -53.502115) (xy 187.969931 -53.551692) (xy 187.985286 -53.603987)
			(xy 187.993042 -53.657935) (xy 187.993528 -53.685186) (xy 187.993095 -53.712521) (xy 187.98528 -53.766631)
			(xy 187.969823 -53.819071) (xy 187.947039 -53.868768) (xy 187.917396 -53.914704) (xy 187.899802 -53.93563)
			(xy 187.899548 -53.935884) (xy 187.899294 -53.936138) (xy 187.893727 -53.943238) (xy 187.887469 -53.960144)
			(xy 187.887102 -53.969158) (xy 187.887102 -54.036214) (xy 187.887452 -54.045232) (xy 187.893704 -54.062148)
			(xy 187.899294 -54.069234) (xy 187.899548 -54.069488) (xy 187.899802 -54.069742) (xy 187.917381 -54.090678)
			(xy 187.947021 -54.136613) (xy 187.9698 -54.186308) (xy 187.985251 -54.238746) (xy 187.993058 -54.292853)
			(xy 187.993528 -54.320186) (xy 187.993042 -54.347437) (xy 187.985286 -54.401385) (xy 187.969931 -54.45368)
			(xy 187.947289 -54.503257) (xy 187.917823 -54.549107) (xy 187.882132 -54.590298) (xy 187.840941 -54.625989)
			(xy 187.795091 -54.655455) (xy 187.745514 -54.678097) (xy 187.693219 -54.693452) (xy 187.639271 -54.701208)
			(xy 187.584769 -54.701208) (xy 187.530821 -54.693452) (xy 187.478526 -54.678097) (xy 187.428949 -54.655455)
			(xy 187.383099 -54.625989) (xy 187.341908 -54.590298) (xy 187.306217 -54.549107) (xy 187.276751 -54.503257)
			(xy 187.254109 -54.45368) (xy 187.238754 -54.401385) (xy 187.230998 -54.347437) (xy 187.230512 -54.320186)
			(xy 185.001988 -54.320186) (xy 184.993042 -54.339693) (xy 184.963385 -54.385625) (xy 184.945782 -54.406546)
			(xy 184.945528 -54.4068) (xy 184.945274 -54.407054) (xy 184.939698 -54.414147) (xy 184.933446 -54.431059)
			(xy 184.933082 -54.440074) (xy 184.933082 -54.50713) (xy 184.933428 -54.516148) (xy 184.939684 -54.533065)
			(xy 184.945274 -54.54015) (xy 184.945528 -54.540404) (xy 184.945782 -54.540658) (xy 184.963365 -54.561591)
			(xy 184.993006 -54.607526) (xy 185.015784 -54.657222) (xy 185.031234 -54.709661) (xy 185.039039 -54.763768)
			(xy 185.039155 -54.770528) (xy 188.171074 -54.770528) (xy 188.171515 -54.743193) (xy 188.179328 -54.689084)
			(xy 188.194783 -54.636644) (xy 188.217565 -54.586947) (xy 188.247206 -54.54101) (xy 188.2648 -54.520084)
			(xy 188.265054 -54.51983) (xy 188.265308 -54.519576) (xy 188.270912 -54.512501) (xy 188.277148 -54.495575)
			(xy 188.2775 -54.486556) (xy 188.2775 -54.4195) (xy 188.277143 -54.410483) (xy 188.270895 -54.393566)
			(xy 188.265308 -54.38648) (xy 188.265054 -54.386226) (xy 188.2648 -54.385972) (xy 188.247228 -54.36503)
			(xy 188.217586 -54.319097) (xy 188.194806 -54.269404) (xy 188.179354 -54.216967) (xy 188.171545 -54.162861)
			(xy 188.171074 -54.135528) (xy 188.17156 -54.108277) (xy 188.179316 -54.054329) (xy 188.194671 -54.002034)
			(xy 188.217313 -53.952457) (xy 188.246779 -53.906607) (xy 188.28247 -53.865416) (xy 188.323661 -53.829725)
			(xy 188.369511 -53.800259) (xy 188.419088 -53.777617) (xy 188.471383 -53.762262) (xy 188.525331 -53.754506)
			(xy 188.579833 -53.754506) (xy 188.633781 -53.762262) (xy 188.686076 -53.777617) (xy 188.735653 -53.800259)
			(xy 188.781503 -53.829725) (xy 188.822694 -53.865416) (xy 188.858385 -53.906607) (xy 188.887851 -53.952457)
			(xy 188.892926 -53.96357) (xy 192.872104 -53.96357) (xy 192.876175 -53.907948) (xy 192.888301 -53.853511)
			(xy 192.908224 -53.80142) (xy 192.93552 -53.752785) (xy 192.969606 -53.708642) (xy 193.009755 -53.669933)
			(xy 193.055113 -53.637482) (xy 193.104713 -53.611981) (xy 193.157497 -53.593974) (xy 193.21234 -53.583844)
			(xy 193.268074 -53.581807) (xy 193.323511 -53.587907) (xy 193.377468 -53.602013) (xy 193.428797 -53.623825)
			(xy 193.476403 -53.652879) (xy 193.519271 -53.688554) (xy 193.556488 -53.730091) (xy 193.587261 -53.776604)
			(xy 193.610933 -53.827101) (xy 193.627001 -53.880508) (xy 193.635121 -53.935684) (xy 193.63563 -53.96357)
			(xy 193.635121 -53.991456) (xy 193.627001 -54.046632) (xy 193.620736 -54.067456) (xy 195.041264 -54.067456)
			(xy 195.045335 -54.011834) (xy 195.057461 -53.957397) (xy 195.077384 -53.905306) (xy 195.10468 -53.856671)
			(xy 195.138766 -53.812528) (xy 195.178915 -53.773819) (xy 195.224273 -53.741368) (xy 195.273873 -53.715867)
			(xy 195.326657 -53.69786) (xy 195.3815 -53.68773) (xy 195.437234 -53.685693) (xy 195.492671 -53.691793)
			(xy 195.546628 -53.705899) (xy 195.597957 -53.727711) (xy 195.645563 -53.756765) (xy 195.688431 -53.79244)
			(xy 195.725648 -53.833977) (xy 195.756421 -53.88049) (xy 195.780093 -53.930987) (xy 195.796161 -53.984394)
			(xy 195.804281 -54.03957) (xy 195.80479 -54.067456) (xy 195.804281 -54.095342) (xy 195.796161 -54.150518)
			(xy 195.780093 -54.203925) (xy 195.763695 -54.238906) (xy 202.486004 -54.238906) (xy 202.490075 -54.183284)
			(xy 202.502201 -54.128847) (xy 202.522124 -54.076756) (xy 202.54942 -54.028121) (xy 202.583506 -53.983978)
			(xy 202.623655 -53.945269) (xy 202.669013 -53.912818) (xy 202.718613 -53.887317) (xy 202.771397 -53.86931)
			(xy 202.82624 -53.85918) (xy 202.881974 -53.857143) (xy 202.937411 -53.863243) (xy 202.991368 -53.877349)
			(xy 203.042697 -53.899161) (xy 203.090303 -53.928215) (xy 203.133171 -53.96389) (xy 203.170388 -54.005427)
			(xy 203.201161 -54.05194) (xy 203.224833 -54.102437) (xy 203.240901 -54.155844) (xy 203.249021 -54.21102)
			(xy 203.24953 -54.238906) (xy 203.249021 -54.266792) (xy 203.240901 -54.321968) (xy 203.224833 -54.375375)
			(xy 203.201161 -54.425872) (xy 203.170388 -54.472385) (xy 203.133171 -54.513922) (xy 203.090303 -54.549597)
			(xy 203.042697 -54.578651) (xy 202.991368 -54.600463) (xy 202.937411 -54.614569) (xy 202.881974 -54.620669)
			(xy 202.82624 -54.618632) (xy 202.771397 -54.608502) (xy 202.718613 -54.590495) (xy 202.669013 -54.564994)
			(xy 202.623655 -54.532543) (xy 202.583506 -54.493834) (xy 202.54942 -54.449691) (xy 202.522124 -54.401056)
			(xy 202.502201 -54.348965) (xy 202.490075 -54.294528) (xy 202.486004 -54.238906) (xy 195.763695 -54.238906)
			(xy 195.756421 -54.254422) (xy 195.725648 -54.300935) (xy 195.688431 -54.342472) (xy 195.645563 -54.378147)
			(xy 195.597957 -54.407201) (xy 195.546628 -54.429013) (xy 195.492671 -54.443119) (xy 195.437234 -54.449219)
			(xy 195.3815 -54.447182) (xy 195.326657 -54.437052) (xy 195.273873 -54.419045) (xy 195.224273 -54.393544)
			(xy 195.178915 -54.361093) (xy 195.138766 -54.322384) (xy 195.10468 -54.278241) (xy 195.077384 -54.229606)
			(xy 195.057461 -54.177515) (xy 195.045335 -54.123078) (xy 195.041264 -54.067456) (xy 193.620736 -54.067456)
			(xy 193.610933 -54.100039) (xy 193.587261 -54.150536) (xy 193.556488 -54.197049) (xy 193.519271 -54.238586)
			(xy 193.476403 -54.274261) (xy 193.428797 -54.303315) (xy 193.377468 -54.325127) (xy 193.323511 -54.339233)
			(xy 193.268074 -54.345333) (xy 193.21234 -54.343296) (xy 193.157497 -54.333166) (xy 193.104713 -54.315159)
			(xy 193.055113 -54.289658) (xy 193.009755 -54.257207) (xy 192.969606 -54.218498) (xy 192.93552 -54.174355)
			(xy 192.908224 -54.12572) (xy 192.888301 -54.073629) (xy 192.876175 -54.019192) (xy 192.872104 -53.96357)
			(xy 188.892926 -53.96357) (xy 188.910493 -54.002034) (xy 188.925848 -54.054329) (xy 188.933604 -54.108277)
			(xy 188.93409 -54.135528) (xy 188.933608 -54.162861) (xy 188.925802 -54.216968) (xy 188.910356 -54.269407)
			(xy 188.887584 -54.319105) (xy 188.857953 -54.365044) (xy 188.840364 -54.385972) (xy 188.84011 -54.386226)
			(xy 188.839856 -54.38648) (xy 188.834266 -54.393564) (xy 188.828023 -54.410483) (xy 188.827664 -54.4195)
			(xy 188.827664 -54.486556) (xy 188.82805 -54.49557) (xy 188.834278 -54.512487) (xy 188.839856 -54.519576)
			(xy 188.84011 -54.51983) (xy 188.840364 -54.520084) (xy 188.857957 -54.54101) (xy 188.887596 -54.586946)
			(xy 188.910373 -54.636644) (xy 188.925821 -54.689085) (xy 188.933623 -54.743194) (xy 188.93409 -54.770528)
			(xy 188.933604 -54.797779) (xy 188.925848 -54.851727) (xy 188.910493 -54.904022) (xy 188.887851 -54.953599)
			(xy 188.858385 -54.999449) (xy 188.822694 -55.04064) (xy 188.781503 -55.076331) (xy 188.770416 -55.083456)
			(xy 195.041264 -55.083456) (xy 195.045335 -55.027834) (xy 195.057461 -54.973397) (xy 195.077384 -54.921306)
			(xy 195.10468 -54.872671) (xy 195.138766 -54.828528) (xy 195.178915 -54.789819) (xy 195.224273 -54.757368)
			(xy 195.273873 -54.731867) (xy 195.326657 -54.71386) (xy 195.3815 -54.70373) (xy 195.437234 -54.701693)
			(xy 195.492671 -54.707793) (xy 195.546628 -54.721899) (xy 195.597957 -54.743711) (xy 195.645563 -54.772765)
			(xy 195.688431 -54.80844) (xy 195.725648 -54.849977) (xy 195.756421 -54.89649) (xy 195.780093 -54.946987)
			(xy 195.79275 -54.989055) (xy 198.001045 -54.989055) (xy 198.001045 -54.934545) (xy 198.008803 -54.88059)
			(xy 198.024161 -54.828289) (xy 198.046806 -54.778705) (xy 198.076277 -54.73285) (xy 198.111975 -54.691655)
			(xy 198.153172 -54.655961) (xy 198.19903 -54.626492) (xy 198.248615 -54.603851) (xy 198.300918 -54.588497)
			(xy 198.354873 -54.580743) (xy 198.382128 -54.580282) (xy 198.41022 -54.580755) (xy 198.465799 -54.588986)
			(xy 198.519568 -54.605281) (xy 198.570366 -54.629287) (xy 198.617092 -54.660485) (xy 198.658737 -54.6982)
			(xy 198.694398 -54.741616) (xy 198.70928 -54.765448) (xy 198.714868 -54.774592) (xy 198.731886 -54.786784)
			(xy 198.82485 -54.80685) (xy 198.845424 -54.802786) (xy 198.85406 -54.79669) (xy 198.878132 -54.780704)
			(xy 198.930061 -54.755358) (xy 198.985216 -54.738129) (xy 199.042338 -54.729409) (xy 199.07123 -54.728872)
			(xy 199.098481 -54.72935) (xy 199.112816 -54.731412) (xy 207.620616 -54.731412) (xy 207.621062 -54.704077)
			(xy 207.628876 -54.649969) (xy 207.644331 -54.59753) (xy 207.667111 -54.547833) (xy 207.69675 -54.501895)
			(xy 207.714342 -54.480968) (xy 207.714596 -54.480714) (xy 207.71485 -54.48046) (xy 207.720424 -54.473365)
			(xy 207.726677 -54.456454) (xy 207.727042 -54.44744) (xy 207.727042 -54.380384) (xy 207.726705 -54.371365)
			(xy 207.720445 -54.354447) (xy 207.71485 -54.347364) (xy 207.714596 -54.34711) (xy 207.714342 -54.346856)
			(xy 207.696754 -54.325924) (xy 207.667103 -54.279992) (xy 207.644315 -54.230296) (xy 207.628858 -54.177855)
			(xy 207.621049 -54.123745) (xy 207.621048 -54.069073) (xy 207.628855 -54.014962) (xy 207.644309 -53.962521)
			(xy 207.667094 -53.912824) (xy 207.696744 -53.866891) (xy 207.714342 -53.845968) (xy 207.714596 -53.845714)
			(xy 207.71485 -53.84546) (xy 207.720424 -53.838365) (xy 207.726677 -53.821454) (xy 207.727042 -53.81244)
			(xy 207.727042 -53.745384) (xy 207.726705 -53.736365) (xy 207.720445 -53.719447) (xy 207.71485 -53.712364)
			(xy 207.714596 -53.71211) (xy 207.714342 -53.711856) (xy 207.696754 -53.690924) (xy 207.667103 -53.644992)
			(xy 207.644315 -53.595296) (xy 207.628858 -53.542855) (xy 207.621049 -53.488745) (xy 207.621048 -53.434073)
			(xy 207.628855 -53.379962) (xy 207.644309 -53.327521) (xy 207.667094 -53.277824) (xy 207.696744 -53.231891)
			(xy 207.714342 -53.210968) (xy 207.714596 -53.210714) (xy 207.71485 -53.21046) (xy 207.720424 -53.203365)
			(xy 207.726677 -53.186454) (xy 207.727042 -53.17744) (xy 207.727042 -53.110384) (xy 207.726705 -53.101365)
			(xy 207.720445 -53.084447) (xy 207.71485 -53.077364) (xy 207.714596 -53.07711) (xy 207.714342 -53.076856)
			(xy 207.696769 -53.055915) (xy 207.667126 -53.009983) (xy 207.644345 -52.960289) (xy 207.628893 -52.907852)
			(xy 207.621086 -52.853745) (xy 207.620616 -52.826412) (xy 207.621102 -52.799161) (xy 207.628858 -52.745213)
			(xy 207.644213 -52.692918) (xy 207.666855 -52.643341) (xy 207.696321 -52.597491) (xy 207.732012 -52.5563)
			(xy 207.773203 -52.520609) (xy 207.819053 -52.491143) (xy 207.86863 -52.468501) (xy 207.920925 -52.453146)
			(xy 207.974873 -52.44539) (xy 208.029375 -52.44539) (xy 208.083323 -52.453146) (xy 208.135618 -52.468501)
			(xy 208.185195 -52.491143) (xy 208.231045 -52.520609) (xy 208.272236 -52.5563) (xy 208.307927 -52.597491)
			(xy 208.337393 -52.643341) (xy 208.360035 -52.692918) (xy 208.37539 -52.745213) (xy 208.383146 -52.799161)
			(xy 208.383632 -52.826412) (xy 208.383154 -52.853746) (xy 208.37535 -52.907853) (xy 208.359903 -52.960292)
			(xy 208.33713 -53.00999) (xy 208.307496 -53.055929) (xy 208.289906 -53.076856) (xy 208.289652 -53.07711)
			(xy 208.289398 -53.077364) (xy 208.28382 -53.084457) (xy 208.277568 -53.101369) (xy 208.277206 -53.110384)
			(xy 208.277206 -53.17744) (xy 208.277543 -53.186459) (xy 208.283804 -53.203376) (xy 208.289398 -53.21046)
			(xy 208.289652 -53.210714) (xy 208.289906 -53.210968) (xy 208.307519 -53.23188) (xy 208.337174 -53.277814)
			(xy 208.359963 -53.327513) (xy 208.37542 -53.379957) (xy 208.383228 -53.434072) (xy 208.383227 -53.488746)
			(xy 208.375416 -53.54286) (xy 208.359957 -53.595304) (xy 208.337165 -53.645002) (xy 208.307508 -53.690934)
			(xy 208.289906 -53.711856) (xy 208.289652 -53.71211) (xy 208.289398 -53.712364) (xy 208.28382 -53.719457)
			(xy 208.277568 -53.736369) (xy 208.277206 -53.745384) (xy 208.277206 -53.81244) (xy 208.277543 -53.821459)
			(xy 208.283804 -53.838376) (xy 208.289398 -53.84546) (xy 208.289652 -53.845714) (xy 208.289906 -53.845968)
			(xy 208.307519 -53.86688) (xy 208.337174 -53.912814) (xy 208.359963 -53.962513) (xy 208.37542 -54.014957)
			(xy 208.383228 -54.069072) (xy 208.383227 -54.123746) (xy 208.375416 -54.17786) (xy 208.359957 -54.230304)
			(xy 208.337165 -54.280002) (xy 208.307508 -54.325934) (xy 208.289906 -54.346856) (xy 208.289652 -54.34711)
			(xy 208.289398 -54.347364) (xy 208.28382 -54.354457) (xy 208.277568 -54.371369) (xy 208.277206 -54.380384)
			(xy 208.277206 -54.44744) (xy 208.277543 -54.456459) (xy 208.283804 -54.473376) (xy 208.289398 -54.48046)
			(xy 208.289652 -54.480714) (xy 208.289906 -54.480968) (xy 208.307498 -54.501894) (xy 208.337136 -54.547831)
			(xy 208.359912 -54.597529) (xy 208.37536 -54.649969) (xy 208.383164 -54.704078) (xy 208.383632 -54.731412)
			(xy 208.383146 -54.758663) (xy 208.378482 -54.791102) (xy 210.27644 -54.791102) (xy 210.276933 -54.763769)
			(xy 210.284734 -54.709663) (xy 210.300178 -54.657223) (xy 210.322948 -54.607525) (xy 210.352578 -54.561586)
			(xy 210.370166 -54.540658) (xy 210.37042 -54.540404) (xy 210.370674 -54.54015) (xy 210.376254 -54.53306)
			(xy 210.382503 -54.516145) (xy 210.382866 -54.50713) (xy 210.382866 -54.440074) (xy 210.382529 -54.431055)
			(xy 210.376268 -54.414138) (xy 210.370674 -54.407054) (xy 210.37042 -54.4068) (xy 210.370166 -54.406546)
			(xy 210.352568 -54.385622) (xy 210.322915 -54.339689) (xy 210.300126 -54.289992) (xy 210.284669 -54.23755)
			(xy 210.27686 -54.183438) (xy 210.27686 -54.128765) (xy 210.284668 -54.074653) (xy 210.300125 -54.02221)
			(xy 210.322913 -53.972513) (xy 210.352566 -53.92658) (xy 210.370166 -53.905658) (xy 210.37042 -53.905404)
			(xy 210.370674 -53.90515) (xy 210.376254 -53.89806) (xy 210.382503 -53.881145) (xy 210.382866 -53.87213)
			(xy 210.382866 -53.805074) (xy 210.382529 -53.796055) (xy 210.376268 -53.779138) (xy 210.370674 -53.772054)
			(xy 210.37042 -53.7718) (xy 210.370166 -53.771546) (xy 210.352568 -53.750622) (xy 210.322915 -53.704689)
			(xy 210.300126 -53.654992) (xy 210.284669 -53.60255) (xy 210.27686 -53.548438) (xy 210.27686 -53.493765)
			(xy 210.284668 -53.439653) (xy 210.300125 -53.38721) (xy 210.322913 -53.337513) (xy 210.352566 -53.29158)
			(xy 210.370166 -53.270658) (xy 210.37042 -53.270404) (xy 210.370674 -53.27015) (xy 210.376254 -53.26306)
			(xy 210.382503 -53.246145) (xy 210.382866 -53.23713) (xy 210.382866 -53.170074) (xy 210.382529 -53.161055)
			(xy 210.376268 -53.144138) (xy 210.370674 -53.137054) (xy 210.37042 -53.1368) (xy 210.370166 -53.136546)
			(xy 210.352576 -53.115618) (xy 210.322939 -53.069681) (xy 210.300162 -53.019984) (xy 210.284714 -52.967544)
			(xy 210.276909 -52.913436) (xy 210.27644 -52.886102) (xy 210.276926 -52.858851) (xy 210.284682 -52.804903)
			(xy 210.300037 -52.752608) (xy 210.322679 -52.703031) (xy 210.352145 -52.657181) (xy 210.387836 -52.61599)
			(xy 210.429027 -52.580299) (xy 210.474877 -52.550833) (xy 210.524454 -52.528191) (xy 210.576749 -52.512836)
			(xy 210.630697 -52.50508) (xy 210.685199 -52.50508) (xy 210.739147 -52.512836) (xy 210.753465 -52.51704)
			(xy 214.940132 -52.51704) (xy 214.944203 -52.461418) (xy 214.956329 -52.406981) (xy 214.976252 -52.35489)
			(xy 215.003548 -52.306255) (xy 215.037634 -52.262112) (xy 215.077783 -52.223403) (xy 215.123141 -52.190952)
			(xy 215.172741 -52.165451) (xy 215.225525 -52.147444) (xy 215.280368 -52.137314) (xy 215.336102 -52.135277)
			(xy 215.391539 -52.141377) (xy 215.445496 -52.155483) (xy 215.496825 -52.177295) (xy 215.544431 -52.206349)
			(xy 215.587299 -52.242024) (xy 215.624516 -52.283561) (xy 215.655289 -52.330074) (xy 215.678961 -52.380571)
			(xy 215.695029 -52.433978) (xy 215.703149 -52.489154) (xy 215.703658 -52.51704) (xy 215.703149 -52.544926)
			(xy 215.696899 -52.587398) (xy 218.855288 -52.587398) (xy 218.859359 -52.531776) (xy 218.871485 -52.477339)
			(xy 218.891408 -52.425248) (xy 218.918704 -52.376613) (xy 218.95279 -52.33247) (xy 218.992939 -52.293761)
			(xy 219.038297 -52.26131) (xy 219.087897 -52.235809) (xy 219.140681 -52.217802) (xy 219.195524 -52.207672)
			(xy 219.251258 -52.205635) (xy 219.306695 -52.211735) (xy 219.360652 -52.225841) (xy 219.411981 -52.247653)
			(xy 219.459587 -52.276707) (xy 219.502455 -52.312382) (xy 219.539672 -52.353919) (xy 219.570445 -52.400432)
			(xy 219.594117 -52.450929) (xy 219.610185 -52.504336) (xy 219.618305 -52.559512) (xy 219.618814 -52.587398)
			(xy 219.618305 -52.615284) (xy 219.610185 -52.67046) (xy 219.594117 -52.723867) (xy 219.570445 -52.774364)
			(xy 219.539672 -52.820877) (xy 219.502455 -52.862414) (xy 219.459587 -52.898089) (xy 219.411981 -52.927143)
			(xy 219.360652 -52.948955) (xy 219.306695 -52.963061) (xy 219.251258 -52.969161) (xy 219.195524 -52.967124)
			(xy 219.140681 -52.956994) (xy 219.087897 -52.938987) (xy 219.038297 -52.913486) (xy 218.992939 -52.881035)
			(xy 218.95279 -52.842326) (xy 218.918704 -52.798183) (xy 218.891408 -52.749548) (xy 218.871485 -52.697457)
			(xy 218.859359 -52.64302) (xy 218.855288 -52.587398) (xy 215.696899 -52.587398) (xy 215.695029 -52.600102)
			(xy 215.678961 -52.653509) (xy 215.655289 -52.704006) (xy 215.624516 -52.750519) (xy 215.587299 -52.792056)
			(xy 215.544431 -52.827731) (xy 215.496825 -52.856785) (xy 215.445496 -52.878597) (xy 215.391539 -52.892703)
			(xy 215.336102 -52.898803) (xy 215.280368 -52.896766) (xy 215.225525 -52.886636) (xy 215.172741 -52.868629)
			(xy 215.123141 -52.843128) (xy 215.077783 -52.810677) (xy 215.037634 -52.771968) (xy 215.003548 -52.727825)
			(xy 214.976252 -52.67919) (xy 214.956329 -52.627099) (xy 214.944203 -52.572662) (xy 214.940132 -52.51704)
			(xy 210.753465 -52.51704) (xy 210.791442 -52.528191) (xy 210.841019 -52.550833) (xy 210.886869 -52.580299)
			(xy 210.92806 -52.61599) (xy 210.963751 -52.657181) (xy 210.993217 -52.703031) (xy 211.015859 -52.752608)
			(xy 211.031214 -52.804903) (xy 211.03897 -52.858851) (xy 211.039456 -52.886102) (xy 211.038967 -52.913435)
			(xy 211.031164 -52.967542) (xy 211.01572 -53.019981) (xy 210.992949 -53.069679) (xy 210.963318 -53.115618)
			(xy 210.94573 -53.136546) (xy 210.945476 -53.1368) (xy 210.945222 -53.137054) (xy 210.939639 -53.144143)
			(xy 210.933392 -53.161058) (xy 210.93303 -53.170074) (xy 210.93303 -53.23713) (xy 210.933366 -53.246149)
			(xy 210.939627 -53.263066) (xy 210.945222 -53.27015) (xy 210.945476 -53.270404) (xy 210.94573 -53.270658)
			(xy 210.963332 -53.291578) (xy 210.992985 -53.337512) (xy 211.015774 -53.387209) (xy 211.031231 -53.439652)
			(xy 211.039039 -53.493765) (xy 211.039039 -53.548438) (xy 211.03123 -53.602551) (xy 211.015773 -53.654994)
			(xy 210.992984 -53.704691) (xy 210.963331 -53.750624) (xy 210.946585 -53.77053) (xy 211.310728 -53.77053)
			(xy 211.311257 -53.741613) (xy 211.319983 -53.684442) (xy 211.337238 -53.629243) (xy 211.362627 -53.577281)
			(xy 211.395569 -53.529747) (xy 211.435309 -53.48773) (xy 211.457794 -53.46954) (xy 211.465171 -53.463249)
			(xy 211.474971 -53.44654) (xy 211.476844 -53.437028) (xy 211.477352 -53.429408) (xy 211.477352 -53.349652)
			(xy 211.476844 -53.342032) (xy 211.474973 -53.332519) (xy 211.465177 -53.315805) (xy 211.457794 -53.30952)
			(xy 211.435319 -53.291319) (xy 211.395583 -53.249301) (xy 211.362644 -53.201768) (xy 211.337254 -53.149809)
			(xy 211.319996 -53.094613) (xy 211.311264 -53.037445) (xy 211.310728 -53.00853) (xy 211.311183 -52.981276)
			(xy 211.318937 -52.927323) (xy 211.334291 -52.875023) (xy 211.356933 -52.825441) (xy 211.386401 -52.779586)
			(xy 211.422096 -52.738392) (xy 211.46329 -52.702697) (xy 211.509146 -52.67323) (xy 211.558729 -52.650589)
			(xy 211.611029 -52.635236) (xy 211.664982 -52.627483) (xy 211.692236 -52.627022) (xy 211.69249 -52.627022)
			(xy 211.718785 -52.62748) (xy 211.770874 -52.634725) (xy 211.821476 -52.64905) (xy 211.869632 -52.670186)
			(xy 211.914431 -52.697731) (xy 211.955026 -52.731165) (xy 211.97316 -52.750212) (xy 211.980746 -52.757636)
			(xy 212.000153 -52.766171) (xy 212.010752 -52.766722) (xy 212.08492 -52.766722) (xy 212.095551 -52.766309)
			(xy 212.115015 -52.757762) (xy 212.122512 -52.750212) (xy 212.140628 -52.731144) (xy 212.181212 -52.697688)
			(xy 212.226011 -52.67013) (xy 212.274174 -52.648993) (xy 212.324785 -52.634678) (xy 212.376884 -52.627458)
			(xy 212.403182 -52.627022) (xy 212.403436 -52.627022) (xy 212.43069 -52.627444) (xy 212.484641 -52.635207)
			(xy 212.536939 -52.650568) (xy 212.586518 -52.673215) (xy 212.63237 -52.702688) (xy 212.67356 -52.738386)
			(xy 212.709251 -52.779583) (xy 212.738716 -52.82544) (xy 212.761355 -52.875023) (xy 212.776707 -52.927324)
			(xy 212.78446 -52.981276) (xy 212.784944 -53.00853) (xy 212.784481 -53.036197) (xy 212.78225 -53.051456)
			(xy 221.041212 -53.051456) (xy 221.045283 -52.995834) (xy 221.057409 -52.941397) (xy 221.077332 -52.889306)
			(xy 221.104628 -52.840671) (xy 221.138714 -52.796528) (xy 221.178863 -52.757819) (xy 221.224221 -52.725368)
			(xy 221.273821 -52.699867) (xy 221.326605 -52.68186) (xy 221.381448 -52.67173) (xy 221.437182 -52.669693)
			(xy 221.492619 -52.675793) (xy 221.546576 -52.689899) (xy 221.597905 -52.711711) (xy 221.645511 -52.740765)
			(xy 221.688379 -52.77644) (xy 221.725596 -52.817977) (xy 221.756369 -52.86449) (xy 221.780041 -52.914987)
			(xy 221.796109 -52.968394) (xy 221.804229 -53.02357) (xy 221.804738 -53.051456) (xy 221.804229 -53.079342)
			(xy 221.796109 -53.134518) (xy 221.780041 -53.187925) (xy 221.756369 -53.238422) (xy 221.725596 -53.284935)
			(xy 221.688379 -53.326472) (xy 221.645511 -53.362147) (xy 221.597905 -53.391201) (xy 221.546576 -53.413013)
			(xy 221.492619 -53.427119) (xy 221.437182 -53.433219) (xy 221.381448 -53.431182) (xy 221.326605 -53.421052)
			(xy 221.273821 -53.403045) (xy 221.224221 -53.377544) (xy 221.178863 -53.345093) (xy 221.138714 -53.306384)
			(xy 221.104628 -53.262241) (xy 221.077332 -53.213606) (xy 221.057409 -53.161515) (xy 221.045283 -53.107078)
			(xy 221.041212 -53.051456) (xy 212.78225 -53.051456) (xy 212.776476 -53.09095) (xy 212.760653 -53.143974)
			(xy 212.737342 -53.194159) (xy 212.707033 -53.240454) (xy 212.670359 -53.28189) (xy 212.628089 -53.317599)
			(xy 212.604858 -53.332634) (xy 212.604604 -53.332888) (xy 212.59508 -53.339556) (xy 212.582772 -53.359248)
			(xy 212.580982 -53.370734) (xy 212.573108 -53.450744) (xy 212.572441 -53.462445) (xy 212.580523 -53.484417)
			(xy 212.588602 -53.492908) (xy 212.588856 -53.492908) (xy 212.607415 -53.511011) (xy 212.639997 -53.551337)
			(xy 212.666814 -53.595707) (xy 212.687371 -53.643301) (xy 212.701289 -53.693242) (xy 212.70831 -53.744608)
			(xy 212.708744 -53.77053) (xy 212.70825 -53.79778) (xy 212.700491 -53.851726) (xy 212.685133 -53.904018)
			(xy 212.662491 -53.953593) (xy 212.633025 -53.999442) (xy 212.597335 -54.040631) (xy 212.556147 -54.076322)
			(xy 212.510299 -54.105789) (xy 212.460724 -54.128431) (xy 212.408432 -54.143789) (xy 212.354486 -54.15155)
			(xy 212.327236 -54.152038) (xy 212.299866 -54.151566) (xy 212.245686 -54.143752) (xy 212.193183 -54.128265)
			(xy 212.143436 -54.105424) (xy 212.097469 -54.0757) (xy 212.076538 -54.058058) (xy 212.076284 -54.057804)
			(xy 212.069206 -54.052205) (xy 212.052283 -54.045966) (xy 212.043264 -54.045612) (xy 211.976208 -54.045612)
			(xy 211.967191 -54.04597) (xy 211.950274 -54.052217) (xy 211.943188 -54.057804) (xy 211.94268 -54.058312)
			(xy 211.921774 -54.075929) (xy 211.875832 -54.105563) (xy 211.826129 -54.128335) (xy 211.773684 -54.143777)
			(xy 211.719572 -54.151573) (xy 211.692236 -54.152038) (xy 211.664985 -54.151511) (xy 211.611038 -54.14376)
			(xy 211.558743 -54.12841) (xy 211.509165 -54.105774) (xy 211.463314 -54.076312) (xy 211.422121 -54.040625)
			(xy 211.386427 -53.999439) (xy 211.356958 -53.953593) (xy 211.334313 -53.904018) (xy 211.318954 -53.851726)
			(xy 211.311193 -53.797781) (xy 211.310728 -53.77053) (xy 210.946585 -53.77053) (xy 210.94573 -53.771546)
			(xy 210.945476 -53.7718) (xy 210.945222 -53.772054) (xy 210.939639 -53.779143) (xy 210.933392 -53.796058)
			(xy 210.93303 -53.805074) (xy 210.93303 -53.87213) (xy 210.933366 -53.881149) (xy 210.939627 -53.898066)
			(xy 210.945222 -53.90515) (xy 210.945476 -53.905404) (xy 210.94573 -53.905658) (xy 210.963332 -53.926578)
			(xy 210.992985 -53.972512) (xy 211.015774 -54.022209) (xy 211.031231 -54.074652) (xy 211.039039 -54.128765)
			(xy 211.039039 -54.183438) (xy 211.03123 -54.237551) (xy 211.015773 -54.289994) (xy 211.001928 -54.320186)
			(xy 213.23046 -54.320186) (xy 213.230938 -54.292852) (xy 213.238743 -54.238745) (xy 213.25419 -54.186306)
			(xy 213.276963 -54.136608) (xy 213.306596 -54.090669) (xy 213.324186 -54.069742) (xy 213.32444 -54.069488)
			(xy 213.324694 -54.069234) (xy 213.330272 -54.062141) (xy 213.336524 -54.045229) (xy 213.336886 -54.036214)
			(xy 213.336886 -53.969158) (xy 213.336504 -53.960144) (xy 213.330274 -53.943226) (xy 213.324694 -53.936138)
			(xy 213.32444 -53.935884) (xy 213.324186 -53.93563) (xy 213.306592 -53.914706) (xy 213.276954 -53.868768)
			(xy 213.254178 -53.81907) (xy 213.238731 -53.766629) (xy 213.230928 -53.71252) (xy 213.23046 -53.685186)
			(xy 213.230946 -53.657935) (xy 213.238702 -53.603987) (xy 213.254057 -53.551692) (xy 213.276699 -53.502115)
			(xy 213.306165 -53.456265) (xy 213.341856 -53.415074) (xy 213.383047 -53.379383) (xy 213.428897 -53.349917)
			(xy 213.478474 -53.327275) (xy 213.530769 -53.31192) (xy 213.584717 -53.304164) (xy 213.639219 -53.304164)
			(xy 213.693167 -53.31192) (xy 213.745462 -53.327275) (xy 213.795039 -53.349917) (xy 213.840889 -53.379383)
			(xy 213.88208 -53.415074) (xy 213.917771 -53.456265) (xy 213.947237 -53.502115) (xy 213.969879 -53.551692)
			(xy 213.985234 -53.603987) (xy 213.99299 -53.657935) (xy 213.993476 -53.685186) (xy 213.993031 -53.712521)
			(xy 213.985217 -53.766629) (xy 213.969762 -53.819068) (xy 213.946982 -53.868766) (xy 213.917342 -53.914703)
			(xy 213.89975 -53.93563) (xy 213.899496 -53.935884) (xy 213.899242 -53.936138) (xy 213.893668 -53.943233)
			(xy 213.887415 -53.960144) (xy 213.88705 -53.969158) (xy 213.88705 -54.036214) (xy 213.88739 -54.045233)
			(xy 213.893648 -54.06215) (xy 213.899242 -54.069234) (xy 213.899496 -54.069488) (xy 213.89975 -54.069742)
			(xy 213.917336 -54.090672) (xy 213.946974 -54.136609) (xy 213.969751 -54.186306) (xy 213.9852 -54.238745)
			(xy 213.993006 -54.292852) (xy 213.993476 -54.320186) (xy 213.99299 -54.347437) (xy 213.985234 -54.401385)
			(xy 213.969879 -54.45368) (xy 213.947237 -54.503257) (xy 213.917771 -54.549107) (xy 213.88208 -54.590298)
			(xy 213.840889 -54.625989) (xy 213.795039 -54.655455) (xy 213.745462 -54.678097) (xy 213.693167 -54.693452)
			(xy 213.639219 -54.701208) (xy 213.584717 -54.701208) (xy 213.530769 -54.693452) (xy 213.478474 -54.678097)
			(xy 213.428897 -54.655455) (xy 213.383047 -54.625989) (xy 213.341856 -54.590298) (xy 213.306165 -54.549107)
			(xy 213.276699 -54.503257) (xy 213.254057 -54.45368) (xy 213.238702 -54.401385) (xy 213.230946 -54.347437)
			(xy 213.23046 -54.320186) (xy 211.001928 -54.320186) (xy 210.992984 -54.339691) (xy 210.963331 -54.385624)
			(xy 210.94573 -54.406546) (xy 210.945476 -54.4068) (xy 210.945222 -54.407054) (xy 210.939639 -54.414143)
			(xy 210.933392 -54.431058) (xy 210.93303 -54.440074) (xy 210.93303 -54.50713) (xy 210.933366 -54.516149)
			(xy 210.939627 -54.533066) (xy 210.945222 -54.54015) (xy 210.945476 -54.540404) (xy 210.94573 -54.540658)
			(xy 210.963321 -54.561585) (xy 210.992958 -54.607522) (xy 211.015735 -54.65722) (xy 211.031183 -54.70966)
			(xy 211.038987 -54.763768) (xy 211.039103 -54.770528) (xy 214.171022 -54.770528) (xy 214.171476 -54.743194)
			(xy 214.179287 -54.689086) (xy 214.194741 -54.636646) (xy 214.217519 -54.586949) (xy 214.247157 -54.541011)
			(xy 214.264748 -54.520084) (xy 214.265002 -54.51983) (xy 214.265256 -54.519576) (xy 214.270865 -54.512505)
			(xy 214.277097 -54.495576) (xy 214.277448 -54.486556) (xy 214.277448 -54.4195) (xy 214.277102 -54.410482)
			(xy 214.270848 -54.393564) (xy 214.265256 -54.38648) (xy 214.265002 -54.386226) (xy 214.264748 -54.385972)
			(xy 214.247183 -54.365024) (xy 214.217539 -54.319094) (xy 214.194757 -54.269402) (xy 214.179302 -54.216966)
			(xy 214.171493 -54.162861) (xy 214.171022 -54.135528) (xy 214.171508 -54.108277) (xy 214.179264 -54.054329)
			(xy 214.194619 -54.002034) (xy 214.217261 -53.952457) (xy 214.246727 -53.906607) (xy 214.282418 -53.865416)
			(xy 214.323609 -53.829725) (xy 214.369459 -53.800259) (xy 214.419036 -53.777617) (xy 214.471331 -53.762262)
			(xy 214.525279 -53.754506) (xy 214.579781 -53.754506) (xy 214.633729 -53.762262) (xy 214.686024 -53.777617)
			(xy 214.735601 -53.800259) (xy 214.781451 -53.829725) (xy 214.822642 -53.865416) (xy 214.858333 -53.906607)
			(xy 214.887799 -53.952457) (xy 214.892874 -53.96357) (xy 218.872052 -53.96357) (xy 218.876123 -53.907948)
			(xy 218.888249 -53.853511) (xy 218.908172 -53.80142) (xy 218.935468 -53.752785) (xy 218.969554 -53.708642)
			(xy 219.009703 -53.669933) (xy 219.055061 -53.637482) (xy 219.104661 -53.611981) (xy 219.157445 -53.593974)
			(xy 219.212288 -53.583844) (xy 219.268022 -53.581807) (xy 219.323459 -53.587907) (xy 219.377416 -53.602013)
			(xy 219.428745 -53.623825) (xy 219.476351 -53.652879) (xy 219.519219 -53.688554) (xy 219.556436 -53.730091)
			(xy 219.587209 -53.776604) (xy 219.610881 -53.827101) (xy 219.626949 -53.880508) (xy 219.635069 -53.935684)
			(xy 219.635578 -53.96357) (xy 219.635069 -53.991456) (xy 219.626949 -54.046632) (xy 219.620684 -54.067456)
			(xy 221.041212 -54.067456) (xy 221.045283 -54.011834) (xy 221.057409 -53.957397) (xy 221.077332 -53.905306)
			(xy 221.104628 -53.856671) (xy 221.138714 -53.812528) (xy 221.178863 -53.773819) (xy 221.224221 -53.741368)
			(xy 221.273821 -53.715867) (xy 221.326605 -53.69786) (xy 221.381448 -53.68773) (xy 221.437182 -53.685693)
			(xy 221.492619 -53.691793) (xy 221.546576 -53.705899) (xy 221.576733 -53.718714) (xy 236.97514 -53.718714)
			(xy 236.979211 -53.663092) (xy 236.991337 -53.608655) (xy 237.01126 -53.556564) (xy 237.038556 -53.507929)
			(xy 237.072642 -53.463786) (xy 237.112791 -53.425077) (xy 237.158149 -53.392626) (xy 237.207749 -53.367125)
			(xy 237.260533 -53.349118) (xy 237.315376 -53.338988) (xy 237.37111 -53.336951) (xy 237.426547 -53.343051)
			(xy 237.480504 -53.357157) (xy 237.531833 -53.378969) (xy 237.579439 -53.408023) (xy 237.622307 -53.443698)
			(xy 237.659524 -53.485235) (xy 237.690297 -53.531748) (xy 237.713969 -53.582245) (xy 237.730037 -53.635652)
			(xy 237.738157 -53.690828) (xy 237.738666 -53.718714) (xy 237.738157 -53.7466) (xy 237.730037 -53.801776)
			(xy 237.713969 -53.855183) (xy 237.690297 -53.90568) (xy 237.659524 -53.952193) (xy 237.622307 -53.99373)
			(xy 237.579439 -54.029405) (xy 237.531833 -54.058459) (xy 237.480504 -54.080271) (xy 237.426547 -54.094377)
			(xy 237.37111 -54.100477) (xy 237.315376 -54.09844) (xy 237.260533 -54.08831) (xy 237.207749 -54.070303)
			(xy 237.158149 -54.044802) (xy 237.112791 -54.012351) (xy 237.072642 -53.973642) (xy 237.038556 -53.929499)
			(xy 237.01126 -53.880864) (xy 236.991337 -53.828773) (xy 236.979211 -53.774336) (xy 236.97514 -53.718714)
			(xy 221.576733 -53.718714) (xy 221.597905 -53.727711) (xy 221.645511 -53.756765) (xy 221.688379 -53.79244)
			(xy 221.725596 -53.833977) (xy 221.756369 -53.88049) (xy 221.780041 -53.930987) (xy 221.796109 -53.984394)
			(xy 221.804229 -54.03957) (xy 221.804738 -54.067456) (xy 221.804229 -54.095342) (xy 221.796109 -54.150518)
			(xy 221.780041 -54.203925) (xy 221.756369 -54.254422) (xy 221.725596 -54.300935) (xy 221.717906 -54.309518)
			(xy 237.727234 -54.309518) (xy 237.731305 -54.253896) (xy 237.743431 -54.199459) (xy 237.763354 -54.147368)
			(xy 237.79065 -54.098733) (xy 237.824736 -54.05459) (xy 237.864885 -54.015881) (xy 237.910243 -53.98343)
			(xy 237.959843 -53.957929) (xy 238.012627 -53.939922) (xy 238.06747 -53.929792) (xy 238.123204 -53.927755)
			(xy 238.178641 -53.933855) (xy 238.232598 -53.947961) (xy 238.283927 -53.969773) (xy 238.331533 -53.998827)
			(xy 238.374401 -54.034502) (xy 238.411618 -54.076039) (xy 238.442391 -54.122552) (xy 238.466063 -54.173049)
			(xy 238.47449 -54.20106) (xy 239.961418 -54.20106) (xy 239.965489 -54.145438) (xy 239.977615 -54.091001)
			(xy 239.997538 -54.03891) (xy 240.024834 -53.990275) (xy 240.05892 -53.946132) (xy 240.099069 -53.907423)
			(xy 240.144427 -53.874972) (xy 240.194027 -53.849471) (xy 240.246811 -53.831464) (xy 240.301654 -53.821334)
			(xy 240.357388 -53.819297) (xy 240.412825 -53.825397) (xy 240.466782 -53.839503) (xy 240.518111 -53.861315)
			(xy 240.565717 -53.890369) (xy 240.608585 -53.926044) (xy 240.645802 -53.967581) (xy 240.676575 -54.014094)
			(xy 240.700247 -54.064591) (xy 240.716315 -54.117998) (xy 240.724435 -54.173174) (xy 240.724944 -54.20106)
			(xy 240.724435 -54.228946) (xy 240.716315 -54.284122) (xy 240.700247 -54.337529) (xy 240.676575 -54.388026)
			(xy 240.645802 -54.434539) (xy 240.608585 -54.476076) (xy 240.565717 -54.511751) (xy 240.518111 -54.540805)
			(xy 240.466782 -54.562617) (xy 240.412825 -54.576723) (xy 240.357388 -54.582823) (xy 240.301654 -54.580786)
			(xy 240.246811 -54.570656) (xy 240.194027 -54.552649) (xy 240.144427 -54.527148) (xy 240.099069 -54.494697)
			(xy 240.05892 -54.455988) (xy 240.024834 -54.411845) (xy 239.997538 -54.36321) (xy 239.977615 -54.311119)
			(xy 239.965489 -54.256682) (xy 239.961418 -54.20106) (xy 238.47449 -54.20106) (xy 238.482131 -54.226456)
			(xy 238.490251 -54.281632) (xy 238.49076 -54.309518) (xy 238.490251 -54.337404) (xy 238.482131 -54.39258)
			(xy 238.466063 -54.445987) (xy 238.442391 -54.496484) (xy 238.411618 -54.542997) (xy 238.374401 -54.584534)
			(xy 238.331533 -54.620209) (xy 238.283927 -54.649263) (xy 238.232598 -54.671075) (xy 238.178641 -54.685181)
			(xy 238.123204 -54.691281) (xy 238.06747 -54.689244) (xy 238.012627 -54.679114) (xy 237.959843 -54.661107)
			(xy 237.910243 -54.635606) (xy 237.864885 -54.603155) (xy 237.824736 -54.564446) (xy 237.79065 -54.520303)
			(xy 237.763354 -54.471668) (xy 237.743431 -54.419577) (xy 237.731305 -54.36514) (xy 237.727234 -54.309518)
			(xy 221.717906 -54.309518) (xy 221.688379 -54.342472) (xy 221.645511 -54.378147) (xy 221.597905 -54.407201)
			(xy 221.546576 -54.429013) (xy 221.492619 -54.443119) (xy 221.437182 -54.449219) (xy 221.381448 -54.447182)
			(xy 221.326605 -54.437052) (xy 221.273821 -54.419045) (xy 221.224221 -54.393544) (xy 221.178863 -54.361093)
			(xy 221.138714 -54.322384) (xy 221.104628 -54.278241) (xy 221.077332 -54.229606) (xy 221.057409 -54.177515)
			(xy 221.045283 -54.123078) (xy 221.041212 -54.067456) (xy 219.620684 -54.067456) (xy 219.610881 -54.100039)
			(xy 219.587209 -54.150536) (xy 219.556436 -54.197049) (xy 219.519219 -54.238586) (xy 219.476351 -54.274261)
			(xy 219.428745 -54.303315) (xy 219.377416 -54.325127) (xy 219.323459 -54.339233) (xy 219.268022 -54.345333)
			(xy 219.212288 -54.343296) (xy 219.157445 -54.333166) (xy 219.104661 -54.315159) (xy 219.055061 -54.289658)
			(xy 219.009703 -54.257207) (xy 218.969554 -54.218498) (xy 218.935468 -54.174355) (xy 218.908172 -54.12572)
			(xy 218.888249 -54.073629) (xy 218.876123 -54.019192) (xy 218.872052 -53.96357) (xy 214.892874 -53.96357)
			(xy 214.910441 -54.002034) (xy 214.925796 -54.054329) (xy 214.933552 -54.108277) (xy 214.934038 -54.135528)
			(xy 214.933568 -54.162862) (xy 214.925762 -54.21697) (xy 214.910313 -54.269409) (xy 214.887538 -54.319107)
			(xy 214.857903 -54.365045) (xy 214.840312 -54.385972) (xy 214.840058 -54.386226) (xy 214.839804 -54.38648)
			(xy 214.83422 -54.393568) (xy 214.827972 -54.410484) (xy 214.827612 -54.4195) (xy 214.827612 -54.486556)
			(xy 214.827988 -54.495571) (xy 214.834222 -54.512488) (xy 214.839804 -54.519576) (xy 214.840058 -54.51983)
			(xy 214.840312 -54.520084) (xy 214.857912 -54.541003) (xy 214.887549 -54.586942) (xy 214.910324 -54.636642)
			(xy 214.92577 -54.689084) (xy 214.933571 -54.743193) (xy 214.934038 -54.770528) (xy 214.933552 -54.797779)
			(xy 214.925796 -54.851727) (xy 214.910441 -54.904022) (xy 214.887799 -54.953599) (xy 214.858333 -54.999449)
			(xy 214.822642 -55.04064) (xy 214.781451 -55.076331) (xy 214.770364 -55.083456) (xy 221.041212 -55.083456)
			(xy 221.045283 -55.027834) (xy 221.057409 -54.973397) (xy 221.077332 -54.921306) (xy 221.104628 -54.872671)
			(xy 221.138714 -54.828528) (xy 221.178863 -54.789819) (xy 221.224221 -54.757368) (xy 221.273821 -54.731867)
			(xy 221.326605 -54.71386) (xy 221.381448 -54.70373) (xy 221.437182 -54.701693) (xy 221.492619 -54.707793)
			(xy 221.546576 -54.721899) (xy 221.597905 -54.743711) (xy 221.645511 -54.772765) (xy 221.671818 -54.794658)
			(xy 238.931448 -54.794658) (xy 238.935519 -54.739036) (xy 238.947645 -54.684599) (xy 238.967568 -54.632508)
			(xy 238.994864 -54.583873) (xy 239.02895 -54.53973) (xy 239.069099 -54.501021) (xy 239.114457 -54.46857)
			(xy 239.164057 -54.443069) (xy 239.216841 -54.425062) (xy 239.271684 -54.414932) (xy 239.327418 -54.412895)
			(xy 239.382855 -54.418995) (xy 239.436812 -54.433101) (xy 239.488141 -54.454913) (xy 239.535747 -54.483967)
			(xy 239.578615 -54.519642) (xy 239.615832 -54.561179) (xy 239.646605 -54.607692) (xy 239.670277 -54.658189)
			(xy 239.686345 -54.711596) (xy 239.694465 -54.766772) (xy 239.694974 -54.794658) (xy 239.69496 -54.79542)
			(xy 240.96294 -54.79542) (xy 240.967011 -54.739798) (xy 240.979137 -54.685361) (xy 240.99906 -54.63327)
			(xy 241.026356 -54.584635) (xy 241.060442 -54.540492) (xy 241.100591 -54.501783) (xy 241.145949 -54.469332)
			(xy 241.195549 -54.443831) (xy 241.248333 -54.425824) (xy 241.303176 -54.415694) (xy 241.35891 -54.413657)
			(xy 241.414347 -54.419757) (xy 241.468304 -54.433863) (xy 241.519633 -54.455675) (xy 241.567239 -54.484729)
			(xy 241.610107 -54.520404) (xy 241.647324 -54.561941) (xy 241.678097 -54.608454) (xy 241.701769 -54.658951)
			(xy 241.717837 -54.712358) (xy 241.720641 -54.731412) (xy 245.720616 -54.731412) (xy 245.721062 -54.704077)
			(xy 245.728876 -54.649969) (xy 245.744331 -54.59753) (xy 245.767111 -54.547833) (xy 245.79675 -54.501895)
			(xy 245.814342 -54.480968) (xy 245.814596 -54.480714) (xy 245.81485 -54.48046) (xy 245.820424 -54.473365)
			(xy 245.826677 -54.456454) (xy 245.827042 -54.44744) (xy 245.827042 -54.380384) (xy 245.826705 -54.371365)
			(xy 245.820445 -54.354447) (xy 245.81485 -54.347364) (xy 245.814596 -54.34711) (xy 245.814342 -54.346856)
			(xy 245.796754 -54.325924) (xy 245.767103 -54.279992) (xy 245.744315 -54.230296) (xy 245.728858 -54.177855)
			(xy 245.721049 -54.123745) (xy 245.721048 -54.069073) (xy 245.728855 -54.014962) (xy 245.744309 -53.962521)
			(xy 245.767094 -53.912824) (xy 245.796744 -53.866891) (xy 245.814342 -53.845968) (xy 245.814596 -53.845714)
			(xy 245.81485 -53.84546) (xy 245.820424 -53.838365) (xy 245.826677 -53.821454) (xy 245.827042 -53.81244)
			(xy 245.827042 -53.745384) (xy 245.826705 -53.736365) (xy 245.820445 -53.719447) (xy 245.81485 -53.712364)
			(xy 245.814596 -53.71211) (xy 245.814342 -53.711856) (xy 245.796754 -53.690924) (xy 245.767103 -53.644992)
			(xy 245.744315 -53.595296) (xy 245.728858 -53.542855) (xy 245.721049 -53.488745) (xy 245.721048 -53.434073)
			(xy 245.728855 -53.379962) (xy 245.744309 -53.327521) (xy 245.767094 -53.277824) (xy 245.796744 -53.231891)
			(xy 245.814342 -53.210968) (xy 245.814596 -53.210714) (xy 245.81485 -53.21046) (xy 245.820424 -53.203365)
			(xy 245.826677 -53.186454) (xy 245.827042 -53.17744) (xy 245.827042 -53.110384) (xy 245.826705 -53.101365)
			(xy 245.820445 -53.084447) (xy 245.81485 -53.077364) (xy 245.814596 -53.07711) (xy 245.814342 -53.076856)
			(xy 245.796769 -53.055915) (xy 245.767126 -53.009983) (xy 245.744345 -52.960289) (xy 245.728893 -52.907852)
			(xy 245.721086 -52.853745) (xy 245.720616 -52.826412) (xy 245.721102 -52.799161) (xy 245.728858 -52.745213)
			(xy 245.744213 -52.692918) (xy 245.766855 -52.643341) (xy 245.796321 -52.597491) (xy 245.832012 -52.5563)
			(xy 245.873203 -52.520609) (xy 245.919053 -52.491143) (xy 245.96863 -52.468501) (xy 246.020925 -52.453146)
			(xy 246.074873 -52.44539) (xy 246.129375 -52.44539) (xy 246.183323 -52.453146) (xy 246.235618 -52.468501)
			(xy 246.285195 -52.491143) (xy 246.331045 -52.520609) (xy 246.372236 -52.5563) (xy 246.407927 -52.597491)
			(xy 246.437393 -52.643341) (xy 246.460035 -52.692918) (xy 246.47539 -52.745213) (xy 246.483146 -52.799161)
			(xy 246.483632 -52.826412) (xy 246.483154 -52.853746) (xy 246.47535 -52.907853) (xy 246.459903 -52.960292)
			(xy 246.43713 -53.00999) (xy 246.407496 -53.055929) (xy 246.389906 -53.076856) (xy 246.389652 -53.07711)
			(xy 246.389398 -53.077364) (xy 246.38382 -53.084457) (xy 246.377568 -53.101369) (xy 246.377206 -53.110384)
			(xy 246.377206 -53.17744) (xy 246.377543 -53.186459) (xy 246.383804 -53.203376) (xy 246.389398 -53.21046)
			(xy 246.389652 -53.210714) (xy 246.389906 -53.210968) (xy 246.407519 -53.23188) (xy 246.437174 -53.277814)
			(xy 246.459963 -53.327513) (xy 246.47542 -53.379957) (xy 246.483228 -53.434072) (xy 246.483227 -53.488746)
			(xy 246.475416 -53.54286) (xy 246.459957 -53.595304) (xy 246.437165 -53.645002) (xy 246.407508 -53.690934)
			(xy 246.389906 -53.711856) (xy 246.389652 -53.71211) (xy 246.389398 -53.712364) (xy 246.38382 -53.719457)
			(xy 246.377568 -53.736369) (xy 246.377206 -53.745384) (xy 246.377206 -53.81244) (xy 246.377543 -53.821459)
			(xy 246.383804 -53.838376) (xy 246.389398 -53.84546) (xy 246.389652 -53.845714) (xy 246.389906 -53.845968)
			(xy 246.407519 -53.86688) (xy 246.437174 -53.912814) (xy 246.459963 -53.962513) (xy 246.47542 -54.014957)
			(xy 246.483228 -54.069072) (xy 246.483227 -54.123746) (xy 246.475416 -54.17786) (xy 246.459957 -54.230304)
			(xy 246.437165 -54.280002) (xy 246.407508 -54.325934) (xy 246.389906 -54.346856) (xy 246.389652 -54.34711)
			(xy 246.389398 -54.347364) (xy 246.38382 -54.354457) (xy 246.377568 -54.371369) (xy 246.377206 -54.380384)
			(xy 246.377206 -54.44744) (xy 246.377543 -54.456459) (xy 246.383804 -54.473376) (xy 246.389398 -54.48046)
			(xy 246.389652 -54.480714) (xy 246.389906 -54.480968) (xy 246.407498 -54.501894) (xy 246.437136 -54.547831)
			(xy 246.459912 -54.597529) (xy 246.47536 -54.649969) (xy 246.483164 -54.704078) (xy 246.483632 -54.731412)
			(xy 246.483146 -54.758663) (xy 246.478482 -54.791102) (xy 248.37644 -54.791102) (xy 248.376933 -54.763769)
			(xy 248.384734 -54.709663) (xy 248.400178 -54.657223) (xy 248.422948 -54.607525) (xy 248.452578 -54.561586)
			(xy 248.470166 -54.540658) (xy 248.47042 -54.540404) (xy 248.470674 -54.54015) (xy 248.476254 -54.53306)
			(xy 248.482503 -54.516145) (xy 248.482866 -54.50713) (xy 248.482866 -54.440074) (xy 248.482529 -54.431055)
			(xy 248.476268 -54.414138) (xy 248.470674 -54.407054) (xy 248.47042 -54.4068) (xy 248.470166 -54.406546)
			(xy 248.452568 -54.385622) (xy 248.422915 -54.339689) (xy 248.400126 -54.289992) (xy 248.384669 -54.23755)
			(xy 248.37686 -54.183438) (xy 248.37686 -54.128765) (xy 248.384668 -54.074653) (xy 248.400125 -54.02221)
			(xy 248.422913 -53.972513) (xy 248.452566 -53.92658) (xy 248.470166 -53.905658) (xy 248.47042 -53.905404)
			(xy 248.470674 -53.90515) (xy 248.476254 -53.89806) (xy 248.482503 -53.881145) (xy 248.482866 -53.87213)
			(xy 248.482866 -53.805074) (xy 248.482529 -53.796055) (xy 248.476268 -53.779138) (xy 248.470674 -53.772054)
			(xy 248.47042 -53.7718) (xy 248.470166 -53.771546) (xy 248.452568 -53.750622) (xy 248.422915 -53.704689)
			(xy 248.400126 -53.654992) (xy 248.384669 -53.60255) (xy 248.37686 -53.548438) (xy 248.37686 -53.493765)
			(xy 248.384668 -53.439653) (xy 248.400125 -53.38721) (xy 248.422913 -53.337513) (xy 248.452566 -53.29158)
			(xy 248.470166 -53.270658) (xy 248.47042 -53.270404) (xy 248.470674 -53.27015) (xy 248.476254 -53.26306)
			(xy 248.482503 -53.246145) (xy 248.482866 -53.23713) (xy 248.482866 -53.170074) (xy 248.482529 -53.161055)
			(xy 248.476268 -53.144138) (xy 248.470674 -53.137054) (xy 248.47042 -53.1368) (xy 248.470166 -53.136546)
			(xy 248.452576 -53.115618) (xy 248.422939 -53.069681) (xy 248.400162 -53.019984) (xy 248.384714 -52.967544)
			(xy 248.376909 -52.913436) (xy 248.37644 -52.886102) (xy 248.376926 -52.858851) (xy 248.384682 -52.804903)
			(xy 248.400037 -52.752608) (xy 248.422679 -52.703031) (xy 248.452145 -52.657181) (xy 248.487836 -52.61599)
			(xy 248.529027 -52.580299) (xy 248.574877 -52.550833) (xy 248.624454 -52.528191) (xy 248.676749 -52.512836)
			(xy 248.730697 -52.50508) (xy 248.785199 -52.50508) (xy 248.839147 -52.512836) (xy 248.853465 -52.51704)
			(xy 253.040132 -52.51704) (xy 253.044203 -52.461418) (xy 253.056329 -52.406981) (xy 253.076252 -52.35489)
			(xy 253.103548 -52.306255) (xy 253.137634 -52.262112) (xy 253.177783 -52.223403) (xy 253.223141 -52.190952)
			(xy 253.272741 -52.165451) (xy 253.325525 -52.147444) (xy 253.380368 -52.137314) (xy 253.436102 -52.135277)
			(xy 253.491539 -52.141377) (xy 253.545496 -52.155483) (xy 253.596825 -52.177295) (xy 253.644431 -52.206349)
			(xy 253.687299 -52.242024) (xy 253.724516 -52.283561) (xy 253.755289 -52.330074) (xy 253.778961 -52.380571)
			(xy 253.795029 -52.433978) (xy 253.803149 -52.489154) (xy 253.803658 -52.51704) (xy 253.803149 -52.544926)
			(xy 253.796899 -52.587398) (xy 256.955288 -52.587398) (xy 256.959359 -52.531776) (xy 256.971485 -52.477339)
			(xy 256.991408 -52.425248) (xy 257.018704 -52.376613) (xy 257.05279 -52.33247) (xy 257.092939 -52.293761)
			(xy 257.138297 -52.26131) (xy 257.187897 -52.235809) (xy 257.240681 -52.217802) (xy 257.295524 -52.207672)
			(xy 257.351258 -52.205635) (xy 257.406695 -52.211735) (xy 257.460652 -52.225841) (xy 257.511981 -52.247653)
			(xy 257.559587 -52.276707) (xy 257.602455 -52.312382) (xy 257.639672 -52.353919) (xy 257.670445 -52.400432)
			(xy 257.694117 -52.450929) (xy 257.710185 -52.504336) (xy 257.718305 -52.559512) (xy 257.71839 -52.564153)
			(xy 262.02713 -52.564153) (xy 262.02713 -52.509647) (xy 262.034886 -52.455696) (xy 262.050241 -52.403398)
			(xy 262.072883 -52.353817) (xy 262.102349 -52.307962) (xy 262.138041 -52.266768) (xy 262.179232 -52.231072)
			(xy 262.225083 -52.201601) (xy 262.274662 -52.178955) (xy 262.326959 -52.163594) (xy 262.380909 -52.155832)
			(xy 262.408162 -52.155344) (xy 262.435532 -52.155822) (xy 262.489711 -52.163635) (xy 262.542214 -52.179121)
			(xy 262.591961 -52.20196) (xy 262.637928 -52.231683) (xy 262.65886 -52.249324) (xy 262.659114 -52.249578)
			(xy 262.666186 -52.255186) (xy 262.683114 -52.261418) (xy 262.692134 -52.26177) (xy 262.75919 -52.26177)
			(xy 262.768207 -52.261414) (xy 262.785124 -52.255166) (xy 262.79221 -52.249578) (xy 262.792718 -52.24907)
			(xy 262.813622 -52.231451) (xy 262.859566 -52.201818) (xy 262.909269 -52.179047) (xy 262.961714 -52.163605)
			(xy 263.015826 -52.155809) (xy 263.043162 -52.155344) (xy 263.070413 -52.155901) (xy 263.124361 -52.163652)
			(xy 263.176657 -52.179003) (xy 263.226236 -52.201641) (xy 263.272088 -52.231104) (xy 263.31328 -52.266793)
			(xy 263.348973 -52.307981) (xy 263.378441 -52.353831) (xy 263.401084 -52.403407) (xy 263.41644 -52.455701)
			(xy 263.424197 -52.509649) (xy 263.424197 -52.555952) (xy 264.783779 -52.555952) (xy 264.783779 -52.501448)
			(xy 264.791536 -52.447498) (xy 264.806893 -52.395202) (xy 264.829536 -52.345623) (xy 264.859004 -52.299772)
			(xy 264.894698 -52.258581) (xy 264.935891 -52.22289) (xy 264.981744 -52.193424) (xy 265.031324 -52.170784)
			(xy 265.083622 -52.155431) (xy 265.137572 -52.147678) (xy 265.164824 -52.147216) (xy 265.192195 -52.147664)
			(xy 265.246375 -52.155486) (xy 265.298878 -52.170979) (xy 265.348625 -52.193825) (xy 265.394591 -52.223553)
			(xy 265.415522 -52.241196) (xy 265.415776 -52.24145) (xy 265.422861 -52.247039) (xy 265.439779 -52.253283)
			(xy 265.448796 -52.253642) (xy 265.515852 -52.253642) (xy 265.524868 -52.253275) (xy 265.541786 -52.247036)
			(xy 265.548872 -52.24145) (xy 265.54938 -52.240942) (xy 265.570308 -52.223352) (xy 265.616244 -52.193712)
			(xy 265.665941 -52.170934) (xy 265.718381 -52.155486) (xy 265.77249 -52.147684) (xy 265.799824 -52.147216)
			(xy 265.827076 -52.147655) (xy 265.881024 -52.155415) (xy 265.93332 -52.170773) (xy 265.982897 -52.193417)
			(xy 266.028747 -52.222886) (xy 266.069937 -52.25858) (xy 266.105628 -52.299772) (xy 266.135094 -52.345624)
			(xy 266.157735 -52.395203) (xy 266.17309 -52.447499) (xy 266.180846 -52.501448) (xy 266.180846 -52.555952)
			(xy 266.17309 -52.609901) (xy 266.157735 -52.662197) (xy 266.135094 -52.711776) (xy 266.105628 -52.757628)
			(xy 266.069937 -52.79882) (xy 266.028747 -52.834514) (xy 265.982897 -52.863983) (xy 265.93332 -52.886627)
			(xy 265.881024 -52.901985) (xy 265.827076 -52.909745) (xy 265.799824 -52.910232) (xy 265.772453 -52.909768)
			(xy 265.718274 -52.901953) (xy 265.66577 -52.886464) (xy 265.616023 -52.863621) (xy 265.570057 -52.833895)
			(xy 265.549126 -52.816252) (xy 265.548872 -52.815998) (xy 265.541769 -52.810435) (xy 265.524865 -52.804174)
			(xy 265.515852 -52.803806) (xy 265.448796 -52.803806) (xy 265.439779 -52.80416) (xy 265.422862 -52.810409)
			(xy 265.415776 -52.815998) (xy 265.415268 -52.816506) (xy 265.394328 -52.834081) (xy 265.348395 -52.863722)
			(xy 265.298701 -52.886501) (xy 265.246263 -52.901953) (xy 265.192157 -52.909761) (xy 265.164824 -52.910232)
			(xy 265.137572 -52.909722) (xy 265.083622 -52.901969) (xy 265.031324 -52.886616) (xy 264.981744 -52.863976)
			(xy 264.935891 -52.83451) (xy 264.894698 -52.798819) (xy 264.859004 -52.757628) (xy 264.829536 -52.711777)
			(xy 264.806893 -52.662198) (xy 264.791536 -52.609902) (xy 264.783779 -52.555952) (xy 263.424197 -52.555952)
			(xy 263.424197 -52.564151) (xy 263.41644 -52.618099) (xy 263.401084 -52.670393) (xy 263.378441 -52.719969)
			(xy 263.348973 -52.765819) (xy 263.31328 -52.807007) (xy 263.272088 -52.842696) (xy 263.226236 -52.872159)
			(xy 263.176657 -52.894797) (xy 263.124361 -52.910148) (xy 263.070413 -52.917899) (xy 263.043162 -52.91836)
			(xy 263.015793 -52.917867) (xy 262.961614 -52.910057) (xy 262.909111 -52.894575) (xy 262.859364 -52.871739)
			(xy 262.813396 -52.842019) (xy 262.792464 -52.82438) (xy 262.79221 -52.824126) (xy 262.785131 -52.818529)
			(xy 262.768208 -52.81229) (xy 262.75919 -52.811934) (xy 262.692134 -52.811934) (xy 262.683118 -52.8123)
			(xy 262.666201 -52.818541) (xy 262.659114 -52.824126) (xy 262.658606 -52.824634) (xy 262.637693 -52.842242)
			(xy 262.591752 -52.871877) (xy 262.542051 -52.89465) (xy 262.489608 -52.910094) (xy 262.435497 -52.917893)
			(xy 262.408162 -52.91836) (xy 262.380909 -52.917968) (xy 262.326959 -52.910206) (xy 262.274662 -52.894845)
			(xy 262.225083 -52.872199) (xy 262.179232 -52.842728) (xy 262.138041 -52.807032) (xy 262.102349 -52.765838)
			(xy 262.072883 -52.719983) (xy 262.050241 -52.670402) (xy 262.034886 -52.618104) (xy 262.02713 -52.564153)
			(xy 257.71839 -52.564153) (xy 257.718814 -52.587398) (xy 257.718305 -52.615284) (xy 257.710185 -52.67046)
			(xy 257.694117 -52.723867) (xy 257.670445 -52.774364) (xy 257.639672 -52.820877) (xy 257.602455 -52.862414)
			(xy 257.559587 -52.898089) (xy 257.511981 -52.927143) (xy 257.460652 -52.948955) (xy 257.406695 -52.963061)
			(xy 257.351258 -52.969161) (xy 257.295524 -52.967124) (xy 257.240681 -52.956994) (xy 257.187897 -52.938987)
			(xy 257.138297 -52.913486) (xy 257.092939 -52.881035) (xy 257.05279 -52.842326) (xy 257.018704 -52.798183)
			(xy 256.991408 -52.749548) (xy 256.971485 -52.697457) (xy 256.959359 -52.64302) (xy 256.955288 -52.587398)
			(xy 253.796899 -52.587398) (xy 253.795029 -52.600102) (xy 253.778961 -52.653509) (xy 253.755289 -52.704006)
			(xy 253.724516 -52.750519) (xy 253.687299 -52.792056) (xy 253.644431 -52.827731) (xy 253.596825 -52.856785)
			(xy 253.545496 -52.878597) (xy 253.491539 -52.892703) (xy 253.436102 -52.898803) (xy 253.380368 -52.896766)
			(xy 253.325525 -52.886636) (xy 253.272741 -52.868629) (xy 253.223141 -52.843128) (xy 253.177783 -52.810677)
			(xy 253.137634 -52.771968) (xy 253.103548 -52.727825) (xy 253.076252 -52.67919) (xy 253.056329 -52.627099)
			(xy 253.044203 -52.572662) (xy 253.040132 -52.51704) (xy 248.853465 -52.51704) (xy 248.891442 -52.528191)
			(xy 248.941019 -52.550833) (xy 248.986869 -52.580299) (xy 249.02806 -52.61599) (xy 249.063751 -52.657181)
			(xy 249.093217 -52.703031) (xy 249.115859 -52.752608) (xy 249.131214 -52.804903) (xy 249.13897 -52.858851)
			(xy 249.139456 -52.886102) (xy 249.138967 -52.913435) (xy 249.131164 -52.967542) (xy 249.11572 -53.019981)
			(xy 249.092949 -53.069679) (xy 249.063318 -53.115618) (xy 249.04573 -53.136546) (xy 249.045476 -53.1368)
			(xy 249.045222 -53.137054) (xy 249.039639 -53.144143) (xy 249.033392 -53.161058) (xy 249.03303 -53.170074)
			(xy 249.03303 -53.23713) (xy 249.033366 -53.246149) (xy 249.039627 -53.263066) (xy 249.045222 -53.27015)
			(xy 249.045476 -53.270404) (xy 249.04573 -53.270658) (xy 249.063332 -53.291578) (xy 249.092985 -53.337512)
			(xy 249.115774 -53.387209) (xy 249.131231 -53.439652) (xy 249.139039 -53.493765) (xy 249.139039 -53.548438)
			(xy 249.13123 -53.602551) (xy 249.115773 -53.654994) (xy 249.092984 -53.704691) (xy 249.063331 -53.750624)
			(xy 249.046585 -53.77053) (xy 249.410728 -53.77053) (xy 249.411257 -53.741613) (xy 249.419983 -53.684442)
			(xy 249.437238 -53.629243) (xy 249.462627 -53.577281) (xy 249.495569 -53.529747) (xy 249.535309 -53.48773)
			(xy 249.557794 -53.46954) (xy 249.565171 -53.463249) (xy 249.574971 -53.44654) (xy 249.576844 -53.437028)
			(xy 249.577352 -53.429408) (xy 249.577352 -53.349652) (xy 249.576844 -53.342032) (xy 249.574973 -53.332519)
			(xy 249.565177 -53.315805) (xy 249.557794 -53.30952) (xy 249.535319 -53.291319) (xy 249.495583 -53.249301)
			(xy 249.462644 -53.201768) (xy 249.437254 -53.149809) (xy 249.419996 -53.094613) (xy 249.411264 -53.037445)
			(xy 249.410728 -53.00853) (xy 249.411183 -52.981276) (xy 249.418937 -52.927323) (xy 249.434291 -52.875023)
			(xy 249.456933 -52.825441) (xy 249.486401 -52.779586) (xy 249.522096 -52.738392) (xy 249.56329 -52.702697)
			(xy 249.609146 -52.67323) (xy 249.658729 -52.650589) (xy 249.711029 -52.635236) (xy 249.764982 -52.627483)
			(xy 249.792236 -52.627022) (xy 249.79249 -52.627022) (xy 249.818785 -52.62748) (xy 249.870874 -52.634725)
			(xy 249.921476 -52.64905) (xy 249.969632 -52.670186) (xy 250.014431 -52.697731) (xy 250.055026 -52.731165)
			(xy 250.07316 -52.750212) (xy 250.080746 -52.757636) (xy 250.100153 -52.766171) (xy 250.110752 -52.766722)
			(xy 250.18492 -52.766722) (xy 250.195551 -52.766309) (xy 250.215015 -52.757762) (xy 250.222512 -52.750212)
			(xy 250.240628 -52.731144) (xy 250.281212 -52.697688) (xy 250.326011 -52.67013) (xy 250.374174 -52.648993)
			(xy 250.424785 -52.634678) (xy 250.476884 -52.627458) (xy 250.503182 -52.627022) (xy 250.503436 -52.627022)
			(xy 250.53069 -52.627444) (xy 250.584641 -52.635207) (xy 250.636939 -52.650568) (xy 250.686518 -52.673215)
			(xy 250.73237 -52.702688) (xy 250.77356 -52.738386) (xy 250.809251 -52.779583) (xy 250.838716 -52.82544)
			(xy 250.861355 -52.875023) (xy 250.876707 -52.927324) (xy 250.88446 -52.981276) (xy 250.884944 -53.00853)
			(xy 250.884481 -53.036197) (xy 250.88225 -53.051456) (xy 259.141212 -53.051456) (xy 259.145283 -52.995834)
			(xy 259.157409 -52.941397) (xy 259.177332 -52.889306) (xy 259.204628 -52.840671) (xy 259.238714 -52.796528)
			(xy 259.278863 -52.757819) (xy 259.324221 -52.725368) (xy 259.373821 -52.699867) (xy 259.426605 -52.68186)
			(xy 259.481448 -52.67173) (xy 259.537182 -52.669693) (xy 259.592619 -52.675793) (xy 259.646576 -52.689899)
			(xy 259.697905 -52.711711) (xy 259.745511 -52.740765) (xy 259.788379 -52.77644) (xy 259.825596 -52.817977)
			(xy 259.856369 -52.86449) (xy 259.880041 -52.914987) (xy 259.896109 -52.968394) (xy 259.904229 -53.02357)
			(xy 259.904738 -53.051456) (xy 259.904229 -53.079342) (xy 259.896109 -53.134518) (xy 259.880041 -53.187925)
			(xy 259.856369 -53.238422) (xy 259.825596 -53.284935) (xy 259.788379 -53.326472) (xy 259.745511 -53.362147)
			(xy 259.697905 -53.391201) (xy 259.646576 -53.413013) (xy 259.592619 -53.427119) (xy 259.537182 -53.433219)
			(xy 259.481448 -53.431182) (xy 259.426605 -53.421052) (xy 259.373821 -53.403045) (xy 259.324221 -53.377544)
			(xy 259.278863 -53.345093) (xy 259.238714 -53.306384) (xy 259.204628 -53.262241) (xy 259.177332 -53.213606)
			(xy 259.157409 -53.161515) (xy 259.145283 -53.107078) (xy 259.141212 -53.051456) (xy 250.88225 -53.051456)
			(xy 250.876476 -53.09095) (xy 250.860653 -53.143974) (xy 250.837342 -53.194159) (xy 250.807033 -53.240454)
			(xy 250.770359 -53.28189) (xy 250.728089 -53.317599) (xy 250.704858 -53.332634) (xy 250.704604 -53.332888)
			(xy 250.69508 -53.339556) (xy 250.682772 -53.359248) (xy 250.680982 -53.370734) (xy 250.673108 -53.450744)
			(xy 250.672441 -53.462445) (xy 250.680523 -53.484417) (xy 250.688602 -53.492908) (xy 250.688856 -53.492908)
			(xy 250.707415 -53.511011) (xy 250.739997 -53.551337) (xy 250.766814 -53.595707) (xy 250.787371 -53.643301)
			(xy 250.801289 -53.693242) (xy 250.80831 -53.744608) (xy 250.808744 -53.77053) (xy 250.80825 -53.79778)
			(xy 250.800491 -53.851726) (xy 250.785133 -53.904018) (xy 250.762491 -53.953593) (xy 250.733025 -53.999442)
			(xy 250.697335 -54.040631) (xy 250.656147 -54.076322) (xy 250.610299 -54.105789) (xy 250.560724 -54.128431)
			(xy 250.508432 -54.143789) (xy 250.454486 -54.15155) (xy 250.427236 -54.152038) (xy 250.399866 -54.151566)
			(xy 250.345686 -54.143752) (xy 250.293183 -54.128265) (xy 250.243436 -54.105424) (xy 250.197469 -54.0757)
			(xy 250.176538 -54.058058) (xy 250.176284 -54.057804) (xy 250.169206 -54.052205) (xy 250.152283 -54.045966)
			(xy 250.143264 -54.045612) (xy 250.076208 -54.045612) (xy 250.067191 -54.04597) (xy 250.050274 -54.052217)
			(xy 250.043188 -54.057804) (xy 250.04268 -54.058312) (xy 250.021774 -54.075929) (xy 249.975832 -54.105563)
			(xy 249.926129 -54.128335) (xy 249.873684 -54.143777) (xy 249.819572 -54.151573) (xy 249.792236 -54.152038)
			(xy 249.764985 -54.151511) (xy 249.711038 -54.14376) (xy 249.658743 -54.12841) (xy 249.609165 -54.105774)
			(xy 249.563314 -54.076312) (xy 249.522121 -54.040625) (xy 249.486427 -53.999439) (xy 249.456958 -53.953593)
			(xy 249.434313 -53.904018) (xy 249.418954 -53.851726) (xy 249.411193 -53.797781) (xy 249.410728 -53.77053)
			(xy 249.046585 -53.77053) (xy 249.04573 -53.771546) (xy 249.045476 -53.7718) (xy 249.045222 -53.772054)
			(xy 249.039639 -53.779143) (xy 249.033392 -53.796058) (xy 249.03303 -53.805074) (xy 249.03303 -53.87213)
			(xy 249.033366 -53.881149) (xy 249.039627 -53.898066) (xy 249.045222 -53.90515) (xy 249.045476 -53.905404)
			(xy 249.04573 -53.905658) (xy 249.063332 -53.926578) (xy 249.092985 -53.972512) (xy 249.115774 -54.022209)
			(xy 249.131231 -54.074652) (xy 249.139039 -54.128765) (xy 249.139039 -54.183438) (xy 249.13123 -54.237551)
			(xy 249.115773 -54.289994) (xy 249.101928 -54.320186) (xy 251.33046 -54.320186) (xy 251.330938 -54.292852)
			(xy 251.338743 -54.238745) (xy 251.35419 -54.186306) (xy 251.376963 -54.136608) (xy 251.406596 -54.090669)
			(xy 251.424186 -54.069742) (xy 251.42444 -54.069488) (xy 251.424694 -54.069234) (xy 251.430272 -54.062141)
			(xy 251.436524 -54.045229) (xy 251.436886 -54.036214) (xy 251.436886 -53.969158) (xy 251.436504 -53.960144)
			(xy 251.430274 -53.943226) (xy 251.424694 -53.936138) (xy 251.42444 -53.935884) (xy 251.424186 -53.93563)
			(xy 251.406592 -53.914706) (xy 251.376954 -53.868768) (xy 251.354178 -53.81907) (xy 251.338731 -53.766629)
			(xy 251.330928 -53.71252) (xy 251.33046 -53.685186) (xy 251.330946 -53.657935) (xy 251.338702 -53.603987)
			(xy 251.354057 -53.551692) (xy 251.376699 -53.502115) (xy 251.406165 -53.456265) (xy 251.441856 -53.415074)
			(xy 251.483047 -53.379383) (xy 251.528897 -53.349917) (xy 251.578474 -53.327275) (xy 251.630769 -53.31192)
			(xy 251.684717 -53.304164) (xy 251.739219 -53.304164) (xy 251.793167 -53.31192) (xy 251.845462 -53.327275)
			(xy 251.895039 -53.349917) (xy 251.940889 -53.379383) (xy 251.98208 -53.415074) (xy 252.017771 -53.456265)
			(xy 252.043661 -53.496551) (xy 264.333464 -53.496551) (xy 264.333464 -53.442049) (xy 264.34122 -53.3881)
			(xy 264.356575 -53.335805) (xy 264.379216 -53.286227) (xy 264.408681 -53.240376) (xy 264.444372 -53.199185)
			(xy 264.485562 -53.163492) (xy 264.531412 -53.134024) (xy 264.580988 -53.111381) (xy 264.633283 -53.096024)
			(xy 264.687231 -53.088265) (xy 264.714482 -53.087778) (xy 264.741853 -53.088236) (xy 264.796033 -53.096053)
			(xy 264.848537 -53.111543) (xy 264.898284 -53.134387) (xy 264.944249 -53.164115) (xy 264.96518 -53.181758)
			(xy 264.965434 -53.182012) (xy 264.972534 -53.187578) (xy 264.989441 -53.193837) (xy 264.998454 -53.194204)
			(xy 265.06551 -53.194204) (xy 265.074527 -53.193851) (xy 265.091444 -53.1876) (xy 265.09853 -53.182012)
			(xy 265.099038 -53.181504) (xy 265.119977 -53.163928) (xy 265.16591 -53.134287) (xy 265.215605 -53.111507)
			(xy 265.268042 -53.096056) (xy 265.322149 -53.088249) (xy 265.349482 -53.087778) (xy 265.376735 -53.088268)
			(xy 265.430686 -53.096023) (xy 265.482984 -53.111377) (xy 265.532564 -53.134017) (xy 265.578418 -53.163484)
			(xy 265.619611 -53.199176) (xy 265.655306 -53.240368) (xy 265.684774 -53.28622) (xy 265.707417 -53.335799)
			(xy 265.722773 -53.388097) (xy 265.730531 -53.442047) (xy 265.730531 -53.496553) (xy 265.722773 -53.550503)
			(xy 265.707417 -53.602801) (xy 265.684774 -53.65238) (xy 265.655306 -53.698232) (xy 265.619611 -53.739424)
			(xy 265.578418 -53.775116) (xy 265.532564 -53.804583) (xy 265.482984 -53.827223) (xy 265.430686 -53.842577)
			(xy 265.376735 -53.850332) (xy 265.349482 -53.850794) (xy 265.322111 -53.85034) (xy 265.267932 -53.842519)
			(xy 265.215428 -53.827028) (xy 265.165682 -53.804183) (xy 265.119715 -53.774456) (xy 265.098784 -53.756814)
			(xy 265.09853 -53.75656) (xy 265.091443 -53.750975) (xy 265.074526 -53.744728) (xy 265.06551 -53.744368)
			(xy 264.998454 -53.744368) (xy 264.989441 -53.744758) (xy 264.972524 -53.750983) (xy 264.965434 -53.75656)
			(xy 264.964926 -53.757068) (xy 264.943997 -53.774657) (xy 264.898062 -53.804297) (xy 264.848365 -53.827074)
			(xy 264.795925 -53.842523) (xy 264.741816 -53.850326) (xy 264.714482 -53.850794) (xy 264.687231 -53.850335)
			(xy 264.633283 -53.842576) (xy 264.580988 -53.827219) (xy 264.531412 -53.804576) (xy 264.485562 -53.775108)
			(xy 264.444372 -53.739415) (xy 264.408681 -53.698224) (xy 264.379216 -53.652373) (xy 264.356575 -53.602795)
			(xy 264.34122 -53.5505) (xy 264.333464 -53.496551) (xy 252.043661 -53.496551) (xy 252.047237 -53.502115)
			(xy 252.069879 -53.551692) (xy 252.085234 -53.603987) (xy 252.09299 -53.657935) (xy 252.093476 -53.685186)
			(xy 252.093031 -53.712521) (xy 252.085217 -53.766629) (xy 252.069762 -53.819068) (xy 252.046982 -53.868766)
			(xy 252.017342 -53.914703) (xy 251.99975 -53.93563) (xy 251.999496 -53.935884) (xy 251.999242 -53.936138)
			(xy 251.993668 -53.943233) (xy 251.987415 -53.960144) (xy 251.98705 -53.969158) (xy 251.98705 -54.036214)
			(xy 251.98739 -54.045233) (xy 251.993648 -54.06215) (xy 251.999242 -54.069234) (xy 251.999496 -54.069488)
			(xy 251.99975 -54.069742) (xy 252.017336 -54.090672) (xy 252.046974 -54.136609) (xy 252.069751 -54.186306)
			(xy 252.0852 -54.238745) (xy 252.093006 -54.292852) (xy 252.093476 -54.320186) (xy 252.09299 -54.347437)
			(xy 252.085234 -54.401385) (xy 252.069879 -54.45368) (xy 252.047237 -54.503257) (xy 252.017771 -54.549107)
			(xy 251.98208 -54.590298) (xy 251.940889 -54.625989) (xy 251.895039 -54.655455) (xy 251.845462 -54.678097)
			(xy 251.793167 -54.693452) (xy 251.739219 -54.701208) (xy 251.684717 -54.701208) (xy 251.630769 -54.693452)
			(xy 251.578474 -54.678097) (xy 251.528897 -54.655455) (xy 251.483047 -54.625989) (xy 251.441856 -54.590298)
			(xy 251.406165 -54.549107) (xy 251.376699 -54.503257) (xy 251.354057 -54.45368) (xy 251.338702 -54.401385)
			(xy 251.330946 -54.347437) (xy 251.33046 -54.320186) (xy 249.101928 -54.320186) (xy 249.092984 -54.339691)
			(xy 249.063331 -54.385624) (xy 249.04573 -54.406546) (xy 249.045476 -54.4068) (xy 249.045222 -54.407054)
			(xy 249.039639 -54.414143) (xy 249.033392 -54.431058) (xy 249.03303 -54.440074) (xy 249.03303 -54.50713)
			(xy 249.033366 -54.516149) (xy 249.039627 -54.533066) (xy 249.045222 -54.54015) (xy 249.045476 -54.540404)
			(xy 249.04573 -54.540658) (xy 249.063321 -54.561585) (xy 249.092958 -54.607522) (xy 249.115735 -54.65722)
			(xy 249.131183 -54.70966) (xy 249.138987 -54.763768) (xy 249.139103 -54.770528) (xy 252.271022 -54.770528)
			(xy 252.271476 -54.743194) (xy 252.279287 -54.689086) (xy 252.294741 -54.636646) (xy 252.317519 -54.586949)
			(xy 252.347157 -54.541011) (xy 252.364748 -54.520084) (xy 252.365002 -54.51983) (xy 252.365256 -54.519576)
			(xy 252.370865 -54.512505) (xy 252.377097 -54.495576) (xy 252.377448 -54.486556) (xy 252.377448 -54.4195)
			(xy 252.377102 -54.410482) (xy 252.370848 -54.393564) (xy 252.365256 -54.38648) (xy 252.365002 -54.386226)
			(xy 252.364748 -54.385972) (xy 252.347183 -54.365024) (xy 252.317539 -54.319094) (xy 252.294757 -54.269402)
			(xy 252.279302 -54.216966) (xy 252.271493 -54.162861) (xy 252.271022 -54.135528) (xy 252.271508 -54.108277)
			(xy 252.279264 -54.054329) (xy 252.294619 -54.002034) (xy 252.317261 -53.952457) (xy 252.346727 -53.906607)
			(xy 252.382418 -53.865416) (xy 252.423609 -53.829725) (xy 252.469459 -53.800259) (xy 252.519036 -53.777617)
			(xy 252.571331 -53.762262) (xy 252.625279 -53.754506) (xy 252.679781 -53.754506) (xy 252.733729 -53.762262)
			(xy 252.786024 -53.777617) (xy 252.835601 -53.800259) (xy 252.881451 -53.829725) (xy 252.922642 -53.865416)
			(xy 252.958333 -53.906607) (xy 252.987799 -53.952457) (xy 252.992874 -53.96357) (xy 256.972052 -53.96357)
			(xy 256.976123 -53.907948) (xy 256.988249 -53.853511) (xy 257.008172 -53.80142) (xy 257.035468 -53.752785)
			(xy 257.069554 -53.708642) (xy 257.109703 -53.669933) (xy 257.155061 -53.637482) (xy 257.204661 -53.611981)
			(xy 257.257445 -53.593974) (xy 257.312288 -53.583844) (xy 257.368022 -53.581807) (xy 257.423459 -53.587907)
			(xy 257.477416 -53.602013) (xy 257.528745 -53.623825) (xy 257.576351 -53.652879) (xy 257.619219 -53.688554)
			(xy 257.656436 -53.730091) (xy 257.687209 -53.776604) (xy 257.710881 -53.827101) (xy 257.726949 -53.880508)
			(xy 257.735069 -53.935684) (xy 257.735578 -53.96357) (xy 257.735069 -53.991456) (xy 257.726949 -54.046632)
			(xy 257.720684 -54.067456) (xy 259.141212 -54.067456) (xy 259.145283 -54.011834) (xy 259.157409 -53.957397)
			(xy 259.177332 -53.905306) (xy 259.204628 -53.856671) (xy 259.238714 -53.812528) (xy 259.278863 -53.773819)
			(xy 259.324221 -53.741368) (xy 259.373821 -53.715867) (xy 259.426605 -53.69786) (xy 259.481448 -53.68773)
			(xy 259.537182 -53.685693) (xy 259.592619 -53.691793) (xy 259.646576 -53.705899) (xy 259.697905 -53.727711)
			(xy 259.745511 -53.756765) (xy 259.788379 -53.79244) (xy 259.825596 -53.833977) (xy 259.856369 -53.88049)
			(xy 259.880041 -53.930987) (xy 259.896109 -53.984394) (xy 259.904229 -54.03957) (xy 259.904738 -54.067456)
			(xy 259.904229 -54.095342) (xy 259.896109 -54.150518) (xy 259.880041 -54.203925) (xy 259.863643 -54.238906)
			(xy 266.585952 -54.238906) (xy 266.590023 -54.183284) (xy 266.602149 -54.128847) (xy 266.622072 -54.076756)
			(xy 266.649368 -54.028121) (xy 266.683454 -53.983978) (xy 266.723603 -53.945269) (xy 266.768961 -53.912818)
			(xy 266.818561 -53.887317) (xy 266.871345 -53.86931) (xy 266.926188 -53.85918) (xy 266.981922 -53.857143)
			(xy 267.037359 -53.863243) (xy 267.091316 -53.877349) (xy 267.142645 -53.899161) (xy 267.190251 -53.928215)
			(xy 267.233119 -53.96389) (xy 267.270336 -54.005427) (xy 267.301109 -54.05194) (xy 267.324781 -54.102437)
			(xy 267.340849 -54.155844) (xy 267.348969 -54.21102) (xy 267.349478 -54.238906) (xy 267.348969 -54.266792)
			(xy 267.340849 -54.321968) (xy 267.324781 -54.375375) (xy 267.301109 -54.425872) (xy 267.270336 -54.472385)
			(xy 267.233119 -54.513922) (xy 267.190251 -54.549597) (xy 267.142645 -54.578651) (xy 267.091316 -54.600463)
			(xy 267.037359 -54.614569) (xy 266.981922 -54.620669) (xy 266.926188 -54.618632) (xy 266.871345 -54.608502)
			(xy 266.818561 -54.590495) (xy 266.768961 -54.564994) (xy 266.723603 -54.532543) (xy 266.683454 -54.493834)
			(xy 266.649368 -54.449691) (xy 266.622072 -54.401056) (xy 266.602149 -54.348965) (xy 266.590023 -54.294528)
			(xy 266.585952 -54.238906) (xy 259.863643 -54.238906) (xy 259.856369 -54.254422) (xy 259.825596 -54.300935)
			(xy 259.788379 -54.342472) (xy 259.745511 -54.378147) (xy 259.697905 -54.407201) (xy 259.646576 -54.429013)
			(xy 259.592619 -54.443119) (xy 259.537182 -54.449219) (xy 259.481448 -54.447182) (xy 259.426605 -54.437052)
			(xy 259.373821 -54.419045) (xy 259.324221 -54.393544) (xy 259.278863 -54.361093) (xy 259.238714 -54.322384)
			(xy 259.204628 -54.278241) (xy 259.177332 -54.229606) (xy 259.157409 -54.177515) (xy 259.145283 -54.123078)
			(xy 259.141212 -54.067456) (xy 257.720684 -54.067456) (xy 257.710881 -54.100039) (xy 257.687209 -54.150536)
			(xy 257.656436 -54.197049) (xy 257.619219 -54.238586) (xy 257.576351 -54.274261) (xy 257.528745 -54.303315)
			(xy 257.477416 -54.325127) (xy 257.423459 -54.339233) (xy 257.368022 -54.345333) (xy 257.312288 -54.343296)
			(xy 257.257445 -54.333166) (xy 257.204661 -54.315159) (xy 257.155061 -54.289658) (xy 257.109703 -54.257207)
			(xy 257.069554 -54.218498) (xy 257.035468 -54.174355) (xy 257.008172 -54.12572) (xy 256.988249 -54.073629)
			(xy 256.976123 -54.019192) (xy 256.972052 -53.96357) (xy 252.992874 -53.96357) (xy 253.010441 -54.002034)
			(xy 253.025796 -54.054329) (xy 253.033552 -54.108277) (xy 253.034038 -54.135528) (xy 253.033568 -54.162862)
			(xy 253.025762 -54.21697) (xy 253.010313 -54.269409) (xy 252.987538 -54.319107) (xy 252.957903 -54.365045)
			(xy 252.940312 -54.385972) (xy 252.940058 -54.386226) (xy 252.939804 -54.38648) (xy 252.93422 -54.393568)
			(xy 252.927972 -54.410484) (xy 252.927612 -54.4195) (xy 252.927612 -54.486556) (xy 252.927988 -54.495571)
			(xy 252.934222 -54.512488) (xy 252.939804 -54.519576) (xy 252.940058 -54.51983) (xy 252.940312 -54.520084)
			(xy 252.957912 -54.541003) (xy 252.987549 -54.586942) (xy 253.010324 -54.636642) (xy 253.02577 -54.689084)
			(xy 253.033571 -54.743193) (xy 253.034038 -54.770528) (xy 253.033552 -54.797779) (xy 253.025796 -54.851727)
			(xy 253.010441 -54.904022) (xy 252.987799 -54.953599) (xy 252.958333 -54.999449) (xy 252.922642 -55.04064)
			(xy 252.881451 -55.076331) (xy 252.870364 -55.083456) (xy 259.141212 -55.083456) (xy 259.145283 -55.027834)
			(xy 259.157409 -54.973397) (xy 259.177332 -54.921306) (xy 259.204628 -54.872671) (xy 259.238714 -54.828528)
			(xy 259.278863 -54.789819) (xy 259.324221 -54.757368) (xy 259.373821 -54.731867) (xy 259.426605 -54.71386)
			(xy 259.481448 -54.70373) (xy 259.537182 -54.701693) (xy 259.592619 -54.707793) (xy 259.646576 -54.721899)
			(xy 259.697905 -54.743711) (xy 259.745511 -54.772765) (xy 259.788379 -54.80844) (xy 259.825596 -54.849977)
			(xy 259.856369 -54.89649) (xy 259.880041 -54.946987) (xy 259.892696 -54.989051) (xy 262.101068 -54.989051)
			(xy 262.101068 -54.934549) (xy 262.108824 -54.880602) (xy 262.124178 -54.828308) (xy 262.146818 -54.778731)
			(xy 262.176283 -54.732881) (xy 262.211973 -54.69169) (xy 262.253161 -54.655997) (xy 262.29901 -54.62653)
			(xy 262.348585 -54.603887) (xy 262.400879 -54.588529) (xy 262.454825 -54.580769) (xy 262.482076 -54.580282)
			(xy 262.510167 -54.580796) (xy 262.565743 -54.58902) (xy 262.619512 -54.605307) (xy 262.670309 -54.629307)
			(xy 262.717036 -54.660499) (xy 262.758682 -54.698208) (xy 262.794345 -54.741619) (xy 262.809228 -54.765448)
			(xy 262.814816 -54.774592) (xy 262.831834 -54.786784) (xy 262.924798 -54.80685) (xy 262.945372 -54.802786)
			(xy 262.954008 -54.79669) (xy 262.978068 -54.780683) (xy 263.030001 -54.755342) (xy 263.08516 -54.738119)
			(xy 263.142285 -54.729406) (xy 263.171178 -54.728872) (xy 263.198429 -54.729376) (xy 263.212596 -54.731412)
			(xy 271.720564 -54.731412) (xy 271.720998 -54.704077) (xy 271.728813 -54.649968) (xy 271.74427 -54.597528)
			(xy 271.767053 -54.547831) (xy 271.796696 -54.501894) (xy 271.81429 -54.480968) (xy 271.814544 -54.480714)
			(xy 271.814798 -54.48046) (xy 271.820365 -54.47336) (xy 271.826624 -54.456454) (xy 271.82699 -54.44744)
			(xy 271.82699 -54.380384) (xy 271.826643 -54.371366) (xy 271.820389 -54.354449) (xy 271.814798 -54.347364)
			(xy 271.814544 -54.34711) (xy 271.81429 -54.346856) (xy 271.7967 -54.325925) (xy 271.767045 -54.279994)
			(xy 271.744255 -54.230298) (xy 271.728796 -54.177857) (xy 271.720986 -54.123745) (xy 271.720984 -54.069073)
			(xy 271.728792 -54.014961) (xy 271.744248 -53.962519) (xy 271.767037 -53.912822) (xy 271.79669 -53.86689)
			(xy 271.81429 -53.845968) (xy 271.814544 -53.845714) (xy 271.814798 -53.84546) (xy 271.820365 -53.83836)
			(xy 271.826624 -53.821454) (xy 271.82699 -53.81244) (xy 271.82699 -53.745384) (xy 271.826643 -53.736366)
			(xy 271.820389 -53.719449) (xy 271.814798 -53.712364) (xy 271.814544 -53.71211) (xy 271.81429 -53.711856)
			(xy 271.7967 -53.690925) (xy 271.767045 -53.644994) (xy 271.744255 -53.595298) (xy 271.728796 -53.542857)
			(xy 271.720986 -53.488745) (xy 271.720984 -53.434073) (xy 271.728792 -53.379961) (xy 271.744248 -53.327519)
			(xy 271.767037 -53.277822) (xy 271.79669 -53.23189) (xy 271.81429 -53.210968) (xy 271.814544 -53.210714)
			(xy 271.814798 -53.21046) (xy 271.820365 -53.20336) (xy 271.826624 -53.186454) (xy 271.82699 -53.17744)
			(xy 271.82699 -53.110384) (xy 271.826643 -53.101366) (xy 271.820389 -53.084449) (xy 271.814798 -53.077364)
			(xy 271.814544 -53.07711) (xy 271.81429 -53.076856) (xy 271.796709 -53.055921) (xy 271.767069 -53.009987)
			(xy 271.744291 -52.960291) (xy 271.72884 -52.907853) (xy 271.721034 -52.853746) (xy 271.720564 -52.826412)
			(xy 271.72105 -52.799161) (xy 271.728806 -52.745213) (xy 271.744161 -52.692918) (xy 271.766803 -52.643341)
			(xy 271.796269 -52.597491) (xy 271.83196 -52.5563) (xy 271.873151 -52.520609) (xy 271.919001 -52.491143)
			(xy 271.968578 -52.468501) (xy 272.020873 -52.453146) (xy 272.074821 -52.44539) (xy 272.129323 -52.44539)
			(xy 272.183271 -52.453146) (xy 272.235566 -52.468501) (xy 272.285143 -52.491143) (xy 272.330993 -52.520609)
			(xy 272.372184 -52.5563) (xy 272.407875 -52.597491) (xy 272.437341 -52.643341) (xy 272.459983 -52.692918)
			(xy 272.475338 -52.745213) (xy 272.483094 -52.799161) (xy 272.48358 -52.826412) (xy 272.483091 -52.853745)
			(xy 272.475288 -52.907851) (xy 272.459843 -52.96029) (xy 272.437072 -53.009988) (xy 272.407442 -53.055928)
			(xy 272.389854 -53.076856) (xy 272.3896 -53.07711) (xy 272.389346 -53.077364) (xy 272.383762 -53.084452)
			(xy 272.377515 -53.101368) (xy 272.377154 -53.110384) (xy 272.377154 -53.17744) (xy 272.37748 -53.18646)
			(xy 272.383748 -53.203378) (xy 272.389346 -53.21046) (xy 272.3896 -53.210714) (xy 272.389854 -53.210968)
			(xy 272.407465 -53.231881) (xy 272.437116 -53.277816) (xy 272.459903 -53.327515) (xy 272.475358 -53.379959)
			(xy 272.483165 -53.434072) (xy 272.483163 -53.488746) (xy 272.475354 -53.542859) (xy 272.459896 -53.595302)
			(xy 272.437107 -53.645) (xy 272.407454 -53.690933) (xy 272.389854 -53.711856) (xy 272.3896 -53.71211)
			(xy 272.389346 -53.712364) (xy 272.383762 -53.719452) (xy 272.377515 -53.736368) (xy 272.377154 -53.745384)
			(xy 272.377154 -53.81244) (xy 272.37748 -53.82146) (xy 272.383748 -53.838378) (xy 272.389346 -53.84546)
			(xy 272.3896 -53.845714) (xy 272.389854 -53.845968) (xy 272.407465 -53.866881) (xy 272.437116 -53.912816)
			(xy 272.459903 -53.962515) (xy 272.475358 -54.014959) (xy 272.483165 -54.069072) (xy 272.483163 -54.123746)
			(xy 272.475354 -54.177859) (xy 272.459896 -54.230302) (xy 272.437107 -54.28) (xy 272.407454 -54.325933)
			(xy 272.389854 -54.346856) (xy 272.3896 -54.34711) (xy 272.389346 -54.347364) (xy 272.383762 -54.354452)
			(xy 272.377515 -54.371368) (xy 272.377154 -54.380384) (xy 272.377154 -54.44744) (xy 272.37748 -54.45646)
			(xy 272.383748 -54.473378) (xy 272.389346 -54.48046) (xy 272.3896 -54.480714) (xy 272.389854 -54.480968)
			(xy 272.407438 -54.501901) (xy 272.437079 -54.547835) (xy 272.459858 -54.597531) (xy 272.475307 -54.64997)
			(xy 272.483111 -54.704078) (xy 272.48358 -54.731412) (xy 272.483094 -54.758663) (xy 272.47843 -54.791102)
			(xy 274.376388 -54.791102) (xy 274.376893 -54.76377) (xy 274.384694 -54.709664) (xy 274.400135 -54.657226)
			(xy 274.422902 -54.607528) (xy 274.452528 -54.561587) (xy 274.470114 -54.540658) (xy 274.470368 -54.540404)
			(xy 274.470622 -54.54015) (xy 274.476196 -54.533055) (xy 274.48245 -54.516145) (xy 274.482814 -54.50713)
			(xy 274.482814 -54.440074) (xy 274.482466 -54.431056) (xy 274.476212 -54.41414) (xy 274.470622 -54.407054)
			(xy 274.470368 -54.4068) (xy 274.470114 -54.406546) (xy 274.452514 -54.385623) (xy 274.422857 -54.339691)
			(xy 274.400066 -54.289995) (xy 274.384606 -54.237552) (xy 274.376797 -54.183438) (xy 274.376796 -54.128765)
			(xy 274.384606 -54.074651) (xy 274.400065 -54.022208) (xy 274.422856 -53.972511) (xy 274.452512 -53.926579)
			(xy 274.470114 -53.905658) (xy 274.470368 -53.905404) (xy 274.470622 -53.90515) (xy 274.476196 -53.898055)
			(xy 274.48245 -53.881145) (xy 274.482814 -53.87213) (xy 274.482814 -53.805074) (xy 274.482466 -53.796056)
			(xy 274.476212 -53.77914) (xy 274.470622 -53.772054) (xy 274.470368 -53.7718) (xy 274.470114 -53.771546)
			(xy 274.452514 -53.750623) (xy 274.422857 -53.704691) (xy 274.400066 -53.654995) (xy 274.384606 -53.602552)
			(xy 274.376797 -53.548438) (xy 274.376796 -53.493765) (xy 274.384606 -53.439651) (xy 274.400065 -53.387208)
			(xy 274.422856 -53.337511) (xy 274.452512 -53.291579) (xy 274.470114 -53.270658) (xy 274.470368 -53.270404)
			(xy 274.470622 -53.27015) (xy 274.476196 -53.263055) (xy 274.48245 -53.246145) (xy 274.482814 -53.23713)
			(xy 274.482814 -53.170074) (xy 274.482466 -53.161056) (xy 274.476212 -53.14414) (xy 274.470622 -53.137054)
			(xy 274.470368 -53.1368) (xy 274.470114 -53.136546) (xy 274.452532 -53.115612) (xy 274.422891 -53.069677)
			(xy 274.400113 -53.019982) (xy 274.384663 -52.967543) (xy 274.376858 -52.913436) (xy 274.376388 -52.886102)
			(xy 274.376874 -52.858851) (xy 274.38463 -52.804903) (xy 274.399985 -52.752608) (xy 274.422627 -52.703031)
			(xy 274.452093 -52.657181) (xy 274.487784 -52.61599) (xy 274.528975 -52.580299) (xy 274.574825 -52.550833)
			(xy 274.624402 -52.528191) (xy 274.676697 -52.512836) (xy 274.730645 -52.50508) (xy 274.785147 -52.50508)
			(xy 274.839095 -52.512836) (xy 274.853413 -52.51704) (xy 279.04008 -52.51704) (xy 279.044151 -52.461418)
			(xy 279.056277 -52.406981) (xy 279.0762 -52.35489) (xy 279.103496 -52.306255) (xy 279.137582 -52.262112)
			(xy 279.177731 -52.223403) (xy 279.223089 -52.190952) (xy 279.272689 -52.165451) (xy 279.325473 -52.147444)
			(xy 279.380316 -52.137314) (xy 279.43605 -52.135277) (xy 279.491487 -52.141377) (xy 279.545444 -52.155483)
			(xy 279.596773 -52.177295) (xy 279.644379 -52.206349) (xy 279.687247 -52.242024) (xy 279.724464 -52.283561)
			(xy 279.755237 -52.330074) (xy 279.778909 -52.380571) (xy 279.794977 -52.433978) (xy 279.803097 -52.489154)
			(xy 279.803606 -52.51704) (xy 279.803097 -52.544926) (xy 279.796847 -52.587398) (xy 282.955236 -52.587398)
			(xy 282.959307 -52.531776) (xy 282.971433 -52.477339) (xy 282.991356 -52.425248) (xy 283.018652 -52.376613)
			(xy 283.052738 -52.33247) (xy 283.092887 -52.293761) (xy 283.138245 -52.26131) (xy 283.187845 -52.235809)
			(xy 283.240629 -52.217802) (xy 283.295472 -52.207672) (xy 283.351206 -52.205635) (xy 283.406643 -52.211735)
			(xy 283.4606 -52.225841) (xy 283.511929 -52.247653) (xy 283.559535 -52.276707) (xy 283.602403 -52.312382)
			(xy 283.63962 -52.353919) (xy 283.670393 -52.400432) (xy 283.694065 -52.450929) (xy 283.710133 -52.504336)
			(xy 283.718253 -52.559512) (xy 283.718338 -52.564157) (xy 288.027007 -52.564157) (xy 288.027007 -52.509643)
			(xy 288.034765 -52.455685) (xy 288.050124 -52.403379) (xy 288.07277 -52.353792) (xy 288.102242 -52.307933)
			(xy 288.137942 -52.266735) (xy 288.179141 -52.231036) (xy 288.225001 -52.201565) (xy 288.274589 -52.17892)
			(xy 288.326894 -52.163563) (xy 288.380853 -52.155806) (xy 288.40811 -52.155344) (xy 288.435481 -52.155793)
			(xy 288.489661 -52.163614) (xy 288.542165 -52.179106) (xy 288.591912 -52.201952) (xy 288.637877 -52.231681)
			(xy 288.658808 -52.249324) (xy 288.659062 -52.249578) (xy 288.666149 -52.255164) (xy 288.683066 -52.261409)
			(xy 288.692082 -52.26177) (xy 288.759138 -52.26177) (xy 288.768158 -52.261438) (xy 288.785075 -52.255174)
			(xy 288.792158 -52.249578) (xy 288.792666 -52.24907) (xy 288.81359 -52.231475) (xy 288.859528 -52.201838)
			(xy 288.909226 -52.179063) (xy 288.961667 -52.163615) (xy 289.015776 -52.155813) (xy 289.04311 -52.155344)
			(xy 289.070357 -52.155927) (xy 289.124297 -52.163684) (xy 289.176584 -52.179038) (xy 289.226154 -52.201676)
			(xy 289.271997 -52.231139) (xy 289.313181 -52.266826) (xy 289.348867 -52.308011) (xy 289.378328 -52.353855)
			(xy 289.400966 -52.403425) (xy 289.416319 -52.455713) (xy 289.424074 -52.509653) (xy 289.424074 -52.555948)
			(xy 290.783802 -52.555948) (xy 290.783802 -52.501452) (xy 290.791557 -52.44751) (xy 290.80691 -52.395221)
			(xy 290.829548 -52.345649) (xy 290.85901 -52.299802) (xy 290.894696 -52.258616) (xy 290.93588 -52.222926)
			(xy 290.981724 -52.193461) (xy 291.031295 -52.17082) (xy 291.083583 -52.155463) (xy 291.137524 -52.147704)
			(xy 291.164772 -52.147216) (xy 291.192142 -52.147695) (xy 291.246321 -52.155509) (xy 291.298824 -52.170995)
			(xy 291.348571 -52.193834) (xy 291.394538 -52.223556) (xy 291.41547 -52.241196) (xy 291.415724 -52.24145)
			(xy 291.422795 -52.247059) (xy 291.439724 -52.253291) (xy 291.448744 -52.253642) (xy 291.5158 -52.253642)
			(xy 291.524818 -52.253297) (xy 291.541736 -52.247043) (xy 291.54882 -52.24145) (xy 291.549328 -52.240942)
			(xy 291.570275 -52.223376) (xy 291.616206 -52.193733) (xy 291.665898 -52.17095) (xy 291.718334 -52.155496)
			(xy 291.772439 -52.147687) (xy 291.799772 -52.147216) (xy 291.827028 -52.147629) (xy 291.880985 -52.155383)
			(xy 291.93329 -52.170738) (xy 291.982877 -52.19338) (xy 292.028736 -52.222849) (xy 292.069935 -52.258545)
			(xy 292.105634 -52.299741) (xy 292.135106 -52.345599) (xy 292.157752 -52.395184) (xy 292.173111 -52.447487)
			(xy 292.180869 -52.501444) (xy 292.180869 -52.555956) (xy 292.173111 -52.609913) (xy 292.157752 -52.662216)
			(xy 292.135106 -52.711801) (xy 292.105634 -52.757659) (xy 292.069935 -52.798855) (xy 292.028736 -52.834551)
			(xy 291.982877 -52.86402) (xy 291.93329 -52.886662) (xy 291.880985 -52.902017) (xy 291.827028 -52.909771)
			(xy 291.799772 -52.910232) (xy 291.7724 -52.909799) (xy 291.718219 -52.901976) (xy 291.665715 -52.88648)
			(xy 291.615969 -52.86363) (xy 291.570004 -52.833897) (xy 291.549074 -52.816252) (xy 291.54882 -52.815998)
			(xy 291.541732 -52.810413) (xy 291.524816 -52.804166) (xy 291.5158 -52.803806) (xy 291.448744 -52.803806)
			(xy 291.439729 -52.804183) (xy 291.422812 -52.810417) (xy 291.415724 -52.815998) (xy 291.415216 -52.816506)
			(xy 291.394296 -52.834105) (xy 291.348357 -52.863742) (xy 291.298658 -52.886517) (xy 291.246216 -52.901964)
			(xy 291.192107 -52.909765) (xy 291.164772 -52.910232) (xy 291.137524 -52.909696) (xy 291.083583 -52.901937)
			(xy 291.031295 -52.88658) (xy 290.981724 -52.863939) (xy 290.93588 -52.834474) (xy 290.894696 -52.798784)
			(xy 290.85901 -52.757598) (xy 290.829548 -52.711751) (xy 290.80691 -52.662179) (xy 290.791557 -52.60989)
			(xy 290.783802 -52.555948) (xy 289.424074 -52.555948) (xy 289.424074 -52.564147) (xy 289.416319 -52.618087)
			(xy 289.400966 -52.670375) (xy 289.378328 -52.719945) (xy 289.348867 -52.765789) (xy 289.313181 -52.806974)
			(xy 289.271997 -52.842661) (xy 289.226154 -52.872124) (xy 289.176584 -52.894762) (xy 289.124297 -52.910116)
			(xy 289.070357 -52.917873) (xy 289.04311 -52.91836) (xy 289.01574 -52.917898) (xy 288.96156 -52.910081)
			(xy 288.909056 -52.894591) (xy 288.85931 -52.871748) (xy 288.813343 -52.842022) (xy 288.792412 -52.82438)
			(xy 288.792158 -52.824126) (xy 288.785065 -52.818549) (xy 288.768153 -52.812298) (xy 288.759138 -52.811934)
			(xy 288.692082 -52.811934) (xy 288.683063 -52.812275) (xy 288.666146 -52.818533) (xy 288.659062 -52.824126)
			(xy 288.658554 -52.824634) (xy 288.637623 -52.84222) (xy 288.591687 -52.871858) (xy 288.54199 -52.894635)
			(xy 288.489551 -52.910085) (xy 288.435444 -52.91789) (xy 288.40811 -52.91836) (xy 288.380853 -52.917994)
			(xy 288.326894 -52.910237) (xy 288.274589 -52.89488) (xy 288.225001 -52.872235) (xy 288.179141 -52.842764)
			(xy 288.137942 -52.807065) (xy 288.102242 -52.765867) (xy 288.07277 -52.720008) (xy 288.050124 -52.670421)
			(xy 288.034765 -52.618115) (xy 288.027007 -52.564157) (xy 283.718338 -52.564157) (xy 283.718762 -52.587398)
			(xy 283.718253 -52.615284) (xy 283.710133 -52.67046) (xy 283.694065 -52.723867) (xy 283.670393 -52.774364)
			(xy 283.63962 -52.820877) (xy 283.602403 -52.862414) (xy 283.559535 -52.898089) (xy 283.511929 -52.927143)
			(xy 283.4606 -52.948955) (xy 283.406643 -52.963061) (xy 283.351206 -52.969161) (xy 283.295472 -52.967124)
			(xy 283.240629 -52.956994) (xy 283.187845 -52.938987) (xy 283.138245 -52.913486) (xy 283.092887 -52.881035)
			(xy 283.052738 -52.842326) (xy 283.018652 -52.798183) (xy 282.991356 -52.749548) (xy 282.971433 -52.697457)
			(xy 282.959307 -52.64302) (xy 282.955236 -52.587398) (xy 279.796847 -52.587398) (xy 279.794977 -52.600102)
			(xy 279.778909 -52.653509) (xy 279.755237 -52.704006) (xy 279.724464 -52.750519) (xy 279.687247 -52.792056)
			(xy 279.644379 -52.827731) (xy 279.596773 -52.856785) (xy 279.545444 -52.878597) (xy 279.491487 -52.892703)
			(xy 279.43605 -52.898803) (xy 279.380316 -52.896766) (xy 279.325473 -52.886636) (xy 279.272689 -52.868629)
			(xy 279.223089 -52.843128) (xy 279.177731 -52.810677) (xy 279.137582 -52.771968) (xy 279.103496 -52.727825)
			(xy 279.0762 -52.67919) (xy 279.056277 -52.627099) (xy 279.044151 -52.572662) (xy 279.04008 -52.51704)
			(xy 274.853413 -52.51704) (xy 274.89139 -52.528191) (xy 274.940967 -52.550833) (xy 274.986817 -52.580299)
			(xy 275.028008 -52.61599) (xy 275.063699 -52.657181) (xy 275.093165 -52.703031) (xy 275.115807 -52.752608)
			(xy 275.131162 -52.804903) (xy 275.138918 -52.858851) (xy 275.139404 -52.886102) (xy 275.138903 -52.913435)
			(xy 275.131102 -52.96754) (xy 275.115659 -53.019979) (xy 275.092891 -53.069677) (xy 275.063264 -53.115617)
			(xy 275.045678 -53.136546) (xy 275.045424 -53.1368) (xy 275.04517 -53.137054) (xy 275.039593 -53.144147)
			(xy 275.033342 -53.161059) (xy 275.032978 -53.170074) (xy 275.032978 -53.23713) (xy 275.033325 -53.246148)
			(xy 275.03958 -53.263064) (xy 275.04517 -53.27015) (xy 275.045424 -53.270404) (xy 275.045678 -53.270658)
			(xy 275.063278 -53.291579) (xy 275.092928 -53.337514) (xy 275.115713 -53.387211) (xy 275.131168 -53.439654)
			(xy 275.138976 -53.493765) (xy 275.138976 -53.548438) (xy 275.131168 -53.602549) (xy 275.115712 -53.654991)
			(xy 275.092926 -53.704689) (xy 275.063277 -53.750623) (xy 275.046533 -53.77053) (xy 275.410676 -53.77053)
			(xy 275.411187 -53.741612) (xy 275.419913 -53.68444) (xy 275.437171 -53.629239) (xy 275.462564 -53.577277)
			(xy 275.49551 -53.529744) (xy 275.535255 -53.487729) (xy 275.557742 -53.46954) (xy 275.565111 -53.46324)
			(xy 275.574916 -53.446538) (xy 275.576792 -53.437028) (xy 275.5773 -53.429408) (xy 275.5773 -53.349652)
			(xy 275.576792 -53.342032) (xy 275.574937 -53.332514) (xy 275.565131 -53.315801) (xy 275.557742 -53.30952)
			(xy 275.535277 -53.291307) (xy 275.495539 -53.249293) (xy 275.462596 -53.201763) (xy 275.437204 -53.149806)
			(xy 275.419945 -53.094612) (xy 275.411212 -53.037445) (xy 275.410676 -53.00853) (xy 275.411183 -52.981279)
			(xy 275.418936 -52.92733) (xy 275.434287 -52.875034) (xy 275.456925 -52.825455) (xy 275.486388 -52.779603)
			(xy 275.522077 -52.73841) (xy 275.563266 -52.702716) (xy 275.609115 -52.673247) (xy 275.658691 -52.650603)
			(xy 275.710985 -52.635245) (xy 275.764933 -52.627486) (xy 275.792184 -52.627022) (xy 275.792438 -52.627022)
			(xy 275.818734 -52.627448) (xy 275.870824 -52.634699) (xy 275.921427 -52.649031) (xy 275.969583 -52.670173)
			(xy 276.014382 -52.697724) (xy 276.054975 -52.731163) (xy 276.073108 -52.750212) (xy 276.080676 -52.757657)
			(xy 276.100097 -52.76618) (xy 276.1107 -52.766722) (xy 276.184868 -52.766722) (xy 276.195502 -52.766335)
			(xy 276.214966 -52.757769) (xy 276.22246 -52.750212) (xy 276.240601 -52.731169) (xy 276.28118 -52.697711)
			(xy 276.325974 -52.670149) (xy 276.374131 -52.649008) (xy 276.424738 -52.634688) (xy 276.476833 -52.627461)
			(xy 276.50313 -52.627022) (xy 276.503384 -52.627022) (xy 276.530638 -52.62747) (xy 276.584591 -52.635226)
			(xy 276.636891 -52.650581) (xy 276.686473 -52.673224) (xy 276.732328 -52.702693) (xy 276.773521 -52.738389)
			(xy 276.809215 -52.779584) (xy 276.838683 -52.825439) (xy 276.861324 -52.875022) (xy 276.876677 -52.927323)
			(xy 276.884431 -52.981276) (xy 276.884892 -53.00853) (xy 276.884407 -53.036196) (xy 276.882176 -53.051456)
			(xy 285.14116 -53.051456) (xy 285.145231 -52.995834) (xy 285.157357 -52.941397) (xy 285.17728 -52.889306)
			(xy 285.204576 -52.840671) (xy 285.238662 -52.796528) (xy 285.278811 -52.757819) (xy 285.324169 -52.725368)
			(xy 285.373769 -52.699867) (xy 285.426553 -52.68186) (xy 285.481396 -52.67173) (xy 285.53713 -52.669693)
			(xy 285.592567 -52.675793) (xy 285.646524 -52.689899) (xy 285.697853 -52.711711) (xy 285.745459 -52.740765)
			(xy 285.788327 -52.77644) (xy 285.825544 -52.817977) (xy 285.856317 -52.86449) (xy 285.879989 -52.914987)
			(xy 285.896057 -52.968394) (xy 285.904177 -53.02357) (xy 285.904686 -53.051456) (xy 285.904177 -53.079342)
			(xy 285.896057 -53.134518) (xy 285.879989 -53.187925) (xy 285.856317 -53.238422) (xy 285.825544 -53.284935)
			(xy 285.788327 -53.326472) (xy 285.745459 -53.362147) (xy 285.697853 -53.391201) (xy 285.646524 -53.413013)
			(xy 285.592567 -53.427119) (xy 285.53713 -53.433219) (xy 285.481396 -53.431182) (xy 285.426553 -53.421052)
			(xy 285.373769 -53.403045) (xy 285.324169 -53.377544) (xy 285.278811 -53.345093) (xy 285.238662 -53.306384)
			(xy 285.204576 -53.262241) (xy 285.17728 -53.213606) (xy 285.157357 -53.161515) (xy 285.145231 -53.107078)
			(xy 285.14116 -53.051456) (xy 276.882176 -53.051456) (xy 276.876403 -53.090947) (xy 276.860582 -53.143969)
			(xy 276.837275 -53.194153) (xy 276.806969 -53.240449) (xy 276.7703 -53.281886) (xy 276.728035 -53.317598)
			(xy 276.704806 -53.332634) (xy 276.704552 -53.332888) (xy 276.695019 -53.339544) (xy 276.682717 -53.359246)
			(xy 276.68093 -53.370734) (xy 276.673056 -53.450744) (xy 276.672375 -53.462445) (xy 276.680465 -53.48442)
			(xy 276.68855 -53.492908) (xy 276.688804 -53.492908) (xy 276.707372 -53.511002) (xy 276.739952 -53.551331)
			(xy 276.766766 -53.595703) (xy 276.787321 -53.643299) (xy 276.801238 -53.693241) (xy 276.808258 -53.744608)
			(xy 276.808692 -53.77053) (xy 276.80825 -53.797783) (xy 276.800489 -53.851733) (xy 276.785129 -53.904029)
			(xy 276.762483 -53.953608) (xy 276.733013 -53.999459) (xy 276.697317 -54.040649) (xy 276.656122 -54.07634)
			(xy 276.610267 -54.105806) (xy 276.560686 -54.128445) (xy 276.508388 -54.143799) (xy 276.454437 -54.151553)
			(xy 276.427184 -54.152038) (xy 276.399813 -54.151596) (xy 276.345632 -54.143775) (xy 276.293128 -54.128281)
			(xy 276.243381 -54.105433) (xy 276.197416 -54.075703) (xy 276.176486 -54.058058) (xy 276.176232 -54.057804)
			(xy 276.16914 -54.052225) (xy 276.152227 -54.045974) (xy 276.143212 -54.045612) (xy 276.076156 -54.045612)
			(xy 276.067142 -54.045993) (xy 276.050224 -54.052224) (xy 276.043136 -54.057804) (xy 276.042628 -54.058312)
			(xy 276.021704 -54.075907) (xy 275.975766 -54.105544) (xy 275.926068 -54.12832) (xy 275.873627 -54.143767)
			(xy 275.819518 -54.15157) (xy 275.792184 -54.152038) (xy 275.764934 -54.151537) (xy 275.710988 -54.143779)
			(xy 275.658695 -54.128424) (xy 275.60912 -54.105783) (xy 275.563271 -54.076318) (xy 275.522082 -54.040628)
			(xy 275.486391 -53.99944) (xy 275.456924 -53.953592) (xy 275.434281 -53.904018) (xy 275.418924 -53.851726)
			(xy 275.411164 -53.79778) (xy 275.410676 -53.77053) (xy 275.046533 -53.77053) (xy 275.045678 -53.771546)
			(xy 275.045424 -53.7718) (xy 275.04517 -53.772054) (xy 275.039593 -53.779147) (xy 275.033342 -53.796059)
			(xy 275.032978 -53.805074) (xy 275.032978 -53.87213) (xy 275.033325 -53.881148) (xy 275.03958 -53.898064)
			(xy 275.04517 -53.90515) (xy 275.045424 -53.905404) (xy 275.045678 -53.905658) (xy 275.063278 -53.926579)
			(xy 275.092928 -53.972514) (xy 275.115713 -54.022211) (xy 275.131168 -54.074654) (xy 275.138976 -54.128765)
			(xy 275.138976 -54.183438) (xy 275.131168 -54.237549) (xy 275.115712 -54.289991) (xy 275.101868 -54.320186)
			(xy 277.330408 -54.320186) (xy 277.330899 -54.292853) (xy 277.338702 -54.238747) (xy 277.354147 -54.186308)
			(xy 277.376917 -54.13661) (xy 277.406546 -54.09067) (xy 277.424134 -54.069742) (xy 277.424388 -54.069488)
			(xy 277.424642 -54.069234) (xy 277.430226 -54.062146) (xy 277.436473 -54.04523) (xy 277.436834 -54.036214)
			(xy 277.436834 -53.969158) (xy 277.436442 -53.960145) (xy 277.430218 -53.943228) (xy 277.424642 -53.936138)
			(xy 277.424388 -53.935884) (xy 277.424134 -53.93563) (xy 277.406547 -53.914699) (xy 277.376907 -53.868764)
			(xy 277.354129 -53.819068) (xy 277.33868 -53.766628) (xy 277.330876 -53.71252) (xy 277.330408 -53.685186)
			(xy 277.330894 -53.657935) (xy 277.33865 -53.603987) (xy 277.354005 -53.551692) (xy 277.376647 -53.502115)
			(xy 277.406113 -53.456265) (xy 277.441804 -53.415074) (xy 277.482995 -53.379383) (xy 277.528845 -53.349917)
			(xy 277.578422 -53.327275) (xy 277.630717 -53.31192) (xy 277.684665 -53.304164) (xy 277.739167 -53.304164)
			(xy 277.793115 -53.31192) (xy 277.84541 -53.327275) (xy 277.894987 -53.349917) (xy 277.940837 -53.379383)
			(xy 277.982028 -53.415074) (xy 278.017719 -53.456265) (xy 278.043612 -53.496555) (xy 290.333341 -53.496555)
			(xy 290.333341 -53.442045) (xy 290.341099 -53.388089) (xy 290.356457 -53.335787) (xy 290.379103 -53.286203)
			(xy 290.408575 -53.240347) (xy 290.444273 -53.199152) (xy 290.485471 -53.163457) (xy 290.531329 -53.133988)
			(xy 290.580915 -53.111347) (xy 290.633219 -53.095993) (xy 290.687175 -53.088239) (xy 290.71443 -53.087778)
			(xy 290.741802 -53.088207) (xy 290.795983 -53.096031) (xy 290.848487 -53.111528) (xy 290.898234 -53.134378)
			(xy 290.944198 -53.164112) (xy 290.965128 -53.181758) (xy 290.965382 -53.182012) (xy 290.972469 -53.187599)
			(xy 290.989385 -53.193845) (xy 290.998402 -53.194204) (xy 291.065458 -53.194204) (xy 291.074473 -53.193826)
			(xy 291.09139 -53.187593) (xy 291.098478 -53.182012) (xy 291.098986 -53.181504) (xy 291.119907 -53.163905)
			(xy 291.165845 -53.134268) (xy 291.215544 -53.111493) (xy 291.267986 -53.096046) (xy 291.322095 -53.088245)
			(xy 291.34943 -53.087778) (xy 291.376679 -53.088294) (xy 291.430621 -53.096054) (xy 291.48291 -53.111411)
			(xy 291.532482 -53.134053) (xy 291.578327 -53.163519) (xy 291.619512 -53.199209) (xy 291.655199 -53.240397)
			(xy 291.684661 -53.286244) (xy 291.707299 -53.335818) (xy 291.722652 -53.388108) (xy 291.730408 -53.442051)
			(xy 291.730408 -53.496549) (xy 291.722652 -53.550492) (xy 291.707299 -53.602782) (xy 291.684661 -53.652356)
			(xy 291.655199 -53.698203) (xy 291.619512 -53.739391) (xy 291.578327 -53.775081) (xy 291.532482 -53.804547)
			(xy 291.48291 -53.827189) (xy 291.430621 -53.842546) (xy 291.376679 -53.850306) (xy 291.34943 -53.850794)
			(xy 291.32206 -53.850312) (xy 291.267882 -53.842498) (xy 291.215379 -53.827013) (xy 291.165632 -53.804175)
			(xy 291.119664 -53.774454) (xy 291.098732 -53.756814) (xy 291.098478 -53.75656) (xy 291.091405 -53.750953)
			(xy 291.074478 -53.74472) (xy 291.065458 -53.744368) (xy 290.998402 -53.744368) (xy 290.989386 -53.744733)
			(xy 290.97247 -53.750976) (xy 290.965382 -53.75656) (xy 290.964874 -53.757068) (xy 290.943927 -53.774634)
			(xy 290.897996 -53.804278) (xy 290.848304 -53.82706) (xy 290.795868 -53.842513) (xy 290.741763 -53.850322)
			(xy 290.71443 -53.850794) (xy 290.687175 -53.850361) (xy 290.633219 -53.842607) (xy 290.580915 -53.827253)
			(xy 290.531329 -53.804612) (xy 290.485471 -53.775143) (xy 290.444273 -53.739448) (xy 290.408575 -53.698253)
			(xy 290.379103 -53.652397) (xy 290.356457 -53.602813) (xy 290.341099 -53.550511) (xy 290.333341 -53.496555)
			(xy 278.043612 -53.496555) (xy 278.047185 -53.502115) (xy 278.069827 -53.551692) (xy 278.085182 -53.603987)
			(xy 278.092938 -53.657935) (xy 278.093424 -53.685186) (xy 278.092992 -53.712521) (xy 278.085177 -53.766631)
			(xy 278.069719 -53.819071) (xy 278.046936 -53.868768) (xy 278.017293 -53.914704) (xy 277.999698 -53.93563)
			(xy 277.999444 -53.935884) (xy 277.99919 -53.936138) (xy 277.993622 -53.943237) (xy 277.987365 -53.960144)
			(xy 277.986998 -53.969158) (xy 277.986998 -54.036214) (xy 277.987349 -54.045231) (xy 277.993601 -54.062148)
			(xy 277.99919 -54.069234) (xy 277.999444 -54.069488) (xy 277.999698 -54.069742) (xy 278.017276 -54.090679)
			(xy 278.046917 -54.136613) (xy 278.069696 -54.186308) (xy 278.085147 -54.238746) (xy 278.092954 -54.292853)
			(xy 278.093424 -54.320186) (xy 278.092938 -54.347437) (xy 278.085182 -54.401385) (xy 278.069827 -54.45368)
			(xy 278.047185 -54.503257) (xy 278.017719 -54.549107) (xy 277.982028 -54.590298) (xy 277.940837 -54.625989)
			(xy 277.894987 -54.655455) (xy 277.84541 -54.678097) (xy 277.793115 -54.693452) (xy 277.739167 -54.701208)
			(xy 277.684665 -54.701208) (xy 277.630717 -54.693452) (xy 277.578422 -54.678097) (xy 277.528845 -54.655455)
			(xy 277.482995 -54.625989) (xy 277.441804 -54.590298) (xy 277.406113 -54.549107) (xy 277.376647 -54.503257)
			(xy 277.354005 -54.45368) (xy 277.33865 -54.401385) (xy 277.330894 -54.347437) (xy 277.330408 -54.320186)
			(xy 275.101868 -54.320186) (xy 275.092926 -54.339689) (xy 275.063277 -54.385623) (xy 275.045678 -54.406546)
			(xy 275.045424 -54.4068) (xy 275.04517 -54.407054) (xy 275.039593 -54.414147) (xy 275.033342 -54.431059)
			(xy 275.032978 -54.440074) (xy 275.032978 -54.50713) (xy 275.033325 -54.516148) (xy 275.03958 -54.533064)
			(xy 275.04517 -54.54015) (xy 275.045424 -54.540404) (xy 275.045678 -54.540658) (xy 275.063261 -54.561592)
			(xy 275.092901 -54.607526) (xy 275.11568 -54.657222) (xy 275.13113 -54.709661) (xy 275.138935 -54.763768)
			(xy 275.139051 -54.770528) (xy 278.27097 -54.770528) (xy 278.271412 -54.743193) (xy 278.279225 -54.689084)
			(xy 278.29468 -54.636644) (xy 278.317461 -54.586947) (xy 278.347103 -54.54101) (xy 278.364696 -54.520084)
			(xy 278.36495 -54.51983) (xy 278.365204 -54.519576) (xy 278.370807 -54.512501) (xy 278.377044 -54.495575)
			(xy 278.377396 -54.486556) (xy 278.377396 -54.4195) (xy 278.37704 -54.410483) (xy 278.370792 -54.393566)
			(xy 278.365204 -54.38648) (xy 278.36495 -54.386226) (xy 278.364696 -54.385972) (xy 278.347123 -54.36503)
			(xy 278.317482 -54.319098) (xy 278.294702 -54.269404) (xy 278.27925 -54.216967) (xy 278.271441 -54.162861)
			(xy 278.27097 -54.135528) (xy 278.271456 -54.108277) (xy 278.279212 -54.054329) (xy 278.294567 -54.002034)
			(xy 278.317209 -53.952457) (xy 278.346675 -53.906607) (xy 278.382366 -53.865416) (xy 278.423557 -53.829725)
			(xy 278.469407 -53.800259) (xy 278.518984 -53.777617) (xy 278.571279 -53.762262) (xy 278.625227 -53.754506)
			(xy 278.679729 -53.754506) (xy 278.733677 -53.762262) (xy 278.785972 -53.777617) (xy 278.835549 -53.800259)
			(xy 278.881399 -53.829725) (xy 278.92259 -53.865416) (xy 278.958281 -53.906607) (xy 278.987747 -53.952457)
			(xy 278.992822 -53.96357) (xy 282.972 -53.96357) (xy 282.976071 -53.907948) (xy 282.988197 -53.853511)
			(xy 283.00812 -53.80142) (xy 283.035416 -53.752785) (xy 283.069502 -53.708642) (xy 283.109651 -53.669933)
			(xy 283.155009 -53.637482) (xy 283.204609 -53.611981) (xy 283.257393 -53.593974) (xy 283.312236 -53.583844)
			(xy 283.36797 -53.581807) (xy 283.423407 -53.587907) (xy 283.477364 -53.602013) (xy 283.528693 -53.623825)
			(xy 283.576299 -53.652879) (xy 283.619167 -53.688554) (xy 283.656384 -53.730091) (xy 283.687157 -53.776604)
			(xy 283.710829 -53.827101) (xy 283.726897 -53.880508) (xy 283.735017 -53.935684) (xy 283.735526 -53.96357)
			(xy 283.735017 -53.991456) (xy 283.726897 -54.046632) (xy 283.720632 -54.067456) (xy 285.14116 -54.067456)
			(xy 285.145231 -54.011834) (xy 285.157357 -53.957397) (xy 285.17728 -53.905306) (xy 285.204576 -53.856671)
			(xy 285.238662 -53.812528) (xy 285.278811 -53.773819) (xy 285.324169 -53.741368) (xy 285.373769 -53.715867)
			(xy 285.426553 -53.69786) (xy 285.481396 -53.68773) (xy 285.53713 -53.685693) (xy 285.592567 -53.691793)
			(xy 285.646524 -53.705899) (xy 285.697853 -53.727711) (xy 285.745459 -53.756765) (xy 285.788327 -53.79244)
			(xy 285.825544 -53.833977) (xy 285.856317 -53.88049) (xy 285.879989 -53.930987) (xy 285.896057 -53.984394)
			(xy 285.904177 -54.03957) (xy 285.904686 -54.067456) (xy 285.904177 -54.095342) (xy 285.896057 -54.150518)
			(xy 285.879989 -54.203925) (xy 285.863591 -54.238906) (xy 292.5859 -54.238906) (xy 292.589971 -54.183284)
			(xy 292.602097 -54.128847) (xy 292.62202 -54.076756) (xy 292.649316 -54.028121) (xy 292.683402 -53.983978)
			(xy 292.723551 -53.945269) (xy 292.768909 -53.912818) (xy 292.818509 -53.887317) (xy 292.871293 -53.86931)
			(xy 292.926136 -53.85918) (xy 292.98187 -53.857143) (xy 293.037307 -53.863243) (xy 293.091264 -53.877349)
			(xy 293.142593 -53.899161) (xy 293.190199 -53.928215) (xy 293.233067 -53.96389) (xy 293.270284 -54.005427)
			(xy 293.301057 -54.05194) (xy 293.324729 -54.102437) (xy 293.340797 -54.155844) (xy 293.348917 -54.21102)
			(xy 293.349426 -54.238906) (xy 293.348917 -54.266792) (xy 293.340797 -54.321968) (xy 293.324729 -54.375375)
			(xy 293.301057 -54.425872) (xy 293.270284 -54.472385) (xy 293.233067 -54.513922) (xy 293.190199 -54.549597)
			(xy 293.142593 -54.578651) (xy 293.091264 -54.600463) (xy 293.037307 -54.614569) (xy 292.98187 -54.620669)
			(xy 292.926136 -54.618632) (xy 292.871293 -54.608502) (xy 292.818509 -54.590495) (xy 292.768909 -54.564994)
			(xy 292.723551 -54.532543) (xy 292.683402 -54.493834) (xy 292.649316 -54.449691) (xy 292.62202 -54.401056)
			(xy 292.602097 -54.348965) (xy 292.589971 -54.294528) (xy 292.5859 -54.238906) (xy 285.863591 -54.238906)
			(xy 285.856317 -54.254422) (xy 285.825544 -54.300935) (xy 285.788327 -54.342472) (xy 285.745459 -54.378147)
			(xy 285.697853 -54.407201) (xy 285.646524 -54.429013) (xy 285.592567 -54.443119) (xy 285.53713 -54.449219)
			(xy 285.481396 -54.447182) (xy 285.426553 -54.437052) (xy 285.373769 -54.419045) (xy 285.324169 -54.393544)
			(xy 285.278811 -54.361093) (xy 285.238662 -54.322384) (xy 285.204576 -54.278241) (xy 285.17728 -54.229606)
			(xy 285.157357 -54.177515) (xy 285.145231 -54.123078) (xy 285.14116 -54.067456) (xy 283.720632 -54.067456)
			(xy 283.710829 -54.100039) (xy 283.687157 -54.150536) (xy 283.656384 -54.197049) (xy 283.619167 -54.238586)
			(xy 283.576299 -54.274261) (xy 283.528693 -54.303315) (xy 283.477364 -54.325127) (xy 283.423407 -54.339233)
			(xy 283.36797 -54.345333) (xy 283.312236 -54.343296) (xy 283.257393 -54.333166) (xy 283.204609 -54.315159)
			(xy 283.155009 -54.289658) (xy 283.109651 -54.257207) (xy 283.069502 -54.218498) (xy 283.035416 -54.174355)
			(xy 283.00812 -54.12572) (xy 282.988197 -54.073629) (xy 282.976071 -54.019192) (xy 282.972 -53.96357)
			(xy 278.992822 -53.96357) (xy 279.010389 -54.002034) (xy 279.025744 -54.054329) (xy 279.0335 -54.108277)
			(xy 279.033986 -54.135528) (xy 279.033505 -54.162861) (xy 279.025699 -54.216968) (xy 279.010252 -54.269407)
			(xy 278.98748 -54.319105) (xy 278.957849 -54.365044) (xy 278.94026 -54.385972) (xy 278.940006 -54.386226)
			(xy 278.939752 -54.38648) (xy 278.934162 -54.393564) (xy 278.927919 -54.410483) (xy 278.92756 -54.4195)
			(xy 278.92756 -54.486556) (xy 278.927925 -54.495572) (xy 278.934166 -54.51249) (xy 278.939752 -54.519576)
			(xy 278.940006 -54.51983) (xy 278.94026 -54.520084) (xy 278.957852 -54.54101) (xy 278.987492 -54.586946)
			(xy 279.010269 -54.636644) (xy 279.025717 -54.689085) (xy 279.033519 -54.743194) (xy 279.033986 -54.770528)
			(xy 279.0335 -54.797779) (xy 279.025744 -54.851727) (xy 279.010389 -54.904022) (xy 278.987747 -54.953599)
			(xy 278.958281 -54.999449) (xy 278.92259 -55.04064) (xy 278.881399 -55.076331) (xy 278.870312 -55.083456)
			(xy 285.14116 -55.083456) (xy 285.145231 -55.027834) (xy 285.157357 -54.973397) (xy 285.17728 -54.921306)
			(xy 285.204576 -54.872671) (xy 285.238662 -54.828528) (xy 285.278811 -54.789819) (xy 285.324169 -54.757368)
			(xy 285.373769 -54.731867) (xy 285.426553 -54.71386) (xy 285.481396 -54.70373) (xy 285.53713 -54.701693)
			(xy 285.592567 -54.707793) (xy 285.646524 -54.721899) (xy 285.697853 -54.743711) (xy 285.745459 -54.772765)
			(xy 285.788327 -54.80844) (xy 285.825544 -54.849977) (xy 285.856317 -54.89649) (xy 285.879989 -54.946987)
			(xy 285.892646 -54.989055) (xy 288.100945 -54.989055) (xy 288.100945 -54.934545) (xy 288.108703 -54.880591)
			(xy 288.12406 -54.82829) (xy 288.146705 -54.778707) (xy 288.176176 -54.732851) (xy 288.211874 -54.691657)
			(xy 288.25307 -54.655962) (xy 288.298928 -54.626494) (xy 288.348512 -54.603852) (xy 288.400814 -54.588498)
			(xy 288.454769 -54.580743) (xy 288.482024 -54.580282) (xy 288.510116 -54.580758) (xy 288.565694 -54.588988)
			(xy 288.619464 -54.605283) (xy 288.670261 -54.629289) (xy 288.716988 -54.660486) (xy 288.758632 -54.698201)
			(xy 288.794294 -54.741616) (xy 288.809176 -54.765448) (xy 288.814764 -54.774592) (xy 288.831782 -54.786784)
			(xy 288.924746 -54.80685) (xy 288.94532 -54.802786) (xy 288.953956 -54.79669) (xy 288.97803 -54.780705)
			(xy 289.029958 -54.755359) (xy 289.085113 -54.73813) (xy 289.142234 -54.729409) (xy 289.171126 -54.728872)
			(xy 289.198377 -54.729354) (xy 289.212686 -54.731412) (xy 297.720512 -54.731412) (xy 297.720959 -54.704077)
			(xy 297.728772 -54.649969) (xy 297.744227 -54.59753) (xy 297.767007 -54.547833) (xy 297.796646 -54.501895)
			(xy 297.814238 -54.480968) (xy 297.814492 -54.480714) (xy 297.814746 -54.48046) (xy 297.820319 -54.473364)
			(xy 297.826573 -54.456454) (xy 297.826938 -54.44744) (xy 297.826938 -54.380384) (xy 297.826581 -54.371367)
			(xy 297.820332 -54.354451) (xy 297.814746 -54.347364) (xy 297.814492 -54.34711) (xy 297.814238 -54.346856)
			(xy 297.796651 -54.325924) (xy 297.767 -54.279992) (xy 297.744212 -54.230296) (xy 297.728755 -54.177855)
			(xy 297.720946 -54.123745) (xy 297.720945 -54.069073) (xy 297.728751 -54.014962) (xy 297.744206 -53.962521)
			(xy 297.766991 -53.912824) (xy 297.79664 -53.866891) (xy 297.814238 -53.845968) (xy 297.814492 -53.845714)
			(xy 297.814746 -53.84546) (xy 297.820319 -53.838364) (xy 297.826573 -53.821454) (xy 297.826938 -53.81244)
			(xy 297.826938 -53.745384) (xy 297.826581 -53.736367) (xy 297.820332 -53.719451) (xy 297.814746 -53.712364)
			(xy 297.814492 -53.71211) (xy 297.814238 -53.711856) (xy 297.796651 -53.690924) (xy 297.767 -53.644992)
			(xy 297.744212 -53.595296) (xy 297.728755 -53.542855) (xy 297.720946 -53.488745) (xy 297.720945 -53.434073)
			(xy 297.728751 -53.379962) (xy 297.744206 -53.327521) (xy 297.766991 -53.277824) (xy 297.79664 -53.231891)
			(xy 297.814238 -53.210968) (xy 297.814492 -53.210714) (xy 297.814746 -53.21046) (xy 297.820319 -53.203364)
			(xy 297.826573 -53.186454) (xy 297.826938 -53.17744) (xy 297.826938 -53.110384) (xy 297.826581 -53.101367)
			(xy 297.820332 -53.084451) (xy 297.814746 -53.077364) (xy 297.814492 -53.07711) (xy 297.814238 -53.076856)
			(xy 297.796664 -53.055915) (xy 297.767022 -53.009983) (xy 297.744241 -52.960289) (xy 297.728789 -52.907852)
			(xy 297.720982 -52.853745) (xy 297.720512 -52.826412) (xy 297.720998 -52.799161) (xy 297.728754 -52.745213)
			(xy 297.744109 -52.692918) (xy 297.766751 -52.643341) (xy 297.796217 -52.597491) (xy 297.831908 -52.5563)
			(xy 297.873099 -52.520609) (xy 297.918949 -52.491143) (xy 297.968526 -52.468501) (xy 298.020821 -52.453146)
			(xy 298.074769 -52.44539) (xy 298.129271 -52.44539) (xy 298.183219 -52.453146) (xy 298.235514 -52.468501)
			(xy 298.285091 -52.491143) (xy 298.330941 -52.520609) (xy 298.372132 -52.5563) (xy 298.407823 -52.597491)
			(xy 298.437289 -52.643341) (xy 298.459931 -52.692918) (xy 298.475286 -52.745213) (xy 298.483042 -52.799161)
			(xy 298.483528 -52.826412) (xy 298.483051 -52.853746) (xy 298.475247 -52.907853) (xy 298.4598 -52.960293)
			(xy 298.437026 -53.009991) (xy 298.407392 -53.055929) (xy 298.389802 -53.076856) (xy 298.389548 -53.07711)
			(xy 298.389294 -53.077364) (xy 298.383716 -53.084456) (xy 298.377464 -53.101369) (xy 298.377102 -53.110384)
			(xy 298.377102 -53.17744) (xy 298.37744 -53.186459) (xy 298.383701 -53.203376) (xy 298.389294 -53.21046)
			(xy 298.389548 -53.210714) (xy 298.389802 -53.210968) (xy 298.407415 -53.23188) (xy 298.43707 -53.277814)
			(xy 298.45986 -53.327513) (xy 298.475317 -53.379957) (xy 298.483125 -53.434072) (xy 298.483124 -53.488746)
			(xy 298.475313 -53.542861) (xy 298.459853 -53.595304) (xy 298.437061 -53.645002) (xy 298.407404 -53.690934)
			(xy 298.389802 -53.711856) (xy 298.389548 -53.71211) (xy 298.389294 -53.712364) (xy 298.383716 -53.719456)
			(xy 298.377464 -53.736369) (xy 298.377102 -53.745384) (xy 298.377102 -53.81244) (xy 298.37744 -53.821459)
			(xy 298.383701 -53.838376) (xy 298.389294 -53.84546) (xy 298.389548 -53.845714) (xy 298.389802 -53.845968)
			(xy 298.407415 -53.86688) (xy 298.43707 -53.912814) (xy 298.45986 -53.962513) (xy 298.475317 -54.014957)
			(xy 298.483125 -54.069072) (xy 298.483124 -54.123746) (xy 298.475313 -54.177861) (xy 298.459853 -54.230304)
			(xy 298.437061 -54.280002) (xy 298.407404 -54.325934) (xy 298.389802 -54.346856) (xy 298.389548 -54.34711)
			(xy 298.389294 -54.347364) (xy 298.383716 -54.354456) (xy 298.377464 -54.371369) (xy 298.377102 -54.380384)
			(xy 298.377102 -54.44744) (xy 298.37744 -54.456459) (xy 298.383701 -54.473376) (xy 298.389294 -54.48046)
			(xy 298.389548 -54.480714) (xy 298.389802 -54.480968) (xy 298.407393 -54.501895) (xy 298.437032 -54.547831)
			(xy 298.459808 -54.597529) (xy 298.475256 -54.649969) (xy 298.483059 -54.704078) (xy 298.483528 -54.731412)
			(xy 298.483042 -54.758663) (xy 298.478378 -54.791102) (xy 300.376336 -54.791102) (xy 300.376829 -54.763769)
			(xy 300.384631 -54.709663) (xy 300.400075 -54.657224) (xy 300.422845 -54.607526) (xy 300.452474 -54.561586)
			(xy 300.470062 -54.540658) (xy 300.470316 -54.540404) (xy 300.47057 -54.54015) (xy 300.47615 -54.533059)
			(xy 300.482399 -54.516145) (xy 300.482762 -54.50713) (xy 300.482762 -54.440074) (xy 300.482426 -54.431055)
			(xy 300.476165 -54.414138) (xy 300.47057 -54.407054) (xy 300.470316 -54.4068) (xy 300.470062 -54.406546)
			(xy 300.452464 -54.385622) (xy 300.422811 -54.339689) (xy 300.400023 -54.289992) (xy 300.384566 -54.23755)
			(xy 300.376757 -54.183438) (xy 300.376757 -54.128765) (xy 300.384565 -54.074653) (xy 300.400022 -54.022211)
			(xy 300.42281 -53.972513) (xy 300.452462 -53.92658) (xy 300.470062 -53.905658) (xy 300.470316 -53.905404)
			(xy 300.47057 -53.90515) (xy 300.47615 -53.898059) (xy 300.482399 -53.881145) (xy 300.482762 -53.87213)
			(xy 300.482762 -53.805074) (xy 300.482426 -53.796055) (xy 300.476165 -53.779138) (xy 300.47057 -53.772054)
			(xy 300.470316 -53.7718) (xy 300.470062 -53.771546) (xy 300.452464 -53.750622) (xy 300.422811 -53.704689)
			(xy 300.400023 -53.654992) (xy 300.384566 -53.60255) (xy 300.376757 -53.548438) (xy 300.376757 -53.493765)
			(xy 300.384565 -53.439653) (xy 300.400022 -53.387211) (xy 300.42281 -53.337513) (xy 300.452462 -53.29158)
			(xy 300.470062 -53.270658) (xy 300.470316 -53.270404) (xy 300.47057 -53.27015) (xy 300.47615 -53.263059)
			(xy 300.482399 -53.246145) (xy 300.482762 -53.23713) (xy 300.482762 -53.170074) (xy 300.482426 -53.161055)
			(xy 300.476165 -53.144138) (xy 300.47057 -53.137054) (xy 300.470316 -53.1368) (xy 300.470062 -53.136546)
			(xy 300.452472 -53.115619) (xy 300.422834 -53.069681) (xy 300.400058 -53.019984) (xy 300.38461 -52.967544)
			(xy 300.376805 -52.913436) (xy 300.376336 -52.886102) (xy 300.376822 -52.858851) (xy 300.384578 -52.804903)
			(xy 300.399933 -52.752608) (xy 300.422575 -52.703031) (xy 300.452041 -52.657181) (xy 300.487732 -52.61599)
			(xy 300.528923 -52.580299) (xy 300.574773 -52.550833) (xy 300.62435 -52.528191) (xy 300.676645 -52.512836)
			(xy 300.730593 -52.50508) (xy 300.785095 -52.50508) (xy 300.839043 -52.512836) (xy 300.853361 -52.51704)
			(xy 305.040028 -52.51704) (xy 305.044099 -52.461418) (xy 305.056225 -52.406981) (xy 305.076148 -52.35489)
			(xy 305.103444 -52.306255) (xy 305.13753 -52.262112) (xy 305.177679 -52.223403) (xy 305.223037 -52.190952)
			(xy 305.272637 -52.165451) (xy 305.325421 -52.147444) (xy 305.380264 -52.137314) (xy 305.435998 -52.135277)
			(xy 305.491435 -52.141377) (xy 305.545392 -52.155483) (xy 305.596721 -52.177295) (xy 305.644327 -52.206349)
			(xy 305.687195 -52.242024) (xy 305.724412 -52.283561) (xy 305.755185 -52.330074) (xy 305.778857 -52.380571)
			(xy 305.794925 -52.433978) (xy 305.803045 -52.489154) (xy 305.803554 -52.51704) (xy 305.803045 -52.544926)
			(xy 305.796795 -52.587398) (xy 308.955184 -52.587398) (xy 308.959255 -52.531776) (xy 308.971381 -52.477339)
			(xy 308.991304 -52.425248) (xy 309.0186 -52.376613) (xy 309.052686 -52.33247) (xy 309.092835 -52.293761)
			(xy 309.138193 -52.26131) (xy 309.187793 -52.235809) (xy 309.240577 -52.217802) (xy 309.29542 -52.207672)
			(xy 309.351154 -52.205635) (xy 309.406591 -52.211735) (xy 309.460548 -52.225841) (xy 309.511877 -52.247653)
			(xy 309.559483 -52.276707) (xy 309.602351 -52.312382) (xy 309.639568 -52.353919) (xy 309.670341 -52.400432)
			(xy 309.694013 -52.450929) (xy 309.710081 -52.504336) (xy 309.718201 -52.559512) (xy 309.718286 -52.564153)
			(xy 314.02703 -52.564153) (xy 314.02703 -52.509647) (xy 314.034786 -52.455696) (xy 314.050141 -52.403398)
			(xy 314.072782 -52.353818) (xy 314.102248 -52.307964) (xy 314.13794 -52.266769) (xy 314.17913 -52.231073)
			(xy 314.224981 -52.201602) (xy 314.274559 -52.178956) (xy 314.326855 -52.163595) (xy 314.380805 -52.155833)
			(xy 314.408058 -52.155344) (xy 314.435428 -52.155824) (xy 314.489607 -52.163637) (xy 314.54211 -52.179122)
			(xy 314.591857 -52.201961) (xy 314.637824 -52.231683) (xy 314.658756 -52.249324) (xy 314.65901 -52.249578)
			(xy 314.666083 -52.255184) (xy 314.68301 -52.261417) (xy 314.69203 -52.26177) (xy 314.759086 -52.26177)
			(xy 314.768103 -52.261413) (xy 314.78502 -52.255166) (xy 314.792106 -52.249578) (xy 314.792614 -52.24907)
			(xy 314.81352 -52.231453) (xy 314.859463 -52.201819) (xy 314.909166 -52.179048) (xy 314.96161 -52.163606)
			(xy 315.015722 -52.155809) (xy 315.043058 -52.155344) (xy 315.070309 -52.1559) (xy 315.124258 -52.163651)
			(xy 315.176554 -52.179002) (xy 315.226134 -52.201639) (xy 315.271986 -52.231102) (xy 315.313179 -52.266792)
			(xy 315.348872 -52.30798) (xy 315.378341 -52.35383) (xy 315.400983 -52.403406) (xy 315.41634 -52.455701)
			(xy 315.424097 -52.509649) (xy 315.424097 -52.555952) (xy 316.783679 -52.555952) (xy 316.783679 -52.501448)
			(xy 316.791436 -52.447499) (xy 316.806792 -52.395203) (xy 316.829435 -52.345624) (xy 316.858903 -52.299773)
			(xy 316.894597 -52.258582) (xy 316.935789 -52.222891) (xy 316.981642 -52.193425) (xy 317.031221 -52.170785)
			(xy 317.083518 -52.155432) (xy 317.137468 -52.147678) (xy 317.16472 -52.147216) (xy 317.192091 -52.147666)
			(xy 317.246271 -52.155487) (xy 317.298774 -52.17098) (xy 317.348521 -52.193825) (xy 317.394487 -52.223553)
			(xy 317.415418 -52.241196) (xy 317.415672 -52.24145) (xy 317.422758 -52.247037) (xy 317.439675 -52.253282)
			(xy 317.448692 -52.253642) (xy 317.515748 -52.253642) (xy 317.524764 -52.253273) (xy 317.541682 -52.247035)
			(xy 317.548768 -52.24145) (xy 317.549276 -52.240942) (xy 317.570205 -52.223354) (xy 317.616141 -52.193713)
			(xy 317.665837 -52.170936) (xy 317.718277 -52.155487) (xy 317.772386 -52.147684) (xy 317.79972 -52.147216)
			(xy 317.826972 -52.147655) (xy 317.880921 -52.155415) (xy 317.933217 -52.170772) (xy 317.982794 -52.193416)
			(xy 318.028645 -52.222885) (xy 318.069836 -52.258579) (xy 318.105527 -52.299771) (xy 318.134994 -52.345623)
			(xy 318.157635 -52.395202) (xy 318.17299 -52.447499) (xy 318.180746 -52.501448) (xy 318.180746 -52.555952)
			(xy 318.17299 -52.609901) (xy 318.157635 -52.662198) (xy 318.134994 -52.711777) (xy 318.105527 -52.757629)
			(xy 318.069836 -52.798821) (xy 318.028645 -52.834515) (xy 317.982794 -52.863984) (xy 317.933217 -52.886628)
			(xy 317.880921 -52.901985) (xy 317.826972 -52.909745) (xy 317.79972 -52.910232) (xy 317.772349 -52.909771)
			(xy 317.718169 -52.901954) (xy 317.665666 -52.886465) (xy 317.615919 -52.863622) (xy 317.569953 -52.833895)
			(xy 317.549022 -52.816252) (xy 317.548768 -52.815998) (xy 317.541666 -52.810434) (xy 317.524761 -52.804174)
			(xy 317.515748 -52.803806) (xy 317.448692 -52.803806) (xy 317.439675 -52.804158) (xy 317.422758 -52.810409)
			(xy 317.415672 -52.815998) (xy 317.415164 -52.816506) (xy 317.394226 -52.834083) (xy 317.348292 -52.863723)
			(xy 317.298597 -52.886503) (xy 317.24616 -52.901954) (xy 317.192053 -52.909761) (xy 317.16472 -52.910232)
			(xy 317.137468 -52.909722) (xy 317.083518 -52.901968) (xy 317.031221 -52.886615) (xy 316.981642 -52.863975)
			(xy 316.935789 -52.834509) (xy 316.894597 -52.798818) (xy 316.858903 -52.757627) (xy 316.829435 -52.711776)
			(xy 316.806792 -52.662197) (xy 316.791436 -52.609901) (xy 316.783679 -52.555952) (xy 315.424097 -52.555952)
			(xy 315.424097 -52.564151) (xy 315.41634 -52.618099) (xy 315.400983 -52.670394) (xy 315.378341 -52.71997)
			(xy 315.348872 -52.76582) (xy 315.313179 -52.807008) (xy 315.271986 -52.842698) (xy 315.226134 -52.872161)
			(xy 315.176554 -52.894798) (xy 315.124258 -52.910149) (xy 315.070309 -52.9179) (xy 315.043058 -52.91836)
			(xy 315.015689 -52.91787) (xy 314.96151 -52.910059) (xy 314.909007 -52.894576) (xy 314.85926 -52.87174)
			(xy 314.813292 -52.842019) (xy 314.79236 -52.82438) (xy 314.792106 -52.824126) (xy 314.785028 -52.818527)
			(xy 314.768104 -52.81229) (xy 314.759086 -52.811934) (xy 314.69203 -52.811934) (xy 314.683014 -52.812298)
			(xy 314.666096 -52.81854) (xy 314.65901 -52.824126) (xy 314.658502 -52.824634) (xy 314.637591 -52.842244)
			(xy 314.591649 -52.871879) (xy 314.541948 -52.894651) (xy 314.489504 -52.910095) (xy 314.435393 -52.917894)
			(xy 314.408058 -52.91836) (xy 314.380805 -52.917967) (xy 314.326855 -52.910205) (xy 314.274559 -52.894844)
			(xy 314.224981 -52.872198) (xy 314.17913 -52.842727) (xy 314.13794 -52.807031) (xy 314.102248 -52.765836)
			(xy 314.072782 -52.719982) (xy 314.050141 -52.670402) (xy 314.034786 -52.618104) (xy 314.02703 -52.564153)
			(xy 309.718286 -52.564153) (xy 309.71871 -52.587398) (xy 309.718201 -52.615284) (xy 309.710081 -52.67046)
			(xy 309.694013 -52.723867) (xy 309.670341 -52.774364) (xy 309.639568 -52.820877) (xy 309.602351 -52.862414)
			(xy 309.559483 -52.898089) (xy 309.511877 -52.927143) (xy 309.460548 -52.948955) (xy 309.406591 -52.963061)
			(xy 309.351154 -52.969161) (xy 309.29542 -52.967124) (xy 309.240577 -52.956994) (xy 309.187793 -52.938987)
			(xy 309.138193 -52.913486) (xy 309.092835 -52.881035) (xy 309.052686 -52.842326) (xy 309.0186 -52.798183)
			(xy 308.991304 -52.749548) (xy 308.971381 -52.697457) (xy 308.959255 -52.64302) (xy 308.955184 -52.587398)
			(xy 305.796795 -52.587398) (xy 305.794925 -52.600102) (xy 305.778857 -52.653509) (xy 305.755185 -52.704006)
			(xy 305.724412 -52.750519) (xy 305.687195 -52.792056) (xy 305.644327 -52.827731) (xy 305.596721 -52.856785)
			(xy 305.545392 -52.878597) (xy 305.491435 -52.892703) (xy 305.435998 -52.898803) (xy 305.380264 -52.896766)
			(xy 305.325421 -52.886636) (xy 305.272637 -52.868629) (xy 305.223037 -52.843128) (xy 305.177679 -52.810677)
			(xy 305.13753 -52.771968) (xy 305.103444 -52.727825) (xy 305.076148 -52.67919) (xy 305.056225 -52.627099)
			(xy 305.044099 -52.572662) (xy 305.040028 -52.51704) (xy 300.853361 -52.51704) (xy 300.891338 -52.528191)
			(xy 300.940915 -52.550833) (xy 300.986765 -52.580299) (xy 301.027956 -52.61599) (xy 301.063647 -52.657181)
			(xy 301.093113 -52.703031) (xy 301.115755 -52.752608) (xy 301.13111 -52.804903) (xy 301.138866 -52.858851)
			(xy 301.139352 -52.886102) (xy 301.138864 -52.913435) (xy 301.131061 -52.967542) (xy 301.115617 -53.019981)
			(xy 301.092846 -53.069679) (xy 301.063215 -53.115618) (xy 301.045626 -53.136546) (xy 301.045372 -53.1368)
			(xy 301.045118 -53.137054) (xy 301.039547 -53.144151) (xy 301.033291 -53.16106) (xy 301.032926 -53.170074)
			(xy 301.032926 -53.23713) (xy 301.033263 -53.246149) (xy 301.039524 -53.263066) (xy 301.045118 -53.27015)
			(xy 301.045372 -53.270404) (xy 301.045626 -53.270658) (xy 301.063229 -53.291578) (xy 301.092882 -53.337512)
			(xy 301.115671 -53.387209) (xy 301.131128 -53.439652) (xy 301.138936 -53.493765) (xy 301.138936 -53.548438)
			(xy 301.131127 -53.602551) (xy 301.11567 -53.654994) (xy 301.09288 -53.704691) (xy 301.063227 -53.750624)
			(xy 301.046481 -53.77053) (xy 301.410624 -53.77053) (xy 301.411155 -53.741613) (xy 301.41988 -53.684442)
			(xy 301.437135 -53.629243) (xy 301.462524 -53.577282) (xy 301.495466 -53.529747) (xy 301.535205 -53.48773)
			(xy 301.55769 -53.46954) (xy 301.565067 -53.463248) (xy 301.574867 -53.44654) (xy 301.57674 -53.437028)
			(xy 301.577248 -53.429408) (xy 301.577248 -53.349652) (xy 301.57674 -53.342032) (xy 301.57487 -53.332518)
			(xy 301.565074 -53.315804) (xy 301.55769 -53.30952) (xy 301.535214 -53.29132) (xy 301.495479 -53.249302)
			(xy 301.462539 -53.201769) (xy 301.43715 -53.149809) (xy 301.419892 -53.094613) (xy 301.41116 -53.037445)
			(xy 301.410624 -53.00853) (xy 301.411083 -52.981276) (xy 301.418837 -52.927324) (xy 301.434191 -52.875024)
			(xy 301.456832 -52.825442) (xy 301.4863 -52.779587) (xy 301.521994 -52.738393) (xy 301.563188 -52.702699)
			(xy 301.609043 -52.673231) (xy 301.658626 -52.65059) (xy 301.710926 -52.635237) (xy 301.764878 -52.627483)
			(xy 301.792132 -52.627022) (xy 301.792386 -52.627022) (xy 301.818681 -52.627483) (xy 301.87077 -52.634727)
			(xy 301.921371 -52.649052) (xy 301.969528 -52.670187) (xy 302.014327 -52.697732) (xy 302.054922 -52.731165)
			(xy 302.073056 -52.750212) (xy 302.080606 -52.757679) (xy 302.10004 -52.766189) (xy 302.110648 -52.766722)
			(xy 302.184816 -52.766722) (xy 302.195447 -52.766307) (xy 302.214911 -52.757761) (xy 302.222408 -52.750212)
			(xy 302.240526 -52.731146) (xy 302.28111 -52.69769) (xy 302.325909 -52.670131) (xy 302.374071 -52.648994)
			(xy 302.424681 -52.634679) (xy 302.47678 -52.627458) (xy 302.503078 -52.627022) (xy 302.503332 -52.627022)
			(xy 302.530585 -52.627448) (xy 302.584537 -52.63521) (xy 302.636835 -52.65057) (xy 302.686414 -52.673218)
			(xy 302.732266 -52.70269) (xy 302.773456 -52.738388) (xy 302.809147 -52.779584) (xy 302.838612 -52.825441)
			(xy 302.861251 -52.875024) (xy 302.876603 -52.927324) (xy 302.884356 -52.981277) (xy 302.88484 -53.00853)
			(xy 302.884379 -53.036197) (xy 302.882148 -53.051456) (xy 311.141108 -53.051456) (xy 311.145179 -52.995834)
			(xy 311.157305 -52.941397) (xy 311.177228 -52.889306) (xy 311.204524 -52.840671) (xy 311.23861 -52.796528)
			(xy 311.278759 -52.757819) (xy 311.324117 -52.725368) (xy 311.373717 -52.699867) (xy 311.426501 -52.68186)
			(xy 311.481344 -52.67173) (xy 311.537078 -52.669693) (xy 311.592515 -52.675793) (xy 311.646472 -52.689899)
			(xy 311.697801 -52.711711) (xy 311.745407 -52.740765) (xy 311.788275 -52.77644) (xy 311.825492 -52.817977)
			(xy 311.856265 -52.86449) (xy 311.879937 -52.914987) (xy 311.896005 -52.968394) (xy 311.904125 -53.02357)
			(xy 311.904634 -53.051456) (xy 311.904125 -53.079342) (xy 311.896005 -53.134518) (xy 311.879937 -53.187925)
			(xy 311.856265 -53.238422) (xy 311.825492 -53.284935) (xy 311.788275 -53.326472) (xy 311.745407 -53.362147)
			(xy 311.697801 -53.391201) (xy 311.646472 -53.413013) (xy 311.592515 -53.427119) (xy 311.537078 -53.433219)
			(xy 311.481344 -53.431182) (xy 311.426501 -53.421052) (xy 311.373717 -53.403045) (xy 311.324117 -53.377544)
			(xy 311.278759 -53.345093) (xy 311.23861 -53.306384) (xy 311.204524 -53.262241) (xy 311.177228 -53.213606)
			(xy 311.157305 -53.161515) (xy 311.145179 -53.107078) (xy 311.141108 -53.051456) (xy 302.882148 -53.051456)
			(xy 302.876374 -53.09095) (xy 302.86055 -53.143974) (xy 302.83724 -53.194159) (xy 302.80693 -53.240454)
			(xy 302.770256 -53.28189) (xy 302.727985 -53.317599) (xy 302.704754 -53.332634) (xy 302.7045 -53.332888)
			(xy 302.694976 -53.339555) (xy 302.682668 -53.359248) (xy 302.680878 -53.370734) (xy 302.673004 -53.450744)
			(xy 302.672339 -53.462445) (xy 302.68042 -53.484417) (xy 302.688498 -53.492908) (xy 302.688752 -53.492908)
			(xy 302.70731 -53.511012) (xy 302.739893 -53.551338) (xy 302.76671 -53.595707) (xy 302.787267 -53.643301)
			(xy 302.801185 -53.693242) (xy 302.808206 -53.744608) (xy 302.80864 -53.77053) (xy 302.80815 -53.797781)
			(xy 302.80039 -53.851726) (xy 302.785033 -53.904019) (xy 302.762391 -53.953594) (xy 302.732924 -53.999443)
			(xy 302.697234 -54.040632) (xy 302.656045 -54.076323) (xy 302.610196 -54.10579) (xy 302.560621 -54.128432)
			(xy 302.508328 -54.14379) (xy 302.454383 -54.15155) (xy 302.427132 -54.152038) (xy 302.399762 -54.151568)
			(xy 302.345582 -54.143754) (xy 302.293079 -54.128266) (xy 302.243332 -54.105425) (xy 302.197365 -54.0757)
			(xy 302.176434 -54.058058) (xy 302.17618 -54.057804) (xy 302.169103 -54.052203) (xy 302.152179 -54.045965)
			(xy 302.14316 -54.045612) (xy 302.076104 -54.045612) (xy 302.067087 -54.045968) (xy 302.05017 -54.052216)
			(xy 302.043084 -54.057804) (xy 302.042576 -54.058312) (xy 302.021634 -54.075884) (xy 301.975701 -54.105525)
			(xy 301.926008 -54.128305) (xy 301.873571 -54.143758) (xy 301.819465 -54.151566) (xy 301.792132 -54.152038)
			(xy 301.764881 -54.151515) (xy 301.710934 -54.143763) (xy 301.658639 -54.128413) (xy 301.609061 -54.105776)
			(xy 301.563209 -54.076314) (xy 301.522017 -54.040627) (xy 301.486323 -53.99944) (xy 301.456854 -53.953593)
			(xy 301.434209 -53.904019) (xy 301.41885 -53.851727) (xy 301.411089 -53.797781) (xy 301.410624 -53.77053)
			(xy 301.046481 -53.77053) (xy 301.045626 -53.771546) (xy 301.045372 -53.7718) (xy 301.045118 -53.772054)
			(xy 301.039547 -53.779151) (xy 301.033291 -53.79606) (xy 301.032926 -53.805074) (xy 301.032926 -53.87213)
			(xy 301.033263 -53.881149) (xy 301.039524 -53.898066) (xy 301.045118 -53.90515) (xy 301.045372 -53.905404)
			(xy 301.045626 -53.905658) (xy 301.063229 -53.926578) (xy 301.092882 -53.972512) (xy 301.115671 -54.022209)
			(xy 301.131128 -54.074652) (xy 301.138936 -54.128765) (xy 301.138936 -54.183438) (xy 301.131127 -54.237551)
			(xy 301.11567 -54.289994) (xy 301.101825 -54.320186) (xy 303.330356 -54.320186) (xy 303.330835 -54.292852)
			(xy 303.33864 -54.238745) (xy 303.354086 -54.186306) (xy 303.376859 -54.136608) (xy 303.406492 -54.090669)
			(xy 303.424082 -54.069742) (xy 303.424336 -54.069488) (xy 303.42459 -54.069234) (xy 303.430167 -54.062141)
			(xy 303.43642 -54.045229) (xy 303.436782 -54.036214) (xy 303.436782 -53.969158) (xy 303.436401 -53.960143)
			(xy 303.43017 -53.943226) (xy 303.42459 -53.936138) (xy 303.424336 -53.935884) (xy 303.424082 -53.93563)
			(xy 303.406487 -53.914706) (xy 303.37685 -53.868768) (xy 303.354074 -53.81907) (xy 303.338627 -53.766629)
			(xy 303.330824 -53.71252) (xy 303.330356 -53.685186) (xy 303.330842 -53.657935) (xy 303.338598 -53.603987)
			(xy 303.353953 -53.551692) (xy 303.376595 -53.502115) (xy 303.406061 -53.456265) (xy 303.441752 -53.415074)
			(xy 303.482943 -53.379383) (xy 303.528793 -53.349917) (xy 303.57837 -53.327275) (xy 303.630665 -53.31192)
			(xy 303.684613 -53.304164) (xy 303.739115 -53.304164) (xy 303.793063 -53.31192) (xy 303.845358 -53.327275)
			(xy 303.894935 -53.349917) (xy 303.940785 -53.379383) (xy 303.981976 -53.415074) (xy 304.017667 -53.456265)
			(xy 304.043557 -53.496551) (xy 316.333364 -53.496551) (xy 316.333364 -53.442049) (xy 316.34112 -53.388101)
			(xy 316.356475 -53.335806) (xy 316.379115 -53.286228) (xy 316.40858 -53.240377) (xy 316.444271 -53.199186)
			(xy 316.48546 -53.163493) (xy 316.531309 -53.134025) (xy 316.580885 -53.111382) (xy 316.633179 -53.096025)
			(xy 316.687127 -53.088265) (xy 316.714378 -53.087778) (xy 316.741749 -53.088238) (xy 316.795929 -53.096054)
			(xy 316.848433 -53.111544) (xy 316.89818 -53.134387) (xy 316.944145 -53.164115) (xy 316.965076 -53.181758)
			(xy 316.96533 -53.182012) (xy 316.972431 -53.187577) (xy 316.989337 -53.193836) (xy 316.99835 -53.194204)
			(xy 317.065406 -53.194204) (xy 317.074423 -53.193849) (xy 317.09134 -53.1876) (xy 317.098426 -53.182012)
			(xy 317.098934 -53.181504) (xy 317.119874 -53.16393) (xy 317.165807 -53.134288) (xy 317.215501 -53.111509)
			(xy 317.267939 -53.096056) (xy 317.322045 -53.088249) (xy 317.349378 -53.087778) (xy 317.376631 -53.088268)
			(xy 317.430582 -53.096022) (xy 317.482881 -53.111376) (xy 317.532462 -53.134016) (xy 317.578316 -53.163482)
			(xy 317.61951 -53.199175) (xy 317.655205 -53.240366) (xy 317.684674 -53.286219) (xy 317.707317 -53.335799)
			(xy 317.722673 -53.388096) (xy 317.730431 -53.442047) (xy 317.730431 -53.496553) (xy 317.722673 -53.550504)
			(xy 317.707317 -53.602801) (xy 317.684674 -53.652381) (xy 317.655205 -53.698234) (xy 317.61951 -53.739425)
			(xy 317.578316 -53.775118) (xy 317.532462 -53.804584) (xy 317.482881 -53.827224) (xy 317.430582 -53.842578)
			(xy 317.376631 -53.850332) (xy 317.349378 -53.850794) (xy 317.322007 -53.850342) (xy 317.267827 -53.842521)
			(xy 317.215324 -53.827029) (xy 317.165578 -53.804184) (xy 317.119611 -53.774457) (xy 317.09868 -53.756814)
			(xy 317.098426 -53.75656) (xy 317.09134 -53.750973) (xy 317.074423 -53.744728) (xy 317.065406 -53.744368)
			(xy 316.99835 -53.744368) (xy 316.989336 -53.744756) (xy 316.97242 -53.750983) (xy 316.96533 -53.75656)
			(xy 316.964822 -53.757068) (xy 316.943895 -53.774659) (xy 316.897959 -53.804298) (xy 316.848261 -53.827076)
			(xy 316.795821 -53.842524) (xy 316.741712 -53.850326) (xy 316.714378 -53.850794) (xy 316.687127 -53.850335)
			(xy 316.633179 -53.842575) (xy 316.580885 -53.827218) (xy 316.531309 -53.804575) (xy 316.48546 -53.775107)
			(xy 316.444271 -53.739414) (xy 316.40858 -53.698223) (xy 316.379115 -53.652372) (xy 316.356475 -53.602794)
			(xy 316.34112 -53.550499) (xy 316.333364 -53.496551) (xy 304.043557 -53.496551) (xy 304.047133 -53.502115)
			(xy 304.069775 -53.551692) (xy 304.08513 -53.603987) (xy 304.092886 -53.657935) (xy 304.093372 -53.685186)
			(xy 304.092928 -53.712521) (xy 304.085114 -53.766629) (xy 304.069659 -53.819069) (xy 304.046878 -53.868766)
			(xy 304.017239 -53.914704) (xy 303.999646 -53.93563) (xy 303.999392 -53.935884) (xy 303.999138 -53.936138)
			(xy 303.993564 -53.943233) (xy 303.987311 -53.960144) (xy 303.986946 -53.969158) (xy 303.986946 -54.036214)
			(xy 303.987286 -54.045233) (xy 303.993544 -54.06215) (xy 303.999138 -54.069234) (xy 303.999392 -54.069488)
			(xy 303.999646 -54.069742) (xy 304.017232 -54.090673) (xy 304.04687 -54.136609) (xy 304.069647 -54.186306)
			(xy 304.085096 -54.238745) (xy 304.092902 -54.292852) (xy 304.093372 -54.320186) (xy 304.092886 -54.347437)
			(xy 304.08513 -54.401385) (xy 304.069775 -54.45368) (xy 304.047133 -54.503257) (xy 304.017667 -54.549107)
			(xy 303.981976 -54.590298) (xy 303.940785 -54.625989) (xy 303.894935 -54.655455) (xy 303.845358 -54.678097)
			(xy 303.793063 -54.693452) (xy 303.739115 -54.701208) (xy 303.684613 -54.701208) (xy 303.630665 -54.693452)
			(xy 303.57837 -54.678097) (xy 303.528793 -54.655455) (xy 303.482943 -54.625989) (xy 303.441752 -54.590298)
			(xy 303.406061 -54.549107) (xy 303.376595 -54.503257) (xy 303.353953 -54.45368) (xy 303.338598 -54.401385)
			(xy 303.330842 -54.347437) (xy 303.330356 -54.320186) (xy 301.101825 -54.320186) (xy 301.09288 -54.339691)
			(xy 301.063227 -54.385624) (xy 301.045626 -54.406546) (xy 301.045372 -54.4068) (xy 301.045118 -54.407054)
			(xy 301.039547 -54.414151) (xy 301.033291 -54.43106) (xy 301.032926 -54.440074) (xy 301.032926 -54.50713)
			(xy 301.033263 -54.516149) (xy 301.039524 -54.533066) (xy 301.045118 -54.54015) (xy 301.045372 -54.540404)
			(xy 301.045626 -54.540658) (xy 301.063216 -54.561585) (xy 301.092854 -54.607522) (xy 301.11563 -54.65722)
			(xy 301.131079 -54.70966) (xy 301.138883 -54.763768) (xy 301.138999 -54.770528) (xy 304.270918 -54.770528)
			(xy 304.271373 -54.743194) (xy 304.279184 -54.689086) (xy 304.294637 -54.636647) (xy 304.317416 -54.586949)
			(xy 304.347053 -54.541011) (xy 304.364644 -54.520084) (xy 304.364898 -54.51983) (xy 304.365152 -54.519576)
			(xy 304.370761 -54.512505) (xy 304.376993 -54.495576) (xy 304.377344 -54.486556) (xy 304.377344 -54.4195)
			(xy 304.376999 -54.410482) (xy 304.370744 -54.393564) (xy 304.365152 -54.38648) (xy 304.364898 -54.386226)
			(xy 304.364644 -54.385972) (xy 304.347079 -54.365024) (xy 304.317435 -54.319094) (xy 304.294652 -54.269402)
			(xy 304.279198 -54.216966) (xy 304.271389 -54.162861) (xy 304.270918 -54.135528) (xy 304.271404 -54.108277)
			(xy 304.27916 -54.054329) (xy 304.294515 -54.002034) (xy 304.317157 -53.952457) (xy 304.346623 -53.906607)
			(xy 304.382314 -53.865416) (xy 304.423505 -53.829725) (xy 304.469355 -53.800259) (xy 304.518932 -53.777617)
			(xy 304.571227 -53.762262) (xy 304.625175 -53.754506) (xy 304.679677 -53.754506) (xy 304.733625 -53.762262)
			(xy 304.78592 -53.777617) (xy 304.835497 -53.800259) (xy 304.881347 -53.829725) (xy 304.922538 -53.865416)
			(xy 304.958229 -53.906607) (xy 304.987695 -53.952457) (xy 304.99277 -53.96357) (xy 308.971948 -53.96357)
			(xy 308.976019 -53.907948) (xy 308.988145 -53.853511) (xy 309.008068 -53.80142) (xy 309.035364 -53.752785)
			(xy 309.06945 -53.708642) (xy 309.109599 -53.669933) (xy 309.154957 -53.637482) (xy 309.204557 -53.611981)
			(xy 309.257341 -53.593974) (xy 309.312184 -53.583844) (xy 309.367918 -53.581807) (xy 309.423355 -53.587907)
			(xy 309.477312 -53.602013) (xy 309.528641 -53.623825) (xy 309.576247 -53.652879) (xy 309.619115 -53.688554)
			(xy 309.656332 -53.730091) (xy 309.687105 -53.776604) (xy 309.710777 -53.827101) (xy 309.726845 -53.880508)
			(xy 309.734965 -53.935684) (xy 309.735474 -53.96357) (xy 309.734965 -53.991456) (xy 309.726845 -54.046632)
			(xy 309.72058 -54.067456) (xy 311.141108 -54.067456) (xy 311.145179 -54.011834) (xy 311.157305 -53.957397)
			(xy 311.177228 -53.905306) (xy 311.204524 -53.856671) (xy 311.23861 -53.812528) (xy 311.278759 -53.773819)
			(xy 311.324117 -53.741368) (xy 311.373717 -53.715867) (xy 311.426501 -53.69786) (xy 311.481344 -53.68773)
			(xy 311.537078 -53.685693) (xy 311.592515 -53.691793) (xy 311.646472 -53.705899) (xy 311.697801 -53.727711)
			(xy 311.745407 -53.756765) (xy 311.788275 -53.79244) (xy 311.825492 -53.833977) (xy 311.856265 -53.88049)
			(xy 311.879937 -53.930987) (xy 311.896005 -53.984394) (xy 311.904125 -54.03957) (xy 311.904634 -54.067456)
			(xy 311.904125 -54.095342) (xy 311.896005 -54.150518) (xy 311.879937 -54.203925) (xy 311.863539 -54.238906)
			(xy 318.585848 -54.238906) (xy 318.589919 -54.183284) (xy 318.602045 -54.128847) (xy 318.621968 -54.076756)
			(xy 318.649264 -54.028121) (xy 318.68335 -53.983978) (xy 318.723499 -53.945269) (xy 318.768857 -53.912818)
			(xy 318.818457 -53.887317) (xy 318.871241 -53.86931) (xy 318.926084 -53.85918) (xy 318.981818 -53.857143)
			(xy 319.037255 -53.863243) (xy 319.091212 -53.877349) (xy 319.142541 -53.899161) (xy 319.190147 -53.928215)
			(xy 319.233015 -53.96389) (xy 319.270232 -54.005427) (xy 319.301005 -54.05194) (xy 319.324677 -54.102437)
			(xy 319.340745 -54.155844) (xy 319.348865 -54.21102) (xy 319.349374 -54.238906) (xy 319.348865 -54.266792)
			(xy 319.340745 -54.321968) (xy 319.324677 -54.375375) (xy 319.301005 -54.425872) (xy 319.270232 -54.472385)
			(xy 319.233015 -54.513922) (xy 319.190147 -54.549597) (xy 319.142541 -54.578651) (xy 319.091212 -54.600463)
			(xy 319.037255 -54.614569) (xy 318.981818 -54.620669) (xy 318.926084 -54.618632) (xy 318.871241 -54.608502)
			(xy 318.818457 -54.590495) (xy 318.768857 -54.564994) (xy 318.723499 -54.532543) (xy 318.68335 -54.493834)
			(xy 318.649264 -54.449691) (xy 318.621968 -54.401056) (xy 318.602045 -54.348965) (xy 318.589919 -54.294528)
			(xy 318.585848 -54.238906) (xy 311.863539 -54.238906) (xy 311.856265 -54.254422) (xy 311.825492 -54.300935)
			(xy 311.788275 -54.342472) (xy 311.745407 -54.378147) (xy 311.697801 -54.407201) (xy 311.646472 -54.429013)
			(xy 311.592515 -54.443119) (xy 311.537078 -54.449219) (xy 311.481344 -54.447182) (xy 311.426501 -54.437052)
			(xy 311.373717 -54.419045) (xy 311.324117 -54.393544) (xy 311.278759 -54.361093) (xy 311.23861 -54.322384)
			(xy 311.204524 -54.278241) (xy 311.177228 -54.229606) (xy 311.157305 -54.177515) (xy 311.145179 -54.123078)
			(xy 311.141108 -54.067456) (xy 309.72058 -54.067456) (xy 309.710777 -54.100039) (xy 309.687105 -54.150536)
			(xy 309.656332 -54.197049) (xy 309.619115 -54.238586) (xy 309.576247 -54.274261) (xy 309.528641 -54.303315)
			(xy 309.477312 -54.325127) (xy 309.423355 -54.339233) (xy 309.367918 -54.345333) (xy 309.312184 -54.343296)
			(xy 309.257341 -54.333166) (xy 309.204557 -54.315159) (xy 309.154957 -54.289658) (xy 309.109599 -54.257207)
			(xy 309.06945 -54.218498) (xy 309.035364 -54.174355) (xy 309.008068 -54.12572) (xy 308.988145 -54.073629)
			(xy 308.976019 -54.019192) (xy 308.971948 -53.96357) (xy 304.99277 -53.96357) (xy 305.010337 -54.002034)
			(xy 305.025692 -54.054329) (xy 305.033448 -54.108277) (xy 305.033934 -54.135528) (xy 305.033465 -54.162862)
			(xy 305.025659 -54.21697) (xy 305.01021 -54.269409) (xy 304.987434 -54.319107) (xy 304.957799 -54.365045)
			(xy 304.940208 -54.385972) (xy 304.939954 -54.386226) (xy 304.9397 -54.38648) (xy 304.934116 -54.393568)
			(xy 304.927868 -54.410484) (xy 304.927508 -54.4195) (xy 304.927508 -54.486556) (xy 304.927885 -54.495571)
			(xy 304.934119 -54.512488) (xy 304.9397 -54.519576) (xy 304.939954 -54.51983) (xy 304.940208 -54.520084)
			(xy 304.957808 -54.541004) (xy 304.987445 -54.586943) (xy 305.01022 -54.636642) (xy 305.025666 -54.689084)
			(xy 305.033467 -54.743193) (xy 305.033934 -54.770528) (xy 305.033448 -54.797779) (xy 305.025692 -54.851727)
			(xy 305.010337 -54.904022) (xy 304.987695 -54.953599) (xy 304.958229 -54.999449) (xy 304.922538 -55.04064)
			(xy 304.881347 -55.076331) (xy 304.87026 -55.083456) (xy 311.141108 -55.083456) (xy 311.145179 -55.027834)
			(xy 311.157305 -54.973397) (xy 311.177228 -54.921306) (xy 311.204524 -54.872671) (xy 311.23861 -54.828528)
			(xy 311.278759 -54.789819) (xy 311.324117 -54.757368) (xy 311.373717 -54.731867) (xy 311.426501 -54.71386)
			(xy 311.481344 -54.70373) (xy 311.537078 -54.701693) (xy 311.592515 -54.707793) (xy 311.646472 -54.721899)
			(xy 311.697801 -54.743711) (xy 311.745407 -54.772765) (xy 311.788275 -54.80844) (xy 311.825492 -54.849977)
			(xy 311.856265 -54.89649) (xy 311.879937 -54.946987) (xy 311.892592 -54.989051) (xy 314.100968 -54.989051)
			(xy 314.100968 -54.934549) (xy 314.108724 -54.880603) (xy 314.124078 -54.828309) (xy 314.146718 -54.778732)
			(xy 314.176182 -54.732882) (xy 314.211871 -54.691691) (xy 314.253059 -54.655999) (xy 314.298907 -54.626531)
			(xy 314.348482 -54.603888) (xy 314.400775 -54.58853) (xy 314.454721 -54.58077) (xy 314.481972 -54.580282)
			(xy 314.510063 -54.580799) (xy 314.565639 -54.589022) (xy 314.619407 -54.605309) (xy 314.670205 -54.629308)
			(xy 314.716932 -54.6605) (xy 314.758578 -54.698209) (xy 314.794241 -54.741619) (xy 314.809124 -54.765448)
			(xy 314.814712 -54.774592) (xy 314.83173 -54.786784) (xy 314.924694 -54.80685) (xy 314.945268 -54.802786)
			(xy 314.953904 -54.79669) (xy 314.977965 -54.780685) (xy 315.029897 -54.755344) (xy 315.085056 -54.738119)
			(xy 315.142181 -54.729406) (xy 315.171074 -54.728872) (xy 315.198325 -54.729379) (xy 315.212472 -54.731412)
			(xy 323.72046 -54.731412) (xy 323.720895 -54.704077) (xy 323.72871 -54.649968) (xy 323.744167 -54.597528)
			(xy 323.76695 -54.547831) (xy 323.796592 -54.501894) (xy 323.814186 -54.480968) (xy 323.81444 -54.480714)
			(xy 323.814694 -54.48046) (xy 323.820261 -54.47336) (xy 323.82652 -54.456454) (xy 323.826886 -54.44744)
			(xy 323.826886 -54.380384) (xy 323.82654 -54.371366) (xy 323.820285 -54.354449) (xy 323.814694 -54.347364)
			(xy 323.81444 -54.34711) (xy 323.814186 -54.346856) (xy 323.796597 -54.325925) (xy 323.766942 -54.279994)
			(xy 323.744151 -54.230298) (xy 323.728693 -54.177857) (xy 323.720883 -54.123745) (xy 323.720881 -54.069073)
			(xy 323.728689 -54.014961) (xy 323.744145 -53.962519) (xy 323.766933 -53.912822) (xy 323.796586 -53.86689)
			(xy 323.814186 -53.845968) (xy 323.81444 -53.845714) (xy 323.814694 -53.84546) (xy 323.820261 -53.83836)
			(xy 323.82652 -53.821454) (xy 323.826886 -53.81244) (xy 323.826886 -53.745384) (xy 323.82654 -53.736366)
			(xy 323.820285 -53.719449) (xy 323.814694 -53.712364) (xy 323.81444 -53.71211) (xy 323.814186 -53.711856)
			(xy 323.796597 -53.690925) (xy 323.766942 -53.644994) (xy 323.744151 -53.595298) (xy 323.728693 -53.542857)
			(xy 323.720883 -53.488745) (xy 323.720881 -53.434073) (xy 323.728689 -53.379961) (xy 323.744145 -53.327519)
			(xy 323.766933 -53.277822) (xy 323.796586 -53.23189) (xy 323.814186 -53.210968) (xy 323.81444 -53.210714)
			(xy 323.814694 -53.21046) (xy 323.820261 -53.20336) (xy 323.82652 -53.186454) (xy 323.826886 -53.17744)
			(xy 323.826886 -53.110384) (xy 323.82654 -53.101366) (xy 323.820285 -53.084449) (xy 323.814694 -53.077364)
			(xy 323.81444 -53.07711) (xy 323.814186 -53.076856) (xy 323.796604 -53.055922) (xy 323.766965 -53.009987)
			(xy 323.744187 -52.960291) (xy 323.728736 -52.907853) (xy 323.72093 -52.853746) (xy 323.72046 -52.826412)
			(xy 323.720946 -52.799161) (xy 323.728702 -52.745213) (xy 323.744057 -52.692918) (xy 323.766699 -52.643341)
			(xy 323.796165 -52.597491) (xy 323.831856 -52.5563) (xy 323.873047 -52.520609) (xy 323.918897 -52.491143)
			(xy 323.968474 -52.468501) (xy 324.020769 -52.453146) (xy 324.074717 -52.44539) (xy 324.129219 -52.44539)
			(xy 324.183167 -52.453146) (xy 324.235462 -52.468501) (xy 324.285039 -52.491143) (xy 324.330889 -52.520609)
			(xy 324.37208 -52.5563) (xy 324.407771 -52.597491) (xy 324.437237 -52.643341) (xy 324.459879 -52.692918)
			(xy 324.475234 -52.745213) (xy 324.48299 -52.799161) (xy 324.483476 -52.826412) (xy 324.482988 -52.853745)
			(xy 324.475184 -52.907852) (xy 324.459739 -52.960291) (xy 324.436969 -53.009989) (xy 324.407338 -53.055928)
			(xy 324.38975 -53.076856) (xy 324.389496 -53.07711) (xy 324.389242 -53.077364) (xy 324.383657 -53.084452)
			(xy 324.377411 -53.101368) (xy 324.37705 -53.110384) (xy 324.37705 -53.17744) (xy 324.377377 -53.18646)
			(xy 324.383644 -53.203377) (xy 324.389242 -53.21046) (xy 324.389496 -53.210714) (xy 324.38975 -53.210968)
			(xy 324.407361 -53.231881) (xy 324.437012 -53.277816) (xy 324.459799 -53.327515) (xy 324.475255 -53.379959)
			(xy 324.483062 -53.434072) (xy 324.48306 -53.488746) (xy 324.475251 -53.542859) (xy 324.459793 -53.595302)
			(xy 324.437004 -53.645) (xy 324.40735 -53.690934) (xy 324.38975 -53.711856) (xy 324.389496 -53.71211)
			(xy 324.389242 -53.712364) (xy 324.383657 -53.719452) (xy 324.377411 -53.736368) (xy 324.37705 -53.745384)
			(xy 324.37705 -53.81244) (xy 324.377377 -53.82146) (xy 324.383644 -53.838377) (xy 324.389242 -53.84546)
			(xy 324.389496 -53.845714) (xy 324.38975 -53.845968) (xy 324.407361 -53.866881) (xy 324.437012 -53.912816)
			(xy 324.459799 -53.962515) (xy 324.475255 -54.014959) (xy 324.483062 -54.069072) (xy 324.48306 -54.123746)
			(xy 324.475251 -54.177859) (xy 324.459793 -54.230302) (xy 324.437004 -54.28) (xy 324.40735 -54.325934)
			(xy 324.38975 -54.346856) (xy 324.389496 -54.34711) (xy 324.389242 -54.347364) (xy 324.383657 -54.354452)
			(xy 324.377411 -54.371368) (xy 324.37705 -54.380384) (xy 324.37705 -54.44744) (xy 324.377377 -54.45646)
			(xy 324.383644 -54.473377) (xy 324.389242 -54.48046) (xy 324.389496 -54.480714) (xy 324.38975 -54.480968)
			(xy 324.407349 -54.501889) (xy 324.436984 -54.547828) (xy 324.459759 -54.597527) (xy 324.475205 -54.649968)
			(xy 324.483008 -54.704078) (xy 324.483476 -54.731412) (xy 324.48299 -54.758663) (xy 324.478326 -54.791102)
			(xy 326.376284 -54.791102) (xy 326.37679 -54.76377) (xy 326.384591 -54.709664) (xy 326.400032 -54.657226)
			(xy 326.422799 -54.607528) (xy 326.452424 -54.561587) (xy 326.47001 -54.540658) (xy 326.470264 -54.540404)
			(xy 326.470518 -54.54015) (xy 326.476092 -54.533055) (xy 326.482346 -54.516145) (xy 326.48271 -54.50713)
			(xy 326.48271 -54.440074) (xy 326.482363 -54.431056) (xy 326.476108 -54.414139) (xy 326.470518 -54.407054)
			(xy 326.470264 -54.4068) (xy 326.47001 -54.406546) (xy 326.45241 -54.385623) (xy 326.422754 -54.339691)
			(xy 326.399962 -54.289994) (xy 326.384503 -54.237552) (xy 326.376694 -54.183438) (xy 326.376693 -54.128765)
			(xy 326.384503 -54.074651) (xy 326.399961 -54.022208) (xy 326.422752 -53.972511) (xy 326.452408 -53.926579)
			(xy 326.47001 -53.905658) (xy 326.470264 -53.905404) (xy 326.470518 -53.90515) (xy 326.476092 -53.898055)
			(xy 326.482346 -53.881145) (xy 326.48271 -53.87213) (xy 326.48271 -53.805074) (xy 326.482363 -53.796056)
			(xy 326.476108 -53.779139) (xy 326.470518 -53.772054) (xy 326.470264 -53.7718) (xy 326.47001 -53.771546)
			(xy 326.45241 -53.750623) (xy 326.422754 -53.704691) (xy 326.399962 -53.654994) (xy 326.384503 -53.602552)
			(xy 326.376694 -53.548438) (xy 326.376693 -53.493765) (xy 326.384503 -53.439651) (xy 326.399961 -53.387208)
			(xy 326.422752 -53.337511) (xy 326.452408 -53.291579) (xy 326.47001 -53.270658) (xy 326.470264 -53.270404)
			(xy 326.470518 -53.27015) (xy 326.476092 -53.263055) (xy 326.482346 -53.246145) (xy 326.48271 -53.23713)
			(xy 326.48271 -53.170074) (xy 326.482363 -53.161056) (xy 326.476108 -53.144139) (xy 326.470518 -53.137054)
			(xy 326.470264 -53.1368) (xy 326.47001 -53.136546) (xy 326.452427 -53.115612) (xy 326.422787 -53.069678)
			(xy 326.400009 -53.019982) (xy 326.384559 -52.967543) (xy 326.376754 -52.913436) (xy 326.376284 -52.886102)
			(xy 326.37677 -52.858851) (xy 326.384526 -52.804903) (xy 326.399881 -52.752608) (xy 326.422523 -52.703031)
			(xy 326.451989 -52.657181) (xy 326.48768 -52.61599) (xy 326.528871 -52.580299) (xy 326.574721 -52.550833)
			(xy 326.624298 -52.528191) (xy 326.676593 -52.512836) (xy 326.730541 -52.50508) (xy 326.785043 -52.50508)
			(xy 326.838991 -52.512836) (xy 326.853309 -52.51704) (xy 331.039976 -52.51704) (xy 331.044047 -52.461418)
			(xy 331.056173 -52.406981) (xy 331.076096 -52.35489) (xy 331.103392 -52.306255) (xy 331.137478 -52.262112)
			(xy 331.177627 -52.223403) (xy 331.222985 -52.190952) (xy 331.272585 -52.165451) (xy 331.325369 -52.147444)
			(xy 331.380212 -52.137314) (xy 331.435946 -52.135277) (xy 331.491383 -52.141377) (xy 331.54534 -52.155483)
			(xy 331.596669 -52.177295) (xy 331.644275 -52.206349) (xy 331.687143 -52.242024) (xy 331.72436 -52.283561)
			(xy 331.755133 -52.330074) (xy 331.778805 -52.380571) (xy 331.794873 -52.433978) (xy 331.802993 -52.489154)
			(xy 331.803502 -52.51704) (xy 331.802993 -52.544926) (xy 331.796743 -52.587398) (xy 334.955132 -52.587398)
			(xy 334.959203 -52.531776) (xy 334.971329 -52.477339) (xy 334.991252 -52.425248) (xy 335.018548 -52.376613)
			(xy 335.052634 -52.33247) (xy 335.092783 -52.293761) (xy 335.138141 -52.26131) (xy 335.187741 -52.235809)
			(xy 335.240525 -52.217802) (xy 335.295368 -52.207672) (xy 335.351102 -52.205635) (xy 335.406539 -52.211735)
			(xy 335.460496 -52.225841) (xy 335.511825 -52.247653) (xy 335.559431 -52.276707) (xy 335.602299 -52.312382)
			(xy 335.639516 -52.353919) (xy 335.670289 -52.400432) (xy 335.693961 -52.450929) (xy 335.710029 -52.504336)
			(xy 335.718149 -52.559512) (xy 335.718234 -52.564157) (xy 352.127207 -52.564157) (xy 352.127207 -52.509643)
			(xy 352.134965 -52.455684) (xy 352.150324 -52.403379) (xy 352.17297 -52.353792) (xy 352.202443 -52.307932)
			(xy 352.238142 -52.266734) (xy 352.279342 -52.231036) (xy 352.325202 -52.201564) (xy 352.37479 -52.17892)
			(xy 352.427096 -52.163563) (xy 352.481055 -52.155806) (xy 352.508312 -52.155344) (xy 352.535683 -52.155792)
			(xy 352.589863 -52.163613) (xy 352.642367 -52.179105) (xy 352.692114 -52.201951) (xy 352.738079 -52.23168)
			(xy 352.75901 -52.249324) (xy 352.759264 -52.249578) (xy 352.76635 -52.255165) (xy 352.783268 -52.261409)
			(xy 352.792284 -52.26177) (xy 352.85934 -52.26177) (xy 352.86836 -52.261439) (xy 352.885277 -52.255174)
			(xy 352.89236 -52.249578) (xy 352.892868 -52.24907) (xy 352.913791 -52.231474) (xy 352.959729 -52.201838)
			(xy 353.009428 -52.179062) (xy 353.061869 -52.163615) (xy 353.115978 -52.155812) (xy 353.143312 -52.155344)
			(xy 353.170559 -52.155927) (xy 353.224499 -52.163684) (xy 353.276785 -52.179038) (xy 353.326355 -52.201677)
			(xy 353.372198 -52.23114) (xy 353.413382 -52.266827) (xy 353.449067 -52.308012) (xy 353.478529 -52.353856)
			(xy 353.501166 -52.403426) (xy 353.516519 -52.455713) (xy 353.524274 -52.509653) (xy 353.524274 -52.555948)
			(xy 354.884002 -52.555948) (xy 354.884002 -52.501452) (xy 354.891757 -52.44751) (xy 354.90711 -52.39522)
			(xy 354.929748 -52.345648) (xy 354.95921 -52.299802) (xy 354.994897 -52.258615) (xy 355.036081 -52.222926)
			(xy 355.081925 -52.193461) (xy 355.131496 -52.170819) (xy 355.183784 -52.155463) (xy 355.237726 -52.147704)
			(xy 355.264974 -52.147216) (xy 355.292344 -52.147693) (xy 355.346523 -52.155508) (xy 355.399026 -52.170994)
			(xy 355.448773 -52.193833) (xy 355.49474 -52.223556) (xy 355.515672 -52.241196) (xy 355.515926 -52.24145)
			(xy 355.523025 -52.247018) (xy 355.539932 -52.253275) (xy 355.548946 -52.253642) (xy 355.616002 -52.253642)
			(xy 355.62502 -52.253298) (xy 355.641938 -52.247043) (xy 355.649022 -52.24145) (xy 355.64953 -52.240942)
			(xy 355.670477 -52.223375) (xy 355.716407 -52.193732) (xy 355.7661 -52.17095) (xy 355.818536 -52.155496)
			(xy 355.872641 -52.147687) (xy 355.899974 -52.147216) (xy 355.92723 -52.147629) (xy 355.981187 -52.155384)
			(xy 356.033491 -52.170738) (xy 356.083078 -52.193381) (xy 356.128937 -52.22285) (xy 356.170136 -52.258546)
			(xy 356.205834 -52.299742) (xy 356.235307 -52.345599) (xy 356.257953 -52.395184) (xy 356.273311 -52.447488)
			(xy 356.281069 -52.501444) (xy 356.281069 -52.555956) (xy 356.273311 -52.609912) (xy 356.257953 -52.662216)
			(xy 356.235307 -52.711801) (xy 356.205834 -52.757658) (xy 356.170136 -52.798854) (xy 356.128937 -52.83455)
			(xy 356.083078 -52.864019) (xy 356.033491 -52.886662) (xy 355.981187 -52.902016) (xy 355.92723 -52.909771)
			(xy 355.899974 -52.910232) (xy 355.872602 -52.909798) (xy 355.818421 -52.901975) (xy 355.765917 -52.886479)
			(xy 355.716171 -52.86363) (xy 355.670206 -52.833897) (xy 355.649276 -52.816252) (xy 355.649022 -52.815998)
			(xy 355.641933 -52.810414) (xy 355.625018 -52.804166) (xy 355.616002 -52.803806) (xy 355.548946 -52.803806)
			(xy 355.539931 -52.804184) (xy 355.523014 -52.810417) (xy 355.515926 -52.815998) (xy 355.515418 -52.816506)
			(xy 355.494497 -52.834104) (xy 355.448559 -52.863742) (xy 355.39886 -52.886517) (xy 355.346418 -52.901963)
			(xy 355.292309 -52.909764) (xy 355.264974 -52.910232) (xy 355.237726 -52.909696) (xy 355.183784 -52.901937)
			(xy 355.131496 -52.886581) (xy 355.081925 -52.863939) (xy 355.036081 -52.834474) (xy 354.994897 -52.798785)
			(xy 354.95921 -52.757598) (xy 354.929748 -52.711752) (xy 354.90711 -52.66218) (xy 354.891757 -52.60989)
			(xy 354.884002 -52.555948) (xy 353.524274 -52.555948) (xy 353.524274 -52.564147) (xy 353.516519 -52.618087)
			(xy 353.501166 -52.670374) (xy 353.478529 -52.719944) (xy 353.449067 -52.765788) (xy 353.413382 -52.806973)
			(xy 353.372198 -52.84266) (xy 353.326355 -52.872123) (xy 353.276785 -52.894762) (xy 353.224499 -52.910116)
			(xy 353.170559 -52.917873) (xy 353.143312 -52.91836) (xy 353.115942 -52.917897) (xy 353.061762 -52.91008)
			(xy 353.009258 -52.89459) (xy 352.959512 -52.871748) (xy 352.913545 -52.842022) (xy 352.892614 -52.82438)
			(xy 352.89236 -52.824126) (xy 352.885267 -52.81855) (xy 352.868355 -52.812299) (xy 352.85934 -52.811934)
			(xy 352.792284 -52.811934) (xy 352.783265 -52.812276) (xy 352.766348 -52.818533) (xy 352.759264 -52.824126)
			(xy 352.758756 -52.824634) (xy 352.737824 -52.842219) (xy 352.691888 -52.871857) (xy 352.642192 -52.894635)
			(xy 352.589753 -52.910084) (xy 352.535646 -52.91789) (xy 352.508312 -52.91836) (xy 352.481055 -52.917994)
			(xy 352.427096 -52.910237) (xy 352.37479 -52.89488) (xy 352.325202 -52.872236) (xy 352.279342 -52.842764)
			(xy 352.238142 -52.807066) (xy 352.202443 -52.765868) (xy 352.17297 -52.720008) (xy 352.150324 -52.670421)
			(xy 352.134965 -52.618116) (xy 352.127207 -52.564157) (xy 335.718234 -52.564157) (xy 335.718658 -52.587398)
			(xy 335.718149 -52.615284) (xy 335.710029 -52.67046) (xy 335.693961 -52.723867) (xy 335.670289 -52.774364)
			(xy 335.639516 -52.820877) (xy 335.602299 -52.862414) (xy 335.559431 -52.898089) (xy 335.511825 -52.927143)
			(xy 335.460496 -52.948955) (xy 335.406539 -52.963061) (xy 335.351102 -52.969161) (xy 335.295368 -52.967124)
			(xy 335.240525 -52.956994) (xy 335.187741 -52.938987) (xy 335.138141 -52.913486) (xy 335.092783 -52.881035)
			(xy 335.052634 -52.842326) (xy 335.018548 -52.798183) (xy 334.991252 -52.749548) (xy 334.971329 -52.697457)
			(xy 334.959203 -52.64302) (xy 334.955132 -52.587398) (xy 331.796743 -52.587398) (xy 331.794873 -52.600102)
			(xy 331.778805 -52.653509) (xy 331.755133 -52.704006) (xy 331.72436 -52.750519) (xy 331.687143 -52.792056)
			(xy 331.644275 -52.827731) (xy 331.596669 -52.856785) (xy 331.54534 -52.878597) (xy 331.491383 -52.892703)
			(xy 331.435946 -52.898803) (xy 331.380212 -52.896766) (xy 331.325369 -52.886636) (xy 331.272585 -52.868629)
			(xy 331.222985 -52.843128) (xy 331.177627 -52.810677) (xy 331.137478 -52.771968) (xy 331.103392 -52.727825)
			(xy 331.076096 -52.67919) (xy 331.056173 -52.627099) (xy 331.044047 -52.572662) (xy 331.039976 -52.51704)
			(xy 326.853309 -52.51704) (xy 326.891286 -52.528191) (xy 326.940863 -52.550833) (xy 326.986713 -52.580299)
			(xy 327.027904 -52.61599) (xy 327.063595 -52.657181) (xy 327.093061 -52.703031) (xy 327.115703 -52.752608)
			(xy 327.131058 -52.804903) (xy 327.138814 -52.858851) (xy 327.1393 -52.886102) (xy 327.1388 -52.913435)
			(xy 327.130999 -52.96754) (xy 327.115556 -53.019979) (xy 327.092788 -53.069677) (xy 327.063161 -53.115617)
			(xy 327.045574 -53.136546) (xy 327.04532 -53.1368) (xy 327.045066 -53.137054) (xy 327.039489 -53.144147)
			(xy 327.033238 -53.161059) (xy 327.032874 -53.170074) (xy 327.032874 -53.23713) (xy 327.033222 -53.246148)
			(xy 327.039476 -53.263064) (xy 327.045066 -53.27015) (xy 327.04532 -53.270404) (xy 327.045574 -53.270658)
			(xy 327.063175 -53.291579) (xy 327.092824 -53.337514) (xy 327.11561 -53.387211) (xy 327.131065 -53.439653)
			(xy 327.138873 -53.493765) (xy 327.138873 -53.548438) (xy 327.131065 -53.602549) (xy 327.115609 -53.654992)
			(xy 327.092823 -53.704689) (xy 327.063173 -53.750623) (xy 327.046429 -53.77053) (xy 327.410572 -53.77053)
			(xy 327.411084 -53.741613) (xy 327.419811 -53.68444) (xy 327.437068 -53.62924) (xy 327.462461 -53.577277)
			(xy 327.495407 -53.529744) (xy 327.535151 -53.487729) (xy 327.557638 -53.46954) (xy 327.565006 -53.463239)
			(xy 327.574812 -53.446538) (xy 327.576688 -53.437028) (xy 327.577196 -53.429408) (xy 327.577196 -53.349652)
			(xy 327.576688 -53.342032) (xy 327.574834 -53.332514) (xy 327.565027 -53.315801) (xy 327.557638 -53.30952)
			(xy 327.535172 -53.291308) (xy 327.495434 -53.249294) (xy 327.462492 -53.201764) (xy 327.4371 -53.149806)
			(xy 327.419841 -53.094612) (xy 327.411108 -53.037445) (xy 327.410572 -53.00853) (xy 327.411083 -52.981279)
			(xy 327.418836 -52.927331) (xy 327.434187 -52.875035) (xy 327.456824 -52.825456) (xy 327.486287 -52.779604)
			(xy 327.521976 -52.738411) (xy 327.563164 -52.702717) (xy 327.609012 -52.673248) (xy 327.658588 -52.650604)
			(xy 327.710882 -52.635246) (xy 327.764829 -52.627487) (xy 327.79208 -52.627022) (xy 327.792334 -52.627022)
			(xy 327.81863 -52.627451) (xy 327.87072 -52.634701) (xy 327.921322 -52.649033) (xy 327.969479 -52.670174)
			(xy 328.014277 -52.697724) (xy 328.054871 -52.731163) (xy 328.073004 -52.750212) (xy 328.080573 -52.757656)
			(xy 328.099993 -52.766179) (xy 328.110596 -52.766722) (xy 328.184764 -52.766722) (xy 328.195398 -52.766332)
			(xy 328.214862 -52.757768) (xy 328.222356 -52.750212) (xy 328.240499 -52.731171) (xy 328.281078 -52.697713)
			(xy 328.325871 -52.670151) (xy 328.374028 -52.649009) (xy 328.424635 -52.634689) (xy 328.476729 -52.627462)
			(xy 328.503026 -52.627022) (xy 328.50328 -52.627022) (xy 328.530534 -52.627474) (xy 328.584487 -52.635229)
			(xy 328.636787 -52.650584) (xy 328.686369 -52.673226) (xy 328.732223 -52.702695) (xy 328.773417 -52.73839)
			(xy 328.809111 -52.779585) (xy 328.838578 -52.82544) (xy 328.861219 -52.875023) (xy 328.876573 -52.927323)
			(xy 328.884327 -52.981276) (xy 328.884788 -53.00853) (xy 328.884305 -53.036196) (xy 328.882074 -53.051456)
			(xy 337.141056 -53.051456) (xy 337.145127 -52.995834) (xy 337.157253 -52.941397) (xy 337.177176 -52.889306)
			(xy 337.204472 -52.840671) (xy 337.238558 -52.796528) (xy 337.278707 -52.757819) (xy 337.324065 -52.725368)
			(xy 337.373665 -52.699867) (xy 337.426449 -52.68186) (xy 337.481292 -52.67173) (xy 337.537026 -52.669693)
			(xy 337.592463 -52.675793) (xy 337.64642 -52.689899) (xy 337.697749 -52.711711) (xy 337.745355 -52.740765)
			(xy 337.788223 -52.77644) (xy 337.82544 -52.817977) (xy 337.856213 -52.86449) (xy 337.879885 -52.914987)
			(xy 337.895953 -52.968394) (xy 337.904073 -53.02357) (xy 337.904582 -53.051456) (xy 337.904073 -53.079342)
			(xy 337.895953 -53.134518) (xy 337.879885 -53.187925) (xy 337.856213 -53.238422) (xy 337.82544 -53.284935)
			(xy 337.788223 -53.326472) (xy 337.745355 -53.362147) (xy 337.697749 -53.391201) (xy 337.64642 -53.413013)
			(xy 337.592463 -53.427119) (xy 337.537026 -53.433219) (xy 337.481292 -53.431182) (xy 337.426449 -53.421052)
			(xy 337.373665 -53.403045) (xy 337.324065 -53.377544) (xy 337.278707 -53.345093) (xy 337.238558 -53.306384)
			(xy 337.204472 -53.262241) (xy 337.177176 -53.213606) (xy 337.157253 -53.161515) (xy 337.145127 -53.107078)
			(xy 337.141056 -53.051456) (xy 328.882074 -53.051456) (xy 328.876301 -53.090947) (xy 328.86048 -53.143969)
			(xy 328.837172 -53.194154) (xy 328.806866 -53.240449) (xy 328.770197 -53.281886) (xy 328.727931 -53.317598)
			(xy 328.704702 -53.332634) (xy 328.704448 -53.332888) (xy 328.694914 -53.339543) (xy 328.682613 -53.359246)
			(xy 328.680826 -53.370734) (xy 328.672952 -53.450744) (xy 328.672272 -53.462445) (xy 328.680362 -53.484419)
			(xy 328.688446 -53.492908) (xy 328.6887 -53.492908) (xy 328.707267 -53.511003) (xy 328.739847 -53.551332)
			(xy 328.766662 -53.595703) (xy 328.787217 -53.643299) (xy 328.801133 -53.693241) (xy 328.808154 -53.744608)
			(xy 328.808588 -53.77053) (xy 328.80815 -53.797783) (xy 328.800389 -53.851733) (xy 328.785029 -53.90403)
			(xy 328.762383 -53.953609) (xy 328.732912 -53.99946) (xy 328.697215 -54.040651) (xy 328.65602 -54.076342)
			(xy 328.610165 -54.105807) (xy 328.560583 -54.128446) (xy 328.508284 -54.1438) (xy 328.454333 -54.151554)
			(xy 328.42708 -54.152038) (xy 328.399709 -54.151599) (xy 328.345528 -54.143777) (xy 328.293024 -54.128282)
			(xy 328.243277 -54.105434) (xy 328.197312 -54.075703) (xy 328.176382 -54.058058) (xy 328.176128 -54.057804)
			(xy 328.169037 -54.052223) (xy 328.152124 -54.045973) (xy 328.143108 -54.045612) (xy 328.076052 -54.045612)
			(xy 328.067037 -54.045991) (xy 328.05012 -54.052223) (xy 328.043032 -54.057804) (xy 328.042524 -54.058312)
			(xy 328.021602 -54.075909) (xy 327.975663 -54.105546) (xy 327.925965 -54.128321) (xy 327.873524 -54.143768)
			(xy 327.819414 -54.15157) (xy 327.79208 -54.152038) (xy 327.76483 -54.151541) (xy 327.710884 -54.143782)
			(xy 327.658591 -54.128426) (xy 327.609016 -54.105785) (xy 327.563167 -54.076319) (xy 327.521978 -54.040629)
			(xy 327.486287 -53.999441) (xy 327.45682 -53.953593) (xy 327.434177 -53.904018) (xy 327.41882 -53.851726)
			(xy 327.41106 -53.79778) (xy 327.410572 -53.77053) (xy 327.046429 -53.77053) (xy 327.045574 -53.771546)
			(xy 327.04532 -53.7718) (xy 327.045066 -53.772054) (xy 327.039489 -53.779147) (xy 327.033238 -53.796059)
			(xy 327.032874 -53.805074) (xy 327.032874 -53.87213) (xy 327.033222 -53.881148) (xy 327.039476 -53.898064)
			(xy 327.045066 -53.90515) (xy 327.04532 -53.905404) (xy 327.045574 -53.905658) (xy 327.063175 -53.926579)
			(xy 327.092824 -53.972514) (xy 327.11561 -54.022211) (xy 327.131065 -54.074653) (xy 327.138873 -54.128765)
			(xy 327.138873 -54.183438) (xy 327.131065 -54.237549) (xy 327.115609 -54.289992) (xy 327.101765 -54.320186)
			(xy 329.330304 -54.320186) (xy 329.330796 -54.292853) (xy 329.338599 -54.238747) (xy 329.354044 -54.186308)
			(xy 329.376813 -54.13661) (xy 329.406443 -54.09067) (xy 329.42403 -54.069742) (xy 329.424284 -54.069488)
			(xy 329.424538 -54.069234) (xy 329.430121 -54.062145) (xy 329.436369 -54.04523) (xy 329.43673 -54.036214)
			(xy 329.43673 -53.969158) (xy 329.436339 -53.960145) (xy 329.430114 -53.943228) (xy 329.424538 -53.936138)
			(xy 329.424284 -53.935884) (xy 329.42403 -53.93563) (xy 329.406443 -53.9147) (xy 329.376803 -53.868765)
			(xy 329.354025 -53.819068) (xy 329.338576 -53.766628) (xy 329.330772 -53.71252) (xy 329.330304 -53.685186)
			(xy 329.33079 -53.657935) (xy 329.338546 -53.603987) (xy 329.353901 -53.551692) (xy 329.376543 -53.502115)
			(xy 329.406009 -53.456265) (xy 329.4417 -53.415074) (xy 329.482891 -53.379383) (xy 329.528741 -53.349917)
			(xy 329.578318 -53.327275) (xy 329.630613 -53.31192) (xy 329.684561 -53.304164) (xy 329.739063 -53.304164)
			(xy 329.793011 -53.31192) (xy 329.845306 -53.327275) (xy 329.894883 -53.349917) (xy 329.940733 -53.379383)
			(xy 329.981924 -53.415074) (xy 330.017615 -53.456265) (xy 330.043508 -53.496555) (xy 354.433541 -53.496555)
			(xy 354.433541 -53.442045) (xy 354.441299 -53.388089) (xy 354.456657 -53.335787) (xy 354.479303 -53.286202)
			(xy 354.508775 -53.240346) (xy 354.544474 -53.199151) (xy 354.585672 -53.163456) (xy 354.63153 -53.133988)
			(xy 354.681117 -53.111346) (xy 354.73342 -53.095992) (xy 354.787377 -53.088239) (xy 354.814632 -53.087778)
			(xy 354.842004 -53.088206) (xy 354.896185 -53.09603) (xy 354.94869 -53.111527) (xy 354.998436 -53.134378)
			(xy 355.0444 -53.164112) (xy 355.06533 -53.181758) (xy 355.065584 -53.182012) (xy 355.07267 -53.187599)
			(xy 355.089587 -53.193845) (xy 355.098604 -53.194204) (xy 355.16566 -53.194204) (xy 355.174675 -53.193827)
			(xy 355.191592 -53.187593) (xy 355.19868 -53.182012) (xy 355.199188 -53.181504) (xy 355.220108 -53.163904)
			(xy 355.266046 -53.134267) (xy 355.315746 -53.111492) (xy 355.368188 -53.096046) (xy 355.422297 -53.088245)
			(xy 355.449632 -53.087778) (xy 355.476881 -53.088294) (xy 355.530823 -53.096054) (xy 355.583112 -53.111412)
			(xy 355.632683 -53.134054) (xy 355.678528 -53.16352) (xy 355.719713 -53.19921) (xy 355.755399 -53.240398)
			(xy 355.784862 -53.286245) (xy 355.8075 -53.335818) (xy 355.822852 -53.388108) (xy 355.830608 -53.442051)
			(xy 355.830608 -53.496549) (xy 355.822852 -53.550492) (xy 355.8075 -53.602782) (xy 355.784862 -53.652355)
			(xy 355.755399 -53.698202) (xy 355.719713 -53.73939) (xy 355.678528 -53.77508) (xy 355.632683 -53.804546)
			(xy 355.583112 -53.827188) (xy 355.530823 -53.842546) (xy 355.476881 -53.850306) (xy 355.449632 -53.850794)
			(xy 355.422262 -53.850311) (xy 355.368084 -53.842497) (xy 355.315581 -53.827012) (xy 355.265834 -53.804174)
			(xy 355.219866 -53.774453) (xy 355.198934 -53.756814) (xy 355.19868 -53.75656) (xy 355.191607 -53.750954)
			(xy 355.17468 -53.74472) (xy 355.16566 -53.744368) (xy 355.098604 -53.744368) (xy 355.089588 -53.744734)
			(xy 355.072672 -53.750976) (xy 355.065584 -53.75656) (xy 355.065076 -53.757068) (xy 355.044128 -53.774633)
			(xy 354.998198 -53.804277) (xy 354.948506 -53.827059) (xy 354.89607 -53.842513) (xy 354.841965 -53.850322)
			(xy 354.814632 -53.850794) (xy 354.787377 -53.850361) (xy 354.73342 -53.842608) (xy 354.681117 -53.827254)
			(xy 354.63153 -53.804612) (xy 354.585672 -53.775144) (xy 354.544474 -53.739449) (xy 354.508775 -53.698254)
			(xy 354.479303 -53.652398) (xy 354.456657 -53.602813) (xy 354.441299 -53.550511) (xy 354.433541 -53.496555)
			(xy 330.043508 -53.496555) (xy 330.047081 -53.502115) (xy 330.069723 -53.551692) (xy 330.085078 -53.603987)
			(xy 330.092834 -53.657935) (xy 330.09332 -53.685186) (xy 330.092864 -53.71252) (xy 330.085052 -53.766628)
			(xy 330.069598 -53.819067) (xy 330.04682 -53.868764) (xy 330.017185 -53.914703) (xy 329.999594 -53.93563)
			(xy 329.99934 -53.935884) (xy 329.999086 -53.936138) (xy 329.993518 -53.943237) (xy 329.98726 -53.960144)
			(xy 329.986894 -53.969158) (xy 329.986894 -54.036214) (xy 329.987246 -54.045231) (xy 329.993497 -54.062148)
			(xy 329.999086 -54.069234) (xy 329.99934 -54.069488) (xy 329.999594 -54.069742) (xy 330.017172 -54.09068)
			(xy 330.046813 -54.136613) (xy 330.069592 -54.186308) (xy 330.085043 -54.238746) (xy 330.09285 -54.292853)
			(xy 330.09332 -54.320186) (xy 330.092834 -54.347437) (xy 330.085078 -54.401385) (xy 330.069723 -54.45368)
			(xy 330.047081 -54.503257) (xy 330.017615 -54.549107) (xy 329.981924 -54.590298) (xy 329.940733 -54.625989)
			(xy 329.894883 -54.655455) (xy 329.845306 -54.678097) (xy 329.793011 -54.693452) (xy 329.739063 -54.701208)
			(xy 329.684561 -54.701208) (xy 329.630613 -54.693452) (xy 329.578318 -54.678097) (xy 329.528741 -54.655455)
			(xy 329.482891 -54.625989) (xy 329.4417 -54.590298) (xy 329.406009 -54.549107) (xy 329.376543 -54.503257)
			(xy 329.353901 -54.45368) (xy 329.338546 -54.401385) (xy 329.33079 -54.347437) (xy 329.330304 -54.320186)
			(xy 327.101765 -54.320186) (xy 327.092823 -54.339689) (xy 327.063173 -54.385623) (xy 327.045574 -54.406546)
			(xy 327.04532 -54.4068) (xy 327.045066 -54.407054) (xy 327.039489 -54.414147) (xy 327.033238 -54.431059)
			(xy 327.032874 -54.440074) (xy 327.032874 -54.50713) (xy 327.033222 -54.516148) (xy 327.039476 -54.533064)
			(xy 327.045066 -54.54015) (xy 327.04532 -54.540404) (xy 327.045574 -54.540658) (xy 327.063156 -54.561592)
			(xy 327.092797 -54.607526) (xy 327.115576 -54.657222) (xy 327.131026 -54.709661) (xy 327.138831 -54.763768)
			(xy 327.138947 -54.770528) (xy 330.270866 -54.770528) (xy 330.271309 -54.743193) (xy 330.279122 -54.689084)
			(xy 330.294577 -54.636644) (xy 330.317358 -54.586947) (xy 330.346999 -54.54101) (xy 330.364592 -54.520084)
			(xy 330.364846 -54.51983) (xy 330.3651 -54.519576) (xy 330.370703 -54.5125) (xy 330.37694 -54.495575)
			(xy 330.377292 -54.486556) (xy 330.377292 -54.4195) (xy 330.376937 -54.410483) (xy 330.370688 -54.393566)
			(xy 330.3651 -54.38648) (xy 330.364846 -54.386226) (xy 330.364592 -54.385972) (xy 330.347019 -54.365031)
			(xy 330.317378 -54.319098) (xy 330.294598 -54.269404) (xy 330.279145 -54.216967) (xy 330.271337 -54.162861)
			(xy 330.270866 -54.135528) (xy 330.271352 -54.108277) (xy 330.279108 -54.054329) (xy 330.294463 -54.002034)
			(xy 330.317105 -53.952457) (xy 330.346571 -53.906607) (xy 330.382262 -53.865416) (xy 330.423453 -53.829725)
			(xy 330.469303 -53.800259) (xy 330.51888 -53.777617) (xy 330.571175 -53.762262) (xy 330.625123 -53.754506)
			(xy 330.679625 -53.754506) (xy 330.733573 -53.762262) (xy 330.785868 -53.777617) (xy 330.835445 -53.800259)
			(xy 330.881295 -53.829725) (xy 330.922486 -53.865416) (xy 330.958177 -53.906607) (xy 330.987643 -53.952457)
			(xy 330.992718 -53.96357) (xy 334.971896 -53.96357) (xy 334.975967 -53.907948) (xy 334.988093 -53.853511)
			(xy 335.008016 -53.80142) (xy 335.035312 -53.752785) (xy 335.069398 -53.708642) (xy 335.109547 -53.669933)
			(xy 335.154905 -53.637482) (xy 335.204505 -53.611981) (xy 335.257289 -53.593974) (xy 335.312132 -53.583844)
			(xy 335.367866 -53.581807) (xy 335.423303 -53.587907) (xy 335.47726 -53.602013) (xy 335.528589 -53.623825)
			(xy 335.576195 -53.652879) (xy 335.619063 -53.688554) (xy 335.65628 -53.730091) (xy 335.687053 -53.776604)
			(xy 335.710725 -53.827101) (xy 335.726793 -53.880508) (xy 335.734913 -53.935684) (xy 335.735422 -53.96357)
			(xy 335.734913 -53.991456) (xy 335.726793 -54.046632) (xy 335.720528 -54.067456) (xy 337.141056 -54.067456)
			(xy 337.145127 -54.011834) (xy 337.157253 -53.957397) (xy 337.177176 -53.905306) (xy 337.204472 -53.856671)
			(xy 337.238558 -53.812528) (xy 337.278707 -53.773819) (xy 337.324065 -53.741368) (xy 337.373665 -53.715867)
			(xy 337.426449 -53.69786) (xy 337.481292 -53.68773) (xy 337.537026 -53.685693) (xy 337.592463 -53.691793)
			(xy 337.64642 -53.705899) (xy 337.697749 -53.727711) (xy 337.745355 -53.756765) (xy 337.788223 -53.79244)
			(xy 337.82544 -53.833977) (xy 337.856213 -53.88049) (xy 337.879885 -53.930987) (xy 337.895953 -53.984394)
			(xy 337.904073 -54.03957) (xy 337.904582 -54.067456) (xy 337.904073 -54.095342) (xy 337.895953 -54.150518)
			(xy 337.879885 -54.203925) (xy 337.863487 -54.238906) (xy 356.686102 -54.238906) (xy 356.690173 -54.183284)
			(xy 356.702299 -54.128847) (xy 356.722222 -54.076756) (xy 356.749518 -54.028121) (xy 356.783604 -53.983978)
			(xy 356.823753 -53.945269) (xy 356.869111 -53.912818) (xy 356.918711 -53.887317) (xy 356.971495 -53.86931)
			(xy 357.026338 -53.85918) (xy 357.082072 -53.857143) (xy 357.137509 -53.863243) (xy 357.191466 -53.877349)
			(xy 357.242795 -53.899161) (xy 357.290401 -53.928215) (xy 357.333269 -53.96389) (xy 357.370486 -54.005427)
			(xy 357.401259 -54.05194) (xy 357.424931 -54.102437) (xy 357.440999 -54.155844) (xy 357.449119 -54.21102)
			(xy 357.449628 -54.238906) (xy 357.449119 -54.266792) (xy 357.440999 -54.321968) (xy 357.424931 -54.375375)
			(xy 357.401259 -54.425872) (xy 357.370486 -54.472385) (xy 357.333269 -54.513922) (xy 357.290401 -54.549597)
			(xy 357.242795 -54.578651) (xy 357.191466 -54.600463) (xy 357.137509 -54.614569) (xy 357.082072 -54.620669)
			(xy 357.026338 -54.618632) (xy 356.971495 -54.608502) (xy 356.918711 -54.590495) (xy 356.869111 -54.564994)
			(xy 356.823753 -54.532543) (xy 356.783604 -54.493834) (xy 356.749518 -54.449691) (xy 356.722222 -54.401056)
			(xy 356.702299 -54.348965) (xy 356.690173 -54.294528) (xy 356.686102 -54.238906) (xy 337.863487 -54.238906)
			(xy 337.856213 -54.254422) (xy 337.82544 -54.300935) (xy 337.788223 -54.342472) (xy 337.745355 -54.378147)
			(xy 337.697749 -54.407201) (xy 337.64642 -54.429013) (xy 337.592463 -54.443119) (xy 337.537026 -54.449219)
			(xy 337.481292 -54.447182) (xy 337.426449 -54.437052) (xy 337.373665 -54.419045) (xy 337.324065 -54.393544)
			(xy 337.278707 -54.361093) (xy 337.238558 -54.322384) (xy 337.204472 -54.278241) (xy 337.177176 -54.229606)
			(xy 337.157253 -54.177515) (xy 337.145127 -54.123078) (xy 337.141056 -54.067456) (xy 335.720528 -54.067456)
			(xy 335.710725 -54.100039) (xy 335.687053 -54.150536) (xy 335.65628 -54.197049) (xy 335.619063 -54.238586)
			(xy 335.576195 -54.274261) (xy 335.528589 -54.303315) (xy 335.47726 -54.325127) (xy 335.423303 -54.339233)
			(xy 335.367866 -54.345333) (xy 335.312132 -54.343296) (xy 335.257289 -54.333166) (xy 335.204505 -54.315159)
			(xy 335.154905 -54.289658) (xy 335.109547 -54.257207) (xy 335.069398 -54.218498) (xy 335.035312 -54.174355)
			(xy 335.008016 -54.12572) (xy 334.988093 -54.073629) (xy 334.975967 -54.019192) (xy 334.971896 -53.96357)
			(xy 330.992718 -53.96357) (xy 331.010285 -54.002034) (xy 331.02564 -54.054329) (xy 331.033396 -54.108277)
			(xy 331.033882 -54.135528) (xy 331.033402 -54.162861) (xy 331.025596 -54.216968) (xy 331.010149 -54.269407)
			(xy 330.987377 -54.319105) (xy 330.957745 -54.365044) (xy 330.940156 -54.385972) (xy 330.939902 -54.386226)
			(xy 330.939648 -54.38648) (xy 330.934057 -54.393564) (xy 330.927814 -54.410483) (xy 330.927456 -54.4195)
			(xy 330.927456 -54.486556) (xy 330.927822 -54.495572) (xy 330.934062 -54.51249) (xy 330.939648 -54.519576)
			(xy 330.939902 -54.51983) (xy 330.940156 -54.520084) (xy 330.957748 -54.541011) (xy 330.987388 -54.586947)
			(xy 331.010165 -54.636644) (xy 331.025613 -54.689085) (xy 331.033415 -54.743194) (xy 331.033882 -54.770528)
			(xy 331.033396 -54.797779) (xy 331.02564 -54.851727) (xy 331.010285 -54.904022) (xy 330.987643 -54.953599)
			(xy 330.958177 -54.999449) (xy 330.922486 -55.04064) (xy 330.881295 -55.076331) (xy 330.870208 -55.083456)
			(xy 337.141056 -55.083456) (xy 337.145127 -55.027834) (xy 337.157253 -54.973397) (xy 337.177176 -54.921306)
			(xy 337.204472 -54.872671) (xy 337.238558 -54.828528) (xy 337.278707 -54.789819) (xy 337.324065 -54.757368)
			(xy 337.373665 -54.731867) (xy 337.426449 -54.71386) (xy 337.481292 -54.70373) (xy 337.537026 -54.701693)
			(xy 337.592463 -54.707793) (xy 337.64642 -54.721899) (xy 337.697749 -54.743711) (xy 337.745355 -54.772765)
			(xy 337.788223 -54.80844) (xy 337.82544 -54.849977) (xy 337.856213 -54.89649) (xy 337.879885 -54.946987)
			(xy 337.892542 -54.989055) (xy 352.201145 -54.989055) (xy 352.201145 -54.934545) (xy 352.208903 -54.880591)
			(xy 352.224261 -54.828289) (xy 352.246906 -54.778706) (xy 352.276377 -54.73285) (xy 352.312074 -54.691656)
			(xy 352.353271 -54.655961) (xy 352.399129 -54.626493) (xy 352.448714 -54.603851) (xy 352.501016 -54.588497)
			(xy 352.554971 -54.580743) (xy 352.582226 -54.580282) (xy 352.610318 -54.580756) (xy 352.665896 -54.588987)
			(xy 352.719666 -54.605282) (xy 352.770463 -54.629288) (xy 352.81719 -54.660486) (xy 352.858835 -54.698201)
			(xy 352.894496 -54.741616) (xy 352.909378 -54.765448) (xy 352.914966 -54.774592) (xy 352.931984 -54.786784)
			(xy 353.024948 -54.80685) (xy 353.045522 -54.802786) (xy 353.054158 -54.79669) (xy 353.078231 -54.780705)
			(xy 353.130159 -54.755359) (xy 353.185314 -54.738129) (xy 353.242436 -54.729409) (xy 353.271328 -54.728872)
			(xy 353.298579 -54.729352) (xy 353.3129 -54.731412) (xy 361.820714 -54.731412) (xy 361.82116 -54.704077)
			(xy 361.828974 -54.649969) (xy 361.844429 -54.59753) (xy 361.867209 -54.547833) (xy 361.896848 -54.501895)
			(xy 361.91444 -54.480968) (xy 361.914694 -54.480714) (xy 361.914948 -54.48046) (xy 361.920521 -54.473365)
			(xy 361.926775 -54.456454) (xy 361.92714 -54.44744) (xy 361.92714 -54.380384) (xy 361.926803 -54.371365)
			(xy 361.920543 -54.354447) (xy 361.914948 -54.347364) (xy 361.914694 -54.34711) (xy 361.91444 -54.346856)
			(xy 361.896853 -54.325924) (xy 361.867201 -54.279992) (xy 361.844414 -54.230296) (xy 361.828957 -54.177855)
			(xy 361.821148 -54.123745) (xy 361.821146 -54.069073) (xy 361.828953 -54.014962) (xy 361.844407 -53.962521)
			(xy 361.867193 -53.912824) (xy 361.896842 -53.866891) (xy 361.91444 -53.845968) (xy 361.914694 -53.845714)
			(xy 361.914948 -53.84546) (xy 361.920521 -53.838365) (xy 361.926775 -53.821454) (xy 361.92714 -53.81244)
			(xy 361.92714 -53.745384) (xy 361.926803 -53.736365) (xy 361.920543 -53.719447) (xy 361.914948 -53.712364)
			(xy 361.914694 -53.71211) (xy 361.91444 -53.711856) (xy 361.896853 -53.690924) (xy 361.867201 -53.644992)
			(xy 361.844414 -53.595296) (xy 361.828957 -53.542855) (xy 361.821148 -53.488745) (xy 361.821146 -53.434073)
			(xy 361.828953 -53.379962) (xy 361.844407 -53.327521) (xy 361.867193 -53.277824) (xy 361.896842 -53.231891)
			(xy 361.91444 -53.210968) (xy 361.914694 -53.210714) (xy 361.914948 -53.21046) (xy 361.920521 -53.203365)
			(xy 361.926775 -53.186454) (xy 361.92714 -53.17744) (xy 361.92714 -53.110384) (xy 361.926803 -53.101365)
			(xy 361.920543 -53.084447) (xy 361.914948 -53.077364) (xy 361.914694 -53.07711) (xy 361.91444 -53.076856)
			(xy 361.896867 -53.055915) (xy 361.867224 -53.009983) (xy 361.844443 -52.960289) (xy 361.828991 -52.907852)
			(xy 361.821184 -52.853745) (xy 361.820714 -52.826412) (xy 361.8212 -52.799161) (xy 361.828956 -52.745213)
			(xy 361.844311 -52.692918) (xy 361.866953 -52.643341) (xy 361.896419 -52.597491) (xy 361.93211 -52.5563)
			(xy 361.973301 -52.520609) (xy 362.019151 -52.491143) (xy 362.068728 -52.468501) (xy 362.121023 -52.453146)
			(xy 362.174971 -52.44539) (xy 362.229473 -52.44539) (xy 362.283421 -52.453146) (xy 362.335716 -52.468501)
			(xy 362.385293 -52.491143) (xy 362.431143 -52.520609) (xy 362.472334 -52.5563) (xy 362.508025 -52.597491)
			(xy 362.537491 -52.643341) (xy 362.560133 -52.692918) (xy 362.575488 -52.745213) (xy 362.583244 -52.799161)
			(xy 362.58373 -52.826412) (xy 362.583253 -52.853746) (xy 362.575449 -52.907853) (xy 362.560002 -52.960293)
			(xy 362.537228 -53.00999) (xy 362.507594 -53.055929) (xy 362.490004 -53.076856) (xy 362.48975 -53.07711)
			(xy 362.489496 -53.077364) (xy 362.483918 -53.084456) (xy 362.477666 -53.101369) (xy 362.477304 -53.110384)
			(xy 362.477304 -53.17744) (xy 362.477641 -53.186459) (xy 362.483903 -53.203376) (xy 362.489496 -53.21046)
			(xy 362.48975 -53.210714) (xy 362.490004 -53.210968) (xy 362.507617 -53.23188) (xy 362.537272 -53.277814)
			(xy 362.560061 -53.327513) (xy 362.575519 -53.379957) (xy 362.583327 -53.434072) (xy 362.583326 -53.488746)
			(xy 362.575515 -53.54286) (xy 362.560055 -53.595304) (xy 362.537263 -53.645002) (xy 362.507606 -53.690934)
			(xy 362.490004 -53.711856) (xy 362.48975 -53.71211) (xy 362.489496 -53.712364) (xy 362.483918 -53.719456)
			(xy 362.477666 -53.736369) (xy 362.477304 -53.745384) (xy 362.477304 -53.81244) (xy 362.477641 -53.821459)
			(xy 362.483903 -53.838376) (xy 362.489496 -53.84546) (xy 362.48975 -53.845714) (xy 362.490004 -53.845968)
			(xy 362.507617 -53.86688) (xy 362.537272 -53.912814) (xy 362.560061 -53.962513) (xy 362.575519 -54.014957)
			(xy 362.583327 -54.069072) (xy 362.583326 -54.123746) (xy 362.575515 -54.17786) (xy 362.560055 -54.230304)
			(xy 362.537263 -54.280002) (xy 362.507606 -54.325934) (xy 362.490004 -54.346856) (xy 362.48975 -54.34711)
			(xy 362.489496 -54.347364) (xy 362.483918 -54.354456) (xy 362.477666 -54.371369) (xy 362.477304 -54.380384)
			(xy 362.477304 -54.44744) (xy 362.477641 -54.456459) (xy 362.483903 -54.473376) (xy 362.489496 -54.48046)
			(xy 362.48975 -54.480714) (xy 362.490004 -54.480968) (xy 362.507596 -54.501894) (xy 362.537234 -54.547831)
			(xy 362.56001 -54.597529) (xy 362.575458 -54.649969) (xy 362.583261 -54.704078) (xy 362.58373 -54.731412)
			(xy 362.583244 -54.758663) (xy 362.57858 -54.791102) (xy 364.476538 -54.791102) (xy 364.477031 -54.763769)
			(xy 364.484833 -54.709663) (xy 364.500276 -54.657224) (xy 364.523046 -54.607525) (xy 364.552676 -54.561586)
			(xy 364.570264 -54.540658) (xy 364.570518 -54.540404) (xy 364.570772 -54.54015) (xy 364.576352 -54.533059)
			(xy 364.582601 -54.516145) (xy 364.582964 -54.50713) (xy 364.582964 -54.440074) (xy 364.582627 -54.431055)
			(xy 364.576367 -54.414138) (xy 364.570772 -54.407054) (xy 364.570518 -54.4068) (xy 364.570264 -54.406546)
			(xy 364.552666 -54.385622) (xy 364.523013 -54.339689) (xy 364.500225 -54.289992) (xy 364.484768 -54.23755)
			(xy 364.476959 -54.183438) (xy 364.476959 -54.128765) (xy 364.484767 -54.074653) (xy 364.500224 -54.02221)
			(xy 364.523012 -53.972513) (xy 364.552664 -53.92658) (xy 364.570264 -53.905658) (xy 364.570518 -53.905404)
			(xy 364.570772 -53.90515) (xy 364.576352 -53.898059) (xy 364.582601 -53.881145) (xy 364.582964 -53.87213)
			(xy 364.582964 -53.805074) (xy 364.582627 -53.796055) (xy 364.576367 -53.779138) (xy 364.570772 -53.772054)
			(xy 364.570518 -53.7718) (xy 364.570264 -53.771546) (xy 364.552666 -53.750622) (xy 364.523013 -53.704689)
			(xy 364.500225 -53.654992) (xy 364.484768 -53.60255) (xy 364.476959 -53.548438) (xy 364.476959 -53.493765)
			(xy 364.484767 -53.439653) (xy 364.500224 -53.38721) (xy 364.523012 -53.337513) (xy 364.552664 -53.29158)
			(xy 364.570264 -53.270658) (xy 364.570518 -53.270404) (xy 364.570772 -53.27015) (xy 364.576352 -53.263059)
			(xy 364.582601 -53.246145) (xy 364.582964 -53.23713) (xy 364.582964 -53.170074) (xy 364.582627 -53.161055)
			(xy 364.576367 -53.144138) (xy 364.570772 -53.137054) (xy 364.570518 -53.1368) (xy 364.570264 -53.136546)
			(xy 364.552674 -53.115618) (xy 364.523037 -53.069681) (xy 364.50026 -53.019984) (xy 364.484812 -52.967544)
			(xy 364.477007 -52.913436) (xy 364.476538 -52.886102) (xy 364.477024 -52.858851) (xy 364.48478 -52.804903)
			(xy 364.500135 -52.752608) (xy 364.522777 -52.703031) (xy 364.552243 -52.657181) (xy 364.587934 -52.61599)
			(xy 364.629125 -52.580299) (xy 364.674975 -52.550833) (xy 364.724552 -52.528191) (xy 364.776847 -52.512836)
			(xy 364.830795 -52.50508) (xy 364.885297 -52.50508) (xy 364.939245 -52.512836) (xy 364.953563 -52.51704)
			(xy 369.14023 -52.51704) (xy 369.144301 -52.461418) (xy 369.156427 -52.406981) (xy 369.17635 -52.35489)
			(xy 369.203646 -52.306255) (xy 369.237732 -52.262112) (xy 369.277881 -52.223403) (xy 369.323239 -52.190952)
			(xy 369.372839 -52.165451) (xy 369.425623 -52.147444) (xy 369.480466 -52.137314) (xy 369.5362 -52.135277)
			(xy 369.591637 -52.141377) (xy 369.645594 -52.155483) (xy 369.696923 -52.177295) (xy 369.744529 -52.206349)
			(xy 369.787397 -52.242024) (xy 369.824614 -52.283561) (xy 369.855387 -52.330074) (xy 369.879059 -52.380571)
			(xy 369.895127 -52.433978) (xy 369.903247 -52.489154) (xy 369.903756 -52.51704) (xy 369.903247 -52.544926)
			(xy 369.896997 -52.587398) (xy 373.055386 -52.587398) (xy 373.059457 -52.531776) (xy 373.071583 -52.477339)
			(xy 373.091506 -52.425248) (xy 373.118802 -52.376613) (xy 373.152888 -52.33247) (xy 373.193037 -52.293761)
			(xy 373.238395 -52.26131) (xy 373.287995 -52.235809) (xy 373.340779 -52.217802) (xy 373.395622 -52.207672)
			(xy 373.451356 -52.205635) (xy 373.506793 -52.211735) (xy 373.56075 -52.225841) (xy 373.612079 -52.247653)
			(xy 373.659685 -52.276707) (xy 373.702553 -52.312382) (xy 373.73977 -52.353919) (xy 373.770543 -52.400432)
			(xy 373.794215 -52.450929) (xy 373.810283 -52.504336) (xy 373.818403 -52.559512) (xy 373.818488 -52.564153)
			(xy 378.12723 -52.564153) (xy 378.12723 -52.509647) (xy 378.134986 -52.455696) (xy 378.150341 -52.403398)
			(xy 378.172982 -52.353817) (xy 378.202449 -52.307963) (xy 378.23814 -52.266769) (xy 378.279331 -52.231073)
			(xy 378.325182 -52.201602) (xy 378.37476 -52.178955) (xy 378.427057 -52.163595) (xy 378.481007 -52.155833)
			(xy 378.50826 -52.155344) (xy 378.53563 -52.155823) (xy 378.589809 -52.163636) (xy 378.642312 -52.179121)
			(xy 378.692059 -52.201961) (xy 378.738026 -52.231683) (xy 378.758958 -52.249324) (xy 378.759212 -52.249578)
			(xy 378.766284 -52.255185) (xy 378.783212 -52.261417) (xy 378.792232 -52.26177) (xy 378.859288 -52.26177)
			(xy 378.868305 -52.261414) (xy 378.885222 -52.255166) (xy 378.892308 -52.249578) (xy 378.892816 -52.24907)
			(xy 378.913721 -52.231452) (xy 378.959664 -52.201818) (xy 379.009367 -52.179048) (xy 379.061812 -52.163606)
			(xy 379.115924 -52.155809) (xy 379.14326 -52.155344) (xy 379.170511 -52.1559) (xy 379.22446 -52.163652)
			(xy 379.276756 -52.179002) (xy 379.326335 -52.20164) (xy 379.372187 -52.231103) (xy 379.413379 -52.266792)
			(xy 379.449073 -52.307981) (xy 379.478541 -52.35383) (xy 379.501184 -52.403407) (xy 379.51654 -52.455701)
			(xy 379.524297 -52.509649) (xy 379.524297 -52.555952) (xy 380.883879 -52.555952) (xy 380.883879 -52.501448)
			(xy 380.891636 -52.447498) (xy 380.906993 -52.395202) (xy 380.929635 -52.345624) (xy 380.959103 -52.299772)
			(xy 380.994797 -52.258582) (xy 381.03599 -52.22289) (xy 381.081843 -52.193425) (xy 381.131423 -52.170785)
			(xy 381.18372 -52.155432) (xy 381.23767 -52.147678) (xy 381.264922 -52.147216) (xy 381.292293 -52.147665)
			(xy 381.346473 -52.155487) (xy 381.398976 -52.170979) (xy 381.448723 -52.193825) (xy 381.494689 -52.223553)
			(xy 381.51562 -52.241196) (xy 381.515874 -52.24145) (xy 381.522959 -52.247038) (xy 381.539877 -52.253283)
			(xy 381.548894 -52.253642) (xy 381.61595 -52.253642) (xy 381.624966 -52.253274) (xy 381.641884 -52.247035)
			(xy 381.64897 -52.24145) (xy 381.649478 -52.240942) (xy 381.670407 -52.223353) (xy 381.716342 -52.193713)
			(xy 381.766039 -52.170935) (xy 381.818479 -52.155486) (xy 381.872588 -52.147684) (xy 381.899922 -52.147216)
			(xy 381.927174 -52.147655) (xy 381.981123 -52.155415) (xy 382.033418 -52.170773) (xy 382.082996 -52.193417)
			(xy 382.128846 -52.222885) (xy 382.170036 -52.258579) (xy 382.205728 -52.299771) (xy 382.235194 -52.345624)
			(xy 382.257835 -52.395203) (xy 382.27319 -52.447499) (xy 382.280946 -52.501448) (xy 382.280946 -52.555952)
			(xy 382.27319 -52.609901) (xy 382.257835 -52.662197) (xy 382.235194 -52.711776) (xy 382.205728 -52.757629)
			(xy 382.170036 -52.798821) (xy 382.128846 -52.834515) (xy 382.082996 -52.863983) (xy 382.033418 -52.886627)
			(xy 381.981123 -52.901985) (xy 381.927174 -52.909745) (xy 381.899922 -52.910232) (xy 381.872551 -52.90977)
			(xy 381.818372 -52.901953) (xy 381.765868 -52.886464) (xy 381.716121 -52.863621) (xy 381.670155 -52.833895)
			(xy 381.649224 -52.816252) (xy 381.64897 -52.815998) (xy 381.641868 -52.810434) (xy 381.624963 -52.804174)
			(xy 381.61595 -52.803806) (xy 381.548894 -52.803806) (xy 381.539877 -52.804159) (xy 381.52296 -52.810409)
			(xy 381.515874 -52.815998) (xy 381.515366 -52.816506) (xy 381.494427 -52.834082) (xy 381.448494 -52.863723)
			(xy 381.398799 -52.886502) (xy 381.346362 -52.901954) (xy 381.292255 -52.909761) (xy 381.264922 -52.910232)
			(xy 381.23767 -52.909722) (xy 381.18372 -52.901968) (xy 381.131423 -52.886615) (xy 381.081843 -52.863975)
			(xy 381.03599 -52.83451) (xy 380.994797 -52.798818) (xy 380.959103 -52.757628) (xy 380.929635 -52.711776)
			(xy 380.906993 -52.662198) (xy 380.891636 -52.609902) (xy 380.883879 -52.555952) (xy 379.524297 -52.555952)
			(xy 379.524297 -52.564151) (xy 379.51654 -52.618099) (xy 379.501184 -52.670393) (xy 379.478541 -52.71997)
			(xy 379.449073 -52.765819) (xy 379.413379 -52.807008) (xy 379.372187 -52.842697) (xy 379.326335 -52.87216)
			(xy 379.276756 -52.894798) (xy 379.22446 -52.910148) (xy 379.170511 -52.9179) (xy 379.14326 -52.91836)
			(xy 379.115891 -52.917869) (xy 379.061712 -52.910058) (xy 379.009209 -52.894576) (xy 378.959462 -52.871739)
			(xy 378.913494 -52.842019) (xy 378.892562 -52.82438) (xy 378.892308 -52.824126) (xy 378.88523 -52.818528)
			(xy 378.868306 -52.81229) (xy 378.859288 -52.811934) (xy 378.792232 -52.811934) (xy 378.783216 -52.812299)
			(xy 378.766298 -52.81854) (xy 378.759212 -52.824126) (xy 378.758704 -52.824634) (xy 378.737792 -52.842243)
			(xy 378.691851 -52.871878) (xy 378.642149 -52.894651) (xy 378.589706 -52.910095) (xy 378.535595 -52.917894)
			(xy 378.50826 -52.91836) (xy 378.481007 -52.917967) (xy 378.427057 -52.910205) (xy 378.37476 -52.894845)
			(xy 378.325182 -52.872198) (xy 378.279331 -52.842727) (xy 378.23814 -52.807031) (xy 378.202449 -52.765837)
			(xy 378.172982 -52.719983) (xy 378.150341 -52.670402) (xy 378.134986 -52.618104) (xy 378.12723 -52.564153)
			(xy 373.818488 -52.564153) (xy 373.818912 -52.587398) (xy 373.818403 -52.615284) (xy 373.810283 -52.67046)
			(xy 373.794215 -52.723867) (xy 373.770543 -52.774364) (xy 373.73977 -52.820877) (xy 373.702553 -52.862414)
			(xy 373.659685 -52.898089) (xy 373.612079 -52.927143) (xy 373.56075 -52.948955) (xy 373.506793 -52.963061)
			(xy 373.451356 -52.969161) (xy 373.395622 -52.967124) (xy 373.340779 -52.956994) (xy 373.287995 -52.938987)
			(xy 373.238395 -52.913486) (xy 373.193037 -52.881035) (xy 373.152888 -52.842326) (xy 373.118802 -52.798183)
			(xy 373.091506 -52.749548) (xy 373.071583 -52.697457) (xy 373.059457 -52.64302) (xy 373.055386 -52.587398)
			(xy 369.896997 -52.587398) (xy 369.895127 -52.600102) (xy 369.879059 -52.653509) (xy 369.855387 -52.704006)
			(xy 369.824614 -52.750519) (xy 369.787397 -52.792056) (xy 369.744529 -52.827731) (xy 369.696923 -52.856785)
			(xy 369.645594 -52.878597) (xy 369.591637 -52.892703) (xy 369.5362 -52.898803) (xy 369.480466 -52.896766)
			(xy 369.425623 -52.886636) (xy 369.372839 -52.868629) (xy 369.323239 -52.843128) (xy 369.277881 -52.810677)
			(xy 369.237732 -52.771968) (xy 369.203646 -52.727825) (xy 369.17635 -52.67919) (xy 369.156427 -52.627099)
			(xy 369.144301 -52.572662) (xy 369.14023 -52.51704) (xy 364.953563 -52.51704) (xy 364.99154 -52.528191)
			(xy 365.041117 -52.550833) (xy 365.086967 -52.580299) (xy 365.128158 -52.61599) (xy 365.163849 -52.657181)
			(xy 365.193315 -52.703031) (xy 365.215957 -52.752608) (xy 365.231312 -52.804903) (xy 365.239068 -52.858851)
			(xy 365.239554 -52.886102) (xy 365.239065 -52.913435) (xy 365.231263 -52.967542) (xy 365.215818 -53.019981)
			(xy 365.193047 -53.069679) (xy 365.163417 -53.115618) (xy 365.145828 -53.136546) (xy 365.145574 -53.1368)
			(xy 365.14532 -53.137054) (xy 365.139737 -53.144143) (xy 365.13349 -53.161058) (xy 365.133128 -53.170074)
			(xy 365.133128 -53.23713) (xy 365.133465 -53.246149) (xy 365.139726 -53.263066) (xy 365.14532 -53.27015)
			(xy 365.145574 -53.270404) (xy 365.145828 -53.270658) (xy 365.16343 -53.291578) (xy 365.193084 -53.337512)
			(xy 365.215872 -53.387209) (xy 365.231329 -53.439652) (xy 365.239138 -53.493765) (xy 365.239138 -53.548438)
			(xy 365.231329 -53.602551) (xy 365.215871 -53.654994) (xy 365.193082 -53.704691) (xy 365.163429 -53.750624)
			(xy 365.146683 -53.77053) (xy 365.510826 -53.77053) (xy 365.511356 -53.741613) (xy 365.520081 -53.684442)
			(xy 365.537336 -53.629243) (xy 365.562726 -53.577281) (xy 365.595668 -53.529747) (xy 365.635407 -53.48773)
			(xy 365.657892 -53.46954) (xy 365.665269 -53.463249) (xy 365.675069 -53.44654) (xy 365.676942 -53.437028)
			(xy 365.67745 -53.429408) (xy 365.67745 -53.349652) (xy 365.676942 -53.342032) (xy 365.675072 -53.332519)
			(xy 365.665275 -53.315804) (xy 365.657892 -53.30952) (xy 365.635416 -53.29132) (xy 365.595681 -53.249302)
			(xy 365.562741 -53.201769) (xy 365.537352 -53.149809) (xy 365.520094 -53.094613) (xy 365.511362 -53.037445)
			(xy 365.510826 -53.00853) (xy 365.511283 -52.981276) (xy 365.519037 -52.927323) (xy 365.534391 -52.875023)
			(xy 365.557033 -52.825441) (xy 365.586501 -52.779586) (xy 365.622195 -52.738392) (xy 365.663389 -52.702698)
			(xy 365.709245 -52.673231) (xy 365.758827 -52.65059) (xy 365.811127 -52.635236) (xy 365.86508 -52.627483)
			(xy 365.892334 -52.627022) (xy 365.892588 -52.627022) (xy 365.918883 -52.627482) (xy 365.970972 -52.634726)
			(xy 366.021573 -52.649051) (xy 366.06973 -52.670186) (xy 366.114529 -52.697732) (xy 366.155124 -52.731165)
			(xy 366.173258 -52.750212) (xy 366.180845 -52.757635) (xy 366.200251 -52.76617) (xy 366.21085 -52.766722)
			(xy 366.285018 -52.766722) (xy 366.295649 -52.766308) (xy 366.315113 -52.757761) (xy 366.32261 -52.750212)
			(xy 366.340727 -52.731145) (xy 366.381311 -52.697689) (xy 366.42611 -52.670131) (xy 366.474272 -52.648993)
			(xy 366.524883 -52.634679) (xy 366.576982 -52.627458) (xy 366.60328 -52.627022) (xy 366.603534 -52.627022)
			(xy 366.630787 -52.627446) (xy 366.684739 -52.635208) (xy 366.737037 -52.650569) (xy 366.786616 -52.673216)
			(xy 366.832468 -52.702689) (xy 366.873658 -52.738387) (xy 366.909349 -52.779584) (xy 366.938814 -52.82544)
			(xy 366.961453 -52.875023) (xy 366.976805 -52.927324) (xy 366.984558 -52.981276) (xy 366.985042 -53.00853)
			(xy 366.98458 -53.036197) (xy 366.982349 -53.051456) (xy 375.24131 -53.051456) (xy 375.245381 -52.995834)
			(xy 375.257507 -52.941397) (xy 375.27743 -52.889306) (xy 375.304726 -52.840671) (xy 375.338812 -52.796528)
			(xy 375.378961 -52.757819) (xy 375.424319 -52.725368) (xy 375.473919 -52.699867) (xy 375.526703 -52.68186)
			(xy 375.581546 -52.67173) (xy 375.63728 -52.669693) (xy 375.692717 -52.675793) (xy 375.746674 -52.689899)
			(xy 375.798003 -52.711711) (xy 375.845609 -52.740765) (xy 375.888477 -52.77644) (xy 375.925694 -52.817977)
			(xy 375.956467 -52.86449) (xy 375.980139 -52.914987) (xy 375.996207 -52.968394) (xy 376.004327 -53.02357)
			(xy 376.004836 -53.051456) (xy 376.004327 -53.079342) (xy 375.996207 -53.134518) (xy 375.980139 -53.187925)
			(xy 375.956467 -53.238422) (xy 375.925694 -53.284935) (xy 375.888477 -53.326472) (xy 375.845609 -53.362147)
			(xy 375.798003 -53.391201) (xy 375.746674 -53.413013) (xy 375.692717 -53.427119) (xy 375.63728 -53.433219)
			(xy 375.581546 -53.431182) (xy 375.526703 -53.421052) (xy 375.473919 -53.403045) (xy 375.424319 -53.377544)
			(xy 375.378961 -53.345093) (xy 375.338812 -53.306384) (xy 375.304726 -53.262241) (xy 375.27743 -53.213606)
			(xy 375.257507 -53.161515) (xy 375.245381 -53.107078) (xy 375.24131 -53.051456) (xy 366.982349 -53.051456)
			(xy 366.976575 -53.09095) (xy 366.960752 -53.143974) (xy 366.937441 -53.194159) (xy 366.907131 -53.240454)
			(xy 366.870457 -53.28189) (xy 366.828187 -53.317599) (xy 366.804956 -53.332634) (xy 366.804702 -53.332888)
			(xy 366.795178 -53.339555) (xy 366.78287 -53.359248) (xy 366.78108 -53.370734) (xy 366.773206 -53.450744)
			(xy 366.77254 -53.462445) (xy 366.780621 -53.484417) (xy 366.7887 -53.492908) (xy 366.788954 -53.492908)
			(xy 366.807513 -53.511012) (xy 366.840095 -53.551337) (xy 366.866912 -53.595707) (xy 366.887469 -53.643301)
			(xy 366.901387 -53.693242) (xy 366.908408 -53.744608) (xy 366.908842 -53.77053) (xy 366.90835 -53.79778)
			(xy 366.90059 -53.851726) (xy 366.885233 -53.904019) (xy 366.862591 -53.953594) (xy 366.833125 -53.999442)
			(xy 366.797434 -54.040631) (xy 366.756246 -54.076322) (xy 366.710397 -54.105789) (xy 366.660822 -54.128432)
			(xy 366.60853 -54.14379) (xy 366.554584 -54.15155) (xy 366.527334 -54.152038) (xy 366.499964 -54.151567)
			(xy 366.445784 -54.143753) (xy 366.393281 -54.128266) (xy 366.343534 -54.105425) (xy 366.297567 -54.0757)
			(xy 366.276636 -54.058058) (xy 366.276382 -54.057804) (xy 366.269304 -54.052204) (xy 366.252381 -54.045965)
			(xy 366.243362 -54.045612) (xy 366.176306 -54.045612) (xy 366.167289 -54.045969) (xy 366.150372 -54.052216)
			(xy 366.143286 -54.057804) (xy 366.142778 -54.058312) (xy 366.121835 -54.075883) (xy 366.075903 -54.105524)
			(xy 366.026209 -54.128305) (xy 365.973773 -54.143757) (xy 365.919667 -54.151566) (xy 365.892334 -54.152038)
			(xy 365.865083 -54.151513) (xy 365.811136 -54.143762) (xy 365.758841 -54.128411) (xy 365.709263 -54.105775)
			(xy 365.663411 -54.076313) (xy 365.622219 -54.040626) (xy 365.586525 -53.99944) (xy 365.557056 -53.953593)
			(xy 365.534411 -53.904019) (xy 365.519052 -53.851726) (xy 365.511291 -53.797781) (xy 365.510826 -53.77053)
			(xy 365.146683 -53.77053) (xy 365.145828 -53.771546) (xy 365.145574 -53.7718) (xy 365.14532 -53.772054)
			(xy 365.139737 -53.779143) (xy 365.13349 -53.796058) (xy 365.133128 -53.805074) (xy 365.133128 -53.87213)
			(xy 365.133465 -53.881149) (xy 365.139726 -53.898066) (xy 365.14532 -53.90515) (xy 365.145574 -53.905404)
			(xy 365.145828 -53.905658) (xy 365.16343 -53.926578) (xy 365.193084 -53.972512) (xy 365.215872 -54.022209)
			(xy 365.231329 -54.074652) (xy 365.239138 -54.128765) (xy 365.239138 -54.183438) (xy 365.231329 -54.237551)
			(xy 365.215871 -54.289994) (xy 365.202026 -54.320186) (xy 367.430558 -54.320186) (xy 367.431037 -54.292852)
			(xy 367.438841 -54.238745) (xy 367.454288 -54.186306) (xy 367.477061 -54.136608) (xy 367.506694 -54.090669)
			(xy 367.524284 -54.069742) (xy 367.524538 -54.069488) (xy 367.524792 -54.069234) (xy 367.53037 -54.062141)
			(xy 367.536622 -54.045229) (xy 367.536984 -54.036214) (xy 367.536984 -53.969158) (xy 367.536603 -53.960144)
			(xy 367.530372 -53.943226) (xy 367.524792 -53.936138) (xy 367.524538 -53.935884) (xy 367.524284 -53.93563)
			(xy 367.50669 -53.914706) (xy 367.477052 -53.868768) (xy 367.454276 -53.81907) (xy 367.438829 -53.766629)
			(xy 367.431026 -53.71252) (xy 367.430558 -53.685186) (xy 367.431044 -53.657935) (xy 367.4388 -53.603987)
			(xy 367.454155 -53.551692) (xy 367.476797 -53.502115) (xy 367.506263 -53.456265) (xy 367.541954 -53.415074)
			(xy 367.583145 -53.379383) (xy 367.628995 -53.349917) (xy 367.678572 -53.327275) (xy 367.730867 -53.31192)
			(xy 367.784815 -53.304164) (xy 367.839317 -53.304164) (xy 367.893265 -53.31192) (xy 367.94556 -53.327275)
			(xy 367.995137 -53.349917) (xy 368.040987 -53.379383) (xy 368.082178 -53.415074) (xy 368.117869 -53.456265)
			(xy 368.143759 -53.496551) (xy 380.433564 -53.496551) (xy 380.433564 -53.442049) (xy 380.44132 -53.388101)
			(xy 380.456675 -53.335806) (xy 380.479315 -53.286228) (xy 380.508781 -53.240377) (xy 380.544471 -53.199186)
			(xy 380.585661 -53.163493) (xy 380.63151 -53.134025) (xy 380.681087 -53.111382) (xy 380.733381 -53.096024)
			(xy 380.787329 -53.088265) (xy 380.81458 -53.087778) (xy 380.841951 -53.088237) (xy 380.896131 -53.096053)
			(xy 380.948635 -53.111543) (xy 380.998382 -53.134387) (xy 381.044347 -53.164115) (xy 381.065278 -53.181758)
			(xy 381.065532 -53.182012) (xy 381.072633 -53.187578) (xy 381.089539 -53.193837) (xy 381.098552 -53.194204)
			(xy 381.165608 -53.194204) (xy 381.174625 -53.19385) (xy 381.191542 -53.1876) (xy 381.198628 -53.182012)
			(xy 381.199136 -53.181504) (xy 381.220076 -53.163929) (xy 381.266009 -53.134288) (xy 381.315703 -53.111508)
			(xy 381.36814 -53.096056) (xy 381.422247 -53.088249) (xy 381.44958 -53.087778) (xy 381.476833 -53.088268)
			(xy 381.530784 -53.096022) (xy 381.583082 -53.111376) (xy 381.632663 -53.134017) (xy 381.678517 -53.163483)
			(xy 381.719711 -53.199175) (xy 381.755405 -53.240367) (xy 381.784874 -53.286219) (xy 381.807517 -53.335799)
			(xy 381.822873 -53.388097) (xy 381.830631 -53.442047) (xy 381.830631 -53.496553) (xy 381.822873 -53.550503)
			(xy 381.807517 -53.602801) (xy 381.784874 -53.652381) (xy 381.755405 -53.698233) (xy 381.719711 -53.739425)
			(xy 381.678517 -53.775117) (xy 381.632663 -53.804583) (xy 381.583082 -53.827224) (xy 381.530784 -53.842578)
			(xy 381.476833 -53.850332) (xy 381.44958 -53.850794) (xy 381.422209 -53.850341) (xy 381.36803 -53.84252)
			(xy 381.315526 -53.827028) (xy 381.26578 -53.804184) (xy 381.219813 -53.774456) (xy 381.198882 -53.756814)
			(xy 381.198628 -53.75656) (xy 381.191541 -53.750974) (xy 381.174624 -53.744728) (xy 381.165608 -53.744368)
			(xy 381.098552 -53.744368) (xy 381.089538 -53.744757) (xy 381.072622 -53.750983) (xy 381.065532 -53.75656)
			(xy 381.065024 -53.757068) (xy 381.044096 -53.774658) (xy 380.99816 -53.804298) (xy 380.948463 -53.827075)
			(xy 380.896023 -53.842523) (xy 380.841914 -53.850326) (xy 380.81458 -53.850794) (xy 380.787329 -53.850335)
			(xy 380.733381 -53.842576) (xy 380.681087 -53.827218) (xy 380.63151 -53.804575) (xy 380.585661 -53.775107)
			(xy 380.544471 -53.739414) (xy 380.508781 -53.698223) (xy 380.479315 -53.652372) (xy 380.456675 -53.602794)
			(xy 380.44132 -53.550499) (xy 380.433564 -53.496551) (xy 368.143759 -53.496551) (xy 368.147335 -53.502115)
			(xy 368.169977 -53.551692) (xy 368.185332 -53.603987) (xy 368.193088 -53.657935) (xy 368.193574 -53.685186)
			(xy 368.19313 -53.712521) (xy 368.185316 -53.766629) (xy 368.16986 -53.819069) (xy 368.14708 -53.868766)
			(xy 368.11744 -53.914704) (xy 368.099848 -53.93563) (xy 368.099594 -53.935884) (xy 368.09934 -53.936138)
			(xy 368.093766 -53.943233) (xy 368.087513 -53.960144) (xy 368.087148 -53.969158) (xy 368.087148 -54.036214)
			(xy 368.087488 -54.045233) (xy 368.093746 -54.06215) (xy 368.09934 -54.069234) (xy 368.099594 -54.069488)
			(xy 368.099848 -54.069742) (xy 368.117434 -54.090673) (xy 368.147072 -54.136609) (xy 368.169849 -54.186306)
			(xy 368.185298 -54.238745) (xy 368.193104 -54.292852) (xy 368.193574 -54.320186) (xy 368.193088 -54.347437)
			(xy 368.185332 -54.401385) (xy 368.169977 -54.45368) (xy 368.147335 -54.503257) (xy 368.117869 -54.549107)
			(xy 368.082178 -54.590298) (xy 368.040987 -54.625989) (xy 367.995137 -54.655455) (xy 367.94556 -54.678097)
			(xy 367.893265 -54.693452) (xy 367.839317 -54.701208) (xy 367.784815 -54.701208) (xy 367.730867 -54.693452)
			(xy 367.678572 -54.678097) (xy 367.628995 -54.655455) (xy 367.583145 -54.625989) (xy 367.541954 -54.590298)
			(xy 367.506263 -54.549107) (xy 367.476797 -54.503257) (xy 367.454155 -54.45368) (xy 367.4388 -54.401385)
			(xy 367.431044 -54.347437) (xy 367.430558 -54.320186) (xy 365.202026 -54.320186) (xy 365.193082 -54.339691)
			(xy 365.163429 -54.385624) (xy 365.145828 -54.406546) (xy 365.145574 -54.4068) (xy 365.14532 -54.407054)
			(xy 365.139737 -54.414143) (xy 365.13349 -54.431058) (xy 365.133128 -54.440074) (xy 365.133128 -54.50713)
			(xy 365.133465 -54.516149) (xy 365.139726 -54.533066) (xy 365.14532 -54.54015) (xy 365.145574 -54.540404)
			(xy 365.145828 -54.540658) (xy 365.163419 -54.561585) (xy 365.193056 -54.607522) (xy 365.215833 -54.65722)
			(xy 365.231281 -54.70966) (xy 365.239085 -54.763768) (xy 365.239201 -54.770528) (xy 368.37112 -54.770528)
			(xy 368.371574 -54.743194) (xy 368.379386 -54.689086) (xy 368.394839 -54.636646) (xy 368.417617 -54.586949)
			(xy 368.447255 -54.541011) (xy 368.464846 -54.520084) (xy 368.4651 -54.51983) (xy 368.465354 -54.519576)
			(xy 368.470963 -54.512505) (xy 368.477195 -54.495576) (xy 368.477546 -54.486556) (xy 368.477546 -54.4195)
			(xy 368.477201 -54.410482) (xy 368.470946 -54.393564) (xy 368.465354 -54.38648) (xy 368.4651 -54.386226)
			(xy 368.464846 -54.385972) (xy 368.447281 -54.365024) (xy 368.417637 -54.319094) (xy 368.394855 -54.269402)
			(xy 368.3794 -54.216966) (xy 368.371591 -54.162861) (xy 368.37112 -54.135528) (xy 368.371606 -54.108277)
			(xy 368.379362 -54.054329) (xy 368.394717 -54.002034) (xy 368.417359 -53.952457) (xy 368.446825 -53.906607)
			(xy 368.482516 -53.865416) (xy 368.523707 -53.829725) (xy 368.569557 -53.800259) (xy 368.619134 -53.777617)
			(xy 368.671429 -53.762262) (xy 368.725377 -53.754506) (xy 368.779879 -53.754506) (xy 368.833827 -53.762262)
			(xy 368.886122 -53.777617) (xy 368.935699 -53.800259) (xy 368.981549 -53.829725) (xy 369.02274 -53.865416)
			(xy 369.058431 -53.906607) (xy 369.087897 -53.952457) (xy 369.092972 -53.96357) (xy 373.07215 -53.96357)
			(xy 373.076221 -53.907948) (xy 373.088347 -53.853511) (xy 373.10827 -53.80142) (xy 373.135566 -53.752785)
			(xy 373.169652 -53.708642) (xy 373.209801 -53.669933) (xy 373.255159 -53.637482) (xy 373.304759 -53.611981)
			(xy 373.357543 -53.593974) (xy 373.412386 -53.583844) (xy 373.46812 -53.581807) (xy 373.523557 -53.587907)
			(xy 373.577514 -53.602013) (xy 373.628843 -53.623825) (xy 373.676449 -53.652879) (xy 373.719317 -53.688554)
			(xy 373.756534 -53.730091) (xy 373.787307 -53.776604) (xy 373.810979 -53.827101) (xy 373.827047 -53.880508)
			(xy 373.835167 -53.935684) (xy 373.835676 -53.96357) (xy 373.835167 -53.991456) (xy 373.827047 -54.046632)
			(xy 373.820782 -54.067456) (xy 375.24131 -54.067456) (xy 375.245381 -54.011834) (xy 375.257507 -53.957397)
			(xy 375.27743 -53.905306) (xy 375.304726 -53.856671) (xy 375.338812 -53.812528) (xy 375.378961 -53.773819)
			(xy 375.424319 -53.741368) (xy 375.473919 -53.715867) (xy 375.526703 -53.69786) (xy 375.581546 -53.68773)
			(xy 375.63728 -53.685693) (xy 375.692717 -53.691793) (xy 375.746674 -53.705899) (xy 375.798003 -53.727711)
			(xy 375.845609 -53.756765) (xy 375.888477 -53.79244) (xy 375.925694 -53.833977) (xy 375.956467 -53.88049)
			(xy 375.980139 -53.930987) (xy 375.996207 -53.984394) (xy 376.004327 -54.03957) (xy 376.004836 -54.067456)
			(xy 376.004327 -54.095342) (xy 375.996207 -54.150518) (xy 375.980139 -54.203925) (xy 375.963741 -54.238906)
			(xy 382.68605 -54.238906) (xy 382.690121 -54.183284) (xy 382.702247 -54.128847) (xy 382.72217 -54.076756)
			(xy 382.749466 -54.028121) (xy 382.783552 -53.983978) (xy 382.823701 -53.945269) (xy 382.869059 -53.912818)
			(xy 382.918659 -53.887317) (xy 382.971443 -53.86931) (xy 383.026286 -53.85918) (xy 383.08202 -53.857143)
			(xy 383.137457 -53.863243) (xy 383.191414 -53.877349) (xy 383.242743 -53.899161) (xy 383.290349 -53.928215)
			(xy 383.333217 -53.96389) (xy 383.370434 -54.005427) (xy 383.401207 -54.05194) (xy 383.424879 -54.102437)
			(xy 383.440947 -54.155844) (xy 383.449067 -54.21102) (xy 383.449576 -54.238906) (xy 383.449067 -54.266792)
			(xy 383.440947 -54.321968) (xy 383.424879 -54.375375) (xy 383.401207 -54.425872) (xy 383.370434 -54.472385)
			(xy 383.333217 -54.513922) (xy 383.290349 -54.549597) (xy 383.242743 -54.578651) (xy 383.191414 -54.600463)
			(xy 383.137457 -54.614569) (xy 383.08202 -54.620669) (xy 383.026286 -54.618632) (xy 382.971443 -54.608502)
			(xy 382.918659 -54.590495) (xy 382.869059 -54.564994) (xy 382.823701 -54.532543) (xy 382.783552 -54.493834)
			(xy 382.749466 -54.449691) (xy 382.72217 -54.401056) (xy 382.702247 -54.348965) (xy 382.690121 -54.294528)
			(xy 382.68605 -54.238906) (xy 375.963741 -54.238906) (xy 375.956467 -54.254422) (xy 375.925694 -54.300935)
			(xy 375.888477 -54.342472) (xy 375.845609 -54.378147) (xy 375.798003 -54.407201) (xy 375.746674 -54.429013)
			(xy 375.692717 -54.443119) (xy 375.63728 -54.449219) (xy 375.581546 -54.447182) (xy 375.526703 -54.437052)
			(xy 375.473919 -54.419045) (xy 375.424319 -54.393544) (xy 375.378961 -54.361093) (xy 375.338812 -54.322384)
			(xy 375.304726 -54.278241) (xy 375.27743 -54.229606) (xy 375.257507 -54.177515) (xy 375.245381 -54.123078)
			(xy 375.24131 -54.067456) (xy 373.820782 -54.067456) (xy 373.810979 -54.100039) (xy 373.787307 -54.150536)
			(xy 373.756534 -54.197049) (xy 373.719317 -54.238586) (xy 373.676449 -54.274261) (xy 373.628843 -54.303315)
			(xy 373.577514 -54.325127) (xy 373.523557 -54.339233) (xy 373.46812 -54.345333) (xy 373.412386 -54.343296)
			(xy 373.357543 -54.333166) (xy 373.304759 -54.315159) (xy 373.255159 -54.289658) (xy 373.209801 -54.257207)
			(xy 373.169652 -54.218498) (xy 373.135566 -54.174355) (xy 373.10827 -54.12572) (xy 373.088347 -54.073629)
			(xy 373.076221 -54.019192) (xy 373.07215 -53.96357) (xy 369.092972 -53.96357) (xy 369.110539 -54.002034)
			(xy 369.125894 -54.054329) (xy 369.13365 -54.108277) (xy 369.134136 -54.135528) (xy 369.133667 -54.162862)
			(xy 369.12586 -54.21697) (xy 369.110411 -54.269409) (xy 369.087636 -54.319107) (xy 369.058001 -54.365045)
			(xy 369.04041 -54.385972) (xy 369.040156 -54.386226) (xy 369.039902 -54.38648) (xy 369.034318 -54.393568)
			(xy 369.02807 -54.410484) (xy 369.02771 -54.4195) (xy 369.02771 -54.486556) (xy 369.028086 -54.495571)
			(xy 369.03432 -54.512488) (xy 369.039902 -54.519576) (xy 369.040156 -54.51983) (xy 369.04041 -54.520084)
			(xy 369.05801 -54.541004) (xy 369.087647 -54.586942) (xy 369.110422 -54.636642) (xy 369.125868 -54.689084)
			(xy 369.133669 -54.743193) (xy 369.134136 -54.770528) (xy 369.13365 -54.797779) (xy 369.125894 -54.851727)
			(xy 369.110539 -54.904022) (xy 369.087897 -54.953599) (xy 369.058431 -54.999449) (xy 369.02274 -55.04064)
			(xy 368.981549 -55.076331) (xy 368.970462 -55.083456) (xy 375.24131 -55.083456) (xy 375.245381 -55.027834)
			(xy 375.257507 -54.973397) (xy 375.27743 -54.921306) (xy 375.304726 -54.872671) (xy 375.338812 -54.828528)
			(xy 375.378961 -54.789819) (xy 375.424319 -54.757368) (xy 375.473919 -54.731867) (xy 375.526703 -54.71386)
			(xy 375.581546 -54.70373) (xy 375.63728 -54.701693) (xy 375.692717 -54.707793) (xy 375.746674 -54.721899)
			(xy 375.798003 -54.743711) (xy 375.845609 -54.772765) (xy 375.888477 -54.80844) (xy 375.925694 -54.849977)
			(xy 375.956467 -54.89649) (xy 375.980139 -54.946987) (xy 375.992794 -54.989051) (xy 378.201168 -54.989051)
			(xy 378.201168 -54.934549) (xy 378.208924 -54.880602) (xy 378.224278 -54.828308) (xy 378.246918 -54.778732)
			(xy 378.276382 -54.732881) (xy 378.312072 -54.691691) (xy 378.35326 -54.655998) (xy 378.399109 -54.62653)
			(xy 378.448684 -54.603887) (xy 378.500977 -54.588529) (xy 378.554923 -54.58077) (xy 378.582174 -54.580282)
			(xy 378.610265 -54.580797) (xy 378.665841 -54.589021) (xy 378.71961 -54.605308) (xy 378.770407 -54.629308)
			(xy 378.817134 -54.660499) (xy 378.85878 -54.698208) (xy 378.894443 -54.741619) (xy 378.909326 -54.765448)
			(xy 378.914914 -54.774592) (xy 378.931932 -54.786784) (xy 379.024896 -54.80685) (xy 379.04547 -54.802786)
			(xy 379.054106 -54.79669) (xy 379.078166 -54.780684) (xy 379.130099 -54.755343) (xy 379.185258 -54.738119)
			(xy 379.242383 -54.729406) (xy 379.271276 -54.728872) (xy 379.298527 -54.729378) (xy 379.312681 -54.731412)
			(xy 387.820662 -54.731412) (xy 387.821097 -54.704077) (xy 387.828911 -54.649968) (xy 387.844369 -54.597528)
			(xy 387.867152 -54.547831) (xy 387.896794 -54.501894) (xy 387.914388 -54.480968) (xy 387.914642 -54.480714)
			(xy 387.914896 -54.48046) (xy 387.920463 -54.47336) (xy 387.926722 -54.456454) (xy 387.927088 -54.44744)
			(xy 387.927088 -54.380384) (xy 387.926741 -54.371366) (xy 387.920487 -54.354449) (xy 387.914896 -54.347364)
			(xy 387.914642 -54.34711) (xy 387.914388 -54.346856) (xy 387.896799 -54.325925) (xy 387.867144 -54.279994)
			(xy 387.844353 -54.230298) (xy 387.828894 -54.177857) (xy 387.821084 -54.123745) (xy 387.821083 -54.069073)
			(xy 387.82889 -54.014961) (xy 387.844347 -53.962519) (xy 387.867135 -53.912822) (xy 387.896788 -53.86689)
			(xy 387.914388 -53.845968) (xy 387.914642 -53.845714) (xy 387.914896 -53.84546) (xy 387.920463 -53.83836)
			(xy 387.926722 -53.821454) (xy 387.927088 -53.81244) (xy 387.927088 -53.745384) (xy 387.926741 -53.736366)
			(xy 387.920487 -53.719449) (xy 387.914896 -53.712364) (xy 387.914642 -53.71211) (xy 387.914388 -53.711856)
			(xy 387.896799 -53.690925) (xy 387.867144 -53.644994) (xy 387.844353 -53.595298) (xy 387.828894 -53.542857)
			(xy 387.821084 -53.488745) (xy 387.821083 -53.434073) (xy 387.82889 -53.379961) (xy 387.844347 -53.327519)
			(xy 387.867135 -53.277822) (xy 387.896788 -53.23189) (xy 387.914388 -53.210968) (xy 387.914642 -53.210714)
			(xy 387.914896 -53.21046) (xy 387.920463 -53.20336) (xy 387.926722 -53.186454) (xy 387.927088 -53.17744)
			(xy 387.927088 -53.110384) (xy 387.926741 -53.101366) (xy 387.920487 -53.084449) (xy 387.914896 -53.077364)
			(xy 387.914642 -53.07711) (xy 387.914388 -53.076856) (xy 387.896806 -53.055922) (xy 387.867167 -53.009987)
			(xy 387.844389 -52.960291) (xy 387.828938 -52.907853) (xy 387.821132 -52.853746) (xy 387.820662 -52.826412)
			(xy 387.821148 -52.799161) (xy 387.828904 -52.745213) (xy 387.844259 -52.692918) (xy 387.866901 -52.643341)
			(xy 387.896367 -52.597491) (xy 387.932058 -52.5563) (xy 387.973249 -52.520609) (xy 388.019099 -52.491143)
			(xy 388.068676 -52.468501) (xy 388.120971 -52.453146) (xy 388.174919 -52.44539) (xy 388.229421 -52.44539)
			(xy 388.283369 -52.453146) (xy 388.335664 -52.468501) (xy 388.385241 -52.491143) (xy 388.431091 -52.520609)
			(xy 388.472282 -52.5563) (xy 388.507973 -52.597491) (xy 388.537439 -52.643341) (xy 388.560081 -52.692918)
			(xy 388.575436 -52.745213) (xy 388.583192 -52.799161) (xy 388.583678 -52.826412) (xy 388.583189 -52.853745)
			(xy 388.575386 -52.907852) (xy 388.559941 -52.96029) (xy 388.53717 -53.009988) (xy 388.50754 -53.055928)
			(xy 388.489952 -53.076856) (xy 388.489698 -53.07711) (xy 388.489444 -53.077364) (xy 388.48386 -53.084452)
			(xy 388.477613 -53.101368) (xy 388.477252 -53.110384) (xy 388.477252 -53.17744) (xy 388.477578 -53.18646)
			(xy 388.483846 -53.203378) (xy 388.489444 -53.21046) (xy 388.489698 -53.210714) (xy 388.489952 -53.210968)
			(xy 388.507563 -53.231881) (xy 388.537214 -53.277816) (xy 388.560001 -53.327515) (xy 388.575456 -53.379959)
			(xy 388.583263 -53.434072) (xy 388.583262 -53.488746) (xy 388.575452 -53.542859) (xy 388.559995 -53.595302)
			(xy 388.537205 -53.645) (xy 388.507552 -53.690933) (xy 388.489952 -53.711856) (xy 388.489698 -53.71211)
			(xy 388.489444 -53.712364) (xy 388.48386 -53.719452) (xy 388.477613 -53.736368) (xy 388.477252 -53.745384)
			(xy 388.477252 -53.81244) (xy 388.477578 -53.82146) (xy 388.483846 -53.838378) (xy 388.489444 -53.84546)
			(xy 388.489698 -53.845714) (xy 388.489952 -53.845968) (xy 388.507563 -53.866881) (xy 388.537214 -53.912816)
			(xy 388.560001 -53.962515) (xy 388.575456 -54.014959) (xy 388.583263 -54.069072) (xy 388.583262 -54.123746)
			(xy 388.575452 -54.177859) (xy 388.559995 -54.230302) (xy 388.537205 -54.28) (xy 388.507552 -54.325933)
			(xy 388.489952 -54.346856) (xy 388.489698 -54.34711) (xy 388.489444 -54.347364) (xy 388.48386 -54.354452)
			(xy 388.477613 -54.371368) (xy 388.477252 -54.380384) (xy 388.477252 -54.44744) (xy 388.477578 -54.45646)
			(xy 388.483846 -54.473378) (xy 388.489444 -54.48046) (xy 388.489698 -54.480714) (xy 388.489952 -54.480968)
			(xy 388.507535 -54.501901) (xy 388.537177 -54.547835) (xy 388.559956 -54.597531) (xy 388.575405 -54.64997)
			(xy 388.583209 -54.704078) (xy 388.583678 -54.731412) (xy 388.583192 -54.758663) (xy 388.578528 -54.791102)
			(xy 390.476486 -54.791102) (xy 390.476992 -54.76377) (xy 390.484792 -54.709664) (xy 390.500234 -54.657226)
			(xy 390.523 -54.607528) (xy 390.552626 -54.561587) (xy 390.570212 -54.540658) (xy 390.570466 -54.540404)
			(xy 390.57072 -54.54015) (xy 390.576294 -54.533055) (xy 390.582548 -54.516145) (xy 390.582912 -54.50713)
			(xy 390.582912 -54.440074) (xy 390.582565 -54.431056) (xy 390.57631 -54.41414) (xy 390.57072 -54.407054)
			(xy 390.570466 -54.4068) (xy 390.570212 -54.406546) (xy 390.552612 -54.385623) (xy 390.522955 -54.339691)
			(xy 390.500164 -54.289994) (xy 390.484705 -54.237552) (xy 390.476895 -54.183438) (xy 390.476895 -54.128765)
			(xy 390.484704 -54.074651) (xy 390.500163 -54.022208) (xy 390.522954 -53.972511) (xy 390.55261 -53.926579)
			(xy 390.570212 -53.905658) (xy 390.570466 -53.905404) (xy 390.57072 -53.90515) (xy 390.576294 -53.898055)
			(xy 390.582548 -53.881145) (xy 390.582912 -53.87213) (xy 390.582912 -53.805074) (xy 390.582565 -53.796056)
			(xy 390.57631 -53.77914) (xy 390.57072 -53.772054) (xy 390.570466 -53.7718) (xy 390.570212 -53.771546)
			(xy 390.552612 -53.750623) (xy 390.522955 -53.704691) (xy 390.500164 -53.654994) (xy 390.484705 -53.602552)
			(xy 390.476895 -53.548438) (xy 390.476895 -53.493765) (xy 390.484704 -53.439651) (xy 390.500163 -53.387208)
			(xy 390.522954 -53.337511) (xy 390.55261 -53.291579) (xy 390.570212 -53.270658) (xy 390.570466 -53.270404)
			(xy 390.57072 -53.27015) (xy 390.576294 -53.263055) (xy 390.582548 -53.246145) (xy 390.582912 -53.23713)
			(xy 390.582912 -53.170074) (xy 390.582565 -53.161056) (xy 390.57631 -53.14414) (xy 390.57072 -53.137054)
			(xy 390.570466 -53.1368) (xy 390.570212 -53.136546) (xy 390.55263 -53.115612) (xy 390.522989 -53.069678)
			(xy 390.500211 -53.019982) (xy 390.484761 -52.967543) (xy 390.476956 -52.913436) (xy 390.476486 -52.886102)
			(xy 390.476972 -52.858851) (xy 390.484728 -52.804903) (xy 390.500083 -52.752608) (xy 390.522725 -52.703031)
			(xy 390.552191 -52.657181) (xy 390.587882 -52.61599) (xy 390.629073 -52.580299) (xy 390.674923 -52.550833)
			(xy 390.7245 -52.528191) (xy 390.776795 -52.512836) (xy 390.830743 -52.50508) (xy 390.885245 -52.50508)
			(xy 390.939193 -52.512836) (xy 390.953511 -52.51704) (xy 395.140178 -52.51704) (xy 395.144249 -52.461418)
			(xy 395.156375 -52.406981) (xy 395.176298 -52.35489) (xy 395.203594 -52.306255) (xy 395.23768 -52.262112)
			(xy 395.277829 -52.223403) (xy 395.323187 -52.190952) (xy 395.372787 -52.165451) (xy 395.425571 -52.147444)
			(xy 395.480414 -52.137314) (xy 395.536148 -52.135277) (xy 395.591585 -52.141377) (xy 395.645542 -52.155483)
			(xy 395.696871 -52.177295) (xy 395.744477 -52.206349) (xy 395.787345 -52.242024) (xy 395.824562 -52.283561)
			(xy 395.855335 -52.330074) (xy 395.879007 -52.380571) (xy 395.895075 -52.433978) (xy 395.903195 -52.489154)
			(xy 395.903704 -52.51704) (xy 395.903195 -52.544926) (xy 395.896945 -52.587398) (xy 399.055334 -52.587398)
			(xy 399.059405 -52.531776) (xy 399.071531 -52.477339) (xy 399.091454 -52.425248) (xy 399.11875 -52.376613)
			(xy 399.152836 -52.33247) (xy 399.192985 -52.293761) (xy 399.238343 -52.26131) (xy 399.287943 -52.235809)
			(xy 399.340727 -52.217802) (xy 399.39557 -52.207672) (xy 399.451304 -52.205635) (xy 399.506741 -52.211735)
			(xy 399.560698 -52.225841) (xy 399.612027 -52.247653) (xy 399.659633 -52.276707) (xy 399.702501 -52.312382)
			(xy 399.739718 -52.353919) (xy 399.770491 -52.400432) (xy 399.794163 -52.450929) (xy 399.810231 -52.504336)
			(xy 399.818351 -52.559512) (xy 399.818436 -52.564157) (xy 404.127107 -52.564157) (xy 404.127107 -52.509643)
			(xy 404.134865 -52.455685) (xy 404.150224 -52.40338) (xy 404.172869 -52.353793) (xy 404.202342 -52.307933)
			(xy 404.238041 -52.266735) (xy 404.27924 -52.231037) (xy 404.3251 -52.201566) (xy 404.374687 -52.178921)
			(xy 404.426993 -52.163563) (xy 404.480951 -52.155806) (xy 404.508208 -52.155344) (xy 404.535579 -52.155795)
			(xy 404.589759 -52.163615) (xy 404.642263 -52.179107) (xy 404.692009 -52.201952) (xy 404.737975 -52.231681)
			(xy 404.758906 -52.249324) (xy 404.75916 -52.249578) (xy 404.766247 -52.255163) (xy 404.783164 -52.261409)
			(xy 404.79218 -52.26177) (xy 404.859236 -52.26177) (xy 404.868255 -52.261437) (xy 404.885173 -52.255173)
			(xy 404.892256 -52.249578) (xy 404.892764 -52.24907) (xy 404.913689 -52.231476) (xy 404.959626 -52.201839)
			(xy 405.009325 -52.179064) (xy 405.061765 -52.163616) (xy 405.115874 -52.155813) (xy 405.143208 -52.155344)
			(xy 405.170455 -52.155927) (xy 405.224395 -52.163683) (xy 405.276683 -52.179037) (xy 405.326253 -52.201676)
			(xy 405.372096 -52.231139) (xy 405.41328 -52.266826) (xy 405.448966 -52.30801) (xy 405.478428 -52.353855)
			(xy 405.501066 -52.403425) (xy 405.516419 -52.455712) (xy 405.524174 -52.509653) (xy 405.524174 -52.555948)
			(xy 406.883902 -52.555948) (xy 406.883902 -52.501452) (xy 406.891657 -52.44751) (xy 406.90701 -52.395221)
			(xy 406.929647 -52.345649) (xy 406.959109 -52.299803) (xy 406.994795 -52.258616) (xy 407.035979 -52.222927)
			(xy 407.081823 -52.193462) (xy 407.131393 -52.17082) (xy 407.183681 -52.155464) (xy 407.237622 -52.147704)
			(xy 407.26487 -52.147216) (xy 407.29224 -52.147696) (xy 407.346418 -52.15551) (xy 407.398922 -52.170995)
			(xy 407.448669 -52.193834) (xy 407.494636 -52.223556) (xy 407.515568 -52.241196) (xy 407.515822 -52.24145)
			(xy 407.522894 -52.247058) (xy 407.539822 -52.253291) (xy 407.548842 -52.253642) (xy 407.615898 -52.253642)
			(xy 407.624916 -52.253296) (xy 407.641834 -52.247042) (xy 407.648918 -52.24145) (xy 407.649426 -52.240942)
			(xy 407.670374 -52.223377) (xy 407.716304 -52.193733) (xy 407.765996 -52.170951) (xy 407.818432 -52.155497)
			(xy 407.872537 -52.147688) (xy 407.89987 -52.147216) (xy 407.927126 -52.147629) (xy 407.981084 -52.155383)
			(xy 408.033388 -52.170737) (xy 408.082976 -52.19338) (xy 408.128835 -52.222849) (xy 408.170034 -52.258545)
			(xy 408.205733 -52.299741) (xy 408.235206 -52.345598) (xy 408.257852 -52.395183) (xy 408.273211 -52.447487)
			(xy 408.280969 -52.501444) (xy 408.280969 -52.555956) (xy 408.273211 -52.609913) (xy 408.257852 -52.662217)
			(xy 408.235206 -52.711802) (xy 408.205733 -52.757659) (xy 408.170034 -52.798855) (xy 408.128835 -52.834551)
			(xy 408.082976 -52.86402) (xy 408.033388 -52.886663) (xy 407.981084 -52.902017) (xy 407.927126 -52.909771)
			(xy 407.89987 -52.910232) (xy 407.872498 -52.9098) (xy 407.818317 -52.901977) (xy 407.765813 -52.88648)
			(xy 407.716067 -52.863631) (xy 407.670102 -52.833898) (xy 407.649172 -52.816252) (xy 407.648918 -52.815998)
			(xy 407.641831 -52.810413) (xy 407.624914 -52.804165) (xy 407.615898 -52.803806) (xy 407.548842 -52.803806)
			(xy 407.539827 -52.804182) (xy 407.52291 -52.810416) (xy 407.515822 -52.815998) (xy 407.515314 -52.816506)
			(xy 407.494395 -52.834106) (xy 407.448456 -52.863743) (xy 407.398756 -52.886518) (xy 407.346314 -52.901964)
			(xy 407.292205 -52.909765) (xy 407.26487 -52.910232) (xy 407.237622 -52.909696) (xy 407.183681 -52.901936)
			(xy 407.131393 -52.88658) (xy 407.081823 -52.863938) (xy 407.035979 -52.834473) (xy 406.994795 -52.798784)
			(xy 406.959109 -52.757597) (xy 406.929647 -52.711751) (xy 406.90701 -52.662179) (xy 406.891657 -52.60989)
			(xy 406.883902 -52.555948) (xy 405.524174 -52.555948) (xy 405.524174 -52.564147) (xy 405.516419 -52.618088)
			(xy 405.501066 -52.670375) (xy 405.478428 -52.719945) (xy 405.448966 -52.76579) (xy 405.41328 -52.806974)
			(xy 405.372096 -52.842661) (xy 405.326253 -52.872124) (xy 405.276683 -52.894763) (xy 405.224395 -52.910117)
			(xy 405.170455 -52.917873) (xy 405.143208 -52.91836) (xy 405.115837 -52.917899) (xy 405.061658 -52.910081)
			(xy 405.009154 -52.894592) (xy 404.959407 -52.871749) (xy 404.913441 -52.842022) (xy 404.89251 -52.82438)
			(xy 404.892256 -52.824126) (xy 404.885164 -52.818548) (xy 404.868251 -52.812298) (xy 404.859236 -52.811934)
			(xy 404.79218 -52.811934) (xy 404.783161 -52.812274) (xy 404.766244 -52.818532) (xy 404.75916 -52.824126)
			(xy 404.758652 -52.824634) (xy 404.737722 -52.842221) (xy 404.691786 -52.871859) (xy 404.642089 -52.894636)
			(xy 404.589649 -52.910085) (xy 404.535542 -52.91789) (xy 404.508208 -52.91836) (xy 404.480951 -52.917994)
			(xy 404.426993 -52.910237) (xy 404.374687 -52.894879) (xy 404.3251 -52.872234) (xy 404.27924 -52.842763)
			(xy 404.238041 -52.807065) (xy 404.202342 -52.765867) (xy 404.172869 -52.720007) (xy 404.150224 -52.67042)
			(xy 404.134865 -52.618115) (xy 404.127107 -52.564157) (xy 399.818436 -52.564157) (xy 399.81886 -52.587398)
			(xy 399.818351 -52.615284) (xy 399.810231 -52.67046) (xy 399.794163 -52.723867) (xy 399.770491 -52.774364)
			(xy 399.739718 -52.820877) (xy 399.702501 -52.862414) (xy 399.659633 -52.898089) (xy 399.612027 -52.927143)
			(xy 399.560698 -52.948955) (xy 399.506741 -52.963061) (xy 399.451304 -52.969161) (xy 399.39557 -52.967124)
			(xy 399.340727 -52.956994) (xy 399.287943 -52.938987) (xy 399.238343 -52.913486) (xy 399.192985 -52.881035)
			(xy 399.152836 -52.842326) (xy 399.11875 -52.798183) (xy 399.091454 -52.749548) (xy 399.071531 -52.697457)
			(xy 399.059405 -52.64302) (xy 399.055334 -52.587398) (xy 395.896945 -52.587398) (xy 395.895075 -52.600102)
			(xy 395.879007 -52.653509) (xy 395.855335 -52.704006) (xy 395.824562 -52.750519) (xy 395.787345 -52.792056)
			(xy 395.744477 -52.827731) (xy 395.696871 -52.856785) (xy 395.645542 -52.878597) (xy 395.591585 -52.892703)
			(xy 395.536148 -52.898803) (xy 395.480414 -52.896766) (xy 395.425571 -52.886636) (xy 395.372787 -52.868629)
			(xy 395.323187 -52.843128) (xy 395.277829 -52.810677) (xy 395.23768 -52.771968) (xy 395.203594 -52.727825)
			(xy 395.176298 -52.67919) (xy 395.156375 -52.627099) (xy 395.144249 -52.572662) (xy 395.140178 -52.51704)
			(xy 390.953511 -52.51704) (xy 390.991488 -52.528191) (xy 391.041065 -52.550833) (xy 391.086915 -52.580299)
			(xy 391.128106 -52.61599) (xy 391.163797 -52.657181) (xy 391.193263 -52.703031) (xy 391.215905 -52.752608)
			(xy 391.23126 -52.804903) (xy 391.239016 -52.858851) (xy 391.239502 -52.886102) (xy 391.239002 -52.913435)
			(xy 391.2312 -52.96754) (xy 391.215758 -53.019979) (xy 391.19299 -53.069677) (xy 391.163363 -53.115617)
			(xy 391.145776 -53.136546) (xy 391.145522 -53.1368) (xy 391.145268 -53.137054) (xy 391.139691 -53.144147)
			(xy 391.13344 -53.161059) (xy 391.133076 -53.170074) (xy 391.133076 -53.23713) (xy 391.133424 -53.246148)
			(xy 391.139678 -53.263064) (xy 391.145268 -53.27015) (xy 391.145522 -53.270404) (xy 391.145776 -53.270658)
			(xy 391.163376 -53.291579) (xy 391.193026 -53.337514) (xy 391.215812 -53.387211) (xy 391.231267 -53.439654)
			(xy 391.239074 -53.493765) (xy 391.239074 -53.548438) (xy 391.231266 -53.602549) (xy 391.215811 -53.654992)
			(xy 391.193025 -53.704689) (xy 391.163375 -53.750623) (xy 391.146631 -53.77053) (xy 391.510774 -53.77053)
			(xy 391.511286 -53.741612) (xy 391.520012 -53.68444) (xy 391.537269 -53.62924) (xy 391.562662 -53.577277)
			(xy 391.595608 -53.529744) (xy 391.635353 -53.487729) (xy 391.65784 -53.46954) (xy 391.665208 -53.463239)
			(xy 391.675014 -53.446538) (xy 391.67689 -53.437028) (xy 391.677398 -53.429408) (xy 391.677398 -53.349652)
			(xy 391.67689 -53.342032) (xy 391.675036 -53.332514) (xy 391.665229 -53.315801) (xy 391.65784 -53.30952)
			(xy 391.635374 -53.291308) (xy 391.595636 -53.249293) (xy 391.562694 -53.201763) (xy 391.537302 -53.149806)
			(xy 391.520043 -53.094612) (xy 391.51131 -53.037445) (xy 391.510774 -53.00853) (xy 391.511283 -52.981279)
			(xy 391.519036 -52.92733) (xy 391.534387 -52.875034) (xy 391.557025 -52.825456) (xy 391.586488 -52.779603)
			(xy 391.622177 -52.738411) (xy 391.663365 -52.702717) (xy 391.709213 -52.673248) (xy 391.758789 -52.650604)
			(xy 391.811083 -52.635246) (xy 391.865031 -52.627487) (xy 391.892282 -52.627022) (xy 391.892536 -52.627022)
			(xy 391.918832 -52.62745) (xy 391.970922 -52.6347) (xy 392.021524 -52.649032) (xy 392.069681 -52.670173)
			(xy 392.114479 -52.697724) (xy 392.155073 -52.731163) (xy 392.173206 -52.750212) (xy 392.180775 -52.757657)
			(xy 392.200195 -52.766179) (xy 392.210798 -52.766722) (xy 392.284966 -52.766722) (xy 392.2956 -52.766334)
			(xy 392.315064 -52.757769) (xy 392.322558 -52.750212) (xy 392.3407 -52.73117) (xy 392.381279 -52.697712)
			(xy 392.426073 -52.67015) (xy 392.47423 -52.649009) (xy 392.524836 -52.634688) (xy 392.576931 -52.627462)
			(xy 392.603228 -52.627022) (xy 392.603482 -52.627022) (xy 392.630736 -52.627472) (xy 392.684689 -52.635227)
			(xy 392.736989 -52.650583) (xy 392.786571 -52.673225) (xy 392.832425 -52.702694) (xy 392.873619 -52.738389)
			(xy 392.909313 -52.779584) (xy 392.93878 -52.82544) (xy 392.961421 -52.875023) (xy 392.976775 -52.927323)
			(xy 392.984529 -52.981276) (xy 392.98499 -53.00853) (xy 392.984506 -53.036196) (xy 392.982275 -53.051456)
			(xy 401.241258 -53.051456) (xy 401.245329 -52.995834) (xy 401.257455 -52.941397) (xy 401.277378 -52.889306)
			(xy 401.304674 -52.840671) (xy 401.33876 -52.796528) (xy 401.378909 -52.757819) (xy 401.424267 -52.725368)
			(xy 401.473867 -52.699867) (xy 401.526651 -52.68186) (xy 401.581494 -52.67173) (xy 401.637228 -52.669693)
			(xy 401.692665 -52.675793) (xy 401.746622 -52.689899) (xy 401.797951 -52.711711) (xy 401.845557 -52.740765)
			(xy 401.888425 -52.77644) (xy 401.925642 -52.817977) (xy 401.956415 -52.86449) (xy 401.980087 -52.914987)
			(xy 401.996155 -52.968394) (xy 402.004275 -53.02357) (xy 402.004784 -53.051456) (xy 402.004275 -53.079342)
			(xy 401.996155 -53.134518) (xy 401.980087 -53.187925) (xy 401.956415 -53.238422) (xy 401.925642 -53.284935)
			(xy 401.888425 -53.326472) (xy 401.845557 -53.362147) (xy 401.797951 -53.391201) (xy 401.746622 -53.413013)
			(xy 401.692665 -53.427119) (xy 401.637228 -53.433219) (xy 401.581494 -53.431182) (xy 401.526651 -53.421052)
			(xy 401.473867 -53.403045) (xy 401.424267 -53.377544) (xy 401.378909 -53.345093) (xy 401.33876 -53.306384)
			(xy 401.304674 -53.262241) (xy 401.277378 -53.213606) (xy 401.257455 -53.161515) (xy 401.245329 -53.107078)
			(xy 401.241258 -53.051456) (xy 392.982275 -53.051456) (xy 392.976502 -53.090947) (xy 392.960681 -53.143969)
			(xy 392.937373 -53.194154) (xy 392.907068 -53.240449) (xy 392.870398 -53.281886) (xy 392.828133 -53.317598)
			(xy 392.804904 -53.332634) (xy 392.80465 -53.332888) (xy 392.795116 -53.339543) (xy 392.782815 -53.359246)
			(xy 392.781028 -53.370734) (xy 392.773154 -53.450744) (xy 392.772474 -53.462445) (xy 392.780563 -53.484419)
			(xy 392.788648 -53.492908) (xy 392.788902 -53.492908) (xy 392.80747 -53.511002) (xy 392.840049 -53.551331)
			(xy 392.866864 -53.595703) (xy 392.887419 -53.643299) (xy 392.901335 -53.693241) (xy 392.908356 -53.744608)
			(xy 392.90879 -53.77053) (xy 392.90835 -53.797783) (xy 392.900589 -53.851733) (xy 392.885229 -53.90403)
			(xy 392.862583 -53.953608) (xy 392.833112 -53.999459) (xy 392.797416 -54.04065) (xy 392.756221 -54.076341)
			(xy 392.710366 -54.105806) (xy 392.660785 -54.128446) (xy 392.608486 -54.143799) (xy 392.554535 -54.151553)
			(xy 392.527282 -54.152038) (xy 392.499911 -54.151598) (xy 392.44573 -54.143776) (xy 392.393226 -54.128282)
			(xy 392.343479 -54.105434) (xy 392.297514 -54.075703) (xy 392.276584 -54.058058) (xy 392.27633 -54.057804)
			(xy 392.269239 -54.052224) (xy 392.252326 -54.045973) (xy 392.24331 -54.045612) (xy 392.176254 -54.045612)
			(xy 392.167239 -54.045992) (xy 392.150322 -54.052224) (xy 392.143234 -54.057804) (xy 392.142726 -54.058312)
			(xy 392.121803 -54.075908) (xy 392.075865 -54.105545) (xy 392.026166 -54.128321) (xy 391.973725 -54.143768)
			(xy 391.919616 -54.15157) (xy 391.892282 -54.152038) (xy 391.865032 -54.151539) (xy 391.811086 -54.143781)
			(xy 391.758793 -54.128425) (xy 391.709218 -54.105784) (xy 391.663369 -54.076319) (xy 391.62218 -54.040629)
			(xy 391.586489 -53.99944) (xy 391.557022 -53.953593) (xy 391.534379 -53.904018) (xy 391.519022 -53.851726)
			(xy 391.511262 -53.79778) (xy 391.510774 -53.77053) (xy 391.146631 -53.77053) (xy 391.145776 -53.771546)
			(xy 391.145522 -53.7718) (xy 391.145268 -53.772054) (xy 391.139691 -53.779147) (xy 391.13344 -53.796059)
			(xy 391.133076 -53.805074) (xy 391.133076 -53.87213) (xy 391.133424 -53.881148) (xy 391.139678 -53.898064)
			(xy 391.145268 -53.90515) (xy 391.145522 -53.905404) (xy 391.145776 -53.905658) (xy 391.163376 -53.926579)
			(xy 391.193026 -53.972514) (xy 391.215812 -54.022211) (xy 391.231267 -54.074654) (xy 391.239074 -54.128765)
			(xy 391.239074 -54.183438) (xy 391.231266 -54.237549) (xy 391.215811 -54.289992) (xy 391.201967 -54.320186)
			(xy 393.430506 -54.320186) (xy 393.430997 -54.292853) (xy 393.438801 -54.238747) (xy 393.454245 -54.186308)
			(xy 393.477015 -54.13661) (xy 393.506644 -54.09067) (xy 393.524232 -54.069742) (xy 393.524486 -54.069488)
			(xy 393.52474 -54.069234) (xy 393.530323 -54.062145) (xy 393.536571 -54.04523) (xy 393.536932 -54.036214)
			(xy 393.536932 -53.969158) (xy 393.53654 -53.960145) (xy 393.530316 -53.943228) (xy 393.52474 -53.936138)
			(xy 393.524486 -53.935884) (xy 393.524232 -53.93563) (xy 393.506645 -53.9147) (xy 393.477005 -53.868764)
			(xy 393.454227 -53.819068) (xy 393.438778 -53.766628) (xy 393.430974 -53.71252) (xy 393.430506 -53.685186)
			(xy 393.430992 -53.657935) (xy 393.438748 -53.603987) (xy 393.454103 -53.551692) (xy 393.476745 -53.502115)
			(xy 393.506211 -53.456265) (xy 393.541902 -53.415074) (xy 393.583093 -53.379383) (xy 393.628943 -53.349917)
			(xy 393.67852 -53.327275) (xy 393.730815 -53.31192) (xy 393.784763 -53.304164) (xy 393.839265 -53.304164)
			(xy 393.893213 -53.31192) (xy 393.945508 -53.327275) (xy 393.995085 -53.349917) (xy 394.040935 -53.379383)
			(xy 394.082126 -53.415074) (xy 394.117817 -53.456265) (xy 394.14371 -53.496555) (xy 406.433441 -53.496555)
			(xy 406.433441 -53.442045) (xy 406.441199 -53.388089) (xy 406.456557 -53.335787) (xy 406.479202 -53.286203)
			(xy 406.508674 -53.240347) (xy 406.544372 -53.199152) (xy 406.58557 -53.163457) (xy 406.631428 -53.133989)
			(xy 406.681014 -53.111347) (xy 406.733317 -53.095993) (xy 406.787273 -53.088239) (xy 406.814528 -53.087778)
			(xy 406.8419 -53.088209) (xy 406.896081 -53.096032) (xy 406.948585 -53.111528) (xy 406.998332 -53.134379)
			(xy 407.044296 -53.164112) (xy 407.065226 -53.181758) (xy 407.06548 -53.182012) (xy 407.072567 -53.187598)
			(xy 407.089484 -53.193845) (xy 407.0985 -53.194204) (xy 407.165556 -53.194204) (xy 407.174571 -53.193825)
			(xy 407.191488 -53.187593) (xy 407.198576 -53.182012) (xy 407.199084 -53.181504) (xy 407.220005 -53.163906)
			(xy 407.265944 -53.134269) (xy 407.315642 -53.111493) (xy 407.368084 -53.096047) (xy 407.422193 -53.088245)
			(xy 407.449528 -53.087778) (xy 407.476777 -53.088294) (xy 407.53072 -53.096054) (xy 407.583009 -53.111411)
			(xy 407.632581 -53.134052) (xy 407.678426 -53.163518) (xy 407.719611 -53.199209) (xy 407.755298 -53.240396)
			(xy 407.784761 -53.286244) (xy 407.807399 -53.335817) (xy 407.822752 -53.388108) (xy 407.830508 -53.442051)
			(xy 407.830508 -53.496549) (xy 407.822752 -53.550492) (xy 407.807399 -53.602783) (xy 407.784761 -53.652356)
			(xy 407.755298 -53.698204) (xy 407.719611 -53.739391) (xy 407.678426 -53.775082) (xy 407.632581 -53.804548)
			(xy 407.583009 -53.827189) (xy 407.53072 -53.842546) (xy 407.476777 -53.850306) (xy 407.449528 -53.850794)
			(xy 407.422158 -53.850313) (xy 407.36798 -53.842499) (xy 407.315477 -53.827013) (xy 407.26573 -53.804175)
			(xy 407.219762 -53.774454) (xy 407.19883 -53.756814) (xy 407.198576 -53.75656) (xy 407.191504 -53.750952)
			(xy 407.174576 -53.744719) (xy 407.165556 -53.744368) (xy 407.0985 -53.744368) (xy 407.089484 -53.744732)
			(xy 407.072567 -53.750976) (xy 407.06548 -53.75656) (xy 407.064972 -53.757068) (xy 407.044026 -53.774635)
			(xy 406.998095 -53.804278) (xy 406.948402 -53.82706) (xy 406.895966 -53.842514) (xy 406.841861 -53.850323)
			(xy 406.814528 -53.850794) (xy 406.787273 -53.850361) (xy 406.733317 -53.842607) (xy 406.681014 -53.827253)
			(xy 406.631428 -53.804611) (xy 406.58557 -53.775143) (xy 406.544372 -53.739448) (xy 406.508674 -53.698253)
			(xy 406.479202 -53.652397) (xy 406.456557 -53.602813) (xy 406.441199 -53.550511) (xy 406.433441 -53.496555)
			(xy 394.14371 -53.496555) (xy 394.147283 -53.502115) (xy 394.169925 -53.551692) (xy 394.18528 -53.603987)
			(xy 394.193036 -53.657935) (xy 394.193522 -53.685186) (xy 394.193066 -53.71252) (xy 394.185253 -53.766628)
			(xy 394.1698 -53.819066) (xy 394.147022 -53.868764) (xy 394.117386 -53.914703) (xy 394.099796 -53.93563)
			(xy 394.099542 -53.935884) (xy 394.099288 -53.936138) (xy 394.09372 -53.943237) (xy 394.087462 -53.960144)
			(xy 394.087096 -53.969158) (xy 394.087096 -54.036214) (xy 394.087447 -54.045231) (xy 394.093699 -54.062148)
			(xy 394.099288 -54.069234) (xy 394.099542 -54.069488) (xy 394.099796 -54.069742) (xy 394.117374 -54.090679)
			(xy 394.147015 -54.136613) (xy 394.169794 -54.186308) (xy 394.185245 -54.238746) (xy 394.193052 -54.292853)
			(xy 394.193522 -54.320186) (xy 394.193036 -54.347437) (xy 394.18528 -54.401385) (xy 394.169925 -54.45368)
			(xy 394.147283 -54.503257) (xy 394.117817 -54.549107) (xy 394.082126 -54.590298) (xy 394.040935 -54.625989)
			(xy 393.995085 -54.655455) (xy 393.945508 -54.678097) (xy 393.893213 -54.693452) (xy 393.839265 -54.701208)
			(xy 393.784763 -54.701208) (xy 393.730815 -54.693452) (xy 393.67852 -54.678097) (xy 393.628943 -54.655455)
			(xy 393.583093 -54.625989) (xy 393.541902 -54.590298) (xy 393.506211 -54.549107) (xy 393.476745 -54.503257)
			(xy 393.454103 -54.45368) (xy 393.438748 -54.401385) (xy 393.430992 -54.347437) (xy 393.430506 -54.320186)
			(xy 391.201967 -54.320186) (xy 391.193025 -54.339689) (xy 391.163375 -54.385623) (xy 391.145776 -54.406546)
			(xy 391.145522 -54.4068) (xy 391.145268 -54.407054) (xy 391.139691 -54.414147) (xy 391.13344 -54.431059)
			(xy 391.133076 -54.440074) (xy 391.133076 -54.50713) (xy 391.133424 -54.516148) (xy 391.139678 -54.533064)
			(xy 391.145268 -54.54015) (xy 391.145522 -54.540404) (xy 391.145776 -54.540658) (xy 391.163359 -54.561592)
			(xy 391.192999 -54.607526) (xy 391.215778 -54.657222) (xy 391.231228 -54.709661) (xy 391.239033 -54.763768)
			(xy 391.239149 -54.770528) (xy 394.371068 -54.770528) (xy 394.37151 -54.743193) (xy 394.379323 -54.689084)
			(xy 394.394778 -54.636644) (xy 394.41756 -54.586947) (xy 394.447201 -54.54101) (xy 394.464794 -54.520084)
			(xy 394.465048 -54.51983) (xy 394.465302 -54.519576) (xy 394.470905 -54.512501) (xy 394.477142 -54.495575)
			(xy 394.477494 -54.486556) (xy 394.477494 -54.4195) (xy 394.477138 -54.410483) (xy 394.47089 -54.393566)
			(xy 394.465302 -54.38648) (xy 394.465048 -54.386226) (xy 394.464794 -54.385972) (xy 394.447221 -54.365031)
			(xy 394.41758 -54.319098) (xy 394.3948 -54.269404) (xy 394.379347 -54.216967) (xy 394.371539 -54.162861)
			(xy 394.371068 -54.135528) (xy 394.371554 -54.108277) (xy 394.37931 -54.054329) (xy 394.394665 -54.002034)
			(xy 394.417307 -53.952457) (xy 394.446773 -53.906607) (xy 394.482464 -53.865416) (xy 394.523655 -53.829725)
			(xy 394.569505 -53.800259) (xy 394.619082 -53.777617) (xy 394.671377 -53.762262) (xy 394.725325 -53.754506)
			(xy 394.779827 -53.754506) (xy 394.833775 -53.762262) (xy 394.88607 -53.777617) (xy 394.935647 -53.800259)
			(xy 394.981497 -53.829725) (xy 395.022688 -53.865416) (xy 395.058379 -53.906607) (xy 395.087845 -53.952457)
			(xy 395.09292 -53.96357) (xy 399.072098 -53.96357) (xy 399.076169 -53.907948) (xy 399.088295 -53.853511)
			(xy 399.108218 -53.80142) (xy 399.135514 -53.752785) (xy 399.1696 -53.708642) (xy 399.209749 -53.669933)
			(xy 399.255107 -53.637482) (xy 399.304707 -53.611981) (xy 399.357491 -53.593974) (xy 399.412334 -53.583844)
			(xy 399.468068 -53.581807) (xy 399.523505 -53.587907) (xy 399.577462 -53.602013) (xy 399.628791 -53.623825)
			(xy 399.676397 -53.652879) (xy 399.719265 -53.688554) (xy 399.756482 -53.730091) (xy 399.787255 -53.776604)
			(xy 399.810927 -53.827101) (xy 399.826995 -53.880508) (xy 399.835115 -53.935684) (xy 399.835624 -53.96357)
			(xy 399.835115 -53.991456) (xy 399.826995 -54.046632) (xy 399.82073 -54.067456) (xy 401.241258 -54.067456)
			(xy 401.245329 -54.011834) (xy 401.257455 -53.957397) (xy 401.277378 -53.905306) (xy 401.304674 -53.856671)
			(xy 401.33876 -53.812528) (xy 401.378909 -53.773819) (xy 401.424267 -53.741368) (xy 401.473867 -53.715867)
			(xy 401.526651 -53.69786) (xy 401.581494 -53.68773) (xy 401.637228 -53.685693) (xy 401.692665 -53.691793)
			(xy 401.746622 -53.705899) (xy 401.797951 -53.727711) (xy 401.845557 -53.756765) (xy 401.888425 -53.79244)
			(xy 401.925642 -53.833977) (xy 401.956415 -53.88049) (xy 401.980087 -53.930987) (xy 401.996155 -53.984394)
			(xy 402.004275 -54.03957) (xy 402.004784 -54.067456) (xy 402.004275 -54.095342) (xy 401.996155 -54.150518)
			(xy 401.980087 -54.203925) (xy 401.963689 -54.238906) (xy 408.685998 -54.238906) (xy 408.690069 -54.183284)
			(xy 408.702195 -54.128847) (xy 408.722118 -54.076756) (xy 408.749414 -54.028121) (xy 408.7835 -53.983978)
			(xy 408.823649 -53.945269) (xy 408.869007 -53.912818) (xy 408.918607 -53.887317) (xy 408.971391 -53.86931)
			(xy 409.026234 -53.85918) (xy 409.081968 -53.857143) (xy 409.137405 -53.863243) (xy 409.191362 -53.877349)
			(xy 409.242691 -53.899161) (xy 409.290297 -53.928215) (xy 409.333165 -53.96389) (xy 409.370382 -54.005427)
			(xy 409.401155 -54.05194) (xy 409.424827 -54.102437) (xy 409.440895 -54.155844) (xy 409.449015 -54.21102)
			(xy 409.449524 -54.238906) (xy 409.449015 -54.266792) (xy 409.440895 -54.321968) (xy 409.424827 -54.375375)
			(xy 409.401155 -54.425872) (xy 409.370382 -54.472385) (xy 409.333165 -54.513922) (xy 409.290297 -54.549597)
			(xy 409.242691 -54.578651) (xy 409.191362 -54.600463) (xy 409.137405 -54.614569) (xy 409.081968 -54.620669)
			(xy 409.026234 -54.618632) (xy 408.971391 -54.608502) (xy 408.918607 -54.590495) (xy 408.869007 -54.564994)
			(xy 408.823649 -54.532543) (xy 408.7835 -54.493834) (xy 408.749414 -54.449691) (xy 408.722118 -54.401056)
			(xy 408.702195 -54.348965) (xy 408.690069 -54.294528) (xy 408.685998 -54.238906) (xy 401.963689 -54.238906)
			(xy 401.956415 -54.254422) (xy 401.925642 -54.300935) (xy 401.888425 -54.342472) (xy 401.845557 -54.378147)
			(xy 401.797951 -54.407201) (xy 401.746622 -54.429013) (xy 401.692665 -54.443119) (xy 401.637228 -54.449219)
			(xy 401.581494 -54.447182) (xy 401.526651 -54.437052) (xy 401.473867 -54.419045) (xy 401.424267 -54.393544)
			(xy 401.378909 -54.361093) (xy 401.33876 -54.322384) (xy 401.304674 -54.278241) (xy 401.277378 -54.229606)
			(xy 401.257455 -54.177515) (xy 401.245329 -54.123078) (xy 401.241258 -54.067456) (xy 399.82073 -54.067456)
			(xy 399.810927 -54.100039) (xy 399.787255 -54.150536) (xy 399.756482 -54.197049) (xy 399.719265 -54.238586)
			(xy 399.676397 -54.274261) (xy 399.628791 -54.303315) (xy 399.577462 -54.325127) (xy 399.523505 -54.339233)
			(xy 399.468068 -54.345333) (xy 399.412334 -54.343296) (xy 399.357491 -54.333166) (xy 399.304707 -54.315159)
			(xy 399.255107 -54.289658) (xy 399.209749 -54.257207) (xy 399.1696 -54.218498) (xy 399.135514 -54.174355)
			(xy 399.108218 -54.12572) (xy 399.088295 -54.073629) (xy 399.076169 -54.019192) (xy 399.072098 -53.96357)
			(xy 395.09292 -53.96357) (xy 395.110487 -54.002034) (xy 395.125842 -54.054329) (xy 395.133598 -54.108277)
			(xy 395.134084 -54.135528) (xy 395.133603 -54.162861) (xy 395.125798 -54.216968) (xy 395.110351 -54.269407)
			(xy 395.087578 -54.319105) (xy 395.057947 -54.365044) (xy 395.040358 -54.385972) (xy 395.040104 -54.386226)
			(xy 395.03985 -54.38648) (xy 395.03426 -54.393564) (xy 395.028016 -54.410483) (xy 395.027658 -54.4195)
			(xy 395.027658 -54.486556) (xy 395.028023 -54.495572) (xy 395.034264 -54.51249) (xy 395.03985 -54.519576)
			(xy 395.040104 -54.51983) (xy 395.040358 -54.520084) (xy 395.05795 -54.54101) (xy 395.08759 -54.586946)
			(xy 395.110367 -54.636644) (xy 395.125815 -54.689085) (xy 395.133617 -54.743194) (xy 395.134084 -54.770528)
			(xy 395.133598 -54.797779) (xy 395.125842 -54.851727) (xy 395.110487 -54.904022) (xy 395.087845 -54.953599)
			(xy 395.058379 -54.999449) (xy 395.022688 -55.04064) (xy 394.981497 -55.076331) (xy 394.97041 -55.083456)
			(xy 401.241258 -55.083456) (xy 401.245329 -55.027834) (xy 401.257455 -54.973397) (xy 401.277378 -54.921306)
			(xy 401.304674 -54.872671) (xy 401.33876 -54.828528) (xy 401.378909 -54.789819) (xy 401.424267 -54.757368)
			(xy 401.473867 -54.731867) (xy 401.526651 -54.71386) (xy 401.581494 -54.70373) (xy 401.637228 -54.701693)
			(xy 401.692665 -54.707793) (xy 401.746622 -54.721899) (xy 401.797951 -54.743711) (xy 401.845557 -54.772765)
			(xy 401.888425 -54.80844) (xy 401.925642 -54.849977) (xy 401.956415 -54.89649) (xy 401.980087 -54.946987)
			(xy 401.992744 -54.989055) (xy 404.201045 -54.989055) (xy 404.201045 -54.934545) (xy 404.208803 -54.880591)
			(xy 404.22416 -54.82829) (xy 404.246805 -54.778707) (xy 404.276276 -54.732852) (xy 404.311973 -54.691657)
			(xy 404.353169 -54.655963) (xy 404.399026 -54.626494) (xy 404.448611 -54.603853) (xy 404.500913 -54.588498)
			(xy 404.554867 -54.580743) (xy 404.582122 -54.580282) (xy 404.610214 -54.580759) (xy 404.665792 -54.58899)
			(xy 404.719562 -54.605284) (xy 404.770359 -54.629289) (xy 404.817086 -54.660487) (xy 404.85873 -54.698201)
			(xy 404.894392 -54.741616) (xy 404.909274 -54.765448) (xy 404.914862 -54.774592) (xy 404.93188 -54.786784)
			(xy 405.024844 -54.80685) (xy 405.045418 -54.802786) (xy 405.054054 -54.79669) (xy 405.078128 -54.780706)
			(xy 405.130056 -54.75536) (xy 405.185211 -54.73813) (xy 405.242332 -54.72941) (xy 405.271224 -54.728872)
			(xy 405.298475 -54.729355) (xy 405.312775 -54.731412) (xy 413.82061 -54.731412) (xy 413.821057 -54.704077)
			(xy 413.828871 -54.649969) (xy 413.844326 -54.59753) (xy 413.867106 -54.547833) (xy 413.896744 -54.501895)
			(xy 413.914336 -54.480968) (xy 413.91459 -54.480714) (xy 413.914844 -54.48046) (xy 413.920417 -54.473364)
			(xy 413.926671 -54.456454) (xy 413.927036 -54.44744) (xy 413.927036 -54.380384) (xy 413.926679 -54.371367)
			(xy 413.920431 -54.354451) (xy 413.914844 -54.347364) (xy 413.91459 -54.34711) (xy 413.914336 -54.346856)
			(xy 413.896749 -54.325924) (xy 413.867098 -54.279992) (xy 413.84431 -54.230296) (xy 413.828854 -54.177855)
			(xy 413.821045 -54.123745) (xy 413.821043 -54.069073) (xy 413.82885 -54.014963) (xy 413.844304 -53.962521)
			(xy 413.867089 -53.912824) (xy 413.896738 -53.866891) (xy 413.914336 -53.845968) (xy 413.91459 -53.845714)
			(xy 413.914844 -53.84546) (xy 413.920417 -53.838364) (xy 413.926671 -53.821454) (xy 413.927036 -53.81244)
			(xy 413.927036 -53.745384) (xy 413.926679 -53.736367) (xy 413.920431 -53.719451) (xy 413.914844 -53.712364)
			(xy 413.91459 -53.71211) (xy 413.914336 -53.711856) (xy 413.896749 -53.690924) (xy 413.867098 -53.644992)
			(xy 413.84431 -53.595296) (xy 413.828854 -53.542855) (xy 413.821045 -53.488745) (xy 413.821043 -53.434073)
			(xy 413.82885 -53.379963) (xy 413.844304 -53.327521) (xy 413.867089 -53.277824) (xy 413.896738 -53.231891)
			(xy 413.914336 -53.210968) (xy 413.91459 -53.210714) (xy 413.914844 -53.21046) (xy 413.920417 -53.203364)
			(xy 413.926671 -53.186454) (xy 413.927036 -53.17744) (xy 413.927036 -53.110384) (xy 413.926679 -53.101367)
			(xy 413.920431 -53.084451) (xy 413.914844 -53.077364) (xy 413.91459 -53.07711) (xy 413.914336 -53.076856)
			(xy 413.896762 -53.055915) (xy 413.86712 -53.009983) (xy 413.844339 -52.960289) (xy 413.828887 -52.907852)
			(xy 413.82108 -52.853745) (xy 413.82061 -52.826412) (xy 413.821096 -52.799161) (xy 413.828852 -52.745213)
			(xy 413.844207 -52.692918) (xy 413.866849 -52.643341) (xy 413.896315 -52.597491) (xy 413.932006 -52.5563)
			(xy 413.973197 -52.520609) (xy 414.019047 -52.491143) (xy 414.068624 -52.468501) (xy 414.120919 -52.453146)
			(xy 414.174867 -52.44539) (xy 414.229369 -52.44539) (xy 414.283317 -52.453146) (xy 414.335612 -52.468501)
			(xy 414.385189 -52.491143) (xy 414.431039 -52.520609) (xy 414.47223 -52.5563) (xy 414.507921 -52.597491)
			(xy 414.537387 -52.643341) (xy 414.560029 -52.692918) (xy 414.575384 -52.745213) (xy 414.58314 -52.799161)
			(xy 414.583626 -52.826412) (xy 414.58315 -52.853746) (xy 414.575346 -52.907853) (xy 414.559898 -52.960293)
			(xy 414.537124 -53.009991) (xy 414.50749 -53.055929) (xy 414.4899 -53.076856) (xy 414.489646 -53.07711)
			(xy 414.489392 -53.077364) (xy 414.483813 -53.084456) (xy 414.477562 -53.101369) (xy 414.4772 -53.110384)
			(xy 414.4772 -53.17744) (xy 414.477538 -53.186459) (xy 414.483799 -53.203376) (xy 414.489392 -53.21046)
			(xy 414.489646 -53.210714) (xy 414.4899 -53.210968) (xy 414.507513 -53.23188) (xy 414.537168 -53.277814)
			(xy 414.559958 -53.327513) (xy 414.575416 -53.379957) (xy 414.583224 -53.434072) (xy 414.583223 -53.488746)
			(xy 414.575412 -53.542861) (xy 414.559952 -53.595304) (xy 414.53716 -53.645002) (xy 414.507503 -53.690935)
			(xy 414.4899 -53.711856) (xy 414.489646 -53.71211) (xy 414.489392 -53.712364) (xy 414.483813 -53.719456)
			(xy 414.477562 -53.736369) (xy 414.4772 -53.745384) (xy 414.4772 -53.81244) (xy 414.477538 -53.821459)
			(xy 414.483799 -53.838376) (xy 414.489392 -53.84546) (xy 414.489646 -53.845714) (xy 414.4899 -53.845968)
			(xy 414.507513 -53.86688) (xy 414.537168 -53.912814) (xy 414.559958 -53.962513) (xy 414.575416 -54.014957)
			(xy 414.583224 -54.069072) (xy 414.583223 -54.123746) (xy 414.575412 -54.177861) (xy 414.559952 -54.230304)
			(xy 414.53716 -54.280002) (xy 414.507503 -54.325935) (xy 414.4899 -54.346856) (xy 414.489646 -54.34711)
			(xy 414.489392 -54.347364) (xy 414.483813 -54.354456) (xy 414.477562 -54.371369) (xy 414.4772 -54.380384)
			(xy 414.4772 -54.44744) (xy 414.477538 -54.456459) (xy 414.483799 -54.473376) (xy 414.489392 -54.48046)
			(xy 414.489646 -54.480714) (xy 414.4899 -54.480968) (xy 414.507491 -54.501895) (xy 414.537129 -54.547832)
			(xy 414.559906 -54.597529) (xy 414.575354 -54.649969) (xy 414.583157 -54.704078) (xy 414.583626 -54.731412)
			(xy 414.58314 -54.758663) (xy 414.578476 -54.791102) (xy 416.476434 -54.791102) (xy 416.476928 -54.763769)
			(xy 416.48473 -54.709663) (xy 416.500173 -54.657224) (xy 416.522943 -54.607526) (xy 416.552572 -54.561586)
			(xy 416.57016 -54.540658) (xy 416.570414 -54.540404) (xy 416.570668 -54.54015) (xy 416.576248 -54.533059)
			(xy 416.582497 -54.516145) (xy 416.58286 -54.50713) (xy 416.58286 -54.440074) (xy 416.582524 -54.431055)
			(xy 416.576263 -54.414137) (xy 416.570668 -54.407054) (xy 416.570414 -54.4068) (xy 416.57016 -54.406546)
			(xy 416.552562 -54.385622) (xy 416.52291 -54.339689) (xy 416.500121 -54.289992) (xy 416.484664 -54.23755)
			(xy 416.476856 -54.183438) (xy 416.476856 -54.128765) (xy 416.484664 -54.074653) (xy 416.50012 -54.022211)
			(xy 416.522908 -53.972513) (xy 416.55256 -53.92658) (xy 416.57016 -53.905658) (xy 416.570414 -53.905404)
			(xy 416.570668 -53.90515) (xy 416.576248 -53.898059) (xy 416.582497 -53.881145) (xy 416.58286 -53.87213)
			(xy 416.58286 -53.805074) (xy 416.582524 -53.796055) (xy 416.576263 -53.779137) (xy 416.570668 -53.772054)
			(xy 416.570414 -53.7718) (xy 416.57016 -53.771546) (xy 416.552562 -53.750622) (xy 416.52291 -53.704689)
			(xy 416.500121 -53.654992) (xy 416.484664 -53.60255) (xy 416.476856 -53.548438) (xy 416.476856 -53.493765)
			(xy 416.484664 -53.439653) (xy 416.50012 -53.387211) (xy 416.522908 -53.337513) (xy 416.55256 -53.29158)
			(xy 416.57016 -53.270658) (xy 416.570414 -53.270404) (xy 416.570668 -53.27015) (xy 416.576248 -53.263059)
			(xy 416.582497 -53.246145) (xy 416.58286 -53.23713) (xy 416.58286 -53.170074) (xy 416.582524 -53.161055)
			(xy 416.576263 -53.144137) (xy 416.570668 -53.137054) (xy 416.570414 -53.1368) (xy 416.57016 -53.136546)
			(xy 416.552569 -53.115619) (xy 416.522932 -53.069682) (xy 416.500156 -53.019984) (xy 416.484708 -52.967544)
			(xy 416.476903 -52.913436) (xy 416.476434 -52.886102) (xy 416.47692 -52.858851) (xy 416.484676 -52.804903)
			(xy 416.500031 -52.752608) (xy 416.522673 -52.703031) (xy 416.552139 -52.657181) (xy 416.58783 -52.61599)
			(xy 416.629021 -52.580299) (xy 416.674871 -52.550833) (xy 416.724448 -52.528191) (xy 416.776743 -52.512836)
			(xy 416.830691 -52.50508) (xy 416.885193 -52.50508) (xy 416.939141 -52.512836) (xy 416.953459 -52.51704)
			(xy 421.140126 -52.51704) (xy 421.144197 -52.461418) (xy 421.156323 -52.406981) (xy 421.176246 -52.35489)
			(xy 421.203542 -52.306255) (xy 421.237628 -52.262112) (xy 421.277777 -52.223403) (xy 421.323135 -52.190952)
			(xy 421.372735 -52.165451) (xy 421.425519 -52.147444) (xy 421.480362 -52.137314) (xy 421.536096 -52.135277)
			(xy 421.591533 -52.141377) (xy 421.64549 -52.155483) (xy 421.696819 -52.177295) (xy 421.744425 -52.206349)
			(xy 421.787293 -52.242024) (xy 421.82451 -52.283561) (xy 421.855283 -52.330074) (xy 421.878955 -52.380571)
			(xy 421.895023 -52.433978) (xy 421.903143 -52.489154) (xy 421.903652 -52.51704) (xy 421.903143 -52.544926)
			(xy 421.896893 -52.587398) (xy 425.055282 -52.587398) (xy 425.059353 -52.531776) (xy 425.071479 -52.477339)
			(xy 425.091402 -52.425248) (xy 425.118698 -52.376613) (xy 425.152784 -52.33247) (xy 425.192933 -52.293761)
			(xy 425.238291 -52.26131) (xy 425.287891 -52.235809) (xy 425.340675 -52.217802) (xy 425.395518 -52.207672)
			(xy 425.451252 -52.205635) (xy 425.506689 -52.211735) (xy 425.560646 -52.225841) (xy 425.611975 -52.247653)
			(xy 425.659581 -52.276707) (xy 425.702449 -52.312382) (xy 425.739666 -52.353919) (xy 425.770439 -52.400432)
			(xy 425.794111 -52.450929) (xy 425.810179 -52.504336) (xy 425.818299 -52.559512) (xy 425.818384 -52.564153)
			(xy 430.12713 -52.564153) (xy 430.12713 -52.509647) (xy 430.134886 -52.455697) (xy 430.150241 -52.403399)
			(xy 430.172882 -52.353818) (xy 430.202348 -52.307964) (xy 430.238039 -52.26677) (xy 430.279229 -52.231074)
			(xy 430.32508 -52.201603) (xy 430.374658 -52.178956) (xy 430.426954 -52.163595) (xy 430.480903 -52.155833)
			(xy 430.508156 -52.155344) (xy 430.535526 -52.155825) (xy 430.589705 -52.163638) (xy 430.642208 -52.179123)
			(xy 430.691955 -52.201961) (xy 430.737922 -52.231684) (xy 430.758854 -52.249324) (xy 430.759108 -52.249578)
			(xy 430.766181 -52.255183) (xy 430.783109 -52.261417) (xy 430.792128 -52.26177) (xy 430.859184 -52.26177)
			(xy 430.868201 -52.261412) (xy 430.885118 -52.255166) (xy 430.892204 -52.249578) (xy 430.892712 -52.24907)
			(xy 430.913619 -52.231454) (xy 430.959561 -52.20182) (xy 431.009264 -52.179049) (xy 431.061709 -52.163606)
			(xy 431.115821 -52.155809) (xy 431.143156 -52.155344) (xy 431.170407 -52.1559) (xy 431.224356 -52.163651)
			(xy 431.276653 -52.179001) (xy 431.326232 -52.201639) (xy 431.372085 -52.231102) (xy 431.413278 -52.266791)
			(xy 431.448972 -52.307979) (xy 431.47844 -52.353829) (xy 431.501083 -52.403406) (xy 431.51644 -52.455701)
			(xy 431.524197 -52.509649) (xy 431.524197 -52.555952) (xy 432.883779 -52.555952) (xy 432.883779 -52.501448)
			(xy 432.891536 -52.447499) (xy 432.906892 -52.395203) (xy 432.929535 -52.345625) (xy 432.959002 -52.299774)
			(xy 432.994696 -52.258583) (xy 433.035888 -52.222892) (xy 433.081741 -52.193426) (xy 433.13132 -52.170786)
			(xy 433.183617 -52.155432) (xy 433.237566 -52.147678) (xy 433.264818 -52.147216) (xy 433.292189 -52.147668)
			(xy 433.346369 -52.155488) (xy 433.398872 -52.170981) (xy 433.448619 -52.193826) (xy 433.494585 -52.223553)
			(xy 433.515516 -52.241196) (xy 433.51577 -52.24145) (xy 433.522857 -52.247036) (xy 433.539774 -52.253282)
			(xy 433.54879 -52.253642) (xy 433.615846 -52.253642) (xy 433.624862 -52.253272) (xy 433.64178 -52.247035)
			(xy 433.648866 -52.24145) (xy 433.649374 -52.240942) (xy 433.670304 -52.223355) (xy 433.716239 -52.193714)
			(xy 433.765936 -52.170936) (xy 433.818376 -52.155487) (xy 433.872484 -52.147684) (xy 433.899818 -52.147216)
			(xy 433.92707 -52.147655) (xy 433.981019 -52.155414) (xy 434.033315 -52.170772) (xy 434.082893 -52.193415)
			(xy 434.128744 -52.222884) (xy 434.169935 -52.258578) (xy 434.205627 -52.29977) (xy 434.235093 -52.345623)
			(xy 434.257734 -52.395202) (xy 434.27309 -52.447498) (xy 434.280846 -52.501448) (xy 434.280846 -52.555952)
			(xy 434.27309 -52.609902) (xy 434.257734 -52.662198) (xy 434.235093 -52.711777) (xy 434.205627 -52.75763)
			(xy 434.169935 -52.798822) (xy 434.128744 -52.834516) (xy 434.082893 -52.863985) (xy 434.033315 -52.886628)
			(xy 433.981019 -52.901986) (xy 433.92707 -52.909745) (xy 433.899818 -52.910232) (xy 433.872447 -52.909772)
			(xy 433.818267 -52.901955) (xy 433.765764 -52.886466) (xy 433.716017 -52.863622) (xy 433.670051 -52.833895)
			(xy 433.64912 -52.816252) (xy 433.648866 -52.815998) (xy 433.641765 -52.810433) (xy 433.624859 -52.804173)
			(xy 433.615846 -52.803806) (xy 433.54879 -52.803806) (xy 433.539772 -52.804157) (xy 433.522856 -52.810409)
			(xy 433.51577 -52.815998) (xy 433.515262 -52.816506) (xy 433.494325 -52.834084) (xy 433.448391 -52.863724)
			(xy 433.398696 -52.886503) (xy 433.346258 -52.901955) (xy 433.292151 -52.909761) (xy 433.264818 -52.910232)
			(xy 433.237566 -52.909722) (xy 433.183617 -52.901968) (xy 433.13132 -52.886614) (xy 433.081741 -52.863974)
			(xy 433.035888 -52.834508) (xy 432.994696 -52.798817) (xy 432.959002 -52.757626) (xy 432.929535 -52.711775)
			(xy 432.906892 -52.662197) (xy 432.891536 -52.609901) (xy 432.883779 -52.555952) (xy 431.524197 -52.555952)
			(xy 431.524197 -52.564151) (xy 431.51644 -52.618099) (xy 431.501083 -52.670394) (xy 431.47844 -52.719971)
			(xy 431.448972 -52.765821) (xy 431.413278 -52.807009) (xy 431.372085 -52.842698) (xy 431.326232 -52.872161)
			(xy 431.276653 -52.894799) (xy 431.224356 -52.910149) (xy 431.170407 -52.9179) (xy 431.143156 -52.91836)
			(xy 431.115786 -52.917871) (xy 431.061608 -52.91006) (xy 431.009105 -52.894577) (xy 430.959357 -52.87174)
			(xy 430.91339 -52.84202) (xy 430.892458 -52.82438) (xy 430.892204 -52.824126) (xy 430.885127 -52.818526)
			(xy 430.868203 -52.812289) (xy 430.859184 -52.811934) (xy 430.792128 -52.811934) (xy 430.783112 -52.812297)
			(xy 430.766194 -52.81854) (xy 430.759108 -52.824126) (xy 430.7586 -52.824634) (xy 430.737689 -52.842245)
			(xy 430.691748 -52.87188) (xy 430.642046 -52.894652) (xy 430.589602 -52.910095) (xy 430.535491 -52.917894)
			(xy 430.508156 -52.91836) (xy 430.480903 -52.917967) (xy 430.426954 -52.910205) (xy 430.374658 -52.894844)
			(xy 430.32508 -52.872197) (xy 430.279229 -52.842726) (xy 430.238039 -52.80703) (xy 430.202348 -52.765836)
			(xy 430.172882 -52.719982) (xy 430.150241 -52.670401) (xy 430.134886 -52.618103) (xy 430.12713 -52.564153)
			(xy 425.818384 -52.564153) (xy 425.818808 -52.587398) (xy 425.818299 -52.615284) (xy 425.810179 -52.67046)
			(xy 425.794111 -52.723867) (xy 425.770439 -52.774364) (xy 425.739666 -52.820877) (xy 425.702449 -52.862414)
			(xy 425.659581 -52.898089) (xy 425.611975 -52.927143) (xy 425.560646 -52.948955) (xy 425.506689 -52.963061)
			(xy 425.451252 -52.969161) (xy 425.395518 -52.967124) (xy 425.340675 -52.956994) (xy 425.287891 -52.938987)
			(xy 425.238291 -52.913486) (xy 425.192933 -52.881035) (xy 425.152784 -52.842326) (xy 425.118698 -52.798183)
			(xy 425.091402 -52.749548) (xy 425.071479 -52.697457) (xy 425.059353 -52.64302) (xy 425.055282 -52.587398)
			(xy 421.896893 -52.587398) (xy 421.895023 -52.600102) (xy 421.878955 -52.653509) (xy 421.855283 -52.704006)
			(xy 421.82451 -52.750519) (xy 421.787293 -52.792056) (xy 421.744425 -52.827731) (xy 421.696819 -52.856785)
			(xy 421.64549 -52.878597) (xy 421.591533 -52.892703) (xy 421.536096 -52.898803) (xy 421.480362 -52.896766)
			(xy 421.425519 -52.886636) (xy 421.372735 -52.868629) (xy 421.323135 -52.843128) (xy 421.277777 -52.810677)
			(xy 421.237628 -52.771968) (xy 421.203542 -52.727825) (xy 421.176246 -52.67919) (xy 421.156323 -52.627099)
			(xy 421.144197 -52.572662) (xy 421.140126 -52.51704) (xy 416.953459 -52.51704) (xy 416.991436 -52.528191)
			(xy 417.041013 -52.550833) (xy 417.086863 -52.580299) (xy 417.128054 -52.61599) (xy 417.163745 -52.657181)
			(xy 417.193211 -52.703031) (xy 417.215853 -52.752608) (xy 417.231208 -52.804903) (xy 417.238964 -52.858851)
			(xy 417.23945 -52.886102) (xy 417.238962 -52.913435) (xy 417.23116 -52.967542) (xy 417.215715 -53.019981)
			(xy 417.192944 -53.069679) (xy 417.163313 -53.115618) (xy 417.145724 -53.136546) (xy 417.14547 -53.1368)
			(xy 417.145216 -53.137054) (xy 417.139644 -53.144151) (xy 417.133388 -53.16106) (xy 417.133024 -53.170074)
			(xy 417.133024 -53.23713) (xy 417.133361 -53.246149) (xy 417.139622 -53.263066) (xy 417.145216 -53.27015)
			(xy 417.14547 -53.270404) (xy 417.145724 -53.270658) (xy 417.163327 -53.291578) (xy 417.19298 -53.337512)
			(xy 417.215769 -53.387209) (xy 417.231226 -53.439652) (xy 417.239035 -53.493765) (xy 417.239035 -53.548438)
			(xy 417.231226 -53.602551) (xy 417.215768 -53.654994) (xy 417.192979 -53.704691) (xy 417.163325 -53.750624)
			(xy 417.146579 -53.77053) (xy 417.510722 -53.77053) (xy 417.511254 -53.741613) (xy 417.519979 -53.684443)
			(xy 417.537233 -53.629244) (xy 417.562623 -53.577282) (xy 417.595564 -53.529747) (xy 417.635303 -53.48773)
			(xy 417.657788 -53.46954) (xy 417.665164 -53.463248) (xy 417.674964 -53.44654) (xy 417.676838 -53.437028)
			(xy 417.677346 -53.429408) (xy 417.677346 -53.349652) (xy 417.676838 -53.342032) (xy 417.674969 -53.332518)
			(xy 417.665172 -53.315804) (xy 417.657788 -53.30952) (xy 417.635312 -53.291321) (xy 417.595577 -53.249302)
			(xy 417.562637 -53.201769) (xy 417.537248 -53.149809) (xy 417.51999 -53.094614) (xy 417.511258 -53.037445)
			(xy 417.510722 -53.00853) (xy 417.511183 -52.981277) (xy 417.518937 -52.927324) (xy 417.534291 -52.875024)
			(xy 417.556932 -52.825442) (xy 417.5864 -52.779587) (xy 417.622094 -52.738394) (xy 417.663287 -52.7027)
			(xy 417.709142 -52.673232) (xy 417.758724 -52.650591) (xy 417.811024 -52.635237) (xy 417.864977 -52.627483)
			(xy 417.89223 -52.627022) (xy 417.892484 -52.627022) (xy 417.918779 -52.627484) (xy 417.970868 -52.634728)
			(xy 418.021469 -52.649053) (xy 418.069625 -52.670188) (xy 418.114425 -52.697732) (xy 418.15502 -52.731165)
			(xy 418.173154 -52.750212) (xy 418.180705 -52.757678) (xy 418.200139 -52.766189) (xy 418.210746 -52.766722)
			(xy 418.284914 -52.766722) (xy 418.295545 -52.766306) (xy 418.315009 -52.757761) (xy 418.322506 -52.750212)
			(xy 418.340625 -52.731147) (xy 418.381209 -52.697691) (xy 418.426007 -52.670132) (xy 418.474169 -52.648995)
			(xy 418.52478 -52.634679) (xy 418.576878 -52.627458) (xy 418.603176 -52.627022) (xy 418.60343 -52.627022)
			(xy 418.630683 -52.62745) (xy 418.684635 -52.635211) (xy 418.736932 -52.650572) (xy 418.786512 -52.673219)
			(xy 418.832363 -52.702691) (xy 418.873554 -52.738388) (xy 418.909245 -52.779585) (xy 418.93871 -52.825441)
			(xy 418.961349 -52.875024) (xy 418.976701 -52.927324) (xy 418.984454 -52.981277) (xy 418.984938 -53.00853)
			(xy 418.984478 -53.036197) (xy 418.982247 -53.051456) (xy 427.241206 -53.051456) (xy 427.245277 -52.995834)
			(xy 427.257403 -52.941397) (xy 427.277326 -52.889306) (xy 427.304622 -52.840671) (xy 427.338708 -52.796528)
			(xy 427.378857 -52.757819) (xy 427.424215 -52.725368) (xy 427.473815 -52.699867) (xy 427.526599 -52.68186)
			(xy 427.581442 -52.67173) (xy 427.637176 -52.669693) (xy 427.692613 -52.675793) (xy 427.74657 -52.689899)
			(xy 427.797899 -52.711711) (xy 427.845505 -52.740765) (xy 427.888373 -52.77644) (xy 427.92559 -52.817977)
			(xy 427.956363 -52.86449) (xy 427.980035 -52.914987) (xy 427.996103 -52.968394) (xy 428.004223 -53.02357)
			(xy 428.004732 -53.051456) (xy 428.004223 -53.079342) (xy 427.996103 -53.134518) (xy 427.980035 -53.187925)
			(xy 427.956363 -53.238422) (xy 427.92559 -53.284935) (xy 427.888373 -53.326472) (xy 427.845505 -53.362147)
			(xy 427.797899 -53.391201) (xy 427.74657 -53.413013) (xy 427.692613 -53.427119) (xy 427.637176 -53.433219)
			(xy 427.581442 -53.431182) (xy 427.526599 -53.421052) (xy 427.473815 -53.403045) (xy 427.424215 -53.377544)
			(xy 427.378857 -53.345093) (xy 427.338708 -53.306384) (xy 427.304622 -53.262241) (xy 427.277326 -53.213606)
			(xy 427.257403 -53.161515) (xy 427.245277 -53.107078) (xy 427.241206 -53.051456) (xy 418.982247 -53.051456)
			(xy 418.976473 -53.09095) (xy 418.960649 -53.143974) (xy 418.937338 -53.194159) (xy 418.907028 -53.240455)
			(xy 418.870354 -53.28189) (xy 418.828083 -53.317599) (xy 418.804852 -53.332634) (xy 418.804598 -53.332888)
			(xy 418.795073 -53.339554) (xy 418.782766 -53.359248) (xy 418.780976 -53.370734) (xy 418.773102 -53.450744)
			(xy 418.772437 -53.462445) (xy 418.780518 -53.484417) (xy 418.788596 -53.492908) (xy 418.78885 -53.492908)
			(xy 418.807408 -53.511012) (xy 418.83999 -53.551338) (xy 418.866808 -53.595707) (xy 418.887365 -53.643301)
			(xy 418.901283 -53.693242) (xy 418.908304 -53.744608) (xy 418.908738 -53.77053) (xy 418.90825 -53.797781)
			(xy 418.90049 -53.851727) (xy 418.885133 -53.90402) (xy 418.862491 -53.953595) (xy 418.833024 -53.999444)
			(xy 418.797333 -54.040633) (xy 418.756144 -54.076324) (xy 418.710295 -54.105791) (xy 418.66072 -54.128433)
			(xy 418.608427 -54.14379) (xy 418.554481 -54.15155) (xy 418.52723 -54.152038) (xy 418.49986 -54.151569)
			(xy 418.44568 -54.143755) (xy 418.393176 -54.128267) (xy 418.343429 -54.105425) (xy 418.297463 -54.0757)
			(xy 418.276532 -54.058058) (xy 418.276278 -54.057804) (xy 418.269202 -54.052203) (xy 418.252277 -54.045965)
			(xy 418.243258 -54.045612) (xy 418.176202 -54.045612) (xy 418.167185 -54.045967) (xy 418.150268 -54.052216)
			(xy 418.143182 -54.057804) (xy 418.142674 -54.058312) (xy 418.121733 -54.075885) (xy 418.0758 -54.105526)
			(xy 418.026106 -54.128306) (xy 417.973669 -54.143758) (xy 417.919563 -54.151567) (xy 417.89223 -54.152038)
			(xy 417.864981 -54.151494) (xy 417.811037 -54.143742) (xy 417.758745 -54.128392) (xy 417.70917 -54.105757)
			(xy 417.663321 -54.076297) (xy 417.622131 -54.040611) (xy 417.586439 -53.999427) (xy 417.556972 -53.953583)
			(xy 417.534328 -53.904011) (xy 417.51897 -53.851722) (xy 417.51121 -53.797779) (xy 417.510722 -53.77053)
			(xy 417.146579 -53.77053) (xy 417.145724 -53.771546) (xy 417.14547 -53.7718) (xy 417.145216 -53.772054)
			(xy 417.139644 -53.779151) (xy 417.133388 -53.79606) (xy 417.133024 -53.805074) (xy 417.133024 -53.87213)
			(xy 417.133361 -53.881149) (xy 417.139622 -53.898066) (xy 417.145216 -53.90515) (xy 417.14547 -53.905404)
			(xy 417.145724 -53.905658) (xy 417.163327 -53.926578) (xy 417.19298 -53.972512) (xy 417.215769 -54.022209)
			(xy 417.231226 -54.074652) (xy 417.239035 -54.128765) (xy 417.239035 -54.183438) (xy 417.231226 -54.237551)
			(xy 417.215768 -54.289994) (xy 417.201923 -54.320186) (xy 419.430454 -54.320186) (xy 419.430934 -54.292852)
			(xy 419.438738 -54.238745) (xy 419.454185 -54.186306) (xy 419.476958 -54.136608) (xy 419.50659 -54.090669)
			(xy 419.52418 -54.069742) (xy 419.524434 -54.069488) (xy 419.524688 -54.069234) (xy 419.530265 -54.062141)
			(xy 419.536518 -54.045229) (xy 419.53688 -54.036214) (xy 419.53688 -53.969158) (xy 419.536499 -53.960143)
			(xy 419.530269 -53.943226) (xy 419.524688 -53.936138) (xy 419.524434 -53.935884) (xy 419.52418 -53.93563)
			(xy 419.506585 -53.914706) (xy 419.476948 -53.868768) (xy 419.454172 -53.81907) (xy 419.438725 -53.766629)
			(xy 419.430922 -53.71252) (xy 419.430454 -53.685186) (xy 419.43094 -53.657935) (xy 419.438696 -53.603987)
			(xy 419.454051 -53.551692) (xy 419.476693 -53.502115) (xy 419.506159 -53.456265) (xy 419.54185 -53.415074)
			(xy 419.583041 -53.379383) (xy 419.628891 -53.349917) (xy 419.678468 -53.327275) (xy 419.730763 -53.31192)
			(xy 419.784711 -53.304164) (xy 419.839213 -53.304164) (xy 419.893161 -53.31192) (xy 419.945456 -53.327275)
			(xy 419.995033 -53.349917) (xy 420.040883 -53.379383) (xy 420.082074 -53.415074) (xy 420.117765 -53.456265)
			(xy 420.143655 -53.496551) (xy 432.433464 -53.496551) (xy 432.433464 -53.442049) (xy 432.44122 -53.388101)
			(xy 432.456574 -53.335806) (xy 432.479215 -53.286229) (xy 432.50868 -53.240378) (xy 432.54437 -53.199187)
			(xy 432.585559 -53.163494) (xy 432.631408 -53.134026) (xy 432.680984 -53.111383) (xy 432.733278 -53.096025)
			(xy 432.787225 -53.088265) (xy 432.814476 -53.087778) (xy 432.841847 -53.088239) (xy 432.896027 -53.096055)
			(xy 432.948531 -53.111544) (xy 432.998277 -53.134388) (xy 433.044243 -53.164115) (xy 433.065174 -53.181758)
			(xy 433.065428 -53.182012) (xy 433.07253 -53.187576) (xy 433.089435 -53.193836) (xy 433.098448 -53.194204)
			(xy 433.165504 -53.194204) (xy 433.174521 -53.193848) (xy 433.191438 -53.1876) (xy 433.198524 -53.182012)
			(xy 433.199032 -53.181504) (xy 433.219973 -53.163931) (xy 433.265906 -53.134289) (xy 433.3156 -53.111509)
			(xy 433.368037 -53.096057) (xy 433.422143 -53.088249) (xy 433.449476 -53.087778) (xy 433.476729 -53.088268)
			(xy 433.530681 -53.096022) (xy 433.582979 -53.111375) (xy 433.632561 -53.134015) (xy 433.678415 -53.163482)
			(xy 433.719609 -53.199174) (xy 433.755304 -53.240366) (xy 433.784773 -53.286218) (xy 433.807417 -53.335798)
			(xy 433.822773 -53.388096) (xy 433.830531 -53.442047) (xy 433.830531 -53.496553) (xy 433.822773 -53.550504)
			(xy 433.807417 -53.602802) (xy 433.784773 -53.652382) (xy 433.755304 -53.698234) (xy 433.719609 -53.739426)
			(xy 433.678415 -53.775118) (xy 433.632561 -53.804585) (xy 433.582979 -53.827225) (xy 433.530681 -53.842578)
			(xy 433.476729 -53.850332) (xy 433.449476 -53.850794) (xy 433.422105 -53.850343) (xy 433.367925 -53.842522)
			(xy 433.315422 -53.827029) (xy 433.265675 -53.804184) (xy 433.219709 -53.774457) (xy 433.198778 -53.756814)
			(xy 433.198524 -53.75656) (xy 433.191438 -53.750972) (xy 433.174521 -53.744727) (xy 433.165504 -53.744368)
			(xy 433.098448 -53.744368) (xy 433.089434 -53.744755) (xy 433.072517 -53.750982) (xy 433.065428 -53.75656)
			(xy 433.06492 -53.757068) (xy 433.043993 -53.77466) (xy 432.998057 -53.804299) (xy 432.94836 -53.827076)
			(xy 432.895919 -53.842524) (xy 432.84181 -53.850326) (xy 432.814476 -53.850794) (xy 432.787225 -53.850335)
			(xy 432.733278 -53.842575) (xy 432.680984 -53.827217) (xy 432.631408 -53.804574) (xy 432.585559 -53.775106)
			(xy 432.54437 -53.739413) (xy 432.50868 -53.698222) (xy 432.479215 -53.652371) (xy 432.456574 -53.602794)
			(xy 432.44122 -53.550499) (xy 432.433464 -53.496551) (xy 420.143655 -53.496551) (xy 420.147231 -53.502115)
			(xy 420.169873 -53.551692) (xy 420.185228 -53.603987) (xy 420.192984 -53.657935) (xy 420.19347 -53.685186)
			(xy 420.193027 -53.712521) (xy 420.185213 -53.766629) (xy 420.169757 -53.819069) (xy 420.146976 -53.868766)
			(xy 420.117337 -53.914704) (xy 420.099744 -53.93563) (xy 420.09949 -53.935884) (xy 420.099236 -53.936138)
			(xy 420.093662 -53.943233) (xy 420.087409 -53.960143) (xy 420.087044 -53.969158) (xy 420.087044 -54.036214)
			(xy 420.087385 -54.045233) (xy 420.093642 -54.06215) (xy 420.099236 -54.069234) (xy 420.09949 -54.069488)
			(xy 420.099744 -54.069742) (xy 420.11733 -54.090673) (xy 420.146967 -54.136609) (xy 420.169744 -54.186306)
			(xy 420.185194 -54.238745) (xy 420.193 -54.292852) (xy 420.19347 -54.320186) (xy 420.192984 -54.347437)
			(xy 420.185228 -54.401385) (xy 420.169873 -54.45368) (xy 420.147231 -54.503257) (xy 420.117765 -54.549107)
			(xy 420.082074 -54.590298) (xy 420.040883 -54.625989) (xy 419.995033 -54.655455) (xy 419.945456 -54.678097)
			(xy 419.893161 -54.693452) (xy 419.839213 -54.701208) (xy 419.784711 -54.701208) (xy 419.730763 -54.693452)
			(xy 419.678468 -54.678097) (xy 419.628891 -54.655455) (xy 419.583041 -54.625989) (xy 419.54185 -54.590298)
			(xy 419.506159 -54.549107) (xy 419.476693 -54.503257) (xy 419.454051 -54.45368) (xy 419.438696 -54.401385)
			(xy 419.43094 -54.347437) (xy 419.430454 -54.320186) (xy 417.201923 -54.320186) (xy 417.192979 -54.339691)
			(xy 417.163325 -54.385624) (xy 417.145724 -54.406546) (xy 417.14547 -54.4068) (xy 417.145216 -54.407054)
			(xy 417.139644 -54.414151) (xy 417.133388 -54.43106) (xy 417.133024 -54.440074) (xy 417.133024 -54.50713)
			(xy 417.133361 -54.516149) (xy 417.139622 -54.533066) (xy 417.145216 -54.54015) (xy 417.14547 -54.540404)
			(xy 417.145724 -54.540658) (xy 417.163314 -54.561586) (xy 417.192952 -54.607522) (xy 417.215728 -54.65722)
			(xy 417.231177 -54.70966) (xy 417.238981 -54.763768) (xy 417.239097 -54.770528) (xy 420.371016 -54.770528)
			(xy 420.371471 -54.743194) (xy 420.379283 -54.689086) (xy 420.394736 -54.636647) (xy 420.417514 -54.586949)
			(xy 420.447151 -54.541011) (xy 420.464742 -54.520084) (xy 420.464996 -54.51983) (xy 420.46525 -54.519576)
			(xy 420.470859 -54.512505) (xy 420.477091 -54.495576) (xy 420.477442 -54.486556) (xy 420.477442 -54.4195)
			(xy 420.477097 -54.410482) (xy 420.470843 -54.393564) (xy 420.46525 -54.38648) (xy 420.464996 -54.386226)
			(xy 420.464742 -54.385972) (xy 420.447176 -54.365025) (xy 420.417533 -54.319094) (xy 420.39475 -54.269402)
			(xy 420.379296 -54.216966) (xy 420.371487 -54.162861) (xy 420.371016 -54.135528) (xy 420.371502 -54.108277)
			(xy 420.379258 -54.054329) (xy 420.394613 -54.002034) (xy 420.417255 -53.952457) (xy 420.446721 -53.906607)
			(xy 420.482412 -53.865416) (xy 420.523603 -53.829725) (xy 420.569453 -53.800259) (xy 420.61903 -53.777617)
			(xy 420.671325 -53.762262) (xy 420.725273 -53.754506) (xy 420.779775 -53.754506) (xy 420.833723 -53.762262)
			(xy 420.886018 -53.777617) (xy 420.935595 -53.800259) (xy 420.981445 -53.829725) (xy 421.022636 -53.865416)
			(xy 421.058327 -53.906607) (xy 421.087793 -53.952457) (xy 421.092868 -53.96357) (xy 425.072046 -53.96357)
			(xy 425.076117 -53.907948) (xy 425.088243 -53.853511) (xy 425.108166 -53.80142) (xy 425.135462 -53.752785)
			(xy 425.169548 -53.708642) (xy 425.209697 -53.669933) (xy 425.255055 -53.637482) (xy 425.304655 -53.611981)
			(xy 425.357439 -53.593974) (xy 425.412282 -53.583844) (xy 425.468016 -53.581807) (xy 425.523453 -53.587907)
			(xy 425.57741 -53.602013) (xy 425.628739 -53.623825) (xy 425.676345 -53.652879) (xy 425.719213 -53.688554)
			(xy 425.75643 -53.730091) (xy 425.787203 -53.776604) (xy 425.810875 -53.827101) (xy 425.826943 -53.880508)
			(xy 425.835063 -53.935684) (xy 425.835572 -53.96357) (xy 425.835063 -53.991456) (xy 425.826943 -54.046632)
			(xy 425.820678 -54.067456) (xy 427.241206 -54.067456) (xy 427.245277 -54.011834) (xy 427.257403 -53.957397)
			(xy 427.277326 -53.905306) (xy 427.304622 -53.856671) (xy 427.338708 -53.812528) (xy 427.378857 -53.773819)
			(xy 427.424215 -53.741368) (xy 427.473815 -53.715867) (xy 427.526599 -53.69786) (xy 427.581442 -53.68773)
			(xy 427.637176 -53.685693) (xy 427.692613 -53.691793) (xy 427.74657 -53.705899) (xy 427.797899 -53.727711)
			(xy 427.845505 -53.756765) (xy 427.888373 -53.79244) (xy 427.92559 -53.833977) (xy 427.956363 -53.88049)
			(xy 427.980035 -53.930987) (xy 427.996103 -53.984394) (xy 428.004223 -54.03957) (xy 428.004732 -54.067456)
			(xy 428.004223 -54.095342) (xy 427.996103 -54.150518) (xy 427.980035 -54.203925) (xy 427.963637 -54.238906)
			(xy 434.685946 -54.238906) (xy 434.690017 -54.183284) (xy 434.702143 -54.128847) (xy 434.722066 -54.076756)
			(xy 434.749362 -54.028121) (xy 434.783448 -53.983978) (xy 434.823597 -53.945269) (xy 434.868955 -53.912818)
			(xy 434.918555 -53.887317) (xy 434.971339 -53.86931) (xy 435.026182 -53.85918) (xy 435.081916 -53.857143)
			(xy 435.137353 -53.863243) (xy 435.19131 -53.877349) (xy 435.242639 -53.899161) (xy 435.290245 -53.928215)
			(xy 435.333113 -53.96389) (xy 435.37033 -54.005427) (xy 435.401103 -54.05194) (xy 435.424775 -54.102437)
			(xy 435.440843 -54.155844) (xy 435.448963 -54.21102) (xy 435.449472 -54.238906) (xy 435.448963 -54.266792)
			(xy 435.440843 -54.321968) (xy 435.424775 -54.375375) (xy 435.401103 -54.425872) (xy 435.37033 -54.472385)
			(xy 435.333113 -54.513922) (xy 435.290245 -54.549597) (xy 435.242639 -54.578651) (xy 435.19131 -54.600463)
			(xy 435.137353 -54.614569) (xy 435.081916 -54.620669) (xy 435.026182 -54.618632) (xy 434.971339 -54.608502)
			(xy 434.918555 -54.590495) (xy 434.868955 -54.564994) (xy 434.823597 -54.532543) (xy 434.783448 -54.493834)
			(xy 434.749362 -54.449691) (xy 434.722066 -54.401056) (xy 434.702143 -54.348965) (xy 434.690017 -54.294528)
			(xy 434.685946 -54.238906) (xy 427.963637 -54.238906) (xy 427.956363 -54.254422) (xy 427.92559 -54.300935)
			(xy 427.888373 -54.342472) (xy 427.845505 -54.378147) (xy 427.797899 -54.407201) (xy 427.74657 -54.429013)
			(xy 427.692613 -54.443119) (xy 427.637176 -54.449219) (xy 427.581442 -54.447182) (xy 427.526599 -54.437052)
			(xy 427.473815 -54.419045) (xy 427.424215 -54.393544) (xy 427.378857 -54.361093) (xy 427.338708 -54.322384)
			(xy 427.304622 -54.278241) (xy 427.277326 -54.229606) (xy 427.257403 -54.177515) (xy 427.245277 -54.123078)
			(xy 427.241206 -54.067456) (xy 425.820678 -54.067456) (xy 425.810875 -54.100039) (xy 425.787203 -54.150536)
			(xy 425.75643 -54.197049) (xy 425.719213 -54.238586) (xy 425.676345 -54.274261) (xy 425.628739 -54.303315)
			(xy 425.57741 -54.325127) (xy 425.523453 -54.339233) (xy 425.468016 -54.345333) (xy 425.412282 -54.343296)
			(xy 425.357439 -54.333166) (xy 425.304655 -54.315159) (xy 425.255055 -54.289658) (xy 425.209697 -54.257207)
			(xy 425.169548 -54.218498) (xy 425.135462 -54.174355) (xy 425.108166 -54.12572) (xy 425.088243 -54.073629)
			(xy 425.076117 -54.019192) (xy 425.072046 -53.96357) (xy 421.092868 -53.96357) (xy 421.110435 -54.002034)
			(xy 421.12579 -54.054329) (xy 421.133546 -54.108277) (xy 421.134032 -54.135528) (xy 421.133564 -54.162862)
			(xy 421.125757 -54.21697) (xy 421.110308 -54.269409) (xy 421.087532 -54.319107) (xy 421.057897 -54.365045)
			(xy 421.040306 -54.385972) (xy 421.040052 -54.386226) (xy 421.039798 -54.38648) (xy 421.034213 -54.393568)
			(xy 421.027966 -54.410484) (xy 421.027606 -54.4195) (xy 421.027606 -54.486556) (xy 421.027983 -54.495571)
			(xy 421.034217 -54.512488) (xy 421.039798 -54.519576) (xy 421.040052 -54.51983) (xy 421.040306 -54.520084)
			(xy 421.057905 -54.541004) (xy 421.087542 -54.586943) (xy 421.110317 -54.636642) (xy 421.125764 -54.689084)
			(xy 421.133565 -54.743193) (xy 421.134032 -54.770528) (xy 421.133546 -54.797779) (xy 421.12579 -54.851727)
			(xy 421.110435 -54.904022) (xy 421.087793 -54.953599) (xy 421.058327 -54.999449) (xy 421.022636 -55.04064)
			(xy 420.981445 -55.076331) (xy 420.970358 -55.083456) (xy 427.241206 -55.083456) (xy 427.245277 -55.027834)
			(xy 427.257403 -54.973397) (xy 427.277326 -54.921306) (xy 427.304622 -54.872671) (xy 427.338708 -54.828528)
			(xy 427.378857 -54.789819) (xy 427.424215 -54.757368) (xy 427.473815 -54.731867) (xy 427.526599 -54.71386)
			(xy 427.581442 -54.70373) (xy 427.637176 -54.701693) (xy 427.692613 -54.707793) (xy 427.74657 -54.721899)
			(xy 427.797899 -54.743711) (xy 427.845505 -54.772765) (xy 427.888373 -54.80844) (xy 427.92559 -54.849977)
			(xy 427.956363 -54.89649) (xy 427.980035 -54.946987) (xy 427.99269 -54.989051) (xy 430.201068 -54.989051)
			(xy 430.201068 -54.934549) (xy 430.208824 -54.880603) (xy 430.224178 -54.828309) (xy 430.246817 -54.778733)
			(xy 430.276281 -54.732882) (xy 430.311971 -54.691692) (xy 430.353158 -54.655999) (xy 430.399006 -54.626532)
			(xy 430.448581 -54.603888) (xy 430.500874 -54.58853) (xy 430.554819 -54.58077) (xy 430.58207 -54.580282)
			(xy 430.610161 -54.580801) (xy 430.665737 -54.589023) (xy 430.719505 -54.60531) (xy 430.770303 -54.629309)
			(xy 430.81703 -54.6605) (xy 430.858675 -54.698209) (xy 430.894339 -54.741619) (xy 430.909222 -54.765448)
			(xy 430.91481 -54.774592) (xy 430.931828 -54.786784) (xy 431.024792 -54.80685) (xy 431.045366 -54.802786)
			(xy 431.054002 -54.79669) (xy 431.078063 -54.780686) (xy 431.129996 -54.755344) (xy 431.185154 -54.73812)
			(xy 431.242279 -54.729406) (xy 431.271172 -54.728872) (xy 431.298423 -54.729381) (xy 431.312555 -54.731412)
			(xy 439.820558 -54.731412) (xy 439.820994 -54.704077) (xy 439.828808 -54.649968) (xy 439.844265 -54.597528)
			(xy 439.867048 -54.547831) (xy 439.89669 -54.501894) (xy 439.914284 -54.480968) (xy 439.914538 -54.480714)
			(xy 439.914792 -54.48046) (xy 439.920359 -54.47336) (xy 439.926618 -54.456454) (xy 439.926984 -54.44744)
			(xy 439.926984 -54.380384) (xy 439.926638 -54.371366) (xy 439.920383 -54.354449) (xy 439.914792 -54.347364)
			(xy 439.914538 -54.34711) (xy 439.914284 -54.346856) (xy 439.896695 -54.325925) (xy 439.86704 -54.279994)
			(xy 439.84425 -54.230298) (xy 439.828791 -54.177857) (xy 439.820981 -54.123745) (xy 439.82098 -54.069073)
			(xy 439.828787 -54.014961) (xy 439.844243 -53.962519) (xy 439.867031 -53.912822) (xy 439.896684 -53.86689)
			(xy 439.914284 -53.845968) (xy 439.914538 -53.845714) (xy 439.914792 -53.84546) (xy 439.920359 -53.83836)
			(xy 439.926618 -53.821454) (xy 439.926984 -53.81244) (xy 439.926984 -53.745384) (xy 439.926638 -53.736366)
			(xy 439.920383 -53.719449) (xy 439.914792 -53.712364) (xy 439.914538 -53.71211) (xy 439.914284 -53.711856)
			(xy 439.896695 -53.690925) (xy 439.86704 -53.644994) (xy 439.84425 -53.595298) (xy 439.828791 -53.542857)
			(xy 439.820981 -53.488745) (xy 439.82098 -53.434073) (xy 439.828787 -53.379961) (xy 439.844243 -53.327519)
			(xy 439.867031 -53.277822) (xy 439.896684 -53.23189) (xy 439.914284 -53.210968) (xy 439.914538 -53.210714)
			(xy 439.914792 -53.21046) (xy 439.920359 -53.20336) (xy 439.926618 -53.186454) (xy 439.926984 -53.17744)
			(xy 439.926984 -53.110384) (xy 439.926638 -53.101366) (xy 439.920383 -53.084449) (xy 439.914792 -53.077364)
			(xy 439.914538 -53.07711) (xy 439.914284 -53.076856) (xy 439.896702 -53.055922) (xy 439.867063 -53.009987)
			(xy 439.844284 -52.960291) (xy 439.828834 -52.907853) (xy 439.821028 -52.853746) (xy 439.820558 -52.826412)
			(xy 439.821044 -52.799161) (xy 439.8288 -52.745213) (xy 439.844155 -52.692918) (xy 439.866797 -52.643341)
			(xy 439.896263 -52.597491) (xy 439.931954 -52.5563) (xy 439.973145 -52.520609) (xy 440.018995 -52.491143)
			(xy 440.068572 -52.468501) (xy 440.120867 -52.453146) (xy 440.174815 -52.44539) (xy 440.229317 -52.44539)
			(xy 440.283265 -52.453146) (xy 440.33556 -52.468501) (xy 440.385137 -52.491143) (xy 440.430987 -52.520609)
			(xy 440.472178 -52.5563) (xy 440.507869 -52.597491) (xy 440.537335 -52.643341) (xy 440.559977 -52.692918)
			(xy 440.575332 -52.745213) (xy 440.583088 -52.799161) (xy 440.583574 -52.826412) (xy 440.583086 -52.853745)
			(xy 440.575283 -52.907852) (xy 440.559838 -52.960291) (xy 440.537067 -53.009989) (xy 440.507436 -53.055928)
			(xy 440.489848 -53.076856) (xy 440.489594 -53.07711) (xy 440.48934 -53.077364) (xy 440.483755 -53.084452)
			(xy 440.477509 -53.101368) (xy 440.477148 -53.110384) (xy 440.477148 -53.17744) (xy 440.477475 -53.18646)
			(xy 440.483742 -53.203377) (xy 440.48934 -53.21046) (xy 440.489594 -53.210714) (xy 440.489848 -53.210968)
			(xy 440.507459 -53.231881) (xy 440.537111 -53.277816) (xy 440.559898 -53.327515) (xy 440.575353 -53.379959)
			(xy 440.58316 -53.434072) (xy 440.583159 -53.488746) (xy 440.575349 -53.542859) (xy 440.559891 -53.595302)
			(xy 440.537102 -53.645) (xy 440.507449 -53.690934) (xy 440.489848 -53.711856) (xy 440.489594 -53.71211)
			(xy 440.48934 -53.712364) (xy 440.483755 -53.719452) (xy 440.477509 -53.736368) (xy 440.477148 -53.745384)
			(xy 440.477148 -53.81244) (xy 440.477475 -53.82146) (xy 440.483742 -53.838377) (xy 440.48934 -53.84546)
			(xy 440.489594 -53.845714) (xy 440.489848 -53.845968) (xy 440.507459 -53.866881) (xy 440.537111 -53.912816)
			(xy 440.559898 -53.962515) (xy 440.575353 -54.014959) (xy 440.58316 -54.069072) (xy 440.583159 -54.123746)
			(xy 440.575349 -54.177859) (xy 440.559891 -54.230302) (xy 440.537102 -54.28) (xy 440.507449 -54.325934)
			(xy 440.489848 -54.346856) (xy 440.489594 -54.34711) (xy 440.48934 -54.347364) (xy 440.483755 -54.354452)
			(xy 440.477509 -54.371368) (xy 440.477148 -54.380384) (xy 440.477148 -54.44744) (xy 440.477475 -54.45646)
			(xy 440.483742 -54.473377) (xy 440.48934 -54.48046) (xy 440.489594 -54.480714) (xy 440.489848 -54.480968)
			(xy 440.507446 -54.501889) (xy 440.537082 -54.547828) (xy 440.559857 -54.597527) (xy 440.575303 -54.649968)
			(xy 440.583106 -54.704078) (xy 440.583574 -54.731412) (xy 440.583088 -54.758663) (xy 440.578424 -54.791102)
			(xy 442.476382 -54.791102) (xy 442.476889 -54.76377) (xy 442.484689 -54.709664) (xy 442.50013 -54.657226)
			(xy 442.522897 -54.607528) (xy 442.552522 -54.561587) (xy 442.570108 -54.540658) (xy 442.570362 -54.540404)
			(xy 442.570616 -54.54015) (xy 442.57619 -54.533055) (xy 442.582444 -54.516145) (xy 442.582808 -54.50713)
			(xy 442.582808 -54.440074) (xy 442.582461 -54.431056) (xy 442.576206 -54.414139) (xy 442.570616 -54.407054)
			(xy 442.570362 -54.4068) (xy 442.570108 -54.406546) (xy 442.552508 -54.385623) (xy 442.522852 -54.339691)
			(xy 442.500061 -54.289994) (xy 442.484602 -54.237552) (xy 442.476792 -54.183438) (xy 442.476792 -54.128765)
			(xy 442.484601 -54.074651) (xy 442.50006 -54.022209) (xy 442.52285 -53.972511) (xy 442.552506 -53.926579)
			(xy 442.570108 -53.905658) (xy 442.570362 -53.905404) (xy 442.570616 -53.90515) (xy 442.57619 -53.898055)
			(xy 442.582444 -53.881145) (xy 442.582808 -53.87213) (xy 442.582808 -53.805074) (xy 442.582461 -53.796056)
			(xy 442.576206 -53.779139) (xy 442.570616 -53.772054) (xy 442.570362 -53.7718) (xy 442.570108 -53.771546)
			(xy 442.552508 -53.750623) (xy 442.522852 -53.704691) (xy 442.500061 -53.654994) (xy 442.484602 -53.602552)
			(xy 442.476792 -53.548438) (xy 442.476792 -53.493765) (xy 442.484601 -53.439651) (xy 442.50006 -53.387209)
			(xy 442.52285 -53.337511) (xy 442.552506 -53.291579) (xy 442.570108 -53.270658) (xy 442.570362 -53.270404)
			(xy 442.570616 -53.27015) (xy 442.57619 -53.263055) (xy 442.582444 -53.246145) (xy 442.582808 -53.23713)
			(xy 442.582808 -53.170074) (xy 442.582461 -53.161056) (xy 442.576206 -53.144139) (xy 442.570616 -53.137054)
			(xy 442.570362 -53.1368) (xy 442.570108 -53.136546) (xy 442.552525 -53.115613) (xy 442.522885 -53.069678)
			(xy 442.500107 -53.019982) (xy 442.484657 -52.967543) (xy 442.476852 -52.913436) (xy 442.476382 -52.886102)
			(xy 442.476868 -52.858851) (xy 442.484624 -52.804903) (xy 442.499979 -52.752608) (xy 442.522621 -52.703031)
			(xy 442.552087 -52.657181) (xy 442.587778 -52.61599) (xy 442.628969 -52.580299) (xy 442.674819 -52.550833)
			(xy 442.724396 -52.528191) (xy 442.776691 -52.512836) (xy 442.830639 -52.50508) (xy 442.885141 -52.50508)
			(xy 442.939089 -52.512836) (xy 442.953407 -52.51704) (xy 447.140074 -52.51704) (xy 447.144145 -52.461418)
			(xy 447.156271 -52.406981) (xy 447.176194 -52.35489) (xy 447.20349 -52.306255) (xy 447.237576 -52.262112)
			(xy 447.277725 -52.223403) (xy 447.323083 -52.190952) (xy 447.372683 -52.165451) (xy 447.425467 -52.147444)
			(xy 447.48031 -52.137314) (xy 447.536044 -52.135277) (xy 447.591481 -52.141377) (xy 447.645438 -52.155483)
			(xy 447.696767 -52.177295) (xy 447.744373 -52.206349) (xy 447.787241 -52.242024) (xy 447.824458 -52.283561)
			(xy 447.855231 -52.330074) (xy 447.878903 -52.380571) (xy 447.894971 -52.433978) (xy 447.903091 -52.489154)
			(xy 447.9036 -52.51704) (xy 447.903091 -52.544926) (xy 447.896841 -52.587398) (xy 451.05523 -52.587398)
			(xy 451.059301 -52.531776) (xy 451.071427 -52.477339) (xy 451.09135 -52.425248) (xy 451.118646 -52.376613)
			(xy 451.152732 -52.33247) (xy 451.192881 -52.293761) (xy 451.238239 -52.26131) (xy 451.287839 -52.235809)
			(xy 451.340623 -52.217802) (xy 451.395466 -52.207672) (xy 451.4512 -52.205635) (xy 451.506637 -52.211735)
			(xy 451.560594 -52.225841) (xy 451.611923 -52.247653) (xy 451.659529 -52.276707) (xy 451.702397 -52.312382)
			(xy 451.739614 -52.353919) (xy 451.770387 -52.400432) (xy 451.794059 -52.450929) (xy 451.810127 -52.504336)
			(xy 451.818247 -52.559512) (xy 451.818756 -52.587398) (xy 451.818247 -52.615284) (xy 451.810127 -52.67046)
			(xy 451.794059 -52.723867) (xy 451.770387 -52.774364) (xy 451.739614 -52.820877) (xy 451.702397 -52.862414)
			(xy 451.659529 -52.898089) (xy 451.611923 -52.927143) (xy 451.560594 -52.948955) (xy 451.506637 -52.963061)
			(xy 451.4512 -52.969161) (xy 451.395466 -52.967124) (xy 451.340623 -52.956994) (xy 451.287839 -52.938987)
			(xy 451.238239 -52.913486) (xy 451.192881 -52.881035) (xy 451.152732 -52.842326) (xy 451.118646 -52.798183)
			(xy 451.09135 -52.749548) (xy 451.071427 -52.697457) (xy 451.059301 -52.64302) (xy 451.05523 -52.587398)
			(xy 447.896841 -52.587398) (xy 447.894971 -52.600102) (xy 447.878903 -52.653509) (xy 447.855231 -52.704006)
			(xy 447.824458 -52.750519) (xy 447.787241 -52.792056) (xy 447.744373 -52.827731) (xy 447.696767 -52.856785)
			(xy 447.645438 -52.878597) (xy 447.591481 -52.892703) (xy 447.536044 -52.898803) (xy 447.48031 -52.896766)
			(xy 447.425467 -52.886636) (xy 447.372683 -52.868629) (xy 447.323083 -52.843128) (xy 447.277725 -52.810677)
			(xy 447.237576 -52.771968) (xy 447.20349 -52.727825) (xy 447.176194 -52.67919) (xy 447.156271 -52.627099)
			(xy 447.144145 -52.572662) (xy 447.140074 -52.51704) (xy 442.953407 -52.51704) (xy 442.991384 -52.528191)
			(xy 443.040961 -52.550833) (xy 443.086811 -52.580299) (xy 443.128002 -52.61599) (xy 443.163693 -52.657181)
			(xy 443.193159 -52.703031) (xy 443.215801 -52.752608) (xy 443.231156 -52.804903) (xy 443.238912 -52.858851)
			(xy 443.239398 -52.886102) (xy 443.238899 -52.913435) (xy 443.231097 -52.96754) (xy 443.215654 -53.019979)
			(xy 443.192886 -53.069677) (xy 443.163259 -53.115618) (xy 443.145672 -53.136546) (xy 443.145418 -53.1368)
			(xy 443.145164 -53.137054) (xy 443.139587 -53.144147) (xy 443.133335 -53.161059) (xy 443.132972 -53.170074)
			(xy 443.132972 -53.23713) (xy 443.133321 -53.246148) (xy 443.139575 -53.263064) (xy 443.145164 -53.27015)
			(xy 443.145418 -53.270404) (xy 443.145672 -53.270658) (xy 443.163273 -53.291579) (xy 443.192922 -53.337513)
			(xy 443.215709 -53.387211) (xy 443.231164 -53.439653) (xy 443.238971 -53.493765) (xy 443.238971 -53.548438)
			(xy 443.231163 -53.60255) (xy 443.215707 -53.654992) (xy 443.192921 -53.704689) (xy 443.163271 -53.750623)
			(xy 443.146527 -53.77053) (xy 443.51067 -53.77053) (xy 443.511183 -53.741613) (xy 443.51991 -53.68444)
			(xy 443.537167 -53.62924) (xy 443.562559 -53.577278) (xy 443.595505 -53.529744) (xy 443.635249 -53.487729)
			(xy 443.657736 -53.46954) (xy 443.66512 -53.463256) (xy 443.674914 -53.446541) (xy 443.676786 -53.437028)
			(xy 443.677294 -53.429408) (xy 443.677294 -53.349652) (xy 443.676786 -53.342032) (xy 443.674933 -53.332514)
			(xy 443.665126 -53.315801) (xy 443.657736 -53.30952) (xy 443.63527 -53.291309) (xy 443.595532 -53.249294)
			(xy 443.56259 -53.201764) (xy 443.537198 -53.149806) (xy 443.519938 -53.094612) (xy 443.511206 -53.037445)
			(xy 443.51067 -53.00853) (xy 443.511183 -52.981279) (xy 443.518935 -52.927331) (xy 443.534287 -52.875035)
			(xy 443.556924 -52.825457) (xy 443.586387 -52.779605) (xy 443.622075 -52.738412) (xy 443.663263 -52.702718)
			(xy 443.709111 -52.673249) (xy 443.758687 -52.650605) (xy 443.81098 -52.635247) (xy 443.864927 -52.627487)
			(xy 443.892178 -52.627022) (xy 443.892432 -52.627022) (xy 443.918728 -52.627452) (xy 443.970818 -52.634703)
			(xy 444.02142 -52.649034) (xy 444.069576 -52.670174) (xy 444.114375 -52.697725) (xy 444.154969 -52.731163)
			(xy 444.173102 -52.750212) (xy 444.180672 -52.757655) (xy 444.200091 -52.766179) (xy 444.210694 -52.766722)
			(xy 444.284862 -52.766722) (xy 444.295496 -52.766331) (xy 444.31496 -52.757768) (xy 444.322454 -52.750212)
			(xy 444.340598 -52.731172) (xy 444.381177 -52.697714) (xy 444.42597 -52.670152) (xy 444.474127 -52.64901)
			(xy 444.524733 -52.634689) (xy 444.576827 -52.627462) (xy 444.603124 -52.627022) (xy 444.603378 -52.627022)
			(xy 444.630632 -52.627476) (xy 444.684585 -52.635231) (xy 444.736884 -52.650585) (xy 444.786466 -52.673228)
			(xy 444.832321 -52.702696) (xy 444.873515 -52.738391) (xy 444.909209 -52.779585) (xy 444.938676 -52.825441)
			(xy 444.961317 -52.875023) (xy 444.976671 -52.927323) (xy 444.984425 -52.981276) (xy 444.984886 -53.00853)
			(xy 444.984404 -53.036196) (xy 444.982173 -53.051456) (xy 453.241154 -53.051456) (xy 453.245225 -52.995834)
			(xy 453.257351 -52.941397) (xy 453.277274 -52.889306) (xy 453.30457 -52.840671) (xy 453.338656 -52.796528)
			(xy 453.378805 -52.757819) (xy 453.424163 -52.725368) (xy 453.473763 -52.699867) (xy 453.526547 -52.68186)
			(xy 453.58139 -52.67173) (xy 453.637124 -52.669693) (xy 453.692561 -52.675793) (xy 453.746518 -52.689899)
			(xy 453.797847 -52.711711) (xy 453.845453 -52.740765) (xy 453.888321 -52.77644) (xy 453.925538 -52.817977)
			(xy 453.956311 -52.86449) (xy 453.979983 -52.914987) (xy 453.996051 -52.968394) (xy 454.004171 -53.02357)
			(xy 454.00468 -53.051456) (xy 454.004171 -53.079342) (xy 453.996051 -53.134518) (xy 453.979983 -53.187925)
			(xy 453.956311 -53.238422) (xy 453.925538 -53.284935) (xy 453.888321 -53.326472) (xy 453.845453 -53.362147)
			(xy 453.797847 -53.391201) (xy 453.746518 -53.413013) (xy 453.692561 -53.427119) (xy 453.637124 -53.433219)
			(xy 453.58139 -53.431182) (xy 453.526547 -53.421052) (xy 453.473763 -53.403045) (xy 453.424163 -53.377544)
			(xy 453.378805 -53.345093) (xy 453.338656 -53.306384) (xy 453.30457 -53.262241) (xy 453.277274 -53.213606)
			(xy 453.257351 -53.161515) (xy 453.245225 -53.107078) (xy 453.241154 -53.051456) (xy 444.982173 -53.051456)
			(xy 444.9764 -53.090947) (xy 444.960578 -53.14397) (xy 444.937271 -53.194154) (xy 444.906965 -53.240449)
			(xy 444.870295 -53.281887) (xy 444.828029 -53.317598) (xy 444.8048 -53.332634) (xy 444.804546 -53.332888)
			(xy 444.795012 -53.339542) (xy 444.782711 -53.359245) (xy 444.780924 -53.370734) (xy 444.77305 -53.450744)
			(xy 444.772371 -53.462445) (xy 444.78046 -53.484419) (xy 444.788544 -53.492908) (xy 444.788798 -53.492908)
			(xy 444.807365 -53.511003) (xy 444.839945 -53.551332) (xy 444.86676 -53.595703) (xy 444.887315 -53.643299)
			(xy 444.901231 -53.693241) (xy 444.908252 -53.744608) (xy 444.908686 -53.77053) (xy 444.90825 -53.797783)
			(xy 444.900489 -53.851734) (xy 444.885129 -53.904031) (xy 444.862483 -53.953609) (xy 444.833011 -53.999461)
			(xy 444.797314 -54.040651) (xy 444.756119 -54.076342) (xy 444.710264 -54.105808) (xy 444.660682 -54.128447)
			(xy 444.608383 -54.1438) (xy 444.554431 -54.151554) (xy 444.527178 -54.152038) (xy 444.499807 -54.1516)
			(xy 444.445626 -54.143778) (xy 444.393122 -54.128283) (xy 444.343375 -54.105435) (xy 444.29741 -54.075703)
			(xy 444.27648 -54.058058) (xy 444.276226 -54.057804) (xy 444.269136 -54.052223) (xy 444.252222 -54.045973)
			(xy 444.243206 -54.045612) (xy 444.17615 -54.045612) (xy 444.167135 -54.045991) (xy 444.150218 -54.052223)
			(xy 444.14313 -54.057804) (xy 444.142622 -54.058312) (xy 444.1217 -54.075909) (xy 444.075762 -54.105547)
			(xy 444.026063 -54.128322) (xy 443.973622 -54.143769) (xy 443.919512 -54.15157) (xy 443.892178 -54.152038)
			(xy 443.864928 -54.151543) (xy 443.810982 -54.143784) (xy 443.758689 -54.128428) (xy 443.709114 -54.105786)
			(xy 443.663265 -54.07632) (xy 443.622076 -54.04063) (xy 443.586384 -53.999442) (xy 443.556918 -53.953593)
			(xy 443.534275 -53.904018) (xy 443.518918 -53.851726) (xy 443.511158 -53.79778) (xy 443.51067 -53.77053)
			(xy 443.146527 -53.77053) (xy 443.145672 -53.771546) (xy 443.145418 -53.7718) (xy 443.145164 -53.772054)
			(xy 443.139587 -53.779147) (xy 443.133335 -53.796059) (xy 443.132972 -53.805074) (xy 443.132972 -53.87213)
			(xy 443.133321 -53.881148) (xy 443.139575 -53.898064) (xy 443.145164 -53.90515) (xy 443.145418 -53.905404)
			(xy 443.145672 -53.905658) (xy 443.163273 -53.926579) (xy 443.192922 -53.972513) (xy 443.215709 -54.022211)
			(xy 443.231164 -54.074653) (xy 443.238971 -54.128765) (xy 443.238971 -54.183438) (xy 443.231163 -54.23755)
			(xy 443.215707 -54.289992) (xy 443.201863 -54.320186) (xy 445.430402 -54.320186) (xy 445.430894 -54.292853)
			(xy 445.438697 -54.238747) (xy 445.454142 -54.186308) (xy 445.476912 -54.13661) (xy 445.506541 -54.09067)
			(xy 445.524128 -54.069742) (xy 445.524382 -54.069488) (xy 445.524636 -54.069234) (xy 445.530218 -54.062145)
			(xy 445.536467 -54.04523) (xy 445.536828 -54.036214) (xy 445.536828 -53.969158) (xy 445.536437 -53.960145)
			(xy 445.530212 -53.943228) (xy 445.524636 -53.936138) (xy 445.524382 -53.935884) (xy 445.524128 -53.93563)
			(xy 445.50654 -53.9147) (xy 445.4769 -53.868765) (xy 445.454123 -53.819068) (xy 445.438674 -53.766628)
			(xy 445.43087 -53.71252) (xy 445.430402 -53.685186) (xy 445.430888 -53.657935) (xy 445.438644 -53.603987)
			(xy 445.453999 -53.551692) (xy 445.476641 -53.502115) (xy 445.506107 -53.456265) (xy 445.541798 -53.415074)
			(xy 445.582989 -53.379383) (xy 445.628839 -53.349917) (xy 445.678416 -53.327275) (xy 445.730711 -53.31192)
			(xy 445.784659 -53.304164) (xy 445.839161 -53.304164) (xy 445.893109 -53.31192) (xy 445.945404 -53.327275)
			(xy 445.994981 -53.349917) (xy 446.040831 -53.379383) (xy 446.082022 -53.415074) (xy 446.117713 -53.456265)
			(xy 446.147179 -53.502115) (xy 446.169821 -53.551692) (xy 446.185176 -53.603987) (xy 446.192932 -53.657935)
			(xy 446.193418 -53.685186) (xy 446.192963 -53.71252) (xy 446.18515 -53.766628) (xy 446.169697 -53.819067)
			(xy 446.146919 -53.868764) (xy 446.117283 -53.914703) (xy 446.099692 -53.93563) (xy 446.099438 -53.935884)
			(xy 446.099184 -53.936138) (xy 446.093615 -53.943237) (xy 446.087358 -53.960144) (xy 446.086992 -53.969158)
			(xy 446.086992 -54.036214) (xy 446.087344 -54.045231) (xy 446.093595 -54.062148) (xy 446.099184 -54.069234)
			(xy 446.099438 -54.069488) (xy 446.099692 -54.069742) (xy 446.117269 -54.09068) (xy 446.14691 -54.136613)
			(xy 446.16969 -54.186308) (xy 446.185141 -54.238746) (xy 446.192948 -54.292853) (xy 446.193418 -54.320186)
			(xy 446.192932 -54.347437) (xy 446.185176 -54.401385) (xy 446.169821 -54.45368) (xy 446.147179 -54.503257)
			(xy 446.117713 -54.549107) (xy 446.082022 -54.590298) (xy 446.040831 -54.625989) (xy 445.994981 -54.655455)
			(xy 445.945404 -54.678097) (xy 445.893109 -54.693452) (xy 445.839161 -54.701208) (xy 445.784659 -54.701208)
			(xy 445.730711 -54.693452) (xy 445.678416 -54.678097) (xy 445.628839 -54.655455) (xy 445.582989 -54.625989)
			(xy 445.541798 -54.590298) (xy 445.506107 -54.549107) (xy 445.476641 -54.503257) (xy 445.453999 -54.45368)
			(xy 445.438644 -54.401385) (xy 445.430888 -54.347437) (xy 445.430402 -54.320186) (xy 443.201863 -54.320186)
			(xy 443.192921 -54.339689) (xy 443.163271 -54.385623) (xy 443.145672 -54.406546) (xy 443.145418 -54.4068)
			(xy 443.145164 -54.407054) (xy 443.139587 -54.414147) (xy 443.133335 -54.431059) (xy 443.132972 -54.440074)
			(xy 443.132972 -54.50713) (xy 443.133321 -54.516148) (xy 443.139575 -54.533064) (xy 443.145164 -54.54015)
			(xy 443.145418 -54.540404) (xy 443.145672 -54.540658) (xy 443.163254 -54.561592) (xy 443.192895 -54.607526)
			(xy 443.215674 -54.657222) (xy 443.231124 -54.709661) (xy 443.238929 -54.763768) (xy 443.239045 -54.770528)
			(xy 446.370964 -54.770528) (xy 446.371407 -54.743193) (xy 446.37922 -54.689084) (xy 446.394675 -54.636645)
			(xy 446.417456 -54.586947) (xy 446.447097 -54.54101) (xy 446.46469 -54.520084) (xy 446.464944 -54.51983)
			(xy 446.465198 -54.519576) (xy 446.470801 -54.5125) (xy 446.477038 -54.495575) (xy 446.47739 -54.486556)
			(xy 446.47739 -54.4195) (xy 446.477035 -54.410483) (xy 446.470786 -54.393566) (xy 446.465198 -54.38648)
			(xy 446.464944 -54.386226) (xy 446.46469 -54.385972) (xy 446.447116 -54.365031) (xy 446.417475 -54.319098)
			(xy 446.394696 -54.269404) (xy 446.379243 -54.216967) (xy 446.371435 -54.162861) (xy 446.370964 -54.135528)
			(xy 446.37145 -54.108277) (xy 446.379206 -54.054329) (xy 446.394561 -54.002034) (xy 446.417203 -53.952457)
			(xy 446.446669 -53.906607) (xy 446.48236 -53.865416) (xy 446.523551 -53.829725) (xy 446.569401 -53.800259)
			(xy 446.618978 -53.777617) (xy 446.671273 -53.762262) (xy 446.725221 -53.754506) (xy 446.779723 -53.754506)
			(xy 446.833671 -53.762262) (xy 446.885966 -53.777617) (xy 446.935543 -53.800259) (xy 446.981393 -53.829725)
			(xy 447.022584 -53.865416) (xy 447.058275 -53.906607) (xy 447.087741 -53.952457) (xy 447.092816 -53.96357)
			(xy 451.071994 -53.96357) (xy 451.076065 -53.907948) (xy 451.088191 -53.853511) (xy 451.108114 -53.80142)
			(xy 451.13541 -53.752785) (xy 451.169496 -53.708642) (xy 451.209645 -53.669933) (xy 451.255003 -53.637482)
			(xy 451.304603 -53.611981) (xy 451.357387 -53.593974) (xy 451.41223 -53.583844) (xy 451.467964 -53.581807)
			(xy 451.523401 -53.587907) (xy 451.577358 -53.602013) (xy 451.628687 -53.623825) (xy 451.676293 -53.652879)
			(xy 451.719161 -53.688554) (xy 451.756378 -53.730091) (xy 451.787151 -53.776604) (xy 451.810823 -53.827101)
			(xy 451.826891 -53.880508) (xy 451.835011 -53.935684) (xy 451.83552 -53.96357) (xy 451.835011 -53.991456)
			(xy 451.826891 -54.046632) (xy 451.820626 -54.067456) (xy 453.241154 -54.067456) (xy 453.245225 -54.011834)
			(xy 453.257351 -53.957397) (xy 453.277274 -53.905306) (xy 453.30457 -53.856671) (xy 453.338656 -53.812528)
			(xy 453.378805 -53.773819) (xy 453.424163 -53.741368) (xy 453.473763 -53.715867) (xy 453.526547 -53.69786)
			(xy 453.58139 -53.68773) (xy 453.637124 -53.685693) (xy 453.692561 -53.691793) (xy 453.746518 -53.705899)
			(xy 453.797847 -53.727711) (xy 453.845453 -53.756765) (xy 453.888321 -53.79244) (xy 453.925538 -53.833977)
			(xy 453.956311 -53.88049) (xy 453.979983 -53.930987) (xy 453.996051 -53.984394) (xy 454.004171 -54.03957)
			(xy 454.00468 -54.067456) (xy 454.004171 -54.095342) (xy 453.996051 -54.150518) (xy 453.979983 -54.203925)
			(xy 453.956311 -54.254422) (xy 453.925538 -54.300935) (xy 453.888321 -54.342472) (xy 453.845453 -54.378147)
			(xy 453.797847 -54.407201) (xy 453.746518 -54.429013) (xy 453.692561 -54.443119) (xy 453.637124 -54.449219)
			(xy 453.58139 -54.447182) (xy 453.526547 -54.437052) (xy 453.473763 -54.419045) (xy 453.424163 -54.393544)
			(xy 453.378805 -54.361093) (xy 453.338656 -54.322384) (xy 453.30457 -54.278241) (xy 453.277274 -54.229606)
			(xy 453.257351 -54.177515) (xy 453.245225 -54.123078) (xy 453.241154 -54.067456) (xy 451.820626 -54.067456)
			(xy 451.810823 -54.100039) (xy 451.787151 -54.150536) (xy 451.756378 -54.197049) (xy 451.719161 -54.238586)
			(xy 451.676293 -54.274261) (xy 451.628687 -54.303315) (xy 451.577358 -54.325127) (xy 451.523401 -54.339233)
			(xy 451.467964 -54.345333) (xy 451.41223 -54.343296) (xy 451.357387 -54.333166) (xy 451.304603 -54.315159)
			(xy 451.255003 -54.289658) (xy 451.209645 -54.257207) (xy 451.169496 -54.218498) (xy 451.13541 -54.174355)
			(xy 451.108114 -54.12572) (xy 451.088191 -54.073629) (xy 451.076065 -54.019192) (xy 451.071994 -53.96357)
			(xy 447.092816 -53.96357) (xy 447.110383 -54.002034) (xy 447.125738 -54.054329) (xy 447.133494 -54.108277)
			(xy 447.13398 -54.135528) (xy 447.1335 -54.162861) (xy 447.125695 -54.216968) (xy 447.110248 -54.269407)
			(xy 447.087475 -54.319105) (xy 447.057843 -54.365044) (xy 447.040254 -54.385972) (xy 447.04 -54.386226)
			(xy 447.039746 -54.38648) (xy 447.034155 -54.393563) (xy 447.027912 -54.410483) (xy 447.027554 -54.4195)
			(xy 447.027554 -54.486556) (xy 447.02792 -54.495572) (xy 447.03416 -54.51249) (xy 447.039746 -54.519576)
			(xy 447.04 -54.51983) (xy 447.040254 -54.520084) (xy 447.057845 -54.541011) (xy 447.087485 -54.586947)
			(xy 447.110263 -54.636644) (xy 447.125711 -54.689085) (xy 447.133513 -54.743194) (xy 447.13398 -54.770528)
			(xy 447.133494 -54.797779) (xy 447.125738 -54.851727) (xy 447.110383 -54.904022) (xy 447.087741 -54.953599)
			(xy 447.058275 -54.999449) (xy 447.022584 -55.04064) (xy 446.981393 -55.076331) (xy 446.970306 -55.083456)
			(xy 453.241154 -55.083456) (xy 453.245225 -55.027834) (xy 453.257351 -54.973397) (xy 453.277274 -54.921306)
			(xy 453.30457 -54.872671) (xy 453.338656 -54.828528) (xy 453.378805 -54.789819) (xy 453.424163 -54.757368)
			(xy 453.473763 -54.731867) (xy 453.526547 -54.71386) (xy 453.58139 -54.70373) (xy 453.637124 -54.701693)
			(xy 453.692561 -54.707793) (xy 453.746518 -54.721899) (xy 453.797847 -54.743711) (xy 453.845453 -54.772765)
			(xy 453.888321 -54.80844) (xy 453.925538 -54.849977) (xy 453.956311 -54.89649) (xy 453.979983 -54.946987)
			(xy 453.996051 -55.000394) (xy 454.004171 -55.05557) (xy 454.00468 -55.083456) (xy 454.004171 -55.111342)
			(xy 453.996051 -55.166518) (xy 453.979983 -55.219925) (xy 453.956311 -55.270422) (xy 453.925538 -55.316935)
			(xy 453.888321 -55.358472) (xy 453.845453 -55.394147) (xy 453.797847 -55.423201) (xy 453.746518 -55.445013)
			(xy 453.692561 -55.459119) (xy 453.637124 -55.465219) (xy 453.58139 -55.463182) (xy 453.526547 -55.453052)
			(xy 453.473763 -55.435045) (xy 453.424163 -55.409544) (xy 453.378805 -55.377093) (xy 453.338656 -55.338384)
			(xy 453.30457 -55.294241) (xy 453.277274 -55.245606) (xy 453.257351 -55.193515) (xy 453.245225 -55.139078)
			(xy 453.241154 -55.083456) (xy 446.970306 -55.083456) (xy 446.935543 -55.105797) (xy 446.885966 -55.128439)
			(xy 446.833671 -55.143794) (xy 446.779723 -55.15155) (xy 446.725221 -55.15155) (xy 446.671273 -55.143794)
			(xy 446.618978 -55.128439) (xy 446.569401 -55.105797) (xy 446.523551 -55.076331) (xy 446.48236 -55.04064)
			(xy 446.446669 -54.999449) (xy 446.417203 -54.953599) (xy 446.394561 -54.904022) (xy 446.379206 -54.851727)
			(xy 446.37145 -54.797779) (xy 446.370964 -54.770528) (xy 443.239045 -54.770528) (xy 443.239398 -54.791102)
			(xy 443.238912 -54.818353) (xy 443.231156 -54.872301) (xy 443.215801 -54.924596) (xy 443.193159 -54.974173)
			(xy 443.163693 -55.020023) (xy 443.128002 -55.061214) (xy 443.086811 -55.096905) (xy 443.040961 -55.126371)
			(xy 442.991384 -55.149013) (xy 442.939089 -55.164368) (xy 442.885141 -55.172124) (xy 442.830639 -55.172124)
			(xy 442.776691 -55.164368) (xy 442.724396 -55.149013) (xy 442.674819 -55.126371) (xy 442.628969 -55.096905)
			(xy 442.587778 -55.061214) (xy 442.552087 -55.020023) (xy 442.522621 -54.974173) (xy 442.499979 -54.924596)
			(xy 442.484624 -54.872301) (xy 442.476868 -54.818353) (xy 442.476382 -54.791102) (xy 440.578424 -54.791102)
			(xy 440.575332 -54.812611) (xy 440.559977 -54.864906) (xy 440.537335 -54.914483) (xy 440.507869 -54.960333)
			(xy 440.472178 -55.001524) (xy 440.430987 -55.037215) (xy 440.385137 -55.066681) (xy 440.33556 -55.089323)
			(xy 440.283265 -55.104678) (xy 440.229317 -55.112434) (xy 440.174815 -55.112434) (xy 440.120867 -55.104678)
			(xy 440.068572 -55.089323) (xy 440.018995 -55.066681) (xy 439.973145 -55.037215) (xy 439.931954 -55.001524)
			(xy 439.896263 -54.960333) (xy 439.866797 -54.914483) (xy 439.844155 -54.864906) (xy 439.8288 -54.812611)
			(xy 439.821044 -54.758663) (xy 439.820558 -54.731412) (xy 431.312555 -54.731412) (xy 431.352371 -54.737134)
			(xy 431.404667 -54.752485) (xy 431.454246 -54.775123) (xy 431.500098 -54.804586) (xy 431.541291 -54.840275)
			(xy 431.576985 -54.881463) (xy 431.606454 -54.927312) (xy 431.629098 -54.976888) (xy 431.644456 -55.029182)
			(xy 431.652215 -55.083129) (xy 431.65268 -55.11038) (xy 431.652231 -55.137715) (xy 431.644418 -55.191823)
			(xy 431.628963 -55.244262) (xy 431.606184 -55.293959) (xy 431.576546 -55.339897) (xy 431.558954 -55.360824)
			(xy 431.5587 -55.361078) (xy 431.558446 -55.361332) (xy 431.552875 -55.368429) (xy 431.54662 -55.385338)
			(xy 431.546254 -55.394352) (xy 431.546254 -55.461408) (xy 431.546596 -55.470427) (xy 431.552853 -55.487344)
			(xy 431.558446 -55.494428) (xy 431.5587 -55.494682) (xy 431.558954 -55.494936) (xy 431.576534 -55.515874)
			(xy 431.606186 -55.561805) (xy 431.628974 -55.6115) (xy 431.644432 -55.66394) (xy 431.652242 -55.71805)
			(xy 431.652242 -55.722266) (xy 452.133968 -55.722266) (xy 452.138039 -55.666644) (xy 452.150165 -55.612207)
			(xy 452.170088 -55.560116) (xy 452.197384 -55.511481) (xy 452.23147 -55.467338) (xy 452.271619 -55.428629)
			(xy 452.316977 -55.396178) (xy 452.366577 -55.370677) (xy 452.419361 -55.35267) (xy 452.474204 -55.34254)
			(xy 452.529938 -55.340503) (xy 452.585375 -55.346603) (xy 452.639332 -55.360709) (xy 452.690661 -55.382521)
			(xy 452.738267 -55.411575) (xy 452.781135 -55.44725) (xy 452.818352 -55.488787) (xy 452.849125 -55.5353)
			(xy 452.872797 -55.585797) (xy 452.888865 -55.639204) (xy 452.896985 -55.69438) (xy 452.897494 -55.722266)
			(xy 452.896985 -55.750152) (xy 452.888865 -55.805328) (xy 452.872797 -55.858735) (xy 452.849125 -55.909232)
			(xy 452.818352 -55.955745) (xy 452.781135 -55.997282) (xy 452.738267 -56.032957) (xy 452.690661 -56.062011)
			(xy 452.639332 -56.083823) (xy 452.585375 -56.097929) (xy 452.529938 -56.104029) (xy 452.474204 -56.101992)
			(xy 452.419361 -56.091862) (xy 452.366577 -56.073855) (xy 452.316977 -56.048354) (xy 452.271619 -56.015903)
			(xy 452.23147 -55.977194) (xy 452.197384 -55.933051) (xy 452.170088 -55.884416) (xy 452.150165 -55.832325)
			(xy 452.138039 -55.777888) (xy 452.133968 -55.722266) (xy 431.652242 -55.722266) (xy 431.652244 -55.77272)
			(xy 431.644438 -55.826831) (xy 431.628985 -55.879272) (xy 431.6062 -55.928968) (xy 431.576552 -55.974902)
			(xy 431.558954 -55.995824) (xy 431.5587 -55.996078) (xy 431.558446 -55.996332) (xy 431.552875 -56.003429)
			(xy 431.54662 -56.020338) (xy 431.546254 -56.029352) (xy 431.546254 -56.096408) (xy 431.546596 -56.105427)
			(xy 431.552853 -56.122344) (xy 431.558446 -56.129428) (xy 431.5587 -56.129682) (xy 431.558954 -56.129936)
			(xy 431.576523 -56.150881) (xy 431.606166 -56.196812) (xy 431.628948 -56.246505) (xy 431.644401 -56.298941)
			(xy 431.652209 -56.353047) (xy 431.65268 -56.38038) (xy 431.652194 -56.407631) (xy 431.644438 -56.461579)
			(xy 431.629083 -56.513874) (xy 431.606441 -56.563451) (xy 431.576975 -56.609301) (xy 431.541284 -56.650492)
			(xy 431.500093 -56.686183) (xy 431.454243 -56.715649) (xy 431.404666 -56.738291) (xy 431.352371 -56.753646)
			(xy 431.298423 -56.761402) (xy 431.243921 -56.761402) (xy 431.189973 -56.753646) (xy 431.137678 -56.738291)
			(xy 431.088101 -56.715649) (xy 431.042251 -56.686183) (xy 431.00106 -56.650492) (xy 430.965369 -56.609301)
			(xy 430.935903 -56.563451) (xy 430.913261 -56.513874) (xy 430.897906 -56.461579) (xy 430.89015 -56.407631)
			(xy 430.889664 -56.38038) (xy 430.890138 -56.353046) (xy 430.897943 -56.298939) (xy 430.913391 -56.246499)
			(xy 430.936165 -56.196801) (xy 430.9658 -56.150863) (xy 430.98339 -56.129936) (xy 430.983644 -56.129682)
			(xy 430.983898 -56.129428) (xy 430.989479 -56.122337) (xy 430.995729 -56.105424) (xy 430.99609 -56.096408)
			(xy 430.99609 -56.029352) (xy 430.99571 -56.020337) (xy 430.989479 -56.00342) (xy 430.983898 -55.996332)
			(xy 430.983644 -55.996078) (xy 430.98339 -55.995824) (xy 430.965769 -55.974918) (xy 430.936115 -55.928983)
			(xy 430.913327 -55.879283) (xy 430.89787 -55.826838) (xy 430.890063 -55.772723) (xy 430.890065 -55.718047)
			(xy 430.897877 -55.663933) (xy 430.913337 -55.611489) (xy 430.93613 -55.561791) (xy 430.965787 -55.515858)
			(xy 430.98339 -55.494936) (xy 430.983644 -55.494682) (xy 430.983898 -55.494428) (xy 430.989479 -55.487337)
			(xy 430.995729 -55.470424) (xy 430.99609 -55.461408) (xy 430.99609 -55.394352) (xy 430.99571 -55.385337)
			(xy 430.989479 -55.36842) (xy 430.983898 -55.361332) (xy 430.983644 -55.361078) (xy 430.98339 -55.360824)
			(xy 430.972521 -55.348076) (xy 430.952809 -55.320985) (xy 430.94402 -55.306722) (xy 430.938432 -55.297578)
			(xy 430.921414 -55.285386) (xy 430.82845 -55.26532) (xy 430.807876 -55.269384) (xy 430.79924 -55.27548)
			(xy 430.775165 -55.291463) (xy 430.723238 -55.31681) (xy 430.668083 -55.334041) (xy 430.610962 -55.342761)
			(xy 430.58207 -55.343298) (xy 430.554819 -55.34283) (xy 430.500874 -55.33507) (xy 430.448581 -55.319712)
			(xy 430.399006 -55.297068) (xy 430.353158 -55.267601) (xy 430.311971 -55.231908) (xy 430.276281 -55.190718)
			(xy 430.246817 -55.144867) (xy 430.224178 -55.095291) (xy 430.208824 -55.042997) (xy 430.201068 -54.989051)
			(xy 427.99269 -54.989051) (xy 427.996103 -55.000394) (xy 428.004223 -55.05557) (xy 428.004732 -55.083456)
			(xy 428.004223 -55.111342) (xy 427.996103 -55.166518) (xy 427.980035 -55.219925) (xy 427.956363 -55.270422)
			(xy 427.92559 -55.316935) (xy 427.888373 -55.358472) (xy 427.845505 -55.394147) (xy 427.80175 -55.420851)
			(xy 428.524668 -55.420851) (xy 428.524668 -55.366349) (xy 428.532424 -55.312403) (xy 428.547778 -55.260109)
			(xy 428.570417 -55.210533) (xy 428.599881 -55.164682) (xy 428.635571 -55.123492) (xy 428.676758 -55.087799)
			(xy 428.722606 -55.058332) (xy 428.772181 -55.035688) (xy 428.824474 -55.02033) (xy 428.878419 -55.01257)
			(xy 428.90567 -55.012082) (xy 428.905924 -55.012082) (xy 428.932219 -55.012531) (xy 428.984308 -55.019779)
			(xy 429.034909 -55.034107) (xy 429.083065 -55.055245) (xy 429.127865 -55.082791) (xy 429.16846 -55.116225)
			(xy 429.186594 -55.135272) (xy 429.194173 -55.142705) (xy 429.213585 -55.151236) (xy 429.224186 -55.151782)
			(xy 429.298354 -55.151782) (xy 429.308989 -55.151399) (xy 429.328454 -55.142832) (xy 429.335946 -55.135272)
			(xy 429.354057 -55.116199) (xy 429.394641 -55.082741) (xy 429.439441 -55.055182) (xy 429.487605 -55.034046)
			(xy 429.538217 -55.019733) (xy 429.590317 -55.012516) (xy 429.616616 -55.012082) (xy 429.61687 -55.012082)
			(xy 429.644124 -55.012563) (xy 429.698076 -55.020317) (xy 429.750376 -55.03567) (xy 429.799959 -55.05831)
			(xy 429.845815 -55.087776) (xy 429.88701 -55.123469) (xy 429.922706 -55.164661) (xy 429.952176 -55.210515)
			(xy 429.97482 -55.260095) (xy 429.990177 -55.312394) (xy 429.997935 -55.366347) (xy 429.997935 -55.420854)
			(xy 429.990177 -55.474806) (xy 429.97482 -55.527105) (xy 429.952176 -55.576685) (xy 429.922706 -55.622539)
			(xy 429.88701 -55.663731) (xy 429.845815 -55.699424) (xy 429.799959 -55.72889) (xy 429.750376 -55.75153)
			(xy 429.698076 -55.766883) (xy 429.644124 -55.774637) (xy 429.61687 -55.775098) (xy 429.616616 -55.775098)
			(xy 429.590321 -55.774629) (xy 429.538233 -55.767386) (xy 429.487632 -55.753062) (xy 429.439476 -55.731928)
			(xy 429.394676 -55.704385) (xy 429.354081 -55.670954) (xy 429.335946 -55.651908) (xy 429.328392 -55.644445)
			(xy 429.308961 -55.635932) (xy 429.298354 -55.635398) (xy 429.224186 -55.635398) (xy 429.213554 -55.635809)
			(xy 429.19409 -55.644357) (xy 429.186594 -55.651908) (xy 429.168479 -55.670977) (xy 429.127894 -55.704432)
			(xy 429.083095 -55.73199) (xy 429.034932 -55.753126) (xy 428.984321 -55.767441) (xy 428.932222 -55.774662)
			(xy 428.905924 -55.775098) (xy 428.90567 -55.775098) (xy 428.878419 -55.77463) (xy 428.824474 -55.76687)
			(xy 428.772181 -55.751512) (xy 428.722606 -55.728868) (xy 428.676758 -55.699401) (xy 428.635571 -55.663708)
			(xy 428.599881 -55.622518) (xy 428.570417 -55.576667) (xy 428.547778 -55.527091) (xy 428.532424 -55.474797)
			(xy 428.524668 -55.420851) (xy 427.80175 -55.420851) (xy 427.797899 -55.423201) (xy 427.74657 -55.445013)
			(xy 427.692613 -55.459119) (xy 427.637176 -55.465219) (xy 427.581442 -55.463182) (xy 427.526599 -55.453052)
			(xy 427.473815 -55.435045) (xy 427.424215 -55.409544) (xy 427.378857 -55.377093) (xy 427.338708 -55.338384)
			(xy 427.304622 -55.294241) (xy 427.277326 -55.245606) (xy 427.257403 -55.193515) (xy 427.245277 -55.139078)
			(xy 427.241206 -55.083456) (xy 420.970358 -55.083456) (xy 420.935595 -55.105797) (xy 420.886018 -55.128439)
			(xy 420.833723 -55.143794) (xy 420.779775 -55.15155) (xy 420.725273 -55.15155) (xy 420.671325 -55.143794)
			(xy 420.61903 -55.128439) (xy 420.569453 -55.105797) (xy 420.523603 -55.076331) (xy 420.482412 -55.04064)
			(xy 420.446721 -54.999449) (xy 420.417255 -54.953599) (xy 420.394613 -54.904022) (xy 420.379258 -54.851727)
			(xy 420.371502 -54.797779) (xy 420.371016 -54.770528) (xy 417.239097 -54.770528) (xy 417.23945 -54.791102)
			(xy 417.238964 -54.818353) (xy 417.231208 -54.872301) (xy 417.215853 -54.924596) (xy 417.193211 -54.974173)
			(xy 417.163745 -55.020023) (xy 417.128054 -55.061214) (xy 417.086863 -55.096905) (xy 417.041013 -55.126371)
			(xy 416.991436 -55.149013) (xy 416.939141 -55.164368) (xy 416.885193 -55.172124) (xy 416.830691 -55.172124)
			(xy 416.776743 -55.164368) (xy 416.724448 -55.149013) (xy 416.674871 -55.126371) (xy 416.629021 -55.096905)
			(xy 416.58783 -55.061214) (xy 416.552139 -55.020023) (xy 416.522673 -54.974173) (xy 416.500031 -54.924596)
			(xy 416.484676 -54.872301) (xy 416.47692 -54.818353) (xy 416.476434 -54.791102) (xy 414.578476 -54.791102)
			(xy 414.575384 -54.812611) (xy 414.560029 -54.864906) (xy 414.537387 -54.914483) (xy 414.507921 -54.960333)
			(xy 414.47223 -55.001524) (xy 414.431039 -55.037215) (xy 414.385189 -55.066681) (xy 414.335612 -55.089323)
			(xy 414.283317 -55.104678) (xy 414.229369 -55.112434) (xy 414.174867 -55.112434) (xy 414.120919 -55.104678)
			(xy 414.068624 -55.089323) (xy 414.019047 -55.066681) (xy 413.973197 -55.037215) (xy 413.932006 -55.001524)
			(xy 413.896315 -54.960333) (xy 413.866849 -54.914483) (xy 413.844207 -54.864906) (xy 413.828852 -54.812611)
			(xy 413.821096 -54.758663) (xy 413.82061 -54.731412) (xy 405.312775 -54.731412) (xy 405.352422 -54.737115)
			(xy 405.404715 -54.752472) (xy 405.454291 -54.775114) (xy 405.500141 -54.804581) (xy 405.54133 -54.840273)
			(xy 405.577021 -54.881463) (xy 405.606488 -54.927312) (xy 405.62913 -54.976888) (xy 405.644486 -55.029182)
			(xy 405.652245 -55.083129) (xy 405.652732 -55.11038) (xy 405.652294 -55.137715) (xy 405.64448 -55.191824)
			(xy 405.629024 -55.244264) (xy 405.606242 -55.293961) (xy 405.5766 -55.339898) (xy 405.559006 -55.360824)
			(xy 405.558752 -55.361078) (xy 405.558498 -55.361332) (xy 405.552934 -55.368434) (xy 405.546674 -55.385339)
			(xy 405.546306 -55.394352) (xy 405.546306 -55.461408) (xy 405.546658 -55.470425) (xy 405.552909 -55.487342)
			(xy 405.558498 -55.494428) (xy 405.558752 -55.494682) (xy 405.559006 -55.494936) (xy 405.576588 -55.515873)
			(xy 405.606244 -55.561803) (xy 405.629035 -55.611498) (xy 405.644495 -55.663938) (xy 405.652306 -55.718049)
			(xy 405.652306 -55.722266) (xy 426.13402 -55.722266) (xy 426.138091 -55.666644) (xy 426.150217 -55.612207)
			(xy 426.17014 -55.560116) (xy 426.197436 -55.511481) (xy 426.231522 -55.467338) (xy 426.271671 -55.428629)
			(xy 426.317029 -55.396178) (xy 426.366629 -55.370677) (xy 426.419413 -55.35267) (xy 426.474256 -55.34254)
			(xy 426.52999 -55.340503) (xy 426.585427 -55.346603) (xy 426.639384 -55.360709) (xy 426.690713 -55.382521)
			(xy 426.738319 -55.411575) (xy 426.781187 -55.44725) (xy 426.818404 -55.488787) (xy 426.849177 -55.5353)
			(xy 426.872849 -55.585797) (xy 426.888917 -55.639204) (xy 426.897037 -55.69438) (xy 426.897546 -55.722266)
			(xy 426.897037 -55.750152) (xy 426.888917 -55.805328) (xy 426.872849 -55.858735) (xy 426.849177 -55.909232)
			(xy 426.818404 -55.955745) (xy 426.781187 -55.997282) (xy 426.738319 -56.032957) (xy 426.690713 -56.062011)
			(xy 426.639384 -56.083823) (xy 426.585427 -56.097929) (xy 426.52999 -56.104029) (xy 426.474256 -56.101992)
			(xy 426.419413 -56.091862) (xy 426.366629 -56.073855) (xy 426.317029 -56.048354) (xy 426.271671 -56.015903)
			(xy 426.231522 -55.977194) (xy 426.197436 -55.933051) (xy 426.17014 -55.884416) (xy 426.150217 -55.832325)
			(xy 426.138091 -55.777888) (xy 426.13402 -55.722266) (xy 405.652306 -55.722266) (xy 405.652308 -55.772721)
			(xy 405.644501 -55.826832) (xy 405.629046 -55.879274) (xy 405.606258 -55.92897) (xy 405.576606 -55.974902)
			(xy 405.559006 -55.995824) (xy 405.558752 -55.996078) (xy 405.558498 -55.996332) (xy 405.552934 -56.003434)
			(xy 405.546674 -56.020339) (xy 405.546306 -56.029352) (xy 405.546306 -56.096408) (xy 405.546658 -56.105425)
			(xy 405.552909 -56.122342) (xy 405.558498 -56.129428) (xy 405.558752 -56.129682) (xy 405.559006 -56.129936)
			(xy 405.576583 -56.150874) (xy 405.606223 -56.196808) (xy 405.629003 -56.246503) (xy 405.644454 -56.29894)
			(xy 405.652261 -56.353047) (xy 405.652732 -56.38038) (xy 405.652246 -56.407631) (xy 405.64449 -56.461579)
			(xy 405.629135 -56.513874) (xy 405.606493 -56.563451) (xy 405.577027 -56.609301) (xy 405.541336 -56.650492)
			(xy 405.500145 -56.686183) (xy 405.454295 -56.715649) (xy 405.404718 -56.738291) (xy 405.352423 -56.753646)
			(xy 405.298475 -56.761402) (xy 405.243973 -56.761402) (xy 405.190025 -56.753646) (xy 405.13773 -56.738291)
			(xy 405.088153 -56.715649) (xy 405.042303 -56.686183) (xy 405.001112 -56.650492) (xy 404.965421 -56.609301)
			(xy 404.935955 -56.563451) (xy 404.913313 -56.513874) (xy 404.897958 -56.461579) (xy 404.890202 -56.407631)
			(xy 404.889716 -56.38038) (xy 404.890201 -56.353047) (xy 404.898006 -56.29894) (xy 404.913452 -56.246501)
			(xy 404.936223 -56.196803) (xy 404.965854 -56.150864) (xy 404.983442 -56.129936) (xy 404.983696 -56.129682)
			(xy 404.98395 -56.129428) (xy 404.989537 -56.122342) (xy 404.995782 -56.105425) (xy 404.996142 -56.096408)
			(xy 404.996142 -56.029352) (xy 404.995773 -56.020336) (xy 404.989535 -56.003418) (xy 404.98395 -55.996332)
			(xy 404.983696 -55.996078) (xy 404.983442 -55.995824) (xy 404.965823 -55.974917) (xy 404.936173 -55.928981)
			(xy 404.913387 -55.879281) (xy 404.897933 -55.826836) (xy 404.890127 -55.772722) (xy 404.890129 -55.718048)
			(xy 404.897939 -55.663934) (xy 404.913398 -55.611491) (xy 404.936188 -55.561793) (xy 404.965841 -55.515859)
			(xy 404.983442 -55.494936) (xy 404.983696 -55.494682) (xy 404.98395 -55.494428) (xy 404.989537 -55.487342)
			(xy 404.995782 -55.470425) (xy 404.996142 -55.461408) (xy 404.996142 -55.394352) (xy 404.995773 -55.385336)
			(xy 404.989535 -55.368418) (xy 404.98395 -55.361332) (xy 404.983696 -55.361078) (xy 404.983442 -55.360824)
			(xy 404.97257 -55.348078) (xy 404.95286 -55.320985) (xy 404.944072 -55.306722) (xy 404.938484 -55.297578)
			(xy 404.921466 -55.285386) (xy 404.828502 -55.26532) (xy 404.807928 -55.269384) (xy 404.799292 -55.27548)
			(xy 404.77523 -55.291483) (xy 404.723298 -55.316826) (xy 404.66814 -55.334051) (xy 404.611015 -55.342764)
			(xy 404.582122 -55.343298) (xy 404.554867 -55.342857) (xy 404.500913 -55.335102) (xy 404.448611 -55.319747)
			(xy 404.399026 -55.297106) (xy 404.353169 -55.267637) (xy 404.311973 -55.231943) (xy 404.276276 -55.190748)
			(xy 404.246805 -55.144893) (xy 404.22416 -55.09531) (xy 404.208803 -55.043009) (xy 404.201045 -54.989055)
			(xy 401.992744 -54.989055) (xy 401.996155 -55.000394) (xy 402.004275 -55.05557) (xy 402.004784 -55.083456)
			(xy 402.004275 -55.111342) (xy 401.996155 -55.166518) (xy 401.980087 -55.219925) (xy 401.956415 -55.270422)
			(xy 401.925642 -55.316935) (xy 401.888425 -55.358472) (xy 401.845557 -55.394147) (xy 401.801795 -55.420855)
			(xy 402.524645 -55.420855) (xy 402.524645 -55.366345) (xy 402.532403 -55.312391) (xy 402.54776 -55.26009)
			(xy 402.570405 -55.210507) (xy 402.599876 -55.164652) (xy 402.635573 -55.123457) (xy 402.676769 -55.087763)
			(xy 402.722626 -55.058294) (xy 402.772211 -55.035653) (xy 402.824513 -55.020298) (xy 402.878467 -55.012543)
			(xy 402.905722 -55.012082) (xy 402.905976 -55.012082) (xy 402.93227 -55.012562) (xy 402.984358 -55.019804)
			(xy 403.034958 -55.034126) (xy 403.083114 -55.055258) (xy 403.127914 -55.082799) (xy 403.168511 -55.116227)
			(xy 403.186646 -55.135272) (xy 403.194205 -55.142728) (xy 403.213632 -55.151246) (xy 403.224238 -55.151782)
			(xy 403.298406 -55.151782) (xy 403.309038 -55.151373) (xy 403.328503 -55.142824) (xy 403.335998 -55.135272)
			(xy 403.354133 -55.116222) (xy 403.394712 -55.082762) (xy 403.439506 -55.0552) (xy 403.487665 -55.03406)
			(xy 403.538274 -55.019742) (xy 403.59037 -55.012519) (xy 403.616668 -55.012082) (xy 403.616922 -55.012082)
			(xy 403.644171 -55.01259) (xy 403.698115 -55.020349) (xy 403.750406 -55.035705) (xy 403.799979 -55.058347)
			(xy 403.845825 -55.087813) (xy 403.887012 -55.123504) (xy 403.9227 -55.164692) (xy 403.952164 -55.21054)
			(xy 403.974802 -55.260115) (xy 403.990156 -55.312406) (xy 403.997912 -55.366351) (xy 403.997912 -55.420849)
			(xy 403.990156 -55.474794) (xy 403.974802 -55.527085) (xy 403.952164 -55.57666) (xy 403.9227 -55.622508)
			(xy 403.887012 -55.663696) (xy 403.845826 -55.699387) (xy 403.799979 -55.728853) (xy 403.750406 -55.751495)
			(xy 403.698115 -55.766851) (xy 403.644171 -55.77461) (xy 403.616922 -55.775098) (xy 403.616668 -55.775098)
			(xy 403.590372 -55.774661) (xy 403.538283 -55.767412) (xy 403.487681 -55.753081) (xy 403.439525 -55.731942)
			(xy 403.394726 -55.704393) (xy 403.354132 -55.670956) (xy 403.335998 -55.651908) (xy 403.328425 -55.644468)
			(xy 403.309008 -55.635942) (xy 403.298406 -55.635398) (xy 403.224238 -55.635398) (xy 403.213603 -55.635783)
			(xy 403.194139 -55.644349) (xy 403.186646 -55.651908) (xy 403.168506 -55.670952) (xy 403.127926 -55.704409)
			(xy 403.083132 -55.73197) (xy 403.034974 -55.753111) (xy 402.984368 -55.767431) (xy 402.932273 -55.774658)
			(xy 402.905976 -55.775098) (xy 402.905722 -55.775098) (xy 402.878467 -55.774657) (xy 402.824513 -55.766902)
			(xy 402.772211 -55.751547) (xy 402.722626 -55.728906) (xy 402.676769 -55.699437) (xy 402.635573 -55.663743)
			(xy 402.599876 -55.622548) (xy 402.570405 -55.576693) (xy 402.54776 -55.52711) (xy 402.532403 -55.474809)
			(xy 402.524645 -55.420855) (xy 401.801795 -55.420855) (xy 401.797951 -55.423201) (xy 401.746622 -55.445013)
			(xy 401.692665 -55.459119) (xy 401.637228 -55.465219) (xy 401.581494 -55.463182) (xy 401.526651 -55.453052)
			(xy 401.473867 -55.435045) (xy 401.424267 -55.409544) (xy 401.378909 -55.377093) (xy 401.33876 -55.338384)
			(xy 401.304674 -55.294241) (xy 401.277378 -55.245606) (xy 401.257455 -55.193515) (xy 401.245329 -55.139078)
			(xy 401.241258 -55.083456) (xy 394.97041 -55.083456) (xy 394.935647 -55.105797) (xy 394.88607 -55.128439)
			(xy 394.833775 -55.143794) (xy 394.779827 -55.15155) (xy 394.725325 -55.15155) (xy 394.671377 -55.143794)
			(xy 394.619082 -55.128439) (xy 394.569505 -55.105797) (xy 394.523655 -55.076331) (xy 394.482464 -55.04064)
			(xy 394.446773 -54.999449) (xy 394.417307 -54.953599) (xy 394.394665 -54.904022) (xy 394.37931 -54.851727)
			(xy 394.371554 -54.797779) (xy 394.371068 -54.770528) (xy 391.239149 -54.770528) (xy 391.239502 -54.791102)
			(xy 391.239016 -54.818353) (xy 391.23126 -54.872301) (xy 391.215905 -54.924596) (xy 391.193263 -54.974173)
			(xy 391.163797 -55.020023) (xy 391.128106 -55.061214) (xy 391.086915 -55.096905) (xy 391.041065 -55.126371)
			(xy 390.991488 -55.149013) (xy 390.939193 -55.164368) (xy 390.885245 -55.172124) (xy 390.830743 -55.172124)
			(xy 390.776795 -55.164368) (xy 390.7245 -55.149013) (xy 390.674923 -55.126371) (xy 390.629073 -55.096905)
			(xy 390.587882 -55.061214) (xy 390.552191 -55.020023) (xy 390.522725 -54.974173) (xy 390.500083 -54.924596)
			(xy 390.484728 -54.872301) (xy 390.476972 -54.818353) (xy 390.476486 -54.791102) (xy 388.578528 -54.791102)
			(xy 388.575436 -54.812611) (xy 388.560081 -54.864906) (xy 388.537439 -54.914483) (xy 388.507973 -54.960333)
			(xy 388.472282 -55.001524) (xy 388.431091 -55.037215) (xy 388.385241 -55.066681) (xy 388.335664 -55.089323)
			(xy 388.283369 -55.104678) (xy 388.229421 -55.112434) (xy 388.174919 -55.112434) (xy 388.120971 -55.104678)
			(xy 388.068676 -55.089323) (xy 388.019099 -55.066681) (xy 387.973249 -55.037215) (xy 387.932058 -55.001524)
			(xy 387.896367 -54.960333) (xy 387.866901 -54.914483) (xy 387.844259 -54.864906) (xy 387.828904 -54.812611)
			(xy 387.821148 -54.758663) (xy 387.820662 -54.731412) (xy 379.312681 -54.731412) (xy 379.352476 -54.737131)
			(xy 379.404772 -54.752483) (xy 379.45435 -54.775121) (xy 379.500203 -54.804585) (xy 379.541395 -54.840274)
			(xy 379.577089 -54.881462) (xy 379.606558 -54.927311) (xy 379.629202 -54.976887) (xy 379.64456 -55.029181)
			(xy 379.652319 -55.083129) (xy 379.652784 -55.11038) (xy 379.652334 -55.137714) (xy 379.644521 -55.191822)
			(xy 379.629067 -55.244262) (xy 379.606288 -55.293959) (xy 379.57665 -55.339897) (xy 379.559058 -55.360824)
			(xy 379.558804 -55.361078) (xy 379.55855 -55.361332) (xy 379.55298 -55.36843) (xy 379.546724 -55.385338)
			(xy 379.546358 -55.394352) (xy 379.546358 -55.461408) (xy 379.546699 -55.470427) (xy 379.552956 -55.487344)
			(xy 379.55855 -55.494428) (xy 379.558804 -55.494682) (xy 379.559058 -55.494936) (xy 379.576638 -55.515874)
			(xy 379.606289 -55.561805) (xy 379.629078 -55.6115) (xy 379.644535 -55.66394) (xy 379.652345 -55.71805)
			(xy 379.652345 -55.722266) (xy 400.134072 -55.722266) (xy 400.138143 -55.666644) (xy 400.150269 -55.612207)
			(xy 400.170192 -55.560116) (xy 400.197488 -55.511481) (xy 400.231574 -55.467338) (xy 400.271723 -55.428629)
			(xy 400.317081 -55.396178) (xy 400.366681 -55.370677) (xy 400.419465 -55.35267) (xy 400.474308 -55.34254)
			(xy 400.530042 -55.340503) (xy 400.585479 -55.346603) (xy 400.639436 -55.360709) (xy 400.690765 -55.382521)
			(xy 400.738371 -55.411575) (xy 400.781239 -55.44725) (xy 400.818456 -55.488787) (xy 400.849229 -55.5353)
			(xy 400.872901 -55.585797) (xy 400.888969 -55.639204) (xy 400.897089 -55.69438) (xy 400.897598 -55.722266)
			(xy 400.897089 -55.750152) (xy 400.888969 -55.805328) (xy 400.872901 -55.858735) (xy 400.849229 -55.909232)
			(xy 400.818456 -55.955745) (xy 400.781239 -55.997282) (xy 400.738371 -56.032957) (xy 400.690765 -56.062011)
			(xy 400.639436 -56.083823) (xy 400.585479 -56.097929) (xy 400.530042 -56.104029) (xy 400.474308 -56.101992)
			(xy 400.419465 -56.091862) (xy 400.366681 -56.073855) (xy 400.317081 -56.048354) (xy 400.271723 -56.015903)
			(xy 400.231574 -55.977194) (xy 400.197488 -55.933051) (xy 400.170192 -55.884416) (xy 400.150269 -55.832325)
			(xy 400.138143 -55.777888) (xy 400.134072 -55.722266) (xy 379.652345 -55.722266) (xy 379.652347 -55.77272)
			(xy 379.644542 -55.826831) (xy 379.629088 -55.879272) (xy 379.606304 -55.928968) (xy 379.576656 -55.974901)
			(xy 379.559058 -55.995824) (xy 379.558804 -55.996078) (xy 379.55855 -55.996332) (xy 379.55298 -56.00343)
			(xy 379.546724 -56.020338) (xy 379.546358 -56.029352) (xy 379.546358 -56.096408) (xy 379.546699 -56.105427)
			(xy 379.552956 -56.122344) (xy 379.55855 -56.129428) (xy 379.558804 -56.129682) (xy 379.559058 -56.129936)
			(xy 379.576627 -56.15088) (xy 379.606271 -56.196812) (xy 379.629052 -56.246505) (xy 379.644505 -56.298941)
			(xy 379.652313 -56.353047) (xy 379.652784 -56.38038) (xy 379.652298 -56.407631) (xy 379.644542 -56.461579)
			(xy 379.629187 -56.513874) (xy 379.606545 -56.563451) (xy 379.577079 -56.609301) (xy 379.541388 -56.650492)
			(xy 379.500197 -56.686183) (xy 379.454347 -56.715649) (xy 379.40477 -56.738291) (xy 379.352475 -56.753646)
			(xy 379.298527 -56.761402) (xy 379.244025 -56.761402) (xy 379.190077 -56.753646) (xy 379.137782 -56.738291)
			(xy 379.088205 -56.715649) (xy 379.042355 -56.686183) (xy 379.001164 -56.650492) (xy 378.965473 -56.609301)
			(xy 378.936007 -56.563451) (xy 378.913365 -56.513874) (xy 378.89801 -56.461579) (xy 378.890254 -56.407631)
			(xy 378.889768 -56.38038) (xy 378.890241 -56.353046) (xy 378.898046 -56.298939) (xy 378.913494 -56.246499)
			(xy 378.936269 -56.196801) (xy 378.965904 -56.150863) (xy 378.983494 -56.129936) (xy 378.983748 -56.129682)
			(xy 378.984002 -56.129428) (xy 378.989583 -56.122338) (xy 378.995833 -56.105424) (xy 378.996194 -56.096408)
			(xy 378.996194 -56.029352) (xy 378.995813 -56.020338) (xy 378.989582 -56.00342) (xy 378.984002 -55.996332)
			(xy 378.983748 -55.996078) (xy 378.983494 -55.995824) (xy 378.965873 -55.974918) (xy 378.936219 -55.928983)
			(xy 378.91343 -55.879283) (xy 378.897973 -55.826838) (xy 378.890166 -55.772723) (xy 378.890168 -55.718047)
			(xy 378.89798 -55.663933) (xy 378.91344 -55.611489) (xy 378.936233 -55.561791) (xy 378.965891 -55.515858)
			(xy 378.983494 -55.494936) (xy 378.983748 -55.494682) (xy 378.984002 -55.494428) (xy 378.989583 -55.487338)
			(xy 378.995833 -55.470424) (xy 378.996194 -55.461408) (xy 378.996194 -55.394352) (xy 378.995813 -55.385338)
			(xy 378.989582 -55.36842) (xy 378.984002 -55.361332) (xy 378.983748 -55.361078) (xy 378.983494 -55.360824)
			(xy 378.972625 -55.348075) (xy 378.952913 -55.320984) (xy 378.944124 -55.306722) (xy 378.938536 -55.297578)
			(xy 378.921518 -55.285386) (xy 378.828554 -55.26532) (xy 378.80798 -55.269384) (xy 378.799344 -55.27548)
			(xy 378.775268 -55.291461) (xy 378.723341 -55.316809) (xy 378.668187 -55.33404) (xy 378.611066 -55.342761)
			(xy 378.582174 -55.343298) (xy 378.554923 -55.34283) (xy 378.500977 -55.335071) (xy 378.448684 -55.319713)
			(xy 378.399109 -55.29707) (xy 378.35326 -55.267602) (xy 378.312072 -55.231909) (xy 378.276382 -55.190719)
			(xy 378.246918 -55.144868) (xy 378.224278 -55.095292) (xy 378.208924 -55.042998) (xy 378.201168 -54.989051)
			(xy 375.992794 -54.989051) (xy 375.996207 -55.000394) (xy 376.004327 -55.05557) (xy 376.004836 -55.083456)
			(xy 376.004327 -55.111342) (xy 375.996207 -55.166518) (xy 375.980139 -55.219925) (xy 375.956467 -55.270422)
			(xy 375.925694 -55.316935) (xy 375.888477 -55.358472) (xy 375.845609 -55.394147) (xy 375.801854 -55.420851)
			(xy 376.524768 -55.420851) (xy 376.524768 -55.366349) (xy 376.532524 -55.312402) (xy 376.547878 -55.260108)
			(xy 376.570518 -55.210532) (xy 376.599982 -55.164681) (xy 376.635672 -55.123491) (xy 376.67686 -55.087798)
			(xy 376.722709 -55.05833) (xy 376.772284 -55.035687) (xy 376.824577 -55.020329) (xy 376.878523 -55.01257)
			(xy 376.905774 -55.012082) (xy 376.906028 -55.012082) (xy 376.932323 -55.012528) (xy 376.984412 -55.019777)
			(xy 377.035014 -55.034106) (xy 377.08317 -55.055243) (xy 377.127969 -55.08279) (xy 377.168564 -55.116225)
			(xy 377.186698 -55.135272) (xy 377.194275 -55.142707) (xy 377.213689 -55.151237) (xy 377.22429 -55.151782)
			(xy 377.298458 -55.151782) (xy 377.309093 -55.151401) (xy 377.328558 -55.142833) (xy 377.33605 -55.135272)
			(xy 377.354159 -55.116197) (xy 377.394744 -55.082739) (xy 377.439544 -55.055181) (xy 377.487708 -55.034044)
			(xy 377.538321 -55.019732) (xy 377.590421 -55.012516) (xy 377.61672 -55.012082) (xy 377.616974 -55.012082)
			(xy 377.644227 -55.012564) (xy 377.69818 -55.020317) (xy 377.750479 -55.035671) (xy 377.800061 -55.058311)
			(xy 377.845917 -55.087778) (xy 377.887111 -55.12347) (xy 377.922807 -55.164663) (xy 377.952276 -55.210516)
			(xy 377.97492 -55.260096) (xy 377.990277 -55.312395) (xy 377.998035 -55.366347) (xy 377.998035 -55.420853)
			(xy 377.990277 -55.474805) (xy 377.97492 -55.527104) (xy 377.952276 -55.576684) (xy 377.922807 -55.622537)
			(xy 377.887111 -55.66373) (xy 377.845917 -55.699422) (xy 377.800061 -55.728889) (xy 377.750479 -55.751529)
			(xy 377.69818 -55.766883) (xy 377.644227 -55.774636) (xy 377.616974 -55.775098) (xy 377.61672 -55.775098)
			(xy 377.590426 -55.774627) (xy 377.538337 -55.767384) (xy 377.487736 -55.75306) (xy 377.43958 -55.731927)
			(xy 377.39478 -55.704385) (xy 377.354185 -55.670954) (xy 377.33605 -55.651908) (xy 377.328495 -55.644447)
			(xy 377.309064 -55.635933) (xy 377.298458 -55.635398) (xy 377.22429 -55.635398) (xy 377.213658 -55.635811)
			(xy 377.194194 -55.644358) (xy 377.186698 -55.651908) (xy 377.168581 -55.670975) (xy 377.127996 -55.70443)
			(xy 377.083197 -55.731988) (xy 377.035035 -55.753125) (xy 376.984424 -55.76744) (xy 376.932326 -55.774661)
			(xy 376.906028 -55.775098) (xy 376.905774 -55.775098) (xy 376.878523 -55.77463) (xy 376.824577 -55.766871)
			(xy 376.772284 -55.751513) (xy 376.722709 -55.72887) (xy 376.67686 -55.699402) (xy 376.635672 -55.663709)
			(xy 376.599982 -55.622519) (xy 376.570518 -55.576668) (xy 376.547878 -55.527092) (xy 376.532524 -55.474798)
			(xy 376.524768 -55.420851) (xy 375.801854 -55.420851) (xy 375.798003 -55.423201) (xy 375.746674 -55.445013)
			(xy 375.692717 -55.459119) (xy 375.63728 -55.465219) (xy 375.581546 -55.463182) (xy 375.526703 -55.453052)
			(xy 375.473919 -55.435045) (xy 375.424319 -55.409544) (xy 375.378961 -55.377093) (xy 375.338812 -55.338384)
			(xy 375.304726 -55.294241) (xy 375.27743 -55.245606) (xy 375.257507 -55.193515) (xy 375.245381 -55.139078)
			(xy 375.24131 -55.083456) (xy 368.970462 -55.083456) (xy 368.935699 -55.105797) (xy 368.886122 -55.128439)
			(xy 368.833827 -55.143794) (xy 368.779879 -55.15155) (xy 368.725377 -55.15155) (xy 368.671429 -55.143794)
			(xy 368.619134 -55.128439) (xy 368.569557 -55.105797) (xy 368.523707 -55.076331) (xy 368.482516 -55.04064)
			(xy 368.446825 -54.999449) (xy 368.417359 -54.953599) (xy 368.394717 -54.904022) (xy 368.379362 -54.851727)
			(xy 368.371606 -54.797779) (xy 368.37112 -54.770528) (xy 365.239201 -54.770528) (xy 365.239554 -54.791102)
			(xy 365.239068 -54.818353) (xy 365.231312 -54.872301) (xy 365.215957 -54.924596) (xy 365.193315 -54.974173)
			(xy 365.163849 -55.020023) (xy 365.128158 -55.061214) (xy 365.086967 -55.096905) (xy 365.041117 -55.126371)
			(xy 364.99154 -55.149013) (xy 364.939245 -55.164368) (xy 364.885297 -55.172124) (xy 364.830795 -55.172124)
			(xy 364.776847 -55.164368) (xy 364.724552 -55.149013) (xy 364.674975 -55.126371) (xy 364.629125 -55.096905)
			(xy 364.587934 -55.061214) (xy 364.552243 -55.020023) (xy 364.522777 -54.974173) (xy 364.500135 -54.924596)
			(xy 364.48478 -54.872301) (xy 364.477024 -54.818353) (xy 364.476538 -54.791102) (xy 362.57858 -54.791102)
			(xy 362.575488 -54.812611) (xy 362.560133 -54.864906) (xy 362.537491 -54.914483) (xy 362.508025 -54.960333)
			(xy 362.472334 -55.001524) (xy 362.431143 -55.037215) (xy 362.385293 -55.066681) (xy 362.335716 -55.089323)
			(xy 362.283421 -55.104678) (xy 362.229473 -55.112434) (xy 362.174971 -55.112434) (xy 362.121023 -55.104678)
			(xy 362.068728 -55.089323) (xy 362.019151 -55.066681) (xy 361.973301 -55.037215) (xy 361.93211 -55.001524)
			(xy 361.896419 -54.960333) (xy 361.866953 -54.914483) (xy 361.844311 -54.864906) (xy 361.828956 -54.812611)
			(xy 361.8212 -54.758663) (xy 361.820714 -54.731412) (xy 353.3129 -54.731412) (xy 353.352526 -54.737112)
			(xy 353.40482 -54.752469) (xy 353.454396 -54.775112) (xy 353.500245 -54.804579) (xy 353.541434 -54.840271)
			(xy 353.577125 -54.881462) (xy 353.606592 -54.927311) (xy 353.629234 -54.976888) (xy 353.64459 -55.029182)
			(xy 353.652349 -55.083129) (xy 353.652836 -55.11038) (xy 353.652397 -55.137715) (xy 353.644583 -55.191824)
			(xy 353.629127 -55.244264) (xy 353.606345 -55.293961) (xy 353.576704 -55.339898) (xy 353.55911 -55.360824)
			(xy 353.558856 -55.361078) (xy 353.558602 -55.361332) (xy 353.553038 -55.368434) (xy 353.546778 -55.385339)
			(xy 353.54641 -55.394352) (xy 353.54641 -55.461408) (xy 353.546761 -55.470426) (xy 353.553012 -55.487343)
			(xy 353.558602 -55.494428) (xy 353.558856 -55.494682) (xy 353.55911 -55.494936) (xy 353.576692 -55.515873)
			(xy 353.606347 -55.561803) (xy 353.629138 -55.611498) (xy 353.644598 -55.663938) (xy 353.652409 -55.718049)
			(xy 353.652409 -55.722266) (xy 374.134124 -55.722266) (xy 374.138195 -55.666644) (xy 374.150321 -55.612207)
			(xy 374.170244 -55.560116) (xy 374.19754 -55.511481) (xy 374.231626 -55.467338) (xy 374.271775 -55.428629)
			(xy 374.317133 -55.396178) (xy 374.366733 -55.370677) (xy 374.419517 -55.35267) (xy 374.47436 -55.34254)
			(xy 374.530094 -55.340503) (xy 374.585531 -55.346603) (xy 374.639488 -55.360709) (xy 374.690817 -55.382521)
			(xy 374.738423 -55.411575) (xy 374.781291 -55.44725) (xy 374.818508 -55.488787) (xy 374.849281 -55.5353)
			(xy 374.872953 -55.585797) (xy 374.889021 -55.639204) (xy 374.897141 -55.69438) (xy 374.89765 -55.722266)
			(xy 374.897141 -55.750152) (xy 374.889021 -55.805328) (xy 374.872953 -55.858735) (xy 374.849281 -55.909232)
			(xy 374.818508 -55.955745) (xy 374.781291 -55.997282) (xy 374.738423 -56.032957) (xy 374.690817 -56.062011)
			(xy 374.639488 -56.083823) (xy 374.585531 -56.097929) (xy 374.530094 -56.104029) (xy 374.47436 -56.101992)
			(xy 374.419517 -56.091862) (xy 374.366733 -56.073855) (xy 374.317133 -56.048354) (xy 374.271775 -56.015903)
			(xy 374.231626 -55.977194) (xy 374.19754 -55.933051) (xy 374.170244 -55.884416) (xy 374.150321 -55.832325)
			(xy 374.138195 -55.777888) (xy 374.134124 -55.722266) (xy 353.652409 -55.722266) (xy 353.652411 -55.772721)
			(xy 353.644604 -55.826832) (xy 353.629149 -55.879274) (xy 353.606362 -55.92897) (xy 353.57671 -55.974902)
			(xy 353.55911 -55.995824) (xy 353.558856 -55.996078) (xy 353.558602 -55.996332) (xy 353.553038 -56.003434)
			(xy 353.546778 -56.020339) (xy 353.54641 -56.029352) (xy 353.54641 -56.096408) (xy 353.546761 -56.105426)
			(xy 353.553012 -56.122343) (xy 353.558602 -56.129428) (xy 353.558856 -56.129682) (xy 353.55911 -56.129936)
			(xy 353.576687 -56.150874) (xy 353.606328 -56.196808) (xy 353.629107 -56.246502) (xy 353.644558 -56.29894)
			(xy 353.652365 -56.353047) (xy 353.652836 -56.38038) (xy 353.65235 -56.407631) (xy 353.644594 -56.461579)
			(xy 353.629239 -56.513874) (xy 353.606597 -56.563451) (xy 353.577131 -56.609301) (xy 353.54144 -56.650492)
			(xy 353.500249 -56.686183) (xy 353.454399 -56.715649) (xy 353.404822 -56.738291) (xy 353.352527 -56.753646)
			(xy 353.298579 -56.761402) (xy 353.244077 -56.761402) (xy 353.190129 -56.753646) (xy 353.137834 -56.738291)
			(xy 353.088257 -56.715649) (xy 353.042407 -56.686183) (xy 353.001216 -56.650492) (xy 352.965525 -56.609301)
			(xy 352.936059 -56.563451) (xy 352.913417 -56.513874) (xy 352.898062 -56.461579) (xy 352.890306 -56.407631)
			(xy 352.88982 -56.38038) (xy 352.890305 -56.353047) (xy 352.898109 -56.29894) (xy 352.913555 -56.246501)
			(xy 352.936327 -56.196803) (xy 352.965958 -56.150864) (xy 352.983546 -56.129936) (xy 352.9838 -56.129682)
			(xy 352.984054 -56.129428) (xy 352.989641 -56.122342) (xy 352.995886 -56.105425) (xy 352.996246 -56.096408)
			(xy 352.996246 -56.029352) (xy 352.995876 -56.020336) (xy 352.989639 -56.003418) (xy 352.984054 -55.996332)
			(xy 352.9838 -55.996078) (xy 352.983546 -55.995824) (xy 352.965927 -55.974917) (xy 352.936277 -55.928981)
			(xy 352.91349 -55.879281) (xy 352.898036 -55.826836) (xy 352.89023 -55.772722) (xy 352.890232 -55.718048)
			(xy 352.898042 -55.663934) (xy 352.913501 -55.611491) (xy 352.936291 -55.561792) (xy 352.965945 -55.515859)
			(xy 352.983546 -55.494936) (xy 352.9838 -55.494682) (xy 352.984054 -55.494428) (xy 352.989641 -55.487342)
			(xy 352.995886 -55.470425) (xy 352.996246 -55.461408) (xy 352.996246 -55.394352) (xy 352.995876 -55.385336)
			(xy 352.989639 -55.368418) (xy 352.984054 -55.361332) (xy 352.9838 -55.361078) (xy 352.983546 -55.360824)
			(xy 352.972675 -55.348078) (xy 352.952964 -55.320985) (xy 352.944176 -55.306722) (xy 352.938588 -55.297578)
			(xy 352.92157 -55.285386) (xy 352.828606 -55.26532) (xy 352.808032 -55.269384) (xy 352.799396 -55.27548)
			(xy 352.775333 -55.291482) (xy 352.723402 -55.316825) (xy 352.668243 -55.33405) (xy 352.611119 -55.342764)
			(xy 352.582226 -55.343298) (xy 352.554971 -55.342857) (xy 352.501016 -55.335103) (xy 352.448714 -55.319749)
			(xy 352.399129 -55.297107) (xy 352.353271 -55.267639) (xy 352.312074 -55.231944) (xy 352.276377 -55.19075)
			(xy 352.246906 -55.144894) (xy 352.224261 -55.095311) (xy 352.208903 -55.043009) (xy 352.201145 -54.989055)
			(xy 337.892542 -54.989055) (xy 337.895953 -55.000394) (xy 337.904073 -55.05557) (xy 337.904582 -55.083456)
			(xy 337.904073 -55.111342) (xy 337.895953 -55.166518) (xy 337.879885 -55.219925) (xy 337.856213 -55.270422)
			(xy 337.82544 -55.316935) (xy 337.788223 -55.358472) (xy 337.745355 -55.394147) (xy 337.701593 -55.420855)
			(xy 350.524745 -55.420855) (xy 350.524745 -55.366345) (xy 350.532503 -55.312391) (xy 350.547861 -55.260089)
			(xy 350.570506 -55.210506) (xy 350.599977 -55.16465) (xy 350.635674 -55.123456) (xy 350.676871 -55.087761)
			(xy 350.722729 -55.058293) (xy 350.772314 -55.035651) (xy 350.824616 -55.020297) (xy 350.878571 -55.012543)
			(xy 350.905826 -55.012082) (xy 350.90608 -55.012082) (xy 350.932374 -55.01256) (xy 350.984462 -55.019802)
			(xy 351.035062 -55.034125) (xy 351.083219 -55.055257) (xy 351.128019 -55.082798) (xy 351.168615 -55.116227)
			(xy 351.18675 -55.135272) (xy 351.194308 -55.14273) (xy 351.213736 -55.151247) (xy 351.224342 -55.151782)
			(xy 351.29851 -55.151782) (xy 351.309142 -55.151375) (xy 351.328607 -55.142825) (xy 351.336102 -55.135272)
			(xy 351.354235 -55.11622) (xy 351.394814 -55.082761) (xy 351.439609 -55.055199) (xy 351.487769 -55.034058)
			(xy 351.538378 -55.019741) (xy 351.590474 -55.012519) (xy 351.616772 -55.012082) (xy 351.617026 -55.012082)
			(xy 351.644275 -55.01259) (xy 351.698219 -55.020349) (xy 351.750509 -55.035706) (xy 351.800082 -55.058348)
			(xy 351.845927 -55.087814) (xy 351.887113 -55.123505) (xy 351.922801 -55.164693) (xy 351.952264 -55.210541)
			(xy 351.974903 -55.260115) (xy 351.990256 -55.312407) (xy 351.998012 -55.366351) (xy 351.998012 -55.420849)
			(xy 351.990256 -55.474793) (xy 351.974903 -55.527085) (xy 351.952264 -55.576659) (xy 351.922801 -55.622507)
			(xy 351.887113 -55.663695) (xy 351.845927 -55.699386) (xy 351.800082 -55.728852) (xy 351.750509 -55.751494)
			(xy 351.698219 -55.766851) (xy 351.644275 -55.77461) (xy 351.617026 -55.775098) (xy 351.616772 -55.775098)
			(xy 351.590476 -55.774659) (xy 351.538387 -55.767409) (xy 351.487785 -55.75308) (xy 351.439629 -55.731941)
			(xy 351.39483 -55.704392) (xy 351.354236 -55.670956) (xy 351.336102 -55.651908) (xy 351.328528 -55.64447)
			(xy 351.309112 -55.635943) (xy 351.29851 -55.635398) (xy 351.224342 -55.635398) (xy 351.213707 -55.635785)
			(xy 351.194243 -55.64435) (xy 351.18675 -55.651908) (xy 351.168657 -55.670998) (xy 351.128067 -55.704451)
			(xy 351.083263 -55.732006) (xy 351.035096 -55.753139) (xy 350.984481 -55.767449) (xy 350.93238 -55.774665)
			(xy 350.90608 -55.775098) (xy 350.905826 -55.775098) (xy 350.878571 -55.774657) (xy 350.824616 -55.766903)
			(xy 350.772314 -55.751549) (xy 350.722729 -55.728907) (xy 350.676871 -55.699439) (xy 350.635674 -55.663744)
			(xy 350.599977 -55.62255) (xy 350.570506 -55.576694) (xy 350.547861 -55.527111) (xy 350.532503 -55.474809)
			(xy 350.524745 -55.420855) (xy 337.701593 -55.420855) (xy 337.697749 -55.423201) (xy 337.64642 -55.445013)
			(xy 337.592463 -55.459119) (xy 337.537026 -55.465219) (xy 337.481292 -55.463182) (xy 337.426449 -55.453052)
			(xy 337.373665 -55.435045) (xy 337.324065 -55.409544) (xy 337.278707 -55.377093) (xy 337.238558 -55.338384)
			(xy 337.204472 -55.294241) (xy 337.177176 -55.245606) (xy 337.157253 -55.193515) (xy 337.145127 -55.139078)
			(xy 337.141056 -55.083456) (xy 330.870208 -55.083456) (xy 330.835445 -55.105797) (xy 330.785868 -55.128439)
			(xy 330.733573 -55.143794) (xy 330.679625 -55.15155) (xy 330.625123 -55.15155) (xy 330.571175 -55.143794)
			(xy 330.51888 -55.128439) (xy 330.469303 -55.105797) (xy 330.423453 -55.076331) (xy 330.382262 -55.04064)
			(xy 330.346571 -54.999449) (xy 330.317105 -54.953599) (xy 330.294463 -54.904022) (xy 330.279108 -54.851727)
			(xy 330.271352 -54.797779) (xy 330.270866 -54.770528) (xy 327.138947 -54.770528) (xy 327.1393 -54.791102)
			(xy 327.138814 -54.818353) (xy 327.131058 -54.872301) (xy 327.115703 -54.924596) (xy 327.093061 -54.974173)
			(xy 327.063595 -55.020023) (xy 327.027904 -55.061214) (xy 326.986713 -55.096905) (xy 326.940863 -55.126371)
			(xy 326.891286 -55.149013) (xy 326.838991 -55.164368) (xy 326.785043 -55.172124) (xy 326.730541 -55.172124)
			(xy 326.676593 -55.164368) (xy 326.624298 -55.149013) (xy 326.574721 -55.126371) (xy 326.528871 -55.096905)
			(xy 326.48768 -55.061214) (xy 326.451989 -55.020023) (xy 326.422523 -54.974173) (xy 326.399881 -54.924596)
			(xy 326.384526 -54.872301) (xy 326.37677 -54.818353) (xy 326.376284 -54.791102) (xy 324.478326 -54.791102)
			(xy 324.475234 -54.812611) (xy 324.459879 -54.864906) (xy 324.437237 -54.914483) (xy 324.407771 -54.960333)
			(xy 324.37208 -55.001524) (xy 324.330889 -55.037215) (xy 324.285039 -55.066681) (xy 324.235462 -55.089323)
			(xy 324.183167 -55.104678) (xy 324.129219 -55.112434) (xy 324.074717 -55.112434) (xy 324.020769 -55.104678)
			(xy 323.968474 -55.089323) (xy 323.918897 -55.066681) (xy 323.873047 -55.037215) (xy 323.831856 -55.001524)
			(xy 323.796165 -54.960333) (xy 323.766699 -54.914483) (xy 323.744057 -54.864906) (xy 323.728702 -54.812611)
			(xy 323.720946 -54.758663) (xy 323.72046 -54.731412) (xy 315.212472 -54.731412) (xy 315.252274 -54.737132)
			(xy 315.304569 -54.752484) (xy 315.354148 -54.775122) (xy 315.4 -54.804586) (xy 315.441193 -54.840275)
			(xy 315.476887 -54.881463) (xy 315.506356 -54.927311) (xy 315.529 -54.976887) (xy 315.544358 -55.029181)
			(xy 315.552117 -55.083129) (xy 315.552582 -55.11038) (xy 315.552132 -55.137714) (xy 315.544319 -55.191823)
			(xy 315.528865 -55.244262) (xy 315.506086 -55.293959) (xy 315.476448 -55.339897) (xy 315.458856 -55.360824)
			(xy 315.458602 -55.361078) (xy 315.458348 -55.361332) (xy 315.452778 -55.368429) (xy 315.446522 -55.385338)
			(xy 315.446156 -55.394352) (xy 315.446156 -55.461408) (xy 315.446497 -55.470427) (xy 315.452755 -55.487344)
			(xy 315.458348 -55.494428) (xy 315.458602 -55.494682) (xy 315.458856 -55.494936) (xy 315.476436 -55.515874)
			(xy 315.506088 -55.561805) (xy 315.528876 -55.6115) (xy 315.544334 -55.66394) (xy 315.552144 -55.71805)
			(xy 315.552144 -55.722266) (xy 336.03387 -55.722266) (xy 336.037941 -55.666644) (xy 336.050067 -55.612207)
			(xy 336.06999 -55.560116) (xy 336.097286 -55.511481) (xy 336.131372 -55.467338) (xy 336.171521 -55.428629)
			(xy 336.216879 -55.396178) (xy 336.266479 -55.370677) (xy 336.319263 -55.35267) (xy 336.374106 -55.34254)
			(xy 336.42984 -55.340503) (xy 336.485277 -55.346603) (xy 336.539234 -55.360709) (xy 336.590563 -55.382521)
			(xy 336.638169 -55.411575) (xy 336.681037 -55.44725) (xy 336.718254 -55.488787) (xy 336.749027 -55.5353)
			(xy 336.772699 -55.585797) (xy 336.788767 -55.639204) (xy 336.796887 -55.69438) (xy 336.797396 -55.722266)
			(xy 336.796887 -55.750152) (xy 336.788767 -55.805328) (xy 336.772699 -55.858735) (xy 336.749027 -55.909232)
			(xy 336.718254 -55.955745) (xy 336.681037 -55.997282) (xy 336.638169 -56.032957) (xy 336.590563 -56.062011)
			(xy 336.539234 -56.083823) (xy 336.485277 -56.097929) (xy 336.42984 -56.104029) (xy 336.374106 -56.101992)
			(xy 336.319263 -56.091862) (xy 336.266479 -56.073855) (xy 336.216879 -56.048354) (xy 336.171521 -56.015903)
			(xy 336.131372 -55.977194) (xy 336.097286 -55.933051) (xy 336.06999 -55.884416) (xy 336.050067 -55.832325)
			(xy 336.037941 -55.777888) (xy 336.03387 -55.722266) (xy 315.552144 -55.722266) (xy 315.552146 -55.77272)
			(xy 315.54434 -55.826831) (xy 315.528887 -55.879272) (xy 315.506102 -55.928968) (xy 315.476454 -55.974901)
			(xy 315.458856 -55.995824) (xy 315.458602 -55.996078) (xy 315.458348 -55.996332) (xy 315.452778 -56.003429)
			(xy 315.446522 -56.020338) (xy 315.446156 -56.029352) (xy 315.446156 -56.096408) (xy 315.446497 -56.105427)
			(xy 315.452755 -56.122344) (xy 315.458348 -56.129428) (xy 315.458602 -56.129682) (xy 315.458856 -56.129936)
			(xy 315.476425 -56.150881) (xy 315.506068 -56.196812) (xy 315.52885 -56.246505) (xy 315.544303 -56.298941)
			(xy 315.552111 -56.353047) (xy 315.552582 -56.38038) (xy 315.552096 -56.407631) (xy 315.54434 -56.461579)
			(xy 315.528985 -56.513874) (xy 315.506343 -56.563451) (xy 315.476877 -56.609301) (xy 315.441186 -56.650492)
			(xy 315.399995 -56.686183) (xy 315.354145 -56.715649) (xy 315.304568 -56.738291) (xy 315.252273 -56.753646)
			(xy 315.198325 -56.761402) (xy 315.143823 -56.761402) (xy 315.089875 -56.753646) (xy 315.03758 -56.738291)
			(xy 314.988003 -56.715649) (xy 314.942153 -56.686183) (xy 314.900962 -56.650492) (xy 314.865271 -56.609301)
			(xy 314.835805 -56.563451) (xy 314.813163 -56.513874) (xy 314.797808 -56.461579) (xy 314.790052 -56.407631)
			(xy 314.789566 -56.38038) (xy 314.790039 -56.353046) (xy 314.797845 -56.298939) (xy 314.813293 -56.246499)
			(xy 314.836067 -56.196801) (xy 314.865702 -56.150863) (xy 314.883292 -56.129936) (xy 314.883546 -56.129682)
			(xy 314.8838 -56.129428) (xy 314.889381 -56.122338) (xy 314.895631 -56.105424) (xy 314.895992 -56.096408)
			(xy 314.895992 -56.029352) (xy 314.895612 -56.020337) (xy 314.88938 -56.00342) (xy 314.8838 -55.996332)
			(xy 314.883546 -55.996078) (xy 314.883292 -55.995824) (xy 314.865671 -55.974918) (xy 314.836017 -55.928983)
			(xy 314.813228 -55.879283) (xy 314.797772 -55.826838) (xy 314.789964 -55.772723) (xy 314.789967 -55.718047)
			(xy 314.797778 -55.663933) (xy 314.813239 -55.611489) (xy 314.836032 -55.561791) (xy 314.865689 -55.515858)
			(xy 314.883292 -55.494936) (xy 314.883546 -55.494682) (xy 314.8838 -55.494428) (xy 314.889381 -55.487338)
			(xy 314.895631 -55.470424) (xy 314.895992 -55.461408) (xy 314.895992 -55.394352) (xy 314.895612 -55.385337)
			(xy 314.88938 -55.36842) (xy 314.8838 -55.361332) (xy 314.883546 -55.361078) (xy 314.883292 -55.360824)
			(xy 314.872423 -55.348075) (xy 314.852711 -55.320984) (xy 314.843922 -55.306722) (xy 314.838334 -55.297578)
			(xy 314.821316 -55.285386) (xy 314.728352 -55.26532) (xy 314.707778 -55.269384) (xy 314.699142 -55.27548)
			(xy 314.675067 -55.291462) (xy 314.62314 -55.316809) (xy 314.567985 -55.33404) (xy 314.510864 -55.342761)
			(xy 314.481972 -55.343298) (xy 314.454721 -55.34283) (xy 314.400775 -55.33507) (xy 314.348482 -55.319712)
			(xy 314.298907 -55.297069) (xy 314.253059 -55.267601) (xy 314.211871 -55.231909) (xy 314.176182 -55.190718)
			(xy 314.146718 -55.144868) (xy 314.124078 -55.095291) (xy 314.108724 -55.042997) (xy 314.100968 -54.989051)
			(xy 311.892592 -54.989051) (xy 311.896005 -55.000394) (xy 311.904125 -55.05557) (xy 311.904634 -55.083456)
			(xy 311.904125 -55.111342) (xy 311.896005 -55.166518) (xy 311.879937 -55.219925) (xy 311.856265 -55.270422)
			(xy 311.825492 -55.316935) (xy 311.788275 -55.358472) (xy 311.745407 -55.394147) (xy 311.701652 -55.420851)
			(xy 312.424568 -55.420851) (xy 312.424568 -55.366349) (xy 312.432324 -55.312403) (xy 312.447678 -55.260109)
			(xy 312.470318 -55.210532) (xy 312.499782 -55.164682) (xy 312.535471 -55.123491) (xy 312.576659 -55.087799)
			(xy 312.622507 -55.058331) (xy 312.672082 -55.035688) (xy 312.724375 -55.02033) (xy 312.778321 -55.01257)
			(xy 312.805572 -55.012082) (xy 312.805826 -55.012082) (xy 312.832121 -55.012529) (xy 312.88421 -55.019778)
			(xy 312.934811 -55.034106) (xy 312.982967 -55.055244) (xy 313.027767 -55.082791) (xy 313.068362 -55.116225)
			(xy 313.086496 -55.135272) (xy 313.094074 -55.142706) (xy 313.113487 -55.151236) (xy 313.124088 -55.151782)
			(xy 313.198256 -55.151782) (xy 313.208891 -55.1514) (xy 313.228356 -55.142832) (xy 313.235848 -55.135272)
			(xy 313.253958 -55.116198) (xy 313.294543 -55.08274) (xy 313.339342 -55.055181) (xy 313.387506 -55.034045)
			(xy 313.438119 -55.019732) (xy 313.490219 -55.012516) (xy 313.516518 -55.012082) (xy 313.516772 -55.012082)
			(xy 313.544025 -55.012563) (xy 313.597978 -55.020317) (xy 313.650278 -55.03567) (xy 313.69986 -55.05831)
			(xy 313.745716 -55.087777) (xy 313.786911 -55.12347) (xy 313.822606 -55.164662) (xy 313.852076 -55.210515)
			(xy 313.87472 -55.260096) (xy 313.890077 -55.312395) (xy 313.897835 -55.366347) (xy 313.897835 -55.420853)
			(xy 313.890077 -55.474805) (xy 313.87472 -55.527104) (xy 313.852076 -55.576685) (xy 313.822606 -55.622538)
			(xy 313.786911 -55.66373) (xy 313.745716 -55.699423) (xy 313.69986 -55.72889) (xy 313.650278 -55.75153)
			(xy 313.597978 -55.766883) (xy 313.544025 -55.774637) (xy 313.516772 -55.775098) (xy 313.516518 -55.775098)
			(xy 313.490224 -55.774628) (xy 313.438135 -55.767385) (xy 313.387534 -55.753061) (xy 313.339378 -55.731928)
			(xy 313.294578 -55.704385) (xy 313.253983 -55.670954) (xy 313.235848 -55.651908) (xy 313.228294 -55.644446)
			(xy 313.208863 -55.635933) (xy 313.198256 -55.635398) (xy 313.124088 -55.635398) (xy 313.113456 -55.63581)
			(xy 313.093992 -55.644357) (xy 313.086496 -55.651908) (xy 313.06838 -55.670976) (xy 313.027795 -55.704431)
			(xy 312.982996 -55.731989) (xy 312.934834 -55.753126) (xy 312.884223 -55.767441) (xy 312.832124 -55.774661)
			(xy 312.805826 -55.775098) (xy 312.805572 -55.775098) (xy 312.778321 -55.77463) (xy 312.724375 -55.76687)
			(xy 312.672082 -55.751512) (xy 312.622507 -55.728869) (xy 312.576659 -55.699401) (xy 312.535471 -55.663709)
			(xy 312.499782 -55.622518) (xy 312.470318 -55.576668) (xy 312.447678 -55.527091) (xy 312.432324 -55.474797)
			(xy 312.424568 -55.420851) (xy 311.701652 -55.420851) (xy 311.697801 -55.423201) (xy 311.646472 -55.445013)
			(xy 311.592515 -55.459119) (xy 311.537078 -55.465219) (xy 311.481344 -55.463182) (xy 311.426501 -55.453052)
			(xy 311.373717 -55.435045) (xy 311.324117 -55.409544) (xy 311.278759 -55.377093) (xy 311.23861 -55.338384)
			(xy 311.204524 -55.294241) (xy 311.177228 -55.245606) (xy 311.157305 -55.193515) (xy 311.145179 -55.139078)
			(xy 311.141108 -55.083456) (xy 304.87026 -55.083456) (xy 304.835497 -55.105797) (xy 304.78592 -55.128439)
			(xy 304.733625 -55.143794) (xy 304.679677 -55.15155) (xy 304.625175 -55.15155) (xy 304.571227 -55.143794)
			(xy 304.518932 -55.128439) (xy 304.469355 -55.105797) (xy 304.423505 -55.076331) (xy 304.382314 -55.04064)
			(xy 304.346623 -54.999449) (xy 304.317157 -54.953599) (xy 304.294515 -54.904022) (xy 304.27916 -54.851727)
			(xy 304.271404 -54.797779) (xy 304.270918 -54.770528) (xy 301.138999 -54.770528) (xy 301.139352 -54.791102)
			(xy 301.138866 -54.818353) (xy 301.13111 -54.872301) (xy 301.115755 -54.924596) (xy 301.093113 -54.974173)
			(xy 301.063647 -55.020023) (xy 301.027956 -55.061214) (xy 300.986765 -55.096905) (xy 300.940915 -55.126371)
			(xy 300.891338 -55.149013) (xy 300.839043 -55.164368) (xy 300.785095 -55.172124) (xy 300.730593 -55.172124)
			(xy 300.676645 -55.164368) (xy 300.62435 -55.149013) (xy 300.574773 -55.126371) (xy 300.528923 -55.096905)
			(xy 300.487732 -55.061214) (xy 300.452041 -55.020023) (xy 300.422575 -54.974173) (xy 300.399933 -54.924596)
			(xy 300.384578 -54.872301) (xy 300.376822 -54.818353) (xy 300.376336 -54.791102) (xy 298.478378 -54.791102)
			(xy 298.475286 -54.812611) (xy 298.459931 -54.864906) (xy 298.437289 -54.914483) (xy 298.407823 -54.960333)
			(xy 298.372132 -55.001524) (xy 298.330941 -55.037215) (xy 298.285091 -55.066681) (xy 298.235514 -55.089323)
			(xy 298.183219 -55.104678) (xy 298.129271 -55.112434) (xy 298.074769 -55.112434) (xy 298.020821 -55.104678)
			(xy 297.968526 -55.089323) (xy 297.918949 -55.066681) (xy 297.873099 -55.037215) (xy 297.831908 -55.001524)
			(xy 297.796217 -54.960333) (xy 297.766751 -54.914483) (xy 297.744109 -54.864906) (xy 297.728754 -54.812611)
			(xy 297.720998 -54.758663) (xy 297.720512 -54.731412) (xy 289.212686 -54.731412) (xy 289.252324 -54.737113)
			(xy 289.304617 -54.752471) (xy 289.354193 -54.775113) (xy 289.400043 -54.80458) (xy 289.441232 -54.840272)
			(xy 289.476923 -54.881462) (xy 289.50639 -54.927312) (xy 289.529032 -54.976888) (xy 289.544388 -55.029182)
			(xy 289.552147 -55.083129) (xy 289.552634 -55.11038) (xy 289.552196 -55.137715) (xy 289.544382 -55.191824)
			(xy 289.528926 -55.244264) (xy 289.506143 -55.293961) (xy 289.476502 -55.339898) (xy 289.458908 -55.360824)
			(xy 289.458654 -55.361078) (xy 289.4584 -55.361332) (xy 289.452836 -55.368434) (xy 289.446576 -55.385339)
			(xy 289.446208 -55.394352) (xy 289.446208 -55.461408) (xy 289.446559 -55.470425) (xy 289.452811 -55.487342)
			(xy 289.4584 -55.494428) (xy 289.458654 -55.494682) (xy 289.458908 -55.494936) (xy 289.47649 -55.515873)
			(xy 289.506145 -55.561803) (xy 289.528937 -55.611498) (xy 289.544396 -55.663938) (xy 289.552207 -55.718049)
			(xy 289.552207 -55.722266) (xy 310.033922 -55.722266) (xy 310.037993 -55.666644) (xy 310.050119 -55.612207)
			(xy 310.070042 -55.560116) (xy 310.097338 -55.511481) (xy 310.131424 -55.467338) (xy 310.171573 -55.428629)
			(xy 310.216931 -55.396178) (xy 310.266531 -55.370677) (xy 310.319315 -55.35267) (xy 310.374158 -55.34254)
			(xy 310.429892 -55.340503) (xy 310.485329 -55.346603) (xy 310.539286 -55.360709) (xy 310.590615 -55.382521)
			(xy 310.638221 -55.411575) (xy 310.681089 -55.44725) (xy 310.718306 -55.488787) (xy 310.749079 -55.5353)
			(xy 310.772751 -55.585797) (xy 310.788819 -55.639204) (xy 310.796939 -55.69438) (xy 310.797448 -55.722266)
			(xy 310.796939 -55.750152) (xy 310.788819 -55.805328) (xy 310.772751 -55.858735) (xy 310.749079 -55.909232)
			(xy 310.718306 -55.955745) (xy 310.681089 -55.997282) (xy 310.638221 -56.032957) (xy 310.590615 -56.062011)
			(xy 310.539286 -56.083823) (xy 310.485329 -56.097929) (xy 310.429892 -56.104029) (xy 310.374158 -56.101992)
			(xy 310.319315 -56.091862) (xy 310.266531 -56.073855) (xy 310.216931 -56.048354) (xy 310.171573 -56.015903)
			(xy 310.131424 -55.977194) (xy 310.097338 -55.933051) (xy 310.070042 -55.884416) (xy 310.050119 -55.832325)
			(xy 310.037993 -55.777888) (xy 310.033922 -55.722266) (xy 289.552207 -55.722266) (xy 289.552209 -55.772721)
			(xy 289.544403 -55.826832) (xy 289.528947 -55.879274) (xy 289.50616 -55.92897) (xy 289.476508 -55.974902)
			(xy 289.458908 -55.995824) (xy 289.458654 -55.996078) (xy 289.4584 -55.996332) (xy 289.452836 -56.003434)
			(xy 289.446576 -56.020339) (xy 289.446208 -56.029352) (xy 289.446208 -56.096408) (xy 289.446559 -56.105425)
			(xy 289.452811 -56.122342) (xy 289.4584 -56.129428) (xy 289.458654 -56.129682) (xy 289.458908 -56.129936)
			(xy 289.476485 -56.150874) (xy 289.506126 -56.196808) (xy 289.528905 -56.246502) (xy 289.544356 -56.29894)
			(xy 289.552163 -56.353047) (xy 289.552634 -56.38038) (xy 289.552148 -56.407631) (xy 289.544392 -56.461579)
			(xy 289.529037 -56.513874) (xy 289.506395 -56.563451) (xy 289.476929 -56.609301) (xy 289.441238 -56.650492)
			(xy 289.400047 -56.686183) (xy 289.354197 -56.715649) (xy 289.30462 -56.738291) (xy 289.252325 -56.753646)
			(xy 289.198377 -56.761402) (xy 289.143875 -56.761402) (xy 289.089927 -56.753646) (xy 289.037632 -56.738291)
			(xy 288.988055 -56.715649) (xy 288.942205 -56.686183) (xy 288.901014 -56.650492) (xy 288.865323 -56.609301)
			(xy 288.835857 -56.563451) (xy 288.813215 -56.513874) (xy 288.79786 -56.461579) (xy 288.790104 -56.407631)
			(xy 288.789618 -56.38038) (xy 288.790103 -56.353047) (xy 288.797907 -56.29894) (xy 288.813353 -56.246501)
			(xy 288.836125 -56.196803) (xy 288.865756 -56.150864) (xy 288.883344 -56.129936) (xy 288.883598 -56.129682)
			(xy 288.883852 -56.129428) (xy 288.889439 -56.122342) (xy 288.895684 -56.105425) (xy 288.896044 -56.096408)
			(xy 288.896044 -56.029352) (xy 288.895674 -56.020336) (xy 288.889437 -56.003418) (xy 288.883852 -55.996332)
			(xy 288.883598 -55.996078) (xy 288.883344 -55.995824) (xy 288.865725 -55.974917) (xy 288.836075 -55.928981)
			(xy 288.813289 -55.879281) (xy 288.797834 -55.826836) (xy 288.790028 -55.772722) (xy 288.79003 -55.718048)
			(xy 288.797841 -55.663934) (xy 288.813299 -55.611491) (xy 288.836089 -55.561793) (xy 288.865743 -55.515859)
			(xy 288.883344 -55.494936) (xy 288.883598 -55.494682) (xy 288.883852 -55.494428) (xy 288.889439 -55.487342)
			(xy 288.895684 -55.470425) (xy 288.896044 -55.461408) (xy 288.896044 -55.394352) (xy 288.895674 -55.385336)
			(xy 288.889437 -55.368418) (xy 288.883852 -55.361332) (xy 288.883598 -55.361078) (xy 288.883344 -55.360824)
			(xy 288.872472 -55.348078) (xy 288.852762 -55.320985) (xy 288.843974 -55.306722) (xy 288.838386 -55.297578)
			(xy 288.821368 -55.285386) (xy 288.728404 -55.26532) (xy 288.70783 -55.269384) (xy 288.699194 -55.27548)
			(xy 288.675132 -55.291483) (xy 288.6232 -55.316825) (xy 288.568041 -55.33405) (xy 288.510917 -55.342764)
			(xy 288.482024 -55.343298) (xy 288.454769 -55.342857) (xy 288.400814 -55.335102) (xy 288.348512 -55.319748)
			(xy 288.298928 -55.297106) (xy 288.25307 -55.267638) (xy 288.211874 -55.231943) (xy 288.176176 -55.190749)
			(xy 288.146705 -55.144893) (xy 288.12406 -55.09531) (xy 288.108703 -55.043009) (xy 288.100945 -54.989055)
			(xy 285.892646 -54.989055) (xy 285.896057 -55.000394) (xy 285.904177 -55.05557) (xy 285.904686 -55.083456)
			(xy 285.904177 -55.111342) (xy 285.896057 -55.166518) (xy 285.879989 -55.219925) (xy 285.856317 -55.270422)
			(xy 285.825544 -55.316935) (xy 285.788327 -55.358472) (xy 285.745459 -55.394147) (xy 285.701697 -55.420855)
			(xy 286.424545 -55.420855) (xy 286.424545 -55.366345) (xy 286.432303 -55.312391) (xy 286.44766 -55.26009)
			(xy 286.470305 -55.210507) (xy 286.499776 -55.164651) (xy 286.535474 -55.123457) (xy 286.57667 -55.087762)
			(xy 286.622528 -55.058294) (xy 286.672112 -55.035652) (xy 286.724414 -55.020298) (xy 286.778369 -55.012543)
			(xy 286.805624 -55.012082) (xy 286.805878 -55.012082) (xy 286.832172 -55.012561) (xy 286.88426 -55.019803)
			(xy 286.93486 -55.034125) (xy 286.983016 -55.055257) (xy 287.027817 -55.082798) (xy 287.068413 -55.116227)
			(xy 287.086548 -55.135272) (xy 287.094106 -55.142729) (xy 287.113534 -55.151246) (xy 287.12414 -55.151782)
			(xy 287.198308 -55.151782) (xy 287.20894 -55.151374) (xy 287.228405 -55.142824) (xy 287.2359 -55.135272)
			(xy 287.254034 -55.116221) (xy 287.294613 -55.082761) (xy 287.339408 -55.0552) (xy 287.387567 -55.034059)
			(xy 287.438176 -55.019741) (xy 287.490272 -55.012519) (xy 287.51657 -55.012082) (xy 287.516824 -55.012082)
			(xy 287.544073 -55.01259) (xy 287.598017 -55.020349) (xy 287.650307 -55.035706) (xy 287.69988 -55.058348)
			(xy 287.745726 -55.087814) (xy 287.786913 -55.123504) (xy 287.822601 -55.164693) (xy 287.852064 -55.210541)
			(xy 287.874703 -55.260115) (xy 287.890056 -55.312406) (xy 287.897812 -55.366351) (xy 287.897812 -55.420849)
			(xy 287.890056 -55.474794) (xy 287.874703 -55.527085) (xy 287.852064 -55.576659) (xy 287.822601 -55.622507)
			(xy 287.786913 -55.663696) (xy 287.745726 -55.699386) (xy 287.69988 -55.728852) (xy 287.650307 -55.751494)
			(xy 287.598017 -55.766851) (xy 287.544073 -55.77461) (xy 287.516824 -55.775098) (xy 287.51657 -55.775098)
			(xy 287.490274 -55.77466) (xy 287.438185 -55.76741) (xy 287.387583 -55.75308) (xy 287.339427 -55.731941)
			(xy 287.294628 -55.704393) (xy 287.254034 -55.670956) (xy 287.2359 -55.651908) (xy 287.228326 -55.644469)
			(xy 287.20891 -55.635942) (xy 287.198308 -55.635398) (xy 287.12414 -55.635398) (xy 287.113505 -55.635784)
			(xy 287.094041 -55.64435) (xy 287.086548 -55.651908) (xy 287.068407 -55.670951) (xy 287.027827 -55.704408)
			(xy 286.983033 -55.731969) (xy 286.934876 -55.753111) (xy 286.88427 -55.767431) (xy 286.832175 -55.774658)
			(xy 286.805878 -55.775098) (xy 286.805624 -55.775098) (xy 286.778369 -55.774657) (xy 286.724414 -55.766902)
			(xy 286.672112 -55.751548) (xy 286.622528 -55.728906) (xy 286.57667 -55.699438) (xy 286.535474 -55.663743)
			(xy 286.499776 -55.622549) (xy 286.470305 -55.576693) (xy 286.44766 -55.52711) (xy 286.432303 -55.474809)
			(xy 286.424545 -55.420855) (xy 285.701697 -55.420855) (xy 285.697853 -55.423201) (xy 285.646524 -55.445013)
			(xy 285.592567 -55.459119) (xy 285.53713 -55.465219) (xy 285.481396 -55.463182) (xy 285.426553 -55.453052)
			(xy 285.373769 -55.435045) (xy 285.324169 -55.409544) (xy 285.278811 -55.377093) (xy 285.238662 -55.338384)
			(xy 285.204576 -55.294241) (xy 285.17728 -55.245606) (xy 285.157357 -55.193515) (xy 285.145231 -55.139078)
			(xy 285.14116 -55.083456) (xy 278.870312 -55.083456) (xy 278.835549 -55.105797) (xy 278.785972 -55.128439)
			(xy 278.733677 -55.143794) (xy 278.679729 -55.15155) (xy 278.625227 -55.15155) (xy 278.571279 -55.143794)
			(xy 278.518984 -55.128439) (xy 278.469407 -55.105797) (xy 278.423557 -55.076331) (xy 278.382366 -55.04064)
			(xy 278.346675 -54.999449) (xy 278.317209 -54.953599) (xy 278.294567 -54.904022) (xy 278.279212 -54.851727)
			(xy 278.271456 -54.797779) (xy 278.27097 -54.770528) (xy 275.139051 -54.770528) (xy 275.139404 -54.791102)
			(xy 275.138918 -54.818353) (xy 275.131162 -54.872301) (xy 275.115807 -54.924596) (xy 275.093165 -54.974173)
			(xy 275.063699 -55.020023) (xy 275.028008 -55.061214) (xy 274.986817 -55.096905) (xy 274.940967 -55.126371)
			(xy 274.89139 -55.149013) (xy 274.839095 -55.164368) (xy 274.785147 -55.172124) (xy 274.730645 -55.172124)
			(xy 274.676697 -55.164368) (xy 274.624402 -55.149013) (xy 274.574825 -55.126371) (xy 274.528975 -55.096905)
			(xy 274.487784 -55.061214) (xy 274.452093 -55.020023) (xy 274.422627 -54.974173) (xy 274.399985 -54.924596)
			(xy 274.38463 -54.872301) (xy 274.376874 -54.818353) (xy 274.376388 -54.791102) (xy 272.47843 -54.791102)
			(xy 272.475338 -54.812611) (xy 272.459983 -54.864906) (xy 272.437341 -54.914483) (xy 272.407875 -54.960333)
			(xy 272.372184 -55.001524) (xy 272.330993 -55.037215) (xy 272.285143 -55.066681) (xy 272.235566 -55.089323)
			(xy 272.183271 -55.104678) (xy 272.129323 -55.112434) (xy 272.074821 -55.112434) (xy 272.020873 -55.104678)
			(xy 271.968578 -55.089323) (xy 271.919001 -55.066681) (xy 271.873151 -55.037215) (xy 271.83196 -55.001524)
			(xy 271.796269 -54.960333) (xy 271.766803 -54.914483) (xy 271.744161 -54.864906) (xy 271.728806 -54.812611)
			(xy 271.72105 -54.758663) (xy 271.720564 -54.731412) (xy 263.212596 -54.731412) (xy 263.252378 -54.737129)
			(xy 263.304674 -54.752481) (xy 263.354252 -54.77512) (xy 263.400105 -54.804584) (xy 263.441297 -54.840273)
			(xy 263.476991 -54.881462) (xy 263.50646 -54.927311) (xy 263.529104 -54.976887) (xy 263.544462 -55.029181)
			(xy 263.552221 -55.083129) (xy 263.552686 -55.11038) (xy 263.552235 -55.137714) (xy 263.544422 -55.191822)
			(xy 263.528968 -55.244262) (xy 263.506189 -55.293959) (xy 263.476552 -55.339897) (xy 263.45896 -55.360824)
			(xy 263.458706 -55.361078) (xy 263.458452 -55.361332) (xy 263.452882 -55.36843) (xy 263.446627 -55.385338)
			(xy 263.44626 -55.394352) (xy 263.44626 -55.461408) (xy 263.4466 -55.470427) (xy 263.452858 -55.487344)
			(xy 263.458452 -55.494428) (xy 263.458706 -55.494682) (xy 263.45896 -55.494936) (xy 263.47654 -55.515874)
			(xy 263.506191 -55.561805) (xy 263.528979 -55.6115) (xy 263.544437 -55.66394) (xy 263.552247 -55.71805)
			(xy 263.552247 -55.722266) (xy 284.033974 -55.722266) (xy 284.038045 -55.666644) (xy 284.050171 -55.612207)
			(xy 284.070094 -55.560116) (xy 284.09739 -55.511481) (xy 284.131476 -55.467338) (xy 284.171625 -55.428629)
			(xy 284.216983 -55.396178) (xy 284.266583 -55.370677) (xy 284.319367 -55.35267) (xy 284.37421 -55.34254)
			(xy 284.429944 -55.340503) (xy 284.485381 -55.346603) (xy 284.539338 -55.360709) (xy 284.590667 -55.382521)
			(xy 284.638273 -55.411575) (xy 284.681141 -55.44725) (xy 284.718358 -55.488787) (xy 284.749131 -55.5353)
			(xy 284.772803 -55.585797) (xy 284.788871 -55.639204) (xy 284.796991 -55.69438) (xy 284.7975 -55.722266)
			(xy 284.796991 -55.750152) (xy 284.788871 -55.805328) (xy 284.772803 -55.858735) (xy 284.749131 -55.909232)
			(xy 284.718358 -55.955745) (xy 284.681141 -55.997282) (xy 284.638273 -56.032957) (xy 284.590667 -56.062011)
			(xy 284.539338 -56.083823) (xy 284.485381 -56.097929) (xy 284.429944 -56.104029) (xy 284.37421 -56.101992)
			(xy 284.319367 -56.091862) (xy 284.266583 -56.073855) (xy 284.216983 -56.048354) (xy 284.171625 -56.015903)
			(xy 284.131476 -55.977194) (xy 284.09739 -55.933051) (xy 284.070094 -55.884416) (xy 284.050171 -55.832325)
			(xy 284.038045 -55.777888) (xy 284.033974 -55.722266) (xy 263.552247 -55.722266) (xy 263.552249 -55.77272)
			(xy 263.544443 -55.826831) (xy 263.52899 -55.879272) (xy 263.506206 -55.928968) (xy 263.476558 -55.974901)
			(xy 263.45896 -55.995824) (xy 263.458706 -55.996078) (xy 263.458452 -55.996332) (xy 263.452882 -56.00343)
			(xy 263.446627 -56.020338) (xy 263.44626 -56.029352) (xy 263.44626 -56.096408) (xy 263.4466 -56.105427)
			(xy 263.452858 -56.122344) (xy 263.458452 -56.129428) (xy 263.458706 -56.129682) (xy 263.45896 -56.129936)
			(xy 263.47653 -56.15088) (xy 263.506173 -56.196811) (xy 263.528954 -56.246505) (xy 263.544407 -56.298941)
			(xy 263.552215 -56.353047) (xy 263.552686 -56.38038) (xy 263.5522 -56.407631) (xy 263.544444 -56.461579)
			(xy 263.529089 -56.513874) (xy 263.506447 -56.563451) (xy 263.476981 -56.609301) (xy 263.44129 -56.650492)
			(xy 263.400099 -56.686183) (xy 263.354249 -56.715649) (xy 263.304672 -56.738291) (xy 263.252377 -56.753646)
			(xy 263.198429 -56.761402) (xy 263.143927 -56.761402) (xy 263.089979 -56.753646) (xy 263.037684 -56.738291)
			(xy 262.988107 -56.715649) (xy 262.942257 -56.686183) (xy 262.901066 -56.650492) (xy 262.865375 -56.609301)
			(xy 262.835909 -56.563451) (xy 262.813267 -56.513874) (xy 262.797912 -56.461579) (xy 262.790156 -56.407631)
			(xy 262.78967 -56.38038) (xy 262.790142 -56.353046) (xy 262.797948 -56.298939) (xy 262.813396 -56.246499)
			(xy 262.836171 -56.196801) (xy 262.865805 -56.150863) (xy 262.883396 -56.129936) (xy 262.88365 -56.129682)
			(xy 262.883904 -56.129428) (xy 262.889485 -56.122338) (xy 262.895735 -56.105424) (xy 262.896096 -56.096408)
			(xy 262.896096 -56.029352) (xy 262.895715 -56.020338) (xy 262.889484 -56.00342) (xy 262.883904 -55.996332)
			(xy 262.88365 -55.996078) (xy 262.883396 -55.995824) (xy 262.865775 -55.974918) (xy 262.836121 -55.928983)
			(xy 262.813332 -55.879283) (xy 262.797875 -55.826838) (xy 262.790067 -55.772723) (xy 262.79007 -55.718047)
			(xy 262.797881 -55.663932) (xy 262.813342 -55.611488) (xy 262.836135 -55.56179) (xy 262.865793 -55.515858)
			(xy 262.883396 -55.494936) (xy 262.88365 -55.494682) (xy 262.883904 -55.494428) (xy 262.889485 -55.487338)
			(xy 262.895735 -55.470424) (xy 262.896096 -55.461408) (xy 262.896096 -55.394352) (xy 262.895715 -55.385338)
			(xy 262.889484 -55.36842) (xy 262.883904 -55.361332) (xy 262.88365 -55.361078) (xy 262.883396 -55.360824)
			(xy 262.872527 -55.348075) (xy 262.852815 -55.320984) (xy 262.844026 -55.306722) (xy 262.838438 -55.297578)
			(xy 262.82142 -55.285386) (xy 262.728456 -55.26532) (xy 262.707882 -55.269384) (xy 262.699246 -55.27548)
			(xy 262.67517 -55.29146) (xy 262.623243 -55.316808) (xy 262.568089 -55.334039) (xy 262.510967 -55.34276)
			(xy 262.482076 -55.343298) (xy 262.454825 -55.342831) (xy 262.400879 -55.335071) (xy 262.348585 -55.319713)
			(xy 262.29901 -55.29707) (xy 262.253161 -55.267603) (xy 262.211973 -55.23191) (xy 262.176283 -55.190719)
			(xy 262.146818 -55.144869) (xy 262.124178 -55.095292) (xy 262.108824 -55.042998) (xy 262.101068 -54.989051)
			(xy 259.892696 -54.989051) (xy 259.896109 -55.000394) (xy 259.904229 -55.05557) (xy 259.904738 -55.083456)
			(xy 259.904229 -55.111342) (xy 259.896109 -55.166518) (xy 259.880041 -55.219925) (xy 259.856369 -55.270422)
			(xy 259.825596 -55.316935) (xy 259.788379 -55.358472) (xy 259.745511 -55.394147) (xy 259.701756 -55.420851)
			(xy 260.424668 -55.420851) (xy 260.424668 -55.366349) (xy 260.432424 -55.312402) (xy 260.447778 -55.260108)
			(xy 260.470418 -55.210531) (xy 260.499883 -55.164681) (xy 260.535573 -55.12349) (xy 260.576761 -55.087797)
			(xy 260.62261 -55.05833) (xy 260.672185 -55.035687) (xy 260.724479 -55.020329) (xy 260.778425 -55.012569)
			(xy 260.805676 -55.012082) (xy 260.80593 -55.012082) (xy 260.832225 -55.012527) (xy 260.884314 -55.019776)
			(xy 260.934916 -55.034105) (xy 260.983072 -55.055243) (xy 261.027871 -55.08279) (xy 261.068466 -55.116225)
			(xy 261.0866 -55.135272) (xy 261.094176 -55.142708) (xy 261.113591 -55.151237) (xy 261.124192 -55.151782)
			(xy 261.19836 -55.151782) (xy 261.208996 -55.151402) (xy 261.22846 -55.142833) (xy 261.235952 -55.135272)
			(xy 261.254109 -55.116244) (xy 261.294683 -55.082783) (xy 261.339473 -55.055218) (xy 261.387628 -55.034073)
			(xy 261.438232 -55.019751) (xy 261.490326 -55.012522) (xy 261.516622 -55.012082) (xy 261.516876 -55.012082)
			(xy 261.544129 -55.012564) (xy 261.598081 -55.020318) (xy 261.650381 -55.035671) (xy 261.699963 -55.058312)
			(xy 261.745817 -55.087778) (xy 261.787012 -55.123471) (xy 261.822707 -55.164663) (xy 261.852177 -55.210516)
			(xy 261.87482 -55.260097) (xy 261.890177 -55.312395) (xy 261.897935 -55.366347) (xy 261.897935 -55.420853)
			(xy 261.890177 -55.474805) (xy 261.87482 -55.527103) (xy 261.852177 -55.576684) (xy 261.822707 -55.622537)
			(xy 261.787012 -55.663729) (xy 261.745817 -55.699422) (xy 261.699963 -55.728888) (xy 261.650381 -55.751529)
			(xy 261.598081 -55.766882) (xy 261.544129 -55.774636) (xy 261.516876 -55.775098) (xy 261.516622 -55.775098)
			(xy 261.490328 -55.774625) (xy 261.43824 -55.767383) (xy 261.387638 -55.75306) (xy 261.339482 -55.731927)
			(xy 261.294682 -55.704384) (xy 261.254087 -55.670953) (xy 261.235952 -55.651908) (xy 261.228396 -55.644448)
			(xy 261.208966 -55.635933) (xy 261.19836 -55.635398) (xy 261.124192 -55.635398) (xy 261.113561 -55.635812)
			(xy 261.094096 -55.644358) (xy 261.0866 -55.651908) (xy 261.068482 -55.670974) (xy 261.027898 -55.704429)
			(xy 260.983099 -55.731987) (xy 260.934937 -55.753125) (xy 260.884326 -55.76744) (xy 260.832228 -55.774661)
			(xy 260.80593 -55.775098) (xy 260.805676 -55.775098) (xy 260.778425 -55.774631) (xy 260.724479 -55.766871)
			(xy 260.672185 -55.751513) (xy 260.62261 -55.72887) (xy 260.576761 -55.699403) (xy 260.535573 -55.66371)
			(xy 260.499883 -55.622519) (xy 260.470418 -55.576669) (xy 260.447778 -55.527092) (xy 260.432424 -55.474798)
			(xy 260.424668 -55.420851) (xy 259.701756 -55.420851) (xy 259.697905 -55.423201) (xy 259.646576 -55.445013)
			(xy 259.592619 -55.459119) (xy 259.537182 -55.465219) (xy 259.481448 -55.463182) (xy 259.426605 -55.453052)
			(xy 259.373821 -55.435045) (xy 259.324221 -55.409544) (xy 259.278863 -55.377093) (xy 259.238714 -55.338384)
			(xy 259.204628 -55.294241) (xy 259.177332 -55.245606) (xy 259.157409 -55.193515) (xy 259.145283 -55.139078)
			(xy 259.141212 -55.083456) (xy 252.870364 -55.083456) (xy 252.835601 -55.105797) (xy 252.786024 -55.128439)
			(xy 252.733729 -55.143794) (xy 252.679781 -55.15155) (xy 252.625279 -55.15155) (xy 252.571331 -55.143794)
			(xy 252.519036 -55.128439) (xy 252.469459 -55.105797) (xy 252.423609 -55.076331) (xy 252.382418 -55.04064)
			(xy 252.346727 -54.999449) (xy 252.317261 -54.953599) (xy 252.294619 -54.904022) (xy 252.279264 -54.851727)
			(xy 252.271508 -54.797779) (xy 252.271022 -54.770528) (xy 249.139103 -54.770528) (xy 249.139456 -54.791102)
			(xy 249.13897 -54.818353) (xy 249.131214 -54.872301) (xy 249.115859 -54.924596) (xy 249.093217 -54.974173)
			(xy 249.063751 -55.020023) (xy 249.02806 -55.061214) (xy 248.986869 -55.096905) (xy 248.941019 -55.126371)
			(xy 248.891442 -55.149013) (xy 248.839147 -55.164368) (xy 248.785199 -55.172124) (xy 248.730697 -55.172124)
			(xy 248.676749 -55.164368) (xy 248.624454 -55.149013) (xy 248.574877 -55.126371) (xy 248.529027 -55.096905)
			(xy 248.487836 -55.061214) (xy 248.452145 -55.020023) (xy 248.422679 -54.974173) (xy 248.400037 -54.924596)
			(xy 248.384682 -54.872301) (xy 248.376926 -54.818353) (xy 248.37644 -54.791102) (xy 246.478482 -54.791102)
			(xy 246.47539 -54.812611) (xy 246.460035 -54.864906) (xy 246.437393 -54.914483) (xy 246.407927 -54.960333)
			(xy 246.372236 -55.001524) (xy 246.331045 -55.037215) (xy 246.285195 -55.066681) (xy 246.235618 -55.089323)
			(xy 246.183323 -55.104678) (xy 246.129375 -55.112434) (xy 246.074873 -55.112434) (xy 246.020925 -55.104678)
			(xy 245.96863 -55.089323) (xy 245.919053 -55.066681) (xy 245.873203 -55.037215) (xy 245.832012 -55.001524)
			(xy 245.796321 -54.960333) (xy 245.766855 -54.914483) (xy 245.744213 -54.864906) (xy 245.728858 -54.812611)
			(xy 245.721102 -54.758663) (xy 245.720616 -54.731412) (xy 241.720641 -54.731412) (xy 241.725957 -54.767534)
			(xy 241.726466 -54.79542) (xy 241.725957 -54.823306) (xy 241.717837 -54.878482) (xy 241.701769 -54.931889)
			(xy 241.678097 -54.982386) (xy 241.647324 -55.028899) (xy 241.610107 -55.070436) (xy 241.567239 -55.106111)
			(xy 241.519633 -55.135165) (xy 241.468304 -55.156977) (xy 241.414347 -55.171083) (xy 241.35891 -55.177183)
			(xy 241.303176 -55.175146) (xy 241.248333 -55.165016) (xy 241.195549 -55.147009) (xy 241.145949 -55.121508)
			(xy 241.100591 -55.089057) (xy 241.060442 -55.050348) (xy 241.026356 -55.006205) (xy 240.99906 -54.95757)
			(xy 240.979137 -54.905479) (xy 240.967011 -54.851042) (xy 240.96294 -54.79542) (xy 239.69496 -54.79542)
			(xy 239.694465 -54.822544) (xy 239.686345 -54.87772) (xy 239.670277 -54.931127) (xy 239.646605 -54.981624)
			(xy 239.615832 -55.028137) (xy 239.578615 -55.069674) (xy 239.535747 -55.105349) (xy 239.488141 -55.134403)
			(xy 239.436812 -55.156215) (xy 239.382855 -55.170321) (xy 239.327418 -55.176421) (xy 239.271684 -55.174384)
			(xy 239.216841 -55.164254) (xy 239.164057 -55.146247) (xy 239.114457 -55.120746) (xy 239.069099 -55.088295)
			(xy 239.02895 -55.049586) (xy 238.994864 -55.005443) (xy 238.967568 -54.956808) (xy 238.947645 -54.904717)
			(xy 238.935519 -54.85028) (xy 238.931448 -54.794658) (xy 221.671818 -54.794658) (xy 221.688379 -54.80844)
			(xy 221.725596 -54.849977) (xy 221.756369 -54.89649) (xy 221.780041 -54.946987) (xy 221.796109 -55.000394)
			(xy 221.804229 -55.05557) (xy 221.804738 -55.083456) (xy 221.804229 -55.111342) (xy 221.796109 -55.166518)
			(xy 221.780041 -55.219925) (xy 221.756369 -55.270422) (xy 221.725596 -55.316935) (xy 221.688379 -55.358472)
			(xy 221.645511 -55.394147) (xy 221.597905 -55.423201) (xy 221.546576 -55.445013) (xy 221.492619 -55.459119)
			(xy 221.437182 -55.465219) (xy 221.381448 -55.463182) (xy 221.326605 -55.453052) (xy 221.273821 -55.435045)
			(xy 221.224221 -55.409544) (xy 221.178863 -55.377093) (xy 221.138714 -55.338384) (xy 221.104628 -55.294241)
			(xy 221.077332 -55.245606) (xy 221.057409 -55.193515) (xy 221.045283 -55.139078) (xy 221.041212 -55.083456)
			(xy 214.770364 -55.083456) (xy 214.735601 -55.105797) (xy 214.686024 -55.128439) (xy 214.633729 -55.143794)
			(xy 214.579781 -55.15155) (xy 214.525279 -55.15155) (xy 214.471331 -55.143794) (xy 214.419036 -55.128439)
			(xy 214.369459 -55.105797) (xy 214.323609 -55.076331) (xy 214.282418 -55.04064) (xy 214.246727 -54.999449)
			(xy 214.217261 -54.953599) (xy 214.194619 -54.904022) (xy 214.179264 -54.851727) (xy 214.171508 -54.797779)
			(xy 214.171022 -54.770528) (xy 211.039103 -54.770528) (xy 211.039456 -54.791102) (xy 211.03897 -54.818353)
			(xy 211.031214 -54.872301) (xy 211.015859 -54.924596) (xy 210.993217 -54.974173) (xy 210.963751 -55.020023)
			(xy 210.92806 -55.061214) (xy 210.886869 -55.096905) (xy 210.841019 -55.126371) (xy 210.791442 -55.149013)
			(xy 210.739147 -55.164368) (xy 210.685199 -55.172124) (xy 210.630697 -55.172124) (xy 210.576749 -55.164368)
			(xy 210.524454 -55.149013) (xy 210.474877 -55.126371) (xy 210.429027 -55.096905) (xy 210.387836 -55.061214)
			(xy 210.352145 -55.020023) (xy 210.322679 -54.974173) (xy 210.300037 -54.924596) (xy 210.284682 -54.872301)
			(xy 210.276926 -54.818353) (xy 210.27644 -54.791102) (xy 208.378482 -54.791102) (xy 208.37539 -54.812611)
			(xy 208.360035 -54.864906) (xy 208.337393 -54.914483) (xy 208.307927 -54.960333) (xy 208.272236 -55.001524)
			(xy 208.231045 -55.037215) (xy 208.185195 -55.066681) (xy 208.135618 -55.089323) (xy 208.083323 -55.104678)
			(xy 208.029375 -55.112434) (xy 207.974873 -55.112434) (xy 207.920925 -55.104678) (xy 207.86863 -55.089323)
			(xy 207.819053 -55.066681) (xy 207.773203 -55.037215) (xy 207.732012 -55.001524) (xy 207.696321 -54.960333)
			(xy 207.666855 -54.914483) (xy 207.644213 -54.864906) (xy 207.628858 -54.812611) (xy 207.621102 -54.758663)
			(xy 207.620616 -54.731412) (xy 199.112816 -54.731412) (xy 199.152428 -54.73711) (xy 199.204722 -54.752468)
			(xy 199.254298 -54.775111) (xy 199.300147 -54.804579) (xy 199.341336 -54.840271) (xy 199.377027 -54.881461)
			(xy 199.406494 -54.927311) (xy 199.429136 -54.976888) (xy 199.444492 -55.029182) (xy 199.452251 -55.083129)
			(xy 199.452738 -55.11038) (xy 199.452299 -55.137715) (xy 199.444485 -55.191824) (xy 199.429029 -55.244264)
			(xy 199.406247 -55.293961) (xy 199.376606 -55.339898) (xy 199.359012 -55.360824) (xy 199.358758 -55.361078)
			(xy 199.358504 -55.361332) (xy 199.35294 -55.368434) (xy 199.34668 -55.385339) (xy 199.346312 -55.394352)
			(xy 199.346312 -55.461408) (xy 199.346663 -55.470426) (xy 199.352914 -55.487343) (xy 199.358504 -55.494428)
			(xy 199.358758 -55.494682) (xy 199.359012 -55.494936) (xy 199.376594 -55.515874) (xy 199.406249 -55.561803)
			(xy 199.42904 -55.611498) (xy 199.444499 -55.663938) (xy 199.45231 -55.718049) (xy 199.45231 -55.722266)
			(xy 219.934026 -55.722266) (xy 219.938097 -55.666644) (xy 219.950223 -55.612207) (xy 219.970146 -55.560116)
			(xy 219.997442 -55.511481) (xy 220.031528 -55.467338) (xy 220.071677 -55.428629) (xy 220.117035 -55.396178)
			(xy 220.166635 -55.370677) (xy 220.219419 -55.35267) (xy 220.274262 -55.34254) (xy 220.329996 -55.340503)
			(xy 220.385433 -55.346603) (xy 220.43939 -55.360709) (xy 220.490719 -55.382521) (xy 220.538325 -55.411575)
			(xy 220.581193 -55.44725) (xy 220.61841 -55.488787) (xy 220.649183 -55.5353) (xy 220.672855 -55.585797)
			(xy 220.688923 -55.639204) (xy 220.697043 -55.69438) (xy 220.697552 -55.722266) (xy 220.697043 -55.750152)
			(xy 220.688923 -55.805328) (xy 220.672855 -55.858735) (xy 220.649183 -55.909232) (xy 220.61841 -55.955745)
			(xy 220.581193 -55.997282) (xy 220.538325 -56.032957) (xy 220.490719 -56.062011) (xy 220.43939 -56.083823)
			(xy 220.385433 -56.097929) (xy 220.329996 -56.104029) (xy 220.274262 -56.101992) (xy 220.219419 -56.091862)
			(xy 220.166635 -56.073855) (xy 220.117035 -56.048354) (xy 220.071677 -56.015903) (xy 220.031528 -55.977194)
			(xy 219.997442 -55.933051) (xy 219.970146 -55.884416) (xy 219.950223 -55.832325) (xy 219.938097 -55.777888)
			(xy 219.934026 -55.722266) (xy 199.45231 -55.722266) (xy 199.452312 -55.772721) (xy 199.444506 -55.826832)
			(xy 199.42905 -55.879274) (xy 199.406263 -55.92897) (xy 199.376612 -55.974902) (xy 199.359012 -55.995824)
			(xy 199.358758 -55.996078) (xy 199.358504 -55.996332) (xy 199.35294 -56.003434) (xy 199.34668 -56.020339)
			(xy 199.346312 -56.029352) (xy 199.346312 -56.096408) (xy 199.346663 -56.105426) (xy 199.352914 -56.122343)
			(xy 199.358504 -56.129428) (xy 199.358758 -56.129682) (xy 199.359012 -56.129936) (xy 199.37659 -56.150873)
			(xy 199.40623 -56.196807) (xy 199.429009 -56.246502) (xy 199.44446 -56.29894) (xy 199.452267 -56.353047)
			(xy 199.452738 -56.38038) (xy 199.452252 -56.407631) (xy 199.444496 -56.461579) (xy 199.429141 -56.513874)
			(xy 199.406499 -56.563451) (xy 199.377033 -56.609301) (xy 199.341342 -56.650492) (xy 199.300151 -56.686183)
			(xy 199.254301 -56.715649) (xy 199.204724 -56.738291) (xy 199.152429 -56.753646) (xy 199.098481 -56.761402)
			(xy 199.043979 -56.761402) (xy 198.990031 -56.753646) (xy 198.937736 -56.738291) (xy 198.888159 -56.715649)
			(xy 198.842309 -56.686183) (xy 198.801118 -56.650492) (xy 198.765427 -56.609301) (xy 198.735961 -56.563451)
			(xy 198.713319 -56.513874) (xy 198.697964 -56.461579) (xy 198.690208 -56.407631) (xy 198.689722 -56.38038)
			(xy 198.690206 -56.353047) (xy 198.69801 -56.29894) (xy 198.713457 -56.246501) (xy 198.736228 -56.196803)
			(xy 198.765859 -56.150864) (xy 198.783448 -56.129936) (xy 198.783702 -56.129682) (xy 198.783956 -56.129428)
			(xy 198.789544 -56.122342) (xy 198.795788 -56.105425) (xy 198.796148 -56.096408) (xy 198.796148 -56.029352)
			(xy 198.795777 -56.020336) (xy 198.789541 -56.003419) (xy 198.783956 -55.996332) (xy 198.783702 -55.996078)
			(xy 198.783448 -55.995824) (xy 198.765829 -55.974917) (xy 198.736178 -55.928981) (xy 198.713392 -55.879281)
			(xy 198.697937 -55.826836) (xy 198.690131 -55.772722) (xy 198.690133 -55.718048) (xy 198.697944 -55.663934)
			(xy 198.713403 -55.611491) (xy 198.736193 -55.561792) (xy 198.765847 -55.515859) (xy 198.783448 -55.494936)
			(xy 198.783702 -55.494682) (xy 198.783956 -55.494428) (xy 198.789544 -55.487342) (xy 198.795788 -55.470425)
			(xy 198.796148 -55.461408) (xy 198.796148 -55.394352) (xy 198.795777 -55.385336) (xy 198.789541 -55.368419)
			(xy 198.783956 -55.361332) (xy 198.783702 -55.361078) (xy 198.783448 -55.360824) (xy 198.772577 -55.348078)
			(xy 198.752866 -55.320985) (xy 198.744078 -55.306722) (xy 198.73849 -55.297578) (xy 198.721472 -55.285386)
			(xy 198.628508 -55.26532) (xy 198.607934 -55.269384) (xy 198.599298 -55.27548) (xy 198.575235 -55.291481)
			(xy 198.523303 -55.316824) (xy 198.468145 -55.334049) (xy 198.411021 -55.342764) (xy 198.382128 -55.343298)
			(xy 198.354873 -55.342857) (xy 198.300918 -55.335103) (xy 198.248615 -55.319749) (xy 198.19903 -55.297108)
			(xy 198.153172 -55.267639) (xy 198.111975 -55.231945) (xy 198.076277 -55.19075) (xy 198.046806 -55.144895)
			(xy 198.024161 -55.095311) (xy 198.008803 -55.04301) (xy 198.001045 -54.989055) (xy 195.79275 -54.989055)
			(xy 195.796161 -55.000394) (xy 195.804281 -55.05557) (xy 195.80479 -55.083456) (xy 195.804281 -55.111342)
			(xy 195.796161 -55.166518) (xy 195.780093 -55.219925) (xy 195.756421 -55.270422) (xy 195.725648 -55.316935)
			(xy 195.688431 -55.358472) (xy 195.645563 -55.394147) (xy 195.601801 -55.420855) (xy 196.324645 -55.420855)
			(xy 196.324645 -55.366345) (xy 196.332403 -55.31239) (xy 196.347761 -55.260089) (xy 196.370406 -55.210505)
			(xy 196.399877 -55.16465) (xy 196.435575 -55.123455) (xy 196.476772 -55.087761) (xy 196.52263 -55.058292)
			(xy 196.572215 -55.035651) (xy 196.624518 -55.020297) (xy 196.678473 -55.012543) (xy 196.705728 -55.012082)
			(xy 196.705982 -55.012082) (xy 196.732276 -55.012558) (xy 196.784364 -55.019801) (xy 196.834965 -55.034124)
			(xy 196.883121 -55.055256) (xy 196.927921 -55.082798) (xy 196.968517 -55.116227) (xy 196.986652 -55.135272)
			(xy 196.994209 -55.142731) (xy 197.013638 -55.151247) (xy 197.024244 -55.151782) (xy 197.098412 -55.151782)
			(xy 197.109045 -55.151376) (xy 197.128509 -55.142825) (xy 197.136004 -55.135272) (xy 197.154136 -55.116219)
			(xy 197.194715 -55.08276) (xy 197.239511 -55.055198) (xy 197.28767 -55.034058) (xy 197.338279 -55.019741)
			(xy 197.390376 -55.012519) (xy 197.416674 -55.012082) (xy 197.416928 -55.012082) (xy 197.444177 -55.01259)
			(xy 197.49812 -55.02035) (xy 197.55041 -55.035707) (xy 197.599983 -55.058349) (xy 197.645828 -55.087815)
			(xy 197.687014 -55.123506) (xy 197.722702 -55.164694) (xy 197.752164 -55.210542) (xy 197.774803 -55.260116)
			(xy 197.790156 -55.312407) (xy 197.797912 -55.366351) (xy 197.797912 -55.420849) (xy 197.790156 -55.474793)
			(xy 197.774803 -55.527084) (xy 197.752164 -55.576658) (xy 197.722702 -55.622506) (xy 197.687014 -55.663694)
			(xy 197.645828 -55.699385) (xy 197.599983 -55.728851) (xy 197.55041 -55.751493) (xy 197.49812 -55.76685)
			(xy 197.444177 -55.77461) (xy 197.416928 -55.775098) (xy 197.416674 -55.775098) (xy 197.390379 -55.774657)
			(xy 197.338289 -55.767408) (xy 197.287687 -55.753079) (xy 197.239531 -55.73194) (xy 197.194732 -55.704392)
			(xy 197.154138 -55.670956) (xy 197.136004 -55.651908) (xy 197.128429 -55.644471) (xy 197.109014 -55.635943)
			(xy 197.098412 -55.635398) (xy 197.024244 -55.635398) (xy 197.01361 -55.635786) (xy 196.994145 -55.64435)
			(xy 196.986652 -55.651908) (xy 196.968558 -55.670998) (xy 196.927968 -55.704451) (xy 196.883164 -55.732005)
			(xy 196.834998 -55.753139) (xy 196.784383 -55.767449) (xy 196.732282 -55.774664) (xy 196.705982 -55.775098)
			(xy 196.705728 -55.775098) (xy 196.678473 -55.774657) (xy 196.624518 -55.766903) (xy 196.572215 -55.751549)
			(xy 196.52263 -55.728908) (xy 196.476772 -55.699439) (xy 196.435575 -55.663745) (xy 196.399877 -55.62255)
			(xy 196.370406 -55.576695) (xy 196.347761 -55.527111) (xy 196.332403 -55.47481) (xy 196.324645 -55.420855)
			(xy 195.601801 -55.420855) (xy 195.597957 -55.423201) (xy 195.546628 -55.445013) (xy 195.492671 -55.459119)
			(xy 195.437234 -55.465219) (xy 195.3815 -55.463182) (xy 195.326657 -55.453052) (xy 195.273873 -55.435045)
			(xy 195.224273 -55.409544) (xy 195.178915 -55.377093) (xy 195.138766 -55.338384) (xy 195.10468 -55.294241)
			(xy 195.077384 -55.245606) (xy 195.057461 -55.193515) (xy 195.045335 -55.139078) (xy 195.041264 -55.083456)
			(xy 188.770416 -55.083456) (xy 188.735653 -55.105797) (xy 188.686076 -55.128439) (xy 188.633781 -55.143794)
			(xy 188.579833 -55.15155) (xy 188.525331 -55.15155) (xy 188.471383 -55.143794) (xy 188.419088 -55.128439)
			(xy 188.369511 -55.105797) (xy 188.323661 -55.076331) (xy 188.28247 -55.04064) (xy 188.246779 -54.999449)
			(xy 188.217313 -54.953599) (xy 188.194671 -54.904022) (xy 188.179316 -54.851727) (xy 188.17156 -54.797779)
			(xy 188.171074 -54.770528) (xy 185.039155 -54.770528) (xy 185.039508 -54.791102) (xy 185.039022 -54.818353)
			(xy 185.031266 -54.872301) (xy 185.015911 -54.924596) (xy 184.993269 -54.974173) (xy 184.963803 -55.020023)
			(xy 184.928112 -55.061214) (xy 184.886921 -55.096905) (xy 184.841071 -55.126371) (xy 184.791494 -55.149013)
			(xy 184.739199 -55.164368) (xy 184.685251 -55.172124) (xy 184.630749 -55.172124) (xy 184.576801 -55.164368)
			(xy 184.524506 -55.149013) (xy 184.474929 -55.126371) (xy 184.429079 -55.096905) (xy 184.387888 -55.061214)
			(xy 184.352197 -55.020023) (xy 184.322731 -54.974173) (xy 184.300089 -54.924596) (xy 184.284734 -54.872301)
			(xy 184.276978 -54.818353) (xy 184.276492 -54.791102) (xy 182.378534 -54.791102) (xy 182.375442 -54.812611)
			(xy 182.360087 -54.864906) (xy 182.337445 -54.914483) (xy 182.307979 -54.960333) (xy 182.272288 -55.001524)
			(xy 182.231097 -55.037215) (xy 182.185247 -55.066681) (xy 182.13567 -55.089323) (xy 182.083375 -55.104678)
			(xy 182.029427 -55.112434) (xy 181.974925 -55.112434) (xy 181.920977 -55.104678) (xy 181.868682 -55.089323)
			(xy 181.819105 -55.066681) (xy 181.773255 -55.037215) (xy 181.732064 -55.001524) (xy 181.696373 -54.960333)
			(xy 181.666907 -54.914483) (xy 181.644265 -54.864906) (xy 181.62891 -54.812611) (xy 181.621154 -54.758663)
			(xy 181.620668 -54.731412) (xy 173.112566 -54.731412) (xy 173.152477 -54.737148) (xy 173.20477 -54.7525)
			(xy 173.254346 -54.775138) (xy 173.300195 -54.8046) (xy 173.341385 -54.840288) (xy 173.377077 -54.881474)
			(xy 173.406544 -54.927321) (xy 173.429186 -54.976894) (xy 173.444543 -55.029186) (xy 173.452302 -55.08313)
			(xy 173.45279 -55.11038) (xy 173.452338 -55.137714) (xy 173.444526 -55.191822) (xy 173.429072 -55.244262)
			(xy 173.406293 -55.293959) (xy 173.376655 -55.339897) (xy 173.359064 -55.360824) (xy 173.35881 -55.361078)
			(xy 173.358556 -55.361332) (xy 173.352986 -55.36843) (xy 173.346731 -55.385338) (xy 173.346364 -55.394352)
			(xy 173.346364 -55.461408) (xy 173.346725 -55.470424) (xy 173.35297 -55.487341) (xy 173.358556 -55.494428)
			(xy 173.35881 -55.494682) (xy 173.359064 -55.494936) (xy 173.376643 -55.515875) (xy 173.406295 -55.561806)
			(xy 173.429083 -55.6115) (xy 173.44454 -55.66394) (xy 173.45235 -55.71805) (xy 173.45235 -55.722266)
			(xy 193.934078 -55.722266) (xy 193.938149 -55.666644) (xy 193.950275 -55.612207) (xy 193.970198 -55.560116)
			(xy 193.997494 -55.511481) (xy 194.03158 -55.467338) (xy 194.071729 -55.428629) (xy 194.117087 -55.396178)
			(xy 194.166687 -55.370677) (xy 194.219471 -55.35267) (xy 194.274314 -55.34254) (xy 194.330048 -55.340503)
			(xy 194.385485 -55.346603) (xy 194.439442 -55.360709) (xy 194.490771 -55.382521) (xy 194.538377 -55.411575)
			(xy 194.581245 -55.44725) (xy 194.618462 -55.488787) (xy 194.649235 -55.5353) (xy 194.672907 -55.585797)
			(xy 194.688975 -55.639204) (xy 194.697095 -55.69438) (xy 194.697604 -55.722266) (xy 194.697095 -55.750152)
			(xy 194.688975 -55.805328) (xy 194.672907 -55.858735) (xy 194.649235 -55.909232) (xy 194.618462 -55.955745)
			(xy 194.581245 -55.997282) (xy 194.538377 -56.032957) (xy 194.490771 -56.062011) (xy 194.439442 -56.083823)
			(xy 194.385485 -56.097929) (xy 194.330048 -56.104029) (xy 194.274314 -56.101992) (xy 194.219471 -56.091862)
			(xy 194.166687 -56.073855) (xy 194.117087 -56.048354) (xy 194.071729 -56.015903) (xy 194.03158 -55.977194)
			(xy 193.997494 -55.933051) (xy 193.970198 -55.884416) (xy 193.950275 -55.832325) (xy 193.938149 -55.777888)
			(xy 193.934078 -55.722266) (xy 173.45235 -55.722266) (xy 173.452352 -55.77272) (xy 173.444546 -55.82683)
			(xy 173.429093 -55.879271) (xy 173.406309 -55.928968) (xy 173.376662 -55.974901) (xy 173.359064 -55.995824)
			(xy 173.35881 -55.996078) (xy 173.358556 -55.996332) (xy 173.352986 -56.00343) (xy 173.346731 -56.020338)
			(xy 173.346364 -56.029352) (xy 173.346364 -56.096408) (xy 173.346725 -56.105424) (xy 173.35297 -56.122341)
			(xy 173.358556 -56.129428) (xy 173.35881 -56.129682) (xy 173.359064 -56.129936) (xy 173.376634 -56.15088)
			(xy 173.406277 -56.196811) (xy 173.429058 -56.246504) (xy 173.444511 -56.298941) (xy 173.452319 -56.353047)
			(xy 173.45279 -56.38038) (xy 173.452304 -56.407631) (xy 173.444548 -56.461579) (xy 173.429193 -56.513874)
			(xy 173.406551 -56.563451) (xy 173.377085 -56.609301) (xy 173.341394 -56.650492) (xy 173.300203 -56.686183)
			(xy 173.254353 -56.715649) (xy 173.204776 -56.738291) (xy 173.152481 -56.753646) (xy 173.098533 -56.761402)
			(xy 173.044031 -56.761402) (xy 172.990083 -56.753646) (xy 172.937788 -56.738291) (xy 172.888211 -56.715649)
			(xy 172.842361 -56.686183) (xy 172.80117 -56.650492) (xy 172.765479 -56.609301) (xy 172.736013 -56.563451)
			(xy 172.713371 -56.513874) (xy 172.698016 -56.461579) (xy 172.69026 -56.407631) (xy 172.689774 -56.38038)
			(xy 172.690245 -56.353046) (xy 172.698051 -56.298938) (xy 172.713499 -56.246499) (xy 172.736274 -56.196801)
			(xy 172.765909 -56.150863) (xy 172.7835 -56.129936) (xy 172.783754 -56.129682) (xy 172.784008 -56.129428)
			(xy 172.78959 -56.122338) (xy 172.795839 -56.105424) (xy 172.7962 -56.096408) (xy 172.7962 -56.029352)
			(xy 172.795818 -56.020338) (xy 172.789588 -56.003421) (xy 172.784008 -55.996332) (xy 172.783754 -55.996078)
			(xy 172.7835 -55.995824) (xy 172.765879 -55.974918) (xy 172.736224 -55.928983) (xy 172.713435 -55.879283)
			(xy 172.697978 -55.826838) (xy 172.69017 -55.772723) (xy 172.690173 -55.718047) (xy 172.697984 -55.663932)
			(xy 172.713445 -55.611488) (xy 172.736239 -55.56179) (xy 172.765897 -55.515858) (xy 172.7835 -55.494936)
			(xy 172.783754 -55.494682) (xy 172.784008 -55.494428) (xy 172.78959 -55.487338) (xy 172.795839 -55.470424)
			(xy 172.7962 -55.461408) (xy 172.7962 -55.394352) (xy 172.795818 -55.385338) (xy 172.789588 -55.368421)
			(xy 172.784008 -55.361332) (xy 172.783754 -55.361078) (xy 172.7835 -55.360824) (xy 172.772632 -55.348075)
			(xy 172.752919 -55.320984) (xy 172.74413 -55.306722) (xy 172.738542 -55.297578) (xy 172.721524 -55.285386)
			(xy 172.62856 -55.26532) (xy 172.607986 -55.269384) (xy 172.59935 -55.27548) (xy 172.575273 -55.291459)
			(xy 172.523346 -55.316807) (xy 172.468192 -55.334038) (xy 172.411071 -55.34276) (xy 172.38218 -55.343298)
			(xy 172.354929 -55.342831) (xy 172.300982 -55.335072) (xy 172.248688 -55.319715) (xy 172.199112 -55.297072)
			(xy 172.153263 -55.267604) (xy 172.112074 -55.231912) (xy 172.076384 -55.190721) (xy 172.046919 -55.14487)
			(xy 172.024278 -55.095293) (xy 172.008924 -55.042998) (xy 172.001168 -54.989051) (xy 169.7928 -54.989051)
			(xy 169.796213 -55.000394) (xy 169.804333 -55.05557) (xy 169.804842 -55.083456) (xy 169.804333 -55.111342)
			(xy 169.796213 -55.166518) (xy 169.780145 -55.219925) (xy 169.756473 -55.270422) (xy 169.7257 -55.316935)
			(xy 169.688483 -55.358472) (xy 169.645615 -55.394147) (xy 169.60186 -55.420851) (xy 170.324768 -55.420851)
			(xy 170.324768 -55.366349) (xy 170.332524 -55.312402) (xy 170.347878 -55.260107) (xy 170.370519 -55.21053)
			(xy 170.399984 -55.164679) (xy 170.435674 -55.123488) (xy 170.476863 -55.087796) (xy 170.522712 -55.058328)
			(xy 170.572288 -55.035685) (xy 170.624582 -55.020328) (xy 170.678529 -55.012569) (xy 170.70578 -55.012082)
			(xy 170.706034 -55.012082) (xy 170.732329 -55.012524) (xy 170.784419 -55.019773) (xy 170.83502 -55.034103)
			(xy 170.883176 -55.055242) (xy 170.927975 -55.082789) (xy 170.96857 -55.116225) (xy 170.986704 -55.135272)
			(xy 170.994279 -55.14271) (xy 171.013694 -55.151238) (xy 171.024296 -55.151782) (xy 171.098464 -55.151782)
			(xy 171.1091 -55.151404) (xy 171.128564 -55.142833) (xy 171.136056 -55.135272) (xy 171.154211 -55.116242)
			(xy 171.194786 -55.082781) (xy 171.239576 -55.055216) (xy 171.287731 -55.034072) (xy 171.338336 -55.01975)
			(xy 171.39043 -55.012522) (xy 171.416726 -55.012082) (xy 171.41698 -55.012082) (xy 171.444233 -55.012564)
			(xy 171.498185 -55.020318) (xy 171.550484 -55.035672) (xy 171.600065 -55.058313) (xy 171.645919 -55.08778)
			(xy 171.687113 -55.123472) (xy 171.722808 -55.164665) (xy 171.752277 -55.210517) (xy 171.774921 -55.260098)
			(xy 171.790277 -55.312396) (xy 171.798035 -55.366347) (xy 171.798035 -55.420853) (xy 171.790277 -55.474804)
			(xy 171.774921 -55.527102) (xy 171.752277 -55.576683) (xy 171.722808 -55.622535) (xy 171.687113 -55.663728)
			(xy 171.645919 -55.69942) (xy 171.600065 -55.728887) (xy 171.550484 -55.751528) (xy 171.498185 -55.766882)
			(xy 171.444233 -55.774636) (xy 171.41698 -55.775098) (xy 171.416726 -55.775098) (xy 171.390432 -55.774623)
			(xy 171.338344 -55.767381) (xy 171.287743 -55.753058) (xy 171.239586 -55.731926) (xy 171.194786 -55.704384)
			(xy 171.154191 -55.670953) (xy 171.136056 -55.651908) (xy 171.128499 -55.64445) (xy 171.10907 -55.635934)
			(xy 171.098464 -55.635398) (xy 171.024296 -55.635398) (xy 171.013665 -55.635814) (xy 170.9942 -55.644359)
			(xy 170.986704 -55.651908) (xy 170.968584 -55.670972) (xy 170.928 -55.704428) (xy 170.883202 -55.731986)
			(xy 170.83504 -55.753123) (xy 170.78443 -55.767439) (xy 170.732332 -55.774661) (xy 170.706034 -55.775098)
			(xy 170.70578 -55.775098) (xy 170.678529 -55.774631) (xy 170.624582 -55.766872) (xy 170.572288 -55.751515)
			(xy 170.522712 -55.728872) (xy 170.476863 -55.699404) (xy 170.435674 -55.663712) (xy 170.399984 -55.622521)
			(xy 170.370519 -55.57667) (xy 170.347878 -55.527093) (xy 170.332524 -55.474798) (xy 170.324768 -55.420851)
			(xy 169.60186 -55.420851) (xy 169.598009 -55.423201) (xy 169.54668 -55.445013) (xy 169.492723 -55.459119)
			(xy 169.437286 -55.465219) (xy 169.381552 -55.463182) (xy 169.326709 -55.453052) (xy 169.273925 -55.435045)
			(xy 169.224325 -55.409544) (xy 169.178967 -55.377093) (xy 169.138818 -55.338384) (xy 169.104732 -55.294241)
			(xy 169.077436 -55.245606) (xy 169.057513 -55.193515) (xy 169.045387 -55.139078) (xy 169.041316 -55.083456)
			(xy 162.770468 -55.083456) (xy 162.735705 -55.105797) (xy 162.686128 -55.128439) (xy 162.633833 -55.143794)
			(xy 162.579885 -55.15155) (xy 162.525383 -55.15155) (xy 162.471435 -55.143794) (xy 162.41914 -55.128439)
			(xy 162.369563 -55.105797) (xy 162.323713 -55.076331) (xy 162.282522 -55.04064) (xy 162.246831 -54.999449)
			(xy 162.217365 -54.953599) (xy 162.194723 -54.904022) (xy 162.179368 -54.851727) (xy 162.171612 -54.797779)
			(xy 162.171126 -54.770528) (xy 159.039207 -54.770528) (xy 159.03956 -54.791102) (xy 159.039074 -54.818353)
			(xy 159.031318 -54.872301) (xy 159.015963 -54.924596) (xy 158.993321 -54.974173) (xy 158.963855 -55.020023)
			(xy 158.928164 -55.061214) (xy 158.886973 -55.096905) (xy 158.841123 -55.126371) (xy 158.791546 -55.149013)
			(xy 158.739251 -55.164368) (xy 158.685303 -55.172124) (xy 158.630801 -55.172124) (xy 158.576853 -55.164368)
			(xy 158.524558 -55.149013) (xy 158.474981 -55.126371) (xy 158.429131 -55.096905) (xy 158.38794 -55.061214)
			(xy 158.352249 -55.020023) (xy 158.322783 -54.974173) (xy 158.300141 -54.924596) (xy 158.284786 -54.872301)
			(xy 158.27703 -54.818353) (xy 158.276544 -54.791102) (xy 156.378586 -54.791102) (xy 156.375494 -54.812611)
			(xy 156.360139 -54.864906) (xy 156.337497 -54.914483) (xy 156.308031 -54.960333) (xy 156.27234 -55.001524)
			(xy 156.231149 -55.037215) (xy 156.185299 -55.066681) (xy 156.135722 -55.089323) (xy 156.083427 -55.104678)
			(xy 156.029479 -55.112434) (xy 155.974977 -55.112434) (xy 155.921029 -55.104678) (xy 155.868734 -55.089323)
			(xy 155.819157 -55.066681) (xy 155.773307 -55.037215) (xy 155.732116 -55.001524) (xy 155.696425 -54.960333)
			(xy 155.666959 -54.914483) (xy 155.644317 -54.864906) (xy 155.628962 -54.812611) (xy 155.621206 -54.758663)
			(xy 155.62072 -54.731412) (xy 147.112946 -54.731412) (xy 147.152532 -54.737107) (xy 147.204826 -54.752465)
			(xy 147.254402 -54.775109) (xy 147.300251 -54.804577) (xy 147.341441 -54.840269) (xy 147.377132 -54.88146)
			(xy 147.406598 -54.92731) (xy 147.42924 -54.976887) (xy 147.444596 -55.029181) (xy 147.452355 -55.083129)
			(xy 147.452842 -55.11038) (xy 147.452402 -55.137715) (xy 147.444588 -55.191824) (xy 147.429132 -55.244264)
			(xy 147.406351 -55.293961) (xy 147.376709 -55.339898) (xy 147.359116 -55.360824) (xy 147.358862 -55.361078)
			(xy 147.358608 -55.361332) (xy 147.353045 -55.368435) (xy 147.346784 -55.385339) (xy 147.346416 -55.394352)
			(xy 147.346416 -55.461408) (xy 147.346766 -55.470426) (xy 147.353018 -55.487343) (xy 147.358608 -55.494428)
			(xy 147.358862 -55.494682) (xy 147.359116 -55.494936) (xy 147.376697 -55.515874) (xy 147.406352 -55.561804)
			(xy 147.429143 -55.611498) (xy 147.444602 -55.663938) (xy 147.452413 -55.718049) (xy 147.452413 -55.722266)
			(xy 167.93413 -55.722266) (xy 167.938201 -55.666644) (xy 167.950327 -55.612207) (xy 167.97025 -55.560116)
			(xy 167.997546 -55.511481) (xy 168.031632 -55.467338) (xy 168.071781 -55.428629) (xy 168.117139 -55.396178)
			(xy 168.166739 -55.370677) (xy 168.219523 -55.35267) (xy 168.274366 -55.34254) (xy 168.3301 -55.340503)
			(xy 168.385537 -55.346603) (xy 168.439494 -55.360709) (xy 168.490823 -55.382521) (xy 168.538429 -55.411575)
			(xy 168.581297 -55.44725) (xy 168.618514 -55.488787) (xy 168.649287 -55.5353) (xy 168.672959 -55.585797)
			(xy 168.689027 -55.639204) (xy 168.697147 -55.69438) (xy 168.697656 -55.722266) (xy 168.697147 -55.750152)
			(xy 168.689027 -55.805328) (xy 168.672959 -55.858735) (xy 168.649287 -55.909232) (xy 168.618514 -55.955745)
			(xy 168.581297 -55.997282) (xy 168.538429 -56.032957) (xy 168.490823 -56.062011) (xy 168.439494 -56.083823)
			(xy 168.385537 -56.097929) (xy 168.3301 -56.104029) (xy 168.274366 -56.101992) (xy 168.219523 -56.091862)
			(xy 168.166739 -56.073855) (xy 168.117139 -56.048354) (xy 168.071781 -56.015903) (xy 168.031632 -55.977194)
			(xy 167.997546 -55.933051) (xy 167.97025 -55.884416) (xy 167.950327 -55.832325) (xy 167.938201 -55.777888)
			(xy 167.93413 -55.722266) (xy 147.452413 -55.722266) (xy 147.452415 -55.772721) (xy 147.444609 -55.826832)
			(xy 147.429154 -55.879274) (xy 147.406367 -55.92897) (xy 147.376716 -55.974902) (xy 147.359116 -55.995824)
			(xy 147.358862 -55.996078) (xy 147.358608 -55.996332) (xy 147.353045 -56.003435) (xy 147.346784 -56.020339)
			(xy 147.346416 -56.029352) (xy 147.346416 -56.096408) (xy 147.346766 -56.105426) (xy 147.353018 -56.122343)
			(xy 147.358608 -56.129428) (xy 147.358862 -56.129682) (xy 147.359116 -56.129936) (xy 147.376694 -56.150873)
			(xy 147.406334 -56.196807) (xy 147.429113 -56.246502) (xy 147.444564 -56.29894) (xy 147.452371 -56.353047)
			(xy 147.452842 -56.38038) (xy 147.452356 -56.407631) (xy 147.4446 -56.461579) (xy 147.429245 -56.513874)
			(xy 147.406603 -56.563451) (xy 147.377137 -56.609301) (xy 147.341446 -56.650492) (xy 147.300255 -56.686183)
			(xy 147.254405 -56.715649) (xy 147.204828 -56.738291) (xy 147.152533 -56.753646) (xy 147.098585 -56.761402)
			(xy 147.044083 -56.761402) (xy 146.990135 -56.753646) (xy 146.93784 -56.738291) (xy 146.888263 -56.715649)
			(xy 146.842413 -56.686183) (xy 146.801222 -56.650492) (xy 146.765531 -56.609301) (xy 146.736065 -56.563451)
			(xy 146.713423 -56.513874) (xy 146.698068 -56.461579) (xy 146.690312 -56.407631) (xy 146.689826 -56.38038)
			(xy 146.690309 -56.353047) (xy 146.698114 -56.29894) (xy 146.71356 -56.246501) (xy 146.736332 -56.196803)
			(xy 146.765963 -56.150864) (xy 146.783552 -56.129936) (xy 146.783806 -56.129682) (xy 146.78406 -56.129428)
			(xy 146.789648 -56.122343) (xy 146.795892 -56.105425) (xy 146.796252 -56.096408) (xy 146.796252 -56.029352)
			(xy 146.795881 -56.020336) (xy 146.789644 -56.003419) (xy 146.78406 -55.996332) (xy 146.783806 -55.996078)
			(xy 146.783552 -55.995824) (xy 146.765933 -55.974917) (xy 146.736282 -55.928981) (xy 146.713495 -55.879281)
			(xy 146.698041 -55.826837) (xy 146.690234 -55.772722) (xy 146.690236 -55.718048) (xy 146.698047 -55.663934)
			(xy 146.713506 -55.61149) (xy 146.736296 -55.561792) (xy 146.765951 -55.515858) (xy 146.783552 -55.494936)
			(xy 146.783806 -55.494682) (xy 146.78406 -55.494428) (xy 146.789648 -55.487343) (xy 146.795892 -55.470425)
			(xy 146.796252 -55.461408) (xy 146.796252 -55.394352) (xy 146.795881 -55.385336) (xy 146.789644 -55.368419)
			(xy 146.78406 -55.361332) (xy 146.783806 -55.361078) (xy 146.783552 -55.360824) (xy 146.772681 -55.348077)
			(xy 146.75297 -55.320985) (xy 146.744182 -55.306722) (xy 146.738594 -55.297578) (xy 146.721576 -55.285386)
			(xy 146.628612 -55.26532) (xy 146.608038 -55.269384) (xy 146.599402 -55.27548) (xy 146.575338 -55.291479)
			(xy 146.523407 -55.316823) (xy 146.468249 -55.334049) (xy 146.411125 -55.342764) (xy 146.382232 -55.343298)
			(xy 146.354977 -55.342857) (xy 146.301021 -55.335104) (xy 146.248718 -55.31975) (xy 146.199132 -55.297109)
			(xy 146.153274 -55.267641) (xy 146.112076 -55.231946) (xy 146.076378 -55.190752) (xy 146.046906 -55.144896)
			(xy 146.024261 -55.095312) (xy 146.008903 -55.04301) (xy 146.001145 -54.989055) (xy 143.792854 -54.989055)
			(xy 143.796265 -55.000394) (xy 143.804385 -55.05557) (xy 143.804894 -55.083456) (xy 143.804385 -55.111342)
			(xy 143.796265 -55.166518) (xy 143.780197 -55.219925) (xy 143.756525 -55.270422) (xy 143.725752 -55.316935)
			(xy 143.688535 -55.358472) (xy 143.645667 -55.394147) (xy 143.601905 -55.420855) (xy 144.324745 -55.420855)
			(xy 144.324745 -55.366345) (xy 144.332503 -55.31239) (xy 144.347861 -55.260088) (xy 144.370506 -55.210504)
			(xy 144.399978 -55.164648) (xy 144.435676 -55.123454) (xy 144.476874 -55.087759) (xy 144.522732 -55.058291)
			(xy 144.572318 -55.03565) (xy 144.624621 -55.020296) (xy 144.678577 -55.012543) (xy 144.705832 -55.012082)
			(xy 144.706086 -55.012082) (xy 144.73238 -55.012556) (xy 144.784468 -55.019799) (xy 144.835069 -55.034122)
			(xy 144.883225 -55.055255) (xy 144.928025 -55.082797) (xy 144.968621 -55.116227) (xy 144.986756 -55.135272)
			(xy 144.994311 -55.142733) (xy 145.013741 -55.151248) (xy 145.024348 -55.151782) (xy 145.098516 -55.151782)
			(xy 145.109149 -55.151378) (xy 145.128613 -55.142826) (xy 145.136108 -55.135272) (xy 145.154238 -55.116217)
			(xy 145.194818 -55.082758) (xy 145.239614 -55.055197) (xy 145.287774 -55.034057) (xy 145.338383 -55.01974)
			(xy 145.39048 -55.012518) (xy 145.416778 -55.012082) (xy 145.417032 -55.012082) (xy 145.444281 -55.01259)
			(xy 145.498224 -55.02035) (xy 145.550513 -55.035708) (xy 145.600085 -55.05835) (xy 145.64593 -55.087817)
			(xy 145.687116 -55.123507) (xy 145.722803 -55.164695) (xy 145.752265 -55.210543) (xy 145.774903 -55.260117)
			(xy 145.790256 -55.312408) (xy 145.798012 -55.366351) (xy 145.798012 -55.420849) (xy 145.790256 -55.474792)
			(xy 145.774903 -55.527083) (xy 145.752265 -55.576657) (xy 145.722803 -55.622505) (xy 145.687116 -55.663693)
			(xy 145.64593 -55.699383) (xy 145.600085 -55.72885) (xy 145.550513 -55.751492) (xy 145.498224 -55.76685)
			(xy 145.444281 -55.77461) (xy 145.417032 -55.775098) (xy 145.416778 -55.775098) (xy 145.390483 -55.774655)
			(xy 145.338393 -55.767406) (xy 145.287792 -55.753077) (xy 145.239636 -55.731939) (xy 145.194836 -55.704391)
			(xy 145.154242 -55.670956) (xy 145.136108 -55.651908) (xy 145.128531 -55.644473) (xy 145.109117 -55.635944)
			(xy 145.098516 -55.635398) (xy 145.024348 -55.635398) (xy 145.013714 -55.635788) (xy 144.99425 -55.644351)
			(xy 144.986756 -55.651908) (xy 144.96866 -55.670996) (xy 144.92807 -55.704449) (xy 144.883267 -55.732004)
			(xy 144.835101 -55.753137) (xy 144.784487 -55.767448) (xy 144.732385 -55.774664) (xy 144.706086 -55.775098)
			(xy 144.705832 -55.775098) (xy 144.678577 -55.774657) (xy 144.624621 -55.766904) (xy 144.572318 -55.75155)
			(xy 144.522732 -55.728909) (xy 144.476874 -55.699441) (xy 144.435676 -55.663746) (xy 144.399978 -55.622552)
			(xy 144.370506 -55.576696) (xy 144.347861 -55.527112) (xy 144.332503 -55.47481) (xy 144.324745 -55.420855)
			(xy 143.601905 -55.420855) (xy 143.598061 -55.423201) (xy 143.546732 -55.445013) (xy 143.492775 -55.459119)
			(xy 143.437338 -55.465219) (xy 143.381604 -55.463182) (xy 143.326761 -55.453052) (xy 143.273977 -55.435045)
			(xy 143.224377 -55.409544) (xy 143.179019 -55.377093) (xy 143.13887 -55.338384) (xy 143.104784 -55.294241)
			(xy 143.077488 -55.245606) (xy 143.057565 -55.193515) (xy 143.045439 -55.139078) (xy 143.041368 -55.083456)
			(xy 136.77052 -55.083456) (xy 136.735757 -55.105797) (xy 136.68618 -55.128439) (xy 136.633885 -55.143794)
			(xy 136.579937 -55.15155) (xy 136.525435 -55.15155) (xy 136.471487 -55.143794) (xy 136.419192 -55.128439)
			(xy 136.369615 -55.105797) (xy 136.323765 -55.076331) (xy 136.282574 -55.04064) (xy 136.246883 -54.999449)
			(xy 136.217417 -54.953599) (xy 136.194775 -54.904022) (xy 136.17942 -54.851727) (xy 136.171664 -54.797779)
			(xy 136.171178 -54.770528) (xy 133.039259 -54.770528) (xy 133.039612 -54.791102) (xy 133.039126 -54.818353)
			(xy 133.03137 -54.872301) (xy 133.016015 -54.924596) (xy 132.993373 -54.974173) (xy 132.963907 -55.020023)
			(xy 132.928216 -55.061214) (xy 132.887025 -55.096905) (xy 132.841175 -55.126371) (xy 132.791598 -55.149013)
			(xy 132.739303 -55.164368) (xy 132.685355 -55.172124) (xy 132.630853 -55.172124) (xy 132.576905 -55.164368)
			(xy 132.52461 -55.149013) (xy 132.475033 -55.126371) (xy 132.429183 -55.096905) (xy 132.387992 -55.061214)
			(xy 132.352301 -55.020023) (xy 132.322835 -54.974173) (xy 132.300193 -54.924596) (xy 132.284838 -54.872301)
			(xy 132.277082 -54.818353) (xy 132.276596 -54.791102) (xy 130.378638 -54.791102) (xy 130.375546 -54.812611)
			(xy 130.360191 -54.864906) (xy 130.337549 -54.914483) (xy 130.308083 -54.960333) (xy 130.272392 -55.001524)
			(xy 130.231201 -55.037215) (xy 130.185351 -55.066681) (xy 130.135774 -55.089323) (xy 130.083479 -55.104678)
			(xy 130.029531 -55.112434) (xy 129.975029 -55.112434) (xy 129.921081 -55.104678) (xy 129.868786 -55.089323)
			(xy 129.819209 -55.066681) (xy 129.773359 -55.037215) (xy 129.732168 -55.001524) (xy 129.696477 -54.960333)
			(xy 129.667011 -54.914483) (xy 129.644369 -54.864906) (xy 129.629014 -54.812611) (xy 129.621258 -54.758663)
			(xy 129.620772 -54.731412) (xy 121.112696 -54.731412) (xy 121.152581 -54.737145) (xy 121.204874 -54.752498)
			(xy 121.25445 -54.775136) (xy 121.300299 -54.804599) (xy 121.341489 -54.840287) (xy 121.377181 -54.881473)
			(xy 121.406648 -54.92732) (xy 121.42929 -54.976894) (xy 121.444647 -55.029185) (xy 121.452406 -55.08313)
			(xy 121.452894 -55.11038) (xy 121.452441 -55.137714) (xy 121.444629 -55.191822) (xy 121.429175 -55.244261)
			(xy 121.406396 -55.293959) (xy 121.376759 -55.339897) (xy 121.359168 -55.360824) (xy 121.358914 -55.361078)
			(xy 121.35866 -55.361332) (xy 121.353091 -55.36843) (xy 121.346835 -55.385338) (xy 121.346468 -55.394352)
			(xy 121.346468 -55.461408) (xy 121.346828 -55.470424) (xy 121.353074 -55.487341) (xy 121.35866 -55.494428)
			(xy 121.358914 -55.494682) (xy 121.359168 -55.494936) (xy 121.376747 -55.515875) (xy 121.406398 -55.561806)
			(xy 121.429186 -55.6115) (xy 121.444643 -55.66394) (xy 121.452453 -55.71805) (xy 121.452453 -55.722266)
			(xy 141.934182 -55.722266) (xy 141.938253 -55.666644) (xy 141.950379 -55.612207) (xy 141.970302 -55.560116)
			(xy 141.997598 -55.511481) (xy 142.031684 -55.467338) (xy 142.071833 -55.428629) (xy 142.117191 -55.396178)
			(xy 142.166791 -55.370677) (xy 142.219575 -55.35267) (xy 142.274418 -55.34254) (xy 142.330152 -55.340503)
			(xy 142.385589 -55.346603) (xy 142.439546 -55.360709) (xy 142.490875 -55.382521) (xy 142.538481 -55.411575)
			(xy 142.581349 -55.44725) (xy 142.618566 -55.488787) (xy 142.649339 -55.5353) (xy 142.673011 -55.585797)
			(xy 142.689079 -55.639204) (xy 142.697199 -55.69438) (xy 142.697708 -55.722266) (xy 142.697199 -55.750152)
			(xy 142.689079 -55.805328) (xy 142.673011 -55.858735) (xy 142.649339 -55.909232) (xy 142.618566 -55.955745)
			(xy 142.581349 -55.997282) (xy 142.538481 -56.032957) (xy 142.490875 -56.062011) (xy 142.439546 -56.083823)
			(xy 142.385589 -56.097929) (xy 142.330152 -56.104029) (xy 142.274418 -56.101992) (xy 142.219575 -56.091862)
			(xy 142.166791 -56.073855) (xy 142.117191 -56.048354) (xy 142.071833 -56.015903) (xy 142.031684 -55.977194)
			(xy 141.997598 -55.933051) (xy 141.970302 -55.884416) (xy 141.950379 -55.832325) (xy 141.938253 -55.777888)
			(xy 141.934182 -55.722266) (xy 121.452453 -55.722266) (xy 121.452455 -55.77272) (xy 121.444649 -55.82683)
			(xy 121.429196 -55.879271) (xy 121.406413 -55.928968) (xy 121.376765 -55.974901) (xy 121.359168 -55.995824)
			(xy 121.358914 -55.996078) (xy 121.35866 -55.996332) (xy 121.353091 -56.00343) (xy 121.346835 -56.020338)
			(xy 121.346468 -56.029352) (xy 121.346468 -56.096408) (xy 121.346828 -56.105424) (xy 121.353074 -56.122341)
			(xy 121.35866 -56.129428) (xy 121.358914 -56.129682) (xy 121.359168 -56.129936) (xy 121.376739 -56.150879)
			(xy 121.406382 -56.196811) (xy 121.429163 -56.246504) (xy 121.444615 -56.298941) (xy 121.452423 -56.353047)
			(xy 121.452894 -56.38038) (xy 121.452408 -56.407631) (xy 121.444652 -56.461579) (xy 121.429297 -56.513874)
			(xy 121.406655 -56.563451) (xy 121.377189 -56.609301) (xy 121.341498 -56.650492) (xy 121.300307 -56.686183)
			(xy 121.254457 -56.715649) (xy 121.20488 -56.738291) (xy 121.152585 -56.753646) (xy 121.098637 -56.761402)
			(xy 121.044135 -56.761402) (xy 120.990187 -56.753646) (xy 120.937892 -56.738291) (xy 120.888315 -56.715649)
			(xy 120.842465 -56.686183) (xy 120.801274 -56.650492) (xy 120.765583 -56.609301) (xy 120.736117 -56.563451)
			(xy 120.713475 -56.513874) (xy 120.69812 -56.461579) (xy 120.690364 -56.407631) (xy 120.689878 -56.38038)
			(xy 120.690373 -56.353047) (xy 120.698176 -56.298942) (xy 120.71362 -56.246503) (xy 120.736389 -56.196805)
			(xy 120.766017 -56.150865) (xy 120.783604 -56.129936) (xy 120.783858 -56.129682) (xy 120.784112 -56.129428)
			(xy 120.789694 -56.122339) (xy 120.795943 -56.105424) (xy 120.796304 -56.096408) (xy 120.796304 -56.029352)
			(xy 120.795921 -56.020338) (xy 120.789691 -56.003421) (xy 120.784112 -55.996332) (xy 120.783858 -55.996078)
			(xy 120.783604 -55.995824) (xy 120.765983 -55.974918) (xy 120.736328 -55.928983) (xy 120.713538 -55.879284)
			(xy 120.698081 -55.826838) (xy 120.690274 -55.772723) (xy 120.690276 -55.718047) (xy 120.698087 -55.663932)
			(xy 120.713549 -55.611488) (xy 120.736342 -55.56179) (xy 120.766001 -55.515857) (xy 120.783604 -55.494936)
			(xy 120.783858 -55.494682) (xy 120.784112 -55.494428) (xy 120.789694 -55.487339) (xy 120.795943 -55.470424)
			(xy 120.796304 -55.461408) (xy 120.796304 -55.394352) (xy 120.795921 -55.385338) (xy 120.789691 -55.368421)
			(xy 120.784112 -55.361332) (xy 120.783858 -55.361078) (xy 120.783604 -55.360824) (xy 120.772736 -55.348075)
			(xy 120.753023 -55.320984) (xy 120.744234 -55.306722) (xy 120.738646 -55.297578) (xy 120.721628 -55.285386)
			(xy 120.628664 -55.26532) (xy 120.60809 -55.269384) (xy 120.599454 -55.27548) (xy 120.575403 -55.2915)
			(xy 120.523467 -55.316838) (xy 120.468305 -55.334059) (xy 120.411178 -55.342767) (xy 120.382284 -55.343298)
			(xy 120.355033 -55.342831) (xy 120.301085 -55.335073) (xy 120.248791 -55.319716) (xy 120.199215 -55.297073)
			(xy 120.153365 -55.267605) (xy 120.112176 -55.231913) (xy 120.076485 -55.190722) (xy 120.047019 -55.144871)
			(xy 120.024379 -55.095294) (xy 120.009024 -55.042999) (xy 120.001268 -54.989051) (xy 105.692598 -54.989051)
			(xy 105.696011 -55.000394) (xy 105.704131 -55.05557) (xy 105.70464 -55.083456) (xy 105.704131 -55.111342)
			(xy 105.696011 -55.166518) (xy 105.679943 -55.219925) (xy 105.656271 -55.270422) (xy 105.625498 -55.316935)
			(xy 105.588281 -55.358472) (xy 105.545413 -55.394147) (xy 105.501658 -55.420851) (xy 118.324868 -55.420851)
			(xy 118.324868 -55.366349) (xy 118.332624 -55.312401) (xy 118.347979 -55.260106) (xy 118.370619 -55.210529)
			(xy 118.400085 -55.164678) (xy 118.435776 -55.123487) (xy 118.476965 -55.087795) (xy 118.522815 -55.058327)
			(xy 118.572391 -55.035684) (xy 118.624685 -55.020327) (xy 118.678633 -55.012569) (xy 118.705884 -55.012082)
			(xy 118.706138 -55.012082) (xy 118.732433 -55.012521) (xy 118.784523 -55.019771) (xy 118.835124 -55.034102)
			(xy 118.88328 -55.055241) (xy 118.928079 -55.082789) (xy 118.968674 -55.116224) (xy 118.986808 -55.135272)
			(xy 118.994381 -55.142712) (xy 119.013798 -55.151239) (xy 119.0244 -55.151782) (xy 119.098568 -55.151782)
			(xy 119.109204 -55.151407) (xy 119.128668 -55.142834) (xy 119.13616 -55.135272) (xy 119.154313 -55.11624)
			(xy 119.194888 -55.082779) (xy 119.239679 -55.055215) (xy 119.287834 -55.034071) (xy 119.33844 -55.019749)
			(xy 119.390534 -55.012522) (xy 119.41683 -55.012082) (xy 119.417084 -55.012082) (xy 119.444337 -55.012564)
			(xy 119.498288 -55.020319) (xy 119.550587 -55.035673) (xy 119.600167 -55.058314) (xy 119.646021 -55.087781)
			(xy 119.687215 -55.123474) (xy 119.722909 -55.164666) (xy 119.752378 -55.210519) (xy 119.775021 -55.260098)
			(xy 119.790377 -55.312396) (xy 119.798135 -55.366347) (xy 119.798135 -55.420853) (xy 119.790377 -55.474804)
			(xy 119.775021 -55.527102) (xy 119.752378 -55.576681) (xy 119.722909 -55.622534) (xy 119.687215 -55.663726)
			(xy 119.646021 -55.699419) (xy 119.600167 -55.728886) (xy 119.550587 -55.751527) (xy 119.498288 -55.766881)
			(xy 119.444337 -55.774636) (xy 119.417084 -55.775098) (xy 119.41683 -55.775098) (xy 119.390536 -55.77462)
			(xy 119.338448 -55.767379) (xy 119.287847 -55.753056) (xy 119.239691 -55.731925) (xy 119.194891 -55.704383)
			(xy 119.154295 -55.670953) (xy 119.13616 -55.651908) (xy 119.128601 -55.644451) (xy 119.109174 -55.635935)
			(xy 119.098568 -55.635398) (xy 119.0244 -55.635398) (xy 119.013769 -55.635816) (xy 118.994305 -55.644359)
			(xy 118.986808 -55.651908) (xy 118.968686 -55.67097) (xy 118.928102 -55.704426) (xy 118.883305 -55.731984)
			(xy 118.835143 -55.753122) (xy 118.784533 -55.767438) (xy 118.732436 -55.774661) (xy 118.706138 -55.775098)
			(xy 118.705884 -55.775098) (xy 118.678633 -55.774631) (xy 118.624685 -55.766873) (xy 118.572391 -55.751516)
			(xy 118.522815 -55.728873) (xy 118.476965 -55.699405) (xy 118.435776 -55.663713) (xy 118.400085 -55.622522)
			(xy 118.370619 -55.576671) (xy 118.347979 -55.527094) (xy 118.332624 -55.474799) (xy 118.324868 -55.420851)
			(xy 105.501658 -55.420851) (xy 105.497807 -55.423201) (xy 105.446478 -55.445013) (xy 105.392521 -55.459119)
			(xy 105.337084 -55.465219) (xy 105.28135 -55.463182) (xy 105.226507 -55.453052) (xy 105.173723 -55.435045)
			(xy 105.124123 -55.409544) (xy 105.078765 -55.377093) (xy 105.038616 -55.338384) (xy 105.00453 -55.294241)
			(xy 104.977234 -55.245606) (xy 104.957311 -55.193515) (xy 104.945185 -55.139078) (xy 104.941114 -55.083456)
			(xy 98.670266 -55.083456) (xy 98.635503 -55.105797) (xy 98.585926 -55.128439) (xy 98.533631 -55.143794)
			(xy 98.479683 -55.15155) (xy 98.425181 -55.15155) (xy 98.371233 -55.143794) (xy 98.318938 -55.128439)
			(xy 98.269361 -55.105797) (xy 98.223511 -55.076331) (xy 98.18232 -55.04064) (xy 98.146629 -54.999449)
			(xy 98.117163 -54.953599) (xy 98.094521 -54.904022) (xy 98.079166 -54.851727) (xy 98.07141 -54.797779)
			(xy 98.070924 -54.770528) (xy 94.939005 -54.770528) (xy 94.939358 -54.791102) (xy 94.938872 -54.818353)
			(xy 94.931116 -54.872301) (xy 94.915761 -54.924596) (xy 94.893119 -54.974173) (xy 94.863653 -55.020023)
			(xy 94.827962 -55.061214) (xy 94.786771 -55.096905) (xy 94.740921 -55.126371) (xy 94.691344 -55.149013)
			(xy 94.639049 -55.164368) (xy 94.585101 -55.172124) (xy 94.530599 -55.172124) (xy 94.476651 -55.164368)
			(xy 94.424356 -55.149013) (xy 94.374779 -55.126371) (xy 94.328929 -55.096905) (xy 94.287738 -55.061214)
			(xy 94.252047 -55.020023) (xy 94.222581 -54.974173) (xy 94.199939 -54.924596) (xy 94.184584 -54.872301)
			(xy 94.176828 -54.818353) (xy 94.176342 -54.791102) (xy 92.278384 -54.791102) (xy 92.275292 -54.812611)
			(xy 92.259937 -54.864906) (xy 92.237295 -54.914483) (xy 92.207829 -54.960333) (xy 92.172138 -55.001524)
			(xy 92.130947 -55.037215) (xy 92.085097 -55.066681) (xy 92.03552 -55.089323) (xy 91.983225 -55.104678)
			(xy 91.929277 -55.112434) (xy 91.874775 -55.112434) (xy 91.820827 -55.104678) (xy 91.768532 -55.089323)
			(xy 91.718955 -55.066681) (xy 91.673105 -55.037215) (xy 91.631914 -55.001524) (xy 91.596223 -54.960333)
			(xy 91.566757 -54.914483) (xy 91.544115 -54.864906) (xy 91.52876 -54.812611) (xy 91.521004 -54.758663)
			(xy 91.520518 -54.731412) (xy 83.012732 -54.731412) (xy 83.05233 -54.737108) (xy 83.104624 -54.752467)
			(xy 83.1542 -54.77511) (xy 83.200049 -54.804578) (xy 83.241238 -54.84027) (xy 83.27693 -54.88146)
			(xy 83.306396 -54.927311) (xy 83.329038 -54.976887) (xy 83.344394 -55.029182) (xy 83.352153 -55.083129)
			(xy 83.35264 -55.11038) (xy 83.3522 -55.137715) (xy 83.344387 -55.191824) (xy 83.328931 -55.244264)
			(xy 83.306149 -55.293961) (xy 83.276508 -55.339898) (xy 83.258914 -55.360824) (xy 83.25866 -55.361078)
			(xy 83.258406 -55.361332) (xy 83.252842 -55.368434) (xy 83.246582 -55.385339) (xy 83.246214 -55.394352)
			(xy 83.246214 -55.461408) (xy 83.246564 -55.470426) (xy 83.252816 -55.487343) (xy 83.258406 -55.494428)
			(xy 83.25866 -55.494682) (xy 83.258914 -55.494936) (xy 83.276496 -55.515874) (xy 83.306151 -55.561803)
			(xy 83.328942 -55.611498) (xy 83.344401 -55.663938) (xy 83.352212 -55.718049) (xy 83.352212 -55.722266)
			(xy 103.833928 -55.722266) (xy 103.837999 -55.666644) (xy 103.850125 -55.612207) (xy 103.870048 -55.560116)
			(xy 103.897344 -55.511481) (xy 103.93143 -55.467338) (xy 103.971579 -55.428629) (xy 104.016937 -55.396178)
			(xy 104.066537 -55.370677) (xy 104.119321 -55.35267) (xy 104.174164 -55.34254) (xy 104.229898 -55.340503)
			(xy 104.285335 -55.346603) (xy 104.339292 -55.360709) (xy 104.390621 -55.382521) (xy 104.438227 -55.411575)
			(xy 104.481095 -55.44725) (xy 104.518312 -55.488787) (xy 104.549085 -55.5353) (xy 104.572757 -55.585797)
			(xy 104.588825 -55.639204) (xy 104.596945 -55.69438) (xy 104.597454 -55.722266) (xy 104.596945 -55.750152)
			(xy 104.588825 -55.805328) (xy 104.572757 -55.858735) (xy 104.549085 -55.909232) (xy 104.518312 -55.955745)
			(xy 104.481095 -55.997282) (xy 104.438227 -56.032957) (xy 104.390621 -56.062011) (xy 104.339292 -56.083823)
			(xy 104.285335 -56.097929) (xy 104.229898 -56.104029) (xy 104.174164 -56.101992) (xy 104.119321 -56.091862)
			(xy 104.066537 -56.073855) (xy 104.016937 -56.048354) (xy 103.971579 -56.015903) (xy 103.93143 -55.977194)
			(xy 103.897344 -55.933051) (xy 103.870048 -55.884416) (xy 103.850125 -55.832325) (xy 103.837999 -55.777888)
			(xy 103.833928 -55.722266) (xy 83.352212 -55.722266) (xy 83.352214 -55.772721) (xy 83.344407 -55.826832)
			(xy 83.328952 -55.879274) (xy 83.306165 -55.92897) (xy 83.276514 -55.974902) (xy 83.258914 -55.995824)
			(xy 83.25866 -55.996078) (xy 83.258406 -55.996332) (xy 83.252842 -56.003434) (xy 83.246582 -56.020339)
			(xy 83.246214 -56.029352) (xy 83.246214 -56.096408) (xy 83.246564 -56.105426) (xy 83.252816 -56.122343)
			(xy 83.258406 -56.129428) (xy 83.25866 -56.129682) (xy 83.258914 -56.129936) (xy 83.276492 -56.150873)
			(xy 83.306132 -56.196807) (xy 83.328911 -56.246502) (xy 83.344362 -56.29894) (xy 83.352169 -56.353047)
			(xy 83.35264 -56.38038) (xy 83.352154 -56.407631) (xy 83.344398 -56.461579) (xy 83.329043 -56.513874)
			(xy 83.306401 -56.563451) (xy 83.276935 -56.609301) (xy 83.241244 -56.650492) (xy 83.200053 -56.686183)
			(xy 83.154203 -56.715649) (xy 83.104626 -56.738291) (xy 83.052331 -56.753646) (xy 82.998383 -56.761402)
			(xy 82.943881 -56.761402) (xy 82.889933 -56.753646) (xy 82.837638 -56.738291) (xy 82.788061 -56.715649)
			(xy 82.742211 -56.686183) (xy 82.70102 -56.650492) (xy 82.665329 -56.609301) (xy 82.635863 -56.563451)
			(xy 82.613221 -56.513874) (xy 82.597866 -56.461579) (xy 82.59011 -56.407631) (xy 82.589624 -56.38038)
			(xy 82.590108 -56.353047) (xy 82.597912 -56.29894) (xy 82.613358 -56.246501) (xy 82.63613 -56.196803)
			(xy 82.665761 -56.150864) (xy 82.68335 -56.129936) (xy 82.683604 -56.129682) (xy 82.683858 -56.129428)
			(xy 82.689446 -56.122343) (xy 82.69569 -56.105425) (xy 82.69605 -56.096408) (xy 82.69605 -56.029352)
			(xy 82.695679 -56.020336) (xy 82.689442 -56.003419) (xy 82.683858 -55.996332) (xy 82.683604 -55.996078)
			(xy 82.68335 -55.995824) (xy 82.665731 -55.974917) (xy 82.63608 -55.928981) (xy 82.613294 -55.879281)
			(xy 82.597839 -55.826837) (xy 82.590033 -55.772722) (xy 82.590035 -55.718048) (xy 82.597845 -55.663934)
			(xy 82.613304 -55.61149) (xy 82.636095 -55.561792) (xy 82.665749 -55.515858) (xy 82.68335 -55.494936)
			(xy 82.683604 -55.494682) (xy 82.683858 -55.494428) (xy 82.689446 -55.487343) (xy 82.69569 -55.470425)
			(xy 82.69605 -55.461408) (xy 82.69605 -55.394352) (xy 82.695679 -55.385336) (xy 82.689442 -55.368419)
			(xy 82.683858 -55.361332) (xy 82.683604 -55.361078) (xy 82.68335 -55.360824) (xy 82.672479 -55.348077)
			(xy 82.652768 -55.320985) (xy 82.64398 -55.306722) (xy 82.638392 -55.297578) (xy 82.621374 -55.285386)
			(xy 82.52841 -55.26532) (xy 82.507836 -55.269384) (xy 82.4992 -55.27548) (xy 82.475136 -55.29148)
			(xy 82.423205 -55.316823) (xy 82.368047 -55.334049) (xy 82.310923 -55.342764) (xy 82.28203 -55.343298)
			(xy 82.254775 -55.342857) (xy 82.200819 -55.335103) (xy 82.148516 -55.31975) (xy 82.098931 -55.297108)
			(xy 82.053073 -55.26764) (xy 82.011876 -55.231946) (xy 81.976178 -55.190751) (xy 81.946706 -55.144895)
			(xy 81.924061 -55.095312) (xy 81.908703 -55.04301) (xy 81.900945 -54.989055) (xy 79.692652 -54.989055)
			(xy 79.696063 -55.000394) (xy 79.704183 -55.05557) (xy 79.704692 -55.083456) (xy 79.704183 -55.111342)
			(xy 79.696063 -55.166518) (xy 79.679995 -55.219925) (xy 79.656323 -55.270422) (xy 79.62555 -55.316935)
			(xy 79.588333 -55.358472) (xy 79.545465 -55.394147) (xy 79.501703 -55.420855) (xy 80.224545 -55.420855)
			(xy 80.224545 -55.366345) (xy 80.232303 -55.31239) (xy 80.247661 -55.260088) (xy 80.270306 -55.210505)
			(xy 80.299778 -55.164649) (xy 80.335476 -55.123454) (xy 80.376673 -55.08776) (xy 80.422531 -55.058292)
			(xy 80.472116 -55.03565) (xy 80.524419 -55.020297) (xy 80.578375 -55.012543) (xy 80.60563 -55.012082)
			(xy 80.605884 -55.012082) (xy 80.632178 -55.012557) (xy 80.684266 -55.0198) (xy 80.734867 -55.034123)
			(xy 80.783023 -55.055256) (xy 80.827823 -55.082797) (xy 80.868419 -55.116227) (xy 80.886554 -55.135272)
			(xy 80.89411 -55.142732) (xy 80.91354 -55.151247) (xy 80.924146 -55.151782) (xy 80.998314 -55.151782)
			(xy 81.008947 -55.151377) (xy 81.028411 -55.142825) (xy 81.035906 -55.135272) (xy 81.054037 -55.116218)
			(xy 81.094617 -55.082759) (xy 81.139412 -55.055197) (xy 81.187572 -55.034057) (xy 81.238181 -55.01974)
			(xy 81.290278 -55.012519) (xy 81.316576 -55.012082) (xy 81.31683 -55.012082) (xy 81.344079 -55.01259)
			(xy 81.398022 -55.02035) (xy 81.450312 -55.035707) (xy 81.499884 -55.05835) (xy 81.545729 -55.087816)
			(xy 81.586915 -55.123506) (xy 81.622602 -55.164695) (xy 81.652065 -55.210542) (xy 81.674703 -55.260116)
			(xy 81.690056 -55.312407) (xy 81.697812 -55.366351) (xy 81.697812 -55.420849) (xy 81.690056 -55.474793)
			(xy 81.674703 -55.527084) (xy 81.652065 -55.576658) (xy 81.622602 -55.622505) (xy 81.586915 -55.663694)
			(xy 81.545729 -55.699384) (xy 81.499884 -55.72885) (xy 81.450312 -55.751493) (xy 81.398022 -55.76685)
			(xy 81.344079 -55.77461) (xy 81.31683 -55.775098) (xy 81.316576 -55.775098) (xy 81.290281 -55.774656)
			(xy 81.238191 -55.767407) (xy 81.18759 -55.753078) (xy 81.139433 -55.731939) (xy 81.094634 -55.704392)
			(xy 81.05404 -55.670956) (xy 81.035906 -55.651908) (xy 81.02833 -55.644472) (xy 81.008915 -55.635944)
			(xy 80.998314 -55.635398) (xy 80.924146 -55.635398) (xy 80.913512 -55.635787) (xy 80.894048 -55.644351)
			(xy 80.886554 -55.651908) (xy 80.868459 -55.670997) (xy 80.827869 -55.70445) (xy 80.783066 -55.732005)
			(xy 80.734899 -55.753138) (xy 80.684285 -55.767449) (xy 80.632183 -55.774664) (xy 80.605884 -55.775098)
			(xy 80.60563 -55.775098) (xy 80.578375 -55.774657) (xy 80.524419 -55.766903) (xy 80.472116 -55.75155)
			(xy 80.422531 -55.728908) (xy 80.376673 -55.69944) (xy 80.335476 -55.663746) (xy 80.299778 -55.622551)
			(xy 80.270306 -55.576695) (xy 80.247661 -55.527112) (xy 80.232303 -55.47481) (xy 80.224545 -55.420855)
			(xy 79.501703 -55.420855) (xy 79.497859 -55.423201) (xy 79.44653 -55.445013) (xy 79.392573 -55.459119)
			(xy 79.337136 -55.465219) (xy 79.281402 -55.463182) (xy 79.226559 -55.453052) (xy 79.173775 -55.435045)
			(xy 79.124175 -55.409544) (xy 79.078817 -55.377093) (xy 79.038668 -55.338384) (xy 79.004582 -55.294241)
			(xy 78.977286 -55.245606) (xy 78.957363 -55.193515) (xy 78.945237 -55.139078) (xy 78.941166 -55.083456)
			(xy 72.670318 -55.083456) (xy 72.635555 -55.105797) (xy 72.585978 -55.128439) (xy 72.533683 -55.143794)
			(xy 72.479735 -55.15155) (xy 72.425233 -55.15155) (xy 72.371285 -55.143794) (xy 72.31899 -55.128439)
			(xy 72.269413 -55.105797) (xy 72.223563 -55.076331) (xy 72.182372 -55.04064) (xy 72.146681 -54.999449)
			(xy 72.117215 -54.953599) (xy 72.094573 -54.904022) (xy 72.079218 -54.851727) (xy 72.071462 -54.797779)
			(xy 72.070976 -54.770528) (xy 68.939057 -54.770528) (xy 68.93941 -54.791102) (xy 68.938924 -54.818353)
			(xy 68.931168 -54.872301) (xy 68.915813 -54.924596) (xy 68.893171 -54.974173) (xy 68.863705 -55.020023)
			(xy 68.828014 -55.061214) (xy 68.786823 -55.096905) (xy 68.740973 -55.126371) (xy 68.691396 -55.149013)
			(xy 68.639101 -55.164368) (xy 68.585153 -55.172124) (xy 68.530651 -55.172124) (xy 68.476703 -55.164368)
			(xy 68.424408 -55.149013) (xy 68.374831 -55.126371) (xy 68.328981 -55.096905) (xy 68.28779 -55.061214)
			(xy 68.252099 -55.020023) (xy 68.222633 -54.974173) (xy 68.199991 -54.924596) (xy 68.184636 -54.872301)
			(xy 68.17688 -54.818353) (xy 68.176394 -54.791102) (xy 66.278436 -54.791102) (xy 66.275344 -54.812611)
			(xy 66.259989 -54.864906) (xy 66.237347 -54.914483) (xy 66.207881 -54.960333) (xy 66.17219 -55.001524)
			(xy 66.130999 -55.037215) (xy 66.085149 -55.066681) (xy 66.035572 -55.089323) (xy 65.983277 -55.104678)
			(xy 65.929329 -55.112434) (xy 65.874827 -55.112434) (xy 65.820879 -55.104678) (xy 65.768584 -55.089323)
			(xy 65.719007 -55.066681) (xy 65.673157 -55.037215) (xy 65.631966 -55.001524) (xy 65.596275 -54.960333)
			(xy 65.566809 -54.914483) (xy 65.544167 -54.864906) (xy 65.528812 -54.812611) (xy 65.521056 -54.758663)
			(xy 65.52057 -54.731412) (xy 57.01248 -54.731412) (xy 57.052379 -54.737147) (xy 57.104672 -54.752499)
			(xy 57.154248 -54.775137) (xy 57.200097 -54.804599) (xy 57.241287 -54.840287) (xy 57.276979 -54.881474)
			(xy 57.306446 -54.92732) (xy 57.329088 -54.976894) (xy 57.344445 -55.029185) (xy 57.352204 -55.08313)
			(xy 57.352692 -55.11038) (xy 57.35224 -55.137714) (xy 57.344427 -55.191822) (xy 57.328973 -55.244261)
			(xy 57.306195 -55.293959) (xy 57.276557 -55.339897) (xy 57.258966 -55.360824) (xy 57.258712 -55.361078)
			(xy 57.258458 -55.361332) (xy 57.252889 -55.36843) (xy 57.246633 -55.385338) (xy 57.246266 -55.394352)
			(xy 57.246266 -55.461408) (xy 57.246626 -55.470424) (xy 57.252872 -55.487341) (xy 57.258458 -55.494428)
			(xy 57.258712 -55.494682) (xy 57.258966 -55.494936) (xy 57.276545 -55.515875) (xy 57.306196 -55.561806)
			(xy 57.328984 -55.6115) (xy 57.344441 -55.66394) (xy 57.352251 -55.71805) (xy 57.352251 -55.722266)
			(xy 77.83398 -55.722266) (xy 77.838051 -55.666644) (xy 77.850177 -55.612207) (xy 77.8701 -55.560116)
			(xy 77.897396 -55.511481) (xy 77.931482 -55.467338) (xy 77.971631 -55.428629) (xy 78.016989 -55.396178)
			(xy 78.066589 -55.370677) (xy 78.119373 -55.35267) (xy 78.174216 -55.34254) (xy 78.22995 -55.340503)
			(xy 78.285387 -55.346603) (xy 78.339344 -55.360709) (xy 78.390673 -55.382521) (xy 78.438279 -55.411575)
			(xy 78.481147 -55.44725) (xy 78.518364 -55.488787) (xy 78.549137 -55.5353) (xy 78.572809 -55.585797)
			(xy 78.588877 -55.639204) (xy 78.596997 -55.69438) (xy 78.597506 -55.722266) (xy 78.596997 -55.750152)
			(xy 78.588877 -55.805328) (xy 78.572809 -55.858735) (xy 78.549137 -55.909232) (xy 78.518364 -55.955745)
			(xy 78.481147 -55.997282) (xy 78.438279 -56.032957) (xy 78.390673 -56.062011) (xy 78.339344 -56.083823)
			(xy 78.285387 -56.097929) (xy 78.22995 -56.104029) (xy 78.174216 -56.101992) (xy 78.119373 -56.091862)
			(xy 78.066589 -56.073855) (xy 78.016989 -56.048354) (xy 77.971631 -56.015903) (xy 77.931482 -55.977194)
			(xy 77.897396 -55.933051) (xy 77.8701 -55.884416) (xy 77.850177 -55.832325) (xy 77.838051 -55.777888)
			(xy 77.83398 -55.722266) (xy 57.352251 -55.722266) (xy 57.352253 -55.77272) (xy 57.344448 -55.82683)
			(xy 57.328995 -55.879271) (xy 57.306211 -55.928968) (xy 57.276563 -55.974901) (xy 57.258966 -55.995824)
			(xy 57.258712 -55.996078) (xy 57.258458 -55.996332) (xy 57.252889 -56.00343) (xy 57.246633 -56.020338)
			(xy 57.246266 -56.029352) (xy 57.246266 -56.096408) (xy 57.246626 -56.105424) (xy 57.252872 -56.122341)
			(xy 57.258458 -56.129428) (xy 57.258712 -56.129682) (xy 57.258966 -56.129936) (xy 57.276537 -56.150879)
			(xy 57.306179 -56.196811) (xy 57.328961 -56.246504) (xy 57.344413 -56.298941) (xy 57.352221 -56.353047)
			(xy 57.352692 -56.38038) (xy 57.352206 -56.407631) (xy 57.34445 -56.461579) (xy 57.329095 -56.513874)
			(xy 57.306453 -56.563451) (xy 57.276987 -56.609301) (xy 57.241296 -56.650492) (xy 57.200105 -56.686183)
			(xy 57.154255 -56.715649) (xy 57.104678 -56.738291) (xy 57.052383 -56.753646) (xy 56.998435 -56.761402)
			(xy 56.943933 -56.761402) (xy 56.889985 -56.753646) (xy 56.83769 -56.738291) (xy 56.788113 -56.715649)
			(xy 56.742263 -56.686183) (xy 56.701072 -56.650492) (xy 56.665381 -56.609301) (xy 56.635915 -56.563451)
			(xy 56.613273 -56.513874) (xy 56.597918 -56.461579) (xy 56.590162 -56.407631) (xy 56.589676 -56.38038)
			(xy 56.590147 -56.353046) (xy 56.597952 -56.298938) (xy 56.613401 -56.246499) (xy 56.636176 -56.196801)
			(xy 56.665811 -56.150863) (xy 56.683402 -56.129936) (xy 56.683656 -56.129682) (xy 56.68391 -56.129428)
			(xy 56.689492 -56.122338) (xy 56.695741 -56.105424) (xy 56.696102 -56.096408) (xy 56.696102 -56.029352)
			(xy 56.695719 -56.020338) (xy 56.689489 -56.003421) (xy 56.68391 -55.996332) (xy 56.683656 -55.996078)
			(xy 56.683402 -55.995824) (xy 56.665781 -55.974918) (xy 56.636126 -55.928983) (xy 56.613336 -55.879284)
			(xy 56.597879 -55.826838) (xy 56.590072 -55.772723) (xy 56.590074 -55.718047) (xy 56.597886 -55.663932)
			(xy 56.613347 -55.611488) (xy 56.63614 -55.56179) (xy 56.665799 -55.515857) (xy 56.683402 -55.494936)
			(xy 56.683656 -55.494682) (xy 56.68391 -55.494428) (xy 56.689492 -55.487338) (xy 56.695741 -55.470424)
			(xy 56.696102 -55.461408) (xy 56.696102 -55.394352) (xy 56.695719 -55.385338) (xy 56.689489 -55.368421)
			(xy 56.68391 -55.361332) (xy 56.683656 -55.361078) (xy 56.683402 -55.360824) (xy 56.672534 -55.348075)
			(xy 56.652821 -55.320984) (xy 56.644032 -55.306722) (xy 56.638444 -55.297578) (xy 56.621426 -55.285386)
			(xy 56.528462 -55.26532) (xy 56.507888 -55.269384) (xy 56.499252 -55.27548) (xy 56.475174 -55.291458)
			(xy 56.423248 -55.316806) (xy 56.368094 -55.334038) (xy 56.310973 -55.34276) (xy 56.282082 -55.343298)
			(xy 56.254831 -55.342831) (xy 56.200884 -55.335072) (xy 56.14859 -55.319715) (xy 56.099013 -55.297072)
			(xy 56.053164 -55.267605) (xy 56.011975 -55.231912) (xy 55.976284 -55.190721) (xy 55.946819 -55.144871)
			(xy 55.924179 -55.095293) (xy 55.908824 -55.042999) (xy 55.901068 -54.989051) (xy 53.692702 -54.989051)
			(xy 53.696115 -55.000394) (xy 53.704235 -55.05557) (xy 53.704744 -55.083456) (xy 53.704235 -55.111342)
			(xy 53.696115 -55.166518) (xy 53.680047 -55.219925) (xy 53.656375 -55.270422) (xy 53.625602 -55.316935)
			(xy 53.588385 -55.358472) (xy 53.545517 -55.394147) (xy 53.501762 -55.420851) (xy 54.224668 -55.420851)
			(xy 54.224668 -55.366349) (xy 54.232424 -55.312401) (xy 54.247779 -55.260107) (xy 54.270419 -55.210529)
			(xy 54.299884 -55.164679) (xy 54.335575 -55.123488) (xy 54.376764 -55.087795) (xy 54.422613 -55.058328)
			(xy 54.47219 -55.035685) (xy 54.524484 -55.020328) (xy 54.578431 -55.012569) (xy 54.605682 -55.012082)
			(xy 54.605936 -55.012082) (xy 54.632231 -55.012523) (xy 54.684321 -55.019772) (xy 54.734922 -55.034102)
			(xy 54.783078 -55.055241) (xy 54.827877 -55.082789) (xy 54.868472 -55.116225) (xy 54.886606 -55.135272)
			(xy 54.89418 -55.142711) (xy 54.913596 -55.151238) (xy 54.924198 -55.151782) (xy 54.998366 -55.151782)
			(xy 55.009002 -55.151406) (xy 55.028466 -55.142834) (xy 55.035958 -55.135272) (xy 55.054112 -55.116241)
			(xy 55.094687 -55.08278) (xy 55.139478 -55.055215) (xy 55.187633 -55.034071) (xy 55.238238 -55.019749)
			(xy 55.290332 -55.012522) (xy 55.316628 -55.012082) (xy 55.316882 -55.012082) (xy 55.344135 -55.012564)
			(xy 55.398086 -55.020319) (xy 55.450385 -55.035673) (xy 55.499966 -55.058314) (xy 55.54582 -55.08778)
			(xy 55.587014 -55.123473) (xy 55.622709 -55.164665) (xy 55.652178 -55.210518) (xy 55.674821 -55.260098)
			(xy 55.690177 -55.312396) (xy 55.697935 -55.366347) (xy 55.697935 -55.420853) (xy 55.690177 -55.474804)
			(xy 55.674821 -55.527102) (xy 55.652178 -55.576682) (xy 55.622709 -55.622535) (xy 55.587014 -55.663727)
			(xy 55.54582 -55.69942) (xy 55.499966 -55.728886) (xy 55.450385 -55.751527) (xy 55.398086 -55.766881)
			(xy 55.344135 -55.774636) (xy 55.316882 -55.775098) (xy 55.316628 -55.775098) (xy 55.290334 -55.774621)
			(xy 55.238246 -55.76738) (xy 55.187645 -55.753057) (xy 55.139489 -55.731925) (xy 55.094689 -55.704383)
			(xy 55.054093 -55.670953) (xy 55.035958 -55.651908) (xy 55.0284 -55.644451) (xy 55.008972 -55.635935)
			(xy 54.998366 -55.635398) (xy 54.924198 -55.635398) (xy 54.913567 -55.635815) (xy 54.894103 -55.644359)
			(xy 54.886606 -55.651908) (xy 54.868485 -55.670971) (xy 54.827901 -55.704427) (xy 54.783103 -55.731985)
			(xy 54.734942 -55.753123) (xy 54.684332 -55.767439) (xy 54.632234 -55.774661) (xy 54.605936 -55.775098)
			(xy 54.605682 -55.775098) (xy 54.578431 -55.774631) (xy 54.524484 -55.766872) (xy 54.47219 -55.751515)
			(xy 54.422613 -55.728872) (xy 54.376764 -55.699405) (xy 54.335575 -55.663712) (xy 54.299884 -55.622521)
			(xy 54.270419 -55.576671) (xy 54.247779 -55.527093) (xy 54.232424 -55.474799) (xy 54.224668 -55.420851)
			(xy 53.501762 -55.420851) (xy 53.497911 -55.423201) (xy 53.446582 -55.445013) (xy 53.392625 -55.459119)
			(xy 53.337188 -55.465219) (xy 53.281454 -55.463182) (xy 53.226611 -55.453052) (xy 53.173827 -55.435045)
			(xy 53.124227 -55.409544) (xy 53.078869 -55.377093) (xy 53.03872 -55.338384) (xy 53.004634 -55.294241)
			(xy 52.977338 -55.245606) (xy 52.957415 -55.193515) (xy 52.945289 -55.139078) (xy 52.941218 -55.083456)
			(xy 46.67037 -55.083456) (xy 46.635607 -55.105797) (xy 46.58603 -55.128439) (xy 46.533735 -55.143794)
			(xy 46.479787 -55.15155) (xy 46.425285 -55.15155) (xy 46.371337 -55.143794) (xy 46.319042 -55.128439)
			(xy 46.269465 -55.105797) (xy 46.223615 -55.076331) (xy 46.182424 -55.04064) (xy 46.146733 -54.999449)
			(xy 46.117267 -54.953599) (xy 46.094625 -54.904022) (xy 46.07927 -54.851727) (xy 46.071514 -54.797779)
			(xy 46.071028 -54.770528) (xy 42.939109 -54.770528) (xy 42.939462 -54.791102) (xy 42.938976 -54.818353)
			(xy 42.93122 -54.872301) (xy 42.915865 -54.924596) (xy 42.893223 -54.974173) (xy 42.863757 -55.020023)
			(xy 42.828066 -55.061214) (xy 42.786875 -55.096905) (xy 42.741025 -55.126371) (xy 42.691448 -55.149013)
			(xy 42.639153 -55.164368) (xy 42.585205 -55.172124) (xy 42.530703 -55.172124) (xy 42.476755 -55.164368)
			(xy 42.42446 -55.149013) (xy 42.374883 -55.126371) (xy 42.329033 -55.096905) (xy 42.287842 -55.061214)
			(xy 42.252151 -55.020023) (xy 42.222685 -54.974173) (xy 42.200043 -54.924596) (xy 42.184688 -54.872301)
			(xy 42.176932 -54.818353) (xy 42.176446 -54.791102) (xy 40.278488 -54.791102) (xy 40.275396 -54.812611)
			(xy 40.260041 -54.864906) (xy 40.237399 -54.914483) (xy 40.207933 -54.960333) (xy 40.172242 -55.001524)
			(xy 40.131051 -55.037215) (xy 40.085201 -55.066681) (xy 40.035624 -55.089323) (xy 39.983329 -55.104678)
			(xy 39.929381 -55.112434) (xy 39.874879 -55.112434) (xy 39.820931 -55.104678) (xy 39.768636 -55.089323)
			(xy 39.719059 -55.066681) (xy 39.673209 -55.037215) (xy 39.632018 -55.001524) (xy 39.596327 -54.960333)
			(xy 39.566861 -54.914483) (xy 39.544219 -54.864906) (xy 39.528864 -54.812611) (xy 39.521108 -54.758663)
			(xy 39.520622 -54.731412) (xy 31.012862 -54.731412) (xy 31.052434 -54.737105) (xy 31.104728 -54.752464)
			(xy 31.154304 -54.775108) (xy 31.200153 -54.804576) (xy 31.241343 -54.840269) (xy 31.277034 -54.881459)
			(xy 31.3065 -54.92731) (xy 31.329142 -54.976887) (xy 31.344498 -55.029181) (xy 31.352257 -55.083129)
			(xy 31.352744 -55.11038) (xy 31.352303 -55.137715) (xy 31.34449 -55.191824) (xy 31.329034 -55.244264)
			(xy 31.306252 -55.293961) (xy 31.276611 -55.339898) (xy 31.259018 -55.360824) (xy 31.258764 -55.361078)
			(xy 31.25851 -55.361332) (xy 31.252947 -55.368435) (xy 31.246686 -55.385339) (xy 31.246318 -55.394352)
			(xy 31.246318 -55.461408) (xy 31.246667 -55.470426) (xy 31.25292 -55.487343) (xy 31.25851 -55.494428)
			(xy 31.258764 -55.494682) (xy 31.259018 -55.494936) (xy 31.276599 -55.515874) (xy 31.306254 -55.561804)
			(xy 31.329045 -55.611498) (xy 31.344504 -55.663939) (xy 31.352315 -55.718049) (xy 31.352315 -55.722266)
			(xy 51.834032 -55.722266) (xy 51.838103 -55.666644) (xy 51.850229 -55.612207) (xy 51.870152 -55.560116)
			(xy 51.897448 -55.511481) (xy 51.931534 -55.467338) (xy 51.971683 -55.428629) (xy 52.017041 -55.396178)
			(xy 52.066641 -55.370677) (xy 52.119425 -55.35267) (xy 52.174268 -55.34254) (xy 52.230002 -55.340503)
			(xy 52.285439 -55.346603) (xy 52.339396 -55.360709) (xy 52.390725 -55.382521) (xy 52.438331 -55.411575)
			(xy 52.481199 -55.44725) (xy 52.518416 -55.488787) (xy 52.549189 -55.5353) (xy 52.572861 -55.585797)
			(xy 52.588929 -55.639204) (xy 52.597049 -55.69438) (xy 52.597558 -55.722266) (xy 52.597049 -55.750152)
			(xy 52.588929 -55.805328) (xy 52.572861 -55.858735) (xy 52.549189 -55.909232) (xy 52.518416 -55.955745)
			(xy 52.481199 -55.997282) (xy 52.438331 -56.032957) (xy 52.390725 -56.062011) (xy 52.339396 -56.083823)
			(xy 52.285439 -56.097929) (xy 52.230002 -56.104029) (xy 52.174268 -56.101992) (xy 52.119425 -56.091862)
			(xy 52.066641 -56.073855) (xy 52.017041 -56.048354) (xy 51.971683 -56.015903) (xy 51.931534 -55.977194)
			(xy 51.897448 -55.933051) (xy 51.870152 -55.884416) (xy 51.850229 -55.832325) (xy 51.838103 -55.777888)
			(xy 51.834032 -55.722266) (xy 31.352315 -55.722266) (xy 31.352317 -55.772721) (xy 31.34451 -55.826832)
			(xy 31.329055 -55.879273) (xy 31.306269 -55.92897) (xy 31.276617 -55.974902) (xy 31.259018 -55.995824)
			(xy 31.258764 -55.996078) (xy 31.25851 -55.996332) (xy 31.252947 -56.003435) (xy 31.246686 -56.020339)
			(xy 31.246318 -56.029352) (xy 31.246318 -56.096408) (xy 31.246667 -56.105426) (xy 31.25292 -56.122343)
			(xy 31.25851 -56.129428) (xy 31.258764 -56.129682) (xy 31.259018 -56.129936) (xy 31.276597 -56.150873)
			(xy 31.306236 -56.196807) (xy 31.329015 -56.246502) (xy 31.344466 -56.29894) (xy 31.352273 -56.353047)
			(xy 31.352744 -56.38038) (xy 31.352258 -56.407631) (xy 31.344502 -56.461579) (xy 31.329147 -56.513874)
			(xy 31.306505 -56.563451) (xy 31.277039 -56.609301) (xy 31.241348 -56.650492) (xy 31.200157 -56.686183)
			(xy 31.154307 -56.715649) (xy 31.10473 -56.738291) (xy 31.052435 -56.753646) (xy 30.998487 -56.761402)
			(xy 30.943985 -56.761402) (xy 30.890037 -56.753646) (xy 30.837742 -56.738291) (xy 30.788165 -56.715649)
			(xy 30.742315 -56.686183) (xy 30.701124 -56.650492) (xy 30.665433 -56.609301) (xy 30.635967 -56.563451)
			(xy 30.613325 -56.513874) (xy 30.59797 -56.461579) (xy 30.590214 -56.407631) (xy 30.589728 -56.38038)
			(xy 30.590211 -56.353047) (xy 30.598015 -56.29894) (xy 30.613462 -56.246501) (xy 30.636234 -56.196803)
			(xy 30.665865 -56.150864) (xy 30.683454 -56.129936) (xy 30.683708 -56.129682) (xy 30.683962 -56.129428)
			(xy 30.68955 -56.122343) (xy 30.695794 -56.105425) (xy 30.696154 -56.096408) (xy 30.696154 -56.029352)
			(xy 30.695782 -56.020336) (xy 30.689546 -56.003419) (xy 30.683962 -55.996332) (xy 30.683708 -55.996078)
			(xy 30.683454 -55.995824) (xy 30.665835 -55.974917) (xy 30.636184 -55.928981) (xy 30.613397 -55.879281)
			(xy 30.597942 -55.826837) (xy 30.590136 -55.772722) (xy 30.590138 -55.718048) (xy 30.597949 -55.663934)
			(xy 30.613408 -55.61149) (xy 30.636198 -55.561792) (xy 30.665853 -55.515858) (xy 30.683454 -55.494936)
			(xy 30.683708 -55.494682) (xy 30.683962 -55.494428) (xy 30.68955 -55.487343) (xy 30.695794 -55.470425)
			(xy 30.696154 -55.461408) (xy 30.696154 -55.394352) (xy 30.695782 -55.385336) (xy 30.689546 -55.368419)
			(xy 30.683962 -55.361332) (xy 30.683708 -55.361078) (xy 30.683454 -55.360824) (xy 30.672583 -55.348077)
			(xy 30.652872 -55.320985) (xy 30.644084 -55.306722) (xy 30.638496 -55.297578) (xy 30.621478 -55.285386)
			(xy 30.528514 -55.26532) (xy 30.50794 -55.269384) (xy 30.499304 -55.27548) (xy 30.475239 -55.291478)
			(xy 30.423308 -55.316822) (xy 30.368151 -55.334048) (xy 30.311026 -55.342763) (xy 30.282134 -55.343298)
			(xy 30.254879 -55.342857) (xy 30.200923 -55.335104) (xy 30.148619 -55.319751) (xy 30.099034 -55.29711)
			(xy 30.053175 -55.267642) (xy 30.011977 -55.231947) (xy 29.976279 -55.190752) (xy 29.946807 -55.144896)
			(xy 29.924161 -55.095313) (xy 29.908803 -55.043011) (xy 29.901045 -54.989055) (xy 27.692756 -54.989055)
			(xy 27.696167 -55.000394) (xy 27.704287 -55.05557) (xy 27.704796 -55.083456) (xy 27.704287 -55.111342)
			(xy 27.696167 -55.166518) (xy 27.680099 -55.219925) (xy 27.656427 -55.270422) (xy 27.625654 -55.316935)
			(xy 27.588437 -55.358472) (xy 27.545569 -55.394147) (xy 27.501807 -55.420855) (xy 28.224645 -55.420855)
			(xy 28.224645 -55.366345) (xy 28.232403 -55.312389) (xy 28.247761 -55.260087) (xy 28.270407 -55.210504)
			(xy 28.299879 -55.164648) (xy 28.335577 -55.123453) (xy 28.376775 -55.087758) (xy 28.422634 -55.05829)
			(xy 28.472219 -55.035649) (xy 28.524523 -55.020296) (xy 28.578479 -55.012543) (xy 28.605734 -55.012082)
			(xy 28.605988 -55.012082) (xy 28.632282 -55.012554) (xy 28.68437 -55.019798) (xy 28.734971 -55.034121)
			(xy 28.783127 -55.055254) (xy 28.827927 -55.082797) (xy 28.868523 -55.116227) (xy 28.886658 -55.135272)
			(xy 28.89425 -55.142689) (xy 28.913652 -55.151229) (xy 28.92425 -55.151782) (xy 28.998418 -55.151782)
			(xy 29.009051 -55.151379) (xy 29.028516 -55.142826) (xy 29.03601 -55.135272) (xy 29.054139 -55.116216)
			(xy 29.094719 -55.082757) (xy 29.139515 -55.055196) (xy 29.187675 -55.034056) (xy 29.238285 -55.01974)
			(xy 29.290382 -55.012518) (xy 29.31668 -55.012082) (xy 29.316934 -55.012082) (xy 29.344183 -55.012591)
			(xy 29.398125 -55.020351) (xy 29.450415 -55.035708) (xy 29.499986 -55.058351) (xy 29.545831 -55.087817)
			(xy 29.587016 -55.123508) (xy 29.622703 -55.164696) (xy 29.652165 -55.210544) (xy 29.674803 -55.260117)
			(xy 29.690156 -55.312408) (xy 29.697912 -55.366351) (xy 29.697912 -55.420849) (xy 29.690156 -55.474792)
			(xy 29.674803 -55.527083) (xy 29.652165 -55.576656) (xy 29.622703 -55.622504) (xy 29.587016 -55.663692)
			(xy 29.545831 -55.699383) (xy 29.499986 -55.728849) (xy 29.450415 -55.751492) (xy 29.398125 -55.766849)
			(xy 29.344183 -55.774609) (xy 29.316934 -55.775098) (xy 29.31668 -55.775098) (xy 29.290385 -55.774653)
			(xy 29.238295 -55.767405) (xy 29.187694 -55.753076) (xy 29.139538 -55.731938) (xy 29.094738 -55.704391)
			(xy 29.054144 -55.670956) (xy 29.03601 -55.651908) (xy 29.028433 -55.644474) (xy 29.009019 -55.635944)
			(xy 28.998418 -55.635398) (xy 28.92425 -55.635398) (xy 28.913616 -55.635789) (xy 28.894152 -55.644351)
			(xy 28.886658 -55.651908) (xy 28.868561 -55.670995) (xy 28.827972 -55.704448) (xy 28.783169 -55.732003)
			(xy 28.735003 -55.753137) (xy 28.684388 -55.767448) (xy 28.632287 -55.774664) (xy 28.605988 -55.775098)
			(xy 28.605734 -55.775098) (xy 28.578479 -55.774657) (xy 28.524523 -55.766904) (xy 28.472219 -55.751551)
			(xy 28.422634 -55.72891) (xy 28.376775 -55.699442) (xy 28.335577 -55.663747) (xy 28.299879 -55.622552)
			(xy 28.270407 -55.576696) (xy 28.247761 -55.527113) (xy 28.232403 -55.474811) (xy 28.224645 -55.420855)
			(xy 27.501807 -55.420855) (xy 27.497963 -55.423201) (xy 27.446634 -55.445013) (xy 27.392677 -55.459119)
			(xy 27.33724 -55.465219) (xy 27.281506 -55.463182) (xy 27.226663 -55.453052) (xy 27.173879 -55.435045)
			(xy 27.124279 -55.409544) (xy 27.078921 -55.377093) (xy 27.038772 -55.338384) (xy 27.004686 -55.294241)
			(xy 26.97739 -55.245606) (xy 26.957467 -55.193515) (xy 26.945341 -55.139078) (xy 26.94127 -55.083456)
			(xy 20.670957 -55.083456) (xy 20.665049 -55.088089) (xy 20.614875 -55.116419) (xy 20.56101 -55.136879)
			(xy 20.504681 -55.149003) (xy 20.475956 -55.151274) (xy 20.46605 -55.151782) (xy 20.448524 -55.160164)
			(xy 20.44192 -55.167276) (xy 20.394422 -55.217568) (xy 20.387564 -55.22468) (xy 20.380452 -55.242714)
			(xy 20.380452 -55.722266) (xy 25.834084 -55.722266) (xy 25.838155 -55.666644) (xy 25.850281 -55.612207)
			(xy 25.870204 -55.560116) (xy 25.8975 -55.511481) (xy 25.931586 -55.467338) (xy 25.971735 -55.428629)
			(xy 26.017093 -55.396178) (xy 26.066693 -55.370677) (xy 26.119477 -55.35267) (xy 26.17432 -55.34254)
			(xy 26.230054 -55.340503) (xy 26.285491 -55.346603) (xy 26.339448 -55.360709) (xy 26.390777 -55.382521)
			(xy 26.438383 -55.411575) (xy 26.481251 -55.44725) (xy 26.518468 -55.488787) (xy 26.549241 -55.5353)
			(xy 26.572913 -55.585797) (xy 26.588981 -55.639204) (xy 26.597101 -55.69438) (xy 26.59761 -55.722266)
			(xy 26.597101 -55.750152) (xy 26.588981 -55.805328) (xy 26.572913 -55.858735) (xy 26.549241 -55.909232)
			(xy 26.518468 -55.955745) (xy 26.481251 -55.997282) (xy 26.438383 -56.032957) (xy 26.390777 -56.062011)
			(xy 26.339448 -56.083823) (xy 26.285491 -56.097929) (xy 26.230054 -56.104029) (xy 26.17432 -56.101992)
			(xy 26.119477 -56.091862) (xy 26.066693 -56.073855) (xy 26.017093 -56.048354) (xy 25.971735 -56.015903)
			(xy 25.931586 -55.977194) (xy 25.8975 -55.933051) (xy 25.870204 -55.884416) (xy 25.850281 -55.832325)
			(xy 25.838155 -55.777888) (xy 25.834084 -55.722266) (xy 20.380452 -55.722266) (xy 20.380452 -56.353456)
			(xy 26.94127 -56.353456) (xy 26.945341 -56.297834) (xy 26.957467 -56.243397) (xy 26.97739 -56.191306)
			(xy 27.004686 -56.142671) (xy 27.038772 -56.098528) (xy 27.078921 -56.059819) (xy 27.124279 -56.027368)
			(xy 27.173879 -56.001867) (xy 27.226663 -55.98386) (xy 27.281506 -55.97373) (xy 27.33724 -55.971693)
			(xy 27.392677 -55.977793) (xy 27.446634 -55.991899) (xy 27.497963 -56.013711) (xy 27.545569 -56.042765)
			(xy 27.588437 -56.07844) (xy 27.625654 -56.119977) (xy 27.656427 -56.16649) (xy 27.680099 -56.216987)
			(xy 27.696167 -56.270394) (xy 27.704287 -56.32557) (xy 27.704796 -56.353456) (xy 27.704287 -56.381342)
			(xy 27.696167 -56.436518) (xy 27.680099 -56.489925) (xy 27.656427 -56.540422) (xy 27.625654 -56.586935)
			(xy 27.588437 -56.628472) (xy 27.545569 -56.664147) (xy 27.497963 -56.693201) (xy 27.446634 -56.715013)
			(xy 27.392677 -56.729119) (xy 27.33724 -56.735219) (xy 27.281506 -56.733182) (xy 27.226663 -56.723052)
			(xy 27.173879 -56.705045) (xy 27.124279 -56.679544) (xy 27.078921 -56.647093) (xy 27.038772 -56.608384)
			(xy 27.004686 -56.564241) (xy 26.97739 -56.515606) (xy 26.957467 -56.463515) (xy 26.945341 -56.409078)
			(xy 26.94127 -56.353456) (xy 20.380452 -56.353456) (xy 20.380452 -57.48528) (xy 30.605982 -57.48528)
			(xy 30.610053 -57.429658) (xy 30.622179 -57.375221) (xy 30.642102 -57.32313) (xy 30.669398 -57.274495)
			(xy 30.703484 -57.230352) (xy 30.743633 -57.191643) (xy 30.788991 -57.159192) (xy 30.838591 -57.133691)
			(xy 30.891375 -57.115684) (xy 30.946218 -57.105554) (xy 31.001952 -57.103517) (xy 31.057389 -57.109617)
			(xy 31.111346 -57.123723) (xy 31.162675 -57.145535) (xy 31.210281 -57.174589) (xy 31.253149 -57.210264)
			(xy 31.290366 -57.251801) (xy 31.321139 -57.298314) (xy 31.344811 -57.348811) (xy 31.360879 -57.402218)
			(xy 31.368999 -57.457394) (xy 31.369508 -57.48528) (xy 31.368999 -57.513166) (xy 31.360879 -57.568342)
			(xy 31.344811 -57.621749) (xy 31.321139 -57.672246) (xy 31.290366 -57.718759) (xy 31.253149 -57.760296)
			(xy 31.210281 -57.795971) (xy 31.162675 -57.825025) (xy 31.111346 -57.846837) (xy 31.057389 -57.860943)
			(xy 31.001952 -57.867043) (xy 30.946218 -57.865006) (xy 30.891375 -57.854876) (xy 30.838591 -57.836869)
			(xy 30.788991 -57.811368) (xy 30.743633 -57.778917) (xy 30.703484 -57.740208) (xy 30.669398 -57.696065)
			(xy 30.642102 -57.64743) (xy 30.622179 -57.595339) (xy 30.610053 -57.540902) (xy 30.605982 -57.48528)
			(xy 20.380452 -57.48528) (xy 20.380452 -58.072274) (xy 25.993596 -58.072274) (xy 25.997667 -58.016652)
			(xy 26.009793 -57.962215) (xy 26.029716 -57.910124) (xy 26.057012 -57.861489) (xy 26.091098 -57.817346)
			(xy 26.131247 -57.778637) (xy 26.176605 -57.746186) (xy 26.226205 -57.720685) (xy 26.278989 -57.702678)
			(xy 26.333832 -57.692548) (xy 26.389566 -57.690511) (xy 26.445003 -57.696611) (xy 26.49896 -57.710717)
			(xy 26.550289 -57.732529) (xy 26.597895 -57.761583) (xy 26.640763 -57.797258) (xy 26.67798 -57.838795)
			(xy 26.708753 -57.885308) (xy 26.732425 -57.935805) (xy 26.748493 -57.989212) (xy 26.756613 -58.044388)
			(xy 26.757122 -58.072274) (xy 26.757052 -58.076084) (xy 31.358076 -58.076084) (xy 31.362147 -58.020462)
			(xy 31.374273 -57.966025) (xy 31.394196 -57.913934) (xy 31.421492 -57.865299) (xy 31.455578 -57.821156)
			(xy 31.495727 -57.782447) (xy 31.541085 -57.749996) (xy 31.590685 -57.724495) (xy 31.643469 -57.706488)
			(xy 31.698312 -57.696358) (xy 31.754046 -57.694321) (xy 31.809483 -57.700421) (xy 31.86344 -57.714527)
			(xy 31.914769 -57.736339) (xy 31.962375 -57.765393) (xy 32.005243 -57.801068) (xy 32.04246 -57.842605)
			(xy 32.058796 -57.867296) (xy 33.64306 -57.867296) (xy 33.647131 -57.811674) (xy 33.659257 -57.757237)
			(xy 33.67918 -57.705146) (xy 33.706476 -57.656511) (xy 33.740562 -57.612368) (xy 33.780711 -57.573659)
			(xy 33.826069 -57.541208) (xy 33.875669 -57.515707) (xy 33.928453 -57.4977) (xy 33.983296 -57.48757)
			(xy 34.03903 -57.485533) (xy 34.094467 -57.491633) (xy 34.148424 -57.505739) (xy 34.199753 -57.527551)
			(xy 34.247359 -57.556605) (xy 34.290227 -57.59228) (xy 34.327444 -57.633817) (xy 34.358217 -57.68033)
			(xy 34.381889 -57.730827) (xy 34.397957 -57.784234) (xy 34.406077 -57.83941) (xy 34.406586 -57.867296)
			(xy 34.406077 -57.895182) (xy 34.397957 -57.950358) (xy 34.381889 -58.003765) (xy 34.358217 -58.054262)
			(xy 34.327444 -58.100775) (xy 34.290227 -58.142312) (xy 34.247359 -58.177987) (xy 34.199753 -58.207041)
			(xy 34.148424 -58.228853) (xy 34.094467 -58.242959) (xy 34.03903 -58.249059) (xy 33.983296 -58.247022)
			(xy 33.928453 -58.236892) (xy 33.875669 -58.218885) (xy 33.826069 -58.193384) (xy 33.780711 -58.160933)
			(xy 33.740562 -58.122224) (xy 33.706476 -58.078081) (xy 33.67918 -58.029446) (xy 33.659257 -57.977355)
			(xy 33.647131 -57.922918) (xy 33.64306 -57.867296) (xy 32.058796 -57.867296) (xy 32.073233 -57.889118)
			(xy 32.096905 -57.939615) (xy 32.112973 -57.993022) (xy 32.121093 -58.048198) (xy 32.121602 -58.076084)
			(xy 32.121093 -58.10397) (xy 32.112973 -58.159146) (xy 32.096905 -58.212553) (xy 32.073233 -58.26305)
			(xy 32.04246 -58.309563) (xy 32.005243 -58.3511) (xy 31.962375 -58.386775) (xy 31.914769 -58.415829)
			(xy 31.86344 -58.437641) (xy 31.809483 -58.451747) (xy 31.754046 -58.457847) (xy 31.698312 -58.45581)
			(xy 31.643469 -58.44568) (xy 31.590685 -58.427673) (xy 31.541085 -58.402172) (xy 31.495727 -58.369721)
			(xy 31.455578 -58.331012) (xy 31.421492 -58.286869) (xy 31.394196 -58.238234) (xy 31.374273 -58.186143)
			(xy 31.362147 -58.131706) (xy 31.358076 -58.076084) (xy 26.757052 -58.076084) (xy 26.756613 -58.10016)
			(xy 26.748493 -58.155336) (xy 26.732425 -58.208743) (xy 26.708753 -58.25924) (xy 26.67798 -58.305753)
			(xy 26.640763 -58.34729) (xy 26.597895 -58.382965) (xy 26.550289 -58.412019) (xy 26.49896 -58.433831)
			(xy 26.445003 -58.447937) (xy 26.389566 -58.454037) (xy 26.333832 -58.452) (xy 26.278989 -58.44187)
			(xy 26.226205 -58.423863) (xy 26.176605 -58.398362) (xy 26.131247 -58.365911) (xy 26.091098 -58.327202)
			(xy 26.057012 -58.283059) (xy 26.029716 -58.234424) (xy 26.009793 -58.182333) (xy 25.997667 -58.127896)
			(xy 25.993596 -58.072274) (xy 20.380452 -58.072274) (xy 20.380452 -58.561224) (xy 32.56229 -58.561224)
			(xy 32.566361 -58.505602) (xy 32.578487 -58.451165) (xy 32.59841 -58.399074) (xy 32.625706 -58.350439)
			(xy 32.659792 -58.306296) (xy 32.699941 -58.267587) (xy 32.745299 -58.235136) (xy 32.794899 -58.209635)
			(xy 32.847683 -58.191628) (xy 32.902526 -58.181498) (xy 32.95826 -58.179461) (xy 33.013697 -58.185561)
			(xy 33.067654 -58.199667) (xy 33.118983 -58.221479) (xy 33.166589 -58.250533) (xy 33.209457 -58.286208)
			(xy 33.246674 -58.327745) (xy 33.277447 -58.374258) (xy 33.301119 -58.424755) (xy 33.308629 -58.449718)
			(xy 34.80892 -58.449718) (xy 34.812991 -58.394096) (xy 34.825117 -58.339659) (xy 34.84504 -58.287568)
			(xy 34.872336 -58.238933) (xy 34.906422 -58.19479) (xy 34.946571 -58.156081) (xy 34.991929 -58.12363)
			(xy 35.041529 -58.098129) (xy 35.094313 -58.080122) (xy 35.149156 -58.069992) (xy 35.20489 -58.067955)
			(xy 35.260327 -58.074055) (xy 35.314284 -58.088161) (xy 35.365613 -58.109973) (xy 35.413219 -58.139027)
			(xy 35.456087 -58.174702) (xy 35.493304 -58.216239) (xy 35.524077 -58.262752) (xy 35.547749 -58.313249)
			(xy 35.563817 -58.366656) (xy 35.571937 -58.421832) (xy 35.572446 -58.449718) (xy 35.571937 -58.477604)
			(xy 35.563817 -58.53278) (xy 35.547749 -58.586187) (xy 35.524077 -58.636684) (xy 35.493304 -58.683197)
			(xy 35.456087 -58.724734) (xy 35.448072 -58.731404) (xy 39.520622 -58.731404) (xy 39.52112 -58.704071)
			(xy 39.528921 -58.649965) (xy 39.544364 -58.597526) (xy 39.567133 -58.547828) (xy 39.596761 -58.501888)
			(xy 39.614348 -58.48096) (xy 39.614602 -58.480706) (xy 39.614856 -58.480452) (xy 39.620434 -58.47336)
			(xy 39.626684 -58.456447) (xy 39.627048 -58.447432) (xy 39.627048 -58.380376) (xy 39.626714 -58.371357)
			(xy 39.620452 -58.354439) (xy 39.614856 -58.347356) (xy 39.614602 -58.347102) (xy 39.614348 -58.346848)
			(xy 39.596752 -58.325922) (xy 39.567101 -58.279989) (xy 39.544313 -58.230293) (xy 39.528857 -58.177851)
			(xy 39.521048 -58.123739) (xy 39.521048 -58.069067) (xy 39.528855 -58.014955) (xy 39.544311 -57.962513)
			(xy 39.567098 -57.912816) (xy 39.596749 -57.866882) (xy 39.614348 -57.84596) (xy 39.614602 -57.845706)
			(xy 39.614856 -57.845452) (xy 39.620434 -57.83836) (xy 39.626684 -57.821447) (xy 39.627048 -57.812432)
			(xy 39.627048 -57.745376) (xy 39.626714 -57.736357) (xy 39.620452 -57.719439) (xy 39.614856 -57.712356)
			(xy 39.614602 -57.712102) (xy 39.614348 -57.711848) (xy 39.596752 -57.690922) (xy 39.567101 -57.644989)
			(xy 39.544313 -57.595293) (xy 39.528857 -57.542851) (xy 39.521048 -57.488739) (xy 39.521048 -57.434067)
			(xy 39.528855 -57.379955) (xy 39.544311 -57.327513) (xy 39.567098 -57.277816) (xy 39.596749 -57.231882)
			(xy 39.614348 -57.21096) (xy 39.614602 -57.210706) (xy 39.614856 -57.210452) (xy 39.620434 -57.20336)
			(xy 39.626684 -57.186447) (xy 39.627048 -57.177432) (xy 39.627048 -57.110376) (xy 39.626714 -57.101357)
			(xy 39.620452 -57.084439) (xy 39.614856 -57.077356) (xy 39.614602 -57.077102) (xy 39.614348 -57.076848)
			(xy 39.596772 -57.055909) (xy 39.56713 -57.009976) (xy 39.544349 -56.960282) (xy 39.528898 -56.907844)
			(xy 39.521092 -56.853737) (xy 39.520622 -56.826404) (xy 39.521108 -56.799153) (xy 39.528864 -56.745205)
			(xy 39.544219 -56.69291) (xy 39.566861 -56.643333) (xy 39.596327 -56.597483) (xy 39.632018 -56.556292)
			(xy 39.673209 -56.520601) (xy 39.719059 -56.491135) (xy 39.768636 -56.468493) (xy 39.820931 -56.453138)
			(xy 39.874879 -56.445382) (xy 39.929381 -56.445382) (xy 39.983329 -56.453138) (xy 40.035624 -56.468493)
			(xy 40.085201 -56.491135) (xy 40.131051 -56.520601) (xy 40.172242 -56.556292) (xy 40.207933 -56.597483)
			(xy 40.237399 -56.643333) (xy 40.260041 -56.69291) (xy 40.275396 -56.745205) (xy 40.283152 -56.799153)
			(xy 40.283638 -56.826404) (xy 40.283154 -56.853737) (xy 40.275351 -56.907844) (xy 40.259906 -56.960284)
			(xy 40.237134 -57.009982) (xy 40.207501 -57.055921) (xy 40.189912 -57.076848) (xy 40.189658 -57.077102)
			(xy 40.189404 -57.077356) (xy 40.18383 -57.084451) (xy 40.177576 -57.101361) (xy 40.177212 -57.110376)
			(xy 40.177212 -57.177432) (xy 40.177551 -57.186451) (xy 40.183811 -57.203368) (xy 40.189404 -57.210452)
			(xy 40.189658 -57.210706) (xy 40.189912 -57.21096) (xy 40.207517 -57.231879) (xy 40.237171 -57.277812)
			(xy 40.259961 -57.327509) (xy 40.275419 -57.379953) (xy 40.283227 -57.434066) (xy 40.283227 -57.48874)
			(xy 40.275417 -57.542853) (xy 40.259959 -57.595296) (xy 40.237168 -57.644994) (xy 40.207513 -57.690926)
			(xy 40.189912 -57.711848) (xy 40.189658 -57.712102) (xy 40.189404 -57.712356) (xy 40.18383 -57.719451)
			(xy 40.177576 -57.736361) (xy 40.177212 -57.745376) (xy 40.177212 -57.812432) (xy 40.177551 -57.821451)
			(xy 40.183811 -57.838368) (xy 40.189404 -57.845452) (xy 40.189658 -57.845706) (xy 40.189912 -57.84596)
			(xy 40.207517 -57.866879) (xy 40.237171 -57.912812) (xy 40.259961 -57.962509) (xy 40.275419 -58.014953)
			(xy 40.283227 -58.069066) (xy 40.283227 -58.12374) (xy 40.275417 -58.177853) (xy 40.259959 -58.230296)
			(xy 40.237168 -58.279994) (xy 40.207513 -58.325926) (xy 40.189912 -58.346848) (xy 40.189658 -58.347102)
			(xy 40.189404 -58.347356) (xy 40.18383 -58.354451) (xy 40.177576 -58.371361) (xy 40.177212 -58.380376)
			(xy 40.177212 -58.447432) (xy 40.177551 -58.456451) (xy 40.183811 -58.473368) (xy 40.189404 -58.480452)
			(xy 40.189658 -58.480706) (xy 40.189912 -58.48096) (xy 40.207501 -58.501888) (xy 40.237139 -58.547825)
			(xy 40.259916 -58.597522) (xy 40.275365 -58.649962) (xy 40.283169 -58.70407) (xy 40.283638 -58.731404)
			(xy 40.283152 -58.758655) (xy 40.278488 -58.791094) (xy 42.176446 -58.791094) (xy 42.176932 -58.763761)
			(xy 42.184735 -58.709654) (xy 42.200181 -58.657215) (xy 42.222952 -58.607517) (xy 42.252583 -58.561578)
			(xy 42.270172 -58.54065) (xy 42.270426 -58.540396) (xy 42.27068 -58.540142) (xy 42.276264 -58.533054)
			(xy 42.28251 -58.516138) (xy 42.282872 -58.507122) (xy 42.282872 -58.440066) (xy 42.282537 -58.431047)
			(xy 42.276275 -58.41413) (xy 42.27068 -58.407046) (xy 42.270426 -58.406792) (xy 42.270172 -58.406538)
			(xy 42.252566 -58.385621) (xy 42.222913 -58.339687) (xy 42.200124 -58.289989) (xy 42.184667 -58.237546)
			(xy 42.176859 -58.183432) (xy 42.17686 -58.128759) (xy 42.184669 -58.074646) (xy 42.200127 -58.022203)
			(xy 42.222917 -57.972505) (xy 42.252571 -57.926572) (xy 42.270172 -57.90565) (xy 42.270426 -57.905396)
			(xy 42.27068 -57.905142) (xy 42.276264 -57.898054) (xy 42.28251 -57.881138) (xy 42.282872 -57.872122)
			(xy 42.282872 -57.805066) (xy 42.282537 -57.796047) (xy 42.276275 -57.77913) (xy 42.27068 -57.772046)
			(xy 42.270426 -57.771792) (xy 42.270172 -57.771538) (xy 42.25258 -57.750612) (xy 42.222942 -57.704675)
			(xy 42.200166 -57.654977) (xy 42.184718 -57.602537) (xy 42.176915 -57.548428) (xy 42.176446 -57.521094)
			(xy 42.176446 -57.52084) (xy 42.176917 -57.494545) (xy 42.184158 -57.442457) (xy 42.19848 -57.391855)
			(xy 42.219613 -57.343698) (xy 42.247157 -57.298899) (xy 42.280589 -57.258304) (xy 42.299636 -57.24017)
			(xy 42.30708 -57.2326) (xy 42.315606 -57.213181) (xy 42.316146 -57.202578) (xy 42.316146 -57.12841)
			(xy 42.315709 -57.117782) (xy 42.307178 -57.098318) (xy 42.299636 -57.090818) (xy 42.280587 -57.072683)
			(xy 42.247128 -57.032103) (xy 42.219567 -56.987308) (xy 42.198427 -56.939149) (xy 42.184108 -56.888541)
			(xy 42.176884 -56.836445) (xy 42.176446 -56.810148) (xy 42.176446 -56.809894) (xy 42.176932 -56.782643)
			(xy 42.184688 -56.728695) (xy 42.200043 -56.6764) (xy 42.222685 -56.626823) (xy 42.252151 -56.580973)
			(xy 42.287842 -56.539782) (xy 42.329033 -56.504091) (xy 42.374883 -56.474625) (xy 42.42446 -56.451983)
			(xy 42.476755 -56.436628) (xy 42.530703 -56.428872) (xy 42.585205 -56.428872) (xy 42.639153 -56.436628)
			(xy 42.691448 -56.451983) (xy 42.741025 -56.474625) (xy 42.786875 -56.504091) (xy 42.828066 -56.539782)
			(xy 42.863757 -56.580973) (xy 42.893223 -56.626823) (xy 42.915865 -56.6764) (xy 42.93122 -56.728695)
			(xy 42.938976 -56.782643) (xy 42.939462 -56.809894) (xy 42.939462 -56.810148) (xy 42.939047 -56.836445)
			(xy 42.931795 -56.888536) (xy 42.917461 -56.939138) (xy 42.896317 -56.987294) (xy 42.868764 -57.032093)
			(xy 42.835323 -57.072685) (xy 42.816272 -57.090818) (xy 42.808835 -57.098393) (xy 42.800305 -57.117808)
			(xy 42.799762 -57.12841) (xy 42.799762 -57.202578) (xy 42.800203 -57.213206) (xy 42.808731 -57.23267)
			(xy 42.816272 -57.24017) (xy 42.835317 -57.25831) (xy 42.868775 -57.298889) (xy 42.896337 -57.343683)
			(xy 42.917478 -57.39184) (xy 42.931798 -57.442448) (xy 42.93521 -57.467053) (xy 43.118469 -57.467053)
			(xy 43.118469 -57.412547) (xy 43.126227 -57.358595) (xy 43.141584 -57.306296) (xy 43.164228 -57.256716)
			(xy 43.193698 -57.210863) (xy 43.229394 -57.169671) (xy 43.270589 -57.133979) (xy 43.316444 -57.104513)
			(xy 43.366026 -57.081873) (xy 43.418326 -57.06652) (xy 43.472279 -57.058767) (xy 43.499532 -57.058306)
			(xy 43.499786 -57.058306) (xy 43.526081 -57.058772) (xy 43.578169 -57.066016) (xy 43.62877 -57.08034)
			(xy 43.676927 -57.101474) (xy 43.721726 -57.129018) (xy 43.762322 -57.16245) (xy 43.780456 -57.181496)
			(xy 43.788008 -57.18896) (xy 43.807441 -57.197472) (xy 43.818048 -57.198006) (xy 43.892216 -57.198006)
			(xy 43.902848 -57.197595) (xy 43.922312 -57.189047) (xy 43.929808 -57.181496) (xy 43.947923 -57.162427)
			(xy 43.988508 -57.128972) (xy 44.033307 -57.101414) (xy 44.08147 -57.080277) (xy 44.132081 -57.065963)
			(xy 44.18418 -57.058742) (xy 44.210478 -57.058306) (xy 44.210732 -57.058306) (xy 44.237983 -57.058766)
			(xy 44.291929 -57.066526) (xy 44.327072 -57.076848) (xy 45.138594 -57.076848) (xy 45.139066 -57.049514)
			(xy 45.146874 -56.995408) (xy 45.162324 -56.942969) (xy 45.185098 -56.893271) (xy 45.214731 -56.847332)
			(xy 45.23232 -56.826404) (xy 45.232574 -56.82615) (xy 45.232828 -56.825896) (xy 45.238425 -56.818817)
			(xy 45.244665 -56.801894) (xy 45.24502 -56.792876) (xy 45.24502 -56.72582) (xy 45.244649 -56.716805)
			(xy 45.238411 -56.699888) (xy 45.232828 -56.6928) (xy 45.232574 -56.692546) (xy 45.23232 -56.692292)
			(xy 45.214713 -56.671378) (xy 45.185077 -56.625438) (xy 45.162303 -56.575737) (xy 45.146858 -56.523294)
			(xy 45.13906 -56.469183) (xy 45.138594 -56.441848) (xy 45.13908 -56.414597) (xy 45.146836 -56.360649)
			(xy 45.162191 -56.308354) (xy 45.184833 -56.258777) (xy 45.214299 -56.212927) (xy 45.24999 -56.171736)
			(xy 45.291181 -56.136045) (xy 45.337031 -56.106579) (xy 45.386608 -56.083937) (xy 45.438903 -56.068582)
			(xy 45.492851 -56.060826) (xy 45.547353 -56.060826) (xy 45.601301 -56.068582) (xy 45.653596 -56.083937)
			(xy 45.703173 -56.106579) (xy 45.749023 -56.136045) (xy 45.790214 -56.171736) (xy 45.825905 -56.212927)
			(xy 45.855371 -56.258777) (xy 45.878013 -56.308354) (xy 45.891256 -56.353456) (xy 52.941218 -56.353456)
			(xy 52.945289 -56.297834) (xy 52.957415 -56.243397) (xy 52.977338 -56.191306) (xy 53.004634 -56.142671)
			(xy 53.03872 -56.098528) (xy 53.078869 -56.059819) (xy 53.124227 -56.027368) (xy 53.173827 -56.001867)
			(xy 53.226611 -55.98386) (xy 53.281454 -55.97373) (xy 53.337188 -55.971693) (xy 53.392625 -55.977793)
			(xy 53.446582 -55.991899) (xy 53.497911 -56.013711) (xy 53.545517 -56.042765) (xy 53.588385 -56.07844)
			(xy 53.625602 -56.119977) (xy 53.656375 -56.16649) (xy 53.680047 -56.216987) (xy 53.696115 -56.270394)
			(xy 53.704235 -56.32557) (xy 53.704744 -56.353456) (xy 53.704235 -56.381342) (xy 53.696115 -56.436518)
			(xy 53.680047 -56.489925) (xy 53.656375 -56.540422) (xy 53.625602 -56.586935) (xy 53.588385 -56.628472)
			(xy 53.545517 -56.664147) (xy 53.497911 -56.693201) (xy 53.446582 -56.715013) (xy 53.392625 -56.729119)
			(xy 53.337188 -56.735219) (xy 53.281454 -56.733182) (xy 53.226611 -56.723052) (xy 53.173827 -56.705045)
			(xy 53.124227 -56.679544) (xy 53.078869 -56.647093) (xy 53.03872 -56.608384) (xy 53.004634 -56.564241)
			(xy 52.977338 -56.515606) (xy 52.957415 -56.463515) (xy 52.945289 -56.409078) (xy 52.941218 -56.353456)
			(xy 45.891256 -56.353456) (xy 45.893368 -56.360649) (xy 45.901124 -56.414597) (xy 45.90161 -56.441848)
			(xy 45.901135 -56.469181) (xy 45.893327 -56.523288) (xy 45.877878 -56.575727) (xy 45.855105 -56.625425)
			(xy 45.825473 -56.671364) (xy 45.807884 -56.692292) (xy 45.80763 -56.692546) (xy 45.807376 -56.6928)
			(xy 45.801781 -56.69988) (xy 45.79554 -56.716802) (xy 45.795184 -56.72582) (xy 45.795184 -56.792876)
			(xy 45.795556 -56.801891) (xy 45.801794 -56.818808) (xy 45.807376 -56.825896) (xy 45.80763 -56.82615)
			(xy 45.807884 -56.826404) (xy 45.825489 -56.847319) (xy 45.855126 -56.893259) (xy 45.8779 -56.942959)
			(xy 45.893345 -56.995402) (xy 45.901144 -57.049513) (xy 45.90161 -57.076848) (xy 45.901124 -57.104099)
			(xy 45.893368 -57.158047) (xy 45.878013 -57.210342) (xy 45.855371 -57.259919) (xy 45.825905 -57.305769)
			(xy 45.790214 -57.34696) (xy 45.749023 -57.382651) (xy 45.703173 -57.412117) (xy 45.653596 -57.434759)
			(xy 45.601301 -57.450114) (xy 45.547353 -57.45787) (xy 45.492851 -57.45787) (xy 45.438903 -57.450114)
			(xy 45.386608 -57.434759) (xy 45.337031 -57.412117) (xy 45.291181 -57.382651) (xy 45.24999 -57.34696)
			(xy 45.214299 -57.305769) (xy 45.184833 -57.259919) (xy 45.162191 -57.210342) (xy 45.146836 -57.158047)
			(xy 45.13908 -57.104099) (xy 45.138594 -57.076848) (xy 44.327072 -57.076848) (xy 44.344222 -57.081885)
			(xy 44.393797 -57.104529) (xy 44.439645 -57.133997) (xy 44.480833 -57.16969) (xy 44.516522 -57.210881)
			(xy 44.545987 -57.256731) (xy 44.568626 -57.306308) (xy 44.58398 -57.358602) (xy 44.591736 -57.412549)
			(xy 44.591736 -57.467051) (xy 44.589115 -57.48528) (xy 56.60593 -57.48528) (xy 56.610001 -57.429658)
			(xy 56.622127 -57.375221) (xy 56.64205 -57.32313) (xy 56.669346 -57.274495) (xy 56.703432 -57.230352)
			(xy 56.743581 -57.191643) (xy 56.788939 -57.159192) (xy 56.838539 -57.133691) (xy 56.891323 -57.115684)
			(xy 56.946166 -57.105554) (xy 57.0019 -57.103517) (xy 57.057337 -57.109617) (xy 57.111294 -57.123723)
			(xy 57.162623 -57.145535) (xy 57.210229 -57.174589) (xy 57.253097 -57.210264) (xy 57.290314 -57.251801)
			(xy 57.321087 -57.298314) (xy 57.344759 -57.348811) (xy 57.360827 -57.402218) (xy 57.368947 -57.457394)
			(xy 57.369456 -57.48528) (xy 57.368947 -57.513166) (xy 57.360827 -57.568342) (xy 57.344759 -57.621749)
			(xy 57.321087 -57.672246) (xy 57.290314 -57.718759) (xy 57.253097 -57.760296) (xy 57.210229 -57.795971)
			(xy 57.162623 -57.825025) (xy 57.111294 -57.846837) (xy 57.057337 -57.860943) (xy 57.0019 -57.867043)
			(xy 56.946166 -57.865006) (xy 56.891323 -57.854876) (xy 56.838539 -57.836869) (xy 56.788939 -57.811368)
			(xy 56.743581 -57.778917) (xy 56.703432 -57.740208) (xy 56.669346 -57.696065) (xy 56.64205 -57.64743)
			(xy 56.622127 -57.595339) (xy 56.610001 -57.540902) (xy 56.60593 -57.48528) (xy 44.589115 -57.48528)
			(xy 44.58398 -57.520998) (xy 44.568626 -57.573292) (xy 44.545987 -57.622869) (xy 44.516522 -57.668719)
			(xy 44.480833 -57.70991) (xy 44.439645 -57.745603) (xy 44.393797 -57.775071) (xy 44.344222 -57.797715)
			(xy 44.291929 -57.813074) (xy 44.237983 -57.820834) (xy 44.210732 -57.821322) (xy 44.210478 -57.821322)
			(xy 44.184183 -57.820871) (xy 44.132094 -57.813623) (xy 44.081493 -57.799295) (xy 44.033337 -57.778158)
			(xy 43.988538 -57.750612) (xy 43.947943 -57.717179) (xy 43.929808 -57.698132) (xy 43.922228 -57.6907)
			(xy 43.902817 -57.682168) (xy 43.892216 -57.681622) (xy 43.818048 -57.681622) (xy 43.807413 -57.682005)
			(xy 43.787948 -57.690572) (xy 43.780456 -57.698132) (xy 43.762345 -57.717205) (xy 43.72176 -57.750663)
			(xy 43.676961 -57.778221) (xy 43.628797 -57.799358) (xy 43.578185 -57.813671) (xy 43.526085 -57.820888)
			(xy 43.499786 -57.821322) (xy 43.499532 -57.821322) (xy 43.472279 -57.820833) (xy 43.418326 -57.81308)
			(xy 43.366026 -57.797727) (xy 43.316444 -57.775087) (xy 43.270589 -57.745621) (xy 43.229394 -57.709929)
			(xy 43.193698 -57.668737) (xy 43.164228 -57.622884) (xy 43.141584 -57.573304) (xy 43.126227 -57.521005)
			(xy 43.118469 -57.467053) (xy 42.93521 -57.467053) (xy 42.939023 -57.494543) (xy 42.939462 -57.52084)
			(xy 42.939462 -57.521094) (xy 42.938967 -57.548427) (xy 42.931166 -57.602533) (xy 42.915722 -57.654972)
			(xy 42.892953 -57.70467) (xy 42.863324 -57.75061) (xy 42.845736 -57.771538) (xy 42.845482 -57.771792)
			(xy 42.845228 -57.772046) (xy 42.839649 -57.779138) (xy 42.8334 -57.796051) (xy 42.833036 -57.805066)
			(xy 42.833036 -57.872122) (xy 42.833375 -57.881141) (xy 42.839634 -57.898058) (xy 42.845228 -57.905142)
			(xy 42.845482 -57.905396) (xy 42.845736 -57.90565) (xy 42.86333 -57.926577) (xy 42.892983 -57.972509)
			(xy 42.915772 -58.022206) (xy 42.931229 -58.074647) (xy 42.939038 -58.128759) (xy 42.939039 -58.183432)
			(xy 42.931231 -58.237544) (xy 42.915775 -58.289986) (xy 42.892988 -58.339683) (xy 42.863336 -58.385616)
			(xy 42.845736 -58.406538) (xy 42.845482 -58.406792) (xy 42.845228 -58.407046) (xy 42.839649 -58.414138)
			(xy 42.8334 -58.431051) (xy 42.833036 -58.440066) (xy 42.833036 -58.507122) (xy 42.833375 -58.516141)
			(xy 42.839634 -58.533058) (xy 42.845228 -58.540142) (xy 42.845482 -58.540396) (xy 42.845736 -58.54065)
			(xy 42.863324 -58.561579) (xy 42.892962 -58.607516) (xy 42.915738 -58.657213) (xy 42.931187 -58.709652)
			(xy 42.938992 -58.76376) (xy 42.939462 -58.791094) (xy 42.938976 -58.818345) (xy 42.93122 -58.872293)
			(xy 42.930823 -58.873644) (xy 44.200572 -58.873644) (xy 44.201023 -58.846309) (xy 44.208833 -58.792201)
			(xy 44.224287 -58.739761) (xy 44.247066 -58.690064) (xy 44.276705 -58.644126) (xy 44.294298 -58.6232)
			(xy 44.294552 -58.622946) (xy 44.294806 -58.622692) (xy 44.300403 -58.615612) (xy 44.306643 -58.59869)
			(xy 44.306998 -58.589672) (xy 44.306998 -58.522616) (xy 44.306634 -58.5136) (xy 44.300391 -58.496683)
			(xy 44.294806 -58.489596) (xy 44.294552 -58.489342) (xy 44.294298 -58.489088) (xy 44.276686 -58.468178)
			(xy 44.247051 -58.422237) (xy 44.224278 -58.372535) (xy 44.208835 -58.320091) (xy 44.201037 -58.265979)
			(xy 44.200572 -58.238644) (xy 44.201058 -58.211393) (xy 44.208814 -58.157445) (xy 44.224169 -58.10515)
			(xy 44.246811 -58.055573) (xy 44.276277 -58.009723) (xy 44.311968 -57.968532) (xy 44.353159 -57.932841)
			(xy 44.399009 -57.903375) (xy 44.448586 -57.880733) (xy 44.500881 -57.865378) (xy 44.554829 -57.857622)
			(xy 44.609331 -57.857622) (xy 44.663279 -57.865378) (xy 44.715574 -57.880733) (xy 44.765151 -57.903375)
			(xy 44.811001 -57.932841) (xy 44.852192 -57.968532) (xy 44.887883 -58.009723) (xy 44.917349 -58.055573)
			(xy 44.924976 -58.072274) (xy 51.993544 -58.072274) (xy 51.997615 -58.016652) (xy 52.009741 -57.962215)
			(xy 52.029664 -57.910124) (xy 52.05696 -57.861489) (xy 52.091046 -57.817346) (xy 52.131195 -57.778637)
			(xy 52.176553 -57.746186) (xy 52.226153 -57.720685) (xy 52.278937 -57.702678) (xy 52.33378 -57.692548)
			(xy 52.389514 -57.690511) (xy 52.444951 -57.696611) (xy 52.498908 -57.710717) (xy 52.550237 -57.732529)
			(xy 52.597843 -57.761583) (xy 52.640711 -57.797258) (xy 52.677928 -57.838795) (xy 52.708701 -57.885308)
			(xy 52.732373 -57.935805) (xy 52.748441 -57.989212) (xy 52.756561 -58.044388) (xy 52.75707 -58.072274)
			(xy 52.757 -58.076084) (xy 57.358024 -58.076084) (xy 57.362095 -58.020462) (xy 57.374221 -57.966025)
			(xy 57.394144 -57.913934) (xy 57.42144 -57.865299) (xy 57.455526 -57.821156) (xy 57.495675 -57.782447)
			(xy 57.541033 -57.749996) (xy 57.590633 -57.724495) (xy 57.643417 -57.706488) (xy 57.69826 -57.696358)
			(xy 57.753994 -57.694321) (xy 57.809431 -57.700421) (xy 57.863388 -57.714527) (xy 57.914717 -57.736339)
			(xy 57.962323 -57.765393) (xy 58.005191 -57.801068) (xy 58.042408 -57.842605) (xy 58.058744 -57.867296)
			(xy 59.643008 -57.867296) (xy 59.647079 -57.811674) (xy 59.659205 -57.757237) (xy 59.679128 -57.705146)
			(xy 59.706424 -57.656511) (xy 59.74051 -57.612368) (xy 59.780659 -57.573659) (xy 59.826017 -57.541208)
			(xy 59.875617 -57.515707) (xy 59.928401 -57.4977) (xy 59.983244 -57.48757) (xy 60.038978 -57.485533)
			(xy 60.094415 -57.491633) (xy 60.148372 -57.505739) (xy 60.199701 -57.527551) (xy 60.247307 -57.556605)
			(xy 60.290175 -57.59228) (xy 60.327392 -57.633817) (xy 60.358165 -57.68033) (xy 60.381837 -57.730827)
			(xy 60.397905 -57.784234) (xy 60.406025 -57.83941) (xy 60.406534 -57.867296) (xy 60.406025 -57.895182)
			(xy 60.397905 -57.950358) (xy 60.381837 -58.003765) (xy 60.358165 -58.054262) (xy 60.327392 -58.100775)
			(xy 60.290175 -58.142312) (xy 60.247307 -58.177987) (xy 60.199701 -58.207041) (xy 60.148372 -58.228853)
			(xy 60.094415 -58.242959) (xy 60.038978 -58.249059) (xy 59.983244 -58.247022) (xy 59.928401 -58.236892)
			(xy 59.875617 -58.218885) (xy 59.826017 -58.193384) (xy 59.780659 -58.160933) (xy 59.74051 -58.122224)
			(xy 59.706424 -58.078081) (xy 59.679128 -58.029446) (xy 59.659205 -57.977355) (xy 59.647079 -57.922918)
			(xy 59.643008 -57.867296) (xy 58.058744 -57.867296) (xy 58.073181 -57.889118) (xy 58.096853 -57.939615)
			(xy 58.112921 -57.993022) (xy 58.121041 -58.048198) (xy 58.12155 -58.076084) (xy 58.121041 -58.10397)
			(xy 58.112921 -58.159146) (xy 58.096853 -58.212553) (xy 58.073181 -58.26305) (xy 58.042408 -58.309563)
			(xy 58.005191 -58.3511) (xy 57.962323 -58.386775) (xy 57.914717 -58.415829) (xy 57.863388 -58.437641)
			(xy 57.809431 -58.451747) (xy 57.753994 -58.457847) (xy 57.69826 -58.45581) (xy 57.643417 -58.44568)
			(xy 57.590633 -58.427673) (xy 57.541033 -58.402172) (xy 57.495675 -58.369721) (xy 57.455526 -58.331012)
			(xy 57.42144 -58.286869) (xy 57.394144 -58.238234) (xy 57.374221 -58.186143) (xy 57.362095 -58.131706)
			(xy 57.358024 -58.076084) (xy 52.757 -58.076084) (xy 52.756561 -58.10016) (xy 52.748441 -58.155336)
			(xy 52.732373 -58.208743) (xy 52.708701 -58.25924) (xy 52.677928 -58.305753) (xy 52.640711 -58.34729)
			(xy 52.597843 -58.382965) (xy 52.550237 -58.412019) (xy 52.498908 -58.433831) (xy 52.444951 -58.447937)
			(xy 52.389514 -58.454037) (xy 52.33378 -58.452) (xy 52.278937 -58.44187) (xy 52.226153 -58.423863)
			(xy 52.176553 -58.398362) (xy 52.131195 -58.365911) (xy 52.091046 -58.327202) (xy 52.05696 -58.283059)
			(xy 52.029664 -58.234424) (xy 52.009741 -58.182333) (xy 51.997615 -58.127896) (xy 51.993544 -58.072274)
			(xy 44.924976 -58.072274) (xy 44.939991 -58.10515) (xy 44.955346 -58.157445) (xy 44.963102 -58.211393)
			(xy 44.963588 -58.238644) (xy 44.963116 -58.265978) (xy 44.955308 -58.320085) (xy 44.939859 -58.372524)
			(xy 44.917085 -58.422221) (xy 44.887451 -58.46816) (xy 44.869862 -58.489088) (xy 44.869608 -58.489342)
			(xy 44.869354 -58.489596) (xy 44.863757 -58.496676) (xy 44.857518 -58.513598) (xy 44.857162 -58.522616)
			(xy 44.857162 -58.561224) (xy 58.562238 -58.561224) (xy 58.566309 -58.505602) (xy 58.578435 -58.451165)
			(xy 58.598358 -58.399074) (xy 58.625654 -58.350439) (xy 58.65974 -58.306296) (xy 58.699889 -58.267587)
			(xy 58.745247 -58.235136) (xy 58.794847 -58.209635) (xy 58.847631 -58.191628) (xy 58.902474 -58.181498)
			(xy 58.958208 -58.179461) (xy 59.013645 -58.185561) (xy 59.067602 -58.199667) (xy 59.118931 -58.221479)
			(xy 59.166537 -58.250533) (xy 59.209405 -58.286208) (xy 59.246622 -58.327745) (xy 59.277395 -58.374258)
			(xy 59.301067 -58.424755) (xy 59.308577 -58.449718) (xy 60.808868 -58.449718) (xy 60.812939 -58.394096)
			(xy 60.825065 -58.339659) (xy 60.844988 -58.287568) (xy 60.872284 -58.238933) (xy 60.90637 -58.19479)
			(xy 60.946519 -58.156081) (xy 60.991877 -58.12363) (xy 61.041477 -58.098129) (xy 61.094261 -58.080122)
			(xy 61.149104 -58.069992) (xy 61.204838 -58.067955) (xy 61.260275 -58.074055) (xy 61.314232 -58.088161)
			(xy 61.365561 -58.109973) (xy 61.413167 -58.139027) (xy 61.456035 -58.174702) (xy 61.493252 -58.216239)
			(xy 61.524025 -58.262752) (xy 61.547697 -58.313249) (xy 61.563765 -58.366656) (xy 61.571885 -58.421832)
			(xy 61.572394 -58.449718) (xy 61.571885 -58.477604) (xy 61.563765 -58.53278) (xy 61.547697 -58.586187)
			(xy 61.524025 -58.636684) (xy 61.493252 -58.683197) (xy 61.456035 -58.724734) (xy 61.44802 -58.731404)
			(xy 65.52057 -58.731404) (xy 65.521057 -58.704071) (xy 65.528859 -58.649964) (xy 65.544304 -58.597524)
			(xy 65.567075 -58.547826) (xy 65.596707 -58.501888) (xy 65.614296 -58.48096) (xy 65.61455 -58.480706)
			(xy 65.614804 -58.480452) (xy 65.620375 -58.473355) (xy 65.626631 -58.456446) (xy 65.626996 -58.447432)
			(xy 65.626996 -58.380376) (xy 65.626651 -58.371358) (xy 65.620395 -58.354441) (xy 65.614804 -58.347356)
			(xy 65.61455 -58.347102) (xy 65.614296 -58.346848) (xy 65.596698 -58.325923) (xy 65.567043 -58.279991)
			(xy 65.544253 -58.230295) (xy 65.528794 -58.177852) (xy 65.520984 -58.12374) (xy 65.520984 -58.069066)
			(xy 65.528793 -58.014954) (xy 65.544251 -57.962511) (xy 65.56704 -57.912814) (xy 65.596695 -57.866882)
			(xy 65.614296 -57.84596) (xy 65.61455 -57.845706) (xy 65.614804 -57.845452) (xy 65.620375 -57.838355)
			(xy 65.626631 -57.821446) (xy 65.626996 -57.812432) (xy 65.626996 -57.745376) (xy 65.626651 -57.736358)
			(xy 65.620395 -57.719441) (xy 65.614804 -57.712356) (xy 65.61455 -57.712102) (xy 65.614296 -57.711848)
			(xy 65.596698 -57.690923) (xy 65.567043 -57.644991) (xy 65.544253 -57.595295) (xy 65.528794 -57.542852)
			(xy 65.520984 -57.48874) (xy 65.520984 -57.434066) (xy 65.528793 -57.379954) (xy 65.544251 -57.327511)
			(xy 65.56704 -57.277814) (xy 65.596695 -57.231882) (xy 65.614296 -57.21096) (xy 65.61455 -57.210706)
			(xy 65.614804 -57.210452) (xy 65.620375 -57.203355) (xy 65.626631 -57.186446) (xy 65.626996 -57.177432)
			(xy 65.626996 -57.110376) (xy 65.626651 -57.101358) (xy 65.620395 -57.084441) (xy 65.614804 -57.077356)
			(xy 65.61455 -57.077102) (xy 65.614296 -57.076848) (xy 65.596712 -57.055916) (xy 65.567073 -57.00998)
			(xy 65.544295 -56.960284) (xy 65.528845 -56.907845) (xy 65.52104 -56.853738) (xy 65.52057 -56.826404)
			(xy 65.521056 -56.799153) (xy 65.528812 -56.745205) (xy 65.544167 -56.69291) (xy 65.566809 -56.643333)
			(xy 65.596275 -56.597483) (xy 65.631966 -56.556292) (xy 65.673157 -56.520601) (xy 65.719007 -56.491135)
			(xy 65.768584 -56.468493) (xy 65.820879 -56.453138) (xy 65.874827 -56.445382) (xy 65.929329 -56.445382)
			(xy 65.983277 -56.453138) (xy 66.035572 -56.468493) (xy 66.085149 -56.491135) (xy 66.130999 -56.520601)
			(xy 66.17219 -56.556292) (xy 66.207881 -56.597483) (xy 66.237347 -56.643333) (xy 66.259989 -56.69291)
			(xy 66.275344 -56.745205) (xy 66.2831 -56.799153) (xy 66.283586 -56.826404) (xy 66.283091 -56.853737)
			(xy 66.275289 -56.907843) (xy 66.259845 -56.960282) (xy 66.237076 -57.00998) (xy 66.207447 -57.05592)
			(xy 66.18986 -57.076848) (xy 66.189606 -57.077102) (xy 66.189352 -57.077356) (xy 66.183772 -57.084447)
			(xy 66.177523 -57.101361) (xy 66.17716 -57.110376) (xy 66.17716 -57.177432) (xy 66.177488 -57.186452)
			(xy 66.183754 -57.20337) (xy 66.189352 -57.210452) (xy 66.189606 -57.210706) (xy 66.18986 -57.21096)
			(xy 66.207463 -57.231879) (xy 66.237114 -57.277814) (xy 66.2599 -57.327512) (xy 66.275356 -57.379954)
			(xy 66.283164 -57.434067) (xy 66.283163 -57.488739) (xy 66.275355 -57.542852) (xy 66.259898 -57.595294)
			(xy 66.237111 -57.644992) (xy 66.207459 -57.690925) (xy 66.18986 -57.711848) (xy 66.189606 -57.712102)
			(xy 66.189352 -57.712356) (xy 66.183772 -57.719447) (xy 66.177523 -57.736361) (xy 66.17716 -57.745376)
			(xy 66.17716 -57.812432) (xy 66.177488 -57.821452) (xy 66.183754 -57.83837) (xy 66.189352 -57.845452)
			(xy 66.189606 -57.845706) (xy 66.18986 -57.84596) (xy 66.207463 -57.866879) (xy 66.237114 -57.912814)
			(xy 66.2599 -57.962512) (xy 66.275356 -58.014954) (xy 66.283164 -58.069067) (xy 66.283163 -58.123739)
			(xy 66.275355 -58.177852) (xy 66.259898 -58.230294) (xy 66.237111 -58.279992) (xy 66.207459 -58.325925)
			(xy 66.18986 -58.346848) (xy 66.189606 -58.347102) (xy 66.189352 -58.347356) (xy 66.183772 -58.354447)
			(xy 66.177523 -58.371361) (xy 66.17716 -58.380376) (xy 66.17716 -58.447432) (xy 66.177488 -58.456452)
			(xy 66.183754 -58.47337) (xy 66.189352 -58.480452) (xy 66.189606 -58.480706) (xy 66.18986 -58.48096)
			(xy 66.207441 -58.501895) (xy 66.237082 -58.547829) (xy 66.259862 -58.597524) (xy 66.275312 -58.649963)
			(xy 66.283117 -58.70407) (xy 66.283586 -58.731404) (xy 66.2831 -58.758655) (xy 66.278436 -58.791094)
			(xy 68.176394 -58.791094) (xy 68.176893 -58.763761) (xy 68.184695 -58.709656) (xy 68.200138 -58.657217)
			(xy 68.222906 -58.607519) (xy 68.252533 -58.561579) (xy 68.27012 -58.54065) (xy 68.270374 -58.540396)
			(xy 68.270628 -58.540142) (xy 68.276206 -58.53305) (xy 68.282457 -58.516137) (xy 68.28282 -58.507122)
			(xy 68.28282 -58.440066) (xy 68.282475 -58.431048) (xy 68.276219 -58.414131) (xy 68.270628 -58.407046)
			(xy 68.270374 -58.406792) (xy 68.27012 -58.406538) (xy 68.252512 -58.385622) (xy 68.222855 -58.339689)
			(xy 68.200064 -58.289991) (xy 68.184605 -58.237547) (xy 68.176796 -58.183433) (xy 68.176796 -58.128758)
			(xy 68.184607 -58.074644) (xy 68.200067 -58.022201) (xy 68.222859 -57.972503) (xy 68.252517 -57.926571)
			(xy 68.27012 -57.90565) (xy 68.270374 -57.905396) (xy 68.270628 -57.905142) (xy 68.276206 -57.89805)
			(xy 68.282457 -57.881137) (xy 68.28282 -57.872122) (xy 68.28282 -57.805066) (xy 68.282475 -57.796048)
			(xy 68.276219 -57.779131) (xy 68.270628 -57.772046) (xy 68.270374 -57.771792) (xy 68.27012 -57.771538)
			(xy 68.252535 -57.750606) (xy 68.222895 -57.704671) (xy 68.200117 -57.654975) (xy 68.184667 -57.602536)
			(xy 68.176863 -57.548428) (xy 68.176394 -57.521094) (xy 68.176394 -57.52084) (xy 68.176881 -57.494546)
			(xy 68.184121 -57.442459) (xy 68.198442 -57.391858) (xy 68.219572 -57.343702) (xy 68.247112 -57.298902)
			(xy 68.28054 -57.258305) (xy 68.299584 -57.24017) (xy 68.307035 -57.232606) (xy 68.315555 -57.213182)
			(xy 68.316094 -57.202578) (xy 68.316094 -57.12841) (xy 68.315673 -57.117779) (xy 68.307132 -57.098315)
			(xy 68.299584 -57.090818) (xy 68.280525 -57.072693) (xy 68.247069 -57.03211) (xy 68.219511 -56.987312)
			(xy 68.198372 -56.939152) (xy 68.184055 -56.888543) (xy 68.176832 -56.836446) (xy 68.176394 -56.810148)
			(xy 68.176394 -56.809894) (xy 68.17688 -56.782643) (xy 68.184636 -56.728695) (xy 68.199991 -56.6764)
			(xy 68.222633 -56.626823) (xy 68.252099 -56.580973) (xy 68.28779 -56.539782) (xy 68.328981 -56.504091)
			(xy 68.374831 -56.474625) (xy 68.424408 -56.451983) (xy 68.476703 -56.436628) (xy 68.530651 -56.428872)
			(xy 68.585153 -56.428872) (xy 68.639101 -56.436628) (xy 68.691396 -56.451983) (xy 68.740973 -56.474625)
			(xy 68.786823 -56.504091) (xy 68.828014 -56.539782) (xy 68.863705 -56.580973) (xy 68.893171 -56.626823)
			(xy 68.915813 -56.6764) (xy 68.931168 -56.728695) (xy 68.938924 -56.782643) (xy 68.93941 -56.809894)
			(xy 68.93941 -56.810148) (xy 68.93898 -56.836444) (xy 68.931728 -56.888534) (xy 68.917397 -56.939135)
			(xy 68.896256 -56.987291) (xy 68.868706 -57.03209) (xy 68.835268 -57.072684) (xy 68.81622 -57.090818)
			(xy 68.808775 -57.098387) (xy 68.800251 -57.117807) (xy 68.79971 -57.12841) (xy 68.79971 -57.202578)
			(xy 68.800137 -57.213208) (xy 68.808674 -57.232673) (xy 68.81622 -57.24017) (xy 68.835274 -57.2583)
			(xy 68.86873 -57.298882) (xy 68.896289 -57.343679) (xy 68.917428 -57.391838) (xy 68.931746 -57.442446)
			(xy 68.935158 -57.467049) (xy 69.118492 -57.467049) (xy 69.118492 -57.412551) (xy 69.126248 -57.358607)
			(xy 69.141601 -57.306316) (xy 69.16424 -57.256742) (xy 69.193704 -57.210894) (xy 69.229392 -57.169706)
			(xy 69.270578 -57.134016) (xy 69.316424 -57.10455) (xy 69.365997 -57.081908) (xy 69.418287 -57.066552)
			(xy 69.472231 -57.058794) (xy 69.49948 -57.058306) (xy 69.499734 -57.058306) (xy 69.52603 -57.05874)
			(xy 69.57812 -57.06599) (xy 69.628721 -57.080321) (xy 69.676877 -57.101461) (xy 69.721676 -57.12901)
			(xy 69.76227 -57.162448) (xy 69.780404 -57.181496) (xy 69.787976 -57.188937) (xy 69.807394 -57.197462)
			(xy 69.817996 -57.198006) (xy 69.892164 -57.198006) (xy 69.902799 -57.197621) (xy 69.922263 -57.189054)
			(xy 69.929756 -57.181496) (xy 69.947896 -57.162452) (xy 69.988476 -57.128995) (xy 70.03327 -57.101434)
			(xy 70.081427 -57.080292) (xy 70.132034 -57.065973) (xy 70.184129 -57.058746) (xy 70.210426 -57.058306)
			(xy 70.21068 -57.058306) (xy 70.237935 -57.05874) (xy 70.29189 -57.066494) (xy 70.327158 -57.076848)
			(xy 71.138542 -57.076848) (xy 71.139002 -57.049514) (xy 71.146812 -56.995406) (xy 71.162263 -56.942967)
			(xy 71.18504 -56.893269) (xy 71.214677 -56.847331) (xy 71.232268 -56.826404) (xy 71.232522 -56.82615)
			(xy 71.232776 -56.825896) (xy 71.238379 -56.818821) (xy 71.244614 -56.801895) (xy 71.244968 -56.792876)
			(xy 71.244968 -56.72582) (xy 71.244608 -56.716803) (xy 71.238363 -56.699886) (xy 71.232776 -56.6928)
			(xy 71.232522 -56.692546) (xy 71.232268 -56.692292) (xy 71.214653 -56.671384) (xy 71.185019 -56.625442)
			(xy 71.162248 -56.575739) (xy 71.146805 -56.523295) (xy 71.139008 -56.469183) (xy 71.138542 -56.441848)
			(xy 71.139028 -56.414597) (xy 71.146784 -56.360649) (xy 71.162139 -56.308354) (xy 71.184781 -56.258777)
			(xy 71.214247 -56.212927) (xy 71.249938 -56.171736) (xy 71.291129 -56.136045) (xy 71.336979 -56.106579)
			(xy 71.386556 -56.083937) (xy 71.438851 -56.068582) (xy 71.492799 -56.060826) (xy 71.547301 -56.060826)
			(xy 71.601249 -56.068582) (xy 71.653544 -56.083937) (xy 71.703121 -56.106579) (xy 71.748971 -56.136045)
			(xy 71.790162 -56.171736) (xy 71.825853 -56.212927) (xy 71.855319 -56.258777) (xy 71.877961 -56.308354)
			(xy 71.891204 -56.353456) (xy 78.941166 -56.353456) (xy 78.945237 -56.297834) (xy 78.957363 -56.243397)
			(xy 78.977286 -56.191306) (xy 79.004582 -56.142671) (xy 79.038668 -56.098528) (xy 79.078817 -56.059819)
			(xy 79.124175 -56.027368) (xy 79.173775 -56.001867) (xy 79.226559 -55.98386) (xy 79.281402 -55.97373)
			(xy 79.337136 -55.971693) (xy 79.392573 -55.977793) (xy 79.44653 -55.991899) (xy 79.497859 -56.013711)
			(xy 79.545465 -56.042765) (xy 79.588333 -56.07844) (xy 79.62555 -56.119977) (xy 79.656323 -56.16649)
			(xy 79.679995 -56.216987) (xy 79.696063 -56.270394) (xy 79.704183 -56.32557) (xy 79.704692 -56.353456)
			(xy 79.704183 -56.381342) (xy 79.696063 -56.436518) (xy 79.679995 -56.489925) (xy 79.656323 -56.540422)
			(xy 79.62555 -56.586935) (xy 79.588333 -56.628472) (xy 79.545465 -56.664147) (xy 79.497859 -56.693201)
			(xy 79.44653 -56.715013) (xy 79.392573 -56.729119) (xy 79.337136 -56.735219) (xy 79.281402 -56.733182)
			(xy 79.226559 -56.723052) (xy 79.173775 -56.705045) (xy 79.124175 -56.679544) (xy 79.078817 -56.647093)
			(xy 79.038668 -56.608384) (xy 79.004582 -56.564241) (xy 78.977286 -56.515606) (xy 78.957363 -56.463515)
			(xy 78.945237 -56.409078) (xy 78.941166 -56.353456) (xy 71.891204 -56.353456) (xy 71.893316 -56.360649)
			(xy 71.901072 -56.414597) (xy 71.901558 -56.441848) (xy 71.901095 -56.469182) (xy 71.893286 -56.52329)
			(xy 71.877836 -56.575729) (xy 71.855059 -56.625427) (xy 71.825423 -56.671365) (xy 71.807832 -56.692292)
			(xy 71.807578 -56.692546) (xy 71.807324 -56.6928) (xy 71.801722 -56.699876) (xy 71.795487 -56.716801)
			(xy 71.795132 -56.72582) (xy 71.795132 -56.792876) (xy 71.795494 -56.801893) (xy 71.801737 -56.81881)
			(xy 71.807324 -56.825896) (xy 71.807578 -56.82615) (xy 71.807832 -56.826404) (xy 71.825445 -56.847313)
			(xy 71.855079 -56.893255) (xy 71.877851 -56.942957) (xy 71.893294 -56.995401) (xy 71.901092 -57.049513)
			(xy 71.901558 -57.076848) (xy 71.901072 -57.104099) (xy 71.893316 -57.158047) (xy 71.877961 -57.210342)
			(xy 71.855319 -57.259919) (xy 71.825853 -57.305769) (xy 71.790162 -57.34696) (xy 71.748971 -57.382651)
			(xy 71.703121 -57.412117) (xy 71.653544 -57.434759) (xy 71.601249 -57.450114) (xy 71.547301 -57.45787)
			(xy 71.492799 -57.45787) (xy 71.438851 -57.450114) (xy 71.386556 -57.434759) (xy 71.336979 -57.412117)
			(xy 71.291129 -57.382651) (xy 71.249938 -57.34696) (xy 71.214247 -57.305769) (xy 71.184781 -57.259919)
			(xy 71.162139 -57.210342) (xy 71.146784 -57.158047) (xy 71.139028 -57.104099) (xy 71.138542 -57.076848)
			(xy 70.327158 -57.076848) (xy 70.344192 -57.081849) (xy 70.393777 -57.104492) (xy 70.439634 -57.13396)
			(xy 70.480831 -57.169655) (xy 70.516528 -57.21085) (xy 70.545999 -57.256706) (xy 70.568644 -57.306289)
			(xy 70.584001 -57.35859) (xy 70.591759 -57.412545) (xy 70.591759 -57.467055) (xy 70.589138 -57.48528)
			(xy 82.605878 -57.48528) (xy 82.609949 -57.429658) (xy 82.622075 -57.375221) (xy 82.641998 -57.32313)
			(xy 82.669294 -57.274495) (xy 82.70338 -57.230352) (xy 82.743529 -57.191643) (xy 82.788887 -57.159192)
			(xy 82.838487 -57.133691) (xy 82.891271 -57.115684) (xy 82.946114 -57.105554) (xy 83.001848 -57.103517)
			(xy 83.057285 -57.109617) (xy 83.111242 -57.123723) (xy 83.162571 -57.145535) (xy 83.210177 -57.174589)
			(xy 83.253045 -57.210264) (xy 83.290262 -57.251801) (xy 83.321035 -57.298314) (xy 83.344707 -57.348811)
			(xy 83.360775 -57.402218) (xy 83.368895 -57.457394) (xy 83.369404 -57.48528) (xy 83.368895 -57.513166)
			(xy 83.360775 -57.568342) (xy 83.344707 -57.621749) (xy 83.321035 -57.672246) (xy 83.290262 -57.718759)
			(xy 83.253045 -57.760296) (xy 83.210177 -57.795971) (xy 83.162571 -57.825025) (xy 83.111242 -57.846837)
			(xy 83.057285 -57.860943) (xy 83.001848 -57.867043) (xy 82.946114 -57.865006) (xy 82.891271 -57.854876)
			(xy 82.838487 -57.836869) (xy 82.788887 -57.811368) (xy 82.743529 -57.778917) (xy 82.70338 -57.740208)
			(xy 82.669294 -57.696065) (xy 82.641998 -57.64743) (xy 82.622075 -57.595339) (xy 82.609949 -57.540902)
			(xy 82.605878 -57.48528) (xy 70.589138 -57.48528) (xy 70.584001 -57.52101) (xy 70.568644 -57.573311)
			(xy 70.545999 -57.622894) (xy 70.516528 -57.66875) (xy 70.480831 -57.709945) (xy 70.439634 -57.74564)
			(xy 70.393777 -57.775108) (xy 70.344192 -57.797751) (xy 70.29189 -57.813106) (xy 70.237935 -57.82086)
			(xy 70.21068 -57.821322) (xy 70.210426 -57.821322) (xy 70.184132 -57.820839) (xy 70.132045 -57.813598)
			(xy 70.081444 -57.799276) (xy 70.033288 -57.778145) (xy 69.988488 -57.750605) (xy 69.947891 -57.717176)
			(xy 69.929756 -57.698132) (xy 69.922196 -57.690677) (xy 69.902769 -57.682159) (xy 69.892164 -57.681622)
			(xy 69.817996 -57.681622) (xy 69.807364 -57.682031) (xy 69.787899 -57.69058) (xy 69.780404 -57.698132)
			(xy 69.762269 -57.717182) (xy 69.72169 -57.750641) (xy 69.676895 -57.778203) (xy 69.628736 -57.799344)
			(xy 69.578128 -57.813662) (xy 69.526031 -57.820885) (xy 69.499734 -57.821322) (xy 69.49948 -57.821322)
			(xy 69.472231 -57.820806) (xy 69.418287 -57.813048) (xy 69.365997 -57.797692) (xy 69.316424 -57.77505)
			(xy 69.270578 -57.745584) (xy 69.229392 -57.709894) (xy 69.193704 -57.668706) (xy 69.16424 -57.622858)
			(xy 69.141601 -57.573284) (xy 69.126248 -57.520993) (xy 69.118492 -57.467049) (xy 68.935158 -57.467049)
			(xy 68.938971 -57.494543) (xy 68.93941 -57.52084) (xy 68.93941 -57.521094) (xy 68.938903 -57.548426)
			(xy 68.931103 -57.602532) (xy 68.915662 -57.65497) (xy 68.892895 -57.704668) (xy 68.86327 -57.750609)
			(xy 68.845684 -57.771538) (xy 68.84543 -57.771792) (xy 68.845176 -57.772046) (xy 68.839603 -57.779142)
			(xy 68.833349 -57.796052) (xy 68.832984 -57.805066) (xy 68.832984 -57.872122) (xy 68.833334 -57.881139)
			(xy 68.839587 -57.898056) (xy 68.845176 -57.905142) (xy 68.84543 -57.905396) (xy 68.845684 -57.90565)
			(xy 68.86328 -57.926576) (xy 68.892937 -57.972507) (xy 68.915729 -58.022203) (xy 68.931189 -58.074646)
			(xy 68.938999 -58.128759) (xy 68.939 -58.183432) (xy 68.931191 -58.237545) (xy 68.915732 -58.289988)
			(xy 68.892942 -58.339685) (xy 68.863286 -58.385617) (xy 68.845684 -58.406538) (xy 68.84543 -58.406792)
			(xy 68.845176 -58.407046) (xy 68.839603 -58.414142) (xy 68.833349 -58.431052) (xy 68.832984 -58.440066)
			(xy 68.832984 -58.507122) (xy 68.833334 -58.516139) (xy 68.839587 -58.533056) (xy 68.845176 -58.540142)
			(xy 68.84543 -58.540396) (xy 68.845684 -58.54065) (xy 68.863264 -58.561586) (xy 68.892905 -58.60752)
			(xy 68.915684 -58.657215) (xy 68.931134 -58.709653) (xy 68.93894 -58.76376) (xy 68.93941 -58.791094)
			(xy 68.938924 -58.818345) (xy 68.931168 -58.872293) (xy 68.930771 -58.873644) (xy 70.20052 -58.873644)
			(xy 70.200983 -58.84631) (xy 70.208793 -58.792203) (xy 70.224244 -58.739763) (xy 70.24702 -58.690066)
			(xy 70.276656 -58.644127) (xy 70.294246 -58.6232) (xy 70.2945 -58.622946) (xy 70.294754 -58.622692)
			(xy 70.300356 -58.615617) (xy 70.306592 -58.598691) (xy 70.306946 -58.589672) (xy 70.306946 -58.522616)
			(xy 70.306593 -58.513598) (xy 70.300344 -58.496681) (xy 70.294754 -58.489596) (xy 70.2945 -58.489342)
			(xy 70.294246 -58.489088) (xy 70.276642 -58.468172) (xy 70.247004 -58.422233) (xy 70.224229 -58.372533)
			(xy 70.208784 -58.32009) (xy 70.200986 -58.265979) (xy 70.20052 -58.238644) (xy 70.201006 -58.211393)
			(xy 70.208762 -58.157445) (xy 70.224117 -58.10515) (xy 70.246759 -58.055573) (xy 70.276225 -58.009723)
			(xy 70.311916 -57.968532) (xy 70.353107 -57.932841) (xy 70.398957 -57.903375) (xy 70.448534 -57.880733)
			(xy 70.500829 -57.865378) (xy 70.554777 -57.857622) (xy 70.609279 -57.857622) (xy 70.663227 -57.865378)
			(xy 70.715522 -57.880733) (xy 70.765099 -57.903375) (xy 70.810949 -57.932841) (xy 70.85214 -57.968532)
			(xy 70.887831 -58.009723) (xy 70.917297 -58.055573) (xy 70.924924 -58.072274) (xy 77.993492 -58.072274)
			(xy 77.997563 -58.016652) (xy 78.009689 -57.962215) (xy 78.029612 -57.910124) (xy 78.056908 -57.861489)
			(xy 78.090994 -57.817346) (xy 78.131143 -57.778637) (xy 78.176501 -57.746186) (xy 78.226101 -57.720685)
			(xy 78.278885 -57.702678) (xy 78.333728 -57.692548) (xy 78.389462 -57.690511) (xy 78.444899 -57.696611)
			(xy 78.498856 -57.710717) (xy 78.550185 -57.732529) (xy 78.597791 -57.761583) (xy 78.640659 -57.797258)
			(xy 78.677876 -57.838795) (xy 78.708649 -57.885308) (xy 78.732321 -57.935805) (xy 78.748389 -57.989212)
			(xy 78.756509 -58.044388) (xy 78.757018 -58.072274) (xy 78.756948 -58.076084) (xy 83.357972 -58.076084)
			(xy 83.362043 -58.020462) (xy 83.374169 -57.966025) (xy 83.394092 -57.913934) (xy 83.421388 -57.865299)
			(xy 83.455474 -57.821156) (xy 83.495623 -57.782447) (xy 83.540981 -57.749996) (xy 83.590581 -57.724495)
			(xy 83.643365 -57.706488) (xy 83.698208 -57.696358) (xy 83.753942 -57.694321) (xy 83.809379 -57.700421)
			(xy 83.863336 -57.714527) (xy 83.914665 -57.736339) (xy 83.962271 -57.765393) (xy 84.005139 -57.801068)
			(xy 84.042356 -57.842605) (xy 84.058692 -57.867296) (xy 85.642956 -57.867296) (xy 85.647027 -57.811674)
			(xy 85.659153 -57.757237) (xy 85.679076 -57.705146) (xy 85.706372 -57.656511) (xy 85.740458 -57.612368)
			(xy 85.780607 -57.573659) (xy 85.825965 -57.541208) (xy 85.875565 -57.515707) (xy 85.928349 -57.4977)
			(xy 85.983192 -57.48757) (xy 86.038926 -57.485533) (xy 86.094363 -57.491633) (xy 86.14832 -57.505739)
			(xy 86.199649 -57.527551) (xy 86.247255 -57.556605) (xy 86.290123 -57.59228) (xy 86.32734 -57.633817)
			(xy 86.358113 -57.68033) (xy 86.381785 -57.730827) (xy 86.397853 -57.784234) (xy 86.405973 -57.83941)
			(xy 86.406482 -57.867296) (xy 86.405973 -57.895182) (xy 86.397853 -57.950358) (xy 86.381785 -58.003765)
			(xy 86.358113 -58.054262) (xy 86.32734 -58.100775) (xy 86.290123 -58.142312) (xy 86.247255 -58.177987)
			(xy 86.199649 -58.207041) (xy 86.14832 -58.228853) (xy 86.094363 -58.242959) (xy 86.038926 -58.249059)
			(xy 85.983192 -58.247022) (xy 85.928349 -58.236892) (xy 85.875565 -58.218885) (xy 85.825965 -58.193384)
			(xy 85.780607 -58.160933) (xy 85.740458 -58.122224) (xy 85.706372 -58.078081) (xy 85.679076 -58.029446)
			(xy 85.659153 -57.977355) (xy 85.647027 -57.922918) (xy 85.642956 -57.867296) (xy 84.058692 -57.867296)
			(xy 84.073129 -57.889118) (xy 84.096801 -57.939615) (xy 84.112869 -57.993022) (xy 84.120989 -58.048198)
			(xy 84.121498 -58.076084) (xy 84.120989 -58.10397) (xy 84.112869 -58.159146) (xy 84.096801 -58.212553)
			(xy 84.073129 -58.26305) (xy 84.042356 -58.309563) (xy 84.005139 -58.3511) (xy 83.962271 -58.386775)
			(xy 83.914665 -58.415829) (xy 83.863336 -58.437641) (xy 83.809379 -58.451747) (xy 83.753942 -58.457847)
			(xy 83.698208 -58.45581) (xy 83.643365 -58.44568) (xy 83.590581 -58.427673) (xy 83.540981 -58.402172)
			(xy 83.495623 -58.369721) (xy 83.455474 -58.331012) (xy 83.421388 -58.286869) (xy 83.394092 -58.238234)
			(xy 83.374169 -58.186143) (xy 83.362043 -58.131706) (xy 83.357972 -58.076084) (xy 78.756948 -58.076084)
			(xy 78.756509 -58.10016) (xy 78.748389 -58.155336) (xy 78.732321 -58.208743) (xy 78.708649 -58.25924)
			(xy 78.677876 -58.305753) (xy 78.640659 -58.34729) (xy 78.597791 -58.382965) (xy 78.550185 -58.412019)
			(xy 78.498856 -58.433831) (xy 78.444899 -58.447937) (xy 78.389462 -58.454037) (xy 78.333728 -58.452)
			(xy 78.278885 -58.44187) (xy 78.226101 -58.423863) (xy 78.176501 -58.398362) (xy 78.131143 -58.365911)
			(xy 78.090994 -58.327202) (xy 78.056908 -58.283059) (xy 78.029612 -58.234424) (xy 78.009689 -58.182333)
			(xy 77.997563 -58.127896) (xy 77.993492 -58.072274) (xy 70.924924 -58.072274) (xy 70.939939 -58.10515)
			(xy 70.955294 -58.157445) (xy 70.96305 -58.211393) (xy 70.963536 -58.238644) (xy 70.963076 -58.265978)
			(xy 70.955268 -58.320086) (xy 70.939816 -58.372526) (xy 70.917039 -58.422224) (xy 70.887402 -58.468162)
			(xy 70.86981 -58.489088) (xy 70.869556 -58.489342) (xy 70.869302 -58.489596) (xy 70.863711 -58.49668)
			(xy 70.857467 -58.513599) (xy 70.85711 -58.522616) (xy 70.85711 -58.561224) (xy 84.562186 -58.561224)
			(xy 84.566257 -58.505602) (xy 84.578383 -58.451165) (xy 84.598306 -58.399074) (xy 84.625602 -58.350439)
			(xy 84.659688 -58.306296) (xy 84.699837 -58.267587) (xy 84.745195 -58.235136) (xy 84.794795 -58.209635)
			(xy 84.847579 -58.191628) (xy 84.902422 -58.181498) (xy 84.958156 -58.179461) (xy 85.013593 -58.185561)
			(xy 85.06755 -58.199667) (xy 85.118879 -58.221479) (xy 85.166485 -58.250533) (xy 85.209353 -58.286208)
			(xy 85.24657 -58.327745) (xy 85.277343 -58.374258) (xy 85.301015 -58.424755) (xy 85.308525 -58.449718)
			(xy 86.808816 -58.449718) (xy 86.812887 -58.394096) (xy 86.825013 -58.339659) (xy 86.844936 -58.287568)
			(xy 86.872232 -58.238933) (xy 86.906318 -58.19479) (xy 86.946467 -58.156081) (xy 86.991825 -58.12363)
			(xy 87.041425 -58.098129) (xy 87.094209 -58.080122) (xy 87.149052 -58.069992) (xy 87.204786 -58.067955)
			(xy 87.260223 -58.074055) (xy 87.31418 -58.088161) (xy 87.365509 -58.109973) (xy 87.413115 -58.139027)
			(xy 87.455983 -58.174702) (xy 87.4932 -58.216239) (xy 87.523973 -58.262752) (xy 87.547645 -58.313249)
			(xy 87.563713 -58.366656) (xy 87.571833 -58.421832) (xy 87.572342 -58.449718) (xy 87.571833 -58.477604)
			(xy 87.563713 -58.53278) (xy 87.547645 -58.586187) (xy 87.523973 -58.636684) (xy 87.4932 -58.683197)
			(xy 87.455983 -58.724734) (xy 87.447968 -58.731404) (xy 91.520518 -58.731404) (xy 91.521017 -58.704071)
			(xy 91.528818 -58.649965) (xy 91.544261 -58.597527) (xy 91.567029 -58.547828) (xy 91.596657 -58.501888)
			(xy 91.614244 -58.48096) (xy 91.614498 -58.480706) (xy 91.614752 -58.480452) (xy 91.620329 -58.473359)
			(xy 91.62658 -58.456447) (xy 91.626944 -58.447432) (xy 91.626944 -58.380376) (xy 91.626611 -58.371356)
			(xy 91.620348 -58.354439) (xy 91.614752 -58.347356) (xy 91.614498 -58.347102) (xy 91.614244 -58.346848)
			(xy 91.596649 -58.325922) (xy 91.566997 -58.279989) (xy 91.54421 -58.230292) (xy 91.528754 -58.177851)
			(xy 91.520945 -58.123739) (xy 91.520945 -58.069067) (xy 91.528752 -58.014955) (xy 91.544208 -57.962513)
			(xy 91.566994 -57.912816) (xy 91.596645 -57.866883) (xy 91.614244 -57.84596) (xy 91.614498 -57.845706)
			(xy 91.614752 -57.845452) (xy 91.620329 -57.838359) (xy 91.62658 -57.821447) (xy 91.626944 -57.812432)
			(xy 91.626944 -57.745376) (xy 91.626611 -57.736356) (xy 91.620348 -57.719439) (xy 91.614752 -57.712356)
			(xy 91.614498 -57.712102) (xy 91.614244 -57.711848) (xy 91.596649 -57.690922) (xy 91.566997 -57.644989)
			(xy 91.54421 -57.595292) (xy 91.528754 -57.542851) (xy 91.520945 -57.488739) (xy 91.520945 -57.434067)
			(xy 91.528752 -57.379955) (xy 91.544208 -57.327513) (xy 91.566994 -57.277816) (xy 91.596645 -57.231883)
			(xy 91.614244 -57.21096) (xy 91.614498 -57.210706) (xy 91.614752 -57.210452) (xy 91.620329 -57.203359)
			(xy 91.62658 -57.186447) (xy 91.626944 -57.177432) (xy 91.626944 -57.110376) (xy 91.626611 -57.101356)
			(xy 91.620348 -57.084439) (xy 91.614752 -57.077356) (xy 91.614498 -57.077102) (xy 91.614244 -57.076848)
			(xy 91.596667 -57.055909) (xy 91.567025 -57.009977) (xy 91.544245 -56.960282) (xy 91.528794 -56.907844)
			(xy 91.520988 -56.853737) (xy 91.520518 -56.826404) (xy 91.521004 -56.799153) (xy 91.52876 -56.745205)
			(xy 91.544115 -56.69291) (xy 91.566757 -56.643333) (xy 91.596223 -56.597483) (xy 91.631914 -56.556292)
			(xy 91.673105 -56.520601) (xy 91.718955 -56.491135) (xy 91.768532 -56.468493) (xy 91.820827 -56.453138)
			(xy 91.874775 -56.445382) (xy 91.929277 -56.445382) (xy 91.983225 -56.453138) (xy 92.03552 -56.468493)
			(xy 92.085097 -56.491135) (xy 92.130947 -56.520601) (xy 92.172138 -56.556292) (xy 92.207829 -56.597483)
			(xy 92.237295 -56.643333) (xy 92.259937 -56.69291) (xy 92.275292 -56.745205) (xy 92.283048 -56.799153)
			(xy 92.283534 -56.826404) (xy 92.283051 -56.853737) (xy 92.275248 -56.907845) (xy 92.259802 -56.960284)
			(xy 92.23703 -57.009982) (xy 92.207397 -57.055921) (xy 92.189808 -57.076848) (xy 92.189554 -57.077102)
			(xy 92.1893 -57.077356) (xy 92.183726 -57.084451) (xy 92.177472 -57.101361) (xy 92.177108 -57.110376)
			(xy 92.177108 -57.177432) (xy 92.177448 -57.186451) (xy 92.183707 -57.203367) (xy 92.1893 -57.210452)
			(xy 92.189554 -57.210706) (xy 92.189808 -57.21096) (xy 92.207413 -57.231878) (xy 92.237068 -57.277812)
			(xy 92.259858 -57.327509) (xy 92.275315 -57.379953) (xy 92.283124 -57.434066) (xy 92.283124 -57.48874)
			(xy 92.275314 -57.542853) (xy 92.259856 -57.595296) (xy 92.237065 -57.644994) (xy 92.20741 -57.690926)
			(xy 92.189808 -57.711848) (xy 92.189554 -57.712102) (xy 92.1893 -57.712356) (xy 92.183726 -57.719451)
			(xy 92.177472 -57.736361) (xy 92.177108 -57.745376) (xy 92.177108 -57.812432) (xy 92.177448 -57.821451)
			(xy 92.183707 -57.838367) (xy 92.1893 -57.845452) (xy 92.189554 -57.845706) (xy 92.189808 -57.84596)
			(xy 92.207413 -57.866878) (xy 92.237068 -57.912812) (xy 92.259858 -57.962509) (xy 92.275315 -58.014953)
			(xy 92.283124 -58.069066) (xy 92.283124 -58.12374) (xy 92.275314 -58.177853) (xy 92.259856 -58.230296)
			(xy 92.237065 -58.279994) (xy 92.20741 -58.325926) (xy 92.189808 -58.346848) (xy 92.189554 -58.347102)
			(xy 92.1893 -58.347356) (xy 92.183726 -58.354451) (xy 92.177472 -58.371361) (xy 92.177108 -58.380376)
			(xy 92.177108 -58.447432) (xy 92.177448 -58.456451) (xy 92.183707 -58.473367) (xy 92.1893 -58.480452)
			(xy 92.189554 -58.480706) (xy 92.189808 -58.48096) (xy 92.207396 -58.501889) (xy 92.237035 -58.547825)
			(xy 92.259812 -58.597522) (xy 92.275261 -58.649962) (xy 92.283065 -58.70407) (xy 92.283534 -58.731404)
			(xy 92.283048 -58.758655) (xy 92.278384 -58.791094) (xy 94.176342 -58.791094) (xy 94.176829 -58.763761)
			(xy 94.184632 -58.709654) (xy 94.200077 -58.657215) (xy 94.222848 -58.607517) (xy 94.252479 -58.561578)
			(xy 94.270068 -58.54065) (xy 94.270322 -58.540396) (xy 94.270576 -58.540142) (xy 94.27616 -58.533054)
			(xy 94.282406 -58.516138) (xy 94.282768 -58.507122) (xy 94.282768 -58.440066) (xy 94.282434 -58.431047)
			(xy 94.276171 -58.414129) (xy 94.270576 -58.407046) (xy 94.270322 -58.406792) (xy 94.270068 -58.406538)
			(xy 94.252462 -58.385621) (xy 94.222809 -58.339687) (xy 94.200021 -58.289989) (xy 94.184564 -58.237545)
			(xy 94.176756 -58.183432) (xy 94.176757 -58.128759) (xy 94.184566 -58.074646) (xy 94.200024 -58.022203)
			(xy 94.222813 -57.972505) (xy 94.252467 -57.926572) (xy 94.270068 -57.90565) (xy 94.270322 -57.905396)
			(xy 94.270576 -57.905142) (xy 94.27616 -57.898054) (xy 94.282406 -57.881138) (xy 94.282768 -57.872122)
			(xy 94.282768 -57.805066) (xy 94.282434 -57.796047) (xy 94.276171 -57.779129) (xy 94.270576 -57.772046)
			(xy 94.270322 -57.771792) (xy 94.270068 -57.771538) (xy 94.252475 -57.750613) (xy 94.222838 -57.704675)
			(xy 94.200062 -57.654977) (xy 94.184614 -57.602537) (xy 94.176811 -57.548428) (xy 94.176342 -57.521094)
			(xy 94.176342 -57.52084) (xy 94.176814 -57.494545) (xy 94.184055 -57.442457) (xy 94.198377 -57.391855)
			(xy 94.21951 -57.343699) (xy 94.247053 -57.298899) (xy 94.280486 -57.258304) (xy 94.299532 -57.24017)
			(xy 94.306975 -57.2326) (xy 94.315502 -57.213181) (xy 94.316042 -57.202578) (xy 94.316042 -57.12841)
			(xy 94.315606 -57.117781) (xy 94.307074 -57.098318) (xy 94.299532 -57.090818) (xy 94.280482 -57.072683)
			(xy 94.247024 -57.032103) (xy 94.219463 -56.987308) (xy 94.198322 -56.93915) (xy 94.184004 -56.888541)
			(xy 94.17678 -56.836445) (xy 94.176342 -56.810148) (xy 94.176342 -56.809894) (xy 94.176828 -56.782643)
			(xy 94.184584 -56.728695) (xy 94.199939 -56.6764) (xy 94.222581 -56.626823) (xy 94.252047 -56.580973)
			(xy 94.287738 -56.539782) (xy 94.328929 -56.504091) (xy 94.374779 -56.474625) (xy 94.424356 -56.451983)
			(xy 94.476651 -56.436628) (xy 94.530599 -56.428872) (xy 94.585101 -56.428872) (xy 94.639049 -56.436628)
			(xy 94.691344 -56.451983) (xy 94.740921 -56.474625) (xy 94.786771 -56.504091) (xy 94.827962 -56.539782)
			(xy 94.863653 -56.580973) (xy 94.893119 -56.626823) (xy 94.915761 -56.6764) (xy 94.931116 -56.728695)
			(xy 94.938872 -56.782643) (xy 94.939358 -56.809894) (xy 94.939358 -56.810148) (xy 94.938945 -56.836445)
			(xy 94.931692 -56.888536) (xy 94.917358 -56.939138) (xy 94.896214 -56.987295) (xy 94.86866 -57.032093)
			(xy 94.835219 -57.072686) (xy 94.816168 -57.090818) (xy 94.80873 -57.098393) (xy 94.800201 -57.117808)
			(xy 94.799658 -57.12841) (xy 94.799658 -57.202578) (xy 94.8001 -57.213206) (xy 94.808628 -57.23267)
			(xy 94.816168 -57.24017) (xy 94.835212 -57.25831) (xy 94.868671 -57.298889) (xy 94.896233 -57.343683)
			(xy 94.917374 -57.391841) (xy 94.931694 -57.442448) (xy 94.935106 -57.467053) (xy 95.118369 -57.467053)
			(xy 95.118369 -57.412547) (xy 95.126127 -57.358595) (xy 95.141484 -57.306297) (xy 95.164127 -57.256717)
			(xy 95.193597 -57.210864) (xy 95.229292 -57.169672) (xy 95.270487 -57.13398) (xy 95.316342 -57.104514)
			(xy 95.365924 -57.081874) (xy 95.418223 -57.066521) (xy 95.472175 -57.058767) (xy 95.499428 -57.058306)
			(xy 95.499682 -57.058306) (xy 95.525977 -57.058775) (xy 95.578065 -57.066018) (xy 95.628666 -57.080342)
			(xy 95.676822 -57.101475) (xy 95.721622 -57.129019) (xy 95.762217 -57.16245) (xy 95.780352 -57.181496)
			(xy 95.787906 -57.188958) (xy 95.807337 -57.197471) (xy 95.817944 -57.198006) (xy 95.892112 -57.198006)
			(xy 95.902744 -57.197593) (xy 95.922208 -57.189046) (xy 95.929704 -57.181496) (xy 95.947821 -57.162429)
			(xy 95.988405 -57.128973) (xy 96.033204 -57.101416) (xy 96.081367 -57.080278) (xy 96.131977 -57.065963)
			(xy 96.184076 -57.058743) (xy 96.210374 -57.058306) (xy 96.210628 -57.058306) (xy 96.237879 -57.058766)
			(xy 96.291826 -57.066526) (xy 96.326972 -57.076848) (xy 97.13849 -57.076848) (xy 97.138963 -57.049514)
			(xy 97.146771 -56.995408) (xy 97.16222 -56.942969) (xy 97.184994 -56.893271) (xy 97.214627 -56.847332)
			(xy 97.232216 -56.826404) (xy 97.23247 -56.82615) (xy 97.232724 -56.825896) (xy 97.238321 -56.818817)
			(xy 97.244561 -56.801894) (xy 97.244916 -56.792876) (xy 97.244916 -56.72582) (xy 97.244546 -56.716805)
			(xy 97.238307 -56.699888) (xy 97.232724 -56.6928) (xy 97.23247 -56.692546) (xy 97.232216 -56.692292)
			(xy 97.214609 -56.671378) (xy 97.184972 -56.625438) (xy 97.162198 -56.575737) (xy 97.146754 -56.523294)
			(xy 97.138956 -56.469183) (xy 97.13849 -56.441848) (xy 97.138976 -56.414597) (xy 97.146732 -56.360649)
			(xy 97.162087 -56.308354) (xy 97.184729 -56.258777) (xy 97.214195 -56.212927) (xy 97.249886 -56.171736)
			(xy 97.291077 -56.136045) (xy 97.336927 -56.106579) (xy 97.386504 -56.083937) (xy 97.438799 -56.068582)
			(xy 97.492747 -56.060826) (xy 97.547249 -56.060826) (xy 97.601197 -56.068582) (xy 97.653492 -56.083937)
			(xy 97.703069 -56.106579) (xy 97.748919 -56.136045) (xy 97.79011 -56.171736) (xy 97.825801 -56.212927)
			(xy 97.855267 -56.258777) (xy 97.877909 -56.308354) (xy 97.891152 -56.353456) (xy 104.941114 -56.353456)
			(xy 104.945185 -56.297834) (xy 104.957311 -56.243397) (xy 104.977234 -56.191306) (xy 105.00453 -56.142671)
			(xy 105.038616 -56.098528) (xy 105.078765 -56.059819) (xy 105.124123 -56.027368) (xy 105.173723 -56.001867)
			(xy 105.226507 -55.98386) (xy 105.28135 -55.97373) (xy 105.337084 -55.971693) (xy 105.392521 -55.977793)
			(xy 105.446478 -55.991899) (xy 105.497807 -56.013711) (xy 105.545413 -56.042765) (xy 105.588281 -56.07844)
			(xy 105.625498 -56.119977) (xy 105.656271 -56.16649) (xy 105.679943 -56.216987) (xy 105.696011 -56.270394)
			(xy 105.704131 -56.32557) (xy 105.70464 -56.353456) (xy 105.704131 -56.381342) (xy 105.696011 -56.436518)
			(xy 105.679943 -56.489925) (xy 105.656271 -56.540422) (xy 105.625498 -56.586935) (xy 105.588281 -56.628472)
			(xy 105.545413 -56.664147) (xy 105.497807 -56.693201) (xy 105.446478 -56.715013) (xy 105.392521 -56.729119)
			(xy 105.337084 -56.735219) (xy 105.28135 -56.733182) (xy 105.226507 -56.723052) (xy 105.173723 -56.705045)
			(xy 105.124123 -56.679544) (xy 105.078765 -56.647093) (xy 105.038616 -56.608384) (xy 105.00453 -56.564241)
			(xy 104.977234 -56.515606) (xy 104.957311 -56.463515) (xy 104.945185 -56.409078) (xy 104.941114 -56.353456)
			(xy 97.891152 -56.353456) (xy 97.893264 -56.360649) (xy 97.90102 -56.414597) (xy 97.901506 -56.441848)
			(xy 97.901032 -56.469182) (xy 97.893224 -56.523288) (xy 97.877775 -56.575727) (xy 97.855001 -56.625425)
			(xy 97.825369 -56.671364) (xy 97.80778 -56.692292) (xy 97.807526 -56.692546) (xy 97.807272 -56.6928)
			(xy 97.801676 -56.69988) (xy 97.795436 -56.716802) (xy 97.79508 -56.72582) (xy 97.79508 -56.792876)
			(xy 97.795453 -56.801891) (xy 97.80169 -56.818808) (xy 97.807272 -56.825896) (xy 97.807526 -56.82615)
			(xy 97.80778 -56.826404) (xy 97.825385 -56.84732) (xy 97.855022 -56.893259) (xy 97.877796 -56.94296)
			(xy 97.893241 -56.995402) (xy 97.90104 -57.049513) (xy 97.901506 -57.076848) (xy 97.90102 -57.104099)
			(xy 97.893264 -57.158047) (xy 97.877909 -57.210342) (xy 97.855267 -57.259919) (xy 97.825801 -57.305769)
			(xy 97.79011 -57.34696) (xy 97.748919 -57.382651) (xy 97.703069 -57.412117) (xy 97.653492 -57.434759)
			(xy 97.601197 -57.450114) (xy 97.547249 -57.45787) (xy 97.492747 -57.45787) (xy 97.438799 -57.450114)
			(xy 97.386504 -57.434759) (xy 97.336927 -57.412117) (xy 97.291077 -57.382651) (xy 97.249886 -57.34696)
			(xy 97.214195 -57.305769) (xy 97.184729 -57.259919) (xy 97.162087 -57.210342) (xy 97.146732 -57.158047)
			(xy 97.138976 -57.104099) (xy 97.13849 -57.076848) (xy 96.326972 -57.076848) (xy 96.344119 -57.081884)
			(xy 96.393694 -57.104527) (xy 96.439543 -57.133996) (xy 96.480731 -57.169688) (xy 96.516421 -57.210879)
			(xy 96.545886 -57.25673) (xy 96.568526 -57.306307) (xy 96.58388 -57.358602) (xy 96.591636 -57.412549)
			(xy 96.591636 -57.467051) (xy 96.589015 -57.48528) (xy 120.706132 -57.48528) (xy 120.710203 -57.429658)
			(xy 120.722329 -57.375221) (xy 120.742252 -57.32313) (xy 120.769548 -57.274495) (xy 120.803634 -57.230352)
			(xy 120.843783 -57.191643) (xy 120.889141 -57.159192) (xy 120.938741 -57.133691) (xy 120.991525 -57.115684)
			(xy 121.046368 -57.105554) (xy 121.102102 -57.103517) (xy 121.157539 -57.109617) (xy 121.211496 -57.123723)
			(xy 121.262825 -57.145535) (xy 121.310431 -57.174589) (xy 121.353299 -57.210264) (xy 121.390516 -57.251801)
			(xy 121.421289 -57.298314) (xy 121.444961 -57.348811) (xy 121.461029 -57.402218) (xy 121.469149 -57.457394)
			(xy 121.469658 -57.48528) (xy 121.469149 -57.513166) (xy 121.461029 -57.568342) (xy 121.444961 -57.621749)
			(xy 121.421289 -57.672246) (xy 121.390516 -57.718759) (xy 121.353299 -57.760296) (xy 121.310431 -57.795971)
			(xy 121.262825 -57.825025) (xy 121.211496 -57.846837) (xy 121.157539 -57.860943) (xy 121.102102 -57.867043)
			(xy 121.046368 -57.865006) (xy 120.991525 -57.854876) (xy 120.938741 -57.836869) (xy 120.889141 -57.811368)
			(xy 120.843783 -57.778917) (xy 120.803634 -57.740208) (xy 120.769548 -57.696065) (xy 120.742252 -57.64743)
			(xy 120.722329 -57.595339) (xy 120.710203 -57.540902) (xy 120.706132 -57.48528) (xy 96.589015 -57.48528)
			(xy 96.58388 -57.520998) (xy 96.568526 -57.573293) (xy 96.545886 -57.62287) (xy 96.516421 -57.668721)
			(xy 96.480731 -57.709912) (xy 96.439543 -57.745604) (xy 96.393694 -57.775073) (xy 96.344119 -57.797716)
			(xy 96.291826 -57.813074) (xy 96.237879 -57.820834) (xy 96.210628 -57.821322) (xy 96.210374 -57.821322)
			(xy 96.184079 -57.820874) (xy 96.13199 -57.813625) (xy 96.081389 -57.799297) (xy 96.033233 -57.778159)
			(xy 95.988433 -57.750613) (xy 95.947838 -57.717179) (xy 95.929704 -57.698132) (xy 95.922126 -57.690698)
			(xy 95.902713 -57.682168) (xy 95.892112 -57.681622) (xy 95.817944 -57.681622) (xy 95.807308 -57.682003)
			(xy 95.787844 -57.690571) (xy 95.780352 -57.698132) (xy 95.762243 -57.717207) (xy 95.721658 -57.750664)
			(xy 95.676858 -57.778223) (xy 95.628694 -57.799359) (xy 95.578081 -57.813672) (xy 95.525981 -57.820888)
			(xy 95.499682 -57.821322) (xy 95.499428 -57.821322) (xy 95.472175 -57.820833) (xy 95.418223 -57.813079)
			(xy 95.365924 -57.797726) (xy 95.316342 -57.775086) (xy 95.270487 -57.74562) (xy 95.229292 -57.709928)
			(xy 95.193597 -57.668736) (xy 95.164127 -57.622883) (xy 95.141484 -57.573303) (xy 95.126127 -57.521005)
			(xy 95.118369 -57.467053) (xy 94.935106 -57.467053) (xy 94.938919 -57.494543) (xy 94.939358 -57.52084)
			(xy 94.939358 -57.521094) (xy 94.938864 -57.548427) (xy 94.931062 -57.602533) (xy 94.915619 -57.654972)
			(xy 94.892849 -57.704671) (xy 94.86322 -57.75061) (xy 94.845632 -57.771538) (xy 94.845378 -57.771792)
			(xy 94.845124 -57.772046) (xy 94.839545 -57.779137) (xy 94.833296 -57.796051) (xy 94.832932 -57.805066)
			(xy 94.832932 -57.872122) (xy 94.833271 -57.881141) (xy 94.83953 -57.898058) (xy 94.845124 -57.905142)
			(xy 94.845378 -57.905396) (xy 94.845632 -57.90565) (xy 94.863226 -57.926577) (xy 94.89288 -57.972509)
			(xy 94.915669 -58.022206) (xy 94.931126 -58.074647) (xy 94.938935 -58.128759) (xy 94.938936 -58.183432)
			(xy 94.931128 -58.237544) (xy 94.915672 -58.289986) (xy 94.892884 -58.339683) (xy 94.863232 -58.385616)
			(xy 94.845632 -58.406538) (xy 94.845378 -58.406792) (xy 94.845124 -58.407046) (xy 94.839545 -58.414137)
			(xy 94.833296 -58.431051) (xy 94.832932 -58.440066) (xy 94.832932 -58.507122) (xy 94.833271 -58.516141)
			(xy 94.83953 -58.533058) (xy 94.845124 -58.540142) (xy 94.845378 -58.540396) (xy 94.845632 -58.54065)
			(xy 94.863219 -58.56158) (xy 94.892857 -58.607516) (xy 94.915634 -58.657213) (xy 94.931083 -58.709652)
			(xy 94.938888 -58.76376) (xy 94.939358 -58.791094) (xy 94.938872 -58.818345) (xy 94.931116 -58.872293)
			(xy 94.930719 -58.873644) (xy 96.200468 -58.873644) (xy 96.20092 -58.846309) (xy 96.20873 -58.792201)
			(xy 96.224183 -58.739761) (xy 96.246963 -58.690064) (xy 96.276602 -58.644126) (xy 96.294194 -58.6232)
			(xy 96.294448 -58.622946) (xy 96.294702 -58.622692) (xy 96.300298 -58.615612) (xy 96.306539 -58.59869)
			(xy 96.306894 -58.589672) (xy 96.306894 -58.522616) (xy 96.306531 -58.5136) (xy 96.300288 -58.496683)
			(xy 96.294702 -58.489596) (xy 96.294448 -58.489342) (xy 96.294194 -58.489088) (xy 96.276582 -58.468178)
			(xy 96.246946 -58.422237) (xy 96.224174 -58.372535) (xy 96.208731 -58.320091) (xy 96.200933 -58.265979)
			(xy 96.200468 -58.238644) (xy 96.200954 -58.211393) (xy 96.20871 -58.157445) (xy 96.224065 -58.10515)
			(xy 96.246707 -58.055573) (xy 96.276173 -58.009723) (xy 96.311864 -57.968532) (xy 96.353055 -57.932841)
			(xy 96.398905 -57.903375) (xy 96.448482 -57.880733) (xy 96.500777 -57.865378) (xy 96.554725 -57.857622)
			(xy 96.609227 -57.857622) (xy 96.663175 -57.865378) (xy 96.71547 -57.880733) (xy 96.765047 -57.903375)
			(xy 96.810897 -57.932841) (xy 96.852088 -57.968532) (xy 96.887779 -58.009723) (xy 96.917245 -58.055573)
			(xy 96.924872 -58.072274) (xy 103.99344 -58.072274) (xy 103.997511 -58.016652) (xy 104.009637 -57.962215)
			(xy 104.02956 -57.910124) (xy 104.056856 -57.861489) (xy 104.090942 -57.817346) (xy 104.131091 -57.778637)
			(xy 104.176449 -57.746186) (xy 104.226049 -57.720685) (xy 104.278833 -57.702678) (xy 104.333676 -57.692548)
			(xy 104.38941 -57.690511) (xy 104.444847 -57.696611) (xy 104.498804 -57.710717) (xy 104.550133 -57.732529)
			(xy 104.597739 -57.761583) (xy 104.640607 -57.797258) (xy 104.677824 -57.838795) (xy 104.708597 -57.885308)
			(xy 104.732269 -57.935805) (xy 104.748337 -57.989212) (xy 104.756457 -58.044388) (xy 104.756966 -58.072274)
			(xy 104.756896 -58.076084) (xy 121.458226 -58.076084) (xy 121.462297 -58.020462) (xy 121.474423 -57.966025)
			(xy 121.494346 -57.913934) (xy 121.521642 -57.865299) (xy 121.555728 -57.821156) (xy 121.595877 -57.782447)
			(xy 121.641235 -57.749996) (xy 121.690835 -57.724495) (xy 121.743619 -57.706488) (xy 121.798462 -57.696358)
			(xy 121.854196 -57.694321) (xy 121.909633 -57.700421) (xy 121.96359 -57.714527) (xy 122.014919 -57.736339)
			(xy 122.062525 -57.765393) (xy 122.105393 -57.801068) (xy 122.14261 -57.842605) (xy 122.158946 -57.867296)
			(xy 123.74321 -57.867296) (xy 123.747281 -57.811674) (xy 123.759407 -57.757237) (xy 123.77933 -57.705146)
			(xy 123.806626 -57.656511) (xy 123.840712 -57.612368) (xy 123.880861 -57.573659) (xy 123.926219 -57.541208)
			(xy 123.975819 -57.515707) (xy 124.028603 -57.4977) (xy 124.083446 -57.48757) (xy 124.13918 -57.485533)
			(xy 124.194617 -57.491633) (xy 124.248574 -57.505739) (xy 124.299903 -57.527551) (xy 124.347509 -57.556605)
			(xy 124.390377 -57.59228) (xy 124.427594 -57.633817) (xy 124.458367 -57.68033) (xy 124.482039 -57.730827)
			(xy 124.498107 -57.784234) (xy 124.506227 -57.83941) (xy 124.506736 -57.867296) (xy 124.506227 -57.895182)
			(xy 124.498107 -57.950358) (xy 124.482039 -58.003765) (xy 124.458367 -58.054262) (xy 124.427594 -58.100775)
			(xy 124.390377 -58.142312) (xy 124.347509 -58.177987) (xy 124.299903 -58.207041) (xy 124.248574 -58.228853)
			(xy 124.194617 -58.242959) (xy 124.13918 -58.249059) (xy 124.083446 -58.247022) (xy 124.028603 -58.236892)
			(xy 123.975819 -58.218885) (xy 123.926219 -58.193384) (xy 123.880861 -58.160933) (xy 123.840712 -58.122224)
			(xy 123.806626 -58.078081) (xy 123.77933 -58.029446) (xy 123.759407 -57.977355) (xy 123.747281 -57.922918)
			(xy 123.74321 -57.867296) (xy 122.158946 -57.867296) (xy 122.173383 -57.889118) (xy 122.197055 -57.939615)
			(xy 122.213123 -57.993022) (xy 122.221243 -58.048198) (xy 122.221752 -58.076084) (xy 122.221243 -58.10397)
			(xy 122.213123 -58.159146) (xy 122.197055 -58.212553) (xy 122.173383 -58.26305) (xy 122.14261 -58.309563)
			(xy 122.105393 -58.3511) (xy 122.062525 -58.386775) (xy 122.014919 -58.415829) (xy 121.96359 -58.437641)
			(xy 121.909633 -58.451747) (xy 121.854196 -58.457847) (xy 121.798462 -58.45581) (xy 121.743619 -58.44568)
			(xy 121.690835 -58.427673) (xy 121.641235 -58.402172) (xy 121.595877 -58.369721) (xy 121.555728 -58.331012)
			(xy 121.521642 -58.286869) (xy 121.494346 -58.238234) (xy 121.474423 -58.186143) (xy 121.462297 -58.131706)
			(xy 121.458226 -58.076084) (xy 104.756896 -58.076084) (xy 104.756457 -58.10016) (xy 104.748337 -58.155336)
			(xy 104.732269 -58.208743) (xy 104.708597 -58.25924) (xy 104.677824 -58.305753) (xy 104.640607 -58.34729)
			(xy 104.597739 -58.382965) (xy 104.550133 -58.412019) (xy 104.498804 -58.433831) (xy 104.444847 -58.447937)
			(xy 104.38941 -58.454037) (xy 104.333676 -58.452) (xy 104.278833 -58.44187) (xy 104.226049 -58.423863)
			(xy 104.176449 -58.398362) (xy 104.131091 -58.365911) (xy 104.090942 -58.327202) (xy 104.056856 -58.283059)
			(xy 104.02956 -58.234424) (xy 104.009637 -58.182333) (xy 103.997511 -58.127896) (xy 103.99344 -58.072274)
			(xy 96.924872 -58.072274) (xy 96.939887 -58.10515) (xy 96.955242 -58.157445) (xy 96.962998 -58.211393)
			(xy 96.963484 -58.238644) (xy 96.963013 -58.265978) (xy 96.955205 -58.320085) (xy 96.939756 -58.372524)
			(xy 96.916981 -58.422222) (xy 96.887348 -58.468161) (xy 96.869758 -58.489088) (xy 96.869504 -58.489342)
			(xy 96.86925 -58.489596) (xy 96.863653 -58.496675) (xy 96.857414 -58.513598) (xy 96.857058 -58.522616)
			(xy 96.857058 -58.561224) (xy 122.66244 -58.561224) (xy 122.666511 -58.505602) (xy 122.678637 -58.451165)
			(xy 122.69856 -58.399074) (xy 122.725856 -58.350439) (xy 122.759942 -58.306296) (xy 122.800091 -58.267587)
			(xy 122.845449 -58.235136) (xy 122.895049 -58.209635) (xy 122.947833 -58.191628) (xy 123.002676 -58.181498)
			(xy 123.05841 -58.179461) (xy 123.113847 -58.185561) (xy 123.167804 -58.199667) (xy 123.219133 -58.221479)
			(xy 123.266739 -58.250533) (xy 123.309607 -58.286208) (xy 123.346824 -58.327745) (xy 123.377597 -58.374258)
			(xy 123.401269 -58.424755) (xy 123.408779 -58.449718) (xy 124.90907 -58.449718) (xy 124.913141 -58.394096)
			(xy 124.925267 -58.339659) (xy 124.94519 -58.287568) (xy 124.972486 -58.238933) (xy 125.006572 -58.19479)
			(xy 125.046721 -58.156081) (xy 125.092079 -58.12363) (xy 125.141679 -58.098129) (xy 125.194463 -58.080122)
			(xy 125.249306 -58.069992) (xy 125.30504 -58.067955) (xy 125.360477 -58.074055) (xy 125.414434 -58.088161)
			(xy 125.465763 -58.109973) (xy 125.513369 -58.139027) (xy 125.556237 -58.174702) (xy 125.593454 -58.216239)
			(xy 125.624227 -58.262752) (xy 125.647899 -58.313249) (xy 125.663967 -58.366656) (xy 125.672087 -58.421832)
			(xy 125.672596 -58.449718) (xy 125.672087 -58.477604) (xy 125.663967 -58.53278) (xy 125.647899 -58.586187)
			(xy 125.624227 -58.636684) (xy 125.593454 -58.683197) (xy 125.556237 -58.724734) (xy 125.548222 -58.731404)
			(xy 129.620772 -58.731404) (xy 129.621258 -58.704071) (xy 129.629061 -58.649964) (xy 129.644506 -58.597524)
			(xy 129.667277 -58.547826) (xy 129.696909 -58.501887) (xy 129.714498 -58.48096) (xy 129.714752 -58.480706)
			(xy 129.715006 -58.480452) (xy 129.720578 -58.473355) (xy 129.726833 -58.456446) (xy 129.727198 -58.447432)
			(xy 129.727198 -58.380376) (xy 129.726853 -58.371358) (xy 129.720597 -58.354441) (xy 129.715006 -58.347356)
			(xy 129.714752 -58.347102) (xy 129.714498 -58.346848) (xy 129.6969 -58.325923) (xy 129.667245 -58.279991)
			(xy 129.644454 -58.230295) (xy 129.628996 -58.177852) (xy 129.621186 -58.12374) (xy 129.621186 -58.069066)
			(xy 129.628994 -58.014954) (xy 129.644452 -57.962511) (xy 129.667242 -57.912814) (xy 129.696897 -57.866881)
			(xy 129.714498 -57.84596) (xy 129.714752 -57.845706) (xy 129.715006 -57.845452) (xy 129.720578 -57.838355)
			(xy 129.726833 -57.821446) (xy 129.727198 -57.812432) (xy 129.727198 -57.745376) (xy 129.726853 -57.736358)
			(xy 129.720597 -57.719441) (xy 129.715006 -57.712356) (xy 129.714752 -57.712102) (xy 129.714498 -57.711848)
			(xy 129.6969 -57.690923) (xy 129.667245 -57.644991) (xy 129.644454 -57.595295) (xy 129.628996 -57.542852)
			(xy 129.621186 -57.48874) (xy 129.621186 -57.434066) (xy 129.628994 -57.379954) (xy 129.644452 -57.327511)
			(xy 129.667242 -57.277814) (xy 129.696897 -57.231881) (xy 129.714498 -57.21096) (xy 129.714752 -57.210706)
			(xy 129.715006 -57.210452) (xy 129.720578 -57.203355) (xy 129.726833 -57.186446) (xy 129.727198 -57.177432)
			(xy 129.727198 -57.110376) (xy 129.726853 -57.101358) (xy 129.720597 -57.084441) (xy 129.715006 -57.077356)
			(xy 129.714752 -57.077102) (xy 129.714498 -57.076848) (xy 129.696914 -57.055915) (xy 129.667275 -57.00998)
			(xy 129.644497 -56.960284) (xy 129.629047 -56.907845) (xy 129.621242 -56.853738) (xy 129.620772 -56.826404)
			(xy 129.621258 -56.799153) (xy 129.629014 -56.745205) (xy 129.644369 -56.69291) (xy 129.667011 -56.643333)
			(xy 129.696477 -56.597483) (xy 129.732168 -56.556292) (xy 129.773359 -56.520601) (xy 129.819209 -56.491135)
			(xy 129.868786 -56.468493) (xy 129.921081 -56.453138) (xy 129.975029 -56.445382) (xy 130.029531 -56.445382)
			(xy 130.083479 -56.453138) (xy 130.135774 -56.468493) (xy 130.185351 -56.491135) (xy 130.231201 -56.520601)
			(xy 130.272392 -56.556292) (xy 130.308083 -56.597483) (xy 130.337549 -56.643333) (xy 130.360191 -56.69291)
			(xy 130.375546 -56.745205) (xy 130.383302 -56.799153) (xy 130.383788 -56.826404) (xy 130.383292 -56.853737)
			(xy 130.37549 -56.907843) (xy 130.360047 -56.960282) (xy 130.337278 -57.00998) (xy 130.307649 -57.05592)
			(xy 130.290062 -57.076848) (xy 130.289808 -57.077102) (xy 130.289554 -57.077356) (xy 130.283974 -57.084447)
			(xy 130.277725 -57.101361) (xy 130.277362 -57.110376) (xy 130.277362 -57.177432) (xy 130.277712 -57.186449)
			(xy 130.283965 -57.203366) (xy 130.289554 -57.210452) (xy 130.289808 -57.210706) (xy 130.290062 -57.21096)
			(xy 130.307665 -57.23188) (xy 130.337315 -57.277814) (xy 130.360102 -57.327512) (xy 130.375558 -57.379954)
			(xy 130.383365 -57.434067) (xy 130.383365 -57.488739) (xy 130.375556 -57.542852) (xy 130.3601 -57.595294)
			(xy 130.337313 -57.644992) (xy 130.307661 -57.690925) (xy 130.290062 -57.711848) (xy 130.289808 -57.712102)
			(xy 130.289554 -57.712356) (xy 130.283974 -57.719447) (xy 130.277725 -57.736361) (xy 130.277362 -57.745376)
			(xy 130.277362 -57.812432) (xy 130.277712 -57.821449) (xy 130.283965 -57.838366) (xy 130.289554 -57.845452)
			(xy 130.289808 -57.845706) (xy 130.290062 -57.84596) (xy 130.307665 -57.86688) (xy 130.337315 -57.912814)
			(xy 130.360102 -57.962512) (xy 130.375558 -58.014954) (xy 130.383365 -58.069067) (xy 130.383365 -58.123739)
			(xy 130.375556 -58.177852) (xy 130.3601 -58.230294) (xy 130.337313 -58.279992) (xy 130.307661 -58.325925)
			(xy 130.290062 -58.346848) (xy 130.289808 -58.347102) (xy 130.289554 -58.347356) (xy 130.283974 -58.354447)
			(xy 130.277725 -58.371361) (xy 130.277362 -58.380376) (xy 130.277362 -58.447432) (xy 130.277712 -58.456449)
			(xy 130.283965 -58.473366) (xy 130.289554 -58.480452) (xy 130.289808 -58.480706) (xy 130.290062 -58.48096)
			(xy 130.307643 -58.501895) (xy 130.337285 -58.547829) (xy 130.360064 -58.597524) (xy 130.375514 -58.649963)
			(xy 130.383319 -58.70407) (xy 130.383788 -58.731404) (xy 130.383302 -58.758655) (xy 130.378638 -58.791094)
			(xy 132.276596 -58.791094) (xy 132.277095 -58.763761) (xy 132.284896 -58.709656) (xy 132.30034 -58.657217)
			(xy 132.323108 -58.607519) (xy 132.352735 -58.561579) (xy 132.370322 -58.54065) (xy 132.370576 -58.540396)
			(xy 132.37083 -58.540142) (xy 132.376408 -58.53305) (xy 132.382659 -58.516137) (xy 132.383022 -58.507122)
			(xy 132.383022 -58.440066) (xy 132.382677 -58.431048) (xy 132.376421 -58.414131) (xy 132.37083 -58.407046)
			(xy 132.370576 -58.406792) (xy 132.370322 -58.406538) (xy 132.352718 -58.38562) (xy 132.323069 -58.339685)
			(xy 132.300283 -58.289987) (xy 132.284828 -58.237544) (xy 132.277021 -58.183432) (xy 132.277022 -58.128759)
			(xy 132.28483 -58.074647) (xy 132.300286 -58.022205) (xy 132.323073 -57.972507) (xy 132.352723 -57.926573)
			(xy 132.370322 -57.90565) (xy 132.370576 -57.905396) (xy 132.37083 -57.905142) (xy 132.376408 -57.89805)
			(xy 132.382659 -57.881137) (xy 132.383022 -57.872122) (xy 132.383022 -57.805066) (xy 132.382677 -57.796048)
			(xy 132.376421 -57.779131) (xy 132.37083 -57.772046) (xy 132.370576 -57.771792) (xy 132.370322 -57.771538)
			(xy 132.352737 -57.750606) (xy 132.323097 -57.704671) (xy 132.300319 -57.654975) (xy 132.284869 -57.602536)
			(xy 132.277065 -57.548428) (xy 132.276596 -57.521094) (xy 132.276596 -57.52084) (xy 132.277083 -57.494546)
			(xy 132.284322 -57.442459) (xy 132.298643 -57.391858) (xy 132.319773 -57.343702) (xy 132.347313 -57.298901)
			(xy 132.380742 -57.258305) (xy 132.399786 -57.24017) (xy 132.407237 -57.232607) (xy 132.415757 -57.213182)
			(xy 132.416296 -57.202578) (xy 132.416296 -57.12841) (xy 132.415874 -57.117779) (xy 132.407334 -57.098315)
			(xy 132.399786 -57.090818) (xy 132.380727 -57.072693) (xy 132.347272 -57.032109) (xy 132.319713 -56.987312)
			(xy 132.298574 -56.939152) (xy 132.284257 -56.888543) (xy 132.277034 -56.836446) (xy 132.276596 -56.810148)
			(xy 132.276596 -56.809894) (xy 132.277082 -56.782643) (xy 132.284838 -56.728695) (xy 132.300193 -56.6764)
			(xy 132.322835 -56.626823) (xy 132.352301 -56.580973) (xy 132.387992 -56.539782) (xy 132.429183 -56.504091)
			(xy 132.475033 -56.474625) (xy 132.52461 -56.451983) (xy 132.576905 -56.436628) (xy 132.630853 -56.428872)
			(xy 132.685355 -56.428872) (xy 132.739303 -56.436628) (xy 132.791598 -56.451983) (xy 132.841175 -56.474625)
			(xy 132.887025 -56.504091) (xy 132.928216 -56.539782) (xy 132.963907 -56.580973) (xy 132.993373 -56.626823)
			(xy 133.016015 -56.6764) (xy 133.03137 -56.728695) (xy 133.039126 -56.782643) (xy 133.039612 -56.809894)
			(xy 133.039612 -56.810148) (xy 133.039181 -56.836444) (xy 133.03193 -56.888534) (xy 133.017598 -56.939135)
			(xy 132.996457 -56.987291) (xy 132.968908 -57.03209) (xy 132.93547 -57.072684) (xy 132.916422 -57.090818)
			(xy 132.908977 -57.098387) (xy 132.900453 -57.117807) (xy 132.899912 -57.12841) (xy 132.899912 -57.202578)
			(xy 132.900338 -57.213208) (xy 132.908875 -57.232673) (xy 132.916422 -57.24017) (xy 132.935476 -57.2583)
			(xy 132.968932 -57.298882) (xy 132.996491 -57.343678) (xy 133.01763 -57.391838) (xy 133.031948 -57.442446)
			(xy 133.03536 -57.467049) (xy 133.218692 -57.467049) (xy 133.218692 -57.412551) (xy 133.226448 -57.358607)
			(xy 133.241802 -57.306315) (xy 133.264441 -57.256741) (xy 133.293904 -57.210893) (xy 133.329592 -57.169705)
			(xy 133.370779 -57.134015) (xy 133.416625 -57.104549) (xy 133.466198 -57.081908) (xy 133.518489 -57.066552)
			(xy 133.572433 -57.058793) (xy 133.599682 -57.058306) (xy 133.599936 -57.058306) (xy 133.626232 -57.058739)
			(xy 133.678322 -57.065989) (xy 133.728924 -57.08032) (xy 133.77708 -57.10146) (xy 133.821879 -57.12901)
			(xy 133.862472 -57.162447) (xy 133.880606 -57.181496) (xy 133.888177 -57.188938) (xy 133.907595 -57.197463)
			(xy 133.918198 -57.198006) (xy 133.992366 -57.198006) (xy 134.003001 -57.197622) (xy 134.022465 -57.189055)
			(xy 134.029958 -57.181496) (xy 134.048097 -57.162451) (xy 134.088677 -57.128994) (xy 134.133471 -57.101433)
			(xy 134.181629 -57.080292) (xy 134.232236 -57.065972) (xy 134.284331 -57.058746) (xy 134.310628 -57.058306)
			(xy 134.310882 -57.058306) (xy 134.338137 -57.05874) (xy 134.392092 -57.066495) (xy 134.427356 -57.076848)
			(xy 135.238744 -57.076848) (xy 135.239204 -57.049514) (xy 135.247013 -56.995406) (xy 135.262465 -56.942966)
			(xy 135.285242 -56.893269) (xy 135.314879 -56.847331) (xy 135.33247 -56.826404) (xy 135.332724 -56.82615)
			(xy 135.332978 -56.825896) (xy 135.338581 -56.818821) (xy 135.344816 -56.801895) (xy 135.34517 -56.792876)
			(xy 135.34517 -56.72582) (xy 135.34481 -56.716803) (xy 135.338565 -56.699886) (xy 135.332978 -56.6928)
			(xy 135.332724 -56.692546) (xy 135.33247 -56.692292) (xy 135.314856 -56.671384) (xy 135.285222 -56.625442)
			(xy 135.26245 -56.575739) (xy 135.247007 -56.523295) (xy 135.23921 -56.469183) (xy 135.238744 -56.441848)
			(xy 135.23923 -56.414597) (xy 135.246986 -56.360649) (xy 135.262341 -56.308354) (xy 135.284983 -56.258777)
			(xy 135.314449 -56.212927) (xy 135.35014 -56.171736) (xy 135.391331 -56.136045) (xy 135.437181 -56.106579)
			(xy 135.486758 -56.083937) (xy 135.539053 -56.068582) (xy 135.593001 -56.060826) (xy 135.647503 -56.060826)
			(xy 135.701451 -56.068582) (xy 135.753746 -56.083937) (xy 135.803323 -56.106579) (xy 135.849173 -56.136045)
			(xy 135.890364 -56.171736) (xy 135.926055 -56.212927) (xy 135.955521 -56.258777) (xy 135.978163 -56.308354)
			(xy 135.991406 -56.353456) (xy 143.041368 -56.353456) (xy 143.045439 -56.297834) (xy 143.057565 -56.243397)
			(xy 143.077488 -56.191306) (xy 143.104784 -56.142671) (xy 143.13887 -56.098528) (xy 143.179019 -56.059819)
			(xy 143.224377 -56.027368) (xy 143.273977 -56.001867) (xy 143.326761 -55.98386) (xy 143.381604 -55.97373)
			(xy 143.437338 -55.971693) (xy 143.492775 -55.977793) (xy 143.546732 -55.991899) (xy 143.598061 -56.013711)
			(xy 143.645667 -56.042765) (xy 143.688535 -56.07844) (xy 143.725752 -56.119977) (xy 143.756525 -56.16649)
			(xy 143.780197 -56.216987) (xy 143.796265 -56.270394) (xy 143.804385 -56.32557) (xy 143.804894 -56.353456)
			(xy 143.804385 -56.381342) (xy 143.796265 -56.436518) (xy 143.780197 -56.489925) (xy 143.756525 -56.540422)
			(xy 143.725752 -56.586935) (xy 143.688535 -56.628472) (xy 143.645667 -56.664147) (xy 143.598061 -56.693201)
			(xy 143.546732 -56.715013) (xy 143.492775 -56.729119) (xy 143.437338 -56.735219) (xy 143.381604 -56.733182)
			(xy 143.326761 -56.723052) (xy 143.273977 -56.705045) (xy 143.224377 -56.679544) (xy 143.179019 -56.647093)
			(xy 143.13887 -56.608384) (xy 143.104784 -56.564241) (xy 143.077488 -56.515606) (xy 143.057565 -56.463515)
			(xy 143.045439 -56.409078) (xy 143.041368 -56.353456) (xy 135.991406 -56.353456) (xy 135.993518 -56.360649)
			(xy 136.001274 -56.414597) (xy 136.00176 -56.441848) (xy 136.001297 -56.469182) (xy 135.993488 -56.52329)
			(xy 135.978037 -56.575729) (xy 135.955261 -56.625427) (xy 135.925625 -56.671365) (xy 135.908034 -56.692292)
			(xy 135.90778 -56.692546) (xy 135.907526 -56.6928) (xy 135.901925 -56.699876) (xy 135.895689 -56.716801)
			(xy 135.895334 -56.72582) (xy 135.895334 -56.792876) (xy 135.895695 -56.801893) (xy 135.901939 -56.81881)
			(xy 135.907526 -56.825896) (xy 135.90778 -56.82615) (xy 135.908034 -56.826404) (xy 135.925647 -56.847313)
			(xy 135.955281 -56.893255) (xy 135.978053 -56.942957) (xy 135.993496 -56.995401) (xy 136.001294 -57.049513)
			(xy 136.00176 -57.076848) (xy 136.001274 -57.104099) (xy 135.993518 -57.158047) (xy 135.978163 -57.210342)
			(xy 135.955521 -57.259919) (xy 135.926055 -57.305769) (xy 135.890364 -57.34696) (xy 135.849173 -57.382651)
			(xy 135.803323 -57.412117) (xy 135.753746 -57.434759) (xy 135.701451 -57.450114) (xy 135.647503 -57.45787)
			(xy 135.593001 -57.45787) (xy 135.539053 -57.450114) (xy 135.486758 -57.434759) (xy 135.437181 -57.412117)
			(xy 135.391331 -57.382651) (xy 135.35014 -57.34696) (xy 135.314449 -57.305769) (xy 135.284983 -57.259919)
			(xy 135.262341 -57.210342) (xy 135.246986 -57.158047) (xy 135.23923 -57.104099) (xy 135.238744 -57.076848)
			(xy 134.427356 -57.076848) (xy 134.444394 -57.08185) (xy 134.493978 -57.104492) (xy 134.539835 -57.133961)
			(xy 134.581031 -57.169656) (xy 134.616728 -57.210851) (xy 134.646199 -57.256706) (xy 134.668844 -57.306289)
			(xy 134.684201 -57.358591) (xy 134.691959 -57.412545) (xy 134.691959 -57.467055) (xy 134.689338 -57.48528)
			(xy 146.70608 -57.48528) (xy 146.710151 -57.429658) (xy 146.722277 -57.375221) (xy 146.7422 -57.32313)
			(xy 146.769496 -57.274495) (xy 146.803582 -57.230352) (xy 146.843731 -57.191643) (xy 146.889089 -57.159192)
			(xy 146.938689 -57.133691) (xy 146.991473 -57.115684) (xy 147.046316 -57.105554) (xy 147.10205 -57.103517)
			(xy 147.157487 -57.109617) (xy 147.211444 -57.123723) (xy 147.262773 -57.145535) (xy 147.310379 -57.174589)
			(xy 147.353247 -57.210264) (xy 147.390464 -57.251801) (xy 147.421237 -57.298314) (xy 147.444909 -57.348811)
			(xy 147.460977 -57.402218) (xy 147.469097 -57.457394) (xy 147.469606 -57.48528) (xy 147.469097 -57.513166)
			(xy 147.460977 -57.568342) (xy 147.444909 -57.621749) (xy 147.421237 -57.672246) (xy 147.390464 -57.718759)
			(xy 147.353247 -57.760296) (xy 147.310379 -57.795971) (xy 147.262773 -57.825025) (xy 147.211444 -57.846837)
			(xy 147.157487 -57.860943) (xy 147.10205 -57.867043) (xy 147.046316 -57.865006) (xy 146.991473 -57.854876)
			(xy 146.938689 -57.836869) (xy 146.889089 -57.811368) (xy 146.843731 -57.778917) (xy 146.803582 -57.740208)
			(xy 146.769496 -57.696065) (xy 146.7422 -57.64743) (xy 146.722277 -57.595339) (xy 146.710151 -57.540902)
			(xy 146.70608 -57.48528) (xy 134.689338 -57.48528) (xy 134.684201 -57.521009) (xy 134.668844 -57.573311)
			(xy 134.646199 -57.622894) (xy 134.616728 -57.668749) (xy 134.581031 -57.709944) (xy 134.539835 -57.745639)
			(xy 134.493978 -57.775108) (xy 134.444394 -57.79775) (xy 134.392092 -57.813105) (xy 134.338137 -57.82086)
			(xy 134.310882 -57.821322) (xy 134.310628 -57.821322) (xy 134.284334 -57.820838) (xy 134.232247 -57.813596)
			(xy 134.181646 -57.799275) (xy 134.13349 -57.778144) (xy 134.08869 -57.750604) (xy 134.048093 -57.717176)
			(xy 134.029958 -57.698132) (xy 134.022397 -57.690678) (xy 134.002971 -57.682159) (xy 133.992366 -57.681622)
			(xy 133.918198 -57.681622) (xy 133.907566 -57.682032) (xy 133.888101 -57.69058) (xy 133.880606 -57.698132)
			(xy 133.86247 -57.717181) (xy 133.821891 -57.75064) (xy 133.777097 -57.778203) (xy 133.728938 -57.799343)
			(xy 133.67833 -57.813661) (xy 133.626233 -57.820885) (xy 133.599936 -57.821322) (xy 133.599682 -57.821322)
			(xy 133.572433 -57.820807) (xy 133.518489 -57.813048) (xy 133.466198 -57.797692) (xy 133.416625 -57.775051)
			(xy 133.370779 -57.745585) (xy 133.329592 -57.709895) (xy 133.293904 -57.668707) (xy 133.264441 -57.622859)
			(xy 133.241802 -57.573285) (xy 133.226448 -57.520994) (xy 133.218692 -57.467049) (xy 133.03536 -57.467049)
			(xy 133.039173 -57.494543) (xy 133.039612 -57.52084) (xy 133.039612 -57.521094) (xy 133.039105 -57.548426)
			(xy 133.031305 -57.602532) (xy 133.015863 -57.65497) (xy 132.993097 -57.704668) (xy 132.963472 -57.750609)
			(xy 132.945886 -57.771538) (xy 132.945632 -57.771792) (xy 132.945378 -57.772046) (xy 132.939805 -57.779142)
			(xy 132.933551 -57.796052) (xy 132.933186 -57.805066) (xy 132.933186 -57.872122) (xy 132.933536 -57.88114)
			(xy 132.939789 -57.898056) (xy 132.945378 -57.905142) (xy 132.945632 -57.905396) (xy 132.945886 -57.90565)
			(xy 132.963482 -57.926576) (xy 132.993139 -57.972507) (xy 133.015931 -58.022204) (xy 133.03139 -58.074646)
			(xy 133.0392 -58.128759) (xy 133.039201 -58.183432) (xy 133.031392 -58.237545) (xy 133.015934 -58.289988)
			(xy 132.993143 -58.339685) (xy 132.963488 -58.385617) (xy 132.945886 -58.406538) (xy 132.945632 -58.406792)
			(xy 132.945378 -58.407046) (xy 132.939805 -58.414142) (xy 132.933551 -58.431052) (xy 132.933186 -58.440066)
			(xy 132.933186 -58.507122) (xy 132.933536 -58.51614) (xy 132.939789 -58.533056) (xy 132.945378 -58.540142)
			(xy 132.945632 -58.540396) (xy 132.945886 -58.54065) (xy 132.963466 -58.561586) (xy 132.993107 -58.60752)
			(xy 133.015886 -58.657215) (xy 133.031337 -58.709653) (xy 133.039142 -58.76376) (xy 133.039612 -58.791094)
			(xy 133.039126 -58.818345) (xy 133.03137 -58.872293) (xy 133.030973 -58.873644) (xy 134.300722 -58.873644)
			(xy 134.301185 -58.84631) (xy 134.308994 -58.792202) (xy 134.324446 -58.739763) (xy 134.347222 -58.690066)
			(xy 134.376857 -58.644127) (xy 134.394448 -58.6232) (xy 134.394702 -58.622946) (xy 134.394956 -58.622692)
			(xy 134.400559 -58.615617) (xy 134.406794 -58.598691) (xy 134.407148 -58.589672) (xy 134.407148 -58.522616)
			(xy 134.406795 -58.513599) (xy 134.400546 -58.496681) (xy 134.394956 -58.489596) (xy 134.394702 -58.489342)
			(xy 134.394448 -58.489088) (xy 134.376844 -58.468171) (xy 134.347206 -58.422233) (xy 134.324431 -58.372533)
			(xy 134.308986 -58.32009) (xy 134.301188 -58.265979) (xy 134.300722 -58.238644) (xy 134.301208 -58.211393)
			(xy 134.308964 -58.157445) (xy 134.324319 -58.10515) (xy 134.346961 -58.055573) (xy 134.376427 -58.009723)
			(xy 134.412118 -57.968532) (xy 134.453309 -57.932841) (xy 134.499159 -57.903375) (xy 134.548736 -57.880733)
			(xy 134.601031 -57.865378) (xy 134.654979 -57.857622) (xy 134.709481 -57.857622) (xy 134.763429 -57.865378)
			(xy 134.815724 -57.880733) (xy 134.865301 -57.903375) (xy 134.911151 -57.932841) (xy 134.952342 -57.968532)
			(xy 134.988033 -58.009723) (xy 135.017499 -58.055573) (xy 135.025126 -58.072274) (xy 142.093694 -58.072274)
			(xy 142.097765 -58.016652) (xy 142.109891 -57.962215) (xy 142.129814 -57.910124) (xy 142.15711 -57.861489)
			(xy 142.191196 -57.817346) (xy 142.231345 -57.778637) (xy 142.276703 -57.746186) (xy 142.326303 -57.720685)
			(xy 142.379087 -57.702678) (xy 142.43393 -57.692548) (xy 142.489664 -57.690511) (xy 142.545101 -57.696611)
			(xy 142.599058 -57.710717) (xy 142.650387 -57.732529) (xy 142.697993 -57.761583) (xy 142.740861 -57.797258)
			(xy 142.778078 -57.838795) (xy 142.808851 -57.885308) (xy 142.832523 -57.935805) (xy 142.848591 -57.989212)
			(xy 142.856711 -58.044388) (xy 142.85722 -58.072274) (xy 142.85715 -58.076084) (xy 147.458174 -58.076084)
			(xy 147.462245 -58.020462) (xy 147.474371 -57.966025) (xy 147.494294 -57.913934) (xy 147.52159 -57.865299)
			(xy 147.555676 -57.821156) (xy 147.595825 -57.782447) (xy 147.641183 -57.749996) (xy 147.690783 -57.724495)
			(xy 147.743567 -57.706488) (xy 147.79841 -57.696358) (xy 147.854144 -57.694321) (xy 147.909581 -57.700421)
			(xy 147.963538 -57.714527) (xy 148.014867 -57.736339) (xy 148.062473 -57.765393) (xy 148.105341 -57.801068)
			(xy 148.142558 -57.842605) (xy 148.158894 -57.867296) (xy 149.743158 -57.867296) (xy 149.747229 -57.811674)
			(xy 149.759355 -57.757237) (xy 149.779278 -57.705146) (xy 149.806574 -57.656511) (xy 149.84066 -57.612368)
			(xy 149.880809 -57.573659) (xy 149.926167 -57.541208) (xy 149.975767 -57.515707) (xy 150.028551 -57.4977)
			(xy 150.083394 -57.48757) (xy 150.139128 -57.485533) (xy 150.194565 -57.491633) (xy 150.248522 -57.505739)
			(xy 150.299851 -57.527551) (xy 150.347457 -57.556605) (xy 150.390325 -57.59228) (xy 150.427542 -57.633817)
			(xy 150.458315 -57.68033) (xy 150.481987 -57.730827) (xy 150.498055 -57.784234) (xy 150.506175 -57.83941)
			(xy 150.506684 -57.867296) (xy 150.506175 -57.895182) (xy 150.498055 -57.950358) (xy 150.481987 -58.003765)
			(xy 150.458315 -58.054262) (xy 150.427542 -58.100775) (xy 150.390325 -58.142312) (xy 150.347457 -58.177987)
			(xy 150.299851 -58.207041) (xy 150.248522 -58.228853) (xy 150.194565 -58.242959) (xy 150.139128 -58.249059)
			(xy 150.083394 -58.247022) (xy 150.028551 -58.236892) (xy 149.975767 -58.218885) (xy 149.926167 -58.193384)
			(xy 149.880809 -58.160933) (xy 149.84066 -58.122224) (xy 149.806574 -58.078081) (xy 149.779278 -58.029446)
			(xy 149.759355 -57.977355) (xy 149.747229 -57.922918) (xy 149.743158 -57.867296) (xy 148.158894 -57.867296)
			(xy 148.173331 -57.889118) (xy 148.197003 -57.939615) (xy 148.213071 -57.993022) (xy 148.221191 -58.048198)
			(xy 148.2217 -58.076084) (xy 148.221191 -58.10397) (xy 148.213071 -58.159146) (xy 148.197003 -58.212553)
			(xy 148.173331 -58.26305) (xy 148.142558 -58.309563) (xy 148.105341 -58.3511) (xy 148.062473 -58.386775)
			(xy 148.014867 -58.415829) (xy 147.963538 -58.437641) (xy 147.909581 -58.451747) (xy 147.854144 -58.457847)
			(xy 147.79841 -58.45581) (xy 147.743567 -58.44568) (xy 147.690783 -58.427673) (xy 147.641183 -58.402172)
			(xy 147.595825 -58.369721) (xy 147.555676 -58.331012) (xy 147.52159 -58.286869) (xy 147.494294 -58.238234)
			(xy 147.474371 -58.186143) (xy 147.462245 -58.131706) (xy 147.458174 -58.076084) (xy 142.85715 -58.076084)
			(xy 142.856711 -58.10016) (xy 142.848591 -58.155336) (xy 142.832523 -58.208743) (xy 142.808851 -58.25924)
			(xy 142.778078 -58.305753) (xy 142.740861 -58.34729) (xy 142.697993 -58.382965) (xy 142.650387 -58.412019)
			(xy 142.599058 -58.433831) (xy 142.545101 -58.447937) (xy 142.489664 -58.454037) (xy 142.43393 -58.452)
			(xy 142.379087 -58.44187) (xy 142.326303 -58.423863) (xy 142.276703 -58.398362) (xy 142.231345 -58.365911)
			(xy 142.191196 -58.327202) (xy 142.15711 -58.283059) (xy 142.129814 -58.234424) (xy 142.109891 -58.182333)
			(xy 142.097765 -58.127896) (xy 142.093694 -58.072274) (xy 135.025126 -58.072274) (xy 135.040141 -58.10515)
			(xy 135.055496 -58.157445) (xy 135.063252 -58.211393) (xy 135.063738 -58.238644) (xy 135.063278 -58.265978)
			(xy 135.055469 -58.320086) (xy 135.040018 -58.372526) (xy 135.017241 -58.422223) (xy 134.987604 -58.468161)
			(xy 134.970012 -58.489088) (xy 134.969758 -58.489342) (xy 134.969504 -58.489596) (xy 134.963913 -58.49668)
			(xy 134.957669 -58.513599) (xy 134.957312 -58.522616) (xy 134.957312 -58.561224) (xy 148.662388 -58.561224)
			(xy 148.666459 -58.505602) (xy 148.678585 -58.451165) (xy 148.698508 -58.399074) (xy 148.725804 -58.350439)
			(xy 148.75989 -58.306296) (xy 148.800039 -58.267587) (xy 148.845397 -58.235136) (xy 148.894997 -58.209635)
			(xy 148.947781 -58.191628) (xy 149.002624 -58.181498) (xy 149.058358 -58.179461) (xy 149.113795 -58.185561)
			(xy 149.167752 -58.199667) (xy 149.219081 -58.221479) (xy 149.266687 -58.250533) (xy 149.309555 -58.286208)
			(xy 149.346772 -58.327745) (xy 149.377545 -58.374258) (xy 149.401217 -58.424755) (xy 149.408727 -58.449718)
			(xy 150.909018 -58.449718) (xy 150.913089 -58.394096) (xy 150.925215 -58.339659) (xy 150.945138 -58.287568)
			(xy 150.972434 -58.238933) (xy 151.00652 -58.19479) (xy 151.046669 -58.156081) (xy 151.092027 -58.12363)
			(xy 151.141627 -58.098129) (xy 151.194411 -58.080122) (xy 151.249254 -58.069992) (xy 151.304988 -58.067955)
			(xy 151.360425 -58.074055) (xy 151.414382 -58.088161) (xy 151.465711 -58.109973) (xy 151.513317 -58.139027)
			(xy 151.556185 -58.174702) (xy 151.593402 -58.216239) (xy 151.624175 -58.262752) (xy 151.647847 -58.313249)
			(xy 151.663915 -58.366656) (xy 151.672035 -58.421832) (xy 151.672544 -58.449718) (xy 151.672035 -58.477604)
			(xy 151.663915 -58.53278) (xy 151.647847 -58.586187) (xy 151.624175 -58.636684) (xy 151.593402 -58.683197)
			(xy 151.556185 -58.724734) (xy 151.54817 -58.731404) (xy 155.62072 -58.731404) (xy 155.621219 -58.704071)
			(xy 155.62902 -58.649965) (xy 155.644462 -58.597526) (xy 155.667231 -58.547828) (xy 155.696859 -58.501888)
			(xy 155.714446 -58.48096) (xy 155.7147 -58.480706) (xy 155.714954 -58.480452) (xy 155.720531 -58.473359)
			(xy 155.726782 -58.456447) (xy 155.727146 -58.447432) (xy 155.727146 -58.380376) (xy 155.726812 -58.371356)
			(xy 155.72055 -58.354439) (xy 155.714954 -58.347356) (xy 155.7147 -58.347102) (xy 155.714446 -58.346848)
			(xy 155.69685 -58.325922) (xy 155.667199 -58.279989) (xy 155.644412 -58.230293) (xy 155.628955 -58.177851)
			(xy 155.621147 -58.123739) (xy 155.621146 -58.069067) (xy 155.628954 -58.014955) (xy 155.644409 -57.962513)
			(xy 155.667196 -57.912816) (xy 155.696847 -57.866883) (xy 155.714446 -57.84596) (xy 155.7147 -57.845706)
			(xy 155.714954 -57.845452) (xy 155.720531 -57.838359) (xy 155.726782 -57.821447) (xy 155.727146 -57.812432)
			(xy 155.727146 -57.745376) (xy 155.726812 -57.736356) (xy 155.72055 -57.719439) (xy 155.714954 -57.712356)
			(xy 155.7147 -57.712102) (xy 155.714446 -57.711848) (xy 155.69685 -57.690922) (xy 155.667199 -57.644989)
			(xy 155.644412 -57.595293) (xy 155.628955 -57.542851) (xy 155.621147 -57.488739) (xy 155.621146 -57.434067)
			(xy 155.628954 -57.379955) (xy 155.644409 -57.327513) (xy 155.667196 -57.277816) (xy 155.696847 -57.231883)
			(xy 155.714446 -57.21096) (xy 155.7147 -57.210706) (xy 155.714954 -57.210452) (xy 155.720531 -57.203359)
			(xy 155.726782 -57.186447) (xy 155.727146 -57.177432) (xy 155.727146 -57.110376) (xy 155.726812 -57.101356)
			(xy 155.72055 -57.084439) (xy 155.714954 -57.077356) (xy 155.7147 -57.077102) (xy 155.714446 -57.076848)
			(xy 155.69687 -57.055909) (xy 155.667227 -57.009976) (xy 155.644447 -56.960282) (xy 155.628996 -56.907844)
			(xy 155.62119 -56.853737) (xy 155.62072 -56.826404) (xy 155.621206 -56.799153) (xy 155.628962 -56.745205)
			(xy 155.644317 -56.69291) (xy 155.666959 -56.643333) (xy 155.696425 -56.597483) (xy 155.732116 -56.556292)
			(xy 155.773307 -56.520601) (xy 155.819157 -56.491135) (xy 155.868734 -56.468493) (xy 155.921029 -56.453138)
			(xy 155.974977 -56.445382) (xy 156.029479 -56.445382) (xy 156.083427 -56.453138) (xy 156.135722 -56.468493)
			(xy 156.185299 -56.491135) (xy 156.231149 -56.520601) (xy 156.27234 -56.556292) (xy 156.308031 -56.597483)
			(xy 156.337497 -56.643333) (xy 156.360139 -56.69291) (xy 156.375494 -56.745205) (xy 156.38325 -56.799153)
			(xy 156.383736 -56.826404) (xy 156.383253 -56.853737) (xy 156.37545 -56.907844) (xy 156.360004 -56.960284)
			(xy 156.337232 -57.009982) (xy 156.307599 -57.055921) (xy 156.29001 -57.076848) (xy 156.289756 -57.077102)
			(xy 156.289502 -57.077356) (xy 156.283928 -57.084451) (xy 156.277674 -57.101361) (xy 156.27731 -57.110376)
			(xy 156.27731 -57.177432) (xy 156.27765 -57.186451) (xy 156.283909 -57.203368) (xy 156.289502 -57.210452)
			(xy 156.289756 -57.210706) (xy 156.29001 -57.21096) (xy 156.307615 -57.231878) (xy 156.33727 -57.277812)
			(xy 156.360059 -57.327509) (xy 156.375517 -57.379953) (xy 156.383326 -57.434066) (xy 156.383325 -57.48874)
			(xy 156.375516 -57.542853) (xy 156.360057 -57.595296) (xy 156.337267 -57.644994) (xy 156.307612 -57.690926)
			(xy 156.29001 -57.711848) (xy 156.289756 -57.712102) (xy 156.289502 -57.712356) (xy 156.283928 -57.719451)
			(xy 156.277674 -57.736361) (xy 156.27731 -57.745376) (xy 156.27731 -57.812432) (xy 156.27765 -57.821451)
			(xy 156.283909 -57.838368) (xy 156.289502 -57.845452) (xy 156.289756 -57.845706) (xy 156.29001 -57.84596)
			(xy 156.307615 -57.866878) (xy 156.33727 -57.912812) (xy 156.360059 -57.962509) (xy 156.375517 -58.014953)
			(xy 156.383326 -58.069066) (xy 156.383325 -58.12374) (xy 156.375516 -58.177853) (xy 156.360057 -58.230296)
			(xy 156.337267 -58.279994) (xy 156.307612 -58.325926) (xy 156.29001 -58.346848) (xy 156.289756 -58.347102)
			(xy 156.289502 -58.347356) (xy 156.283928 -58.354451) (xy 156.277674 -58.371361) (xy 156.27731 -58.380376)
			(xy 156.27731 -58.447432) (xy 156.27765 -58.456451) (xy 156.283909 -58.473368) (xy 156.289502 -58.480452)
			(xy 156.289756 -58.480706) (xy 156.29001 -58.48096) (xy 156.307599 -58.501889) (xy 156.337237 -58.547825)
			(xy 156.360014 -58.597522) (xy 156.375463 -58.649962) (xy 156.383267 -58.70407) (xy 156.383736 -58.731404)
			(xy 156.38325 -58.758655) (xy 156.378586 -58.791094) (xy 158.276544 -58.791094) (xy 158.277031 -58.763761)
			(xy 158.284834 -58.709654) (xy 158.300279 -58.657215) (xy 158.32305 -58.607517) (xy 158.352681 -58.561578)
			(xy 158.37027 -58.54065) (xy 158.370524 -58.540396) (xy 158.370778 -58.540142) (xy 158.376362 -58.533054)
			(xy 158.382608 -58.516138) (xy 158.38297 -58.507122) (xy 158.38297 -58.440066) (xy 158.382636 -58.431047)
			(xy 158.376373 -58.41413) (xy 158.370778 -58.407046) (xy 158.370524 -58.406792) (xy 158.37027 -58.406538)
			(xy 158.352664 -58.385621) (xy 158.323011 -58.339687) (xy 158.300222 -58.289989) (xy 158.284766 -58.237546)
			(xy 158.276958 -58.183432) (xy 158.276958 -58.128759) (xy 158.284768 -58.074646) (xy 158.300226 -58.022203)
			(xy 158.323015 -57.972505) (xy 158.352669 -57.926572) (xy 158.37027 -57.90565) (xy 158.370524 -57.905396)
			(xy 158.370778 -57.905142) (xy 158.376362 -57.898054) (xy 158.382608 -57.881138) (xy 158.38297 -57.872122)
			(xy 158.38297 -57.805066) (xy 158.382636 -57.796047) (xy 158.376373 -57.77913) (xy 158.370778 -57.772046)
			(xy 158.370524 -57.771792) (xy 158.37027 -57.771538) (xy 158.352677 -57.750613) (xy 158.32304 -57.704675)
			(xy 158.300264 -57.654977) (xy 158.284816 -57.602537) (xy 158.277013 -57.548428) (xy 158.276544 -57.521094)
			(xy 158.276544 -57.52084) (xy 158.277015 -57.494545) (xy 158.284256 -57.442457) (xy 158.298579 -57.391855)
			(xy 158.319712 -57.343699) (xy 158.347255 -57.298899) (xy 158.380688 -57.258304) (xy 158.399734 -57.24017)
			(xy 158.407178 -57.2326) (xy 158.415704 -57.213181) (xy 158.416244 -57.202578) (xy 158.416244 -57.12841)
			(xy 158.415807 -57.117781) (xy 158.407276 -57.098318) (xy 158.399734 -57.090818) (xy 158.380684 -57.072683)
			(xy 158.347226 -57.032103) (xy 158.319665 -56.987308) (xy 158.298525 -56.93915) (xy 158.284206 -56.888541)
			(xy 158.276982 -56.836445) (xy 158.276544 -56.810148) (xy 158.276544 -56.809894) (xy 158.27703 -56.782643)
			(xy 158.284786 -56.728695) (xy 158.300141 -56.6764) (xy 158.322783 -56.626823) (xy 158.352249 -56.580973)
			(xy 158.38794 -56.539782) (xy 158.429131 -56.504091) (xy 158.474981 -56.474625) (xy 158.524558 -56.451983)
			(xy 158.576853 -56.436628) (xy 158.630801 -56.428872) (xy 158.685303 -56.428872) (xy 158.739251 -56.436628)
			(xy 158.791546 -56.451983) (xy 158.841123 -56.474625) (xy 158.886973 -56.504091) (xy 158.928164 -56.539782)
			(xy 158.963855 -56.580973) (xy 158.993321 -56.626823) (xy 159.015963 -56.6764) (xy 159.031318 -56.728695)
			(xy 159.039074 -56.782643) (xy 159.03956 -56.809894) (xy 159.03956 -56.810148) (xy 159.039146 -56.836445)
			(xy 159.031893 -56.888536) (xy 159.017559 -56.939138) (xy 158.996416 -56.987295) (xy 158.968862 -57.032093)
			(xy 158.935421 -57.072685) (xy 158.91637 -57.090818) (xy 158.908932 -57.098393) (xy 158.900403 -57.117808)
			(xy 158.89986 -57.12841) (xy 158.89986 -57.202578) (xy 158.900302 -57.213206) (xy 158.90883 -57.23267)
			(xy 158.91637 -57.24017) (xy 158.935414 -57.25831) (xy 158.968873 -57.298889) (xy 158.996435 -57.343683)
			(xy 159.017576 -57.391841) (xy 159.031896 -57.442448) (xy 159.035308 -57.467053) (xy 159.218569 -57.467053)
			(xy 159.218569 -57.412547) (xy 159.226327 -57.358595) (xy 159.241684 -57.306297) (xy 159.264328 -57.256717)
			(xy 159.293797 -57.210864) (xy 159.329493 -57.169672) (xy 159.370688 -57.133979) (xy 159.416543 -57.104513)
			(xy 159.466125 -57.081873) (xy 159.518425 -57.06652) (xy 159.572377 -57.058767) (xy 159.59963 -57.058306)
			(xy 159.599884 -57.058306) (xy 159.626179 -57.058773) (xy 159.678267 -57.066017) (xy 159.728868 -57.080341)
			(xy 159.777024 -57.101475) (xy 159.821824 -57.129018) (xy 159.862419 -57.16245) (xy 159.880554 -57.181496)
			(xy 159.888107 -57.188959) (xy 159.907539 -57.197472) (xy 159.918146 -57.198006) (xy 159.992314 -57.198006)
			(xy 160.002946 -57.197594) (xy 160.02241 -57.189046) (xy 160.029906 -57.181496) (xy 160.048022 -57.162428)
			(xy 160.088607 -57.128972) (xy 160.133406 -57.101415) (xy 160.181568 -57.080278) (xy 160.232179 -57.065963)
			(xy 160.284278 -57.058742) (xy 160.310576 -57.058306) (xy 160.31083 -57.058306) (xy 160.338081 -57.058766)
			(xy 160.392027 -57.066526) (xy 160.427173 -57.076848) (xy 161.238692 -57.076848) (xy 161.239165 -57.049514)
			(xy 161.246973 -56.995408) (xy 161.262422 -56.942969) (xy 161.285196 -56.893271) (xy 161.314829 -56.847332)
			(xy 161.332418 -56.826404) (xy 161.332672 -56.82615) (xy 161.332926 -56.825896) (xy 161.338523 -56.818817)
			(xy 161.344763 -56.801894) (xy 161.345118 -56.792876) (xy 161.345118 -56.72582) (xy 161.344748 -56.716805)
			(xy 161.338509 -56.699888) (xy 161.332926 -56.6928) (xy 161.332672 -56.692546) (xy 161.332418 -56.692292)
			(xy 161.314811 -56.671378) (xy 161.285174 -56.625438) (xy 161.2624 -56.575737) (xy 161.246956 -56.523294)
			(xy 161.239158 -56.469183) (xy 161.238692 -56.441848) (xy 161.239178 -56.414597) (xy 161.246934 -56.360649)
			(xy 161.262289 -56.308354) (xy 161.284931 -56.258777) (xy 161.314397 -56.212927) (xy 161.350088 -56.171736)
			(xy 161.391279 -56.136045) (xy 161.437129 -56.106579) (xy 161.486706 -56.083937) (xy 161.539001 -56.068582)
			(xy 161.592949 -56.060826) (xy 161.647451 -56.060826) (xy 161.701399 -56.068582) (xy 161.753694 -56.083937)
			(xy 161.803271 -56.106579) (xy 161.849121 -56.136045) (xy 161.890312 -56.171736) (xy 161.926003 -56.212927)
			(xy 161.955469 -56.258777) (xy 161.978111 -56.308354) (xy 161.991354 -56.353456) (xy 169.041316 -56.353456)
			(xy 169.045387 -56.297834) (xy 169.057513 -56.243397) (xy 169.077436 -56.191306) (xy 169.104732 -56.142671)
			(xy 169.138818 -56.098528) (xy 169.178967 -56.059819) (xy 169.224325 -56.027368) (xy 169.273925 -56.001867)
			(xy 169.326709 -55.98386) (xy 169.381552 -55.97373) (xy 169.437286 -55.971693) (xy 169.492723 -55.977793)
			(xy 169.54668 -55.991899) (xy 169.598009 -56.013711) (xy 169.645615 -56.042765) (xy 169.688483 -56.07844)
			(xy 169.7257 -56.119977) (xy 169.756473 -56.16649) (xy 169.780145 -56.216987) (xy 169.796213 -56.270394)
			(xy 169.804333 -56.32557) (xy 169.804842 -56.353456) (xy 169.804333 -56.381342) (xy 169.796213 -56.436518)
			(xy 169.780145 -56.489925) (xy 169.756473 -56.540422) (xy 169.7257 -56.586935) (xy 169.688483 -56.628472)
			(xy 169.645615 -56.664147) (xy 169.598009 -56.693201) (xy 169.54668 -56.715013) (xy 169.492723 -56.729119)
			(xy 169.437286 -56.735219) (xy 169.381552 -56.733182) (xy 169.326709 -56.723052) (xy 169.273925 -56.705045)
			(xy 169.224325 -56.679544) (xy 169.178967 -56.647093) (xy 169.138818 -56.608384) (xy 169.104732 -56.564241)
			(xy 169.077436 -56.515606) (xy 169.057513 -56.463515) (xy 169.045387 -56.409078) (xy 169.041316 -56.353456)
			(xy 161.991354 -56.353456) (xy 161.993466 -56.360649) (xy 162.001222 -56.414597) (xy 162.001708 -56.441848)
			(xy 162.001233 -56.469182) (xy 161.993425 -56.523288) (xy 161.977977 -56.575727) (xy 161.955203 -56.625425)
			(xy 161.925571 -56.671364) (xy 161.907982 -56.692292) (xy 161.907728 -56.692546) (xy 161.907474 -56.6928)
			(xy 161.901878 -56.69988) (xy 161.895638 -56.716802) (xy 161.895282 -56.72582) (xy 161.895282 -56.792876)
			(xy 161.895654 -56.801891) (xy 161.901892 -56.818808) (xy 161.907474 -56.825896) (xy 161.907728 -56.82615)
			(xy 161.907982 -56.826404) (xy 161.925587 -56.84732) (xy 161.955224 -56.893259) (xy 161.977998 -56.94296)
			(xy 161.993443 -56.995402) (xy 162.001242 -57.049513) (xy 162.001708 -57.076848) (xy 162.001222 -57.104099)
			(xy 161.993466 -57.158047) (xy 161.978111 -57.210342) (xy 161.955469 -57.259919) (xy 161.926003 -57.305769)
			(xy 161.890312 -57.34696) (xy 161.849121 -57.382651) (xy 161.803271 -57.412117) (xy 161.753694 -57.434759)
			(xy 161.701399 -57.450114) (xy 161.647451 -57.45787) (xy 161.592949 -57.45787) (xy 161.539001 -57.450114)
			(xy 161.486706 -57.434759) (xy 161.437129 -57.412117) (xy 161.391279 -57.382651) (xy 161.350088 -57.34696)
			(xy 161.314397 -57.305769) (xy 161.284931 -57.259919) (xy 161.262289 -57.210342) (xy 161.246934 -57.158047)
			(xy 161.239178 -57.104099) (xy 161.238692 -57.076848) (xy 160.427173 -57.076848) (xy 160.44432 -57.081884)
			(xy 160.493896 -57.104528) (xy 160.539744 -57.133996) (xy 160.580932 -57.169689) (xy 160.616622 -57.21088)
			(xy 160.646086 -57.256731) (xy 160.668726 -57.306308) (xy 160.68408 -57.358602) (xy 160.691836 -57.412549)
			(xy 160.691836 -57.467051) (xy 160.689215 -57.48528) (xy 172.706028 -57.48528) (xy 172.710099 -57.429658)
			(xy 172.722225 -57.375221) (xy 172.742148 -57.32313) (xy 172.769444 -57.274495) (xy 172.80353 -57.230352)
			(xy 172.843679 -57.191643) (xy 172.889037 -57.159192) (xy 172.938637 -57.133691) (xy 172.991421 -57.115684)
			(xy 173.046264 -57.105554) (xy 173.101998 -57.103517) (xy 173.157435 -57.109617) (xy 173.211392 -57.123723)
			(xy 173.262721 -57.145535) (xy 173.310327 -57.174589) (xy 173.353195 -57.210264) (xy 173.390412 -57.251801)
			(xy 173.421185 -57.298314) (xy 173.444857 -57.348811) (xy 173.460925 -57.402218) (xy 173.469045 -57.457394)
			(xy 173.469554 -57.48528) (xy 173.469045 -57.513166) (xy 173.460925 -57.568342) (xy 173.444857 -57.621749)
			(xy 173.421185 -57.672246) (xy 173.390412 -57.718759) (xy 173.353195 -57.760296) (xy 173.310327 -57.795971)
			(xy 173.262721 -57.825025) (xy 173.211392 -57.846837) (xy 173.157435 -57.860943) (xy 173.101998 -57.867043)
			(xy 173.046264 -57.865006) (xy 172.991421 -57.854876) (xy 172.938637 -57.836869) (xy 172.889037 -57.811368)
			(xy 172.843679 -57.778917) (xy 172.80353 -57.740208) (xy 172.769444 -57.696065) (xy 172.742148 -57.64743)
			(xy 172.722225 -57.595339) (xy 172.710099 -57.540902) (xy 172.706028 -57.48528) (xy 160.689215 -57.48528)
			(xy 160.68408 -57.520998) (xy 160.668726 -57.573292) (xy 160.646086 -57.622869) (xy 160.616622 -57.66872)
			(xy 160.580932 -57.709911) (xy 160.539744 -57.745604) (xy 160.493896 -57.775072) (xy 160.44432 -57.797716)
			(xy 160.392027 -57.813074) (xy 160.338081 -57.820834) (xy 160.31083 -57.821322) (xy 160.310576 -57.821322)
			(xy 160.284281 -57.820872) (xy 160.232192 -57.813624) (xy 160.181591 -57.799296) (xy 160.133435 -57.778159)
			(xy 160.088636 -57.750613) (xy 160.04804 -57.717179) (xy 160.029906 -57.698132) (xy 160.022327 -57.690699)
			(xy 160.002915 -57.682168) (xy 159.992314 -57.681622) (xy 159.918146 -57.681622) (xy 159.907511 -57.682004)
			(xy 159.888046 -57.690572) (xy 159.880554 -57.698132) (xy 159.862444 -57.717206) (xy 159.821859 -57.750663)
			(xy 159.777059 -57.778222) (xy 159.728896 -57.799359) (xy 159.678283 -57.813671) (xy 159.626183 -57.820888)
			(xy 159.599884 -57.821322) (xy 159.59963 -57.821322) (xy 159.572377 -57.820833) (xy 159.518425 -57.81308)
			(xy 159.466125 -57.797727) (xy 159.416543 -57.775087) (xy 159.370688 -57.745621) (xy 159.329493 -57.709928)
			(xy 159.293797 -57.668736) (xy 159.264328 -57.622883) (xy 159.241684 -57.573303) (xy 159.226327 -57.521005)
			(xy 159.218569 -57.467053) (xy 159.035308 -57.467053) (xy 159.039121 -57.494543) (xy 159.03956 -57.52084)
			(xy 159.03956 -57.521094) (xy 159.039065 -57.548427) (xy 159.031264 -57.602533) (xy 159.015821 -57.654972)
			(xy 158.993051 -57.70467) (xy 158.963422 -57.75061) (xy 158.945834 -57.771538) (xy 158.94558 -57.771792)
			(xy 158.945326 -57.772046) (xy 158.939747 -57.779138) (xy 158.933498 -57.796051) (xy 158.933134 -57.805066)
			(xy 158.933134 -57.872122) (xy 158.933473 -57.881141) (xy 158.939732 -57.898058) (xy 158.945326 -57.905142)
			(xy 158.94558 -57.905396) (xy 158.945834 -57.90565) (xy 158.963428 -57.926577) (xy 158.993081 -57.972509)
			(xy 159.01587 -58.022206) (xy 159.031328 -58.074647) (xy 159.039137 -58.128759) (xy 159.039137 -58.183432)
			(xy 159.03133 -58.237544) (xy 159.015873 -58.289986) (xy 158.993086 -58.339683) (xy 158.963434 -58.385616)
			(xy 158.945834 -58.406538) (xy 158.94558 -58.406792) (xy 158.945326 -58.407046) (xy 158.939747 -58.414138)
			(xy 158.933498 -58.431051) (xy 158.933134 -58.440066) (xy 158.933134 -58.507122) (xy 158.933473 -58.516141)
			(xy 158.939732 -58.533058) (xy 158.945326 -58.540142) (xy 158.94558 -58.540396) (xy 158.945834 -58.54065)
			(xy 158.963422 -58.561579) (xy 158.99306 -58.607516) (xy 159.015836 -58.657213) (xy 159.031285 -58.709652)
			(xy 159.03909 -58.76376) (xy 159.03956 -58.791094) (xy 159.039074 -58.818345) (xy 159.031318 -58.872293)
			(xy 159.030921 -58.873644) (xy 160.30067 -58.873644) (xy 160.301121 -58.846309) (xy 160.308932 -58.792201)
			(xy 160.324385 -58.739761) (xy 160.347164 -58.690064) (xy 160.376803 -58.644126) (xy 160.394396 -58.6232)
			(xy 160.39465 -58.622946) (xy 160.394904 -58.622692) (xy 160.400501 -58.615612) (xy 160.406741 -58.59869)
			(xy 160.407096 -58.589672) (xy 160.407096 -58.522616) (xy 160.406732 -58.5136) (xy 160.40049 -58.496683)
			(xy 160.394904 -58.489596) (xy 160.39465 -58.489342) (xy 160.394396 -58.489088) (xy 160.376784 -58.468178)
			(xy 160.347149 -58.422237) (xy 160.324376 -58.372535) (xy 160.308933 -58.320091) (xy 160.301135 -58.265979)
			(xy 160.30067 -58.238644) (xy 160.301156 -58.211393) (xy 160.308912 -58.157445) (xy 160.324267 -58.10515)
			(xy 160.346909 -58.055573) (xy 160.376375 -58.009723) (xy 160.412066 -57.968532) (xy 160.453257 -57.932841)
			(xy 160.499107 -57.903375) (xy 160.548684 -57.880733) (xy 160.600979 -57.865378) (xy 160.654927 -57.857622)
			(xy 160.709429 -57.857622) (xy 160.763377 -57.865378) (xy 160.815672 -57.880733) (xy 160.865249 -57.903375)
			(xy 160.911099 -57.932841) (xy 160.95229 -57.968532) (xy 160.987981 -58.009723) (xy 161.017447 -58.055573)
			(xy 161.025074 -58.072274) (xy 168.093642 -58.072274) (xy 168.097713 -58.016652) (xy 168.109839 -57.962215)
			(xy 168.129762 -57.910124) (xy 168.157058 -57.861489) (xy 168.191144 -57.817346) (xy 168.231293 -57.778637)
			(xy 168.276651 -57.746186) (xy 168.326251 -57.720685) (xy 168.379035 -57.702678) (xy 168.433878 -57.692548)
			(xy 168.489612 -57.690511) (xy 168.545049 -57.696611) (xy 168.599006 -57.710717) (xy 168.650335 -57.732529)
			(xy 168.697941 -57.761583) (xy 168.740809 -57.797258) (xy 168.778026 -57.838795) (xy 168.808799 -57.885308)
			(xy 168.832471 -57.935805) (xy 168.848539 -57.989212) (xy 168.856659 -58.044388) (xy 168.857168 -58.072274)
			(xy 168.857098 -58.076084) (xy 173.458122 -58.076084) (xy 173.462193 -58.020462) (xy 173.474319 -57.966025)
			(xy 173.494242 -57.913934) (xy 173.521538 -57.865299) (xy 173.555624 -57.821156) (xy 173.595773 -57.782447)
			(xy 173.641131 -57.749996) (xy 173.690731 -57.724495) (xy 173.743515 -57.706488) (xy 173.798358 -57.696358)
			(xy 173.854092 -57.694321) (xy 173.909529 -57.700421) (xy 173.963486 -57.714527) (xy 174.014815 -57.736339)
			(xy 174.062421 -57.765393) (xy 174.105289 -57.801068) (xy 174.142506 -57.842605) (xy 174.158842 -57.867296)
			(xy 175.743106 -57.867296) (xy 175.747177 -57.811674) (xy 175.759303 -57.757237) (xy 175.779226 -57.705146)
			(xy 175.806522 -57.656511) (xy 175.840608 -57.612368) (xy 175.880757 -57.573659) (xy 175.926115 -57.541208)
			(xy 175.975715 -57.515707) (xy 176.028499 -57.4977) (xy 176.083342 -57.48757) (xy 176.139076 -57.485533)
			(xy 176.194513 -57.491633) (xy 176.24847 -57.505739) (xy 176.299799 -57.527551) (xy 176.347405 -57.556605)
			(xy 176.390273 -57.59228) (xy 176.42749 -57.633817) (xy 176.458263 -57.68033) (xy 176.481935 -57.730827)
			(xy 176.498003 -57.784234) (xy 176.506123 -57.83941) (xy 176.506632 -57.867296) (xy 176.506123 -57.895182)
			(xy 176.498003 -57.950358) (xy 176.481935 -58.003765) (xy 176.458263 -58.054262) (xy 176.42749 -58.100775)
			(xy 176.390273 -58.142312) (xy 176.347405 -58.177987) (xy 176.299799 -58.207041) (xy 176.24847 -58.228853)
			(xy 176.194513 -58.242959) (xy 176.139076 -58.249059) (xy 176.083342 -58.247022) (xy 176.028499 -58.236892)
			(xy 175.975715 -58.218885) (xy 175.926115 -58.193384) (xy 175.880757 -58.160933) (xy 175.840608 -58.122224)
			(xy 175.806522 -58.078081) (xy 175.779226 -58.029446) (xy 175.759303 -57.977355) (xy 175.747177 -57.922918)
			(xy 175.743106 -57.867296) (xy 174.158842 -57.867296) (xy 174.173279 -57.889118) (xy 174.196951 -57.939615)
			(xy 174.213019 -57.993022) (xy 174.221139 -58.048198) (xy 174.221648 -58.076084) (xy 174.221139 -58.10397)
			(xy 174.213019 -58.159146) (xy 174.196951 -58.212553) (xy 174.173279 -58.26305) (xy 174.142506 -58.309563)
			(xy 174.105289 -58.3511) (xy 174.062421 -58.386775) (xy 174.014815 -58.415829) (xy 173.963486 -58.437641)
			(xy 173.909529 -58.451747) (xy 173.854092 -58.457847) (xy 173.798358 -58.45581) (xy 173.743515 -58.44568)
			(xy 173.690731 -58.427673) (xy 173.641131 -58.402172) (xy 173.595773 -58.369721) (xy 173.555624 -58.331012)
			(xy 173.521538 -58.286869) (xy 173.494242 -58.238234) (xy 173.474319 -58.186143) (xy 173.462193 -58.131706)
			(xy 173.458122 -58.076084) (xy 168.857098 -58.076084) (xy 168.856659 -58.10016) (xy 168.848539 -58.155336)
			(xy 168.832471 -58.208743) (xy 168.808799 -58.25924) (xy 168.778026 -58.305753) (xy 168.740809 -58.34729)
			(xy 168.697941 -58.382965) (xy 168.650335 -58.412019) (xy 168.599006 -58.433831) (xy 168.545049 -58.447937)
			(xy 168.489612 -58.454037) (xy 168.433878 -58.452) (xy 168.379035 -58.44187) (xy 168.326251 -58.423863)
			(xy 168.276651 -58.398362) (xy 168.231293 -58.365911) (xy 168.191144 -58.327202) (xy 168.157058 -58.283059)
			(xy 168.129762 -58.234424) (xy 168.109839 -58.182333) (xy 168.097713 -58.127896) (xy 168.093642 -58.072274)
			(xy 161.025074 -58.072274) (xy 161.040089 -58.10515) (xy 161.055444 -58.157445) (xy 161.0632 -58.211393)
			(xy 161.063686 -58.238644) (xy 161.063214 -58.265978) (xy 161.055406 -58.320085) (xy 161.039957 -58.372524)
			(xy 161.017183 -58.422222) (xy 160.98755 -58.468161) (xy 160.96996 -58.489088) (xy 160.969706 -58.489342)
			(xy 160.969452 -58.489596) (xy 160.963855 -58.496675) (xy 160.957616 -58.513598) (xy 160.95726 -58.522616)
			(xy 160.95726 -58.561224) (xy 174.662336 -58.561224) (xy 174.666407 -58.505602) (xy 174.678533 -58.451165)
			(xy 174.698456 -58.399074) (xy 174.725752 -58.350439) (xy 174.759838 -58.306296) (xy 174.799987 -58.267587)
			(xy 174.845345 -58.235136) (xy 174.894945 -58.209635) (xy 174.947729 -58.191628) (xy 175.002572 -58.181498)
			(xy 175.058306 -58.179461) (xy 175.113743 -58.185561) (xy 175.1677 -58.199667) (xy 175.219029 -58.221479)
			(xy 175.266635 -58.250533) (xy 175.309503 -58.286208) (xy 175.34672 -58.327745) (xy 175.377493 -58.374258)
			(xy 175.401165 -58.424755) (xy 175.408675 -58.449718) (xy 176.908966 -58.449718) (xy 176.913037 -58.394096)
			(xy 176.925163 -58.339659) (xy 176.945086 -58.287568) (xy 176.972382 -58.238933) (xy 177.006468 -58.19479)
			(xy 177.046617 -58.156081) (xy 177.091975 -58.12363) (xy 177.141575 -58.098129) (xy 177.194359 -58.080122)
			(xy 177.249202 -58.069992) (xy 177.304936 -58.067955) (xy 177.360373 -58.074055) (xy 177.41433 -58.088161)
			(xy 177.465659 -58.109973) (xy 177.513265 -58.139027) (xy 177.556133 -58.174702) (xy 177.59335 -58.216239)
			(xy 177.624123 -58.262752) (xy 177.647795 -58.313249) (xy 177.663863 -58.366656) (xy 177.671983 -58.421832)
			(xy 177.672492 -58.449718) (xy 177.671983 -58.477604) (xy 177.663863 -58.53278) (xy 177.647795 -58.586187)
			(xy 177.624123 -58.636684) (xy 177.59335 -58.683197) (xy 177.556133 -58.724734) (xy 177.548118 -58.731404)
			(xy 181.620668 -58.731404) (xy 181.621155 -58.704071) (xy 181.628957 -58.649964) (xy 181.644402 -58.597525)
			(xy 181.667174 -58.547827) (xy 181.696805 -58.501888) (xy 181.714394 -58.48096) (xy 181.714648 -58.480706)
			(xy 181.714902 -58.480452) (xy 181.720473 -58.473355) (xy 181.726729 -58.456446) (xy 181.727094 -58.447432)
			(xy 181.727094 -58.380376) (xy 181.72675 -58.371358) (xy 181.720493 -58.354441) (xy 181.714902 -58.347356)
			(xy 181.714648 -58.347102) (xy 181.714394 -58.346848) (xy 181.696797 -58.325923) (xy 181.667141 -58.279991)
			(xy 181.644351 -58.230295) (xy 181.628893 -58.177852) (xy 181.621083 -58.12374) (xy 181.621083 -58.069066)
			(xy 181.628891 -58.014954) (xy 181.644349 -57.962511) (xy 181.667139 -57.912814) (xy 181.696793 -57.866882)
			(xy 181.714394 -57.84596) (xy 181.714648 -57.845706) (xy 181.714902 -57.845452) (xy 181.720473 -57.838355)
			(xy 181.726729 -57.821446) (xy 181.727094 -57.812432) (xy 181.727094 -57.745376) (xy 181.72675 -57.736358)
			(xy 181.720493 -57.719441) (xy 181.714902 -57.712356) (xy 181.714648 -57.712102) (xy 181.714394 -57.711848)
			(xy 181.696797 -57.690923) (xy 181.667141 -57.644991) (xy 181.644351 -57.595295) (xy 181.628893 -57.542852)
			(xy 181.621083 -57.48874) (xy 181.621083 -57.434066) (xy 181.628891 -57.379954) (xy 181.644349 -57.327511)
			(xy 181.667139 -57.277814) (xy 181.696793 -57.231882) (xy 181.714394 -57.21096) (xy 181.714648 -57.210706)
			(xy 181.714902 -57.210452) (xy 181.720473 -57.203355) (xy 181.726729 -57.186446) (xy 181.727094 -57.177432)
			(xy 181.727094 -57.110376) (xy 181.72675 -57.101358) (xy 181.720493 -57.084441) (xy 181.714902 -57.077356)
			(xy 181.714648 -57.077102) (xy 181.714394 -57.076848) (xy 181.69681 -57.055916) (xy 181.66717 -57.00998)
			(xy 181.644392 -56.960284) (xy 181.628943 -56.907845) (xy 181.621138 -56.853738) (xy 181.620668 -56.826404)
			(xy 181.621154 -56.799153) (xy 181.62891 -56.745205) (xy 181.644265 -56.69291) (xy 181.666907 -56.643333)
			(xy 181.696373 -56.597483) (xy 181.732064 -56.556292) (xy 181.773255 -56.520601) (xy 181.819105 -56.491135)
			(xy 181.868682 -56.468493) (xy 181.920977 -56.453138) (xy 181.974925 -56.445382) (xy 182.029427 -56.445382)
			(xy 182.083375 -56.453138) (xy 182.13567 -56.468493) (xy 182.185247 -56.491135) (xy 182.231097 -56.520601)
			(xy 182.272288 -56.556292) (xy 182.307979 -56.597483) (xy 182.337445 -56.643333) (xy 182.360087 -56.69291)
			(xy 182.375442 -56.745205) (xy 182.383198 -56.799153) (xy 182.383684 -56.826404) (xy 182.383189 -56.853737)
			(xy 182.375387 -56.907843) (xy 182.359943 -56.960282) (xy 182.337174 -57.00998) (xy 182.307545 -57.05592)
			(xy 182.289958 -57.076848) (xy 182.289704 -57.077102) (xy 182.28945 -57.077356) (xy 182.28387 -57.084447)
			(xy 182.27762 -57.10136) (xy 182.277258 -57.110376) (xy 182.277258 -57.177432) (xy 182.277587 -57.186452)
			(xy 182.283852 -57.203369) (xy 182.28945 -57.210452) (xy 182.289704 -57.210706) (xy 182.289958 -57.21096)
			(xy 182.307561 -57.231879) (xy 182.337212 -57.277814) (xy 182.359999 -57.327511) (xy 182.375454 -57.379954)
			(xy 182.383262 -57.434067) (xy 182.383262 -57.488739) (xy 182.375453 -57.542852) (xy 182.359997 -57.595294)
			(xy 182.337209 -57.644992) (xy 182.307558 -57.690925) (xy 182.289958 -57.711848) (xy 182.289704 -57.712102)
			(xy 182.28945 -57.712356) (xy 182.28387 -57.719447) (xy 182.27762 -57.73636) (xy 182.277258 -57.745376)
			(xy 182.277258 -57.812432) (xy 182.277587 -57.821452) (xy 182.283852 -57.838369) (xy 182.28945 -57.845452)
			(xy 182.289704 -57.845706) (xy 182.289958 -57.84596) (xy 182.307561 -57.866879) (xy 182.337212 -57.912814)
			(xy 182.359999 -57.962511) (xy 182.375454 -58.014954) (xy 182.383262 -58.069067) (xy 182.383262 -58.123739)
			(xy 182.375453 -58.177852) (xy 182.359997 -58.230294) (xy 182.337209 -58.279992) (xy 182.307558 -58.325925)
			(xy 182.289958 -58.346848) (xy 182.289704 -58.347102) (xy 182.28945 -58.347356) (xy 182.28387 -58.354447)
			(xy 182.27762 -58.37136) (xy 182.277258 -58.380376) (xy 182.277258 -58.447432) (xy 182.277587 -58.456452)
			(xy 182.283852 -58.473369) (xy 182.28945 -58.480452) (xy 182.289704 -58.480706) (xy 182.289958 -58.48096)
			(xy 182.307539 -58.501895) (xy 182.33718 -58.547829) (xy 182.35996 -58.597524) (xy 182.37541 -58.649963)
			(xy 182.383215 -58.70407) (xy 182.383684 -58.731404) (xy 182.383198 -58.758655) (xy 182.378534 -58.791094)
			(xy 184.276492 -58.791094) (xy 184.276991 -58.763761) (xy 184.284793 -58.709656) (xy 184.300236 -58.657217)
			(xy 184.323004 -58.607519) (xy 184.352631 -58.561579) (xy 184.370218 -58.54065) (xy 184.370472 -58.540396)
			(xy 184.370726 -58.540142) (xy 184.376304 -58.53305) (xy 184.382555 -58.516137) (xy 184.382918 -58.507122)
			(xy 184.382918 -58.440066) (xy 184.382574 -58.431048) (xy 184.376317 -58.414131) (xy 184.370726 -58.407046)
			(xy 184.370472 -58.406792) (xy 184.370218 -58.406538) (xy 184.35261 -58.385622) (xy 184.322953 -58.339689)
			(xy 184.300162 -58.289991) (xy 184.284703 -58.237547) (xy 184.276894 -58.183433) (xy 184.276895 -58.128758)
			(xy 184.284705 -58.074644) (xy 184.300165 -58.022201) (xy 184.322958 -57.972503) (xy 184.352615 -57.926571)
			(xy 184.370218 -57.90565) (xy 184.370472 -57.905396) (xy 184.370726 -57.905142) (xy 184.376304 -57.89805)
			(xy 184.382555 -57.881137) (xy 184.382918 -57.872122) (xy 184.382918 -57.805066) (xy 184.382574 -57.796048)
			(xy 184.376317 -57.779131) (xy 184.370726 -57.772046) (xy 184.370472 -57.771792) (xy 184.370218 -57.771538)
			(xy 184.352633 -57.750606) (xy 184.322993 -57.704671) (xy 184.300215 -57.654975) (xy 184.284765 -57.602536)
			(xy 184.276961 -57.548428) (xy 184.276492 -57.521094) (xy 184.276492 -57.52084) (xy 184.27698 -57.494546)
			(xy 184.28422 -57.442459) (xy 184.29854 -57.391858) (xy 184.31967 -57.343702) (xy 184.34721 -57.298902)
			(xy 184.380638 -57.258305) (xy 184.399682 -57.24017) (xy 184.407133 -57.232606) (xy 184.415653 -57.213182)
			(xy 184.416192 -57.202578) (xy 184.416192 -57.12841) (xy 184.415771 -57.117779) (xy 184.40723 -57.098315)
			(xy 184.399682 -57.090818) (xy 184.380623 -57.072693) (xy 184.347167 -57.03211) (xy 184.319609 -56.987313)
			(xy 184.29847 -56.939152) (xy 184.284153 -56.888543) (xy 184.27693 -56.836446) (xy 184.276492 -56.810148)
			(xy 184.276492 -56.809894) (xy 184.276978 -56.782643) (xy 184.284734 -56.728695) (xy 184.300089 -56.6764)
			(xy 184.322731 -56.626823) (xy 184.352197 -56.580973) (xy 184.387888 -56.539782) (xy 184.429079 -56.504091)
			(xy 184.474929 -56.474625) (xy 184.524506 -56.451983) (xy 184.576801 -56.436628) (xy 184.630749 -56.428872)
			(xy 184.685251 -56.428872) (xy 184.739199 -56.436628) (xy 184.791494 -56.451983) (xy 184.841071 -56.474625)
			(xy 184.886921 -56.504091) (xy 184.928112 -56.539782) (xy 184.963803 -56.580973) (xy 184.993269 -56.626823)
			(xy 185.015911 -56.6764) (xy 185.031266 -56.728695) (xy 185.039022 -56.782643) (xy 185.039508 -56.809894)
			(xy 185.039508 -56.810148) (xy 185.039079 -56.836444) (xy 185.031827 -56.888534) (xy 185.017495 -56.939135)
			(xy 184.996354 -56.987291) (xy 184.968804 -57.03209) (xy 184.935367 -57.072684) (xy 184.916318 -57.090818)
			(xy 184.908873 -57.098386) (xy 184.900349 -57.117807) (xy 184.899808 -57.12841) (xy 184.899808 -57.202578)
			(xy 184.900236 -57.213208) (xy 184.908772 -57.232673) (xy 184.916318 -57.24017) (xy 184.935372 -57.2583)
			(xy 184.968828 -57.298883) (xy 184.996387 -57.343679) (xy 185.017526 -57.391838) (xy 185.031844 -57.442446)
			(xy 185.035256 -57.467049) (xy 185.218592 -57.467049) (xy 185.218592 -57.412551) (xy 185.226348 -57.358607)
			(xy 185.241701 -57.306316) (xy 185.26434 -57.256742) (xy 185.293803 -57.210895) (xy 185.329491 -57.169706)
			(xy 185.370677 -57.134016) (xy 185.416523 -57.10455) (xy 185.466095 -57.081909) (xy 185.518386 -57.066553)
			(xy 185.572329 -57.058794) (xy 185.599578 -57.058306) (xy 185.599832 -57.058306) (xy 185.626128 -57.058741)
			(xy 185.678217 -57.065991) (xy 185.728819 -57.080322) (xy 185.776975 -57.101462) (xy 185.821774 -57.129011)
			(xy 185.862368 -57.162448) (xy 185.880502 -57.181496) (xy 185.888074 -57.188936) (xy 185.907492 -57.197462)
			(xy 185.918094 -57.198006) (xy 185.992262 -57.198006) (xy 186.002897 -57.19762) (xy 186.022361 -57.189054)
			(xy 186.029854 -57.181496) (xy 186.047995 -57.162453) (xy 186.088575 -57.128995) (xy 186.133368 -57.101434)
			(xy 186.181526 -57.080293) (xy 186.232132 -57.065973) (xy 186.284227 -57.058746) (xy 186.310524 -57.058306)
			(xy 186.310778 -57.058306) (xy 186.338033 -57.058739) (xy 186.391988 -57.066494) (xy 186.427256 -57.076848)
			(xy 187.23864 -57.076848) (xy 187.239101 -57.049514) (xy 187.24691 -56.995406) (xy 187.262362 -56.942967)
			(xy 187.285139 -56.893269) (xy 187.314775 -56.847331) (xy 187.332366 -56.826404) (xy 187.33262 -56.82615)
			(xy 187.332874 -56.825896) (xy 187.338477 -56.818821) (xy 187.344712 -56.801895) (xy 187.345066 -56.792876)
			(xy 187.345066 -56.72582) (xy 187.344707 -56.716803) (xy 187.338461 -56.699886) (xy 187.332874 -56.6928)
			(xy 187.33262 -56.692546) (xy 187.332366 -56.692292) (xy 187.314751 -56.671384) (xy 187.285117 -56.625442)
			(xy 187.262346 -56.575739) (xy 187.246903 -56.523295) (xy 187.239106 -56.469183) (xy 187.23864 -56.441848)
			(xy 187.239126 -56.414597) (xy 187.246882 -56.360649) (xy 187.262237 -56.308354) (xy 187.284879 -56.258777)
			(xy 187.314345 -56.212927) (xy 187.350036 -56.171736) (xy 187.391227 -56.136045) (xy 187.437077 -56.106579)
			(xy 187.486654 -56.083937) (xy 187.538949 -56.068582) (xy 187.592897 -56.060826) (xy 187.647399 -56.060826)
			(xy 187.701347 -56.068582) (xy 187.753642 -56.083937) (xy 187.803219 -56.106579) (xy 187.849069 -56.136045)
			(xy 187.89026 -56.171736) (xy 187.925951 -56.212927) (xy 187.955417 -56.258777) (xy 187.978059 -56.308354)
			(xy 187.991302 -56.353456) (xy 195.041264 -56.353456) (xy 195.045335 -56.297834) (xy 195.057461 -56.243397)
			(xy 195.077384 -56.191306) (xy 195.10468 -56.142671) (xy 195.138766 -56.098528) (xy 195.178915 -56.059819)
			(xy 195.224273 -56.027368) (xy 195.273873 -56.001867) (xy 195.326657 -55.98386) (xy 195.3815 -55.97373)
			(xy 195.437234 -55.971693) (xy 195.492671 -55.977793) (xy 195.546628 -55.991899) (xy 195.597957 -56.013711)
			(xy 195.645563 -56.042765) (xy 195.688431 -56.07844) (xy 195.725648 -56.119977) (xy 195.756421 -56.16649)
			(xy 195.780093 -56.216987) (xy 195.796161 -56.270394) (xy 195.804281 -56.32557) (xy 195.80479 -56.353456)
			(xy 195.804281 -56.381342) (xy 195.796161 -56.436518) (xy 195.780093 -56.489925) (xy 195.756421 -56.540422)
			(xy 195.725648 -56.586935) (xy 195.688431 -56.628472) (xy 195.645563 -56.664147) (xy 195.597957 -56.693201)
			(xy 195.546628 -56.715013) (xy 195.492671 -56.729119) (xy 195.437234 -56.735219) (xy 195.3815 -56.733182)
			(xy 195.326657 -56.723052) (xy 195.273873 -56.705045) (xy 195.224273 -56.679544) (xy 195.178915 -56.647093)
			(xy 195.138766 -56.608384) (xy 195.10468 -56.564241) (xy 195.077384 -56.515606) (xy 195.057461 -56.463515)
			(xy 195.045335 -56.409078) (xy 195.041264 -56.353456) (xy 187.991302 -56.353456) (xy 187.993414 -56.360649)
			(xy 188.00117 -56.414597) (xy 188.001656 -56.441848) (xy 188.001194 -56.469182) (xy 187.993385 -56.52329)
			(xy 187.977934 -56.575729) (xy 187.955157 -56.625427) (xy 187.925521 -56.671365) (xy 187.90793 -56.692292)
			(xy 187.907676 -56.692546) (xy 187.907422 -56.6928) (xy 187.90182 -56.699876) (xy 187.895585 -56.716801)
			(xy 187.89523 -56.72582) (xy 187.89523 -56.792876) (xy 187.895592 -56.801892) (xy 187.901836 -56.81881)
			(xy 187.907422 -56.825896) (xy 187.907676 -56.82615) (xy 187.90793 -56.826404) (xy 187.925542 -56.847314)
			(xy 187.955177 -56.893255) (xy 187.977949 -56.942957) (xy 187.993392 -56.995401) (xy 187.998687 -57.032144)
			(xy 193.585844 -57.032144) (xy 193.589915 -56.976522) (xy 193.602041 -56.922085) (xy 193.621964 -56.869994)
			(xy 193.64926 -56.821359) (xy 193.683346 -56.777216) (xy 193.723495 -56.738507) (xy 193.768853 -56.706056)
			(xy 193.818453 -56.680555) (xy 193.871237 -56.662548) (xy 193.92608 -56.652418) (xy 193.981814 -56.650381)
			(xy 194.037251 -56.656481) (xy 194.091208 -56.670587) (xy 194.142537 -56.692399) (xy 194.190143 -56.721453)
			(xy 194.233011 -56.757128) (xy 194.270228 -56.798665) (xy 194.301001 -56.845178) (xy 194.324673 -56.895675)
			(xy 194.340741 -56.949082) (xy 194.348861 -57.004258) (xy 194.34937 -57.032144) (xy 194.348861 -57.06003)
			(xy 194.340741 -57.115206) (xy 194.324673 -57.168613) (xy 194.301001 -57.21911) (xy 194.270228 -57.265623)
			(xy 194.233011 -57.30716) (xy 194.190143 -57.342835) (xy 194.142537 -57.371889) (xy 194.091208 -57.393701)
			(xy 194.037251 -57.407807) (xy 193.981814 -57.413907) (xy 193.92608 -57.41187) (xy 193.871237 -57.40174)
			(xy 193.818453 -57.383733) (xy 193.768853 -57.358232) (xy 193.723495 -57.325781) (xy 193.683346 -57.287072)
			(xy 193.64926 -57.242929) (xy 193.621964 -57.194294) (xy 193.602041 -57.142203) (xy 193.589915 -57.087766)
			(xy 193.585844 -57.032144) (xy 187.998687 -57.032144) (xy 188.00119 -57.049513) (xy 188.001656 -57.076848)
			(xy 188.00117 -57.104099) (xy 187.993414 -57.158047) (xy 187.978059 -57.210342) (xy 187.955417 -57.259919)
			(xy 187.925951 -57.305769) (xy 187.89026 -57.34696) (xy 187.849069 -57.382651) (xy 187.803219 -57.412117)
			(xy 187.753642 -57.434759) (xy 187.701347 -57.450114) (xy 187.647399 -57.45787) (xy 187.592897 -57.45787)
			(xy 187.538949 -57.450114) (xy 187.486654 -57.434759) (xy 187.437077 -57.412117) (xy 187.391227 -57.382651)
			(xy 187.350036 -57.34696) (xy 187.314345 -57.305769) (xy 187.284879 -57.259919) (xy 187.262237 -57.210342)
			(xy 187.246882 -57.158047) (xy 187.239126 -57.104099) (xy 187.23864 -57.076848) (xy 186.427256 -57.076848)
			(xy 186.444291 -57.081849) (xy 186.493876 -57.104491) (xy 186.539733 -57.133959) (xy 186.58093 -57.169654)
			(xy 186.616627 -57.210849) (xy 186.646099 -57.256705) (xy 186.668743 -57.306289) (xy 186.684101 -57.35859)
			(xy 186.691859 -57.412545) (xy 186.691859 -57.467055) (xy 186.689238 -57.48528) (xy 198.705976 -57.48528)
			(xy 198.710047 -57.429658) (xy 198.722173 -57.375221) (xy 198.742096 -57.32313) (xy 198.769392 -57.274495)
			(xy 198.803478 -57.230352) (xy 198.843627 -57.191643) (xy 198.888985 -57.159192) (xy 198.938585 -57.133691)
			(xy 198.991369 -57.115684) (xy 199.046212 -57.105554) (xy 199.101946 -57.103517) (xy 199.157383 -57.109617)
			(xy 199.21134 -57.123723) (xy 199.262669 -57.145535) (xy 199.310275 -57.174589) (xy 199.353143 -57.210264)
			(xy 199.39036 -57.251801) (xy 199.421133 -57.298314) (xy 199.444805 -57.348811) (xy 199.460873 -57.402218)
			(xy 199.468993 -57.457394) (xy 199.469502 -57.48528) (xy 199.468993 -57.513166) (xy 199.460873 -57.568342)
			(xy 199.444805 -57.621749) (xy 199.421133 -57.672246) (xy 199.39036 -57.718759) (xy 199.353143 -57.760296)
			(xy 199.310275 -57.795971) (xy 199.262669 -57.825025) (xy 199.21134 -57.846837) (xy 199.157383 -57.860943)
			(xy 199.101946 -57.867043) (xy 199.046212 -57.865006) (xy 198.991369 -57.854876) (xy 198.938585 -57.836869)
			(xy 198.888985 -57.811368) (xy 198.843627 -57.778917) (xy 198.803478 -57.740208) (xy 198.769392 -57.696065)
			(xy 198.742096 -57.64743) (xy 198.722173 -57.595339) (xy 198.710047 -57.540902) (xy 198.705976 -57.48528)
			(xy 186.689238 -57.48528) (xy 186.684101 -57.52101) (xy 186.668743 -57.573311) (xy 186.646099 -57.622895)
			(xy 186.616627 -57.668751) (xy 186.58093 -57.709946) (xy 186.539733 -57.745641) (xy 186.493876 -57.775109)
			(xy 186.444291 -57.797751) (xy 186.391988 -57.813106) (xy 186.338033 -57.820861) (xy 186.310778 -57.821322)
			(xy 186.310524 -57.821322) (xy 186.28423 -57.82084) (xy 186.232143 -57.813599) (xy 186.181542 -57.799277)
			(xy 186.133386 -57.778145) (xy 186.088586 -57.750605) (xy 186.047989 -57.717176) (xy 186.029854 -57.698132)
			(xy 186.022294 -57.690676) (xy 186.002868 -57.682158) (xy 185.992262 -57.681622) (xy 185.918094 -57.681622)
			(xy 185.907462 -57.68203) (xy 185.887997 -57.690579) (xy 185.880502 -57.698132) (xy 185.862368 -57.717183)
			(xy 185.821789 -57.750642) (xy 185.776994 -57.778204) (xy 185.728835 -57.799345) (xy 185.678226 -57.813662)
			(xy 185.62613 -57.820885) (xy 185.599832 -57.821322) (xy 185.599578 -57.821322) (xy 185.572329 -57.820806)
			(xy 185.518386 -57.813047) (xy 185.466095 -57.797691) (xy 185.416523 -57.77505) (xy 185.370677 -57.745584)
			(xy 185.329491 -57.709894) (xy 185.293803 -57.668705) (xy 185.26434 -57.622858) (xy 185.241701 -57.573284)
			(xy 185.226348 -57.520993) (xy 185.218592 -57.467049) (xy 185.035256 -57.467049) (xy 185.039069 -57.494543)
			(xy 185.039508 -57.52084) (xy 185.039508 -57.521094) (xy 185.039001 -57.548426) (xy 185.031201 -57.602532)
			(xy 185.01576 -57.65497) (xy 184.992994 -57.704668) (xy 184.963368 -57.750609) (xy 184.945782 -57.771538)
			(xy 184.945528 -57.771792) (xy 184.945274 -57.772046) (xy 184.939701 -57.779142) (xy 184.933447 -57.796052)
			(xy 184.933082 -57.805066) (xy 184.933082 -57.872122) (xy 184.933433 -57.881139) (xy 184.939685 -57.898056)
			(xy 184.945274 -57.905142) (xy 184.945528 -57.905396) (xy 184.945782 -57.90565) (xy 184.963379 -57.926576)
			(xy 184.993036 -57.972507) (xy 185.015828 -58.022203) (xy 185.031287 -58.074646) (xy 185.039097 -58.128759)
			(xy 185.039098 -58.183432) (xy 185.031289 -58.237545) (xy 185.015831 -58.289988) (xy 184.99304 -58.339685)
			(xy 184.963384 -58.385617) (xy 184.945782 -58.406538) (xy 184.945528 -58.406792) (xy 184.945274 -58.407046)
			(xy 184.939701 -58.414142) (xy 184.933447 -58.431052) (xy 184.933082 -58.440066) (xy 184.933082 -58.507122)
			(xy 184.933433 -58.516139) (xy 184.939685 -58.533056) (xy 184.945274 -58.540142) (xy 184.945528 -58.540396)
			(xy 184.945782 -58.54065) (xy 184.963362 -58.561586) (xy 184.993003 -58.60752) (xy 185.015782 -58.657215)
			(xy 185.031232 -58.709653) (xy 185.039038 -58.76376) (xy 185.039508 -58.791094) (xy 185.039022 -58.818345)
			(xy 185.031266 -58.872293) (xy 185.030869 -58.873644) (xy 186.300618 -58.873644) (xy 186.301082 -58.84631)
			(xy 186.308891 -58.792203) (xy 186.324342 -58.739763) (xy 186.347118 -58.690066) (xy 186.376754 -58.644127)
			(xy 186.394344 -58.6232) (xy 186.394598 -58.622946) (xy 186.394852 -58.622692) (xy 186.400454 -58.615616)
			(xy 186.40669 -58.598691) (xy 186.407044 -58.589672) (xy 186.407044 -58.522616) (xy 186.406691 -58.513598)
			(xy 186.400442 -58.496681) (xy 186.394852 -58.489596) (xy 186.394598 -58.489342) (xy 186.394344 -58.489088)
			(xy 186.376739 -58.468172) (xy 186.347101 -58.422233) (xy 186.324327 -58.372533) (xy 186.308882 -58.32009)
			(xy 186.301084 -58.265979) (xy 186.300618 -58.238644) (xy 186.301104 -58.211393) (xy 186.30886 -58.157445)
			(xy 186.324215 -58.10515) (xy 186.346857 -58.055573) (xy 186.376323 -58.009723) (xy 186.412014 -57.968532)
			(xy 186.453205 -57.932841) (xy 186.499055 -57.903375) (xy 186.548632 -57.880733) (xy 186.600927 -57.865378)
			(xy 186.654875 -57.857622) (xy 186.709377 -57.857622) (xy 186.763325 -57.865378) (xy 186.81562 -57.880733)
			(xy 186.865197 -57.903375) (xy 186.911047 -57.932841) (xy 186.952238 -57.968532) (xy 186.987929 -58.009723)
			(xy 187.017395 -58.055573) (xy 187.026762 -58.076084) (xy 199.45807 -58.076084) (xy 199.462141 -58.020462)
			(xy 199.474267 -57.966025) (xy 199.49419 -57.913934) (xy 199.521486 -57.865299) (xy 199.555572 -57.821156)
			(xy 199.595721 -57.782447) (xy 199.641079 -57.749996) (xy 199.690679 -57.724495) (xy 199.743463 -57.706488)
			(xy 199.798306 -57.696358) (xy 199.85404 -57.694321) (xy 199.909477 -57.700421) (xy 199.963434 -57.714527)
			(xy 200.014763 -57.736339) (xy 200.062369 -57.765393) (xy 200.105237 -57.801068) (xy 200.142454 -57.842605)
			(xy 200.15879 -57.867296) (xy 201.743054 -57.867296) (xy 201.747125 -57.811674) (xy 201.759251 -57.757237)
			(xy 201.779174 -57.705146) (xy 201.80647 -57.656511) (xy 201.840556 -57.612368) (xy 201.880705 -57.573659)
			(xy 201.926063 -57.541208) (xy 201.975663 -57.515707) (xy 202.028447 -57.4977) (xy 202.08329 -57.48757)
			(xy 202.139024 -57.485533) (xy 202.194461 -57.491633) (xy 202.248418 -57.505739) (xy 202.299747 -57.527551)
			(xy 202.347353 -57.556605) (xy 202.390221 -57.59228) (xy 202.427438 -57.633817) (xy 202.458211 -57.68033)
			(xy 202.481883 -57.730827) (xy 202.497951 -57.784234) (xy 202.506071 -57.83941) (xy 202.50658 -57.867296)
			(xy 202.506071 -57.895182) (xy 202.497951 -57.950358) (xy 202.481883 -58.003765) (xy 202.458211 -58.054262)
			(xy 202.427438 -58.100775) (xy 202.390221 -58.142312) (xy 202.347353 -58.177987) (xy 202.299747 -58.207041)
			(xy 202.248418 -58.228853) (xy 202.194461 -58.242959) (xy 202.139024 -58.249059) (xy 202.08329 -58.247022)
			(xy 202.028447 -58.236892) (xy 201.975663 -58.218885) (xy 201.926063 -58.193384) (xy 201.880705 -58.160933)
			(xy 201.840556 -58.122224) (xy 201.80647 -58.078081) (xy 201.779174 -58.029446) (xy 201.759251 -57.977355)
			(xy 201.747125 -57.922918) (xy 201.743054 -57.867296) (xy 200.15879 -57.867296) (xy 200.173227 -57.889118)
			(xy 200.196899 -57.939615) (xy 200.212967 -57.993022) (xy 200.221087 -58.048198) (xy 200.221596 -58.076084)
			(xy 200.221087 -58.10397) (xy 200.212967 -58.159146) (xy 200.196899 -58.212553) (xy 200.173227 -58.26305)
			(xy 200.142454 -58.309563) (xy 200.105237 -58.3511) (xy 200.062369 -58.386775) (xy 200.014763 -58.415829)
			(xy 199.963434 -58.437641) (xy 199.909477 -58.451747) (xy 199.85404 -58.457847) (xy 199.798306 -58.45581)
			(xy 199.743463 -58.44568) (xy 199.690679 -58.427673) (xy 199.641079 -58.402172) (xy 199.595721 -58.369721)
			(xy 199.555572 -58.331012) (xy 199.521486 -58.286869) (xy 199.49419 -58.238234) (xy 199.474267 -58.186143)
			(xy 199.462141 -58.131706) (xy 199.45807 -58.076084) (xy 187.026762 -58.076084) (xy 187.040037 -58.10515)
			(xy 187.055392 -58.157445) (xy 187.063148 -58.211393) (xy 187.063634 -58.238644) (xy 187.063175 -58.265978)
			(xy 187.055366 -58.320086) (xy 187.039915 -58.372526) (xy 187.017137 -58.422224) (xy 186.9875 -58.468162)
			(xy 186.969908 -58.489088) (xy 186.969654 -58.489342) (xy 186.9694 -58.489596) (xy 186.963809 -58.49668)
			(xy 186.957565 -58.513599) (xy 186.957208 -58.522616) (xy 186.957208 -58.561224) (xy 200.662284 -58.561224)
			(xy 200.666355 -58.505602) (xy 200.678481 -58.451165) (xy 200.698404 -58.399074) (xy 200.7257 -58.350439)
			(xy 200.759786 -58.306296) (xy 200.799935 -58.267587) (xy 200.845293 -58.235136) (xy 200.894893 -58.209635)
			(xy 200.947677 -58.191628) (xy 201.00252 -58.181498) (xy 201.058254 -58.179461) (xy 201.113691 -58.185561)
			(xy 201.167648 -58.199667) (xy 201.218977 -58.221479) (xy 201.266583 -58.250533) (xy 201.309451 -58.286208)
			(xy 201.346668 -58.327745) (xy 201.377441 -58.374258) (xy 201.401113 -58.424755) (xy 201.408623 -58.449718)
			(xy 202.908914 -58.449718) (xy 202.912985 -58.394096) (xy 202.925111 -58.339659) (xy 202.945034 -58.287568)
			(xy 202.97233 -58.238933) (xy 203.006416 -58.19479) (xy 203.046565 -58.156081) (xy 203.091923 -58.12363)
			(xy 203.141523 -58.098129) (xy 203.194307 -58.080122) (xy 203.24915 -58.069992) (xy 203.304884 -58.067955)
			(xy 203.360321 -58.074055) (xy 203.414278 -58.088161) (xy 203.465607 -58.109973) (xy 203.513213 -58.139027)
			(xy 203.556081 -58.174702) (xy 203.593298 -58.216239) (xy 203.624071 -58.262752) (xy 203.647743 -58.313249)
			(xy 203.663811 -58.366656) (xy 203.671931 -58.421832) (xy 203.67244 -58.449718) (xy 203.671931 -58.477604)
			(xy 203.663811 -58.53278) (xy 203.647743 -58.586187) (xy 203.624071 -58.636684) (xy 203.593298 -58.683197)
			(xy 203.556081 -58.724734) (xy 203.548066 -58.731404) (xy 207.620616 -58.731404) (xy 207.621116 -58.704071)
			(xy 207.628916 -58.649965) (xy 207.644359 -58.597527) (xy 207.667127 -58.547828) (xy 207.696755 -58.501888)
			(xy 207.714342 -58.48096) (xy 207.714596 -58.480706) (xy 207.71485 -58.480452) (xy 207.720427 -58.473359)
			(xy 207.726678 -58.456447) (xy 207.727042 -58.447432) (xy 207.727042 -58.380376) (xy 207.726709 -58.371356)
			(xy 207.720446 -58.354439) (xy 207.71485 -58.347356) (xy 207.714596 -58.347102) (xy 207.714342 -58.346848)
			(xy 207.696747 -58.325922) (xy 207.667096 -58.279989) (xy 207.644308 -58.230292) (xy 207.628852 -58.177851)
			(xy 207.621044 -58.123739) (xy 207.621043 -58.069067) (xy 207.628851 -58.014955) (xy 207.644306 -57.962513)
			(xy 207.667093 -57.912816) (xy 207.696743 -57.866883) (xy 207.714342 -57.84596) (xy 207.714596 -57.845706)
			(xy 207.71485 -57.845452) (xy 207.720427 -57.838359) (xy 207.726678 -57.821447) (xy 207.727042 -57.812432)
			(xy 207.727042 -57.745376) (xy 207.726709 -57.736356) (xy 207.720446 -57.719439) (xy 207.71485 -57.712356)
			(xy 207.714596 -57.712102) (xy 207.714342 -57.711848) (xy 207.696747 -57.690922) (xy 207.667096 -57.644989)
			(xy 207.644308 -57.595292) (xy 207.628852 -57.542851) (xy 207.621044 -57.488739) (xy 207.621043 -57.434067)
			(xy 207.628851 -57.379955) (xy 207.644306 -57.327513) (xy 207.667093 -57.277816) (xy 207.696743 -57.231883)
			(xy 207.714342 -57.21096) (xy 207.714596 -57.210706) (xy 207.71485 -57.210452) (xy 207.720427 -57.203359)
			(xy 207.726678 -57.186447) (xy 207.727042 -57.177432) (xy 207.727042 -57.110376) (xy 207.726709 -57.101356)
			(xy 207.720446 -57.084439) (xy 207.71485 -57.077356) (xy 207.714596 -57.077102) (xy 207.714342 -57.076848)
			(xy 207.696765 -57.05591) (xy 207.667123 -57.009977) (xy 207.644343 -56.960282) (xy 207.628892 -56.907844)
			(xy 207.621086 -56.853737) (xy 207.620616 -56.826404) (xy 207.621102 -56.799153) (xy 207.628858 -56.745205)
			(xy 207.644213 -56.69291) (xy 207.666855 -56.643333) (xy 207.696321 -56.597483) (xy 207.732012 -56.556292)
			(xy 207.773203 -56.520601) (xy 207.819053 -56.491135) (xy 207.86863 -56.468493) (xy 207.920925 -56.453138)
			(xy 207.974873 -56.445382) (xy 208.029375 -56.445382) (xy 208.083323 -56.453138) (xy 208.135618 -56.468493)
			(xy 208.185195 -56.491135) (xy 208.231045 -56.520601) (xy 208.272236 -56.556292) (xy 208.307927 -56.597483)
			(xy 208.337393 -56.643333) (xy 208.360035 -56.69291) (xy 208.37539 -56.745205) (xy 208.383146 -56.799153)
			(xy 208.383632 -56.826404) (xy 208.38315 -56.853737) (xy 208.375347 -56.907845) (xy 208.359901 -56.960284)
			(xy 208.337128 -57.009982) (xy 208.307496 -57.055921) (xy 208.289906 -57.076848) (xy 208.289652 -57.077102)
			(xy 208.289398 -57.077356) (xy 208.283823 -57.084451) (xy 208.27757 -57.101361) (xy 208.277206 -57.110376)
			(xy 208.277206 -57.177432) (xy 208.277547 -57.186451) (xy 208.283805 -57.203367) (xy 208.289398 -57.210452)
			(xy 208.289652 -57.210706) (xy 208.289906 -57.21096) (xy 208.307511 -57.231878) (xy 208.337166 -57.277811)
			(xy 208.359956 -57.327509) (xy 208.375414 -57.379953) (xy 208.383223 -57.434066) (xy 208.383222 -57.48874)
			(xy 208.375413 -57.542853) (xy 208.359954 -57.595296) (xy 208.337163 -57.644994) (xy 208.307508 -57.690926)
			(xy 208.289906 -57.711848) (xy 208.289652 -57.712102) (xy 208.289398 -57.712356) (xy 208.283823 -57.719451)
			(xy 208.27757 -57.736361) (xy 208.277206 -57.745376) (xy 208.277206 -57.812432) (xy 208.277547 -57.821451)
			(xy 208.283805 -57.838367) (xy 208.289398 -57.845452) (xy 208.289652 -57.845706) (xy 208.289906 -57.84596)
			(xy 208.307511 -57.866878) (xy 208.337166 -57.912811) (xy 208.359956 -57.962509) (xy 208.375414 -58.014953)
			(xy 208.383223 -58.069066) (xy 208.383222 -58.12374) (xy 208.375413 -58.177853) (xy 208.359954 -58.230296)
			(xy 208.337163 -58.279994) (xy 208.307508 -58.325926) (xy 208.289906 -58.346848) (xy 208.289652 -58.347102)
			(xy 208.289398 -58.347356) (xy 208.283823 -58.354451) (xy 208.27757 -58.371361) (xy 208.277206 -58.380376)
			(xy 208.277206 -58.447432) (xy 208.277547 -58.456451) (xy 208.283805 -58.473367) (xy 208.289398 -58.480452)
			(xy 208.289652 -58.480706) (xy 208.289906 -58.48096) (xy 208.307494 -58.501889) (xy 208.337133 -58.547825)
			(xy 208.35991 -58.597522) (xy 208.375359 -58.649962) (xy 208.383163 -58.70407) (xy 208.383632 -58.731404)
			(xy 208.383146 -58.758655) (xy 208.378482 -58.791094) (xy 210.27644 -58.791094) (xy 210.276928 -58.763761)
			(xy 210.284731 -58.709654) (xy 210.300176 -58.657215) (xy 210.322947 -58.607517) (xy 210.352577 -58.561578)
			(xy 210.370166 -58.54065) (xy 210.37042 -58.540396) (xy 210.370674 -58.540142) (xy 210.376258 -58.533054)
			(xy 210.382504 -58.516138) (xy 210.382866 -58.507122) (xy 210.382866 -58.440066) (xy 210.382533 -58.431047)
			(xy 210.376269 -58.414129) (xy 210.370674 -58.407046) (xy 210.37042 -58.406792) (xy 210.370166 -58.406538)
			(xy 210.35256 -58.385621) (xy 210.322907 -58.339687) (xy 210.300119 -58.289989) (xy 210.284663 -58.237545)
			(xy 210.276855 -58.183432) (xy 210.276855 -58.128759) (xy 210.284665 -58.074646) (xy 210.300122 -58.022203)
			(xy 210.322912 -57.972505) (xy 210.352565 -57.926572) (xy 210.370166 -57.90565) (xy 210.37042 -57.905396)
			(xy 210.370674 -57.905142) (xy 210.376258 -57.898054) (xy 210.382504 -57.881138) (xy 210.382866 -57.872122)
			(xy 210.382866 -57.805066) (xy 210.382533 -57.796047) (xy 210.376269 -57.779129) (xy 210.370674 -57.772046)
			(xy 210.37042 -57.771792) (xy 210.370166 -57.771538) (xy 210.352573 -57.750613) (xy 210.322936 -57.704675)
			(xy 210.30016 -57.654977) (xy 210.284712 -57.602537) (xy 210.276909 -57.548428) (xy 210.27644 -57.521094)
			(xy 210.27644 -57.52084) (xy 210.276913 -57.494545) (xy 210.284153 -57.442457) (xy 210.298476 -57.391855)
			(xy 210.319608 -57.343699) (xy 210.347152 -57.298899) (xy 210.380584 -57.258304) (xy 210.39963 -57.24017)
			(xy 210.407073 -57.232599) (xy 210.4156 -57.213181) (xy 210.41614 -57.202578) (xy 210.41614 -57.12841)
			(xy 210.415705 -57.117781) (xy 210.407172 -57.098318) (xy 210.39963 -57.090818) (xy 210.38058 -57.072684)
			(xy 210.347122 -57.032104) (xy 210.319561 -56.987309) (xy 210.29842 -56.93915) (xy 210.284102 -56.888542)
			(xy 210.276878 -56.836445) (xy 210.27644 -56.810148) (xy 210.27644 -56.809894) (xy 210.276926 -56.782643)
			(xy 210.284682 -56.728695) (xy 210.300037 -56.6764) (xy 210.322679 -56.626823) (xy 210.352145 -56.580973)
			(xy 210.387836 -56.539782) (xy 210.429027 -56.504091) (xy 210.474877 -56.474625) (xy 210.524454 -56.451983)
			(xy 210.576749 -56.436628) (xy 210.630697 -56.428872) (xy 210.685199 -56.428872) (xy 210.739147 -56.436628)
			(xy 210.791442 -56.451983) (xy 210.841019 -56.474625) (xy 210.886869 -56.504091) (xy 210.92806 -56.539782)
			(xy 210.963751 -56.580973) (xy 210.993217 -56.626823) (xy 211.015859 -56.6764) (xy 211.031214 -56.728695)
			(xy 211.03897 -56.782643) (xy 211.039456 -56.809894) (xy 211.039456 -56.810148) (xy 211.039043 -56.836445)
			(xy 211.031791 -56.888536) (xy 211.017457 -56.939139) (xy 210.996312 -56.987295) (xy 210.968759 -57.032093)
			(xy 210.935317 -57.072686) (xy 210.916266 -57.090818) (xy 210.908828 -57.098393) (xy 210.900299 -57.117808)
			(xy 210.899756 -57.12841) (xy 210.899756 -57.202578) (xy 210.900199 -57.213206) (xy 210.908726 -57.23267)
			(xy 210.916266 -57.24017) (xy 210.93531 -57.258311) (xy 210.968768 -57.298889) (xy 210.99633 -57.343683)
			(xy 211.017472 -57.391841) (xy 211.031791 -57.442448) (xy 211.035204 -57.467053) (xy 211.218469 -57.467053)
			(xy 211.218469 -57.412547) (xy 211.226227 -57.358596) (xy 211.241584 -57.306298) (xy 211.264227 -57.256718)
			(xy 211.293696 -57.210865) (xy 211.329392 -57.169673) (xy 211.370586 -57.133981) (xy 211.416441 -57.104515)
			(xy 211.466022 -57.081874) (xy 211.518321 -57.066521) (xy 211.572273 -57.058768) (xy 211.599526 -57.058306)
			(xy 211.59978 -57.058306) (xy 211.626074 -57.058776) (xy 211.678163 -57.066019) (xy 211.728764 -57.080342)
			(xy 211.77692 -57.101476) (xy 211.82172 -57.129019) (xy 211.862315 -57.16245) (xy 211.88045 -57.181496)
			(xy 211.888005 -57.188957) (xy 211.907435 -57.197471) (xy 211.918042 -57.198006) (xy 211.99221 -57.198006)
			(xy 212.002841 -57.197592) (xy 212.022306 -57.189046) (xy 212.029802 -57.181496) (xy 212.04792 -57.16243)
			(xy 212.088504 -57.128974) (xy 212.133303 -57.101416) (xy 212.181465 -57.080279) (xy 212.232076 -57.065964)
			(xy 212.284174 -57.058743) (xy 212.310472 -57.058306) (xy 212.310726 -57.058306) (xy 212.337977 -57.058766)
			(xy 212.391924 -57.066525) (xy 212.427073 -57.076848) (xy 213.238588 -57.076848) (xy 213.239062 -57.049514)
			(xy 213.24687 -56.995408) (xy 213.262319 -56.942969) (xy 213.285093 -56.893271) (xy 213.314725 -56.847332)
			(xy 213.332314 -56.826404) (xy 213.332568 -56.82615) (xy 213.332822 -56.825896) (xy 213.338419 -56.818817)
			(xy 213.344659 -56.801894) (xy 213.345014 -56.792876) (xy 213.345014 -56.72582) (xy 213.344644 -56.716804)
			(xy 213.338405 -56.699888) (xy 213.332822 -56.6928) (xy 213.332568 -56.692546) (xy 213.332314 -56.692292)
			(xy 213.314707 -56.671378) (xy 213.28507 -56.625438) (xy 213.262296 -56.575737) (xy 213.246852 -56.523294)
			(xy 213.239054 -56.469183) (xy 213.238588 -56.441848) (xy 213.239074 -56.414597) (xy 213.24683 -56.360649)
			(xy 213.262185 -56.308354) (xy 213.284827 -56.258777) (xy 213.314293 -56.212927) (xy 213.349984 -56.171736)
			(xy 213.391175 -56.136045) (xy 213.437025 -56.106579) (xy 213.486602 -56.083937) (xy 213.538897 -56.068582)
			(xy 213.592845 -56.060826) (xy 213.647347 -56.060826) (xy 213.701295 -56.068582) (xy 213.75359 -56.083937)
			(xy 213.803167 -56.106579) (xy 213.849017 -56.136045) (xy 213.890208 -56.171736) (xy 213.925899 -56.212927)
			(xy 213.955365 -56.258777) (xy 213.978007 -56.308354) (xy 213.99125 -56.353456) (xy 221.041212 -56.353456)
			(xy 221.045283 -56.297834) (xy 221.057409 -56.243397) (xy 221.077332 -56.191306) (xy 221.104628 -56.142671)
			(xy 221.138714 -56.098528) (xy 221.178863 -56.059819) (xy 221.224221 -56.027368) (xy 221.273821 -56.001867)
			(xy 221.326605 -55.98386) (xy 221.381448 -55.97373) (xy 221.437182 -55.971693) (xy 221.492619 -55.977793)
			(xy 221.546576 -55.991899) (xy 221.597905 -56.013711) (xy 221.645511 -56.042765) (xy 221.688379 -56.07844)
			(xy 221.725596 -56.119977) (xy 221.756369 -56.16649) (xy 221.775907 -56.208168) (xy 237.456218 -56.208168)
			(xy 237.456668 -56.181342) (xy 237.464184 -56.128218) (xy 237.479063 -56.076669) (xy 237.501014 -56.027712)
			(xy 237.529602 -55.982309) (xy 237.564265 -55.941357) (xy 237.604321 -55.905661) (xy 237.626398 -55.890414)
			(xy 237.637934 -55.882155) (xy 237.656341 -55.860586) (xy 237.668098 -55.834782) (xy 237.672298 -55.806738)
			(xy 237.668615 -55.778622) (xy 237.657334 -55.752607) (xy 237.639327 -55.730702) (xy 237.627922 -55.722266)
			(xy 237.606422 -55.706971) (xy 237.567513 -55.671333) (xy 237.533886 -55.630673) (xy 237.506181 -55.585767)
			(xy 237.484928 -55.537473) (xy 237.470531 -55.486711) (xy 237.463266 -55.43445) (xy 237.462822 -55.408068)
			(xy 237.463308 -55.380817) (xy 237.471064 -55.326869) (xy 237.486419 -55.274574) (xy 237.509061 -55.224997)
			(xy 237.538527 -55.179147) (xy 237.574218 -55.137956) (xy 237.615409 -55.102265) (xy 237.661259 -55.072799)
			(xy 237.710836 -55.050157) (xy 237.763131 -55.034802) (xy 237.817079 -55.027046) (xy 237.871581 -55.027046)
			(xy 237.925529 -55.034802) (xy 237.977824 -55.050157) (xy 238.027401 -55.072799) (xy 238.073251 -55.102265)
			(xy 238.114442 -55.137956) (xy 238.150133 -55.179147) (xy 238.179599 -55.224997) (xy 238.202241 -55.274574)
			(xy 238.217596 -55.326869) (xy 238.225352 -55.380817) (xy 238.225838 -55.408068) (xy 238.225391 -55.434894)
			(xy 238.217871 -55.488017) (xy 238.202989 -55.539565) (xy 238.181038 -55.588521) (xy 238.15245 -55.633923)
			(xy 238.117788 -55.674876) (xy 238.077734 -55.710574) (xy 238.060806 -55.722266) (xy 258.034026 -55.722266)
			(xy 258.038097 -55.666644) (xy 258.050223 -55.612207) (xy 258.070146 -55.560116) (xy 258.097442 -55.511481)
			(xy 258.131528 -55.467338) (xy 258.171677 -55.428629) (xy 258.217035 -55.396178) (xy 258.266635 -55.370677)
			(xy 258.319419 -55.35267) (xy 258.374262 -55.34254) (xy 258.429996 -55.340503) (xy 258.485433 -55.346603)
			(xy 258.53939 -55.360709) (xy 258.590719 -55.382521) (xy 258.638325 -55.411575) (xy 258.681193 -55.44725)
			(xy 258.71841 -55.488787) (xy 258.749183 -55.5353) (xy 258.772855 -55.585797) (xy 258.788923 -55.639204)
			(xy 258.797043 -55.69438) (xy 258.797552 -55.722266) (xy 258.797043 -55.750152) (xy 258.788923 -55.805328)
			(xy 258.772855 -55.858735) (xy 258.749183 -55.909232) (xy 258.71841 -55.955745) (xy 258.681193 -55.997282)
			(xy 258.638325 -56.032957) (xy 258.590719 -56.062011) (xy 258.53939 -56.083823) (xy 258.485433 -56.097929)
			(xy 258.429996 -56.104029) (xy 258.374262 -56.101992) (xy 258.319419 -56.091862) (xy 258.266635 -56.073855)
			(xy 258.217035 -56.048354) (xy 258.171677 -56.015903) (xy 258.131528 -55.977194) (xy 258.097442 -55.933051)
			(xy 258.070146 -55.884416) (xy 258.050223 -55.832325) (xy 258.038097 -55.777888) (xy 258.034026 -55.722266)
			(xy 238.060806 -55.722266) (xy 238.055658 -55.725822) (xy 238.044091 -55.734038) (xy 238.025691 -55.75562)
			(xy 238.013941 -55.781432) (xy 238.009747 -55.809482) (xy 238.013435 -55.837602) (xy 238.024719 -55.863622)
			(xy 238.042728 -55.885531) (xy 238.054134 -55.89397) (xy 238.075594 -55.909318) (xy 238.114506 -55.944946)
			(xy 238.148138 -55.985596) (xy 238.175848 -56.030493) (xy 238.197108 -56.078779) (xy 238.211512 -56.129533)
			(xy 238.218786 -56.181789) (xy 238.219234 -56.208168) (xy 238.218748 -56.235419) (xy 238.210992 -56.289367)
			(xy 238.195637 -56.341662) (xy 238.172995 -56.391239) (xy 238.143529 -56.437089) (xy 238.107838 -56.47828)
			(xy 238.066647 -56.513971) (xy 238.020797 -56.543437) (xy 237.97122 -56.566079) (xy 237.918925 -56.581434)
			(xy 237.864977 -56.58919) (xy 237.810475 -56.58919) (xy 237.756527 -56.581434) (xy 237.704232 -56.566079)
			(xy 237.654655 -56.543437) (xy 237.608805 -56.513971) (xy 237.567614 -56.47828) (xy 237.531923 -56.437089)
			(xy 237.502457 -56.391239) (xy 237.479815 -56.341662) (xy 237.46446 -56.289367) (xy 237.456704 -56.235419)
			(xy 237.456218 -56.208168) (xy 221.775907 -56.208168) (xy 221.780041 -56.216987) (xy 221.796109 -56.270394)
			(xy 221.804229 -56.32557) (xy 221.804738 -56.353456) (xy 221.804229 -56.381342) (xy 221.796109 -56.436518)
			(xy 221.780041 -56.489925) (xy 221.756369 -56.540422) (xy 221.725596 -56.586935) (xy 221.688379 -56.628472)
			(xy 221.645511 -56.664147) (xy 221.597905 -56.693201) (xy 221.546576 -56.715013) (xy 221.492619 -56.729119)
			(xy 221.437182 -56.735219) (xy 221.381448 -56.733182) (xy 221.326605 -56.723052) (xy 221.273821 -56.705045)
			(xy 221.224221 -56.679544) (xy 221.178863 -56.647093) (xy 221.138714 -56.608384) (xy 221.104628 -56.564241)
			(xy 221.077332 -56.515606) (xy 221.057409 -56.463515) (xy 221.045283 -56.409078) (xy 221.041212 -56.353456)
			(xy 213.99125 -56.353456) (xy 213.993362 -56.360649) (xy 214.001118 -56.414597) (xy 214.001604 -56.441848)
			(xy 214.00113 -56.469182) (xy 213.993322 -56.523288) (xy 213.977873 -56.575727) (xy 213.9551 -56.625425)
			(xy 213.925467 -56.671364) (xy 213.907878 -56.692292) (xy 213.907624 -56.692546) (xy 213.90737 -56.6928)
			(xy 213.901774 -56.69988) (xy 213.895534 -56.716802) (xy 213.895178 -56.72582) (xy 213.895178 -56.792876)
			(xy 213.895551 -56.801891) (xy 213.901788 -56.818808) (xy 213.90737 -56.825896) (xy 213.907624 -56.82615)
			(xy 213.907878 -56.826404) (xy 213.925482 -56.84732) (xy 213.95512 -56.893259) (xy 213.977894 -56.94296)
			(xy 213.993339 -56.995402) (xy 213.998635 -57.032144) (xy 219.585792 -57.032144) (xy 219.589863 -56.976522)
			(xy 219.601989 -56.922085) (xy 219.621912 -56.869994) (xy 219.649208 -56.821359) (xy 219.683294 -56.777216)
			(xy 219.723443 -56.738507) (xy 219.768801 -56.706056) (xy 219.818401 -56.680555) (xy 219.871185 -56.662548)
			(xy 219.926028 -56.652418) (xy 219.981762 -56.650381) (xy 220.037199 -56.656481) (xy 220.091156 -56.670587)
			(xy 220.142485 -56.692399) (xy 220.190091 -56.721453) (xy 220.232959 -56.757128) (xy 220.270176 -56.798665)
			(xy 220.300949 -56.845178) (xy 220.308104 -56.86044) (xy 239.090452 -56.86044) (xy 239.094523 -56.804818)
			(xy 239.106649 -56.750381) (xy 239.126572 -56.69829) (xy 239.153868 -56.649655) (xy 239.187954 -56.605512)
			(xy 239.228103 -56.566803) (xy 239.273461 -56.534352) (xy 239.323061 -56.508851) (xy 239.375845 -56.490844)
			(xy 239.430688 -56.480714) (xy 239.486422 -56.478677) (xy 239.541859 -56.484777) (xy 239.595816 -56.498883)
			(xy 239.647145 -56.520695) (xy 239.694751 -56.549749) (xy 239.737619 -56.585424) (xy 239.774836 -56.626961)
			(xy 239.805609 -56.673474) (xy 239.829281 -56.723971) (xy 239.845349 -56.777378) (xy 239.853469 -56.832554)
			(xy 239.853978 -56.86044) (xy 239.853862 -56.86679) (xy 240.166142 -56.86679) (xy 240.170213 -56.811168)
			(xy 240.182339 -56.756731) (xy 240.202262 -56.70464) (xy 240.229558 -56.656005) (xy 240.263644 -56.611862)
			(xy 240.303793 -56.573153) (xy 240.349151 -56.540702) (xy 240.398751 -56.515201) (xy 240.451535 -56.497194)
			(xy 240.506378 -56.487064) (xy 240.562112 -56.485027) (xy 240.617549 -56.491127) (xy 240.671506 -56.505233)
			(xy 240.722835 -56.527045) (xy 240.770441 -56.556099) (xy 240.813309 -56.591774) (xy 240.850526 -56.633311)
			(xy 240.881299 -56.679824) (xy 240.904971 -56.730321) (xy 240.921039 -56.783728) (xy 240.929159 -56.838904)
			(xy 240.929668 -56.86679) (xy 241.182142 -56.86679) (xy 241.186213 -56.811168) (xy 241.198339 -56.756731)
			(xy 241.218262 -56.70464) (xy 241.245558 -56.656005) (xy 241.279644 -56.611862) (xy 241.319793 -56.573153)
			(xy 241.365151 -56.540702) (xy 241.414751 -56.515201) (xy 241.467535 -56.497194) (xy 241.522378 -56.487064)
			(xy 241.578112 -56.485027) (xy 241.633549 -56.491127) (xy 241.687506 -56.505233) (xy 241.738835 -56.527045)
			(xy 241.786441 -56.556099) (xy 241.829309 -56.591774) (xy 241.866526 -56.633311) (xy 241.897299 -56.679824)
			(xy 241.920971 -56.730321) (xy 241.937039 -56.783728) (xy 241.945159 -56.838904) (xy 241.945668 -56.86679)
			(xy 241.945159 -56.894676) (xy 241.937039 -56.949852) (xy 241.920971 -57.003259) (xy 241.897299 -57.053756)
			(xy 241.866526 -57.100269) (xy 241.829309 -57.141806) (xy 241.786441 -57.177481) (xy 241.738835 -57.206535)
			(xy 241.687506 -57.228347) (xy 241.633549 -57.242453) (xy 241.578112 -57.248553) (xy 241.522378 -57.246516)
			(xy 241.467535 -57.236386) (xy 241.414751 -57.218379) (xy 241.365151 -57.192878) (xy 241.319793 -57.160427)
			(xy 241.279644 -57.121718) (xy 241.245558 -57.077575) (xy 241.218262 -57.02894) (xy 241.198339 -56.976849)
			(xy 241.186213 -56.922412) (xy 241.182142 -56.86679) (xy 240.929668 -56.86679) (xy 240.929159 -56.894676)
			(xy 240.921039 -56.949852) (xy 240.904971 -57.003259) (xy 240.881299 -57.053756) (xy 240.850526 -57.100269)
			(xy 240.813309 -57.141806) (xy 240.770441 -57.177481) (xy 240.722835 -57.206535) (xy 240.671506 -57.228347)
			(xy 240.617549 -57.242453) (xy 240.562112 -57.248553) (xy 240.506378 -57.246516) (xy 240.451535 -57.236386)
			(xy 240.398751 -57.218379) (xy 240.349151 -57.192878) (xy 240.303793 -57.160427) (xy 240.263644 -57.121718)
			(xy 240.229558 -57.077575) (xy 240.202262 -57.02894) (xy 240.182339 -56.976849) (xy 240.170213 -56.922412)
			(xy 240.166142 -56.86679) (xy 239.853862 -56.86679) (xy 239.853469 -56.888326) (xy 239.845349 -56.943502)
			(xy 239.829281 -56.996909) (xy 239.805609 -57.047406) (xy 239.774836 -57.093919) (xy 239.737619 -57.135456)
			(xy 239.694751 -57.171131) (xy 239.647145 -57.200185) (xy 239.595816 -57.221997) (xy 239.541859 -57.236103)
			(xy 239.486422 -57.242203) (xy 239.430688 -57.240166) (xy 239.375845 -57.230036) (xy 239.323061 -57.212029)
			(xy 239.273461 -57.186528) (xy 239.228103 -57.154077) (xy 239.187954 -57.115368) (xy 239.153868 -57.071225)
			(xy 239.126572 -57.02259) (xy 239.106649 -56.970499) (xy 239.094523 -56.916062) (xy 239.090452 -56.86044)
			(xy 220.308104 -56.86044) (xy 220.324621 -56.895675) (xy 220.340689 -56.949082) (xy 220.348809 -57.004258)
			(xy 220.349318 -57.032144) (xy 220.348809 -57.06003) (xy 220.340689 -57.115206) (xy 220.324621 -57.168613)
			(xy 220.300949 -57.21911) (xy 220.270176 -57.265623) (xy 220.232959 -57.30716) (xy 220.190091 -57.342835)
			(xy 220.142485 -57.371889) (xy 220.091156 -57.393701) (xy 220.037199 -57.407807) (xy 219.981762 -57.413907)
			(xy 219.926028 -57.41187) (xy 219.871185 -57.40174) (xy 219.818401 -57.383733) (xy 219.768801 -57.358232)
			(xy 219.723443 -57.325781) (xy 219.683294 -57.287072) (xy 219.649208 -57.242929) (xy 219.621912 -57.194294)
			(xy 219.601989 -57.142203) (xy 219.589863 -57.087766) (xy 219.585792 -57.032144) (xy 213.998635 -57.032144)
			(xy 214.001138 -57.049513) (xy 214.001604 -57.076848) (xy 214.001118 -57.104099) (xy 213.993362 -57.158047)
			(xy 213.978007 -57.210342) (xy 213.955365 -57.259919) (xy 213.925899 -57.305769) (xy 213.890208 -57.34696)
			(xy 213.849017 -57.382651) (xy 213.803167 -57.412117) (xy 213.75359 -57.434759) (xy 213.701295 -57.450114)
			(xy 213.647347 -57.45787) (xy 213.592845 -57.45787) (xy 213.538897 -57.450114) (xy 213.486602 -57.434759)
			(xy 213.437025 -57.412117) (xy 213.391175 -57.382651) (xy 213.349984 -57.34696) (xy 213.314293 -57.305769)
			(xy 213.284827 -57.259919) (xy 213.262185 -57.210342) (xy 213.24683 -57.158047) (xy 213.239074 -57.104099)
			(xy 213.238588 -57.076848) (xy 212.427073 -57.076848) (xy 212.444217 -57.081883) (xy 212.493793 -57.104527)
			(xy 212.539642 -57.133995) (xy 212.580831 -57.169688) (xy 212.616521 -57.210879) (xy 212.645986 -57.25673)
			(xy 212.668626 -57.306307) (xy 212.68398 -57.358602) (xy 212.691736 -57.412549) (xy 212.691736 -57.467051)
			(xy 212.68398 -57.520998) (xy 212.668626 -57.573293) (xy 212.645986 -57.62287) (xy 212.616521 -57.668721)
			(xy 212.580831 -57.709912) (xy 212.539642 -57.745605) (xy 212.493793 -57.775073) (xy 212.444217 -57.797717)
			(xy 212.391924 -57.813075) (xy 212.337977 -57.820834) (xy 212.310726 -57.821322) (xy 212.310472 -57.821322)
			(xy 212.284177 -57.820875) (xy 212.232088 -57.813626) (xy 212.181487 -57.799297) (xy 212.133331 -57.77816)
			(xy 212.088531 -57.750613) (xy 212.047936 -57.717179) (xy 212.029802 -57.698132) (xy 212.022224 -57.690697)
			(xy 212.002811 -57.682167) (xy 211.99221 -57.681622) (xy 211.918042 -57.681622) (xy 211.907406 -57.682002)
			(xy 211.887942 -57.690571) (xy 211.88045 -57.698132) (xy 211.862342 -57.717208) (xy 211.821757 -57.750665)
			(xy 211.776957 -57.778224) (xy 211.728792 -57.79936) (xy 211.678179 -57.813672) (xy 211.626079 -57.820888)
			(xy 211.59978 -57.821322) (xy 211.599526 -57.821322) (xy 211.572273 -57.820832) (xy 211.518321 -57.813079)
			(xy 211.466022 -57.797726) (xy 211.416441 -57.775085) (xy 211.370586 -57.745619) (xy 211.329392 -57.709927)
			(xy 211.293696 -57.668735) (xy 211.264227 -57.622882) (xy 211.241584 -57.573302) (xy 211.226227 -57.521004)
			(xy 211.218469 -57.467053) (xy 211.035204 -57.467053) (xy 211.039017 -57.494543) (xy 211.039456 -57.52084)
			(xy 211.039456 -57.521094) (xy 211.038962 -57.548427) (xy 211.031161 -57.602533) (xy 211.015717 -57.654972)
			(xy 210.992948 -57.704671) (xy 210.963318 -57.75061) (xy 210.94573 -57.771538) (xy 210.945476 -57.771792)
			(xy 210.945222 -57.772046) (xy 210.939643 -57.779137) (xy 210.933394 -57.796051) (xy 210.93303 -57.805066)
			(xy 210.93303 -57.872122) (xy 210.93337 -57.881141) (xy 210.939629 -57.898058) (xy 210.945222 -57.905142)
			(xy 210.945476 -57.905396) (xy 210.94573 -57.90565) (xy 210.963325 -57.926577) (xy 210.992978 -57.972509)
			(xy 211.015767 -58.022205) (xy 211.031225 -58.074647) (xy 211.039034 -58.128759) (xy 211.039034 -58.183432)
			(xy 211.031227 -58.237544) (xy 211.01577 -58.289986) (xy 210.992982 -58.339683) (xy 210.96333 -58.385616)
			(xy 210.94573 -58.406538) (xy 210.945476 -58.406792) (xy 210.945222 -58.407046) (xy 210.939643 -58.414137)
			(xy 210.933394 -58.431051) (xy 210.93303 -58.440066) (xy 210.93303 -58.507122) (xy 210.93337 -58.516141)
			(xy 210.939629 -58.533058) (xy 210.945222 -58.540142) (xy 210.945476 -58.540396) (xy 210.94573 -58.54065)
			(xy 210.963317 -58.56158) (xy 210.992955 -58.607516) (xy 211.015732 -58.657213) (xy 211.031181 -58.709652)
			(xy 211.038986 -58.76376) (xy 211.039456 -58.791094) (xy 211.03897 -58.818345) (xy 211.031214 -58.872293)
			(xy 211.030817 -58.873644) (xy 212.300566 -58.873644) (xy 212.301018 -58.846309) (xy 212.308829 -58.792201)
			(xy 212.324282 -58.739761) (xy 212.347061 -58.690064) (xy 212.3767 -58.644126) (xy 212.394292 -58.6232)
			(xy 212.394546 -58.622946) (xy 212.3948 -58.622692) (xy 212.400396 -58.615612) (xy 212.406637 -58.59869)
			(xy 212.406992 -58.589672) (xy 212.406992 -58.522616) (xy 212.406629 -58.5136) (xy 212.400386 -58.496683)
			(xy 212.3948 -58.489596) (xy 212.394546 -58.489342) (xy 212.394292 -58.489088) (xy 212.376679 -58.468179)
			(xy 212.347044 -58.422237) (xy 212.324272 -58.372535) (xy 212.308829 -58.320091) (xy 212.301031 -58.265979)
			(xy 212.300566 -58.238644) (xy 212.301052 -58.211393) (xy 212.308808 -58.157445) (xy 212.324163 -58.10515)
			(xy 212.346805 -58.055573) (xy 212.376271 -58.009723) (xy 212.411962 -57.968532) (xy 212.453153 -57.932841)
			(xy 212.499003 -57.903375) (xy 212.54858 -57.880733) (xy 212.600875 -57.865378) (xy 212.654823 -57.857622)
			(xy 212.709325 -57.857622) (xy 212.763273 -57.865378) (xy 212.815568 -57.880733) (xy 212.865145 -57.903375)
			(xy 212.910995 -57.932841) (xy 212.952186 -57.968532) (xy 212.987877 -58.009723) (xy 213.017343 -58.055573)
			(xy 213.039985 -58.10515) (xy 213.05534 -58.157445) (xy 213.063096 -58.211393) (xy 213.063582 -58.238644)
			(xy 213.063111 -58.265978) (xy 213.055303 -58.320085) (xy 213.039854 -58.372524) (xy 213.017079 -58.422222)
			(xy 212.987446 -58.468161) (xy 212.969856 -58.489088) (xy 212.969602 -58.489342) (xy 212.969348 -58.489596)
			(xy 212.963751 -58.496675) (xy 212.957512 -58.513598) (xy 212.957156 -58.522616) (xy 212.957156 -58.589672)
			(xy 212.957514 -58.598689) (xy 212.96376 -58.615607) (xy 212.969348 -58.622692) (xy 212.969602 -58.622946)
			(xy 212.969856 -58.6232) (xy 212.987455 -58.644121) (xy 213.017094 -58.690058) (xy 213.03987 -58.739757)
			(xy 213.055316 -58.792199) (xy 213.063116 -58.846309) (xy 213.063582 -58.873644) (xy 213.063096 -58.900895)
			(xy 213.05534 -58.954843) (xy 213.039985 -59.007138) (xy 213.017343 -59.056715) (xy 212.987877 -59.102565)
			(xy 212.952186 -59.143756) (xy 212.910995 -59.179447) (xy 212.865145 -59.208913) (xy 212.815568 -59.231555)
			(xy 212.763273 -59.24691) (xy 212.709325 -59.254666) (xy 212.654823 -59.254666) (xy 212.600875 -59.24691)
			(xy 212.54858 -59.231555) (xy 212.499003 -59.208913) (xy 212.453153 -59.179447) (xy 212.411962 -59.143756)
			(xy 212.376271 -59.102565) (xy 212.346805 -59.056715) (xy 212.324163 -59.007138) (xy 212.308808 -58.954843)
			(xy 212.301052 -58.900895) (xy 212.300566 -58.873644) (xy 211.030817 -58.873644) (xy 211.015859 -58.924588)
			(xy 210.993217 -58.974165) (xy 210.963751 -59.020015) (xy 210.92806 -59.061206) (xy 210.886869 -59.096897)
			(xy 210.841019 -59.126363) (xy 210.791442 -59.149005) (xy 210.739147 -59.16436) (xy 210.685199 -59.172116)
			(xy 210.630697 -59.172116) (xy 210.576749 -59.16436) (xy 210.524454 -59.149005) (xy 210.474877 -59.126363)
			(xy 210.429027 -59.096897) (xy 210.387836 -59.061206) (xy 210.352145 -59.020015) (xy 210.322679 -58.974165)
			(xy 210.300037 -58.924588) (xy 210.284682 -58.872293) (xy 210.276926 -58.818345) (xy 210.27644 -58.791094)
			(xy 208.378482 -58.791094) (xy 208.37539 -58.812603) (xy 208.360035 -58.864898) (xy 208.337393 -58.914475)
			(xy 208.307927 -58.960325) (xy 208.272236 -59.001516) (xy 208.231045 -59.037207) (xy 208.185195 -59.066673)
			(xy 208.135618 -59.089315) (xy 208.083323 -59.10467) (xy 208.029375 -59.112426) (xy 207.974873 -59.112426)
			(xy 207.920925 -59.10467) (xy 207.86863 -59.089315) (xy 207.819053 -59.066673) (xy 207.773203 -59.037207)
			(xy 207.732012 -59.001516) (xy 207.696321 -58.960325) (xy 207.666855 -58.914475) (xy 207.644213 -58.864898)
			(xy 207.628858 -58.812603) (xy 207.621102 -58.758655) (xy 207.620616 -58.731404) (xy 203.548066 -58.731404)
			(xy 203.513213 -58.760409) (xy 203.465607 -58.789463) (xy 203.414278 -58.811275) (xy 203.360321 -58.825381)
			(xy 203.304884 -58.831481) (xy 203.24915 -58.829444) (xy 203.194307 -58.819314) (xy 203.141523 -58.801307)
			(xy 203.091923 -58.775806) (xy 203.046565 -58.743355) (xy 203.006416 -58.704646) (xy 202.97233 -58.660503)
			(xy 202.945034 -58.611868) (xy 202.925111 -58.559777) (xy 202.912985 -58.50534) (xy 202.908914 -58.449718)
			(xy 201.408623 -58.449718) (xy 201.417181 -58.478162) (xy 201.425301 -58.533338) (xy 201.42581 -58.561224)
			(xy 201.425301 -58.58911) (xy 201.417181 -58.644286) (xy 201.401113 -58.697693) (xy 201.377441 -58.74819)
			(xy 201.346668 -58.794703) (xy 201.309451 -58.83624) (xy 201.266583 -58.871915) (xy 201.218977 -58.900969)
			(xy 201.167648 -58.922781) (xy 201.113691 -58.936887) (xy 201.058254 -58.942987) (xy 201.00252 -58.94095)
			(xy 200.947677 -58.93082) (xy 200.894893 -58.912813) (xy 200.845293 -58.887312) (xy 200.799935 -58.854861)
			(xy 200.759786 -58.816152) (xy 200.7257 -58.772009) (xy 200.698404 -58.723374) (xy 200.678481 -58.671283)
			(xy 200.666355 -58.616846) (xy 200.662284 -58.561224) (xy 186.957208 -58.561224) (xy 186.957208 -58.589672)
			(xy 186.957576 -58.598688) (xy 186.963816 -58.615605) (xy 186.9694 -58.622692) (xy 186.969654 -58.622946)
			(xy 186.969908 -58.6232) (xy 186.987515 -58.644114) (xy 187.017151 -58.690054) (xy 187.039924 -58.739755)
			(xy 187.055369 -58.792198) (xy 187.063168 -58.846309) (xy 187.063634 -58.873644) (xy 187.063148 -58.900895)
			(xy 187.055392 -58.954843) (xy 187.040037 -59.007138) (xy 187.017395 -59.056715) (xy 186.987929 -59.102565)
			(xy 186.952238 -59.143756) (xy 186.911047 -59.179447) (xy 186.865197 -59.208913) (xy 186.81562 -59.231555)
			(xy 186.763325 -59.24691) (xy 186.709377 -59.254666) (xy 186.654875 -59.254666) (xy 186.600927 -59.24691)
			(xy 186.548632 -59.231555) (xy 186.499055 -59.208913) (xy 186.453205 -59.179447) (xy 186.412014 -59.143756)
			(xy 186.376323 -59.102565) (xy 186.346857 -59.056715) (xy 186.324215 -59.007138) (xy 186.30886 -58.954843)
			(xy 186.301104 -58.900895) (xy 186.300618 -58.873644) (xy 185.030869 -58.873644) (xy 185.015911 -58.924588)
			(xy 184.993269 -58.974165) (xy 184.963803 -59.020015) (xy 184.928112 -59.061206) (xy 184.886921 -59.096897)
			(xy 184.841071 -59.126363) (xy 184.791494 -59.149005) (xy 184.739199 -59.16436) (xy 184.685251 -59.172116)
			(xy 184.630749 -59.172116) (xy 184.576801 -59.16436) (xy 184.524506 -59.149005) (xy 184.474929 -59.126363)
			(xy 184.429079 -59.096897) (xy 184.387888 -59.061206) (xy 184.352197 -59.020015) (xy 184.322731 -58.974165)
			(xy 184.300089 -58.924588) (xy 184.284734 -58.872293) (xy 184.276978 -58.818345) (xy 184.276492 -58.791094)
			(xy 182.378534 -58.791094) (xy 182.375442 -58.812603) (xy 182.360087 -58.864898) (xy 182.337445 -58.914475)
			(xy 182.307979 -58.960325) (xy 182.272288 -59.001516) (xy 182.231097 -59.037207) (xy 182.185247 -59.066673)
			(xy 182.13567 -59.089315) (xy 182.083375 -59.10467) (xy 182.029427 -59.112426) (xy 181.974925 -59.112426)
			(xy 181.920977 -59.10467) (xy 181.868682 -59.089315) (xy 181.819105 -59.066673) (xy 181.773255 -59.037207)
			(xy 181.732064 -59.001516) (xy 181.696373 -58.960325) (xy 181.666907 -58.914475) (xy 181.644265 -58.864898)
			(xy 181.62891 -58.812603) (xy 181.621154 -58.758655) (xy 181.620668 -58.731404) (xy 177.548118 -58.731404)
			(xy 177.513265 -58.760409) (xy 177.465659 -58.789463) (xy 177.41433 -58.811275) (xy 177.360373 -58.825381)
			(xy 177.304936 -58.831481) (xy 177.249202 -58.829444) (xy 177.194359 -58.819314) (xy 177.141575 -58.801307)
			(xy 177.091975 -58.775806) (xy 177.046617 -58.743355) (xy 177.006468 -58.704646) (xy 176.972382 -58.660503)
			(xy 176.945086 -58.611868) (xy 176.925163 -58.559777) (xy 176.913037 -58.50534) (xy 176.908966 -58.449718)
			(xy 175.408675 -58.449718) (xy 175.417233 -58.478162) (xy 175.425353 -58.533338) (xy 175.425862 -58.561224)
			(xy 175.425353 -58.58911) (xy 175.417233 -58.644286) (xy 175.401165 -58.697693) (xy 175.377493 -58.74819)
			(xy 175.34672 -58.794703) (xy 175.309503 -58.83624) (xy 175.266635 -58.871915) (xy 175.219029 -58.900969)
			(xy 175.1677 -58.922781) (xy 175.113743 -58.936887) (xy 175.058306 -58.942987) (xy 175.002572 -58.94095)
			(xy 174.947729 -58.93082) (xy 174.894945 -58.912813) (xy 174.845345 -58.887312) (xy 174.799987 -58.854861)
			(xy 174.759838 -58.816152) (xy 174.725752 -58.772009) (xy 174.698456 -58.723374) (xy 174.678533 -58.671283)
			(xy 174.666407 -58.616846) (xy 174.662336 -58.561224) (xy 160.95726 -58.561224) (xy 160.95726 -58.589672)
			(xy 160.957617 -58.598689) (xy 160.963863 -58.615607) (xy 160.969452 -58.622692) (xy 160.969706 -58.622946)
			(xy 160.96996 -58.6232) (xy 160.98756 -58.64412) (xy 161.017198 -58.690058) (xy 161.039974 -58.739757)
			(xy 161.05542 -58.792199) (xy 161.06322 -58.846309) (xy 161.063686 -58.873644) (xy 161.0632 -58.900895)
			(xy 161.055444 -58.954843) (xy 161.040089 -59.007138) (xy 161.017447 -59.056715) (xy 160.987981 -59.102565)
			(xy 160.95229 -59.143756) (xy 160.911099 -59.179447) (xy 160.865249 -59.208913) (xy 160.815672 -59.231555)
			(xy 160.763377 -59.24691) (xy 160.709429 -59.254666) (xy 160.654927 -59.254666) (xy 160.600979 -59.24691)
			(xy 160.548684 -59.231555) (xy 160.499107 -59.208913) (xy 160.453257 -59.179447) (xy 160.412066 -59.143756)
			(xy 160.376375 -59.102565) (xy 160.346909 -59.056715) (xy 160.324267 -59.007138) (xy 160.308912 -58.954843)
			(xy 160.301156 -58.900895) (xy 160.30067 -58.873644) (xy 159.030921 -58.873644) (xy 159.015963 -58.924588)
			(xy 158.993321 -58.974165) (xy 158.963855 -59.020015) (xy 158.928164 -59.061206) (xy 158.886973 -59.096897)
			(xy 158.841123 -59.126363) (xy 158.791546 -59.149005) (xy 158.739251 -59.16436) (xy 158.685303 -59.172116)
			(xy 158.630801 -59.172116) (xy 158.576853 -59.16436) (xy 158.524558 -59.149005) (xy 158.474981 -59.126363)
			(xy 158.429131 -59.096897) (xy 158.38794 -59.061206) (xy 158.352249 -59.020015) (xy 158.322783 -58.974165)
			(xy 158.300141 -58.924588) (xy 158.284786 -58.872293) (xy 158.27703 -58.818345) (xy 158.276544 -58.791094)
			(xy 156.378586 -58.791094) (xy 156.375494 -58.812603) (xy 156.360139 -58.864898) (xy 156.337497 -58.914475)
			(xy 156.308031 -58.960325) (xy 156.27234 -59.001516) (xy 156.231149 -59.037207) (xy 156.185299 -59.066673)
			(xy 156.135722 -59.089315) (xy 156.083427 -59.10467) (xy 156.029479 -59.112426) (xy 155.974977 -59.112426)
			(xy 155.921029 -59.10467) (xy 155.868734 -59.089315) (xy 155.819157 -59.066673) (xy 155.773307 -59.037207)
			(xy 155.732116 -59.001516) (xy 155.696425 -58.960325) (xy 155.666959 -58.914475) (xy 155.644317 -58.864898)
			(xy 155.628962 -58.812603) (xy 155.621206 -58.758655) (xy 155.62072 -58.731404) (xy 151.54817 -58.731404)
			(xy 151.513317 -58.760409) (xy 151.465711 -58.789463) (xy 151.414382 -58.811275) (xy 151.360425 -58.825381)
			(xy 151.304988 -58.831481) (xy 151.249254 -58.829444) (xy 151.194411 -58.819314) (xy 151.141627 -58.801307)
			(xy 151.092027 -58.775806) (xy 151.046669 -58.743355) (xy 151.00652 -58.704646) (xy 150.972434 -58.660503)
			(xy 150.945138 -58.611868) (xy 150.925215 -58.559777) (xy 150.913089 -58.50534) (xy 150.909018 -58.449718)
			(xy 149.408727 -58.449718) (xy 149.417285 -58.478162) (xy 149.425405 -58.533338) (xy 149.425914 -58.561224)
			(xy 149.425405 -58.58911) (xy 149.417285 -58.644286) (xy 149.401217 -58.697693) (xy 149.377545 -58.74819)
			(xy 149.346772 -58.794703) (xy 149.309555 -58.83624) (xy 149.266687 -58.871915) (xy 149.219081 -58.900969)
			(xy 149.167752 -58.922781) (xy 149.113795 -58.936887) (xy 149.058358 -58.942987) (xy 149.002624 -58.94095)
			(xy 148.947781 -58.93082) (xy 148.894997 -58.912813) (xy 148.845397 -58.887312) (xy 148.800039 -58.854861)
			(xy 148.75989 -58.816152) (xy 148.725804 -58.772009) (xy 148.698508 -58.723374) (xy 148.678585 -58.671283)
			(xy 148.666459 -58.616846) (xy 148.662388 -58.561224) (xy 134.957312 -58.561224) (xy 134.957312 -58.589672)
			(xy 134.95768 -58.598688) (xy 134.963919 -58.615605) (xy 134.969504 -58.622692) (xy 134.969758 -58.622946)
			(xy 134.970012 -58.6232) (xy 134.98762 -58.644113) (xy 135.017255 -58.690054) (xy 135.040029 -58.739755)
			(xy 135.055473 -58.792198) (xy 135.063272 -58.846309) (xy 135.063738 -58.873644) (xy 135.063252 -58.900895)
			(xy 135.055496 -58.954843) (xy 135.040141 -59.007138) (xy 135.017499 -59.056715) (xy 134.988033 -59.102565)
			(xy 134.952342 -59.143756) (xy 134.911151 -59.179447) (xy 134.865301 -59.208913) (xy 134.815724 -59.231555)
			(xy 134.763429 -59.24691) (xy 134.709481 -59.254666) (xy 134.654979 -59.254666) (xy 134.601031 -59.24691)
			(xy 134.548736 -59.231555) (xy 134.499159 -59.208913) (xy 134.453309 -59.179447) (xy 134.412118 -59.143756)
			(xy 134.376427 -59.102565) (xy 134.346961 -59.056715) (xy 134.324319 -59.007138) (xy 134.308964 -58.954843)
			(xy 134.301208 -58.900895) (xy 134.300722 -58.873644) (xy 133.030973 -58.873644) (xy 133.016015 -58.924588)
			(xy 132.993373 -58.974165) (xy 132.963907 -59.020015) (xy 132.928216 -59.061206) (xy 132.887025 -59.096897)
			(xy 132.841175 -59.126363) (xy 132.791598 -59.149005) (xy 132.739303 -59.16436) (xy 132.685355 -59.172116)
			(xy 132.630853 -59.172116) (xy 132.576905 -59.16436) (xy 132.52461 -59.149005) (xy 132.475033 -59.126363)
			(xy 132.429183 -59.096897) (xy 132.387992 -59.061206) (xy 132.352301 -59.020015) (xy 132.322835 -58.974165)
			(xy 132.300193 -58.924588) (xy 132.284838 -58.872293) (xy 132.277082 -58.818345) (xy 132.276596 -58.791094)
			(xy 130.378638 -58.791094) (xy 130.375546 -58.812603) (xy 130.360191 -58.864898) (xy 130.337549 -58.914475)
			(xy 130.308083 -58.960325) (xy 130.272392 -59.001516) (xy 130.231201 -59.037207) (xy 130.185351 -59.066673)
			(xy 130.135774 -59.089315) (xy 130.083479 -59.10467) (xy 130.029531 -59.112426) (xy 129.975029 -59.112426)
			(xy 129.921081 -59.10467) (xy 129.868786 -59.089315) (xy 129.819209 -59.066673) (xy 129.773359 -59.037207)
			(xy 129.732168 -59.001516) (xy 129.696477 -58.960325) (xy 129.667011 -58.914475) (xy 129.644369 -58.864898)
			(xy 129.629014 -58.812603) (xy 129.621258 -58.758655) (xy 129.620772 -58.731404) (xy 125.548222 -58.731404)
			(xy 125.513369 -58.760409) (xy 125.465763 -58.789463) (xy 125.414434 -58.811275) (xy 125.360477 -58.825381)
			(xy 125.30504 -58.831481) (xy 125.249306 -58.829444) (xy 125.194463 -58.819314) (xy 125.141679 -58.801307)
			(xy 125.092079 -58.775806) (xy 125.046721 -58.743355) (xy 125.006572 -58.704646) (xy 124.972486 -58.660503)
			(xy 124.94519 -58.611868) (xy 124.925267 -58.559777) (xy 124.913141 -58.50534) (xy 124.90907 -58.449718)
			(xy 123.408779 -58.449718) (xy 123.417337 -58.478162) (xy 123.425457 -58.533338) (xy 123.425966 -58.561224)
			(xy 123.425457 -58.58911) (xy 123.417337 -58.644286) (xy 123.401269 -58.697693) (xy 123.377597 -58.74819)
			(xy 123.346824 -58.794703) (xy 123.309607 -58.83624) (xy 123.266739 -58.871915) (xy 123.219133 -58.900969)
			(xy 123.167804 -58.922781) (xy 123.113847 -58.936887) (xy 123.05841 -58.942987) (xy 123.002676 -58.94095)
			(xy 122.947833 -58.93082) (xy 122.895049 -58.912813) (xy 122.845449 -58.887312) (xy 122.800091 -58.854861)
			(xy 122.759942 -58.816152) (xy 122.725856 -58.772009) (xy 122.69856 -58.723374) (xy 122.678637 -58.671283)
			(xy 122.666511 -58.616846) (xy 122.66244 -58.561224) (xy 96.857058 -58.561224) (xy 96.857058 -58.589672)
			(xy 96.857416 -58.598689) (xy 96.863661 -58.615607) (xy 96.86925 -58.622692) (xy 96.869504 -58.622946)
			(xy 96.869758 -58.6232) (xy 96.887357 -58.64412) (xy 96.916996 -58.690058) (xy 96.939772 -58.739757)
			(xy 96.955218 -58.792199) (xy 96.963018 -58.846309) (xy 96.963484 -58.873644) (xy 96.962998 -58.900895)
			(xy 96.955242 -58.954843) (xy 96.939887 -59.007138) (xy 96.917245 -59.056715) (xy 96.887779 -59.102565)
			(xy 96.852088 -59.143756) (xy 96.810897 -59.179447) (xy 96.765047 -59.208913) (xy 96.71547 -59.231555)
			(xy 96.663175 -59.24691) (xy 96.609227 -59.254666) (xy 96.554725 -59.254666) (xy 96.500777 -59.24691)
			(xy 96.448482 -59.231555) (xy 96.398905 -59.208913) (xy 96.353055 -59.179447) (xy 96.311864 -59.143756)
			(xy 96.276173 -59.102565) (xy 96.246707 -59.056715) (xy 96.224065 -59.007138) (xy 96.20871 -58.954843)
			(xy 96.200954 -58.900895) (xy 96.200468 -58.873644) (xy 94.930719 -58.873644) (xy 94.915761 -58.924588)
			(xy 94.893119 -58.974165) (xy 94.863653 -59.020015) (xy 94.827962 -59.061206) (xy 94.786771 -59.096897)
			(xy 94.740921 -59.126363) (xy 94.691344 -59.149005) (xy 94.639049 -59.16436) (xy 94.585101 -59.172116)
			(xy 94.530599 -59.172116) (xy 94.476651 -59.16436) (xy 94.424356 -59.149005) (xy 94.374779 -59.126363)
			(xy 94.328929 -59.096897) (xy 94.287738 -59.061206) (xy 94.252047 -59.020015) (xy 94.222581 -58.974165)
			(xy 94.199939 -58.924588) (xy 94.184584 -58.872293) (xy 94.176828 -58.818345) (xy 94.176342 -58.791094)
			(xy 92.278384 -58.791094) (xy 92.275292 -58.812603) (xy 92.259937 -58.864898) (xy 92.237295 -58.914475)
			(xy 92.207829 -58.960325) (xy 92.172138 -59.001516) (xy 92.130947 -59.037207) (xy 92.085097 -59.066673)
			(xy 92.03552 -59.089315) (xy 91.983225 -59.10467) (xy 91.929277 -59.112426) (xy 91.874775 -59.112426)
			(xy 91.820827 -59.10467) (xy 91.768532 -59.089315) (xy 91.718955 -59.066673) (xy 91.673105 -59.037207)
			(xy 91.631914 -59.001516) (xy 91.596223 -58.960325) (xy 91.566757 -58.914475) (xy 91.544115 -58.864898)
			(xy 91.52876 -58.812603) (xy 91.521004 -58.758655) (xy 91.520518 -58.731404) (xy 87.447968 -58.731404)
			(xy 87.413115 -58.760409) (xy 87.365509 -58.789463) (xy 87.31418 -58.811275) (xy 87.260223 -58.825381)
			(xy 87.204786 -58.831481) (xy 87.149052 -58.829444) (xy 87.094209 -58.819314) (xy 87.041425 -58.801307)
			(xy 86.991825 -58.775806) (xy 86.946467 -58.743355) (xy 86.906318 -58.704646) (xy 86.872232 -58.660503)
			(xy 86.844936 -58.611868) (xy 86.825013 -58.559777) (xy 86.812887 -58.50534) (xy 86.808816 -58.449718)
			(xy 85.308525 -58.449718) (xy 85.317083 -58.478162) (xy 85.325203 -58.533338) (xy 85.325712 -58.561224)
			(xy 85.325203 -58.58911) (xy 85.317083 -58.644286) (xy 85.301015 -58.697693) (xy 85.277343 -58.74819)
			(xy 85.24657 -58.794703) (xy 85.209353 -58.83624) (xy 85.166485 -58.871915) (xy 85.118879 -58.900969)
			(xy 85.06755 -58.922781) (xy 85.013593 -58.936887) (xy 84.958156 -58.942987) (xy 84.902422 -58.94095)
			(xy 84.847579 -58.93082) (xy 84.794795 -58.912813) (xy 84.745195 -58.887312) (xy 84.699837 -58.854861)
			(xy 84.659688 -58.816152) (xy 84.625602 -58.772009) (xy 84.598306 -58.723374) (xy 84.578383 -58.671283)
			(xy 84.566257 -58.616846) (xy 84.562186 -58.561224) (xy 70.85711 -58.561224) (xy 70.85711 -58.589672)
			(xy 70.857478 -58.598688) (xy 70.863718 -58.615605) (xy 70.869302 -58.622692) (xy 70.869556 -58.622946)
			(xy 70.86981 -58.6232) (xy 70.887417 -58.644114) (xy 70.917053 -58.690054) (xy 70.939827 -58.739755)
			(xy 70.955271 -58.792198) (xy 70.96307 -58.846309) (xy 70.963536 -58.873644) (xy 70.96305 -58.900895)
			(xy 70.955294 -58.954843) (xy 70.939939 -59.007138) (xy 70.917297 -59.056715) (xy 70.887831 -59.102565)
			(xy 70.85214 -59.143756) (xy 70.810949 -59.179447) (xy 70.765099 -59.208913) (xy 70.715522 -59.231555)
			(xy 70.663227 -59.24691) (xy 70.609279 -59.254666) (xy 70.554777 -59.254666) (xy 70.500829 -59.24691)
			(xy 70.448534 -59.231555) (xy 70.398957 -59.208913) (xy 70.353107 -59.179447) (xy 70.311916 -59.143756)
			(xy 70.276225 -59.102565) (xy 70.246759 -59.056715) (xy 70.224117 -59.007138) (xy 70.208762 -58.954843)
			(xy 70.201006 -58.900895) (xy 70.20052 -58.873644) (xy 68.930771 -58.873644) (xy 68.915813 -58.924588)
			(xy 68.893171 -58.974165) (xy 68.863705 -59.020015) (xy 68.828014 -59.061206) (xy 68.786823 -59.096897)
			(xy 68.740973 -59.126363) (xy 68.691396 -59.149005) (xy 68.639101 -59.16436) (xy 68.585153 -59.172116)
			(xy 68.530651 -59.172116) (xy 68.476703 -59.16436) (xy 68.424408 -59.149005) (xy 68.374831 -59.126363)
			(xy 68.328981 -59.096897) (xy 68.28779 -59.061206) (xy 68.252099 -59.020015) (xy 68.222633 -58.974165)
			(xy 68.199991 -58.924588) (xy 68.184636 -58.872293) (xy 68.17688 -58.818345) (xy 68.176394 -58.791094)
			(xy 66.278436 -58.791094) (xy 66.275344 -58.812603) (xy 66.259989 -58.864898) (xy 66.237347 -58.914475)
			(xy 66.207881 -58.960325) (xy 66.17219 -59.001516) (xy 66.130999 -59.037207) (xy 66.085149 -59.066673)
			(xy 66.035572 -59.089315) (xy 65.983277 -59.10467) (xy 65.929329 -59.112426) (xy 65.874827 -59.112426)
			(xy 65.820879 -59.10467) (xy 65.768584 -59.089315) (xy 65.719007 -59.066673) (xy 65.673157 -59.037207)
			(xy 65.631966 -59.001516) (xy 65.596275 -58.960325) (xy 65.566809 -58.914475) (xy 65.544167 -58.864898)
			(xy 65.528812 -58.812603) (xy 65.521056 -58.758655) (xy 65.52057 -58.731404) (xy 61.44802 -58.731404)
			(xy 61.413167 -58.760409) (xy 61.365561 -58.789463) (xy 61.314232 -58.811275) (xy 61.260275 -58.825381)
			(xy 61.204838 -58.831481) (xy 61.149104 -58.829444) (xy 61.094261 -58.819314) (xy 61.041477 -58.801307)
			(xy 60.991877 -58.775806) (xy 60.946519 -58.743355) (xy 60.90637 -58.704646) (xy 60.872284 -58.660503)
			(xy 60.844988 -58.611868) (xy 60.825065 -58.559777) (xy 60.812939 -58.50534) (xy 60.808868 -58.449718)
			(xy 59.308577 -58.449718) (xy 59.317135 -58.478162) (xy 59.325255 -58.533338) (xy 59.325764 -58.561224)
			(xy 59.325255 -58.58911) (xy 59.317135 -58.644286) (xy 59.301067 -58.697693) (xy 59.277395 -58.74819)
			(xy 59.246622 -58.794703) (xy 59.209405 -58.83624) (xy 59.166537 -58.871915) (xy 59.118931 -58.900969)
			(xy 59.067602 -58.922781) (xy 59.013645 -58.936887) (xy 58.958208 -58.942987) (xy 58.902474 -58.94095)
			(xy 58.847631 -58.93082) (xy 58.794847 -58.912813) (xy 58.745247 -58.887312) (xy 58.699889 -58.854861)
			(xy 58.65974 -58.816152) (xy 58.625654 -58.772009) (xy 58.598358 -58.723374) (xy 58.578435 -58.671283)
			(xy 58.566309 -58.616846) (xy 58.562238 -58.561224) (xy 44.857162 -58.561224) (xy 44.857162 -58.589672)
			(xy 44.857541 -58.598686) (xy 44.863774 -58.615603) (xy 44.869354 -58.622692) (xy 44.869608 -58.622946)
			(xy 44.869862 -58.6232) (xy 44.887462 -58.64412) (xy 44.917101 -58.690058) (xy 44.939876 -58.739757)
			(xy 44.955322 -58.792199) (xy 44.963122 -58.846309) (xy 44.963588 -58.873644) (xy 44.963102 -58.900895)
			(xy 44.955346 -58.954843) (xy 44.939991 -59.007138) (xy 44.917349 -59.056715) (xy 44.887883 -59.102565)
			(xy 44.852192 -59.143756) (xy 44.811001 -59.179447) (xy 44.765151 -59.208913) (xy 44.715574 -59.231555)
			(xy 44.663279 -59.24691) (xy 44.609331 -59.254666) (xy 44.554829 -59.254666) (xy 44.500881 -59.24691)
			(xy 44.448586 -59.231555) (xy 44.399009 -59.208913) (xy 44.353159 -59.179447) (xy 44.311968 -59.143756)
			(xy 44.276277 -59.102565) (xy 44.246811 -59.056715) (xy 44.224169 -59.007138) (xy 44.208814 -58.954843)
			(xy 44.201058 -58.900895) (xy 44.200572 -58.873644) (xy 42.930823 -58.873644) (xy 42.915865 -58.924588)
			(xy 42.893223 -58.974165) (xy 42.863757 -59.020015) (xy 42.828066 -59.061206) (xy 42.786875 -59.096897)
			(xy 42.741025 -59.126363) (xy 42.691448 -59.149005) (xy 42.639153 -59.16436) (xy 42.585205 -59.172116)
			(xy 42.530703 -59.172116) (xy 42.476755 -59.16436) (xy 42.42446 -59.149005) (xy 42.374883 -59.126363)
			(xy 42.329033 -59.096897) (xy 42.287842 -59.061206) (xy 42.252151 -59.020015) (xy 42.222685 -58.974165)
			(xy 42.200043 -58.924588) (xy 42.184688 -58.872293) (xy 42.176932 -58.818345) (xy 42.176446 -58.791094)
			(xy 40.278488 -58.791094) (xy 40.275396 -58.812603) (xy 40.260041 -58.864898) (xy 40.237399 -58.914475)
			(xy 40.207933 -58.960325) (xy 40.172242 -59.001516) (xy 40.131051 -59.037207) (xy 40.085201 -59.066673)
			(xy 40.035624 -59.089315) (xy 39.983329 -59.10467) (xy 39.929381 -59.112426) (xy 39.874879 -59.112426)
			(xy 39.820931 -59.10467) (xy 39.768636 -59.089315) (xy 39.719059 -59.066673) (xy 39.673209 -59.037207)
			(xy 39.632018 -59.001516) (xy 39.596327 -58.960325) (xy 39.566861 -58.914475) (xy 39.544219 -58.864898)
			(xy 39.528864 -58.812603) (xy 39.521108 -58.758655) (xy 39.520622 -58.731404) (xy 35.448072 -58.731404)
			(xy 35.413219 -58.760409) (xy 35.365613 -58.789463) (xy 35.314284 -58.811275) (xy 35.260327 -58.825381)
			(xy 35.20489 -58.831481) (xy 35.149156 -58.829444) (xy 35.094313 -58.819314) (xy 35.041529 -58.801307)
			(xy 34.991929 -58.775806) (xy 34.946571 -58.743355) (xy 34.906422 -58.704646) (xy 34.872336 -58.660503)
			(xy 34.84504 -58.611868) (xy 34.825117 -58.559777) (xy 34.812991 -58.50534) (xy 34.80892 -58.449718)
			(xy 33.308629 -58.449718) (xy 33.317187 -58.478162) (xy 33.325307 -58.533338) (xy 33.325816 -58.561224)
			(xy 33.325307 -58.58911) (xy 33.317187 -58.644286) (xy 33.301119 -58.697693) (xy 33.277447 -58.74819)
			(xy 33.246674 -58.794703) (xy 33.209457 -58.83624) (xy 33.166589 -58.871915) (xy 33.118983 -58.900969)
			(xy 33.067654 -58.922781) (xy 33.013697 -58.936887) (xy 32.95826 -58.942987) (xy 32.902526 -58.94095)
			(xy 32.847683 -58.93082) (xy 32.794899 -58.912813) (xy 32.745299 -58.887312) (xy 32.699941 -58.854861)
			(xy 32.659792 -58.816152) (xy 32.625706 -58.772009) (xy 32.59841 -58.723374) (xy 32.578487 -58.671283)
			(xy 32.566361 -58.616846) (xy 32.56229 -58.561224) (xy 20.380452 -58.561224) (xy 20.380452 -59.974734)
			(xy 31.08706 -59.974734) (xy 31.087509 -59.947908) (xy 31.095029 -59.894785) (xy 31.109911 -59.843238)
			(xy 31.131861 -59.794281) (xy 31.160449 -59.748879) (xy 31.195111 -59.707926) (xy 31.235164 -59.672228)
			(xy 31.25724 -59.65698) (xy 31.268805 -59.648762) (xy 31.287205 -59.62718) (xy 31.298956 -59.601368)
			(xy 31.30315 -59.573319) (xy 31.299462 -59.545199) (xy 31.288178 -59.51918) (xy 31.27017 -59.497271)
			(xy 31.258764 -59.488832) (xy 31.237304 -59.473483) (xy 31.198393 -59.437855) (xy 31.164761 -59.397205)
			(xy 31.137051 -59.352309) (xy 31.115791 -59.304023) (xy 31.101386 -59.253269) (xy 31.094112 -59.201013)
			(xy 31.093664 -59.174634) (xy 31.09415 -59.147383) (xy 31.101906 -59.093435) (xy 31.117261 -59.04114)
			(xy 31.139903 -58.991563) (xy 31.169369 -58.945713) (xy 31.20506 -58.904522) (xy 31.246251 -58.868831)
			(xy 31.292101 -58.839365) (xy 31.341678 -58.816723) (xy 31.393973 -58.801368) (xy 31.447921 -58.793612)
			(xy 31.502423 -58.793612) (xy 31.556371 -58.801368) (xy 31.608666 -58.816723) (xy 31.658243 -58.839365)
			(xy 31.704093 -58.868831) (xy 31.745284 -58.904522) (xy 31.780975 -58.945713) (xy 31.810441 -58.991563)
			(xy 31.833083 -59.04114) (xy 31.848438 -59.093435) (xy 31.856194 -59.147383) (xy 31.85668 -59.174634)
			(xy 31.856233 -59.201461) (xy 31.848716 -59.254585) (xy 31.833836 -59.306133) (xy 31.811886 -59.355091)
			(xy 31.783297 -59.400493) (xy 31.748633 -59.441445) (xy 31.708577 -59.477141) (xy 31.6865 -59.492388)
			(xy 31.674963 -59.500644) (xy 31.656556 -59.522215) (xy 31.644799 -59.548019) (xy 31.640599 -59.576063)
			(xy 31.644283 -59.604179) (xy 31.655564 -59.630195) (xy 31.673571 -59.6521) (xy 31.684976 -59.660536)
			(xy 31.706476 -59.67583) (xy 31.745385 -59.711469) (xy 31.779013 -59.752129) (xy 31.806717 -59.797034)
			(xy 31.827971 -59.845329) (xy 31.842367 -59.896091) (xy 31.849632 -59.948352) (xy 31.850076 -59.974734)
			(xy 31.84959 -60.001985) (xy 31.841834 -60.055933) (xy 31.826479 -60.108228) (xy 31.818157 -60.12645)
			(xy 43.180272 -60.12645) (xy 43.180272 -60.07195) (xy 43.188027 -60.018006) (xy 43.20338 -59.965714)
			(xy 43.226018 -59.916139) (xy 43.255481 -59.87029) (xy 43.291168 -59.8291) (xy 43.332353 -59.793408)
			(xy 43.378199 -59.76394) (xy 43.427771 -59.741296) (xy 43.480061 -59.725937) (xy 43.534004 -59.718175)
			(xy 43.561254 -59.717686) (xy 43.588623 -59.718182) (xy 43.642801 -59.725993) (xy 43.695303 -59.741476)
			(xy 43.745051 -59.76431) (xy 43.791019 -59.794028) (xy 43.811952 -59.811666) (xy 43.812206 -59.81192)
			(xy 43.819285 -59.817517) (xy 43.836208 -59.823757) (xy 43.845226 -59.824112) (xy 43.912282 -59.824112)
			(xy 43.921298 -59.823744) (xy 43.938215 -59.817504) (xy 43.945302 -59.81192) (xy 43.94581 -59.811412)
			(xy 43.96672 -59.79377) (xy 44.012691 -59.76411) (xy 44.062429 -59.741324) (xy 44.114913 -59.725879)
			(xy 44.169065 -59.718093) (xy 44.223774 -59.718124) (xy 44.277917 -59.725973) (xy 44.330383 -59.741479)
			(xy 44.380095 -59.764322) (xy 44.426032 -59.794035) (xy 44.446952 -59.811666) (xy 44.447206 -59.81192)
			(xy 44.454285 -59.817517) (xy 44.471208 -59.823757) (xy 44.480226 -59.824112) (xy 44.547282 -59.824112)
			(xy 44.556298 -59.823744) (xy 44.573215 -59.817504) (xy 44.580302 -59.81192) (xy 44.58081 -59.811412)
			(xy 44.601723 -59.793803) (xy 44.647663 -59.764167) (xy 44.697364 -59.741394) (xy 44.749808 -59.72595)
			(xy 44.803919 -59.718152) (xy 44.831254 -59.717686) (xy 44.858509 -59.718158) (xy 44.912464 -59.72591)
			(xy 44.964766 -59.741262) (xy 45.014351 -59.763901) (xy 45.060209 -59.793367) (xy 45.101407 -59.82906)
			(xy 45.137105 -59.870254) (xy 45.166577 -59.916108) (xy 45.189222 -59.965691) (xy 45.191877 -59.974734)
			(xy 57.087008 -59.974734) (xy 57.087436 -59.947907) (xy 57.094957 -59.894782) (xy 57.10984 -59.843233)
			(xy 57.131794 -59.794276) (xy 57.160386 -59.748874) (xy 57.195052 -59.707922) (xy 57.23511 -59.672227)
			(xy 57.257188 -59.65698) (xy 57.268757 -59.648764) (xy 57.287167 -59.627186) (xy 57.298924 -59.601372)
			(xy 57.30312 -59.573319) (xy 57.299431 -59.545196) (xy 57.288141 -59.519175) (xy 57.270123 -59.497268)
			(xy 57.258712 -59.488832) (xy 57.237263 -59.473469) (xy 57.198349 -59.437844) (xy 57.164715 -59.397198)
			(xy 57.137002 -59.352304) (xy 57.11574 -59.30402) (xy 57.101335 -59.253267) (xy 57.09406 -59.201013)
			(xy 57.093612 -59.174634) (xy 57.094098 -59.147383) (xy 57.101854 -59.093435) (xy 57.117209 -59.04114)
			(xy 57.139851 -58.991563) (xy 57.169317 -58.945713) (xy 57.205008 -58.904522) (xy 57.246199 -58.868831)
			(xy 57.292049 -58.839365) (xy 57.341626 -58.816723) (xy 57.393921 -58.801368) (xy 57.447869 -58.793612)
			(xy 57.502371 -58.793612) (xy 57.556319 -58.801368) (xy 57.608614 -58.816723) (xy 57.658191 -58.839365)
			(xy 57.704041 -58.868831) (xy 57.745232 -58.904522) (xy 57.780923 -58.945713) (xy 57.810389 -58.991563)
			(xy 57.833031 -59.04114) (xy 57.848386 -59.093435) (xy 57.856142 -59.147383) (xy 57.856628 -59.174634)
			(xy 57.85616 -59.20146) (xy 57.848644 -59.254582) (xy 57.833766 -59.306129) (xy 57.811819 -59.355086)
			(xy 57.783234 -59.400488) (xy 57.748574 -59.441441) (xy 57.708523 -59.47714) (xy 57.686448 -59.492388)
			(xy 57.674915 -59.500647) (xy 57.656518 -59.52222) (xy 57.644767 -59.548023) (xy 57.64057 -59.576063)
			(xy 57.644251 -59.604175) (xy 57.655526 -59.630189) (xy 57.673524 -59.652097) (xy 57.684924 -59.660536)
			(xy 57.706413 -59.675846) (xy 57.745324 -59.71148) (xy 57.778954 -59.752137) (xy 57.806661 -59.797039)
			(xy 57.827916 -59.845332) (xy 57.842314 -59.896092) (xy 57.84958 -59.948352) (xy 57.850024 -59.974734)
			(xy 57.849538 -60.001985) (xy 57.841782 -60.055933) (xy 57.826427 -60.108228) (xy 57.818104 -60.126453)
			(xy 69.180149 -60.126453) (xy 69.180149 -60.071947) (xy 69.187907 -60.017995) (xy 69.203263 -59.965696)
			(xy 69.225906 -59.916115) (xy 69.255375 -59.870261) (xy 69.291069 -59.829068) (xy 69.332262 -59.793373)
			(xy 69.378117 -59.763905) (xy 69.427698 -59.741262) (xy 69.479997 -59.725906) (xy 69.533949 -59.718149)
			(xy 69.561202 -59.717686) (xy 69.588572 -59.718154) (xy 69.642751 -59.725972) (xy 69.695254 -59.741461)
			(xy 69.745001 -59.764302) (xy 69.790968 -59.794025) (xy 69.8119 -59.811666) (xy 69.812154 -59.81192)
			(xy 69.819248 -59.817496) (xy 69.836159 -59.823748) (xy 69.845174 -59.824112) (xy 69.91223 -59.824112)
			(xy 69.921248 -59.823766) (xy 69.938165 -59.817511) (xy 69.94525 -59.81192) (xy 69.945758 -59.811412)
			(xy 69.966709 -59.793821) (xy 70.012673 -59.764159) (xy 70.062404 -59.74137) (xy 70.114882 -59.725921)
			(xy 70.169028 -59.71813) (xy 70.223733 -59.718156) (xy 70.277872 -59.725998) (xy 70.330334 -59.741497)
			(xy 70.380044 -59.764333) (xy 70.42598 -59.794039) (xy 70.4469 -59.811666) (xy 70.447154 -59.81192)
			(xy 70.454248 -59.817496) (xy 70.471159 -59.823748) (xy 70.480174 -59.824112) (xy 70.54723 -59.824112)
			(xy 70.556248 -59.823766) (xy 70.573165 -59.817511) (xy 70.58025 -59.81192) (xy 70.580758 -59.811412)
			(xy 70.60169 -59.793828) (xy 70.647625 -59.764188) (xy 70.697321 -59.74141) (xy 70.749761 -59.72596)
			(xy 70.803868 -59.718155) (xy 70.831202 -59.717686) (xy 70.858453 -59.718184) (xy 70.912399 -59.725941)
			(xy 70.964693 -59.741296) (xy 71.014269 -59.763936) (xy 71.060119 -59.793402) (xy 71.101308 -59.829093)
			(xy 71.136999 -59.870283) (xy 71.166464 -59.916132) (xy 71.189105 -59.965709) (xy 71.191755 -59.974734)
			(xy 83.086956 -59.974734) (xy 83.087407 -59.947908) (xy 83.094927 -59.894785) (xy 83.109808 -59.843238)
			(xy 83.131759 -59.794281) (xy 83.160346 -59.74888) (xy 83.195008 -59.707926) (xy 83.23506 -59.672228)
			(xy 83.257136 -59.65698) (xy 83.268701 -59.648762) (xy 83.287102 -59.627181) (xy 83.298854 -59.601369)
			(xy 83.303048 -59.573319) (xy 83.29936 -59.545199) (xy 83.288076 -59.51918) (xy 83.270066 -59.497271)
			(xy 83.25866 -59.488832) (xy 83.2372 -59.473485) (xy 83.198288 -59.437856) (xy 83.164656 -59.397206)
			(xy 83.136946 -59.352309) (xy 83.115686 -59.304023) (xy 83.101282 -59.253269) (xy 83.094008 -59.201013)
			(xy 83.09356 -59.174634) (xy 83.094046 -59.147383) (xy 83.101802 -59.093435) (xy 83.117157 -59.04114)
			(xy 83.139799 -58.991563) (xy 83.169265 -58.945713) (xy 83.204956 -58.904522) (xy 83.246147 -58.868831)
			(xy 83.291997 -58.839365) (xy 83.341574 -58.816723) (xy 83.393869 -58.801368) (xy 83.447817 -58.793612)
			(xy 83.502319 -58.793612) (xy 83.556267 -58.801368) (xy 83.608562 -58.816723) (xy 83.658139 -58.839365)
			(xy 83.703989 -58.868831) (xy 83.74518 -58.904522) (xy 83.780871 -58.945713) (xy 83.810337 -58.991563)
			(xy 83.832979 -59.04114) (xy 83.848334 -59.093435) (xy 83.85609 -59.147383) (xy 83.856576 -59.174634)
			(xy 83.856131 -59.201461) (xy 83.848614 -59.254585) (xy 83.833734 -59.306134) (xy 83.811783 -59.355091)
			(xy 83.783194 -59.400493) (xy 83.74853 -59.441446) (xy 83.708474 -59.477141) (xy 83.686396 -59.492388)
			(xy 83.674859 -59.500645) (xy 83.656453 -59.522215) (xy 83.644696 -59.548019) (xy 83.640497 -59.576063)
			(xy 83.64418 -59.604179) (xy 83.655461 -59.630194) (xy 83.673467 -59.6521) (xy 83.684872 -59.660536)
			(xy 83.706371 -59.675831) (xy 83.745281 -59.71147) (xy 83.778908 -59.752129) (xy 83.806613 -59.797035)
			(xy 83.827866 -59.845329) (xy 83.842263 -59.896091) (xy 83.849528 -59.948352) (xy 83.849972 -59.974734)
			(xy 83.849486 -60.001985) (xy 83.84173 -60.055933) (xy 83.826375 -60.108228) (xy 83.818053 -60.126449)
			(xy 95.180172 -60.126449) (xy 95.180172 -60.071951) (xy 95.187927 -60.018006) (xy 95.20328 -59.965715)
			(xy 95.225918 -59.91614) (xy 95.25538 -59.870291) (xy 95.291066 -59.829102) (xy 95.332251 -59.79341)
			(xy 95.378096 -59.763942) (xy 95.427668 -59.741297) (xy 95.479957 -59.725938) (xy 95.533901 -59.718175)
			(xy 95.56115 -59.717686) (xy 95.588519 -59.718185) (xy 95.642697 -59.725995) (xy 95.695199 -59.741477)
			(xy 95.744947 -59.764311) (xy 95.790915 -59.794028) (xy 95.811848 -59.811666) (xy 95.812102 -59.81192)
			(xy 95.819182 -59.817516) (xy 95.836104 -59.823756) (xy 95.845122 -59.824112) (xy 95.912178 -59.824112)
			(xy 95.921193 -59.823742) (xy 95.93811 -59.817503) (xy 95.945198 -59.81192) (xy 95.945706 -59.811412)
			(xy 95.966619 -59.793774) (xy 96.01259 -59.764114) (xy 96.062327 -59.741328) (xy 96.114811 -59.725883)
			(xy 96.168962 -59.718096) (xy 96.223671 -59.718127) (xy 96.277814 -59.725975) (xy 96.330279 -59.74148)
			(xy 96.379991 -59.764323) (xy 96.425928 -59.794035) (xy 96.446848 -59.811666) (xy 96.447102 -59.81192)
			(xy 96.454182 -59.817516) (xy 96.471104 -59.823756) (xy 96.480122 -59.824112) (xy 96.547178 -59.824112)
			(xy 96.556193 -59.823742) (xy 96.57311 -59.817503) (xy 96.580198 -59.81192) (xy 96.580706 -59.811412)
			(xy 96.60162 -59.793805) (xy 96.64756 -59.764169) (xy 96.697261 -59.741395) (xy 96.749704 -59.72595)
			(xy 96.803815 -59.718152) (xy 96.83115 -59.717686) (xy 96.858405 -59.718158) (xy 96.91236 -59.725909)
			(xy 96.964663 -59.74126) (xy 97.014249 -59.7639) (xy 97.060108 -59.793366) (xy 97.101306 -59.829059)
			(xy 97.137004 -59.870252) (xy 97.166476 -59.916107) (xy 97.189122 -59.96569) (xy 97.191778 -59.974734)
			(xy 121.18721 -59.974734) (xy 121.187637 -59.947907) (xy 121.195158 -59.894782) (xy 121.210042 -59.843233)
			(xy 121.231996 -59.794276) (xy 121.260587 -59.748874) (xy 121.295254 -59.707922) (xy 121.335312 -59.672227)
			(xy 121.35739 -59.65698) (xy 121.368959 -59.648764) (xy 121.387369 -59.627185) (xy 121.399126 -59.601372)
			(xy 121.403321 -59.573319) (xy 121.399632 -59.545196) (xy 121.388342 -59.519175) (xy 121.370324 -59.497268)
			(xy 121.358914 -59.488832) (xy 121.337466 -59.473468) (xy 121.298551 -59.437844) (xy 121.264917 -59.397197)
			(xy 121.237204 -59.352304) (xy 121.215943 -59.30402) (xy 121.201537 -59.253267) (xy 121.194262 -59.201013)
			(xy 121.193814 -59.174634) (xy 121.1943 -59.147383) (xy 121.202056 -59.093435) (xy 121.217411 -59.04114)
			(xy 121.240053 -58.991563) (xy 121.269519 -58.945713) (xy 121.30521 -58.904522) (xy 121.346401 -58.868831)
			(xy 121.392251 -58.839365) (xy 121.441828 -58.816723) (xy 121.494123 -58.801368) (xy 121.548071 -58.793612)
			(xy 121.602573 -58.793612) (xy 121.656521 -58.801368) (xy 121.708816 -58.816723) (xy 121.758393 -58.839365)
			(xy 121.804243 -58.868831) (xy 121.845434 -58.904522) (xy 121.881125 -58.945713) (xy 121.910591 -58.991563)
			(xy 121.933233 -59.04114) (xy 121.948588 -59.093435) (xy 121.956344 -59.147383) (xy 121.95683 -59.174634)
			(xy 121.956361 -59.20146) (xy 121.948845 -59.254582) (xy 121.933967 -59.306129) (xy 121.91202 -59.355085)
			(xy 121.883435 -59.400488) (xy 121.848776 -59.441441) (xy 121.808725 -59.477139) (xy 121.78665 -59.492388)
			(xy 121.775117 -59.500647) (xy 121.756719 -59.52222) (xy 121.744968 -59.548023) (xy 121.740771 -59.576063)
			(xy 121.744452 -59.604175) (xy 121.755727 -59.63019) (xy 121.773726 -59.652097) (xy 121.785126 -59.660536)
			(xy 121.806615 -59.675845) (xy 121.845527 -59.71148) (xy 121.879157 -59.752136) (xy 121.906863 -59.797039)
			(xy 121.928119 -59.845332) (xy 121.942516 -59.896092) (xy 121.949782 -59.948352) (xy 121.950226 -59.974734)
			(xy 121.94974 -60.001985) (xy 121.941984 -60.055933) (xy 121.926629 -60.108228) (xy 121.918306 -60.126453)
			(xy 133.280349 -60.126453) (xy 133.280349 -60.071947) (xy 133.288107 -60.017994) (xy 133.303463 -59.965695)
			(xy 133.326106 -59.916114) (xy 133.355575 -59.87026) (xy 133.39127 -59.829067) (xy 133.432463 -59.793373)
			(xy 133.478318 -59.763904) (xy 133.527899 -59.741262) (xy 133.580198 -59.725906) (xy 133.634151 -59.718149)
			(xy 133.661404 -59.717686) (xy 133.688774 -59.718153) (xy 133.742953 -59.725971) (xy 133.795456 -59.74146)
			(xy 133.845203 -59.764302) (xy 133.89117 -59.794025) (xy 133.912102 -59.811666) (xy 133.912356 -59.81192)
			(xy 133.919449 -59.817497) (xy 133.936361 -59.823749) (xy 133.945376 -59.824112) (xy 134.012432 -59.824112)
			(xy 134.02145 -59.823768) (xy 134.038367 -59.817511) (xy 134.045452 -59.81192) (xy 134.04596 -59.811412)
			(xy 134.066909 -59.793819) (xy 134.112874 -59.764157) (xy 134.162605 -59.741368) (xy 134.215083 -59.725919)
			(xy 134.26923 -59.718128) (xy 134.323934 -59.718154) (xy 134.378073 -59.725997) (xy 134.430536 -59.741496)
			(xy 134.480246 -59.764333) (xy 134.526182 -59.794038) (xy 134.547102 -59.811666) (xy 134.547356 -59.81192)
			(xy 134.554449 -59.817497) (xy 134.571361 -59.823749) (xy 134.580376 -59.824112) (xy 134.647432 -59.824112)
			(xy 134.65645 -59.823768) (xy 134.673367 -59.817511) (xy 134.680452 -59.81192) (xy 134.68096 -59.811412)
			(xy 134.701892 -59.793827) (xy 134.747827 -59.764187) (xy 134.797523 -59.741409) (xy 134.849962 -59.725959)
			(xy 134.90407 -59.718155) (xy 134.931404 -59.717686) (xy 134.958655 -59.718184) (xy 135.012601 -59.725941)
			(xy 135.064895 -59.741296) (xy 135.11447 -59.763937) (xy 135.16032 -59.793403) (xy 135.201509 -59.829094)
			(xy 135.237199 -59.870284) (xy 135.266665 -59.916133) (xy 135.289305 -59.965709) (xy 135.291955 -59.974734)
			(xy 147.187158 -59.974734) (xy 147.187608 -59.947908) (xy 147.195128 -59.894785) (xy 147.210009 -59.843238)
			(xy 147.23196 -59.794281) (xy 147.260548 -59.748879) (xy 147.295209 -59.707926) (xy 147.335262 -59.672228)
			(xy 147.357338 -59.65698) (xy 147.368903 -59.648762) (xy 147.387304 -59.62718) (xy 147.399055 -59.601369)
			(xy 147.403249 -59.573319) (xy 147.399561 -59.545199) (xy 147.388277 -59.51918) (xy 147.370268 -59.497271)
			(xy 147.358862 -59.488832) (xy 147.337402 -59.473484) (xy 147.29849 -59.437855) (xy 147.264859 -59.397205)
			(xy 147.237148 -59.352309) (xy 147.215888 -59.304023) (xy 147.201484 -59.253269) (xy 147.19421 -59.201013)
			(xy 147.193762 -59.174634) (xy 147.194248 -59.147383) (xy 147.202004 -59.093435) (xy 147.217359 -59.04114)
			(xy 147.240001 -58.991563) (xy 147.269467 -58.945713) (xy 147.305158 -58.904522) (xy 147.346349 -58.868831)
			(xy 147.392199 -58.839365) (xy 147.441776 -58.816723) (xy 147.494071 -58.801368) (xy 147.548019 -58.793612)
			(xy 147.602521 -58.793612) (xy 147.656469 -58.801368) (xy 147.708764 -58.816723) (xy 147.758341 -58.839365)
			(xy 147.804191 -58.868831) (xy 147.845382 -58.904522) (xy 147.881073 -58.945713) (xy 147.910539 -58.991563)
			(xy 147.933181 -59.04114) (xy 147.948536 -59.093435) (xy 147.956292 -59.147383) (xy 147.956778 -59.174634)
			(xy 147.956332 -59.201461) (xy 147.948815 -59.254585) (xy 147.933935 -59.306133) (xy 147.911984 -59.355091)
			(xy 147.883395 -59.400493) (xy 147.848731 -59.441445) (xy 147.808675 -59.477141) (xy 147.786598 -59.492388)
			(xy 147.775061 -59.500644) (xy 147.756654 -59.522215) (xy 147.744897 -59.548019) (xy 147.740698 -59.576063)
			(xy 147.744381 -59.604179) (xy 147.755662 -59.630195) (xy 147.773669 -59.6521) (xy 147.785074 -59.660536)
			(xy 147.806574 -59.67583) (xy 147.845483 -59.711469) (xy 147.87911 -59.752129) (xy 147.906815 -59.797034)
			(xy 147.928069 -59.845329) (xy 147.942465 -59.896091) (xy 147.94973 -59.948352) (xy 147.950174 -59.974734)
			(xy 147.949688 -60.001985) (xy 147.941932 -60.055933) (xy 147.926577 -60.108228) (xy 147.918255 -60.126449)
			(xy 159.280372 -60.126449) (xy 159.280372 -60.071951) (xy 159.288127 -60.018006) (xy 159.30348 -59.965714)
			(xy 159.326118 -59.91614) (xy 159.35558 -59.870291) (xy 159.391267 -59.829101) (xy 159.432452 -59.793409)
			(xy 159.478297 -59.763941) (xy 159.527869 -59.741297) (xy 159.580159 -59.725937) (xy 159.634103 -59.718175)
			(xy 159.661352 -59.717686) (xy 159.688721 -59.718184) (xy 159.742899 -59.725994) (xy 159.795401 -59.741476)
			(xy 159.845149 -59.764311) (xy 159.891117 -59.794028) (xy 159.91205 -59.811666) (xy 159.912304 -59.81192)
			(xy 159.919384 -59.817517) (xy 159.936306 -59.823757) (xy 159.945324 -59.824112) (xy 160.01238 -59.824112)
			(xy 160.021396 -59.823743) (xy 160.038313 -59.817503) (xy 160.0454 -59.81192) (xy 160.045908 -59.811412)
			(xy 160.066819 -59.793772) (xy 160.11279 -59.764112) (xy 160.162528 -59.741326) (xy 160.215012 -59.725881)
			(xy 160.269164 -59.718094) (xy 160.323873 -59.718125) (xy 160.378016 -59.725974) (xy 160.430481 -59.741479)
			(xy 160.480193 -59.764323) (xy 160.52613 -59.794035) (xy 160.54705 -59.811666) (xy 160.547304 -59.81192)
			(xy 160.554384 -59.817517) (xy 160.571306 -59.823757) (xy 160.580324 -59.824112) (xy 160.64738 -59.824112)
			(xy 160.656396 -59.823743) (xy 160.673313 -59.817503) (xy 160.6804 -59.81192) (xy 160.680908 -59.811412)
			(xy 160.701821 -59.793804) (xy 160.747762 -59.764168) (xy 160.797463 -59.741394) (xy 160.849906 -59.72595)
			(xy 160.904017 -59.718152) (xy 160.931352 -59.717686) (xy 160.958607 -59.718158) (xy 161.012562 -59.725909)
			(xy 161.064865 -59.741261) (xy 161.11445 -59.7639) (xy 161.160309 -59.793367) (xy 161.201506 -59.82906)
			(xy 161.237205 -59.870253) (xy 161.266677 -59.916108) (xy 161.289322 -59.96569) (xy 161.291978 -59.974734)
			(xy 173.187106 -59.974734) (xy 173.187535 -59.947907) (xy 173.195056 -59.894782) (xy 173.209939 -59.843234)
			(xy 173.231893 -59.794276) (xy 173.260484 -59.748874) (xy 173.29515 -59.707922) (xy 173.335208 -59.672227)
			(xy 173.357286 -59.65698) (xy 173.368855 -59.648764) (xy 173.387266 -59.627186) (xy 173.399023 -59.601372)
			(xy 173.403219 -59.573319) (xy 173.399529 -59.545195) (xy 173.388239 -59.519174) (xy 173.370221 -59.497267)
			(xy 173.35881 -59.488832) (xy 173.337361 -59.473469) (xy 173.298446 -59.437845) (xy 173.264812 -59.397198)
			(xy 173.2371 -59.352304) (xy 173.215838 -59.30402) (xy 173.201433 -59.253267) (xy 173.194158 -59.201013)
			(xy 173.19371 -59.174634) (xy 173.194196 -59.147383) (xy 173.201952 -59.093435) (xy 173.217307 -59.04114)
			(xy 173.239949 -58.991563) (xy 173.269415 -58.945713) (xy 173.305106 -58.904522) (xy 173.346297 -58.868831)
			(xy 173.392147 -58.839365) (xy 173.441724 -58.816723) (xy 173.494019 -58.801368) (xy 173.547967 -58.793612)
			(xy 173.602469 -58.793612) (xy 173.656417 -58.801368) (xy 173.708712 -58.816723) (xy 173.758289 -58.839365)
			(xy 173.804139 -58.868831) (xy 173.84533 -58.904522) (xy 173.881021 -58.945713) (xy 173.910487 -58.991563)
			(xy 173.933129 -59.04114) (xy 173.948484 -59.093435) (xy 173.95624 -59.147383) (xy 173.956726 -59.174634)
			(xy 173.956259 -59.20146) (xy 173.948743 -59.254582) (xy 173.933865 -59.306129) (xy 173.911917 -59.355086)
			(xy 173.883332 -59.400488) (xy 173.848672 -59.441441) (xy 173.808621 -59.47714) (xy 173.786546 -59.492388)
			(xy 173.775013 -59.500647) (xy 173.756616 -59.52222) (xy 173.744865 -59.548023) (xy 173.740669 -59.576063)
			(xy 173.74435 -59.604175) (xy 173.755624 -59.630189) (xy 173.773622 -59.652097) (xy 173.785022 -59.660536)
			(xy 173.80651 -59.675846) (xy 173.845422 -59.711481) (xy 173.879052 -59.752137) (xy 173.906759 -59.79704)
			(xy 173.928014 -59.845332) (xy 173.942412 -59.896092) (xy 173.949678 -59.948353) (xy 173.950122 -59.974734)
			(xy 173.949636 -60.001985) (xy 173.94188 -60.055933) (xy 173.926525 -60.108228) (xy 173.918202 -60.126452)
			(xy 185.280272 -60.126452) (xy 185.280272 -60.071948) (xy 185.288028 -60.018) (xy 185.303384 -59.965704)
			(xy 185.326025 -59.916126) (xy 185.355492 -59.870275) (xy 185.391184 -59.829084) (xy 185.432375 -59.793392)
			(xy 185.478226 -59.763925) (xy 185.527804 -59.741284) (xy 185.5801 -59.725928) (xy 185.634048 -59.718172)
			(xy 185.6613 -59.717686) (xy 185.68867 -59.718155) (xy 185.742849 -59.725973) (xy 185.795352 -59.741461)
			(xy 185.845099 -59.764302) (xy 185.891066 -59.794026) (xy 185.911998 -59.811666) (xy 185.912252 -59.81192)
			(xy 185.919347 -59.817495) (xy 185.936257 -59.823748) (xy 185.945272 -59.824112) (xy 186.012328 -59.824112)
			(xy 186.021346 -59.823766) (xy 186.038263 -59.81751) (xy 186.045348 -59.81192) (xy 186.045856 -59.811412)
			(xy 186.066808 -59.793823) (xy 186.112772 -59.764161) (xy 186.162503 -59.741372) (xy 186.214981 -59.725923)
			(xy 186.269127 -59.718131) (xy 186.323831 -59.718157) (xy 186.37797 -59.725999) (xy 186.430433 -59.741498)
			(xy 186.480142 -59.764334) (xy 186.526078 -59.794039) (xy 186.546998 -59.811666) (xy 186.547252 -59.81192)
			(xy 186.554347 -59.817495) (xy 186.571257 -59.823748) (xy 186.580272 -59.824112) (xy 186.647328 -59.824112)
			(xy 186.656346 -59.823766) (xy 186.673263 -59.81751) (xy 186.680348 -59.81192) (xy 186.680856 -59.811412)
			(xy 186.701789 -59.793829) (xy 186.747724 -59.764188) (xy 186.79742 -59.74141) (xy 186.849859 -59.72596)
			(xy 186.903966 -59.718155) (xy 186.9313 -59.717686) (xy 186.958551 -59.718184) (xy 187.012498 -59.72594)
			(xy 187.064792 -59.741295) (xy 187.114368 -59.763936) (xy 187.160218 -59.793402) (xy 187.201407 -59.829093)
			(xy 187.237098 -59.870282) (xy 187.266564 -59.916132) (xy 187.289205 -59.965708) (xy 187.291855 -59.974734)
			(xy 199.187054 -59.974734) (xy 199.187462 -59.947906) (xy 199.194983 -59.894779) (xy 199.209869 -59.843229)
			(xy 199.231826 -59.794271) (xy 199.260421 -59.748869) (xy 199.295091 -59.707918) (xy 199.335154 -59.672225)
			(xy 199.357234 -59.65698) (xy 199.368799 -59.648762) (xy 199.387201 -59.627181) (xy 199.398953 -59.601369)
			(xy 199.403146 -59.573319) (xy 199.399459 -59.545199) (xy 199.388174 -59.519179) (xy 199.370164 -59.49727)
			(xy 199.358758 -59.488832) (xy 199.337297 -59.473485) (xy 199.298386 -59.437856) (xy 199.264754 -59.397206)
			(xy 199.237044 -59.35231) (xy 199.215784 -59.304024) (xy 199.20138 -59.253269) (xy 199.194106 -59.201014)
			(xy 199.193658 -59.174634) (xy 199.194144 -59.147383) (xy 199.2019 -59.093435) (xy 199.217255 -59.04114)
			(xy 199.239897 -58.991563) (xy 199.269363 -58.945713) (xy 199.305054 -58.904522) (xy 199.346245 -58.868831)
			(xy 199.392095 -58.839365) (xy 199.441672 -58.816723) (xy 199.493967 -58.801368) (xy 199.547915 -58.793612)
			(xy 199.602417 -58.793612) (xy 199.656365 -58.801368) (xy 199.70866 -58.816723) (xy 199.758237 -58.839365)
			(xy 199.804087 -58.868831) (xy 199.845278 -58.904522) (xy 199.880969 -58.945713) (xy 199.910435 -58.991563)
			(xy 199.933077 -59.04114) (xy 199.948432 -59.093435) (xy 199.956188 -59.147383) (xy 199.956674 -59.174634)
			(xy 199.95623 -59.201461) (xy 199.948713 -59.254585) (xy 199.933833 -59.306134) (xy 199.911882 -59.355091)
			(xy 199.883292 -59.400494) (xy 199.848628 -59.441446) (xy 199.808572 -59.477141) (xy 199.786494 -59.492388)
			(xy 199.774957 -59.500645) (xy 199.756551 -59.522215) (xy 199.744795 -59.548019) (xy 199.740596 -59.576063)
			(xy 199.744279 -59.604179) (xy 199.755559 -59.630194) (xy 199.773566 -59.6521) (xy 199.78497 -59.660536)
			(xy 199.806469 -59.675832) (xy 199.845378 -59.71147) (xy 199.879006 -59.75213) (xy 199.906711 -59.797035)
			(xy 199.927964 -59.845329) (xy 199.942361 -59.896091) (xy 199.949626 -59.948352) (xy 199.95007 -59.974734)
			(xy 199.949584 -60.001985) (xy 199.941828 -60.055933) (xy 199.926473 -60.108228) (xy 199.918149 -60.126455)
			(xy 211.28015 -60.126455) (xy 211.28015 -60.071945) (xy 211.287908 -60.017989) (xy 211.303267 -59.965686)
			(xy 211.325913 -59.916102) (xy 211.355386 -59.870246) (xy 211.391085 -59.829051) (xy 211.432284 -59.793357)
			(xy 211.478144 -59.76389) (xy 211.527731 -59.74125) (xy 211.580036 -59.725898) (xy 211.633992 -59.718146)
			(xy 211.661248 -59.717686) (xy 211.688617 -59.718186) (xy 211.742794 -59.725996) (xy 211.795297 -59.741477)
			(xy 211.845044 -59.764312) (xy 211.891013 -59.794028) (xy 211.911946 -59.811666) (xy 211.9122 -59.81192)
			(xy 211.919281 -59.817515) (xy 211.936202 -59.823756) (xy 211.94522 -59.824112) (xy 212.012276 -59.824112)
			(xy 212.021291 -59.823741) (xy 212.038208 -59.817503) (xy 212.045296 -59.81192) (xy 212.045804 -59.811412)
			(xy 212.066718 -59.793776) (xy 212.112689 -59.764116) (xy 212.162426 -59.741329) (xy 212.214909 -59.725884)
			(xy 212.269061 -59.718097) (xy 212.323769 -59.718128) (xy 212.377912 -59.725976) (xy 212.430378 -59.741481)
			(xy 212.480089 -59.764323) (xy 212.526026 -59.794035) (xy 212.546946 -59.811666) (xy 212.5472 -59.81192)
			(xy 212.554281 -59.817515) (xy 212.571202 -59.823756) (xy 212.58022 -59.824112) (xy 212.647276 -59.824112)
			(xy 212.656291 -59.823741) (xy 212.673208 -59.817503) (xy 212.680296 -59.81192) (xy 212.680804 -59.811412)
			(xy 212.701719 -59.793806) (xy 212.747659 -59.764169) (xy 212.797359 -59.741395) (xy 212.849802 -59.725951)
			(xy 212.903913 -59.718152) (xy 212.931248 -59.717686) (xy 212.958497 -59.718187) (xy 213.012438 -59.725949)
			(xy 213.064726 -59.741308) (xy 213.114297 -59.763952) (xy 213.160141 -59.793419) (xy 213.201324 -59.82911)
			(xy 213.23701 -59.870298) (xy 213.266471 -59.916145) (xy 213.289109 -59.965719) (xy 213.304461 -60.018009)
			(xy 213.312216 -60.071951) (xy 213.312216 -60.126449) (xy 213.311424 -60.13196) (xy 226.436428 -60.13196)
			(xy 226.436428 -59.26836) (xy 226.436885 -59.237214) (xy 226.445338 -59.175497) (xy 226.462083 -59.115497)
			(xy 226.48681 -59.058322) (xy 226.519062 -59.005029) (xy 226.558243 -58.956601) (xy 226.60363 -58.913935)
			(xy 226.654384 -58.877818) (xy 226.709567 -58.848917) (xy 226.768159 -58.827767) (xy 226.829079 -58.814759)
			(xy 226.8601 -58.811922) (xy 226.860354 -58.811922) (xy 226.870024 -58.810704) (xy 226.887441 -58.801992)
			(xy 226.900356 -58.787417) (xy 226.904042 -58.778394) (xy 226.935284 -58.69051) (xy 226.938064 -58.681115)
			(xy 226.937191 -58.661563) (xy 226.929101 -58.643741) (xy 226.92233 -58.636662) (xy 226.922076 -58.636408)
			(xy 226.895066 -58.610303) (xy 226.845912 -58.553499) (xy 226.80279 -58.491989) (xy 226.766148 -58.426412)
			(xy 226.736366 -58.357448) (xy 226.713754 -58.285813) (xy 226.698546 -58.212249) (xy 226.690899 -58.13752)
			(xy 226.690428 -58.09996) (xy 226.690933 -58.061356) (xy 226.699003 -57.984572) (xy 226.715056 -57.909051)
			(xy 226.738914 -57.835623) (xy 226.770317 -57.76509) (xy 226.808921 -57.698227) (xy 226.854302 -57.635764)
			(xy 226.905964 -57.578388) (xy 226.96334 -57.526726) (xy 227.025803 -57.481345) (xy 227.092666 -57.442741)
			(xy 227.163199 -57.411338) (xy 227.236627 -57.38748) (xy 227.312148 -57.371427) (xy 227.388932 -57.363357)
			(xy 227.46614 -57.363357) (xy 227.542924 -57.371427) (xy 227.618445 -57.38748) (xy 227.691873 -57.411338)
			(xy 227.762406 -57.442741) (xy 227.829269 -57.481345) (xy 227.891732 -57.526726) (xy 227.949108 -57.578388)
			(xy 228.00077 -57.635764) (xy 228.046151 -57.698227) (xy 228.084755 -57.76509) (xy 228.116158 -57.835623)
			(xy 228.140016 -57.909051) (xy 228.156069 -57.984572) (xy 228.164139 -58.061356) (xy 228.164644 -58.09996)
			(xy 228.164257 -58.132872) (xy 228.158346 -58.198432) (xy 228.14661 -58.263203) (xy 228.138228 -58.295032)
			(xy 228.138228 -58.295286) (xy 228.137974 -58.296048) (xy 228.135433 -58.308344) (xy 228.141305 -58.332726)
			(xy 228.14915 -58.34253) (xy 228.205792 -58.406284) (xy 228.214625 -58.415247) (xy 228.238216 -58.423911)
			(xy 228.25075 -58.422794) (xy 228.251004 -58.422794) (xy 228.251512 -58.422794) (xy 228.265587 -58.420786)
			(xy 228.293938 -58.418623) (xy 228.308154 -58.418476) (xy 228.335405 -58.418998) (xy 228.389353 -58.426748)
			(xy 228.441649 -58.442098) (xy 228.491228 -58.464734) (xy 228.53708 -58.494195) (xy 228.578273 -58.529883)
			(xy 228.613967 -58.57107) (xy 228.643437 -58.616918) (xy 228.666081 -58.666493) (xy 228.675469 -58.69846)
			(xy 229.808777 -58.69846) (xy 229.808777 -58.601788) (xy 229.81676 -58.505445) (xy 229.832672 -58.410091)
			(xy 229.856404 -58.316377) (xy 229.887793 -58.224943) (xy 229.926626 -58.136412) (xy 229.972637 -58.051392)
			(xy 230.025512 -57.970461) (xy 230.08489 -57.894172) (xy 230.150364 -57.823048) (xy 230.221488 -57.757574)
			(xy 230.297777 -57.698196) (xy 230.378708 -57.645321) (xy 230.463728 -57.59931) (xy 230.552259 -57.560477)
			(xy 230.643693 -57.529088) (xy 230.737407 -57.505356) (xy 230.832761 -57.489444) (xy 230.929104 -57.481461)
			(xy 231.025776 -57.481461) (xy 231.122119 -57.489444) (xy 231.217473 -57.505356) (xy 231.311187 -57.529088)
			(xy 231.402621 -57.560477) (xy 231.491152 -57.59931) (xy 231.563923 -57.638692) (xy 233.790741 -57.638692)
			(xy 233.790741 -57.561484) (xy 233.798811 -57.4847) (xy 233.814864 -57.409179) (xy 233.838722 -57.335751)
			(xy 233.870125 -57.265218) (xy 233.908729 -57.198355) (xy 233.95411 -57.135892) (xy 234.005772 -57.078516)
			(xy 234.063148 -57.026854) (xy 234.125611 -56.981473) (xy 234.192474 -56.942869) (xy 234.263007 -56.911466)
			(xy 234.336435 -56.887608) (xy 234.411956 -56.871555) (xy 234.48874 -56.863485) (xy 234.565948 -56.863485)
			(xy 234.642732 -56.871555) (xy 234.718253 -56.887608) (xy 234.791681 -56.911466) (xy 234.862214 -56.942869)
			(xy 234.929077 -56.981473) (xy 234.99154 -57.026854) (xy 235.048916 -57.078516) (xy 235.100578 -57.135892)
			(xy 235.145959 -57.198355) (xy 235.184563 -57.265218) (xy 235.215966 -57.335751) (xy 235.239824 -57.409179)
			(xy 235.255877 -57.4847) (xy 235.263947 -57.561484) (xy 235.264452 -57.600088) (xy 235.263947 -57.638692)
			(xy 235.255877 -57.715476) (xy 235.239824 -57.790997) (xy 235.215966 -57.864425) (xy 235.184563 -57.934958)
			(xy 235.145959 -58.001821) (xy 235.100578 -58.064284) (xy 235.048916 -58.12166) (xy 234.99154 -58.173322)
			(xy 234.929077 -58.218703) (xy 234.862214 -58.257307) (xy 234.791681 -58.28871) (xy 234.718253 -58.312568)
			(xy 234.642732 -58.328621) (xy 234.565948 -58.336691) (xy 234.48874 -58.336691) (xy 234.411956 -58.328621)
			(xy 234.336435 -58.312568) (xy 234.263007 -58.28871) (xy 234.192474 -58.257307) (xy 234.125611 -58.218703)
			(xy 234.063148 -58.173322) (xy 234.005772 -58.12166) (xy 233.95411 -58.064284) (xy 233.908729 -58.001821)
			(xy 233.870125 -57.934958) (xy 233.838722 -57.864425) (xy 233.814864 -57.790997) (xy 233.798811 -57.715476)
			(xy 233.790741 -57.638692) (xy 231.563923 -57.638692) (xy 231.576172 -57.645321) (xy 231.657103 -57.698196)
			(xy 231.733392 -57.757574) (xy 231.804516 -57.823048) (xy 231.86999 -57.894172) (xy 231.929368 -57.970461)
			(xy 231.982243 -58.051392) (xy 232.028254 -58.136412) (xy 232.067087 -58.224943) (xy 232.098476 -58.316377)
			(xy 232.122208 -58.410091) (xy 232.13812 -58.505445) (xy 232.146103 -58.601788) (xy 232.146602 -58.650124)
			(xy 232.146103 -58.69846) (xy 232.13812 -58.794803) (xy 232.122208 -58.890157) (xy 232.098476 -58.983871)
			(xy 232.067087 -59.075305) (xy 232.028254 -59.163836) (xy 231.982243 -59.248856) (xy 231.929368 -59.329787)
			(xy 231.874772 -59.399932) (xy 233.19105 -59.399932) (xy 233.19105 -59.399678) (xy 233.191567 -59.372332)
			(xy 233.19939 -59.318203) (xy 233.214858 -59.265744) (xy 233.237655 -59.216031) (xy 233.267314 -59.170079)
			(xy 233.303228 -59.128831) (xy 233.323638 -59.110626) (xy 233.33202 -59.103514) (xy 233.341164 -59.083702)
			(xy 233.34218 -58.985404) (xy 233.333544 -58.965338) (xy 233.325162 -58.957972) (xy 233.305584 -58.939806)
			(xy 233.271191 -58.898946) (xy 233.242834 -58.853689) (xy 233.221066 -58.804919) (xy 233.206313 -58.753589)
			(xy 233.198864 -58.700704) (xy 233.198416 -58.674) (xy 233.198902 -58.646749) (xy 233.206658 -58.592801)
			(xy 233.222013 -58.540506) (xy 233.244655 -58.490929) (xy 233.274121 -58.445079) (xy 233.309812 -58.403888)
			(xy 233.351003 -58.368197) (xy 233.396853 -58.338731) (xy 233.44643 -58.316089) (xy 233.498725 -58.300734)
			(xy 233.552673 -58.292978) (xy 233.607175 -58.292978) (xy 233.661123 -58.300734) (xy 233.713418 -58.316089)
			(xy 233.762995 -58.338731) (xy 233.808845 -58.368197) (xy 233.850036 -58.403888) (xy 233.885727 -58.445079)
			(xy 233.915193 -58.490929) (xy 233.937835 -58.540506) (xy 233.95319 -58.592801) (xy 233.960883 -58.646314)
			(xy 237.901732 -58.646314) (xy 237.905803 -58.590692) (xy 237.917929 -58.536255) (xy 237.937852 -58.484164)
			(xy 237.965148 -58.435529) (xy 237.999234 -58.391386) (xy 238.039383 -58.352677) (xy 238.084741 -58.320226)
			(xy 238.134341 -58.294725) (xy 238.187125 -58.276718) (xy 238.241968 -58.266588) (xy 238.297702 -58.264551)
			(xy 238.353139 -58.270651) (xy 238.407096 -58.284757) (xy 238.407367 -58.284872) (xy 240.598196 -58.284872)
			(xy 240.602267 -58.22925) (xy 240.614393 -58.174813) (xy 240.634316 -58.122722) (xy 240.661612 -58.074087)
			(xy 240.695698 -58.029944) (xy 240.735847 -57.991235) (xy 240.781205 -57.958784) (xy 240.830805 -57.933283)
			(xy 240.883589 -57.915276) (xy 240.938432 -57.905146) (xy 240.994166 -57.903109) (xy 241.049603 -57.909209)
			(xy 241.10356 -57.923315) (xy 241.154889 -57.945127) (xy 241.202495 -57.974181) (xy 241.245363 -58.009856)
			(xy 241.28258 -58.051393) (xy 241.313353 -58.097906) (xy 241.337025 -58.148403) (xy 241.353093 -58.20181)
			(xy 241.361213 -58.256986) (xy 241.361722 -58.284872) (xy 241.361213 -58.312758) (xy 241.353093 -58.367934)
			(xy 241.337025 -58.421341) (xy 241.313353 -58.471838) (xy 241.28258 -58.518351) (xy 241.245363 -58.559888)
			(xy 241.202495 -58.595563) (xy 241.154889 -58.624617) (xy 241.10356 -58.646429) (xy 241.049603 -58.660535)
			(xy 240.994166 -58.666635) (xy 240.938432 -58.664598) (xy 240.883589 -58.654468) (xy 240.830805 -58.636461)
			(xy 240.781205 -58.61096) (xy 240.735847 -58.578509) (xy 240.695698 -58.5398) (xy 240.661612 -58.495657)
			(xy 240.634316 -58.447022) (xy 240.614393 -58.394931) (xy 240.602267 -58.340494) (xy 240.598196 -58.284872)
			(xy 238.407367 -58.284872) (xy 238.458425 -58.306569) (xy 238.506031 -58.335623) (xy 238.548899 -58.371298)
			(xy 238.586116 -58.412835) (xy 238.616889 -58.459348) (xy 238.640561 -58.509845) (xy 238.656629 -58.563252)
			(xy 238.664749 -58.618428) (xy 238.665258 -58.646314) (xy 238.664749 -58.6742) (xy 238.656629 -58.729376)
			(xy 238.656019 -58.731404) (xy 245.720616 -58.731404) (xy 245.721116 -58.704071) (xy 245.728916 -58.649965)
			(xy 245.744359 -58.597527) (xy 245.767127 -58.547828) (xy 245.796755 -58.501888) (xy 245.814342 -58.48096)
			(xy 245.814596 -58.480706) (xy 245.81485 -58.480452) (xy 245.820427 -58.473359) (xy 245.826678 -58.456447)
			(xy 245.827042 -58.447432) (xy 245.827042 -58.380376) (xy 245.826709 -58.371356) (xy 245.820446 -58.354439)
			(xy 245.81485 -58.347356) (xy 245.814596 -58.347102) (xy 245.814342 -58.346848) (xy 245.796747 -58.325922)
			(xy 245.767096 -58.279989) (xy 245.744308 -58.230292) (xy 245.728852 -58.177851) (xy 245.721044 -58.123739)
			(xy 245.721043 -58.069067) (xy 245.728851 -58.014955) (xy 245.744306 -57.962513) (xy 245.767093 -57.912816)
			(xy 245.796743 -57.866883) (xy 245.814342 -57.84596) (xy 245.814596 -57.845706) (xy 245.81485 -57.845452)
			(xy 245.820427 -57.838359) (xy 245.826678 -57.821447) (xy 245.827042 -57.812432) (xy 245.827042 -57.745376)
			(xy 245.826709 -57.736356) (xy 245.820446 -57.719439) (xy 245.81485 -57.712356) (xy 245.814596 -57.712102)
			(xy 245.814342 -57.711848) (xy 245.796747 -57.690922) (xy 245.767096 -57.644989) (xy 245.744308 -57.595292)
			(xy 245.728852 -57.542851) (xy 245.721044 -57.488739) (xy 245.721043 -57.434067) (xy 245.728851 -57.379955)
			(xy 245.744306 -57.327513) (xy 245.767093 -57.277816) (xy 245.796743 -57.231883) (xy 245.814342 -57.21096)
			(xy 245.814596 -57.210706) (xy 245.81485 -57.210452) (xy 245.820427 -57.203359) (xy 245.826678 -57.186447)
			(xy 245.827042 -57.177432) (xy 245.827042 -57.110376) (xy 245.826709 -57.101356) (xy 245.820446 -57.084439)
			(xy 245.81485 -57.077356) (xy 245.814596 -57.077102) (xy 245.814342 -57.076848) (xy 245.796765 -57.05591)
			(xy 245.767123 -57.009977) (xy 245.744343 -56.960282) (xy 245.728892 -56.907844) (xy 245.721086 -56.853737)
			(xy 245.720616 -56.826404) (xy 245.721102 -56.799153) (xy 245.728858 -56.745205) (xy 245.744213 -56.69291)
			(xy 245.766855 -56.643333) (xy 245.796321 -56.597483) (xy 245.832012 -56.556292) (xy 245.873203 -56.520601)
			(xy 245.919053 -56.491135) (xy 245.96863 -56.468493) (xy 246.020925 -56.453138) (xy 246.074873 -56.445382)
			(xy 246.129375 -56.445382) (xy 246.183323 -56.453138) (xy 246.235618 -56.468493) (xy 246.285195 -56.491135)
			(xy 246.331045 -56.520601) (xy 246.372236 -56.556292) (xy 246.407927 -56.597483) (xy 246.437393 -56.643333)
			(xy 246.460035 -56.69291) (xy 246.47539 -56.745205) (xy 246.483146 -56.799153) (xy 246.483632 -56.826404)
			(xy 246.48315 -56.853737) (xy 246.475347 -56.907845) (xy 246.459901 -56.960284) (xy 246.437128 -57.009982)
			(xy 246.407496 -57.055921) (xy 246.389906 -57.076848) (xy 246.389652 -57.077102) (xy 246.389398 -57.077356)
			(xy 246.383823 -57.084451) (xy 246.37757 -57.101361) (xy 246.377206 -57.110376) (xy 246.377206 -57.177432)
			(xy 246.377547 -57.186451) (xy 246.383805 -57.203367) (xy 246.389398 -57.210452) (xy 246.389652 -57.210706)
			(xy 246.389906 -57.21096) (xy 246.407511 -57.231878) (xy 246.437166 -57.277811) (xy 246.459956 -57.327509)
			(xy 246.475414 -57.379953) (xy 246.483223 -57.434066) (xy 246.483222 -57.48874) (xy 246.475413 -57.542853)
			(xy 246.459954 -57.595296) (xy 246.437163 -57.644994) (xy 246.407508 -57.690926) (xy 246.389906 -57.711848)
			(xy 246.389652 -57.712102) (xy 246.389398 -57.712356) (xy 246.383823 -57.719451) (xy 246.37757 -57.736361)
			(xy 246.377206 -57.745376) (xy 246.377206 -57.812432) (xy 246.377547 -57.821451) (xy 246.383805 -57.838367)
			(xy 246.389398 -57.845452) (xy 246.389652 -57.845706) (xy 246.389906 -57.84596) (xy 246.407511 -57.866878)
			(xy 246.437166 -57.912811) (xy 246.459956 -57.962509) (xy 246.475414 -58.014953) (xy 246.483223 -58.069066)
			(xy 246.483222 -58.12374) (xy 246.475413 -58.177853) (xy 246.459954 -58.230296) (xy 246.437163 -58.279994)
			(xy 246.407508 -58.325926) (xy 246.389906 -58.346848) (xy 246.389652 -58.347102) (xy 246.389398 -58.347356)
			(xy 246.383823 -58.354451) (xy 246.37757 -58.371361) (xy 246.377206 -58.380376) (xy 246.377206 -58.447432)
			(xy 246.377547 -58.456451) (xy 246.383805 -58.473367) (xy 246.389398 -58.480452) (xy 246.389652 -58.480706)
			(xy 246.389906 -58.48096) (xy 246.407494 -58.501889) (xy 246.437133 -58.547825) (xy 246.45991 -58.597522)
			(xy 246.475359 -58.649962) (xy 246.483163 -58.70407) (xy 246.483632 -58.731404) (xy 246.483146 -58.758655)
			(xy 246.478482 -58.791094) (xy 248.37644 -58.791094) (xy 248.376928 -58.763761) (xy 248.384731 -58.709654)
			(xy 248.400176 -58.657215) (xy 248.422947 -58.607517) (xy 248.452577 -58.561578) (xy 248.470166 -58.54065)
			(xy 248.47042 -58.540396) (xy 248.470674 -58.540142) (xy 248.476258 -58.533054) (xy 248.482504 -58.516138)
			(xy 248.482866 -58.507122) (xy 248.482866 -58.440066) (xy 248.482533 -58.431047) (xy 248.476269 -58.414129)
			(xy 248.470674 -58.407046) (xy 248.47042 -58.406792) (xy 248.470166 -58.406538) (xy 248.45256 -58.385621)
			(xy 248.422907 -58.339687) (xy 248.400119 -58.289989) (xy 248.384663 -58.237545) (xy 248.376855 -58.183432)
			(xy 248.376855 -58.128759) (xy 248.384665 -58.074646) (xy 248.400122 -58.022203) (xy 248.422912 -57.972505)
			(xy 248.452565 -57.926572) (xy 248.470166 -57.90565) (xy 248.47042 -57.905396) (xy 248.470674 -57.905142)
			(xy 248.476258 -57.898054) (xy 248.482504 -57.881138) (xy 248.482866 -57.872122) (xy 248.482866 -57.805066)
			(xy 248.482533 -57.796047) (xy 248.476269 -57.779129) (xy 248.470674 -57.772046) (xy 248.47042 -57.771792)
			(xy 248.470166 -57.771538) (xy 248.452573 -57.750613) (xy 248.422936 -57.704675) (xy 248.40016 -57.654977)
			(xy 248.384712 -57.602537) (xy 248.376909 -57.548428) (xy 248.37644 -57.521094) (xy 248.37644 -57.52084)
			(xy 248.376913 -57.494545) (xy 248.384153 -57.442457) (xy 248.398476 -57.391855) (xy 248.419608 -57.343699)
			(xy 248.447152 -57.298899) (xy 248.480584 -57.258304) (xy 248.49963 -57.24017) (xy 248.507073 -57.232599)
			(xy 248.5156 -57.213181) (xy 248.51614 -57.202578) (xy 248.51614 -57.12841) (xy 248.515705 -57.117781)
			(xy 248.507172 -57.098318) (xy 248.49963 -57.090818) (xy 248.48058 -57.072684) (xy 248.447122 -57.032104)
			(xy 248.419561 -56.987309) (xy 248.39842 -56.93915) (xy 248.384102 -56.888542) (xy 248.376878 -56.836445)
			(xy 248.37644 -56.810148) (xy 248.37644 -56.809894) (xy 248.376926 -56.782643) (xy 248.384682 -56.728695)
			(xy 248.400037 -56.6764) (xy 248.422679 -56.626823) (xy 248.452145 -56.580973) (xy 248.487836 -56.539782)
			(xy 248.529027 -56.504091) (xy 248.574877 -56.474625) (xy 248.624454 -56.451983) (xy 248.676749 -56.436628)
			(xy 248.730697 -56.428872) (xy 248.785199 -56.428872) (xy 248.839147 -56.436628) (xy 248.891442 -56.451983)
			(xy 248.941019 -56.474625) (xy 248.986869 -56.504091) (xy 249.02806 -56.539782) (xy 249.063751 -56.580973)
			(xy 249.093217 -56.626823) (xy 249.115859 -56.6764) (xy 249.131214 -56.728695) (xy 249.13897 -56.782643)
			(xy 249.139456 -56.809894) (xy 249.139456 -56.810148) (xy 249.139043 -56.836445) (xy 249.131791 -56.888536)
			(xy 249.117457 -56.939139) (xy 249.096312 -56.987295) (xy 249.068759 -57.032093) (xy 249.035317 -57.072686)
			(xy 249.016266 -57.090818) (xy 249.008828 -57.098393) (xy 249.000299 -57.117808) (xy 248.999756 -57.12841)
			(xy 248.999756 -57.202578) (xy 249.000199 -57.213206) (xy 249.008726 -57.23267) (xy 249.016266 -57.24017)
			(xy 249.03531 -57.258311) (xy 249.068768 -57.298889) (xy 249.09633 -57.343683) (xy 249.117472 -57.391841)
			(xy 249.131791 -57.442448) (xy 249.135204 -57.467053) (xy 249.318469 -57.467053) (xy 249.318469 -57.412547)
			(xy 249.326227 -57.358596) (xy 249.341584 -57.306298) (xy 249.364227 -57.256718) (xy 249.393696 -57.210865)
			(xy 249.429392 -57.169673) (xy 249.470586 -57.133981) (xy 249.516441 -57.104515) (xy 249.566022 -57.081874)
			(xy 249.618321 -57.066521) (xy 249.672273 -57.058768) (xy 249.699526 -57.058306) (xy 249.69978 -57.058306)
			(xy 249.726074 -57.058776) (xy 249.778163 -57.066019) (xy 249.828764 -57.080342) (xy 249.87692 -57.101476)
			(xy 249.92172 -57.129019) (xy 249.962315 -57.16245) (xy 249.98045 -57.181496) (xy 249.988005 -57.188957)
			(xy 250.007435 -57.197471) (xy 250.018042 -57.198006) (xy 250.09221 -57.198006) (xy 250.102841 -57.197592)
			(xy 250.122306 -57.189046) (xy 250.129802 -57.181496) (xy 250.14792 -57.16243) (xy 250.188504 -57.128974)
			(xy 250.233303 -57.101416) (xy 250.281465 -57.080279) (xy 250.332076 -57.065964) (xy 250.384174 -57.058743)
			(xy 250.410472 -57.058306) (xy 250.410726 -57.058306) (xy 250.437977 -57.058766) (xy 250.491924 -57.066525)
			(xy 250.527073 -57.076848) (xy 251.338588 -57.076848) (xy 251.339062 -57.049514) (xy 251.34687 -56.995408)
			(xy 251.362319 -56.942969) (xy 251.385093 -56.893271) (xy 251.414725 -56.847332) (xy 251.432314 -56.826404)
			(xy 251.432568 -56.82615) (xy 251.432822 -56.825896) (xy 251.438419 -56.818817) (xy 251.444659 -56.801894)
			(xy 251.445014 -56.792876) (xy 251.445014 -56.72582) (xy 251.444644 -56.716804) (xy 251.438405 -56.699888)
			(xy 251.432822 -56.6928) (xy 251.432568 -56.692546) (xy 251.432314 -56.692292) (xy 251.414707 -56.671378)
			(xy 251.38507 -56.625438) (xy 251.362296 -56.575737) (xy 251.346852 -56.523294) (xy 251.339054 -56.469183)
			(xy 251.338588 -56.441848) (xy 251.339074 -56.414597) (xy 251.34683 -56.360649) (xy 251.362185 -56.308354)
			(xy 251.384827 -56.258777) (xy 251.414293 -56.212927) (xy 251.449984 -56.171736) (xy 251.491175 -56.136045)
			(xy 251.537025 -56.106579) (xy 251.586602 -56.083937) (xy 251.638897 -56.068582) (xy 251.692845 -56.060826)
			(xy 251.747347 -56.060826) (xy 251.801295 -56.068582) (xy 251.85359 -56.083937) (xy 251.903167 -56.106579)
			(xy 251.949017 -56.136045) (xy 251.990208 -56.171736) (xy 252.025899 -56.212927) (xy 252.055365 -56.258777)
			(xy 252.078007 -56.308354) (xy 252.09125 -56.353456) (xy 259.141212 -56.353456) (xy 259.145283 -56.297834)
			(xy 259.157409 -56.243397) (xy 259.177332 -56.191306) (xy 259.204628 -56.142671) (xy 259.238714 -56.098528)
			(xy 259.278863 -56.059819) (xy 259.324221 -56.027368) (xy 259.373821 -56.001867) (xy 259.426605 -55.98386)
			(xy 259.481448 -55.97373) (xy 259.537182 -55.971693) (xy 259.592619 -55.977793) (xy 259.646576 -55.991899)
			(xy 259.697905 -56.013711) (xy 259.745511 -56.042765) (xy 259.788379 -56.07844) (xy 259.825596 -56.119977)
			(xy 259.856369 -56.16649) (xy 259.880041 -56.216987) (xy 259.896109 -56.270394) (xy 259.904229 -56.32557)
			(xy 259.904738 -56.353456) (xy 259.904229 -56.381342) (xy 259.896109 -56.436518) (xy 259.880041 -56.489925)
			(xy 259.856369 -56.540422) (xy 259.825596 -56.586935) (xy 259.788379 -56.628472) (xy 259.745511 -56.664147)
			(xy 259.697905 -56.693201) (xy 259.646576 -56.715013) (xy 259.592619 -56.729119) (xy 259.537182 -56.735219)
			(xy 259.481448 -56.733182) (xy 259.426605 -56.723052) (xy 259.373821 -56.705045) (xy 259.324221 -56.679544)
			(xy 259.278863 -56.647093) (xy 259.238714 -56.608384) (xy 259.204628 -56.564241) (xy 259.177332 -56.515606)
			(xy 259.157409 -56.463515) (xy 259.145283 -56.409078) (xy 259.141212 -56.353456) (xy 252.09125 -56.353456)
			(xy 252.093362 -56.360649) (xy 252.101118 -56.414597) (xy 252.101604 -56.441848) (xy 252.10113 -56.469182)
			(xy 252.093322 -56.523288) (xy 252.077873 -56.575727) (xy 252.0551 -56.625425) (xy 252.025467 -56.671364)
			(xy 252.007878 -56.692292) (xy 252.007624 -56.692546) (xy 252.00737 -56.6928) (xy 252.001774 -56.69988)
			(xy 251.995534 -56.716802) (xy 251.995178 -56.72582) (xy 251.995178 -56.792876) (xy 251.995551 -56.801891)
			(xy 252.001788 -56.818808) (xy 252.00737 -56.825896) (xy 252.007624 -56.82615) (xy 252.007878 -56.826404)
			(xy 252.025482 -56.84732) (xy 252.05512 -56.893259) (xy 252.077894 -56.94296) (xy 252.093339 -56.995402)
			(xy 252.101138 -57.049513) (xy 252.101604 -57.076848) (xy 252.101118 -57.104099) (xy 252.093362 -57.158047)
			(xy 252.078007 -57.210342) (xy 252.055365 -57.259919) (xy 252.025899 -57.305769) (xy 251.990208 -57.34696)
			(xy 251.949017 -57.382651) (xy 251.903167 -57.412117) (xy 251.85359 -57.434759) (xy 251.801295 -57.450114)
			(xy 251.747347 -57.45787) (xy 251.692845 -57.45787) (xy 251.638897 -57.450114) (xy 251.586602 -57.434759)
			(xy 251.537025 -57.412117) (xy 251.491175 -57.382651) (xy 251.449984 -57.34696) (xy 251.414293 -57.305769)
			(xy 251.384827 -57.259919) (xy 251.362185 -57.210342) (xy 251.34683 -57.158047) (xy 251.339074 -57.104099)
			(xy 251.338588 -57.076848) (xy 250.527073 -57.076848) (xy 250.544217 -57.081883) (xy 250.593793 -57.104527)
			(xy 250.639642 -57.133995) (xy 250.680831 -57.169688) (xy 250.716521 -57.210879) (xy 250.745986 -57.25673)
			(xy 250.768626 -57.306307) (xy 250.78398 -57.358602) (xy 250.791736 -57.412549) (xy 250.791736 -57.467051)
			(xy 250.789115 -57.48528) (xy 262.805924 -57.48528) (xy 262.809995 -57.429658) (xy 262.822121 -57.375221)
			(xy 262.842044 -57.32313) (xy 262.86934 -57.274495) (xy 262.903426 -57.230352) (xy 262.943575 -57.191643)
			(xy 262.988933 -57.159192) (xy 263.038533 -57.133691) (xy 263.091317 -57.115684) (xy 263.14616 -57.105554)
			(xy 263.201894 -57.103517) (xy 263.257331 -57.109617) (xy 263.311288 -57.123723) (xy 263.362617 -57.145535)
			(xy 263.410223 -57.174589) (xy 263.453091 -57.210264) (xy 263.490308 -57.251801) (xy 263.521081 -57.298314)
			(xy 263.544753 -57.348811) (xy 263.560821 -57.402218) (xy 263.568941 -57.457394) (xy 263.56945 -57.48528)
			(xy 263.568941 -57.513166) (xy 263.560821 -57.568342) (xy 263.544753 -57.621749) (xy 263.521081 -57.672246)
			(xy 263.490308 -57.718759) (xy 263.453091 -57.760296) (xy 263.410223 -57.795971) (xy 263.362617 -57.825025)
			(xy 263.311288 -57.846837) (xy 263.257331 -57.860943) (xy 263.201894 -57.867043) (xy 263.14616 -57.865006)
			(xy 263.091317 -57.854876) (xy 263.038533 -57.836869) (xy 262.988933 -57.811368) (xy 262.943575 -57.778917)
			(xy 262.903426 -57.740208) (xy 262.86934 -57.696065) (xy 262.842044 -57.64743) (xy 262.822121 -57.595339)
			(xy 262.809995 -57.540902) (xy 262.805924 -57.48528) (xy 250.789115 -57.48528) (xy 250.78398 -57.520998)
			(xy 250.768626 -57.573293) (xy 250.745986 -57.62287) (xy 250.716521 -57.668721) (xy 250.680831 -57.709912)
			(xy 250.639642 -57.745605) (xy 250.593793 -57.775073) (xy 250.544217 -57.797717) (xy 250.491924 -57.813075)
			(xy 250.437977 -57.820834) (xy 250.410726 -57.821322) (xy 250.410472 -57.821322) (xy 250.384177 -57.820875)
			(xy 250.332088 -57.813626) (xy 250.281487 -57.799297) (xy 250.233331 -57.77816) (xy 250.188531 -57.750613)
			(xy 250.147936 -57.717179) (xy 250.129802 -57.698132) (xy 250.122224 -57.690697) (xy 250.102811 -57.682167)
			(xy 250.09221 -57.681622) (xy 250.018042 -57.681622) (xy 250.007406 -57.682002) (xy 249.987942 -57.690571)
			(xy 249.98045 -57.698132) (xy 249.962342 -57.717208) (xy 249.921757 -57.750665) (xy 249.876957 -57.778224)
			(xy 249.828792 -57.79936) (xy 249.778179 -57.813672) (xy 249.726079 -57.820888) (xy 249.69978 -57.821322)
			(xy 249.699526 -57.821322) (xy 249.672273 -57.820832) (xy 249.618321 -57.813079) (xy 249.566022 -57.797726)
			(xy 249.516441 -57.775085) (xy 249.470586 -57.745619) (xy 249.429392 -57.709927) (xy 249.393696 -57.668735)
			(xy 249.364227 -57.622882) (xy 249.341584 -57.573302) (xy 249.326227 -57.521004) (xy 249.318469 -57.467053)
			(xy 249.135204 -57.467053) (xy 249.139017 -57.494543) (xy 249.139456 -57.52084) (xy 249.139456 -57.521094)
			(xy 249.138962 -57.548427) (xy 249.131161 -57.602533) (xy 249.115717 -57.654972) (xy 249.092948 -57.704671)
			(xy 249.063318 -57.75061) (xy 249.04573 -57.771538) (xy 249.045476 -57.771792) (xy 249.045222 -57.772046)
			(xy 249.039643 -57.779137) (xy 249.033394 -57.796051) (xy 249.03303 -57.805066) (xy 249.03303 -57.872122)
			(xy 249.03337 -57.881141) (xy 249.039629 -57.898058) (xy 249.045222 -57.905142) (xy 249.045476 -57.905396)
			(xy 249.04573 -57.90565) (xy 249.063325 -57.926577) (xy 249.092978 -57.972509) (xy 249.115767 -58.022205)
			(xy 249.131225 -58.074647) (xy 249.139034 -58.128759) (xy 249.139034 -58.183432) (xy 249.131227 -58.237544)
			(xy 249.11577 -58.289986) (xy 249.092982 -58.339683) (xy 249.06333 -58.385616) (xy 249.04573 -58.406538)
			(xy 249.045476 -58.406792) (xy 249.045222 -58.407046) (xy 249.039643 -58.414137) (xy 249.033394 -58.431051)
			(xy 249.03303 -58.440066) (xy 249.03303 -58.507122) (xy 249.03337 -58.516141) (xy 249.039629 -58.533058)
			(xy 249.045222 -58.540142) (xy 249.045476 -58.540396) (xy 249.04573 -58.54065) (xy 249.063317 -58.56158)
			(xy 249.092955 -58.607516) (xy 249.115732 -58.657213) (xy 249.131181 -58.709652) (xy 249.138986 -58.76376)
			(xy 249.139456 -58.791094) (xy 249.13897 -58.818345) (xy 249.131214 -58.872293) (xy 249.130817 -58.873644)
			(xy 250.400566 -58.873644) (xy 250.401018 -58.846309) (xy 250.408829 -58.792201) (xy 250.424282 -58.739761)
			(xy 250.447061 -58.690064) (xy 250.4767 -58.644126) (xy 250.494292 -58.6232) (xy 250.494546 -58.622946)
			(xy 250.4948 -58.622692) (xy 250.500396 -58.615612) (xy 250.506637 -58.59869) (xy 250.506992 -58.589672)
			(xy 250.506992 -58.522616) (xy 250.506629 -58.5136) (xy 250.500386 -58.496683) (xy 250.4948 -58.489596)
			(xy 250.494546 -58.489342) (xy 250.494292 -58.489088) (xy 250.476679 -58.468179) (xy 250.447044 -58.422237)
			(xy 250.424272 -58.372535) (xy 250.408829 -58.320091) (xy 250.401031 -58.265979) (xy 250.400566 -58.238644)
			(xy 250.401052 -58.211393) (xy 250.408808 -58.157445) (xy 250.424163 -58.10515) (xy 250.446805 -58.055573)
			(xy 250.476271 -58.009723) (xy 250.511962 -57.968532) (xy 250.553153 -57.932841) (xy 250.599003 -57.903375)
			(xy 250.64858 -57.880733) (xy 250.700875 -57.865378) (xy 250.754823 -57.857622) (xy 250.809325 -57.857622)
			(xy 250.863273 -57.865378) (xy 250.915568 -57.880733) (xy 250.965145 -57.903375) (xy 251.010995 -57.932841)
			(xy 251.052186 -57.968532) (xy 251.087877 -58.009723) (xy 251.117343 -58.055573) (xy 251.12497 -58.072274)
			(xy 258.193538 -58.072274) (xy 258.197609 -58.016652) (xy 258.209735 -57.962215) (xy 258.229658 -57.910124)
			(xy 258.256954 -57.861489) (xy 258.29104 -57.817346) (xy 258.331189 -57.778637) (xy 258.376547 -57.746186)
			(xy 258.426147 -57.720685) (xy 258.478931 -57.702678) (xy 258.533774 -57.692548) (xy 258.589508 -57.690511)
			(xy 258.644945 -57.696611) (xy 258.698902 -57.710717) (xy 258.750231 -57.732529) (xy 258.797837 -57.761583)
			(xy 258.840705 -57.797258) (xy 258.877922 -57.838795) (xy 258.908695 -57.885308) (xy 258.932367 -57.935805)
			(xy 258.948435 -57.989212) (xy 258.956555 -58.044388) (xy 258.957064 -58.072274) (xy 258.956994 -58.076084)
			(xy 263.558018 -58.076084) (xy 263.562089 -58.020462) (xy 263.574215 -57.966025) (xy 263.594138 -57.913934)
			(xy 263.621434 -57.865299) (xy 263.65552 -57.821156) (xy 263.695669 -57.782447) (xy 263.741027 -57.749996)
			(xy 263.790627 -57.724495) (xy 263.843411 -57.706488) (xy 263.898254 -57.696358) (xy 263.953988 -57.694321)
			(xy 264.009425 -57.700421) (xy 264.063382 -57.714527) (xy 264.114711 -57.736339) (xy 264.162317 -57.765393)
			(xy 264.205185 -57.801068) (xy 264.242402 -57.842605) (xy 264.258738 -57.867296) (xy 265.843002 -57.867296)
			(xy 265.847073 -57.811674) (xy 265.859199 -57.757237) (xy 265.879122 -57.705146) (xy 265.906418 -57.656511)
			(xy 265.940504 -57.612368) (xy 265.980653 -57.573659) (xy 266.026011 -57.541208) (xy 266.075611 -57.515707)
			(xy 266.128395 -57.4977) (xy 266.183238 -57.48757) (xy 266.238972 -57.485533) (xy 266.294409 -57.491633)
			(xy 266.348366 -57.505739) (xy 266.399695 -57.527551) (xy 266.447301 -57.556605) (xy 266.490169 -57.59228)
			(xy 266.527386 -57.633817) (xy 266.558159 -57.68033) (xy 266.581831 -57.730827) (xy 266.597899 -57.784234)
			(xy 266.606019 -57.83941) (xy 266.606528 -57.867296) (xy 266.606019 -57.895182) (xy 266.597899 -57.950358)
			(xy 266.581831 -58.003765) (xy 266.558159 -58.054262) (xy 266.527386 -58.100775) (xy 266.490169 -58.142312)
			(xy 266.447301 -58.177987) (xy 266.399695 -58.207041) (xy 266.348366 -58.228853) (xy 266.294409 -58.242959)
			(xy 266.238972 -58.249059) (xy 266.183238 -58.247022) (xy 266.128395 -58.236892) (xy 266.075611 -58.218885)
			(xy 266.026011 -58.193384) (xy 265.980653 -58.160933) (xy 265.940504 -58.122224) (xy 265.906418 -58.078081)
			(xy 265.879122 -58.029446) (xy 265.859199 -57.977355) (xy 265.847073 -57.922918) (xy 265.843002 -57.867296)
			(xy 264.258738 -57.867296) (xy 264.273175 -57.889118) (xy 264.296847 -57.939615) (xy 264.312915 -57.993022)
			(xy 264.321035 -58.048198) (xy 264.321544 -58.076084) (xy 264.321035 -58.10397) (xy 264.312915 -58.159146)
			(xy 264.296847 -58.212553) (xy 264.273175 -58.26305) (xy 264.242402 -58.309563) (xy 264.205185 -58.3511)
			(xy 264.162317 -58.386775) (xy 264.114711 -58.415829) (xy 264.063382 -58.437641) (xy 264.009425 -58.451747)
			(xy 263.953988 -58.457847) (xy 263.898254 -58.45581) (xy 263.843411 -58.44568) (xy 263.790627 -58.427673)
			(xy 263.741027 -58.402172) (xy 263.695669 -58.369721) (xy 263.65552 -58.331012) (xy 263.621434 -58.286869)
			(xy 263.594138 -58.238234) (xy 263.574215 -58.186143) (xy 263.562089 -58.131706) (xy 263.558018 -58.076084)
			(xy 258.956994 -58.076084) (xy 258.956555 -58.10016) (xy 258.948435 -58.155336) (xy 258.932367 -58.208743)
			(xy 258.908695 -58.25924) (xy 258.877922 -58.305753) (xy 258.840705 -58.34729) (xy 258.797837 -58.382965)
			(xy 258.750231 -58.412019) (xy 258.698902 -58.433831) (xy 258.644945 -58.447937) (xy 258.589508 -58.454037)
			(xy 258.533774 -58.452) (xy 258.478931 -58.44187) (xy 258.426147 -58.423863) (xy 258.376547 -58.398362)
			(xy 258.331189 -58.365911) (xy 258.29104 -58.327202) (xy 258.256954 -58.283059) (xy 258.229658 -58.234424)
			(xy 258.209735 -58.182333) (xy 258.197609 -58.127896) (xy 258.193538 -58.072274) (xy 251.12497 -58.072274)
			(xy 251.139985 -58.10515) (xy 251.15534 -58.157445) (xy 251.163096 -58.211393) (xy 251.163582 -58.238644)
			(xy 251.163111 -58.265978) (xy 251.155303 -58.320085) (xy 251.139854 -58.372524) (xy 251.117079 -58.422222)
			(xy 251.087446 -58.468161) (xy 251.069856 -58.489088) (xy 251.069602 -58.489342) (xy 251.069348 -58.489596)
			(xy 251.063751 -58.496675) (xy 251.057512 -58.513598) (xy 251.057156 -58.522616) (xy 251.057156 -58.561224)
			(xy 264.762232 -58.561224) (xy 264.766303 -58.505602) (xy 264.778429 -58.451165) (xy 264.798352 -58.399074)
			(xy 264.825648 -58.350439) (xy 264.859734 -58.306296) (xy 264.899883 -58.267587) (xy 264.945241 -58.235136)
			(xy 264.994841 -58.209635) (xy 265.047625 -58.191628) (xy 265.102468 -58.181498) (xy 265.158202 -58.179461)
			(xy 265.213639 -58.185561) (xy 265.267596 -58.199667) (xy 265.318925 -58.221479) (xy 265.366531 -58.250533)
			(xy 265.409399 -58.286208) (xy 265.446616 -58.327745) (xy 265.477389 -58.374258) (xy 265.501061 -58.424755)
			(xy 265.508571 -58.449718) (xy 267.008862 -58.449718) (xy 267.012933 -58.394096) (xy 267.025059 -58.339659)
			(xy 267.044982 -58.287568) (xy 267.072278 -58.238933) (xy 267.106364 -58.19479) (xy 267.146513 -58.156081)
			(xy 267.191871 -58.12363) (xy 267.241471 -58.098129) (xy 267.294255 -58.080122) (xy 267.349098 -58.069992)
			(xy 267.404832 -58.067955) (xy 267.460269 -58.074055) (xy 267.514226 -58.088161) (xy 267.565555 -58.109973)
			(xy 267.613161 -58.139027) (xy 267.656029 -58.174702) (xy 267.693246 -58.216239) (xy 267.724019 -58.262752)
			(xy 267.747691 -58.313249) (xy 267.763759 -58.366656) (xy 267.771879 -58.421832) (xy 267.772388 -58.449718)
			(xy 267.771879 -58.477604) (xy 267.763759 -58.53278) (xy 267.747691 -58.586187) (xy 267.724019 -58.636684)
			(xy 267.693246 -58.683197) (xy 267.656029 -58.724734) (xy 267.648014 -58.731404) (xy 271.720564 -58.731404)
			(xy 271.721052 -58.704071) (xy 271.728854 -58.649964) (xy 271.744299 -58.597525) (xy 271.76707 -58.547827)
			(xy 271.796701 -58.501888) (xy 271.81429 -58.48096) (xy 271.814544 -58.480706) (xy 271.814798 -58.480452)
			(xy 271.820369 -58.473355) (xy 271.826625 -58.456446) (xy 271.82699 -58.447432) (xy 271.82699 -58.380376)
			(xy 271.826647 -58.371358) (xy 271.82039 -58.354441) (xy 271.814798 -58.347356) (xy 271.814544 -58.347102)
			(xy 271.81429 -58.346848) (xy 271.796693 -58.325923) (xy 271.767038 -58.279991) (xy 271.744248 -58.230294)
			(xy 271.728789 -58.177852) (xy 271.72098 -58.12374) (xy 271.72098 -58.069066) (xy 271.728788 -58.014954)
			(xy 271.744246 -57.962511) (xy 271.767035 -57.912814) (xy 271.796689 -57.866882) (xy 271.81429 -57.84596)
			(xy 271.814544 -57.845706) (xy 271.814798 -57.845452) (xy 271.820369 -57.838355) (xy 271.826625 -57.821446)
			(xy 271.82699 -57.812432) (xy 271.82699 -57.745376) (xy 271.826647 -57.736358) (xy 271.82039 -57.719441)
			(xy 271.814798 -57.712356) (xy 271.814544 -57.712102) (xy 271.81429 -57.711848) (xy 271.796693 -57.690923)
			(xy 271.767038 -57.644991) (xy 271.744248 -57.595294) (xy 271.728789 -57.542852) (xy 271.72098 -57.48874)
			(xy 271.72098 -57.434066) (xy 271.728788 -57.379954) (xy 271.744246 -57.327511) (xy 271.767035 -57.277814)
			(xy 271.796689 -57.231882) (xy 271.81429 -57.21096) (xy 271.814544 -57.210706) (xy 271.814798 -57.210452)
			(xy 271.820369 -57.203355) (xy 271.826625 -57.186446) (xy 271.82699 -57.177432) (xy 271.82699 -57.110376)
			(xy 271.826647 -57.101358) (xy 271.82039 -57.084441) (xy 271.814798 -57.077356) (xy 271.814544 -57.077102)
			(xy 271.81429 -57.076848) (xy 271.796705 -57.055916) (xy 271.767066 -57.009981) (xy 271.744288 -56.960284)
			(xy 271.728839 -56.907845) (xy 271.721034 -56.853738) (xy 271.720564 -56.826404) (xy 271.72105 -56.799153)
			(xy 271.728806 -56.745205) (xy 271.744161 -56.69291) (xy 271.766803 -56.643333) (xy 271.796269 -56.597483)
			(xy 271.83196 -56.556292) (xy 271.873151 -56.520601) (xy 271.919001 -56.491135) (xy 271.968578 -56.468493)
			(xy 272.020873 -56.453138) (xy 272.074821 -56.445382) (xy 272.129323 -56.445382) (xy 272.183271 -56.453138)
			(xy 272.235566 -56.468493) (xy 272.285143 -56.491135) (xy 272.330993 -56.520601) (xy 272.372184 -56.556292)
			(xy 272.407875 -56.597483) (xy 272.437341 -56.643333) (xy 272.459983 -56.69291) (xy 272.475338 -56.745205)
			(xy 272.483094 -56.799153) (xy 272.48358 -56.826404) (xy 272.483086 -56.853737) (xy 272.475284 -56.907843)
			(xy 272.45984 -56.960282) (xy 272.437071 -57.00998) (xy 272.407442 -57.05592) (xy 272.389854 -57.076848)
			(xy 272.3896 -57.077102) (xy 272.389346 -57.077356) (xy 272.383765 -57.084446) (xy 272.377516 -57.10136)
			(xy 272.377154 -57.110376) (xy 272.377154 -57.177432) (xy 272.377484 -57.186452) (xy 272.383749 -57.203369)
			(xy 272.389346 -57.210452) (xy 272.3896 -57.210706) (xy 272.389854 -57.21096) (xy 272.407457 -57.231879)
			(xy 272.437108 -57.277813) (xy 272.459895 -57.327511) (xy 272.475351 -57.379954) (xy 272.483159 -57.434067)
			(xy 272.483159 -57.488739) (xy 272.47535 -57.542852) (xy 272.459893 -57.595294) (xy 272.437106 -57.644992)
			(xy 272.407454 -57.690925) (xy 272.389854 -57.711848) (xy 272.3896 -57.712102) (xy 272.389346 -57.712356)
			(xy 272.383765 -57.719446) (xy 272.377516 -57.73636) (xy 272.377154 -57.745376) (xy 272.377154 -57.812432)
			(xy 272.377484 -57.821452) (xy 272.383749 -57.838369) (xy 272.389346 -57.845452) (xy 272.3896 -57.845706)
			(xy 272.389854 -57.84596) (xy 272.407457 -57.866879) (xy 272.437108 -57.912813) (xy 272.459895 -57.962511)
			(xy 272.475351 -58.014954) (xy 272.483159 -58.069067) (xy 272.483159 -58.123739) (xy 272.47535 -58.177852)
			(xy 272.459893 -58.230294) (xy 272.437106 -58.279992) (xy 272.407454 -58.325925) (xy 272.389854 -58.346848)
			(xy 272.3896 -58.347102) (xy 272.389346 -58.347356) (xy 272.383765 -58.354446) (xy 272.377516 -58.37136)
			(xy 272.377154 -58.380376) (xy 272.377154 -58.447432) (xy 272.377484 -58.456452) (xy 272.383749 -58.473369)
			(xy 272.389346 -58.480452) (xy 272.3896 -58.480706) (xy 272.389854 -58.48096) (xy 272.407434 -58.501896)
			(xy 272.437076 -58.547829) (xy 272.459855 -58.597525) (xy 272.475306 -58.649963) (xy 272.483111 -58.70407)
			(xy 272.48358 -58.731404) (xy 272.483094 -58.758655) (xy 272.47843 -58.791094) (xy 274.376388 -58.791094)
			(xy 274.376888 -58.763761) (xy 274.38469 -58.709656) (xy 274.400133 -58.657217) (xy 274.422901 -58.607519)
			(xy 274.452528 -58.561579) (xy 274.470114 -58.54065) (xy 274.470368 -58.540396) (xy 274.470622 -58.540142)
			(xy 274.4762 -58.533049) (xy 274.482451 -58.516137) (xy 274.482814 -58.507122) (xy 274.482814 -58.440066)
			(xy 274.48247 -58.431048) (xy 274.476213 -58.414131) (xy 274.470622 -58.407046) (xy 274.470368 -58.406792)
			(xy 274.470114 -58.406538) (xy 274.452506 -58.385622) (xy 274.42285 -58.339689) (xy 274.400059 -58.289991)
			(xy 274.3846 -58.237547) (xy 274.376791 -58.183433) (xy 274.376792 -58.128758) (xy 274.384602 -58.074644)
			(xy 274.400062 -58.022201) (xy 274.422854 -57.972503) (xy 274.452511 -57.926571) (xy 274.470114 -57.90565)
			(xy 274.470368 -57.905396) (xy 274.470622 -57.905142) (xy 274.4762 -57.898049) (xy 274.482451 -57.881137)
			(xy 274.482814 -57.872122) (xy 274.482814 -57.805066) (xy 274.48247 -57.796048) (xy 274.476213 -57.779131)
			(xy 274.470622 -57.772046) (xy 274.470368 -57.771792) (xy 274.470114 -57.771538) (xy 274.452528 -57.750607)
			(xy 274.422888 -57.704672) (xy 274.40011 -57.654975) (xy 274.384661 -57.602536) (xy 274.376857 -57.548428)
			(xy 274.376388 -57.521094) (xy 274.376388 -57.52084) (xy 274.376877 -57.494546) (xy 274.384117 -57.442459)
			(xy 274.398437 -57.391858) (xy 274.419567 -57.343702) (xy 274.447106 -57.298902) (xy 274.480534 -57.258305)
			(xy 274.499578 -57.24017) (xy 274.507028 -57.232606) (xy 274.515549 -57.213182) (xy 274.516088 -57.202578)
			(xy 274.516088 -57.12841) (xy 274.515668 -57.117779) (xy 274.507126 -57.098315) (xy 274.499578 -57.090818)
			(xy 274.480518 -57.072694) (xy 274.447063 -57.032111) (xy 274.419504 -56.987313) (xy 274.398366 -56.939152)
			(xy 274.384049 -56.888543) (xy 274.376826 -56.836446) (xy 274.376388 -56.810148) (xy 274.376388 -56.809894)
			(xy 274.376874 -56.782643) (xy 274.38463 -56.728695) (xy 274.399985 -56.6764) (xy 274.422627 -56.626823)
			(xy 274.452093 -56.580973) (xy 274.487784 -56.539782) (xy 274.528975 -56.504091) (xy 274.574825 -56.474625)
			(xy 274.624402 -56.451983) (xy 274.676697 -56.436628) (xy 274.730645 -56.428872) (xy 274.785147 -56.428872)
			(xy 274.839095 -56.436628) (xy 274.89139 -56.451983) (xy 274.940967 -56.474625) (xy 274.986817 -56.504091)
			(xy 275.028008 -56.539782) (xy 275.063699 -56.580973) (xy 275.093165 -56.626823) (xy 275.115807 -56.6764)
			(xy 275.131162 -56.728695) (xy 275.138918 -56.782643) (xy 275.139404 -56.809894) (xy 275.139404 -56.810148)
			(xy 275.138976 -56.836444) (xy 275.131724 -56.888534) (xy 275.117392 -56.939136) (xy 275.096251 -56.987292)
			(xy 275.068701 -57.032091) (xy 275.035263 -57.072684) (xy 275.016214 -57.090818) (xy 275.008768 -57.098386)
			(xy 275.000245 -57.117807) (xy 274.999704 -57.12841) (xy 274.999704 -57.202578) (xy 275.000133 -57.213208)
			(xy 275.008668 -57.232672) (xy 275.016214 -57.24017) (xy 275.035267 -57.258301) (xy 275.068723 -57.298883)
			(xy 275.096283 -57.343679) (xy 275.117422 -57.391838) (xy 275.13174 -57.442447) (xy 275.135152 -57.467049)
			(xy 275.318492 -57.467049) (xy 275.318492 -57.412551) (xy 275.326248 -57.358608) (xy 275.341601 -57.306317)
			(xy 275.364239 -57.256743) (xy 275.393702 -57.210896) (xy 275.429389 -57.169708) (xy 275.470575 -57.134018)
			(xy 275.51642 -57.104552) (xy 275.565992 -57.08191) (xy 275.618282 -57.066553) (xy 275.672225 -57.058794)
			(xy 275.699474 -57.058306) (xy 275.699728 -57.058306) (xy 275.726024 -57.058744) (xy 275.778113 -57.065993)
			(xy 275.828715 -57.080323) (xy 275.876871 -57.101463) (xy 275.92167 -57.129011) (xy 275.962264 -57.162448)
			(xy 275.980398 -57.181496) (xy 275.987972 -57.188934) (xy 276.007388 -57.197461) (xy 276.01799 -57.198006)
			(xy 276.092158 -57.198006) (xy 276.102792 -57.197618) (xy 276.122256 -57.189054) (xy 276.12975 -57.181496)
			(xy 276.147844 -57.162406) (xy 276.188434 -57.128953) (xy 276.233237 -57.101398) (xy 276.281404 -57.080265)
			(xy 276.332019 -57.065955) (xy 276.38412 -57.058739) (xy 276.41042 -57.058306) (xy 276.410674 -57.058306)
			(xy 276.437929 -57.058739) (xy 276.491885 -57.066493) (xy 276.527157 -57.076848) (xy 277.338536 -57.076848)
			(xy 277.338998 -57.049514) (xy 277.346807 -56.995406) (xy 277.362258 -56.942967) (xy 277.385035 -56.893269)
			(xy 277.414671 -56.847331) (xy 277.432262 -56.826404) (xy 277.432516 -56.82615) (xy 277.43277 -56.825896)
			(xy 277.438373 -56.818821) (xy 277.444608 -56.801895) (xy 277.444962 -56.792876) (xy 277.444962 -56.72582)
			(xy 277.444604 -56.716803) (xy 277.438358 -56.699886) (xy 277.43277 -56.6928) (xy 277.432516 -56.692546)
			(xy 277.432262 -56.692292) (xy 277.414646 -56.671385) (xy 277.385013 -56.625442) (xy 277.362242 -56.57574)
			(xy 277.346799 -56.523295) (xy 277.339002 -56.469183) (xy 277.338536 -56.441848) (xy 277.339022 -56.414597)
			(xy 277.346778 -56.360649) (xy 277.362133 -56.308354) (xy 277.384775 -56.258777) (xy 277.414241 -56.212927)
			(xy 277.449932 -56.171736) (xy 277.491123 -56.136045) (xy 277.536973 -56.106579) (xy 277.58655 -56.083937)
			(xy 277.638845 -56.068582) (xy 277.692793 -56.060826) (xy 277.747295 -56.060826) (xy 277.801243 -56.068582)
			(xy 277.853538 -56.083937) (xy 277.903115 -56.106579) (xy 277.948965 -56.136045) (xy 277.990156 -56.171736)
			(xy 278.025847 -56.212927) (xy 278.055313 -56.258777) (xy 278.077955 -56.308354) (xy 278.091198 -56.353456)
			(xy 285.14116 -56.353456) (xy 285.145231 -56.297834) (xy 285.157357 -56.243397) (xy 285.17728 -56.191306)
			(xy 285.204576 -56.142671) (xy 285.238662 -56.098528) (xy 285.278811 -56.059819) (xy 285.324169 -56.027368)
			(xy 285.373769 -56.001867) (xy 285.426553 -55.98386) (xy 285.481396 -55.97373) (xy 285.53713 -55.971693)
			(xy 285.592567 -55.977793) (xy 285.646524 -55.991899) (xy 285.697853 -56.013711) (xy 285.745459 -56.042765)
			(xy 285.788327 -56.07844) (xy 285.825544 -56.119977) (xy 285.856317 -56.16649) (xy 285.879989 -56.216987)
			(xy 285.896057 -56.270394) (xy 285.904177 -56.32557) (xy 285.904686 -56.353456) (xy 285.904177 -56.381342)
			(xy 285.896057 -56.436518) (xy 285.879989 -56.489925) (xy 285.856317 -56.540422) (xy 285.825544 -56.586935)
			(xy 285.788327 -56.628472) (xy 285.745459 -56.664147) (xy 285.697853 -56.693201) (xy 285.646524 -56.715013)
			(xy 285.592567 -56.729119) (xy 285.53713 -56.735219) (xy 285.481396 -56.733182) (xy 285.426553 -56.723052)
			(xy 285.373769 -56.705045) (xy 285.324169 -56.679544) (xy 285.278811 -56.647093) (xy 285.238662 -56.608384)
			(xy 285.204576 -56.564241) (xy 285.17728 -56.515606) (xy 285.157357 -56.463515) (xy 285.145231 -56.409078)
			(xy 285.14116 -56.353456) (xy 278.091198 -56.353456) (xy 278.09331 -56.360649) (xy 278.101066 -56.414597)
			(xy 278.101552 -56.441848) (xy 278.101091 -56.469182) (xy 278.093282 -56.52329) (xy 278.077831 -56.57573)
			(xy 278.055054 -56.625427) (xy 278.025417 -56.671365) (xy 278.007826 -56.692292) (xy 278.007572 -56.692546)
			(xy 278.007318 -56.6928) (xy 278.001728 -56.699884) (xy 277.995483 -56.716803) (xy 277.995126 -56.72582)
			(xy 277.995126 -56.792876) (xy 277.995489 -56.801892) (xy 278.001732 -56.81881) (xy 278.007318 -56.825896)
			(xy 278.007572 -56.82615) (xy 278.007826 -56.826404) (xy 278.025438 -56.847314) (xy 278.055072 -56.893256)
			(xy 278.077845 -56.942958) (xy 278.093288 -56.995401) (xy 278.101086 -57.049513) (xy 278.101552 -57.076848)
			(xy 278.101066 -57.104099) (xy 278.09331 -57.158047) (xy 278.077955 -57.210342) (xy 278.055313 -57.259919)
			(xy 278.025847 -57.305769) (xy 277.990156 -57.34696) (xy 277.948965 -57.382651) (xy 277.903115 -57.412117)
			(xy 277.853538 -57.434759) (xy 277.801243 -57.450114) (xy 277.747295 -57.45787) (xy 277.692793 -57.45787)
			(xy 277.638845 -57.450114) (xy 277.58655 -57.434759) (xy 277.536973 -57.412117) (xy 277.491123 -57.382651)
			(xy 277.449932 -57.34696) (xy 277.414241 -57.305769) (xy 277.384775 -57.259919) (xy 277.362133 -57.210342)
			(xy 277.346778 -57.158047) (xy 277.339022 -57.104099) (xy 277.338536 -57.076848) (xy 276.527157 -57.076848)
			(xy 276.544188 -57.081848) (xy 276.593773 -57.10449) (xy 276.639631 -57.133958) (xy 276.680829 -57.169653)
			(xy 276.716526 -57.210848) (xy 276.745998 -57.256704) (xy 276.768643 -57.306288) (xy 276.784001 -57.35859)
			(xy 276.791759 -57.412545) (xy 276.791759 -57.467055) (xy 276.789138 -57.48528) (xy 288.805872 -57.48528)
			(xy 288.809943 -57.429658) (xy 288.822069 -57.375221) (xy 288.841992 -57.32313) (xy 288.869288 -57.274495)
			(xy 288.903374 -57.230352) (xy 288.943523 -57.191643) (xy 288.988881 -57.159192) (xy 289.038481 -57.133691)
			(xy 289.091265 -57.115684) (xy 289.146108 -57.105554) (xy 289.201842 -57.103517) (xy 289.257279 -57.109617)
			(xy 289.311236 -57.123723) (xy 289.362565 -57.145535) (xy 289.410171 -57.174589) (xy 289.453039 -57.210264)
			(xy 289.490256 -57.251801) (xy 289.521029 -57.298314) (xy 289.544701 -57.348811) (xy 289.560769 -57.402218)
			(xy 289.568889 -57.457394) (xy 289.569398 -57.48528) (xy 289.568889 -57.513166) (xy 289.560769 -57.568342)
			(xy 289.544701 -57.621749) (xy 289.521029 -57.672246) (xy 289.490256 -57.718759) (xy 289.453039 -57.760296)
			(xy 289.410171 -57.795971) (xy 289.362565 -57.825025) (xy 289.311236 -57.846837) (xy 289.257279 -57.860943)
			(xy 289.201842 -57.867043) (xy 289.146108 -57.865006) (xy 289.091265 -57.854876) (xy 289.038481 -57.836869)
			(xy 288.988881 -57.811368) (xy 288.943523 -57.778917) (xy 288.903374 -57.740208) (xy 288.869288 -57.696065)
			(xy 288.841992 -57.64743) (xy 288.822069 -57.595339) (xy 288.809943 -57.540902) (xy 288.805872 -57.48528)
			(xy 276.789138 -57.48528) (xy 276.784001 -57.52101) (xy 276.768643 -57.573312) (xy 276.745998 -57.622896)
			(xy 276.716526 -57.668752) (xy 276.680829 -57.709947) (xy 276.639631 -57.745642) (xy 276.593773 -57.77511)
			(xy 276.544188 -57.797752) (xy 276.491885 -57.813107) (xy 276.437929 -57.820861) (xy 276.410674 -57.821322)
			(xy 276.41042 -57.821322) (xy 276.384126 -57.820843) (xy 276.332038 -57.813601) (xy 276.281438 -57.799278)
			(xy 276.233282 -57.778147) (xy 276.188482 -57.750606) (xy 276.147885 -57.717177) (xy 276.12975 -57.698132)
			(xy 276.122192 -57.690674) (xy 276.102764 -57.682157) (xy 276.092158 -57.681622) (xy 276.01799 -57.681622)
			(xy 276.007357 -57.682028) (xy 275.987893 -57.690579) (xy 275.980398 -57.698132) (xy 275.962266 -57.717185)
			(xy 275.921686 -57.750644) (xy 275.876891 -57.778206) (xy 275.828732 -57.799346) (xy 275.778123 -57.813663)
			(xy 275.726026 -57.820885) (xy 275.699728 -57.821322) (xy 275.699474 -57.821322) (xy 275.672225 -57.820806)
			(xy 275.618282 -57.813047) (xy 275.565992 -57.79769) (xy 275.51642 -57.775048) (xy 275.470575 -57.745582)
			(xy 275.429389 -57.709892) (xy 275.393702 -57.668704) (xy 275.364239 -57.622857) (xy 275.341601 -57.573283)
			(xy 275.326248 -57.520992) (xy 275.318492 -57.467049) (xy 275.135152 -57.467049) (xy 275.138965 -57.494543)
			(xy 275.139404 -57.52084) (xy 275.139404 -57.521094) (xy 275.138898 -57.548426) (xy 275.131098 -57.602532)
			(xy 275.115657 -57.65497) (xy 275.09289 -57.704669) (xy 275.063264 -57.750609) (xy 275.045678 -57.771538)
			(xy 275.045424 -57.771792) (xy 275.04517 -57.772046) (xy 275.039597 -57.779141) (xy 275.033343 -57.796052)
			(xy 275.032978 -57.805066) (xy 275.032978 -57.872122) (xy 275.033329 -57.881139) (xy 275.039581 -57.898056)
			(xy 275.04517 -57.905142) (xy 275.045424 -57.905396) (xy 275.045678 -57.90565) (xy 275.063271 -57.926578)
			(xy 275.09292 -57.972511) (xy 275.115706 -58.022208) (xy 275.131162 -58.074649) (xy 275.13897 -58.12876)
			(xy 275.138971 -58.183431) (xy 275.131164 -58.237542) (xy 275.11571 -58.289984) (xy 275.092925 -58.339681)
			(xy 275.063276 -58.385615) (xy 275.045678 -58.406538) (xy 275.045424 -58.406792) (xy 275.04517 -58.407046)
			(xy 275.039597 -58.414141) (xy 275.033343 -58.431052) (xy 275.032978 -58.440066) (xy 275.032978 -58.507122)
			(xy 275.033329 -58.516139) (xy 275.039581 -58.533056) (xy 275.04517 -58.540142) (xy 275.045424 -58.540396)
			(xy 275.045678 -58.54065) (xy 275.063257 -58.561587) (xy 275.092898 -58.60752) (xy 275.115677 -58.657215)
			(xy 275.131128 -58.709653) (xy 275.138934 -58.76376) (xy 275.139404 -58.791094) (xy 275.138918 -58.818345)
			(xy 275.131162 -58.872293) (xy 275.130765 -58.873644) (xy 276.400514 -58.873644) (xy 276.400979 -58.84631)
			(xy 276.408788 -58.792203) (xy 276.424239 -58.739764) (xy 276.447015 -58.690066) (xy 276.47665 -58.644127)
			(xy 276.49424 -58.6232) (xy 276.494494 -58.622946) (xy 276.494748 -58.622692) (xy 276.50035 -58.615616)
			(xy 276.506586 -58.598691) (xy 276.50694 -58.589672) (xy 276.50694 -58.522616) (xy 276.506588 -58.513598)
			(xy 276.500338 -58.496681) (xy 276.494748 -58.489596) (xy 276.494494 -58.489342) (xy 276.49424 -58.489088)
			(xy 276.476635 -58.468173) (xy 276.446997 -58.422233) (xy 276.424222 -58.372533) (xy 276.408778 -58.32009)
			(xy 276.40098 -58.265979) (xy 276.400514 -58.238644) (xy 276.401 -58.211393) (xy 276.408756 -58.157445)
			(xy 276.424111 -58.10515) (xy 276.446753 -58.055573) (xy 276.476219 -58.009723) (xy 276.51191 -57.968532)
			(xy 276.553101 -57.932841) (xy 276.598951 -57.903375) (xy 276.648528 -57.880733) (xy 276.700823 -57.865378)
			(xy 276.754771 -57.857622) (xy 276.809273 -57.857622) (xy 276.863221 -57.865378) (xy 276.915516 -57.880733)
			(xy 276.965093 -57.903375) (xy 277.010943 -57.932841) (xy 277.052134 -57.968532) (xy 277.087825 -58.009723)
			(xy 277.117291 -58.055573) (xy 277.124918 -58.072274) (xy 284.193486 -58.072274) (xy 284.197557 -58.016652)
			(xy 284.209683 -57.962215) (xy 284.229606 -57.910124) (xy 284.256902 -57.861489) (xy 284.290988 -57.817346)
			(xy 284.331137 -57.778637) (xy 284.376495 -57.746186) (xy 284.426095 -57.720685) (xy 284.478879 -57.702678)
			(xy 284.533722 -57.692548) (xy 284.589456 -57.690511) (xy 284.644893 -57.696611) (xy 284.69885 -57.710717)
			(xy 284.750179 -57.732529) (xy 284.797785 -57.761583) (xy 284.840653 -57.797258) (xy 284.87787 -57.838795)
			(xy 284.908643 -57.885308) (xy 284.932315 -57.935805) (xy 284.948383 -57.989212) (xy 284.956503 -58.044388)
			(xy 284.957012 -58.072274) (xy 284.956942 -58.076084) (xy 289.557966 -58.076084) (xy 289.562037 -58.020462)
			(xy 289.574163 -57.966025) (xy 289.594086 -57.913934) (xy 289.621382 -57.865299) (xy 289.655468 -57.821156)
			(xy 289.695617 -57.782447) (xy 289.740975 -57.749996) (xy 289.790575 -57.724495) (xy 289.843359 -57.706488)
			(xy 289.898202 -57.696358) (xy 289.953936 -57.694321) (xy 290.009373 -57.700421) (xy 290.06333 -57.714527)
			(xy 290.114659 -57.736339) (xy 290.162265 -57.765393) (xy 290.205133 -57.801068) (xy 290.24235 -57.842605)
			(xy 290.258686 -57.867296) (xy 291.84295 -57.867296) (xy 291.847021 -57.811674) (xy 291.859147 -57.757237)
			(xy 291.87907 -57.705146) (xy 291.906366 -57.656511) (xy 291.940452 -57.612368) (xy 291.980601 -57.573659)
			(xy 292.025959 -57.541208) (xy 292.075559 -57.515707) (xy 292.128343 -57.4977) (xy 292.183186 -57.48757)
			(xy 292.23892 -57.485533) (xy 292.294357 -57.491633) (xy 292.348314 -57.505739) (xy 292.399643 -57.527551)
			(xy 292.447249 -57.556605) (xy 292.490117 -57.59228) (xy 292.527334 -57.633817) (xy 292.558107 -57.68033)
			(xy 292.581779 -57.730827) (xy 292.597847 -57.784234) (xy 292.605967 -57.83941) (xy 292.606476 -57.867296)
			(xy 292.605967 -57.895182) (xy 292.597847 -57.950358) (xy 292.581779 -58.003765) (xy 292.558107 -58.054262)
			(xy 292.527334 -58.100775) (xy 292.490117 -58.142312) (xy 292.447249 -58.177987) (xy 292.399643 -58.207041)
			(xy 292.348314 -58.228853) (xy 292.294357 -58.242959) (xy 292.23892 -58.249059) (xy 292.183186 -58.247022)
			(xy 292.128343 -58.236892) (xy 292.075559 -58.218885) (xy 292.025959 -58.193384) (xy 291.980601 -58.160933)
			(xy 291.940452 -58.122224) (xy 291.906366 -58.078081) (xy 291.87907 -58.029446) (xy 291.859147 -57.977355)
			(xy 291.847021 -57.922918) (xy 291.84295 -57.867296) (xy 290.258686 -57.867296) (xy 290.273123 -57.889118)
			(xy 290.296795 -57.939615) (xy 290.312863 -57.993022) (xy 290.320983 -58.048198) (xy 290.321492 -58.076084)
			(xy 290.320983 -58.10397) (xy 290.312863 -58.159146) (xy 290.296795 -58.212553) (xy 290.273123 -58.26305)
			(xy 290.24235 -58.309563) (xy 290.205133 -58.3511) (xy 290.162265 -58.386775) (xy 290.114659 -58.415829)
			(xy 290.06333 -58.437641) (xy 290.009373 -58.451747) (xy 289.953936 -58.457847) (xy 289.898202 -58.45581)
			(xy 289.843359 -58.44568) (xy 289.790575 -58.427673) (xy 289.740975 -58.402172) (xy 289.695617 -58.369721)
			(xy 289.655468 -58.331012) (xy 289.621382 -58.286869) (xy 289.594086 -58.238234) (xy 289.574163 -58.186143)
			(xy 289.562037 -58.131706) (xy 289.557966 -58.076084) (xy 284.956942 -58.076084) (xy 284.956503 -58.10016)
			(xy 284.948383 -58.155336) (xy 284.932315 -58.208743) (xy 284.908643 -58.25924) (xy 284.87787 -58.305753)
			(xy 284.840653 -58.34729) (xy 284.797785 -58.382965) (xy 284.750179 -58.412019) (xy 284.69885 -58.433831)
			(xy 284.644893 -58.447937) (xy 284.589456 -58.454037) (xy 284.533722 -58.452) (xy 284.478879 -58.44187)
			(xy 284.426095 -58.423863) (xy 284.376495 -58.398362) (xy 284.331137 -58.365911) (xy 284.290988 -58.327202)
			(xy 284.256902 -58.283059) (xy 284.229606 -58.234424) (xy 284.209683 -58.182333) (xy 284.197557 -58.127896)
			(xy 284.193486 -58.072274) (xy 277.124918 -58.072274) (xy 277.139933 -58.10515) (xy 277.155288 -58.157445)
			(xy 277.163044 -58.211393) (xy 277.16353 -58.238644) (xy 277.163072 -58.265978) (xy 277.155263 -58.320087)
			(xy 277.139811 -58.372526) (xy 277.117034 -58.422224) (xy 277.087396 -58.468162) (xy 277.069804 -58.489088)
			(xy 277.06955 -58.489342) (xy 277.069296 -58.489596) (xy 277.063705 -58.496679) (xy 277.057461 -58.513599)
			(xy 277.057104 -58.522616) (xy 277.057104 -58.561224) (xy 290.76218 -58.561224) (xy 290.766251 -58.505602)
			(xy 290.778377 -58.451165) (xy 290.7983 -58.399074) (xy 290.825596 -58.350439) (xy 290.859682 -58.306296)
			(xy 290.899831 -58.267587) (xy 290.945189 -58.235136) (xy 290.994789 -58.209635) (xy 291.047573 -58.191628)
			(xy 291.102416 -58.181498) (xy 291.15815 -58.179461) (xy 291.213587 -58.185561) (xy 291.267544 -58.199667)
			(xy 291.318873 -58.221479) (xy 291.366479 -58.250533) (xy 291.409347 -58.286208) (xy 291.446564 -58.327745)
			(xy 291.477337 -58.374258) (xy 291.501009 -58.424755) (xy 291.508519 -58.449718) (xy 293.00881 -58.449718)
			(xy 293.012881 -58.394096) (xy 293.025007 -58.339659) (xy 293.04493 -58.287568) (xy 293.072226 -58.238933)
			(xy 293.106312 -58.19479) (xy 293.146461 -58.156081) (xy 293.191819 -58.12363) (xy 293.241419 -58.098129)
			(xy 293.294203 -58.080122) (xy 293.349046 -58.069992) (xy 293.40478 -58.067955) (xy 293.460217 -58.074055)
			(xy 293.514174 -58.088161) (xy 293.565503 -58.109973) (xy 293.613109 -58.139027) (xy 293.655977 -58.174702)
			(xy 293.693194 -58.216239) (xy 293.723967 -58.262752) (xy 293.747639 -58.313249) (xy 293.763707 -58.366656)
			(xy 293.771827 -58.421832) (xy 293.772336 -58.449718) (xy 293.771827 -58.477604) (xy 293.763707 -58.53278)
			(xy 293.747639 -58.586187) (xy 293.723967 -58.636684) (xy 293.693194 -58.683197) (xy 293.655977 -58.724734)
			(xy 293.647962 -58.731404) (xy 297.720512 -58.731404) (xy 297.721012 -58.704071) (xy 297.728813 -58.649966)
			(xy 297.744256 -58.597527) (xy 297.767024 -58.547829) (xy 297.796651 -58.501888) (xy 297.814238 -58.48096)
			(xy 297.814492 -58.480706) (xy 297.814746 -58.480452) (xy 297.820323 -58.473359) (xy 297.826574 -58.456447)
			(xy 297.826938 -58.447432) (xy 297.826938 -58.380376) (xy 297.826584 -58.371359) (xy 297.820334 -58.354442)
			(xy 297.814746 -58.347356) (xy 297.814492 -58.347102) (xy 297.814238 -58.346848) (xy 297.796643 -58.325922)
			(xy 297.766992 -58.279989) (xy 297.744205 -58.230292) (xy 297.728749 -58.17785) (xy 297.720941 -58.123739)
			(xy 297.72094 -58.069067) (xy 297.728748 -58.014955) (xy 297.744203 -57.962513) (xy 297.766989 -57.912816)
			(xy 297.796639 -57.866883) (xy 297.814238 -57.84596) (xy 297.814492 -57.845706) (xy 297.814746 -57.845452)
			(xy 297.820323 -57.838359) (xy 297.826574 -57.821447) (xy 297.826938 -57.812432) (xy 297.826938 -57.745376)
			(xy 297.826584 -57.736359) (xy 297.820334 -57.719442) (xy 297.814746 -57.712356) (xy 297.814492 -57.712102)
			(xy 297.814238 -57.711848) (xy 297.796643 -57.690922) (xy 297.766992 -57.644989) (xy 297.744205 -57.595292)
			(xy 297.728749 -57.54285) (xy 297.720941 -57.488739) (xy 297.72094 -57.434067) (xy 297.728748 -57.379955)
			(xy 297.744203 -57.327513) (xy 297.766989 -57.277816) (xy 297.796639 -57.231883) (xy 297.814238 -57.21096)
			(xy 297.814492 -57.210706) (xy 297.814746 -57.210452) (xy 297.820323 -57.203359) (xy 297.826574 -57.186447)
			(xy 297.826938 -57.177432) (xy 297.826938 -57.110376) (xy 297.826584 -57.101359) (xy 297.820334 -57.084442)
			(xy 297.814746 -57.077356) (xy 297.814492 -57.077102) (xy 297.814238 -57.076848) (xy 297.79666 -57.05591)
			(xy 297.767019 -57.009977) (xy 297.744239 -56.960282) (xy 297.728788 -56.907844) (xy 297.720982 -56.853738)
			(xy 297.720512 -56.826404) (xy 297.720998 -56.799153) (xy 297.728754 -56.745205) (xy 297.744109 -56.69291)
			(xy 297.766751 -56.643333) (xy 297.796217 -56.597483) (xy 297.831908 -56.556292) (xy 297.873099 -56.520601)
			(xy 297.918949 -56.491135) (xy 297.968526 -56.468493) (xy 298.020821 -56.453138) (xy 298.074769 -56.445382)
			(xy 298.129271 -56.445382) (xy 298.183219 -56.453138) (xy 298.235514 -56.468493) (xy 298.285091 -56.491135)
			(xy 298.330941 -56.520601) (xy 298.372132 -56.556292) (xy 298.407823 -56.597483) (xy 298.437289 -56.643333)
			(xy 298.459931 -56.69291) (xy 298.475286 -56.745205) (xy 298.483042 -56.799153) (xy 298.483528 -56.826404)
			(xy 298.483046 -56.853737) (xy 298.475243 -56.907845) (xy 298.459797 -56.960284) (xy 298.437024 -57.009982)
			(xy 298.407391 -57.055921) (xy 298.389802 -57.076848) (xy 298.389548 -57.077102) (xy 298.389294 -57.077356)
			(xy 298.383719 -57.084451) (xy 298.377466 -57.101361) (xy 298.377102 -57.110376) (xy 298.377102 -57.177432)
			(xy 298.377443 -57.18645) (xy 298.383702 -57.203367) (xy 298.389294 -57.210452) (xy 298.389548 -57.210706)
			(xy 298.389802 -57.21096) (xy 298.407407 -57.231878) (xy 298.437063 -57.277811) (xy 298.459853 -57.327509)
			(xy 298.475311 -57.379952) (xy 298.48312 -57.434066) (xy 298.483119 -57.48874) (xy 298.47531 -57.542854)
			(xy 298.459851 -57.595297) (xy 298.43706 -57.644994) (xy 298.407404 -57.690926) (xy 298.389802 -57.711848)
			(xy 298.389548 -57.712102) (xy 298.389294 -57.712356) (xy 298.383719 -57.719451) (xy 298.377466 -57.736361)
			(xy 298.377102 -57.745376) (xy 298.377102 -57.812432) (xy 298.377443 -57.82145) (xy 298.383702 -57.838367)
			(xy 298.389294 -57.845452) (xy 298.389548 -57.845706) (xy 298.389802 -57.84596) (xy 298.407407 -57.866878)
			(xy 298.437063 -57.912811) (xy 298.459853 -57.962509) (xy 298.475311 -58.014952) (xy 298.48312 -58.069066)
			(xy 298.483119 -58.12374) (xy 298.47531 -58.177854) (xy 298.459851 -58.230297) (xy 298.43706 -58.279994)
			(xy 298.407404 -58.325926) (xy 298.389802 -58.346848) (xy 298.389548 -58.347102) (xy 298.389294 -58.347356)
			(xy 298.383719 -58.354451) (xy 298.377466 -58.371361) (xy 298.377102 -58.380376) (xy 298.377102 -58.447432)
			(xy 298.377443 -58.45645) (xy 298.383702 -58.473367) (xy 298.389294 -58.480452) (xy 298.389548 -58.480706)
			(xy 298.389802 -58.48096) (xy 298.407389 -58.50189) (xy 298.437028 -58.547826) (xy 298.459806 -58.597522)
			(xy 298.475255 -58.649962) (xy 298.483059 -58.70407) (xy 298.483528 -58.731404) (xy 298.483042 -58.758655)
			(xy 298.478378 -58.791094) (xy 300.376336 -58.791094) (xy 300.376825 -58.763761) (xy 300.384628 -58.709654)
			(xy 300.400072 -58.657215) (xy 300.422843 -58.607517) (xy 300.452474 -58.561578) (xy 300.470062 -58.54065)
			(xy 300.470316 -58.540396) (xy 300.47057 -58.540142) (xy 300.476153 -58.533054) (xy 300.4824 -58.516138)
			(xy 300.482762 -58.507122) (xy 300.482762 -58.440066) (xy 300.48243 -58.431046) (xy 300.476166 -58.414129)
			(xy 300.47057 -58.407046) (xy 300.470316 -58.406792) (xy 300.470062 -58.406538) (xy 300.452456 -58.385621)
			(xy 300.422804 -58.339687) (xy 300.400016 -58.289988) (xy 300.38456 -58.237545) (xy 300.376752 -58.183432)
			(xy 300.376752 -58.128759) (xy 300.384561 -58.074646) (xy 300.400019 -58.022203) (xy 300.422808 -57.972506)
			(xy 300.452461 -57.926572) (xy 300.470062 -57.90565) (xy 300.470316 -57.905396) (xy 300.47057 -57.905142)
			(xy 300.476153 -57.898054) (xy 300.4824 -57.881138) (xy 300.482762 -57.872122) (xy 300.482762 -57.805066)
			(xy 300.48243 -57.796046) (xy 300.476166 -57.779129) (xy 300.47057 -57.772046) (xy 300.470316 -57.771792)
			(xy 300.470062 -57.771538) (xy 300.452468 -57.750614) (xy 300.422831 -57.704676) (xy 300.400056 -57.654977)
			(xy 300.384608 -57.602537) (xy 300.376805 -57.548428) (xy 300.376336 -57.521094) (xy 300.376336 -57.52084)
			(xy 300.37681 -57.494546) (xy 300.384051 -57.442457) (xy 300.398373 -57.391856) (xy 300.419505 -57.343699)
			(xy 300.447048 -57.298899) (xy 300.48048 -57.258304) (xy 300.499526 -57.24017) (xy 300.506969 -57.232599)
			(xy 300.515496 -57.213181) (xy 300.516036 -57.202578) (xy 300.516036 -57.12841) (xy 300.515602 -57.117781)
			(xy 300.507069 -57.098317) (xy 300.499526 -57.090818) (xy 300.480475 -57.072685) (xy 300.447017 -57.032104)
			(xy 300.419456 -56.987309) (xy 300.398316 -56.93915) (xy 300.383998 -56.888542) (xy 300.376774 -56.836445)
			(xy 300.376336 -56.810148) (xy 300.376336 -56.809894) (xy 300.376822 -56.782643) (xy 300.384578 -56.728695)
			(xy 300.399933 -56.6764) (xy 300.422575 -56.626823) (xy 300.452041 -56.580973) (xy 300.487732 -56.539782)
			(xy 300.528923 -56.504091) (xy 300.574773 -56.474625) (xy 300.62435 -56.451983) (xy 300.676645 -56.436628)
			(xy 300.730593 -56.428872) (xy 300.785095 -56.428872) (xy 300.839043 -56.436628) (xy 300.891338 -56.451983)
			(xy 300.940915 -56.474625) (xy 300.986765 -56.504091) (xy 301.027956 -56.539782) (xy 301.063647 -56.580973)
			(xy 301.093113 -56.626823) (xy 301.115755 -56.6764) (xy 301.13111 -56.728695) (xy 301.138866 -56.782643)
			(xy 301.139352 -56.809894) (xy 301.139352 -56.810148) (xy 301.138941 -56.836445) (xy 301.131688 -56.888536)
			(xy 301.117354 -56.939139) (xy 301.096209 -56.987295) (xy 301.068655 -57.032093) (xy 301.035213 -57.072686)
			(xy 301.016162 -57.090818) (xy 301.008723 -57.098392) (xy 301.000194 -57.117808) (xy 300.999652 -57.12841)
			(xy 300.999652 -57.202578) (xy 301.000096 -57.213206) (xy 301.008623 -57.232669) (xy 301.016162 -57.24017)
			(xy 301.035205 -57.258312) (xy 301.068664 -57.29889) (xy 301.096226 -57.343683) (xy 301.117368 -57.391841)
			(xy 301.131687 -57.442448) (xy 301.1351 -57.467053) (xy 301.318369 -57.467053) (xy 301.318369 -57.412547)
			(xy 301.326127 -57.358596) (xy 301.341483 -57.306299) (xy 301.364126 -57.256719) (xy 301.393595 -57.210866)
			(xy 301.42929 -57.169675) (xy 301.470484 -57.133982) (xy 301.516338 -57.104516) (xy 301.565919 -57.081876)
			(xy 301.618218 -57.066522) (xy 301.672169 -57.058768) (xy 301.699422 -57.058306) (xy 301.699676 -57.058306)
			(xy 301.72597 -57.058779) (xy 301.778059 -57.066021) (xy 301.82866 -57.080344) (xy 301.876816 -57.101477)
			(xy 301.921616 -57.129019) (xy 301.962211 -57.16245) (xy 301.980346 -57.181496) (xy 301.987902 -57.188956)
			(xy 302.007332 -57.19747) (xy 302.017938 -57.198006) (xy 302.092106 -57.198006) (xy 302.102737 -57.19759)
			(xy 302.122201 -57.189045) (xy 302.129698 -57.181496) (xy 302.147818 -57.162431) (xy 302.188402 -57.128976)
			(xy 302.2332 -57.101418) (xy 302.281362 -57.08028) (xy 302.331972 -57.065965) (xy 302.38407 -57.058743)
			(xy 302.410368 -57.058306) (xy 302.410622 -57.058306) (xy 302.437873 -57.058765) (xy 302.491821 -57.066525)
			(xy 302.526973 -57.076848) (xy 303.338484 -57.076848) (xy 303.338959 -57.049514) (xy 303.346767 -56.995408)
			(xy 303.362216 -56.942969) (xy 303.384989 -56.893271) (xy 303.414621 -56.847332) (xy 303.43221 -56.826404)
			(xy 303.432464 -56.82615) (xy 303.432718 -56.825896) (xy 303.438314 -56.818816) (xy 303.444555 -56.801894)
			(xy 303.44491 -56.792876) (xy 303.44491 -56.72582) (xy 303.444541 -56.716804) (xy 303.438302 -56.699887)
			(xy 303.432718 -56.6928) (xy 303.432464 -56.692546) (xy 303.43221 -56.692292) (xy 303.414602 -56.671379)
			(xy 303.384966 -56.625439) (xy 303.362192 -56.575738) (xy 303.346748 -56.523294) (xy 303.33895 -56.469183)
			(xy 303.338484 -56.441848) (xy 303.33897 -56.414597) (xy 303.346726 -56.360649) (xy 303.362081 -56.308354)
			(xy 303.384723 -56.258777) (xy 303.414189 -56.212927) (xy 303.44988 -56.171736) (xy 303.491071 -56.136045)
			(xy 303.536921 -56.106579) (xy 303.586498 -56.083937) (xy 303.638793 -56.068582) (xy 303.692741 -56.060826)
			(xy 303.747243 -56.060826) (xy 303.801191 -56.068582) (xy 303.853486 -56.083937) (xy 303.903063 -56.106579)
			(xy 303.948913 -56.136045) (xy 303.990104 -56.171736) (xy 304.025795 -56.212927) (xy 304.055261 -56.258777)
			(xy 304.077903 -56.308354) (xy 304.091146 -56.353456) (xy 311.141108 -56.353456) (xy 311.145179 -56.297834)
			(xy 311.157305 -56.243397) (xy 311.177228 -56.191306) (xy 311.204524 -56.142671) (xy 311.23861 -56.098528)
			(xy 311.278759 -56.059819) (xy 311.324117 -56.027368) (xy 311.373717 -56.001867) (xy 311.426501 -55.98386)
			(xy 311.481344 -55.97373) (xy 311.537078 -55.971693) (xy 311.592515 -55.977793) (xy 311.646472 -55.991899)
			(xy 311.697801 -56.013711) (xy 311.745407 -56.042765) (xy 311.788275 -56.07844) (xy 311.825492 -56.119977)
			(xy 311.856265 -56.16649) (xy 311.879937 -56.216987) (xy 311.896005 -56.270394) (xy 311.904125 -56.32557)
			(xy 311.904634 -56.353456) (xy 311.904125 -56.381342) (xy 311.896005 -56.436518) (xy 311.879937 -56.489925)
			(xy 311.856265 -56.540422) (xy 311.825492 -56.586935) (xy 311.788275 -56.628472) (xy 311.745407 -56.664147)
			(xy 311.697801 -56.693201) (xy 311.646472 -56.715013) (xy 311.592515 -56.729119) (xy 311.537078 -56.735219)
			(xy 311.481344 -56.733182) (xy 311.426501 -56.723052) (xy 311.373717 -56.705045) (xy 311.324117 -56.679544)
			(xy 311.278759 -56.647093) (xy 311.23861 -56.608384) (xy 311.204524 -56.564241) (xy 311.177228 -56.515606)
			(xy 311.157305 -56.463515) (xy 311.145179 -56.409078) (xy 311.141108 -56.353456) (xy 304.091146 -56.353456)
			(xy 304.093258 -56.360649) (xy 304.101014 -56.414597) (xy 304.1015 -56.441848) (xy 304.101027 -56.469182)
			(xy 304.093219 -56.523288) (xy 304.07777 -56.575727) (xy 304.054996 -56.625425) (xy 304.025363 -56.671364)
			(xy 304.007774 -56.692292) (xy 304.00752 -56.692546) (xy 304.007266 -56.6928) (xy 304.00167 -56.69988)
			(xy 303.99543 -56.716802) (xy 303.995074 -56.72582) (xy 303.995074 -56.792876) (xy 303.995448 -56.801891)
			(xy 304.001684 -56.818808) (xy 304.007266 -56.825896) (xy 304.00752 -56.82615) (xy 304.007774 -56.826404)
			(xy 304.025378 -56.847321) (xy 304.055015 -56.89326) (xy 304.07779 -56.94296) (xy 304.093235 -56.995402)
			(xy 304.101034 -57.049513) (xy 304.1015 -57.076848) (xy 304.101014 -57.104099) (xy 304.093258 -57.158047)
			(xy 304.077903 -57.210342) (xy 304.055261 -57.259919) (xy 304.025795 -57.305769) (xy 303.990104 -57.34696)
			(xy 303.948913 -57.382651) (xy 303.903063 -57.412117) (xy 303.853486 -57.434759) (xy 303.801191 -57.450114)
			(xy 303.747243 -57.45787) (xy 303.692741 -57.45787) (xy 303.638793 -57.450114) (xy 303.586498 -57.434759)
			(xy 303.536921 -57.412117) (xy 303.491071 -57.382651) (xy 303.44988 -57.34696) (xy 303.414189 -57.305769)
			(xy 303.384723 -57.259919) (xy 303.362081 -57.210342) (xy 303.346726 -57.158047) (xy 303.33897 -57.104099)
			(xy 303.338484 -57.076848) (xy 302.526973 -57.076848) (xy 302.544115 -57.081882) (xy 302.593691 -57.104525)
			(xy 302.63954 -57.133993) (xy 302.680729 -57.169686) (xy 302.71642 -57.210877) (xy 302.745885 -57.256728)
			(xy 302.768525 -57.306306) (xy 302.78388 -57.358601) (xy 302.791636 -57.412549) (xy 302.791636 -57.467051)
			(xy 302.789015 -57.48528) (xy 314.80582 -57.48528) (xy 314.809891 -57.429658) (xy 314.822017 -57.375221)
			(xy 314.84194 -57.32313) (xy 314.869236 -57.274495) (xy 314.903322 -57.230352) (xy 314.943471 -57.191643)
			(xy 314.988829 -57.159192) (xy 315.038429 -57.133691) (xy 315.091213 -57.115684) (xy 315.146056 -57.105554)
			(xy 315.20179 -57.103517) (xy 315.257227 -57.109617) (xy 315.311184 -57.123723) (xy 315.362513 -57.145535)
			(xy 315.410119 -57.174589) (xy 315.452987 -57.210264) (xy 315.490204 -57.251801) (xy 315.520977 -57.298314)
			(xy 315.544649 -57.348811) (xy 315.560717 -57.402218) (xy 315.568837 -57.457394) (xy 315.569346 -57.48528)
			(xy 315.568837 -57.513166) (xy 315.560717 -57.568342) (xy 315.544649 -57.621749) (xy 315.520977 -57.672246)
			(xy 315.490204 -57.718759) (xy 315.452987 -57.760296) (xy 315.410119 -57.795971) (xy 315.362513 -57.825025)
			(xy 315.311184 -57.846837) (xy 315.257227 -57.860943) (xy 315.20179 -57.867043) (xy 315.146056 -57.865006)
			(xy 315.091213 -57.854876) (xy 315.038429 -57.836869) (xy 314.988829 -57.811368) (xy 314.943471 -57.778917)
			(xy 314.903322 -57.740208) (xy 314.869236 -57.696065) (xy 314.84194 -57.64743) (xy 314.822017 -57.595339)
			(xy 314.809891 -57.540902) (xy 314.80582 -57.48528) (xy 302.789015 -57.48528) (xy 302.78388 -57.520999)
			(xy 302.768525 -57.573294) (xy 302.745885 -57.622872) (xy 302.71642 -57.668723) (xy 302.680729 -57.709914)
			(xy 302.63954 -57.745607) (xy 302.593691 -57.775075) (xy 302.544115 -57.797718) (xy 302.491821 -57.813075)
			(xy 302.437873 -57.820835) (xy 302.410622 -57.821322) (xy 302.410368 -57.821322) (xy 302.384073 -57.820878)
			(xy 302.331984 -57.813628) (xy 302.281382 -57.799299) (xy 302.233226 -57.778161) (xy 302.188427 -57.750614)
			(xy 302.147832 -57.717179) (xy 302.129698 -57.698132) (xy 302.122122 -57.690696) (xy 302.102708 -57.682167)
			(xy 302.092106 -57.681622) (xy 302.017938 -57.681622) (xy 302.007302 -57.681999) (xy 301.987838 -57.69057)
			(xy 301.980346 -57.698132) (xy 301.962191 -57.717161) (xy 301.921616 -57.750623) (xy 301.876826 -57.778187)
			(xy 301.828671 -57.799332) (xy 301.778066 -57.813654) (xy 301.725972 -57.820882) (xy 301.699676 -57.821322)
			(xy 301.699422 -57.821322) (xy 301.672169 -57.820832) (xy 301.618218 -57.813078) (xy 301.565919 -57.797724)
			(xy 301.516338 -57.775084) (xy 301.470484 -57.745618) (xy 301.42929 -57.709925) (xy 301.393595 -57.668734)
			(xy 301.364126 -57.622881) (xy 301.341483 -57.573301) (xy 301.326127 -57.521004) (xy 301.318369 -57.467053)
			(xy 301.1351 -57.467053) (xy 301.138913 -57.494543) (xy 301.139352 -57.52084) (xy 301.139352 -57.521094)
			(xy 301.138859 -57.548427) (xy 301.131058 -57.602534) (xy 301.115614 -57.654973) (xy 301.092844 -57.704671)
			(xy 301.063214 -57.75061) (xy 301.045626 -57.771538) (xy 301.045372 -57.771792) (xy 301.045118 -57.772046)
			(xy 301.03955 -57.779146) (xy 301.033292 -57.796052) (xy 301.032926 -57.805066) (xy 301.032926 -57.872122)
			(xy 301.033267 -57.881141) (xy 301.039525 -57.898058) (xy 301.045118 -57.905142) (xy 301.045372 -57.905396)
			(xy 301.045626 -57.90565) (xy 301.063221 -57.926577) (xy 301.092874 -57.972509) (xy 301.115664 -58.022205)
			(xy 301.131121 -58.074647) (xy 301.138931 -58.128759) (xy 301.138931 -58.183432) (xy 301.131123 -58.237544)
			(xy 301.115667 -58.289986) (xy 301.092879 -58.339683) (xy 301.063226 -58.385616) (xy 301.045626 -58.406538)
			(xy 301.045372 -58.406792) (xy 301.045118 -58.407046) (xy 301.03955 -58.414146) (xy 301.033292 -58.431052)
			(xy 301.032926 -58.440066) (xy 301.032926 -58.507122) (xy 301.033267 -58.516141) (xy 301.039525 -58.533058)
			(xy 301.045118 -58.540142) (xy 301.045372 -58.540396) (xy 301.045626 -58.54065) (xy 301.063213 -58.56158)
			(xy 301.092851 -58.607517) (xy 301.115628 -58.657213) (xy 301.131077 -58.709652) (xy 301.138882 -58.76376)
			(xy 301.139352 -58.791094) (xy 301.138866 -58.818345) (xy 301.13111 -58.872293) (xy 301.130713 -58.873644)
			(xy 302.400462 -58.873644) (xy 302.400915 -58.84631) (xy 302.408726 -58.792201) (xy 302.424178 -58.739761)
			(xy 302.446957 -58.690064) (xy 302.476596 -58.644126) (xy 302.494188 -58.6232) (xy 302.494442 -58.622946)
			(xy 302.494696 -58.622692) (xy 302.500292 -58.615612) (xy 302.506533 -58.59869) (xy 302.506888 -58.589672)
			(xy 302.506888 -58.522616) (xy 302.506526 -58.5136) (xy 302.500282 -58.496682) (xy 302.494696 -58.489596)
			(xy 302.494442 -58.489342) (xy 302.494188 -58.489088) (xy 302.476575 -58.468179) (xy 302.44694 -58.422237)
			(xy 302.424168 -58.372535) (xy 302.408725 -58.320091) (xy 302.400927 -58.265979) (xy 302.400462 -58.238644)
			(xy 302.400948 -58.211393) (xy 302.408704 -58.157445) (xy 302.424059 -58.10515) (xy 302.446701 -58.055573)
			(xy 302.476167 -58.009723) (xy 302.511858 -57.968532) (xy 302.553049 -57.932841) (xy 302.598899 -57.903375)
			(xy 302.648476 -57.880733) (xy 302.700771 -57.865378) (xy 302.754719 -57.857622) (xy 302.809221 -57.857622)
			(xy 302.863169 -57.865378) (xy 302.915464 -57.880733) (xy 302.965041 -57.903375) (xy 303.010891 -57.932841)
			(xy 303.052082 -57.968532) (xy 303.087773 -58.009723) (xy 303.117239 -58.055573) (xy 303.124866 -58.072274)
			(xy 310.193434 -58.072274) (xy 310.197505 -58.016652) (xy 310.209631 -57.962215) (xy 310.229554 -57.910124)
			(xy 310.25685 -57.861489) (xy 310.290936 -57.817346) (xy 310.331085 -57.778637) (xy 310.376443 -57.746186)
			(xy 310.426043 -57.720685) (xy 310.478827 -57.702678) (xy 310.53367 -57.692548) (xy 310.589404 -57.690511)
			(xy 310.644841 -57.696611) (xy 310.698798 -57.710717) (xy 310.750127 -57.732529) (xy 310.797733 -57.761583)
			(xy 310.840601 -57.797258) (xy 310.877818 -57.838795) (xy 310.908591 -57.885308) (xy 310.932263 -57.935805)
			(xy 310.948331 -57.989212) (xy 310.956451 -58.044388) (xy 310.95696 -58.072274) (xy 310.95689 -58.076084)
			(xy 315.557914 -58.076084) (xy 315.561985 -58.020462) (xy 315.574111 -57.966025) (xy 315.594034 -57.913934)
			(xy 315.62133 -57.865299) (xy 315.655416 -57.821156) (xy 315.695565 -57.782447) (xy 315.740923 -57.749996)
			(xy 315.790523 -57.724495) (xy 315.843307 -57.706488) (xy 315.89815 -57.696358) (xy 315.953884 -57.694321)
			(xy 316.009321 -57.700421) (xy 316.063278 -57.714527) (xy 316.114607 -57.736339) (xy 316.162213 -57.765393)
			(xy 316.205081 -57.801068) (xy 316.242298 -57.842605) (xy 316.258634 -57.867296) (xy 317.842898 -57.867296)
			(xy 317.846969 -57.811674) (xy 317.859095 -57.757237) (xy 317.879018 -57.705146) (xy 317.906314 -57.656511)
			(xy 317.9404 -57.612368) (xy 317.980549 -57.573659) (xy 318.025907 -57.541208) (xy 318.075507 -57.515707)
			(xy 318.128291 -57.4977) (xy 318.183134 -57.48757) (xy 318.238868 -57.485533) (xy 318.294305 -57.491633)
			(xy 318.348262 -57.505739) (xy 318.399591 -57.527551) (xy 318.447197 -57.556605) (xy 318.490065 -57.59228)
			(xy 318.527282 -57.633817) (xy 318.558055 -57.68033) (xy 318.581727 -57.730827) (xy 318.597795 -57.784234)
			(xy 318.605915 -57.83941) (xy 318.606424 -57.867296) (xy 318.605915 -57.895182) (xy 318.597795 -57.950358)
			(xy 318.581727 -58.003765) (xy 318.558055 -58.054262) (xy 318.527282 -58.100775) (xy 318.490065 -58.142312)
			(xy 318.447197 -58.177987) (xy 318.399591 -58.207041) (xy 318.348262 -58.228853) (xy 318.294305 -58.242959)
			(xy 318.238868 -58.249059) (xy 318.183134 -58.247022) (xy 318.128291 -58.236892) (xy 318.075507 -58.218885)
			(xy 318.025907 -58.193384) (xy 317.980549 -58.160933) (xy 317.9404 -58.122224) (xy 317.906314 -58.078081)
			(xy 317.879018 -58.029446) (xy 317.859095 -57.977355) (xy 317.846969 -57.922918) (xy 317.842898 -57.867296)
			(xy 316.258634 -57.867296) (xy 316.273071 -57.889118) (xy 316.296743 -57.939615) (xy 316.312811 -57.993022)
			(xy 316.320931 -58.048198) (xy 316.32144 -58.076084) (xy 316.320931 -58.10397) (xy 316.312811 -58.159146)
			(xy 316.296743 -58.212553) (xy 316.273071 -58.26305) (xy 316.242298 -58.309563) (xy 316.205081 -58.3511)
			(xy 316.162213 -58.386775) (xy 316.114607 -58.415829) (xy 316.063278 -58.437641) (xy 316.009321 -58.451747)
			(xy 315.953884 -58.457847) (xy 315.89815 -58.45581) (xy 315.843307 -58.44568) (xy 315.790523 -58.427673)
			(xy 315.740923 -58.402172) (xy 315.695565 -58.369721) (xy 315.655416 -58.331012) (xy 315.62133 -58.286869)
			(xy 315.594034 -58.238234) (xy 315.574111 -58.186143) (xy 315.561985 -58.131706) (xy 315.557914 -58.076084)
			(xy 310.95689 -58.076084) (xy 310.956451 -58.10016) (xy 310.948331 -58.155336) (xy 310.932263 -58.208743)
			(xy 310.908591 -58.25924) (xy 310.877818 -58.305753) (xy 310.840601 -58.34729) (xy 310.797733 -58.382965)
			(xy 310.750127 -58.412019) (xy 310.698798 -58.433831) (xy 310.644841 -58.447937) (xy 310.589404 -58.454037)
			(xy 310.53367 -58.452) (xy 310.478827 -58.44187) (xy 310.426043 -58.423863) (xy 310.376443 -58.398362)
			(xy 310.331085 -58.365911) (xy 310.290936 -58.327202) (xy 310.25685 -58.283059) (xy 310.229554 -58.234424)
			(xy 310.209631 -58.182333) (xy 310.197505 -58.127896) (xy 310.193434 -58.072274) (xy 303.124866 -58.072274)
			(xy 303.139881 -58.10515) (xy 303.155236 -58.157445) (xy 303.162992 -58.211393) (xy 303.163478 -58.238644)
			(xy 303.163008 -58.265978) (xy 303.1552 -58.320085) (xy 303.139751 -58.372524) (xy 303.116976 -58.422222)
			(xy 303.087342 -58.468161) (xy 303.069752 -58.489088) (xy 303.069498 -58.489342) (xy 303.069244 -58.489596)
			(xy 303.063646 -58.496675) (xy 303.057408 -58.513598) (xy 303.057052 -58.522616) (xy 303.057052 -58.561224)
			(xy 316.762128 -58.561224) (xy 316.766199 -58.505602) (xy 316.778325 -58.451165) (xy 316.798248 -58.399074)
			(xy 316.825544 -58.350439) (xy 316.85963 -58.306296) (xy 316.899779 -58.267587) (xy 316.945137 -58.235136)
			(xy 316.994737 -58.209635) (xy 317.047521 -58.191628) (xy 317.102364 -58.181498) (xy 317.158098 -58.179461)
			(xy 317.213535 -58.185561) (xy 317.267492 -58.199667) (xy 317.318821 -58.221479) (xy 317.366427 -58.250533)
			(xy 317.409295 -58.286208) (xy 317.446512 -58.327745) (xy 317.477285 -58.374258) (xy 317.500957 -58.424755)
			(xy 317.508467 -58.449718) (xy 319.008758 -58.449718) (xy 319.012829 -58.394096) (xy 319.024955 -58.339659)
			(xy 319.044878 -58.287568) (xy 319.072174 -58.238933) (xy 319.10626 -58.19479) (xy 319.146409 -58.156081)
			(xy 319.191767 -58.12363) (xy 319.241367 -58.098129) (xy 319.294151 -58.080122) (xy 319.348994 -58.069992)
			(xy 319.404728 -58.067955) (xy 319.460165 -58.074055) (xy 319.514122 -58.088161) (xy 319.565451 -58.109973)
			(xy 319.613057 -58.139027) (xy 319.655925 -58.174702) (xy 319.693142 -58.216239) (xy 319.723915 -58.262752)
			(xy 319.747587 -58.313249) (xy 319.763655 -58.366656) (xy 319.771775 -58.421832) (xy 319.772284 -58.449718)
			(xy 319.771775 -58.477604) (xy 319.763655 -58.53278) (xy 319.747587 -58.586187) (xy 319.723915 -58.636684)
			(xy 319.693142 -58.683197) (xy 319.655925 -58.724734) (xy 319.64791 -58.731404) (xy 323.72046 -58.731404)
			(xy 323.720949 -58.704071) (xy 323.728751 -58.649964) (xy 323.744195 -58.597525) (xy 323.766966 -58.547827)
			(xy 323.796597 -58.501887) (xy 323.814186 -58.48096) (xy 323.81444 -58.480706) (xy 323.814694 -58.480452)
			(xy 323.820264 -58.473354) (xy 323.826521 -58.456446) (xy 323.826886 -58.447432) (xy 323.826886 -58.380376)
			(xy 323.826543 -58.371358) (xy 323.820286 -58.354441) (xy 323.814694 -58.347356) (xy 323.81444 -58.347102)
			(xy 323.814186 -58.346848) (xy 323.796589 -58.325923) (xy 323.766934 -58.279991) (xy 323.744144 -58.230294)
			(xy 323.728686 -58.177852) (xy 323.720877 -58.12374) (xy 323.720876 -58.069066) (xy 323.728685 -58.014954)
			(xy 323.744142 -57.962511) (xy 323.766931 -57.912814) (xy 323.796585 -57.866882) (xy 323.814186 -57.84596)
			(xy 323.81444 -57.845706) (xy 323.814694 -57.845452) (xy 323.820264 -57.838354) (xy 323.826521 -57.821446)
			(xy 323.826886 -57.812432) (xy 323.826886 -57.745376) (xy 323.826543 -57.736358) (xy 323.820286 -57.719441)
			(xy 323.814694 -57.712356) (xy 323.81444 -57.712102) (xy 323.814186 -57.711848) (xy 323.796589 -57.690923)
			(xy 323.766934 -57.644991) (xy 323.744144 -57.595294) (xy 323.728686 -57.542852) (xy 323.720877 -57.48874)
			(xy 323.720876 -57.434066) (xy 323.728685 -57.379954) (xy 323.744142 -57.327511) (xy 323.766931 -57.277814)
			(xy 323.796585 -57.231882) (xy 323.814186 -57.21096) (xy 323.81444 -57.210706) (xy 323.814694 -57.210452)
			(xy 323.820264 -57.203354) (xy 323.826521 -57.186446) (xy 323.826886 -57.177432) (xy 323.826886 -57.110376)
			(xy 323.826543 -57.101358) (xy 323.820286 -57.084441) (xy 323.814694 -57.077356) (xy 323.81444 -57.077102)
			(xy 323.814186 -57.076848) (xy 323.7966 -57.055917) (xy 323.766962 -57.009981) (xy 323.744184 -56.960285)
			(xy 323.728735 -56.907845) (xy 323.72093 -56.853738) (xy 323.72046 -56.826404) (xy 323.720946 -56.799153)
			(xy 323.728702 -56.745205) (xy 323.744057 -56.69291) (xy 323.766699 -56.643333) (xy 323.796165 -56.597483)
			(xy 323.831856 -56.556292) (xy 323.873047 -56.520601) (xy 323.918897 -56.491135) (xy 323.968474 -56.468493)
			(xy 324.020769 -56.453138) (xy 324.074717 -56.445382) (xy 324.129219 -56.445382) (xy 324.183167 -56.453138)
			(xy 324.235462 -56.468493) (xy 324.285039 -56.491135) (xy 324.330889 -56.520601) (xy 324.37208 -56.556292)
			(xy 324.407771 -56.597483) (xy 324.437237 -56.643333) (xy 324.459879 -56.69291) (xy 324.475234 -56.745205)
			(xy 324.48299 -56.799153) (xy 324.483476 -56.826404) (xy 324.482983 -56.853737) (xy 324.475181 -56.907843)
			(xy 324.459737 -56.960282) (xy 324.436967 -57.00998) (xy 324.407338 -57.05592) (xy 324.38975 -57.076848)
			(xy 324.389496 -57.077102) (xy 324.389242 -57.077356) (xy 324.383661 -57.084446) (xy 324.377412 -57.10136)
			(xy 324.37705 -57.110376) (xy 324.37705 -57.177432) (xy 324.377381 -57.186452) (xy 324.383645 -57.203369)
			(xy 324.389242 -57.210452) (xy 324.389496 -57.210706) (xy 324.38975 -57.21096) (xy 324.407353 -57.231879)
			(xy 324.437005 -57.277813) (xy 324.459792 -57.327511) (xy 324.475248 -57.379954) (xy 324.483056 -57.434067)
			(xy 324.483056 -57.48874) (xy 324.475247 -57.542852) (xy 324.45979 -57.595295) (xy 324.437002 -57.644992)
			(xy 324.40735 -57.690926) (xy 324.38975 -57.711848) (xy 324.389496 -57.712102) (xy 324.389242 -57.712356)
			(xy 324.383661 -57.719446) (xy 324.377412 -57.73636) (xy 324.37705 -57.745376) (xy 324.37705 -57.812432)
			(xy 324.377381 -57.821452) (xy 324.383645 -57.838369) (xy 324.389242 -57.845452) (xy 324.389496 -57.845706)
			(xy 324.38975 -57.84596) (xy 324.407353 -57.866879) (xy 324.437005 -57.912813) (xy 324.459792 -57.962511)
			(xy 324.475248 -58.014954) (xy 324.483056 -58.069067) (xy 324.483056 -58.12374) (xy 324.475247 -58.177852)
			(xy 324.45979 -58.230295) (xy 324.437002 -58.279992) (xy 324.40735 -58.325926) (xy 324.38975 -58.346848)
			(xy 324.389496 -58.347102) (xy 324.389242 -58.347356) (xy 324.383661 -58.354446) (xy 324.377412 -58.37136)
			(xy 324.37705 -58.380376) (xy 324.37705 -58.447432) (xy 324.377381 -58.456452) (xy 324.383645 -58.473369)
			(xy 324.389242 -58.480452) (xy 324.389496 -58.480706) (xy 324.38975 -58.48096) (xy 324.407345 -58.501884)
			(xy 324.436981 -58.547822) (xy 324.459756 -58.59752) (xy 324.475204 -58.649961) (xy 324.483007 -58.70407)
			(xy 324.483476 -58.731404) (xy 324.48299 -58.758655) (xy 324.478326 -58.791094) (xy 326.376284 -58.791094)
			(xy 326.376785 -58.763761) (xy 326.384587 -58.709656) (xy 326.40003 -58.657217) (xy 326.422797 -58.607519)
			(xy 326.452424 -58.561579) (xy 326.47001 -58.54065) (xy 326.470264 -58.540396) (xy 326.470518 -58.540142)
			(xy 326.476095 -58.533049) (xy 326.482347 -58.516137) (xy 326.48271 -58.507122) (xy 326.48271 -58.440066)
			(xy 326.482367 -58.431048) (xy 326.47611 -58.414131) (xy 326.470518 -58.407046) (xy 326.470264 -58.406792)
			(xy 326.47001 -58.406538) (xy 326.452402 -58.385621) (xy 326.422746 -58.339689) (xy 326.399955 -58.289991)
			(xy 326.384497 -58.237547) (xy 326.376688 -58.183433) (xy 326.376689 -58.128758) (xy 326.384499 -58.074644)
			(xy 326.399959 -58.022201) (xy 326.422751 -57.972504) (xy 326.452407 -57.926571) (xy 326.47001 -57.90565)
			(xy 326.470264 -57.905396) (xy 326.470518 -57.905142) (xy 326.476095 -57.898049) (xy 326.482347 -57.881137)
			(xy 326.48271 -57.872122) (xy 326.48271 -57.805066) (xy 326.482367 -57.796048) (xy 326.47611 -57.779131)
			(xy 326.470518 -57.772046) (xy 326.470264 -57.771792) (xy 326.47001 -57.771538) (xy 326.452423 -57.750608)
			(xy 326.422784 -57.704672) (xy 326.400006 -57.654975) (xy 326.384557 -57.602536) (xy 326.376753 -57.548428)
			(xy 326.376284 -57.521094) (xy 326.376284 -57.52084) (xy 326.376775 -57.494546) (xy 326.384014 -57.442459)
			(xy 326.398334 -57.391859) (xy 326.419464 -57.343703) (xy 326.447003 -57.298902) (xy 326.48043 -57.258305)
			(xy 326.499474 -57.24017) (xy 326.506924 -57.232605) (xy 326.515445 -57.213182) (xy 326.515984 -57.202578)
			(xy 326.515984 -57.12841) (xy 326.515565 -57.117779) (xy 326.507023 -57.098314) (xy 326.499474 -57.090818)
			(xy 326.480413 -57.072695) (xy 326.446958 -57.032111) (xy 326.4194 -56.987313) (xy 326.398262 -56.939152)
			(xy 326.383945 -56.888543) (xy 326.376722 -56.836446) (xy 326.376284 -56.810148) (xy 326.376284 -56.809894)
			(xy 326.37677 -56.782643) (xy 326.384526 -56.728695) (xy 326.399881 -56.6764) (xy 326.422523 -56.626823)
			(xy 326.451989 -56.580973) (xy 326.48768 -56.539782) (xy 326.528871 -56.504091) (xy 326.574721 -56.474625)
			(xy 326.624298 -56.451983) (xy 326.676593 -56.436628) (xy 326.730541 -56.428872) (xy 326.785043 -56.428872)
			(xy 326.838991 -56.436628) (xy 326.891286 -56.451983) (xy 326.940863 -56.474625) (xy 326.986713 -56.504091)
			(xy 327.027904 -56.539782) (xy 327.063595 -56.580973) (xy 327.093061 -56.626823) (xy 327.115703 -56.6764)
			(xy 327.131058 -56.728695) (xy 327.138814 -56.782643) (xy 327.1393 -56.809894) (xy 327.1393 -56.810148)
			(xy 327.138873 -56.836444) (xy 327.131621 -56.888534) (xy 327.117289 -56.939136) (xy 327.096148 -56.987292)
			(xy 327.068597 -57.032091) (xy 327.035159 -57.072684) (xy 327.01611 -57.090818) (xy 327.008664 -57.098385)
			(xy 327.000141 -57.117806) (xy 326.9996 -57.12841) (xy 326.9996 -57.202578) (xy 327.00003 -57.213208)
			(xy 327.008565 -57.232672) (xy 327.01611 -57.24017) (xy 327.035162 -57.258302) (xy 327.068618 -57.298884)
			(xy 327.096178 -57.343679) (xy 327.117318 -57.391839) (xy 327.131636 -57.442447) (xy 327.135048 -57.467049)
			(xy 327.318392 -57.467049) (xy 327.318392 -57.412551) (xy 327.326148 -57.358608) (xy 327.341501 -57.306318)
			(xy 327.364139 -57.256744) (xy 327.393601 -57.210897) (xy 327.429288 -57.169709) (xy 327.470473 -57.134019)
			(xy 327.516318 -57.104553) (xy 327.56589 -57.081911) (xy 327.618179 -57.066554) (xy 327.672121 -57.058794)
			(xy 327.69937 -57.058306) (xy 327.699624 -57.058306) (xy 327.725919 -57.058747) (xy 327.778009 -57.065996)
			(xy 327.828611 -57.080325) (xy 327.876767 -57.101464) (xy 327.921566 -57.129012) (xy 327.96216 -57.162448)
			(xy 327.980294 -57.181496) (xy 327.987869 -57.188933) (xy 328.007285 -57.19746) (xy 328.017886 -57.198006)
			(xy 328.092054 -57.198006) (xy 328.102688 -57.197616) (xy 328.122152 -57.189053) (xy 328.129646 -57.181496)
			(xy 328.147742 -57.162408) (xy 328.188331 -57.128955) (xy 328.233135 -57.1014) (xy 328.281301 -57.080266)
			(xy 328.331915 -57.065956) (xy 328.384017 -57.05874) (xy 328.410316 -57.058306) (xy 328.41057 -57.058306)
			(xy 328.437825 -57.058739) (xy 328.491781 -57.066493) (xy 328.527056 -57.076848) (xy 329.338432 -57.076848)
			(xy 329.338895 -57.049514) (xy 329.346704 -56.995406) (xy 329.362155 -56.942967) (xy 329.384931 -56.893269)
			(xy 329.414567 -56.847331) (xy 329.432158 -56.826404) (xy 329.432412 -56.82615) (xy 329.432666 -56.825896)
			(xy 329.438268 -56.81882) (xy 329.444504 -56.801895) (xy 329.444858 -56.792876) (xy 329.444858 -56.72582)
			(xy 329.4445 -56.716803) (xy 329.438254 -56.699886) (xy 329.432666 -56.6928) (xy 329.432412 -56.692546)
			(xy 329.432158 -56.692292) (xy 329.414542 -56.671385) (xy 329.384908 -56.625443) (xy 329.362137 -56.57574)
			(xy 329.346695 -56.523295) (xy 329.338898 -56.469183) (xy 329.338432 -56.441848) (xy 329.338918 -56.414597)
			(xy 329.346674 -56.360649) (xy 329.362029 -56.308354) (xy 329.384671 -56.258777) (xy 329.414137 -56.212927)
			(xy 329.449828 -56.171736) (xy 329.491019 -56.136045) (xy 329.536869 -56.106579) (xy 329.586446 -56.083937)
			(xy 329.638741 -56.068582) (xy 329.692689 -56.060826) (xy 329.747191 -56.060826) (xy 329.801139 -56.068582)
			(xy 329.853434 -56.083937) (xy 329.903011 -56.106579) (xy 329.948861 -56.136045) (xy 329.990052 -56.171736)
			(xy 330.025743 -56.212927) (xy 330.055209 -56.258777) (xy 330.077851 -56.308354) (xy 330.091094 -56.353456)
			(xy 337.141056 -56.353456) (xy 337.145127 -56.297834) (xy 337.157253 -56.243397) (xy 337.177176 -56.191306)
			(xy 337.204472 -56.142671) (xy 337.238558 -56.098528) (xy 337.278707 -56.059819) (xy 337.324065 -56.027368)
			(xy 337.373665 -56.001867) (xy 337.426449 -55.98386) (xy 337.481292 -55.97373) (xy 337.537026 -55.971693)
			(xy 337.592463 -55.977793) (xy 337.64642 -55.991899) (xy 337.697749 -56.013711) (xy 337.745355 -56.042765)
			(xy 337.788223 -56.07844) (xy 337.82544 -56.119977) (xy 337.856213 -56.16649) (xy 337.879885 -56.216987)
			(xy 337.895953 -56.270394) (xy 337.904073 -56.32557) (xy 337.904582 -56.353456) (xy 337.904073 -56.381342)
			(xy 337.895953 -56.436518) (xy 337.879885 -56.489925) (xy 337.856213 -56.540422) (xy 337.82544 -56.586935)
			(xy 337.788223 -56.628472) (xy 337.745355 -56.664147) (xy 337.697749 -56.693201) (xy 337.64642 -56.715013)
			(xy 337.592463 -56.729119) (xy 337.537026 -56.735219) (xy 337.481292 -56.733182) (xy 337.426449 -56.723052)
			(xy 337.373665 -56.705045) (xy 337.324065 -56.679544) (xy 337.278707 -56.647093) (xy 337.238558 -56.608384)
			(xy 337.204472 -56.564241) (xy 337.177176 -56.515606) (xy 337.157253 -56.463515) (xy 337.145127 -56.409078)
			(xy 337.141056 -56.353456) (xy 330.091094 -56.353456) (xy 330.093206 -56.360649) (xy 330.100962 -56.414597)
			(xy 330.101448 -56.441848) (xy 330.100988 -56.469182) (xy 330.093179 -56.52329) (xy 330.077727 -56.57573)
			(xy 330.05495 -56.625427) (xy 330.025313 -56.671365) (xy 330.007722 -56.692292) (xy 330.007468 -56.692546)
			(xy 330.007214 -56.6928) (xy 330.001623 -56.699884) (xy 329.995378 -56.716803) (xy 329.995022 -56.72582)
			(xy 329.995022 -56.792876) (xy 329.995386 -56.801892) (xy 330.001628 -56.818809) (xy 330.007214 -56.825896)
			(xy 330.007468 -56.82615) (xy 330.007722 -56.826404) (xy 330.025333 -56.847315) (xy 330.054968 -56.893256)
			(xy 330.07774 -56.942958) (xy 330.093184 -56.995402) (xy 330.100982 -57.049513) (xy 330.101448 -57.076848)
			(xy 330.100962 -57.104099) (xy 330.093206 -57.158047) (xy 330.077851 -57.210342) (xy 330.055209 -57.259919)
			(xy 330.025743 -57.305769) (xy 329.990052 -57.34696) (xy 329.948861 -57.382651) (xy 329.903011 -57.412117)
			(xy 329.853434 -57.434759) (xy 329.801139 -57.450114) (xy 329.747191 -57.45787) (xy 329.692689 -57.45787)
			(xy 329.638741 -57.450114) (xy 329.586446 -57.434759) (xy 329.536869 -57.412117) (xy 329.491019 -57.382651)
			(xy 329.449828 -57.34696) (xy 329.414137 -57.305769) (xy 329.384671 -57.259919) (xy 329.362029 -57.210342)
			(xy 329.346674 -57.158047) (xy 329.338918 -57.104099) (xy 329.338432 -57.076848) (xy 328.527056 -57.076848)
			(xy 328.544085 -57.081847) (xy 328.593671 -57.104488) (xy 328.639529 -57.133957) (xy 328.680727 -57.169652)
			(xy 328.716425 -57.210847) (xy 328.745897 -57.256703) (xy 328.768543 -57.306287) (xy 328.783901 -57.358589)
			(xy 328.791659 -57.412545) (xy 328.791659 -57.467055) (xy 328.789039 -57.48528) (xy 352.906074 -57.48528)
			(xy 352.910145 -57.429658) (xy 352.922271 -57.375221) (xy 352.942194 -57.32313) (xy 352.96949 -57.274495)
			(xy 353.003576 -57.230352) (xy 353.043725 -57.191643) (xy 353.089083 -57.159192) (xy 353.138683 -57.133691)
			(xy 353.191467 -57.115684) (xy 353.24631 -57.105554) (xy 353.302044 -57.103517) (xy 353.357481 -57.109617)
			(xy 353.411438 -57.123723) (xy 353.462767 -57.145535) (xy 353.510373 -57.174589) (xy 353.553241 -57.210264)
			(xy 353.590458 -57.251801) (xy 353.621231 -57.298314) (xy 353.644903 -57.348811) (xy 353.660971 -57.402218)
			(xy 353.669091 -57.457394) (xy 353.6696 -57.48528) (xy 353.669091 -57.513166) (xy 353.660971 -57.568342)
			(xy 353.644903 -57.621749) (xy 353.621231 -57.672246) (xy 353.590458 -57.718759) (xy 353.553241 -57.760296)
			(xy 353.510373 -57.795971) (xy 353.462767 -57.825025) (xy 353.411438 -57.846837) (xy 353.357481 -57.860943)
			(xy 353.302044 -57.867043) (xy 353.24631 -57.865006) (xy 353.191467 -57.854876) (xy 353.138683 -57.836869)
			(xy 353.089083 -57.811368) (xy 353.043725 -57.778917) (xy 353.003576 -57.740208) (xy 352.96949 -57.696065)
			(xy 352.942194 -57.64743) (xy 352.922271 -57.595339) (xy 352.910145 -57.540902) (xy 352.906074 -57.48528)
			(xy 328.789039 -57.48528) (xy 328.783901 -57.521011) (xy 328.768543 -57.573313) (xy 328.745897 -57.622897)
			(xy 328.716425 -57.668753) (xy 328.680727 -57.709948) (xy 328.639529 -57.745643) (xy 328.593671 -57.775112)
			(xy 328.544085 -57.797753) (xy 328.491781 -57.813107) (xy 328.437825 -57.820861) (xy 328.41057 -57.821322)
			(xy 328.410316 -57.821322) (xy 328.384022 -57.820846) (xy 328.331934 -57.813603) (xy 328.281334 -57.79928)
			(xy 328.233177 -57.778148) (xy 328.188377 -57.750606) (xy 328.147781 -57.717177) (xy 328.129646 -57.698132)
			(xy 328.122089 -57.690673) (xy 328.10266 -57.682157) (xy 328.092054 -57.681622) (xy 328.017886 -57.681622)
			(xy 328.007253 -57.682026) (xy 327.987788 -57.690578) (xy 327.980294 -57.698132) (xy 327.962164 -57.717187)
			(xy 327.921584 -57.750646) (xy 327.876788 -57.778207) (xy 327.828628 -57.799347) (xy 327.778019 -57.813664)
			(xy 327.725922 -57.820885) (xy 327.699624 -57.821322) (xy 327.69937 -57.821322) (xy 327.672121 -57.820806)
			(xy 327.618179 -57.813046) (xy 327.56589 -57.797689) (xy 327.516318 -57.775047) (xy 327.470473 -57.745581)
			(xy 327.429288 -57.709891) (xy 327.393601 -57.668703) (xy 327.364139 -57.622856) (xy 327.341501 -57.573282)
			(xy 327.326148 -57.520992) (xy 327.318392 -57.467049) (xy 327.135048 -57.467049) (xy 327.138861 -57.494543)
			(xy 327.1393 -57.52084) (xy 327.1393 -57.521094) (xy 327.138795 -57.548426) (xy 327.130995 -57.602532)
			(xy 327.115554 -57.654971) (xy 327.092786 -57.704669) (xy 327.06316 -57.750609) (xy 327.045574 -57.771538)
			(xy 327.04532 -57.771792) (xy 327.045066 -57.772046) (xy 327.039492 -57.779141) (xy 327.033239 -57.796051)
			(xy 327.032874 -57.805066) (xy 327.032874 -57.872122) (xy 327.033226 -57.881139) (xy 327.039478 -57.898056)
			(xy 327.045066 -57.905142) (xy 327.04532 -57.905396) (xy 327.045574 -57.90565) (xy 327.063167 -57.926578)
			(xy 327.092817 -57.972511) (xy 327.115603 -58.022207) (xy 327.131059 -58.074649) (xy 327.138867 -58.12876)
			(xy 327.138868 -58.183431) (xy 327.131061 -58.237542) (xy 327.115606 -58.289984) (xy 327.092821 -58.339681)
			(xy 327.063172 -58.385615) (xy 327.045574 -58.406538) (xy 327.04532 -58.406792) (xy 327.045066 -58.407046)
			(xy 327.039492 -58.414141) (xy 327.033239 -58.431051) (xy 327.032874 -58.440066) (xy 327.032874 -58.507122)
			(xy 327.033226 -58.516139) (xy 327.039478 -58.533056) (xy 327.045066 -58.540142) (xy 327.04532 -58.540396)
			(xy 327.045574 -58.54065) (xy 327.063152 -58.561587) (xy 327.092794 -58.607521) (xy 327.115573 -58.657215)
			(xy 327.131024 -58.709654) (xy 327.13883 -58.76376) (xy 327.1393 -58.791094) (xy 327.138814 -58.818345)
			(xy 327.131058 -58.872293) (xy 327.130661 -58.873644) (xy 328.40041 -58.873644) (xy 328.400876 -58.84631)
			(xy 328.408685 -58.792203) (xy 328.424136 -58.739764) (xy 328.446911 -58.690066) (xy 328.476546 -58.644127)
			(xy 328.494136 -58.6232) (xy 328.49439 -58.622946) (xy 328.494644 -58.622692) (xy 328.500245 -58.615616)
			(xy 328.506482 -58.598691) (xy 328.506836 -58.589672) (xy 328.506836 -58.522616) (xy 328.506463 -58.513601)
			(xy 328.500226 -58.496684) (xy 328.494644 -58.489596) (xy 328.49439 -58.489342) (xy 328.494136 -58.489088)
			(xy 328.47653 -58.468173) (xy 328.446893 -58.422234) (xy 328.424118 -58.372533) (xy 328.408674 -58.32009)
			(xy 328.400876 -58.265979) (xy 328.40041 -58.238644) (xy 328.400896 -58.211393) (xy 328.408652 -58.157445)
			(xy 328.424007 -58.10515) (xy 328.446649 -58.055573) (xy 328.476115 -58.009723) (xy 328.511806 -57.968532)
			(xy 328.552997 -57.932841) (xy 328.598847 -57.903375) (xy 328.648424 -57.880733) (xy 328.700719 -57.865378)
			(xy 328.754667 -57.857622) (xy 328.809169 -57.857622) (xy 328.863117 -57.865378) (xy 328.915412 -57.880733)
			(xy 328.964989 -57.903375) (xy 329.010839 -57.932841) (xy 329.05203 -57.968532) (xy 329.087721 -58.009723)
			(xy 329.117187 -58.055573) (xy 329.124814 -58.072274) (xy 336.193382 -58.072274) (xy 336.197453 -58.016652)
			(xy 336.209579 -57.962215) (xy 336.229502 -57.910124) (xy 336.256798 -57.861489) (xy 336.290884 -57.817346)
			(xy 336.331033 -57.778637) (xy 336.376391 -57.746186) (xy 336.425991 -57.720685) (xy 336.478775 -57.702678)
			(xy 336.533618 -57.692548) (xy 336.589352 -57.690511) (xy 336.644789 -57.696611) (xy 336.698746 -57.710717)
			(xy 336.750075 -57.732529) (xy 336.797681 -57.761583) (xy 336.840549 -57.797258) (xy 336.877766 -57.838795)
			(xy 336.908539 -57.885308) (xy 336.932211 -57.935805) (xy 336.948279 -57.989212) (xy 336.956399 -58.044388)
			(xy 336.956908 -58.072274) (xy 336.956838 -58.076084) (xy 353.658168 -58.076084) (xy 353.662239 -58.020462)
			(xy 353.674365 -57.966025) (xy 353.694288 -57.913934) (xy 353.721584 -57.865299) (xy 353.75567 -57.821156)
			(xy 353.795819 -57.782447) (xy 353.841177 -57.749996) (xy 353.890777 -57.724495) (xy 353.943561 -57.706488)
			(xy 353.998404 -57.696358) (xy 354.054138 -57.694321) (xy 354.109575 -57.700421) (xy 354.163532 -57.714527)
			(xy 354.214861 -57.736339) (xy 354.262467 -57.765393) (xy 354.305335 -57.801068) (xy 354.342552 -57.842605)
			(xy 354.358888 -57.867296) (xy 355.943152 -57.867296) (xy 355.947223 -57.811674) (xy 355.959349 -57.757237)
			(xy 355.979272 -57.705146) (xy 356.006568 -57.656511) (xy 356.040654 -57.612368) (xy 356.080803 -57.573659)
			(xy 356.126161 -57.541208) (xy 356.175761 -57.515707) (xy 356.228545 -57.4977) (xy 356.283388 -57.48757)
			(xy 356.339122 -57.485533) (xy 356.394559 -57.491633) (xy 356.448516 -57.505739) (xy 356.499845 -57.527551)
			(xy 356.547451 -57.556605) (xy 356.590319 -57.59228) (xy 356.627536 -57.633817) (xy 356.658309 -57.68033)
			(xy 356.681981 -57.730827) (xy 356.698049 -57.784234) (xy 356.706169 -57.83941) (xy 356.706678 -57.867296)
			(xy 356.706169 -57.895182) (xy 356.698049 -57.950358) (xy 356.681981 -58.003765) (xy 356.658309 -58.054262)
			(xy 356.627536 -58.100775) (xy 356.590319 -58.142312) (xy 356.547451 -58.177987) (xy 356.499845 -58.207041)
			(xy 356.448516 -58.228853) (xy 356.394559 -58.242959) (xy 356.339122 -58.249059) (xy 356.283388 -58.247022)
			(xy 356.228545 -58.236892) (xy 356.175761 -58.218885) (xy 356.126161 -58.193384) (xy 356.080803 -58.160933)
			(xy 356.040654 -58.122224) (xy 356.006568 -58.078081) (xy 355.979272 -58.029446) (xy 355.959349 -57.977355)
			(xy 355.947223 -57.922918) (xy 355.943152 -57.867296) (xy 354.358888 -57.867296) (xy 354.373325 -57.889118)
			(xy 354.396997 -57.939615) (xy 354.413065 -57.993022) (xy 354.421185 -58.048198) (xy 354.421694 -58.076084)
			(xy 354.421185 -58.10397) (xy 354.413065 -58.159146) (xy 354.396997 -58.212553) (xy 354.373325 -58.26305)
			(xy 354.342552 -58.309563) (xy 354.305335 -58.3511) (xy 354.262467 -58.386775) (xy 354.214861 -58.415829)
			(xy 354.163532 -58.437641) (xy 354.109575 -58.451747) (xy 354.054138 -58.457847) (xy 353.998404 -58.45581)
			(xy 353.943561 -58.44568) (xy 353.890777 -58.427673) (xy 353.841177 -58.402172) (xy 353.795819 -58.369721)
			(xy 353.75567 -58.331012) (xy 353.721584 -58.286869) (xy 353.694288 -58.238234) (xy 353.674365 -58.186143)
			(xy 353.662239 -58.131706) (xy 353.658168 -58.076084) (xy 336.956838 -58.076084) (xy 336.956399 -58.10016)
			(xy 336.948279 -58.155336) (xy 336.932211 -58.208743) (xy 336.908539 -58.25924) (xy 336.877766 -58.305753)
			(xy 336.840549 -58.34729) (xy 336.797681 -58.382965) (xy 336.750075 -58.412019) (xy 336.698746 -58.433831)
			(xy 336.644789 -58.447937) (xy 336.589352 -58.454037) (xy 336.533618 -58.452) (xy 336.478775 -58.44187)
			(xy 336.425991 -58.423863) (xy 336.376391 -58.398362) (xy 336.331033 -58.365911) (xy 336.290884 -58.327202)
			(xy 336.256798 -58.283059) (xy 336.229502 -58.234424) (xy 336.209579 -58.182333) (xy 336.197453 -58.127896)
			(xy 336.193382 -58.072274) (xy 329.124814 -58.072274) (xy 329.139829 -58.10515) (xy 329.155184 -58.157445)
			(xy 329.16294 -58.211393) (xy 329.163426 -58.238644) (xy 329.162969 -58.265978) (xy 329.15516 -58.320087)
			(xy 329.139708 -58.372526) (xy 329.11693 -58.422224) (xy 329.087292 -58.468162) (xy 329.0697 -58.489088)
			(xy 329.069446 -58.489342) (xy 329.069192 -58.489596) (xy 329.0636 -58.496679) (xy 329.057357 -58.513599)
			(xy 329.057 -58.522616) (xy 329.057 -58.561224) (xy 354.862382 -58.561224) (xy 354.866453 -58.505602)
			(xy 354.878579 -58.451165) (xy 354.898502 -58.399074) (xy 354.925798 -58.350439) (xy 354.959884 -58.306296)
			(xy 355.000033 -58.267587) (xy 355.045391 -58.235136) (xy 355.094991 -58.209635) (xy 355.147775 -58.191628)
			(xy 355.202618 -58.181498) (xy 355.258352 -58.179461) (xy 355.313789 -58.185561) (xy 355.367746 -58.199667)
			(xy 355.419075 -58.221479) (xy 355.466681 -58.250533) (xy 355.509549 -58.286208) (xy 355.546766 -58.327745)
			(xy 355.577539 -58.374258) (xy 355.601211 -58.424755) (xy 355.608721 -58.449718) (xy 357.109012 -58.449718)
			(xy 357.113083 -58.394096) (xy 357.125209 -58.339659) (xy 357.145132 -58.287568) (xy 357.172428 -58.238933)
			(xy 357.206514 -58.19479) (xy 357.246663 -58.156081) (xy 357.292021 -58.12363) (xy 357.341621 -58.098129)
			(xy 357.394405 -58.080122) (xy 357.449248 -58.069992) (xy 357.504982 -58.067955) (xy 357.560419 -58.074055)
			(xy 357.614376 -58.088161) (xy 357.665705 -58.109973) (xy 357.713311 -58.139027) (xy 357.756179 -58.174702)
			(xy 357.793396 -58.216239) (xy 357.824169 -58.262752) (xy 357.847841 -58.313249) (xy 357.863909 -58.366656)
			(xy 357.872029 -58.421832) (xy 357.872538 -58.449718) (xy 357.872029 -58.477604) (xy 357.863909 -58.53278)
			(xy 357.847841 -58.586187) (xy 357.824169 -58.636684) (xy 357.793396 -58.683197) (xy 357.756179 -58.724734)
			(xy 357.748164 -58.731404) (xy 361.820714 -58.731404) (xy 361.821214 -58.704071) (xy 361.829015 -58.649965)
			(xy 361.844457 -58.597527) (xy 361.867226 -58.547829) (xy 361.896853 -58.501888) (xy 361.91444 -58.48096)
			(xy 361.914694 -58.480706) (xy 361.914948 -58.480452) (xy 361.920525 -58.473359) (xy 361.926776 -58.456447)
			(xy 361.92714 -58.447432) (xy 361.92714 -58.380376) (xy 361.926807 -58.371356) (xy 361.920544 -58.354439)
			(xy 361.914948 -58.347356) (xy 361.914694 -58.347102) (xy 361.91444 -58.346848) (xy 361.896845 -58.325922)
			(xy 361.867194 -58.279989) (xy 361.844407 -58.230292) (xy 361.82895 -58.177851) (xy 361.821142 -58.123739)
			(xy 361.821142 -58.069067) (xy 361.828949 -58.014955) (xy 361.844405 -57.962513) (xy 361.867191 -57.912816)
			(xy 361.896841 -57.866883) (xy 361.91444 -57.84596) (xy 361.914694 -57.845706) (xy 361.914948 -57.845452)
			(xy 361.920525 -57.838359) (xy 361.926776 -57.821447) (xy 361.92714 -57.812432) (xy 361.92714 -57.745376)
			(xy 361.926807 -57.736356) (xy 361.920544 -57.719439) (xy 361.914948 -57.712356) (xy 361.914694 -57.712102)
			(xy 361.91444 -57.711848) (xy 361.896845 -57.690922) (xy 361.867194 -57.644989) (xy 361.844407 -57.595292)
			(xy 361.82895 -57.542851) (xy 361.821142 -57.488739) (xy 361.821142 -57.434067) (xy 361.828949 -57.379955)
			(xy 361.844405 -57.327513) (xy 361.867191 -57.277816) (xy 361.896841 -57.231883) (xy 361.91444 -57.21096)
			(xy 361.914694 -57.210706) (xy 361.914948 -57.210452) (xy 361.920525 -57.203359) (xy 361.926776 -57.186447)
			(xy 361.92714 -57.177432) (xy 361.92714 -57.110376) (xy 361.926807 -57.101356) (xy 361.920544 -57.084439)
			(xy 361.914948 -57.077356) (xy 361.914694 -57.077102) (xy 361.91444 -57.076848) (xy 361.896863 -57.05591)
			(xy 361.867221 -57.009977) (xy 361.844441 -56.960282) (xy 361.82899 -56.907844) (xy 361.821184 -56.853738)
			(xy 361.820714 -56.826404) (xy 361.8212 -56.799153) (xy 361.828956 -56.745205) (xy 361.844311 -56.69291)
			(xy 361.866953 -56.643333) (xy 361.896419 -56.597483) (xy 361.93211 -56.556292) (xy 361.973301 -56.520601)
			(xy 362.019151 -56.491135) (xy 362.068728 -56.468493) (xy 362.121023 -56.453138) (xy 362.174971 -56.445382)
			(xy 362.229473 -56.445382) (xy 362.283421 -56.453138) (xy 362.335716 -56.468493) (xy 362.385293 -56.491135)
			(xy 362.431143 -56.520601) (xy 362.472334 -56.556292) (xy 362.508025 -56.597483) (xy 362.537491 -56.643333)
			(xy 362.560133 -56.69291) (xy 362.575488 -56.745205) (xy 362.583244 -56.799153) (xy 362.58373 -56.826404)
			(xy 362.583248 -56.853737) (xy 362.575445 -56.907845) (xy 362.559999 -56.960284) (xy 362.537226 -57.009982)
			(xy 362.507594 -57.055921) (xy 362.490004 -57.076848) (xy 362.48975 -57.077102) (xy 362.489496 -57.077356)
			(xy 362.483921 -57.084451) (xy 362.477668 -57.101361) (xy 362.477304 -57.110376) (xy 362.477304 -57.177432)
			(xy 362.477645 -57.186451) (xy 362.483904 -57.203367) (xy 362.489496 -57.210452) (xy 362.48975 -57.210706)
			(xy 362.490004 -57.21096) (xy 362.507609 -57.231878) (xy 362.537264 -57.277811) (xy 362.560054 -57.327509)
			(xy 362.575512 -57.379952) (xy 362.583321 -57.434066) (xy 362.583321 -57.48874) (xy 362.575511 -57.542853)
			(xy 362.560052 -57.595297) (xy 362.537261 -57.644994) (xy 362.507606 -57.690926) (xy 362.490004 -57.711848)
			(xy 362.48975 -57.712102) (xy 362.489496 -57.712356) (xy 362.483921 -57.719451) (xy 362.477668 -57.736361)
			(xy 362.477304 -57.745376) (xy 362.477304 -57.812432) (xy 362.477645 -57.821451) (xy 362.483904 -57.838367)
			(xy 362.489496 -57.845452) (xy 362.48975 -57.845706) (xy 362.490004 -57.84596) (xy 362.507609 -57.866878)
			(xy 362.537264 -57.912811) (xy 362.560054 -57.962509) (xy 362.575512 -58.014952) (xy 362.583321 -58.069066)
			(xy 362.583321 -58.12374) (xy 362.575511 -58.177853) (xy 362.560052 -58.230297) (xy 362.537261 -58.279994)
			(xy 362.507606 -58.325926) (xy 362.490004 -58.346848) (xy 362.48975 -58.347102) (xy 362.489496 -58.347356)
			(xy 362.483921 -58.354451) (xy 362.477668 -58.371361) (xy 362.477304 -58.380376) (xy 362.477304 -58.447432)
			(xy 362.477645 -58.456451) (xy 362.483904 -58.473367) (xy 362.489496 -58.480452) (xy 362.48975 -58.480706)
			(xy 362.490004 -58.48096) (xy 362.507592 -58.501889) (xy 362.537231 -58.547825) (xy 362.560008 -58.597522)
			(xy 362.575457 -58.649962) (xy 362.583261 -58.70407) (xy 362.58373 -58.731404) (xy 362.583244 -58.758655)
			(xy 362.57858 -58.791094) (xy 364.476538 -58.791094) (xy 364.477026 -58.763761) (xy 364.484829 -58.709654)
			(xy 364.500274 -58.657215) (xy 364.523045 -58.607517) (xy 364.552676 -58.561578) (xy 364.570264 -58.54065)
			(xy 364.570518 -58.540396) (xy 364.570772 -58.540142) (xy 364.576356 -58.533054) (xy 364.582602 -58.516138)
			(xy 364.582964 -58.507122) (xy 364.582964 -58.440066) (xy 364.582631 -58.431047) (xy 364.576368 -58.414129)
			(xy 364.570772 -58.407046) (xy 364.570518 -58.406792) (xy 364.570264 -58.406538) (xy 364.552658 -58.385621)
			(xy 364.523006 -58.339687) (xy 364.500218 -58.289989) (xy 364.484761 -58.237545) (xy 364.476953 -58.183432)
			(xy 364.476954 -58.128759) (xy 364.484763 -58.074646) (xy 364.500221 -58.022203) (xy 364.52301 -57.972505)
			(xy 364.552663 -57.926572) (xy 364.570264 -57.90565) (xy 364.570518 -57.905396) (xy 364.570772 -57.905142)
			(xy 364.576356 -57.898054) (xy 364.582602 -57.881138) (xy 364.582964 -57.872122) (xy 364.582964 -57.805066)
			(xy 364.582631 -57.796047) (xy 364.576368 -57.779129) (xy 364.570772 -57.772046) (xy 364.570518 -57.771792)
			(xy 364.570264 -57.771538) (xy 364.55267 -57.750613) (xy 364.523033 -57.704676) (xy 364.500258 -57.654977)
			(xy 364.48481 -57.602537) (xy 364.477007 -57.548428) (xy 364.476538 -57.521094) (xy 364.476538 -57.52084)
			(xy 364.477011 -57.494546) (xy 364.484252 -57.442457) (xy 364.498574 -57.391855) (xy 364.519707 -57.343699)
			(xy 364.54725 -57.298899) (xy 364.580682 -57.258304) (xy 364.599728 -57.24017) (xy 364.607171 -57.232599)
			(xy 364.615698 -57.213181) (xy 364.616238 -57.202578) (xy 364.616238 -57.12841) (xy 364.615803 -57.117781)
			(xy 364.607271 -57.098317) (xy 364.599728 -57.090818) (xy 364.580677 -57.072684) (xy 364.547219 -57.032104)
			(xy 364.519659 -56.987309) (xy 364.498518 -56.93915) (xy 364.4842 -56.888542) (xy 364.476976 -56.836445)
			(xy 364.476538 -56.810148) (xy 364.476538 -56.809894) (xy 364.477024 -56.782643) (xy 364.48478 -56.728695)
			(xy 364.500135 -56.6764) (xy 364.522777 -56.626823) (xy 364.552243 -56.580973) (xy 364.587934 -56.539782)
			(xy 364.629125 -56.504091) (xy 364.674975 -56.474625) (xy 364.724552 -56.451983) (xy 364.776847 -56.436628)
			(xy 364.830795 -56.428872) (xy 364.885297 -56.428872) (xy 364.939245 -56.436628) (xy 364.99154 -56.451983)
			(xy 365.041117 -56.474625) (xy 365.086967 -56.504091) (xy 365.128158 -56.539782) (xy 365.163849 -56.580973)
			(xy 365.193315 -56.626823) (xy 365.215957 -56.6764) (xy 365.231312 -56.728695) (xy 365.239068 -56.782643)
			(xy 365.239554 -56.809894) (xy 365.239554 -56.810148) (xy 365.239142 -56.836445) (xy 365.231889 -56.888536)
			(xy 365.217555 -56.939139) (xy 365.196411 -56.987295) (xy 365.168857 -57.032093) (xy 365.135415 -57.072686)
			(xy 365.116364 -57.090818) (xy 365.108925 -57.098392) (xy 365.100397 -57.117808) (xy 365.099854 -57.12841)
			(xy 365.099854 -57.202578) (xy 365.100298 -57.213206) (xy 365.108824 -57.232669) (xy 365.116364 -57.24017)
			(xy 365.135407 -57.258311) (xy 365.168866 -57.29889) (xy 365.196428 -57.343683) (xy 365.21757 -57.391841)
			(xy 365.231889 -57.442448) (xy 365.235302 -57.467053) (xy 365.418569 -57.467053) (xy 365.418569 -57.412547)
			(xy 365.426327 -57.358596) (xy 365.441683 -57.306298) (xy 365.464327 -57.256718) (xy 365.493796 -57.210866)
			(xy 365.529491 -57.169674) (xy 365.570685 -57.133982) (xy 365.616539 -57.104515) (xy 365.666121 -57.081875)
			(xy 365.718419 -57.066522) (xy 365.772371 -57.058768) (xy 365.799624 -57.058306) (xy 365.799878 -57.058306)
			(xy 365.826172 -57.058777) (xy 365.878261 -57.06602) (xy 365.928862 -57.080343) (xy 365.977018 -57.101476)
			(xy 366.021818 -57.129019) (xy 366.062413 -57.16245) (xy 366.080548 -57.181496) (xy 366.088103 -57.188957)
			(xy 366.107534 -57.197471) (xy 366.11814 -57.198006) (xy 366.192308 -57.198006) (xy 366.202939 -57.197591)
			(xy 366.222403 -57.189045) (xy 366.2299 -57.181496) (xy 366.248019 -57.162431) (xy 366.288603 -57.128975)
			(xy 366.333401 -57.101417) (xy 366.381563 -57.08028) (xy 366.432174 -57.065964) (xy 366.484272 -57.058743)
			(xy 366.51057 -57.058306) (xy 366.510824 -57.058306) (xy 366.538075 -57.058765) (xy 366.592022 -57.066525)
			(xy 366.627172 -57.076848) (xy 367.438686 -57.076848) (xy 367.43916 -57.049514) (xy 367.446968 -56.995408)
			(xy 367.462417 -56.942969) (xy 367.485191 -56.893271) (xy 367.514823 -56.847332) (xy 367.532412 -56.826404)
			(xy 367.532666 -56.82615) (xy 367.53292 -56.825896) (xy 367.538517 -56.818816) (xy 367.544757 -56.801894)
			(xy 367.545112 -56.792876) (xy 367.545112 -56.72582) (xy 367.544743 -56.716804) (xy 367.538503 -56.699887)
			(xy 367.53292 -56.6928) (xy 367.532666 -56.692546) (xy 367.532412 -56.692292) (xy 367.514804 -56.671379)
			(xy 367.485168 -56.625438) (xy 367.462394 -56.575737) (xy 367.44695 -56.523294) (xy 367.439152 -56.469183)
			(xy 367.438686 -56.441848) (xy 367.439172 -56.414597) (xy 367.446928 -56.360649) (xy 367.462283 -56.308354)
			(xy 367.484925 -56.258777) (xy 367.514391 -56.212927) (xy 367.550082 -56.171736) (xy 367.591273 -56.136045)
			(xy 367.637123 -56.106579) (xy 367.6867 -56.083937) (xy 367.738995 -56.068582) (xy 367.792943 -56.060826)
			(xy 367.847445 -56.060826) (xy 367.901393 -56.068582) (xy 367.953688 -56.083937) (xy 368.003265 -56.106579)
			(xy 368.049115 -56.136045) (xy 368.090306 -56.171736) (xy 368.125997 -56.212927) (xy 368.155463 -56.258777)
			(xy 368.178105 -56.308354) (xy 368.191348 -56.353456) (xy 375.24131 -56.353456) (xy 375.245381 -56.297834)
			(xy 375.257507 -56.243397) (xy 375.27743 -56.191306) (xy 375.304726 -56.142671) (xy 375.338812 -56.098528)
			(xy 375.378961 -56.059819) (xy 375.424319 -56.027368) (xy 375.473919 -56.001867) (xy 375.526703 -55.98386)
			(xy 375.581546 -55.97373) (xy 375.63728 -55.971693) (xy 375.692717 -55.977793) (xy 375.746674 -55.991899)
			(xy 375.798003 -56.013711) (xy 375.845609 -56.042765) (xy 375.888477 -56.07844) (xy 375.925694 -56.119977)
			(xy 375.956467 -56.16649) (xy 375.980139 -56.216987) (xy 375.996207 -56.270394) (xy 376.004327 -56.32557)
			(xy 376.004836 -56.353456) (xy 376.004327 -56.381342) (xy 375.996207 -56.436518) (xy 375.980139 -56.489925)
			(xy 375.956467 -56.540422) (xy 375.925694 -56.586935) (xy 375.888477 -56.628472) (xy 375.845609 -56.664147)
			(xy 375.798003 -56.693201) (xy 375.746674 -56.715013) (xy 375.692717 -56.729119) (xy 375.63728 -56.735219)
			(xy 375.581546 -56.733182) (xy 375.526703 -56.723052) (xy 375.473919 -56.705045) (xy 375.424319 -56.679544)
			(xy 375.378961 -56.647093) (xy 375.338812 -56.608384) (xy 375.304726 -56.564241) (xy 375.27743 -56.515606)
			(xy 375.257507 -56.463515) (xy 375.245381 -56.409078) (xy 375.24131 -56.353456) (xy 368.191348 -56.353456)
			(xy 368.19346 -56.360649) (xy 368.201216 -56.414597) (xy 368.201702 -56.441848) (xy 368.201229 -56.469182)
			(xy 368.193421 -56.523288) (xy 368.177972 -56.575727) (xy 368.155198 -56.625425) (xy 368.125565 -56.671364)
			(xy 368.107976 -56.692292) (xy 368.107722 -56.692546) (xy 368.107468 -56.6928) (xy 368.101872 -56.69988)
			(xy 368.095632 -56.716802) (xy 368.095276 -56.72582) (xy 368.095276 -56.792876) (xy 368.09565 -56.801891)
			(xy 368.101886 -56.818808) (xy 368.107468 -56.825896) (xy 368.107722 -56.82615) (xy 368.107976 -56.826404)
			(xy 368.12558 -56.84732) (xy 368.155217 -56.89326) (xy 368.177992 -56.94296) (xy 368.193437 -56.995402)
			(xy 368.201236 -57.049513) (xy 368.201702 -57.076848) (xy 368.201216 -57.104099) (xy 368.19346 -57.158047)
			(xy 368.178105 -57.210342) (xy 368.155463 -57.259919) (xy 368.125997 -57.305769) (xy 368.090306 -57.34696)
			(xy 368.049115 -57.382651) (xy 368.003265 -57.412117) (xy 367.953688 -57.434759) (xy 367.901393 -57.450114)
			(xy 367.847445 -57.45787) (xy 367.792943 -57.45787) (xy 367.738995 -57.450114) (xy 367.6867 -57.434759)
			(xy 367.637123 -57.412117) (xy 367.591273 -57.382651) (xy 367.550082 -57.34696) (xy 367.514391 -57.305769)
			(xy 367.484925 -57.259919) (xy 367.462283 -57.210342) (xy 367.446928 -57.158047) (xy 367.439172 -57.104099)
			(xy 367.438686 -57.076848) (xy 366.627172 -57.076848) (xy 366.644316 -57.081883) (xy 366.693892 -57.104526)
			(xy 366.739741 -57.133994) (xy 366.78093 -57.169687) (xy 366.81662 -57.210878) (xy 366.846085 -57.256729)
			(xy 366.868726 -57.306306) (xy 366.88408 -57.358601) (xy 366.891836 -57.412549) (xy 366.891836 -57.467051)
			(xy 366.889215 -57.48528) (xy 378.906022 -57.48528) (xy 378.910093 -57.429658) (xy 378.922219 -57.375221)
			(xy 378.942142 -57.32313) (xy 378.969438 -57.274495) (xy 379.003524 -57.230352) (xy 379.043673 -57.191643)
			(xy 379.089031 -57.159192) (xy 379.138631 -57.133691) (xy 379.191415 -57.115684) (xy 379.246258 -57.105554)
			(xy 379.301992 -57.103517) (xy 379.357429 -57.109617) (xy 379.411386 -57.123723) (xy 379.462715 -57.145535)
			(xy 379.510321 -57.174589) (xy 379.553189 -57.210264) (xy 379.590406 -57.251801) (xy 379.621179 -57.298314)
			(xy 379.644851 -57.348811) (xy 379.660919 -57.402218) (xy 379.669039 -57.457394) (xy 379.669548 -57.48528)
			(xy 379.669039 -57.513166) (xy 379.660919 -57.568342) (xy 379.644851 -57.621749) (xy 379.621179 -57.672246)
			(xy 379.590406 -57.718759) (xy 379.553189 -57.760296) (xy 379.510321 -57.795971) (xy 379.462715 -57.825025)
			(xy 379.411386 -57.846837) (xy 379.357429 -57.860943) (xy 379.301992 -57.867043) (xy 379.246258 -57.865006)
			(xy 379.191415 -57.854876) (xy 379.138631 -57.836869) (xy 379.089031 -57.811368) (xy 379.043673 -57.778917)
			(xy 379.003524 -57.740208) (xy 378.969438 -57.696065) (xy 378.942142 -57.64743) (xy 378.922219 -57.595339)
			(xy 378.910093 -57.540902) (xy 378.906022 -57.48528) (xy 366.889215 -57.48528) (xy 366.88408 -57.520999)
			(xy 366.868726 -57.573294) (xy 366.846085 -57.622871) (xy 366.81662 -57.668722) (xy 366.78093 -57.709913)
			(xy 366.739741 -57.745606) (xy 366.693892 -57.775074) (xy 366.644316 -57.797717) (xy 366.592022 -57.813075)
			(xy 366.538075 -57.820835) (xy 366.510824 -57.821322) (xy 366.51057 -57.821322) (xy 366.484275 -57.820876)
			(xy 366.432186 -57.813627) (xy 366.381585 -57.799298) (xy 366.333429 -57.77816) (xy 366.288629 -57.750613)
			(xy 366.248034 -57.717179) (xy 366.2299 -57.698132) (xy 366.222323 -57.690697) (xy 366.202909 -57.682167)
			(xy 366.192308 -57.681622) (xy 366.11814 -57.681622) (xy 366.107504 -57.682) (xy 366.08804 -57.690571)
			(xy 366.080548 -57.698132) (xy 366.062392 -57.71716) (xy 366.021817 -57.750622) (xy 365.977027 -57.778187)
			(xy 365.928872 -57.799331) (xy 365.878268 -57.813654) (xy 365.826174 -57.820882) (xy 365.799878 -57.821322)
			(xy 365.799624 -57.821322) (xy 365.772371 -57.820832) (xy 365.718419 -57.813078) (xy 365.666121 -57.797725)
			(xy 365.616539 -57.775085) (xy 365.570685 -57.745618) (xy 365.529491 -57.709926) (xy 365.493796 -57.668734)
			(xy 365.464327 -57.622882) (xy 365.441683 -57.573302) (xy 365.426327 -57.521004) (xy 365.418569 -57.467053)
			(xy 365.235302 -57.467053) (xy 365.239115 -57.494543) (xy 365.239554 -57.52084) (xy 365.239554 -57.521094)
			(xy 365.239061 -57.548427) (xy 365.231259 -57.602533) (xy 365.215816 -57.654973) (xy 365.193046 -57.704671)
			(xy 365.163416 -57.75061) (xy 365.145828 -57.771538) (xy 365.145574 -57.771792) (xy 365.14532 -57.772046)
			(xy 365.139741 -57.779137) (xy 365.133492 -57.796051) (xy 365.133128 -57.805066) (xy 365.133128 -57.872122)
			(xy 365.133468 -57.881141) (xy 365.139727 -57.898058) (xy 365.14532 -57.905142) (xy 365.145574 -57.905396)
			(xy 365.145828 -57.90565) (xy 365.163423 -57.926577) (xy 365.193076 -57.972509) (xy 365.215865 -58.022205)
			(xy 365.231323 -58.074647) (xy 365.239132 -58.128759) (xy 365.239133 -58.183432) (xy 365.231325 -58.237544)
			(xy 365.215869 -58.289986) (xy 365.19308 -58.339683) (xy 365.163428 -58.385616) (xy 365.145828 -58.406538)
			(xy 365.145574 -58.406792) (xy 365.14532 -58.407046) (xy 365.139741 -58.414137) (xy 365.133492 -58.431051)
			(xy 365.133128 -58.440066) (xy 365.133128 -58.507122) (xy 365.133468 -58.516141) (xy 365.139727 -58.533058)
			(xy 365.14532 -58.540142) (xy 365.145574 -58.540396) (xy 365.145828 -58.54065) (xy 365.163415 -58.56158)
			(xy 365.193053 -58.607516) (xy 365.21583 -58.657213) (xy 365.231279 -58.709652) (xy 365.239084 -58.76376)
			(xy 365.239554 -58.791094) (xy 365.239068 -58.818345) (xy 365.231312 -58.872293) (xy 365.230915 -58.873644)
			(xy 366.500664 -58.873644) (xy 366.501117 -58.846309) (xy 366.508927 -58.792201) (xy 366.52438 -58.739761)
			(xy 366.547159 -58.690064) (xy 366.576798 -58.644126) (xy 366.59439 -58.6232) (xy 366.594644 -58.622946)
			(xy 366.594898 -58.622692) (xy 366.600494 -58.615612) (xy 366.606735 -58.59869) (xy 366.60709 -58.589672)
			(xy 366.60709 -58.522616) (xy 366.606728 -58.5136) (xy 366.600484 -58.496682) (xy 366.594898 -58.489596)
			(xy 366.594644 -58.489342) (xy 366.59439 -58.489088) (xy 366.576777 -58.468179) (xy 366.547142 -58.422237)
			(xy 366.52437 -58.372535) (xy 366.508927 -58.320091) (xy 366.501129 -58.265979) (xy 366.500664 -58.238644)
			(xy 366.50115 -58.211393) (xy 366.508906 -58.157445) (xy 366.524261 -58.10515) (xy 366.546903 -58.055573)
			(xy 366.576369 -58.009723) (xy 366.61206 -57.968532) (xy 366.653251 -57.932841) (xy 366.699101 -57.903375)
			(xy 366.748678 -57.880733) (xy 366.800973 -57.865378) (xy 366.854921 -57.857622) (xy 366.909423 -57.857622)
			(xy 366.963371 -57.865378) (xy 367.015666 -57.880733) (xy 367.065243 -57.903375) (xy 367.111093 -57.932841)
			(xy 367.152284 -57.968532) (xy 367.187975 -58.009723) (xy 367.217441 -58.055573) (xy 367.225068 -58.072274)
			(xy 374.293636 -58.072274) (xy 374.297707 -58.016652) (xy 374.309833 -57.962215) (xy 374.329756 -57.910124)
			(xy 374.357052 -57.861489) (xy 374.391138 -57.817346) (xy 374.431287 -57.778637) (xy 374.476645 -57.746186)
			(xy 374.526245 -57.720685) (xy 374.579029 -57.702678) (xy 374.633872 -57.692548) (xy 374.689606 -57.690511)
			(xy 374.745043 -57.696611) (xy 374.799 -57.710717) (xy 374.850329 -57.732529) (xy 374.897935 -57.761583)
			(xy 374.940803 -57.797258) (xy 374.97802 -57.838795) (xy 375.008793 -57.885308) (xy 375.032465 -57.935805)
			(xy 375.048533 -57.989212) (xy 375.056653 -58.044388) (xy 375.057162 -58.072274) (xy 375.057092 -58.076084)
			(xy 379.658116 -58.076084) (xy 379.662187 -58.020462) (xy 379.674313 -57.966025) (xy 379.694236 -57.913934)
			(xy 379.721532 -57.865299) (xy 379.755618 -57.821156) (xy 379.795767 -57.782447) (xy 379.841125 -57.749996)
			(xy 379.890725 -57.724495) (xy 379.943509 -57.706488) (xy 379.998352 -57.696358) (xy 380.054086 -57.694321)
			(xy 380.109523 -57.700421) (xy 380.16348 -57.714527) (xy 380.214809 -57.736339) (xy 380.262415 -57.765393)
			(xy 380.305283 -57.801068) (xy 380.3425 -57.842605) (xy 380.358836 -57.867296) (xy 381.9431 -57.867296)
			(xy 381.947171 -57.811674) (xy 381.959297 -57.757237) (xy 381.97922 -57.705146) (xy 382.006516 -57.656511)
			(xy 382.040602 -57.612368) (xy 382.080751 -57.573659) (xy 382.126109 -57.541208) (xy 382.175709 -57.515707)
			(xy 382.228493 -57.4977) (xy 382.283336 -57.48757) (xy 382.33907 -57.485533) (xy 382.394507 -57.491633)
			(xy 382.448464 -57.505739) (xy 382.499793 -57.527551) (xy 382.547399 -57.556605) (xy 382.590267 -57.59228)
			(xy 382.627484 -57.633817) (xy 382.658257 -57.68033) (xy 382.681929 -57.730827) (xy 382.697997 -57.784234)
			(xy 382.706117 -57.83941) (xy 382.706626 -57.867296) (xy 382.706117 -57.895182) (xy 382.697997 -57.950358)
			(xy 382.681929 -58.003765) (xy 382.658257 -58.054262) (xy 382.627484 -58.100775) (xy 382.590267 -58.142312)
			(xy 382.547399 -58.177987) (xy 382.499793 -58.207041) (xy 382.448464 -58.228853) (xy 382.394507 -58.242959)
			(xy 382.33907 -58.249059) (xy 382.283336 -58.247022) (xy 382.228493 -58.236892) (xy 382.175709 -58.218885)
			(xy 382.126109 -58.193384) (xy 382.080751 -58.160933) (xy 382.040602 -58.122224) (xy 382.006516 -58.078081)
			(xy 381.97922 -58.029446) (xy 381.959297 -57.977355) (xy 381.947171 -57.922918) (xy 381.9431 -57.867296)
			(xy 380.358836 -57.867296) (xy 380.373273 -57.889118) (xy 380.396945 -57.939615) (xy 380.413013 -57.993022)
			(xy 380.421133 -58.048198) (xy 380.421642 -58.076084) (xy 380.421133 -58.10397) (xy 380.413013 -58.159146)
			(xy 380.396945 -58.212553) (xy 380.373273 -58.26305) (xy 380.3425 -58.309563) (xy 380.305283 -58.3511)
			(xy 380.262415 -58.386775) (xy 380.214809 -58.415829) (xy 380.16348 -58.437641) (xy 380.109523 -58.451747)
			(xy 380.054086 -58.457847) (xy 379.998352 -58.45581) (xy 379.943509 -58.44568) (xy 379.890725 -58.427673)
			(xy 379.841125 -58.402172) (xy 379.795767 -58.369721) (xy 379.755618 -58.331012) (xy 379.721532 -58.286869)
			(xy 379.694236 -58.238234) (xy 379.674313 -58.186143) (xy 379.662187 -58.131706) (xy 379.658116 -58.076084)
			(xy 375.057092 -58.076084) (xy 375.056653 -58.10016) (xy 375.048533 -58.155336) (xy 375.032465 -58.208743)
			(xy 375.008793 -58.25924) (xy 374.97802 -58.305753) (xy 374.940803 -58.34729) (xy 374.897935 -58.382965)
			(xy 374.850329 -58.412019) (xy 374.799 -58.433831) (xy 374.745043 -58.447937) (xy 374.689606 -58.454037)
			(xy 374.633872 -58.452) (xy 374.579029 -58.44187) (xy 374.526245 -58.423863) (xy 374.476645 -58.398362)
			(xy 374.431287 -58.365911) (xy 374.391138 -58.327202) (xy 374.357052 -58.283059) (xy 374.329756 -58.234424)
			(xy 374.309833 -58.182333) (xy 374.297707 -58.127896) (xy 374.293636 -58.072274) (xy 367.225068 -58.072274)
			(xy 367.240083 -58.10515) (xy 367.255438 -58.157445) (xy 367.263194 -58.211393) (xy 367.26368 -58.238644)
			(xy 367.26321 -58.265978) (xy 367.255402 -58.320085) (xy 367.239952 -58.372524) (xy 367.217178 -58.422222)
			(xy 367.187544 -58.468161) (xy 367.169954 -58.489088) (xy 367.1697 -58.489342) (xy 367.169446 -58.489596)
			(xy 367.163849 -58.496675) (xy 367.15761 -58.513598) (xy 367.157254 -58.522616) (xy 367.157254 -58.561224)
			(xy 380.86233 -58.561224) (xy 380.866401 -58.505602) (xy 380.878527 -58.451165) (xy 380.89845 -58.399074)
			(xy 380.925746 -58.350439) (xy 380.959832 -58.306296) (xy 380.999981 -58.267587) (xy 381.045339 -58.235136)
			(xy 381.094939 -58.209635) (xy 381.147723 -58.191628) (xy 381.202566 -58.181498) (xy 381.2583 -58.179461)
			(xy 381.313737 -58.185561) (xy 381.367694 -58.199667) (xy 381.419023 -58.221479) (xy 381.466629 -58.250533)
			(xy 381.509497 -58.286208) (xy 381.546714 -58.327745) (xy 381.577487 -58.374258) (xy 381.601159 -58.424755)
			(xy 381.608669 -58.449718) (xy 383.10896 -58.449718) (xy 383.113031 -58.394096) (xy 383.125157 -58.339659)
			(xy 383.14508 -58.287568) (xy 383.172376 -58.238933) (xy 383.206462 -58.19479) (xy 383.246611 -58.156081)
			(xy 383.291969 -58.12363) (xy 383.341569 -58.098129) (xy 383.394353 -58.080122) (xy 383.449196 -58.069992)
			(xy 383.50493 -58.067955) (xy 383.560367 -58.074055) (xy 383.614324 -58.088161) (xy 383.665653 -58.109973)
			(xy 383.713259 -58.139027) (xy 383.756127 -58.174702) (xy 383.793344 -58.216239) (xy 383.824117 -58.262752)
			(xy 383.847789 -58.313249) (xy 383.863857 -58.366656) (xy 383.871977 -58.421832) (xy 383.872486 -58.449718)
			(xy 383.871977 -58.477604) (xy 383.863857 -58.53278) (xy 383.847789 -58.586187) (xy 383.824117 -58.636684)
			(xy 383.793344 -58.683197) (xy 383.756127 -58.724734) (xy 383.748112 -58.731404) (xy 387.820662 -58.731404)
			(xy 387.82115 -58.704071) (xy 387.828952 -58.649964) (xy 387.844397 -58.597525) (xy 387.867168 -58.547827)
			(xy 387.896799 -58.501887) (xy 387.914388 -58.48096) (xy 387.914642 -58.480706) (xy 387.914896 -58.480452)
			(xy 387.920467 -58.473354) (xy 387.926723 -58.456446) (xy 387.927088 -58.447432) (xy 387.927088 -58.380376)
			(xy 387.926745 -58.371358) (xy 387.920488 -58.354441) (xy 387.914896 -58.347356) (xy 387.914642 -58.347102)
			(xy 387.914388 -58.346848) (xy 387.896791 -58.325923) (xy 387.867136 -58.279991) (xy 387.844346 -58.230294)
			(xy 387.828888 -58.177852) (xy 387.821078 -58.12374) (xy 387.821078 -58.069066) (xy 387.828887 -58.014954)
			(xy 387.844344 -57.962511) (xy 387.867133 -57.912814) (xy 387.896787 -57.866882) (xy 387.914388 -57.84596)
			(xy 387.914642 -57.845706) (xy 387.914896 -57.845452) (xy 387.920467 -57.838354) (xy 387.926723 -57.821446)
			(xy 387.927088 -57.812432) (xy 387.927088 -57.745376) (xy 387.926745 -57.736358) (xy 387.920488 -57.719441)
			(xy 387.914896 -57.712356) (xy 387.914642 -57.712102) (xy 387.914388 -57.711848) (xy 387.896791 -57.690923)
			(xy 387.867136 -57.644991) (xy 387.844346 -57.595294) (xy 387.828888 -57.542852) (xy 387.821078 -57.48874)
			(xy 387.821078 -57.434066) (xy 387.828887 -57.379954) (xy 387.844344 -57.327511) (xy 387.867133 -57.277814)
			(xy 387.896787 -57.231882) (xy 387.914388 -57.21096) (xy 387.914642 -57.210706) (xy 387.914896 -57.210452)
			(xy 387.920467 -57.203354) (xy 387.926723 -57.186446) (xy 387.927088 -57.177432) (xy 387.927088 -57.110376)
			(xy 387.926745 -57.101358) (xy 387.920488 -57.084441) (xy 387.914896 -57.077356) (xy 387.914642 -57.077102)
			(xy 387.914388 -57.076848) (xy 387.896803 -57.055917) (xy 387.867164 -57.009981) (xy 387.844386 -56.960285)
			(xy 387.828937 -56.907845) (xy 387.821132 -56.853738) (xy 387.820662 -56.826404) (xy 387.821148 -56.799153)
			(xy 387.828904 -56.745205) (xy 387.844259 -56.69291) (xy 387.866901 -56.643333) (xy 387.896367 -56.597483)
			(xy 387.932058 -56.556292) (xy 387.973249 -56.520601) (xy 388.019099 -56.491135) (xy 388.068676 -56.468493)
			(xy 388.120971 -56.453138) (xy 388.174919 -56.445382) (xy 388.229421 -56.445382) (xy 388.283369 -56.453138)
			(xy 388.335664 -56.468493) (xy 388.385241 -56.491135) (xy 388.431091 -56.520601) (xy 388.472282 -56.556292)
			(xy 388.507973 -56.597483) (xy 388.537439 -56.643333) (xy 388.560081 -56.69291) (xy 388.575436 -56.745205)
			(xy 388.583192 -56.799153) (xy 388.583678 -56.826404) (xy 388.583185 -56.853737) (xy 388.575382 -56.907843)
			(xy 388.559939 -56.960282) (xy 388.537169 -57.00998) (xy 388.50754 -57.05592) (xy 388.489952 -57.076848)
			(xy 388.489698 -57.077102) (xy 388.489444 -57.077356) (xy 388.483863 -57.084446) (xy 388.477614 -57.10136)
			(xy 388.477252 -57.110376) (xy 388.477252 -57.177432) (xy 388.477582 -57.186452) (xy 388.483847 -57.203369)
			(xy 388.489444 -57.210452) (xy 388.489698 -57.210706) (xy 388.489952 -57.21096) (xy 388.507555 -57.231879)
			(xy 388.537207 -57.277813) (xy 388.559994 -57.327511) (xy 388.57545 -57.379954) (xy 388.583258 -57.434067)
			(xy 388.583257 -57.488739) (xy 388.575448 -57.542852) (xy 388.559992 -57.595294) (xy 388.537204 -57.644992)
			(xy 388.507552 -57.690926) (xy 388.489952 -57.711848) (xy 388.489698 -57.712102) (xy 388.489444 -57.712356)
			(xy 388.483863 -57.719446) (xy 388.477614 -57.73636) (xy 388.477252 -57.745376) (xy 388.477252 -57.812432)
			(xy 388.477582 -57.821452) (xy 388.483847 -57.838369) (xy 388.489444 -57.845452) (xy 388.489698 -57.845706)
			(xy 388.489952 -57.84596) (xy 388.507555 -57.866879) (xy 388.537207 -57.912813) (xy 388.559994 -57.962511)
			(xy 388.57545 -58.014954) (xy 388.583258 -58.069067) (xy 388.583257 -58.123739) (xy 388.575448 -58.177852)
			(xy 388.559992 -58.230294) (xy 388.537204 -58.279992) (xy 388.507552 -58.325926) (xy 388.489952 -58.346848)
			(xy 388.489698 -58.347102) (xy 388.489444 -58.347356) (xy 388.483863 -58.354446) (xy 388.477614 -58.37136)
			(xy 388.477252 -58.380376) (xy 388.477252 -58.447432) (xy 388.477582 -58.456452) (xy 388.483847 -58.473369)
			(xy 388.489444 -58.480452) (xy 388.489698 -58.480706) (xy 388.489952 -58.48096) (xy 388.507532 -58.501896)
			(xy 388.537174 -58.547829) (xy 388.559953 -58.597525) (xy 388.575404 -58.649963) (xy 388.583209 -58.70407)
			(xy 388.583678 -58.731404) (xy 388.583192 -58.758655) (xy 388.578528 -58.791094) (xy 390.476486 -58.791094)
			(xy 390.476987 -58.763761) (xy 390.484789 -58.709656) (xy 390.500231 -58.657217) (xy 390.522999 -58.607519)
			(xy 390.552626 -58.561579) (xy 390.570212 -58.54065) (xy 390.570466 -58.540396) (xy 390.57072 -58.540142)
			(xy 390.576297 -58.533049) (xy 390.582549 -58.516137) (xy 390.582912 -58.507122) (xy 390.582912 -58.440066)
			(xy 390.582569 -58.431048) (xy 390.576312 -58.414131) (xy 390.57072 -58.407046) (xy 390.570466 -58.406792)
			(xy 390.570212 -58.406538) (xy 390.552604 -58.385622) (xy 390.522948 -58.339689) (xy 390.500157 -58.289991)
			(xy 390.484698 -58.237547) (xy 390.476889 -58.183433) (xy 390.47689 -58.128758) (xy 390.4847 -58.074644)
			(xy 390.50016 -58.022201) (xy 390.522952 -57.972503) (xy 390.552609 -57.926571) (xy 390.570212 -57.90565)
			(xy 390.570466 -57.905396) (xy 390.57072 -57.905142) (xy 390.576297 -57.898049) (xy 390.582549 -57.881137)
			(xy 390.582912 -57.872122) (xy 390.582912 -57.805066) (xy 390.582569 -57.796048) (xy 390.576312 -57.779131)
			(xy 390.57072 -57.772046) (xy 390.570466 -57.771792) (xy 390.570212 -57.771538) (xy 390.552626 -57.750607)
			(xy 390.522986 -57.704672) (xy 390.500208 -57.654975) (xy 390.484759 -57.602536) (xy 390.476955 -57.548428)
			(xy 390.476486 -57.521094) (xy 390.476486 -57.52084) (xy 390.476976 -57.494546) (xy 390.484215 -57.442459)
			(xy 390.498536 -57.391859) (xy 390.519665 -57.343702) (xy 390.547205 -57.298902) (xy 390.580632 -57.258305)
			(xy 390.599676 -57.24017) (xy 390.607126 -57.232605) (xy 390.615647 -57.213182) (xy 390.616186 -57.202578)
			(xy 390.616186 -57.12841) (xy 390.615767 -57.117779) (xy 390.607225 -57.098314) (xy 390.599676 -57.090818)
			(xy 390.580615 -57.072695) (xy 390.54716 -57.032111) (xy 390.519602 -56.987313) (xy 390.498464 -56.939152)
			(xy 390.484147 -56.888543) (xy 390.476924 -56.836446) (xy 390.476486 -56.810148) (xy 390.476486 -56.809894)
			(xy 390.476972 -56.782643) (xy 390.484728 -56.728695) (xy 390.500083 -56.6764) (xy 390.522725 -56.626823)
			(xy 390.552191 -56.580973) (xy 390.587882 -56.539782) (xy 390.629073 -56.504091) (xy 390.674923 -56.474625)
			(xy 390.7245 -56.451983) (xy 390.776795 -56.436628) (xy 390.830743 -56.428872) (xy 390.885245 -56.428872)
			(xy 390.939193 -56.436628) (xy 390.991488 -56.451983) (xy 391.041065 -56.474625) (xy 391.086915 -56.504091)
			(xy 391.128106 -56.539782) (xy 391.163797 -56.580973) (xy 391.193263 -56.626823) (xy 391.215905 -56.6764)
			(xy 391.23126 -56.728695) (xy 391.239016 -56.782643) (xy 391.239502 -56.809894) (xy 391.239502 -56.810148)
			(xy 391.239075 -56.836444) (xy 391.231823 -56.888534) (xy 391.217491 -56.939136) (xy 391.196349 -56.987292)
			(xy 391.168799 -57.032091) (xy 391.135361 -57.072684) (xy 391.116312 -57.090818) (xy 391.108866 -57.098386)
			(xy 391.100343 -57.117807) (xy 391.099802 -57.12841) (xy 391.099802 -57.202578) (xy 391.100231 -57.213208)
			(xy 391.108767 -57.232672) (xy 391.116312 -57.24017) (xy 391.135364 -57.258302) (xy 391.168821 -57.298883)
			(xy 391.19638 -57.343679) (xy 391.21752 -57.391838) (xy 391.231838 -57.442447) (xy 391.23525 -57.467049)
			(xy 391.418592 -57.467049) (xy 391.418592 -57.412551) (xy 391.426348 -57.358608) (xy 391.441701 -57.306317)
			(xy 391.464339 -57.256744) (xy 391.493802 -57.210896) (xy 391.529489 -57.169709) (xy 391.570674 -57.134018)
			(xy 391.616519 -57.104552) (xy 391.666091 -57.081911) (xy 391.71838 -57.066554) (xy 391.772323 -57.058794)
			(xy 391.799572 -57.058306) (xy 391.799826 -57.058306) (xy 391.826122 -57.058745) (xy 391.878211 -57.065994)
			(xy 391.928813 -57.080324) (xy 391.976969 -57.101463) (xy 392.021768 -57.129012) (xy 392.062362 -57.162448)
			(xy 392.080496 -57.181496) (xy 392.088071 -57.188934) (xy 392.107486 -57.197461) (xy 392.118088 -57.198006)
			(xy 392.192256 -57.198006) (xy 392.20289 -57.197617) (xy 392.222354 -57.189053) (xy 392.229848 -57.181496)
			(xy 392.247943 -57.162407) (xy 392.288533 -57.128954) (xy 392.333336 -57.101399) (xy 392.381502 -57.080266)
			(xy 392.432117 -57.065955) (xy 392.484219 -57.05874) (xy 392.510518 -57.058306) (xy 392.510772 -57.058306)
			(xy 392.538027 -57.058739) (xy 392.591983 -57.066493) (xy 392.627257 -57.076848) (xy 393.438634 -57.076848)
			(xy 393.439096 -57.049514) (xy 393.446906 -56.995406) (xy 393.462357 -56.942967) (xy 393.485133 -56.893269)
			(xy 393.514769 -56.847331) (xy 393.53236 -56.826404) (xy 393.532614 -56.82615) (xy 393.532868 -56.825896)
			(xy 393.53847 -56.818821) (xy 393.544706 -56.801895) (xy 393.54506 -56.792876) (xy 393.54506 -56.72582)
			(xy 393.544702 -56.716803) (xy 393.538456 -56.699886) (xy 393.532868 -56.6928) (xy 393.532614 -56.692546)
			(xy 393.53236 -56.692292) (xy 393.514744 -56.671385) (xy 393.485111 -56.625442) (xy 393.462339 -56.57574)
			(xy 393.446897 -56.523295) (xy 393.4391 -56.469183) (xy 393.438634 -56.441848) (xy 393.43912 -56.414597)
			(xy 393.446876 -56.360649) (xy 393.462231 -56.308354) (xy 393.484873 -56.258777) (xy 393.514339 -56.212927)
			(xy 393.55003 -56.171736) (xy 393.591221 -56.136045) (xy 393.637071 -56.106579) (xy 393.686648 -56.083937)
			(xy 393.738943 -56.068582) (xy 393.792891 -56.060826) (xy 393.847393 -56.060826) (xy 393.901341 -56.068582)
			(xy 393.953636 -56.083937) (xy 394.003213 -56.106579) (xy 394.049063 -56.136045) (xy 394.090254 -56.171736)
			(xy 394.125945 -56.212927) (xy 394.155411 -56.258777) (xy 394.178053 -56.308354) (xy 394.191296 -56.353456)
			(xy 401.241258 -56.353456) (xy 401.245329 -56.297834) (xy 401.257455 -56.243397) (xy 401.277378 -56.191306)
			(xy 401.304674 -56.142671) (xy 401.33876 -56.098528) (xy 401.378909 -56.059819) (xy 401.424267 -56.027368)
			(xy 401.473867 -56.001867) (xy 401.526651 -55.98386) (xy 401.581494 -55.97373) (xy 401.637228 -55.971693)
			(xy 401.692665 -55.977793) (xy 401.746622 -55.991899) (xy 401.797951 -56.013711) (xy 401.845557 -56.042765)
			(xy 401.888425 -56.07844) (xy 401.925642 -56.119977) (xy 401.956415 -56.16649) (xy 401.980087 -56.216987)
			(xy 401.996155 -56.270394) (xy 402.004275 -56.32557) (xy 402.004784 -56.353456) (xy 402.004275 -56.381342)
			(xy 401.996155 -56.436518) (xy 401.980087 -56.489925) (xy 401.956415 -56.540422) (xy 401.925642 -56.586935)
			(xy 401.888425 -56.628472) (xy 401.845557 -56.664147) (xy 401.797951 -56.693201) (xy 401.746622 -56.715013)
			(xy 401.692665 -56.729119) (xy 401.637228 -56.735219) (xy 401.581494 -56.733182) (xy 401.526651 -56.723052)
			(xy 401.473867 -56.705045) (xy 401.424267 -56.679544) (xy 401.378909 -56.647093) (xy 401.33876 -56.608384)
			(xy 401.304674 -56.564241) (xy 401.277378 -56.515606) (xy 401.257455 -56.463515) (xy 401.245329 -56.409078)
			(xy 401.241258 -56.353456) (xy 394.191296 -56.353456) (xy 394.193408 -56.360649) (xy 394.201164 -56.414597)
			(xy 394.20165 -56.441848) (xy 394.201189 -56.469182) (xy 394.19338 -56.52329) (xy 394.177929 -56.57573)
			(xy 394.155152 -56.625427) (xy 394.125515 -56.671365) (xy 394.107924 -56.692292) (xy 394.10767 -56.692546)
			(xy 394.107416 -56.6928) (xy 394.101825 -56.699884) (xy 394.095581 -56.716803) (xy 394.095224 -56.72582)
			(xy 394.095224 -56.792876) (xy 394.095588 -56.801892) (xy 394.10183 -56.81881) (xy 394.107416 -56.825896)
			(xy 394.10767 -56.82615) (xy 394.107924 -56.826404) (xy 394.125536 -56.847314) (xy 394.15517 -56.893256)
			(xy 394.177942 -56.942958) (xy 394.193386 -56.995401) (xy 394.201184 -57.049513) (xy 394.20165 -57.076848)
			(xy 394.201164 -57.104099) (xy 394.193408 -57.158047) (xy 394.178053 -57.210342) (xy 394.155411 -57.259919)
			(xy 394.125945 -57.305769) (xy 394.090254 -57.34696) (xy 394.049063 -57.382651) (xy 394.003213 -57.412117)
			(xy 393.953636 -57.434759) (xy 393.901341 -57.450114) (xy 393.847393 -57.45787) (xy 393.792891 -57.45787)
			(xy 393.738943 -57.450114) (xy 393.686648 -57.434759) (xy 393.637071 -57.412117) (xy 393.591221 -57.382651)
			(xy 393.55003 -57.34696) (xy 393.514339 -57.305769) (xy 393.484873 -57.259919) (xy 393.462231 -57.210342)
			(xy 393.446876 -57.158047) (xy 393.43912 -57.104099) (xy 393.438634 -57.076848) (xy 392.627257 -57.076848)
			(xy 392.644286 -57.081847) (xy 392.693872 -57.104489) (xy 392.73973 -57.133957) (xy 392.780928 -57.169652)
			(xy 392.816626 -57.210847) (xy 392.846098 -57.256703) (xy 392.868743 -57.306287) (xy 392.884101 -57.358589)
			(xy 392.891859 -57.412545) (xy 392.891859 -57.467055) (xy 392.889239 -57.48528) (xy 404.90597 -57.48528)
			(xy 404.910041 -57.429658) (xy 404.922167 -57.375221) (xy 404.94209 -57.32313) (xy 404.969386 -57.274495)
			(xy 405.003472 -57.230352) (xy 405.043621 -57.191643) (xy 405.088979 -57.159192) (xy 405.138579 -57.133691)
			(xy 405.191363 -57.115684) (xy 405.246206 -57.105554) (xy 405.30194 -57.103517) (xy 405.357377 -57.109617)
			(xy 405.411334 -57.123723) (xy 405.462663 -57.145535) (xy 405.510269 -57.174589) (xy 405.553137 -57.210264)
			(xy 405.590354 -57.251801) (xy 405.621127 -57.298314) (xy 405.644799 -57.348811) (xy 405.660867 -57.402218)
			(xy 405.668987 -57.457394) (xy 405.669496 -57.48528) (xy 405.668987 -57.513166) (xy 405.660867 -57.568342)
			(xy 405.644799 -57.621749) (xy 405.621127 -57.672246) (xy 405.590354 -57.718759) (xy 405.553137 -57.760296)
			(xy 405.510269 -57.795971) (xy 405.462663 -57.825025) (xy 405.411334 -57.846837) (xy 405.357377 -57.860943)
			(xy 405.30194 -57.867043) (xy 405.246206 -57.865006) (xy 405.191363 -57.854876) (xy 405.138579 -57.836869)
			(xy 405.088979 -57.811368) (xy 405.043621 -57.778917) (xy 405.003472 -57.740208) (xy 404.969386 -57.696065)
			(xy 404.94209 -57.64743) (xy 404.922167 -57.595339) (xy 404.910041 -57.540902) (xy 404.90597 -57.48528)
			(xy 392.889239 -57.48528) (xy 392.884101 -57.521011) (xy 392.868743 -57.573313) (xy 392.846098 -57.622897)
			(xy 392.816626 -57.668753) (xy 392.780928 -57.709948) (xy 392.73973 -57.745643) (xy 392.693872 -57.775111)
			(xy 392.644286 -57.797753) (xy 392.591983 -57.813107) (xy 392.538027 -57.820861) (xy 392.510772 -57.821322)
			(xy 392.510518 -57.821322) (xy 392.484224 -57.820844) (xy 392.432136 -57.813602) (xy 392.381536 -57.799279)
			(xy 392.33338 -57.778147) (xy 392.288579 -57.750606) (xy 392.247983 -57.717177) (xy 392.229848 -57.698132)
			(xy 392.222291 -57.690673) (xy 392.202862 -57.682157) (xy 392.192256 -57.681622) (xy 392.118088 -57.681622)
			(xy 392.107455 -57.682027) (xy 392.087991 -57.690578) (xy 392.080496 -57.698132) (xy 392.062365 -57.717186)
			(xy 392.021785 -57.750645) (xy 391.97699 -57.778206) (xy 391.92883 -57.799346) (xy 391.878221 -57.813663)
			(xy 391.826124 -57.820885) (xy 391.799826 -57.821322) (xy 391.799572 -57.821322) (xy 391.772323 -57.820806)
			(xy 391.71838 -57.813046) (xy 391.666091 -57.797689) (xy 391.616519 -57.775048) (xy 391.570674 -57.745582)
			(xy 391.529489 -57.709891) (xy 391.493802 -57.668704) (xy 391.464339 -57.622856) (xy 391.441701 -57.573283)
			(xy 391.426348 -57.520992) (xy 391.418592 -57.467049) (xy 391.23525 -57.467049) (xy 391.239063 -57.494543)
			(xy 391.239502 -57.52084) (xy 391.239502 -57.521094) (xy 391.238997 -57.548426) (xy 391.231197 -57.602532)
			(xy 391.215755 -57.65497) (xy 391.192988 -57.704669) (xy 391.163362 -57.750609) (xy 391.145776 -57.771538)
			(xy 391.145522 -57.771792) (xy 391.145268 -57.772046) (xy 391.139694 -57.779141) (xy 391.133441 -57.796051)
			(xy 391.133076 -57.805066) (xy 391.133076 -57.872122) (xy 391.133427 -57.881139) (xy 391.139679 -57.898056)
			(xy 391.145268 -57.905142) (xy 391.145522 -57.905396) (xy 391.145776 -57.90565) (xy 391.163369 -57.926578)
			(xy 391.193018 -57.972511) (xy 391.215805 -58.022207) (xy 391.23126 -58.074649) (xy 391.239069 -58.12876)
			(xy 391.239069 -58.183431) (xy 391.231262 -58.237542) (xy 391.215808 -58.289984) (xy 391.193023 -58.339681)
			(xy 391.163374 -58.385615) (xy 391.145776 -58.406538) (xy 391.145522 -58.406792) (xy 391.145268 -58.407046)
			(xy 391.139694 -58.414141) (xy 391.133441 -58.431051) (xy 391.133076 -58.440066) (xy 391.133076 -58.507122)
			(xy 391.133427 -58.516139) (xy 391.139679 -58.533056) (xy 391.145268 -58.540142) (xy 391.145522 -58.540396)
			(xy 391.145776 -58.54065) (xy 391.163355 -58.561587) (xy 391.192996 -58.60752) (xy 391.215775 -58.657215)
			(xy 391.231226 -58.709654) (xy 391.239032 -58.76376) (xy 391.239502 -58.791094) (xy 391.239016 -58.818345)
			(xy 391.23126 -58.872293) (xy 391.230863 -58.873644) (xy 392.500612 -58.873644) (xy 392.501077 -58.84631)
			(xy 392.508887 -58.792203) (xy 392.524337 -58.739764) (xy 392.547113 -58.690066) (xy 392.576748 -58.644127)
			(xy 392.594338 -58.6232) (xy 392.594592 -58.622946) (xy 392.594846 -58.622692) (xy 392.600448 -58.615616)
			(xy 392.606684 -58.598691) (xy 392.607038 -58.589672) (xy 392.607038 -58.522616) (xy 392.606665 -58.513601)
			(xy 392.600428 -58.496684) (xy 392.594846 -58.489596) (xy 392.594592 -58.489342) (xy 392.594338 -58.489088)
			(xy 392.576732 -58.468173) (xy 392.547095 -58.422233) (xy 392.52432 -58.372533) (xy 392.508876 -58.32009)
			(xy 392.501078 -58.265979) (xy 392.500612 -58.238644) (xy 392.501098 -58.211393) (xy 392.508854 -58.157445)
			(xy 392.524209 -58.10515) (xy 392.546851 -58.055573) (xy 392.576317 -58.009723) (xy 392.612008 -57.968532)
			(xy 392.653199 -57.932841) (xy 392.699049 -57.903375) (xy 392.748626 -57.880733) (xy 392.800921 -57.865378)
			(xy 392.854869 -57.857622) (xy 392.909371 -57.857622) (xy 392.963319 -57.865378) (xy 393.015614 -57.880733)
			(xy 393.065191 -57.903375) (xy 393.111041 -57.932841) (xy 393.152232 -57.968532) (xy 393.187923 -58.009723)
			(xy 393.217389 -58.055573) (xy 393.225016 -58.072274) (xy 400.293584 -58.072274) (xy 400.297655 -58.016652)
			(xy 400.309781 -57.962215) (xy 400.329704 -57.910124) (xy 400.357 -57.861489) (xy 400.391086 -57.817346)
			(xy 400.431235 -57.778637) (xy 400.476593 -57.746186) (xy 400.526193 -57.720685) (xy 400.578977 -57.702678)
			(xy 400.63382 -57.692548) (xy 400.689554 -57.690511) (xy 400.744991 -57.696611) (xy 400.798948 -57.710717)
			(xy 400.850277 -57.732529) (xy 400.897883 -57.761583) (xy 400.940751 -57.797258) (xy 400.977968 -57.838795)
			(xy 401.008741 -57.885308) (xy 401.032413 -57.935805) (xy 401.048481 -57.989212) (xy 401.056601 -58.044388)
			(xy 401.05711 -58.072274) (xy 401.05704 -58.076084) (xy 405.658064 -58.076084) (xy 405.662135 -58.020462)
			(xy 405.674261 -57.966025) (xy 405.694184 -57.913934) (xy 405.72148 -57.865299) (xy 405.755566 -57.821156)
			(xy 405.795715 -57.782447) (xy 405.841073 -57.749996) (xy 405.890673 -57.724495) (xy 405.943457 -57.706488)
			(xy 405.9983 -57.696358) (xy 406.054034 -57.694321) (xy 406.109471 -57.700421) (xy 406.163428 -57.714527)
			(xy 406.214757 -57.736339) (xy 406.262363 -57.765393) (xy 406.305231 -57.801068) (xy 406.342448 -57.842605)
			(xy 406.358784 -57.867296) (xy 407.943048 -57.867296) (xy 407.947119 -57.811674) (xy 407.959245 -57.757237)
			(xy 407.979168 -57.705146) (xy 408.006464 -57.656511) (xy 408.04055 -57.612368) (xy 408.080699 -57.573659)
			(xy 408.126057 -57.541208) (xy 408.175657 -57.515707) (xy 408.228441 -57.4977) (xy 408.283284 -57.48757)
			(xy 408.339018 -57.485533) (xy 408.394455 -57.491633) (xy 408.448412 -57.505739) (xy 408.499741 -57.527551)
			(xy 408.547347 -57.556605) (xy 408.590215 -57.59228) (xy 408.627432 -57.633817) (xy 408.658205 -57.68033)
			(xy 408.681877 -57.730827) (xy 408.697945 -57.784234) (xy 408.706065 -57.83941) (xy 408.706574 -57.867296)
			(xy 408.706065 -57.895182) (xy 408.697945 -57.950358) (xy 408.681877 -58.003765) (xy 408.658205 -58.054262)
			(xy 408.627432 -58.100775) (xy 408.590215 -58.142312) (xy 408.547347 -58.177987) (xy 408.499741 -58.207041)
			(xy 408.448412 -58.228853) (xy 408.394455 -58.242959) (xy 408.339018 -58.249059) (xy 408.283284 -58.247022)
			(xy 408.228441 -58.236892) (xy 408.175657 -58.218885) (xy 408.126057 -58.193384) (xy 408.080699 -58.160933)
			(xy 408.04055 -58.122224) (xy 408.006464 -58.078081) (xy 407.979168 -58.029446) (xy 407.959245 -57.977355)
			(xy 407.947119 -57.922918) (xy 407.943048 -57.867296) (xy 406.358784 -57.867296) (xy 406.373221 -57.889118)
			(xy 406.396893 -57.939615) (xy 406.412961 -57.993022) (xy 406.421081 -58.048198) (xy 406.42159 -58.076084)
			(xy 406.421081 -58.10397) (xy 406.412961 -58.159146) (xy 406.396893 -58.212553) (xy 406.373221 -58.26305)
			(xy 406.342448 -58.309563) (xy 406.305231 -58.3511) (xy 406.262363 -58.386775) (xy 406.214757 -58.415829)
			(xy 406.163428 -58.437641) (xy 406.109471 -58.451747) (xy 406.054034 -58.457847) (xy 405.9983 -58.45581)
			(xy 405.943457 -58.44568) (xy 405.890673 -58.427673) (xy 405.841073 -58.402172) (xy 405.795715 -58.369721)
			(xy 405.755566 -58.331012) (xy 405.72148 -58.286869) (xy 405.694184 -58.238234) (xy 405.674261 -58.186143)
			(xy 405.662135 -58.131706) (xy 405.658064 -58.076084) (xy 401.05704 -58.076084) (xy 401.056601 -58.10016)
			(xy 401.048481 -58.155336) (xy 401.032413 -58.208743) (xy 401.008741 -58.25924) (xy 400.977968 -58.305753)
			(xy 400.940751 -58.34729) (xy 400.897883 -58.382965) (xy 400.850277 -58.412019) (xy 400.798948 -58.433831)
			(xy 400.744991 -58.447937) (xy 400.689554 -58.454037) (xy 400.63382 -58.452) (xy 400.578977 -58.44187)
			(xy 400.526193 -58.423863) (xy 400.476593 -58.398362) (xy 400.431235 -58.365911) (xy 400.391086 -58.327202)
			(xy 400.357 -58.283059) (xy 400.329704 -58.234424) (xy 400.309781 -58.182333) (xy 400.297655 -58.127896)
			(xy 400.293584 -58.072274) (xy 393.225016 -58.072274) (xy 393.240031 -58.10515) (xy 393.255386 -58.157445)
			(xy 393.263142 -58.211393) (xy 393.263628 -58.238644) (xy 393.26317 -58.265978) (xy 393.255361 -58.320087)
			(xy 393.23991 -58.372526) (xy 393.217132 -58.422224) (xy 393.187494 -58.468162) (xy 393.169902 -58.489088)
			(xy 393.169648 -58.489342) (xy 393.169394 -58.489596) (xy 393.163802 -58.496679) (xy 393.157559 -58.513599)
			(xy 393.157202 -58.522616) (xy 393.157202 -58.561224) (xy 406.862278 -58.561224) (xy 406.866349 -58.505602)
			(xy 406.878475 -58.451165) (xy 406.898398 -58.399074) (xy 406.925694 -58.350439) (xy 406.95978 -58.306296)
			(xy 406.999929 -58.267587) (xy 407.045287 -58.235136) (xy 407.094887 -58.209635) (xy 407.147671 -58.191628)
			(xy 407.202514 -58.181498) (xy 407.258248 -58.179461) (xy 407.313685 -58.185561) (xy 407.367642 -58.199667)
			(xy 407.418971 -58.221479) (xy 407.466577 -58.250533) (xy 407.509445 -58.286208) (xy 407.546662 -58.327745)
			(xy 407.577435 -58.374258) (xy 407.601107 -58.424755) (xy 407.608617 -58.449718) (xy 409.108908 -58.449718)
			(xy 409.112979 -58.394096) (xy 409.125105 -58.339659) (xy 409.145028 -58.287568) (xy 409.172324 -58.238933)
			(xy 409.20641 -58.19479) (xy 409.246559 -58.156081) (xy 409.291917 -58.12363) (xy 409.341517 -58.098129)
			(xy 409.394301 -58.080122) (xy 409.449144 -58.069992) (xy 409.504878 -58.067955) (xy 409.560315 -58.074055)
			(xy 409.614272 -58.088161) (xy 409.665601 -58.109973) (xy 409.713207 -58.139027) (xy 409.756075 -58.174702)
			(xy 409.793292 -58.216239) (xy 409.824065 -58.262752) (xy 409.847737 -58.313249) (xy 409.863805 -58.366656)
			(xy 409.871925 -58.421832) (xy 409.872434 -58.449718) (xy 409.871925 -58.477604) (xy 409.863805 -58.53278)
			(xy 409.847737 -58.586187) (xy 409.824065 -58.636684) (xy 409.793292 -58.683197) (xy 409.756075 -58.724734)
			(xy 409.74806 -58.731404) (xy 413.82061 -58.731404) (xy 413.821111 -58.704071) (xy 413.828912 -58.649966)
			(xy 413.844354 -58.597527) (xy 413.867122 -58.547829) (xy 413.896749 -58.501888) (xy 413.914336 -58.48096)
			(xy 413.91459 -58.480706) (xy 413.914844 -58.480452) (xy 413.92042 -58.473359) (xy 413.926672 -58.456447)
			(xy 413.927036 -58.447432) (xy 413.927036 -58.380376) (xy 413.926683 -58.371359) (xy 413.920432 -58.354442)
			(xy 413.914844 -58.347356) (xy 413.91459 -58.347102) (xy 413.914336 -58.346848) (xy 413.896741 -58.325922)
			(xy 413.86709 -58.279989) (xy 413.844303 -58.230292) (xy 413.828847 -58.17785) (xy 413.821039 -58.123739)
			(xy 413.821039 -58.069067) (xy 413.828846 -58.014955) (xy 413.844301 -57.962514) (xy 413.867087 -57.912816)
			(xy 413.896737 -57.866883) (xy 413.914336 -57.84596) (xy 413.91459 -57.845706) (xy 413.914844 -57.845452)
			(xy 413.92042 -57.838359) (xy 413.926672 -57.821447) (xy 413.927036 -57.812432) (xy 413.927036 -57.745376)
			(xy 413.926683 -57.736359) (xy 413.920432 -57.719442) (xy 413.914844 -57.712356) (xy 413.91459 -57.712102)
			(xy 413.914336 -57.711848) (xy 413.896741 -57.690922) (xy 413.86709 -57.644989) (xy 413.844303 -57.595292)
			(xy 413.828847 -57.54285) (xy 413.821039 -57.488739) (xy 413.821039 -57.434067) (xy 413.828846 -57.379955)
			(xy 413.844301 -57.327514) (xy 413.867087 -57.277816) (xy 413.896737 -57.231883) (xy 413.914336 -57.21096)
			(xy 413.91459 -57.210706) (xy 413.914844 -57.210452) (xy 413.92042 -57.203359) (xy 413.926672 -57.186447)
			(xy 413.927036 -57.177432) (xy 413.927036 -57.110376) (xy 413.926683 -57.101359) (xy 413.920432 -57.084442)
			(xy 413.914844 -57.077356) (xy 413.91459 -57.077102) (xy 413.914336 -57.076848) (xy 413.896758 -57.05591)
			(xy 413.867116 -57.009977) (xy 413.844337 -56.960282) (xy 413.828886 -56.907844) (xy 413.82108 -56.853738)
			(xy 413.82061 -56.826404) (xy 413.821096 -56.799153) (xy 413.828852 -56.745205) (xy 413.844207 -56.69291)
			(xy 413.866849 -56.643333) (xy 413.896315 -56.597483) (xy 413.932006 -56.556292) (xy 413.973197 -56.520601)
			(xy 414.019047 -56.491135) (xy 414.068624 -56.468493) (xy 414.120919 -56.453138) (xy 414.174867 -56.445382)
			(xy 414.229369 -56.445382) (xy 414.283317 -56.453138) (xy 414.335612 -56.468493) (xy 414.385189 -56.491135)
			(xy 414.431039 -56.520601) (xy 414.47223 -56.556292) (xy 414.507921 -56.597483) (xy 414.537387 -56.643333)
			(xy 414.560029 -56.69291) (xy 414.575384 -56.745205) (xy 414.58314 -56.799153) (xy 414.583626 -56.826404)
			(xy 414.583145 -56.853737) (xy 414.575341 -56.907845) (xy 414.559895 -56.960284) (xy 414.537123 -57.009982)
			(xy 414.507489 -57.055921) (xy 414.4899 -57.076848) (xy 414.489646 -57.077102) (xy 414.489392 -57.077356)
			(xy 414.483817 -57.08445) (xy 414.477564 -57.101361) (xy 414.4772 -57.110376) (xy 414.4772 -57.177432)
			(xy 414.477542 -57.18645) (xy 414.4838 -57.203367) (xy 414.489392 -57.210452) (xy 414.489646 -57.210706)
			(xy 414.4899 -57.21096) (xy 414.507506 -57.231878) (xy 414.537161 -57.277811) (xy 414.559951 -57.327509)
			(xy 414.575409 -57.379952) (xy 414.583218 -57.434066) (xy 414.583218 -57.48874) (xy 414.575408 -57.542854)
			(xy 414.559949 -57.595297) (xy 414.537158 -57.644994) (xy 414.507502 -57.690927) (xy 414.4899 -57.711848)
			(xy 414.489646 -57.712102) (xy 414.489392 -57.712356) (xy 414.483817 -57.71945) (xy 414.477564 -57.736361)
			(xy 414.4772 -57.745376) (xy 414.4772 -57.812432) (xy 414.477542 -57.82145) (xy 414.4838 -57.838367)
			(xy 414.489392 -57.845452) (xy 414.489646 -57.845706) (xy 414.4899 -57.84596) (xy 414.507506 -57.866878)
			(xy 414.537161 -57.912811) (xy 414.559951 -57.962509) (xy 414.575409 -58.014952) (xy 414.583218 -58.069066)
			(xy 414.583218 -58.12374) (xy 414.575408 -58.177854) (xy 414.559949 -58.230297) (xy 414.537158 -58.279994)
			(xy 414.507502 -58.325927) (xy 414.4899 -58.346848) (xy 414.489646 -58.347102) (xy 414.489392 -58.347356)
			(xy 414.483817 -58.35445) (xy 414.477564 -58.371361) (xy 414.4772 -58.380376) (xy 414.4772 -58.447432)
			(xy 414.477542 -58.45645) (xy 414.4838 -58.473367) (xy 414.489392 -58.480452) (xy 414.489646 -58.480706)
			(xy 414.4899 -58.48096) (xy 414.507487 -58.50189) (xy 414.537126 -58.547826) (xy 414.559904 -58.597523)
			(xy 414.575353 -58.649962) (xy 414.583157 -58.70407) (xy 414.583626 -58.731404) (xy 414.58314 -58.758655)
			(xy 414.578476 -58.791094) (xy 416.476434 -58.791094) (xy 416.476923 -58.763761) (xy 416.484726 -58.709654)
			(xy 416.500171 -58.657215) (xy 416.522941 -58.607517) (xy 416.552572 -58.561578) (xy 416.57016 -58.54065)
			(xy 416.570414 -58.540396) (xy 416.570668 -58.540142) (xy 416.576251 -58.533053) (xy 416.582498 -58.516138)
			(xy 416.58286 -58.507122) (xy 416.58286 -58.440066) (xy 416.582528 -58.431046) (xy 416.576264 -58.414129)
			(xy 416.570668 -58.407046) (xy 416.570414 -58.406792) (xy 416.57016 -58.406538) (xy 416.552554 -58.38562)
			(xy 416.522902 -58.339686) (xy 416.500114 -58.289988) (xy 416.484658 -58.237545) (xy 416.47685 -58.183432)
			(xy 416.476851 -58.128759) (xy 416.48466 -58.074646) (xy 416.500117 -58.022203) (xy 416.522906 -57.972506)
			(xy 416.55256 -57.926572) (xy 416.57016 -57.90565) (xy 416.570414 -57.905396) (xy 416.570668 -57.905142)
			(xy 416.576251 -57.898053) (xy 416.582498 -57.881138) (xy 416.58286 -57.872122) (xy 416.58286 -57.805066)
			(xy 416.582528 -57.796046) (xy 416.576264 -57.779129) (xy 416.570668 -57.772046) (xy 416.570414 -57.771792)
			(xy 416.57016 -57.771538) (xy 416.552566 -57.750614) (xy 416.522929 -57.704676) (xy 416.500154 -57.654978)
			(xy 416.484706 -57.602537) (xy 416.476903 -57.548428) (xy 416.476434 -57.521094) (xy 416.476434 -57.52084)
			(xy 416.476909 -57.494546) (xy 416.484149 -57.442457) (xy 416.498471 -57.391856) (xy 416.519604 -57.343699)
			(xy 416.547146 -57.298899) (xy 416.580578 -57.258304) (xy 416.599624 -57.24017) (xy 416.607066 -57.232599)
			(xy 416.615594 -57.213181) (xy 416.616134 -57.202578) (xy 416.616134 -57.12841) (xy 416.6157 -57.117781)
			(xy 416.607167 -57.098317) (xy 416.599624 -57.090818) (xy 416.580573 -57.072685) (xy 416.547115 -57.032104)
			(xy 416.519554 -56.987309) (xy 416.498414 -56.93915) (xy 416.484096 -56.888542) (xy 416.476872 -56.836445)
			(xy 416.476434 -56.810148) (xy 416.476434 -56.809894) (xy 416.47692 -56.782643) (xy 416.484676 -56.728695)
			(xy 416.500031 -56.6764) (xy 416.522673 -56.626823) (xy 416.552139 -56.580973) (xy 416.58783 -56.539782)
			(xy 416.629021 -56.504091) (xy 416.674871 -56.474625) (xy 416.724448 -56.451983) (xy 416.776743 -56.436628)
			(xy 416.830691 -56.428872) (xy 416.885193 -56.428872) (xy 416.939141 -56.436628) (xy 416.991436 -56.451983)
			(xy 417.041013 -56.474625) (xy 417.086863 -56.504091) (xy 417.128054 -56.539782) (xy 417.163745 -56.580973)
			(xy 417.193211 -56.626823) (xy 417.215853 -56.6764) (xy 417.231208 -56.728695) (xy 417.238964 -56.782643)
			(xy 417.23945 -56.809894) (xy 417.23945 -56.810148) (xy 417.239039 -56.836445) (xy 417.231786 -56.888536)
			(xy 417.217452 -56.939139) (xy 417.196308 -56.987295) (xy 417.168753 -57.032094) (xy 417.135311 -57.072686)
			(xy 417.11626 -57.090818) (xy 417.108821 -57.098392) (xy 417.100292 -57.117808) (xy 417.09975 -57.12841)
			(xy 417.09975 -57.202578) (xy 417.100195 -57.213206) (xy 417.108721 -57.232669) (xy 417.11626 -57.24017)
			(xy 417.135303 -57.258312) (xy 417.168762 -57.29889) (xy 417.196324 -57.343684) (xy 417.217466 -57.391841)
			(xy 417.231785 -57.442448) (xy 417.235198 -57.467053) (xy 417.418469 -57.467053) (xy 417.418469 -57.412547)
			(xy 417.426227 -57.358597) (xy 417.441583 -57.306299) (xy 417.464226 -57.256719) (xy 417.493695 -57.210867)
			(xy 417.529389 -57.169675) (xy 417.570583 -57.133983) (xy 417.616437 -57.104517) (xy 417.666018 -57.081876)
			(xy 417.718316 -57.066522) (xy 417.772267 -57.058768) (xy 417.79952 -57.058306) (xy 417.799774 -57.058306)
			(xy 417.826068 -57.05878) (xy 417.878156 -57.066022) (xy 417.928758 -57.080345) (xy 417.976914 -57.101477)
			(xy 418.021714 -57.12902) (xy 418.062309 -57.162451) (xy 418.080444 -57.181496) (xy 418.088001 -57.188955)
			(xy 418.10743 -57.19747) (xy 418.118036 -57.198006) (xy 418.192204 -57.198006) (xy 418.202835 -57.197589)
			(xy 418.222299 -57.189045) (xy 418.229796 -57.181496) (xy 418.247917 -57.162432) (xy 418.288501 -57.128977)
			(xy 418.333299 -57.101419) (xy 418.38146 -57.080281) (xy 418.43207 -57.065965) (xy 418.484168 -57.058743)
			(xy 418.510466 -57.058306) (xy 418.51072 -57.058306) (xy 418.537971 -57.058765) (xy 418.591919 -57.066524)
			(xy 418.627072 -57.076848) (xy 419.438582 -57.076848) (xy 419.439057 -57.049515) (xy 419.446865 -56.995408)
			(xy 419.462314 -56.942969) (xy 419.485087 -56.893271) (xy 419.514719 -56.847332) (xy 419.532308 -56.826404)
			(xy 419.532562 -56.82615) (xy 419.532816 -56.825896) (xy 419.538412 -56.818816) (xy 419.544653 -56.801894)
			(xy 419.545008 -56.792876) (xy 419.545008 -56.72582) (xy 419.54464 -56.716804) (xy 419.5384 -56.699887)
			(xy 419.532816 -56.6928) (xy 419.532562 -56.692546) (xy 419.532308 -56.692292) (xy 419.5147 -56.671379)
			(xy 419.485063 -56.625439) (xy 419.46229 -56.575738) (xy 419.446846 -56.523294) (xy 419.439048 -56.469183)
			(xy 419.438582 -56.441848) (xy 419.439068 -56.414597) (xy 419.446824 -56.360649) (xy 419.462179 -56.308354)
			(xy 419.484821 -56.258777) (xy 419.514287 -56.212927) (xy 419.549978 -56.171736) (xy 419.591169 -56.136045)
			(xy 419.637019 -56.106579) (xy 419.686596 -56.083937) (xy 419.738891 -56.068582) (xy 419.792839 -56.060826)
			(xy 419.847341 -56.060826) (xy 419.901289 -56.068582) (xy 419.953584 -56.083937) (xy 420.003161 -56.106579)
			(xy 420.049011 -56.136045) (xy 420.090202 -56.171736) (xy 420.125893 -56.212927) (xy 420.155359 -56.258777)
			(xy 420.178001 -56.308354) (xy 420.191244 -56.353456) (xy 427.241206 -56.353456) (xy 427.245277 -56.297834)
			(xy 427.257403 -56.243397) (xy 427.277326 -56.191306) (xy 427.304622 -56.142671) (xy 427.338708 -56.098528)
			(xy 427.378857 -56.059819) (xy 427.424215 -56.027368) (xy 427.473815 -56.001867) (xy 427.526599 -55.98386)
			(xy 427.581442 -55.97373) (xy 427.637176 -55.971693) (xy 427.692613 -55.977793) (xy 427.74657 -55.991899)
			(xy 427.797899 -56.013711) (xy 427.845505 -56.042765) (xy 427.888373 -56.07844) (xy 427.92559 -56.119977)
			(xy 427.956363 -56.16649) (xy 427.980035 -56.216987) (xy 427.996103 -56.270394) (xy 428.004223 -56.32557)
			(xy 428.004732 -56.353456) (xy 428.004223 -56.381342) (xy 427.996103 -56.436518) (xy 427.980035 -56.489925)
			(xy 427.956363 -56.540422) (xy 427.92559 -56.586935) (xy 427.888373 -56.628472) (xy 427.845505 -56.664147)
			(xy 427.797899 -56.693201) (xy 427.74657 -56.715013) (xy 427.692613 -56.729119) (xy 427.637176 -56.735219)
			(xy 427.581442 -56.733182) (xy 427.526599 -56.723052) (xy 427.473815 -56.705045) (xy 427.424215 -56.679544)
			(xy 427.378857 -56.647093) (xy 427.338708 -56.608384) (xy 427.304622 -56.564241) (xy 427.277326 -56.515606)
			(xy 427.257403 -56.463515) (xy 427.245277 -56.409078) (xy 427.241206 -56.353456) (xy 420.191244 -56.353456)
			(xy 420.193356 -56.360649) (xy 420.201112 -56.414597) (xy 420.201598 -56.441848) (xy 420.201126 -56.469182)
			(xy 420.193318 -56.523289) (xy 420.177868 -56.575728) (xy 420.155094 -56.625425) (xy 420.125461 -56.671364)
			(xy 420.107872 -56.692292) (xy 420.107618 -56.692546) (xy 420.107364 -56.6928) (xy 420.101767 -56.699879)
			(xy 420.095528 -56.716802) (xy 420.095172 -56.72582) (xy 420.095172 -56.792876) (xy 420.095547 -56.801891)
			(xy 420.101783 -56.818808) (xy 420.107364 -56.825896) (xy 420.107618 -56.82615) (xy 420.107872 -56.826404)
			(xy 420.125475 -56.847321) (xy 420.155113 -56.89326) (xy 420.177888 -56.94296) (xy 420.193333 -56.995403)
			(xy 420.201132 -57.049513) (xy 420.201598 -57.076848) (xy 420.201112 -57.104099) (xy 420.193356 -57.158047)
			(xy 420.178001 -57.210342) (xy 420.155359 -57.259919) (xy 420.125893 -57.305769) (xy 420.090202 -57.34696)
			(xy 420.049011 -57.382651) (xy 420.003161 -57.412117) (xy 419.953584 -57.434759) (xy 419.901289 -57.450114)
			(xy 419.847341 -57.45787) (xy 419.792839 -57.45787) (xy 419.738891 -57.450114) (xy 419.686596 -57.434759)
			(xy 419.637019 -57.412117) (xy 419.591169 -57.382651) (xy 419.549978 -57.34696) (xy 419.514287 -57.305769)
			(xy 419.484821 -57.259919) (xy 419.462179 -57.210342) (xy 419.446824 -57.158047) (xy 419.439068 -57.104099)
			(xy 419.438582 -57.076848) (xy 418.627072 -57.076848) (xy 418.644213 -57.081882) (xy 418.69379 -57.104525)
			(xy 418.739639 -57.133993) (xy 418.780829 -57.169686) (xy 418.816519 -57.210877) (xy 418.845985 -57.256728)
			(xy 418.868625 -57.306306) (xy 418.88398 -57.358601) (xy 418.891736 -57.412549) (xy 418.891736 -57.467051)
			(xy 418.889115 -57.48528) (xy 430.905918 -57.48528) (xy 430.909989 -57.429658) (xy 430.922115 -57.375221)
			(xy 430.942038 -57.32313) (xy 430.969334 -57.274495) (xy 431.00342 -57.230352) (xy 431.043569 -57.191643)
			(xy 431.088927 -57.159192) (xy 431.138527 -57.133691) (xy 431.191311 -57.115684) (xy 431.246154 -57.105554)
			(xy 431.301888 -57.103517) (xy 431.357325 -57.109617) (xy 431.411282 -57.123723) (xy 431.462611 -57.145535)
			(xy 431.510217 -57.174589) (xy 431.553085 -57.210264) (xy 431.590302 -57.251801) (xy 431.621075 -57.298314)
			(xy 431.644747 -57.348811) (xy 431.660815 -57.402218) (xy 431.668935 -57.457394) (xy 431.669444 -57.48528)
			(xy 431.668935 -57.513166) (xy 431.660815 -57.568342) (xy 431.644747 -57.621749) (xy 431.621075 -57.672246)
			(xy 431.590302 -57.718759) (xy 431.553085 -57.760296) (xy 431.510217 -57.795971) (xy 431.462611 -57.825025)
			(xy 431.411282 -57.846837) (xy 431.357325 -57.860943) (xy 431.301888 -57.867043) (xy 431.246154 -57.865006)
			(xy 431.191311 -57.854876) (xy 431.138527 -57.836869) (xy 431.088927 -57.811368) (xy 431.043569 -57.778917)
			(xy 431.00342 -57.740208) (xy 430.969334 -57.696065) (xy 430.942038 -57.64743) (xy 430.922115 -57.595339)
			(xy 430.909989 -57.540902) (xy 430.905918 -57.48528) (xy 418.889115 -57.48528) (xy 418.88398 -57.520999)
			(xy 418.868625 -57.573294) (xy 418.845985 -57.622872) (xy 418.816519 -57.668723) (xy 418.780829 -57.709914)
			(xy 418.739639 -57.745607) (xy 418.69379 -57.775075) (xy 418.644213 -57.797718) (xy 418.591919 -57.813076)
			(xy 418.537971 -57.820835) (xy 418.51072 -57.821322) (xy 418.510466 -57.821322) (xy 418.484171 -57.820879)
			(xy 418.432082 -57.813629) (xy 418.38148 -57.7993) (xy 418.333324 -57.778161) (xy 418.288525 -57.750614)
			(xy 418.24793 -57.717179) (xy 418.229796 -57.698132) (xy 418.222221 -57.690695) (xy 418.202806 -57.682166)
			(xy 418.192204 -57.681622) (xy 418.118036 -57.681622) (xy 418.1074 -57.681998) (xy 418.087936 -57.69057)
			(xy 418.080444 -57.698132) (xy 418.06229 -57.717162) (xy 418.021715 -57.750624) (xy 417.976924 -57.778188)
			(xy 417.928769 -57.799332) (xy 417.878164 -57.813654) (xy 417.82607 -57.820882) (xy 417.799774 -57.821322)
			(xy 417.79952 -57.821322) (xy 417.772267 -57.820832) (xy 417.718316 -57.813078) (xy 417.666018 -57.797724)
			(xy 417.616437 -57.775083) (xy 417.570583 -57.745617) (xy 417.529389 -57.709925) (xy 417.493695 -57.668733)
			(xy 417.464226 -57.622881) (xy 417.441583 -57.573301) (xy 417.426227 -57.521003) (xy 417.418469 -57.467053)
			(xy 417.235198 -57.467053) (xy 417.239011 -57.494543) (xy 417.23945 -57.52084) (xy 417.23945 -57.521094)
			(xy 417.238958 -57.548427) (xy 417.231156 -57.602534) (xy 417.215712 -57.654973) (xy 417.192942 -57.704671)
			(xy 417.163312 -57.75061) (xy 417.145724 -57.771538) (xy 417.14547 -57.771792) (xy 417.145216 -57.772046)
			(xy 417.139648 -57.779145) (xy 417.13339 -57.796052) (xy 417.133024 -57.805066) (xy 417.133024 -57.872122)
			(xy 417.133365 -57.881141) (xy 417.139623 -57.898058) (xy 417.145216 -57.905142) (xy 417.14547 -57.905396)
			(xy 417.145724 -57.90565) (xy 417.163319 -57.926577) (xy 417.192973 -57.972509) (xy 417.215762 -58.022205)
			(xy 417.23122 -58.074647) (xy 417.239029 -58.128759) (xy 417.23903 -58.183432) (xy 417.231222 -58.237544)
			(xy 417.215765 -58.289986) (xy 417.192977 -58.339683) (xy 417.163324 -58.385616) (xy 417.145724 -58.406538)
			(xy 417.14547 -58.406792) (xy 417.145216 -58.407046) (xy 417.139648 -58.414145) (xy 417.13339 -58.431052)
			(xy 417.133024 -58.440066) (xy 417.133024 -58.507122) (xy 417.133365 -58.516141) (xy 417.139623 -58.533058)
			(xy 417.145216 -58.540142) (xy 417.14547 -58.540396) (xy 417.145724 -58.54065) (xy 417.16331 -58.561581)
			(xy 417.192949 -58.607517) (xy 417.215726 -58.657213) (xy 417.231175 -58.709653) (xy 417.23898 -58.76376)
			(xy 417.23945 -58.791094) (xy 417.238964 -58.818345) (xy 417.231208 -58.872293) (xy 417.230811 -58.873644)
			(xy 418.50056 -58.873644) (xy 418.501014 -58.84631) (xy 418.508824 -58.792201) (xy 418.524277 -58.739762)
			(xy 418.547055 -58.690064) (xy 418.576694 -58.644126) (xy 418.594286 -58.6232) (xy 418.59454 -58.622946)
			(xy 418.594794 -58.622692) (xy 418.600389 -58.615611) (xy 418.606631 -58.59869) (xy 418.606986 -58.589672)
			(xy 418.606986 -58.522616) (xy 418.606625 -58.5136) (xy 418.60038 -58.496682) (xy 418.594794 -58.489596)
			(xy 418.59454 -58.489342) (xy 418.594286 -58.489088) (xy 418.576672 -58.468179) (xy 418.547038 -58.422237)
			(xy 418.524266 -58.372535) (xy 418.508823 -58.320091) (xy 418.501025 -58.265979) (xy 418.50056 -58.238644)
			(xy 418.501046 -58.211393) (xy 418.508802 -58.157445) (xy 418.524157 -58.10515) (xy 418.546799 -58.055573)
			(xy 418.576265 -58.009723) (xy 418.611956 -57.968532) (xy 418.653147 -57.932841) (xy 418.698997 -57.903375)
			(xy 418.748574 -57.880733) (xy 418.800869 -57.865378) (xy 418.854817 -57.857622) (xy 418.909319 -57.857622)
			(xy 418.963267 -57.865378) (xy 419.015562 -57.880733) (xy 419.065139 -57.903375) (xy 419.110989 -57.932841)
			(xy 419.15218 -57.968532) (xy 419.187871 -58.009723) (xy 419.217337 -58.055573) (xy 419.224964 -58.072274)
			(xy 426.293532 -58.072274) (xy 426.297603 -58.016652) (xy 426.309729 -57.962215) (xy 426.329652 -57.910124)
			(xy 426.356948 -57.861489) (xy 426.391034 -57.817346) (xy 426.431183 -57.778637) (xy 426.476541 -57.746186)
			(xy 426.526141 -57.720685) (xy 426.578925 -57.702678) (xy 426.633768 -57.692548) (xy 426.689502 -57.690511)
			(xy 426.744939 -57.696611) (xy 426.798896 -57.710717) (xy 426.850225 -57.732529) (xy 426.897831 -57.761583)
			(xy 426.940699 -57.797258) (xy 426.977916 -57.838795) (xy 427.008689 -57.885308) (xy 427.032361 -57.935805)
			(xy 427.048429 -57.989212) (xy 427.056549 -58.044388) (xy 427.057058 -58.072274) (xy 427.056988 -58.076084)
			(xy 431.658012 -58.076084) (xy 431.662083 -58.020462) (xy 431.674209 -57.966025) (xy 431.694132 -57.913934)
			(xy 431.721428 -57.865299) (xy 431.755514 -57.821156) (xy 431.795663 -57.782447) (xy 431.841021 -57.749996)
			(xy 431.890621 -57.724495) (xy 431.943405 -57.706488) (xy 431.998248 -57.696358) (xy 432.053982 -57.694321)
			(xy 432.109419 -57.700421) (xy 432.163376 -57.714527) (xy 432.214705 -57.736339) (xy 432.262311 -57.765393)
			(xy 432.305179 -57.801068) (xy 432.342396 -57.842605) (xy 432.373169 -57.889118) (xy 432.396841 -57.939615)
			(xy 432.412909 -57.993022) (xy 432.421029 -58.048198) (xy 432.421538 -58.076084) (xy 432.42107 -58.101738)
			(xy 433.942996 -58.101738) (xy 433.947067 -58.046116) (xy 433.959193 -57.991679) (xy 433.979116 -57.939588)
			(xy 434.006412 -57.890953) (xy 434.040498 -57.84681) (xy 434.080647 -57.808101) (xy 434.126005 -57.77565)
			(xy 434.175605 -57.750149) (xy 434.228389 -57.732142) (xy 434.283232 -57.722012) (xy 434.338966 -57.719975)
			(xy 434.394403 -57.726075) (xy 434.44836 -57.740181) (xy 434.499689 -57.761993) (xy 434.547295 -57.791047)
			(xy 434.590163 -57.826722) (xy 434.62738 -57.868259) (xy 434.658153 -57.914772) (xy 434.681825 -57.965269)
			(xy 434.697893 -58.018676) (xy 434.706013 -58.073852) (xy 434.706522 -58.101738) (xy 434.706013 -58.129624)
			(xy 434.697893 -58.1848) (xy 434.681825 -58.238207) (xy 434.658153 -58.288704) (xy 434.62738 -58.335217)
			(xy 434.590163 -58.376754) (xy 434.547295 -58.412429) (xy 434.499689 -58.441483) (xy 434.48031 -58.449718)
			(xy 435.108856 -58.449718) (xy 435.112927 -58.394096) (xy 435.125053 -58.339659) (xy 435.144976 -58.287568)
			(xy 435.172272 -58.238933) (xy 435.206358 -58.19479) (xy 435.246507 -58.156081) (xy 435.291865 -58.12363)
			(xy 435.341465 -58.098129) (xy 435.394249 -58.080122) (xy 435.449092 -58.069992) (xy 435.504826 -58.067955)
			(xy 435.560263 -58.074055) (xy 435.61422 -58.088161) (xy 435.665549 -58.109973) (xy 435.713155 -58.139027)
			(xy 435.756023 -58.174702) (xy 435.79324 -58.216239) (xy 435.824013 -58.262752) (xy 435.847685 -58.313249)
			(xy 435.863753 -58.366656) (xy 435.871873 -58.421832) (xy 435.872382 -58.449718) (xy 435.871873 -58.477604)
			(xy 435.863753 -58.53278) (xy 435.847685 -58.586187) (xy 435.824013 -58.636684) (xy 435.79324 -58.683197)
			(xy 435.756023 -58.724734) (xy 435.748008 -58.731404) (xy 439.820558 -58.731404) (xy 439.821047 -58.704071)
			(xy 439.828849 -58.649964) (xy 439.844294 -58.597525) (xy 439.867064 -58.547827) (xy 439.896695 -58.501887)
			(xy 439.914284 -58.48096) (xy 439.914538 -58.480706) (xy 439.914792 -58.480452) (xy 439.920362 -58.473354)
			(xy 439.926619 -58.456446) (xy 439.926984 -58.447432) (xy 439.926984 -58.380376) (xy 439.926642 -58.371358)
			(xy 439.920384 -58.354441) (xy 439.914792 -58.347356) (xy 439.914538 -58.347102) (xy 439.914284 -58.346848)
			(xy 439.896687 -58.325923) (xy 439.867033 -58.279991) (xy 439.844243 -58.230294) (xy 439.828785 -58.177852)
			(xy 439.820975 -58.12374) (xy 439.820975 -58.069066) (xy 439.828783 -58.014954) (xy 439.844241 -57.962511)
			(xy 439.86703 -57.912814) (xy 439.896683 -57.866882) (xy 439.914284 -57.84596) (xy 439.914538 -57.845706)
			(xy 439.914792 -57.845452) (xy 439.920362 -57.838354) (xy 439.926619 -57.821446) (xy 439.926984 -57.812432)
			(xy 439.926984 -57.745376) (xy 439.926642 -57.736358) (xy 439.920384 -57.719441) (xy 439.914792 -57.712356)
			(xy 439.914538 -57.712102) (xy 439.914284 -57.711848) (xy 439.896687 -57.690923) (xy 439.867033 -57.644991)
			(xy 439.844243 -57.595294) (xy 439.828785 -57.542852) (xy 439.820975 -57.48874) (xy 439.820975 -57.434066)
			(xy 439.828783 -57.379954) (xy 439.844241 -57.327511) (xy 439.86703 -57.277814) (xy 439.896683 -57.231882)
			(xy 439.914284 -57.21096) (xy 439.914538 -57.210706) (xy 439.914792 -57.210452) (xy 439.920362 -57.203354)
			(xy 439.926619 -57.186446) (xy 439.926984 -57.177432) (xy 439.926984 -57.110376) (xy 439.926642 -57.101358)
			(xy 439.920384 -57.084441) (xy 439.914792 -57.077356) (xy 439.914538 -57.077102) (xy 439.914284 -57.076848)
			(xy 439.896698 -57.055917) (xy 439.867059 -57.009981) (xy 439.844282 -56.960285) (xy 439.828833 -56.907845)
			(xy 439.821028 -56.853738) (xy 439.820558 -56.826404) (xy 439.821044 -56.799153) (xy 439.8288 -56.745205)
			(xy 439.844155 -56.69291) (xy 439.866797 -56.643333) (xy 439.896263 -56.597483) (xy 439.931954 -56.556292)
			(xy 439.973145 -56.520601) (xy 440.018995 -56.491135) (xy 440.068572 -56.468493) (xy 440.120867 -56.453138)
			(xy 440.174815 -56.445382) (xy 440.229317 -56.445382) (xy 440.283265 -56.453138) (xy 440.33556 -56.468493)
			(xy 440.385137 -56.491135) (xy 440.430987 -56.520601) (xy 440.472178 -56.556292) (xy 440.507869 -56.597483)
			(xy 440.537335 -56.643333) (xy 440.559977 -56.69291) (xy 440.575332 -56.745205) (xy 440.583088 -56.799153)
			(xy 440.583574 -56.826404) (xy 440.583082 -56.853737) (xy 440.575279 -56.907843) (xy 440.559835 -56.960282)
			(xy 440.537065 -57.00998) (xy 440.507436 -57.05592) (xy 440.489848 -57.076848) (xy 440.489594 -57.077102)
			(xy 440.48934 -57.077356) (xy 440.483759 -57.084446) (xy 440.47751 -57.10136) (xy 440.477148 -57.110376)
			(xy 440.477148 -57.177432) (xy 440.477479 -57.186452) (xy 440.483743 -57.203369) (xy 440.48934 -57.210452)
			(xy 440.489594 -57.210706) (xy 440.489848 -57.21096) (xy 440.507452 -57.231879) (xy 440.537103 -57.277813)
			(xy 440.559891 -57.327511) (xy 440.575347 -57.379954) (xy 440.583154 -57.434066) (xy 440.583154 -57.48874)
			(xy 440.575345 -57.542852) (xy 440.559888 -57.595295) (xy 440.5371 -57.644992) (xy 440.507448 -57.690926)
			(xy 440.489848 -57.711848) (xy 440.489594 -57.712102) (xy 440.48934 -57.712356) (xy 440.483759 -57.719446)
			(xy 440.47751 -57.73636) (xy 440.477148 -57.745376) (xy 440.477148 -57.812432) (xy 440.477479 -57.821452)
			(xy 440.483743 -57.838369) (xy 440.48934 -57.845452) (xy 440.489594 -57.845706) (xy 440.489848 -57.84596)
			(xy 440.507452 -57.866879) (xy 440.537103 -57.912813) (xy 440.559891 -57.962511) (xy 440.575347 -58.014954)
			(xy 440.583154 -58.069066) (xy 440.583154 -58.12374) (xy 440.575345 -58.177852) (xy 440.559888 -58.230295)
			(xy 440.5371 -58.279992) (xy 440.507448 -58.325926) (xy 440.489848 -58.346848) (xy 440.489594 -58.347102)
			(xy 440.48934 -58.347356) (xy 440.483759 -58.354446) (xy 440.47751 -58.37136) (xy 440.477148 -58.380376)
			(xy 440.477148 -58.447432) (xy 440.477479 -58.456452) (xy 440.483743 -58.473369) (xy 440.48934 -58.480452)
			(xy 440.489594 -58.480706) (xy 440.489848 -58.48096) (xy 440.507443 -58.501884) (xy 440.537079 -58.547822)
			(xy 440.559854 -58.59752) (xy 440.575302 -58.649961) (xy 440.583105 -58.70407) (xy 440.583574 -58.731404)
			(xy 440.583088 -58.758655) (xy 440.578424 -58.791094) (xy 442.476382 -58.791094) (xy 442.476884 -58.763761)
			(xy 442.484685 -58.709656) (xy 442.500128 -58.657218) (xy 442.522895 -58.607519) (xy 442.552522 -58.561579)
			(xy 442.570108 -58.54065) (xy 442.570362 -58.540396) (xy 442.570616 -58.540142) (xy 442.576193 -58.533049)
			(xy 442.582445 -58.516137) (xy 442.582808 -58.507122) (xy 442.582808 -58.440066) (xy 442.582465 -58.431048)
			(xy 442.576207 -58.414131) (xy 442.570616 -58.407046) (xy 442.570362 -58.406792) (xy 442.570108 -58.406538)
			(xy 442.5525 -58.385621) (xy 442.522844 -58.339688) (xy 442.500054 -58.28999) (xy 442.484595 -58.237547)
			(xy 442.476786 -58.183433) (xy 442.476787 -58.128758) (xy 442.484597 -58.074644) (xy 442.500057 -58.022201)
			(xy 442.522849 -57.972504) (xy 442.552506 -57.926571) (xy 442.570108 -57.90565) (xy 442.570362 -57.905396)
			(xy 442.570616 -57.905142) (xy 442.576193 -57.898049) (xy 442.582445 -57.881137) (xy 442.582808 -57.872122)
			(xy 442.582808 -57.805066) (xy 442.582465 -57.796048) (xy 442.576207 -57.779131) (xy 442.570616 -57.772046)
			(xy 442.570362 -57.771792) (xy 442.570108 -57.771538) (xy 442.552521 -57.750608) (xy 442.522882 -57.704672)
			(xy 442.500104 -57.654975) (xy 442.484655 -57.602536) (xy 442.476851 -57.548428) (xy 442.476382 -57.521094)
			(xy 442.476382 -57.52084) (xy 442.476873 -57.494546) (xy 442.484113 -57.442459) (xy 442.498433 -57.391859)
			(xy 442.519562 -57.343703) (xy 442.547101 -57.298902) (xy 442.580528 -57.258306) (xy 442.599572 -57.24017)
			(xy 442.607021 -57.232605) (xy 442.615543 -57.213182) (xy 442.616082 -57.202578) (xy 442.616082 -57.12841)
			(xy 442.615664 -57.117779) (xy 442.607121 -57.098314) (xy 442.599572 -57.090818) (xy 442.58053 -57.072676)
			(xy 442.547069 -57.032098) (xy 442.519506 -56.987305) (xy 442.498364 -56.939148) (xy 442.484045 -56.88854)
			(xy 442.47682 -56.836445) (xy 442.476382 -56.810148) (xy 442.476382 -56.809894) (xy 442.476868 -56.782643)
			(xy 442.484624 -56.728695) (xy 442.499979 -56.6764) (xy 442.522621 -56.626823) (xy 442.552087 -56.580973)
			(xy 442.587778 -56.539782) (xy 442.628969 -56.504091) (xy 442.674819 -56.474625) (xy 442.724396 -56.451983)
			(xy 442.776691 -56.436628) (xy 442.830639 -56.428872) (xy 442.885141 -56.428872) (xy 442.939089 -56.436628)
			(xy 442.991384 -56.451983) (xy 443.040961 -56.474625) (xy 443.086811 -56.504091) (xy 443.128002 -56.539782)
			(xy 443.163693 -56.580973) (xy 443.193159 -56.626823) (xy 443.215801 -56.6764) (xy 443.231156 -56.728695)
			(xy 443.238912 -56.782643) (xy 443.239398 -56.809894) (xy 443.239398 -56.810148) (xy 443.238972 -56.836444)
			(xy 443.23172 -56.888534) (xy 443.217388 -56.939136) (xy 443.196246 -56.987292) (xy 443.168695 -57.032091)
			(xy 443.135257 -57.072685) (xy 443.116208 -57.090818) (xy 443.108761 -57.098385) (xy 443.100239 -57.117806)
			(xy 443.099698 -57.12841) (xy 443.099698 -57.202578) (xy 443.100129 -57.213208) (xy 443.108663 -57.232672)
			(xy 443.116208 -57.24017) (xy 443.13526 -57.258302) (xy 443.168716 -57.298884) (xy 443.196276 -57.34368)
			(xy 443.217416 -57.391839) (xy 443.231734 -57.442447) (xy 443.235146 -57.467049) (xy 443.418492 -57.467049)
			(xy 443.418492 -57.412551) (xy 443.426248 -57.358608) (xy 443.4416 -57.306318) (xy 443.464238 -57.256745)
			(xy 443.493701 -57.210898) (xy 443.529387 -57.16971) (xy 443.570572 -57.13402) (xy 443.616417 -57.104554)
			(xy 443.665988 -57.081912) (xy 443.718277 -57.066554) (xy 443.772219 -57.058794) (xy 443.799468 -57.058306)
			(xy 443.799722 -57.058306) (xy 443.826017 -57.058748) (xy 443.878107 -57.065997) (xy 443.928709 -57.080326)
			(xy 443.976865 -57.101464) (xy 444.021664 -57.129012) (xy 444.062258 -57.162448) (xy 444.080392 -57.181496)
			(xy 444.087968 -57.188932) (xy 444.107383 -57.19746) (xy 444.117984 -57.198006) (xy 444.192152 -57.198006)
			(xy 444.202786 -57.197615) (xy 444.22225 -57.189053) (xy 444.229744 -57.181496) (xy 444.247841 -57.162409)
			(xy 444.28843 -57.128956) (xy 444.333233 -57.1014) (xy 444.381399 -57.080267) (xy 444.432013 -57.065956)
			(xy 444.484115 -57.05874) (xy 444.510414 -57.058306) (xy 444.510668 -57.058306) (xy 444.537923 -57.058739)
			(xy 444.59188 -57.066492) (xy 444.627157 -57.076848) (xy 445.43853 -57.076848) (xy 445.438993 -57.049514)
			(xy 445.446802 -56.995406) (xy 445.462253 -56.942967) (xy 445.48503 -56.893269) (xy 445.514665 -56.847331)
			(xy 445.532256 -56.826404) (xy 445.53251 -56.82615) (xy 445.532764 -56.825896) (xy 445.538366 -56.81882)
			(xy 445.544602 -56.801895) (xy 445.544956 -56.792876) (xy 445.544956 -56.72582) (xy 445.544599 -56.716803)
			(xy 445.538352 -56.699886) (xy 445.532764 -56.6928) (xy 445.53251 -56.692546) (xy 445.532256 -56.692292)
			(xy 445.51464 -56.671386) (xy 445.485006 -56.625443) (xy 445.462235 -56.57574) (xy 445.446793 -56.523295)
			(xy 445.438996 -56.469183) (xy 445.43853 -56.441848) (xy 445.439016 -56.414597) (xy 445.446772 -56.360649)
			(xy 445.462127 -56.308354) (xy 445.484769 -56.258777) (xy 445.514235 -56.212927) (xy 445.549926 -56.171736)
			(xy 445.591117 -56.136045) (xy 445.636967 -56.106579) (xy 445.686544 -56.083937) (xy 445.738839 -56.068582)
			(xy 445.792787 -56.060826) (xy 445.847289 -56.060826) (xy 445.901237 -56.068582) (xy 445.953532 -56.083937)
			(xy 446.003109 -56.106579) (xy 446.048959 -56.136045) (xy 446.09015 -56.171736) (xy 446.125841 -56.212927)
			(xy 446.155307 -56.258777) (xy 446.177949 -56.308354) (xy 446.191192 -56.353456) (xy 453.241154 -56.353456)
			(xy 453.245225 -56.297834) (xy 453.257351 -56.243397) (xy 453.277274 -56.191306) (xy 453.30457 -56.142671)
			(xy 453.338656 -56.098528) (xy 453.378805 -56.059819) (xy 453.424163 -56.027368) (xy 453.473763 -56.001867)
			(xy 453.526547 -55.98386) (xy 453.58139 -55.97373) (xy 453.637124 -55.971693) (xy 453.692561 -55.977793)
			(xy 453.746518 -55.991899) (xy 453.797847 -56.013711) (xy 453.845453 -56.042765) (xy 453.888321 -56.07844)
			(xy 453.925538 -56.119977) (xy 453.956311 -56.16649) (xy 453.979983 -56.216987) (xy 453.996051 -56.270394)
			(xy 454.004171 -56.32557) (xy 454.00468 -56.353456) (xy 454.004171 -56.381342) (xy 453.996051 -56.436518)
			(xy 453.979983 -56.489925) (xy 453.956311 -56.540422) (xy 453.925538 -56.586935) (xy 453.888321 -56.628472)
			(xy 453.845453 -56.664147) (xy 453.797847 -56.693201) (xy 453.746518 -56.715013) (xy 453.692561 -56.729119)
			(xy 453.637124 -56.735219) (xy 453.58139 -56.733182) (xy 453.526547 -56.723052) (xy 453.473763 -56.705045)
			(xy 453.424163 -56.679544) (xy 453.378805 -56.647093) (xy 453.338656 -56.608384) (xy 453.30457 -56.564241)
			(xy 453.277274 -56.515606) (xy 453.257351 -56.463515) (xy 453.245225 -56.409078) (xy 453.241154 -56.353456)
			(xy 446.191192 -56.353456) (xy 446.193304 -56.360649) (xy 446.20106 -56.414597) (xy 446.201546 -56.441848)
			(xy 446.201086 -56.469182) (xy 446.193277 -56.52329) (xy 446.177826 -56.57573) (xy 446.155048 -56.625427)
			(xy 446.125411 -56.671365) (xy 446.10782 -56.692292) (xy 446.107566 -56.692546) (xy 446.107312 -56.6928)
			(xy 446.101721 -56.699883) (xy 446.095476 -56.716803) (xy 446.09512 -56.72582) (xy 446.09512 -56.792876)
			(xy 446.095484 -56.801892) (xy 446.101727 -56.818809) (xy 446.107312 -56.825896) (xy 446.107566 -56.82615)
			(xy 446.10782 -56.826404) (xy 446.125431 -56.847315) (xy 446.155066 -56.893256) (xy 446.177838 -56.942958)
			(xy 446.193282 -56.995402) (xy 446.20108 -57.049513) (xy 446.201546 -57.076848) (xy 446.20106 -57.104099)
			(xy 446.193304 -57.158047) (xy 446.177949 -57.210342) (xy 446.155307 -57.259919) (xy 446.125841 -57.305769)
			(xy 446.09015 -57.34696) (xy 446.048959 -57.382651) (xy 446.003109 -57.412117) (xy 445.953532 -57.434759)
			(xy 445.901237 -57.450114) (xy 445.847289 -57.45787) (xy 445.792787 -57.45787) (xy 445.738839 -57.450114)
			(xy 445.686544 -57.434759) (xy 445.636967 -57.412117) (xy 445.591117 -57.382651) (xy 445.549926 -57.34696)
			(xy 445.514235 -57.305769) (xy 445.484769 -57.259919) (xy 445.462127 -57.210342) (xy 445.446772 -57.158047)
			(xy 445.439016 -57.104099) (xy 445.43853 -57.076848) (xy 444.627157 -57.076848) (xy 444.644183 -57.081846)
			(xy 444.69377 -57.104488) (xy 444.739628 -57.133956) (xy 444.780826 -57.169651) (xy 444.816525 -57.210846)
			(xy 444.845997 -57.256702) (xy 444.868643 -57.306287) (xy 444.884001 -57.358589) (xy 444.891759 -57.412545)
			(xy 444.891759 -57.467055) (xy 444.884001 -57.521011) (xy 444.868643 -57.573313) (xy 444.845997 -57.622898)
			(xy 444.816525 -57.668754) (xy 444.780826 -57.709949) (xy 444.739628 -57.745644) (xy 444.69377 -57.775112)
			(xy 444.644183 -57.797754) (xy 444.59188 -57.813108) (xy 444.537923 -57.820861) (xy 444.510668 -57.821322)
			(xy 444.510414 -57.821322) (xy 444.48412 -57.820847) (xy 444.432032 -57.813604) (xy 444.381431 -57.799281)
			(xy 444.333275 -57.778148) (xy 444.288475 -57.750607) (xy 444.247879 -57.717177) (xy 444.229744 -57.698132)
			(xy 444.222188 -57.690672) (xy 444.202758 -57.682156) (xy 444.192152 -57.681622) (xy 444.117984 -57.681622)
			(xy 444.107351 -57.682025) (xy 444.087886 -57.690578) (xy 444.080392 -57.698132) (xy 444.062263 -57.717188)
			(xy 444.021683 -57.750647) (xy 443.976887 -57.778208) (xy 443.928727 -57.799348) (xy 443.878117 -57.813664)
			(xy 443.82602 -57.820886) (xy 443.799722 -57.821322) (xy 443.799468 -57.821322) (xy 443.772219 -57.820806)
			(xy 443.718277 -57.813046) (xy 443.665988 -57.797688) (xy 443.616417 -57.775046) (xy 443.570572 -57.74558)
			(xy 443.529387 -57.70989) (xy 443.493701 -57.668702) (xy 443.464238 -57.622855) (xy 443.4416 -57.573282)
			(xy 443.426248 -57.520992) (xy 443.418492 -57.467049) (xy 443.235146 -57.467049) (xy 443.238959 -57.494543)
			(xy 443.239398 -57.52084) (xy 443.239398 -57.521094) (xy 443.238894 -57.548426) (xy 443.231094 -57.602532)
			(xy 443.215652 -57.654971) (xy 443.192885 -57.704669) (xy 443.163258 -57.750609) (xy 443.145672 -57.771538)
			(xy 443.145418 -57.771792) (xy 443.145164 -57.772046) (xy 443.13959 -57.779141) (xy 443.133337 -57.796051)
			(xy 443.132972 -57.805066) (xy 443.132972 -57.872122) (xy 443.133324 -57.881139) (xy 443.139576 -57.898056)
			(xy 443.145164 -57.905142) (xy 443.145418 -57.905396) (xy 443.145672 -57.90565) (xy 443.163265 -57.926578)
			(xy 443.192915 -57.972511) (xy 443.215701 -58.022207) (xy 443.231157 -58.074649) (xy 443.238966 -58.12876)
			(xy 443.238966 -58.183431) (xy 443.231159 -58.237543) (xy 443.215705 -58.289984) (xy 443.192919 -58.339681)
			(xy 443.16327 -58.385615) (xy 443.145672 -58.406538) (xy 443.145418 -58.406792) (xy 443.145164 -58.407046)
			(xy 443.13959 -58.414141) (xy 443.133337 -58.431051) (xy 443.132972 -58.440066) (xy 443.132972 -58.507122)
			(xy 443.133324 -58.516139) (xy 443.139576 -58.533056) (xy 443.145164 -58.540142) (xy 443.145418 -58.540396)
			(xy 443.145672 -58.54065) (xy 443.16325 -58.561587) (xy 443.192892 -58.607521) (xy 443.215671 -58.657216)
			(xy 443.231122 -58.709654) (xy 443.238928 -58.76376) (xy 443.239398 -58.791094) (xy 443.238912 -58.818345)
			(xy 443.231156 -58.872293) (xy 443.230759 -58.873644) (xy 444.500508 -58.873644) (xy 444.500974 -58.84631)
			(xy 444.508784 -58.792203) (xy 444.524234 -58.739764) (xy 444.54701 -58.690066) (xy 444.576644 -58.644127)
			(xy 444.594234 -58.6232) (xy 444.594488 -58.622946) (xy 444.594742 -58.622692) (xy 444.600343 -58.615616)
			(xy 444.60658 -58.598691) (xy 444.606934 -58.589672) (xy 444.606934 -58.522616) (xy 444.606562 -58.513601)
			(xy 444.600324 -58.496684) (xy 444.594742 -58.489596) (xy 444.594488 -58.489342) (xy 444.594234 -58.489088)
			(xy 444.576628 -58.468173) (xy 444.54699 -58.422234) (xy 444.524216 -58.372533) (xy 444.508772 -58.32009)
			(xy 444.500974 -58.265979) (xy 444.500508 -58.238644) (xy 444.500994 -58.211393) (xy 444.50875 -58.157445)
			(xy 444.524105 -58.10515) (xy 444.546747 -58.055573) (xy 444.576213 -58.009723) (xy 444.611904 -57.968532)
			(xy 444.653095 -57.932841) (xy 444.698945 -57.903375) (xy 444.748522 -57.880733) (xy 444.800817 -57.865378)
			(xy 444.854765 -57.857622) (xy 444.909267 -57.857622) (xy 444.963215 -57.865378) (xy 445.01551 -57.880733)
			(xy 445.065087 -57.903375) (xy 445.110937 -57.932841) (xy 445.152128 -57.968532) (xy 445.187819 -58.009723)
			(xy 445.217285 -58.055573) (xy 445.224912 -58.072274) (xy 452.29348 -58.072274) (xy 452.297551 -58.016652)
			(xy 452.309677 -57.962215) (xy 452.3296 -57.910124) (xy 452.356896 -57.861489) (xy 452.390982 -57.817346)
			(xy 452.431131 -57.778637) (xy 452.476489 -57.746186) (xy 452.526089 -57.720685) (xy 452.578873 -57.702678)
			(xy 452.633716 -57.692548) (xy 452.68945 -57.690511) (xy 452.744887 -57.696611) (xy 452.798844 -57.710717)
			(xy 452.850173 -57.732529) (xy 452.897779 -57.761583) (xy 452.940647 -57.797258) (xy 452.977864 -57.838795)
			(xy 453.008637 -57.885308) (xy 453.032309 -57.935805) (xy 453.048377 -57.989212) (xy 453.056497 -58.044388)
			(xy 453.057006 -58.072274) (xy 453.056497 -58.10016) (xy 453.048377 -58.155336) (xy 453.032309 -58.208743)
			(xy 453.008637 -58.25924) (xy 452.977864 -58.305753) (xy 452.940647 -58.34729) (xy 452.897779 -58.382965)
			(xy 452.850173 -58.412019) (xy 452.798844 -58.433831) (xy 452.744887 -58.447937) (xy 452.68945 -58.454037)
			(xy 452.633716 -58.452) (xy 452.578873 -58.44187) (xy 452.526089 -58.423863) (xy 452.476489 -58.398362)
			(xy 452.431131 -58.365911) (xy 452.390982 -58.327202) (xy 452.356896 -58.283059) (xy 452.3296 -58.234424)
			(xy 452.309677 -58.182333) (xy 452.297551 -58.127896) (xy 452.29348 -58.072274) (xy 445.224912 -58.072274)
			(xy 445.239927 -58.10515) (xy 445.255282 -58.157445) (xy 445.263038 -58.211393) (xy 445.263524 -58.238644)
			(xy 445.263067 -58.265978) (xy 445.255258 -58.320087) (xy 445.239806 -58.372527) (xy 445.217028 -58.422224)
			(xy 445.18739 -58.468162) (xy 445.169798 -58.489088) (xy 445.169544 -58.489342) (xy 445.16929 -58.489596)
			(xy 445.163698 -58.496679) (xy 445.157455 -58.513598) (xy 445.157098 -58.522616) (xy 445.157098 -58.589672)
			(xy 445.157469 -58.598687) (xy 445.163707 -58.615605) (xy 445.16929 -58.622692) (xy 445.169544 -58.622946)
			(xy 445.169798 -58.6232) (xy 445.187404 -58.644115) (xy 445.21704 -58.690055) (xy 445.239814 -58.739756)
			(xy 445.255259 -58.792198) (xy 445.263058 -58.846309) (xy 445.263524 -58.873644) (xy 445.263038 -58.900895)
			(xy 445.255282 -58.954843) (xy 445.239927 -59.007138) (xy 445.217285 -59.056715) (xy 445.187819 -59.102565)
			(xy 445.152128 -59.143756) (xy 445.110937 -59.179447) (xy 445.065087 -59.208913) (xy 445.01551 -59.231555)
			(xy 444.963215 -59.24691) (xy 444.909267 -59.254666) (xy 444.854765 -59.254666) (xy 444.800817 -59.24691)
			(xy 444.748522 -59.231555) (xy 444.698945 -59.208913) (xy 444.653095 -59.179447) (xy 444.611904 -59.143756)
			(xy 444.576213 -59.102565) (xy 444.546747 -59.056715) (xy 444.524105 -59.007138) (xy 444.50875 -58.954843)
			(xy 444.500994 -58.900895) (xy 444.500508 -58.873644) (xy 443.230759 -58.873644) (xy 443.215801 -58.924588)
			(xy 443.193159 -58.974165) (xy 443.163693 -59.020015) (xy 443.128002 -59.061206) (xy 443.086811 -59.096897)
			(xy 443.040961 -59.126363) (xy 442.991384 -59.149005) (xy 442.939089 -59.16436) (xy 442.885141 -59.172116)
			(xy 442.830639 -59.172116) (xy 442.776691 -59.16436) (xy 442.724396 -59.149005) (xy 442.674819 -59.126363)
			(xy 442.628969 -59.096897) (xy 442.587778 -59.061206) (xy 442.552087 -59.020015) (xy 442.522621 -58.974165)
			(xy 442.499979 -58.924588) (xy 442.484624 -58.872293) (xy 442.476868 -58.818345) (xy 442.476382 -58.791094)
			(xy 440.578424 -58.791094) (xy 440.575332 -58.812603) (xy 440.559977 -58.864898) (xy 440.537335 -58.914475)
			(xy 440.507869 -58.960325) (xy 440.472178 -59.001516) (xy 440.430987 -59.037207) (xy 440.385137 -59.066673)
			(xy 440.33556 -59.089315) (xy 440.283265 -59.10467) (xy 440.229317 -59.112426) (xy 440.174815 -59.112426)
			(xy 440.120867 -59.10467) (xy 440.068572 -59.089315) (xy 440.018995 -59.066673) (xy 439.973145 -59.037207)
			(xy 439.931954 -59.001516) (xy 439.896263 -58.960325) (xy 439.866797 -58.914475) (xy 439.844155 -58.864898)
			(xy 439.8288 -58.812603) (xy 439.821044 -58.758655) (xy 439.820558 -58.731404) (xy 435.748008 -58.731404)
			(xy 435.713155 -58.760409) (xy 435.665549 -58.789463) (xy 435.61422 -58.811275) (xy 435.560263 -58.825381)
			(xy 435.504826 -58.831481) (xy 435.449092 -58.829444) (xy 435.394249 -58.819314) (xy 435.341465 -58.801307)
			(xy 435.291865 -58.775806) (xy 435.246507 -58.743355) (xy 435.206358 -58.704646) (xy 435.172272 -58.660503)
			(xy 435.144976 -58.611868) (xy 435.125053 -58.559777) (xy 435.112927 -58.50534) (xy 435.108856 -58.449718)
			(xy 434.48031 -58.449718) (xy 434.44836 -58.463295) (xy 434.394403 -58.477401) (xy 434.338966 -58.483501)
			(xy 434.283232 -58.481464) (xy 434.228389 -58.471334) (xy 434.175605 -58.453327) (xy 434.126005 -58.427826)
			(xy 434.080647 -58.395375) (xy 434.040498 -58.356666) (xy 434.006412 -58.312523) (xy 433.979116 -58.263888)
			(xy 433.959193 -58.211797) (xy 433.947067 -58.15736) (xy 433.942996 -58.101738) (xy 432.42107 -58.101738)
			(xy 432.421029 -58.10397) (xy 432.412909 -58.159146) (xy 432.396841 -58.212553) (xy 432.373169 -58.26305)
			(xy 432.342396 -58.309563) (xy 432.305179 -58.3511) (xy 432.262311 -58.386775) (xy 432.214705 -58.415829)
			(xy 432.163376 -58.437641) (xy 432.109419 -58.451747) (xy 432.053982 -58.457847) (xy 431.998248 -58.45581)
			(xy 431.943405 -58.44568) (xy 431.890621 -58.427673) (xy 431.841021 -58.402172) (xy 431.795663 -58.369721)
			(xy 431.755514 -58.331012) (xy 431.721428 -58.286869) (xy 431.694132 -58.238234) (xy 431.674209 -58.186143)
			(xy 431.662083 -58.131706) (xy 431.658012 -58.076084) (xy 427.056988 -58.076084) (xy 427.056549 -58.10016)
			(xy 427.048429 -58.155336) (xy 427.032361 -58.208743) (xy 427.008689 -58.25924) (xy 426.977916 -58.305753)
			(xy 426.940699 -58.34729) (xy 426.897831 -58.382965) (xy 426.850225 -58.412019) (xy 426.798896 -58.433831)
			(xy 426.744939 -58.447937) (xy 426.689502 -58.454037) (xy 426.633768 -58.452) (xy 426.578925 -58.44187)
			(xy 426.526141 -58.423863) (xy 426.476541 -58.398362) (xy 426.431183 -58.365911) (xy 426.391034 -58.327202)
			(xy 426.356948 -58.283059) (xy 426.329652 -58.234424) (xy 426.309729 -58.182333) (xy 426.297603 -58.127896)
			(xy 426.293532 -58.072274) (xy 419.224964 -58.072274) (xy 419.239979 -58.10515) (xy 419.255334 -58.157445)
			(xy 419.26309 -58.211393) (xy 419.263576 -58.238644) (xy 419.263107 -58.265978) (xy 419.255299 -58.320085)
			(xy 419.239849 -58.372524) (xy 419.217074 -58.422222) (xy 419.18744 -58.468161) (xy 419.16985 -58.489088)
			(xy 419.169596 -58.489342) (xy 419.169342 -58.489596) (xy 419.163744 -58.496675) (xy 419.157506 -58.513598)
			(xy 419.15715 -58.522616) (xy 419.15715 -58.561224) (xy 432.862226 -58.561224) (xy 432.866297 -58.505602)
			(xy 432.878423 -58.451165) (xy 432.898346 -58.399074) (xy 432.925642 -58.350439) (xy 432.959728 -58.306296)
			(xy 432.999877 -58.267587) (xy 433.045235 -58.235136) (xy 433.094835 -58.209635) (xy 433.147619 -58.191628)
			(xy 433.202462 -58.181498) (xy 433.258196 -58.179461) (xy 433.313633 -58.185561) (xy 433.36759 -58.199667)
			(xy 433.418919 -58.221479) (xy 433.466525 -58.250533) (xy 433.509393 -58.286208) (xy 433.54661 -58.327745)
			(xy 433.577383 -58.374258) (xy 433.601055 -58.424755) (xy 433.617123 -58.478162) (xy 433.625243 -58.533338)
			(xy 433.625752 -58.561224) (xy 433.625243 -58.58911) (xy 433.617123 -58.644286) (xy 433.601055 -58.697693)
			(xy 433.577383 -58.74819) (xy 433.54661 -58.794703) (xy 433.509393 -58.83624) (xy 433.466525 -58.871915)
			(xy 433.418919 -58.900969) (xy 433.36759 -58.922781) (xy 433.313633 -58.936887) (xy 433.258196 -58.942987)
			(xy 433.202462 -58.94095) (xy 433.147619 -58.93082) (xy 433.094835 -58.912813) (xy 433.045235 -58.887312)
			(xy 432.999877 -58.854861) (xy 432.959728 -58.816152) (xy 432.925642 -58.772009) (xy 432.898346 -58.723374)
			(xy 432.878423 -58.671283) (xy 432.866297 -58.616846) (xy 432.862226 -58.561224) (xy 419.15715 -58.561224)
			(xy 419.15715 -58.589672) (xy 419.15751 -58.598689) (xy 419.163754 -58.615606) (xy 419.169342 -58.622692)
			(xy 419.169596 -58.622946) (xy 419.16985 -58.6232) (xy 419.187464 -58.644109) (xy 419.217097 -58.690051)
			(xy 419.239869 -58.739753) (xy 419.255312 -58.792197) (xy 419.26311 -58.846309) (xy 419.263576 -58.873644)
			(xy 419.26309 -58.900895) (xy 419.255334 -58.954843) (xy 419.239979 -59.007138) (xy 419.217337 -59.056715)
			(xy 419.187871 -59.102565) (xy 419.15218 -59.143756) (xy 419.110989 -59.179447) (xy 419.065139 -59.208913)
			(xy 419.015562 -59.231555) (xy 418.963267 -59.24691) (xy 418.909319 -59.254666) (xy 418.854817 -59.254666)
			(xy 418.800869 -59.24691) (xy 418.748574 -59.231555) (xy 418.698997 -59.208913) (xy 418.653147 -59.179447)
			(xy 418.611956 -59.143756) (xy 418.576265 -59.102565) (xy 418.546799 -59.056715) (xy 418.524157 -59.007138)
			(xy 418.508802 -58.954843) (xy 418.501046 -58.900895) (xy 418.50056 -58.873644) (xy 417.230811 -58.873644)
			(xy 417.215853 -58.924588) (xy 417.193211 -58.974165) (xy 417.163745 -59.020015) (xy 417.128054 -59.061206)
			(xy 417.086863 -59.096897) (xy 417.041013 -59.126363) (xy 416.991436 -59.149005) (xy 416.939141 -59.16436)
			(xy 416.885193 -59.172116) (xy 416.830691 -59.172116) (xy 416.776743 -59.16436) (xy 416.724448 -59.149005)
			(xy 416.674871 -59.126363) (xy 416.629021 -59.096897) (xy 416.58783 -59.061206) (xy 416.552139 -59.020015)
			(xy 416.522673 -58.974165) (xy 416.500031 -58.924588) (xy 416.484676 -58.872293) (xy 416.47692 -58.818345)
			(xy 416.476434 -58.791094) (xy 414.578476 -58.791094) (xy 414.575384 -58.812603) (xy 414.560029 -58.864898)
			(xy 414.537387 -58.914475) (xy 414.507921 -58.960325) (xy 414.47223 -59.001516) (xy 414.431039 -59.037207)
			(xy 414.385189 -59.066673) (xy 414.335612 -59.089315) (xy 414.283317 -59.10467) (xy 414.229369 -59.112426)
			(xy 414.174867 -59.112426) (xy 414.120919 -59.10467) (xy 414.068624 -59.089315) (xy 414.019047 -59.066673)
			(xy 413.973197 -59.037207) (xy 413.932006 -59.001516) (xy 413.896315 -58.960325) (xy 413.866849 -58.914475)
			(xy 413.844207 -58.864898) (xy 413.828852 -58.812603) (xy 413.821096 -58.758655) (xy 413.82061 -58.731404)
			(xy 409.74806 -58.731404) (xy 409.713207 -58.760409) (xy 409.665601 -58.789463) (xy 409.614272 -58.811275)
			(xy 409.560315 -58.825381) (xy 409.504878 -58.831481) (xy 409.449144 -58.829444) (xy 409.394301 -58.819314)
			(xy 409.341517 -58.801307) (xy 409.291917 -58.775806) (xy 409.246559 -58.743355) (xy 409.20641 -58.704646)
			(xy 409.172324 -58.660503) (xy 409.145028 -58.611868) (xy 409.125105 -58.559777) (xy 409.112979 -58.50534)
			(xy 409.108908 -58.449718) (xy 407.608617 -58.449718) (xy 407.617175 -58.478162) (xy 407.625295 -58.533338)
			(xy 407.625804 -58.561224) (xy 407.625295 -58.58911) (xy 407.617175 -58.644286) (xy 407.601107 -58.697693)
			(xy 407.577435 -58.74819) (xy 407.546662 -58.794703) (xy 407.509445 -58.83624) (xy 407.466577 -58.871915)
			(xy 407.418971 -58.900969) (xy 407.367642 -58.922781) (xy 407.313685 -58.936887) (xy 407.258248 -58.942987)
			(xy 407.202514 -58.94095) (xy 407.147671 -58.93082) (xy 407.094887 -58.912813) (xy 407.045287 -58.887312)
			(xy 406.999929 -58.854861) (xy 406.95978 -58.816152) (xy 406.925694 -58.772009) (xy 406.898398 -58.723374)
			(xy 406.878475 -58.671283) (xy 406.866349 -58.616846) (xy 406.862278 -58.561224) (xy 393.157202 -58.561224)
			(xy 393.157202 -58.589672) (xy 393.157572 -58.598688) (xy 393.16381 -58.615605) (xy 393.169394 -58.622692)
			(xy 393.169648 -58.622946) (xy 393.169902 -58.6232) (xy 393.187508 -58.644115) (xy 393.217144 -58.690055)
			(xy 393.239918 -58.739755) (xy 393.255363 -58.792198) (xy 393.263162 -58.846309) (xy 393.263628 -58.873644)
			(xy 393.263142 -58.900895) (xy 393.255386 -58.954843) (xy 393.240031 -59.007138) (xy 393.217389 -59.056715)
			(xy 393.187923 -59.102565) (xy 393.152232 -59.143756) (xy 393.111041 -59.179447) (xy 393.065191 -59.208913)
			(xy 393.015614 -59.231555) (xy 392.963319 -59.24691) (xy 392.909371 -59.254666) (xy 392.854869 -59.254666)
			(xy 392.800921 -59.24691) (xy 392.748626 -59.231555) (xy 392.699049 -59.208913) (xy 392.653199 -59.179447)
			(xy 392.612008 -59.143756) (xy 392.576317 -59.102565) (xy 392.546851 -59.056715) (xy 392.524209 -59.007138)
			(xy 392.508854 -58.954843) (xy 392.501098 -58.900895) (xy 392.500612 -58.873644) (xy 391.230863 -58.873644)
			(xy 391.215905 -58.924588) (xy 391.193263 -58.974165) (xy 391.163797 -59.020015) (xy 391.128106 -59.061206)
			(xy 391.086915 -59.096897) (xy 391.041065 -59.126363) (xy 390.991488 -59.149005) (xy 390.939193 -59.16436)
			(xy 390.885245 -59.172116) (xy 390.830743 -59.172116) (xy 390.776795 -59.16436) (xy 390.7245 -59.149005)
			(xy 390.674923 -59.126363) (xy 390.629073 -59.096897) (xy 390.587882 -59.061206) (xy 390.552191 -59.020015)
			(xy 390.522725 -58.974165) (xy 390.500083 -58.924588) (xy 390.484728 -58.872293) (xy 390.476972 -58.818345)
			(xy 390.476486 -58.791094) (xy 388.578528 -58.791094) (xy 388.575436 -58.812603) (xy 388.560081 -58.864898)
			(xy 388.537439 -58.914475) (xy 388.507973 -58.960325) (xy 388.472282 -59.001516) (xy 388.431091 -59.037207)
			(xy 388.385241 -59.066673) (xy 388.335664 -59.089315) (xy 388.283369 -59.10467) (xy 388.229421 -59.112426)
			(xy 388.174919 -59.112426) (xy 388.120971 -59.10467) (xy 388.068676 -59.089315) (xy 388.019099 -59.066673)
			(xy 387.973249 -59.037207) (xy 387.932058 -59.001516) (xy 387.896367 -58.960325) (xy 387.866901 -58.914475)
			(xy 387.844259 -58.864898) (xy 387.828904 -58.812603) (xy 387.821148 -58.758655) (xy 387.820662 -58.731404)
			(xy 383.748112 -58.731404) (xy 383.713259 -58.760409) (xy 383.665653 -58.789463) (xy 383.614324 -58.811275)
			(xy 383.560367 -58.825381) (xy 383.50493 -58.831481) (xy 383.449196 -58.829444) (xy 383.394353 -58.819314)
			(xy 383.341569 -58.801307) (xy 383.291969 -58.775806) (xy 383.246611 -58.743355) (xy 383.206462 -58.704646)
			(xy 383.172376 -58.660503) (xy 383.14508 -58.611868) (xy 383.125157 -58.559777) (xy 383.113031 -58.50534)
			(xy 383.10896 -58.449718) (xy 381.608669 -58.449718) (xy 381.617227 -58.478162) (xy 381.625347 -58.533338)
			(xy 381.625856 -58.561224) (xy 381.625347 -58.58911) (xy 381.617227 -58.644286) (xy 381.601159 -58.697693)
			(xy 381.577487 -58.74819) (xy 381.546714 -58.794703) (xy 381.509497 -58.83624) (xy 381.466629 -58.871915)
			(xy 381.419023 -58.900969) (xy 381.367694 -58.922781) (xy 381.313737 -58.936887) (xy 381.2583 -58.942987)
			(xy 381.202566 -58.94095) (xy 381.147723 -58.93082) (xy 381.094939 -58.912813) (xy 381.045339 -58.887312)
			(xy 380.999981 -58.854861) (xy 380.959832 -58.816152) (xy 380.925746 -58.772009) (xy 380.89845 -58.723374)
			(xy 380.878527 -58.671283) (xy 380.866401 -58.616846) (xy 380.86233 -58.561224) (xy 367.157254 -58.561224)
			(xy 367.157254 -58.589672) (xy 367.157613 -58.598689) (xy 367.163858 -58.615607) (xy 367.169446 -58.622692)
			(xy 367.1697 -58.622946) (xy 367.169954 -58.6232) (xy 367.187553 -58.644121) (xy 367.217192 -58.690058)
			(xy 367.239968 -58.739757) (xy 367.255414 -58.792199) (xy 367.263214 -58.846309) (xy 367.26368 -58.873644)
			(xy 367.263194 -58.900895) (xy 367.255438 -58.954843) (xy 367.240083 -59.007138) (xy 367.217441 -59.056715)
			(xy 367.187975 -59.102565) (xy 367.152284 -59.143756) (xy 367.111093 -59.179447) (xy 367.065243 -59.208913)
			(xy 367.015666 -59.231555) (xy 366.963371 -59.24691) (xy 366.909423 -59.254666) (xy 366.854921 -59.254666)
			(xy 366.800973 -59.24691) (xy 366.748678 -59.231555) (xy 366.699101 -59.208913) (xy 366.653251 -59.179447)
			(xy 366.61206 -59.143756) (xy 366.576369 -59.102565) (xy 366.546903 -59.056715) (xy 366.524261 -59.007138)
			(xy 366.508906 -58.954843) (xy 366.50115 -58.900895) (xy 366.500664 -58.873644) (xy 365.230915 -58.873644)
			(xy 365.215957 -58.924588) (xy 365.193315 -58.974165) (xy 365.163849 -59.020015) (xy 365.128158 -59.061206)
			(xy 365.086967 -59.096897) (xy 365.041117 -59.126363) (xy 364.99154 -59.149005) (xy 364.939245 -59.16436)
			(xy 364.885297 -59.172116) (xy 364.830795 -59.172116) (xy 364.776847 -59.16436) (xy 364.724552 -59.149005)
			(xy 364.674975 -59.126363) (xy 364.629125 -59.096897) (xy 364.587934 -59.061206) (xy 364.552243 -59.020015)
			(xy 364.522777 -58.974165) (xy 364.500135 -58.924588) (xy 364.48478 -58.872293) (xy 364.477024 -58.818345)
			(xy 364.476538 -58.791094) (xy 362.57858 -58.791094) (xy 362.575488 -58.812603) (xy 362.560133 -58.864898)
			(xy 362.537491 -58.914475) (xy 362.508025 -58.960325) (xy 362.472334 -59.001516) (xy 362.431143 -59.037207)
			(xy 362.385293 -59.066673) (xy 362.335716 -59.089315) (xy 362.283421 -59.10467) (xy 362.229473 -59.112426)
			(xy 362.174971 -59.112426) (xy 362.121023 -59.10467) (xy 362.068728 -59.089315) (xy 362.019151 -59.066673)
			(xy 361.973301 -59.037207) (xy 361.93211 -59.001516) (xy 361.896419 -58.960325) (xy 361.866953 -58.914475)
			(xy 361.844311 -58.864898) (xy 361.828956 -58.812603) (xy 361.8212 -58.758655) (xy 361.820714 -58.731404)
			(xy 357.748164 -58.731404) (xy 357.713311 -58.760409) (xy 357.665705 -58.789463) (xy 357.614376 -58.811275)
			(xy 357.560419 -58.825381) (xy 357.504982 -58.831481) (xy 357.449248 -58.829444) (xy 357.394405 -58.819314)
			(xy 357.341621 -58.801307) (xy 357.292021 -58.775806) (xy 357.246663 -58.743355) (xy 357.206514 -58.704646)
			(xy 357.172428 -58.660503) (xy 357.145132 -58.611868) (xy 357.125209 -58.559777) (xy 357.113083 -58.50534)
			(xy 357.109012 -58.449718) (xy 355.608721 -58.449718) (xy 355.617279 -58.478162) (xy 355.625399 -58.533338)
			(xy 355.625908 -58.561224) (xy 355.625399 -58.58911) (xy 355.617279 -58.644286) (xy 355.601211 -58.697693)
			(xy 355.577539 -58.74819) (xy 355.546766 -58.794703) (xy 355.509549 -58.83624) (xy 355.466681 -58.871915)
			(xy 355.419075 -58.900969) (xy 355.367746 -58.922781) (xy 355.313789 -58.936887) (xy 355.258352 -58.942987)
			(xy 355.202618 -58.94095) (xy 355.147775 -58.93082) (xy 355.094991 -58.912813) (xy 355.045391 -58.887312)
			(xy 355.000033 -58.854861) (xy 354.959884 -58.816152) (xy 354.925798 -58.772009) (xy 354.898502 -58.723374)
			(xy 354.878579 -58.671283) (xy 354.866453 -58.616846) (xy 354.862382 -58.561224) (xy 329.057 -58.561224)
			(xy 329.057 -58.589672) (xy 329.05737 -58.598688) (xy 329.063609 -58.615605) (xy 329.069192 -58.622692)
			(xy 329.069446 -58.622946) (xy 329.0697 -58.6232) (xy 329.087306 -58.644115) (xy 329.116942 -58.690055)
			(xy 329.139716 -58.739755) (xy 329.155161 -58.792198) (xy 329.16296 -58.846309) (xy 329.163426 -58.873644)
			(xy 329.16294 -58.900895) (xy 329.155184 -58.954843) (xy 329.139829 -59.007138) (xy 329.117187 -59.056715)
			(xy 329.087721 -59.102565) (xy 329.05203 -59.143756) (xy 329.010839 -59.179447) (xy 328.964989 -59.208913)
			(xy 328.915412 -59.231555) (xy 328.863117 -59.24691) (xy 328.809169 -59.254666) (xy 328.754667 -59.254666)
			(xy 328.700719 -59.24691) (xy 328.648424 -59.231555) (xy 328.598847 -59.208913) (xy 328.552997 -59.179447)
			(xy 328.511806 -59.143756) (xy 328.476115 -59.102565) (xy 328.446649 -59.056715) (xy 328.424007 -59.007138)
			(xy 328.408652 -58.954843) (xy 328.400896 -58.900895) (xy 328.40041 -58.873644) (xy 327.130661 -58.873644)
			(xy 327.115703 -58.924588) (xy 327.093061 -58.974165) (xy 327.063595 -59.020015) (xy 327.027904 -59.061206)
			(xy 326.986713 -59.096897) (xy 326.940863 -59.126363) (xy 326.891286 -59.149005) (xy 326.838991 -59.16436)
			(xy 326.785043 -59.172116) (xy 326.730541 -59.172116) (xy 326.676593 -59.16436) (xy 326.624298 -59.149005)
			(xy 326.574721 -59.126363) (xy 326.528871 -59.096897) (xy 326.48768 -59.061206) (xy 326.451989 -59.020015)
			(xy 326.422523 -58.974165) (xy 326.399881 -58.924588) (xy 326.384526 -58.872293) (xy 326.37677 -58.818345)
			(xy 326.376284 -58.791094) (xy 324.478326 -58.791094) (xy 324.475234 -58.812603) (xy 324.459879 -58.864898)
			(xy 324.437237 -58.914475) (xy 324.407771 -58.960325) (xy 324.37208 -59.001516) (xy 324.330889 -59.037207)
			(xy 324.285039 -59.066673) (xy 324.235462 -59.089315) (xy 324.183167 -59.10467) (xy 324.129219 -59.112426)
			(xy 324.074717 -59.112426) (xy 324.020769 -59.10467) (xy 323.968474 -59.089315) (xy 323.918897 -59.066673)
			(xy 323.873047 -59.037207) (xy 323.831856 -59.001516) (xy 323.796165 -58.960325) (xy 323.766699 -58.914475)
			(xy 323.744057 -58.864898) (xy 323.728702 -58.812603) (xy 323.720946 -58.758655) (xy 323.72046 -58.731404)
			(xy 319.64791 -58.731404) (xy 319.613057 -58.760409) (xy 319.565451 -58.789463) (xy 319.514122 -58.811275)
			(xy 319.460165 -58.825381) (xy 319.404728 -58.831481) (xy 319.348994 -58.829444) (xy 319.294151 -58.819314)
			(xy 319.241367 -58.801307) (xy 319.191767 -58.775806) (xy 319.146409 -58.743355) (xy 319.10626 -58.704646)
			(xy 319.072174 -58.660503) (xy 319.044878 -58.611868) (xy 319.024955 -58.559777) (xy 319.012829 -58.50534)
			(xy 319.008758 -58.449718) (xy 317.508467 -58.449718) (xy 317.517025 -58.478162) (xy 317.525145 -58.533338)
			(xy 317.525654 -58.561224) (xy 317.525145 -58.58911) (xy 317.517025 -58.644286) (xy 317.500957 -58.697693)
			(xy 317.477285 -58.74819) (xy 317.446512 -58.794703) (xy 317.409295 -58.83624) (xy 317.366427 -58.871915)
			(xy 317.318821 -58.900969) (xy 317.267492 -58.922781) (xy 317.213535 -58.936887) (xy 317.158098 -58.942987)
			(xy 317.102364 -58.94095) (xy 317.047521 -58.93082) (xy 316.994737 -58.912813) (xy 316.945137 -58.887312)
			(xy 316.899779 -58.854861) (xy 316.85963 -58.816152) (xy 316.825544 -58.772009) (xy 316.798248 -58.723374)
			(xy 316.778325 -58.671283) (xy 316.766199 -58.616846) (xy 316.762128 -58.561224) (xy 303.057052 -58.561224)
			(xy 303.057052 -58.589672) (xy 303.057411 -58.598689) (xy 303.063656 -58.615606) (xy 303.069244 -58.622692)
			(xy 303.069498 -58.622946) (xy 303.069752 -58.6232) (xy 303.08735 -58.644121) (xy 303.11699 -58.690059)
			(xy 303.139766 -58.739757) (xy 303.155212 -58.792199) (xy 303.163012 -58.846309) (xy 303.163478 -58.873644)
			(xy 303.162992 -58.900895) (xy 303.155236 -58.954843) (xy 303.139881 -59.007138) (xy 303.117239 -59.056715)
			(xy 303.087773 -59.102565) (xy 303.052082 -59.143756) (xy 303.010891 -59.179447) (xy 302.965041 -59.208913)
			(xy 302.915464 -59.231555) (xy 302.863169 -59.24691) (xy 302.809221 -59.254666) (xy 302.754719 -59.254666)
			(xy 302.700771 -59.24691) (xy 302.648476 -59.231555) (xy 302.598899 -59.208913) (xy 302.553049 -59.179447)
			(xy 302.511858 -59.143756) (xy 302.476167 -59.102565) (xy 302.446701 -59.056715) (xy 302.424059 -59.007138)
			(xy 302.408704 -58.954843) (xy 302.400948 -58.900895) (xy 302.400462 -58.873644) (xy 301.130713 -58.873644)
			(xy 301.115755 -58.924588) (xy 301.093113 -58.974165) (xy 301.063647 -59.020015) (xy 301.027956 -59.061206)
			(xy 300.986765 -59.096897) (xy 300.940915 -59.126363) (xy 300.891338 -59.149005) (xy 300.839043 -59.16436)
			(xy 300.785095 -59.172116) (xy 300.730593 -59.172116) (xy 300.676645 -59.16436) (xy 300.62435 -59.149005)
			(xy 300.574773 -59.126363) (xy 300.528923 -59.096897) (xy 300.487732 -59.061206) (xy 300.452041 -59.020015)
			(xy 300.422575 -58.974165) (xy 300.399933 -58.924588) (xy 300.384578 -58.872293) (xy 300.376822 -58.818345)
			(xy 300.376336 -58.791094) (xy 298.478378 -58.791094) (xy 298.475286 -58.812603) (xy 298.459931 -58.864898)
			(xy 298.437289 -58.914475) (xy 298.407823 -58.960325) (xy 298.372132 -59.001516) (xy 298.330941 -59.037207)
			(xy 298.285091 -59.066673) (xy 298.235514 -59.089315) (xy 298.183219 -59.10467) (xy 298.129271 -59.112426)
			(xy 298.074769 -59.112426) (xy 298.020821 -59.10467) (xy 297.968526 -59.089315) (xy 297.918949 -59.066673)
			(xy 297.873099 -59.037207) (xy 297.831908 -59.001516) (xy 297.796217 -58.960325) (xy 297.766751 -58.914475)
			(xy 297.744109 -58.864898) (xy 297.728754 -58.812603) (xy 297.720998 -58.758655) (xy 297.720512 -58.731404)
			(xy 293.647962 -58.731404) (xy 293.613109 -58.760409) (xy 293.565503 -58.789463) (xy 293.514174 -58.811275)
			(xy 293.460217 -58.825381) (xy 293.40478 -58.831481) (xy 293.349046 -58.829444) (xy 293.294203 -58.819314)
			(xy 293.241419 -58.801307) (xy 293.191819 -58.775806) (xy 293.146461 -58.743355) (xy 293.106312 -58.704646)
			(xy 293.072226 -58.660503) (xy 293.04493 -58.611868) (xy 293.025007 -58.559777) (xy 293.012881 -58.50534)
			(xy 293.00881 -58.449718) (xy 291.508519 -58.449718) (xy 291.517077 -58.478162) (xy 291.525197 -58.533338)
			(xy 291.525706 -58.561224) (xy 291.525197 -58.58911) (xy 291.517077 -58.644286) (xy 291.501009 -58.697693)
			(xy 291.477337 -58.74819) (xy 291.446564 -58.794703) (xy 291.409347 -58.83624) (xy 291.366479 -58.871915)
			(xy 291.318873 -58.900969) (xy 291.267544 -58.922781) (xy 291.213587 -58.936887) (xy 291.15815 -58.942987)
			(xy 291.102416 -58.94095) (xy 291.047573 -58.93082) (xy 290.994789 -58.912813) (xy 290.945189 -58.887312)
			(xy 290.899831 -58.854861) (xy 290.859682 -58.816152) (xy 290.825596 -58.772009) (xy 290.7983 -58.723374)
			(xy 290.778377 -58.671283) (xy 290.766251 -58.616846) (xy 290.76218 -58.561224) (xy 277.057104 -58.561224)
			(xy 277.057104 -58.589672) (xy 277.057473 -58.598688) (xy 277.063712 -58.615605) (xy 277.069296 -58.622692)
			(xy 277.06955 -58.622946) (xy 277.069804 -58.6232) (xy 277.087411 -58.644114) (xy 277.117047 -58.690055)
			(xy 277.13982 -58.739755) (xy 277.155265 -58.792198) (xy 277.163064 -58.846309) (xy 277.16353 -58.873644)
			(xy 277.163044 -58.900895) (xy 277.155288 -58.954843) (xy 277.139933 -59.007138) (xy 277.117291 -59.056715)
			(xy 277.087825 -59.102565) (xy 277.052134 -59.143756) (xy 277.010943 -59.179447) (xy 276.965093 -59.208913)
			(xy 276.915516 -59.231555) (xy 276.863221 -59.24691) (xy 276.809273 -59.254666) (xy 276.754771 -59.254666)
			(xy 276.700823 -59.24691) (xy 276.648528 -59.231555) (xy 276.598951 -59.208913) (xy 276.553101 -59.179447)
			(xy 276.51191 -59.143756) (xy 276.476219 -59.102565) (xy 276.446753 -59.056715) (xy 276.424111 -59.007138)
			(xy 276.408756 -58.954843) (xy 276.401 -58.900895) (xy 276.400514 -58.873644) (xy 275.130765 -58.873644)
			(xy 275.115807 -58.924588) (xy 275.093165 -58.974165) (xy 275.063699 -59.020015) (xy 275.028008 -59.061206)
			(xy 274.986817 -59.096897) (xy 274.940967 -59.126363) (xy 274.89139 -59.149005) (xy 274.839095 -59.16436)
			(xy 274.785147 -59.172116) (xy 274.730645 -59.172116) (xy 274.676697 -59.16436) (xy 274.624402 -59.149005)
			(xy 274.574825 -59.126363) (xy 274.528975 -59.096897) (xy 274.487784 -59.061206) (xy 274.452093 -59.020015)
			(xy 274.422627 -58.974165) (xy 274.399985 -58.924588) (xy 274.38463 -58.872293) (xy 274.376874 -58.818345)
			(xy 274.376388 -58.791094) (xy 272.47843 -58.791094) (xy 272.475338 -58.812603) (xy 272.459983 -58.864898)
			(xy 272.437341 -58.914475) (xy 272.407875 -58.960325) (xy 272.372184 -59.001516) (xy 272.330993 -59.037207)
			(xy 272.285143 -59.066673) (xy 272.235566 -59.089315) (xy 272.183271 -59.10467) (xy 272.129323 -59.112426)
			(xy 272.074821 -59.112426) (xy 272.020873 -59.10467) (xy 271.968578 -59.089315) (xy 271.919001 -59.066673)
			(xy 271.873151 -59.037207) (xy 271.83196 -59.001516) (xy 271.796269 -58.960325) (xy 271.766803 -58.914475)
			(xy 271.744161 -58.864898) (xy 271.728806 -58.812603) (xy 271.72105 -58.758655) (xy 271.720564 -58.731404)
			(xy 267.648014 -58.731404) (xy 267.613161 -58.760409) (xy 267.565555 -58.789463) (xy 267.514226 -58.811275)
			(xy 267.460269 -58.825381) (xy 267.404832 -58.831481) (xy 267.349098 -58.829444) (xy 267.294255 -58.819314)
			(xy 267.241471 -58.801307) (xy 267.191871 -58.775806) (xy 267.146513 -58.743355) (xy 267.106364 -58.704646)
			(xy 267.072278 -58.660503) (xy 267.044982 -58.611868) (xy 267.025059 -58.559777) (xy 267.012933 -58.50534)
			(xy 267.008862 -58.449718) (xy 265.508571 -58.449718) (xy 265.517129 -58.478162) (xy 265.525249 -58.533338)
			(xy 265.525758 -58.561224) (xy 265.525249 -58.58911) (xy 265.517129 -58.644286) (xy 265.501061 -58.697693)
			(xy 265.477389 -58.74819) (xy 265.446616 -58.794703) (xy 265.409399 -58.83624) (xy 265.366531 -58.871915)
			(xy 265.318925 -58.900969) (xy 265.267596 -58.922781) (xy 265.213639 -58.936887) (xy 265.158202 -58.942987)
			(xy 265.102468 -58.94095) (xy 265.047625 -58.93082) (xy 264.994841 -58.912813) (xy 264.945241 -58.887312)
			(xy 264.899883 -58.854861) (xy 264.859734 -58.816152) (xy 264.825648 -58.772009) (xy 264.798352 -58.723374)
			(xy 264.778429 -58.671283) (xy 264.766303 -58.616846) (xy 264.762232 -58.561224) (xy 251.057156 -58.561224)
			(xy 251.057156 -58.589672) (xy 251.057514 -58.598689) (xy 251.06376 -58.615607) (xy 251.069348 -58.622692)
			(xy 251.069602 -58.622946) (xy 251.069856 -58.6232) (xy 251.087455 -58.644121) (xy 251.117094 -58.690058)
			(xy 251.13987 -58.739757) (xy 251.155316 -58.792199) (xy 251.163116 -58.846309) (xy 251.163582 -58.873644)
			(xy 251.163096 -58.900895) (xy 251.15534 -58.954843) (xy 251.139985 -59.007138) (xy 251.117343 -59.056715)
			(xy 251.087877 -59.102565) (xy 251.052186 -59.143756) (xy 251.010995 -59.179447) (xy 250.965145 -59.208913)
			(xy 250.915568 -59.231555) (xy 250.863273 -59.24691) (xy 250.809325 -59.254666) (xy 250.754823 -59.254666)
			(xy 250.700875 -59.24691) (xy 250.64858 -59.231555) (xy 250.599003 -59.208913) (xy 250.553153 -59.179447)
			(xy 250.511962 -59.143756) (xy 250.476271 -59.102565) (xy 250.446805 -59.056715) (xy 250.424163 -59.007138)
			(xy 250.408808 -58.954843) (xy 250.401052 -58.900895) (xy 250.400566 -58.873644) (xy 249.130817 -58.873644)
			(xy 249.115859 -58.924588) (xy 249.093217 -58.974165) (xy 249.063751 -59.020015) (xy 249.02806 -59.061206)
			(xy 248.986869 -59.096897) (xy 248.941019 -59.126363) (xy 248.891442 -59.149005) (xy 248.839147 -59.16436)
			(xy 248.785199 -59.172116) (xy 248.730697 -59.172116) (xy 248.676749 -59.16436) (xy 248.624454 -59.149005)
			(xy 248.574877 -59.126363) (xy 248.529027 -59.096897) (xy 248.487836 -59.061206) (xy 248.452145 -59.020015)
			(xy 248.422679 -58.974165) (xy 248.400037 -58.924588) (xy 248.384682 -58.872293) (xy 248.376926 -58.818345)
			(xy 248.37644 -58.791094) (xy 246.478482 -58.791094) (xy 246.47539 -58.812603) (xy 246.460035 -58.864898)
			(xy 246.437393 -58.914475) (xy 246.407927 -58.960325) (xy 246.372236 -59.001516) (xy 246.331045 -59.037207)
			(xy 246.285195 -59.066673) (xy 246.235618 -59.089315) (xy 246.183323 -59.10467) (xy 246.129375 -59.112426)
			(xy 246.074873 -59.112426) (xy 246.020925 -59.10467) (xy 245.96863 -59.089315) (xy 245.919053 -59.066673)
			(xy 245.873203 -59.037207) (xy 245.832012 -59.001516) (xy 245.796321 -58.960325) (xy 245.766855 -58.914475)
			(xy 245.744213 -58.864898) (xy 245.728858 -58.812603) (xy 245.721102 -58.758655) (xy 245.720616 -58.731404)
			(xy 238.656019 -58.731404) (xy 238.640561 -58.782783) (xy 238.616889 -58.83328) (xy 238.586116 -58.879793)
			(xy 238.548899 -58.92133) (xy 238.506031 -58.957005) (xy 238.458425 -58.986059) (xy 238.407096 -59.007871)
			(xy 238.353139 -59.021977) (xy 238.297702 -59.028077) (xy 238.241968 -59.02604) (xy 238.187125 -59.01591)
			(xy 238.134341 -58.997903) (xy 238.084741 -58.972402) (xy 238.039383 -58.939951) (xy 237.999234 -58.901242)
			(xy 237.965148 -58.857099) (xy 237.937852 -58.808464) (xy 237.917929 -58.756373) (xy 237.905803 -58.701936)
			(xy 237.901732 -58.646314) (xy 233.960883 -58.646314) (xy 233.960946 -58.646749) (xy 233.961432 -58.674)
			(xy 233.961432 -58.674254) (xy 233.960943 -58.701601) (xy 233.953116 -58.755732) (xy 233.937642 -58.808191)
			(xy 233.91484 -58.857905) (xy 233.885176 -58.903855) (xy 233.849257 -58.945102) (xy 233.828844 -58.963306)
			(xy 233.820462 -58.970418) (xy 233.811318 -58.99023) (xy 233.810302 -59.088528) (xy 233.818938 -59.108594)
			(xy 233.82732 -59.11596) (xy 233.84691 -59.134114) (xy 233.881302 -59.174976) (xy 233.909659 -59.220235)
			(xy 233.931425 -59.269008) (xy 233.946175 -59.32034) (xy 233.953621 -59.373227) (xy 233.954066 -59.399932)
			(xy 233.953574 -59.428638) (xy 233.94496 -59.485401) (xy 233.927947 -59.540235) (xy 233.902917 -59.591905)
			(xy 233.870434 -59.639246) (xy 233.831231 -59.681191) (xy 233.809032 -59.699398) (xy 233.800041 -59.707336)
			(xy 233.789964 -59.729063) (xy 233.789728 -59.741054) (xy 233.792776 -59.835034) (xy 233.80446 -59.856116)
			(xy 233.81462 -59.862974) (xy 233.836203 -59.878309) (xy 233.87535 -59.913955) (xy 233.909191 -59.954672)
			(xy 233.937078 -59.999676) (xy 233.958475 -60.048104) (xy 233.97297 -60.099025) (xy 233.976797 -60.126455)
			(xy 249.38015 -60.126455) (xy 249.38015 -60.071945) (xy 249.387908 -60.017989) (xy 249.403267 -59.965686)
			(xy 249.425913 -59.916102) (xy 249.455386 -59.870246) (xy 249.491085 -59.829051) (xy 249.532284 -59.793357)
			(xy 249.578144 -59.76389) (xy 249.627731 -59.74125) (xy 249.680036 -59.725898) (xy 249.733992 -59.718146)
			(xy 249.761248 -59.717686) (xy 249.788617 -59.718186) (xy 249.842794 -59.725996) (xy 249.895297 -59.741477)
			(xy 249.945044 -59.764312) (xy 249.991013 -59.794028) (xy 250.011946 -59.811666) (xy 250.0122 -59.81192)
			(xy 250.019281 -59.817515) (xy 250.036202 -59.823756) (xy 250.04522 -59.824112) (xy 250.112276 -59.824112)
			(xy 250.121291 -59.823741) (xy 250.138208 -59.817503) (xy 250.145296 -59.81192) (xy 250.145804 -59.811412)
			(xy 250.166718 -59.793776) (xy 250.212689 -59.764116) (xy 250.262426 -59.741329) (xy 250.314909 -59.725884)
			(xy 250.369061 -59.718097) (xy 250.423769 -59.718128) (xy 250.477912 -59.725976) (xy 250.530378 -59.741481)
			(xy 250.580089 -59.764323) (xy 250.626026 -59.794035) (xy 250.646946 -59.811666) (xy 250.6472 -59.81192)
			(xy 250.654281 -59.817515) (xy 250.671202 -59.823756) (xy 250.68022 -59.824112) (xy 250.747276 -59.824112)
			(xy 250.756291 -59.823741) (xy 250.773208 -59.817503) (xy 250.780296 -59.81192) (xy 250.780804 -59.811412)
			(xy 250.801719 -59.793806) (xy 250.847659 -59.764169) (xy 250.897359 -59.741395) (xy 250.949802 -59.725951)
			(xy 251.003913 -59.718152) (xy 251.031248 -59.717686) (xy 251.058497 -59.718187) (xy 251.112438 -59.725949)
			(xy 251.164726 -59.741308) (xy 251.214297 -59.763952) (xy 251.260141 -59.793419) (xy 251.301324 -59.82911)
			(xy 251.33701 -59.870298) (xy 251.366471 -59.916145) (xy 251.389109 -59.965719) (xy 251.391756 -59.974734)
			(xy 263.287002 -59.974734) (xy 263.287433 -59.947907) (xy 263.294953 -59.894782) (xy 263.309837 -59.843234)
			(xy 263.33179 -59.794277) (xy 263.360381 -59.748875) (xy 263.395047 -59.707923) (xy 263.435104 -59.672227)
			(xy 263.457182 -59.65698) (xy 263.468752 -59.648765) (xy 263.487163 -59.627186) (xy 263.498921 -59.601373)
			(xy 263.503117 -59.573319) (xy 263.499427 -59.545195) (xy 263.488136 -59.519174) (xy 263.470117 -59.497267)
			(xy 263.458706 -59.488832) (xy 263.437256 -59.47347) (xy 263.398342 -59.437846) (xy 263.364708 -59.397199)
			(xy 263.336996 -59.352305) (xy 263.315734 -59.304021) (xy 263.301329 -59.253267) (xy 263.294054 -59.201013)
			(xy 263.293606 -59.174634) (xy 263.294092 -59.147383) (xy 263.301848 -59.093435) (xy 263.317203 -59.04114)
			(xy 263.339845 -58.991563) (xy 263.369311 -58.945713) (xy 263.405002 -58.904522) (xy 263.446193 -58.868831)
			(xy 263.492043 -58.839365) (xy 263.54162 -58.816723) (xy 263.593915 -58.801368) (xy 263.647863 -58.793612)
			(xy 263.702365 -58.793612) (xy 263.756313 -58.801368) (xy 263.808608 -58.816723) (xy 263.858185 -58.839365)
			(xy 263.904035 -58.868831) (xy 263.945226 -58.904522) (xy 263.980917 -58.945713) (xy 264.010383 -58.991563)
			(xy 264.033025 -59.04114) (xy 264.04838 -59.093435) (xy 264.056136 -59.147383) (xy 264.056622 -59.174634)
			(xy 264.056156 -59.20146) (xy 264.048641 -59.254582) (xy 264.033762 -59.30613) (xy 264.011814 -59.355086)
			(xy 263.983229 -59.400488) (xy 263.948569 -59.441442) (xy 263.908517 -59.47714) (xy 263.886442 -59.492388)
			(xy 263.87491 -59.500647) (xy 263.856513 -59.522221) (xy 263.844763 -59.548023) (xy 263.840566 -59.576063)
			(xy 263.844247 -59.604175) (xy 263.855521 -59.630189) (xy 263.873518 -59.652096) (xy 263.884918 -59.660536)
			(xy 263.906405 -59.675848) (xy 263.945317 -59.711482) (xy 263.978948 -59.752138) (xy 264.006655 -59.79704)
			(xy 264.02791 -59.845332) (xy 264.042308 -59.896092) (xy 264.049574 -59.948353) (xy 264.050018 -59.974734)
			(xy 264.049532 -60.001985) (xy 264.041776 -60.055933) (xy 264.026421 -60.108228) (xy 264.018098 -60.126451)
			(xy 275.380172 -60.126451) (xy 275.380172 -60.071949) (xy 275.387928 -60.018) (xy 275.403283 -59.965705)
			(xy 275.425925 -59.916127) (xy 275.455391 -59.870276) (xy 275.491083 -59.829086) (xy 275.532273 -59.793393)
			(xy 275.578124 -59.763927) (xy 275.627701 -59.741285) (xy 275.679996 -59.725929) (xy 275.733945 -59.718172)
			(xy 275.761196 -59.717686) (xy 275.788566 -59.718158) (xy 275.842745 -59.725975) (xy 275.895248 -59.741463)
			(xy 275.944995 -59.764303) (xy 275.990962 -59.794026) (xy 276.011894 -59.811666) (xy 276.012148 -59.81192)
			(xy 276.019244 -59.817493) (xy 276.036154 -59.823747) (xy 276.045168 -59.824112) (xy 276.112224 -59.824112)
			(xy 276.121242 -59.823764) (xy 276.138158 -59.81751) (xy 276.145244 -59.81192) (xy 276.145752 -59.811412)
			(xy 276.166707 -59.793827) (xy 276.212671 -59.764165) (xy 276.262402 -59.741375) (xy 276.314878 -59.725926)
			(xy 276.369024 -59.718134) (xy 276.423728 -59.718159) (xy 276.477866 -59.726001) (xy 276.530329 -59.741499)
			(xy 276.580038 -59.764334) (xy 276.625974 -59.794039) (xy 276.646894 -59.811666) (xy 276.647148 -59.81192)
			(xy 276.654244 -59.817493) (xy 276.671154 -59.823747) (xy 276.680168 -59.824112) (xy 276.747224 -59.824112)
			(xy 276.756242 -59.823764) (xy 276.773158 -59.81751) (xy 276.780244 -59.81192) (xy 276.780752 -59.811412)
			(xy 276.801687 -59.79383) (xy 276.847621 -59.76419) (xy 276.897316 -59.741411) (xy 276.949755 -59.725961)
			(xy 277.003862 -59.718156) (xy 277.031196 -59.717686) (xy 277.058449 -59.718161) (xy 277.112399 -59.725917)
			(xy 277.164697 -59.741273) (xy 277.214276 -59.763915) (xy 277.260129 -59.793382) (xy 277.301322 -59.829075)
			(xy 277.337015 -59.870267) (xy 277.366483 -59.91612) (xy 277.389126 -59.9657) (xy 277.391779 -59.974734)
			(xy 289.28695 -59.974734) (xy 289.287359 -59.947906) (xy 289.294881 -59.89478) (xy 289.309767 -59.84323)
			(xy 289.331723 -59.794272) (xy 289.360318 -59.74887) (xy 289.394988 -59.707919) (xy 289.43505 -59.672225)
			(xy 289.45713 -59.65698) (xy 289.468696 -59.648762) (xy 289.487098 -59.627181) (xy 289.49885 -59.601369)
			(xy 289.503044 -59.573319) (xy 289.499356 -59.545199) (xy 289.488071 -59.519179) (xy 289.470061 -59.49727)
			(xy 289.458654 -59.488832) (xy 289.437192 -59.473486) (xy 289.398281 -59.437857) (xy 289.36465 -59.397207)
			(xy 289.33694 -59.35231) (xy 289.31568 -59.304024) (xy 289.301276 -59.253269) (xy 289.294002 -59.201014)
			(xy 289.293554 -59.174634) (xy 289.29404 -59.147383) (xy 289.301796 -59.093435) (xy 289.317151 -59.04114)
			(xy 289.339793 -58.991563) (xy 289.369259 -58.945713) (xy 289.40495 -58.904522) (xy 289.446141 -58.868831)
			(xy 289.491991 -58.839365) (xy 289.541568 -58.816723) (xy 289.593863 -58.801368) (xy 289.647811 -58.793612)
			(xy 289.702313 -58.793612) (xy 289.756261 -58.801368) (xy 289.808556 -58.816723) (xy 289.858133 -58.839365)
			(xy 289.903983 -58.868831) (xy 289.945174 -58.904522) (xy 289.980865 -58.945713) (xy 290.010331 -58.991563)
			(xy 290.032973 -59.04114) (xy 290.048328 -59.093435) (xy 290.056084 -59.147383) (xy 290.05657 -59.174634)
			(xy 290.056127 -59.201461) (xy 290.048611 -59.254585) (xy 290.03373 -59.306134) (xy 290.011779 -59.355092)
			(xy 289.983189 -59.400494) (xy 289.948525 -59.441446) (xy 289.908468 -59.477142) (xy 289.88639 -59.492388)
			(xy 289.874853 -59.500645) (xy 289.856449 -59.522216) (xy 289.844692 -59.54802) (xy 289.840494 -59.576063)
			(xy 289.844177 -59.604178) (xy 289.855456 -59.630194) (xy 289.873462 -59.652099) (xy 289.884866 -59.660536)
			(xy 289.906364 -59.675833) (xy 289.945274 -59.711471) (xy 289.978902 -59.75213) (xy 290.006607 -59.797035)
			(xy 290.02786 -59.845329) (xy 290.042257 -59.896091) (xy 290.049522 -59.948352) (xy 290.049966 -59.974734)
			(xy 290.04948 -60.001985) (xy 290.041724 -60.055933) (xy 290.026369 -60.108228) (xy 290.018045 -60.126455)
			(xy 301.380049 -60.126455) (xy 301.380049 -60.071945) (xy 301.387808 -60.017989) (xy 301.403166 -59.965687)
			(xy 301.425812 -59.916103) (xy 301.455285 -59.870247) (xy 301.490984 -59.829053) (xy 301.532182 -59.793358)
			(xy 301.578042 -59.763891) (xy 301.627628 -59.741251) (xy 301.679932 -59.725898) (xy 301.733889 -59.718146)
			(xy 301.761144 -59.717686) (xy 301.788513 -59.718188) (xy 301.84269 -59.725998) (xy 301.895193 -59.741479)
			(xy 301.94494 -59.764312) (xy 301.990909 -59.794029) (xy 302.011842 -59.811666) (xy 302.012096 -59.81192)
			(xy 302.019178 -59.817513) (xy 302.036098 -59.823755) (xy 302.045116 -59.824112) (xy 302.112172 -59.824112)
			(xy 302.121187 -59.823739) (xy 302.138104 -59.817502) (xy 302.145192 -59.81192) (xy 302.1457 -59.811412)
			(xy 302.166617 -59.79378) (xy 302.212588 -59.76412) (xy 302.262324 -59.741333) (xy 302.314807 -59.725887)
			(xy 302.368958 -59.7181) (xy 302.423666 -59.71813) (xy 302.477809 -59.725978) (xy 302.530274 -59.741482)
			(xy 302.579985 -59.764324) (xy 302.625922 -59.794036) (xy 302.646842 -59.811666) (xy 302.647096 -59.81192)
			(xy 302.654178 -59.817513) (xy 302.671098 -59.823755) (xy 302.680116 -59.824112) (xy 302.747172 -59.824112)
			(xy 302.756187 -59.823739) (xy 302.773104 -59.817502) (xy 302.780192 -59.81192) (xy 302.7807 -59.811412)
			(xy 302.801616 -59.793808) (xy 302.847556 -59.764171) (xy 302.897256 -59.741397) (xy 302.949699 -59.725952)
			(xy 303.003809 -59.718152) (xy 303.031144 -59.717686) (xy 303.058393 -59.718187) (xy 303.112335 -59.725948)
			(xy 303.164624 -59.741307) (xy 303.214194 -59.76395) (xy 303.260039 -59.793417) (xy 303.301223 -59.829108)
			(xy 303.336909 -59.870297) (xy 303.366371 -59.916144) (xy 303.389008 -59.965718) (xy 303.391655 -59.974734)
			(xy 315.286898 -59.974734) (xy 315.28733 -59.947907) (xy 315.294851 -59.894783) (xy 315.309734 -59.843234)
			(xy 315.331688 -59.794277) (xy 315.360278 -59.748875) (xy 315.394943 -59.707923) (xy 315.435 -59.672227)
			(xy 315.457078 -59.65698) (xy 315.468648 -59.648765) (xy 315.48706 -59.627187) (xy 315.498818 -59.601373)
			(xy 315.503015 -59.573319) (xy 315.499325 -59.545195) (xy 315.488033 -59.519174) (xy 315.470014 -59.497267)
			(xy 315.458602 -59.488832) (xy 315.437151 -59.473472) (xy 315.398237 -59.437847) (xy 315.364603 -59.397199)
			(xy 315.336891 -59.352305) (xy 315.31563 -59.304021) (xy 315.301225 -59.253267) (xy 315.29395 -59.201013)
			(xy 315.293502 -59.174634) (xy 315.293988 -59.147383) (xy 315.301744 -59.093435) (xy 315.317099 -59.04114)
			(xy 315.339741 -58.991563) (xy 315.369207 -58.945713) (xy 315.404898 -58.904522) (xy 315.446089 -58.868831)
			(xy 315.491939 -58.839365) (xy 315.541516 -58.816723) (xy 315.593811 -58.801368) (xy 315.647759 -58.793612)
			(xy 315.702261 -58.793612) (xy 315.756209 -58.801368) (xy 315.808504 -58.816723) (xy 315.858081 -58.839365)
			(xy 315.903931 -58.868831) (xy 315.945122 -58.904522) (xy 315.980813 -58.945713) (xy 316.010279 -58.991563)
			(xy 316.032921 -59.04114) (xy 316.048276 -59.093435) (xy 316.056032 -59.147383) (xy 316.056518 -59.174634)
			(xy 316.056054 -59.20146) (xy 316.048538 -59.254582) (xy 316.03366 -59.30613) (xy 316.011712 -59.355087)
			(xy 315.983126 -59.400489) (xy 315.948466 -59.441442) (xy 315.908413 -59.47714) (xy 315.886338 -59.492388)
			(xy 315.874806 -59.500647) (xy 315.85641 -59.522221) (xy 315.844661 -59.548023) (xy 315.840464 -59.576063)
			(xy 315.844145 -59.604175) (xy 315.855418 -59.630188) (xy 315.873415 -59.652096) (xy 315.884814 -59.660536)
			(xy 315.906301 -59.675849) (xy 315.945213 -59.711482) (xy 315.978843 -59.752138) (xy 316.006551 -59.79704)
			(xy 316.027806 -59.845332) (xy 316.042204 -59.896093) (xy 316.04947 -59.948353) (xy 316.049914 -59.974734)
			(xy 316.049428 -60.001985) (xy 316.041672 -60.055933) (xy 316.026317 -60.108228) (xy 316.017994 -60.126451)
			(xy 327.380072 -60.126451) (xy 327.380072 -60.071949) (xy 327.387828 -60.018001) (xy 327.403183 -59.965706)
			(xy 327.425824 -59.916128) (xy 327.45529 -59.870278) (xy 327.490981 -59.829087) (xy 327.532171 -59.793395)
			(xy 327.578021 -59.763928) (xy 327.627598 -59.741286) (xy 327.679893 -59.72593) (xy 327.733841 -59.718172)
			(xy 327.761092 -59.717686) (xy 327.788462 -59.71816) (xy 327.84264 -59.725977) (xy 327.895143 -59.741464)
			(xy 327.94489 -59.764304) (xy 327.990858 -59.794026) (xy 328.01179 -59.811666) (xy 328.012044 -59.81192)
			(xy 328.019141 -59.817492) (xy 328.03605 -59.823747) (xy 328.045064 -59.824112) (xy 328.11212 -59.824112)
			(xy 328.121137 -59.823762) (xy 328.138054 -59.817509) (xy 328.14514 -59.81192) (xy 328.145648 -59.811412)
			(xy 328.166607 -59.793831) (xy 328.21257 -59.764168) (xy 328.2623 -59.741379) (xy 328.314776 -59.725929)
			(xy 328.368921 -59.718137) (xy 328.423625 -59.718162) (xy 328.477763 -59.726003) (xy 328.530225 -59.7415)
			(xy 328.579934 -59.764335) (xy 328.62587 -59.794039) (xy 328.64679 -59.811666) (xy 328.647044 -59.81192)
			(xy 328.654141 -59.817492) (xy 328.67105 -59.823747) (xy 328.680064 -59.824112) (xy 328.74712 -59.824112)
			(xy 328.756137 -59.823762) (xy 328.773054 -59.817509) (xy 328.78014 -59.81192) (xy 328.780648 -59.811412)
			(xy 328.801584 -59.793832) (xy 328.847518 -59.764192) (xy 328.897213 -59.741413) (xy 328.949651 -59.725962)
			(xy 329.003758 -59.718156) (xy 329.031092 -59.717686) (xy 329.058345 -59.718161) (xy 329.112296 -59.725917)
			(xy 329.164594 -59.741272) (xy 329.214174 -59.763913) (xy 329.260027 -59.793381) (xy 329.30122 -59.829074)
			(xy 329.336914 -59.870266) (xy 329.366383 -59.916119) (xy 329.389025 -59.965699) (xy 329.391678 -59.974734)
			(xy 353.387152 -59.974734) (xy 353.387561 -59.947906) (xy 353.395082 -59.89478) (xy 353.409968 -59.843229)
			(xy 353.431925 -59.794271) (xy 353.46052 -59.74887) (xy 353.49519 -59.707919) (xy 353.535252 -59.672225)
			(xy 353.557332 -59.65698) (xy 353.568897 -59.648762) (xy 353.5873 -59.627181) (xy 353.599051 -59.601369)
			(xy 353.603245 -59.573319) (xy 353.599557 -59.545199) (xy 353.588273 -59.519179) (xy 353.570262 -59.49727)
			(xy 353.558856 -59.488832) (xy 353.537395 -59.473486) (xy 353.498483 -59.437857) (xy 353.464852 -59.397206)
			(xy 353.437142 -59.35231) (xy 353.415882 -59.304024) (xy 353.401478 -59.253269) (xy 353.394204 -59.201014)
			(xy 353.393756 -59.174634) (xy 353.394242 -59.147383) (xy 353.401998 -59.093435) (xy 353.417353 -59.04114)
			(xy 353.439995 -58.991563) (xy 353.469461 -58.945713) (xy 353.505152 -58.904522) (xy 353.546343 -58.868831)
			(xy 353.592193 -58.839365) (xy 353.64177 -58.816723) (xy 353.694065 -58.801368) (xy 353.748013 -58.793612)
			(xy 353.802515 -58.793612) (xy 353.856463 -58.801368) (xy 353.908758 -58.816723) (xy 353.958335 -58.839365)
			(xy 354.004185 -58.868831) (xy 354.045376 -58.904522) (xy 354.081067 -58.945713) (xy 354.110533 -58.991563)
			(xy 354.133175 -59.04114) (xy 354.14853 -59.093435) (xy 354.156286 -59.147383) (xy 354.156772 -59.174634)
			(xy 354.156328 -59.201461) (xy 354.148812 -59.254585) (xy 354.133931 -59.306134) (xy 354.11198 -59.355092)
			(xy 354.083391 -59.400494) (xy 354.048726 -59.441446) (xy 354.00867 -59.477141) (xy 353.986592 -59.492388)
			(xy 353.975055 -59.500645) (xy 353.95665 -59.522216) (xy 353.944894 -59.54802) (xy 353.940695 -59.576063)
			(xy 353.944378 -59.604178) (xy 353.955658 -59.630194) (xy 353.973664 -59.652099) (xy 353.985068 -59.660536)
			(xy 354.006567 -59.675832) (xy 354.045476 -59.711471) (xy 354.079104 -59.75213) (xy 354.106809 -59.797035)
			(xy 354.128062 -59.845329) (xy 354.142459 -59.896091) (xy 354.149724 -59.948352) (xy 354.150168 -59.974734)
			(xy 354.149682 -60.001985) (xy 354.141926 -60.055933) (xy 354.137225 -60.071945) (xy 365.480249 -60.071945)
			(xy 365.488008 -60.017989) (xy 365.503366 -59.965686) (xy 365.526013 -59.916103) (xy 365.555485 -59.870246)
			(xy 365.591185 -59.829052) (xy 365.632383 -59.793358) (xy 365.678243 -59.763891) (xy 365.72783 -59.74125)
			(xy 365.780134 -59.725898) (xy 365.834091 -59.718146) (xy 365.861346 -59.717686) (xy 365.888715 -59.718187)
			(xy 365.942892 -59.725997) (xy 365.995395 -59.741478) (xy 366.045142 -59.764312) (xy 366.091111 -59.794029)
			(xy 366.112044 -59.811666) (xy 366.112298 -59.81192) (xy 366.119379 -59.817514) (xy 366.1363 -59.823756)
			(xy 366.145318 -59.824112) (xy 366.212374 -59.824112) (xy 366.221389 -59.82374) (xy 366.238306 -59.817503)
			(xy 366.245394 -59.81192) (xy 366.245902 -59.811412) (xy 366.266818 -59.793778) (xy 366.312788 -59.764118)
			(xy 366.362525 -59.741331) (xy 366.415008 -59.725886) (xy 366.469159 -59.718098) (xy 366.523868 -59.718129)
			(xy 366.57801 -59.725977) (xy 366.630476 -59.741481) (xy 366.680187 -59.764324) (xy 366.726124 -59.794035)
			(xy 366.747044 -59.811666) (xy 366.747298 -59.81192) (xy 366.754379 -59.817514) (xy 366.7713 -59.823756)
			(xy 366.780318 -59.824112) (xy 366.847374 -59.824112) (xy 366.856389 -59.82374) (xy 366.873306 -59.817503)
			(xy 366.880394 -59.81192) (xy 366.880902 -59.811412) (xy 366.901818 -59.793807) (xy 366.947757 -59.76417)
			(xy 366.997458 -59.741396) (xy 367.0499 -59.725951) (xy 367.104011 -59.718152) (xy 367.131346 -59.717686)
			(xy 367.158595 -59.718187) (xy 367.212537 -59.725949) (xy 367.264825 -59.741307) (xy 367.314396 -59.763951)
			(xy 367.36024 -59.793418) (xy 367.401424 -59.829109) (xy 367.43711 -59.870297) (xy 367.466571 -59.916145)
			(xy 367.489209 -59.965718) (xy 367.491856 -59.974734) (xy 379.3871 -59.974734) (xy 379.387532 -59.947907)
			(xy 379.395052 -59.894783) (xy 379.409936 -59.843234) (xy 379.431889 -59.794277) (xy 379.46048 -59.748875)
			(xy 379.495145 -59.707923) (xy 379.535202 -59.672227) (xy 379.55728 -59.65698) (xy 379.56885 -59.648765)
			(xy 379.587261 -59.627186) (xy 379.599019 -59.601373) (xy 379.603216 -59.573319) (xy 379.599526 -59.545195)
			(xy 379.588235 -59.519174) (xy 379.570215 -59.497267) (xy 379.558804 -59.488832) (xy 379.537353 -59.473471)
			(xy 379.498439 -59.437846) (xy 379.464806 -59.397199) (xy 379.437094 -59.352305) (xy 379.415832 -59.304021)
			(xy 379.401427 -59.253267) (xy 379.394152 -59.201013) (xy 379.393704 -59.174634) (xy 379.39419 -59.147383)
			(xy 379.401946 -59.093435) (xy 379.417301 -59.04114) (xy 379.439943 -58.991563) (xy 379.469409 -58.945713)
			(xy 379.5051 -58.904522) (xy 379.546291 -58.868831) (xy 379.592141 -58.839365) (xy 379.641718 -58.816723)
			(xy 379.694013 -58.801368) (xy 379.747961 -58.793612) (xy 379.802463 -58.793612) (xy 379.856411 -58.801368)
			(xy 379.908706 -58.816723) (xy 379.958283 -58.839365) (xy 380.004133 -58.868831) (xy 380.045324 -58.904522)
			(xy 380.081015 -58.945713) (xy 380.110481 -58.991563) (xy 380.133123 -59.04114) (xy 380.148478 -59.093435)
			(xy 380.156234 -59.147383) (xy 380.15672 -59.174634) (xy 380.156255 -59.20146) (xy 380.14874 -59.254582)
			(xy 380.133861 -59.30613) (xy 380.111913 -59.355087) (xy 380.083327 -59.400489) (xy 380.048667 -59.441442)
			(xy 380.008615 -59.47714) (xy 379.98654 -59.492388) (xy 379.975008 -59.500647) (xy 379.956612 -59.522221)
			(xy 379.944862 -59.548023) (xy 379.940665 -59.576063) (xy 379.944346 -59.604175) (xy 379.95562 -59.630189)
			(xy 379.973617 -59.652096) (xy 379.985016 -59.660536) (xy 380.006503 -59.675848) (xy 380.045415 -59.711482)
			(xy 380.079045 -59.752138) (xy 380.106753 -59.79704) (xy 380.128008 -59.845332) (xy 380.142406 -59.896092)
			(xy 380.149672 -59.948353) (xy 380.150116 -59.974734) (xy 380.14963 -60.001985) (xy 380.141874 -60.055933)
			(xy 380.126519 -60.108228) (xy 380.118196 -60.126451) (xy 391.480272 -60.126451) (xy 391.480272 -60.071949)
			(xy 391.488028 -60.018001) (xy 391.503383 -59.965705) (xy 391.526024 -59.916128) (xy 391.555491 -59.870277)
			(xy 391.591182 -59.829086) (xy 391.632372 -59.793394) (xy 391.678223 -59.763927) (xy 391.7278 -59.741285)
			(xy 391.780095 -59.72593) (xy 391.834043 -59.718172) (xy 391.861294 -59.717686) (xy 391.888664 -59.718159)
			(xy 391.942843 -59.725976) (xy 391.995346 -59.741463) (xy 392.045092 -59.764303) (xy 392.09106 -59.794026)
			(xy 392.111992 -59.811666) (xy 392.112246 -59.81192) (xy 392.119342 -59.817492) (xy 392.136252 -59.823747)
			(xy 392.145266 -59.824112) (xy 392.212322 -59.824112) (xy 392.22134 -59.823763) (xy 392.238256 -59.817509)
			(xy 392.245342 -59.81192) (xy 392.24585 -59.811412) (xy 392.266807 -59.793829) (xy 392.31277 -59.764167)
			(xy 392.362501 -59.741377) (xy 392.414977 -59.725927) (xy 392.469123 -59.718135) (xy 392.523826 -59.71816)
			(xy 392.577965 -59.726002) (xy 392.630427 -59.7415) (xy 392.680136 -59.764335) (xy 392.726072 -59.794039)
			(xy 392.746992 -59.811666) (xy 392.747246 -59.81192) (xy 392.754342 -59.817492) (xy 392.771252 -59.823747)
			(xy 392.780266 -59.824112) (xy 392.847322 -59.824112) (xy 392.85634 -59.823763) (xy 392.873256 -59.817509)
			(xy 392.880342 -59.81192) (xy 392.88085 -59.811412) (xy 392.901785 -59.793831) (xy 392.947719 -59.764191)
			(xy 392.997415 -59.741412) (xy 393.049853 -59.725961) (xy 393.10396 -59.718156) (xy 393.131294 -59.717686)
			(xy 393.158547 -59.718161) (xy 393.212497 -59.725917) (xy 393.264795 -59.741272) (xy 393.314375 -59.763914)
			(xy 393.360228 -59.793382) (xy 393.401421 -59.829075) (xy 393.437115 -59.870267) (xy 393.466583 -59.916119)
			(xy 393.489226 -59.965699) (xy 393.491879 -59.974734) (xy 405.387048 -59.974734) (xy 405.387458 -59.947906)
			(xy 405.39498 -59.89478) (xy 405.409865 -59.84323) (xy 405.431822 -59.794272) (xy 405.460416 -59.74887)
			(xy 405.495086 -59.707919) (xy 405.535148 -59.672225) (xy 405.557228 -59.65698) (xy 405.568794 -59.648762)
			(xy 405.587197 -59.627181) (xy 405.598949 -59.601369) (xy 405.603143 -59.573319) (xy 405.599455 -59.545199)
			(xy 405.58817 -59.519179) (xy 405.570159 -59.49727) (xy 405.558752 -59.488832) (xy 405.53729 -59.473487)
			(xy 405.498379 -59.437858) (xy 405.464747 -59.397207) (xy 405.437038 -59.35231) (xy 405.415778 -59.304024)
			(xy 405.401374 -59.253269) (xy 405.3941 -59.201014) (xy 405.393652 -59.174634) (xy 405.394138 -59.147383)
			(xy 405.401894 -59.093435) (xy 405.417249 -59.04114) (xy 405.439891 -58.991563) (xy 405.469357 -58.945713)
			(xy 405.505048 -58.904522) (xy 405.546239 -58.868831) (xy 405.592089 -58.839365) (xy 405.641666 -58.816723)
			(xy 405.693961 -58.801368) (xy 405.747909 -58.793612) (xy 405.802411 -58.793612) (xy 405.856359 -58.801368)
			(xy 405.908654 -58.816723) (xy 405.958231 -58.839365) (xy 406.004081 -58.868831) (xy 406.045272 -58.904522)
			(xy 406.080963 -58.945713) (xy 406.110429 -58.991563) (xy 406.133071 -59.04114) (xy 406.148426 -59.093435)
			(xy 406.156182 -59.147383) (xy 406.156668 -59.174634) (xy 406.156226 -59.201461) (xy 406.148709 -59.254585)
			(xy 406.133829 -59.306134) (xy 406.111877 -59.355092) (xy 406.083288 -59.400494) (xy 406.048623 -59.441446)
			(xy 406.008566 -59.477142) (xy 405.986488 -59.492388) (xy 405.974952 -59.500645) (xy 405.956547 -59.522216)
			(xy 405.944791 -59.54802) (xy 405.940593 -59.576063) (xy 405.944275 -59.604178) (xy 405.955555 -59.630194)
			(xy 405.97356 -59.652099) (xy 405.984964 -59.660536) (xy 406.006462 -59.675834) (xy 406.045371 -59.711471)
			(xy 406.078999 -59.752131) (xy 406.106704 -59.797035) (xy 406.127958 -59.845329) (xy 406.142355 -59.896091)
			(xy 406.14962 -59.948352) (xy 406.150064 -59.974734) (xy 406.149578 -60.001985) (xy 406.141822 -60.055933)
			(xy 406.126467 -60.108228) (xy 406.118143 -60.126455) (xy 417.480149 -60.126455) (xy 417.480149 -60.071945)
			(xy 417.487908 -60.017989) (xy 417.503266 -59.965687) (xy 417.525912 -59.916104) (xy 417.555384 -59.870248)
			(xy 417.591083 -59.829053) (xy 417.632281 -59.793359) (xy 417.678141 -59.763892) (xy 417.727727 -59.741251)
			(xy 417.78003 -59.725899) (xy 417.833987 -59.718146) (xy 417.861242 -59.717686) (xy 417.888611 -59.718189)
			(xy 417.942788 -59.725999) (xy 417.995291 -59.741479) (xy 418.045038 -59.764313) (xy 418.091007 -59.794029)
			(xy 418.11194 -59.811666) (xy 418.112194 -59.81192) (xy 418.119276 -59.817512) (xy 418.136196 -59.823755)
			(xy 418.145214 -59.824112) (xy 418.21227 -59.824112) (xy 418.221285 -59.823738) (xy 418.238202 -59.817502)
			(xy 418.24529 -59.81192) (xy 418.245798 -59.811412) (xy 418.266717 -59.793782) (xy 418.312687 -59.764122)
			(xy 418.362424 -59.741335) (xy 418.414906 -59.725889) (xy 418.469057 -59.718101) (xy 418.523765 -59.718132)
			(xy 418.577907 -59.725979) (xy 418.630372 -59.741483) (xy 418.680083 -59.764325) (xy 418.72602 -59.794036)
			(xy 418.74694 -59.811666) (xy 418.747194 -59.81192) (xy 418.754276 -59.817512) (xy 418.771196 -59.823755)
			(xy 418.780214 -59.824112) (xy 418.84727 -59.824112) (xy 418.856285 -59.823738) (xy 418.873202 -59.817502)
			(xy 418.88029 -59.81192) (xy 418.880798 -59.811412) (xy 418.901715 -59.793809) (xy 418.947654 -59.764172)
			(xy 418.997354 -59.741397) (xy 419.049797 -59.725952) (xy 419.103907 -59.718152) (xy 419.131242 -59.717686)
			(xy 419.158491 -59.718187) (xy 419.212433 -59.725948) (xy 419.264722 -59.741306) (xy 419.314293 -59.76395)
			(xy 419.360138 -59.793417) (xy 419.401322 -59.829108) (xy 419.437009 -59.870296) (xy 419.466471 -59.916144)
			(xy 419.489108 -59.965717) (xy 419.491755 -59.974734) (xy 431.386996 -59.974734) (xy 431.387429 -59.947907)
			(xy 431.39495 -59.894783) (xy 431.409833 -59.843234) (xy 431.431786 -59.794277) (xy 431.460377 -59.748875)
			(xy 431.495042 -59.707923) (xy 431.535098 -59.672227) (xy 431.557176 -59.65698) (xy 431.568746 -59.648765)
			(xy 431.587158 -59.627187) (xy 431.598917 -59.601373) (xy 431.603114 -59.573319) (xy 431.599423 -59.545195)
			(xy 431.588132 -59.519173) (xy 431.570112 -59.497267) (xy 431.5587 -59.488832) (xy 431.537248 -59.473472)
			(xy 431.498335 -59.437847) (xy 431.464701 -59.3972) (xy 431.436989 -59.352305) (xy 431.415728 -59.304021)
			(xy 431.401323 -59.253267) (xy 431.394048 -59.201013) (xy 431.3936 -59.174634) (xy 431.394086 -59.147383)
			(xy 431.401842 -59.093435) (xy 431.417197 -59.04114) (xy 431.439839 -58.991563) (xy 431.469305 -58.945713)
			(xy 431.504996 -58.904522) (xy 431.546187 -58.868831) (xy 431.592037 -58.839365) (xy 431.641614 -58.816723)
			(xy 431.693909 -58.801368) (xy 431.747857 -58.793612) (xy 431.802359 -58.793612) (xy 431.856307 -58.801368)
			(xy 431.908602 -58.816723) (xy 431.958179 -58.839365) (xy 432.004029 -58.868831) (xy 432.04522 -58.904522)
			(xy 432.080911 -58.945713) (xy 432.110377 -58.991563) (xy 432.133019 -59.04114) (xy 432.148374 -59.093435)
			(xy 432.15613 -59.147383) (xy 432.156616 -59.174634) (xy 432.156153 -59.20146) (xy 432.148637 -59.254583)
			(xy 432.133759 -59.30613) (xy 432.11181 -59.355087) (xy 432.083224 -59.400489) (xy 432.048564 -59.441442)
			(xy 432.008512 -59.47714) (xy 431.986436 -59.492388) (xy 431.974904 -59.500648) (xy 431.956509 -59.522221)
			(xy 431.944759 -59.548024) (xy 431.940563 -59.576063) (xy 431.944244 -59.604174) (xy 431.955517 -59.630188)
			(xy 431.973513 -59.652096) (xy 431.984912 -59.660536) (xy 432.006398 -59.675849) (xy 432.04531 -59.711483)
			(xy 432.078941 -59.752139) (xy 432.106648 -59.797041) (xy 432.127904 -59.845332) (xy 432.142302 -59.896093)
			(xy 432.149568 -59.948353) (xy 432.150012 -59.974734) (xy 432.149526 -60.001985) (xy 432.14177 -60.055933)
			(xy 432.126415 -60.108228) (xy 432.118092 -60.126451) (xy 443.480172 -60.126451) (xy 443.480172 -60.071949)
			(xy 443.487928 -60.018001) (xy 443.503283 -59.965706) (xy 443.525924 -59.916129) (xy 443.55539 -59.870278)
			(xy 443.591081 -59.829088) (xy 443.63227 -59.793396) (xy 443.67812 -59.763929) (xy 443.727697 -59.741287)
			(xy 443.779991 -59.72593) (xy 443.833939 -59.718172) (xy 443.86119 -59.717686) (xy 443.88856 -59.718161)
			(xy 443.942738 -59.725977) (xy 443.995241 -59.741465) (xy 444.044988 -59.764304) (xy 444.090956 -59.794026)
			(xy 444.111888 -59.811666) (xy 444.112142 -59.81192) (xy 444.119239 -59.817491) (xy 444.136148 -59.823746)
			(xy 444.145162 -59.824112) (xy 444.212218 -59.824112) (xy 444.221235 -59.823761) (xy 444.238152 -59.817509)
			(xy 444.245238 -59.81192) (xy 444.245746 -59.811412) (xy 444.266706 -59.793833) (xy 444.312669 -59.76417)
			(xy 444.362399 -59.74138) (xy 444.414875 -59.725931) (xy 444.46902 -59.718138) (xy 444.523723 -59.718163)
			(xy 444.577861 -59.726004) (xy 444.630323 -59.741501) (xy 444.680032 -59.764336) (xy 444.725968 -59.794039)
			(xy 444.746888 -59.811666) (xy 444.747142 -59.81192) (xy 444.754239 -59.817491) (xy 444.771148 -59.823746)
			(xy 444.780162 -59.824112) (xy 444.847218 -59.824112) (xy 444.856235 -59.823761) (xy 444.873152 -59.817509)
			(xy 444.880238 -59.81192) (xy 444.880746 -59.811412) (xy 444.901683 -59.793833) (xy 444.947617 -59.764192)
			(xy 444.997312 -59.741413) (xy 445.04975 -59.725962) (xy 445.103856 -59.718156) (xy 445.13119 -59.717686)
			(xy 445.158443 -59.718161) (xy 445.212394 -59.725916) (xy 445.264692 -59.741271) (xy 445.314273 -59.763913)
			(xy 445.360127 -59.79338) (xy 445.40132 -59.829073) (xy 445.437014 -59.870265) (xy 445.466482 -59.916118)
			(xy 445.489125 -59.965698) (xy 445.504482 -60.017996) (xy 445.512239 -60.071947) (xy 445.512239 -60.126453)
			(xy 445.504482 -60.180404) (xy 445.489125 -60.232702) (xy 445.466482 -60.282282) (xy 445.437014 -60.328135)
			(xy 445.40132 -60.369327) (xy 445.360127 -60.40502) (xy 445.314273 -60.434487) (xy 445.264692 -60.457129)
			(xy 445.212394 -60.472484) (xy 445.158443 -60.480239) (xy 445.13119 -60.480702) (xy 445.10382 -60.480241)
			(xy 445.04964 -60.472422) (xy 444.997137 -60.456932) (xy 444.94739 -60.434089) (xy 444.901424 -60.404364)
			(xy 444.880492 -60.386722) (xy 444.880238 -60.386468) (xy 444.873147 -60.380888) (xy 444.856234 -60.374638)
			(xy 444.847218 -60.374276) (xy 444.780162 -60.374276) (xy 444.771144 -60.37462) (xy 444.754227 -60.380877)
			(xy 444.747142 -60.386468) (xy 444.746634 -60.386976) (xy 444.72569 -60.404575) (xy 444.679725 -60.434238)
			(xy 444.629992 -60.457027) (xy 444.577514 -60.472476) (xy 444.523366 -60.480267) (xy 444.468661 -60.48024)
			(xy 444.414521 -60.472396) (xy 444.362058 -60.456896) (xy 444.312348 -60.434058) (xy 444.266411 -60.404351)
			(xy 444.245492 -60.386722) (xy 444.245238 -60.386468) (xy 444.238147 -60.380888) (xy 444.221234 -60.374638)
			(xy 444.212218 -60.374276) (xy 444.145162 -60.374276) (xy 444.136144 -60.37462) (xy 444.119227 -60.380877)
			(xy 444.112142 -60.386468) (xy 444.111634 -60.386976) (xy 444.090703 -60.404562) (xy 444.044768 -60.434202)
			(xy 443.995071 -60.45698) (xy 443.942632 -60.472429) (xy 443.888524 -60.480233) (xy 443.86119 -60.480702)
			(xy 443.833939 -60.480228) (xy 443.779991 -60.47247) (xy 443.727697 -60.457113) (xy 443.67812 -60.434471)
			(xy 443.63227 -60.405004) (xy 443.591081 -60.369312) (xy 443.55539 -60.328122) (xy 443.525924 -60.282271)
			(xy 443.503283 -60.232694) (xy 443.487928 -60.180399) (xy 443.480172 -60.126451) (xy 432.118092 -60.126451)
			(xy 432.103773 -60.157805) (xy 432.074307 -60.203655) (xy 432.038616 -60.244846) (xy 431.997425 -60.280537)
			(xy 431.951575 -60.310003) (xy 431.901998 -60.332645) (xy 431.849703 -60.348) (xy 431.795755 -60.355756)
			(xy 431.741253 -60.355756) (xy 431.687305 -60.348) (xy 431.63501 -60.332645) (xy 431.585433 -60.310003)
			(xy 431.539583 -60.280537) (xy 431.498392 -60.244846) (xy 431.462701 -60.203655) (xy 431.433235 -60.157805)
			(xy 431.410593 -60.108228) (xy 431.395238 -60.055933) (xy 431.387482 -60.001985) (xy 431.386996 -59.974734)
			(xy 419.491755 -59.974734) (xy 419.504461 -60.018008) (xy 419.512216 -60.071951) (xy 419.512216 -60.126449)
			(xy 419.504461 -60.180392) (xy 419.489108 -60.232683) (xy 419.466471 -60.282256) (xy 419.437009 -60.328104)
			(xy 419.401322 -60.369292) (xy 419.360138 -60.404983) (xy 419.314293 -60.43445) (xy 419.264722 -60.457094)
			(xy 419.212433 -60.472452) (xy 419.158491 -60.480213) (xy 419.131242 -60.480702) (xy 419.103873 -60.480211)
			(xy 419.049695 -60.472399) (xy 418.997192 -60.456916) (xy 418.947445 -60.43408) (xy 418.901477 -60.404361)
			(xy 418.880544 -60.386722) (xy 418.88029 -60.386468) (xy 418.873213 -60.380868) (xy 418.856289 -60.37463)
			(xy 418.84727 -60.374276) (xy 418.780214 -60.374276) (xy 418.771198 -60.374645) (xy 418.754282 -60.380885)
			(xy 418.747194 -60.386468) (xy 418.746686 -60.386976) (xy 418.72578 -60.404622) (xy 418.679808 -60.434283)
			(xy 418.630069 -60.45707) (xy 418.577585 -60.472515) (xy 418.523432 -60.480301) (xy 418.468722 -60.480269)
			(xy 418.414579 -60.472419) (xy 418.362113 -60.456913) (xy 418.312401 -60.434068) (xy 418.266463 -60.404354)
			(xy 418.245544 -60.386722) (xy 418.24529 -60.386468) (xy 418.238213 -60.380868) (xy 418.221289 -60.37463)
			(xy 418.21227 -60.374276) (xy 418.145214 -60.374276) (xy 418.136198 -60.374645) (xy 418.119282 -60.380885)
			(xy 418.112194 -60.386468) (xy 418.111686 -60.386976) (xy 418.090773 -60.404585) (xy 418.044833 -60.434221)
			(xy 417.995132 -60.456995) (xy 417.942688 -60.472439) (xy 417.888577 -60.480237) (xy 417.861242 -60.480702)
			(xy 417.833987 -60.480254) (xy 417.78003 -60.472501) (xy 417.727727 -60.457149) (xy 417.678141 -60.434508)
			(xy 417.632281 -60.405041) (xy 417.591083 -60.369347) (xy 417.555384 -60.328152) (xy 417.525912 -60.282296)
			(xy 417.503266 -60.232713) (xy 417.487908 -60.180411) (xy 417.480149 -60.126455) (xy 406.118143 -60.126455)
			(xy 406.103825 -60.157805) (xy 406.074359 -60.203655) (xy 406.038668 -60.244846) (xy 405.997477 -60.280537)
			(xy 405.951627 -60.310003) (xy 405.90205 -60.332645) (xy 405.849755 -60.348) (xy 405.795807 -60.355756)
			(xy 405.741305 -60.355756) (xy 405.687357 -60.348) (xy 405.635062 -60.332645) (xy 405.585485 -60.310003)
			(xy 405.539635 -60.280537) (xy 405.498444 -60.244846) (xy 405.462753 -60.203655) (xy 405.433287 -60.157805)
			(xy 405.410645 -60.108228) (xy 405.39529 -60.055933) (xy 405.387534 -60.001985) (xy 405.387048 -59.974734)
			(xy 393.491879 -59.974734) (xy 393.504582 -60.017997) (xy 393.512339 -60.071947) (xy 393.512339 -60.126453)
			(xy 393.504582 -60.180403) (xy 393.489226 -60.232701) (xy 393.466583 -60.282281) (xy 393.437115 -60.328133)
			(xy 393.401421 -60.369325) (xy 393.360228 -60.405018) (xy 393.314375 -60.434486) (xy 393.264795 -60.457128)
			(xy 393.212497 -60.472483) (xy 393.158547 -60.480239) (xy 393.131294 -60.480702) (xy 393.103924 -60.480239)
			(xy 393.049744 -60.47242) (xy 392.997241 -60.456931) (xy 392.947495 -60.434088) (xy 392.901528 -60.404363)
			(xy 392.880596 -60.386722) (xy 392.880342 -60.386468) (xy 392.87325 -60.380889) (xy 392.856337 -60.374639)
			(xy 392.847322 -60.374276) (xy 392.780266 -60.374276) (xy 392.771248 -60.374622) (xy 392.754331 -60.380878)
			(xy 392.747246 -60.386468) (xy 392.746738 -60.386976) (xy 392.725791 -60.404572) (xy 392.679826 -60.434234)
			(xy 392.630094 -60.457024) (xy 392.577616 -60.472473) (xy 392.523469 -60.480264) (xy 392.468764 -60.480238)
			(xy 392.414624 -60.472394) (xy 392.362161 -60.456895) (xy 392.312451 -60.434057) (xy 392.266515 -60.40435)
			(xy 392.245596 -60.386722) (xy 392.245342 -60.386468) (xy 392.23825 -60.380889) (xy 392.221337 -60.374639)
			(xy 392.212322 -60.374276) (xy 392.145266 -60.374276) (xy 392.136248 -60.374622) (xy 392.119331 -60.380878)
			(xy 392.112246 -60.386468) (xy 392.111738 -60.386976) (xy 392.090806 -60.40456) (xy 392.044871 -60.434201)
			(xy 391.995175 -60.456979) (xy 391.942736 -60.472429) (xy 391.888628 -60.480233) (xy 391.861294 -60.480702)
			(xy 391.834043 -60.480228) (xy 391.780095 -60.47247) (xy 391.7278 -60.457115) (xy 391.678223 -60.434473)
			(xy 391.632372 -60.405006) (xy 391.591182 -60.369314) (xy 391.555491 -60.328123) (xy 391.526024 -60.282272)
			(xy 391.503383 -60.232695) (xy 391.488028 -60.180399) (xy 391.480272 -60.126451) (xy 380.118196 -60.126451)
			(xy 380.103877 -60.157805) (xy 380.074411 -60.203655) (xy 380.03872 -60.244846) (xy 379.997529 -60.280537)
			(xy 379.951679 -60.310003) (xy 379.902102 -60.332645) (xy 379.849807 -60.348) (xy 379.795859 -60.355756)
			(xy 379.741357 -60.355756) (xy 379.687409 -60.348) (xy 379.635114 -60.332645) (xy 379.585537 -60.310003)
			(xy 379.539687 -60.280537) (xy 379.498496 -60.244846) (xy 379.462805 -60.203655) (xy 379.433339 -60.157805)
			(xy 379.410697 -60.108228) (xy 379.395342 -60.055933) (xy 379.387586 -60.001985) (xy 379.3871 -59.974734)
			(xy 367.491856 -59.974734) (xy 367.504561 -60.018008) (xy 367.512316 -60.071951) (xy 367.512316 -60.126449)
			(xy 367.504561 -60.180392) (xy 367.489209 -60.232682) (xy 367.466571 -60.282255) (xy 367.43711 -60.328103)
			(xy 367.401424 -60.369291) (xy 367.36024 -60.404982) (xy 367.314396 -60.434449) (xy 367.264825 -60.457093)
			(xy 367.212537 -60.472451) (xy 367.158595 -60.480213) (xy 367.131346 -60.480702) (xy 367.103977 -60.480208)
			(xy 367.049799 -60.472397) (xy 366.997296 -60.456915) (xy 366.947549 -60.434079) (xy 366.901581 -60.40436)
			(xy 366.880648 -60.386722) (xy 366.880394 -60.386468) (xy 366.873316 -60.380869) (xy 366.856392 -60.374631)
			(xy 366.847374 -60.374276) (xy 366.780318 -60.374276) (xy 366.771303 -60.374647) (xy 366.754386 -60.380885)
			(xy 366.747298 -60.386468) (xy 366.74679 -60.386976) (xy 366.725881 -60.404619) (xy 366.679909 -60.434279)
			(xy 366.630171 -60.457066) (xy 366.577687 -60.472511) (xy 366.523535 -60.480298) (xy 366.468826 -60.480267)
			(xy 366.414682 -60.472417) (xy 366.362216 -60.456912) (xy 366.312505 -60.434067) (xy 366.266567 -60.404354)
			(xy 366.245648 -60.386722) (xy 366.245394 -60.386468) (xy 366.238316 -60.380869) (xy 366.221392 -60.374631)
			(xy 366.212374 -60.374276) (xy 366.145318 -60.374276) (xy 366.136303 -60.374647) (xy 366.119386 -60.380885)
			(xy 366.112298 -60.386468) (xy 366.11179 -60.386976) (xy 366.090876 -60.404583) (xy 366.044936 -60.43422)
			(xy 365.995235 -60.456994) (xy 365.942792 -60.472438) (xy 365.888681 -60.480236) (xy 365.861346 -60.480702)
			(xy 365.834091 -60.480254) (xy 365.780134 -60.472502) (xy 365.72783 -60.45715) (xy 365.678243 -60.434509)
			(xy 365.632383 -60.405042) (xy 365.591185 -60.369348) (xy 365.555485 -60.328154) (xy 365.526013 -60.282297)
			(xy 365.503366 -60.232714) (xy 365.488008 -60.180411) (xy 365.48025 -60.126455) (xy 365.480249 -60.071945)
			(xy 354.137225 -60.071945) (xy 354.126571 -60.108228) (xy 354.103929 -60.157805) (xy 354.074463 -60.203655)
			(xy 354.038772 -60.244846) (xy 353.997581 -60.280537) (xy 353.951731 -60.310003) (xy 353.902154 -60.332645)
			(xy 353.849859 -60.348) (xy 353.795911 -60.355756) (xy 353.741409 -60.355756) (xy 353.687461 -60.348)
			(xy 353.635166 -60.332645) (xy 353.585589 -60.310003) (xy 353.539739 -60.280537) (xy 353.498548 -60.244846)
			(xy 353.462857 -60.203655) (xy 353.433391 -60.157805) (xy 353.410749 -60.108228) (xy 353.395394 -60.055933)
			(xy 353.387638 -60.001985) (xy 353.387152 -59.974734) (xy 329.391678 -59.974734) (xy 329.404382 -60.017996)
			(xy 329.412139 -60.071947) (xy 329.412139 -60.126453) (xy 329.404382 -60.180404) (xy 329.389025 -60.232701)
			(xy 329.366383 -60.282281) (xy 329.336914 -60.328134) (xy 329.30122 -60.369326) (xy 329.260027 -60.405019)
			(xy 329.214174 -60.434487) (xy 329.164594 -60.457128) (xy 329.112296 -60.472483) (xy 329.058345 -60.480239)
			(xy 329.031092 -60.480702) (xy 329.003722 -60.48024) (xy 328.949542 -60.472421) (xy 328.897039 -60.456931)
			(xy 328.847292 -60.434089) (xy 328.801326 -60.404363) (xy 328.780394 -60.386722) (xy 328.78014 -60.386468)
			(xy 328.773049 -60.380888) (xy 328.756135 -60.374639) (xy 328.74712 -60.374276) (xy 328.680064 -60.374276)
			(xy 328.671046 -60.374621) (xy 328.654129 -60.380877) (xy 328.647044 -60.386468) (xy 328.646536 -60.386976)
			(xy 328.62559 -60.404573) (xy 328.579625 -60.434236) (xy 328.529893 -60.457026) (xy 328.477415 -60.472474)
			(xy 328.423268 -60.480266) (xy 328.368563 -60.480239) (xy 328.314423 -60.472395) (xy 328.261959 -60.456895)
			(xy 328.21225 -60.434058) (xy 328.166313 -60.40435) (xy 328.145394 -60.386722) (xy 328.14514 -60.386468)
			(xy 328.138049 -60.380888) (xy 328.121135 -60.374639) (xy 328.11212 -60.374276) (xy 328.045064 -60.374276)
			(xy 328.036046 -60.374621) (xy 328.019129 -60.380877) (xy 328.012044 -60.386468) (xy 328.011536 -60.386976)
			(xy 327.990604 -60.404561) (xy 327.944669 -60.434202) (xy 327.894973 -60.45698) (xy 327.842534 -60.472429)
			(xy 327.788426 -60.480233) (xy 327.761092 -60.480702) (xy 327.733841 -60.480228) (xy 327.679893 -60.47247)
			(xy 327.627598 -60.457114) (xy 327.578021 -60.434472) (xy 327.532171 -60.405005) (xy 327.490981 -60.369313)
			(xy 327.45529 -60.328122) (xy 327.425824 -60.282272) (xy 327.403183 -60.232694) (xy 327.387828 -60.180399)
			(xy 327.380072 -60.126451) (xy 316.017994 -60.126451) (xy 316.003675 -60.157805) (xy 315.974209 -60.203655)
			(xy 315.938518 -60.244846) (xy 315.897327 -60.280537) (xy 315.851477 -60.310003) (xy 315.8019 -60.332645)
			(xy 315.749605 -60.348) (xy 315.695657 -60.355756) (xy 315.641155 -60.355756) (xy 315.587207 -60.348)
			(xy 315.534912 -60.332645) (xy 315.485335 -60.310003) (xy 315.439485 -60.280537) (xy 315.398294 -60.244846)
			(xy 315.362603 -60.203655) (xy 315.333137 -60.157805) (xy 315.310495 -60.108228) (xy 315.29514 -60.055933)
			(xy 315.287384 -60.001985) (xy 315.286898 -59.974734) (xy 303.391655 -59.974734) (xy 303.404361 -60.018008)
			(xy 303.412116 -60.071951) (xy 303.412116 -60.126449) (xy 303.404361 -60.180392) (xy 303.389008 -60.232682)
			(xy 303.366371 -60.282256) (xy 303.336909 -60.328103) (xy 303.301223 -60.369292) (xy 303.260039 -60.404983)
			(xy 303.214194 -60.43445) (xy 303.164624 -60.457093) (xy 303.112335 -60.472452) (xy 303.058393 -60.480213)
			(xy 303.031144 -60.480702) (xy 303.003775 -60.48021) (xy 302.949597 -60.472398) (xy 302.897094 -60.456915)
			(xy 302.847347 -60.434079) (xy 302.801379 -60.40436) (xy 302.780446 -60.386722) (xy 302.780192 -60.386468)
			(xy 302.773115 -60.380868) (xy 302.756191 -60.374631) (xy 302.747172 -60.374276) (xy 302.680116 -60.374276)
			(xy 302.671101 -60.374646) (xy 302.654184 -60.380885) (xy 302.647096 -60.386468) (xy 302.646588 -60.386976)
			(xy 302.62568 -60.40462) (xy 302.579709 -60.434281) (xy 302.52997 -60.457068) (xy 302.477486 -60.472513)
			(xy 302.423334 -60.4803) (xy 302.368624 -60.480268) (xy 302.314481 -60.472418) (xy 302.262014 -60.456912)
			(xy 302.212303 -60.434068) (xy 302.166365 -60.404354) (xy 302.145446 -60.386722) (xy 302.145192 -60.386468)
			(xy 302.138115 -60.380868) (xy 302.121191 -60.374631) (xy 302.112172 -60.374276) (xy 302.045116 -60.374276)
			(xy 302.036101 -60.374646) (xy 302.019184 -60.380885) (xy 302.012096 -60.386468) (xy 302.011588 -60.386976)
			(xy 301.990675 -60.404584) (xy 301.944735 -60.434221) (xy 301.895034 -60.456994) (xy 301.84259 -60.472439)
			(xy 301.788479 -60.480237) (xy 301.761144 -60.480702) (xy 301.733889 -60.480254) (xy 301.679932 -60.472502)
			(xy 301.627628 -60.457149) (xy 301.578042 -60.434509) (xy 301.532182 -60.405042) (xy 301.490984 -60.369347)
			(xy 301.455285 -60.328153) (xy 301.425812 -60.282297) (xy 301.403166 -60.232713) (xy 301.387808 -60.180411)
			(xy 301.380049 -60.126455) (xy 290.018045 -60.126455) (xy 290.003727 -60.157805) (xy 289.974261 -60.203655)
			(xy 289.93857 -60.244846) (xy 289.897379 -60.280537) (xy 289.851529 -60.310003) (xy 289.801952 -60.332645)
			(xy 289.749657 -60.348) (xy 289.695709 -60.355756) (xy 289.641207 -60.355756) (xy 289.587259 -60.348)
			(xy 289.534964 -60.332645) (xy 289.485387 -60.310003) (xy 289.439537 -60.280537) (xy 289.398346 -60.244846)
			(xy 289.362655 -60.203655) (xy 289.333189 -60.157805) (xy 289.310547 -60.108228) (xy 289.295192 -60.055933)
			(xy 289.287436 -60.001985) (xy 289.28695 -59.974734) (xy 277.391779 -59.974734) (xy 277.404482 -60.017997)
			(xy 277.412239 -60.071947) (xy 277.412239 -60.126453) (xy 277.404482 -60.180403) (xy 277.389126 -60.2327)
			(xy 277.366483 -60.28228) (xy 277.337015 -60.328133) (xy 277.301322 -60.369325) (xy 277.260129 -60.405018)
			(xy 277.214276 -60.434485) (xy 277.164697 -60.457127) (xy 277.112399 -60.472483) (xy 277.058449 -60.480239)
			(xy 277.031196 -60.480702) (xy 277.003826 -60.480238) (xy 276.949647 -60.472419) (xy 276.897143 -60.45693)
			(xy 276.847397 -60.434088) (xy 276.80143 -60.404363) (xy 276.780498 -60.386722) (xy 276.780244 -60.386468)
			(xy 276.773152 -60.38089) (xy 276.756239 -60.374639) (xy 276.747224 -60.374276) (xy 276.680168 -60.374276)
			(xy 276.67115 -60.374623) (xy 276.654234 -60.380878) (xy 276.647148 -60.386468) (xy 276.64664 -60.386976)
			(xy 276.625691 -60.40457) (xy 276.579727 -60.434232) (xy 276.529995 -60.457022) (xy 276.477517 -60.472471)
			(xy 276.42337 -60.480263) (xy 276.368666 -60.480237) (xy 276.314526 -60.472393) (xy 276.262063 -60.456894)
			(xy 276.212353 -60.434057) (xy 276.166417 -60.40435) (xy 276.145498 -60.386722) (xy 276.145244 -60.386468)
			(xy 276.138152 -60.38089) (xy 276.121239 -60.374639) (xy 276.112224 -60.374276) (xy 276.045168 -60.374276)
			(xy 276.03615 -60.374623) (xy 276.019234 -60.380878) (xy 276.012148 -60.386468) (xy 276.01164 -60.386976)
			(xy 275.990707 -60.404559) (xy 275.944772 -60.4342) (xy 275.895076 -60.456978) (xy 275.842637 -60.472428)
			(xy 275.78853 -60.480233) (xy 275.761196 -60.480702) (xy 275.733945 -60.480228) (xy 275.679996 -60.472471)
			(xy 275.627701 -60.457115) (xy 275.578124 -60.434473) (xy 275.532273 -60.405007) (xy 275.491083 -60.369314)
			(xy 275.455391 -60.328124) (xy 275.425925 -60.282273) (xy 275.403283 -60.232695) (xy 275.387928 -60.1804)
			(xy 275.380172 -60.126451) (xy 264.018098 -60.126451) (xy 264.003779 -60.157805) (xy 263.974313 -60.203655)
			(xy 263.938622 -60.244846) (xy 263.897431 -60.280537) (xy 263.851581 -60.310003) (xy 263.802004 -60.332645)
			(xy 263.749709 -60.348) (xy 263.695761 -60.355756) (xy 263.641259 -60.355756) (xy 263.587311 -60.348)
			(xy 263.535016 -60.332645) (xy 263.485439 -60.310003) (xy 263.439589 -60.280537) (xy 263.398398 -60.244846)
			(xy 263.362707 -60.203655) (xy 263.333241 -60.157805) (xy 263.310599 -60.108228) (xy 263.295244 -60.055933)
			(xy 263.287488 -60.001985) (xy 263.287002 -59.974734) (xy 251.391756 -59.974734) (xy 251.404461 -60.018009)
			(xy 251.412216 -60.071951) (xy 251.412216 -60.126449) (xy 251.404461 -60.180391) (xy 251.389109 -60.232681)
			(xy 251.366471 -60.282255) (xy 251.33701 -60.328102) (xy 251.301324 -60.36929) (xy 251.260141 -60.404981)
			(xy 251.214297 -60.434448) (xy 251.164726 -60.457092) (xy 251.112438 -60.472451) (xy 251.058497 -60.480213)
			(xy 251.031248 -60.480702) (xy 251.003879 -60.480207) (xy 250.949701 -60.472396) (xy 250.897198 -60.456914)
			(xy 250.847451 -60.434079) (xy 250.801483 -60.40436) (xy 250.78055 -60.386722) (xy 250.780296 -60.386468)
			(xy 250.773217 -60.38087) (xy 250.756294 -60.374631) (xy 250.747276 -60.374276) (xy 250.68022 -60.374276)
			(xy 250.671205 -60.374648) (xy 250.654288 -60.380886) (xy 250.6472 -60.386468) (xy 250.646692 -60.386976)
			(xy 250.625781 -60.404617) (xy 250.57981 -60.434277) (xy 250.530072 -60.457064) (xy 250.477589 -60.47251)
			(xy 250.423436 -60.480297) (xy 250.368727 -60.480265) (xy 250.314584 -60.472416) (xy 250.262118 -60.456911)
			(xy 250.212407 -60.434067) (xy 250.166469 -60.404354) (xy 250.14555 -60.386722) (xy 250.145296 -60.386468)
			(xy 250.138217 -60.38087) (xy 250.121294 -60.374631) (xy 250.112276 -60.374276) (xy 250.04522 -60.374276)
			(xy 250.036205 -60.374648) (xy 250.019288 -60.380886) (xy 250.0122 -60.386468) (xy 250.011692 -60.386976)
			(xy 249.990777 -60.404582) (xy 249.944837 -60.434219) (xy 249.895137 -60.456993) (xy 249.842694 -60.472438)
			(xy 249.788583 -60.480236) (xy 249.761248 -60.480702) (xy 249.733992 -60.480254) (xy 249.680036 -60.472502)
			(xy 249.627731 -60.45715) (xy 249.578144 -60.43451) (xy 249.532284 -60.405043) (xy 249.491085 -60.369349)
			(xy 249.455386 -60.328154) (xy 249.425913 -60.282298) (xy 249.403267 -60.232714) (xy 249.387908 -60.180411)
			(xy 249.38015 -60.126455) (xy 233.976797 -60.126455) (xy 233.980286 -60.151462) (xy 233.980736 -60.177934)
			(xy 233.98025 -60.205185) (xy 233.972494 -60.259133) (xy 233.957139 -60.311428) (xy 233.934497 -60.361005)
			(xy 233.905031 -60.406855) (xy 233.86934 -60.448046) (xy 233.828149 -60.483737) (xy 233.782299 -60.513203)
			(xy 233.732722 -60.535845) (xy 233.680427 -60.5512) (xy 233.626479 -60.558956) (xy 233.571977 -60.558956)
			(xy 233.518029 -60.5512) (xy 233.465734 -60.535845) (xy 233.416157 -60.513203) (xy 233.370307 -60.483737)
			(xy 233.329116 -60.448046) (xy 233.293425 -60.406855) (xy 233.263959 -60.361005) (xy 233.241317 -60.311428)
			(xy 233.225962 -60.259133) (xy 233.218206 -60.205185) (xy 233.21772 -60.177934) (xy 233.218264 -60.14923)
			(xy 233.226868 -60.092469) (xy 233.243871 -60.037636) (xy 233.268891 -59.985967) (xy 233.301364 -59.938625)
			(xy 233.340559 -59.896677) (xy 233.362754 -59.878468) (xy 233.371759 -59.870543) (xy 233.381829 -59.848806)
			(xy 233.382058 -59.836812) (xy 233.37901 -59.742832) (xy 233.367326 -59.72175) (xy 233.357166 -59.714892)
			(xy 233.335564 -59.699583) (xy 233.296418 -59.663932) (xy 233.262579 -59.623211) (xy 233.234694 -59.578202)
			(xy 233.213301 -59.52977) (xy 233.198809 -59.478845) (xy 233.191498 -59.426405) (xy 233.19105 -59.399932)
			(xy 231.874772 -59.399932) (xy 231.86999 -59.406076) (xy 231.804516 -59.4772) (xy 231.733392 -59.542674)
			(xy 231.657103 -59.602052) (xy 231.576172 -59.654927) (xy 231.491152 -59.700938) (xy 231.402621 -59.739771)
			(xy 231.311187 -59.77116) (xy 231.217473 -59.794892) (xy 231.122119 -59.810804) (xy 231.025776 -59.818787)
			(xy 230.929104 -59.818787) (xy 230.832761 -59.810804) (xy 230.737407 -59.794892) (xy 230.643693 -59.77116)
			(xy 230.552259 -59.739771) (xy 230.463728 -59.700938) (xy 230.378708 -59.654927) (xy 230.297777 -59.602052)
			(xy 230.221488 -59.542674) (xy 230.150364 -59.4772) (xy 230.08489 -59.406076) (xy 230.025512 -59.329787)
			(xy 229.972637 -59.248856) (xy 229.926626 -59.163836) (xy 229.887793 -59.075305) (xy 229.856404 -58.983871)
			(xy 229.832672 -58.890157) (xy 229.81676 -58.794803) (xy 229.808777 -58.69846) (xy 228.675469 -58.69846)
			(xy 228.681438 -58.718786) (xy 228.689198 -58.772733) (xy 228.689662 -58.799984) (xy 228.68923 -58.827239)
			(xy 228.681474 -58.881193) (xy 228.666117 -58.933494) (xy 228.643473 -58.983077) (xy 228.614003 -59.028933)
			(xy 228.578306 -59.070127) (xy 228.537109 -59.105821) (xy 228.491251 -59.135288) (xy 228.441666 -59.157928)
			(xy 228.389364 -59.17328) (xy 228.335409 -59.181032) (xy 228.308154 -59.181492) (xy 228.282307 -59.181054)
			(xy 228.231089 -59.17405) (xy 228.181287 -59.16019) (xy 228.133814 -59.139729) (xy 228.089541 -59.113041)
			(xy 228.06914 -59.097164) (xy 228.068886 -59.09691) (xy 228.061784 -59.091681) (xy 228.045078 -59.086058)
			(xy 228.027456 -59.086456) (xy 228.019102 -59.08929) (xy 227.924106 -59.12612) (xy 227.907088 -59.146948)
			(xy 227.905056 -59.160664) (xy 227.900422 -59.187285) (xy 227.884623 -59.238958) (xy 227.861691 -59.287885)
			(xy 227.832086 -59.333088) (xy 227.7964 -59.373662) (xy 227.755347 -59.408795) (xy 227.709747 -59.437784)
			(xy 227.660513 -59.46005) (xy 227.608631 -59.475147) (xy 227.555137 -59.482774) (xy 227.52812 -59.483244)
			(xy 227.513327 -59.483109) (xy 227.483829 -59.48082) (xy 227.469192 -59.478672) (xy 227.45827 -59.476894)
			(xy 227.436934 -59.48299) (xy 227.369624 -59.540394) (xy 227.367592 -59.542172) (xy 227.360581 -59.549517)
			(xy 227.352451 -59.568105) (xy 227.351844 -59.57824) (xy 227.351844 -59.579002) (xy 227.351844 -59.852052)
			(xy 227.351844 -59.852814) (xy 227.352411 -59.86296) (xy 227.36054 -59.881566) (xy 227.367592 -59.888882)
			(xy 227.369624 -59.89066) (xy 227.436934 -59.948064) (xy 227.45827 -59.95416) (xy 227.469192 -59.952382)
			(xy 227.483831 -59.950247) (xy 227.513327 -59.947955) (xy 227.52812 -59.94781) (xy 227.55693 -59.948297)
			(xy 227.613891 -59.956992) (xy 227.668897 -59.974151) (xy 227.720699 -59.999384) (xy 227.768119 -60.032118)
			(xy 227.810079 -60.071608) (xy 227.845626 -60.116957) (xy 227.873952 -60.167135) (xy 227.894413 -60.221)
			(xy 227.900992 -60.249054) (xy 227.902262 -60.255658) (xy 227.908104 -60.266834) (xy 227.912676 -60.272168)
			(xy 227.917207 -60.276896) (xy 227.92813 -60.284108) (xy 227.934266 -60.286392) (xy 228.029008 -60.319158)
			(xy 228.054662 -60.314586) (xy 228.065076 -60.30595) (xy 228.085701 -60.289528) (xy 228.130587 -60.261873)
			(xy 228.178851 -60.240656) (xy 228.229574 -60.226281) (xy 228.281793 -60.219021) (xy 228.308154 -60.218574)
			(xy 228.335408 -60.21907) (xy 228.389361 -60.226821) (xy 228.441662 -60.242173) (xy 228.491246 -60.264812)
			(xy 228.537102 -60.294277) (xy 228.578299 -60.329969) (xy 228.613995 -60.371161) (xy 228.643466 -60.417014)
			(xy 228.666111 -60.466595) (xy 228.681469 -60.518894) (xy 228.689227 -60.572846) (xy 228.689227 -60.600082)
			(xy 231.00614 -60.600082) (xy 231.010211 -60.54446) (xy 231.022337 -60.490023) (xy 231.04226 -60.437932)
			(xy 231.069556 -60.389297) (xy 231.103642 -60.345154) (xy 231.143791 -60.306445) (xy 231.189149 -60.273994)
			(xy 231.238749 -60.248493) (xy 231.291533 -60.230486) (xy 231.346376 -60.220356) (xy 231.40211 -60.218319)
			(xy 231.457547 -60.224419) (xy 231.511504 -60.238525) (xy 231.562833 -60.260337) (xy 231.610439 -60.289391)
			(xy 231.653307 -60.325066) (xy 231.690524 -60.366603) (xy 231.721297 -60.413116) (xy 231.744969 -60.463613)
			(xy 231.761037 -60.51702) (xy 231.769157 -60.572196) (xy 231.769666 -60.600082) (xy 231.769157 -60.627968)
			(xy 231.761037 -60.683144) (xy 231.744969 -60.736551) (xy 231.721297 -60.787048) (xy 231.690524 -60.833561)
			(xy 231.653307 -60.875098) (xy 231.610439 -60.910773) (xy 231.562833 -60.939827) (xy 231.511504 -60.961639)
			(xy 231.457547 -60.975745) (xy 231.40211 -60.981845) (xy 231.346376 -60.979808) (xy 231.291533 -60.969678)
			(xy 231.238749 -60.951671) (xy 231.189149 -60.92617) (xy 231.143791 -60.893719) (xy 231.103642 -60.85501)
			(xy 231.069556 -60.810867) (xy 231.04226 -60.762232) (xy 231.022337 -60.710141) (xy 231.010211 -60.655704)
			(xy 231.00614 -60.600082) (xy 228.689227 -60.600082) (xy 228.689227 -60.627354) (xy 228.681469 -60.681306)
			(xy 228.666111 -60.733605) (xy 228.643466 -60.783186) (xy 228.613995 -60.829039) (xy 228.578299 -60.870231)
			(xy 228.537102 -60.905923) (xy 228.491246 -60.935388) (xy 228.441662 -60.958027) (xy 228.389361 -60.973379)
			(xy 228.335408 -60.98113) (xy 228.308154 -60.98159) (xy 228.279346 -60.981036) (xy 228.222388 -60.972352)
			(xy 228.167383 -60.955203) (xy 228.115582 -60.929979) (xy 228.068161 -60.897254) (xy 228.0262 -60.857772)
			(xy 227.990652 -60.812429) (xy 227.962324 -60.762258) (xy 227.941862 -60.708397) (xy 227.935282 -60.680346)
			(xy 227.934012 -60.673742) (xy 227.92817 -60.662566) (xy 227.923598 -60.657232) (xy 227.919073 -60.652498)
			(xy 227.908146 -60.64529) (xy 227.902008 -60.643008) (xy 227.807266 -60.610242) (xy 227.781612 -60.614814)
			(xy 227.771198 -60.62345) (xy 227.750582 -60.639884) (xy 227.705694 -60.667538) (xy 227.657428 -60.688752)
			(xy 227.606702 -60.703124) (xy 227.554481 -60.710381) (xy 227.52812 -60.710826) (xy 227.502212 -60.710386)
			(xy 227.450875 -60.703352) (xy 227.400961 -60.689439) (xy 227.353388 -60.668902) (xy 227.309031 -60.642118)
			(xy 227.268704 -60.60958) (xy 227.233149 -60.571887) (xy 227.217732 -60.55106) (xy 227.214287 -60.546483)
			(xy 227.205686 -60.53892) (xy 227.200714 -60.536074) (xy 227.197524 -60.53438) (xy 227.190766 -60.53183)
			(xy 227.187252 -60.530994) (xy 227.147374 -60.522358) (xy 227.129086 -60.525152) (xy 227.120704 -60.529724)
			(xy 227.094794 -60.543918) (xy 227.040113 -60.566287) (xy 226.983012 -60.581448) (xy 226.924437 -60.589151)
			(xy 226.894898 -60.589668) (xy 226.894136 -60.589668) (xy 226.864166 -60.589205) (xy 226.804739 -60.581385)
			(xy 226.746841 -60.565875) (xy 226.691463 -60.542939) (xy 226.639553 -60.51297) (xy 226.591999 -60.476482)
			(xy 226.549616 -60.434098) (xy 226.513128 -60.386544) (xy 226.483159 -60.334634) (xy 226.460224 -60.279256)
			(xy 226.444714 -60.221357) (xy 226.436895 -60.16193) (xy 226.436428 -60.13196) (xy 213.311424 -60.13196)
			(xy 213.304461 -60.180391) (xy 213.289109 -60.232681) (xy 213.266471 -60.282255) (xy 213.23701 -60.328102)
			(xy 213.201324 -60.36929) (xy 213.160141 -60.404981) (xy 213.114297 -60.434448) (xy 213.064726 -60.457092)
			(xy 213.012438 -60.472451) (xy 212.958497 -60.480213) (xy 212.931248 -60.480702) (xy 212.903879 -60.480207)
			(xy 212.849701 -60.472396) (xy 212.797198 -60.456914) (xy 212.747451 -60.434079) (xy 212.701483 -60.40436)
			(xy 212.68055 -60.386722) (xy 212.680296 -60.386468) (xy 212.673217 -60.38087) (xy 212.656294 -60.374631)
			(xy 212.647276 -60.374276) (xy 212.58022 -60.374276) (xy 212.571205 -60.374648) (xy 212.554288 -60.380886)
			(xy 212.5472 -60.386468) (xy 212.546692 -60.386976) (xy 212.525781 -60.404617) (xy 212.47981 -60.434277)
			(xy 212.430072 -60.457064) (xy 212.377589 -60.47251) (xy 212.323436 -60.480297) (xy 212.268727 -60.480265)
			(xy 212.214584 -60.472416) (xy 212.162118 -60.456911) (xy 212.112407 -60.434067) (xy 212.066469 -60.404354)
			(xy 212.04555 -60.386722) (xy 212.045296 -60.386468) (xy 212.038217 -60.38087) (xy 212.021294 -60.374631)
			(xy 212.012276 -60.374276) (xy 211.94522 -60.374276) (xy 211.936205 -60.374648) (xy 211.919288 -60.380886)
			(xy 211.9122 -60.386468) (xy 211.911692 -60.386976) (xy 211.890777 -60.404582) (xy 211.844837 -60.434219)
			(xy 211.795137 -60.456993) (xy 211.742694 -60.472438) (xy 211.688583 -60.480236) (xy 211.661248 -60.480702)
			(xy 211.633992 -60.480254) (xy 211.580036 -60.472502) (xy 211.527731 -60.45715) (xy 211.478144 -60.43451)
			(xy 211.432284 -60.405043) (xy 211.391085 -60.369349) (xy 211.355386 -60.328154) (xy 211.325913 -60.282298)
			(xy 211.303267 -60.232714) (xy 211.287908 -60.180411) (xy 211.28015 -60.126455) (xy 199.918149 -60.126455)
			(xy 199.903831 -60.157805) (xy 199.874365 -60.203655) (xy 199.838674 -60.244846) (xy 199.797483 -60.280537)
			(xy 199.751633 -60.310003) (xy 199.702056 -60.332645) (xy 199.649761 -60.348) (xy 199.595813 -60.355756)
			(xy 199.541311 -60.355756) (xy 199.487363 -60.348) (xy 199.435068 -60.332645) (xy 199.385491 -60.310003)
			(xy 199.339641 -60.280537) (xy 199.29845 -60.244846) (xy 199.262759 -60.203655) (xy 199.233293 -60.157805)
			(xy 199.210651 -60.108228) (xy 199.195296 -60.055933) (xy 199.18754 -60.001985) (xy 199.187054 -59.974734)
			(xy 187.291855 -59.974734) (xy 187.30456 -60.018002) (xy 187.312316 -60.071949) (xy 187.312316 -60.126451)
			(xy 187.30456 -60.180398) (xy 187.289205 -60.232692) (xy 187.266564 -60.282268) (xy 187.237098 -60.328118)
			(xy 187.201407 -60.369307) (xy 187.160218 -60.404998) (xy 187.114368 -60.434464) (xy 187.064792 -60.457105)
			(xy 187.012498 -60.47246) (xy 186.958551 -60.480216) (xy 186.9313 -60.480702) (xy 186.90393 -60.480235)
			(xy 186.849751 -60.472418) (xy 186.797248 -60.456929) (xy 186.747501 -60.434087) (xy 186.701534 -60.404363)
			(xy 186.680602 -60.386722) (xy 186.680348 -60.386468) (xy 186.673254 -60.380892) (xy 186.656343 -60.37464)
			(xy 186.647328 -60.374276) (xy 186.580272 -60.374276) (xy 186.571254 -60.374625) (xy 186.554338 -60.380878)
			(xy 186.547252 -60.386468) (xy 186.546744 -60.386976) (xy 186.525792 -60.404566) (xy 186.479828 -60.434228)
			(xy 186.430097 -60.457018) (xy 186.37762 -60.472468) (xy 186.323473 -60.48026) (xy 186.268769 -60.480234)
			(xy 186.21463 -60.472391) (xy 186.162167 -60.456893) (xy 186.112457 -60.434056) (xy 186.066521 -60.40435)
			(xy 186.045602 -60.386722) (xy 186.045348 -60.386468) (xy 186.038254 -60.380892) (xy 186.021343 -60.37464)
			(xy 186.012328 -60.374276) (xy 185.945272 -60.374276) (xy 185.936254 -60.374625) (xy 185.919338 -60.380878)
			(xy 185.912252 -60.386468) (xy 185.911744 -60.386976) (xy 185.890809 -60.404558) (xy 185.844875 -60.434198)
			(xy 185.79518 -60.456977) (xy 185.742741 -60.472427) (xy 185.688634 -60.480233) (xy 185.6613 -60.480702)
			(xy 185.634048 -60.480228) (xy 185.5801 -60.472472) (xy 185.527804 -60.457116) (xy 185.478226 -60.434475)
			(xy 185.432375 -60.405008) (xy 185.391184 -60.369316) (xy 185.355492 -60.328125) (xy 185.326025 -60.282274)
			(xy 185.303384 -60.232696) (xy 185.288028 -60.1804) (xy 185.280272 -60.126452) (xy 173.918202 -60.126452)
			(xy 173.903883 -60.157805) (xy 173.874417 -60.203655) (xy 173.838726 -60.244846) (xy 173.797535 -60.280537)
			(xy 173.751685 -60.310003) (xy 173.702108 -60.332645) (xy 173.649813 -60.348) (xy 173.595865 -60.355756)
			(xy 173.541363 -60.355756) (xy 173.487415 -60.348) (xy 173.43512 -60.332645) (xy 173.385543 -60.310003)
			(xy 173.339693 -60.280537) (xy 173.298502 -60.244846) (xy 173.262811 -60.203655) (xy 173.233345 -60.157805)
			(xy 173.210703 -60.108228) (xy 173.195348 -60.055933) (xy 173.187592 -60.001985) (xy 173.187106 -59.974734)
			(xy 161.291978 -59.974734) (xy 161.30468 -60.017991) (xy 161.312439 -60.071945) (xy 161.312439 -60.126455)
			(xy 161.30468 -60.180409) (xy 161.289322 -60.23271) (xy 161.266677 -60.282292) (xy 161.237205 -60.328147)
			(xy 161.201506 -60.36934) (xy 161.160309 -60.405033) (xy 161.11445 -60.4345) (xy 161.064865 -60.457139)
			(xy 161.012562 -60.472491) (xy 160.958607 -60.480242) (xy 160.931352 -60.480702) (xy 160.903983 -60.480205)
			(xy 160.849805 -60.472395) (xy 160.797302 -60.456913) (xy 160.747555 -60.434078) (xy 160.701587 -60.40436)
			(xy 160.680654 -60.386722) (xy 160.6804 -60.386468) (xy 160.67332 -60.380872) (xy 160.656398 -60.374632)
			(xy 160.64738 -60.374276) (xy 160.580324 -60.374276) (xy 160.571309 -60.37465) (xy 160.554392 -60.380886)
			(xy 160.547304 -60.386468) (xy 160.546796 -60.386976) (xy 160.525882 -60.404613) (xy 160.479911 -60.434274)
			(xy 160.430174 -60.457061) (xy 160.377691 -60.472507) (xy 160.323539 -60.480294) (xy 160.26883 -60.480263)
			(xy 160.214688 -60.472414) (xy 160.162222 -60.456909) (xy 160.11251 -60.434066) (xy 160.066573 -60.404353)
			(xy 160.045654 -60.386722) (xy 160.0454 -60.386468) (xy 160.03832 -60.380872) (xy 160.021398 -60.374632)
			(xy 160.01238 -60.374276) (xy 159.945324 -60.374276) (xy 159.936309 -60.37465) (xy 159.919392 -60.380886)
			(xy 159.912304 -60.386468) (xy 159.911796 -60.386976) (xy 159.89088 -60.40458) (xy 159.84494 -60.434217)
			(xy 159.79524 -60.456992) (xy 159.742798 -60.472437) (xy 159.688687 -60.480236) (xy 159.661352 -60.480702)
			(xy 159.634103 -60.480225) (xy 159.580159 -60.472463) (xy 159.527869 -60.457103) (xy 159.478297 -60.434459)
			(xy 159.432452 -60.404991) (xy 159.391267 -60.369299) (xy 159.35558 -60.328109) (xy 159.326118 -60.28226)
			(xy 159.30348 -60.232686) (xy 159.288127 -60.180394) (xy 159.280372 -60.126449) (xy 147.918255 -60.126449)
			(xy 147.903935 -60.157805) (xy 147.874469 -60.203655) (xy 147.838778 -60.244846) (xy 147.797587 -60.280537)
			(xy 147.751737 -60.310003) (xy 147.70216 -60.332645) (xy 147.649865 -60.348) (xy 147.595917 -60.355756)
			(xy 147.541415 -60.355756) (xy 147.487467 -60.348) (xy 147.435172 -60.332645) (xy 147.385595 -60.310003)
			(xy 147.339745 -60.280537) (xy 147.298554 -60.244846) (xy 147.262863 -60.203655) (xy 147.233397 -60.157805)
			(xy 147.210755 -60.108228) (xy 147.1954 -60.055933) (xy 147.187644 -60.001985) (xy 147.187158 -59.974734)
			(xy 135.291955 -59.974734) (xy 135.30466 -60.018003) (xy 135.312416 -60.071949) (xy 135.312416 -60.126451)
			(xy 135.30466 -60.180397) (xy 135.289305 -60.232691) (xy 135.266665 -60.282267) (xy 135.237199 -60.328116)
			(xy 135.201509 -60.369306) (xy 135.16032 -60.404997) (xy 135.11447 -60.434463) (xy 135.064895 -60.457104)
			(xy 135.012601 -60.472459) (xy 134.958655 -60.480216) (xy 134.931404 -60.480702) (xy 134.904034 -60.480233)
			(xy 134.849855 -60.472416) (xy 134.797352 -60.456927) (xy 134.747605 -60.434086) (xy 134.701638 -60.404363)
			(xy 134.680706 -60.386722) (xy 134.680452 -60.386468) (xy 134.673357 -60.380893) (xy 134.656447 -60.374641)
			(xy 134.647432 -60.374276) (xy 134.580376 -60.374276) (xy 134.571359 -60.374627) (xy 134.554442 -60.380879)
			(xy 134.547356 -60.386468) (xy 134.546848 -60.386976) (xy 134.525893 -60.404562) (xy 134.479929 -60.434225)
			(xy 134.430199 -60.457015) (xy 134.377722 -60.472465) (xy 134.323576 -60.480257) (xy 134.268872 -60.480232)
			(xy 134.214733 -60.472389) (xy 134.162271 -60.456891) (xy 134.112561 -60.434055) (xy 134.066625 -60.40435)
			(xy 134.045706 -60.386722) (xy 134.045452 -60.386468) (xy 134.038357 -60.380893) (xy 134.021447 -60.374641)
			(xy 134.012432 -60.374276) (xy 133.945376 -60.374276) (xy 133.936359 -60.374627) (xy 133.919442 -60.380879)
			(xy 133.912356 -60.386468) (xy 133.911848 -60.386976) (xy 133.890912 -60.404556) (xy 133.844978 -60.434197)
			(xy 133.795283 -60.456976) (xy 133.742845 -60.472427) (xy 133.688738 -60.480232) (xy 133.661404 -60.480702)
			(xy 133.634151 -60.480251) (xy 133.580198 -60.472494) (xy 133.527899 -60.457138) (xy 133.478318 -60.434496)
			(xy 133.432463 -60.405027) (xy 133.39127 -60.369333) (xy 133.355575 -60.32814) (xy 133.326106 -60.282286)
			(xy 133.303463 -60.232705) (xy 133.288107 -60.180406) (xy 133.280349 -60.126453) (xy 121.918306 -60.126453)
			(xy 121.903987 -60.157805) (xy 121.874521 -60.203655) (xy 121.83883 -60.244846) (xy 121.797639 -60.280537)
			(xy 121.751789 -60.310003) (xy 121.702212 -60.332645) (xy 121.649917 -60.348) (xy 121.595969 -60.355756)
			(xy 121.541467 -60.355756) (xy 121.487519 -60.348) (xy 121.435224 -60.332645) (xy 121.385647 -60.310003)
			(xy 121.339797 -60.280537) (xy 121.298606 -60.244846) (xy 121.262915 -60.203655) (xy 121.233449 -60.157805)
			(xy 121.210807 -60.108228) (xy 121.195452 -60.055933) (xy 121.187696 -60.001985) (xy 121.18721 -59.974734)
			(xy 97.191778 -59.974734) (xy 97.20448 -60.017991) (xy 97.212239 -60.071945) (xy 97.212239 -60.126455)
			(xy 97.20448 -60.180409) (xy 97.189122 -60.23271) (xy 97.166476 -60.282293) (xy 97.137004 -60.328148)
			(xy 97.101306 -60.369341) (xy 97.060108 -60.405034) (xy 97.014249 -60.4345) (xy 96.964663 -60.45714)
			(xy 96.91236 -60.472491) (xy 96.858405 -60.480242) (xy 96.83115 -60.480702) (xy 96.803781 -60.480206)
			(xy 96.749603 -60.472395) (xy 96.6971 -60.456913) (xy 96.647353 -60.434078) (xy 96.601385 -60.40436)
			(xy 96.580452 -60.386722) (xy 96.580198 -60.386468) (xy 96.573119 -60.380871) (xy 96.556196 -60.374632)
			(xy 96.547178 -60.374276) (xy 96.480122 -60.374276) (xy 96.471107 -60.374649) (xy 96.45419 -60.380886)
			(xy 96.447102 -60.386468) (xy 96.446594 -60.386976) (xy 96.425682 -60.404615) (xy 96.379711 -60.434275)
			(xy 96.329973 -60.457062) (xy 96.27749 -60.472508) (xy 96.223338 -60.480295) (xy 96.168629 -60.480264)
			(xy 96.114486 -60.472415) (xy 96.06202 -60.45691) (xy 96.012308 -60.434066) (xy 95.966371 -60.404353)
			(xy 95.945452 -60.386722) (xy 95.945198 -60.386468) (xy 95.938119 -60.380871) (xy 95.921196 -60.374632)
			(xy 95.912178 -60.374276) (xy 95.845122 -60.374276) (xy 95.836107 -60.374649) (xy 95.81919 -60.380886)
			(xy 95.812102 -60.386468) (xy 95.811594 -60.386976) (xy 95.790678 -60.404581) (xy 95.744739 -60.434218)
			(xy 95.695039 -60.456993) (xy 95.642596 -60.472437) (xy 95.588485 -60.480236) (xy 95.56115 -60.480702)
			(xy 95.533901 -60.480225) (xy 95.479957 -60.472462) (xy 95.427668 -60.457103) (xy 95.378096 -60.434458)
			(xy 95.332251 -60.40499) (xy 95.291066 -60.369298) (xy 95.25538 -60.328109) (xy 95.225918 -60.28226)
			(xy 95.20328 -60.232685) (xy 95.187927 -60.180394) (xy 95.180172 -60.126449) (xy 83.818053 -60.126449)
			(xy 83.803733 -60.157805) (xy 83.774267 -60.203655) (xy 83.738576 -60.244846) (xy 83.697385 -60.280537)
			(xy 83.651535 -60.310003) (xy 83.601958 -60.332645) (xy 83.549663 -60.348) (xy 83.495715 -60.355756)
			(xy 83.441213 -60.355756) (xy 83.387265 -60.348) (xy 83.33497 -60.332645) (xy 83.285393 -60.310003)
			(xy 83.239543 -60.280537) (xy 83.198352 -60.244846) (xy 83.162661 -60.203655) (xy 83.133195 -60.157805)
			(xy 83.110553 -60.108228) (xy 83.095198 -60.055933) (xy 83.087442 -60.001985) (xy 83.086956 -59.974734)
			(xy 71.191755 -59.974734) (xy 71.20446 -60.018003) (xy 71.212216 -60.071949) (xy 71.212216 -60.126451)
			(xy 71.20446 -60.180397) (xy 71.189105 -60.232691) (xy 71.166464 -60.282268) (xy 71.136999 -60.328117)
			(xy 71.101308 -60.369307) (xy 71.060119 -60.404998) (xy 71.014269 -60.434464) (xy 70.964693 -60.457104)
			(xy 70.912399 -60.472459) (xy 70.858453 -60.480216) (xy 70.831202 -60.480702) (xy 70.803832 -60.480234)
			(xy 70.749653 -60.472417) (xy 70.69715 -60.456928) (xy 70.647403 -60.434087) (xy 70.601436 -60.404363)
			(xy 70.580504 -60.386722) (xy 70.58025 -60.386468) (xy 70.573156 -60.380893) (xy 70.556245 -60.37464)
			(xy 70.54723 -60.374276) (xy 70.480174 -60.374276) (xy 70.471156 -60.374626) (xy 70.45424 -60.380879)
			(xy 70.447154 -60.386468) (xy 70.446646 -60.386976) (xy 70.425692 -60.404564) (xy 70.379729 -60.434227)
			(xy 70.329998 -60.457017) (xy 70.277521 -60.472466) (xy 70.223375 -60.480258) (xy 70.168671 -60.480233)
			(xy 70.114531 -60.47239) (xy 70.062069 -60.456892) (xy 70.012359 -60.434055) (xy 69.966423 -60.40435)
			(xy 69.945504 -60.386722) (xy 69.94525 -60.386468) (xy 69.938156 -60.380893) (xy 69.921245 -60.37464)
			(xy 69.91223 -60.374276) (xy 69.845174 -60.374276) (xy 69.836156 -60.374626) (xy 69.81924 -60.380879)
			(xy 69.812154 -60.386468) (xy 69.811646 -60.386976) (xy 69.790711 -60.404557) (xy 69.744777 -60.434198)
			(xy 69.695081 -60.456977) (xy 69.642643 -60.472427) (xy 69.588536 -60.480232) (xy 69.561202 -60.480702)
			(xy 69.533949 -60.480251) (xy 69.479997 -60.472494) (xy 69.427698 -60.457138) (xy 69.378117 -60.434495)
			(xy 69.332262 -60.405027) (xy 69.291069 -60.369332) (xy 69.255375 -60.328139) (xy 69.225906 -60.282285)
			(xy 69.203263 -60.232704) (xy 69.187907 -60.180405) (xy 69.180149 -60.126453) (xy 57.818104 -60.126453)
			(xy 57.803785 -60.157805) (xy 57.774319 -60.203655) (xy 57.738628 -60.244846) (xy 57.697437 -60.280537)
			(xy 57.651587 -60.310003) (xy 57.60201 -60.332645) (xy 57.549715 -60.348) (xy 57.495767 -60.355756)
			(xy 57.441265 -60.355756) (xy 57.387317 -60.348) (xy 57.335022 -60.332645) (xy 57.285445 -60.310003)
			(xy 57.239595 -60.280537) (xy 57.198404 -60.244846) (xy 57.162713 -60.203655) (xy 57.133247 -60.157805)
			(xy 57.110605 -60.108228) (xy 57.09525 -60.055933) (xy 57.087494 -60.001985) (xy 57.087008 -59.974734)
			(xy 45.191877 -59.974734) (xy 45.20458 -60.017991) (xy 45.212339 -60.071945) (xy 45.212339 -60.126455)
			(xy 45.20458 -60.180409) (xy 45.189222 -60.232709) (xy 45.166577 -60.282292) (xy 45.137105 -60.328146)
			(xy 45.101407 -60.36934) (xy 45.060209 -60.405033) (xy 45.014351 -60.434499) (xy 44.964766 -60.457138)
			(xy 44.912464 -60.47249) (xy 44.858509 -60.480242) (xy 44.831254 -60.480702) (xy 44.803885 -60.480204)
			(xy 44.749707 -60.472394) (xy 44.697205 -60.456912) (xy 44.647457 -60.434077) (xy 44.601489 -60.40436)
			(xy 44.580556 -60.386722) (xy 44.580302 -60.386468) (xy 44.573222 -60.380873) (xy 44.5563 -60.374632)
			(xy 44.547282 -60.374276) (xy 44.480226 -60.374276) (xy 44.471211 -60.374651) (xy 44.454294 -60.380887)
			(xy 44.447206 -60.386468) (xy 44.446698 -60.386976) (xy 44.425782 -60.404611) (xy 44.379812 -60.434272)
			(xy 44.330075 -60.457059) (xy 44.277592 -60.472505) (xy 44.223441 -60.480293) (xy 44.168732 -60.480262)
			(xy 44.114589 -60.472414) (xy 44.062124 -60.456909) (xy 44.012412 -60.434066) (xy 43.966475 -60.404353)
			(xy 43.945556 -60.386722) (xy 43.945302 -60.386468) (xy 43.938222 -60.380873) (xy 43.9213 -60.374632)
			(xy 43.912282 -60.374276) (xy 43.845226 -60.374276) (xy 43.836211 -60.374651) (xy 43.819294 -60.380887)
			(xy 43.812206 -60.386468) (xy 43.811698 -60.386976) (xy 43.790781 -60.404579) (xy 43.744842 -60.434217)
			(xy 43.695142 -60.456991) (xy 43.642699 -60.472437) (xy 43.588589 -60.480236) (xy 43.561254 -60.480702)
			(xy 43.534004 -60.480225) (xy 43.480061 -60.472463) (xy 43.427771 -60.457104) (xy 43.378199 -60.43446)
			(xy 43.332353 -60.404992) (xy 43.291168 -60.3693) (xy 43.255481 -60.32811) (xy 43.226018 -60.282261)
			(xy 43.20338 -60.232686) (xy 43.188027 -60.180394) (xy 43.180272 -60.12645) (xy 31.818157 -60.12645)
			(xy 31.803837 -60.157805) (xy 31.774371 -60.203655) (xy 31.73868 -60.244846) (xy 31.697489 -60.280537)
			(xy 31.651639 -60.310003) (xy 31.602062 -60.332645) (xy 31.549767 -60.348) (xy 31.495819 -60.355756)
			(xy 31.441317 -60.355756) (xy 31.387369 -60.348) (xy 31.335074 -60.332645) (xy 31.285497 -60.310003)
			(xy 31.239647 -60.280537) (xy 31.198456 -60.244846) (xy 31.162765 -60.203655) (xy 31.133299 -60.157805)
			(xy 31.110657 -60.108228) (xy 31.095302 -60.055933) (xy 31.087546 -60.001985) (xy 31.08706 -59.974734)
			(xy 20.380452 -59.974734) (xy 20.380452 -60.601606) (xy 30.333186 -60.601606) (xy 30.337257 -60.545984)
			(xy 30.349383 -60.491547) (xy 30.369306 -60.439456) (xy 30.396602 -60.390821) (xy 30.430688 -60.346678)
			(xy 30.470837 -60.307969) (xy 30.516195 -60.275518) (xy 30.565795 -60.250017) (xy 30.618579 -60.23201)
			(xy 30.673422 -60.22188) (xy 30.729156 -60.219843) (xy 30.784593 -60.225943) (xy 30.83855 -60.240049)
			(xy 30.889879 -60.261861) (xy 30.937485 -60.290915) (xy 30.980353 -60.32659) (xy 31.01757 -60.368127)
			(xy 31.048343 -60.41464) (xy 31.072015 -60.465137) (xy 31.088083 -60.518544) (xy 31.096203 -60.57372)
			(xy 31.096712 -60.601606) (xy 31.096248 -60.627006) (xy 32.721294 -60.627006) (xy 32.725365 -60.571384)
			(xy 32.737491 -60.516947) (xy 32.757414 -60.464856) (xy 32.78471 -60.416221) (xy 32.818796 -60.372078)
			(xy 32.858945 -60.333369) (xy 32.904303 -60.300918) (xy 32.953903 -60.275417) (xy 33.006687 -60.25741)
			(xy 33.06153 -60.24728) (xy 33.117264 -60.245243) (xy 33.172701 -60.251343) (xy 33.226658 -60.265449)
			(xy 33.277987 -60.287261) (xy 33.325593 -60.316315) (xy 33.368461 -60.35199) (xy 33.405678 -60.393527)
			(xy 33.436451 -60.44004) (xy 33.460123 -60.490537) (xy 33.476191 -60.543944) (xy 33.484311 -60.59912)
			(xy 33.48482 -60.627006) (xy 33.484704 -60.633356) (xy 33.796984 -60.633356) (xy 33.801055 -60.577734)
			(xy 33.813181 -60.523297) (xy 33.833104 -60.471206) (xy 33.8604 -60.422571) (xy 33.894486 -60.378428)
			(xy 33.934635 -60.339719) (xy 33.979993 -60.307268) (xy 34.029593 -60.281767) (xy 34.082377 -60.26376)
			(xy 34.13722 -60.25363) (xy 34.192954 -60.251593) (xy 34.248391 -60.257693) (xy 34.302348 -60.271799)
			(xy 34.353677 -60.293611) (xy 34.401283 -60.322665) (xy 34.444151 -60.35834) (xy 34.481368 -60.399877)
			(xy 34.512141 -60.44639) (xy 34.535813 -60.496887) (xy 34.551881 -60.550294) (xy 34.560001 -60.60547)
			(xy 34.56051 -60.633356) (xy 34.813494 -60.633356) (xy 34.81398 -60.606105) (xy 34.821736 -60.552157)
			(xy 34.837091 -60.499862) (xy 34.859733 -60.450285) (xy 34.889199 -60.404435) (xy 34.92489 -60.363244)
			(xy 34.966081 -60.327553) (xy 35.011931 -60.298087) (xy 35.061508 -60.275445) (xy 35.113803 -60.26009)
			(xy 35.167751 -60.252334) (xy 35.222253 -60.252334) (xy 35.276201 -60.26009) (xy 35.328496 -60.275445)
			(xy 35.378073 -60.298087) (xy 35.423923 -60.327553) (xy 35.465114 -60.363244) (xy 35.500805 -60.404435)
			(xy 35.530271 -60.450285) (xy 35.552913 -60.499862) (xy 35.568268 -60.552157) (xy 35.575377 -60.601606)
			(xy 56.333134 -60.601606) (xy 56.337205 -60.545984) (xy 56.349331 -60.491547) (xy 56.369254 -60.439456)
			(xy 56.39655 -60.390821) (xy 56.430636 -60.346678) (xy 56.470785 -60.307969) (xy 56.516143 -60.275518)
			(xy 56.565743 -60.250017) (xy 56.618527 -60.23201) (xy 56.67337 -60.22188) (xy 56.729104 -60.219843)
			(xy 56.784541 -60.225943) (xy 56.838498 -60.240049) (xy 56.889827 -60.261861) (xy 56.937433 -60.290915)
			(xy 56.980301 -60.32659) (xy 57.017518 -60.368127) (xy 57.048291 -60.41464) (xy 57.071963 -60.465137)
			(xy 57.088031 -60.518544) (xy 57.096151 -60.57372) (xy 57.09666 -60.601606) (xy 57.096196 -60.627006)
			(xy 58.721242 -60.627006) (xy 58.725313 -60.571384) (xy 58.737439 -60.516947) (xy 58.757362 -60.464856)
			(xy 58.784658 -60.416221) (xy 58.818744 -60.372078) (xy 58.858893 -60.333369) (xy 58.904251 -60.300918)
			(xy 58.953851 -60.275417) (xy 59.006635 -60.25741) (xy 59.061478 -60.24728) (xy 59.117212 -60.245243)
			(xy 59.172649 -60.251343) (xy 59.226606 -60.265449) (xy 59.277935 -60.287261) (xy 59.325541 -60.316315)
			(xy 59.368409 -60.35199) (xy 59.405626 -60.393527) (xy 59.436399 -60.44004) (xy 59.460071 -60.490537)
			(xy 59.476139 -60.543944) (xy 59.484259 -60.59912) (xy 59.484768 -60.627006) (xy 59.484652 -60.633356)
			(xy 59.796932 -60.633356) (xy 59.801003 -60.577734) (xy 59.813129 -60.523297) (xy 59.833052 -60.471206)
			(xy 59.860348 -60.422571) (xy 59.894434 -60.378428) (xy 59.934583 -60.339719) (xy 59.979941 -60.307268)
			(xy 60.029541 -60.281767) (xy 60.082325 -60.26376) (xy 60.137168 -60.25363) (xy 60.192902 -60.251593)
			(xy 60.248339 -60.257693) (xy 60.302296 -60.271799) (xy 60.353625 -60.293611) (xy 60.401231 -60.322665)
			(xy 60.444099 -60.35834) (xy 60.481316 -60.399877) (xy 60.512089 -60.44639) (xy 60.535761 -60.496887)
			(xy 60.551829 -60.550294) (xy 60.559949 -60.60547) (xy 60.560458 -60.633356) (xy 60.812932 -60.633356)
			(xy 60.817003 -60.577734) (xy 60.829129 -60.523297) (xy 60.849052 -60.471206) (xy 60.876348 -60.422571)
			(xy 60.910434 -60.378428) (xy 60.950583 -60.339719) (xy 60.995941 -60.307268) (xy 61.045541 -60.281767)
			(xy 61.098325 -60.26376) (xy 61.153168 -60.25363) (xy 61.208902 -60.251593) (xy 61.264339 -60.257693)
			(xy 61.318296 -60.271799) (xy 61.369625 -60.293611) (xy 61.417231 -60.322665) (xy 61.460099 -60.35834)
			(xy 61.497316 -60.399877) (xy 61.528089 -60.44639) (xy 61.551761 -60.496887) (xy 61.567829 -60.550294)
			(xy 61.57538 -60.601606) (xy 82.333082 -60.601606) (xy 82.337153 -60.545984) (xy 82.349279 -60.491547)
			(xy 82.369202 -60.439456) (xy 82.396498 -60.390821) (xy 82.430584 -60.346678) (xy 82.470733 -60.307969)
			(xy 82.516091 -60.275518) (xy 82.565691 -60.250017) (xy 82.618475 -60.23201) (xy 82.673318 -60.22188)
			(xy 82.729052 -60.219843) (xy 82.784489 -60.225943) (xy 82.838446 -60.240049) (xy 82.889775 -60.261861)
			(xy 82.937381 -60.290915) (xy 82.980249 -60.32659) (xy 83.017466 -60.368127) (xy 83.048239 -60.41464)
			(xy 83.071911 -60.465137) (xy 83.087979 -60.518544) (xy 83.096099 -60.57372) (xy 83.096608 -60.601606)
			(xy 83.096144 -60.627006) (xy 84.72119 -60.627006) (xy 84.725261 -60.571384) (xy 84.737387 -60.516947)
			(xy 84.75731 -60.464856) (xy 84.784606 -60.416221) (xy 84.818692 -60.372078) (xy 84.858841 -60.333369)
			(xy 84.904199 -60.300918) (xy 84.953799 -60.275417) (xy 85.006583 -60.25741) (xy 85.061426 -60.24728)
			(xy 85.11716 -60.245243) (xy 85.172597 -60.251343) (xy 85.226554 -60.265449) (xy 85.277883 -60.287261)
			(xy 85.325489 -60.316315) (xy 85.368357 -60.35199) (xy 85.405574 -60.393527) (xy 85.436347 -60.44004)
			(xy 85.460019 -60.490537) (xy 85.476087 -60.543944) (xy 85.484207 -60.59912) (xy 85.484716 -60.627006)
			(xy 85.4846 -60.633356) (xy 85.79688 -60.633356) (xy 85.800951 -60.577734) (xy 85.813077 -60.523297)
			(xy 85.833 -60.471206) (xy 85.860296 -60.422571) (xy 85.894382 -60.378428) (xy 85.934531 -60.339719)
			(xy 85.979889 -60.307268) (xy 86.029489 -60.281767) (xy 86.082273 -60.26376) (xy 86.137116 -60.25363)
			(xy 86.19285 -60.251593) (xy 86.248287 -60.257693) (xy 86.302244 -60.271799) (xy 86.353573 -60.293611)
			(xy 86.401179 -60.322665) (xy 86.444047 -60.35834) (xy 86.481264 -60.399877) (xy 86.512037 -60.44639)
			(xy 86.535709 -60.496887) (xy 86.551777 -60.550294) (xy 86.559897 -60.60547) (xy 86.560406 -60.633356)
			(xy 86.81288 -60.633356) (xy 86.816951 -60.577734) (xy 86.829077 -60.523297) (xy 86.849 -60.471206)
			(xy 86.876296 -60.422571) (xy 86.910382 -60.378428) (xy 86.950531 -60.339719) (xy 86.995889 -60.307268)
			(xy 87.045489 -60.281767) (xy 87.098273 -60.26376) (xy 87.153116 -60.25363) (xy 87.20885 -60.251593)
			(xy 87.264287 -60.257693) (xy 87.318244 -60.271799) (xy 87.369573 -60.293611) (xy 87.417179 -60.322665)
			(xy 87.460047 -60.35834) (xy 87.497264 -60.399877) (xy 87.528037 -60.44639) (xy 87.551709 -60.496887)
			(xy 87.567777 -60.550294) (xy 87.575328 -60.601606) (xy 120.433336 -60.601606) (xy 120.437407 -60.545984)
			(xy 120.449533 -60.491547) (xy 120.469456 -60.439456) (xy 120.496752 -60.390821) (xy 120.530838 -60.346678)
			(xy 120.570987 -60.307969) (xy 120.616345 -60.275518) (xy 120.665945 -60.250017) (xy 120.718729 -60.23201)
			(xy 120.773572 -60.22188) (xy 120.829306 -60.219843) (xy 120.884743 -60.225943) (xy 120.9387 -60.240049)
			(xy 120.990029 -60.261861) (xy 121.037635 -60.290915) (xy 121.080503 -60.32659) (xy 121.11772 -60.368127)
			(xy 121.148493 -60.41464) (xy 121.172165 -60.465137) (xy 121.188233 -60.518544) (xy 121.196353 -60.57372)
			(xy 121.196862 -60.601606) (xy 121.196398 -60.627006) (xy 122.821444 -60.627006) (xy 122.825515 -60.571384)
			(xy 122.837641 -60.516947) (xy 122.857564 -60.464856) (xy 122.88486 -60.416221) (xy 122.918946 -60.372078)
			(xy 122.959095 -60.333369) (xy 123.004453 -60.300918) (xy 123.054053 -60.275417) (xy 123.106837 -60.25741)
			(xy 123.16168 -60.24728) (xy 123.217414 -60.245243) (xy 123.272851 -60.251343) (xy 123.326808 -60.265449)
			(xy 123.378137 -60.287261) (xy 123.425743 -60.316315) (xy 123.468611 -60.35199) (xy 123.505828 -60.393527)
			(xy 123.536601 -60.44004) (xy 123.560273 -60.490537) (xy 123.576341 -60.543944) (xy 123.584461 -60.59912)
			(xy 123.58497 -60.627006) (xy 123.584854 -60.633356) (xy 123.897134 -60.633356) (xy 123.901205 -60.577734)
			(xy 123.913331 -60.523297) (xy 123.933254 -60.471206) (xy 123.96055 -60.422571) (xy 123.994636 -60.378428)
			(xy 124.034785 -60.339719) (xy 124.080143 -60.307268) (xy 124.129743 -60.281767) (xy 124.182527 -60.26376)
			(xy 124.23737 -60.25363) (xy 124.293104 -60.251593) (xy 124.348541 -60.257693) (xy 124.402498 -60.271799)
			(xy 124.453827 -60.293611) (xy 124.501433 -60.322665) (xy 124.544301 -60.35834) (xy 124.581518 -60.399877)
			(xy 124.612291 -60.44639) (xy 124.635963 -60.496887) (xy 124.652031 -60.550294) (xy 124.660151 -60.60547)
			(xy 124.66066 -60.633356) (xy 124.913134 -60.633356) (xy 124.917205 -60.577734) (xy 124.929331 -60.523297)
			(xy 124.949254 -60.471206) (xy 124.97655 -60.422571) (xy 125.010636 -60.378428) (xy 125.050785 -60.339719)
			(xy 125.096143 -60.307268) (xy 125.145743 -60.281767) (xy 125.198527 -60.26376) (xy 125.25337 -60.25363)
			(xy 125.309104 -60.251593) (xy 125.364541 -60.257693) (xy 125.418498 -60.271799) (xy 125.469827 -60.293611)
			(xy 125.517433 -60.322665) (xy 125.560301 -60.35834) (xy 125.597518 -60.399877) (xy 125.628291 -60.44639)
			(xy 125.651963 -60.496887) (xy 125.668031 -60.550294) (xy 125.675582 -60.601606) (xy 146.433284 -60.601606)
			(xy 146.437355 -60.545984) (xy 146.449481 -60.491547) (xy 146.469404 -60.439456) (xy 146.4967 -60.390821)
			(xy 146.530786 -60.346678) (xy 146.570935 -60.307969) (xy 146.616293 -60.275518) (xy 146.665893 -60.250017)
			(xy 146.718677 -60.23201) (xy 146.77352 -60.22188) (xy 146.829254 -60.219843) (xy 146.884691 -60.225943)
			(xy 146.938648 -60.240049) (xy 146.989977 -60.261861) (xy 147.037583 -60.290915) (xy 147.080451 -60.32659)
			(xy 147.117668 -60.368127) (xy 147.148441 -60.41464) (xy 147.172113 -60.465137) (xy 147.188181 -60.518544)
			(xy 147.196301 -60.57372) (xy 147.19681 -60.601606) (xy 147.196346 -60.627006) (xy 148.821392 -60.627006)
			(xy 148.825463 -60.571384) (xy 148.837589 -60.516947) (xy 148.857512 -60.464856) (xy 148.884808 -60.416221)
			(xy 148.918894 -60.372078) (xy 148.959043 -60.333369) (xy 149.004401 -60.300918) (xy 149.054001 -60.275417)
			(xy 149.106785 -60.25741) (xy 149.161628 -60.24728) (xy 149.217362 -60.245243) (xy 149.272799 -60.251343)
			(xy 149.326756 -60.265449) (xy 149.378085 -60.287261) (xy 149.425691 -60.316315) (xy 149.468559 -60.35199)
			(xy 149.505776 -60.393527) (xy 149.536549 -60.44004) (xy 149.560221 -60.490537) (xy 149.576289 -60.543944)
			(xy 149.584409 -60.59912) (xy 149.584918 -60.627006) (xy 149.584802 -60.633356) (xy 149.897082 -60.633356)
			(xy 149.901153 -60.577734) (xy 149.913279 -60.523297) (xy 149.933202 -60.471206) (xy 149.960498 -60.422571)
			(xy 149.994584 -60.378428) (xy 150.034733 -60.339719) (xy 150.080091 -60.307268) (xy 150.129691 -60.281767)
			(xy 150.182475 -60.26376) (xy 150.237318 -60.25363) (xy 150.293052 -60.251593) (xy 150.348489 -60.257693)
			(xy 150.402446 -60.271799) (xy 150.453775 -60.293611) (xy 150.501381 -60.322665) (xy 150.544249 -60.35834)
			(xy 150.581466 -60.399877) (xy 150.612239 -60.44639) (xy 150.635911 -60.496887) (xy 150.651979 -60.550294)
			(xy 150.660099 -60.60547) (xy 150.660608 -60.633356) (xy 150.913082 -60.633356) (xy 150.917153 -60.577734)
			(xy 150.929279 -60.523297) (xy 150.949202 -60.471206) (xy 150.976498 -60.422571) (xy 151.010584 -60.378428)
			(xy 151.050733 -60.339719) (xy 151.096091 -60.307268) (xy 151.145691 -60.281767) (xy 151.198475 -60.26376)
			(xy 151.253318 -60.25363) (xy 151.309052 -60.251593) (xy 151.364489 -60.257693) (xy 151.418446 -60.271799)
			(xy 151.469775 -60.293611) (xy 151.517381 -60.322665) (xy 151.560249 -60.35834) (xy 151.597466 -60.399877)
			(xy 151.628239 -60.44639) (xy 151.651911 -60.496887) (xy 151.667979 -60.550294) (xy 151.67553 -60.601606)
			(xy 172.433232 -60.601606) (xy 172.437303 -60.545984) (xy 172.449429 -60.491547) (xy 172.469352 -60.439456)
			(xy 172.496648 -60.390821) (xy 172.530734 -60.346678) (xy 172.570883 -60.307969) (xy 172.616241 -60.275518)
			(xy 172.665841 -60.250017) (xy 172.718625 -60.23201) (xy 172.773468 -60.22188) (xy 172.829202 -60.219843)
			(xy 172.884639 -60.225943) (xy 172.938596 -60.240049) (xy 172.989925 -60.261861) (xy 173.037531 -60.290915)
			(xy 173.080399 -60.32659) (xy 173.117616 -60.368127) (xy 173.148389 -60.41464) (xy 173.172061 -60.465137)
			(xy 173.188129 -60.518544) (xy 173.196249 -60.57372) (xy 173.196758 -60.601606) (xy 173.196294 -60.627006)
			(xy 174.82134 -60.627006) (xy 174.825411 -60.571384) (xy 174.837537 -60.516947) (xy 174.85746 -60.464856)
			(xy 174.884756 -60.416221) (xy 174.918842 -60.372078) (xy 174.958991 -60.333369) (xy 175.004349 -60.300918)
			(xy 175.053949 -60.275417) (xy 175.106733 -60.25741) (xy 175.161576 -60.24728) (xy 175.21731 -60.245243)
			(xy 175.272747 -60.251343) (xy 175.326704 -60.265449) (xy 175.378033 -60.287261) (xy 175.425639 -60.316315)
			(xy 175.468507 -60.35199) (xy 175.505724 -60.393527) (xy 175.536497 -60.44004) (xy 175.560169 -60.490537)
			(xy 175.576237 -60.543944) (xy 175.584357 -60.59912) (xy 175.584866 -60.627006) (xy 175.58475 -60.633356)
			(xy 175.89703 -60.633356) (xy 175.901101 -60.577734) (xy 175.913227 -60.523297) (xy 175.93315 -60.471206)
			(xy 175.960446 -60.422571) (xy 175.994532 -60.378428) (xy 176.034681 -60.339719) (xy 176.080039 -60.307268)
			(xy 176.129639 -60.281767) (xy 176.182423 -60.26376) (xy 176.237266 -60.25363) (xy 176.293 -60.251593)
			(xy 176.348437 -60.257693) (xy 176.402394 -60.271799) (xy 176.453723 -60.293611) (xy 176.501329 -60.322665)
			(xy 176.544197 -60.35834) (xy 176.581414 -60.399877) (xy 176.612187 -60.44639) (xy 176.635859 -60.496887)
			(xy 176.651927 -60.550294) (xy 176.660047 -60.60547) (xy 176.660556 -60.633356) (xy 176.91303 -60.633356)
			(xy 176.917101 -60.577734) (xy 176.929227 -60.523297) (xy 176.94915 -60.471206) (xy 176.976446 -60.422571)
			(xy 177.010532 -60.378428) (xy 177.050681 -60.339719) (xy 177.096039 -60.307268) (xy 177.145639 -60.281767)
			(xy 177.198423 -60.26376) (xy 177.253266 -60.25363) (xy 177.309 -60.251593) (xy 177.364437 -60.257693)
			(xy 177.418394 -60.271799) (xy 177.469723 -60.293611) (xy 177.517329 -60.322665) (xy 177.560197 -60.35834)
			(xy 177.597414 -60.399877) (xy 177.628187 -60.44639) (xy 177.651859 -60.496887) (xy 177.667927 -60.550294)
			(xy 177.675478 -60.601606) (xy 198.43318 -60.601606) (xy 198.437251 -60.545984) (xy 198.449377 -60.491547)
			(xy 198.4693 -60.439456) (xy 198.496596 -60.390821) (xy 198.530682 -60.346678) (xy 198.570831 -60.307969)
			(xy 198.616189 -60.275518) (xy 198.665789 -60.250017) (xy 198.718573 -60.23201) (xy 198.773416 -60.22188)
			(xy 198.82915 -60.219843) (xy 198.884587 -60.225943) (xy 198.938544 -60.240049) (xy 198.989873 -60.261861)
			(xy 199.037479 -60.290915) (xy 199.080347 -60.32659) (xy 199.117564 -60.368127) (xy 199.148337 -60.41464)
			(xy 199.172009 -60.465137) (xy 199.188077 -60.518544) (xy 199.196197 -60.57372) (xy 199.196706 -60.601606)
			(xy 199.196242 -60.627006) (xy 200.821288 -60.627006) (xy 200.825359 -60.571384) (xy 200.837485 -60.516947)
			(xy 200.857408 -60.464856) (xy 200.884704 -60.416221) (xy 200.91879 -60.372078) (xy 200.958939 -60.333369)
			(xy 201.004297 -60.300918) (xy 201.053897 -60.275417) (xy 201.106681 -60.25741) (xy 201.161524 -60.24728)
			(xy 201.217258 -60.245243) (xy 201.272695 -60.251343) (xy 201.326652 -60.265449) (xy 201.377981 -60.287261)
			(xy 201.425587 -60.316315) (xy 201.468455 -60.35199) (xy 201.505672 -60.393527) (xy 201.536445 -60.44004)
			(xy 201.560117 -60.490537) (xy 201.576185 -60.543944) (xy 201.584305 -60.59912) (xy 201.584814 -60.627006)
			(xy 201.584698 -60.633356) (xy 201.896978 -60.633356) (xy 201.901049 -60.577734) (xy 201.913175 -60.523297)
			(xy 201.933098 -60.471206) (xy 201.960394 -60.422571) (xy 201.99448 -60.378428) (xy 202.034629 -60.339719)
			(xy 202.079987 -60.307268) (xy 202.129587 -60.281767) (xy 202.182371 -60.26376) (xy 202.237214 -60.25363)
			(xy 202.292948 -60.251593) (xy 202.348385 -60.257693) (xy 202.402342 -60.271799) (xy 202.453671 -60.293611)
			(xy 202.501277 -60.322665) (xy 202.544145 -60.35834) (xy 202.581362 -60.399877) (xy 202.612135 -60.44639)
			(xy 202.635807 -60.496887) (xy 202.651875 -60.550294) (xy 202.659995 -60.60547) (xy 202.660504 -60.633356)
			(xy 202.912978 -60.633356) (xy 202.917049 -60.577734) (xy 202.929175 -60.523297) (xy 202.949098 -60.471206)
			(xy 202.976394 -60.422571) (xy 203.01048 -60.378428) (xy 203.050629 -60.339719) (xy 203.095987 -60.307268)
			(xy 203.145587 -60.281767) (xy 203.198371 -60.26376) (xy 203.253214 -60.25363) (xy 203.308948 -60.251593)
			(xy 203.364385 -60.257693) (xy 203.418342 -60.271799) (xy 203.469671 -60.293611) (xy 203.517277 -60.322665)
			(xy 203.560145 -60.35834) (xy 203.597362 -60.399877) (xy 203.628135 -60.44639) (xy 203.651807 -60.496887)
			(xy 203.667875 -60.550294) (xy 203.675995 -60.60547) (xy 203.676504 -60.633356) (xy 203.675995 -60.661242)
			(xy 203.667875 -60.716418) (xy 203.651807 -60.769825) (xy 203.628135 -60.820322) (xy 203.597362 -60.866835)
			(xy 203.560145 -60.908372) (xy 203.517277 -60.944047) (xy 203.469671 -60.973101) (xy 203.418342 -60.994913)
			(xy 203.364385 -61.009019) (xy 203.308948 -61.015119) (xy 203.253214 -61.013082) (xy 203.198371 -61.002952)
			(xy 203.145587 -60.984945) (xy 203.095987 -60.959444) (xy 203.050629 -60.926993) (xy 203.01048 -60.888284)
			(xy 202.976394 -60.844141) (xy 202.949098 -60.795506) (xy 202.929175 -60.743415) (xy 202.917049 -60.688978)
			(xy 202.912978 -60.633356) (xy 202.660504 -60.633356) (xy 202.659995 -60.661242) (xy 202.651875 -60.716418)
			(xy 202.635807 -60.769825) (xy 202.612135 -60.820322) (xy 202.581362 -60.866835) (xy 202.544145 -60.908372)
			(xy 202.501277 -60.944047) (xy 202.453671 -60.973101) (xy 202.402342 -60.994913) (xy 202.348385 -61.009019)
			(xy 202.292948 -61.015119) (xy 202.237214 -61.013082) (xy 202.182371 -61.002952) (xy 202.129587 -60.984945)
			(xy 202.079987 -60.959444) (xy 202.034629 -60.926993) (xy 201.99448 -60.888284) (xy 201.960394 -60.844141)
			(xy 201.933098 -60.795506) (xy 201.913175 -60.743415) (xy 201.901049 -60.688978) (xy 201.896978 -60.633356)
			(xy 201.584698 -60.633356) (xy 201.584305 -60.654892) (xy 201.576185 -60.710068) (xy 201.560117 -60.763475)
			(xy 201.536445 -60.813972) (xy 201.505672 -60.860485) (xy 201.468455 -60.902022) (xy 201.425587 -60.937697)
			(xy 201.377981 -60.966751) (xy 201.326652 -60.988563) (xy 201.272695 -61.002669) (xy 201.217258 -61.008769)
			(xy 201.161524 -61.006732) (xy 201.106681 -60.996602) (xy 201.053897 -60.978595) (xy 201.004297 -60.953094)
			(xy 200.958939 -60.920643) (xy 200.91879 -60.881934) (xy 200.884704 -60.837791) (xy 200.857408 -60.789156)
			(xy 200.837485 -60.737065) (xy 200.825359 -60.682628) (xy 200.821288 -60.627006) (xy 199.196242 -60.627006)
			(xy 199.196197 -60.629492) (xy 199.188077 -60.684668) (xy 199.172009 -60.738075) (xy 199.148337 -60.788572)
			(xy 199.117564 -60.835085) (xy 199.080347 -60.876622) (xy 199.037479 -60.912297) (xy 198.989873 -60.941351)
			(xy 198.938544 -60.963163) (xy 198.884587 -60.977269) (xy 198.82915 -60.983369) (xy 198.773416 -60.981332)
			(xy 198.718573 -60.971202) (xy 198.665789 -60.953195) (xy 198.616189 -60.927694) (xy 198.570831 -60.895243)
			(xy 198.530682 -60.856534) (xy 198.496596 -60.812391) (xy 198.4693 -60.763756) (xy 198.449377 -60.711665)
			(xy 198.437251 -60.657228) (xy 198.43318 -60.601606) (xy 177.675478 -60.601606) (xy 177.676047 -60.60547)
			(xy 177.676556 -60.633356) (xy 177.676047 -60.661242) (xy 177.667927 -60.716418) (xy 177.651859 -60.769825)
			(xy 177.628187 -60.820322) (xy 177.597414 -60.866835) (xy 177.560197 -60.908372) (xy 177.517329 -60.944047)
			(xy 177.469723 -60.973101) (xy 177.418394 -60.994913) (xy 177.364437 -61.009019) (xy 177.309 -61.015119)
			(xy 177.253266 -61.013082) (xy 177.198423 -61.002952) (xy 177.145639 -60.984945) (xy 177.096039 -60.959444)
			(xy 177.050681 -60.926993) (xy 177.010532 -60.888284) (xy 176.976446 -60.844141) (xy 176.94915 -60.795506)
			(xy 176.929227 -60.743415) (xy 176.917101 -60.688978) (xy 176.91303 -60.633356) (xy 176.660556 -60.633356)
			(xy 176.660047 -60.661242) (xy 176.651927 -60.716418) (xy 176.635859 -60.769825) (xy 176.612187 -60.820322)
			(xy 176.581414 -60.866835) (xy 176.544197 -60.908372) (xy 176.501329 -60.944047) (xy 176.453723 -60.973101)
			(xy 176.402394 -60.994913) (xy 176.348437 -61.009019) (xy 176.293 -61.015119) (xy 176.237266 -61.013082)
			(xy 176.182423 -61.002952) (xy 176.129639 -60.984945) (xy 176.080039 -60.959444) (xy 176.034681 -60.926993)
			(xy 175.994532 -60.888284) (xy 175.960446 -60.844141) (xy 175.93315 -60.795506) (xy 175.913227 -60.743415)
			(xy 175.901101 -60.688978) (xy 175.89703 -60.633356) (xy 175.58475 -60.633356) (xy 175.584357 -60.654892)
			(xy 175.576237 -60.710068) (xy 175.560169 -60.763475) (xy 175.536497 -60.813972) (xy 175.505724 -60.860485)
			(xy 175.468507 -60.902022) (xy 175.425639 -60.937697) (xy 175.378033 -60.966751) (xy 175.326704 -60.988563)
			(xy 175.272747 -61.002669) (xy 175.21731 -61.008769) (xy 175.161576 -61.006732) (xy 175.106733 -60.996602)
			(xy 175.053949 -60.978595) (xy 175.004349 -60.953094) (xy 174.958991 -60.920643) (xy 174.918842 -60.881934)
			(xy 174.884756 -60.837791) (xy 174.85746 -60.789156) (xy 174.837537 -60.737065) (xy 174.825411 -60.682628)
			(xy 174.82134 -60.627006) (xy 173.196294 -60.627006) (xy 173.196249 -60.629492) (xy 173.188129 -60.684668)
			(xy 173.172061 -60.738075) (xy 173.148389 -60.788572) (xy 173.117616 -60.835085) (xy 173.080399 -60.876622)
			(xy 173.037531 -60.912297) (xy 172.989925 -60.941351) (xy 172.938596 -60.963163) (xy 172.884639 -60.977269)
			(xy 172.829202 -60.983369) (xy 172.773468 -60.981332) (xy 172.718625 -60.971202) (xy 172.665841 -60.953195)
			(xy 172.616241 -60.927694) (xy 172.570883 -60.895243) (xy 172.530734 -60.856534) (xy 172.496648 -60.812391)
			(xy 172.469352 -60.763756) (xy 172.449429 -60.711665) (xy 172.437303 -60.657228) (xy 172.433232 -60.601606)
			(xy 151.67553 -60.601606) (xy 151.676099 -60.60547) (xy 151.676608 -60.633356) (xy 151.676099 -60.661242)
			(xy 151.667979 -60.716418) (xy 151.651911 -60.769825) (xy 151.628239 -60.820322) (xy 151.597466 -60.866835)
			(xy 151.560249 -60.908372) (xy 151.517381 -60.944047) (xy 151.469775 -60.973101) (xy 151.418446 -60.994913)
			(xy 151.364489 -61.009019) (xy 151.309052 -61.015119) (xy 151.253318 -61.013082) (xy 151.198475 -61.002952)
			(xy 151.145691 -60.984945) (xy 151.096091 -60.959444) (xy 151.050733 -60.926993) (xy 151.010584 -60.888284)
			(xy 150.976498 -60.844141) (xy 150.949202 -60.795506) (xy 150.929279 -60.743415) (xy 150.917153 -60.688978)
			(xy 150.913082 -60.633356) (xy 150.660608 -60.633356) (xy 150.660099 -60.661242) (xy 150.651979 -60.716418)
			(xy 150.635911 -60.769825) (xy 150.612239 -60.820322) (xy 150.581466 -60.866835) (xy 150.544249 -60.908372)
			(xy 150.501381 -60.944047) (xy 150.453775 -60.973101) (xy 150.402446 -60.994913) (xy 150.348489 -61.009019)
			(xy 150.293052 -61.015119) (xy 150.237318 -61.013082) (xy 150.182475 -61.002952) (xy 150.129691 -60.984945)
			(xy 150.080091 -60.959444) (xy 150.034733 -60.926993) (xy 149.994584 -60.888284) (xy 149.960498 -60.844141)
			(xy 149.933202 -60.795506) (xy 149.913279 -60.743415) (xy 149.901153 -60.688978) (xy 149.897082 -60.633356)
			(xy 149.584802 -60.633356) (xy 149.584409 -60.654892) (xy 149.576289 -60.710068) (xy 149.560221 -60.763475)
			(xy 149.536549 -60.813972) (xy 149.505776 -60.860485) (xy 149.468559 -60.902022) (xy 149.425691 -60.937697)
			(xy 149.378085 -60.966751) (xy 149.326756 -60.988563) (xy 149.272799 -61.002669) (xy 149.217362 -61.008769)
			(xy 149.161628 -61.006732) (xy 149.106785 -60.996602) (xy 149.054001 -60.978595) (xy 149.004401 -60.953094)
			(xy 148.959043 -60.920643) (xy 148.918894 -60.881934) (xy 148.884808 -60.837791) (xy 148.857512 -60.789156)
			(xy 148.837589 -60.737065) (xy 148.825463 -60.682628) (xy 148.821392 -60.627006) (xy 147.196346 -60.627006)
			(xy 147.196301 -60.629492) (xy 147.188181 -60.684668) (xy 147.172113 -60.738075) (xy 147.148441 -60.788572)
			(xy 147.117668 -60.835085) (xy 147.080451 -60.876622) (xy 147.037583 -60.912297) (xy 146.989977 -60.941351)
			(xy 146.938648 -60.963163) (xy 146.884691 -60.977269) (xy 146.829254 -60.983369) (xy 146.77352 -60.981332)
			(xy 146.718677 -60.971202) (xy 146.665893 -60.953195) (xy 146.616293 -60.927694) (xy 146.570935 -60.895243)
			(xy 146.530786 -60.856534) (xy 146.4967 -60.812391) (xy 146.469404 -60.763756) (xy 146.449481 -60.711665)
			(xy 146.437355 -60.657228) (xy 146.433284 -60.601606) (xy 125.675582 -60.601606) (xy 125.676151 -60.60547)
			(xy 125.67666 -60.633356) (xy 125.676151 -60.661242) (xy 125.668031 -60.716418) (xy 125.651963 -60.769825)
			(xy 125.628291 -60.820322) (xy 125.597518 -60.866835) (xy 125.560301 -60.908372) (xy 125.517433 -60.944047)
			(xy 125.469827 -60.973101) (xy 125.418498 -60.994913) (xy 125.364541 -61.009019) (xy 125.309104 -61.015119)
			(xy 125.25337 -61.013082) (xy 125.198527 -61.002952) (xy 125.145743 -60.984945) (xy 125.096143 -60.959444)
			(xy 125.050785 -60.926993) (xy 125.010636 -60.888284) (xy 124.97655 -60.844141) (xy 124.949254 -60.795506)
			(xy 124.929331 -60.743415) (xy 124.917205 -60.688978) (xy 124.913134 -60.633356) (xy 124.66066 -60.633356)
			(xy 124.660151 -60.661242) (xy 124.652031 -60.716418) (xy 124.635963 -60.769825) (xy 124.612291 -60.820322)
			(xy 124.581518 -60.866835) (xy 124.544301 -60.908372) (xy 124.501433 -60.944047) (xy 124.453827 -60.973101)
			(xy 124.402498 -60.994913) (xy 124.348541 -61.009019) (xy 124.293104 -61.015119) (xy 124.23737 -61.013082)
			(xy 124.182527 -61.002952) (xy 124.129743 -60.984945) (xy 124.080143 -60.959444) (xy 124.034785 -60.926993)
			(xy 123.994636 -60.888284) (xy 123.96055 -60.844141) (xy 123.933254 -60.795506) (xy 123.913331 -60.743415)
			(xy 123.901205 -60.688978) (xy 123.897134 -60.633356) (xy 123.584854 -60.633356) (xy 123.584461 -60.654892)
			(xy 123.576341 -60.710068) (xy 123.560273 -60.763475) (xy 123.536601 -60.813972) (xy 123.505828 -60.860485)
			(xy 123.468611 -60.902022) (xy 123.425743 -60.937697) (xy 123.378137 -60.966751) (xy 123.326808 -60.988563)
			(xy 123.272851 -61.002669) (xy 123.217414 -61.008769) (xy 123.16168 -61.006732) (xy 123.106837 -60.996602)
			(xy 123.054053 -60.978595) (xy 123.004453 -60.953094) (xy 122.959095 -60.920643) (xy 122.918946 -60.881934)
			(xy 122.88486 -60.837791) (xy 122.857564 -60.789156) (xy 122.837641 -60.737065) (xy 122.825515 -60.682628)
			(xy 122.821444 -60.627006) (xy 121.196398 -60.627006) (xy 121.196353 -60.629492) (xy 121.188233 -60.684668)
			(xy 121.172165 -60.738075) (xy 121.148493 -60.788572) (xy 121.11772 -60.835085) (xy 121.080503 -60.876622)
			(xy 121.037635 -60.912297) (xy 120.990029 -60.941351) (xy 120.9387 -60.963163) (xy 120.884743 -60.977269)
			(xy 120.829306 -60.983369) (xy 120.773572 -60.981332) (xy 120.718729 -60.971202) (xy 120.665945 -60.953195)
			(xy 120.616345 -60.927694) (xy 120.570987 -60.895243) (xy 120.530838 -60.856534) (xy 120.496752 -60.812391)
			(xy 120.469456 -60.763756) (xy 120.449533 -60.711665) (xy 120.437407 -60.657228) (xy 120.433336 -60.601606)
			(xy 87.575328 -60.601606) (xy 87.575897 -60.60547) (xy 87.576406 -60.633356) (xy 87.575897 -60.661242)
			(xy 87.567777 -60.716418) (xy 87.551709 -60.769825) (xy 87.528037 -60.820322) (xy 87.497264 -60.866835)
			(xy 87.460047 -60.908372) (xy 87.417179 -60.944047) (xy 87.369573 -60.973101) (xy 87.318244 -60.994913)
			(xy 87.264287 -61.009019) (xy 87.20885 -61.015119) (xy 87.153116 -61.013082) (xy 87.098273 -61.002952)
			(xy 87.045489 -60.984945) (xy 86.995889 -60.959444) (xy 86.950531 -60.926993) (xy 86.910382 -60.888284)
			(xy 86.876296 -60.844141) (xy 86.849 -60.795506) (xy 86.829077 -60.743415) (xy 86.816951 -60.688978)
			(xy 86.81288 -60.633356) (xy 86.560406 -60.633356) (xy 86.559897 -60.661242) (xy 86.551777 -60.716418)
			(xy 86.535709 -60.769825) (xy 86.512037 -60.820322) (xy 86.481264 -60.866835) (xy 86.444047 -60.908372)
			(xy 86.401179 -60.944047) (xy 86.353573 -60.973101) (xy 86.302244 -60.994913) (xy 86.248287 -61.009019)
			(xy 86.19285 -61.015119) (xy 86.137116 -61.013082) (xy 86.082273 -61.002952) (xy 86.029489 -60.984945)
			(xy 85.979889 -60.959444) (xy 85.934531 -60.926993) (xy 85.894382 -60.888284) (xy 85.860296 -60.844141)
			(xy 85.833 -60.795506) (xy 85.813077 -60.743415) (xy 85.800951 -60.688978) (xy 85.79688 -60.633356)
			(xy 85.4846 -60.633356) (xy 85.484207 -60.654892) (xy 85.476087 -60.710068) (xy 85.460019 -60.763475)
			(xy 85.436347 -60.813972) (xy 85.405574 -60.860485) (xy 85.368357 -60.902022) (xy 85.325489 -60.937697)
			(xy 85.277883 -60.966751) (xy 85.226554 -60.988563) (xy 85.172597 -61.002669) (xy 85.11716 -61.008769)
			(xy 85.061426 -61.006732) (xy 85.006583 -60.996602) (xy 84.953799 -60.978595) (xy 84.904199 -60.953094)
			(xy 84.858841 -60.920643) (xy 84.818692 -60.881934) (xy 84.784606 -60.837791) (xy 84.75731 -60.789156)
			(xy 84.737387 -60.737065) (xy 84.725261 -60.682628) (xy 84.72119 -60.627006) (xy 83.096144 -60.627006)
			(xy 83.096099 -60.629492) (xy 83.087979 -60.684668) (xy 83.071911 -60.738075) (xy 83.048239 -60.788572)
			(xy 83.017466 -60.835085) (xy 82.980249 -60.876622) (xy 82.937381 -60.912297) (xy 82.889775 -60.941351)
			(xy 82.838446 -60.963163) (xy 82.784489 -60.977269) (xy 82.729052 -60.983369) (xy 82.673318 -60.981332)
			(xy 82.618475 -60.971202) (xy 82.565691 -60.953195) (xy 82.516091 -60.927694) (xy 82.470733 -60.895243)
			(xy 82.430584 -60.856534) (xy 82.396498 -60.812391) (xy 82.369202 -60.763756) (xy 82.349279 -60.711665)
			(xy 82.337153 -60.657228) (xy 82.333082 -60.601606) (xy 61.57538 -60.601606) (xy 61.575949 -60.60547)
			(xy 61.576458 -60.633356) (xy 61.575949 -60.661242) (xy 61.567829 -60.716418) (xy 61.551761 -60.769825)
			(xy 61.528089 -60.820322) (xy 61.497316 -60.866835) (xy 61.460099 -60.908372) (xy 61.417231 -60.944047)
			(xy 61.369625 -60.973101) (xy 61.318296 -60.994913) (xy 61.264339 -61.009019) (xy 61.208902 -61.015119)
			(xy 61.153168 -61.013082) (xy 61.098325 -61.002952) (xy 61.045541 -60.984945) (xy 60.995941 -60.959444)
			(xy 60.950583 -60.926993) (xy 60.910434 -60.888284) (xy 60.876348 -60.844141) (xy 60.849052 -60.795506)
			(xy 60.829129 -60.743415) (xy 60.817003 -60.688978) (xy 60.812932 -60.633356) (xy 60.560458 -60.633356)
			(xy 60.559949 -60.661242) (xy 60.551829 -60.716418) (xy 60.535761 -60.769825) (xy 60.512089 -60.820322)
			(xy 60.481316 -60.866835) (xy 60.444099 -60.908372) (xy 60.401231 -60.944047) (xy 60.353625 -60.973101)
			(xy 60.302296 -60.994913) (xy 60.248339 -61.009019) (xy 60.192902 -61.015119) (xy 60.137168 -61.013082)
			(xy 60.082325 -61.002952) (xy 60.029541 -60.984945) (xy 59.979941 -60.959444) (xy 59.934583 -60.926993)
			(xy 59.894434 -60.888284) (xy 59.860348 -60.844141) (xy 59.833052 -60.795506) (xy 59.813129 -60.743415)
			(xy 59.801003 -60.688978) (xy 59.796932 -60.633356) (xy 59.484652 -60.633356) (xy 59.484259 -60.654892)
			(xy 59.476139 -60.710068) (xy 59.460071 -60.763475) (xy 59.436399 -60.813972) (xy 59.405626 -60.860485)
			(xy 59.368409 -60.902022) (xy 59.325541 -60.937697) (xy 59.277935 -60.966751) (xy 59.226606 -60.988563)
			(xy 59.172649 -61.002669) (xy 59.117212 -61.008769) (xy 59.061478 -61.006732) (xy 59.006635 -60.996602)
			(xy 58.953851 -60.978595) (xy 58.904251 -60.953094) (xy 58.858893 -60.920643) (xy 58.818744 -60.881934)
			(xy 58.784658 -60.837791) (xy 58.757362 -60.789156) (xy 58.737439 -60.737065) (xy 58.725313 -60.682628)
			(xy 58.721242 -60.627006) (xy 57.096196 -60.627006) (xy 57.096151 -60.629492) (xy 57.088031 -60.684668)
			(xy 57.071963 -60.738075) (xy 57.048291 -60.788572) (xy 57.017518 -60.835085) (xy 56.980301 -60.876622)
			(xy 56.937433 -60.912297) (xy 56.889827 -60.941351) (xy 56.838498 -60.963163) (xy 56.784541 -60.977269)
			(xy 56.729104 -60.983369) (xy 56.67337 -60.981332) (xy 56.618527 -60.971202) (xy 56.565743 -60.953195)
			(xy 56.516143 -60.927694) (xy 56.470785 -60.895243) (xy 56.430636 -60.856534) (xy 56.39655 -60.812391)
			(xy 56.369254 -60.763756) (xy 56.349331 -60.711665) (xy 56.337205 -60.657228) (xy 56.333134 -60.601606)
			(xy 35.575377 -60.601606) (xy 35.576024 -60.606105) (xy 35.57651 -60.633356) (xy 35.576032 -60.660993)
			(xy 35.568072 -60.715691) (xy 35.552298 -60.768667) (xy 35.52904 -60.81881) (xy 35.498786 -60.865069)
			(xy 35.46217 -60.906476) (xy 35.441382 -60.924694) (xy 35.432238 -60.932314) (xy 35.42284 -60.953396)
			(xy 35.425888 -61.044836) (xy 35.42626 -61.050532) (xy 35.429216 -61.061555) (xy 35.43173 -61.06668)
			(xy 35.434524 -61.072014) (xy 35.44189 -61.08065) (xy 35.446716 -61.084206) (xy 35.470353 -61.102351)
			(xy 35.512278 -61.144688) (xy 35.547113 -61.193028) (xy 35.57401 -61.246195) (xy 35.592317 -61.302896)
			(xy 35.601587 -61.361754) (xy 35.602164 -61.391546) (xy 35.601678 -61.418797) (xy 35.593922 -61.472745)
			(xy 35.589498 -61.487812) (xy 58.304428 -61.487812) (xy 58.308499 -61.43219) (xy 58.320625 -61.377753)
			(xy 58.340548 -61.325662) (xy 58.367844 -61.277027) (xy 58.40193 -61.232884) (xy 58.442079 -61.194175)
			(xy 58.487437 -61.161724) (xy 58.537037 -61.136223) (xy 58.589821 -61.118216) (xy 58.644664 -61.108086)
			(xy 58.700398 -61.106049) (xy 58.755835 -61.112149) (xy 58.809792 -61.126255) (xy 58.861121 -61.148067)
			(xy 58.908727 -61.177121) (xy 58.951595 -61.212796) (xy 58.988812 -61.254333) (xy 59.019585 -61.300846)
			(xy 59.043257 -61.351343) (xy 59.059325 -61.40475) (xy 59.067445 -61.459926) (xy 59.067954 -61.487812)
			(xy 84.304376 -61.487812) (xy 84.308447 -61.43219) (xy 84.320573 -61.377753) (xy 84.340496 -61.325662)
			(xy 84.367792 -61.277027) (xy 84.401878 -61.232884) (xy 84.442027 -61.194175) (xy 84.487385 -61.161724)
			(xy 84.536985 -61.136223) (xy 84.589769 -61.118216) (xy 84.644612 -61.108086) (xy 84.700346 -61.106049)
			(xy 84.755783 -61.112149) (xy 84.80974 -61.126255) (xy 84.861069 -61.148067) (xy 84.908675 -61.177121)
			(xy 84.951543 -61.212796) (xy 84.98876 -61.254333) (xy 85.019533 -61.300846) (xy 85.043205 -61.351343)
			(xy 85.059273 -61.40475) (xy 85.067393 -61.459926) (xy 85.067902 -61.487812) (xy 122.40463 -61.487812)
			(xy 122.408701 -61.43219) (xy 122.420827 -61.377753) (xy 122.44075 -61.325662) (xy 122.468046 -61.277027)
			(xy 122.502132 -61.232884) (xy 122.542281 -61.194175) (xy 122.587639 -61.161724) (xy 122.637239 -61.136223)
			(xy 122.690023 -61.118216) (xy 122.744866 -61.108086) (xy 122.8006 -61.106049) (xy 122.856037 -61.112149)
			(xy 122.909994 -61.126255) (xy 122.961323 -61.148067) (xy 123.008929 -61.177121) (xy 123.051797 -61.212796)
			(xy 123.089014 -61.254333) (xy 123.119787 -61.300846) (xy 123.143459 -61.351343) (xy 123.159527 -61.40475)
			(xy 123.167647 -61.459926) (xy 123.168156 -61.487812) (xy 148.404578 -61.487812) (xy 148.408649 -61.43219)
			(xy 148.420775 -61.377753) (xy 148.440698 -61.325662) (xy 148.467994 -61.277027) (xy 148.50208 -61.232884)
			(xy 148.542229 -61.194175) (xy 148.587587 -61.161724) (xy 148.637187 -61.136223) (xy 148.689971 -61.118216)
			(xy 148.744814 -61.108086) (xy 148.800548 -61.106049) (xy 148.855985 -61.112149) (xy 148.909942 -61.126255)
			(xy 148.961271 -61.148067) (xy 149.008877 -61.177121) (xy 149.051745 -61.212796) (xy 149.088962 -61.254333)
			(xy 149.119735 -61.300846) (xy 149.143407 -61.351343) (xy 149.159475 -61.40475) (xy 149.167595 -61.459926)
			(xy 149.168104 -61.487812) (xy 174.404526 -61.487812) (xy 174.408597 -61.43219) (xy 174.420723 -61.377753)
			(xy 174.440646 -61.325662) (xy 174.467942 -61.277027) (xy 174.502028 -61.232884) (xy 174.542177 -61.194175)
			(xy 174.587535 -61.161724) (xy 174.637135 -61.136223) (xy 174.689919 -61.118216) (xy 174.744762 -61.108086)
			(xy 174.800496 -61.106049) (xy 174.855933 -61.112149) (xy 174.90989 -61.126255) (xy 174.961219 -61.148067)
			(xy 175.008825 -61.177121) (xy 175.051693 -61.212796) (xy 175.08891 -61.254333) (xy 175.119683 -61.300846)
			(xy 175.143355 -61.351343) (xy 175.159423 -61.40475) (xy 175.167543 -61.459926) (xy 175.168052 -61.487812)
			(xy 200.404474 -61.487812) (xy 200.408545 -61.43219) (xy 200.420671 -61.377753) (xy 200.440594 -61.325662)
			(xy 200.46789 -61.277027) (xy 200.501976 -61.232884) (xy 200.542125 -61.194175) (xy 200.587483 -61.161724)
			(xy 200.637083 -61.136223) (xy 200.689867 -61.118216) (xy 200.74471 -61.108086) (xy 200.800444 -61.106049)
			(xy 200.855881 -61.112149) (xy 200.909838 -61.126255) (xy 200.961167 -61.148067) (xy 201.008773 -61.177121)
			(xy 201.036301 -61.20003) (xy 233.19054 -61.20003) (xy 233.194611 -61.144408) (xy 233.206737 -61.089971)
			(xy 233.22666 -61.03788) (xy 233.253956 -60.989245) (xy 233.288042 -60.945102) (xy 233.328191 -60.906393)
			(xy 233.373549 -60.873942) (xy 233.423149 -60.848441) (xy 233.475933 -60.830434) (xy 233.530776 -60.820304)
			(xy 233.58651 -60.818267) (xy 233.641947 -60.824367) (xy 233.695904 -60.838473) (xy 233.747233 -60.860285)
			(xy 233.794839 -60.889339) (xy 233.832134 -60.920376) (xy 239.456974 -60.920376) (xy 239.461045 -60.864754)
			(xy 239.473171 -60.810317) (xy 239.493094 -60.758226) (xy 239.52039 -60.709591) (xy 239.554476 -60.665448)
			(xy 239.594625 -60.626739) (xy 239.639983 -60.594288) (xy 239.689583 -60.568787) (xy 239.742367 -60.55078)
			(xy 239.79721 -60.54065) (xy 239.852944 -60.538613) (xy 239.908381 -60.544713) (xy 239.962338 -60.558819)
			(xy 240.013667 -60.580631) (xy 240.048035 -60.601606) (xy 262.533128 -60.601606) (xy 262.537199 -60.545984)
			(xy 262.549325 -60.491547) (xy 262.569248 -60.439456) (xy 262.596544 -60.390821) (xy 262.63063 -60.346678)
			(xy 262.670779 -60.307969) (xy 262.716137 -60.275518) (xy 262.765737 -60.250017) (xy 262.818521 -60.23201)
			(xy 262.873364 -60.22188) (xy 262.929098 -60.219843) (xy 262.984535 -60.225943) (xy 263.038492 -60.240049)
			(xy 263.089821 -60.261861) (xy 263.137427 -60.290915) (xy 263.180295 -60.32659) (xy 263.217512 -60.368127)
			(xy 263.248285 -60.41464) (xy 263.271957 -60.465137) (xy 263.288025 -60.518544) (xy 263.296145 -60.57372)
			(xy 263.296654 -60.601606) (xy 263.29619 -60.627006) (xy 264.921236 -60.627006) (xy 264.925307 -60.571384)
			(xy 264.937433 -60.516947) (xy 264.957356 -60.464856) (xy 264.984652 -60.416221) (xy 265.018738 -60.372078)
			(xy 265.058887 -60.333369) (xy 265.104245 -60.300918) (xy 265.153845 -60.275417) (xy 265.206629 -60.25741)
			(xy 265.261472 -60.24728) (xy 265.317206 -60.245243) (xy 265.372643 -60.251343) (xy 265.4266 -60.265449)
			(xy 265.477929 -60.287261) (xy 265.525535 -60.316315) (xy 265.568403 -60.35199) (xy 265.60562 -60.393527)
			(xy 265.636393 -60.44004) (xy 265.660065 -60.490537) (xy 265.676133 -60.543944) (xy 265.684253 -60.59912)
			(xy 265.684762 -60.627006) (xy 265.684646 -60.633356) (xy 265.996926 -60.633356) (xy 266.000997 -60.577734)
			(xy 266.013123 -60.523297) (xy 266.033046 -60.471206) (xy 266.060342 -60.422571) (xy 266.094428 -60.378428)
			(xy 266.134577 -60.339719) (xy 266.179935 -60.307268) (xy 266.229535 -60.281767) (xy 266.282319 -60.26376)
			(xy 266.337162 -60.25363) (xy 266.392896 -60.251593) (xy 266.448333 -60.257693) (xy 266.50229 -60.271799)
			(xy 266.553619 -60.293611) (xy 266.601225 -60.322665) (xy 266.644093 -60.35834) (xy 266.68131 -60.399877)
			(xy 266.712083 -60.44639) (xy 266.735755 -60.496887) (xy 266.751823 -60.550294) (xy 266.759943 -60.60547)
			(xy 266.760452 -60.633356) (xy 267.012926 -60.633356) (xy 267.016997 -60.577734) (xy 267.029123 -60.523297)
			(xy 267.049046 -60.471206) (xy 267.076342 -60.422571) (xy 267.110428 -60.378428) (xy 267.150577 -60.339719)
			(xy 267.195935 -60.307268) (xy 267.245535 -60.281767) (xy 267.298319 -60.26376) (xy 267.353162 -60.25363)
			(xy 267.408896 -60.251593) (xy 267.464333 -60.257693) (xy 267.51829 -60.271799) (xy 267.569619 -60.293611)
			(xy 267.617225 -60.322665) (xy 267.660093 -60.35834) (xy 267.69731 -60.399877) (xy 267.728083 -60.44639)
			(xy 267.751755 -60.496887) (xy 267.767823 -60.550294) (xy 267.775374 -60.601606) (xy 288.533076 -60.601606)
			(xy 288.537147 -60.545984) (xy 288.549273 -60.491547) (xy 288.569196 -60.439456) (xy 288.596492 -60.390821)
			(xy 288.630578 -60.346678) (xy 288.670727 -60.307969) (xy 288.716085 -60.275518) (xy 288.765685 -60.250017)
			(xy 288.818469 -60.23201) (xy 288.873312 -60.22188) (xy 288.929046 -60.219843) (xy 288.984483 -60.225943)
			(xy 289.03844 -60.240049) (xy 289.089769 -60.261861) (xy 289.137375 -60.290915) (xy 289.180243 -60.32659)
			(xy 289.21746 -60.368127) (xy 289.248233 -60.41464) (xy 289.271905 -60.465137) (xy 289.287973 -60.518544)
			(xy 289.296093 -60.57372) (xy 289.296602 -60.601606) (xy 289.296138 -60.627006) (xy 290.921184 -60.627006)
			(xy 290.925255 -60.571384) (xy 290.937381 -60.516947) (xy 290.957304 -60.464856) (xy 290.9846 -60.416221)
			(xy 291.018686 -60.372078) (xy 291.058835 -60.333369) (xy 291.104193 -60.300918) (xy 291.153793 -60.275417)
			(xy 291.206577 -60.25741) (xy 291.26142 -60.24728) (xy 291.317154 -60.245243) (xy 291.372591 -60.251343)
			(xy 291.426548 -60.265449) (xy 291.477877 -60.287261) (xy 291.525483 -60.316315) (xy 291.568351 -60.35199)
			(xy 291.605568 -60.393527) (xy 291.636341 -60.44004) (xy 291.660013 -60.490537) (xy 291.676081 -60.543944)
			(xy 291.684201 -60.59912) (xy 291.68471 -60.627006) (xy 291.684594 -60.633356) (xy 291.996874 -60.633356)
			(xy 292.000945 -60.577734) (xy 292.013071 -60.523297) (xy 292.032994 -60.471206) (xy 292.06029 -60.422571)
			(xy 292.094376 -60.378428) (xy 292.134525 -60.339719) (xy 292.179883 -60.307268) (xy 292.229483 -60.281767)
			(xy 292.282267 -60.26376) (xy 292.33711 -60.25363) (xy 292.392844 -60.251593) (xy 292.448281 -60.257693)
			(xy 292.502238 -60.271799) (xy 292.553567 -60.293611) (xy 292.601173 -60.322665) (xy 292.644041 -60.35834)
			(xy 292.681258 -60.399877) (xy 292.712031 -60.44639) (xy 292.735703 -60.496887) (xy 292.751771 -60.550294)
			(xy 292.759891 -60.60547) (xy 292.7604 -60.633356) (xy 293.012874 -60.633356) (xy 293.016945 -60.577734)
			(xy 293.029071 -60.523297) (xy 293.048994 -60.471206) (xy 293.07629 -60.422571) (xy 293.110376 -60.378428)
			(xy 293.150525 -60.339719) (xy 293.195883 -60.307268) (xy 293.245483 -60.281767) (xy 293.298267 -60.26376)
			(xy 293.35311 -60.25363) (xy 293.408844 -60.251593) (xy 293.464281 -60.257693) (xy 293.518238 -60.271799)
			(xy 293.569567 -60.293611) (xy 293.617173 -60.322665) (xy 293.660041 -60.35834) (xy 293.697258 -60.399877)
			(xy 293.728031 -60.44639) (xy 293.751703 -60.496887) (xy 293.767771 -60.550294) (xy 293.775322 -60.601606)
			(xy 314.533024 -60.601606) (xy 314.537095 -60.545984) (xy 314.549221 -60.491547) (xy 314.569144 -60.439456)
			(xy 314.59644 -60.390821) (xy 314.630526 -60.346678) (xy 314.670675 -60.307969) (xy 314.716033 -60.275518)
			(xy 314.765633 -60.250017) (xy 314.818417 -60.23201) (xy 314.87326 -60.22188) (xy 314.928994 -60.219843)
			(xy 314.984431 -60.225943) (xy 315.038388 -60.240049) (xy 315.089717 -60.261861) (xy 315.137323 -60.290915)
			(xy 315.180191 -60.32659) (xy 315.217408 -60.368127) (xy 315.248181 -60.41464) (xy 315.271853 -60.465137)
			(xy 315.287921 -60.518544) (xy 315.296041 -60.57372) (xy 315.29655 -60.601606) (xy 315.296041 -60.629492)
			(xy 315.295472 -60.633356) (xy 317.996822 -60.633356) (xy 318.000893 -60.577734) (xy 318.013019 -60.523297)
			(xy 318.032942 -60.471206) (xy 318.060238 -60.422571) (xy 318.094324 -60.378428) (xy 318.134473 -60.339719)
			(xy 318.179831 -60.307268) (xy 318.229431 -60.281767) (xy 318.282215 -60.26376) (xy 318.337058 -60.25363)
			(xy 318.392792 -60.251593) (xy 318.448229 -60.257693) (xy 318.502186 -60.271799) (xy 318.553515 -60.293611)
			(xy 318.601121 -60.322665) (xy 318.643989 -60.35834) (xy 318.681206 -60.399877) (xy 318.711979 -60.44639)
			(xy 318.735651 -60.496887) (xy 318.751719 -60.550294) (xy 318.759839 -60.60547) (xy 318.760348 -60.633356)
			(xy 319.012822 -60.633356) (xy 319.016893 -60.577734) (xy 319.029019 -60.523297) (xy 319.048942 -60.471206)
			(xy 319.076238 -60.422571) (xy 319.110324 -60.378428) (xy 319.150473 -60.339719) (xy 319.195831 -60.307268)
			(xy 319.245431 -60.281767) (xy 319.298215 -60.26376) (xy 319.353058 -60.25363) (xy 319.408792 -60.251593)
			(xy 319.464229 -60.257693) (xy 319.518186 -60.271799) (xy 319.569515 -60.293611) (xy 319.617121 -60.322665)
			(xy 319.659989 -60.35834) (xy 319.697206 -60.399877) (xy 319.727979 -60.44639) (xy 319.751651 -60.496887)
			(xy 319.767719 -60.550294) (xy 319.77527 -60.601606) (xy 352.633278 -60.601606) (xy 352.637349 -60.545984)
			(xy 352.649475 -60.491547) (xy 352.669398 -60.439456) (xy 352.696694 -60.390821) (xy 352.73078 -60.346678)
			(xy 352.770929 -60.307969) (xy 352.816287 -60.275518) (xy 352.865887 -60.250017) (xy 352.918671 -60.23201)
			(xy 352.973514 -60.22188) (xy 353.029248 -60.219843) (xy 353.084685 -60.225943) (xy 353.138642 -60.240049)
			(xy 353.189971 -60.261861) (xy 353.237577 -60.290915) (xy 353.280445 -60.32659) (xy 353.317662 -60.368127)
			(xy 353.348435 -60.41464) (xy 353.372107 -60.465137) (xy 353.388175 -60.518544) (xy 353.396295 -60.57372)
			(xy 353.396804 -60.601606) (xy 353.39634 -60.627006) (xy 355.021386 -60.627006) (xy 355.025457 -60.571384)
			(xy 355.037583 -60.516947) (xy 355.057506 -60.464856) (xy 355.084802 -60.416221) (xy 355.118888 -60.372078)
			(xy 355.159037 -60.333369) (xy 355.204395 -60.300918) (xy 355.253995 -60.275417) (xy 355.306779 -60.25741)
			(xy 355.361622 -60.24728) (xy 355.417356 -60.245243) (xy 355.472793 -60.251343) (xy 355.52675 -60.265449)
			(xy 355.578079 -60.287261) (xy 355.625685 -60.316315) (xy 355.668553 -60.35199) (xy 355.70577 -60.393527)
			(xy 355.736543 -60.44004) (xy 355.760215 -60.490537) (xy 355.776283 -60.543944) (xy 355.784403 -60.59912)
			(xy 355.784912 -60.627006) (xy 355.784796 -60.633356) (xy 356.097076 -60.633356) (xy 356.101147 -60.577734)
			(xy 356.113273 -60.523297) (xy 356.133196 -60.471206) (xy 356.160492 -60.422571) (xy 356.194578 -60.378428)
			(xy 356.234727 -60.339719) (xy 356.280085 -60.307268) (xy 356.329685 -60.281767) (xy 356.382469 -60.26376)
			(xy 356.437312 -60.25363) (xy 356.493046 -60.251593) (xy 356.548483 -60.257693) (xy 356.60244 -60.271799)
			(xy 356.653769 -60.293611) (xy 356.701375 -60.322665) (xy 356.744243 -60.35834) (xy 356.78146 -60.399877)
			(xy 356.812233 -60.44639) (xy 356.835905 -60.496887) (xy 356.851973 -60.550294) (xy 356.860093 -60.60547)
			(xy 356.860602 -60.633356) (xy 357.113076 -60.633356) (xy 357.117147 -60.577734) (xy 357.129273 -60.523297)
			(xy 357.149196 -60.471206) (xy 357.176492 -60.422571) (xy 357.210578 -60.378428) (xy 357.250727 -60.339719)
			(xy 357.296085 -60.307268) (xy 357.345685 -60.281767) (xy 357.398469 -60.26376) (xy 357.453312 -60.25363)
			(xy 357.509046 -60.251593) (xy 357.564483 -60.257693) (xy 357.61844 -60.271799) (xy 357.669769 -60.293611)
			(xy 357.717375 -60.322665) (xy 357.760243 -60.35834) (xy 357.79746 -60.399877) (xy 357.828233 -60.44639)
			(xy 357.851905 -60.496887) (xy 357.867973 -60.550294) (xy 357.875524 -60.601606) (xy 378.633226 -60.601606)
			(xy 378.637297 -60.545984) (xy 378.649423 -60.491547) (xy 378.669346 -60.439456) (xy 378.696642 -60.390821)
			(xy 378.730728 -60.346678) (xy 378.770877 -60.307969) (xy 378.816235 -60.275518) (xy 378.865835 -60.250017)
			(xy 378.918619 -60.23201) (xy 378.973462 -60.22188) (xy 379.029196 -60.219843) (xy 379.084633 -60.225943)
			(xy 379.13859 -60.240049) (xy 379.189919 -60.261861) (xy 379.237525 -60.290915) (xy 379.280393 -60.32659)
			(xy 379.31761 -60.368127) (xy 379.348383 -60.41464) (xy 379.372055 -60.465137) (xy 379.388123 -60.518544)
			(xy 379.396243 -60.57372) (xy 379.396752 -60.601606) (xy 379.396288 -60.627006) (xy 381.021334 -60.627006)
			(xy 381.025405 -60.571384) (xy 381.037531 -60.516947) (xy 381.057454 -60.464856) (xy 381.08475 -60.416221)
			(xy 381.118836 -60.372078) (xy 381.158985 -60.333369) (xy 381.204343 -60.300918) (xy 381.253943 -60.275417)
			(xy 381.306727 -60.25741) (xy 381.36157 -60.24728) (xy 381.417304 -60.245243) (xy 381.472741 -60.251343)
			(xy 381.526698 -60.265449) (xy 381.578027 -60.287261) (xy 381.625633 -60.316315) (xy 381.668501 -60.35199)
			(xy 381.705718 -60.393527) (xy 381.736491 -60.44004) (xy 381.760163 -60.490537) (xy 381.776231 -60.543944)
			(xy 381.784351 -60.59912) (xy 381.78486 -60.627006) (xy 381.784744 -60.633356) (xy 382.097024 -60.633356)
			(xy 382.101095 -60.577734) (xy 382.113221 -60.523297) (xy 382.133144 -60.471206) (xy 382.16044 -60.422571)
			(xy 382.194526 -60.378428) (xy 382.234675 -60.339719) (xy 382.280033 -60.307268) (xy 382.329633 -60.281767)
			(xy 382.382417 -60.26376) (xy 382.43726 -60.25363) (xy 382.492994 -60.251593) (xy 382.548431 -60.257693)
			(xy 382.602388 -60.271799) (xy 382.653717 -60.293611) (xy 382.701323 -60.322665) (xy 382.744191 -60.35834)
			(xy 382.781408 -60.399877) (xy 382.812181 -60.44639) (xy 382.835853 -60.496887) (xy 382.851921 -60.550294)
			(xy 382.860041 -60.60547) (xy 382.86055 -60.633356) (xy 383.113024 -60.633356) (xy 383.117095 -60.577734)
			(xy 383.129221 -60.523297) (xy 383.149144 -60.471206) (xy 383.17644 -60.422571) (xy 383.210526 -60.378428)
			(xy 383.250675 -60.339719) (xy 383.296033 -60.307268) (xy 383.345633 -60.281767) (xy 383.398417 -60.26376)
			(xy 383.45326 -60.25363) (xy 383.508994 -60.251593) (xy 383.564431 -60.257693) (xy 383.618388 -60.271799)
			(xy 383.669717 -60.293611) (xy 383.717323 -60.322665) (xy 383.760191 -60.35834) (xy 383.797408 -60.399877)
			(xy 383.828181 -60.44639) (xy 383.851853 -60.496887) (xy 383.867921 -60.550294) (xy 383.875472 -60.601606)
			(xy 404.633174 -60.601606) (xy 404.637245 -60.545984) (xy 404.649371 -60.491547) (xy 404.669294 -60.439456)
			(xy 404.69659 -60.390821) (xy 404.730676 -60.346678) (xy 404.770825 -60.307969) (xy 404.816183 -60.275518)
			(xy 404.865783 -60.250017) (xy 404.918567 -60.23201) (xy 404.97341 -60.22188) (xy 405.029144 -60.219843)
			(xy 405.084581 -60.225943) (xy 405.138538 -60.240049) (xy 405.189867 -60.261861) (xy 405.237473 -60.290915)
			(xy 405.280341 -60.32659) (xy 405.317558 -60.368127) (xy 405.348331 -60.41464) (xy 405.372003 -60.465137)
			(xy 405.388071 -60.518544) (xy 405.396191 -60.57372) (xy 405.3967 -60.601606) (xy 405.396236 -60.627006)
			(xy 407.021282 -60.627006) (xy 407.025353 -60.571384) (xy 407.037479 -60.516947) (xy 407.057402 -60.464856)
			(xy 407.084698 -60.416221) (xy 407.118784 -60.372078) (xy 407.158933 -60.333369) (xy 407.204291 -60.300918)
			(xy 407.253891 -60.275417) (xy 407.306675 -60.25741) (xy 407.361518 -60.24728) (xy 407.417252 -60.245243)
			(xy 407.472689 -60.251343) (xy 407.526646 -60.265449) (xy 407.577975 -60.287261) (xy 407.625581 -60.316315)
			(xy 407.668449 -60.35199) (xy 407.705666 -60.393527) (xy 407.736439 -60.44004) (xy 407.760111 -60.490537)
			(xy 407.776179 -60.543944) (xy 407.784299 -60.59912) (xy 407.784808 -60.627006) (xy 407.784692 -60.633356)
			(xy 408.096972 -60.633356) (xy 408.101043 -60.577734) (xy 408.113169 -60.523297) (xy 408.133092 -60.471206)
			(xy 408.160388 -60.422571) (xy 408.194474 -60.378428) (xy 408.234623 -60.339719) (xy 408.279981 -60.307268)
			(xy 408.329581 -60.281767) (xy 408.382365 -60.26376) (xy 408.437208 -60.25363) (xy 408.492942 -60.251593)
			(xy 408.548379 -60.257693) (xy 408.602336 -60.271799) (xy 408.653665 -60.293611) (xy 408.701271 -60.322665)
			(xy 408.744139 -60.35834) (xy 408.781356 -60.399877) (xy 408.812129 -60.44639) (xy 408.835801 -60.496887)
			(xy 408.851869 -60.550294) (xy 408.859989 -60.60547) (xy 408.860498 -60.633356) (xy 409.112972 -60.633356)
			(xy 409.117043 -60.577734) (xy 409.129169 -60.523297) (xy 409.149092 -60.471206) (xy 409.176388 -60.422571)
			(xy 409.210474 -60.378428) (xy 409.250623 -60.339719) (xy 409.295981 -60.307268) (xy 409.345581 -60.281767)
			(xy 409.398365 -60.26376) (xy 409.453208 -60.25363) (xy 409.508942 -60.251593) (xy 409.564379 -60.257693)
			(xy 409.618336 -60.271799) (xy 409.669665 -60.293611) (xy 409.717271 -60.322665) (xy 409.760139 -60.35834)
			(xy 409.797356 -60.399877) (xy 409.828129 -60.44639) (xy 409.851801 -60.496887) (xy 409.867869 -60.550294)
			(xy 409.87542 -60.601606) (xy 430.633122 -60.601606) (xy 430.637193 -60.545984) (xy 430.649319 -60.491547)
			(xy 430.669242 -60.439456) (xy 430.696538 -60.390821) (xy 430.730624 -60.346678) (xy 430.770773 -60.307969)
			(xy 430.816131 -60.275518) (xy 430.865731 -60.250017) (xy 430.918515 -60.23201) (xy 430.973358 -60.22188)
			(xy 431.029092 -60.219843) (xy 431.084529 -60.225943) (xy 431.138486 -60.240049) (xy 431.189815 -60.261861)
			(xy 431.237421 -60.290915) (xy 431.280289 -60.32659) (xy 431.317506 -60.368127) (xy 431.348279 -60.41464)
			(xy 431.371951 -60.465137) (xy 431.388019 -60.518544) (xy 431.396139 -60.57372) (xy 431.396648 -60.601606)
			(xy 431.396184 -60.627006) (xy 433.02123 -60.627006) (xy 433.025301 -60.571384) (xy 433.037427 -60.516947)
			(xy 433.05735 -60.464856) (xy 433.084646 -60.416221) (xy 433.118732 -60.372078) (xy 433.158881 -60.333369)
			(xy 433.204239 -60.300918) (xy 433.253839 -60.275417) (xy 433.306623 -60.25741) (xy 433.361466 -60.24728)
			(xy 433.4172 -60.245243) (xy 433.472637 -60.251343) (xy 433.526594 -60.265449) (xy 433.577923 -60.287261)
			(xy 433.625529 -60.316315) (xy 433.668397 -60.35199) (xy 433.705614 -60.393527) (xy 433.736387 -60.44004)
			(xy 433.760059 -60.490537) (xy 433.776127 -60.543944) (xy 433.784247 -60.59912) (xy 433.784756 -60.627006)
			(xy 433.78464 -60.633356) (xy 434.09692 -60.633356) (xy 434.100991 -60.577734) (xy 434.113117 -60.523297)
			(xy 434.13304 -60.471206) (xy 434.160336 -60.422571) (xy 434.194422 -60.378428) (xy 434.234571 -60.339719)
			(xy 434.279929 -60.307268) (xy 434.329529 -60.281767) (xy 434.382313 -60.26376) (xy 434.437156 -60.25363)
			(xy 434.49289 -60.251593) (xy 434.548327 -60.257693) (xy 434.602284 -60.271799) (xy 434.653613 -60.293611)
			(xy 434.701219 -60.322665) (xy 434.744087 -60.35834) (xy 434.781304 -60.399877) (xy 434.812077 -60.44639)
			(xy 434.835749 -60.496887) (xy 434.851817 -60.550294) (xy 434.859937 -60.60547) (xy 434.860446 -60.633356)
			(xy 435.11292 -60.633356) (xy 435.116991 -60.577734) (xy 435.129117 -60.523297) (xy 435.14904 -60.471206)
			(xy 435.176336 -60.422571) (xy 435.210422 -60.378428) (xy 435.250571 -60.339719) (xy 435.295929 -60.307268)
			(xy 435.345529 -60.281767) (xy 435.398313 -60.26376) (xy 435.453156 -60.25363) (xy 435.50889 -60.251593)
			(xy 435.564327 -60.257693) (xy 435.618284 -60.271799) (xy 435.669613 -60.293611) (xy 435.717219 -60.322665)
			(xy 435.760087 -60.35834) (xy 435.797304 -60.399877) (xy 435.828077 -60.44639) (xy 435.851749 -60.496887)
			(xy 435.867817 -60.550294) (xy 435.875937 -60.60547) (xy 435.876446 -60.633356) (xy 435.875937 -60.661242)
			(xy 435.867817 -60.716418) (xy 435.851749 -60.769825) (xy 435.828077 -60.820322) (xy 435.797304 -60.866835)
			(xy 435.760087 -60.908372) (xy 435.717219 -60.944047) (xy 435.669613 -60.973101) (xy 435.618284 -60.994913)
			(xy 435.564327 -61.009019) (xy 435.50889 -61.015119) (xy 435.453156 -61.013082) (xy 435.398313 -61.002952)
			(xy 435.345529 -60.984945) (xy 435.295929 -60.959444) (xy 435.250571 -60.926993) (xy 435.210422 -60.888284)
			(xy 435.176336 -60.844141) (xy 435.14904 -60.795506) (xy 435.129117 -60.743415) (xy 435.116991 -60.688978)
			(xy 435.11292 -60.633356) (xy 434.860446 -60.633356) (xy 434.859937 -60.661242) (xy 434.851817 -60.716418)
			(xy 434.835749 -60.769825) (xy 434.812077 -60.820322) (xy 434.781304 -60.866835) (xy 434.744087 -60.908372)
			(xy 434.701219 -60.944047) (xy 434.653613 -60.973101) (xy 434.602284 -60.994913) (xy 434.548327 -61.009019)
			(xy 434.49289 -61.015119) (xy 434.437156 -61.013082) (xy 434.382313 -61.002952) (xy 434.329529 -60.984945)
			(xy 434.279929 -60.959444) (xy 434.234571 -60.926993) (xy 434.194422 -60.888284) (xy 434.160336 -60.844141)
			(xy 434.13304 -60.795506) (xy 434.113117 -60.743415) (xy 434.100991 -60.688978) (xy 434.09692 -60.633356)
			(xy 433.78464 -60.633356) (xy 433.784247 -60.654892) (xy 433.776127 -60.710068) (xy 433.760059 -60.763475)
			(xy 433.736387 -60.813972) (xy 433.705614 -60.860485) (xy 433.668397 -60.902022) (xy 433.625529 -60.937697)
			(xy 433.577923 -60.966751) (xy 433.526594 -60.988563) (xy 433.472637 -61.002669) (xy 433.4172 -61.008769)
			(xy 433.361466 -61.006732) (xy 433.306623 -60.996602) (xy 433.253839 -60.978595) (xy 433.204239 -60.953094)
			(xy 433.158881 -60.920643) (xy 433.118732 -60.881934) (xy 433.084646 -60.837791) (xy 433.05735 -60.789156)
			(xy 433.037427 -60.737065) (xy 433.025301 -60.682628) (xy 433.02123 -60.627006) (xy 431.396184 -60.627006)
			(xy 431.396139 -60.629492) (xy 431.388019 -60.684668) (xy 431.371951 -60.738075) (xy 431.348279 -60.788572)
			(xy 431.317506 -60.835085) (xy 431.280289 -60.876622) (xy 431.237421 -60.912297) (xy 431.189815 -60.941351)
			(xy 431.138486 -60.963163) (xy 431.084529 -60.977269) (xy 431.029092 -60.983369) (xy 430.973358 -60.981332)
			(xy 430.918515 -60.971202) (xy 430.865731 -60.953195) (xy 430.816131 -60.927694) (xy 430.770773 -60.895243)
			(xy 430.730624 -60.856534) (xy 430.696538 -60.812391) (xy 430.669242 -60.763756) (xy 430.649319 -60.711665)
			(xy 430.637193 -60.657228) (xy 430.633122 -60.601606) (xy 409.87542 -60.601606) (xy 409.875989 -60.60547)
			(xy 409.876498 -60.633356) (xy 409.875989 -60.661242) (xy 409.867869 -60.716418) (xy 409.851801 -60.769825)
			(xy 409.828129 -60.820322) (xy 409.797356 -60.866835) (xy 409.760139 -60.908372) (xy 409.717271 -60.944047)
			(xy 409.669665 -60.973101) (xy 409.618336 -60.994913) (xy 409.564379 -61.009019) (xy 409.508942 -61.015119)
			(xy 409.453208 -61.013082) (xy 409.398365 -61.002952) (xy 409.345581 -60.984945) (xy 409.295981 -60.959444)
			(xy 409.250623 -60.926993) (xy 409.210474 -60.888284) (xy 409.176388 -60.844141) (xy 409.149092 -60.795506)
			(xy 409.129169 -60.743415) (xy 409.117043 -60.688978) (xy 409.112972 -60.633356) (xy 408.860498 -60.633356)
			(xy 408.859989 -60.661242) (xy 408.851869 -60.716418) (xy 408.835801 -60.769825) (xy 408.812129 -60.820322)
			(xy 408.781356 -60.866835) (xy 408.744139 -60.908372) (xy 408.701271 -60.944047) (xy 408.653665 -60.973101)
			(xy 408.602336 -60.994913) (xy 408.548379 -61.009019) (xy 408.492942 -61.015119) (xy 408.437208 -61.013082)
			(xy 408.382365 -61.002952) (xy 408.329581 -60.984945) (xy 408.279981 -60.959444) (xy 408.234623 -60.926993)
			(xy 408.194474 -60.888284) (xy 408.160388 -60.844141) (xy 408.133092 -60.795506) (xy 408.113169 -60.743415)
			(xy 408.101043 -60.688978) (xy 408.096972 -60.633356) (xy 407.784692 -60.633356) (xy 407.784299 -60.654892)
			(xy 407.776179 -60.710068) (xy 407.760111 -60.763475) (xy 407.736439 -60.813972) (xy 407.705666 -60.860485)
			(xy 407.668449 -60.902022) (xy 407.625581 -60.937697) (xy 407.577975 -60.966751) (xy 407.526646 -60.988563)
			(xy 407.472689 -61.002669) (xy 407.417252 -61.008769) (xy 407.361518 -61.006732) (xy 407.306675 -60.996602)
			(xy 407.253891 -60.978595) (xy 407.204291 -60.953094) (xy 407.158933 -60.920643) (xy 407.118784 -60.881934)
			(xy 407.084698 -60.837791) (xy 407.057402 -60.789156) (xy 407.037479 -60.737065) (xy 407.025353 -60.682628)
			(xy 407.021282 -60.627006) (xy 405.396236 -60.627006) (xy 405.396191 -60.629492) (xy 405.388071 -60.684668)
			(xy 405.372003 -60.738075) (xy 405.348331 -60.788572) (xy 405.317558 -60.835085) (xy 405.280341 -60.876622)
			(xy 405.237473 -60.912297) (xy 405.189867 -60.941351) (xy 405.138538 -60.963163) (xy 405.084581 -60.977269)
			(xy 405.029144 -60.983369) (xy 404.97341 -60.981332) (xy 404.918567 -60.971202) (xy 404.865783 -60.953195)
			(xy 404.816183 -60.927694) (xy 404.770825 -60.895243) (xy 404.730676 -60.856534) (xy 404.69659 -60.812391)
			(xy 404.669294 -60.763756) (xy 404.649371 -60.711665) (xy 404.637245 -60.657228) (xy 404.633174 -60.601606)
			(xy 383.875472 -60.601606) (xy 383.876041 -60.60547) (xy 383.87655 -60.633356) (xy 383.876041 -60.661242)
			(xy 383.867921 -60.716418) (xy 383.851853 -60.769825) (xy 383.828181 -60.820322) (xy 383.797408 -60.866835)
			(xy 383.760191 -60.908372) (xy 383.717323 -60.944047) (xy 383.669717 -60.973101) (xy 383.618388 -60.994913)
			(xy 383.564431 -61.009019) (xy 383.508994 -61.015119) (xy 383.45326 -61.013082) (xy 383.398417 -61.002952)
			(xy 383.345633 -60.984945) (xy 383.296033 -60.959444) (xy 383.250675 -60.926993) (xy 383.210526 -60.888284)
			(xy 383.17644 -60.844141) (xy 383.149144 -60.795506) (xy 383.129221 -60.743415) (xy 383.117095 -60.688978)
			(xy 383.113024 -60.633356) (xy 382.86055 -60.633356) (xy 382.860041 -60.661242) (xy 382.851921 -60.716418)
			(xy 382.835853 -60.769825) (xy 382.812181 -60.820322) (xy 382.781408 -60.866835) (xy 382.744191 -60.908372)
			(xy 382.701323 -60.944047) (xy 382.653717 -60.973101) (xy 382.602388 -60.994913) (xy 382.548431 -61.009019)
			(xy 382.492994 -61.015119) (xy 382.43726 -61.013082) (xy 382.382417 -61.002952) (xy 382.329633 -60.984945)
			(xy 382.280033 -60.959444) (xy 382.234675 -60.926993) (xy 382.194526 -60.888284) (xy 382.16044 -60.844141)
			(xy 382.133144 -60.795506) (xy 382.113221 -60.743415) (xy 382.101095 -60.688978) (xy 382.097024 -60.633356)
			(xy 381.784744 -60.633356) (xy 381.784351 -60.654892) (xy 381.776231 -60.710068) (xy 381.760163 -60.763475)
			(xy 381.736491 -60.813972) (xy 381.705718 -60.860485) (xy 381.668501 -60.902022) (xy 381.625633 -60.937697)
			(xy 381.578027 -60.966751) (xy 381.526698 -60.988563) (xy 381.472741 -61.002669) (xy 381.417304 -61.008769)
			(xy 381.36157 -61.006732) (xy 381.306727 -60.996602) (xy 381.253943 -60.978595) (xy 381.204343 -60.953094)
			(xy 381.158985 -60.920643) (xy 381.118836 -60.881934) (xy 381.08475 -60.837791) (xy 381.057454 -60.789156)
			(xy 381.037531 -60.737065) (xy 381.025405 -60.682628) (xy 381.021334 -60.627006) (xy 379.396288 -60.627006)
			(xy 379.396243 -60.629492) (xy 379.388123 -60.684668) (xy 379.372055 -60.738075) (xy 379.348383 -60.788572)
			(xy 379.31761 -60.835085) (xy 379.280393 -60.876622) (xy 379.237525 -60.912297) (xy 379.189919 -60.941351)
			(xy 379.13859 -60.963163) (xy 379.084633 -60.977269) (xy 379.029196 -60.983369) (xy 378.973462 -60.981332)
			(xy 378.918619 -60.971202) (xy 378.865835 -60.953195) (xy 378.816235 -60.927694) (xy 378.770877 -60.895243)
			(xy 378.730728 -60.856534) (xy 378.696642 -60.812391) (xy 378.669346 -60.763756) (xy 378.649423 -60.711665)
			(xy 378.637297 -60.657228) (xy 378.633226 -60.601606) (xy 357.875524 -60.601606) (xy 357.876093 -60.60547)
			(xy 357.876602 -60.633356) (xy 357.876093 -60.661242) (xy 357.867973 -60.716418) (xy 357.851905 -60.769825)
			(xy 357.828233 -60.820322) (xy 357.79746 -60.866835) (xy 357.760243 -60.908372) (xy 357.717375 -60.944047)
			(xy 357.669769 -60.973101) (xy 357.61844 -60.994913) (xy 357.564483 -61.009019) (xy 357.509046 -61.015119)
			(xy 357.453312 -61.013082) (xy 357.398469 -61.002952) (xy 357.345685 -60.984945) (xy 357.296085 -60.959444)
			(xy 357.250727 -60.926993) (xy 357.210578 -60.888284) (xy 357.176492 -60.844141) (xy 357.149196 -60.795506)
			(xy 357.129273 -60.743415) (xy 357.117147 -60.688978) (xy 357.113076 -60.633356) (xy 356.860602 -60.633356)
			(xy 356.860093 -60.661242) (xy 356.851973 -60.716418) (xy 356.835905 -60.769825) (xy 356.812233 -60.820322)
			(xy 356.78146 -60.866835) (xy 356.744243 -60.908372) (xy 356.701375 -60.944047) (xy 356.653769 -60.973101)
			(xy 356.60244 -60.994913) (xy 356.548483 -61.009019) (xy 356.493046 -61.015119) (xy 356.437312 -61.013082)
			(xy 356.382469 -61.002952) (xy 356.329685 -60.984945) (xy 356.280085 -60.959444) (xy 356.234727 -60.926993)
			(xy 356.194578 -60.888284) (xy 356.160492 -60.844141) (xy 356.133196 -60.795506) (xy 356.113273 -60.743415)
			(xy 356.101147 -60.688978) (xy 356.097076 -60.633356) (xy 355.784796 -60.633356) (xy 355.784403 -60.654892)
			(xy 355.776283 -60.710068) (xy 355.760215 -60.763475) (xy 355.736543 -60.813972) (xy 355.70577 -60.860485)
			(xy 355.668553 -60.902022) (xy 355.625685 -60.937697) (xy 355.578079 -60.966751) (xy 355.52675 -60.988563)
			(xy 355.472793 -61.002669) (xy 355.417356 -61.008769) (xy 355.361622 -61.006732) (xy 355.306779 -60.996602)
			(xy 355.253995 -60.978595) (xy 355.204395 -60.953094) (xy 355.159037 -60.920643) (xy 355.118888 -60.881934)
			(xy 355.084802 -60.837791) (xy 355.057506 -60.789156) (xy 355.037583 -60.737065) (xy 355.025457 -60.682628)
			(xy 355.021386 -60.627006) (xy 353.39634 -60.627006) (xy 353.396295 -60.629492) (xy 353.388175 -60.684668)
			(xy 353.372107 -60.738075) (xy 353.348435 -60.788572) (xy 353.317662 -60.835085) (xy 353.280445 -60.876622)
			(xy 353.237577 -60.912297) (xy 353.189971 -60.941351) (xy 353.138642 -60.963163) (xy 353.084685 -60.977269)
			(xy 353.029248 -60.983369) (xy 352.973514 -60.981332) (xy 352.918671 -60.971202) (xy 352.865887 -60.953195)
			(xy 352.816287 -60.927694) (xy 352.770929 -60.895243) (xy 352.73078 -60.856534) (xy 352.696694 -60.812391)
			(xy 352.669398 -60.763756) (xy 352.649475 -60.711665) (xy 352.637349 -60.657228) (xy 352.633278 -60.601606)
			(xy 319.77527 -60.601606) (xy 319.775839 -60.60547) (xy 319.776348 -60.633356) (xy 319.775839 -60.661242)
			(xy 319.767719 -60.716418) (xy 319.751651 -60.769825) (xy 319.727979 -60.820322) (xy 319.697206 -60.866835)
			(xy 319.659989 -60.908372) (xy 319.617121 -60.944047) (xy 319.569515 -60.973101) (xy 319.518186 -60.994913)
			(xy 319.464229 -61.009019) (xy 319.408792 -61.015119) (xy 319.353058 -61.013082) (xy 319.298215 -61.002952)
			(xy 319.245431 -60.984945) (xy 319.195831 -60.959444) (xy 319.150473 -60.926993) (xy 319.110324 -60.888284)
			(xy 319.076238 -60.844141) (xy 319.048942 -60.795506) (xy 319.029019 -60.743415) (xy 319.016893 -60.688978)
			(xy 319.012822 -60.633356) (xy 318.760348 -60.633356) (xy 318.759839 -60.661242) (xy 318.751719 -60.716418)
			(xy 318.735651 -60.769825) (xy 318.711979 -60.820322) (xy 318.681206 -60.866835) (xy 318.643989 -60.908372)
			(xy 318.601121 -60.944047) (xy 318.553515 -60.973101) (xy 318.502186 -60.994913) (xy 318.448229 -61.009019)
			(xy 318.392792 -61.015119) (xy 318.337058 -61.013082) (xy 318.282215 -61.002952) (xy 318.229431 -60.984945)
			(xy 318.179831 -60.959444) (xy 318.134473 -60.926993) (xy 318.094324 -60.888284) (xy 318.060238 -60.844141)
			(xy 318.032942 -60.795506) (xy 318.013019 -60.743415) (xy 318.000893 -60.688978) (xy 317.996822 -60.633356)
			(xy 315.295472 -60.633356) (xy 315.287921 -60.684668) (xy 315.271853 -60.738075) (xy 315.248181 -60.788572)
			(xy 315.217408 -60.835085) (xy 315.180191 -60.876622) (xy 315.137323 -60.912297) (xy 315.089717 -60.941351)
			(xy 315.038388 -60.963163) (xy 314.984431 -60.977269) (xy 314.928994 -60.983369) (xy 314.87326 -60.981332)
			(xy 314.818417 -60.971202) (xy 314.765633 -60.953195) (xy 314.716033 -60.927694) (xy 314.670675 -60.895243)
			(xy 314.630526 -60.856534) (xy 314.59644 -60.812391) (xy 314.569144 -60.763756) (xy 314.549221 -60.711665)
			(xy 314.537095 -60.657228) (xy 314.533024 -60.601606) (xy 293.775322 -60.601606) (xy 293.775891 -60.60547)
			(xy 293.7764 -60.633356) (xy 293.775891 -60.661242) (xy 293.767771 -60.716418) (xy 293.751703 -60.769825)
			(xy 293.728031 -60.820322) (xy 293.697258 -60.866835) (xy 293.660041 -60.908372) (xy 293.617173 -60.944047)
			(xy 293.569567 -60.973101) (xy 293.518238 -60.994913) (xy 293.464281 -61.009019) (xy 293.408844 -61.015119)
			(xy 293.35311 -61.013082) (xy 293.298267 -61.002952) (xy 293.245483 -60.984945) (xy 293.195883 -60.959444)
			(xy 293.150525 -60.926993) (xy 293.110376 -60.888284) (xy 293.07629 -60.844141) (xy 293.048994 -60.795506)
			(xy 293.029071 -60.743415) (xy 293.016945 -60.688978) (xy 293.012874 -60.633356) (xy 292.7604 -60.633356)
			(xy 292.759891 -60.661242) (xy 292.751771 -60.716418) (xy 292.735703 -60.769825) (xy 292.712031 -60.820322)
			(xy 292.681258 -60.866835) (xy 292.644041 -60.908372) (xy 292.601173 -60.944047) (xy 292.553567 -60.973101)
			(xy 292.502238 -60.994913) (xy 292.448281 -61.009019) (xy 292.392844 -61.015119) (xy 292.33711 -61.013082)
			(xy 292.282267 -61.002952) (xy 292.229483 -60.984945) (xy 292.179883 -60.959444) (xy 292.134525 -60.926993)
			(xy 292.094376 -60.888284) (xy 292.06029 -60.844141) (xy 292.032994 -60.795506) (xy 292.013071 -60.743415)
			(xy 292.000945 -60.688978) (xy 291.996874 -60.633356) (xy 291.684594 -60.633356) (xy 291.684201 -60.654892)
			(xy 291.676081 -60.710068) (xy 291.660013 -60.763475) (xy 291.636341 -60.813972) (xy 291.605568 -60.860485)
			(xy 291.568351 -60.902022) (xy 291.525483 -60.937697) (xy 291.477877 -60.966751) (xy 291.426548 -60.988563)
			(xy 291.372591 -61.002669) (xy 291.317154 -61.008769) (xy 291.26142 -61.006732) (xy 291.206577 -60.996602)
			(xy 291.153793 -60.978595) (xy 291.104193 -60.953094) (xy 291.058835 -60.920643) (xy 291.018686 -60.881934)
			(xy 290.9846 -60.837791) (xy 290.957304 -60.789156) (xy 290.937381 -60.737065) (xy 290.925255 -60.682628)
			(xy 290.921184 -60.627006) (xy 289.296138 -60.627006) (xy 289.296093 -60.629492) (xy 289.287973 -60.684668)
			(xy 289.271905 -60.738075) (xy 289.248233 -60.788572) (xy 289.21746 -60.835085) (xy 289.180243 -60.876622)
			(xy 289.137375 -60.912297) (xy 289.089769 -60.941351) (xy 289.03844 -60.963163) (xy 288.984483 -60.977269)
			(xy 288.929046 -60.983369) (xy 288.873312 -60.981332) (xy 288.818469 -60.971202) (xy 288.765685 -60.953195)
			(xy 288.716085 -60.927694) (xy 288.670727 -60.895243) (xy 288.630578 -60.856534) (xy 288.596492 -60.812391)
			(xy 288.569196 -60.763756) (xy 288.549273 -60.711665) (xy 288.537147 -60.657228) (xy 288.533076 -60.601606)
			(xy 267.775374 -60.601606) (xy 267.775943 -60.60547) (xy 267.776452 -60.633356) (xy 267.775943 -60.661242)
			(xy 267.767823 -60.716418) (xy 267.751755 -60.769825) (xy 267.728083 -60.820322) (xy 267.69731 -60.866835)
			(xy 267.660093 -60.908372) (xy 267.617225 -60.944047) (xy 267.569619 -60.973101) (xy 267.51829 -60.994913)
			(xy 267.464333 -61.009019) (xy 267.408896 -61.015119) (xy 267.353162 -61.013082) (xy 267.298319 -61.002952)
			(xy 267.245535 -60.984945) (xy 267.195935 -60.959444) (xy 267.150577 -60.926993) (xy 267.110428 -60.888284)
			(xy 267.076342 -60.844141) (xy 267.049046 -60.795506) (xy 267.029123 -60.743415) (xy 267.016997 -60.688978)
			(xy 267.012926 -60.633356) (xy 266.760452 -60.633356) (xy 266.759943 -60.661242) (xy 266.751823 -60.716418)
			(xy 266.735755 -60.769825) (xy 266.712083 -60.820322) (xy 266.68131 -60.866835) (xy 266.644093 -60.908372)
			(xy 266.601225 -60.944047) (xy 266.553619 -60.973101) (xy 266.50229 -60.994913) (xy 266.448333 -61.009019)
			(xy 266.392896 -61.015119) (xy 266.337162 -61.013082) (xy 266.282319 -61.002952) (xy 266.229535 -60.984945)
			(xy 266.179935 -60.959444) (xy 266.134577 -60.926993) (xy 266.094428 -60.888284) (xy 266.060342 -60.844141)
			(xy 266.033046 -60.795506) (xy 266.013123 -60.743415) (xy 266.000997 -60.688978) (xy 265.996926 -60.633356)
			(xy 265.684646 -60.633356) (xy 265.684253 -60.654892) (xy 265.676133 -60.710068) (xy 265.660065 -60.763475)
			(xy 265.636393 -60.813972) (xy 265.60562 -60.860485) (xy 265.568403 -60.902022) (xy 265.525535 -60.937697)
			(xy 265.477929 -60.966751) (xy 265.4266 -60.988563) (xy 265.372643 -61.002669) (xy 265.317206 -61.008769)
			(xy 265.261472 -61.006732) (xy 265.206629 -60.996602) (xy 265.153845 -60.978595) (xy 265.104245 -60.953094)
			(xy 265.058887 -60.920643) (xy 265.018738 -60.881934) (xy 264.984652 -60.837791) (xy 264.957356 -60.789156)
			(xy 264.937433 -60.737065) (xy 264.925307 -60.682628) (xy 264.921236 -60.627006) (xy 263.29619 -60.627006)
			(xy 263.296145 -60.629492) (xy 263.288025 -60.684668) (xy 263.271957 -60.738075) (xy 263.248285 -60.788572)
			(xy 263.217512 -60.835085) (xy 263.180295 -60.876622) (xy 263.137427 -60.912297) (xy 263.089821 -60.941351)
			(xy 263.038492 -60.963163) (xy 262.984535 -60.977269) (xy 262.929098 -60.983369) (xy 262.873364 -60.981332)
			(xy 262.818521 -60.971202) (xy 262.765737 -60.953195) (xy 262.716137 -60.927694) (xy 262.670779 -60.895243)
			(xy 262.63063 -60.856534) (xy 262.596544 -60.812391) (xy 262.569248 -60.763756) (xy 262.549325 -60.711665)
			(xy 262.537199 -60.657228) (xy 262.533128 -60.601606) (xy 240.048035 -60.601606) (xy 240.061273 -60.609685)
			(xy 240.104141 -60.64536) (xy 240.141358 -60.686897) (xy 240.172131 -60.73341) (xy 240.195803 -60.783907)
			(xy 240.211871 -60.837314) (xy 240.219991 -60.89249) (xy 240.2205 -60.920376) (xy 240.219991 -60.948262)
			(xy 240.211871 -61.003438) (xy 240.195803 -61.056845) (xy 240.172131 -61.107342) (xy 240.141358 -61.153855)
			(xy 240.104141 -61.195392) (xy 240.061273 -61.231067) (xy 240.013667 -61.260121) (xy 239.962338 -61.281933)
			(xy 239.908381 -61.296039) (xy 239.852944 -61.302139) (xy 239.79721 -61.300102) (xy 239.742367 -61.289972)
			(xy 239.689583 -61.271965) (xy 239.639983 -61.246464) (xy 239.594625 -61.214013) (xy 239.554476 -61.175304)
			(xy 239.52039 -61.131161) (xy 239.493094 -61.082526) (xy 239.473171 -61.030435) (xy 239.461045 -60.975998)
			(xy 239.456974 -60.920376) (xy 233.832134 -60.920376) (xy 233.837707 -60.925014) (xy 233.874924 -60.966551)
			(xy 233.905697 -61.013064) (xy 233.929369 -61.063561) (xy 233.945437 -61.116968) (xy 233.953557 -61.172144)
			(xy 233.954066 -61.20003) (xy 233.953557 -61.227916) (xy 233.945437 -61.283092) (xy 233.929369 -61.336499)
			(xy 233.905697 -61.386996) (xy 233.874924 -61.433509) (xy 233.837707 -61.475046) (xy 233.794839 -61.510721)
			(xy 233.747233 -61.539775) (xy 233.695904 -61.561587) (xy 233.641947 -61.575693) (xy 233.58651 -61.581793)
			(xy 233.530776 -61.579756) (xy 233.475933 -61.569626) (xy 233.423149 -61.551619) (xy 233.373549 -61.526118)
			(xy 233.328191 -61.493667) (xy 233.288042 -61.454958) (xy 233.253956 -61.410815) (xy 233.22666 -61.36218)
			(xy 233.206737 -61.310089) (xy 233.194611 -61.255652) (xy 233.19054 -61.20003) (xy 201.036301 -61.20003)
			(xy 201.051641 -61.212796) (xy 201.088858 -61.254333) (xy 201.119631 -61.300846) (xy 201.143303 -61.351343)
			(xy 201.159371 -61.40475) (xy 201.167491 -61.459926) (xy 201.168 -61.487812) (xy 201.167491 -61.515698)
			(xy 201.159371 -61.570874) (xy 201.143303 -61.624281) (xy 201.119631 -61.674778) (xy 201.088858 -61.721291)
			(xy 201.051641 -61.762828) (xy 201.008773 -61.798503) (xy 200.961167 -61.827557) (xy 200.909838 -61.849369)
			(xy 200.855881 -61.863475) (xy 200.800444 -61.869575) (xy 200.74471 -61.867538) (xy 200.689867 -61.857408)
			(xy 200.637083 -61.839401) (xy 200.587483 -61.8139) (xy 200.542125 -61.781449) (xy 200.501976 -61.74274)
			(xy 200.46789 -61.698597) (xy 200.440594 -61.649962) (xy 200.420671 -61.597871) (xy 200.408545 -61.543434)
			(xy 200.404474 -61.487812) (xy 175.168052 -61.487812) (xy 175.167543 -61.515698) (xy 175.159423 -61.570874)
			(xy 175.143355 -61.624281) (xy 175.119683 -61.674778) (xy 175.08891 -61.721291) (xy 175.051693 -61.762828)
			(xy 175.008825 -61.798503) (xy 174.961219 -61.827557) (xy 174.90989 -61.849369) (xy 174.855933 -61.863475)
			(xy 174.800496 -61.869575) (xy 174.744762 -61.867538) (xy 174.689919 -61.857408) (xy 174.637135 -61.839401)
			(xy 174.587535 -61.8139) (xy 174.542177 -61.781449) (xy 174.502028 -61.74274) (xy 174.467942 -61.698597)
			(xy 174.440646 -61.649962) (xy 174.420723 -61.597871) (xy 174.408597 -61.543434) (xy 174.404526 -61.487812)
			(xy 149.168104 -61.487812) (xy 149.167595 -61.515698) (xy 149.159475 -61.570874) (xy 149.143407 -61.624281)
			(xy 149.119735 -61.674778) (xy 149.088962 -61.721291) (xy 149.051745 -61.762828) (xy 149.008877 -61.798503)
			(xy 148.961271 -61.827557) (xy 148.909942 -61.849369) (xy 148.855985 -61.863475) (xy 148.800548 -61.869575)
			(xy 148.744814 -61.867538) (xy 148.689971 -61.857408) (xy 148.637187 -61.839401) (xy 148.587587 -61.8139)
			(xy 148.542229 -61.781449) (xy 148.50208 -61.74274) (xy 148.467994 -61.698597) (xy 148.440698 -61.649962)
			(xy 148.420775 -61.597871) (xy 148.408649 -61.543434) (xy 148.404578 -61.487812) (xy 123.168156 -61.487812)
			(xy 123.167647 -61.515698) (xy 123.159527 -61.570874) (xy 123.143459 -61.624281) (xy 123.119787 -61.674778)
			(xy 123.089014 -61.721291) (xy 123.051797 -61.762828) (xy 123.008929 -61.798503) (xy 122.961323 -61.827557)
			(xy 122.909994 -61.849369) (xy 122.856037 -61.863475) (xy 122.8006 -61.869575) (xy 122.744866 -61.867538)
			(xy 122.690023 -61.857408) (xy 122.637239 -61.839401) (xy 122.587639 -61.8139) (xy 122.542281 -61.781449)
			(xy 122.502132 -61.74274) (xy 122.468046 -61.698597) (xy 122.44075 -61.649962) (xy 122.420827 -61.597871)
			(xy 122.408701 -61.543434) (xy 122.40463 -61.487812) (xy 85.067902 -61.487812) (xy 85.067393 -61.515698)
			(xy 85.059273 -61.570874) (xy 85.043205 -61.624281) (xy 85.019533 -61.674778) (xy 84.98876 -61.721291)
			(xy 84.951543 -61.762828) (xy 84.908675 -61.798503) (xy 84.861069 -61.827557) (xy 84.80974 -61.849369)
			(xy 84.755783 -61.863475) (xy 84.700346 -61.869575) (xy 84.644612 -61.867538) (xy 84.589769 -61.857408)
			(xy 84.536985 -61.839401) (xy 84.487385 -61.8139) (xy 84.442027 -61.781449) (xy 84.401878 -61.74274)
			(xy 84.367792 -61.698597) (xy 84.340496 -61.649962) (xy 84.320573 -61.597871) (xy 84.308447 -61.543434)
			(xy 84.304376 -61.487812) (xy 59.067954 -61.487812) (xy 59.067445 -61.515698) (xy 59.059325 -61.570874)
			(xy 59.043257 -61.624281) (xy 59.019585 -61.674778) (xy 58.988812 -61.721291) (xy 58.951595 -61.762828)
			(xy 58.908727 -61.798503) (xy 58.861121 -61.827557) (xy 58.809792 -61.849369) (xy 58.755835 -61.863475)
			(xy 58.700398 -61.869575) (xy 58.644664 -61.867538) (xy 58.589821 -61.857408) (xy 58.537037 -61.839401)
			(xy 58.487437 -61.8139) (xy 58.442079 -61.781449) (xy 58.40193 -61.74274) (xy 58.367844 -61.698597)
			(xy 58.340548 -61.649962) (xy 58.320625 -61.597871) (xy 58.308499 -61.543434) (xy 58.304428 -61.487812)
			(xy 35.589498 -61.487812) (xy 35.578567 -61.52504) (xy 35.555925 -61.574617) (xy 35.526459 -61.620467)
			(xy 35.490768 -61.661658) (xy 35.449577 -61.697349) (xy 35.403727 -61.726815) (xy 35.35415 -61.749457)
			(xy 35.301855 -61.764812) (xy 35.247907 -61.772568) (xy 35.193405 -61.772568) (xy 35.139457 -61.764812)
			(xy 35.087162 -61.749457) (xy 35.037585 -61.726815) (xy 34.991735 -61.697349) (xy 34.950544 -61.661658)
			(xy 34.914853 -61.620467) (xy 34.885387 -61.574617) (xy 34.862745 -61.52504) (xy 34.84739 -61.472745)
			(xy 34.839634 -61.418797) (xy 34.839148 -61.391546) (xy 34.839642 -61.363909) (xy 34.847601 -61.309213)
			(xy 34.863373 -61.256238) (xy 34.886628 -61.206096) (xy 34.916878 -61.159836) (xy 34.95349 -61.118428)
			(xy 34.974276 -61.100208) (xy 34.98342 -61.092588) (xy 34.992818 -61.071506) (xy 34.98977 -60.980066)
			(xy 34.989391 -60.974371) (xy 34.986439 -60.963348) (xy 34.983928 -60.958222) (xy 34.981134 -60.952888)
			(xy 34.973768 -60.944252) (xy 34.968942 -60.940696) (xy 34.945297 -60.922562) (xy 34.903374 -60.880221)
			(xy 34.868542 -60.831879) (xy 34.841646 -60.77871) (xy 34.823341 -60.722007) (xy 34.814071 -60.663148)
			(xy 34.813494 -60.633356) (xy 34.56051 -60.633356) (xy 34.560001 -60.661242) (xy 34.551881 -60.716418)
			(xy 34.535813 -60.769825) (xy 34.512141 -60.820322) (xy 34.481368 -60.866835) (xy 34.444151 -60.908372)
			(xy 34.401283 -60.944047) (xy 34.353677 -60.973101) (xy 34.302348 -60.994913) (xy 34.248391 -61.009019)
			(xy 34.192954 -61.015119) (xy 34.13722 -61.013082) (xy 34.082377 -61.002952) (xy 34.029593 -60.984945)
			(xy 33.979993 -60.959444) (xy 33.934635 -60.926993) (xy 33.894486 -60.888284) (xy 33.8604 -60.844141)
			(xy 33.833104 -60.795506) (xy 33.813181 -60.743415) (xy 33.801055 -60.688978) (xy 33.796984 -60.633356)
			(xy 33.484704 -60.633356) (xy 33.484311 -60.654892) (xy 33.476191 -60.710068) (xy 33.460123 -60.763475)
			(xy 33.436451 -60.813972) (xy 33.405678 -60.860485) (xy 33.368461 -60.902022) (xy 33.325593 -60.937697)
			(xy 33.277987 -60.966751) (xy 33.226658 -60.988563) (xy 33.172701 -61.002669) (xy 33.117264 -61.008769)
			(xy 33.06153 -61.006732) (xy 33.006687 -60.996602) (xy 32.953903 -60.978595) (xy 32.904303 -60.953094)
			(xy 32.858945 -60.920643) (xy 32.818796 -60.881934) (xy 32.78471 -60.837791) (xy 32.757414 -60.789156)
			(xy 32.737491 -60.737065) (xy 32.725365 -60.682628) (xy 32.721294 -60.627006) (xy 31.096248 -60.627006)
			(xy 31.096203 -60.629492) (xy 31.088083 -60.684668) (xy 31.072015 -60.738075) (xy 31.048343 -60.788572)
			(xy 31.01757 -60.835085) (xy 30.980353 -60.876622) (xy 30.937485 -60.912297) (xy 30.889879 -60.941351)
			(xy 30.83855 -60.963163) (xy 30.784593 -60.977269) (xy 30.729156 -60.983369) (xy 30.673422 -60.981332)
			(xy 30.618579 -60.971202) (xy 30.565795 -60.953195) (xy 30.516195 -60.927694) (xy 30.470837 -60.895243)
			(xy 30.430688 -60.856534) (xy 30.396602 -60.812391) (xy 30.369306 -60.763756) (xy 30.349383 -60.711665)
			(xy 30.337257 -60.657228) (xy 30.333186 -60.601606) (xy 20.380452 -60.601606) (xy 20.380452 -61.487812)
			(xy 32.30448 -61.487812) (xy 32.308551 -61.43219) (xy 32.320677 -61.377753) (xy 32.3406 -61.325662)
			(xy 32.367896 -61.277027) (xy 32.401982 -61.232884) (xy 32.442131 -61.194175) (xy 32.487489 -61.161724)
			(xy 32.537089 -61.136223) (xy 32.589873 -61.118216) (xy 32.644716 -61.108086) (xy 32.70045 -61.106049)
			(xy 32.755887 -61.112149) (xy 32.809844 -61.126255) (xy 32.861173 -61.148067) (xy 32.908779 -61.177121)
			(xy 32.951647 -61.212796) (xy 32.988864 -61.254333) (xy 33.019637 -61.300846) (xy 33.043309 -61.351343)
			(xy 33.059377 -61.40475) (xy 33.067497 -61.459926) (xy 33.068006 -61.487812) (xy 33.067497 -61.515698)
			(xy 33.059377 -61.570874) (xy 33.043309 -61.624281) (xy 33.019637 -61.674778) (xy 32.988864 -61.721291)
			(xy 32.951647 -61.762828) (xy 32.908779 -61.798503) (xy 32.861173 -61.827557) (xy 32.809844 -61.849369)
			(xy 32.755887 -61.863475) (xy 32.70045 -61.869575) (xy 32.644716 -61.867538) (xy 32.589873 -61.857408)
			(xy 32.537089 -61.839401) (xy 32.487489 -61.8139) (xy 32.442131 -61.781449) (xy 32.401982 -61.74274)
			(xy 32.367896 -61.698597) (xy 32.3406 -61.649962) (xy 32.320677 -61.597871) (xy 32.308551 -61.543434)
			(xy 32.30448 -61.487812) (xy 20.380452 -61.487812) (xy 20.380452 -62.121034) (xy 30.242254 -62.121034)
			(xy 30.246325 -62.065412) (xy 30.258451 -62.010975) (xy 30.278374 -61.958884) (xy 30.30567 -61.910249)
			(xy 30.339756 -61.866106) (xy 30.379905 -61.827397) (xy 30.425263 -61.794946) (xy 30.474863 -61.769445)
			(xy 30.527647 -61.751438) (xy 30.58249 -61.741308) (xy 30.638224 -61.739271) (xy 30.693661 -61.745371)
			(xy 30.747618 -61.759477) (xy 30.798947 -61.781289) (xy 30.846553 -61.810343) (xy 30.889421 -61.846018)
			(xy 30.926638 -61.887555) (xy 30.957411 -61.934068) (xy 30.981083 -61.984565) (xy 30.997151 -62.037972)
			(xy 31.005271 -62.093148) (xy 31.00578 -62.121034) (xy 56.242202 -62.121034) (xy 56.246273 -62.065412)
			(xy 56.258399 -62.010975) (xy 56.278322 -61.958884) (xy 56.305618 -61.910249) (xy 56.339704 -61.866106)
			(xy 56.379853 -61.827397) (xy 56.425211 -61.794946) (xy 56.474811 -61.769445) (xy 56.527595 -61.751438)
			(xy 56.582438 -61.741308) (xy 56.638172 -61.739271) (xy 56.693609 -61.745371) (xy 56.747566 -61.759477)
			(xy 56.798895 -61.781289) (xy 56.846501 -61.810343) (xy 56.889369 -61.846018) (xy 56.926586 -61.887555)
			(xy 56.957359 -61.934068) (xy 56.981031 -61.984565) (xy 56.997099 -62.037972) (xy 57.005219 -62.093148)
			(xy 57.005728 -62.121034) (xy 57.005219 -62.14892) (xy 56.997099 -62.204096) (xy 56.981031 -62.257503)
			(xy 56.957359 -62.308) (xy 56.926586 -62.354513) (xy 56.889369 -62.39605) (xy 56.846501 -62.431725)
			(xy 56.798895 -62.460779) (xy 56.747566 -62.482591) (xy 56.693609 -62.496697) (xy 56.638172 -62.502797)
			(xy 56.582438 -62.50076) (xy 56.527595 -62.49063) (xy 56.474811 -62.472623) (xy 56.425211 -62.447122)
			(xy 56.379853 -62.414671) (xy 56.339704 -62.375962) (xy 56.305618 -62.331819) (xy 56.278322 -62.283184)
			(xy 56.258399 -62.231093) (xy 56.246273 -62.176656) (xy 56.242202 -62.121034) (xy 31.00578 -62.121034)
			(xy 31.005271 -62.14892) (xy 30.997151 -62.204096) (xy 30.981083 -62.257503) (xy 30.957411 -62.308)
			(xy 30.926638 -62.354513) (xy 30.889421 -62.39605) (xy 30.846553 -62.431725) (xy 30.798947 -62.460779)
			(xy 30.747618 -62.482591) (xy 30.693661 -62.496697) (xy 30.638224 -62.502797) (xy 30.58249 -62.50076)
			(xy 30.527647 -62.49063) (xy 30.474863 -62.472623) (xy 30.425263 -62.447122) (xy 30.379905 -62.414671)
			(xy 30.339756 -62.375962) (xy 30.30567 -62.331819) (xy 30.278374 -62.283184) (xy 30.258451 -62.231093)
			(xy 30.246325 -62.176656) (xy 30.242254 -62.121034) (xy 20.380452 -62.121034) (xy 20.380452 -63.086234)
			(xy 27.387548 -63.086234) (xy 27.391619 -63.030612) (xy 27.403745 -62.976175) (xy 27.423668 -62.924084)
			(xy 27.450964 -62.875449) (xy 27.48505 -62.831306) (xy 27.525199 -62.792597) (xy 27.570557 -62.760146)
			(xy 27.620157 -62.734645) (xy 27.672941 -62.716638) (xy 27.727784 -62.706508) (xy 27.783518 -62.704471)
			(xy 27.838955 -62.710571) (xy 27.892912 -62.724677) (xy 27.944241 -62.746489) (xy 27.991847 -62.775543)
			(xy 28.034715 -62.811218) (xy 28.060016 -62.839456) (xy 32.918823 -62.839456) (xy 32.918823 -62.784944)
			(xy 32.926581 -62.730988) (xy 32.941939 -62.678685) (xy 32.964584 -62.6291) (xy 32.994055 -62.583243)
			(xy 33.029752 -62.542047) (xy 33.070949 -62.50635) (xy 33.116807 -62.47688) (xy 33.166393 -62.454236)
			(xy 33.218696 -62.438879) (xy 33.272652 -62.431122) (xy 33.299908 -62.43066) (xy 33.328718 -62.431183)
			(xy 33.38568 -62.439861) (xy 33.44069 -62.457003) (xy 33.492499 -62.482219) (xy 33.539928 -62.514937)
			(xy 33.561274 -62.534292) (xy 33.56991 -62.54242) (xy 33.591754 -62.549278) (xy 33.68167 -62.536832)
			(xy 33.693035 -62.534738) (xy 33.712219 -62.521895) (xy 33.7185 -62.512194) (xy 33.733304 -62.488067)
			(xy 33.768959 -62.444104) (xy 33.810715 -62.405887) (xy 33.857657 -62.374257) (xy 33.908756 -62.349905)
			(xy 33.96289 -62.333367) (xy 34.018874 -62.325004) (xy 34.047176 -62.324488) (xy 34.07443 -62.324958)
			(xy 34.128383 -62.332712) (xy 34.180683 -62.348066) (xy 34.230265 -62.370706) (xy 34.276121 -62.400174)
			(xy 34.317316 -62.435867) (xy 34.353012 -62.47706) (xy 34.382482 -62.522913) (xy 34.405126 -62.572495)
			(xy 34.420483 -62.624794) (xy 34.428241 -62.678746) (xy 34.428241 -62.733254) (xy 34.420483 -62.787206)
			(xy 34.405126 -62.839505) (xy 34.382482 -62.889087) (xy 34.353012 -62.93494) (xy 34.317316 -62.976133)
			(xy 34.276121 -63.011826) (xy 34.230265 -63.041294) (xy 34.180683 -63.063934) (xy 34.128383 -63.079288)
			(xy 34.07443 -63.087042) (xy 34.047176 -63.087504) (xy 34.018367 -63.086973) (xy 33.961406 -63.078295)
			(xy 33.906396 -63.061154) (xy 33.854588 -63.035939) (xy 33.807157 -63.003225) (xy 33.78581 -62.983872)
			(xy 33.777174 -62.975744) (xy 33.75533 -62.968886) (xy 33.665414 -62.981332) (xy 33.654051 -62.983433)
			(xy 33.634868 -62.996272) (xy 33.628584 -63.00597) (xy 33.613778 -63.030096) (xy 33.578125 -63.074061)
			(xy 33.53637 -63.112279) (xy 33.489428 -63.14391) (xy 33.438329 -63.168262) (xy 33.384194 -63.1848)
			(xy 33.32821 -63.193161) (xy 33.299908 -63.193676) (xy 33.272652 -63.193278) (xy 33.218696 -63.185521)
			(xy 33.166393 -63.170164) (xy 33.116807 -63.14752) (xy 33.070949 -63.11805) (xy 33.029752 -63.082353)
			(xy 32.994055 -63.041157) (xy 32.964584 -62.9953) (xy 32.941939 -62.945715) (xy 32.926581 -62.893412)
			(xy 32.918823 -62.839456) (xy 28.060016 -62.839456) (xy 28.071932 -62.852755) (xy 28.102705 -62.899268)
			(xy 28.126377 -62.949765) (xy 28.142445 -63.003172) (xy 28.150565 -63.058348) (xy 28.151074 -63.086234)
			(xy 28.150565 -63.11412) (xy 28.142445 -63.169296) (xy 28.126377 -63.222703) (xy 28.102705 -63.2732)
			(xy 28.102552 -63.273432) (xy 29.576774 -63.273432) (xy 29.580845 -63.21781) (xy 29.592971 -63.163373)
			(xy 29.612894 -63.111282) (xy 29.64019 -63.062647) (xy 29.674276 -63.018504) (xy 29.714425 -62.979795)
			(xy 29.759783 -62.947344) (xy 29.809383 -62.921843) (xy 29.862167 -62.903836) (xy 29.91701 -62.893706)
			(xy 29.972744 -62.891669) (xy 30.028181 -62.897769) (xy 30.082138 -62.911875) (xy 30.133467 -62.933687)
			(xy 30.181073 -62.962741) (xy 30.223941 -62.998416) (xy 30.261158 -63.039953) (xy 30.291931 -63.086466)
			(xy 30.315603 -63.136963) (xy 30.331671 -63.19037) (xy 30.339791 -63.245546) (xy 30.339791 -63.245548)
			(xy 43.104592 -63.245548) (xy 43.104592 -63.191052) (xy 43.112347 -63.137109) (xy 43.1277 -63.084819)
			(xy 43.150337 -63.035247) (xy 43.179799 -62.9894) (xy 43.215485 -62.948212) (xy 43.256669 -62.912522)
			(xy 43.302513 -62.883056) (xy 43.352084 -62.860413) (xy 43.404372 -62.845055) (xy 43.458314 -62.837295)
			(xy 43.485562 -62.836806) (xy 43.512931 -62.837293) (xy 43.56711 -62.845105) (xy 43.619613 -62.86059)
			(xy 43.66936 -62.883427) (xy 43.715328 -62.913147) (xy 43.73626 -62.930786) (xy 43.736514 -62.93104)
			(xy 43.743589 -62.936643) (xy 43.760515 -62.942879) (xy 43.769534 -62.943232) (xy 43.83659 -62.943232)
			(xy 43.845606 -62.942863) (xy 43.862522 -62.936623) (xy 43.86961 -62.93104) (xy 43.870118 -62.930532)
			(xy 43.891021 -62.912881) (xy 43.936993 -62.88322) (xy 43.986732 -62.860434) (xy 44.039217 -62.844988)
			(xy 44.093371 -62.837202) (xy 44.148081 -62.837235) (xy 44.202225 -62.845085) (xy 44.254692 -62.860592)
			(xy 44.304404 -62.883438) (xy 44.350341 -62.913153) (xy 44.37126 -62.930786) (xy 44.371514 -62.93104)
			(xy 44.378589 -62.936643) (xy 44.395515 -62.942879) (xy 44.404534 -62.943232) (xy 44.47159 -62.943232)
			(xy 44.480606 -62.942863) (xy 44.497522 -62.936623) (xy 44.50461 -62.93104) (xy 44.505118 -62.930532)
			(xy 44.52603 -62.912923) (xy 44.57197 -62.883286) (xy 44.621672 -62.860512) (xy 44.674115 -62.845068)
			(xy 44.728227 -62.837271) (xy 44.755562 -62.836806) (xy 44.782818 -62.837238) (xy 44.836775 -62.844991)
			(xy 44.889079 -62.860344) (xy 44.938666 -62.882986) (xy 44.984526 -62.912454) (xy 45.025724 -62.948149)
			(xy 45.061423 -62.989344) (xy 45.090896 -63.035201) (xy 45.113542 -63.084785) (xy 45.113968 -63.086234)
			(xy 53.387496 -63.086234) (xy 53.391567 -63.030612) (xy 53.403693 -62.976175) (xy 53.423616 -62.924084)
			(xy 53.450912 -62.875449) (xy 53.484998 -62.831306) (xy 53.525147 -62.792597) (xy 53.570505 -62.760146)
			(xy 53.620105 -62.734645) (xy 53.672889 -62.716638) (xy 53.727732 -62.706508) (xy 53.783466 -62.704471)
			(xy 53.838903 -62.710571) (xy 53.89286 -62.724677) (xy 53.944189 -62.746489) (xy 53.991795 -62.775543)
			(xy 54.034663 -62.811218) (xy 54.059961 -62.839452) (xy 58.918846 -62.839452) (xy 58.918846 -62.784948)
			(xy 58.926602 -62.731) (xy 58.941956 -62.678704) (xy 58.964596 -62.629126) (xy 58.99406 -62.583274)
			(xy 59.02975 -62.542081) (xy 59.070939 -62.506387) (xy 59.116787 -62.476917) (xy 59.166363 -62.454271)
			(xy 59.218657 -62.438911) (xy 59.272605 -62.431149) (xy 59.299856 -62.43066) (xy 59.328664 -62.431215)
			(xy 59.385625 -62.439885) (xy 59.440635 -62.457019) (xy 59.492444 -62.482229) (xy 59.539875 -62.51494)
			(xy 59.561222 -62.534292) (xy 59.569858 -62.54242) (xy 59.591702 -62.549278) (xy 59.681618 -62.536832)
			(xy 59.692989 -62.534763) (xy 59.712171 -62.521902) (xy 59.718448 -62.512194) (xy 59.733288 -62.48809)
			(xy 59.768937 -62.444127) (xy 59.810687 -62.405909) (xy 59.857623 -62.374276) (xy 59.908716 -62.349921)
			(xy 59.962845 -62.333377) (xy 60.018824 -62.325008) (xy 60.047124 -62.324488) (xy 60.070679 -62.324864)
			(xy 60.117423 -62.330724) (xy 60.140342 -62.336172) (xy 60.149555 -62.338033) (xy 60.168187 -62.33569)
			(xy 60.184717 -62.326776) (xy 60.191142 -62.319916) (xy 60.259976 -62.24016) (xy 60.264548 -62.211966)
			(xy 60.25896 -62.198504) (xy 60.249649 -62.175114) (xy 60.236524 -62.126514) (xy 60.229901 -62.076609)
			(xy 60.229496 -62.051438) (xy 60.229982 -62.024187) (xy 60.237738 -61.970239) (xy 60.253093 -61.917944)
			(xy 60.275735 -61.868367) (xy 60.305201 -61.822517) (xy 60.340892 -61.781326) (xy 60.382083 -61.745635)
			(xy 60.427933 -61.716169) (xy 60.47751 -61.693527) (xy 60.529805 -61.678172) (xy 60.583753 -61.670416)
			(xy 60.638255 -61.670416) (xy 60.692203 -61.678172) (xy 60.744498 -61.693527) (xy 60.794075 -61.716169)
			(xy 60.839925 -61.745635) (xy 60.881116 -61.781326) (xy 60.916807 -61.822517) (xy 60.946273 -61.868367)
			(xy 60.968915 -61.917944) (xy 60.98427 -61.970239) (xy 60.992026 -62.024187) (xy 60.992512 -62.051438)
			(xy 60.992058 -62.07869) (xy 60.985966 -62.121034) (xy 82.24215 -62.121034) (xy 82.246221 -62.065412)
			(xy 82.258347 -62.010975) (xy 82.27827 -61.958884) (xy 82.305566 -61.910249) (xy 82.339652 -61.866106)
			(xy 82.379801 -61.827397) (xy 82.425159 -61.794946) (xy 82.474759 -61.769445) (xy 82.527543 -61.751438)
			(xy 82.582386 -61.741308) (xy 82.63812 -61.739271) (xy 82.693557 -61.745371) (xy 82.747514 -61.759477)
			(xy 82.798843 -61.781289) (xy 82.846449 -61.810343) (xy 82.889317 -61.846018) (xy 82.926534 -61.887555)
			(xy 82.957307 -61.934068) (xy 82.980979 -61.984565) (xy 82.997047 -62.037972) (xy 83.005167 -62.093148)
			(xy 83.005676 -62.121034) (xy 83.005167 -62.14892) (xy 82.997047 -62.204096) (xy 82.980979 -62.257503)
			(xy 82.957307 -62.308) (xy 82.926534 -62.354513) (xy 82.889317 -62.39605) (xy 82.846449 -62.431725)
			(xy 82.798843 -62.460779) (xy 82.747514 -62.482591) (xy 82.693557 -62.496697) (xy 82.63812 -62.502797)
			(xy 82.582386 -62.50076) (xy 82.527543 -62.49063) (xy 82.474759 -62.472623) (xy 82.425159 -62.447122)
			(xy 82.379801 -62.414671) (xy 82.339652 -62.375962) (xy 82.305566 -62.331819) (xy 82.27827 -62.283184)
			(xy 82.258347 -62.231093) (xy 82.246221 -62.176656) (xy 82.24215 -62.121034) (xy 60.985966 -62.121034)
			(xy 60.984296 -62.132639) (xy 60.968936 -62.184934) (xy 60.946291 -62.234511) (xy 60.916821 -62.280361)
			(xy 60.881126 -62.321551) (xy 60.839934 -62.357241) (xy 60.794081 -62.386707) (xy 60.744502 -62.409348)
			(xy 60.692205 -62.424703) (xy 60.638256 -62.43246) (xy 60.611004 -62.432946) (xy 60.58745 -62.432564)
			(xy 60.540705 -62.426708) (xy 60.517786 -62.421262) (xy 60.508574 -62.419355) (xy 60.489922 -62.421693)
			(xy 60.473374 -62.430613) (xy 60.466986 -62.437518) (xy 60.398152 -62.517274) (xy 60.39358 -62.545468)
			(xy 60.399168 -62.55893) (xy 60.40849 -62.582315) (xy 60.421611 -62.630918) (xy 60.428229 -62.680824)
			(xy 60.428632 -62.705996) (xy 60.428119 -62.733246) (xy 60.420363 -62.787192) (xy 60.40501 -62.839484)
			(xy 60.382371 -62.88906) (xy 60.352907 -62.934909) (xy 60.317219 -62.976099) (xy 60.276032 -63.01179)
			(xy 60.230185 -63.041257) (xy 60.180611 -63.0639) (xy 60.128319 -63.079257) (xy 60.074374 -63.087017)
			(xy 60.047124 -63.087504) (xy 60.018316 -63.086944) (xy 59.961356 -63.078272) (xy 59.906347 -63.061138)
			(xy 59.854538 -63.035931) (xy 59.807106 -63.003222) (xy 59.785758 -62.983872) (xy 59.777122 -62.975744)
			(xy 59.755278 -62.968886) (xy 59.665362 -62.981332) (xy 59.654006 -62.983457) (xy 59.634819 -62.996279)
			(xy 59.628532 -63.00597) (xy 59.613693 -63.030074) (xy 59.578045 -63.07404) (xy 59.536296 -63.112258)
			(xy 59.489359 -63.143892) (xy 59.438266 -63.168248) (xy 59.384136 -63.18479) (xy 59.328157 -63.193158)
			(xy 59.299856 -63.193676) (xy 59.272605 -63.193251) (xy 59.218657 -63.185489) (xy 59.166363 -63.170129)
			(xy 59.116787 -63.147483) (xy 59.070939 -63.118013) (xy 59.02975 -63.082319) (xy 58.99406 -63.041126)
			(xy 58.964596 -62.995274) (xy 58.941956 -62.945696) (xy 58.926602 -62.8934) (xy 58.918846 -62.839452)
			(xy 54.059961 -62.839452) (xy 54.07188 -62.852755) (xy 54.102653 -62.899268) (xy 54.126325 -62.949765)
			(xy 54.142393 -63.003172) (xy 54.150513 -63.058348) (xy 54.151022 -63.086234) (xy 54.150513 -63.11412)
			(xy 54.142393 -63.169296) (xy 54.126325 -63.222703) (xy 54.102653 -63.2732) (xy 54.1025 -63.273432)
			(xy 55.576722 -63.273432) (xy 55.580793 -63.21781) (xy 55.592919 -63.163373) (xy 55.612842 -63.111282)
			(xy 55.640138 -63.062647) (xy 55.674224 -63.018504) (xy 55.714373 -62.979795) (xy 55.759731 -62.947344)
			(xy 55.809331 -62.921843) (xy 55.862115 -62.903836) (xy 55.916958 -62.893706) (xy 55.972692 -62.891669)
			(xy 56.028129 -62.897769) (xy 56.082086 -62.911875) (xy 56.133415 -62.933687) (xy 56.181021 -62.962741)
			(xy 56.223889 -62.998416) (xy 56.261106 -63.039953) (xy 56.291879 -63.086466) (xy 56.315551 -63.136963)
			(xy 56.331619 -63.19037) (xy 56.339739 -63.245546) (xy 56.339739 -63.245552) (xy 69.104469 -63.245552)
			(xy 69.104469 -63.191048) (xy 69.112226 -63.137098) (xy 69.127582 -63.084801) (xy 69.150225 -63.035222)
			(xy 69.179692 -62.98937) (xy 69.215386 -62.948179) (xy 69.256578 -62.912486) (xy 69.302431 -62.88302)
			(xy 69.352011 -62.860379) (xy 69.404308 -62.845024) (xy 69.458258 -62.837269) (xy 69.48551 -62.836806)
			(xy 69.512881 -62.837265) (xy 69.56706 -62.845084) (xy 69.619563 -62.860575) (xy 69.66931 -62.883418)
			(xy 69.715276 -62.913144) (xy 69.736208 -62.930786) (xy 69.736462 -62.93104) (xy 69.743552 -62.936622)
			(xy 69.760466 -62.94287) (xy 69.769482 -62.943232) (xy 69.836538 -62.943232) (xy 69.845556 -62.942886)
			(xy 69.862472 -62.93663) (xy 69.869558 -62.93104) (xy 69.870066 -62.930532) (xy 69.89101 -62.912932)
			(xy 69.936975 -62.883269) (xy 69.986707 -62.860479) (xy 70.039186 -62.84503) (xy 70.093334 -62.837239)
			(xy 70.148039 -62.837266) (xy 70.202179 -62.84511) (xy 70.254643 -62.86061) (xy 70.304353 -62.883449)
			(xy 70.350289 -62.913157) (xy 70.371208 -62.930786) (xy 70.371462 -62.93104) (xy 70.378552 -62.936622)
			(xy 70.395466 -62.94287) (xy 70.404482 -62.943232) (xy 70.471538 -62.943232) (xy 70.480556 -62.942886)
			(xy 70.497472 -62.93663) (xy 70.504558 -62.93104) (xy 70.505066 -62.930532) (xy 70.525998 -62.912947)
			(xy 70.571933 -62.883306) (xy 70.621629 -62.860528) (xy 70.674068 -62.845079) (xy 70.728176 -62.837275)
			(xy 70.75551 -62.836806) (xy 70.782762 -62.837264) (xy 70.83671 -62.845022) (xy 70.889006 -62.860379)
			(xy 70.938584 -62.883022) (xy 70.984434 -62.912489) (xy 71.025625 -62.948182) (xy 71.061317 -62.989374)
			(xy 71.090783 -63.035225) (xy 71.113424 -63.084803) (xy 71.113844 -63.086234) (xy 79.387444 -63.086234)
			(xy 79.391515 -63.030612) (xy 79.403641 -62.976175) (xy 79.423564 -62.924084) (xy 79.45086 -62.875449)
			(xy 79.484946 -62.831306) (xy 79.525095 -62.792597) (xy 79.570453 -62.760146) (xy 79.620053 -62.734645)
			(xy 79.672837 -62.716638) (xy 79.72768 -62.706508) (xy 79.783414 -62.704471) (xy 79.838851 -62.710571)
			(xy 79.892808 -62.724677) (xy 79.944137 -62.746489) (xy 79.991743 -62.775543) (xy 80.034611 -62.811218)
			(xy 80.059911 -62.839455) (xy 84.918723 -62.839455) (xy 84.918723 -62.784945) (xy 84.926481 -62.730989)
			(xy 84.941838 -62.678686) (xy 84.964483 -62.629102) (xy 84.993954 -62.583244) (xy 85.029651 -62.542048)
			(xy 85.070848 -62.506351) (xy 85.116705 -62.476881) (xy 85.16629 -62.454237) (xy 85.218593 -62.43888)
			(xy 85.272549 -62.431123) (xy 85.299804 -62.43066) (xy 85.328613 -62.431186) (xy 85.385575 -62.439863)
			(xy 85.440586 -62.457004) (xy 85.492394 -62.48222) (xy 85.539824 -62.514937) (xy 85.56117 -62.534292)
			(xy 85.569806 -62.54242) (xy 85.59165 -62.549278) (xy 85.681566 -62.536832) (xy 85.69293 -62.534736)
			(xy 85.712114 -62.521894) (xy 85.718396 -62.512194) (xy 85.733203 -62.488069) (xy 85.768857 -62.444105)
			(xy 85.810613 -62.405889) (xy 85.857555 -62.374258) (xy 85.908653 -62.349906) (xy 85.962787 -62.333367)
			(xy 86.01877 -62.325004) (xy 86.047072 -62.324488) (xy 86.070626 -62.324873) (xy 86.117371 -62.330727)
			(xy 86.14029 -62.336172) (xy 86.149509 -62.33799) (xy 86.168135 -62.335664) (xy 86.184663 -62.326768)
			(xy 86.19109 -62.319916) (xy 86.259924 -62.24016) (xy 86.264496 -62.211966) (xy 86.258908 -62.198504)
			(xy 86.249595 -62.175115) (xy 86.236471 -62.126514) (xy 86.229849 -62.076609) (xy 86.229444 -62.051438)
			(xy 86.22993 -62.024187) (xy 86.237686 -61.970239) (xy 86.253041 -61.917944) (xy 86.275683 -61.868367)
			(xy 86.305149 -61.822517) (xy 86.34084 -61.781326) (xy 86.382031 -61.745635) (xy 86.427881 -61.716169)
			(xy 86.477458 -61.693527) (xy 86.529753 -61.678172) (xy 86.583701 -61.670416) (xy 86.638203 -61.670416)
			(xy 86.692151 -61.678172) (xy 86.744446 -61.693527) (xy 86.794023 -61.716169) (xy 86.839873 -61.745635)
			(xy 86.881064 -61.781326) (xy 86.916755 -61.822517) (xy 86.946221 -61.868367) (xy 86.968863 -61.917944)
			(xy 86.984218 -61.970239) (xy 86.991974 -62.024187) (xy 86.99246 -62.051438) (xy 86.99208 -62.078694)
			(xy 86.985988 -62.121034) (xy 120.342404 -62.121034) (xy 120.346475 -62.065412) (xy 120.358601 -62.010975)
			(xy 120.378524 -61.958884) (xy 120.40582 -61.910249) (xy 120.439906 -61.866106) (xy 120.480055 -61.827397)
			(xy 120.525413 -61.794946) (xy 120.575013 -61.769445) (xy 120.627797 -61.751438) (xy 120.68264 -61.741308)
			(xy 120.738374 -61.739271) (xy 120.793811 -61.745371) (xy 120.847768 -61.759477) (xy 120.899097 -61.781289)
			(xy 120.946703 -61.810343) (xy 120.989571 -61.846018) (xy 121.026788 -61.887555) (xy 121.057561 -61.934068)
			(xy 121.081233 -61.984565) (xy 121.097301 -62.037972) (xy 121.105421 -62.093148) (xy 121.10593 -62.121034)
			(xy 121.105421 -62.14892) (xy 121.097301 -62.204096) (xy 121.081233 -62.257503) (xy 121.057561 -62.308)
			(xy 121.026788 -62.354513) (xy 120.989571 -62.39605) (xy 120.946703 -62.431725) (xy 120.899097 -62.460779)
			(xy 120.847768 -62.482591) (xy 120.793811 -62.496697) (xy 120.738374 -62.502797) (xy 120.68264 -62.50076)
			(xy 120.627797 -62.49063) (xy 120.575013 -62.472623) (xy 120.525413 -62.447122) (xy 120.480055 -62.414671)
			(xy 120.439906 -62.375962) (xy 120.40582 -62.331819) (xy 120.378524 -62.283184) (xy 120.358601 -62.231093)
			(xy 120.346475 -62.176656) (xy 120.342404 -62.121034) (xy 86.985988 -62.121034) (xy 86.984317 -62.13265)
			(xy 86.968954 -62.184953) (xy 86.946303 -62.234536) (xy 86.916827 -62.280392) (xy 86.881124 -62.321585)
			(xy 86.839923 -62.357278) (xy 86.794061 -62.386744) (xy 86.744472 -62.409384) (xy 86.692166 -62.424735)
			(xy 86.638208 -62.432486) (xy 86.610952 -62.432946) (xy 86.587397 -62.432574) (xy 86.540653 -62.426711)
			(xy 86.517734 -62.421262) (xy 86.508525 -62.41937) (xy 86.489887 -62.421723) (xy 86.473357 -62.43065)
			(xy 86.466934 -62.437518) (xy 86.3981 -62.517274) (xy 86.393528 -62.545468) (xy 86.399116 -62.55893)
			(xy 86.408441 -62.582314) (xy 86.42156 -62.630918) (xy 86.428177 -62.680824) (xy 86.42858 -62.705996)
			(xy 86.428141 -62.73325) (xy 86.420384 -62.787203) (xy 86.405027 -62.839503) (xy 86.382383 -62.889085)
			(xy 86.352913 -62.93494) (xy 86.317216 -62.976133) (xy 86.276021 -63.011827) (xy 86.230164 -63.041294)
			(xy 86.180581 -63.063935) (xy 86.12828 -63.079289) (xy 86.074326 -63.087043) (xy 86.047072 -63.087504)
			(xy 86.018263 -63.086976) (xy 85.961302 -63.078296) (xy 85.906292 -63.061155) (xy 85.854484 -63.03594)
			(xy 85.807053 -63.003225) (xy 85.785706 -62.983872) (xy 85.77707 -62.975744) (xy 85.755226 -62.968886)
			(xy 85.66531 -62.981332) (xy 85.653947 -62.98343) (xy 85.634763 -62.996271) (xy 85.62848 -63.00597)
			(xy 85.613677 -63.030098) (xy 85.578023 -63.074063) (xy 85.536268 -63.11228) (xy 85.489325 -63.143912)
			(xy 85.438226 -63.168263) (xy 85.384091 -63.184801) (xy 85.328106 -63.193161) (xy 85.299804 -63.193676)
			(xy 85.272549 -63.193277) (xy 85.218593 -63.18552) (xy 85.16629 -63.170163) (xy 85.116705 -63.147519)
			(xy 85.070848 -63.118049) (xy 85.029651 -63.082352) (xy 84.993954 -63.041156) (xy 84.964483 -62.995298)
			(xy 84.941838 -62.945714) (xy 84.926481 -62.893411) (xy 84.918723 -62.839455) (xy 80.059911 -62.839455)
			(xy 80.071828 -62.852755) (xy 80.102601 -62.899268) (xy 80.126273 -62.949765) (xy 80.142341 -63.003172)
			(xy 80.150461 -63.058348) (xy 80.15097 -63.086234) (xy 80.150461 -63.11412) (xy 80.142341 -63.169296)
			(xy 80.126273 -63.222703) (xy 80.102601 -63.2732) (xy 80.102448 -63.273432) (xy 81.57667 -63.273432)
			(xy 81.580741 -63.21781) (xy 81.592867 -63.163373) (xy 81.61279 -63.111282) (xy 81.640086 -63.062647)
			(xy 81.674172 -63.018504) (xy 81.714321 -62.979795) (xy 81.759679 -62.947344) (xy 81.809279 -62.921843)
			(xy 81.862063 -62.903836) (xy 81.916906 -62.893706) (xy 81.97264 -62.891669) (xy 82.028077 -62.897769)
			(xy 82.082034 -62.911875) (xy 82.133363 -62.933687) (xy 82.180969 -62.962741) (xy 82.223837 -62.998416)
			(xy 82.261054 -63.039953) (xy 82.291827 -63.086466) (xy 82.315499 -63.136963) (xy 82.331567 -63.19037)
			(xy 82.339687 -63.245546) (xy 82.339687 -63.245548) (xy 95.104492 -63.245548) (xy 95.104492 -63.191052)
			(xy 95.112247 -63.13711) (xy 95.1276 -63.08482) (xy 95.150237 -63.035248) (xy 95.179698 -62.989401)
			(xy 95.215384 -62.948214) (xy 95.256567 -62.912523) (xy 95.302411 -62.883057) (xy 95.351981 -62.860414)
			(xy 95.404269 -62.845056) (xy 95.45821 -62.837295) (xy 95.485458 -62.836806) (xy 95.512827 -62.837295)
			(xy 95.567006 -62.845107) (xy 95.619508 -62.860591) (xy 95.669256 -62.883427) (xy 95.715224 -62.913147)
			(xy 95.736156 -62.930786) (xy 95.73641 -62.93104) (xy 95.743486 -62.936642) (xy 95.760411 -62.942878)
			(xy 95.76943 -62.943232) (xy 95.836486 -62.943232) (xy 95.845501 -62.942861) (xy 95.862418 -62.936622)
			(xy 95.869506 -62.93104) (xy 95.870014 -62.930532) (xy 95.89092 -62.912885) (xy 95.936892 -62.883224)
			(xy 95.98663 -62.860437) (xy 96.039115 -62.844992) (xy 96.093268 -62.837205) (xy 96.147978 -62.837237)
			(xy 96.202121 -62.845087) (xy 96.254588 -62.860594) (xy 96.3043 -62.883439) (xy 96.350237 -62.913154)
			(xy 96.371156 -62.930786) (xy 96.37141 -62.93104) (xy 96.378486 -62.936642) (xy 96.395411 -62.942878)
			(xy 96.40443 -62.943232) (xy 96.471486 -62.943232) (xy 96.480501 -62.942861) (xy 96.497418 -62.936622)
			(xy 96.504506 -62.93104) (xy 96.505014 -62.930532) (xy 96.525928 -62.912924) (xy 96.571868 -62.883287)
			(xy 96.621568 -62.860513) (xy 96.674012 -62.845069) (xy 96.728123 -62.837271) (xy 96.755458 -62.836806)
			(xy 96.782714 -62.837238) (xy 96.836671 -62.84499) (xy 96.888976 -62.860343) (xy 96.938564 -62.882984)
			(xy 96.984424 -62.912452) (xy 97.025623 -62.948147) (xy 97.061322 -62.989343) (xy 97.090795 -63.0352)
			(xy 97.113442 -63.084784) (xy 97.113868 -63.086234) (xy 117.487698 -63.086234) (xy 117.491769 -63.030612)
			(xy 117.503895 -62.976175) (xy 117.523818 -62.924084) (xy 117.551114 -62.875449) (xy 117.5852 -62.831306)
			(xy 117.625349 -62.792597) (xy 117.670707 -62.760146) (xy 117.720307 -62.734645) (xy 117.773091 -62.716638)
			(xy 117.827934 -62.706508) (xy 117.883668 -62.704471) (xy 117.939105 -62.710571) (xy 117.993062 -62.724677)
			(xy 118.044391 -62.746489) (xy 118.091997 -62.775543) (xy 118.134865 -62.811218) (xy 118.160163 -62.839452)
			(xy 123.019046 -62.839452) (xy 123.019046 -62.784948) (xy 123.026802 -62.731) (xy 123.042156 -62.678704)
			(xy 123.064796 -62.629125) (xy 123.094261 -62.583273) (xy 123.129951 -62.542081) (xy 123.17114 -62.506386)
			(xy 123.216989 -62.476916) (xy 123.266565 -62.454271) (xy 123.318859 -62.438911) (xy 123.372806 -62.431149)
			(xy 123.400058 -62.43066) (xy 123.428866 -62.431214) (xy 123.485827 -62.439884) (xy 123.540837 -62.457019)
			(xy 123.592646 -62.482228) (xy 123.640077 -62.51494) (xy 123.661424 -62.534292) (xy 123.67006 -62.54242)
			(xy 123.691904 -62.549278) (xy 123.78182 -62.536832) (xy 123.793192 -62.534764) (xy 123.812373 -62.521902)
			(xy 123.81865 -62.512194) (xy 123.833488 -62.48809) (xy 123.869138 -62.444126) (xy 123.910888 -62.405909)
			(xy 123.957824 -62.374275) (xy 124.008917 -62.34992) (xy 124.063047 -62.333377) (xy 124.119026 -62.325008)
			(xy 124.147326 -62.324488) (xy 124.170881 -62.324863) (xy 124.217625 -62.330724) (xy 124.240544 -62.336172)
			(xy 124.249757 -62.338035) (xy 124.268389 -62.335691) (xy 124.284919 -62.326777) (xy 124.291344 -62.319916)
			(xy 124.360178 -62.24016) (xy 124.36475 -62.211966) (xy 124.359162 -62.198504) (xy 124.349851 -62.175114)
			(xy 124.336726 -62.126514) (xy 124.330103 -62.076609) (xy 124.329698 -62.051438) (xy 124.330184 -62.024187)
			(xy 124.33794 -61.970239) (xy 124.353295 -61.917944) (xy 124.375937 -61.868367) (xy 124.405403 -61.822517)
			(xy 124.441094 -61.781326) (xy 124.482285 -61.745635) (xy 124.528135 -61.716169) (xy 124.577712 -61.693527)
			(xy 124.630007 -61.678172) (xy 124.683955 -61.670416) (xy 124.738457 -61.670416) (xy 124.792405 -61.678172)
			(xy 124.8447 -61.693527) (xy 124.894277 -61.716169) (xy 124.940127 -61.745635) (xy 124.981318 -61.781326)
			(xy 125.017009 -61.822517) (xy 125.046475 -61.868367) (xy 125.069117 -61.917944) (xy 125.084472 -61.970239)
			(xy 125.092228 -62.024187) (xy 125.092714 -62.051438) (xy 125.092258 -62.07869) (xy 125.086166 -62.121034)
			(xy 146.342352 -62.121034) (xy 146.346423 -62.065412) (xy 146.358549 -62.010975) (xy 146.378472 -61.958884)
			(xy 146.405768 -61.910249) (xy 146.439854 -61.866106) (xy 146.480003 -61.827397) (xy 146.525361 -61.794946)
			(xy 146.574961 -61.769445) (xy 146.627745 -61.751438) (xy 146.682588 -61.741308) (xy 146.738322 -61.739271)
			(xy 146.793759 -61.745371) (xy 146.847716 -61.759477) (xy 146.899045 -61.781289) (xy 146.946651 -61.810343)
			(xy 146.989519 -61.846018) (xy 147.026736 -61.887555) (xy 147.057509 -61.934068) (xy 147.081181 -61.984565)
			(xy 147.097249 -62.037972) (xy 147.105369 -62.093148) (xy 147.105878 -62.121034) (xy 147.105369 -62.14892)
			(xy 147.097249 -62.204096) (xy 147.081181 -62.257503) (xy 147.057509 -62.308) (xy 147.026736 -62.354513)
			(xy 146.989519 -62.39605) (xy 146.946651 -62.431725) (xy 146.899045 -62.460779) (xy 146.847716 -62.482591)
			(xy 146.793759 -62.496697) (xy 146.738322 -62.502797) (xy 146.682588 -62.50076) (xy 146.627745 -62.49063)
			(xy 146.574961 -62.472623) (xy 146.525361 -62.447122) (xy 146.480003 -62.414671) (xy 146.439854 -62.375962)
			(xy 146.405768 -62.331819) (xy 146.378472 -62.283184) (xy 146.358549 -62.231093) (xy 146.346423 -62.176656)
			(xy 146.342352 -62.121034) (xy 125.086166 -62.121034) (xy 125.084496 -62.132638) (xy 125.069136 -62.184933)
			(xy 125.046491 -62.23451) (xy 125.017022 -62.28036) (xy 124.981327 -62.32155) (xy 124.940135 -62.357241)
			(xy 124.894282 -62.386707) (xy 124.844703 -62.409348) (xy 124.792407 -62.424703) (xy 124.738458 -62.43246)
			(xy 124.711206 -62.432946) (xy 124.687652 -62.432564) (xy 124.640907 -62.426708) (xy 124.617988 -62.421262)
			(xy 124.608776 -62.419357) (xy 124.590124 -62.421694) (xy 124.573576 -62.430614) (xy 124.567188 -62.437518)
			(xy 124.498354 -62.517274) (xy 124.493782 -62.545468) (xy 124.49937 -62.55893) (xy 124.508692 -62.582315)
			(xy 124.521813 -62.630918) (xy 124.528431 -62.680824) (xy 124.528834 -62.705996) (xy 124.528319 -62.733246)
			(xy 124.520563 -62.787191) (xy 124.50521 -62.839484) (xy 124.482571 -62.889059) (xy 124.453108 -62.934909)
			(xy 124.417419 -62.976098) (xy 124.376233 -63.01179) (xy 124.330386 -63.041257) (xy 124.280812 -63.063899)
			(xy 124.228521 -63.079257) (xy 124.174576 -63.087016) (xy 124.147326 -63.087504) (xy 124.118518 -63.086943)
			(xy 124.061558 -63.078272) (xy 124.006549 -63.061138) (xy 123.95474 -63.03593) (xy 123.907308 -63.003222)
			(xy 123.88596 -62.983872) (xy 123.877324 -62.975744) (xy 123.85548 -62.968886) (xy 123.765564 -62.981332)
			(xy 123.754208 -62.983458) (xy 123.735021 -62.996279) (xy 123.728734 -63.00597) (xy 123.713894 -63.030073)
			(xy 123.678246 -63.074039) (xy 123.636497 -63.112258) (xy 123.589561 -63.143892) (xy 123.538468 -63.168247)
			(xy 123.484338 -63.18479) (xy 123.428359 -63.193158) (xy 123.400058 -63.193676) (xy 123.372806 -63.193251)
			(xy 123.318859 -63.185489) (xy 123.266565 -63.170129) (xy 123.216989 -63.147484) (xy 123.17114 -63.118014)
			(xy 123.129951 -63.082319) (xy 123.094261 -63.041127) (xy 123.064796 -62.995275) (xy 123.042156 -62.945696)
			(xy 123.026802 -62.8934) (xy 123.019046 -62.839452) (xy 118.160163 -62.839452) (xy 118.172082 -62.852755)
			(xy 118.202855 -62.899268) (xy 118.226527 -62.949765) (xy 118.242595 -63.003172) (xy 118.250715 -63.058348)
			(xy 118.251224 -63.086234) (xy 118.250715 -63.11412) (xy 118.242595 -63.169296) (xy 118.226527 -63.222703)
			(xy 118.202855 -63.2732) (xy 118.202702 -63.273432) (xy 119.676924 -63.273432) (xy 119.680995 -63.21781)
			(xy 119.693121 -63.163373) (xy 119.713044 -63.111282) (xy 119.74034 -63.062647) (xy 119.774426 -63.018504)
			(xy 119.814575 -62.979795) (xy 119.859933 -62.947344) (xy 119.909533 -62.921843) (xy 119.962317 -62.903836)
			(xy 120.01716 -62.893706) (xy 120.072894 -62.891669) (xy 120.128331 -62.897769) (xy 120.182288 -62.911875)
			(xy 120.233617 -62.933687) (xy 120.281223 -62.962741) (xy 120.324091 -62.998416) (xy 120.361308 -63.039953)
			(xy 120.392081 -63.086466) (xy 120.415753 -63.136963) (xy 120.431821 -63.19037) (xy 120.439941 -63.245546)
			(xy 120.439941 -63.245552) (xy 133.204669 -63.245552) (xy 133.204669 -63.191048) (xy 133.212426 -63.137098)
			(xy 133.227782 -63.084801) (xy 133.250425 -63.035222) (xy 133.279893 -62.98937) (xy 133.315587 -62.948178)
			(xy 133.356779 -62.912486) (xy 133.402632 -62.883019) (xy 133.452212 -62.860378) (xy 133.504509 -62.845024)
			(xy 133.55846 -62.837268) (xy 133.585712 -62.836806) (xy 133.613083 -62.837264) (xy 133.667262 -62.845083)
			(xy 133.719765 -62.860574) (xy 133.769512 -62.883418) (xy 133.815479 -62.913144) (xy 133.83641 -62.930786)
			(xy 133.836664 -62.93104) (xy 133.843753 -62.936623) (xy 133.860668 -62.942871) (xy 133.869684 -62.943232)
			(xy 133.93674 -62.943232) (xy 133.945758 -62.942887) (xy 133.962675 -62.93663) (xy 133.96976 -62.93104)
			(xy 133.970268 -62.930532) (xy 133.99121 -62.91293) (xy 134.037176 -62.883267) (xy 134.086908 -62.860478)
			(xy 134.139387 -62.845029) (xy 134.193535 -62.837238) (xy 134.248241 -62.837265) (xy 134.302381 -62.845109)
			(xy 134.354845 -62.86061) (xy 134.404555 -62.883449) (xy 134.450491 -62.913157) (xy 134.47141 -62.930786)
			(xy 134.471664 -62.93104) (xy 134.478753 -62.936623) (xy 134.495668 -62.942871) (xy 134.504684 -62.943232)
			(xy 134.57174 -62.943232) (xy 134.580758 -62.942887) (xy 134.597675 -62.93663) (xy 134.60476 -62.93104)
			(xy 134.605268 -62.930532) (xy 134.626199 -62.912946) (xy 134.672134 -62.883306) (xy 134.72183 -62.860527)
			(xy 134.77427 -62.845078) (xy 134.828378 -62.837275) (xy 134.855712 -62.836806) (xy 134.882964 -62.837265)
			(xy 134.936912 -62.845023) (xy 134.989207 -62.86038) (xy 135.038785 -62.883022) (xy 135.084635 -62.91249)
			(xy 135.125826 -62.948183) (xy 135.161517 -62.989374) (xy 135.190984 -63.035226) (xy 135.213625 -63.084804)
			(xy 135.214045 -63.086234) (xy 143.487646 -63.086234) (xy 143.491717 -63.030612) (xy 143.503843 -62.976175)
			(xy 143.523766 -62.924084) (xy 143.551062 -62.875449) (xy 143.585148 -62.831306) (xy 143.625297 -62.792597)
			(xy 143.670655 -62.760146) (xy 143.720255 -62.734645) (xy 143.773039 -62.716638) (xy 143.827882 -62.706508)
			(xy 143.883616 -62.704471) (xy 143.939053 -62.710571) (xy 143.99301 -62.724677) (xy 144.044339 -62.746489)
			(xy 144.091945 -62.775543) (xy 144.134813 -62.811218) (xy 144.160113 -62.839455) (xy 149.018923 -62.839455)
			(xy 149.018923 -62.784945) (xy 149.026681 -62.730989) (xy 149.042038 -62.678686) (xy 149.064683 -62.629101)
			(xy 149.094154 -62.583244) (xy 149.129852 -62.542047) (xy 149.171049 -62.506351) (xy 149.216906 -62.47688)
			(xy 149.266491 -62.454236) (xy 149.318794 -62.438879) (xy 149.372751 -62.431123) (xy 149.400006 -62.43066)
			(xy 149.428815 -62.431185) (xy 149.485778 -62.439862) (xy 149.540788 -62.457004) (xy 149.592596 -62.48222)
			(xy 149.640026 -62.514937) (xy 149.661372 -62.534292) (xy 149.670008 -62.54242) (xy 149.691852 -62.549278)
			(xy 149.781768 -62.536832) (xy 149.793132 -62.534737) (xy 149.812317 -62.521895) (xy 149.818598 -62.512194)
			(xy 149.833403 -62.488068) (xy 149.869058 -62.444104) (xy 149.910814 -62.405888) (xy 149.957756 -62.374258)
			(xy 150.008854 -62.349906) (xy 150.062989 -62.333367) (xy 150.118972 -62.325004) (xy 150.147274 -62.324488)
			(xy 150.170828 -62.324873) (xy 150.217573 -62.330727) (xy 150.240492 -62.336172) (xy 150.249711 -62.337992)
			(xy 150.268337 -62.335665) (xy 150.284865 -62.326769) (xy 150.291292 -62.319916) (xy 150.360126 -62.24016)
			(xy 150.364698 -62.211966) (xy 150.35911 -62.198504) (xy 150.349797 -62.175115) (xy 150.336673 -62.126514)
			(xy 150.330051 -62.076609) (xy 150.329646 -62.051438) (xy 150.330132 -62.024187) (xy 150.337888 -61.970239)
			(xy 150.353243 -61.917944) (xy 150.375885 -61.868367) (xy 150.405351 -61.822517) (xy 150.441042 -61.781326)
			(xy 150.482233 -61.745635) (xy 150.528083 -61.716169) (xy 150.57766 -61.693527) (xy 150.629955 -61.678172)
			(xy 150.683903 -61.670416) (xy 150.738405 -61.670416) (xy 150.792353 -61.678172) (xy 150.844648 -61.693527)
			(xy 150.894225 -61.716169) (xy 150.940075 -61.745635) (xy 150.981266 -61.781326) (xy 151.016957 -61.822517)
			(xy 151.046423 -61.868367) (xy 151.069065 -61.917944) (xy 151.08442 -61.970239) (xy 151.092176 -62.024187)
			(xy 151.092662 -62.051438) (xy 151.09228 -62.078694) (xy 151.086188 -62.121034) (xy 172.3423 -62.121034)
			(xy 172.346371 -62.065412) (xy 172.358497 -62.010975) (xy 172.37842 -61.958884) (xy 172.405716 -61.910249)
			(xy 172.439802 -61.866106) (xy 172.479951 -61.827397) (xy 172.525309 -61.794946) (xy 172.574909 -61.769445)
			(xy 172.627693 -61.751438) (xy 172.682536 -61.741308) (xy 172.73827 -61.739271) (xy 172.793707 -61.745371)
			(xy 172.847664 -61.759477) (xy 172.898993 -61.781289) (xy 172.946599 -61.810343) (xy 172.989467 -61.846018)
			(xy 173.026684 -61.887555) (xy 173.057457 -61.934068) (xy 173.081129 -61.984565) (xy 173.097197 -62.037972)
			(xy 173.105317 -62.093148) (xy 173.105826 -62.121034) (xy 173.105317 -62.14892) (xy 173.097197 -62.204096)
			(xy 173.081129 -62.257503) (xy 173.057457 -62.308) (xy 173.026684 -62.354513) (xy 172.989467 -62.39605)
			(xy 172.946599 -62.431725) (xy 172.898993 -62.460779) (xy 172.847664 -62.482591) (xy 172.793707 -62.496697)
			(xy 172.73827 -62.502797) (xy 172.682536 -62.50076) (xy 172.627693 -62.49063) (xy 172.574909 -62.472623)
			(xy 172.525309 -62.447122) (xy 172.479951 -62.414671) (xy 172.439802 -62.375962) (xy 172.405716 -62.331819)
			(xy 172.37842 -62.283184) (xy 172.358497 -62.231093) (xy 172.346371 -62.176656) (xy 172.3423 -62.121034)
			(xy 151.086188 -62.121034) (xy 151.084517 -62.13265) (xy 151.069154 -62.184952) (xy 151.046504 -62.234536)
			(xy 151.017027 -62.280391) (xy 150.981325 -62.321584) (xy 150.940124 -62.357278) (xy 150.894262 -62.386744)
			(xy 150.844674 -62.409383) (xy 150.792368 -62.424735) (xy 150.73841 -62.432486) (xy 150.711154 -62.432946)
			(xy 150.687599 -62.432573) (xy 150.640855 -62.426711) (xy 150.617936 -62.421262) (xy 150.60873 -62.419314)
			(xy 150.590071 -62.421669) (xy 150.573523 -62.430606) (xy 150.567136 -62.437518) (xy 150.498302 -62.517274)
			(xy 150.49373 -62.545468) (xy 150.499318 -62.55893) (xy 150.508643 -62.582314) (xy 150.521762 -62.630918)
			(xy 150.528379 -62.680824) (xy 150.528782 -62.705996) (xy 150.528341 -62.73325) (xy 150.520584 -62.787203)
			(xy 150.505227 -62.839503) (xy 150.482583 -62.889085) (xy 150.453113 -62.934939) (xy 150.417417 -62.976132)
			(xy 150.376221 -63.011826) (xy 150.330365 -63.041294) (xy 150.280782 -63.063935) (xy 150.228481 -63.079288)
			(xy 150.174528 -63.087042) (xy 150.147274 -63.087504) (xy 150.118465 -63.086974) (xy 150.061504 -63.078296)
			(xy 150.006494 -63.061154) (xy 149.954686 -63.03594) (xy 149.907255 -63.003225) (xy 149.885908 -62.983872)
			(xy 149.877272 -62.975744) (xy 149.855428 -62.968886) (xy 149.765512 -62.981332) (xy 149.754149 -62.983431)
			(xy 149.734965 -62.996272) (xy 149.728682 -63.00597) (xy 149.713878 -63.030097) (xy 149.678224 -63.074062)
			(xy 149.636469 -63.11228) (xy 149.589527 -63.143911) (xy 149.538428 -63.168263) (xy 149.484292 -63.1848)
			(xy 149.428308 -63.193161) (xy 149.400006 -63.193676) (xy 149.372751 -63.193277) (xy 149.318794 -63.185521)
			(xy 149.266491 -63.170164) (xy 149.216906 -63.14752) (xy 149.171049 -63.118049) (xy 149.129852 -63.082353)
			(xy 149.094154 -63.041156) (xy 149.064683 -62.995299) (xy 149.042038 -62.945714) (xy 149.026681 -62.893411)
			(xy 149.018923 -62.839455) (xy 144.160113 -62.839455) (xy 144.17203 -62.852755) (xy 144.202803 -62.899268)
			(xy 144.226475 -62.949765) (xy 144.242543 -63.003172) (xy 144.250663 -63.058348) (xy 144.251172 -63.086234)
			(xy 144.250663 -63.11412) (xy 144.242543 -63.169296) (xy 144.226475 -63.222703) (xy 144.202803 -63.2732)
			(xy 144.20265 -63.273432) (xy 145.676872 -63.273432) (xy 145.680943 -63.21781) (xy 145.693069 -63.163373)
			(xy 145.712992 -63.111282) (xy 145.740288 -63.062647) (xy 145.774374 -63.018504) (xy 145.814523 -62.979795)
			(xy 145.859881 -62.947344) (xy 145.909481 -62.921843) (xy 145.962265 -62.903836) (xy 146.017108 -62.893706)
			(xy 146.072842 -62.891669) (xy 146.128279 -62.897769) (xy 146.182236 -62.911875) (xy 146.233565 -62.933687)
			(xy 146.281171 -62.962741) (xy 146.324039 -62.998416) (xy 146.361256 -63.039953) (xy 146.392029 -63.086466)
			(xy 146.415701 -63.136963) (xy 146.431769 -63.19037) (xy 146.439889 -63.245546) (xy 146.439889 -63.245548)
			(xy 159.204692 -63.245548) (xy 159.204692 -63.191052) (xy 159.212447 -63.137109) (xy 159.2278 -63.08482)
			(xy 159.250437 -63.035247) (xy 159.279899 -62.9894) (xy 159.315584 -62.948213) (xy 159.356768 -62.912523)
			(xy 159.402612 -62.883056) (xy 159.452182 -62.860414) (xy 159.50447 -62.845056) (xy 159.558412 -62.837295)
			(xy 159.58566 -62.836806) (xy 159.613029 -62.837294) (xy 159.667208 -62.845106) (xy 159.719711 -62.86059)
			(xy 159.769458 -62.883427) (xy 159.815426 -62.913147) (xy 159.836358 -62.930786) (xy 159.836612 -62.93104)
			(xy 159.843687 -62.936643) (xy 159.860613 -62.942879) (xy 159.869632 -62.943232) (xy 159.936688 -62.943232)
			(xy 159.945703 -62.942862) (xy 159.96262 -62.936623) (xy 159.969708 -62.93104) (xy 159.970216 -62.930532)
			(xy 159.99112 -62.912883) (xy 160.037092 -62.883222) (xy 160.086831 -62.860435) (xy 160.139316 -62.84499)
			(xy 160.193469 -62.837204) (xy 160.248179 -62.837236) (xy 160.302323 -62.845086) (xy 160.35479 -62.860593)
			(xy 160.404502 -62.883438) (xy 160.450439 -62.913154) (xy 160.471358 -62.930786) (xy 160.471612 -62.93104)
			(xy 160.478687 -62.936643) (xy 160.495613 -62.942879) (xy 160.504632 -62.943232) (xy 160.571688 -62.943232)
			(xy 160.580703 -62.942862) (xy 160.59762 -62.936623) (xy 160.604708 -62.93104) (xy 160.605216 -62.930532)
			(xy 160.626129 -62.912924) (xy 160.672069 -62.883287) (xy 160.72177 -62.860513) (xy 160.774213 -62.845069)
			(xy 160.828325 -62.837271) (xy 160.85566 -62.836806) (xy 160.882916 -62.837238) (xy 160.936873 -62.844991)
			(xy 160.989178 -62.860344) (xy 161.038765 -62.882985) (xy 161.084625 -62.912453) (xy 161.125824 -62.948148)
			(xy 161.161523 -62.989343) (xy 161.190996 -63.0352) (xy 161.213642 -63.084785) (xy 161.214068 -63.086234)
			(xy 169.515026 -63.086234) (xy 169.519097 -63.030612) (xy 169.531223 -62.976175) (xy 169.551146 -62.924084)
			(xy 169.578442 -62.875449) (xy 169.612528 -62.831306) (xy 169.652677 -62.792597) (xy 169.698035 -62.760146)
			(xy 169.747635 -62.734645) (xy 169.800419 -62.716638) (xy 169.855262 -62.706508) (xy 169.910996 -62.704471)
			(xy 169.966433 -62.710571) (xy 170.02039 -62.724677) (xy 170.071719 -62.746489) (xy 170.119325 -62.775543)
			(xy 170.162193 -62.811218) (xy 170.18749 -62.839451) (xy 175.018946 -62.839451) (xy 175.018946 -62.784949)
			(xy 175.026702 -62.731) (xy 175.042056 -62.678705) (xy 175.064695 -62.629127) (xy 175.09416 -62.583275)
			(xy 175.129849 -62.542082) (xy 175.171038 -62.506388) (xy 175.216886 -62.476918) (xy 175.266462 -62.454272)
			(xy 175.318755 -62.438911) (xy 175.372703 -62.431149) (xy 175.399954 -62.43066) (xy 175.428765 -62.431155)
			(xy 175.485728 -62.43984) (xy 175.540739 -62.456988) (xy 175.592547 -62.482211) (xy 175.639975 -62.514934)
			(xy 175.66132 -62.534292) (xy 175.669956 -62.54242) (xy 175.6918 -62.549278) (xy 175.781716 -62.536832)
			(xy 175.793087 -62.534762) (xy 175.812268 -62.521902) (xy 175.818546 -62.512194) (xy 175.833387 -62.488091)
			(xy 175.869036 -62.444128) (xy 175.910786 -62.40591) (xy 175.957722 -62.374277) (xy 176.008814 -62.349921)
			(xy 176.062943 -62.333377) (xy 176.118922 -62.325008) (xy 176.147222 -62.324488) (xy 176.170777 -62.324864)
			(xy 176.217521 -62.330724) (xy 176.24044 -62.336172) (xy 176.249653 -62.338031) (xy 176.268285 -62.335689)
			(xy 176.284815 -62.326776) (xy 176.29124 -62.319916) (xy 176.360074 -62.24016) (xy 176.364646 -62.211966)
			(xy 176.359058 -62.198504) (xy 176.349747 -62.175114) (xy 176.336622 -62.126514) (xy 176.329999 -62.076609)
			(xy 176.329594 -62.051438) (xy 176.33008 -62.024187) (xy 176.337836 -61.970239) (xy 176.353191 -61.917944)
			(xy 176.375833 -61.868367) (xy 176.405299 -61.822517) (xy 176.44099 -61.781326) (xy 176.482181 -61.745635)
			(xy 176.528031 -61.716169) (xy 176.577608 -61.693527) (xy 176.629903 -61.678172) (xy 176.683851 -61.670416)
			(xy 176.738353 -61.670416) (xy 176.792301 -61.678172) (xy 176.844596 -61.693527) (xy 176.894173 -61.716169)
			(xy 176.940023 -61.745635) (xy 176.981214 -61.781326) (xy 177.016905 -61.822517) (xy 177.046371 -61.868367)
			(xy 177.069013 -61.917944) (xy 177.084368 -61.970239) (xy 177.092124 -62.024187) (xy 177.09261 -62.051438)
			(xy 177.092158 -62.07869) (xy 177.086066 -62.121034) (xy 198.342248 -62.121034) (xy 198.346319 -62.065412)
			(xy 198.358445 -62.010975) (xy 198.378368 -61.958884) (xy 198.405664 -61.910249) (xy 198.43975 -61.866106)
			(xy 198.479899 -61.827397) (xy 198.525257 -61.794946) (xy 198.574857 -61.769445) (xy 198.627641 -61.751438)
			(xy 198.682484 -61.741308) (xy 198.738218 -61.739271) (xy 198.793655 -61.745371) (xy 198.847612 -61.759477)
			(xy 198.898941 -61.781289) (xy 198.946547 -61.810343) (xy 198.989415 -61.846018) (xy 199.026632 -61.887555)
			(xy 199.057405 -61.934068) (xy 199.081077 -61.984565) (xy 199.097145 -62.037972) (xy 199.105265 -62.093148)
			(xy 199.105774 -62.121034) (xy 199.105265 -62.14892) (xy 199.097145 -62.204096) (xy 199.081077 -62.257503)
			(xy 199.057405 -62.308) (xy 199.026632 -62.354513) (xy 198.989415 -62.39605) (xy 198.946547 -62.431725)
			(xy 198.898941 -62.460779) (xy 198.847612 -62.482591) (xy 198.793655 -62.496697) (xy 198.738218 -62.502797)
			(xy 198.682484 -62.50076) (xy 198.627641 -62.49063) (xy 198.574857 -62.472623) (xy 198.525257 -62.447122)
			(xy 198.479899 -62.414671) (xy 198.43975 -62.375962) (xy 198.405664 -62.331819) (xy 198.378368 -62.283184)
			(xy 198.358445 -62.231093) (xy 198.346319 -62.176656) (xy 198.342248 -62.121034) (xy 177.086066 -62.121034)
			(xy 177.084396 -62.132639) (xy 177.069036 -62.184934) (xy 177.046391 -62.234511) (xy 177.016921 -62.280361)
			(xy 176.981226 -62.321551) (xy 176.940033 -62.357242) (xy 176.89418 -62.386708) (xy 176.8446 -62.409349)
			(xy 176.792304 -62.424704) (xy 176.738354 -62.43246) (xy 176.711102 -62.432946) (xy 176.687548 -62.432565)
			(xy 176.640803 -62.426708) (xy 176.617884 -62.421262) (xy 176.608672 -62.419353) (xy 176.59002 -62.421692)
			(xy 176.573472 -62.430613) (xy 176.567084 -62.437518) (xy 176.49825 -62.517274) (xy 176.493678 -62.545468)
			(xy 176.499266 -62.55893) (xy 176.508588 -62.582315) (xy 176.521709 -62.630918) (xy 176.528327 -62.680824)
			(xy 176.52873 -62.705996) (xy 176.528219 -62.733246) (xy 176.520463 -62.787192) (xy 176.50511 -62.839485)
			(xy 176.482471 -62.88906) (xy 176.453007 -62.93491) (xy 176.417318 -62.9761) (xy 176.376131 -63.011791)
			(xy 176.330283 -63.041258) (xy 176.280709 -63.063901) (xy 176.228417 -63.079258) (xy 176.174472 -63.087017)
			(xy 176.147222 -63.087504) (xy 176.118414 -63.086945) (xy 176.061454 -63.078273) (xy 176.006445 -63.061139)
			(xy 175.954636 -63.035931) (xy 175.907204 -63.003222) (xy 175.885856 -62.983872) (xy 175.87722 -62.975744)
			(xy 175.855376 -62.968886) (xy 175.76546 -62.981332) (xy 175.754104 -62.983456) (xy 175.734917 -62.996278)
			(xy 175.72863 -63.00597) (xy 175.713792 -63.030075) (xy 175.678145 -63.074041) (xy 175.636395 -63.112259)
			(xy 175.589458 -63.143893) (xy 175.538365 -63.168248) (xy 175.484234 -63.184791) (xy 175.428255 -63.193158)
			(xy 175.399954 -63.193676) (xy 175.372703 -63.193251) (xy 175.318755 -63.185489) (xy 175.266462 -63.170128)
			(xy 175.216886 -63.147482) (xy 175.171038 -63.118012) (xy 175.129849 -63.082318) (xy 175.09416 -63.041125)
			(xy 175.064695 -62.995273) (xy 175.042056 -62.945695) (xy 175.026702 -62.8934) (xy 175.018946 -62.839451)
			(xy 170.18749 -62.839451) (xy 170.19941 -62.852755) (xy 170.230183 -62.899268) (xy 170.253855 -62.949765)
			(xy 170.269923 -63.003172) (xy 170.278043 -63.058348) (xy 170.278552 -63.086234) (xy 170.278043 -63.11412)
			(xy 170.269923 -63.169296) (xy 170.253855 -63.222703) (xy 170.230183 -63.2732) (xy 170.23003 -63.273432)
			(xy 171.67682 -63.273432) (xy 171.680891 -63.21781) (xy 171.693017 -63.163373) (xy 171.71294 -63.111282)
			(xy 171.740236 -63.062647) (xy 171.774322 -63.018504) (xy 171.814471 -62.979795) (xy 171.859829 -62.947344)
			(xy 171.909429 -62.921843) (xy 171.962213 -62.903836) (xy 172.017056 -62.893706) (xy 172.07279 -62.891669)
			(xy 172.128227 -62.897769) (xy 172.182184 -62.911875) (xy 172.233513 -62.933687) (xy 172.281119 -62.962741)
			(xy 172.323987 -62.998416) (xy 172.361204 -63.039953) (xy 172.391977 -63.086466) (xy 172.415649 -63.136963)
			(xy 172.431717 -63.19037) (xy 172.439837 -63.245546) (xy 172.439837 -63.245552) (xy 185.204569 -63.245552)
			(xy 185.204569 -63.191048) (xy 185.212326 -63.137098) (xy 185.227682 -63.084802) (xy 185.250324 -63.035223)
			(xy 185.279792 -62.989371) (xy 185.315485 -62.94818) (xy 185.356677 -62.912487) (xy 185.40253 -62.88302)
			(xy 185.452109 -62.860379) (xy 185.504406 -62.845025) (xy 185.558356 -62.837269) (xy 185.585608 -62.836806)
			(xy 185.612978 -62.837266) (xy 185.667158 -62.845085) (xy 185.719661 -62.860575) (xy 185.769408 -62.883419)
			(xy 185.815374 -62.913144) (xy 185.836306 -62.930786) (xy 185.83656 -62.93104) (xy 185.84365 -62.936621)
			(xy 185.860564 -62.94287) (xy 185.86958 -62.943232) (xy 185.936636 -62.943232) (xy 185.945654 -62.942885)
			(xy 185.96257 -62.93663) (xy 185.969656 -62.93104) (xy 185.970164 -62.930532) (xy 185.99111 -62.912934)
			(xy 186.037074 -62.883271) (xy 186.086806 -62.860481) (xy 186.139285 -62.845032) (xy 186.193432 -62.837241)
			(xy 186.248138 -62.837267) (xy 186.302278 -62.845111) (xy 186.354741 -62.860611) (xy 186.404451 -62.88345)
			(xy 186.450387 -62.913157) (xy 186.471306 -62.930786) (xy 186.47156 -62.93104) (xy 186.47865 -62.936621)
			(xy 186.495564 -62.94287) (xy 186.50458 -62.943232) (xy 186.571636 -62.943232) (xy 186.580654 -62.942885)
			(xy 186.59757 -62.93663) (xy 186.604656 -62.93104) (xy 186.605164 -62.930532) (xy 186.626097 -62.912948)
			(xy 186.672031 -62.883307) (xy 186.721727 -62.860529) (xy 186.774166 -62.845079) (xy 186.828274 -62.837275)
			(xy 186.855608 -62.836806) (xy 186.88286 -62.837264) (xy 186.936809 -62.845022) (xy 186.989104 -62.860378)
			(xy 187.038682 -62.883021) (xy 187.084534 -62.912488) (xy 187.125724 -62.948181) (xy 187.161416 -62.989373)
			(xy 187.190883 -63.035225) (xy 187.213524 -63.084803) (xy 187.213944 -63.086234) (xy 195.487542 -63.086234)
			(xy 195.491613 -63.030612) (xy 195.503739 -62.976175) (xy 195.523662 -62.924084) (xy 195.550958 -62.875449)
			(xy 195.585044 -62.831306) (xy 195.625193 -62.792597) (xy 195.670551 -62.760146) (xy 195.720151 -62.734645)
			(xy 195.772935 -62.716638) (xy 195.827778 -62.706508) (xy 195.883512 -62.704471) (xy 195.938949 -62.710571)
			(xy 195.992906 -62.724677) (xy 196.044235 -62.746489) (xy 196.091841 -62.775543) (xy 196.134709 -62.811218)
			(xy 196.160009 -62.839455) (xy 201.018823 -62.839455) (xy 201.018823 -62.784945) (xy 201.026581 -62.730989)
			(xy 201.041938 -62.678687) (xy 201.064583 -62.629102) (xy 201.094053 -62.583245) (xy 201.12975 -62.542049)
			(xy 201.170947 -62.506352) (xy 201.216804 -62.476882) (xy 201.266388 -62.454237) (xy 201.318691 -62.43888)
			(xy 201.372647 -62.431123) (xy 201.399902 -62.43066) (xy 201.428711 -62.431187) (xy 201.485673 -62.439864)
			(xy 201.540684 -62.457005) (xy 201.592492 -62.48222) (xy 201.639922 -62.514937) (xy 201.661268 -62.534292)
			(xy 201.669904 -62.54242) (xy 201.691748 -62.549278) (xy 201.781664 -62.536832) (xy 201.793028 -62.534735)
			(xy 201.812212 -62.521894) (xy 201.818494 -62.512194) (xy 201.833302 -62.48807) (xy 201.868956 -62.444106)
			(xy 201.910712 -62.40589) (xy 201.957653 -62.374259) (xy 202.008751 -62.349907) (xy 202.062885 -62.333368)
			(xy 202.118868 -62.325004) (xy 202.14717 -62.324488) (xy 202.170724 -62.324873) (xy 202.217469 -62.330727)
			(xy 202.240388 -62.336172) (xy 202.249608 -62.337989) (xy 202.268233 -62.335663) (xy 202.284761 -62.326768)
			(xy 202.291188 -62.319916) (xy 202.360022 -62.24016) (xy 202.364594 -62.211966) (xy 202.359006 -62.198504)
			(xy 202.349693 -62.175115) (xy 202.336569 -62.126514) (xy 202.329947 -62.076609) (xy 202.329542 -62.051438)
			(xy 202.330028 -62.024187) (xy 202.337784 -61.970239) (xy 202.353139 -61.917944) (xy 202.375781 -61.868367)
			(xy 202.405247 -61.822517) (xy 202.440938 -61.781326) (xy 202.482129 -61.745635) (xy 202.527979 -61.716169)
			(xy 202.577556 -61.693527) (xy 202.629851 -61.678172) (xy 202.683799 -61.670416) (xy 202.738301 -61.670416)
			(xy 202.792249 -61.678172) (xy 202.844544 -61.693527) (xy 202.894121 -61.716169) (xy 202.939971 -61.745635)
			(xy 202.972202 -61.773562) (xy 226.029264 -61.773562) (xy 226.033335 -61.71794) (xy 226.045461 -61.663503)
			(xy 226.065384 -61.611412) (xy 226.09268 -61.562777) (xy 226.126766 -61.518634) (xy 226.166915 -61.479925)
			(xy 226.212273 -61.447474) (xy 226.261873 -61.421973) (xy 226.314657 -61.403966) (xy 226.3695 -61.393836)
			(xy 226.425234 -61.391799) (xy 226.480671 -61.397899) (xy 226.534628 -61.412005) (xy 226.585957 -61.433817)
			(xy 226.633563 -61.462871) (xy 226.676431 -61.498546) (xy 226.713648 -61.540083) (xy 226.744421 -61.586596)
			(xy 226.768093 -61.637093) (xy 226.784161 -61.6905) (xy 226.792281 -61.745676) (xy 226.79279 -61.773562)
			(xy 226.792308 -61.799978) (xy 227.210618 -61.799978) (xy 227.214689 -61.744356) (xy 227.226815 -61.689919)
			(xy 227.246738 -61.637828) (xy 227.274034 -61.589193) (xy 227.30812 -61.54505) (xy 227.348269 -61.506341)
			(xy 227.393627 -61.47389) (xy 227.443227 -61.448389) (xy 227.496011 -61.430382) (xy 227.550854 -61.420252)
			(xy 227.606588 -61.418215) (xy 227.662025 -61.424315) (xy 227.715982 -61.438421) (xy 227.767311 -61.460233)
			(xy 227.814917 -61.489287) (xy 227.857785 -61.524962) (xy 227.895002 -61.566499) (xy 227.925775 -61.613012)
			(xy 227.949447 -61.663509) (xy 227.965515 -61.716916) (xy 227.973635 -61.772092) (xy 227.974144 -61.799978)
			(xy 231.00614 -61.799978) (xy 231.010211 -61.744356) (xy 231.022337 -61.689919) (xy 231.04226 -61.637828)
			(xy 231.069556 -61.589193) (xy 231.103642 -61.54505) (xy 231.143791 -61.506341) (xy 231.189149 -61.47389)
			(xy 231.238749 -61.448389) (xy 231.291533 -61.430382) (xy 231.346376 -61.420252) (xy 231.40211 -61.418215)
			(xy 231.457547 -61.424315) (xy 231.511504 -61.438421) (xy 231.562833 -61.460233) (xy 231.610439 -61.489287)
			(xy 231.653307 -61.524962) (xy 231.690524 -61.566499) (xy 231.703331 -61.585856) (xy 240.609372 -61.585856)
			(xy 240.613443 -61.530234) (xy 240.625569 -61.475797) (xy 240.645492 -61.423706) (xy 240.672788 -61.375071)
			(xy 240.706874 -61.330928) (xy 240.747023 -61.292219) (xy 240.792381 -61.259768) (xy 240.841981 -61.234267)
			(xy 240.894765 -61.21626) (xy 240.949608 -61.20613) (xy 241.005342 -61.204093) (xy 241.060779 -61.210193)
			(xy 241.114736 -61.224299) (xy 241.166065 -61.246111) (xy 241.213671 -61.275165) (xy 241.256539 -61.31084)
			(xy 241.293756 -61.352377) (xy 241.324529 -61.39889) (xy 241.348201 -61.449387) (xy 241.359762 -61.487812)
			(xy 264.504422 -61.487812) (xy 264.508493 -61.43219) (xy 264.520619 -61.377753) (xy 264.540542 -61.325662)
			(xy 264.567838 -61.277027) (xy 264.601924 -61.232884) (xy 264.642073 -61.194175) (xy 264.687431 -61.161724)
			(xy 264.737031 -61.136223) (xy 264.789815 -61.118216) (xy 264.844658 -61.108086) (xy 264.900392 -61.106049)
			(xy 264.955829 -61.112149) (xy 265.009786 -61.126255) (xy 265.061115 -61.148067) (xy 265.108721 -61.177121)
			(xy 265.151589 -61.212796) (xy 265.188806 -61.254333) (xy 265.219579 -61.300846) (xy 265.243251 -61.351343)
			(xy 265.259319 -61.40475) (xy 265.267439 -61.459926) (xy 265.267948 -61.487812) (xy 290.50437 -61.487812)
			(xy 290.508441 -61.43219) (xy 290.520567 -61.377753) (xy 290.54049 -61.325662) (xy 290.567786 -61.277027)
			(xy 290.601872 -61.232884) (xy 290.642021 -61.194175) (xy 290.687379 -61.161724) (xy 290.736979 -61.136223)
			(xy 290.789763 -61.118216) (xy 290.844606 -61.108086) (xy 290.90034 -61.106049) (xy 290.955777 -61.112149)
			(xy 291.009734 -61.126255) (xy 291.061063 -61.148067) (xy 291.108669 -61.177121) (xy 291.151537 -61.212796)
			(xy 291.188754 -61.254333) (xy 291.219527 -61.300846) (xy 291.243199 -61.351343) (xy 291.259267 -61.40475)
			(xy 291.267387 -61.459926) (xy 291.267896 -61.487812) (xy 316.504318 -61.487812) (xy 316.508389 -61.43219)
			(xy 316.520515 -61.377753) (xy 316.540438 -61.325662) (xy 316.567734 -61.277027) (xy 316.60182 -61.232884)
			(xy 316.641969 -61.194175) (xy 316.687327 -61.161724) (xy 316.736927 -61.136223) (xy 316.789711 -61.118216)
			(xy 316.844554 -61.108086) (xy 316.900288 -61.106049) (xy 316.955725 -61.112149) (xy 317.009682 -61.126255)
			(xy 317.061011 -61.148067) (xy 317.108617 -61.177121) (xy 317.151485 -61.212796) (xy 317.188702 -61.254333)
			(xy 317.219475 -61.300846) (xy 317.243147 -61.351343) (xy 317.259215 -61.40475) (xy 317.267335 -61.459926)
			(xy 317.267844 -61.487812) (xy 354.604572 -61.487812) (xy 354.608643 -61.43219) (xy 354.620769 -61.377753)
			(xy 354.640692 -61.325662) (xy 354.667988 -61.277027) (xy 354.702074 -61.232884) (xy 354.742223 -61.194175)
			(xy 354.787581 -61.161724) (xy 354.837181 -61.136223) (xy 354.889965 -61.118216) (xy 354.944808 -61.108086)
			(xy 355.000542 -61.106049) (xy 355.055979 -61.112149) (xy 355.109936 -61.126255) (xy 355.161265 -61.148067)
			(xy 355.208871 -61.177121) (xy 355.251739 -61.212796) (xy 355.288956 -61.254333) (xy 355.319729 -61.300846)
			(xy 355.343401 -61.351343) (xy 355.359469 -61.40475) (xy 355.367589 -61.459926) (xy 355.368098 -61.487812)
			(xy 380.60452 -61.487812) (xy 380.608591 -61.43219) (xy 380.620717 -61.377753) (xy 380.64064 -61.325662)
			(xy 380.667936 -61.277027) (xy 380.702022 -61.232884) (xy 380.742171 -61.194175) (xy 380.787529 -61.161724)
			(xy 380.837129 -61.136223) (xy 380.889913 -61.118216) (xy 380.944756 -61.108086) (xy 381.00049 -61.106049)
			(xy 381.055927 -61.112149) (xy 381.109884 -61.126255) (xy 381.161213 -61.148067) (xy 381.208819 -61.177121)
			(xy 381.251687 -61.212796) (xy 381.288904 -61.254333) (xy 381.319677 -61.300846) (xy 381.343349 -61.351343)
			(xy 381.359417 -61.40475) (xy 381.367537 -61.459926) (xy 381.368046 -61.487812) (xy 406.604468 -61.487812)
			(xy 406.608539 -61.43219) (xy 406.620665 -61.377753) (xy 406.640588 -61.325662) (xy 406.667884 -61.277027)
			(xy 406.70197 -61.232884) (xy 406.742119 -61.194175) (xy 406.787477 -61.161724) (xy 406.837077 -61.136223)
			(xy 406.889861 -61.118216) (xy 406.944704 -61.108086) (xy 407.000438 -61.106049) (xy 407.055875 -61.112149)
			(xy 407.109832 -61.126255) (xy 407.161161 -61.148067) (xy 407.208767 -61.177121) (xy 407.251635 -61.212796)
			(xy 407.288852 -61.254333) (xy 407.319625 -61.300846) (xy 407.343297 -61.351343) (xy 407.359365 -61.40475)
			(xy 407.367485 -61.459926) (xy 407.367994 -61.487812) (xy 432.604416 -61.487812) (xy 432.608487 -61.43219)
			(xy 432.620613 -61.377753) (xy 432.640536 -61.325662) (xy 432.667832 -61.277027) (xy 432.701918 -61.232884)
			(xy 432.742067 -61.194175) (xy 432.787425 -61.161724) (xy 432.837025 -61.136223) (xy 432.889809 -61.118216)
			(xy 432.944652 -61.108086) (xy 433.000386 -61.106049) (xy 433.055823 -61.112149) (xy 433.10978 -61.126255)
			(xy 433.161109 -61.148067) (xy 433.208715 -61.177121) (xy 433.251583 -61.212796) (xy 433.2888 -61.254333)
			(xy 433.319573 -61.300846) (xy 433.343245 -61.351343) (xy 433.359313 -61.40475) (xy 433.367433 -61.459926)
			(xy 433.367942 -61.487812) (xy 433.367433 -61.515698) (xy 433.359313 -61.570874) (xy 433.343245 -61.624281)
			(xy 433.319573 -61.674778) (xy 433.2888 -61.721291) (xy 433.251583 -61.762828) (xy 433.208715 -61.798503)
			(xy 433.161109 -61.827557) (xy 433.10978 -61.849369) (xy 433.055823 -61.863475) (xy 433.000386 -61.869575)
			(xy 432.944652 -61.867538) (xy 432.889809 -61.857408) (xy 432.837025 -61.839401) (xy 432.787425 -61.8139)
			(xy 432.742067 -61.781449) (xy 432.701918 -61.74274) (xy 432.667832 -61.698597) (xy 432.640536 -61.649962)
			(xy 432.620613 -61.597871) (xy 432.608487 -61.543434) (xy 432.604416 -61.487812) (xy 407.367994 -61.487812)
			(xy 407.367485 -61.515698) (xy 407.359365 -61.570874) (xy 407.343297 -61.624281) (xy 407.319625 -61.674778)
			(xy 407.288852 -61.721291) (xy 407.251635 -61.762828) (xy 407.208767 -61.798503) (xy 407.161161 -61.827557)
			(xy 407.109832 -61.849369) (xy 407.055875 -61.863475) (xy 407.000438 -61.869575) (xy 406.944704 -61.867538)
			(xy 406.889861 -61.857408) (xy 406.837077 -61.839401) (xy 406.787477 -61.8139) (xy 406.742119 -61.781449)
			(xy 406.70197 -61.74274) (xy 406.667884 -61.698597) (xy 406.640588 -61.649962) (xy 406.620665 -61.597871)
			(xy 406.608539 -61.543434) (xy 406.604468 -61.487812) (xy 381.368046 -61.487812) (xy 381.367537 -61.515698)
			(xy 381.359417 -61.570874) (xy 381.343349 -61.624281) (xy 381.319677 -61.674778) (xy 381.288904 -61.721291)
			(xy 381.251687 -61.762828) (xy 381.208819 -61.798503) (xy 381.161213 -61.827557) (xy 381.109884 -61.849369)
			(xy 381.055927 -61.863475) (xy 381.00049 -61.869575) (xy 380.944756 -61.867538) (xy 380.889913 -61.857408)
			(xy 380.837129 -61.839401) (xy 380.787529 -61.8139) (xy 380.742171 -61.781449) (xy 380.702022 -61.74274)
			(xy 380.667936 -61.698597) (xy 380.64064 -61.649962) (xy 380.620717 -61.597871) (xy 380.608591 -61.543434)
			(xy 380.60452 -61.487812) (xy 355.368098 -61.487812) (xy 355.367589 -61.515698) (xy 355.359469 -61.570874)
			(xy 355.343401 -61.624281) (xy 355.319729 -61.674778) (xy 355.288956 -61.721291) (xy 355.251739 -61.762828)
			(xy 355.208871 -61.798503) (xy 355.161265 -61.827557) (xy 355.109936 -61.849369) (xy 355.055979 -61.863475)
			(xy 355.000542 -61.869575) (xy 354.944808 -61.867538) (xy 354.889965 -61.857408) (xy 354.837181 -61.839401)
			(xy 354.787581 -61.8139) (xy 354.742223 -61.781449) (xy 354.702074 -61.74274) (xy 354.667988 -61.698597)
			(xy 354.640692 -61.649962) (xy 354.620769 -61.597871) (xy 354.608643 -61.543434) (xy 354.604572 -61.487812)
			(xy 317.267844 -61.487812) (xy 317.267335 -61.515698) (xy 317.259215 -61.570874) (xy 317.243147 -61.624281)
			(xy 317.219475 -61.674778) (xy 317.188702 -61.721291) (xy 317.151485 -61.762828) (xy 317.108617 -61.798503)
			(xy 317.061011 -61.827557) (xy 317.009682 -61.849369) (xy 316.955725 -61.863475) (xy 316.900288 -61.869575)
			(xy 316.844554 -61.867538) (xy 316.789711 -61.857408) (xy 316.736927 -61.839401) (xy 316.687327 -61.8139)
			(xy 316.641969 -61.781449) (xy 316.60182 -61.74274) (xy 316.567734 -61.698597) (xy 316.540438 -61.649962)
			(xy 316.520515 -61.597871) (xy 316.508389 -61.543434) (xy 316.504318 -61.487812) (xy 291.267896 -61.487812)
			(xy 291.267387 -61.515698) (xy 291.259267 -61.570874) (xy 291.243199 -61.624281) (xy 291.219527 -61.674778)
			(xy 291.188754 -61.721291) (xy 291.151537 -61.762828) (xy 291.108669 -61.798503) (xy 291.061063 -61.827557)
			(xy 291.009734 -61.849369) (xy 290.955777 -61.863475) (xy 290.90034 -61.869575) (xy 290.844606 -61.867538)
			(xy 290.789763 -61.857408) (xy 290.736979 -61.839401) (xy 290.687379 -61.8139) (xy 290.642021 -61.781449)
			(xy 290.601872 -61.74274) (xy 290.567786 -61.698597) (xy 290.54049 -61.649962) (xy 290.520567 -61.597871)
			(xy 290.508441 -61.543434) (xy 290.50437 -61.487812) (xy 265.267948 -61.487812) (xy 265.267439 -61.515698)
			(xy 265.259319 -61.570874) (xy 265.243251 -61.624281) (xy 265.219579 -61.674778) (xy 265.188806 -61.721291)
			(xy 265.151589 -61.762828) (xy 265.108721 -61.798503) (xy 265.061115 -61.827557) (xy 265.009786 -61.849369)
			(xy 264.955829 -61.863475) (xy 264.900392 -61.869575) (xy 264.844658 -61.867538) (xy 264.789815 -61.857408)
			(xy 264.737031 -61.839401) (xy 264.687431 -61.8139) (xy 264.642073 -61.781449) (xy 264.601924 -61.74274)
			(xy 264.567838 -61.698597) (xy 264.540542 -61.649962) (xy 264.520619 -61.597871) (xy 264.508493 -61.543434)
			(xy 264.504422 -61.487812) (xy 241.359762 -61.487812) (xy 241.364269 -61.502794) (xy 241.372389 -61.55797)
			(xy 241.372898 -61.585856) (xy 241.372389 -61.613742) (xy 241.364269 -61.668918) (xy 241.348201 -61.722325)
			(xy 241.324529 -61.772822) (xy 241.293756 -61.819335) (xy 241.256539 -61.860872) (xy 241.213671 -61.896547)
			(xy 241.166065 -61.925601) (xy 241.114736 -61.947413) (xy 241.060779 -61.961519) (xy 241.005342 -61.967619)
			(xy 240.949608 -61.965582) (xy 240.894765 -61.955452) (xy 240.841981 -61.937445) (xy 240.792381 -61.911944)
			(xy 240.747023 -61.879493) (xy 240.706874 -61.840784) (xy 240.672788 -61.796641) (xy 240.645492 -61.748006)
			(xy 240.625569 -61.695915) (xy 240.613443 -61.641478) (xy 240.609372 -61.585856) (xy 231.703331 -61.585856)
			(xy 231.721297 -61.613012) (xy 231.744969 -61.663509) (xy 231.761037 -61.716916) (xy 231.769157 -61.772092)
			(xy 231.769666 -61.799978) (xy 231.769157 -61.827864) (xy 231.761037 -61.88304) (xy 231.744969 -61.936447)
			(xy 231.721297 -61.986944) (xy 231.690524 -62.033457) (xy 231.653307 -62.074994) (xy 231.610439 -62.110669)
			(xy 231.562833 -62.139723) (xy 231.511504 -62.161535) (xy 231.457547 -62.175641) (xy 231.40211 -62.181741)
			(xy 231.346376 -62.179704) (xy 231.291533 -62.169574) (xy 231.238749 -62.151567) (xy 231.189149 -62.126066)
			(xy 231.143791 -62.093615) (xy 231.103642 -62.054906) (xy 231.069556 -62.010763) (xy 231.04226 -61.962128)
			(xy 231.022337 -61.910037) (xy 231.010211 -61.8556) (xy 231.00614 -61.799978) (xy 227.974144 -61.799978)
			(xy 227.973635 -61.827864) (xy 227.965515 -61.88304) (xy 227.949447 -61.936447) (xy 227.925775 -61.986944)
			(xy 227.895002 -62.033457) (xy 227.857785 -62.074994) (xy 227.814917 -62.110669) (xy 227.767311 -62.139723)
			(xy 227.715982 -62.161535) (xy 227.662025 -62.175641) (xy 227.606588 -62.181741) (xy 227.550854 -62.179704)
			(xy 227.496011 -62.169574) (xy 227.443227 -62.151567) (xy 227.393627 -62.126066) (xy 227.348269 -62.093615)
			(xy 227.30812 -62.054906) (xy 227.274034 -62.010763) (xy 227.246738 -61.962128) (xy 227.226815 -61.910037)
			(xy 227.214689 -61.8556) (xy 227.210618 -61.799978) (xy 226.792308 -61.799978) (xy 226.792281 -61.801448)
			(xy 226.784161 -61.856624) (xy 226.768093 -61.910031) (xy 226.744421 -61.960528) (xy 226.713648 -62.007041)
			(xy 226.676431 -62.048578) (xy 226.633563 -62.084253) (xy 226.585957 -62.113307) (xy 226.534628 -62.135119)
			(xy 226.480671 -62.149225) (xy 226.425234 -62.155325) (xy 226.3695 -62.153288) (xy 226.314657 -62.143158)
			(xy 226.261873 -62.125151) (xy 226.212273 -62.09965) (xy 226.166915 -62.067199) (xy 226.126766 -62.02849)
			(xy 226.09268 -61.984347) (xy 226.065384 -61.935712) (xy 226.045461 -61.883621) (xy 226.033335 -61.829184)
			(xy 226.029264 -61.773562) (xy 202.972202 -61.773562) (xy 202.981162 -61.781326) (xy 203.016853 -61.822517)
			(xy 203.046319 -61.868367) (xy 203.068961 -61.917944) (xy 203.084316 -61.970239) (xy 203.092072 -62.024187)
			(xy 203.092558 -62.051438) (xy 203.09218 -62.078694) (xy 203.084417 -62.132651) (xy 203.069053 -62.184953)
			(xy 203.046403 -62.234537) (xy 203.016926 -62.280392) (xy 202.981224 -62.321586) (xy 202.940022 -62.357279)
			(xy 202.89416 -62.386745) (xy 202.865288 -62.399926) (xy 227.926136 -62.399926) (xy 227.930207 -62.344304)
			(xy 227.942333 -62.289867) (xy 227.962256 -62.237776) (xy 227.989552 -62.189141) (xy 228.023638 -62.144998)
			(xy 228.063787 -62.106289) (xy 228.109145 -62.073838) (xy 228.158745 -62.048337) (xy 228.211529 -62.03033)
			(xy 228.266372 -62.0202) (xy 228.322106 -62.018163) (xy 228.377543 -62.024263) (xy 228.4315 -62.038369)
			(xy 228.482829 -62.060181) (xy 228.530435 -62.089235) (xy 228.573303 -62.12491) (xy 228.61052 -62.166447)
			(xy 228.641293 -62.21296) (xy 228.664965 -62.263457) (xy 228.681033 -62.316864) (xy 228.689153 -62.37204)
			(xy 228.689662 -62.399926) (xy 233.19054 -62.399926) (xy 233.194611 -62.344304) (xy 233.206737 -62.289867)
			(xy 233.22666 -62.237776) (xy 233.253956 -62.189141) (xy 233.288042 -62.144998) (xy 233.328191 -62.106289)
			(xy 233.373549 -62.073838) (xy 233.423149 -62.048337) (xy 233.475933 -62.03033) (xy 233.530776 -62.0202)
			(xy 233.58651 -62.018163) (xy 233.641947 -62.024263) (xy 233.695904 -62.038369) (xy 233.747233 -62.060181)
			(xy 233.794839 -62.089235) (xy 233.837707 -62.12491) (xy 233.874924 -62.166447) (xy 233.905697 -62.21296)
			(xy 233.929369 -62.263457) (xy 233.945437 -62.316864) (xy 233.951605 -62.358778) (xy 236.702344 -62.358778)
			(xy 236.706415 -62.303156) (xy 236.718541 -62.248719) (xy 236.738464 -62.196628) (xy 236.76576 -62.147993)
			(xy 236.799846 -62.10385) (xy 236.839995 -62.065141) (xy 236.885353 -62.03269) (xy 236.934953 -62.007189)
			(xy 236.987737 -61.989182) (xy 237.04258 -61.979052) (xy 237.098314 -61.977015) (xy 237.153751 -61.983115)
			(xy 237.207708 -61.997221) (xy 237.259037 -62.019033) (xy 237.306643 -62.048087) (xy 237.349511 -62.083762)
			(xy 237.386728 -62.125299) (xy 237.417501 -62.171812) (xy 237.441173 -62.222309) (xy 237.457241 -62.275716)
			(xy 237.465361 -62.330892) (xy 237.46587 -62.358778) (xy 237.465361 -62.386664) (xy 237.461989 -62.409578)
			(xy 238.418114 -62.409578) (xy 238.422185 -62.353956) (xy 238.434311 -62.299519) (xy 238.454234 -62.247428)
			(xy 238.48153 -62.198793) (xy 238.515616 -62.15465) (xy 238.555765 -62.115941) (xy 238.601123 -62.08349)
			(xy 238.650723 -62.057989) (xy 238.703507 -62.039982) (xy 238.75835 -62.029852) (xy 238.814084 -62.027815)
			(xy 238.869521 -62.033915) (xy 238.923478 -62.048021) (xy 238.974807 -62.069833) (xy 239.022413 -62.098887)
			(xy 239.049025 -62.121034) (xy 262.442196 -62.121034) (xy 262.446267 -62.065412) (xy 262.458393 -62.010975)
			(xy 262.478316 -61.958884) (xy 262.505612 -61.910249) (xy 262.539698 -61.866106) (xy 262.579847 -61.827397)
			(xy 262.625205 -61.794946) (xy 262.674805 -61.769445) (xy 262.727589 -61.751438) (xy 262.782432 -61.741308)
			(xy 262.838166 -61.739271) (xy 262.893603 -61.745371) (xy 262.94756 -61.759477) (xy 262.998889 -61.781289)
			(xy 263.046495 -61.810343) (xy 263.089363 -61.846018) (xy 263.12658 -61.887555) (xy 263.157353 -61.934068)
			(xy 263.181025 -61.984565) (xy 263.197093 -62.037972) (xy 263.205213 -62.093148) (xy 263.205722 -62.121034)
			(xy 263.205213 -62.14892) (xy 263.197093 -62.204096) (xy 263.181025 -62.257503) (xy 263.157353 -62.308)
			(xy 263.12658 -62.354513) (xy 263.089363 -62.39605) (xy 263.046495 -62.431725) (xy 262.998889 -62.460779)
			(xy 262.94756 -62.482591) (xy 262.893603 -62.496697) (xy 262.838166 -62.502797) (xy 262.782432 -62.50076)
			(xy 262.727589 -62.49063) (xy 262.674805 -62.472623) (xy 262.625205 -62.447122) (xy 262.579847 -62.414671)
			(xy 262.539698 -62.375962) (xy 262.505612 -62.331819) (xy 262.478316 -62.283184) (xy 262.458393 -62.231093)
			(xy 262.446267 -62.176656) (xy 262.442196 -62.121034) (xy 239.049025 -62.121034) (xy 239.065281 -62.134562)
			(xy 239.102498 -62.176099) (xy 239.133271 -62.222612) (xy 239.156943 -62.273109) (xy 239.173011 -62.326516)
			(xy 239.181131 -62.381692) (xy 239.18164 -62.409578) (xy 239.181131 -62.437464) (xy 239.173011 -62.49264)
			(xy 239.156943 -62.546047) (xy 239.133271 -62.596544) (xy 239.102498 -62.643057) (xy 239.065281 -62.684594)
			(xy 239.022413 -62.720269) (xy 238.974807 -62.749323) (xy 238.923478 -62.771135) (xy 238.869521 -62.785241)
			(xy 238.814084 -62.791341) (xy 238.75835 -62.789304) (xy 238.703507 -62.779174) (xy 238.650723 -62.761167)
			(xy 238.601123 -62.735666) (xy 238.555765 -62.703215) (xy 238.515616 -62.664506) (xy 238.48153 -62.620363)
			(xy 238.454234 -62.571728) (xy 238.434311 -62.519637) (xy 238.422185 -62.4652) (xy 238.418114 -62.409578)
			(xy 237.461989 -62.409578) (xy 237.457241 -62.44184) (xy 237.441173 -62.495247) (xy 237.417501 -62.545744)
			(xy 237.386728 -62.592257) (xy 237.349511 -62.633794) (xy 237.306643 -62.669469) (xy 237.259037 -62.698523)
			(xy 237.207708 -62.720335) (xy 237.153751 -62.734441) (xy 237.098314 -62.740541) (xy 237.04258 -62.738504)
			(xy 236.987737 -62.728374) (xy 236.934953 -62.710367) (xy 236.885353 -62.684866) (xy 236.839995 -62.652415)
			(xy 236.799846 -62.613706) (xy 236.76576 -62.569563) (xy 236.738464 -62.520928) (xy 236.718541 -62.468837)
			(xy 236.706415 -62.4144) (xy 236.702344 -62.358778) (xy 233.951605 -62.358778) (xy 233.953557 -62.37204)
			(xy 233.954066 -62.399926) (xy 233.953557 -62.427812) (xy 233.945437 -62.482988) (xy 233.929369 -62.536395)
			(xy 233.905697 -62.586892) (xy 233.874924 -62.633405) (xy 233.837707 -62.674942) (xy 233.794839 -62.710617)
			(xy 233.747233 -62.739671) (xy 233.695904 -62.761483) (xy 233.641947 -62.775589) (xy 233.58651 -62.781689)
			(xy 233.530776 -62.779652) (xy 233.475933 -62.769522) (xy 233.423149 -62.751515) (xy 233.373549 -62.726014)
			(xy 233.328191 -62.693563) (xy 233.288042 -62.654854) (xy 233.253956 -62.610711) (xy 233.22666 -62.562076)
			(xy 233.206737 -62.509985) (xy 233.194611 -62.455548) (xy 233.19054 -62.399926) (xy 228.689662 -62.399926)
			(xy 228.689153 -62.427812) (xy 228.681033 -62.482988) (xy 228.664965 -62.536395) (xy 228.641293 -62.586892)
			(xy 228.61052 -62.633405) (xy 228.573303 -62.674942) (xy 228.530435 -62.710617) (xy 228.482829 -62.739671)
			(xy 228.4315 -62.761483) (xy 228.377543 -62.775589) (xy 228.322106 -62.781689) (xy 228.266372 -62.779652)
			(xy 228.211529 -62.769522) (xy 228.158745 -62.751515) (xy 228.109145 -62.726014) (xy 228.063787 -62.693563)
			(xy 228.023638 -62.654854) (xy 227.989552 -62.610711) (xy 227.962256 -62.562076) (xy 227.942333 -62.509985)
			(xy 227.930207 -62.455548) (xy 227.926136 -62.399926) (xy 202.865288 -62.399926) (xy 202.844571 -62.409384)
			(xy 202.792265 -62.424736) (xy 202.738306 -62.432487) (xy 202.71105 -62.432946) (xy 202.687495 -62.432574)
			(xy 202.640751 -62.426711) (xy 202.617832 -62.421262) (xy 202.608623 -62.419368) (xy 202.589985 -62.421722)
			(xy 202.573455 -62.43065) (xy 202.567032 -62.437518) (xy 202.498198 -62.517274) (xy 202.493626 -62.545468)
			(xy 202.499214 -62.55893) (xy 202.508539 -62.582314) (xy 202.521658 -62.630918) (xy 202.528275 -62.680824)
			(xy 202.528678 -62.705996) (xy 202.528241 -62.73325) (xy 202.520484 -62.787204) (xy 202.505127 -62.839504)
			(xy 202.482482 -62.889086) (xy 202.453012 -62.93494) (xy 202.417315 -62.976134) (xy 202.37612 -63.011828)
			(xy 202.330263 -63.041295) (xy 202.280679 -63.063936) (xy 202.228378 -63.079289) (xy 202.174424 -63.087043)
			(xy 202.14717 -63.087504) (xy 202.118361 -63.086977) (xy 202.0614 -63.078297) (xy 202.00639 -63.061155)
			(xy 201.954581 -63.03594) (xy 201.907151 -63.003225) (xy 201.885804 -62.983872) (xy 201.877168 -62.975744)
			(xy 201.855324 -62.968886) (xy 201.765408 -62.981332) (xy 201.754044 -62.983429) (xy 201.734861 -62.996271)
			(xy 201.728578 -63.00597) (xy 201.713776 -63.030098) (xy 201.678123 -63.074064) (xy 201.636367 -63.112281)
			(xy 201.589424 -63.143913) (xy 201.538324 -63.168264) (xy 201.484189 -63.184801) (xy 201.428205 -63.193162)
			(xy 201.399902 -63.193676) (xy 201.372647 -63.193277) (xy 201.318691 -63.18552) (xy 201.266388 -63.170163)
			(xy 201.216804 -63.147518) (xy 201.170947 -63.118048) (xy 201.12975 -63.082351) (xy 201.094053 -63.041155)
			(xy 201.064583 -62.995298) (xy 201.041938 -62.945713) (xy 201.026581 -62.893411) (xy 201.018823 -62.839455)
			(xy 196.160009 -62.839455) (xy 196.171926 -62.852755) (xy 196.202699 -62.899268) (xy 196.226371 -62.949765)
			(xy 196.242439 -63.003172) (xy 196.250559 -63.058348) (xy 196.251068 -63.086234) (xy 196.250559 -63.11412)
			(xy 196.242439 -63.169296) (xy 196.226371 -63.222703) (xy 196.202699 -63.2732) (xy 196.202546 -63.273432)
			(xy 197.676768 -63.273432) (xy 197.680839 -63.21781) (xy 197.692965 -63.163373) (xy 197.712888 -63.111282)
			(xy 197.740184 -63.062647) (xy 197.77427 -63.018504) (xy 197.814419 -62.979795) (xy 197.859777 -62.947344)
			(xy 197.909377 -62.921843) (xy 197.962161 -62.903836) (xy 198.017004 -62.893706) (xy 198.072738 -62.891669)
			(xy 198.128175 -62.897769) (xy 198.182132 -62.911875) (xy 198.233461 -62.933687) (xy 198.281067 -62.962741)
			(xy 198.323935 -62.998416) (xy 198.361152 -63.039953) (xy 198.391925 -63.086466) (xy 198.415597 -63.136963)
			(xy 198.431665 -63.19037) (xy 198.439785 -63.245546) (xy 198.439785 -63.245548) (xy 211.204592 -63.245548)
			(xy 211.204592 -63.191052) (xy 211.212347 -63.13711) (xy 211.2277 -63.084821) (xy 211.250337 -63.035248)
			(xy 211.279798 -62.989402) (xy 211.315483 -62.948214) (xy 211.356666 -62.912524) (xy 211.40251 -62.883058)
			(xy 211.452079 -62.860415) (xy 211.504367 -62.845057) (xy 211.558308 -62.837295) (xy 211.585556 -62.836806)
			(xy 211.612925 -62.837296) (xy 211.667103 -62.845108) (xy 211.719606 -62.860591) (xy 211.769354 -62.883428)
			(xy 211.815322 -62.913147) (xy 211.836254 -62.930786) (xy 211.836508 -62.93104) (xy 211.843585 -62.936641)
			(xy 211.860509 -62.942878) (xy 211.869528 -62.943232) (xy 211.936584 -62.943232) (xy 211.945599 -62.94286)
			(xy 211.962516 -62.936622) (xy 211.969604 -62.93104) (xy 211.970112 -62.930532) (xy 211.99102 -62.912887)
			(xy 212.036991 -62.883226) (xy 212.086729 -62.860439) (xy 212.139214 -62.844993) (xy 212.193366 -62.837206)
			(xy 212.248076 -62.837238) (xy 212.30222 -62.845088) (xy 212.354686 -62.860594) (xy 212.404398 -62.883439)
			(xy 212.450335 -62.913154) (xy 212.471254 -62.930786) (xy 212.471508 -62.93104) (xy 212.478585 -62.936641)
			(xy 212.495509 -62.942878) (xy 212.504528 -62.943232) (xy 212.571584 -62.943232) (xy 212.580599 -62.94286)
			(xy 212.597516 -62.936622) (xy 212.604604 -62.93104) (xy 212.605112 -62.930532) (xy 212.626026 -62.912925)
			(xy 212.671966 -62.883288) (xy 212.721667 -62.860514) (xy 212.77411 -62.84507) (xy 212.828221 -62.837272)
			(xy 212.855556 -62.836806) (xy 212.882812 -62.837238) (xy 212.93677 -62.84499) (xy 212.989075 -62.860343)
			(xy 213.038662 -62.882984) (xy 213.084523 -62.912452) (xy 213.125722 -62.948147) (xy 213.161422 -62.989342)
			(xy 213.168354 -63.000128) (xy 231.00614 -63.000128) (xy 231.010211 -62.944506) (xy 231.022337 -62.890069)
			(xy 231.04226 -62.837978) (xy 231.069556 -62.789343) (xy 231.103642 -62.7452) (xy 231.143791 -62.706491)
			(xy 231.189149 -62.67404) (xy 231.238749 -62.648539) (xy 231.291533 -62.630532) (xy 231.346376 -62.620402)
			(xy 231.40211 -62.618365) (xy 231.457547 -62.624465) (xy 231.511504 -62.638571) (xy 231.562833 -62.660383)
			(xy 231.610439 -62.689437) (xy 231.653307 -62.725112) (xy 231.690524 -62.766649) (xy 231.721297 -62.813162)
			(xy 231.744969 -62.863659) (xy 231.761037 -62.917066) (xy 231.769157 -62.972242) (xy 231.769666 -63.000128)
			(xy 231.769157 -63.028014) (xy 231.761037 -63.08319) (xy 231.744969 -63.136597) (xy 231.721297 -63.187094)
			(xy 231.690524 -63.233607) (xy 231.653307 -63.275144) (xy 231.610439 -63.310819) (xy 231.562833 -63.339873)
			(xy 231.511504 -63.361685) (xy 231.457547 -63.375791) (xy 231.40211 -63.381891) (xy 231.346376 -63.379854)
			(xy 231.291533 -63.369724) (xy 231.238749 -63.351717) (xy 231.189149 -63.326216) (xy 231.143791 -63.293765)
			(xy 231.103642 -63.255056) (xy 231.069556 -63.210913) (xy 231.04226 -63.162278) (xy 231.022337 -63.110187)
			(xy 231.010211 -63.05575) (xy 231.00614 -63.000128) (xy 213.168354 -63.000128) (xy 213.190895 -63.035199)
			(xy 213.213542 -63.084784) (xy 213.228901 -63.137087) (xy 213.236659 -63.191044) (xy 213.236659 -63.245556)
			(xy 213.228901 -63.299513) (xy 213.213542 -63.351816) (xy 213.190895 -63.401401) (xy 213.161422 -63.447258)
			(xy 213.125722 -63.488453) (xy 213.084523 -63.524148) (xy 213.038662 -63.553616) (xy 212.989075 -63.576257)
			(xy 212.93677 -63.59161) (xy 212.882812 -63.599362) (xy 212.855556 -63.599822) (xy 212.828186 -63.599342)
			(xy 212.774007 -63.591531) (xy 212.721503 -63.576046) (xy 212.671756 -63.553207) (xy 212.625789 -63.523483)
			(xy 212.604858 -63.505842) (xy 212.604604 -63.505588) (xy 212.597521 -63.499996) (xy 212.580602 -63.493753)
			(xy 212.571584 -63.493396) (xy 212.504528 -63.493396) (xy 212.495513 -63.493767) (xy 212.478596 -63.500005)
			(xy 212.471508 -63.505588) (xy 212.471 -63.506096) (xy 212.450082 -63.523728) (xy 212.404112 -63.553387)
			(xy 212.354375 -63.576174) (xy 212.301893 -63.591619) (xy 212.247742 -63.599406) (xy 212.193034 -63.599376)
			(xy 212.138892 -63.591528) (xy 212.086427 -63.576024) (xy 212.036715 -63.553183) (xy 211.990778 -63.523472)
			(xy 211.969858 -63.505842) (xy 211.969604 -63.505588) (xy 211.962521 -63.499996) (xy 211.945602 -63.493753)
			(xy 211.936584 -63.493396) (xy 211.869528 -63.493396) (xy 211.860513 -63.493767) (xy 211.843596 -63.500005)
			(xy 211.836508 -63.505588) (xy 211.836 -63.506096) (xy 211.815085 -63.523701) (xy 211.769145 -63.553338)
			(xy 211.719444 -63.576112) (xy 211.667002 -63.591557) (xy 211.612891 -63.599356) (xy 211.585556 -63.599822)
			(xy 211.558308 -63.599305) (xy 211.504367 -63.591543) (xy 211.452079 -63.576185) (xy 211.40251 -63.553542)
			(xy 211.356666 -63.524076) (xy 211.315483 -63.488386) (xy 211.279798 -63.447198) (xy 211.250337 -63.401352)
			(xy 211.2277 -63.351779) (xy 211.212347 -63.29949) (xy 211.204592 -63.245548) (xy 198.439785 -63.245548)
			(xy 198.440294 -63.273432) (xy 198.439785 -63.301318) (xy 198.431665 -63.356494) (xy 198.415597 -63.409901)
			(xy 198.391925 -63.460398) (xy 198.361152 -63.506911) (xy 198.323935 -63.548448) (xy 198.281067 -63.584123)
			(xy 198.233461 -63.613177) (xy 198.182132 -63.634989) (xy 198.128175 -63.649095) (xy 198.072738 -63.655195)
			(xy 198.017004 -63.653158) (xy 197.962161 -63.643028) (xy 197.909377 -63.625021) (xy 197.859777 -63.59952)
			(xy 197.814419 -63.567069) (xy 197.77427 -63.52836) (xy 197.740184 -63.484217) (xy 197.712888 -63.435582)
			(xy 197.692965 -63.383491) (xy 197.680839 -63.329054) (xy 197.676768 -63.273432) (xy 196.202546 -63.273432)
			(xy 196.171926 -63.319713) (xy 196.134709 -63.36125) (xy 196.091841 -63.396925) (xy 196.044235 -63.425979)
			(xy 195.992906 -63.447791) (xy 195.938949 -63.461897) (xy 195.883512 -63.467997) (xy 195.827778 -63.46596)
			(xy 195.772935 -63.45583) (xy 195.720151 -63.437823) (xy 195.670551 -63.412322) (xy 195.625193 -63.379871)
			(xy 195.585044 -63.341162) (xy 195.550958 -63.297019) (xy 195.523662 -63.248384) (xy 195.503739 -63.196293)
			(xy 195.491613 -63.141856) (xy 195.487542 -63.086234) (xy 187.213944 -63.086234) (xy 187.22888 -63.137099)
			(xy 187.236636 -63.191048) (xy 187.236636 -63.245552) (xy 187.22888 -63.299501) (xy 187.213524 -63.351797)
			(xy 187.190883 -63.401375) (xy 187.161416 -63.447227) (xy 187.125724 -63.488419) (xy 187.084534 -63.524112)
			(xy 187.038682 -63.553579) (xy 186.989104 -63.576222) (xy 186.936809 -63.591578) (xy 186.88286 -63.599336)
			(xy 186.855608 -63.599822) (xy 186.828237 -63.59937) (xy 186.774057 -63.591552) (xy 186.721553 -63.576061)
			(xy 186.671806 -63.553215) (xy 186.62584 -63.523486) (xy 186.60491 -63.505842) (xy 186.604656 -63.505588)
			(xy 186.597559 -63.500017) (xy 186.58065 -63.493761) (xy 186.571636 -63.493396) (xy 186.50458 -63.493396)
			(xy 186.495562 -63.493744) (xy 186.478645 -63.499998) (xy 186.47156 -63.505588) (xy 186.471052 -63.506096)
			(xy 186.450093 -63.523677) (xy 186.40413 -63.553339) (xy 186.3544 -63.576128) (xy 186.301924 -63.591577)
			(xy 186.247779 -63.599369) (xy 186.193076 -63.599344) (xy 186.138937 -63.591503) (xy 186.086475 -63.576006)
			(xy 186.036766 -63.553172) (xy 185.99083 -63.523468) (xy 185.96991 -63.505842) (xy 185.969656 -63.505588)
			(xy 185.962559 -63.500017) (xy 185.94565 -63.493761) (xy 185.936636 -63.493396) (xy 185.86958 -63.493396)
			(xy 185.860562 -63.493744) (xy 185.843645 -63.499998) (xy 185.83656 -63.505588) (xy 185.836052 -63.506096)
			(xy 185.815117 -63.523677) (xy 185.769183 -63.553317) (xy 185.719487 -63.576096) (xy 185.667049 -63.591546)
			(xy 185.612942 -63.599352) (xy 185.585608 -63.599822) (xy 185.558356 -63.599331) (xy 185.504406 -63.591575)
			(xy 185.452109 -63.576221) (xy 185.40253 -63.55358) (xy 185.356677 -63.524113) (xy 185.315485 -63.48842)
			(xy 185.279792 -63.447229) (xy 185.250324 -63.401377) (xy 185.227682 -63.351798) (xy 185.212326 -63.299502)
			(xy 185.204569 -63.245552) (xy 172.439837 -63.245552) (xy 172.440346 -63.273432) (xy 172.439837 -63.301318)
			(xy 172.431717 -63.356494) (xy 172.415649 -63.409901) (xy 172.391977 -63.460398) (xy 172.361204 -63.506911)
			(xy 172.323987 -63.548448) (xy 172.281119 -63.584123) (xy 172.233513 -63.613177) (xy 172.182184 -63.634989)
			(xy 172.128227 -63.649095) (xy 172.07279 -63.655195) (xy 172.017056 -63.653158) (xy 171.962213 -63.643028)
			(xy 171.909429 -63.625021) (xy 171.859829 -63.59952) (xy 171.814471 -63.567069) (xy 171.774322 -63.52836)
			(xy 171.740236 -63.484217) (xy 171.71294 -63.435582) (xy 171.693017 -63.383491) (xy 171.680891 -63.329054)
			(xy 171.67682 -63.273432) (xy 170.23003 -63.273432) (xy 170.19941 -63.319713) (xy 170.162193 -63.36125)
			(xy 170.119325 -63.396925) (xy 170.071719 -63.425979) (xy 170.02039 -63.447791) (xy 169.966433 -63.461897)
			(xy 169.910996 -63.467997) (xy 169.855262 -63.46596) (xy 169.800419 -63.45583) (xy 169.747635 -63.437823)
			(xy 169.698035 -63.412322) (xy 169.652677 -63.379871) (xy 169.612528 -63.341162) (xy 169.578442 -63.297019)
			(xy 169.551146 -63.248384) (xy 169.531223 -63.196293) (xy 169.519097 -63.141856) (xy 169.515026 -63.086234)
			(xy 161.214068 -63.086234) (xy 161.229001 -63.137088) (xy 161.236759 -63.191044) (xy 161.236759 -63.245556)
			(xy 161.229001 -63.299512) (xy 161.213642 -63.351815) (xy 161.190996 -63.4014) (xy 161.161523 -63.447257)
			(xy 161.125824 -63.488452) (xy 161.084625 -63.524147) (xy 161.038765 -63.553615) (xy 160.989178 -63.576256)
			(xy 160.936873 -63.591609) (xy 160.882916 -63.599362) (xy 160.85566 -63.599822) (xy 160.82829 -63.59934)
			(xy 160.774111 -63.591529) (xy 160.721607 -63.576045) (xy 160.67186 -63.553206) (xy 160.625893 -63.523483)
			(xy 160.604962 -63.505842) (xy 160.604708 -63.505588) (xy 160.597624 -63.499997) (xy 160.580705 -63.493753)
			(xy 160.571688 -63.493396) (xy 160.504632 -63.493396) (xy 160.495617 -63.493769) (xy 160.4787 -63.500006)
			(xy 160.471612 -63.505588) (xy 160.471104 -63.506096) (xy 160.450183 -63.523724) (xy 160.404213 -63.553384)
			(xy 160.354477 -63.57617) (xy 160.301995 -63.591616) (xy 160.247845 -63.599403) (xy 160.193137 -63.599373)
			(xy 160.138995 -63.591526) (xy 160.08653 -63.576023) (xy 160.036819 -63.553182) (xy 159.990882 -63.523472)
			(xy 159.969962 -63.505842) (xy 159.969708 -63.505588) (xy 159.962624 -63.499997) (xy 159.945705 -63.493753)
			(xy 159.936688 -63.493396) (xy 159.869632 -63.493396) (xy 159.860617 -63.493769) (xy 159.8437 -63.500006)
			(xy 159.836612 -63.505588) (xy 159.836104 -63.506096) (xy 159.815187 -63.523699) (xy 159.769248 -63.553336)
			(xy 159.719548 -63.576111) (xy 159.667105 -63.591556) (xy 159.612995 -63.599355) (xy 159.58566 -63.599822)
			(xy 159.558412 -63.599305) (xy 159.50447 -63.591544) (xy 159.452182 -63.576186) (xy 159.402612 -63.553544)
			(xy 159.356768 -63.524077) (xy 159.315584 -63.488387) (xy 159.279899 -63.4472) (xy 159.250437 -63.401353)
			(xy 159.2278 -63.35178) (xy 159.212447 -63.299491) (xy 159.204692 -63.245548) (xy 146.439889 -63.245548)
			(xy 146.440398 -63.273432) (xy 146.439889 -63.301318) (xy 146.431769 -63.356494) (xy 146.415701 -63.409901)
			(xy 146.392029 -63.460398) (xy 146.361256 -63.506911) (xy 146.324039 -63.548448) (xy 146.281171 -63.584123)
			(xy 146.233565 -63.613177) (xy 146.182236 -63.634989) (xy 146.128279 -63.649095) (xy 146.072842 -63.655195)
			(xy 146.017108 -63.653158) (xy 145.962265 -63.643028) (xy 145.909481 -63.625021) (xy 145.859881 -63.59952)
			(xy 145.814523 -63.567069) (xy 145.774374 -63.52836) (xy 145.740288 -63.484217) (xy 145.712992 -63.435582)
			(xy 145.693069 -63.383491) (xy 145.680943 -63.329054) (xy 145.676872 -63.273432) (xy 144.20265 -63.273432)
			(xy 144.17203 -63.319713) (xy 144.134813 -63.36125) (xy 144.091945 -63.396925) (xy 144.044339 -63.425979)
			(xy 143.99301 -63.447791) (xy 143.939053 -63.461897) (xy 143.883616 -63.467997) (xy 143.827882 -63.46596)
			(xy 143.773039 -63.45583) (xy 143.720255 -63.437823) (xy 143.670655 -63.412322) (xy 143.625297 -63.379871)
			(xy 143.585148 -63.341162) (xy 143.551062 -63.297019) (xy 143.523766 -63.248384) (xy 143.503843 -63.196293)
			(xy 143.491717 -63.141856) (xy 143.487646 -63.086234) (xy 135.214045 -63.086234) (xy 135.22898 -63.1371)
			(xy 135.236736 -63.191048) (xy 135.236736 -63.245552) (xy 135.22898 -63.2995) (xy 135.213625 -63.351796)
			(xy 135.190984 -63.401374) (xy 135.161517 -63.447226) (xy 135.125826 -63.488417) (xy 135.084635 -63.52411)
			(xy 135.038785 -63.553578) (xy 134.989207 -63.57622) (xy 134.936912 -63.591577) (xy 134.882964 -63.599335)
			(xy 134.855712 -63.599822) (xy 134.828341 -63.599368) (xy 134.774161 -63.59155) (xy 134.721657 -63.576059)
			(xy 134.67191 -63.553214) (xy 134.625944 -63.523486) (xy 134.605014 -63.505842) (xy 134.60476 -63.505588)
			(xy 134.597661 -63.500019) (xy 134.580754 -63.493762) (xy 134.57174 -63.493396) (xy 134.504684 -63.493396)
			(xy 134.495666 -63.493746) (xy 134.47875 -63.499999) (xy 134.471664 -63.505588) (xy 134.471156 -63.506096)
			(xy 134.450194 -63.523673) (xy 134.404231 -63.553335) (xy 134.354502 -63.576124) (xy 134.302026 -63.591574)
			(xy 134.247881 -63.599366) (xy 134.193179 -63.599342) (xy 134.139041 -63.591501) (xy 134.086579 -63.576005)
			(xy 134.03687 -63.553171) (xy 133.990934 -63.523468) (xy 133.970014 -63.505842) (xy 133.96976 -63.505588)
			(xy 133.962661 -63.500019) (xy 133.945754 -63.493762) (xy 133.93674 -63.493396) (xy 133.869684 -63.493396)
			(xy 133.860666 -63.493746) (xy 133.84375 -63.499999) (xy 133.836664 -63.505588) (xy 133.836156 -63.506096)
			(xy 133.815219 -63.523675) (xy 133.769286 -63.553316) (xy 133.71959 -63.576095) (xy 133.667152 -63.591546)
			(xy 133.613046 -63.599352) (xy 133.585712 -63.599822) (xy 133.55846 -63.599332) (xy 133.504509 -63.591576)
			(xy 133.452212 -63.576222) (xy 133.402632 -63.553581) (xy 133.356779 -63.524114) (xy 133.315587 -63.488422)
			(xy 133.279893 -63.44723) (xy 133.250425 -63.401378) (xy 133.227782 -63.351799) (xy 133.212426 -63.299502)
			(xy 133.204669 -63.245552) (xy 120.439941 -63.245552) (xy 120.44045 -63.273432) (xy 120.439941 -63.301318)
			(xy 120.431821 -63.356494) (xy 120.415753 -63.409901) (xy 120.392081 -63.460398) (xy 120.361308 -63.506911)
			(xy 120.324091 -63.548448) (xy 120.281223 -63.584123) (xy 120.233617 -63.613177) (xy 120.182288 -63.634989)
			(xy 120.128331 -63.649095) (xy 120.072894 -63.655195) (xy 120.01716 -63.653158) (xy 119.962317 -63.643028)
			(xy 119.909533 -63.625021) (xy 119.859933 -63.59952) (xy 119.814575 -63.567069) (xy 119.774426 -63.52836)
			(xy 119.74034 -63.484217) (xy 119.713044 -63.435582) (xy 119.693121 -63.383491) (xy 119.680995 -63.329054)
			(xy 119.676924 -63.273432) (xy 118.202702 -63.273432) (xy 118.172082 -63.319713) (xy 118.134865 -63.36125)
			(xy 118.091997 -63.396925) (xy 118.044391 -63.425979) (xy 117.993062 -63.447791) (xy 117.939105 -63.461897)
			(xy 117.883668 -63.467997) (xy 117.827934 -63.46596) (xy 117.773091 -63.45583) (xy 117.720307 -63.437823)
			(xy 117.670707 -63.412322) (xy 117.625349 -63.379871) (xy 117.5852 -63.341162) (xy 117.551114 -63.297019)
			(xy 117.523818 -63.248384) (xy 117.503895 -63.196293) (xy 117.491769 -63.141856) (xy 117.487698 -63.086234)
			(xy 97.113868 -63.086234) (xy 97.128801 -63.137088) (xy 97.136559 -63.191044) (xy 97.136559 -63.245556)
			(xy 97.128801 -63.299512) (xy 97.113442 -63.351816) (xy 97.090795 -63.4014) (xy 97.061322 -63.447257)
			(xy 97.025623 -63.488453) (xy 96.984424 -63.524148) (xy 96.938564 -63.553616) (xy 96.888976 -63.576257)
			(xy 96.836671 -63.59161) (xy 96.782714 -63.599362) (xy 96.755458 -63.599822) (xy 96.728088 -63.599341)
			(xy 96.673909 -63.59153) (xy 96.621405 -63.576045) (xy 96.571658 -63.553206) (xy 96.525691 -63.523483)
			(xy 96.50476 -63.505842) (xy 96.504506 -63.505588) (xy 96.497423 -63.499996) (xy 96.480503 -63.493753)
			(xy 96.471486 -63.493396) (xy 96.40443 -63.493396) (xy 96.395415 -63.493768) (xy 96.378498 -63.500005)
			(xy 96.37141 -63.505588) (xy 96.370902 -63.506096) (xy 96.349983 -63.523726) (xy 96.304013 -63.553386)
			(xy 96.254276 -63.576172) (xy 96.201794 -63.591617) (xy 96.147643 -63.599405) (xy 96.092936 -63.599375)
			(xy 96.038793 -63.591527) (xy 95.986328 -63.576024) (xy 95.936617 -63.553182) (xy 95.89068 -63.523472)
			(xy 95.86976 -63.505842) (xy 95.869506 -63.505588) (xy 95.862423 -63.499996) (xy 95.845503 -63.493753)
			(xy 95.836486 -63.493396) (xy 95.76943 -63.493396) (xy 95.760415 -63.493768) (xy 95.743498 -63.500005)
			(xy 95.73641 -63.505588) (xy 95.735902 -63.506096) (xy 95.714986 -63.5237) (xy 95.669046 -63.553337)
			(xy 95.619346 -63.576111) (xy 95.566903 -63.591556) (xy 95.512793 -63.599356) (xy 95.485458 -63.599822)
			(xy 95.45821 -63.599305) (xy 95.404269 -63.591544) (xy 95.351981 -63.576186) (xy 95.302411 -63.553543)
			(xy 95.256567 -63.524077) (xy 95.215384 -63.488386) (xy 95.179698 -63.447199) (xy 95.150237 -63.401352)
			(xy 95.1276 -63.35178) (xy 95.112247 -63.29949) (xy 95.104492 -63.245548) (xy 82.339687 -63.245548)
			(xy 82.340196 -63.273432) (xy 82.339687 -63.301318) (xy 82.331567 -63.356494) (xy 82.315499 -63.409901)
			(xy 82.291827 -63.460398) (xy 82.261054 -63.506911) (xy 82.223837 -63.548448) (xy 82.180969 -63.584123)
			(xy 82.133363 -63.613177) (xy 82.082034 -63.634989) (xy 82.028077 -63.649095) (xy 81.97264 -63.655195)
			(xy 81.916906 -63.653158) (xy 81.862063 -63.643028) (xy 81.809279 -63.625021) (xy 81.759679 -63.59952)
			(xy 81.714321 -63.567069) (xy 81.674172 -63.52836) (xy 81.640086 -63.484217) (xy 81.61279 -63.435582)
			(xy 81.592867 -63.383491) (xy 81.580741 -63.329054) (xy 81.57667 -63.273432) (xy 80.102448 -63.273432)
			(xy 80.071828 -63.319713) (xy 80.034611 -63.36125) (xy 79.991743 -63.396925) (xy 79.944137 -63.425979)
			(xy 79.892808 -63.447791) (xy 79.838851 -63.461897) (xy 79.783414 -63.467997) (xy 79.72768 -63.46596)
			(xy 79.672837 -63.45583) (xy 79.620053 -63.437823) (xy 79.570453 -63.412322) (xy 79.525095 -63.379871)
			(xy 79.484946 -63.341162) (xy 79.45086 -63.297019) (xy 79.423564 -63.248384) (xy 79.403641 -63.196293)
			(xy 79.391515 -63.141856) (xy 79.387444 -63.086234) (xy 71.113844 -63.086234) (xy 71.12878 -63.137099)
			(xy 71.136536 -63.191048) (xy 71.136536 -63.245552) (xy 71.12878 -63.299501) (xy 71.113424 -63.351797)
			(xy 71.090783 -63.401375) (xy 71.061317 -63.447226) (xy 71.025625 -63.488418) (xy 70.984434 -63.524111)
			(xy 70.938584 -63.553578) (xy 70.889006 -63.576221) (xy 70.83671 -63.591578) (xy 70.782762 -63.599336)
			(xy 70.75551 -63.599822) (xy 70.728139 -63.599369) (xy 70.673959 -63.591551) (xy 70.621455 -63.57606)
			(xy 70.571708 -63.553215) (xy 70.525742 -63.523486) (xy 70.504812 -63.505842) (xy 70.504558 -63.505588)
			(xy 70.49746 -63.500018) (xy 70.480552 -63.493762) (xy 70.471538 -63.493396) (xy 70.404482 -63.493396)
			(xy 70.395464 -63.493745) (xy 70.378548 -63.499998) (xy 70.371462 -63.505588) (xy 70.370954 -63.506096)
			(xy 70.349994 -63.523675) (xy 70.304031 -63.553337) (xy 70.254301 -63.576126) (xy 70.201825 -63.591576)
			(xy 70.14768 -63.599368) (xy 70.092977 -63.599343) (xy 70.038839 -63.591502) (xy 69.986377 -63.576005)
			(xy 69.936668 -63.553171) (xy 69.890732 -63.523468) (xy 69.869812 -63.505842) (xy 69.869558 -63.505588)
			(xy 69.86246 -63.500018) (xy 69.845552 -63.493762) (xy 69.836538 -63.493396) (xy 69.769482 -63.493396)
			(xy 69.760464 -63.493745) (xy 69.743548 -63.499998) (xy 69.736462 -63.505588) (xy 69.735954 -63.506096)
			(xy 69.715018 -63.523676) (xy 69.669084 -63.553316) (xy 69.619389 -63.576095) (xy 69.566951 -63.591546)
			(xy 69.512844 -63.599352) (xy 69.48551 -63.599822) (xy 69.458258 -63.599331) (xy 69.404308 -63.591576)
			(xy 69.352011 -63.576221) (xy 69.302431 -63.55358) (xy 69.256578 -63.524114) (xy 69.215386 -63.488421)
			(xy 69.179692 -63.44723) (xy 69.150225 -63.401378) (xy 69.127582 -63.351799) (xy 69.112226 -63.299502)
			(xy 69.104469 -63.245552) (xy 56.339739 -63.245552) (xy 56.340248 -63.273432) (xy 56.339739 -63.301318)
			(xy 56.331619 -63.356494) (xy 56.315551 -63.409901) (xy 56.291879 -63.460398) (xy 56.261106 -63.506911)
			(xy 56.223889 -63.548448) (xy 56.181021 -63.584123) (xy 56.133415 -63.613177) (xy 56.082086 -63.634989)
			(xy 56.028129 -63.649095) (xy 55.972692 -63.655195) (xy 55.916958 -63.653158) (xy 55.862115 -63.643028)
			(xy 55.809331 -63.625021) (xy 55.759731 -63.59952) (xy 55.714373 -63.567069) (xy 55.674224 -63.52836)
			(xy 55.640138 -63.484217) (xy 55.612842 -63.435582) (xy 55.592919 -63.383491) (xy 55.580793 -63.329054)
			(xy 55.576722 -63.273432) (xy 54.1025 -63.273432) (xy 54.07188 -63.319713) (xy 54.034663 -63.36125)
			(xy 53.991795 -63.396925) (xy 53.944189 -63.425979) (xy 53.89286 -63.447791) (xy 53.838903 -63.461897)
			(xy 53.783466 -63.467997) (xy 53.727732 -63.46596) (xy 53.672889 -63.45583) (xy 53.620105 -63.437823)
			(xy 53.570505 -63.412322) (xy 53.525147 -63.379871) (xy 53.484998 -63.341162) (xy 53.450912 -63.297019)
			(xy 53.423616 -63.248384) (xy 53.403693 -63.196293) (xy 53.391567 -63.141856) (xy 53.387496 -63.086234)
			(xy 45.113968 -63.086234) (xy 45.128901 -63.137088) (xy 45.136659 -63.191044) (xy 45.136659 -63.245556)
			(xy 45.128901 -63.299512) (xy 45.113542 -63.351815) (xy 45.090896 -63.401399) (xy 45.061423 -63.447256)
			(xy 45.025724 -63.488451) (xy 44.984526 -63.524146) (xy 44.938666 -63.553614) (xy 44.889079 -63.576256)
			(xy 44.836775 -63.591609) (xy 44.782818 -63.599362) (xy 44.755562 -63.599822) (xy 44.728192 -63.599339)
			(xy 44.674013 -63.591528) (xy 44.621509 -63.576044) (xy 44.571762 -63.553206) (xy 44.525795 -63.523483)
			(xy 44.504864 -63.505842) (xy 44.50461 -63.505588) (xy 44.497526 -63.499998) (xy 44.480607 -63.493754)
			(xy 44.47159 -63.493396) (xy 44.404534 -63.493396) (xy 44.395519 -63.49377) (xy 44.378602 -63.500006)
			(xy 44.371514 -63.505588) (xy 44.371006 -63.506096) (xy 44.350084 -63.523722) (xy 44.304114 -63.553382)
			(xy 44.254378 -63.576168) (xy 44.201896 -63.591614) (xy 44.147746 -63.599402) (xy 44.093039 -63.599372)
			(xy 44.038897 -63.591525) (xy 43.986432 -63.576022) (xy 43.936721 -63.553182) (xy 43.890784 -63.523472)
			(xy 43.869864 -63.505842) (xy 43.86961 -63.505588) (xy 43.862526 -63.499998) (xy 43.845607 -63.493754)
			(xy 43.83659 -63.493396) (xy 43.769534 -63.493396) (xy 43.760519 -63.49377) (xy 43.743602 -63.500006)
			(xy 43.736514 -63.505588) (xy 43.736006 -63.506096) (xy 43.715088 -63.523698) (xy 43.669149 -63.553335)
			(xy 43.619449 -63.57611) (xy 43.567007 -63.591555) (xy 43.512897 -63.599355) (xy 43.485562 -63.599822)
			(xy 43.458314 -63.599305) (xy 43.404372 -63.591545) (xy 43.352084 -63.576187) (xy 43.302513 -63.553544)
			(xy 43.256669 -63.524078) (xy 43.215485 -63.488388) (xy 43.179799 -63.4472) (xy 43.150337 -63.401353)
			(xy 43.1277 -63.351781) (xy 43.112347 -63.299491) (xy 43.104592 -63.245548) (xy 30.339791 -63.245548)
			(xy 30.3403 -63.273432) (xy 30.339791 -63.301318) (xy 30.331671 -63.356494) (xy 30.315603 -63.409901)
			(xy 30.291931 -63.460398) (xy 30.261158 -63.506911) (xy 30.223941 -63.548448) (xy 30.181073 -63.584123)
			(xy 30.133467 -63.613177) (xy 30.082138 -63.634989) (xy 30.028181 -63.649095) (xy 29.972744 -63.655195)
			(xy 29.91701 -63.653158) (xy 29.862167 -63.643028) (xy 29.809383 -63.625021) (xy 29.759783 -63.59952)
			(xy 29.714425 -63.567069) (xy 29.674276 -63.52836) (xy 29.64019 -63.484217) (xy 29.612894 -63.435582)
			(xy 29.592971 -63.383491) (xy 29.580845 -63.329054) (xy 29.576774 -63.273432) (xy 28.102552 -63.273432)
			(xy 28.071932 -63.319713) (xy 28.034715 -63.36125) (xy 27.991847 -63.396925) (xy 27.944241 -63.425979)
			(xy 27.892912 -63.447791) (xy 27.838955 -63.461897) (xy 27.783518 -63.467997) (xy 27.727784 -63.46596)
			(xy 27.672941 -63.45583) (xy 27.620157 -63.437823) (xy 27.570557 -63.412322) (xy 27.525199 -63.379871)
			(xy 27.48505 -63.341162) (xy 27.450964 -63.297019) (xy 27.423668 -63.248384) (xy 27.403745 -63.196293)
			(xy 27.391619 -63.141856) (xy 27.387548 -63.086234) (xy 20.380452 -63.086234) (xy 20.380452 -64.102234)
			(xy 27.387548 -64.102234) (xy 27.391619 -64.046612) (xy 27.403745 -63.992175) (xy 27.423668 -63.940084)
			(xy 27.450964 -63.891449) (xy 27.48505 -63.847306) (xy 27.525199 -63.808597) (xy 27.570557 -63.776146)
			(xy 27.620157 -63.750645) (xy 27.672941 -63.732638) (xy 27.727784 -63.722508) (xy 27.783518 -63.720471)
			(xy 27.838955 -63.726571) (xy 27.892912 -63.740677) (xy 27.944241 -63.762489) (xy 27.991847 -63.791543)
			(xy 28.034715 -63.827218) (xy 28.071932 -63.868755) (xy 28.102705 -63.915268) (xy 28.126377 -63.965765)
			(xy 28.142445 -64.019172) (xy 28.150565 -64.074348) (xy 28.151074 -64.102234) (xy 28.150565 -64.13012)
			(xy 28.142445 -64.185296) (xy 28.126377 -64.238703) (xy 28.102705 -64.2892) (xy 28.087427 -64.312292)
			(xy 31.065976 -64.312292) (xy 31.070047 -64.25667) (xy 31.082173 -64.202233) (xy 31.102096 -64.150142)
			(xy 31.129392 -64.101507) (xy 31.163478 -64.057364) (xy 31.203627 -64.018655) (xy 31.248985 -63.986204)
			(xy 31.298585 -63.960703) (xy 31.351369 -63.942696) (xy 31.406212 -63.932566) (xy 31.461946 -63.930529)
			(xy 31.517383 -63.936629) (xy 31.57134 -63.950735) (xy 31.622669 -63.972547) (xy 31.670275 -64.001601)
			(xy 31.713143 -64.037276) (xy 31.75036 -64.078813) (xy 31.765855 -64.102234) (xy 53.387496 -64.102234)
			(xy 53.391567 -64.046612) (xy 53.403693 -63.992175) (xy 53.423616 -63.940084) (xy 53.450912 -63.891449)
			(xy 53.484998 -63.847306) (xy 53.525147 -63.808597) (xy 53.570505 -63.776146) (xy 53.620105 -63.750645)
			(xy 53.672889 -63.732638) (xy 53.727732 -63.722508) (xy 53.783466 -63.720471) (xy 53.838903 -63.726571)
			(xy 53.89286 -63.740677) (xy 53.944189 -63.762489) (xy 53.991795 -63.791543) (xy 54.034663 -63.827218)
			(xy 54.07188 -63.868755) (xy 54.102653 -63.915268) (xy 54.126325 -63.965765) (xy 54.142393 -64.019172)
			(xy 54.150513 -64.074348) (xy 54.151022 -64.102234) (xy 54.150513 -64.13012) (xy 54.142393 -64.185296)
			(xy 54.126325 -64.238703) (xy 54.102653 -64.2892) (xy 54.087375 -64.312292) (xy 57.065924 -64.312292)
			(xy 57.069995 -64.25667) (xy 57.082121 -64.202233) (xy 57.102044 -64.150142) (xy 57.12934 -64.101507)
			(xy 57.163426 -64.057364) (xy 57.203575 -64.018655) (xy 57.248933 -63.986204) (xy 57.298533 -63.960703)
			(xy 57.351317 -63.942696) (xy 57.40616 -63.932566) (xy 57.461894 -63.930529) (xy 57.517331 -63.936629)
			(xy 57.571288 -63.950735) (xy 57.622617 -63.972547) (xy 57.670223 -64.001601) (xy 57.713091 -64.037276)
			(xy 57.750308 -64.078813) (xy 57.781081 -64.125326) (xy 57.804753 -64.175823) (xy 57.820821 -64.22923)
			(xy 57.828941 -64.284406) (xy 57.82945 -64.312292) (xy 58.9059 -64.312292) (xy 58.909971 -64.25667)
			(xy 58.922097 -64.202233) (xy 58.94202 -64.150142) (xy 58.969316 -64.101507) (xy 59.003402 -64.057364)
			(xy 59.043551 -64.018655) (xy 59.088909 -63.986204) (xy 59.138509 -63.960703) (xy 59.191293 -63.942696)
			(xy 59.246136 -63.932566) (xy 59.30187 -63.930529) (xy 59.357307 -63.936629) (xy 59.411264 -63.950735)
			(xy 59.462593 -63.972547) (xy 59.510199 -64.001601) (xy 59.553067 -64.037276) (xy 59.590284 -64.078813)
			(xy 59.605779 -64.102234) (xy 79.387444 -64.102234) (xy 79.391515 -64.046612) (xy 79.403641 -63.992175)
			(xy 79.423564 -63.940084) (xy 79.45086 -63.891449) (xy 79.484946 -63.847306) (xy 79.525095 -63.808597)
			(xy 79.570453 -63.776146) (xy 79.620053 -63.750645) (xy 79.672837 -63.732638) (xy 79.72768 -63.722508)
			(xy 79.783414 -63.720471) (xy 79.838851 -63.726571) (xy 79.892808 -63.740677) (xy 79.944137 -63.762489)
			(xy 79.991743 -63.791543) (xy 80.034611 -63.827218) (xy 80.071828 -63.868755) (xy 80.102601 -63.915268)
			(xy 80.126273 -63.965765) (xy 80.142341 -64.019172) (xy 80.150461 -64.074348) (xy 80.15097 -64.102234)
			(xy 80.150461 -64.13012) (xy 80.142341 -64.185296) (xy 80.126273 -64.238703) (xy 80.102601 -64.2892)
			(xy 80.087323 -64.312292) (xy 83.065872 -64.312292) (xy 83.069943 -64.25667) (xy 83.082069 -64.202233)
			(xy 83.101992 -64.150142) (xy 83.129288 -64.101507) (xy 83.163374 -64.057364) (xy 83.203523 -64.018655)
			(xy 83.248881 -63.986204) (xy 83.298481 -63.960703) (xy 83.351265 -63.942696) (xy 83.406108 -63.932566)
			(xy 83.461842 -63.930529) (xy 83.517279 -63.936629) (xy 83.571236 -63.950735) (xy 83.622565 -63.972547)
			(xy 83.670171 -64.001601) (xy 83.713039 -64.037276) (xy 83.750256 -64.078813) (xy 83.765751 -64.102234)
			(xy 117.487698 -64.102234) (xy 117.491769 -64.046612) (xy 117.503895 -63.992175) (xy 117.523818 -63.940084)
			(xy 117.551114 -63.891449) (xy 117.5852 -63.847306) (xy 117.625349 -63.808597) (xy 117.670707 -63.776146)
			(xy 117.720307 -63.750645) (xy 117.773091 -63.732638) (xy 117.827934 -63.722508) (xy 117.883668 -63.720471)
			(xy 117.939105 -63.726571) (xy 117.993062 -63.740677) (xy 118.044391 -63.762489) (xy 118.091997 -63.791543)
			(xy 118.134865 -63.827218) (xy 118.172082 -63.868755) (xy 118.202855 -63.915268) (xy 118.226527 -63.965765)
			(xy 118.242595 -64.019172) (xy 118.250715 -64.074348) (xy 118.251224 -64.102234) (xy 118.250715 -64.13012)
			(xy 118.242595 -64.185296) (xy 118.226527 -64.238703) (xy 118.202855 -64.2892) (xy 118.187577 -64.312292)
			(xy 121.166126 -64.312292) (xy 121.170197 -64.25667) (xy 121.182323 -64.202233) (xy 121.202246 -64.150142)
			(xy 121.229542 -64.101507) (xy 121.263628 -64.057364) (xy 121.303777 -64.018655) (xy 121.349135 -63.986204)
			(xy 121.398735 -63.960703) (xy 121.451519 -63.942696) (xy 121.506362 -63.932566) (xy 121.562096 -63.930529)
			(xy 121.617533 -63.936629) (xy 121.67149 -63.950735) (xy 121.722819 -63.972547) (xy 121.770425 -64.001601)
			(xy 121.813293 -64.037276) (xy 121.85051 -64.078813) (xy 121.866005 -64.102234) (xy 143.487646 -64.102234)
			(xy 143.491717 -64.046612) (xy 143.503843 -63.992175) (xy 143.523766 -63.940084) (xy 143.551062 -63.891449)
			(xy 143.585148 -63.847306) (xy 143.625297 -63.808597) (xy 143.670655 -63.776146) (xy 143.720255 -63.750645)
			(xy 143.773039 -63.732638) (xy 143.827882 -63.722508) (xy 143.883616 -63.720471) (xy 143.939053 -63.726571)
			(xy 143.99301 -63.740677) (xy 144.044339 -63.762489) (xy 144.091945 -63.791543) (xy 144.134813 -63.827218)
			(xy 144.17203 -63.868755) (xy 144.202803 -63.915268) (xy 144.226475 -63.965765) (xy 144.242543 -64.019172)
			(xy 144.250663 -64.074348) (xy 144.251172 -64.102234) (xy 144.250663 -64.13012) (xy 144.242543 -64.185296)
			(xy 144.226475 -64.238703) (xy 144.202803 -64.2892) (xy 144.187525 -64.312292) (xy 147.166074 -64.312292)
			(xy 147.170145 -64.25667) (xy 147.182271 -64.202233) (xy 147.202194 -64.150142) (xy 147.22949 -64.101507)
			(xy 147.263576 -64.057364) (xy 147.303725 -64.018655) (xy 147.349083 -63.986204) (xy 147.398683 -63.960703)
			(xy 147.451467 -63.942696) (xy 147.50631 -63.932566) (xy 147.562044 -63.930529) (xy 147.617481 -63.936629)
			(xy 147.671438 -63.950735) (xy 147.722767 -63.972547) (xy 147.770373 -64.001601) (xy 147.813241 -64.037276)
			(xy 147.850458 -64.078813) (xy 147.865953 -64.102234) (xy 169.487594 -64.102234) (xy 169.491665 -64.046612)
			(xy 169.503791 -63.992175) (xy 169.523714 -63.940084) (xy 169.55101 -63.891449) (xy 169.585096 -63.847306)
			(xy 169.625245 -63.808597) (xy 169.670603 -63.776146) (xy 169.720203 -63.750645) (xy 169.772987 -63.732638)
			(xy 169.82783 -63.722508) (xy 169.883564 -63.720471) (xy 169.939001 -63.726571) (xy 169.992958 -63.740677)
			(xy 170.044287 -63.762489) (xy 170.091893 -63.791543) (xy 170.134761 -63.827218) (xy 170.171978 -63.868755)
			(xy 170.202751 -63.915268) (xy 170.226423 -63.965765) (xy 170.242491 -64.019172) (xy 170.250611 -64.074348)
			(xy 170.25112 -64.102234) (xy 170.250611 -64.13012) (xy 170.242491 -64.185296) (xy 170.226423 -64.238703)
			(xy 170.202751 -64.2892) (xy 170.187473 -64.312292) (xy 173.166022 -64.312292) (xy 173.170093 -64.25667)
			(xy 173.182219 -64.202233) (xy 173.202142 -64.150142) (xy 173.229438 -64.101507) (xy 173.263524 -64.057364)
			(xy 173.303673 -64.018655) (xy 173.349031 -63.986204) (xy 173.398631 -63.960703) (xy 173.451415 -63.942696)
			(xy 173.506258 -63.932566) (xy 173.561992 -63.930529) (xy 173.617429 -63.936629) (xy 173.671386 -63.950735)
			(xy 173.722715 -63.972547) (xy 173.770321 -64.001601) (xy 173.813189 -64.037276) (xy 173.850406 -64.078813)
			(xy 173.881179 -64.125326) (xy 173.904851 -64.175823) (xy 173.920919 -64.22923) (xy 173.929039 -64.284406)
			(xy 173.929548 -64.312292) (xy 175.005998 -64.312292) (xy 175.010069 -64.25667) (xy 175.022195 -64.202233)
			(xy 175.042118 -64.150142) (xy 175.069414 -64.101507) (xy 175.1035 -64.057364) (xy 175.143649 -64.018655)
			(xy 175.189007 -63.986204) (xy 175.238607 -63.960703) (xy 175.291391 -63.942696) (xy 175.346234 -63.932566)
			(xy 175.401968 -63.930529) (xy 175.457405 -63.936629) (xy 175.511362 -63.950735) (xy 175.562691 -63.972547)
			(xy 175.610297 -64.001601) (xy 175.653165 -64.037276) (xy 175.690382 -64.078813) (xy 175.705877 -64.102234)
			(xy 195.487542 -64.102234) (xy 195.491613 -64.046612) (xy 195.503739 -63.992175) (xy 195.523662 -63.940084)
			(xy 195.550958 -63.891449) (xy 195.585044 -63.847306) (xy 195.625193 -63.808597) (xy 195.670551 -63.776146)
			(xy 195.720151 -63.750645) (xy 195.772935 -63.732638) (xy 195.827778 -63.722508) (xy 195.883512 -63.720471)
			(xy 195.938949 -63.726571) (xy 195.992906 -63.740677) (xy 196.044235 -63.762489) (xy 196.091841 -63.791543)
			(xy 196.134709 -63.827218) (xy 196.171926 -63.868755) (xy 196.202699 -63.915268) (xy 196.226371 -63.965765)
			(xy 196.242439 -64.019172) (xy 196.250559 -64.074348) (xy 196.251068 -64.102234) (xy 196.250559 -64.13012)
			(xy 196.242439 -64.185296) (xy 196.226371 -64.238703) (xy 196.202699 -64.2892) (xy 196.187421 -64.312292)
			(xy 199.16597 -64.312292) (xy 199.170041 -64.25667) (xy 199.182167 -64.202233) (xy 199.20209 -64.150142)
			(xy 199.229386 -64.101507) (xy 199.263472 -64.057364) (xy 199.303621 -64.018655) (xy 199.348979 -63.986204)
			(xy 199.398579 -63.960703) (xy 199.451363 -63.942696) (xy 199.506206 -63.932566) (xy 199.56194 -63.930529)
			(xy 199.617377 -63.936629) (xy 199.671334 -63.950735) (xy 199.722663 -63.972547) (xy 199.770269 -64.001601)
			(xy 199.813137 -64.037276) (xy 199.850354 -64.078813) (xy 199.881127 -64.125326) (xy 199.904799 -64.175823)
			(xy 199.920867 -64.22923) (xy 199.928987 -64.284406) (xy 199.929496 -64.312292) (xy 199.928987 -64.340178)
			(xy 199.920867 -64.395354) (xy 199.904799 -64.448761) (xy 199.881127 -64.499258) (xy 199.850354 -64.545771)
			(xy 199.813137 -64.587308) (xy 199.770269 -64.622983) (xy 199.722663 -64.652037) (xy 199.671334 -64.673849)
			(xy 199.617377 -64.687955) (xy 199.56194 -64.694055) (xy 199.506206 -64.692018) (xy 199.451363 -64.681888)
			(xy 199.398579 -64.663881) (xy 199.348979 -64.63838) (xy 199.303621 -64.605929) (xy 199.263472 -64.56722)
			(xy 199.229386 -64.523077) (xy 199.20209 -64.474442) (xy 199.182167 -64.422351) (xy 199.170041 -64.367914)
			(xy 199.16597 -64.312292) (xy 196.187421 -64.312292) (xy 196.171926 -64.335713) (xy 196.134709 -64.37725)
			(xy 196.091841 -64.412925) (xy 196.044235 -64.441979) (xy 195.992906 -64.463791) (xy 195.938949 -64.477897)
			(xy 195.883512 -64.483997) (xy 195.827778 -64.48196) (xy 195.772935 -64.47183) (xy 195.720151 -64.453823)
			(xy 195.670551 -64.428322) (xy 195.625193 -64.395871) (xy 195.585044 -64.357162) (xy 195.550958 -64.313019)
			(xy 195.523662 -64.264384) (xy 195.503739 -64.212293) (xy 195.491613 -64.157856) (xy 195.487542 -64.102234)
			(xy 175.705877 -64.102234) (xy 175.721155 -64.125326) (xy 175.744827 -64.175823) (xy 175.760895 -64.22923)
			(xy 175.769015 -64.284406) (xy 175.769524 -64.312292) (xy 175.769015 -64.340178) (xy 175.760895 -64.395354)
			(xy 175.744827 -64.448761) (xy 175.721155 -64.499258) (xy 175.690382 -64.545771) (xy 175.653165 -64.587308)
			(xy 175.610297 -64.622983) (xy 175.562691 -64.652037) (xy 175.511362 -64.673849) (xy 175.457405 -64.687955)
			(xy 175.401968 -64.694055) (xy 175.346234 -64.692018) (xy 175.291391 -64.681888) (xy 175.238607 -64.663881)
			(xy 175.189007 -64.63838) (xy 175.143649 -64.605929) (xy 175.1035 -64.56722) (xy 175.069414 -64.523077)
			(xy 175.042118 -64.474442) (xy 175.022195 -64.422351) (xy 175.010069 -64.367914) (xy 175.005998 -64.312292)
			(xy 173.929548 -64.312292) (xy 173.929039 -64.340178) (xy 173.920919 -64.395354) (xy 173.904851 -64.448761)
			(xy 173.881179 -64.499258) (xy 173.850406 -64.545771) (xy 173.813189 -64.587308) (xy 173.770321 -64.622983)
			(xy 173.722715 -64.652037) (xy 173.671386 -64.673849) (xy 173.617429 -64.687955) (xy 173.561992 -64.694055)
			(xy 173.506258 -64.692018) (xy 173.451415 -64.681888) (xy 173.398631 -64.663881) (xy 173.349031 -64.63838)
			(xy 173.303673 -64.605929) (xy 173.263524 -64.56722) (xy 173.229438 -64.523077) (xy 173.202142 -64.474442)
			(xy 173.182219 -64.422351) (xy 173.170093 -64.367914) (xy 173.166022 -64.312292) (xy 170.187473 -64.312292)
			(xy 170.171978 -64.335713) (xy 170.134761 -64.37725) (xy 170.091893 -64.412925) (xy 170.044287 -64.441979)
			(xy 169.992958 -64.463791) (xy 169.939001 -64.477897) (xy 169.883564 -64.483997) (xy 169.82783 -64.48196)
			(xy 169.772987 -64.47183) (xy 169.720203 -64.453823) (xy 169.670603 -64.428322) (xy 169.625245 -64.395871)
			(xy 169.585096 -64.357162) (xy 169.55101 -64.313019) (xy 169.523714 -64.264384) (xy 169.503791 -64.212293)
			(xy 169.491665 -64.157856) (xy 169.487594 -64.102234) (xy 147.865953 -64.102234) (xy 147.881231 -64.125326)
			(xy 147.904903 -64.175823) (xy 147.920971 -64.22923) (xy 147.929091 -64.284406) (xy 147.9296 -64.312292)
			(xy 147.929091 -64.340178) (xy 147.920971 -64.395354) (xy 147.904903 -64.448761) (xy 147.881231 -64.499258)
			(xy 147.850458 -64.545771) (xy 147.813241 -64.587308) (xy 147.770373 -64.622983) (xy 147.722767 -64.652037)
			(xy 147.671438 -64.673849) (xy 147.617481 -64.687955) (xy 147.562044 -64.694055) (xy 147.50631 -64.692018)
			(xy 147.451467 -64.681888) (xy 147.398683 -64.663881) (xy 147.349083 -64.63838) (xy 147.303725 -64.605929)
			(xy 147.263576 -64.56722) (xy 147.22949 -64.523077) (xy 147.202194 -64.474442) (xy 147.182271 -64.422351)
			(xy 147.170145 -64.367914) (xy 147.166074 -64.312292) (xy 144.187525 -64.312292) (xy 144.17203 -64.335713)
			(xy 144.134813 -64.37725) (xy 144.091945 -64.412925) (xy 144.044339 -64.441979) (xy 143.99301 -64.463791)
			(xy 143.939053 -64.477897) (xy 143.883616 -64.483997) (xy 143.827882 -64.48196) (xy 143.773039 -64.47183)
			(xy 143.720255 -64.453823) (xy 143.670655 -64.428322) (xy 143.625297 -64.395871) (xy 143.585148 -64.357162)
			(xy 143.551062 -64.313019) (xy 143.523766 -64.264384) (xy 143.503843 -64.212293) (xy 143.491717 -64.157856)
			(xy 143.487646 -64.102234) (xy 121.866005 -64.102234) (xy 121.881283 -64.125326) (xy 121.904955 -64.175823)
			(xy 121.921023 -64.22923) (xy 121.929143 -64.284406) (xy 121.929652 -64.312292) (xy 121.929143 -64.340178)
			(xy 121.921023 -64.395354) (xy 121.904955 -64.448761) (xy 121.881283 -64.499258) (xy 121.85051 -64.545771)
			(xy 121.813293 -64.587308) (xy 121.770425 -64.622983) (xy 121.722819 -64.652037) (xy 121.67149 -64.673849)
			(xy 121.617533 -64.687955) (xy 121.562096 -64.694055) (xy 121.506362 -64.692018) (xy 121.451519 -64.681888)
			(xy 121.398735 -64.663881) (xy 121.349135 -64.63838) (xy 121.303777 -64.605929) (xy 121.263628 -64.56722)
			(xy 121.229542 -64.523077) (xy 121.202246 -64.474442) (xy 121.182323 -64.422351) (xy 121.170197 -64.367914)
			(xy 121.166126 -64.312292) (xy 118.187577 -64.312292) (xy 118.172082 -64.335713) (xy 118.134865 -64.37725)
			(xy 118.091997 -64.412925) (xy 118.044391 -64.441979) (xy 117.993062 -64.463791) (xy 117.939105 -64.477897)
			(xy 117.883668 -64.483997) (xy 117.827934 -64.48196) (xy 117.773091 -64.47183) (xy 117.720307 -64.453823)
			(xy 117.670707 -64.428322) (xy 117.625349 -64.395871) (xy 117.5852 -64.357162) (xy 117.551114 -64.313019)
			(xy 117.523818 -64.264384) (xy 117.503895 -64.212293) (xy 117.491769 -64.157856) (xy 117.487698 -64.102234)
			(xy 83.765751 -64.102234) (xy 83.781029 -64.125326) (xy 83.804701 -64.175823) (xy 83.820769 -64.22923)
			(xy 83.828889 -64.284406) (xy 83.829398 -64.312292) (xy 83.828889 -64.340178) (xy 83.820769 -64.395354)
			(xy 83.804701 -64.448761) (xy 83.781029 -64.499258) (xy 83.750256 -64.545771) (xy 83.713039 -64.587308)
			(xy 83.670171 -64.622983) (xy 83.622565 -64.652037) (xy 83.571236 -64.673849) (xy 83.517279 -64.687955)
			(xy 83.461842 -64.694055) (xy 83.406108 -64.692018) (xy 83.351265 -64.681888) (xy 83.298481 -64.663881)
			(xy 83.248881 -64.63838) (xy 83.203523 -64.605929) (xy 83.163374 -64.56722) (xy 83.129288 -64.523077)
			(xy 83.101992 -64.474442) (xy 83.082069 -64.422351) (xy 83.069943 -64.367914) (xy 83.065872 -64.312292)
			(xy 80.087323 -64.312292) (xy 80.071828 -64.335713) (xy 80.034611 -64.37725) (xy 79.991743 -64.412925)
			(xy 79.944137 -64.441979) (xy 79.892808 -64.463791) (xy 79.838851 -64.477897) (xy 79.783414 -64.483997)
			(xy 79.72768 -64.48196) (xy 79.672837 -64.47183) (xy 79.620053 -64.453823) (xy 79.570453 -64.428322)
			(xy 79.525095 -64.395871) (xy 79.484946 -64.357162) (xy 79.45086 -64.313019) (xy 79.423564 -64.264384)
			(xy 79.403641 -64.212293) (xy 79.391515 -64.157856) (xy 79.387444 -64.102234) (xy 59.605779 -64.102234)
			(xy 59.621057 -64.125326) (xy 59.644729 -64.175823) (xy 59.660797 -64.22923) (xy 59.668917 -64.284406)
			(xy 59.669426 -64.312292) (xy 59.668917 -64.340178) (xy 59.660797 -64.395354) (xy 59.644729 -64.448761)
			(xy 59.621057 -64.499258) (xy 59.590284 -64.545771) (xy 59.553067 -64.587308) (xy 59.510199 -64.622983)
			(xy 59.462593 -64.652037) (xy 59.411264 -64.673849) (xy 59.357307 -64.687955) (xy 59.30187 -64.694055)
			(xy 59.246136 -64.692018) (xy 59.191293 -64.681888) (xy 59.138509 -64.663881) (xy 59.088909 -64.63838)
			(xy 59.043551 -64.605929) (xy 59.003402 -64.56722) (xy 58.969316 -64.523077) (xy 58.94202 -64.474442)
			(xy 58.922097 -64.422351) (xy 58.909971 -64.367914) (xy 58.9059 -64.312292) (xy 57.82945 -64.312292)
			(xy 57.828941 -64.340178) (xy 57.820821 -64.395354) (xy 57.804753 -64.448761) (xy 57.781081 -64.499258)
			(xy 57.750308 -64.545771) (xy 57.713091 -64.587308) (xy 57.670223 -64.622983) (xy 57.622617 -64.652037)
			(xy 57.571288 -64.673849) (xy 57.517331 -64.687955) (xy 57.461894 -64.694055) (xy 57.40616 -64.692018)
			(xy 57.351317 -64.681888) (xy 57.298533 -64.663881) (xy 57.248933 -64.63838) (xy 57.203575 -64.605929)
			(xy 57.163426 -64.56722) (xy 57.12934 -64.523077) (xy 57.102044 -64.474442) (xy 57.082121 -64.422351)
			(xy 57.069995 -64.367914) (xy 57.065924 -64.312292) (xy 54.087375 -64.312292) (xy 54.07188 -64.335713)
			(xy 54.034663 -64.37725) (xy 53.991795 -64.412925) (xy 53.944189 -64.441979) (xy 53.89286 -64.463791)
			(xy 53.838903 -64.477897) (xy 53.783466 -64.483997) (xy 53.727732 -64.48196) (xy 53.672889 -64.47183)
			(xy 53.620105 -64.453823) (xy 53.570505 -64.428322) (xy 53.525147 -64.395871) (xy 53.484998 -64.357162)
			(xy 53.450912 -64.313019) (xy 53.423616 -64.264384) (xy 53.403693 -64.212293) (xy 53.391567 -64.157856)
			(xy 53.387496 -64.102234) (xy 31.765855 -64.102234) (xy 31.781133 -64.125326) (xy 31.804805 -64.175823)
			(xy 31.820873 -64.22923) (xy 31.828993 -64.284406) (xy 31.829502 -64.312292) (xy 31.828993 -64.340178)
			(xy 31.820873 -64.395354) (xy 31.804805 -64.448761) (xy 31.781133 -64.499258) (xy 31.75036 -64.545771)
			(xy 31.713143 -64.587308) (xy 31.670275 -64.622983) (xy 31.622669 -64.652037) (xy 31.57134 -64.673849)
			(xy 31.517383 -64.687955) (xy 31.461946 -64.694055) (xy 31.406212 -64.692018) (xy 31.351369 -64.681888)
			(xy 31.298585 -64.663881) (xy 31.248985 -64.63838) (xy 31.203627 -64.605929) (xy 31.163478 -64.56722)
			(xy 31.129392 -64.523077) (xy 31.102096 -64.474442) (xy 31.082173 -64.422351) (xy 31.070047 -64.367914)
			(xy 31.065976 -64.312292) (xy 28.087427 -64.312292) (xy 28.071932 -64.335713) (xy 28.034715 -64.37725)
			(xy 27.991847 -64.412925) (xy 27.944241 -64.441979) (xy 27.892912 -64.463791) (xy 27.838955 -64.477897)
			(xy 27.783518 -64.483997) (xy 27.727784 -64.48196) (xy 27.672941 -64.47183) (xy 27.620157 -64.453823)
			(xy 27.570557 -64.428322) (xy 27.525199 -64.395871) (xy 27.48505 -64.357162) (xy 27.450964 -64.313019)
			(xy 27.423668 -64.264384) (xy 27.403745 -64.212293) (xy 27.391619 -64.157856) (xy 27.387548 -64.102234)
			(xy 20.380452 -64.102234) (xy 20.380452 -64.61887) (xy 20.380956 -64.629294) (xy 20.389215 -64.648438)
			(xy 20.396454 -64.655954) (xy 20.450302 -64.7065) (xy 20.458272 -64.713282) (xy 20.477939 -64.720368)
			(xy 20.488402 -64.720216) (xy 20.514564 -64.719454) (xy 20.541818 -64.719937) (xy 20.595772 -64.727689)
			(xy 20.648073 -64.743041) (xy 20.697657 -64.76568) (xy 20.743515 -64.795144) (xy 20.784712 -64.830835)
			(xy 20.820411 -64.872026) (xy 20.849885 -64.917878) (xy 20.872533 -64.967458) (xy 20.887895 -65.019756)
			(xy 20.895657 -65.073708) (xy 20.896072 -65.100962) (xy 20.895611 -65.128216) (xy 20.891059 -65.15989)
			(xy 21.148546 -65.15989) (xy 21.152617 -65.104268) (xy 21.164743 -65.049831) (xy 21.184666 -64.99774)
			(xy 21.211962 -64.949105) (xy 21.246048 -64.904962) (xy 21.286197 -64.866253) (xy 21.331555 -64.833802)
			(xy 21.381155 -64.808301) (xy 21.433939 -64.790294) (xy 21.488782 -64.780164) (xy 21.544516 -64.778127)
			(xy 21.599953 -64.784227) (xy 21.65391 -64.798333) (xy 21.705239 -64.820145) (xy 21.752845 -64.849199)
			(xy 21.795713 -64.884874) (xy 21.83293 -64.926411) (xy 21.863703 -64.972924) (xy 21.887375 -65.023421)
			(xy 21.903443 -65.076828) (xy 21.910396 -65.124076) (xy 32.107376 -65.124076) (xy 32.111447 -65.068454)
			(xy 32.123573 -65.014017) (xy 32.143496 -64.961926) (xy 32.170792 -64.913291) (xy 32.204878 -64.869148)
			(xy 32.245027 -64.830439) (xy 32.290385 -64.797988) (xy 32.339985 -64.772487) (xy 32.392769 -64.75448)
			(xy 32.447612 -64.74435) (xy 32.503346 -64.742313) (xy 32.558783 -64.748413) (xy 32.61274 -64.762519)
			(xy 32.664069 -64.784331) (xy 32.711675 -64.813385) (xy 32.754543 -64.84906) (xy 32.79176 -64.890597)
			(xy 32.822533 -64.93711) (xy 32.846205 -64.987607) (xy 32.862273 -65.041014) (xy 32.870393 -65.09619)
			(xy 32.870902 -65.124076) (xy 32.870393 -65.151962) (xy 32.869226 -65.15989) (xy 45.116494 -65.15989)
			(xy 45.120565 -65.104268) (xy 45.132691 -65.049831) (xy 45.152614 -64.99774) (xy 45.17991 -64.949105)
			(xy 45.213996 -64.904962) (xy 45.254145 -64.866253) (xy 45.299503 -64.833802) (xy 45.349103 -64.808301)
			(xy 45.401887 -64.790294) (xy 45.45673 -64.780164) (xy 45.512464 -64.778127) (xy 45.567901 -64.784227)
			(xy 45.621858 -64.798333) (xy 45.673187 -64.820145) (xy 45.720793 -64.849199) (xy 45.763661 -64.884874)
			(xy 45.800878 -64.926411) (xy 45.831651 -64.972924) (xy 45.855323 -65.023421) (xy 45.871391 -65.076828)
			(xy 45.874943 -65.100962) (xy 46.132494 -65.100962) (xy 46.136565 -65.04534) (xy 46.148691 -64.990903)
			(xy 46.168614 -64.938812) (xy 46.19591 -64.890177) (xy 46.229996 -64.846034) (xy 46.270145 -64.807325)
			(xy 46.315503 -64.774874) (xy 46.365103 -64.749373) (xy 46.417887 -64.731366) (xy 46.47273 -64.721236)
			(xy 46.528464 -64.719199) (xy 46.583901 -64.725299) (xy 46.637858 -64.739405) (xy 46.689187 -64.761217)
			(xy 46.736793 -64.790271) (xy 46.779661 -64.825946) (xy 46.816878 -64.867483) (xy 46.847651 -64.913996)
			(xy 46.871323 -64.964493) (xy 46.887391 -65.0179) (xy 46.895511 -65.073076) (xy 46.89602 -65.100962)
			(xy 46.895511 -65.128848) (xy 46.890943 -65.15989) (xy 47.148494 -65.15989) (xy 47.152565 -65.104268)
			(xy 47.164691 -65.049831) (xy 47.184614 -64.99774) (xy 47.21191 -64.949105) (xy 47.245996 -64.904962)
			(xy 47.286145 -64.866253) (xy 47.331503 -64.833802) (xy 47.381103 -64.808301) (xy 47.433887 -64.790294)
			(xy 47.48873 -64.780164) (xy 47.544464 -64.778127) (xy 47.599901 -64.784227) (xy 47.653858 -64.798333)
			(xy 47.705187 -64.820145) (xy 47.752793 -64.849199) (xy 47.795661 -64.884874) (xy 47.832878 -64.926411)
			(xy 47.863651 -64.972924) (xy 47.887323 -65.023421) (xy 47.903391 -65.076828) (xy 47.911511 -65.132004)
			(xy 47.91202 -65.15989) (xy 71.116442 -65.15989) (xy 71.120513 -65.104268) (xy 71.132639 -65.049831)
			(xy 71.152562 -64.99774) (xy 71.179858 -64.949105) (xy 71.213944 -64.904962) (xy 71.254093 -64.866253)
			(xy 71.299451 -64.833802) (xy 71.349051 -64.808301) (xy 71.401835 -64.790294) (xy 71.456678 -64.780164)
			(xy 71.512412 -64.778127) (xy 71.567849 -64.784227) (xy 71.621806 -64.798333) (xy 71.673135 -64.820145)
			(xy 71.720741 -64.849199) (xy 71.763609 -64.884874) (xy 71.800826 -64.926411) (xy 71.831599 -64.972924)
			(xy 71.855271 -65.023421) (xy 71.871339 -65.076828) (xy 71.874891 -65.100962) (xy 72.132442 -65.100962)
			(xy 72.136513 -65.04534) (xy 72.148639 -64.990903) (xy 72.168562 -64.938812) (xy 72.195858 -64.890177)
			(xy 72.229944 -64.846034) (xy 72.270093 -64.807325) (xy 72.315451 -64.774874) (xy 72.365051 -64.749373)
			(xy 72.417835 -64.731366) (xy 72.472678 -64.721236) (xy 72.528412 -64.719199) (xy 72.583849 -64.725299)
			(xy 72.637806 -64.739405) (xy 72.689135 -64.761217) (xy 72.736741 -64.790271) (xy 72.779609 -64.825946)
			(xy 72.816826 -64.867483) (xy 72.847599 -64.913996) (xy 72.871271 -64.964493) (xy 72.887339 -65.0179)
			(xy 72.895459 -65.073076) (xy 72.895968 -65.100962) (xy 72.895459 -65.128848) (xy 72.890891 -65.15989)
			(xy 73.148442 -65.15989) (xy 73.152513 -65.104268) (xy 73.164639 -65.049831) (xy 73.184562 -64.99774)
			(xy 73.211858 -64.949105) (xy 73.245944 -64.904962) (xy 73.286093 -64.866253) (xy 73.331451 -64.833802)
			(xy 73.381051 -64.808301) (xy 73.433835 -64.790294) (xy 73.488678 -64.780164) (xy 73.544412 -64.778127)
			(xy 73.599849 -64.784227) (xy 73.653806 -64.798333) (xy 73.705135 -64.820145) (xy 73.752741 -64.849199)
			(xy 73.795609 -64.884874) (xy 73.832826 -64.926411) (xy 73.863599 -64.972924) (xy 73.887271 -65.023421)
			(xy 73.903339 -65.076828) (xy 73.910292 -65.124076) (xy 84.107272 -65.124076) (xy 84.111343 -65.068454)
			(xy 84.123469 -65.014017) (xy 84.143392 -64.961926) (xy 84.170688 -64.913291) (xy 84.204774 -64.869148)
			(xy 84.244923 -64.830439) (xy 84.290281 -64.797988) (xy 84.339881 -64.772487) (xy 84.392665 -64.75448)
			(xy 84.447508 -64.74435) (xy 84.503242 -64.742313) (xy 84.558679 -64.748413) (xy 84.612636 -64.762519)
			(xy 84.663965 -64.784331) (xy 84.711571 -64.813385) (xy 84.754439 -64.84906) (xy 84.791656 -64.890597)
			(xy 84.822429 -64.93711) (xy 84.846101 -64.987607) (xy 84.862169 -65.041014) (xy 84.870289 -65.09619)
			(xy 84.870798 -65.124076) (xy 84.870289 -65.151962) (xy 84.869122 -65.15989) (xy 97.11639 -65.15989)
			(xy 97.120461 -65.104268) (xy 97.132587 -65.049831) (xy 97.15251 -64.99774) (xy 97.179806 -64.949105)
			(xy 97.213892 -64.904962) (xy 97.254041 -64.866253) (xy 97.299399 -64.833802) (xy 97.348999 -64.808301)
			(xy 97.401783 -64.790294) (xy 97.456626 -64.780164) (xy 97.51236 -64.778127) (xy 97.567797 -64.784227)
			(xy 97.621754 -64.798333) (xy 97.673083 -64.820145) (xy 97.720689 -64.849199) (xy 97.763557 -64.884874)
			(xy 97.800774 -64.926411) (xy 97.831547 -64.972924) (xy 97.855219 -65.023421) (xy 97.871287 -65.076828)
			(xy 97.874839 -65.100962) (xy 98.13239 -65.100962) (xy 98.136461 -65.04534) (xy 98.148587 -64.990903)
			(xy 98.16851 -64.938812) (xy 98.195806 -64.890177) (xy 98.229892 -64.846034) (xy 98.270041 -64.807325)
			(xy 98.315399 -64.774874) (xy 98.364999 -64.749373) (xy 98.417783 -64.731366) (xy 98.472626 -64.721236)
			(xy 98.52836 -64.719199) (xy 98.583797 -64.725299) (xy 98.637754 -64.739405) (xy 98.689083 -64.761217)
			(xy 98.736689 -64.790271) (xy 98.779557 -64.825946) (xy 98.816774 -64.867483) (xy 98.847547 -64.913996)
			(xy 98.871219 -64.964493) (xy 98.887287 -65.0179) (xy 98.895407 -65.073076) (xy 98.895916 -65.100962)
			(xy 98.895407 -65.128848) (xy 98.890839 -65.15989) (xy 99.14839 -65.15989) (xy 99.152461 -65.104268)
			(xy 99.164587 -65.049831) (xy 99.18451 -64.99774) (xy 99.211806 -64.949105) (xy 99.245892 -64.904962)
			(xy 99.286041 -64.866253) (xy 99.331399 -64.833802) (xy 99.380999 -64.808301) (xy 99.433783 -64.790294)
			(xy 99.488626 -64.780164) (xy 99.54436 -64.778127) (xy 99.599797 -64.784227) (xy 99.653754 -64.798333)
			(xy 99.705083 -64.820145) (xy 99.752689 -64.849199) (xy 99.795557 -64.884874) (xy 99.832774 -64.926411)
			(xy 99.863547 -64.972924) (xy 99.887219 -65.023421) (xy 99.903287 -65.076828) (xy 99.91024 -65.124076)
			(xy 122.207526 -65.124076) (xy 122.211597 -65.068454) (xy 122.223723 -65.014017) (xy 122.243646 -64.961926)
			(xy 122.270942 -64.913291) (xy 122.305028 -64.869148) (xy 122.345177 -64.830439) (xy 122.390535 -64.797988)
			(xy 122.440135 -64.772487) (xy 122.492919 -64.75448) (xy 122.547762 -64.74435) (xy 122.603496 -64.742313)
			(xy 122.658933 -64.748413) (xy 122.71289 -64.762519) (xy 122.764219 -64.784331) (xy 122.811825 -64.813385)
			(xy 122.854693 -64.84906) (xy 122.89191 -64.890597) (xy 122.922683 -64.93711) (xy 122.946355 -64.987607)
			(xy 122.962423 -65.041014) (xy 122.970543 -65.09619) (xy 122.971052 -65.124076) (xy 122.970543 -65.151962)
			(xy 122.969376 -65.15989) (xy 135.216644 -65.15989) (xy 135.220715 -65.104268) (xy 135.232841 -65.049831)
			(xy 135.252764 -64.99774) (xy 135.28006 -64.949105) (xy 135.314146 -64.904962) (xy 135.354295 -64.866253)
			(xy 135.399653 -64.833802) (xy 135.449253 -64.808301) (xy 135.502037 -64.790294) (xy 135.55688 -64.780164)
			(xy 135.612614 -64.778127) (xy 135.668051 -64.784227) (xy 135.722008 -64.798333) (xy 135.773337 -64.820145)
			(xy 135.820943 -64.849199) (xy 135.863811 -64.884874) (xy 135.901028 -64.926411) (xy 135.931801 -64.972924)
			(xy 135.955473 -65.023421) (xy 135.971541 -65.076828) (xy 135.975093 -65.100962) (xy 136.232644 -65.100962)
			(xy 136.236715 -65.04534) (xy 136.248841 -64.990903) (xy 136.268764 -64.938812) (xy 136.29606 -64.890177)
			(xy 136.330146 -64.846034) (xy 136.370295 -64.807325) (xy 136.415653 -64.774874) (xy 136.465253 -64.749373)
			(xy 136.518037 -64.731366) (xy 136.57288 -64.721236) (xy 136.628614 -64.719199) (xy 136.684051 -64.725299)
			(xy 136.738008 -64.739405) (xy 136.789337 -64.761217) (xy 136.836943 -64.790271) (xy 136.879811 -64.825946)
			(xy 136.917028 -64.867483) (xy 136.947801 -64.913996) (xy 136.971473 -64.964493) (xy 136.987541 -65.0179)
			(xy 136.995661 -65.073076) (xy 136.99617 -65.100962) (xy 136.995661 -65.128848) (xy 136.991093 -65.15989)
			(xy 137.248644 -65.15989) (xy 137.252715 -65.104268) (xy 137.264841 -65.049831) (xy 137.284764 -64.99774)
			(xy 137.31206 -64.949105) (xy 137.346146 -64.904962) (xy 137.386295 -64.866253) (xy 137.431653 -64.833802)
			(xy 137.481253 -64.808301) (xy 137.534037 -64.790294) (xy 137.58888 -64.780164) (xy 137.644614 -64.778127)
			(xy 137.700051 -64.784227) (xy 137.754008 -64.798333) (xy 137.805337 -64.820145) (xy 137.852943 -64.849199)
			(xy 137.895811 -64.884874) (xy 137.933028 -64.926411) (xy 137.963801 -64.972924) (xy 137.987473 -65.023421)
			(xy 138.003541 -65.076828) (xy 138.010494 -65.124076) (xy 148.207474 -65.124076) (xy 148.211545 -65.068454)
			(xy 148.223671 -65.014017) (xy 148.243594 -64.961926) (xy 148.27089 -64.913291) (xy 148.304976 -64.869148)
			(xy 148.345125 -64.830439) (xy 148.390483 -64.797988) (xy 148.440083 -64.772487) (xy 148.492867 -64.75448)
			(xy 148.54771 -64.74435) (xy 148.603444 -64.742313) (xy 148.658881 -64.748413) (xy 148.712838 -64.762519)
			(xy 148.764167 -64.784331) (xy 148.811773 -64.813385) (xy 148.854641 -64.84906) (xy 148.891858 -64.890597)
			(xy 148.922631 -64.93711) (xy 148.946303 -64.987607) (xy 148.962371 -65.041014) (xy 148.970491 -65.09619)
			(xy 148.971 -65.124076) (xy 148.970491 -65.151962) (xy 148.969324 -65.15989) (xy 161.216592 -65.15989)
			(xy 161.220663 -65.104268) (xy 161.232789 -65.049831) (xy 161.252712 -64.99774) (xy 161.280008 -64.949105)
			(xy 161.314094 -64.904962) (xy 161.354243 -64.866253) (xy 161.399601 -64.833802) (xy 161.449201 -64.808301)
			(xy 161.501985 -64.790294) (xy 161.556828 -64.780164) (xy 161.612562 -64.778127) (xy 161.667999 -64.784227)
			(xy 161.721956 -64.798333) (xy 161.773285 -64.820145) (xy 161.820891 -64.849199) (xy 161.863759 -64.884874)
			(xy 161.900976 -64.926411) (xy 161.931749 -64.972924) (xy 161.955421 -65.023421) (xy 161.971489 -65.076828)
			(xy 161.975041 -65.100962) (xy 162.232592 -65.100962) (xy 162.236663 -65.04534) (xy 162.248789 -64.990903)
			(xy 162.268712 -64.938812) (xy 162.296008 -64.890177) (xy 162.330094 -64.846034) (xy 162.370243 -64.807325)
			(xy 162.415601 -64.774874) (xy 162.465201 -64.749373) (xy 162.517985 -64.731366) (xy 162.572828 -64.721236)
			(xy 162.628562 -64.719199) (xy 162.683999 -64.725299) (xy 162.737956 -64.739405) (xy 162.789285 -64.761217)
			(xy 162.836891 -64.790271) (xy 162.879759 -64.825946) (xy 162.916976 -64.867483) (xy 162.947749 -64.913996)
			(xy 162.971421 -64.964493) (xy 162.987489 -65.0179) (xy 162.995609 -65.073076) (xy 162.996118 -65.100962)
			(xy 162.995609 -65.128848) (xy 162.991041 -65.15989) (xy 163.248592 -65.15989) (xy 163.252663 -65.104268)
			(xy 163.264789 -65.049831) (xy 163.284712 -64.99774) (xy 163.312008 -64.949105) (xy 163.346094 -64.904962)
			(xy 163.386243 -64.866253) (xy 163.431601 -64.833802) (xy 163.481201 -64.808301) (xy 163.533985 -64.790294)
			(xy 163.588828 -64.780164) (xy 163.644562 -64.778127) (xy 163.699999 -64.784227) (xy 163.753956 -64.798333)
			(xy 163.805285 -64.820145) (xy 163.852891 -64.849199) (xy 163.895759 -64.884874) (xy 163.932976 -64.926411)
			(xy 163.963749 -64.972924) (xy 163.987421 -65.023421) (xy 164.003489 -65.076828) (xy 164.011609 -65.132004)
			(xy 164.012118 -65.15989) (xy 187.21654 -65.15989) (xy 187.220611 -65.104268) (xy 187.232737 -65.049831)
			(xy 187.25266 -64.99774) (xy 187.279956 -64.949105) (xy 187.314042 -64.904962) (xy 187.354191 -64.866253)
			(xy 187.399549 -64.833802) (xy 187.449149 -64.808301) (xy 187.501933 -64.790294) (xy 187.556776 -64.780164)
			(xy 187.61251 -64.778127) (xy 187.667947 -64.784227) (xy 187.721904 -64.798333) (xy 187.773233 -64.820145)
			(xy 187.820839 -64.849199) (xy 187.863707 -64.884874) (xy 187.900924 -64.926411) (xy 187.931697 -64.972924)
			(xy 187.955369 -65.023421) (xy 187.971437 -65.076828) (xy 187.974989 -65.100962) (xy 188.23254 -65.100962)
			(xy 188.236611 -65.04534) (xy 188.248737 -64.990903) (xy 188.26866 -64.938812) (xy 188.295956 -64.890177)
			(xy 188.330042 -64.846034) (xy 188.370191 -64.807325) (xy 188.415549 -64.774874) (xy 188.465149 -64.749373)
			(xy 188.517933 -64.731366) (xy 188.572776 -64.721236) (xy 188.62851 -64.719199) (xy 188.683947 -64.725299)
			(xy 188.737904 -64.739405) (xy 188.789233 -64.761217) (xy 188.836839 -64.790271) (xy 188.879707 -64.825946)
			(xy 188.916924 -64.867483) (xy 188.947697 -64.913996) (xy 188.971369 -64.964493) (xy 188.987437 -65.0179)
			(xy 188.995557 -65.073076) (xy 188.996066 -65.100962) (xy 188.995557 -65.128848) (xy 188.990989 -65.15989)
			(xy 189.24854 -65.15989) (xy 189.252611 -65.104268) (xy 189.264737 -65.049831) (xy 189.28466 -64.99774)
			(xy 189.311956 -64.949105) (xy 189.346042 -64.904962) (xy 189.386191 -64.866253) (xy 189.431549 -64.833802)
			(xy 189.481149 -64.808301) (xy 189.533933 -64.790294) (xy 189.588776 -64.780164) (xy 189.64451 -64.778127)
			(xy 189.699947 -64.784227) (xy 189.753904 -64.798333) (xy 189.805233 -64.820145) (xy 189.852839 -64.849199)
			(xy 189.895707 -64.884874) (xy 189.932924 -64.926411) (xy 189.963697 -64.972924) (xy 189.987369 -65.023421)
			(xy 190.003437 -65.076828) (xy 190.01039 -65.124076) (xy 200.20737 -65.124076) (xy 200.211441 -65.068454)
			(xy 200.223567 -65.014017) (xy 200.24349 -64.961926) (xy 200.270786 -64.913291) (xy 200.304872 -64.869148)
			(xy 200.345021 -64.830439) (xy 200.390379 -64.797988) (xy 200.439979 -64.772487) (xy 200.492763 -64.75448)
			(xy 200.547606 -64.74435) (xy 200.60334 -64.742313) (xy 200.658777 -64.748413) (xy 200.712734 -64.762519)
			(xy 200.764063 -64.784331) (xy 200.811669 -64.813385) (xy 200.854537 -64.84906) (xy 200.891754 -64.890597)
			(xy 200.922527 -64.93711) (xy 200.946199 -64.987607) (xy 200.962267 -65.041014) (xy 200.970387 -65.09619)
			(xy 200.970896 -65.124076) (xy 200.970387 -65.151962) (xy 200.96922 -65.15989) (xy 213.216488 -65.15989)
			(xy 213.220559 -65.104268) (xy 213.232685 -65.049831) (xy 213.252608 -64.99774) (xy 213.279904 -64.949105)
			(xy 213.31399 -64.904962) (xy 213.354139 -64.866253) (xy 213.399497 -64.833802) (xy 213.449097 -64.808301)
			(xy 213.501881 -64.790294) (xy 213.556724 -64.780164) (xy 213.612458 -64.778127) (xy 213.667895 -64.784227)
			(xy 213.721852 -64.798333) (xy 213.773181 -64.820145) (xy 213.820787 -64.849199) (xy 213.863655 -64.884874)
			(xy 213.900872 -64.926411) (xy 213.931645 -64.972924) (xy 213.955317 -65.023421) (xy 213.971385 -65.076828)
			(xy 213.974937 -65.100962) (xy 214.232488 -65.100962) (xy 214.236559 -65.04534) (xy 214.248685 -64.990903)
			(xy 214.268608 -64.938812) (xy 214.295904 -64.890177) (xy 214.32999 -64.846034) (xy 214.370139 -64.807325)
			(xy 214.415497 -64.774874) (xy 214.465097 -64.749373) (xy 214.517881 -64.731366) (xy 214.572724 -64.721236)
			(xy 214.628458 -64.719199) (xy 214.683895 -64.725299) (xy 214.737852 -64.739405) (xy 214.789181 -64.761217)
			(xy 214.836787 -64.790271) (xy 214.879655 -64.825946) (xy 214.916872 -64.867483) (xy 214.947645 -64.913996)
			(xy 214.971317 -64.964493) (xy 214.987385 -65.0179) (xy 214.995505 -65.073076) (xy 214.996014 -65.100962)
			(xy 214.995505 -65.128848) (xy 214.990937 -65.15989) (xy 215.248488 -65.15989) (xy 215.252559 -65.104268)
			(xy 215.264685 -65.049831) (xy 215.284608 -64.99774) (xy 215.311904 -64.949105) (xy 215.34599 -64.904962)
			(xy 215.386139 -64.866253) (xy 215.431497 -64.833802) (xy 215.481097 -64.808301) (xy 215.533881 -64.790294)
			(xy 215.588724 -64.780164) (xy 215.644458 -64.778127) (xy 215.699895 -64.784227) (xy 215.753852 -64.798333)
			(xy 215.757709 -64.799972) (xy 224.633028 -64.799972) (xy 224.633547 -64.771217) (xy 224.642176 -64.714359)
			(xy 224.659248 -64.659443) (xy 224.684376 -64.607714) (xy 224.71699 -64.560348) (xy 224.756349 -64.518418)
			(xy 224.801561 -64.482877) (xy 224.826322 -64.468248) (xy 224.826576 -64.467994) (xy 224.831488 -64.464981)
			(xy 224.839947 -64.457158) (xy 224.84334 -64.4525) (xy 224.84334 -64.452246) (xy 224.846586 -64.447228)
			(xy 224.850816 -64.436055) (xy 224.851722 -64.430148) (xy 224.861628 -64.349376) (xy 224.862209 -64.343464)
			(xy 224.860928 -64.331656) (xy 224.859088 -64.326008) (xy 224.857015 -64.320586) (xy 224.850721 -64.310834)
			(xy 224.846642 -64.306704) (xy 224.846388 -64.30645) (xy 224.828142 -64.288388) (xy 224.796167 -64.248219)
			(xy 224.769867 -64.204126) (xy 224.749717 -64.156905) (xy 224.736079 -64.107409) (xy 224.729201 -64.056531)
			(xy 224.728786 -64.03086) (xy 224.729247 -64.00472) (xy 224.736397 -63.952932) (xy 224.750545 -63.902603)
			(xy 224.771426 -63.854675) (xy 224.79865 -63.810043) (xy 224.831708 -63.769541) (xy 224.869981 -63.733928)
			(xy 224.912755 -63.703868) (xy 224.935796 -63.691516) (xy 224.944432 -63.687198) (xy 224.956878 -63.672974)
			(xy 224.984056 -63.599314) (xy 224.985607 -63.594776) (xy 224.987145 -63.585313) (xy 224.987104 -63.580518)
			(xy 224.98685 -63.571374) (xy 224.983294 -63.56223) (xy 224.98304 -63.561722) (xy 224.973905 -63.538555)
			(xy 224.961021 -63.490451) (xy 224.954505 -63.441079) (xy 224.954084 -63.41618) (xy 224.954559 -63.388929)
			(xy 224.962318 -63.334981) (xy 224.977675 -63.282686) (xy 225.000318 -63.23311) (xy 225.029786 -63.18726)
			(xy 225.065478 -63.14607) (xy 225.106669 -63.110379) (xy 225.15252 -63.080913) (xy 225.202098 -63.058271)
			(xy 225.254393 -63.042916) (xy 225.308341 -63.035158) (xy 225.335592 -63.034672) (xy 225.362842 -63.035185)
			(xy 225.416788 -63.04294) (xy 225.469081 -63.058293) (xy 225.518657 -63.080932) (xy 225.564506 -63.110396)
			(xy 225.605696 -63.146084) (xy 225.641388 -63.187271) (xy 225.670855 -63.233119) (xy 225.693497 -63.282693)
			(xy 225.708854 -63.334985) (xy 225.716613 -63.38893) (xy 225.7171 -63.41618) (xy 225.71668 -63.442321)
			(xy 225.709524 -63.494111) (xy 225.69537 -63.544442) (xy 225.694149 -63.547244) (xy 226.964238 -63.547244)
			(xy 226.968309 -63.491622) (xy 226.980435 -63.437185) (xy 227.000358 -63.385094) (xy 227.027654 -63.336459)
			(xy 227.06174 -63.292316) (xy 227.101889 -63.253607) (xy 227.147247 -63.221156) (xy 227.196847 -63.195655)
			(xy 227.249631 -63.177648) (xy 227.304474 -63.167518) (xy 227.360208 -63.165481) (xy 227.415645 -63.171581)
			(xy 227.469602 -63.185687) (xy 227.520931 -63.207499) (xy 227.568537 -63.236553) (xy 227.611405 -63.272228)
			(xy 227.648622 -63.313765) (xy 227.679395 -63.360278) (xy 227.703067 -63.410775) (xy 227.719135 -63.464182)
			(xy 227.727255 -63.519358) (xy 227.727764 -63.547244) (xy 227.727255 -63.57513) (xy 227.723584 -63.600076)
			(xy 233.19054 -63.600076) (xy 233.194611 -63.544454) (xy 233.206737 -63.490017) (xy 233.22666 -63.437926)
			(xy 233.253956 -63.389291) (xy 233.288042 -63.345148) (xy 233.328191 -63.306439) (xy 233.373549 -63.273988)
			(xy 233.423149 -63.248487) (xy 233.475933 -63.23048) (xy 233.530776 -63.22035) (xy 233.58651 -63.218313)
			(xy 233.641947 -63.224413) (xy 233.695904 -63.238519) (xy 233.747233 -63.260331) (xy 233.794839 -63.289385)
			(xy 233.837707 -63.32506) (xy 233.874924 -63.366597) (xy 233.905697 -63.41311) (xy 233.923449 -63.450978)
			(xy 237.60633 -63.450978) (xy 237.610401 -63.395356) (xy 237.622527 -63.340919) (xy 237.64245 -63.288828)
			(xy 237.669746 -63.240193) (xy 237.703832 -63.19605) (xy 237.743981 -63.157341) (xy 237.789339 -63.12489)
			(xy 237.838939 -63.099389) (xy 237.891723 -63.081382) (xy 237.946566 -63.071252) (xy 238.0023 -63.069215)
			(xy 238.057737 -63.075315) (xy 238.111694 -63.089421) (xy 238.163023 -63.111233) (xy 238.210629 -63.140287)
			(xy 238.253497 -63.175962) (xy 238.290714 -63.217499) (xy 238.309271 -63.245548) (xy 249.304592 -63.245548)
			(xy 249.304592 -63.191052) (xy 249.312347 -63.13711) (xy 249.3277 -63.084821) (xy 249.350337 -63.035248)
			(xy 249.379798 -62.989402) (xy 249.415483 -62.948214) (xy 249.456666 -62.912524) (xy 249.50251 -62.883058)
			(xy 249.552079 -62.860415) (xy 249.604367 -62.845057) (xy 249.658308 -62.837295) (xy 249.685556 -62.836806)
			(xy 249.712925 -62.837296) (xy 249.767103 -62.845108) (xy 249.819606 -62.860591) (xy 249.869354 -62.883428)
			(xy 249.915322 -62.913147) (xy 249.936254 -62.930786) (xy 249.936508 -62.93104) (xy 249.943585 -62.936641)
			(xy 249.960509 -62.942878) (xy 249.969528 -62.943232) (xy 250.036584 -62.943232) (xy 250.045599 -62.94286)
			(xy 250.062516 -62.936622) (xy 250.069604 -62.93104) (xy 250.070112 -62.930532) (xy 250.09102 -62.912887)
			(xy 250.136991 -62.883226) (xy 250.186729 -62.860439) (xy 250.239214 -62.844993) (xy 250.293366 -62.837206)
			(xy 250.348076 -62.837238) (xy 250.40222 -62.845088) (xy 250.454686 -62.860594) (xy 250.504398 -62.883439)
			(xy 250.550335 -62.913154) (xy 250.571254 -62.930786) (xy 250.571508 -62.93104) (xy 250.578585 -62.936641)
			(xy 250.595509 -62.942878) (xy 250.604528 -62.943232) (xy 250.671584 -62.943232) (xy 250.680599 -62.94286)
			(xy 250.697516 -62.936622) (xy 250.704604 -62.93104) (xy 250.705112 -62.930532) (xy 250.726026 -62.912925)
			(xy 250.771966 -62.883288) (xy 250.821667 -62.860514) (xy 250.87411 -62.84507) (xy 250.928221 -62.837272)
			(xy 250.955556 -62.836806) (xy 250.982812 -62.837238) (xy 251.03677 -62.84499) (xy 251.089075 -62.860343)
			(xy 251.138662 -62.882984) (xy 251.184523 -62.912452) (xy 251.225722 -62.948147) (xy 251.261422 -62.989342)
			(xy 251.290895 -63.035199) (xy 251.313542 -63.084784) (xy 251.313968 -63.086234) (xy 259.58749 -63.086234)
			(xy 259.591561 -63.030612) (xy 259.603687 -62.976175) (xy 259.62361 -62.924084) (xy 259.650906 -62.875449)
			(xy 259.684992 -62.831306) (xy 259.725141 -62.792597) (xy 259.770499 -62.760146) (xy 259.820099 -62.734645)
			(xy 259.872883 -62.716638) (xy 259.927726 -62.706508) (xy 259.98346 -62.704471) (xy 260.038897 -62.710571)
			(xy 260.092854 -62.724677) (xy 260.144183 -62.746489) (xy 260.191789 -62.775543) (xy 260.234657 -62.811218)
			(xy 260.259954 -62.839451) (xy 265.118846 -62.839451) (xy 265.118846 -62.784949) (xy 265.126602 -62.731001)
			(xy 265.141955 -62.678706) (xy 265.164595 -62.629128) (xy 265.194059 -62.583276) (xy 265.229748 -62.542083)
			(xy 265.270936 -62.506389) (xy 265.316784 -62.476919) (xy 265.366359 -62.454273) (xy 265.418652 -62.438912)
			(xy 265.472599 -62.431149) (xy 265.49985 -62.43066) (xy 265.52866 -62.431158) (xy 265.585624 -62.439842)
			(xy 265.640634 -62.45699) (xy 265.692442 -62.482212) (xy 265.739871 -62.514935) (xy 265.761216 -62.534292)
			(xy 265.769852 -62.54242) (xy 265.791696 -62.549278) (xy 265.881612 -62.536832) (xy 265.892983 -62.53476)
			(xy 265.912164 -62.521901) (xy 265.918442 -62.512194) (xy 265.933286 -62.488093) (xy 265.968934 -62.44413)
			(xy 266.010684 -62.405912) (xy 266.057619 -62.374278) (xy 266.108711 -62.349923) (xy 266.16284 -62.333378)
			(xy 266.218818 -62.325008) (xy 266.247118 -62.324488) (xy 266.270673 -62.324865) (xy 266.317417 -62.330724)
			(xy 266.340336 -62.336172) (xy 266.34955 -62.338028) (xy 266.368181 -62.335687) (xy 266.38471 -62.326776)
			(xy 266.391136 -62.319916) (xy 266.45997 -62.24016) (xy 266.464542 -62.211966) (xy 266.458954 -62.198504)
			(xy 266.449643 -62.175115) (xy 266.436518 -62.126514) (xy 266.429895 -62.076609) (xy 266.42949 -62.051438)
			(xy 266.429976 -62.024187) (xy 266.437732 -61.970239) (xy 266.453087 -61.917944) (xy 266.475729 -61.868367)
			(xy 266.505195 -61.822517) (xy 266.540886 -61.781326) (xy 266.582077 -61.745635) (xy 266.627927 -61.716169)
			(xy 266.677504 -61.693527) (xy 266.729799 -61.678172) (xy 266.783747 -61.670416) (xy 266.838249 -61.670416)
			(xy 266.892197 -61.678172) (xy 266.944492 -61.693527) (xy 266.994069 -61.716169) (xy 267.039919 -61.745635)
			(xy 267.08111 -61.781326) (xy 267.116801 -61.822517) (xy 267.146267 -61.868367) (xy 267.168909 -61.917944)
			(xy 267.184264 -61.970239) (xy 267.19202 -62.024187) (xy 267.192506 -62.051438) (xy 267.192058 -62.07869)
			(xy 267.185966 -62.121034) (xy 288.442144 -62.121034) (xy 288.446215 -62.065412) (xy 288.458341 -62.010975)
			(xy 288.478264 -61.958884) (xy 288.50556 -61.910249) (xy 288.539646 -61.866106) (xy 288.579795 -61.827397)
			(xy 288.625153 -61.794946) (xy 288.674753 -61.769445) (xy 288.727537 -61.751438) (xy 288.78238 -61.741308)
			(xy 288.838114 -61.739271) (xy 288.893551 -61.745371) (xy 288.947508 -61.759477) (xy 288.998837 -61.781289)
			(xy 289.046443 -61.810343) (xy 289.089311 -61.846018) (xy 289.126528 -61.887555) (xy 289.157301 -61.934068)
			(xy 289.180973 -61.984565) (xy 289.197041 -62.037972) (xy 289.205161 -62.093148) (xy 289.20567 -62.121034)
			(xy 289.205161 -62.14892) (xy 289.197041 -62.204096) (xy 289.180973 -62.257503) (xy 289.157301 -62.308)
			(xy 289.126528 -62.354513) (xy 289.089311 -62.39605) (xy 289.046443 -62.431725) (xy 288.998837 -62.460779)
			(xy 288.947508 -62.482591) (xy 288.893551 -62.496697) (xy 288.838114 -62.502797) (xy 288.78238 -62.50076)
			(xy 288.727537 -62.49063) (xy 288.674753 -62.472623) (xy 288.625153 -62.447122) (xy 288.579795 -62.414671)
			(xy 288.539646 -62.375962) (xy 288.50556 -62.331819) (xy 288.478264 -62.283184) (xy 288.458341 -62.231093)
			(xy 288.446215 -62.176656) (xy 288.442144 -62.121034) (xy 267.185966 -62.121034) (xy 267.184296 -62.132639)
			(xy 267.168936 -62.184935) (xy 267.14629 -62.234512) (xy 267.11682 -62.280363) (xy 267.081124 -62.321553)
			(xy 267.039931 -62.357244) (xy 266.994077 -62.386709) (xy 266.944497 -62.40935) (xy 266.8922 -62.424704)
			(xy 266.83825 -62.43246) (xy 266.810998 -62.432946) (xy 266.787444 -62.432565) (xy 266.740699 -62.426709)
			(xy 266.71778 -62.421262) (xy 266.708569 -62.41935) (xy 266.689916 -62.42169) (xy 266.673368 -62.430612)
			(xy 266.66698 -62.437518) (xy 266.598146 -62.517274) (xy 266.593574 -62.545468) (xy 266.599162 -62.55893)
			(xy 266.608484 -62.582315) (xy 266.621605 -62.630918) (xy 266.628223 -62.680825) (xy 266.628626 -62.705996)
			(xy 266.628119 -62.733246) (xy 266.620363 -62.787192) (xy 266.605009 -62.839486) (xy 266.58237 -62.889062)
			(xy 266.552906 -62.934911) (xy 266.517217 -62.976101) (xy 266.476029 -63.011793) (xy 266.430181 -63.041259)
			(xy 266.380606 -63.063902) (xy 266.328314 -63.079258) (xy 266.274368 -63.087017) (xy 266.247118 -63.087504)
			(xy 266.21831 -63.086947) (xy 266.16135 -63.078275) (xy 266.106341 -63.06114) (xy 266.054532 -63.035932)
			(xy 266.0071 -63.003222) (xy 265.985752 -62.983872) (xy 265.977116 -62.975744) (xy 265.955272 -62.968886)
			(xy 265.865356 -62.981332) (xy 265.853999 -62.983454) (xy 265.834813 -62.996278) (xy 265.828526 -63.00597)
			(xy 265.813691 -63.030077) (xy 265.778043 -63.074042) (xy 265.736292 -63.112261) (xy 265.689355 -63.143895)
			(xy 265.638261 -63.168249) (xy 265.584131 -63.184792) (xy 265.528151 -63.193158) (xy 265.49985 -63.193676)
			(xy 265.472599 -63.193251) (xy 265.418652 -63.185488) (xy 265.366359 -63.170127) (xy 265.316784 -63.147481)
			(xy 265.270936 -63.118011) (xy 265.229748 -63.082317) (xy 265.194059 -63.041124) (xy 265.164595 -62.995272)
			(xy 265.141955 -62.945694) (xy 265.126602 -62.893399) (xy 265.118846 -62.839451) (xy 260.259954 -62.839451)
			(xy 260.271874 -62.852755) (xy 260.302647 -62.899268) (xy 260.326319 -62.949765) (xy 260.342387 -63.003172)
			(xy 260.350507 -63.058348) (xy 260.351016 -63.086234) (xy 260.350507 -63.11412) (xy 260.342387 -63.169296)
			(xy 260.326319 -63.222703) (xy 260.302647 -63.2732) (xy 260.302494 -63.273432) (xy 261.776716 -63.273432)
			(xy 261.780787 -63.21781) (xy 261.792913 -63.163373) (xy 261.812836 -63.111282) (xy 261.840132 -63.062647)
			(xy 261.874218 -63.018504) (xy 261.914367 -62.979795) (xy 261.959725 -62.947344) (xy 262.009325 -62.921843)
			(xy 262.062109 -62.903836) (xy 262.116952 -62.893706) (xy 262.172686 -62.891669) (xy 262.228123 -62.897769)
			(xy 262.28208 -62.911875) (xy 262.333409 -62.933687) (xy 262.381015 -62.962741) (xy 262.423883 -62.998416)
			(xy 262.4611 -63.039953) (xy 262.491873 -63.086466) (xy 262.515545 -63.136963) (xy 262.531613 -63.19037)
			(xy 262.539733 -63.245546) (xy 262.539733 -63.245552) (xy 275.304469 -63.245552) (xy 275.304469 -63.191048)
			(xy 275.312226 -63.137099) (xy 275.327582 -63.084802) (xy 275.350224 -63.035224) (xy 275.379691 -62.989372)
			(xy 275.415384 -62.948181) (xy 275.456575 -62.912489) (xy 275.502427 -62.883022) (xy 275.552006 -62.86038)
			(xy 275.604303 -62.845025) (xy 275.658252 -62.837269) (xy 275.685504 -62.836806) (xy 275.712874 -62.837268)
			(xy 275.767054 -62.845087) (xy 275.819557 -62.860577) (xy 275.869304 -62.883419) (xy 275.91527 -62.913144)
			(xy 275.936202 -62.930786) (xy 275.936456 -62.93104) (xy 275.943547 -62.936619) (xy 275.960461 -62.942869)
			(xy 275.969476 -62.943232) (xy 276.036532 -62.943232) (xy 276.04555 -62.942883) (xy 276.062466 -62.936629)
			(xy 276.069552 -62.93104) (xy 276.07006 -62.930532) (xy 276.091009 -62.912938) (xy 276.136973 -62.883275)
			(xy 276.186705 -62.860485) (xy 276.239182 -62.845035) (xy 276.29333 -62.837243) (xy 276.348034 -62.837269)
			(xy 276.402174 -62.845113) (xy 276.454637 -62.860613) (xy 276.504347 -62.88345) (xy 276.550283 -62.913158)
			(xy 276.571202 -62.930786) (xy 276.571456 -62.93104) (xy 276.578547 -62.936619) (xy 276.595461 -62.942869)
			(xy 276.604476 -62.943232) (xy 276.671532 -62.943232) (xy 276.68055 -62.942883) (xy 276.697466 -62.936629)
			(xy 276.704552 -62.93104) (xy 276.70506 -62.930532) (xy 276.725994 -62.91295) (xy 276.771928 -62.883309)
			(xy 276.821624 -62.86053) (xy 276.874063 -62.84508) (xy 276.92817 -62.837275) (xy 276.955504 -62.836806)
			(xy 276.982756 -62.837264) (xy 277.036705 -62.845021) (xy 277.089002 -62.860377) (xy 277.13858 -62.88302)
			(xy 277.184432 -62.912487) (xy 277.225623 -62.94818) (xy 277.261315 -62.989372) (xy 277.290782 -63.035223)
			(xy 277.313424 -63.084802) (xy 277.313844 -63.086234) (xy 285.587438 -63.086234) (xy 285.591509 -63.030612)
			(xy 285.603635 -62.976175) (xy 285.623558 -62.924084) (xy 285.650854 -62.875449) (xy 285.68494 -62.831306)
			(xy 285.725089 -62.792597) (xy 285.770447 -62.760146) (xy 285.820047 -62.734645) (xy 285.872831 -62.716638)
			(xy 285.927674 -62.706508) (xy 285.983408 -62.704471) (xy 286.038845 -62.710571) (xy 286.092802 -62.724677)
			(xy 286.144131 -62.746489) (xy 286.191737 -62.775543) (xy 286.234605 -62.811218) (xy 286.259903 -62.839453)
			(xy 291.118746 -62.839453) (xy 291.118746 -62.784947) (xy 291.126503 -62.730994) (xy 291.141859 -62.678695)
			(xy 291.164502 -62.629114) (xy 291.193971 -62.58326) (xy 291.229665 -62.542066) (xy 291.270859 -62.506372)
			(xy 291.316713 -62.476903) (xy 291.366294 -62.45426) (xy 291.418593 -62.438903) (xy 291.472545 -62.431146)
			(xy 291.499798 -62.43066) (xy 291.528607 -62.43119) (xy 291.585569 -62.439866) (xy 291.640579 -62.457006)
			(xy 291.692388 -62.482221) (xy 291.739818 -62.514938) (xy 291.761164 -62.534292) (xy 291.7698 -62.54242)
			(xy 291.791644 -62.549278) (xy 291.88156 -62.536832) (xy 291.892923 -62.534733) (xy 291.912108 -62.521894)
			(xy 291.91839 -62.512194) (xy 291.933201 -62.488072) (xy 291.968854 -62.444108) (xy 292.01061 -62.405892)
			(xy 292.057551 -62.374261) (xy 292.108648 -62.349908) (xy 292.162782 -62.333369) (xy 292.218764 -62.325005)
			(xy 292.247066 -62.324488) (xy 292.270621 -62.324856) (xy 292.317365 -62.330721) (xy 292.340284 -62.336172)
			(xy 292.349504 -62.337985) (xy 292.368129 -62.335662) (xy 292.384657 -62.326768) (xy 292.391084 -62.319916)
			(xy 292.459918 -62.24016) (xy 292.46449 -62.211966) (xy 292.458902 -62.198504) (xy 292.449588 -62.175116)
			(xy 292.436465 -62.126514) (xy 292.429843 -62.076609) (xy 292.429438 -62.051438) (xy 292.429924 -62.024187)
			(xy 292.43768 -61.970239) (xy 292.453035 -61.917944) (xy 292.475677 -61.868367) (xy 292.505143 -61.822517)
			(xy 292.540834 -61.781326) (xy 292.582025 -61.745635) (xy 292.627875 -61.716169) (xy 292.677452 -61.693527)
			(xy 292.729747 -61.678172) (xy 292.783695 -61.670416) (xy 292.838197 -61.670416) (xy 292.892145 -61.678172)
			(xy 292.94444 -61.693527) (xy 292.994017 -61.716169) (xy 293.039867 -61.745635) (xy 293.081058 -61.781326)
			(xy 293.116749 -61.822517) (xy 293.146215 -61.868367) (xy 293.168857 -61.917944) (xy 293.184212 -61.970239)
			(xy 293.191968 -62.024187) (xy 293.192454 -62.051438) (xy 293.191958 -62.078688) (xy 293.185866 -62.121034)
			(xy 314.442092 -62.121034) (xy 314.446163 -62.065412) (xy 314.458289 -62.010975) (xy 314.478212 -61.958884)
			(xy 314.505508 -61.910249) (xy 314.539594 -61.866106) (xy 314.579743 -61.827397) (xy 314.625101 -61.794946)
			(xy 314.674701 -61.769445) (xy 314.727485 -61.751438) (xy 314.782328 -61.741308) (xy 314.838062 -61.739271)
			(xy 314.893499 -61.745371) (xy 314.947456 -61.759477) (xy 314.998785 -61.781289) (xy 315.046391 -61.810343)
			(xy 315.089259 -61.846018) (xy 315.126476 -61.887555) (xy 315.157249 -61.934068) (xy 315.180921 -61.984565)
			(xy 315.196989 -62.037972) (xy 315.205109 -62.093148) (xy 315.205618 -62.121034) (xy 315.205109 -62.14892)
			(xy 315.196989 -62.204096) (xy 315.180921 -62.257503) (xy 315.157249 -62.308) (xy 315.126476 -62.354513)
			(xy 315.089259 -62.39605) (xy 315.046391 -62.431725) (xy 314.998785 -62.460779) (xy 314.947456 -62.482591)
			(xy 314.893499 -62.496697) (xy 314.838062 -62.502797) (xy 314.782328 -62.50076) (xy 314.727485 -62.49063)
			(xy 314.674701 -62.472623) (xy 314.625101 -62.447122) (xy 314.579743 -62.414671) (xy 314.539594 -62.375962)
			(xy 314.505508 -62.331819) (xy 314.478212 -62.283184) (xy 314.458289 -62.231093) (xy 314.446163 -62.176656)
			(xy 314.442092 -62.121034) (xy 293.185866 -62.121034) (xy 293.184197 -62.132633) (xy 293.16884 -62.184925)
			(xy 293.146197 -62.234499) (xy 293.116731 -62.280347) (xy 293.081041 -62.321536) (xy 293.039853 -62.357227)
			(xy 292.994006 -62.386694) (xy 292.944432 -62.409337) (xy 292.892141 -62.424695) (xy 292.838196 -62.432457)
			(xy 292.810946 -62.432946) (xy 292.787391 -62.432575) (xy 292.740647 -62.426712) (xy 292.717728 -62.421262)
			(xy 292.70852 -62.419365) (xy 292.689881 -62.42172) (xy 292.67335 -62.430649) (xy 292.666928 -62.437518)
			(xy 292.598094 -62.517274) (xy 292.593522 -62.545468) (xy 292.59911 -62.55893) (xy 292.608434 -62.582314)
			(xy 292.621554 -62.630918) (xy 292.628171 -62.680824) (xy 292.628574 -62.705996) (xy 292.628141 -62.73325)
			(xy 292.620384 -62.787204) (xy 292.605026 -62.839505) (xy 292.582382 -62.889087) (xy 292.552911 -62.934942)
			(xy 292.517214 -62.976135) (xy 292.476018 -63.011829) (xy 292.430161 -63.041296) (xy 292.380576 -63.063937)
			(xy 292.328275 -63.07929) (xy 292.27432 -63.087043) (xy 292.247066 -63.087504) (xy 292.218257 -63.086979)
			(xy 292.161295 -63.078299) (xy 292.106286 -63.061157) (xy 292.054477 -63.035941) (xy 292.007047 -63.003225)
			(xy 291.9857 -62.983872) (xy 291.977064 -62.975744) (xy 291.95522 -62.968886) (xy 291.865304 -62.981332)
			(xy 291.85394 -62.983427) (xy 291.834757 -62.996271) (xy 291.828474 -63.00597) (xy 291.813606 -63.030056)
			(xy 291.777963 -63.074021) (xy 291.736218 -63.112241) (xy 291.689287 -63.143877) (xy 291.638198 -63.168235)
			(xy 291.584073 -63.184782) (xy 291.528097 -63.193155) (xy 291.499798 -63.193676) (xy 291.472545 -63.193254)
			(xy 291.418593 -63.185497) (xy 291.366294 -63.17014) (xy 291.316713 -63.147497) (xy 291.270859 -63.118028)
			(xy 291.229665 -63.082334) (xy 291.193971 -63.04114) (xy 291.164502 -62.995286) (xy 291.141859 -62.945705)
			(xy 291.126503 -62.893406) (xy 291.118746 -62.839453) (xy 286.259903 -62.839453) (xy 286.271822 -62.852755)
			(xy 286.302595 -62.899268) (xy 286.326267 -62.949765) (xy 286.342335 -63.003172) (xy 286.350455 -63.058348)
			(xy 286.350964 -63.086234) (xy 286.350455 -63.11412) (xy 286.342335 -63.169296) (xy 286.326267 -63.222703)
			(xy 286.302595 -63.2732) (xy 286.302442 -63.273432) (xy 287.776664 -63.273432) (xy 287.780735 -63.21781)
			(xy 287.792861 -63.163373) (xy 287.812784 -63.111282) (xy 287.84008 -63.062647) (xy 287.874166 -63.018504)
			(xy 287.914315 -62.979795) (xy 287.959673 -62.947344) (xy 288.009273 -62.921843) (xy 288.062057 -62.903836)
			(xy 288.1169 -62.893706) (xy 288.172634 -62.891669) (xy 288.228071 -62.897769) (xy 288.282028 -62.911875)
			(xy 288.333357 -62.933687) (xy 288.380963 -62.962741) (xy 288.423831 -62.998416) (xy 288.461048 -63.039953)
			(xy 288.491821 -63.086466) (xy 288.515493 -63.136963) (xy 288.531561 -63.19037) (xy 288.539681 -63.245546)
			(xy 288.539681 -63.245548) (xy 301.304492 -63.245548) (xy 301.304492 -63.191052) (xy 301.312247 -63.137111)
			(xy 301.327599 -63.084822) (xy 301.350236 -63.035249) (xy 301.379697 -62.989403) (xy 301.415382 -62.948216)
			(xy 301.456565 -62.912525) (xy 301.502407 -62.883059) (xy 301.551977 -62.860416) (xy 301.604264 -62.845057)
			(xy 301.658204 -62.837296) (xy 301.685452 -62.836806) (xy 301.712821 -62.837299) (xy 301.766999 -62.84511)
			(xy 301.819502 -62.860593) (xy 301.869249 -62.883428) (xy 301.915217 -62.913147) (xy 301.93615 -62.930786)
			(xy 301.936404 -62.93104) (xy 301.943482 -62.936639) (xy 301.960405 -62.942877) (xy 301.969424 -62.943232)
			(xy 302.03648 -62.943232) (xy 302.045495 -62.942858) (xy 302.062412 -62.936622) (xy 302.0695 -62.93104)
			(xy 302.070008 -62.930532) (xy 302.090919 -62.912891) (xy 302.13689 -62.88323) (xy 302.186627 -62.860442)
			(xy 302.239111 -62.844996) (xy 302.293263 -62.837209) (xy 302.347973 -62.837241) (xy 302.402116 -62.84509)
			(xy 302.454582 -62.860596) (xy 302.504294 -62.88344) (xy 302.550231 -62.913154) (xy 302.57115 -62.930786)
			(xy 302.571404 -62.93104) (xy 302.578482 -62.936639) (xy 302.595405 -62.942877) (xy 302.604424 -62.943232)
			(xy 302.67148 -62.943232) (xy 302.680495 -62.942858) (xy 302.697412 -62.936622) (xy 302.7045 -62.93104)
			(xy 302.705008 -62.930532) (xy 302.725924 -62.912927) (xy 302.771863 -62.88329) (xy 302.821563 -62.860515)
			(xy 302.874006 -62.84507) (xy 302.928117 -62.837272) (xy 302.955452 -62.836806) (xy 302.982708 -62.837238)
			(xy 303.036666 -62.844989) (xy 303.088972 -62.860342) (xy 303.13856 -62.882982) (xy 303.184421 -62.91245)
			(xy 303.225621 -62.948145) (xy 303.261321 -62.989341) (xy 303.290795 -63.035198) (xy 303.313441 -63.084783)
			(xy 303.313867 -63.086234) (xy 311.587386 -63.086234) (xy 311.591457 -63.030612) (xy 311.603583 -62.976175)
			(xy 311.623506 -62.924084) (xy 311.650802 -62.875449) (xy 311.684888 -62.831306) (xy 311.725037 -62.792597)
			(xy 311.770395 -62.760146) (xy 311.819995 -62.734645) (xy 311.872779 -62.716638) (xy 311.927622 -62.706508)
			(xy 311.983356 -62.704471) (xy 312.038793 -62.710571) (xy 312.09275 -62.724677) (xy 312.144079 -62.746489)
			(xy 312.191685 -62.775543) (xy 312.234553 -62.811218) (xy 312.259855 -62.839457) (xy 317.118623 -62.839457)
			(xy 317.118623 -62.784943) (xy 317.126382 -62.730983) (xy 317.141742 -62.678677) (xy 317.164389 -62.62909)
			(xy 317.193864 -62.583231) (xy 317.229566 -62.542033) (xy 317.270767 -62.506337) (xy 317.31663 -62.476867)
			(xy 317.36622 -62.454225) (xy 317.418528 -62.438872) (xy 317.472489 -62.43112) (xy 317.499746 -62.43066)
			(xy 317.528556 -62.43116) (xy 317.58552 -62.439844) (xy 317.64053 -62.456991) (xy 317.692338 -62.482212)
			(xy 317.739766 -62.514935) (xy 317.761112 -62.534292) (xy 317.769748 -62.54242) (xy 317.791592 -62.549278)
			(xy 317.881508 -62.536832) (xy 317.892878 -62.534757) (xy 317.91206 -62.5219) (xy 317.918338 -62.512194)
			(xy 317.933184 -62.488095) (xy 317.968833 -62.444131) (xy 318.010582 -62.405914) (xy 318.057517 -62.37428)
			(xy 318.108608 -62.349924) (xy 318.162736 -62.333379) (xy 318.218714 -62.325008) (xy 318.247014 -62.324488)
			(xy 318.270569 -62.324865) (xy 318.317313 -62.330724) (xy 318.340232 -62.336172) (xy 318.349446 -62.338025)
			(xy 318.368077 -62.335685) (xy 318.384606 -62.326775) (xy 318.391032 -62.319916) (xy 318.459866 -62.24016)
			(xy 318.464438 -62.211966) (xy 318.45885 -62.198504) (xy 318.449539 -62.175115) (xy 318.436414 -62.126514)
			(xy 318.429791 -62.076609) (xy 318.429386 -62.051438) (xy 318.429872 -62.024187) (xy 318.437628 -61.970239)
			(xy 318.452983 -61.917944) (xy 318.475625 -61.868367) (xy 318.505091 -61.822517) (xy 318.540782 -61.781326)
			(xy 318.581973 -61.745635) (xy 318.627823 -61.716169) (xy 318.6774 -61.693527) (xy 318.729695 -61.678172)
			(xy 318.783643 -61.670416) (xy 318.838145 -61.670416) (xy 318.892093 -61.678172) (xy 318.944388 -61.693527)
			(xy 318.993965 -61.716169) (xy 319.039815 -61.745635) (xy 319.081006 -61.781326) (xy 319.116697 -61.822517)
			(xy 319.146163 -61.868367) (xy 319.168805 -61.917944) (xy 319.18416 -61.970239) (xy 319.191916 -62.024187)
			(xy 319.192402 -62.051438) (xy 319.191958 -62.07869) (xy 319.185866 -62.121034) (xy 352.542346 -62.121034)
			(xy 352.546417 -62.065412) (xy 352.558543 -62.010975) (xy 352.578466 -61.958884) (xy 352.605762 -61.910249)
			(xy 352.639848 -61.866106) (xy 352.679997 -61.827397) (xy 352.725355 -61.794946) (xy 352.774955 -61.769445)
			(xy 352.827739 -61.751438) (xy 352.882582 -61.741308) (xy 352.938316 -61.739271) (xy 352.993753 -61.745371)
			(xy 353.04771 -61.759477) (xy 353.099039 -61.781289) (xy 353.146645 -61.810343) (xy 353.189513 -61.846018)
			(xy 353.22673 -61.887555) (xy 353.257503 -61.934068) (xy 353.281175 -61.984565) (xy 353.297243 -62.037972)
			(xy 353.305363 -62.093148) (xy 353.305872 -62.121034) (xy 353.305363 -62.14892) (xy 353.297243 -62.204096)
			(xy 353.281175 -62.257503) (xy 353.257503 -62.308) (xy 353.22673 -62.354513) (xy 353.189513 -62.39605)
			(xy 353.146645 -62.431725) (xy 353.099039 -62.460779) (xy 353.04771 -62.482591) (xy 352.993753 -62.496697)
			(xy 352.938316 -62.502797) (xy 352.882582 -62.50076) (xy 352.827739 -62.49063) (xy 352.774955 -62.472623)
			(xy 352.725355 -62.447122) (xy 352.679997 -62.414671) (xy 352.639848 -62.375962) (xy 352.605762 -62.331819)
			(xy 352.578466 -62.283184) (xy 352.558543 -62.231093) (xy 352.546417 -62.176656) (xy 352.542346 -62.121034)
			(xy 319.185866 -62.121034) (xy 319.184196 -62.13264) (xy 319.168835 -62.184936) (xy 319.146189 -62.234514)
			(xy 319.116719 -62.280364) (xy 319.081023 -62.321554) (xy 319.039829 -62.357245) (xy 318.993975 -62.386711)
			(xy 318.944395 -62.409351) (xy 318.892097 -62.424705) (xy 318.838147 -62.432461) (xy 318.810894 -62.432946)
			(xy 318.787339 -62.432566) (xy 318.740595 -62.426709) (xy 318.717676 -62.421262) (xy 318.708465 -62.419347)
			(xy 318.689812 -62.421688) (xy 318.673264 -62.430612) (xy 318.666876 -62.437518) (xy 318.598042 -62.517274)
			(xy 318.59347 -62.545468) (xy 318.599058 -62.55893) (xy 318.60838 -62.582315) (xy 318.621501 -62.630918)
			(xy 318.628119 -62.680825) (xy 318.628522 -62.705996) (xy 318.628019 -62.733247) (xy 318.620263 -62.787193)
			(xy 318.604909 -62.839486) (xy 318.582269 -62.889063) (xy 318.552805 -62.934912) (xy 318.517115 -62.976102)
			(xy 318.475927 -63.011794) (xy 318.430079 -63.041261) (xy 318.380503 -63.063903) (xy 318.32821 -63.079259)
			(xy 318.274264 -63.087017) (xy 318.247014 -63.087504) (xy 318.218206 -63.08695) (xy 318.161246 -63.078277)
			(xy 318.106236 -63.061142) (xy 318.054427 -63.035932) (xy 318.006996 -63.003223) (xy 317.985648 -62.983872)
			(xy 317.977012 -62.975744) (xy 317.955168 -62.968886) (xy 317.865252 -62.981332) (xy 317.853895 -62.983452)
			(xy 317.834709 -62.996277) (xy 317.828422 -63.00597) (xy 317.81359 -63.030079) (xy 317.777941 -63.074044)
			(xy 317.73619 -63.112263) (xy 317.689253 -63.143896) (xy 317.638158 -63.168251) (xy 317.584027 -63.184792)
			(xy 317.528047 -63.193158) (xy 317.499746 -63.193676) (xy 317.472489 -63.19328) (xy 317.418528 -63.185528)
			(xy 317.36622 -63.170175) (xy 317.31663 -63.147533) (xy 317.270767 -63.118063) (xy 317.229566 -63.082367)
			(xy 317.193864 -63.041169) (xy 317.164389 -62.99531) (xy 317.141742 -62.945723) (xy 317.126382 -62.893417)
			(xy 317.118623 -62.839457) (xy 312.259855 -62.839457) (xy 312.27177 -62.852755) (xy 312.302543 -62.899268)
			(xy 312.326215 -62.949765) (xy 312.342283 -63.003172) (xy 312.350403 -63.058348) (xy 312.350912 -63.086234)
			(xy 312.350403 -63.11412) (xy 312.342283 -63.169296) (xy 312.326215 -63.222703) (xy 312.302543 -63.2732)
			(xy 312.30239 -63.273432) (xy 313.776612 -63.273432) (xy 313.780683 -63.21781) (xy 313.792809 -63.163373)
			(xy 313.812732 -63.111282) (xy 313.840028 -63.062647) (xy 313.874114 -63.018504) (xy 313.914263 -62.979795)
			(xy 313.959621 -62.947344) (xy 314.009221 -62.921843) (xy 314.062005 -62.903836) (xy 314.116848 -62.893706)
			(xy 314.172582 -62.891669) (xy 314.228019 -62.897769) (xy 314.281976 -62.911875) (xy 314.333305 -62.933687)
			(xy 314.380911 -62.962741) (xy 314.423779 -62.998416) (xy 314.460996 -63.039953) (xy 314.491769 -63.086466)
			(xy 314.515441 -63.136963) (xy 314.531509 -63.19037) (xy 314.539629 -63.245546) (xy 314.539629 -63.24555)
			(xy 327.304392 -63.24555) (xy 327.304392 -63.19105) (xy 327.312148 -63.137104) (xy 327.327503 -63.084811)
			(xy 327.350143 -63.035236) (xy 327.379608 -62.989387) (xy 327.415299 -62.948199) (xy 327.456487 -62.912508)
			(xy 327.502336 -62.883043) (xy 327.551911 -62.860403) (xy 327.604204 -62.845048) (xy 327.65815 -62.837292)
			(xy 327.6854 -62.836806) (xy 327.71277 -62.837271) (xy 327.76695 -62.845089) (xy 327.819453 -62.860578)
			(xy 327.8692 -62.88342) (xy 327.915166 -62.913145) (xy 327.936098 -62.930786) (xy 327.936352 -62.93104)
			(xy 327.943445 -62.936618) (xy 327.960357 -62.942869) (xy 327.969372 -62.943232) (xy 328.036428 -62.943232)
			(xy 328.045445 -62.942882) (xy 328.062362 -62.936629) (xy 328.069448 -62.93104) (xy 328.069956 -62.930532)
			(xy 328.090908 -62.912942) (xy 328.136872 -62.883279) (xy 328.186603 -62.860488) (xy 328.23908 -62.845038)
			(xy 328.293227 -62.837246) (xy 328.347931 -62.837272) (xy 328.402071 -62.845115) (xy 328.454533 -62.860614)
			(xy 328.504243 -62.883451) (xy 328.550179 -62.913158) (xy 328.571098 -62.930786) (xy 328.571352 -62.93104)
			(xy 328.578445 -62.936618) (xy 328.595357 -62.942869) (xy 328.604372 -62.943232) (xy 328.671428 -62.943232)
			(xy 328.680445 -62.942882) (xy 328.697362 -62.936629) (xy 328.704448 -62.93104) (xy 328.704956 -62.930532)
			(xy 328.725892 -62.912952) (xy 328.771825 -62.88331) (xy 328.821521 -62.860531) (xy 328.873959 -62.845081)
			(xy 328.928066 -62.837275) (xy 328.9554 -62.836806) (xy 328.982652 -62.837264) (xy 329.036602 -62.845021)
			(xy 329.088899 -62.860376) (xy 329.138478 -62.883018) (xy 329.18433 -62.912486) (xy 329.225522 -62.948178)
			(xy 329.261214 -62.98937) (xy 329.290682 -63.035222) (xy 329.313324 -63.084801) (xy 329.313745 -63.086234)
			(xy 349.68764 -63.086234) (xy 349.691711 -63.030612) (xy 349.703837 -62.976175) (xy 349.72376 -62.924084)
			(xy 349.751056 -62.875449) (xy 349.785142 -62.831306) (xy 349.825291 -62.792597) (xy 349.870649 -62.760146)
			(xy 349.920249 -62.734645) (xy 349.973033 -62.716638) (xy 350.027876 -62.706508) (xy 350.08361 -62.704471)
			(xy 350.139047 -62.710571) (xy 350.193004 -62.724677) (xy 350.244333 -62.746489) (xy 350.291939 -62.775543)
			(xy 350.334807 -62.811218) (xy 350.360106 -62.839454) (xy 355.218946 -62.839454) (xy 355.218946 -62.784946)
			(xy 355.226703 -62.730994) (xy 355.242059 -62.678695) (xy 355.264702 -62.629114) (xy 355.294171 -62.583259)
			(xy 355.329866 -62.542066) (xy 355.371059 -62.506371) (xy 355.416914 -62.476902) (xy 355.466495 -62.454259)
			(xy 355.518794 -62.438903) (xy 355.572746 -62.431146) (xy 355.6 -62.43066) (xy 355.628809 -62.431188)
			(xy 355.685771 -62.439865) (xy 355.740782 -62.457005) (xy 355.79259 -62.482221) (xy 355.84002 -62.514938)
			(xy 355.861366 -62.534292) (xy 355.870002 -62.54242) (xy 355.891846 -62.549278) (xy 355.981762 -62.536832)
			(xy 355.993126 -62.534734) (xy 356.01231 -62.521894) (xy 356.018592 -62.512194) (xy 356.033401 -62.488071)
			(xy 356.069055 -62.444107) (xy 356.110811 -62.405891) (xy 356.157752 -62.37426) (xy 356.20885 -62.349908)
			(xy 356.262983 -62.333368) (xy 356.318966 -62.325005) (xy 356.347268 -62.324488) (xy 356.370823 -62.324856)
			(xy 356.417567 -62.330721) (xy 356.440486 -62.336172) (xy 356.449706 -62.337987) (xy 356.468331 -62.335662)
			(xy 356.484859 -62.326768) (xy 356.491286 -62.319916) (xy 356.56012 -62.24016) (xy 356.564692 -62.211966)
			(xy 356.559104 -62.198504) (xy 356.549791 -62.175116) (xy 356.536667 -62.126514) (xy 356.530045 -62.076609)
			(xy 356.52964 -62.051438) (xy 356.530126 -62.024187) (xy 356.537882 -61.970239) (xy 356.553237 -61.917944)
			(xy 356.575879 -61.868367) (xy 356.605345 -61.822517) (xy 356.641036 -61.781326) (xy 356.682227 -61.745635)
			(xy 356.728077 -61.716169) (xy 356.777654 -61.693527) (xy 356.829949 -61.678172) (xy 356.883897 -61.670416)
			(xy 356.938399 -61.670416) (xy 356.992347 -61.678172) (xy 357.044642 -61.693527) (xy 357.094219 -61.716169)
			(xy 357.140069 -61.745635) (xy 357.18126 -61.781326) (xy 357.216951 -61.822517) (xy 357.246417 -61.868367)
			(xy 357.269059 -61.917944) (xy 357.284414 -61.970239) (xy 357.29217 -62.024187) (xy 357.292656 -62.051438)
			(xy 357.292158 -62.078688) (xy 357.286066 -62.121034) (xy 378.542294 -62.121034) (xy 378.546365 -62.065412)
			(xy 378.558491 -62.010975) (xy 378.578414 -61.958884) (xy 378.60571 -61.910249) (xy 378.639796 -61.866106)
			(xy 378.679945 -61.827397) (xy 378.725303 -61.794946) (xy 378.774903 -61.769445) (xy 378.827687 -61.751438)
			(xy 378.88253 -61.741308) (xy 378.938264 -61.739271) (xy 378.993701 -61.745371) (xy 379.047658 -61.759477)
			(xy 379.098987 -61.781289) (xy 379.146593 -61.810343) (xy 379.189461 -61.846018) (xy 379.226678 -61.887555)
			(xy 379.257451 -61.934068) (xy 379.281123 -61.984565) (xy 379.297191 -62.037972) (xy 379.305311 -62.093148)
			(xy 379.30582 -62.121034) (xy 379.305311 -62.14892) (xy 379.297191 -62.204096) (xy 379.281123 -62.257503)
			(xy 379.257451 -62.308) (xy 379.226678 -62.354513) (xy 379.189461 -62.39605) (xy 379.146593 -62.431725)
			(xy 379.098987 -62.460779) (xy 379.047658 -62.482591) (xy 378.993701 -62.496697) (xy 378.938264 -62.502797)
			(xy 378.88253 -62.50076) (xy 378.827687 -62.49063) (xy 378.774903 -62.472623) (xy 378.725303 -62.447122)
			(xy 378.679945 -62.414671) (xy 378.639796 -62.375962) (xy 378.60571 -62.331819) (xy 378.578414 -62.283184)
			(xy 378.558491 -62.231093) (xy 378.546365 -62.176656) (xy 378.542294 -62.121034) (xy 357.286066 -62.121034)
			(xy 357.284397 -62.132633) (xy 357.26904 -62.184924) (xy 357.246398 -62.234499) (xy 357.216932 -62.280346)
			(xy 357.181242 -62.321535) (xy 357.140054 -62.357226) (xy 357.094207 -62.386693) (xy 357.044634 -62.409336)
			(xy 356.992343 -62.424695) (xy 356.938398 -62.432457) (xy 356.911148 -62.432946) (xy 356.887593 -62.432575)
			(xy 356.840849 -62.426712) (xy 356.81793 -62.421262) (xy 356.808722 -62.419366) (xy 356.790083 -62.421721)
			(xy 356.773553 -62.430649) (xy 356.76713 -62.437518) (xy 356.698296 -62.517274) (xy 356.693724 -62.545468)
			(xy 356.699312 -62.55893) (xy 356.708637 -62.582314) (xy 356.721756 -62.630918) (xy 356.728373 -62.680824)
			(xy 356.728776 -62.705996) (xy 356.728341 -62.73325) (xy 356.720584 -62.787204) (xy 356.705226 -62.839504)
			(xy 356.682582 -62.889086) (xy 356.653112 -62.934941) (xy 356.617415 -62.976135) (xy 356.576219 -63.011828)
			(xy 356.530362 -63.041296) (xy 356.480778 -63.063936) (xy 356.428476 -63.07929) (xy 356.374522 -63.087043)
			(xy 356.347268 -63.087504) (xy 356.318459 -63.086978) (xy 356.261498 -63.078298) (xy 356.206488 -63.061156)
			(xy 356.154679 -63.035941) (xy 356.107249 -63.003225) (xy 356.085902 -62.983872) (xy 356.077266 -62.975744)
			(xy 356.055422 -62.968886) (xy 355.965506 -62.981332) (xy 355.954142 -62.983428) (xy 355.934959 -62.996271)
			(xy 355.928676 -63.00597) (xy 355.913807 -63.030055) (xy 355.878164 -63.07402) (xy 355.836419 -63.11224)
			(xy 355.789488 -63.143876) (xy 355.7384 -63.168235) (xy 355.684275 -63.184782) (xy 355.628299 -63.193155)
			(xy 355.6 -63.193676) (xy 355.572746 -63.193254) (xy 355.518794 -63.185497) (xy 355.466495 -63.170141)
			(xy 355.416914 -63.147498) (xy 355.371059 -63.118029) (xy 355.329866 -63.082334) (xy 355.294171 -63.041141)
			(xy 355.264702 -62.995286) (xy 355.242059 -62.945705) (xy 355.226703 -62.893406) (xy 355.218946 -62.839454)
			(xy 350.360106 -62.839454) (xy 350.372024 -62.852755) (xy 350.402797 -62.899268) (xy 350.426469 -62.949765)
			(xy 350.442537 -63.003172) (xy 350.450657 -63.058348) (xy 350.451166 -63.086234) (xy 350.450657 -63.11412)
			(xy 350.442537 -63.169296) (xy 350.426469 -63.222703) (xy 350.402797 -63.2732) (xy 350.402644 -63.273432)
			(xy 351.876866 -63.273432) (xy 351.880937 -63.21781) (xy 351.893063 -63.163373) (xy 351.912986 -63.111282)
			(xy 351.940282 -63.062647) (xy 351.974368 -63.018504) (xy 352.014517 -62.979795) (xy 352.059875 -62.947344)
			(xy 352.109475 -62.921843) (xy 352.162259 -62.903836) (xy 352.217102 -62.893706) (xy 352.272836 -62.891669)
			(xy 352.328273 -62.897769) (xy 352.38223 -62.911875) (xy 352.433559 -62.933687) (xy 352.481165 -62.962741)
			(xy 352.524033 -62.998416) (xy 352.56125 -63.039953) (xy 352.592023 -63.086466) (xy 352.615695 -63.136963)
			(xy 352.631763 -63.19037) (xy 352.639883 -63.245546) (xy 352.639883 -63.245548) (xy 365.404692 -63.245548)
			(xy 365.404692 -63.191052) (xy 365.412447 -63.13711) (xy 365.427799 -63.084821) (xy 365.450436 -63.035249)
			(xy 365.479897 -62.989402) (xy 365.515582 -62.948215) (xy 365.556766 -62.912525) (xy 365.602608 -62.883058)
			(xy 365.652178 -62.860415) (xy 365.704465 -62.845057) (xy 365.758406 -62.837295) (xy 365.785654 -62.836806)
			(xy 365.813023 -62.837298) (xy 365.867201 -62.845109) (xy 365.919704 -62.860592) (xy 365.969452 -62.883428)
			(xy 366.015419 -62.913147) (xy 366.036352 -62.930786) (xy 366.036606 -62.93104) (xy 366.043683 -62.93664)
			(xy 366.060607 -62.942878) (xy 366.069626 -62.943232) (xy 366.136682 -62.943232) (xy 366.145697 -62.942859)
			(xy 366.162614 -62.936622) (xy 366.169702 -62.93104) (xy 366.17021 -62.930532) (xy 366.191119 -62.912889)
			(xy 366.23709 -62.883228) (xy 366.286828 -62.860441) (xy 366.339312 -62.844995) (xy 366.393465 -62.837208)
			(xy 366.448174 -62.837239) (xy 366.502318 -62.845089) (xy 366.554784 -62.860595) (xy 366.604496 -62.88344)
			(xy 366.650433 -62.913154) (xy 366.671352 -62.930786) (xy 366.671606 -62.93104) (xy 366.678683 -62.93664)
			(xy 366.695607 -62.942878) (xy 366.704626 -62.943232) (xy 366.771682 -62.943232) (xy 366.780697 -62.942859)
			(xy 366.797614 -62.936622) (xy 366.804702 -62.93104) (xy 366.80521 -62.930532) (xy 366.826125 -62.912926)
			(xy 366.872065 -62.883289) (xy 366.921765 -62.860515) (xy 366.974208 -62.84507) (xy 367.028319 -62.837272)
			(xy 367.055654 -62.836806) (xy 367.08291 -62.837238) (xy 367.136868 -62.84499) (xy 367.189173 -62.860342)
			(xy 367.238761 -62.882983) (xy 367.284622 -62.912451) (xy 367.325821 -62.948146) (xy 367.361521 -62.989341)
			(xy 367.390995 -63.035198) (xy 367.413642 -63.084784) (xy 367.414068 -63.086234) (xy 375.687588 -63.086234)
			(xy 375.691659 -63.030612) (xy 375.703785 -62.976175) (xy 375.723708 -62.924084) (xy 375.751004 -62.875449)
			(xy 375.78509 -62.831306) (xy 375.825239 -62.792597) (xy 375.870597 -62.760146) (xy 375.920197 -62.734645)
			(xy 375.972981 -62.716638) (xy 376.027824 -62.706508) (xy 376.083558 -62.704471) (xy 376.138995 -62.710571)
			(xy 376.192952 -62.724677) (xy 376.244281 -62.746489) (xy 376.291887 -62.775543) (xy 376.334755 -62.811218)
			(xy 376.360057 -62.839457) (xy 381.218823 -62.839457) (xy 381.218823 -62.784943) (xy 381.226582 -62.730983)
			(xy 381.241942 -62.678677) (xy 381.26459 -62.629089) (xy 381.294065 -62.58323) (xy 381.329766 -62.542033)
			(xy 381.370968 -62.506336) (xy 381.416831 -62.476867) (xy 381.466422 -62.454225) (xy 381.51873 -62.438872)
			(xy 381.572691 -62.43112) (xy 381.599948 -62.43066) (xy 381.628758 -62.431159) (xy 381.685722 -62.439843)
			(xy 381.740732 -62.45699) (xy 381.79254 -62.482212) (xy 381.839969 -62.514935) (xy 381.861314 -62.534292)
			(xy 381.86995 -62.54242) (xy 381.891794 -62.549278) (xy 381.98171 -62.536832) (xy 381.99308 -62.534759)
			(xy 382.012262 -62.521901) (xy 382.01854 -62.512194) (xy 382.033385 -62.488094) (xy 382.069033 -62.44413)
			(xy 382.110783 -62.405913) (xy 382.157718 -62.374279) (xy 382.20881 -62.349923) (xy 382.262938 -62.333379)
			(xy 382.318916 -62.325008) (xy 382.347216 -62.324488) (xy 382.370771 -62.324865) (xy 382.417515 -62.330724)
			(xy 382.440434 -62.336172) (xy 382.449648 -62.338027) (xy 382.468279 -62.335686) (xy 382.484808 -62.326775)
			(xy 382.491234 -62.319916) (xy 382.560068 -62.24016) (xy 382.56464 -62.211966) (xy 382.559052 -62.198504)
			(xy 382.549741 -62.175115) (xy 382.536616 -62.126514) (xy 382.529993 -62.076609) (xy 382.529588 -62.051438)
			(xy 382.530074 -62.024187) (xy 382.53783 -61.970239) (xy 382.553185 -61.917944) (xy 382.575827 -61.868367)
			(xy 382.605293 -61.822517) (xy 382.640984 -61.781326) (xy 382.682175 -61.745635) (xy 382.728025 -61.716169)
			(xy 382.777602 -61.693527) (xy 382.829897 -61.678172) (xy 382.883845 -61.670416) (xy 382.938347 -61.670416)
			(xy 382.992295 -61.678172) (xy 383.04459 -61.693527) (xy 383.094167 -61.716169) (xy 383.140017 -61.745635)
			(xy 383.181208 -61.781326) (xy 383.216899 -61.822517) (xy 383.246365 -61.868367) (xy 383.269007 -61.917944)
			(xy 383.284362 -61.970239) (xy 383.292118 -62.024187) (xy 383.292604 -62.051438) (xy 383.292158 -62.07869)
			(xy 383.286066 -62.121034) (xy 404.542242 -62.121034) (xy 404.546313 -62.065412) (xy 404.558439 -62.010975)
			(xy 404.578362 -61.958884) (xy 404.605658 -61.910249) (xy 404.639744 -61.866106) (xy 404.679893 -61.827397)
			(xy 404.725251 -61.794946) (xy 404.774851 -61.769445) (xy 404.827635 -61.751438) (xy 404.882478 -61.741308)
			(xy 404.938212 -61.739271) (xy 404.993649 -61.745371) (xy 405.047606 -61.759477) (xy 405.098935 -61.781289)
			(xy 405.146541 -61.810343) (xy 405.189409 -61.846018) (xy 405.226626 -61.887555) (xy 405.257399 -61.934068)
			(xy 405.281071 -61.984565) (xy 405.297139 -62.037972) (xy 405.305259 -62.093148) (xy 405.305768 -62.121034)
			(xy 405.305259 -62.14892) (xy 405.297139 -62.204096) (xy 405.281071 -62.257503) (xy 405.257399 -62.308)
			(xy 405.226626 -62.354513) (xy 405.189409 -62.39605) (xy 405.146541 -62.431725) (xy 405.098935 -62.460779)
			(xy 405.047606 -62.482591) (xy 404.993649 -62.496697) (xy 404.938212 -62.502797) (xy 404.882478 -62.50076)
			(xy 404.827635 -62.49063) (xy 404.774851 -62.472623) (xy 404.725251 -62.447122) (xy 404.679893 -62.414671)
			(xy 404.639744 -62.375962) (xy 404.605658 -62.331819) (xy 404.578362 -62.283184) (xy 404.558439 -62.231093)
			(xy 404.546313 -62.176656) (xy 404.542242 -62.121034) (xy 383.286066 -62.121034) (xy 383.284396 -62.13264)
			(xy 383.269036 -62.184935) (xy 383.24639 -62.234513) (xy 383.216919 -62.280363) (xy 383.181224 -62.321553)
			(xy 383.14003 -62.357244) (xy 383.094176 -62.38671) (xy 383.044596 -62.40935) (xy 382.992299 -62.424705)
			(xy 382.938348 -62.432461) (xy 382.911096 -62.432946) (xy 382.887541 -62.432566) (xy 382.840797 -62.426709)
			(xy 382.817878 -62.421262) (xy 382.808667 -62.419349) (xy 382.790014 -62.421689) (xy 382.773466 -62.430612)
			(xy 382.767078 -62.437518) (xy 382.698244 -62.517274) (xy 382.693672 -62.545468) (xy 382.69926 -62.55893)
			(xy 382.708582 -62.582315) (xy 382.721703 -62.630918) (xy 382.728321 -62.680825) (xy 382.728724 -62.705996)
			(xy 382.728219 -62.733246) (xy 382.720463 -62.787193) (xy 382.705109 -62.839486) (xy 382.68247 -62.889062)
			(xy 382.653005 -62.934912) (xy 382.617316 -62.976102) (xy 382.576128 -63.011793) (xy 382.53028 -63.04126)
			(xy 382.480705 -63.063902) (xy 382.428412 -63.079259) (xy 382.374466 -63.087017) (xy 382.347216 -63.087504)
			(xy 382.318408 -63.086949) (xy 382.261448 -63.078276) (xy 382.206439 -63.061141) (xy 382.15463 -63.035932)
			(xy 382.107198 -63.003223) (xy 382.08585 -62.983872) (xy 382.077214 -62.975744) (xy 382.05537 -62.968886)
			(xy 381.965454 -62.981332) (xy 381.954097 -62.983453) (xy 381.934911 -62.996278) (xy 381.928624 -63.00597)
			(xy 381.913791 -63.030078) (xy 381.878142 -63.074043) (xy 381.836391 -63.112262) (xy 381.789454 -63.143895)
			(xy 381.73836 -63.16825) (xy 381.684229 -63.184792) (xy 381.628249 -63.193158) (xy 381.599948 -63.193676)
			(xy 381.572691 -63.19328) (xy 381.51873 -63.185528) (xy 381.466422 -63.170175) (xy 381.416831 -63.147533)
			(xy 381.370968 -63.118064) (xy 381.329766 -63.082367) (xy 381.294065 -63.04117) (xy 381.26459 -62.995311)
			(xy 381.241942 -62.945723) (xy 381.226582 -62.893417) (xy 381.218823 -62.839457) (xy 376.360057 -62.839457)
			(xy 376.371972 -62.852755) (xy 376.402745 -62.899268) (xy 376.426417 -62.949765) (xy 376.442485 -63.003172)
			(xy 376.450605 -63.058348) (xy 376.451114 -63.086234) (xy 376.450605 -63.11412) (xy 376.442485 -63.169296)
			(xy 376.426417 -63.222703) (xy 376.402745 -63.2732) (xy 376.402592 -63.273432) (xy 377.876814 -63.273432)
			(xy 377.880885 -63.21781) (xy 377.893011 -63.163373) (xy 377.912934 -63.111282) (xy 377.94023 -63.062647)
			(xy 377.974316 -63.018504) (xy 378.014465 -62.979795) (xy 378.059823 -62.947344) (xy 378.109423 -62.921843)
			(xy 378.162207 -62.903836) (xy 378.21705 -62.893706) (xy 378.272784 -62.891669) (xy 378.328221 -62.897769)
			(xy 378.382178 -62.911875) (xy 378.433507 -62.933687) (xy 378.481113 -62.962741) (xy 378.523981 -62.998416)
			(xy 378.561198 -63.039953) (xy 378.591971 -63.086466) (xy 378.615643 -63.136963) (xy 378.631711 -63.19037)
			(xy 378.639831 -63.245546) (xy 378.639831 -63.245552) (xy 391.404569 -63.245552) (xy 391.404569 -63.191048)
			(xy 391.412326 -63.137099) (xy 391.427682 -63.084803) (xy 391.450323 -63.035224) (xy 391.479791 -62.989373)
			(xy 391.515483 -62.948182) (xy 391.556674 -62.912489) (xy 391.602526 -62.883022) (xy 391.652105 -62.860381)
			(xy 391.704401 -62.845026) (xy 391.75835 -62.837269) (xy 391.785602 -62.836806) (xy 391.812972 -62.837269)
			(xy 391.867152 -62.845088) (xy 391.919655 -62.860577) (xy 391.969402 -62.88342) (xy 392.015368 -62.913145)
			(xy 392.0363 -62.930786) (xy 392.036554 -62.93104) (xy 392.043646 -62.936618) (xy 392.060559 -62.942869)
			(xy 392.069574 -62.943232) (xy 392.13663 -62.943232) (xy 392.145648 -62.942883) (xy 392.162564 -62.936629)
			(xy 392.16965 -62.93104) (xy 392.170158 -62.930532) (xy 392.191108 -62.91294) (xy 392.237072 -62.883277)
			(xy 392.286804 -62.860486) (xy 392.339281 -62.845037) (xy 392.393428 -62.837245) (xy 392.448133 -62.837271)
			(xy 392.502272 -62.845114) (xy 392.554735 -62.860613) (xy 392.604445 -62.883451) (xy 392.650381 -62.913158)
			(xy 392.6713 -62.930786) (xy 392.671554 -62.93104) (xy 392.678646 -62.936618) (xy 392.695559 -62.942869)
			(xy 392.704574 -62.943232) (xy 392.77163 -62.943232) (xy 392.780648 -62.942883) (xy 392.797564 -62.936629)
			(xy 392.80465 -62.93104) (xy 392.805158 -62.930532) (xy 392.826093 -62.912951) (xy 392.872027 -62.88331)
			(xy 392.921722 -62.860531) (xy 392.974161 -62.84508) (xy 393.028268 -62.837275) (xy 393.055602 -62.836806)
			(xy 393.082854 -62.837264) (xy 393.136804 -62.845021) (xy 393.1891 -62.860377) (xy 393.238679 -62.883019)
			(xy 393.284531 -62.912486) (xy 393.325722 -62.948179) (xy 393.361415 -62.989371) (xy 393.390882 -63.035223)
			(xy 393.413524 -63.084802) (xy 393.413944 -63.086234) (xy 401.687536 -63.086234) (xy 401.691607 -63.030612)
			(xy 401.703733 -62.976175) (xy 401.723656 -62.924084) (xy 401.750952 -62.875449) (xy 401.785038 -62.831306)
			(xy 401.825187 -62.792597) (xy 401.870545 -62.760146) (xy 401.920145 -62.734645) (xy 401.972929 -62.716638)
			(xy 402.027772 -62.706508) (xy 402.083506 -62.704471) (xy 402.138943 -62.710571) (xy 402.1929 -62.724677)
			(xy 402.244229 -62.746489) (xy 402.291835 -62.775543) (xy 402.334703 -62.811218) (xy 402.360001 -62.839453)
			(xy 407.218846 -62.839453) (xy 407.218846 -62.784947) (xy 407.226603 -62.730995) (xy 407.241959 -62.678696)
			(xy 407.264602 -62.629115) (xy 407.29407 -62.583261) (xy 407.329764 -62.542067) (xy 407.370958 -62.506373)
			(xy 407.416811 -62.476904) (xy 407.466392 -62.454261) (xy 407.518691 -62.438904) (xy 407.572643 -62.431146)
			(xy 407.599896 -62.43066) (xy 407.628705 -62.431191) (xy 407.685667 -62.439867) (xy 407.740677 -62.457007)
			(xy 407.792486 -62.482221) (xy 407.839916 -62.514938) (xy 407.861262 -62.534292) (xy 407.869898 -62.54242)
			(xy 407.891742 -62.549278) (xy 407.981658 -62.536832) (xy 407.993021 -62.534732) (xy 408.012206 -62.521893)
			(xy 408.018488 -62.512194) (xy 408.0333 -62.488073) (xy 408.068954 -62.444109) (xy 408.110709 -62.405893)
			(xy 408.157649 -62.374261) (xy 408.208747 -62.349909) (xy 408.26288 -62.333369) (xy 408.318862 -62.325005)
			(xy 408.347164 -62.324488) (xy 408.370719 -62.324856) (xy 408.417463 -62.330721) (xy 408.440382 -62.336172)
			(xy 408.449602 -62.337984) (xy 408.468227 -62.335661) (xy 408.484755 -62.326767) (xy 408.491182 -62.319916)
			(xy 408.560016 -62.24016) (xy 408.564588 -62.211966) (xy 408.559 -62.198504) (xy 408.549686 -62.175116)
			(xy 408.536563 -62.126514) (xy 408.529941 -62.076609) (xy 408.529536 -62.051438) (xy 408.530022 -62.024187)
			(xy 408.537778 -61.970239) (xy 408.553133 -61.917944) (xy 408.575775 -61.868367) (xy 408.605241 -61.822517)
			(xy 408.640932 -61.781326) (xy 408.682123 -61.745635) (xy 408.727973 -61.716169) (xy 408.77755 -61.693527)
			(xy 408.829845 -61.678172) (xy 408.883793 -61.670416) (xy 408.938295 -61.670416) (xy 408.992243 -61.678172)
			(xy 409.044538 -61.693527) (xy 409.094115 -61.716169) (xy 409.139965 -61.745635) (xy 409.181156 -61.781326)
			(xy 409.216847 -61.822517) (xy 409.246313 -61.868367) (xy 409.268955 -61.917944) (xy 409.28431 -61.970239)
			(xy 409.292066 -62.024187) (xy 409.292552 -62.051438) (xy 409.292058 -62.078688) (xy 409.285966 -62.121034)
			(xy 430.54219 -62.121034) (xy 430.546261 -62.065412) (xy 430.558387 -62.010975) (xy 430.57831 -61.958884)
			(xy 430.605606 -61.910249) (xy 430.639692 -61.866106) (xy 430.679841 -61.827397) (xy 430.725199 -61.794946)
			(xy 430.774799 -61.769445) (xy 430.827583 -61.751438) (xy 430.882426 -61.741308) (xy 430.93816 -61.739271)
			(xy 430.993597 -61.745371) (xy 431.047554 -61.759477) (xy 431.098883 -61.781289) (xy 431.146489 -61.810343)
			(xy 431.189357 -61.846018) (xy 431.226574 -61.887555) (xy 431.257347 -61.934068) (xy 431.281019 -61.984565)
			(xy 431.297087 -62.037972) (xy 431.305207 -62.093148) (xy 431.305716 -62.121034) (xy 431.305207 -62.14892)
			(xy 431.297087 -62.204096) (xy 431.281019 -62.257503) (xy 431.257347 -62.308) (xy 431.226574 -62.354513)
			(xy 431.189357 -62.39605) (xy 431.146489 -62.431725) (xy 431.098883 -62.460779) (xy 431.047554 -62.482591)
			(xy 430.993597 -62.496697) (xy 430.93816 -62.502797) (xy 430.882426 -62.50076) (xy 430.827583 -62.49063)
			(xy 430.774799 -62.472623) (xy 430.725199 -62.447122) (xy 430.679841 -62.414671) (xy 430.639692 -62.375962)
			(xy 430.605606 -62.331819) (xy 430.57831 -62.283184) (xy 430.558387 -62.231093) (xy 430.546261 -62.176656)
			(xy 430.54219 -62.121034) (xy 409.285966 -62.121034) (xy 409.284297 -62.132633) (xy 409.268939 -62.184925)
			(xy 409.246297 -62.2345) (xy 409.216831 -62.280348) (xy 409.181141 -62.321536) (xy 409.139953 -62.357227)
			(xy 409.094105 -62.386694) (xy 409.044531 -62.409337) (xy 408.992239 -62.424696) (xy 408.938294 -62.432457)
			(xy 408.911044 -62.432946) (xy 408.887489 -62.432575) (xy 408.840745 -62.426712) (xy 408.817826 -62.421262)
			(xy 408.808618 -62.419363) (xy 408.789978 -62.421719) (xy 408.773448 -62.430649) (xy 408.767026 -62.437518)
			(xy 408.698192 -62.517274) (xy 408.69362 -62.545468) (xy 408.699208 -62.55893) (xy 408.708532 -62.582314)
			(xy 408.721652 -62.630918) (xy 408.728269 -62.680824) (xy 408.728672 -62.705996) (xy 408.728241 -62.73325)
			(xy 408.720483 -62.787204) (xy 408.705126 -62.839505) (xy 408.682481 -62.889087) (xy 408.653011 -62.934942)
			(xy 408.617313 -62.976136) (xy 408.576117 -63.01183) (xy 408.530259 -63.041297) (xy 408.480675 -63.063937)
			(xy 408.428373 -63.07929) (xy 408.374418 -63.087043) (xy 408.347164 -63.087504) (xy 408.318355 -63.08698)
			(xy 408.261393 -63.0783) (xy 408.206384 -63.061157) (xy 408.154575 -63.035942) (xy 408.107145 -63.003226)
			(xy 408.085798 -62.983872) (xy 408.077162 -62.975744) (xy 408.055318 -62.968886) (xy 407.965402 -62.981332)
			(xy 407.954038 -62.983426) (xy 407.934855 -62.99627) (xy 407.928572 -63.00597) (xy 407.913705 -63.030056)
			(xy 407.878062 -63.074022) (xy 407.836317 -63.112241) (xy 407.789386 -63.143877) (xy 407.738297 -63.168236)
			(xy 407.684171 -63.184782) (xy 407.628195 -63.193155) (xy 407.599896 -63.193676) (xy 407.572643 -63.193254)
			(xy 407.518691 -63.185496) (xy 407.466392 -63.170139) (xy 407.416811 -63.147496) (xy 407.370958 -63.118027)
			(xy 407.329764 -63.082333) (xy 407.29407 -63.041139) (xy 407.264602 -62.995285) (xy 407.241959 -62.945704)
			(xy 407.226603 -62.893405) (xy 407.218846 -62.839453) (xy 402.360001 -62.839453) (xy 402.37192 -62.852755)
			(xy 402.402693 -62.899268) (xy 402.426365 -62.949765) (xy 402.442433 -63.003172) (xy 402.450553 -63.058348)
			(xy 402.451062 -63.086234) (xy 402.450553 -63.11412) (xy 402.442433 -63.169296) (xy 402.426365 -63.222703)
			(xy 402.402693 -63.2732) (xy 402.40254 -63.273432) (xy 403.876762 -63.273432) (xy 403.880833 -63.21781)
			(xy 403.892959 -63.163373) (xy 403.912882 -63.111282) (xy 403.940178 -63.062647) (xy 403.974264 -63.018504)
			(xy 404.014413 -62.979795) (xy 404.059771 -62.947344) (xy 404.109371 -62.921843) (xy 404.162155 -62.903836)
			(xy 404.216998 -62.893706) (xy 404.272732 -62.891669) (xy 404.328169 -62.897769) (xy 404.382126 -62.911875)
			(xy 404.433455 -62.933687) (xy 404.481061 -62.962741) (xy 404.523929 -62.998416) (xy 404.561146 -63.039953)
			(xy 404.591919 -63.086466) (xy 404.615591 -63.136963) (xy 404.631659 -63.19037) (xy 404.639779 -63.245546)
			(xy 404.639779 -63.245548) (xy 417.404592 -63.245548) (xy 417.404592 -63.191052) (xy 417.412347 -63.137111)
			(xy 417.427699 -63.084822) (xy 417.450336 -63.03525) (xy 417.479796 -62.989404) (xy 417.515481 -62.948216)
			(xy 417.556664 -62.912526) (xy 417.602506 -62.88306) (xy 417.652075 -62.860417) (xy 417.704362 -62.845058)
			(xy 417.758302 -62.837296) (xy 417.78555 -62.836806) (xy 417.812919 -62.8373) (xy 417.867097 -62.845111)
			(xy 417.9196 -62.860593) (xy 417.969347 -62.883429) (xy 418.015315 -62.913148) (xy 418.036248 -62.930786)
			(xy 418.036502 -62.93104) (xy 418.04358 -62.936638) (xy 418.060504 -62.942877) (xy 418.069522 -62.943232)
			(xy 418.136578 -62.943232) (xy 418.145593 -62.942857) (xy 418.16251 -62.936621) (xy 418.169598 -62.93104)
			(xy 418.170106 -62.930532) (xy 418.191018 -62.912893) (xy 418.236989 -62.883232) (xy 418.286726 -62.860444)
			(xy 418.33921 -62.844998) (xy 418.393362 -62.837211) (xy 418.448071 -62.837242) (xy 418.502214 -62.845091)
			(xy 418.55468 -62.860596) (xy 418.604392 -62.883441) (xy 418.650329 -62.913154) (xy 418.671248 -62.930786)
			(xy 418.671502 -62.93104) (xy 418.67858 -62.936638) (xy 418.695504 -62.942877) (xy 418.704522 -62.943232)
			(xy 418.771578 -62.943232) (xy 418.780593 -62.942857) (xy 418.79751 -62.936621) (xy 418.804598 -62.93104)
			(xy 418.805106 -62.930532) (xy 418.826023 -62.912928) (xy 418.871962 -62.883291) (xy 418.921662 -62.860516)
			(xy 418.974104 -62.845071) (xy 419.028215 -62.837272) (xy 419.05555 -62.836806) (xy 419.082806 -62.837237)
			(xy 419.136765 -62.844989) (xy 419.18907 -62.860341) (xy 419.238659 -62.882982) (xy 419.28452 -62.912449)
			(xy 419.32572 -62.948145) (xy 419.36142 -62.98934) (xy 419.390894 -63.035197) (xy 419.413541 -63.084783)
			(xy 419.413967 -63.086234) (xy 427.687484 -63.086234) (xy 427.691555 -63.030612) (xy 427.703681 -62.976175)
			(xy 427.723604 -62.924084) (xy 427.7509 -62.875449) (xy 427.784986 -62.831306) (xy 427.825135 -62.792597)
			(xy 427.870493 -62.760146) (xy 427.920093 -62.734645) (xy 427.972877 -62.716638) (xy 428.02772 -62.706508)
			(xy 428.083454 -62.704471) (xy 428.138891 -62.710571) (xy 428.192848 -62.724677) (xy 428.244177 -62.746489)
			(xy 428.291783 -62.775543) (xy 428.334651 -62.811218) (xy 428.359953 -62.839457) (xy 433.218723 -62.839457)
			(xy 433.218723 -62.784943) (xy 433.226482 -62.730983) (xy 433.241841 -62.678678) (xy 433.264489 -62.62909)
			(xy 433.293964 -62.583231) (xy 433.329665 -62.542034) (xy 433.370867 -62.506337) (xy 433.416729 -62.476868)
			(xy 433.466319 -62.454226) (xy 433.518627 -62.438872) (xy 433.572587 -62.43112) (xy 433.599844 -62.43066)
			(xy 433.628654 -62.431162) (xy 433.685617 -62.439845) (xy 433.740628 -62.456991) (xy 433.792436 -62.482213)
			(xy 433.839864 -62.514935) (xy 433.86121 -62.534292) (xy 433.869846 -62.54242) (xy 433.89169 -62.549278)
			(xy 433.981606 -62.536832) (xy 433.992976 -62.534756) (xy 434.012157 -62.5219) (xy 434.018436 -62.512194)
			(xy 434.033284 -62.488096) (xy 434.068932 -62.444132) (xy 434.110681 -62.405915) (xy 434.157615 -62.374281)
			(xy 434.208707 -62.349924) (xy 434.262835 -62.333379) (xy 434.318812 -62.325009) (xy 434.347112 -62.324488)
			(xy 434.370667 -62.324866) (xy 434.417411 -62.330724) (xy 434.44033 -62.336172) (xy 434.449545 -62.338023)
			(xy 434.468175 -62.335684) (xy 434.484704 -62.326775) (xy 434.49113 -62.319916) (xy 434.559964 -62.24016)
			(xy 434.564536 -62.211966) (xy 434.558948 -62.198504) (xy 434.549637 -62.175115) (xy 434.536512 -62.126514)
			(xy 434.529889 -62.076609) (xy 434.529484 -62.051438) (xy 434.52997 -62.024187) (xy 434.537726 -61.970239)
			(xy 434.553081 -61.917944) (xy 434.575723 -61.868367) (xy 434.605189 -61.822517) (xy 434.64088 -61.781326)
			(xy 434.682071 -61.745635) (xy 434.727921 -61.716169) (xy 434.777498 -61.693527) (xy 434.829793 -61.678172)
			(xy 434.883741 -61.670416) (xy 434.938243 -61.670416) (xy 434.992191 -61.678172) (xy 435.044486 -61.693527)
			(xy 435.094063 -61.716169) (xy 435.139913 -61.745635) (xy 435.181104 -61.781326) (xy 435.216795 -61.822517)
			(xy 435.246261 -61.868367) (xy 435.268903 -61.917944) (xy 435.284258 -61.970239) (xy 435.292014 -62.024187)
			(xy 435.2925 -62.051438) (xy 435.292058 -62.078691) (xy 435.284296 -62.13264) (xy 435.268935 -62.184936)
			(xy 435.246289 -62.234514) (xy 435.216818 -62.280365) (xy 435.181122 -62.321555) (xy 435.139928 -62.357246)
			(xy 435.094074 -62.386711) (xy 435.044493 -62.409351) (xy 434.992195 -62.424705) (xy 434.938245 -62.432461)
			(xy 434.910992 -62.432946) (xy 434.887437 -62.432566) (xy 434.840693 -62.426709) (xy 434.817774 -62.421262)
			(xy 434.808564 -62.419345) (xy 434.78991 -62.421687) (xy 434.773362 -62.430612) (xy 434.766974 -62.437518)
			(xy 434.69814 -62.517274) (xy 434.693568 -62.545468) (xy 434.699156 -62.55893) (xy 434.708478 -62.582315)
			(xy 434.721599 -62.630918) (xy 434.728217 -62.680825) (xy 434.72862 -62.705996) (xy 434.728119 -62.733247)
			(xy 434.720363 -62.787193) (xy 434.705009 -62.839487) (xy 434.682369 -62.889063) (xy 434.652904 -62.934913)
			(xy 434.617214 -62.976103) (xy 434.576026 -63.011795) (xy 434.530177 -63.041261) (xy 434.480602 -63.063903)
			(xy 434.428309 -63.079259) (xy 434.374363 -63.087017) (xy 434.347112 -63.087504) (xy 434.318304 -63.086951)
			(xy 434.261344 -63.078278) (xy 434.206334 -63.061142) (xy 434.154525 -63.035933) (xy 434.107094 -63.003223)
			(xy 434.085746 -62.983872) (xy 434.07711 -62.975744) (xy 434.055266 -62.968886) (xy 433.96535 -62.981332)
			(xy 433.953992 -62.983451) (xy 433.934806 -62.996277) (xy 433.92852 -63.00597) (xy 433.913689 -63.03008)
			(xy 433.87804 -63.074045) (xy 433.836289 -63.112263) (xy 433.789352 -63.143897) (xy 433.738257 -63.168251)
			(xy 433.684126 -63.184793) (xy 433.628145 -63.193159) (xy 433.599844 -63.193676) (xy 433.572587 -63.19328)
			(xy 433.518627 -63.185528) (xy 433.466319 -63.170174) (xy 433.416729 -63.147532) (xy 433.370867 -63.118063)
			(xy 433.329665 -63.082366) (xy 433.293964 -63.041169) (xy 433.264489 -62.99531) (xy 433.241841 -62.945722)
			(xy 433.226482 -62.893417) (xy 433.218723 -62.839457) (xy 428.359953 -62.839457) (xy 428.371868 -62.852755)
			(xy 428.402641 -62.899268) (xy 428.426313 -62.949765) (xy 428.442381 -63.003172) (xy 428.450501 -63.058348)
			(xy 428.45101 -63.086234) (xy 428.450501 -63.11412) (xy 428.442381 -63.169296) (xy 428.426313 -63.222703)
			(xy 428.402641 -63.2732) (xy 428.402488 -63.273432) (xy 429.87671 -63.273432) (xy 429.880781 -63.21781)
			(xy 429.892907 -63.163373) (xy 429.91283 -63.111282) (xy 429.940126 -63.062647) (xy 429.974212 -63.018504)
			(xy 430.014361 -62.979795) (xy 430.059719 -62.947344) (xy 430.109319 -62.921843) (xy 430.162103 -62.903836)
			(xy 430.216946 -62.893706) (xy 430.27268 -62.891669) (xy 430.328117 -62.897769) (xy 430.382074 -62.911875)
			(xy 430.433403 -62.933687) (xy 430.481009 -62.962741) (xy 430.523877 -62.998416) (xy 430.561094 -63.039953)
			(xy 430.591867 -63.086466) (xy 430.615539 -63.136963) (xy 430.631607 -63.19037) (xy 430.639727 -63.245546)
			(xy 430.639727 -63.24555) (xy 443.404492 -63.24555) (xy 443.404492 -63.19105) (xy 443.412248 -63.137104)
			(xy 443.427603 -63.084812) (xy 443.450243 -63.035237) (xy 443.479708 -62.989388) (xy 443.515398 -62.948199)
			(xy 443.556586 -62.912509) (xy 443.602435 -62.883044) (xy 443.65201 -62.860404) (xy 443.704302 -62.845049)
			(xy 443.758248 -62.837292) (xy 443.785498 -62.836806) (xy 443.812868 -62.837272) (xy 443.867047 -62.845089)
			(xy 443.919551 -62.860579) (xy 443.969297 -62.88342) (xy 444.015264 -62.913145) (xy 444.036196 -62.930786)
			(xy 444.03645 -62.93104) (xy 444.043543 -62.936617) (xy 444.060455 -62.942868) (xy 444.06947 -62.943232)
			(xy 444.136526 -62.943232) (xy 444.145543 -62.942881) (xy 444.16246 -62.936628) (xy 444.169546 -62.93104)
			(xy 444.170054 -62.930532) (xy 444.191007 -62.912944) (xy 444.236971 -62.883281) (xy 444.286702 -62.86049)
			(xy 444.339179 -62.84504) (xy 444.393325 -62.837248) (xy 444.44803 -62.837273) (xy 444.502169 -62.845116)
			(xy 444.554632 -62.860615) (xy 444.604341 -62.883452) (xy 444.650277 -62.913158) (xy 444.671196 -62.930786)
			(xy 444.67145 -62.93104) (xy 444.678543 -62.936617) (xy 444.695455 -62.942868) (xy 444.70447 -62.943232)
			(xy 444.771526 -62.943232) (xy 444.780543 -62.942881) (xy 444.79746 -62.936628) (xy 444.804546 -62.93104)
			(xy 444.805054 -62.930532) (xy 444.82599 -62.912953) (xy 444.871924 -62.883311) (xy 444.921619 -62.860532)
			(xy 444.974057 -62.845081) (xy 445.028164 -62.837276) (xy 445.055498 -62.836806) (xy 445.082752 -62.837241)
			(xy 445.136705 -62.844998) (xy 445.189005 -62.860354) (xy 445.238587 -62.882997) (xy 445.284443 -62.912467)
			(xy 445.325637 -62.948162) (xy 445.361332 -62.989356) (xy 445.390802 -63.035211) (xy 445.413445 -63.084793)
			(xy 445.428802 -63.137093) (xy 445.436559 -63.191046) (xy 445.436559 -63.245554) (xy 445.428802 -63.299507)
			(xy 445.413445 -63.351807) (xy 445.390802 -63.401389) (xy 445.361332 -63.447244) (xy 445.325637 -63.488438)
			(xy 445.284443 -63.524133) (xy 445.238587 -63.553603) (xy 445.189005 -63.576246) (xy 445.136705 -63.591602)
			(xy 445.082752 -63.599359) (xy 445.055498 -63.599822) (xy 445.028127 -63.599376) (xy 444.973946 -63.591556)
			(xy 444.921442 -63.576064) (xy 444.871695 -63.553217) (xy 444.82573 -63.523486) (xy 444.8048 -63.505842)
			(xy 444.804546 -63.505588) (xy 444.797451 -63.500013) (xy 444.780541 -63.49376) (xy 444.771526 -63.493396)
			(xy 444.70447 -63.493396) (xy 444.695452 -63.49374) (xy 444.678535 -63.499997) (xy 444.67145 -63.505588)
			(xy 444.670942 -63.506096) (xy 444.649991 -63.523687) (xy 444.604027 -63.553348) (xy 444.554295 -63.576137)
			(xy 444.501818 -63.591585) (xy 444.447672 -63.599376) (xy 444.392968 -63.59935) (xy 444.338829 -63.591508)
			(xy 444.286366 -63.57601) (xy 444.236656 -63.553174) (xy 444.19072 -63.523469) (xy 444.1698 -63.505842)
			(xy 444.169546 -63.505588) (xy 444.162451 -63.500013) (xy 444.145541 -63.49376) (xy 444.136526 -63.493396)
			(xy 444.06947 -63.493396) (xy 444.060452 -63.49374) (xy 444.043535 -63.499997) (xy 444.03645 -63.505588)
			(xy 444.035942 -63.506096) (xy 444.015011 -63.523682) (xy 443.969075 -63.553321) (xy 443.919379 -63.576099)
			(xy 443.86694 -63.591548) (xy 443.812832 -63.599353) (xy 443.785498 -63.599822) (xy 443.758248 -63.599308)
			(xy 443.704302 -63.591551) (xy 443.65201 -63.576196) (xy 443.602435 -63.553556) (xy 443.556586 -63.524091)
			(xy 443.515398 -63.488401) (xy 443.479708 -63.447212) (xy 443.450243 -63.401363) (xy 443.427603 -63.351788)
			(xy 443.412248 -63.299496) (xy 443.404492 -63.24555) (xy 430.639727 -63.24555) (xy 430.640236 -63.273432)
			(xy 430.639727 -63.301318) (xy 430.631607 -63.356494) (xy 430.615539 -63.409901) (xy 430.591867 -63.460398)
			(xy 430.561094 -63.506911) (xy 430.523877 -63.548448) (xy 430.481009 -63.584123) (xy 430.433403 -63.613177)
			(xy 430.382074 -63.634989) (xy 430.328117 -63.649095) (xy 430.27268 -63.655195) (xy 430.216946 -63.653158)
			(xy 430.162103 -63.643028) (xy 430.109319 -63.625021) (xy 430.059719 -63.59952) (xy 430.014361 -63.567069)
			(xy 429.974212 -63.52836) (xy 429.940126 -63.484217) (xy 429.91283 -63.435582) (xy 429.892907 -63.383491)
			(xy 429.880781 -63.329054) (xy 429.87671 -63.273432) (xy 428.402488 -63.273432) (xy 428.371868 -63.319713)
			(xy 428.334651 -63.36125) (xy 428.291783 -63.396925) (xy 428.244177 -63.425979) (xy 428.192848 -63.447791)
			(xy 428.138891 -63.461897) (xy 428.083454 -63.467997) (xy 428.02772 -63.46596) (xy 427.972877 -63.45583)
			(xy 427.920093 -63.437823) (xy 427.870493 -63.412322) (xy 427.825135 -63.379871) (xy 427.784986 -63.341162)
			(xy 427.7509 -63.297019) (xy 427.723604 -63.248384) (xy 427.703681 -63.196293) (xy 427.691555 -63.141856)
			(xy 427.687484 -63.086234) (xy 419.413967 -63.086234) (xy 419.4289 -63.137086) (xy 419.436659 -63.191044)
			(xy 419.436659 -63.245556) (xy 419.4289 -63.299514) (xy 419.413541 -63.351817) (xy 419.390894 -63.401403)
			(xy 419.361421 -63.44726) (xy 419.32572 -63.488455) (xy 419.28452 -63.524151) (xy 419.238659 -63.553618)
			(xy 419.18907 -63.576259) (xy 419.136765 -63.591611) (xy 419.082806 -63.599363) (xy 419.05555 -63.599822)
			(xy 419.02818 -63.599346) (xy 418.974001 -63.591533) (xy 418.921497 -63.576048) (xy 418.87175 -63.553208)
			(xy 418.825783 -63.523483) (xy 418.804852 -63.505842) (xy 418.804598 -63.505588) (xy 418.797517 -63.499993)
			(xy 418.780596 -63.493752) (xy 418.771578 -63.493396) (xy 418.704522 -63.493396) (xy 418.695506 -63.493764)
			(xy 418.678589 -63.500004) (xy 418.671502 -63.505588) (xy 418.670994 -63.506096) (xy 418.650081 -63.523734)
			(xy 418.60411 -63.553393) (xy 418.554372 -63.576179) (xy 418.501889 -63.591624) (xy 418.447738 -63.59941)
			(xy 418.393029 -63.599379) (xy 418.338886 -63.591531) (xy 418.286421 -63.576027) (xy 418.236709 -63.553184)
			(xy 418.190772 -63.523473) (xy 418.169852 -63.505842) (xy 418.169598 -63.505588) (xy 418.162517 -63.499993)
			(xy 418.145596 -63.493752) (xy 418.136578 -63.493396) (xy 418.069522 -63.493396) (xy 418.060506 -63.493764)
			(xy 418.043589 -63.500004) (xy 418.036502 -63.505588) (xy 418.035994 -63.506096) (xy 418.015081 -63.523704)
			(xy 417.96914 -63.55334) (xy 417.919439 -63.576114) (xy 417.866996 -63.591558) (xy 417.812885 -63.599356)
			(xy 417.78555 -63.599822) (xy 417.758302 -63.599304) (xy 417.704362 -63.591542) (xy 417.652075 -63.576183)
			(xy 417.602506 -63.55354) (xy 417.556664 -63.524074) (xy 417.515481 -63.488384) (xy 417.479796 -63.447196)
			(xy 417.450336 -63.40135) (xy 417.427699 -63.351778) (xy 417.412347 -63.299489) (xy 417.404592 -63.245548)
			(xy 404.639779 -63.245548) (xy 404.640288 -63.273432) (xy 404.639779 -63.301318) (xy 404.631659 -63.356494)
			(xy 404.615591 -63.409901) (xy 404.591919 -63.460398) (xy 404.561146 -63.506911) (xy 404.523929 -63.548448)
			(xy 404.481061 -63.584123) (xy 404.433455 -63.613177) (xy 404.382126 -63.634989) (xy 404.328169 -63.649095)
			(xy 404.272732 -63.655195) (xy 404.216998 -63.653158) (xy 404.162155 -63.643028) (xy 404.109371 -63.625021)
			(xy 404.059771 -63.59952) (xy 404.014413 -63.567069) (xy 403.974264 -63.52836) (xy 403.940178 -63.484217)
			(xy 403.912882 -63.435582) (xy 403.892959 -63.383491) (xy 403.880833 -63.329054) (xy 403.876762 -63.273432)
			(xy 402.40254 -63.273432) (xy 402.37192 -63.319713) (xy 402.334703 -63.36125) (xy 402.291835 -63.396925)
			(xy 402.244229 -63.425979) (xy 402.1929 -63.447791) (xy 402.138943 -63.461897) (xy 402.083506 -63.467997)
			(xy 402.027772 -63.46596) (xy 401.972929 -63.45583) (xy 401.920145 -63.437823) (xy 401.870545 -63.412322)
			(xy 401.825187 -63.379871) (xy 401.785038 -63.341162) (xy 401.750952 -63.297019) (xy 401.723656 -63.248384)
			(xy 401.703733 -63.196293) (xy 401.691607 -63.141856) (xy 401.687536 -63.086234) (xy 393.413944 -63.086234)
			(xy 393.428879 -63.137098) (xy 393.436636 -63.191048) (xy 393.436636 -63.245552) (xy 393.428879 -63.299502)
			(xy 393.413524 -63.351798) (xy 393.390882 -63.401377) (xy 393.361415 -63.447229) (xy 393.325722 -63.488421)
			(xy 393.284531 -63.524114) (xy 393.238679 -63.553581) (xy 393.1891 -63.576223) (xy 393.136804 -63.591579)
			(xy 393.082854 -63.599336) (xy 393.055602 -63.599822) (xy 393.028231 -63.599374) (xy 392.97405 -63.591555)
			(xy 392.921546 -63.576062) (xy 392.8718 -63.553216) (xy 392.825834 -63.523486) (xy 392.804904 -63.505842)
			(xy 392.80465 -63.505588) (xy 392.797554 -63.500015) (xy 392.780644 -63.49376) (xy 392.77163 -63.493396)
			(xy 392.704574 -63.493396) (xy 392.695556 -63.493742) (xy 392.678639 -63.499997) (xy 392.671554 -63.505588)
			(xy 392.671046 -63.506096) (xy 392.650092 -63.523683) (xy 392.604128 -63.553344) (xy 392.554397 -63.576133)
			(xy 392.50192 -63.591582) (xy 392.447774 -63.599374) (xy 392.393071 -63.599348) (xy 392.338932 -63.591506)
			(xy 392.28647 -63.576008) (xy 392.23676 -63.553173) (xy 392.190824 -63.523469) (xy 392.169904 -63.505842)
			(xy 392.16965 -63.505588) (xy 392.162554 -63.500015) (xy 392.145644 -63.49376) (xy 392.13663 -63.493396)
			(xy 392.069574 -63.493396) (xy 392.060556 -63.493742) (xy 392.043639 -63.499997) (xy 392.036554 -63.505588)
			(xy 392.036046 -63.506096) (xy 392.015113 -63.52368) (xy 391.969178 -63.55332) (xy 391.919482 -63.576098)
			(xy 391.867043 -63.591547) (xy 391.812936 -63.599353) (xy 391.785602 -63.599822) (xy 391.75835 -63.599331)
			(xy 391.704401 -63.591574) (xy 391.652105 -63.576219) (xy 391.602526 -63.553578) (xy 391.556674 -63.524111)
			(xy 391.515483 -63.488418) (xy 391.479791 -63.447227) (xy 391.450323 -63.401376) (xy 391.427682 -63.351797)
			(xy 391.412326 -63.299501) (xy 391.404569 -63.245552) (xy 378.639831 -63.245552) (xy 378.64034 -63.273432)
			(xy 378.639831 -63.301318) (xy 378.631711 -63.356494) (xy 378.615643 -63.409901) (xy 378.591971 -63.460398)
			(xy 378.561198 -63.506911) (xy 378.523981 -63.548448) (xy 378.481113 -63.584123) (xy 378.433507 -63.613177)
			(xy 378.382178 -63.634989) (xy 378.328221 -63.649095) (xy 378.272784 -63.655195) (xy 378.21705 -63.653158)
			(xy 378.162207 -63.643028) (xy 378.109423 -63.625021) (xy 378.059823 -63.59952) (xy 378.014465 -63.567069)
			(xy 377.974316 -63.52836) (xy 377.94023 -63.484217) (xy 377.912934 -63.435582) (xy 377.893011 -63.383491)
			(xy 377.880885 -63.329054) (xy 377.876814 -63.273432) (xy 376.402592 -63.273432) (xy 376.371972 -63.319713)
			(xy 376.334755 -63.36125) (xy 376.291887 -63.396925) (xy 376.244281 -63.425979) (xy 376.192952 -63.447791)
			(xy 376.138995 -63.461897) (xy 376.083558 -63.467997) (xy 376.027824 -63.46596) (xy 375.972981 -63.45583)
			(xy 375.920197 -63.437823) (xy 375.870597 -63.412322) (xy 375.825239 -63.379871) (xy 375.78509 -63.341162)
			(xy 375.751004 -63.297019) (xy 375.723708 -63.248384) (xy 375.703785 -63.196293) (xy 375.691659 -63.141856)
			(xy 375.687588 -63.086234) (xy 367.414068 -63.086234) (xy 367.429001 -63.137087) (xy 367.436759 -63.191044)
			(xy 367.436759 -63.245556) (xy 367.429001 -63.299513) (xy 367.413642 -63.351816) (xy 367.390995 -63.401402)
			(xy 367.361521 -63.447259) (xy 367.325821 -63.488454) (xy 367.284622 -63.524149) (xy 367.238761 -63.553617)
			(xy 367.189173 -63.576258) (xy 367.136868 -63.59161) (xy 367.08291 -63.599362) (xy 367.055654 -63.599822)
			(xy 367.028284 -63.599343) (xy 366.974105 -63.591531) (xy 366.921601 -63.576046) (xy 366.871854 -63.553207)
			(xy 366.825887 -63.523483) (xy 366.804956 -63.505842) (xy 366.804702 -63.505588) (xy 366.79762 -63.499995)
			(xy 366.7807 -63.493752) (xy 366.771682 -63.493396) (xy 366.704626 -63.493396) (xy 366.69561 -63.493766)
			(xy 366.678693 -63.500005) (xy 366.671606 -63.505588) (xy 366.671098 -63.506096) (xy 366.650182 -63.52373)
			(xy 366.604211 -63.553389) (xy 366.554474 -63.576175) (xy 366.501992 -63.591621) (xy 366.44784 -63.599408)
			(xy 366.393132 -63.599377) (xy 366.33899 -63.591529) (xy 366.286525 -63.576025) (xy 366.236813 -63.553183)
			(xy 366.190876 -63.523472) (xy 366.169956 -63.505842) (xy 366.169702 -63.505588) (xy 366.16262 -63.499995)
			(xy 366.1457 -63.493752) (xy 366.136682 -63.493396) (xy 366.069626 -63.493396) (xy 366.06061 -63.493766)
			(xy 366.043693 -63.500005) (xy 366.036606 -63.505588) (xy 366.036098 -63.506096) (xy 366.015183 -63.523702)
			(xy 365.969243 -63.553339) (xy 365.919543 -63.576112) (xy 365.8671 -63.591557) (xy 365.812989 -63.599356)
			(xy 365.785654 -63.599822) (xy 365.758406 -63.599305) (xy 365.704465 -63.591543) (xy 365.652178 -63.576185)
			(xy 365.602608 -63.553542) (xy 365.556766 -63.524075) (xy 365.515582 -63.488385) (xy 365.479897 -63.447198)
			(xy 365.450436 -63.401351) (xy 365.427799 -63.351779) (xy 365.412447 -63.29949) (xy 365.404692 -63.245548)
			(xy 352.639883 -63.245548) (xy 352.640392 -63.273432) (xy 352.639883 -63.301318) (xy 352.631763 -63.356494)
			(xy 352.615695 -63.409901) (xy 352.592023 -63.460398) (xy 352.56125 -63.506911) (xy 352.524033 -63.548448)
			(xy 352.481165 -63.584123) (xy 352.433559 -63.613177) (xy 352.38223 -63.634989) (xy 352.328273 -63.649095)
			(xy 352.272836 -63.655195) (xy 352.217102 -63.653158) (xy 352.162259 -63.643028) (xy 352.109475 -63.625021)
			(xy 352.059875 -63.59952) (xy 352.014517 -63.567069) (xy 351.974368 -63.52836) (xy 351.940282 -63.484217)
			(xy 351.912986 -63.435582) (xy 351.893063 -63.383491) (xy 351.880937 -63.329054) (xy 351.876866 -63.273432)
			(xy 350.402644 -63.273432) (xy 350.372024 -63.319713) (xy 350.334807 -63.36125) (xy 350.291939 -63.396925)
			(xy 350.244333 -63.425979) (xy 350.193004 -63.447791) (xy 350.139047 -63.461897) (xy 350.08361 -63.467997)
			(xy 350.027876 -63.46596) (xy 349.973033 -63.45583) (xy 349.920249 -63.437823) (xy 349.870649 -63.412322)
			(xy 349.825291 -63.379871) (xy 349.785142 -63.341162) (xy 349.751056 -63.297019) (xy 349.72376 -63.248384)
			(xy 349.703837 -63.196293) (xy 349.691711 -63.141856) (xy 349.68764 -63.086234) (xy 329.313745 -63.086234)
			(xy 329.328679 -63.137098) (xy 329.336436 -63.191048) (xy 329.336436 -63.245552) (xy 329.328679 -63.299502)
			(xy 329.313324 -63.351799) (xy 329.290682 -63.401378) (xy 329.261214 -63.44723) (xy 329.225522 -63.488422)
			(xy 329.18433 -63.524114) (xy 329.138478 -63.553582) (xy 329.088899 -63.576224) (xy 329.036602 -63.591579)
			(xy 328.982652 -63.599336) (xy 328.9554 -63.599822) (xy 328.928029 -63.599375) (xy 328.873848 -63.591555)
			(xy 328.821344 -63.576063) (xy 328.771598 -63.553217) (xy 328.725632 -63.523486) (xy 328.704702 -63.505842)
			(xy 328.704448 -63.505588) (xy 328.697353 -63.500014) (xy 328.680443 -63.49376) (xy 328.671428 -63.493396)
			(xy 328.604372 -63.493396) (xy 328.595354 -63.493741) (xy 328.578437 -63.499997) (xy 328.571352 -63.505588)
			(xy 328.570844 -63.506096) (xy 328.549892 -63.523685) (xy 328.503927 -63.553346) (xy 328.454196 -63.576135)
			(xy 328.401719 -63.591584) (xy 328.347573 -63.599375) (xy 328.292869 -63.599349) (xy 328.23873 -63.591507)
			(xy 328.186268 -63.576009) (xy 328.136558 -63.553173) (xy 328.090622 -63.523469) (xy 328.069702 -63.505842)
			(xy 328.069448 -63.505588) (xy 328.062353 -63.500014) (xy 328.045443 -63.49376) (xy 328.036428 -63.493396)
			(xy 327.969372 -63.493396) (xy 327.960354 -63.493741) (xy 327.943437 -63.499997) (xy 327.936352 -63.505588)
			(xy 327.935844 -63.506096) (xy 327.914912 -63.523681) (xy 327.868977 -63.55332) (xy 327.819281 -63.576098)
			(xy 327.766841 -63.591548) (xy 327.712734 -63.599353) (xy 327.6854 -63.599822) (xy 327.65815 -63.599308)
			(xy 327.604204 -63.591552) (xy 327.551911 -63.576197) (xy 327.502336 -63.553557) (xy 327.456487 -63.524092)
			(xy 327.415299 -63.488401) (xy 327.379608 -63.447213) (xy 327.350143 -63.401364) (xy 327.327503 -63.351789)
			(xy 327.312148 -63.299496) (xy 327.304392 -63.24555) (xy 314.539629 -63.24555) (xy 314.540138 -63.273432)
			(xy 314.539629 -63.301318) (xy 314.531509 -63.356494) (xy 314.515441 -63.409901) (xy 314.491769 -63.460398)
			(xy 314.460996 -63.506911) (xy 314.423779 -63.548448) (xy 314.380911 -63.584123) (xy 314.333305 -63.613177)
			(xy 314.281976 -63.634989) (xy 314.228019 -63.649095) (xy 314.172582 -63.655195) (xy 314.116848 -63.653158)
			(xy 314.062005 -63.643028) (xy 314.009221 -63.625021) (xy 313.959621 -63.59952) (xy 313.914263 -63.567069)
			(xy 313.874114 -63.52836) (xy 313.840028 -63.484217) (xy 313.812732 -63.435582) (xy 313.792809 -63.383491)
			(xy 313.780683 -63.329054) (xy 313.776612 -63.273432) (xy 312.30239 -63.273432) (xy 312.27177 -63.319713)
			(xy 312.234553 -63.36125) (xy 312.191685 -63.396925) (xy 312.144079 -63.425979) (xy 312.09275 -63.447791)
			(xy 312.038793 -63.461897) (xy 311.983356 -63.467997) (xy 311.927622 -63.46596) (xy 311.872779 -63.45583)
			(xy 311.819995 -63.437823) (xy 311.770395 -63.412322) (xy 311.725037 -63.379871) (xy 311.684888 -63.341162)
			(xy 311.650802 -63.297019) (xy 311.623506 -63.248384) (xy 311.603583 -63.196293) (xy 311.591457 -63.141856)
			(xy 311.587386 -63.086234) (xy 303.313867 -63.086234) (xy 303.3288 -63.137087) (xy 303.336559 -63.191044)
			(xy 303.336559 -63.245556) (xy 303.3288 -63.299513) (xy 303.313441 -63.351817) (xy 303.290795 -63.401402)
			(xy 303.261321 -63.447259) (xy 303.225621 -63.488455) (xy 303.184421 -63.52415) (xy 303.13856 -63.553618)
			(xy 303.088972 -63.576258) (xy 303.036666 -63.591611) (xy 302.982708 -63.599362) (xy 302.955452 -63.599822)
			(xy 302.928082 -63.599344) (xy 302.873903 -63.591532) (xy 302.821399 -63.576047) (xy 302.771652 -63.553207)
			(xy 302.725685 -63.523483) (xy 302.704754 -63.505842) (xy 302.7045 -63.505588) (xy 302.697419 -63.499994)
			(xy 302.680498 -63.493752) (xy 302.67148 -63.493396) (xy 302.604424 -63.493396) (xy 302.595408 -63.493765)
			(xy 302.578491 -63.500004) (xy 302.571404 -63.505588) (xy 302.570896 -63.506096) (xy 302.549982 -63.523732)
			(xy 302.504011 -63.553391) (xy 302.454273 -63.576177) (xy 302.40179 -63.591622) (xy 302.347639 -63.599409)
			(xy 302.292931 -63.599378) (xy 302.238788 -63.59153) (xy 302.186323 -63.576026) (xy 302.136611 -63.553184)
			(xy 302.090674 -63.523472) (xy 302.069754 -63.505842) (xy 302.0695 -63.505588) (xy 302.062419 -63.499994)
			(xy 302.045498 -63.493752) (xy 302.03648 -63.493396) (xy 301.969424 -63.493396) (xy 301.960408 -63.493765)
			(xy 301.943491 -63.500004) (xy 301.936404 -63.505588) (xy 301.935896 -63.506096) (xy 301.914982 -63.523703)
			(xy 301.869042 -63.553339) (xy 301.819341 -63.576113) (xy 301.766898 -63.591557) (xy 301.712787 -63.599356)
			(xy 301.685452 -63.599822) (xy 301.658204 -63.599304) (xy 301.604264 -63.591543) (xy 301.551977 -63.576184)
			(xy 301.502407 -63.553541) (xy 301.456565 -63.524075) (xy 301.415382 -63.488384) (xy 301.379697 -63.447197)
			(xy 301.350236 -63.401351) (xy 301.327599 -63.351778) (xy 301.312247 -63.29949) (xy 301.304492 -63.245548)
			(xy 288.539681 -63.245548) (xy 288.54019 -63.273432) (xy 288.539681 -63.301318) (xy 288.531561 -63.356494)
			(xy 288.515493 -63.409901) (xy 288.491821 -63.460398) (xy 288.461048 -63.506911) (xy 288.423831 -63.548448)
			(xy 288.380963 -63.584123) (xy 288.333357 -63.613177) (xy 288.282028 -63.634989) (xy 288.228071 -63.649095)
			(xy 288.172634 -63.655195) (xy 288.1169 -63.653158) (xy 288.062057 -63.643028) (xy 288.009273 -63.625021)
			(xy 287.959673 -63.59952) (xy 287.914315 -63.567069) (xy 287.874166 -63.52836) (xy 287.84008 -63.484217)
			(xy 287.812784 -63.435582) (xy 287.792861 -63.383491) (xy 287.780735 -63.329054) (xy 287.776664 -63.273432)
			(xy 286.302442 -63.273432) (xy 286.271822 -63.319713) (xy 286.234605 -63.36125) (xy 286.191737 -63.396925)
			(xy 286.144131 -63.425979) (xy 286.092802 -63.447791) (xy 286.038845 -63.461897) (xy 285.983408 -63.467997)
			(xy 285.927674 -63.46596) (xy 285.872831 -63.45583) (xy 285.820047 -63.437823) (xy 285.770447 -63.412322)
			(xy 285.725089 -63.379871) (xy 285.68494 -63.341162) (xy 285.650854 -63.297019) (xy 285.623558 -63.248384)
			(xy 285.603635 -63.196293) (xy 285.591509 -63.141856) (xy 285.587438 -63.086234) (xy 277.313844 -63.086234)
			(xy 277.32878 -63.137099) (xy 277.336536 -63.191048) (xy 277.336536 -63.245552) (xy 277.32878 -63.299501)
			(xy 277.313424 -63.351798) (xy 277.290782 -63.401377) (xy 277.261315 -63.447228) (xy 277.225623 -63.48842)
			(xy 277.184432 -63.524113) (xy 277.13858 -63.55358) (xy 277.089002 -63.576223) (xy 277.036705 -63.591579)
			(xy 276.982756 -63.599336) (xy 276.955504 -63.599822) (xy 276.928133 -63.599373) (xy 276.873952 -63.591554)
			(xy 276.821448 -63.576062) (xy 276.771702 -63.553216) (xy 276.725736 -63.523486) (xy 276.704806 -63.505842)
			(xy 276.704552 -63.505588) (xy 276.697456 -63.500016) (xy 276.680546 -63.493761) (xy 276.671532 -63.493396)
			(xy 276.604476 -63.493396) (xy 276.595458 -63.493743) (xy 276.578541 -63.499998) (xy 276.571456 -63.505588)
			(xy 276.570948 -63.506096) (xy 276.549992 -63.523681) (xy 276.504029 -63.553342) (xy 276.454298 -63.576131)
			(xy 276.401821 -63.59158) (xy 276.347676 -63.599372) (xy 276.292972 -63.599347) (xy 276.238834 -63.591505)
			(xy 276.186372 -63.576008) (xy 276.136662 -63.553173) (xy 276.090726 -63.523469) (xy 276.069806 -63.505842)
			(xy 276.069552 -63.505588) (xy 276.062456 -63.500016) (xy 276.045546 -63.493761) (xy 276.036532 -63.493396)
			(xy 275.969476 -63.493396) (xy 275.960458 -63.493743) (xy 275.943541 -63.499998) (xy 275.936456 -63.505588)
			(xy 275.935948 -63.506096) (xy 275.915015 -63.523679) (xy 275.86908 -63.553319) (xy 275.819384 -63.576097)
			(xy 275.766945 -63.591547) (xy 275.712838 -63.599352) (xy 275.685504 -63.599822) (xy 275.658252 -63.599331)
			(xy 275.604303 -63.591575) (xy 275.552006 -63.57622) (xy 275.502427 -63.553578) (xy 275.456575 -63.524111)
			(xy 275.415384 -63.488419) (xy 275.379691 -63.447228) (xy 275.350224 -63.401376) (xy 275.327582 -63.351798)
			(xy 275.312226 -63.299501) (xy 275.304469 -63.245552) (xy 262.539733 -63.245552) (xy 262.540242 -63.273432)
			(xy 262.539733 -63.301318) (xy 262.531613 -63.356494) (xy 262.515545 -63.409901) (xy 262.491873 -63.460398)
			(xy 262.4611 -63.506911) (xy 262.423883 -63.548448) (xy 262.381015 -63.584123) (xy 262.333409 -63.613177)
			(xy 262.28208 -63.634989) (xy 262.228123 -63.649095) (xy 262.172686 -63.655195) (xy 262.116952 -63.653158)
			(xy 262.062109 -63.643028) (xy 262.009325 -63.625021) (xy 261.959725 -63.59952) (xy 261.914367 -63.567069)
			(xy 261.874218 -63.52836) (xy 261.840132 -63.484217) (xy 261.812836 -63.435582) (xy 261.792913 -63.383491)
			(xy 261.780787 -63.329054) (xy 261.776716 -63.273432) (xy 260.302494 -63.273432) (xy 260.271874 -63.319713)
			(xy 260.234657 -63.36125) (xy 260.191789 -63.396925) (xy 260.144183 -63.425979) (xy 260.092854 -63.447791)
			(xy 260.038897 -63.461897) (xy 259.98346 -63.467997) (xy 259.927726 -63.46596) (xy 259.872883 -63.45583)
			(xy 259.820099 -63.437823) (xy 259.770499 -63.412322) (xy 259.725141 -63.379871) (xy 259.684992 -63.341162)
			(xy 259.650906 -63.297019) (xy 259.62361 -63.248384) (xy 259.603687 -63.196293) (xy 259.591561 -63.141856)
			(xy 259.58749 -63.086234) (xy 251.313968 -63.086234) (xy 251.328901 -63.137087) (xy 251.336659 -63.191044)
			(xy 251.336659 -63.245556) (xy 251.328901 -63.299513) (xy 251.313542 -63.351816) (xy 251.290895 -63.401401)
			(xy 251.261422 -63.447258) (xy 251.225722 -63.488453) (xy 251.184523 -63.524148) (xy 251.138662 -63.553616)
			(xy 251.089075 -63.576257) (xy 251.03677 -63.59161) (xy 250.982812 -63.599362) (xy 250.955556 -63.599822)
			(xy 250.928186 -63.599342) (xy 250.874007 -63.591531) (xy 250.821503 -63.576046) (xy 250.771756 -63.553207)
			(xy 250.725789 -63.523483) (xy 250.704858 -63.505842) (xy 250.704604 -63.505588) (xy 250.697521 -63.499996)
			(xy 250.680602 -63.493753) (xy 250.671584 -63.493396) (xy 250.604528 -63.493396) (xy 250.595513 -63.493767)
			(xy 250.578596 -63.500005) (xy 250.571508 -63.505588) (xy 250.571 -63.506096) (xy 250.550082 -63.523728)
			(xy 250.504112 -63.553387) (xy 250.454375 -63.576174) (xy 250.401893 -63.591619) (xy 250.347742 -63.599406)
			(xy 250.293034 -63.599376) (xy 250.238892 -63.591528) (xy 250.186427 -63.576024) (xy 250.136715 -63.553183)
			(xy 250.090778 -63.523472) (xy 250.069858 -63.505842) (xy 250.069604 -63.505588) (xy 250.062521 -63.499996)
			(xy 250.045602 -63.493753) (xy 250.036584 -63.493396) (xy 249.969528 -63.493396) (xy 249.960513 -63.493767)
			(xy 249.943596 -63.500005) (xy 249.936508 -63.505588) (xy 249.936 -63.506096) (xy 249.915085 -63.523701)
			(xy 249.869145 -63.553338) (xy 249.819444 -63.576112) (xy 249.767002 -63.591557) (xy 249.712891 -63.599356)
			(xy 249.685556 -63.599822) (xy 249.658308 -63.599305) (xy 249.604367 -63.591543) (xy 249.552079 -63.576185)
			(xy 249.50251 -63.553542) (xy 249.456666 -63.524076) (xy 249.415483 -63.488386) (xy 249.379798 -63.447198)
			(xy 249.350337 -63.401352) (xy 249.3277 -63.351779) (xy 249.312347 -63.29949) (xy 249.304592 -63.245548)
			(xy 238.309271 -63.245548) (xy 238.321487 -63.264012) (xy 238.345159 -63.314509) (xy 238.361227 -63.367916)
			(xy 238.369347 -63.423092) (xy 238.369856 -63.450978) (xy 238.369347 -63.478864) (xy 238.361227 -63.53404)
			(xy 238.345159 -63.587447) (xy 238.321487 -63.637944) (xy 238.31478 -63.648082) (xy 241.242594 -63.648082)
			(xy 241.246665 -63.59246) (xy 241.258791 -63.538023) (xy 241.278714 -63.485932) (xy 241.30601 -63.437297)
			(xy 241.340096 -63.393154) (xy 241.380245 -63.354445) (xy 241.425603 -63.321994) (xy 241.475203 -63.296493)
			(xy 241.527987 -63.278486) (xy 241.58283 -63.268356) (xy 241.638564 -63.266319) (xy 241.694001 -63.272419)
			(xy 241.747958 -63.286525) (xy 241.799287 -63.308337) (xy 241.846893 -63.337391) (xy 241.889761 -63.373066)
			(xy 241.926978 -63.414603) (xy 241.957751 -63.461116) (xy 241.981423 -63.511613) (xy 241.997491 -63.56502)
			(xy 242.005611 -63.620196) (xy 242.00612 -63.648082) (xy 242.005611 -63.675968) (xy 241.997491 -63.731144)
			(xy 241.981423 -63.784551) (xy 241.957751 -63.835048) (xy 241.926978 -63.881561) (xy 241.889761 -63.923098)
			(xy 241.846893 -63.958773) (xy 241.799287 -63.987827) (xy 241.747958 -64.009639) (xy 241.694001 -64.023745)
			(xy 241.638564 -64.029845) (xy 241.58283 -64.027808) (xy 241.527987 -64.017678) (xy 241.475203 -63.999671)
			(xy 241.425603 -63.97417) (xy 241.380245 -63.941719) (xy 241.340096 -63.90301) (xy 241.30601 -63.858867)
			(xy 241.278714 -63.810232) (xy 241.258791 -63.758141) (xy 241.246665 -63.703704) (xy 241.242594 -63.648082)
			(xy 238.31478 -63.648082) (xy 238.290714 -63.684457) (xy 238.253497 -63.725994) (xy 238.210629 -63.761669)
			(xy 238.163023 -63.790723) (xy 238.111694 -63.812535) (xy 238.057737 -63.826641) (xy 238.0023 -63.832741)
			(xy 237.946566 -63.830704) (xy 237.891723 -63.820574) (xy 237.838939 -63.802567) (xy 237.789339 -63.777066)
			(xy 237.743981 -63.744615) (xy 237.703832 -63.705906) (xy 237.669746 -63.661763) (xy 237.64245 -63.613128)
			(xy 237.622527 -63.561037) (xy 237.610401 -63.5066) (xy 237.60633 -63.450978) (xy 233.923449 -63.450978)
			(xy 233.929369 -63.463607) (xy 233.945437 -63.517014) (xy 233.953557 -63.57219) (xy 233.954066 -63.600076)
			(xy 233.953557 -63.627962) (xy 233.945437 -63.683138) (xy 233.929369 -63.736545) (xy 233.905697 -63.787042)
			(xy 233.874924 -63.833555) (xy 233.837707 -63.875092) (xy 233.794839 -63.910767) (xy 233.747233 -63.939821)
			(xy 233.695904 -63.961633) (xy 233.641947 -63.975739) (xy 233.58651 -63.981839) (xy 233.530776 -63.979802)
			(xy 233.475933 -63.969672) (xy 233.423149 -63.951665) (xy 233.373549 -63.926164) (xy 233.328191 -63.893713)
			(xy 233.288042 -63.855004) (xy 233.253956 -63.810861) (xy 233.22666 -63.762226) (xy 233.206737 -63.710135)
			(xy 233.194611 -63.655698) (xy 233.19054 -63.600076) (xy 227.723584 -63.600076) (xy 227.719135 -63.630306)
			(xy 227.703067 -63.683713) (xy 227.679395 -63.73421) (xy 227.648622 -63.780723) (xy 227.611405 -63.82226)
			(xy 227.568537 -63.857935) (xy 227.520931 -63.886989) (xy 227.469602 -63.908801) (xy 227.415645 -63.922907)
			(xy 227.360208 -63.929007) (xy 227.304474 -63.92697) (xy 227.249631 -63.91684) (xy 227.196847 -63.898833)
			(xy 227.147247 -63.873332) (xy 227.101889 -63.840881) (xy 227.06174 -63.802172) (xy 227.027654 -63.758029)
			(xy 227.000358 -63.709394) (xy 226.980435 -63.657303) (xy 226.968309 -63.602866) (xy 226.964238 -63.547244)
			(xy 225.694149 -63.547244) (xy 225.674483 -63.592371) (xy 225.647254 -63.637003) (xy 225.61419 -63.677503)
			(xy 225.575912 -63.713115) (xy 225.533133 -63.743173) (xy 225.51009 -63.755524) (xy 225.501454 -63.759842)
			(xy 225.489008 -63.774066) (xy 225.46183 -63.847726) (xy 225.460268 -63.85226) (xy 225.458737 -63.861726)
			(xy 225.458782 -63.866522) (xy 225.459036 -63.875666) (xy 225.462592 -63.88481) (xy 225.462846 -63.885318)
			(xy 225.471992 -63.908481) (xy 225.484872 -63.956587) (xy 225.491383 -64.00596) (xy 225.491802 -64.03086)
			(xy 225.491293 -64.059615) (xy 225.482661 -64.116472) (xy 225.465586 -64.171388) (xy 225.440455 -64.223117)
			(xy 225.40784 -64.270483) (xy 225.402451 -64.276224) (xy 227.856286 -64.276224) (xy 227.860357 -64.220602)
			(xy 227.872483 -64.166165) (xy 227.892406 -64.114074) (xy 227.919702 -64.065439) (xy 227.953788 -64.021296)
			(xy 227.993937 -63.982587) (xy 228.039295 -63.950136) (xy 228.088895 -63.924635) (xy 228.141679 -63.906628)
			(xy 228.196522 -63.896498) (xy 228.252256 -63.894461) (xy 228.307693 -63.900561) (xy 228.36165 -63.914667)
			(xy 228.412979 -63.936479) (xy 228.460585 -63.965533) (xy 228.503453 -64.001208) (xy 228.54067 -64.042745)
			(xy 228.571443 -64.089258) (xy 228.595115 -64.139755) (xy 228.611183 -64.193162) (xy 228.612193 -64.200024)
			(xy 231.00614 -64.200024) (xy 231.010211 -64.144402) (xy 231.022337 -64.089965) (xy 231.04226 -64.037874)
			(xy 231.069556 -63.989239) (xy 231.103642 -63.945096) (xy 231.143791 -63.906387) (xy 231.189149 -63.873936)
			(xy 231.238749 -63.848435) (xy 231.291533 -63.830428) (xy 231.346376 -63.820298) (xy 231.40211 -63.818261)
			(xy 231.457547 -63.824361) (xy 231.511504 -63.838467) (xy 231.562833 -63.860279) (xy 231.610439 -63.889333)
			(xy 231.653307 -63.925008) (xy 231.690524 -63.966545) (xy 231.721297 -64.013058) (xy 231.744969 -64.063555)
			(xy 231.761037 -64.116962) (xy 231.769157 -64.172138) (xy 231.769666 -64.200024) (xy 231.769157 -64.22791)
			(xy 231.764215 -64.261492) (xy 239.918748 -64.261492) (xy 239.919234 -64.234241) (xy 239.92699 -64.180293)
			(xy 239.942345 -64.127998) (xy 239.964987 -64.078421) (xy 239.994453 -64.032571) (xy 240.030144 -63.99138)
			(xy 240.071335 -63.955689) (xy 240.117185 -63.926223) (xy 240.166762 -63.903581) (xy 240.219057 -63.888226)
			(xy 240.273005 -63.88047) (xy 240.327507 -63.88047) (xy 240.381455 -63.888226) (xy 240.43375 -63.903581)
			(xy 240.483327 -63.926223) (xy 240.529177 -63.955689) (xy 240.570368 -63.99138) (xy 240.606059 -64.032571)
			(xy 240.635525 -64.078421) (xy 240.6464 -64.102234) (xy 259.58749 -64.102234) (xy 259.591561 -64.046612)
			(xy 259.603687 -63.992175) (xy 259.62361 -63.940084) (xy 259.650906 -63.891449) (xy 259.684992 -63.847306)
			(xy 259.725141 -63.808597) (xy 259.770499 -63.776146) (xy 259.820099 -63.750645) (xy 259.872883 -63.732638)
			(xy 259.927726 -63.722508) (xy 259.98346 -63.720471) (xy 260.038897 -63.726571) (xy 260.092854 -63.740677)
			(xy 260.144183 -63.762489) (xy 260.191789 -63.791543) (xy 260.234657 -63.827218) (xy 260.271874 -63.868755)
			(xy 260.302647 -63.915268) (xy 260.326319 -63.965765) (xy 260.342387 -64.019172) (xy 260.350507 -64.074348)
			(xy 260.351016 -64.102234) (xy 260.350507 -64.13012) (xy 260.342387 -64.185296) (xy 260.326319 -64.238703)
			(xy 260.302647 -64.2892) (xy 260.287369 -64.312292) (xy 263.265918 -64.312292) (xy 263.269989 -64.25667)
			(xy 263.282115 -64.202233) (xy 263.302038 -64.150142) (xy 263.329334 -64.101507) (xy 263.36342 -64.057364)
			(xy 263.403569 -64.018655) (xy 263.448927 -63.986204) (xy 263.498527 -63.960703) (xy 263.551311 -63.942696)
			(xy 263.606154 -63.932566) (xy 263.661888 -63.930529) (xy 263.717325 -63.936629) (xy 263.771282 -63.950735)
			(xy 263.822611 -63.972547) (xy 263.870217 -64.001601) (xy 263.913085 -64.037276) (xy 263.950302 -64.078813)
			(xy 263.965797 -64.102234) (xy 285.587438 -64.102234) (xy 285.591509 -64.046612) (xy 285.603635 -63.992175)
			(xy 285.623558 -63.940084) (xy 285.650854 -63.891449) (xy 285.68494 -63.847306) (xy 285.725089 -63.808597)
			(xy 285.770447 -63.776146) (xy 285.820047 -63.750645) (xy 285.872831 -63.732638) (xy 285.927674 -63.722508)
			(xy 285.983408 -63.720471) (xy 286.038845 -63.726571) (xy 286.092802 -63.740677) (xy 286.144131 -63.762489)
			(xy 286.191737 -63.791543) (xy 286.234605 -63.827218) (xy 286.271822 -63.868755) (xy 286.302595 -63.915268)
			(xy 286.326267 -63.965765) (xy 286.342335 -64.019172) (xy 286.350455 -64.074348) (xy 286.350964 -64.102234)
			(xy 286.350455 -64.13012) (xy 286.342335 -64.185296) (xy 286.326267 -64.238703) (xy 286.302595 -64.2892)
			(xy 286.287317 -64.312292) (xy 289.265866 -64.312292) (xy 289.269937 -64.25667) (xy 289.282063 -64.202233)
			(xy 289.301986 -64.150142) (xy 289.329282 -64.101507) (xy 289.363368 -64.057364) (xy 289.403517 -64.018655)
			(xy 289.448875 -63.986204) (xy 289.498475 -63.960703) (xy 289.551259 -63.942696) (xy 289.606102 -63.932566)
			(xy 289.661836 -63.930529) (xy 289.717273 -63.936629) (xy 289.77123 -63.950735) (xy 289.822559 -63.972547)
			(xy 289.870165 -64.001601) (xy 289.913033 -64.037276) (xy 289.95025 -64.078813) (xy 289.981023 -64.125326)
			(xy 290.004695 -64.175823) (xy 290.020763 -64.22923) (xy 290.028883 -64.284406) (xy 290.029392 -64.312292)
			(xy 291.105842 -64.312292) (xy 291.109913 -64.25667) (xy 291.122039 -64.202233) (xy 291.141962 -64.150142)
			(xy 291.169258 -64.101507) (xy 291.203344 -64.057364) (xy 291.243493 -64.018655) (xy 291.288851 -63.986204)
			(xy 291.338451 -63.960703) (xy 291.391235 -63.942696) (xy 291.446078 -63.932566) (xy 291.501812 -63.930529)
			(xy 291.557249 -63.936629) (xy 291.611206 -63.950735) (xy 291.662535 -63.972547) (xy 291.710141 -64.001601)
			(xy 291.753009 -64.037276) (xy 291.790226 -64.078813) (xy 291.805721 -64.102234) (xy 311.587386 -64.102234)
			(xy 311.591457 -64.046612) (xy 311.603583 -63.992175) (xy 311.623506 -63.940084) (xy 311.650802 -63.891449)
			(xy 311.684888 -63.847306) (xy 311.725037 -63.808597) (xy 311.770395 -63.776146) (xy 311.819995 -63.750645)
			(xy 311.872779 -63.732638) (xy 311.927622 -63.722508) (xy 311.983356 -63.720471) (xy 312.038793 -63.726571)
			(xy 312.09275 -63.740677) (xy 312.144079 -63.762489) (xy 312.191685 -63.791543) (xy 312.234553 -63.827218)
			(xy 312.27177 -63.868755) (xy 312.302543 -63.915268) (xy 312.326215 -63.965765) (xy 312.342283 -64.019172)
			(xy 312.350403 -64.074348) (xy 312.350912 -64.102234) (xy 312.350403 -64.13012) (xy 312.342283 -64.185296)
			(xy 312.326215 -64.238703) (xy 312.302543 -64.2892) (xy 312.287265 -64.312292) (xy 315.265814 -64.312292)
			(xy 315.269885 -64.25667) (xy 315.282011 -64.202233) (xy 315.301934 -64.150142) (xy 315.32923 -64.101507)
			(xy 315.363316 -64.057364) (xy 315.403465 -64.018655) (xy 315.448823 -63.986204) (xy 315.498423 -63.960703)
			(xy 315.551207 -63.942696) (xy 315.60605 -63.932566) (xy 315.661784 -63.930529) (xy 315.717221 -63.936629)
			(xy 315.771178 -63.950735) (xy 315.822507 -63.972547) (xy 315.870113 -64.001601) (xy 315.912981 -64.037276)
			(xy 315.950198 -64.078813) (xy 315.965693 -64.102234) (xy 349.68764 -64.102234) (xy 349.691711 -64.046612)
			(xy 349.703837 -63.992175) (xy 349.72376 -63.940084) (xy 349.751056 -63.891449) (xy 349.785142 -63.847306)
			(xy 349.825291 -63.808597) (xy 349.870649 -63.776146) (xy 349.920249 -63.750645) (xy 349.973033 -63.732638)
			(xy 350.027876 -63.722508) (xy 350.08361 -63.720471) (xy 350.139047 -63.726571) (xy 350.193004 -63.740677)
			(xy 350.244333 -63.762489) (xy 350.291939 -63.791543) (xy 350.334807 -63.827218) (xy 350.372024 -63.868755)
			(xy 350.402797 -63.915268) (xy 350.426469 -63.965765) (xy 350.442537 -64.019172) (xy 350.450657 -64.074348)
			(xy 350.451166 -64.102234) (xy 350.450657 -64.13012) (xy 350.442537 -64.185296) (xy 350.426469 -64.238703)
			(xy 350.402797 -64.2892) (xy 350.387519 -64.312292) (xy 353.366068 -64.312292) (xy 353.370139 -64.25667)
			(xy 353.382265 -64.202233) (xy 353.402188 -64.150142) (xy 353.429484 -64.101507) (xy 353.46357 -64.057364)
			(xy 353.503719 -64.018655) (xy 353.549077 -63.986204) (xy 353.598677 -63.960703) (xy 353.651461 -63.942696)
			(xy 353.706304 -63.932566) (xy 353.762038 -63.930529) (xy 353.817475 -63.936629) (xy 353.871432 -63.950735)
			(xy 353.922761 -63.972547) (xy 353.970367 -64.001601) (xy 354.013235 -64.037276) (xy 354.050452 -64.078813)
			(xy 354.065947 -64.102234) (xy 375.687588 -64.102234) (xy 375.691659 -64.046612) (xy 375.703785 -63.992175)
			(xy 375.723708 -63.940084) (xy 375.751004 -63.891449) (xy 375.78509 -63.847306) (xy 375.825239 -63.808597)
			(xy 375.870597 -63.776146) (xy 375.920197 -63.750645) (xy 375.972981 -63.732638) (xy 376.027824 -63.722508)
			(xy 376.083558 -63.720471) (xy 376.138995 -63.726571) (xy 376.192952 -63.740677) (xy 376.244281 -63.762489)
			(xy 376.291887 -63.791543) (xy 376.334755 -63.827218) (xy 376.371972 -63.868755) (xy 376.402745 -63.915268)
			(xy 376.426417 -63.965765) (xy 376.442485 -64.019172) (xy 376.450605 -64.074348) (xy 376.451114 -64.102234)
			(xy 376.450605 -64.13012) (xy 376.442485 -64.185296) (xy 376.426417 -64.238703) (xy 376.402745 -64.2892)
			(xy 376.387467 -64.312292) (xy 379.366016 -64.312292) (xy 379.370087 -64.25667) (xy 379.382213 -64.202233)
			(xy 379.402136 -64.150142) (xy 379.429432 -64.101507) (xy 379.463518 -64.057364) (xy 379.503667 -64.018655)
			(xy 379.549025 -63.986204) (xy 379.598625 -63.960703) (xy 379.651409 -63.942696) (xy 379.706252 -63.932566)
			(xy 379.761986 -63.930529) (xy 379.817423 -63.936629) (xy 379.87138 -63.950735) (xy 379.922709 -63.972547)
			(xy 379.970315 -64.001601) (xy 380.013183 -64.037276) (xy 380.0504 -64.078813) (xy 380.065895 -64.102234)
			(xy 401.687536 -64.102234) (xy 401.691607 -64.046612) (xy 401.703733 -63.992175) (xy 401.723656 -63.940084)
			(xy 401.750952 -63.891449) (xy 401.785038 -63.847306) (xy 401.825187 -63.808597) (xy 401.870545 -63.776146)
			(xy 401.920145 -63.750645) (xy 401.972929 -63.732638) (xy 402.027772 -63.722508) (xy 402.083506 -63.720471)
			(xy 402.138943 -63.726571) (xy 402.1929 -63.740677) (xy 402.244229 -63.762489) (xy 402.291835 -63.791543)
			(xy 402.334703 -63.827218) (xy 402.37192 -63.868755) (xy 402.402693 -63.915268) (xy 402.426365 -63.965765)
			(xy 402.442433 -64.019172) (xy 402.450553 -64.074348) (xy 402.451062 -64.102234) (xy 402.450553 -64.13012)
			(xy 402.442433 -64.185296) (xy 402.426365 -64.238703) (xy 402.402693 -64.2892) (xy 402.387415 -64.312292)
			(xy 405.365964 -64.312292) (xy 405.370035 -64.25667) (xy 405.382161 -64.202233) (xy 405.402084 -64.150142)
			(xy 405.42938 -64.101507) (xy 405.463466 -64.057364) (xy 405.503615 -64.018655) (xy 405.548973 -63.986204)
			(xy 405.598573 -63.960703) (xy 405.651357 -63.942696) (xy 405.7062 -63.932566) (xy 405.761934 -63.930529)
			(xy 405.817371 -63.936629) (xy 405.871328 -63.950735) (xy 405.922657 -63.972547) (xy 405.970263 -64.001601)
			(xy 406.013131 -64.037276) (xy 406.050348 -64.078813) (xy 406.081121 -64.125326) (xy 406.104793 -64.175823)
			(xy 406.120861 -64.22923) (xy 406.128981 -64.284406) (xy 406.12949 -64.312292) (xy 407.20594 -64.312292)
			(xy 407.210011 -64.25667) (xy 407.222137 -64.202233) (xy 407.24206 -64.150142) (xy 407.269356 -64.101507)
			(xy 407.303442 -64.057364) (xy 407.343591 -64.018655) (xy 407.388949 -63.986204) (xy 407.438549 -63.960703)
			(xy 407.491333 -63.942696) (xy 407.546176 -63.932566) (xy 407.60191 -63.930529) (xy 407.657347 -63.936629)
			(xy 407.711304 -63.950735) (xy 407.762633 -63.972547) (xy 407.810239 -64.001601) (xy 407.853107 -64.037276)
			(xy 407.890324 -64.078813) (xy 407.905819 -64.102234) (xy 427.687484 -64.102234) (xy 427.691555 -64.046612)
			(xy 427.703681 -63.992175) (xy 427.723604 -63.940084) (xy 427.7509 -63.891449) (xy 427.784986 -63.847306)
			(xy 427.825135 -63.808597) (xy 427.870493 -63.776146) (xy 427.920093 -63.750645) (xy 427.972877 -63.732638)
			(xy 428.02772 -63.722508) (xy 428.083454 -63.720471) (xy 428.138891 -63.726571) (xy 428.192848 -63.740677)
			(xy 428.244177 -63.762489) (xy 428.291783 -63.791543) (xy 428.334651 -63.827218) (xy 428.371868 -63.868755)
			(xy 428.402641 -63.915268) (xy 428.426313 -63.965765) (xy 428.442381 -64.019172) (xy 428.450501 -64.074348)
			(xy 428.45101 -64.102234) (xy 428.450501 -64.13012) (xy 428.442381 -64.185296) (xy 428.426313 -64.238703)
			(xy 428.402641 -64.2892) (xy 428.387363 -64.312292) (xy 431.365912 -64.312292) (xy 431.369983 -64.25667)
			(xy 431.382109 -64.202233) (xy 431.402032 -64.150142) (xy 431.429328 -64.101507) (xy 431.463414 -64.057364)
			(xy 431.503563 -64.018655) (xy 431.548921 -63.986204) (xy 431.598521 -63.960703) (xy 431.651305 -63.942696)
			(xy 431.706148 -63.932566) (xy 431.761882 -63.930529) (xy 431.817319 -63.936629) (xy 431.871276 -63.950735)
			(xy 431.922605 -63.972547) (xy 431.970211 -64.001601) (xy 432.013079 -64.037276) (xy 432.050296 -64.078813)
			(xy 432.081069 -64.125326) (xy 432.104741 -64.175823) (xy 432.120809 -64.22923) (xy 432.128929 -64.284406)
			(xy 432.129438 -64.312292) (xy 432.128929 -64.340178) (xy 432.120809 -64.395354) (xy 432.104741 -64.448761)
			(xy 432.081069 -64.499258) (xy 432.050296 -64.545771) (xy 432.013079 -64.587308) (xy 431.970211 -64.622983)
			(xy 431.922605 -64.652037) (xy 431.871276 -64.673849) (xy 431.817319 -64.687955) (xy 431.761882 -64.694055)
			(xy 431.706148 -64.692018) (xy 431.651305 -64.681888) (xy 431.598521 -64.663881) (xy 431.548921 -64.63838)
			(xy 431.503563 -64.605929) (xy 431.463414 -64.56722) (xy 431.429328 -64.523077) (xy 431.402032 -64.474442)
			(xy 431.382109 -64.422351) (xy 431.369983 -64.367914) (xy 431.365912 -64.312292) (xy 428.387363 -64.312292)
			(xy 428.371868 -64.335713) (xy 428.334651 -64.37725) (xy 428.291783 -64.412925) (xy 428.244177 -64.441979)
			(xy 428.192848 -64.463791) (xy 428.138891 -64.477897) (xy 428.083454 -64.483997) (xy 428.02772 -64.48196)
			(xy 427.972877 -64.47183) (xy 427.920093 -64.453823) (xy 427.870493 -64.428322) (xy 427.825135 -64.395871)
			(xy 427.784986 -64.357162) (xy 427.7509 -64.313019) (xy 427.723604 -64.264384) (xy 427.703681 -64.212293)
			(xy 427.691555 -64.157856) (xy 427.687484 -64.102234) (xy 407.905819 -64.102234) (xy 407.921097 -64.125326)
			(xy 407.944769 -64.175823) (xy 407.960837 -64.22923) (xy 407.968957 -64.284406) (xy 407.969466 -64.312292)
			(xy 407.968957 -64.340178) (xy 407.960837 -64.395354) (xy 407.944769 -64.448761) (xy 407.921097 -64.499258)
			(xy 407.890324 -64.545771) (xy 407.853107 -64.587308) (xy 407.810239 -64.622983) (xy 407.762633 -64.652037)
			(xy 407.711304 -64.673849) (xy 407.657347 -64.687955) (xy 407.60191 -64.694055) (xy 407.546176 -64.692018)
			(xy 407.491333 -64.681888) (xy 407.438549 -64.663881) (xy 407.388949 -64.63838) (xy 407.343591 -64.605929)
			(xy 407.303442 -64.56722) (xy 407.269356 -64.523077) (xy 407.24206 -64.474442) (xy 407.222137 -64.422351)
			(xy 407.210011 -64.367914) (xy 407.20594 -64.312292) (xy 406.12949 -64.312292) (xy 406.128981 -64.340178)
			(xy 406.120861 -64.395354) (xy 406.104793 -64.448761) (xy 406.081121 -64.499258) (xy 406.050348 -64.545771)
			(xy 406.013131 -64.587308) (xy 405.970263 -64.622983) (xy 405.922657 -64.652037) (xy 405.871328 -64.673849)
			(xy 405.817371 -64.687955) (xy 405.761934 -64.694055) (xy 405.7062 -64.692018) (xy 405.651357 -64.681888)
			(xy 405.598573 -64.663881) (xy 405.548973 -64.63838) (xy 405.503615 -64.605929) (xy 405.463466 -64.56722)
			(xy 405.42938 -64.523077) (xy 405.402084 -64.474442) (xy 405.382161 -64.422351) (xy 405.370035 -64.367914)
			(xy 405.365964 -64.312292) (xy 402.387415 -64.312292) (xy 402.37192 -64.335713) (xy 402.334703 -64.37725)
			(xy 402.291835 -64.412925) (xy 402.244229 -64.441979) (xy 402.1929 -64.463791) (xy 402.138943 -64.477897)
			(xy 402.083506 -64.483997) (xy 402.027772 -64.48196) (xy 401.972929 -64.47183) (xy 401.920145 -64.453823)
			(xy 401.870545 -64.428322) (xy 401.825187 -64.395871) (xy 401.785038 -64.357162) (xy 401.750952 -64.313019)
			(xy 401.723656 -64.264384) (xy 401.703733 -64.212293) (xy 401.691607 -64.157856) (xy 401.687536 -64.102234)
			(xy 380.065895 -64.102234) (xy 380.081173 -64.125326) (xy 380.104845 -64.175823) (xy 380.120913 -64.22923)
			(xy 380.129033 -64.284406) (xy 380.129542 -64.312292) (xy 380.129033 -64.340178) (xy 380.120913 -64.395354)
			(xy 380.104845 -64.448761) (xy 380.081173 -64.499258) (xy 380.0504 -64.545771) (xy 380.013183 -64.587308)
			(xy 379.970315 -64.622983) (xy 379.922709 -64.652037) (xy 379.87138 -64.673849) (xy 379.817423 -64.687955)
			(xy 379.761986 -64.694055) (xy 379.706252 -64.692018) (xy 379.651409 -64.681888) (xy 379.598625 -64.663881)
			(xy 379.549025 -64.63838) (xy 379.503667 -64.605929) (xy 379.463518 -64.56722) (xy 379.429432 -64.523077)
			(xy 379.402136 -64.474442) (xy 379.382213 -64.422351) (xy 379.370087 -64.367914) (xy 379.366016 -64.312292)
			(xy 376.387467 -64.312292) (xy 376.371972 -64.335713) (xy 376.334755 -64.37725) (xy 376.291887 -64.412925)
			(xy 376.244281 -64.441979) (xy 376.192952 -64.463791) (xy 376.138995 -64.477897) (xy 376.083558 -64.483997)
			(xy 376.027824 -64.48196) (xy 375.972981 -64.47183) (xy 375.920197 -64.453823) (xy 375.870597 -64.428322)
			(xy 375.825239 -64.395871) (xy 375.78509 -64.357162) (xy 375.751004 -64.313019) (xy 375.723708 -64.264384)
			(xy 375.703785 -64.212293) (xy 375.691659 -64.157856) (xy 375.687588 -64.102234) (xy 354.065947 -64.102234)
			(xy 354.081225 -64.125326) (xy 354.104897 -64.175823) (xy 354.120965 -64.22923) (xy 354.129085 -64.284406)
			(xy 354.129594 -64.312292) (xy 354.129085 -64.340178) (xy 354.120965 -64.395354) (xy 354.104897 -64.448761)
			(xy 354.081225 -64.499258) (xy 354.050452 -64.545771) (xy 354.013235 -64.587308) (xy 353.970367 -64.622983)
			(xy 353.922761 -64.652037) (xy 353.871432 -64.673849) (xy 353.817475 -64.687955) (xy 353.762038 -64.694055)
			(xy 353.706304 -64.692018) (xy 353.651461 -64.681888) (xy 353.598677 -64.663881) (xy 353.549077 -64.63838)
			(xy 353.503719 -64.605929) (xy 353.46357 -64.56722) (xy 353.429484 -64.523077) (xy 353.402188 -64.474442)
			(xy 353.382265 -64.422351) (xy 353.370139 -64.367914) (xy 353.366068 -64.312292) (xy 350.387519 -64.312292)
			(xy 350.372024 -64.335713) (xy 350.334807 -64.37725) (xy 350.291939 -64.412925) (xy 350.244333 -64.441979)
			(xy 350.193004 -64.463791) (xy 350.139047 -64.477897) (xy 350.08361 -64.483997) (xy 350.027876 -64.48196)
			(xy 349.973033 -64.47183) (xy 349.920249 -64.453823) (xy 349.870649 -64.428322) (xy 349.825291 -64.395871)
			(xy 349.785142 -64.357162) (xy 349.751056 -64.313019) (xy 349.72376 -64.264384) (xy 349.703837 -64.212293)
			(xy 349.691711 -64.157856) (xy 349.68764 -64.102234) (xy 315.965693 -64.102234) (xy 315.980971 -64.125326)
			(xy 316.004643 -64.175823) (xy 316.020711 -64.22923) (xy 316.028831 -64.284406) (xy 316.02934 -64.312292)
			(xy 316.028831 -64.340178) (xy 316.020711 -64.395354) (xy 316.004643 -64.448761) (xy 315.980971 -64.499258)
			(xy 315.950198 -64.545771) (xy 315.912981 -64.587308) (xy 315.870113 -64.622983) (xy 315.822507 -64.652037)
			(xy 315.771178 -64.673849) (xy 315.717221 -64.687955) (xy 315.661784 -64.694055) (xy 315.60605 -64.692018)
			(xy 315.551207 -64.681888) (xy 315.498423 -64.663881) (xy 315.448823 -64.63838) (xy 315.403465 -64.605929)
			(xy 315.363316 -64.56722) (xy 315.32923 -64.523077) (xy 315.301934 -64.474442) (xy 315.282011 -64.422351)
			(xy 315.269885 -64.367914) (xy 315.265814 -64.312292) (xy 312.287265 -64.312292) (xy 312.27177 -64.335713)
			(xy 312.234553 -64.37725) (xy 312.191685 -64.412925) (xy 312.144079 -64.441979) (xy 312.09275 -64.463791)
			(xy 312.038793 -64.477897) (xy 311.983356 -64.483997) (xy 311.927622 -64.48196) (xy 311.872779 -64.47183)
			(xy 311.819995 -64.453823) (xy 311.770395 -64.428322) (xy 311.725037 -64.395871) (xy 311.684888 -64.357162)
			(xy 311.650802 -64.313019) (xy 311.623506 -64.264384) (xy 311.603583 -64.212293) (xy 311.591457 -64.157856)
			(xy 311.587386 -64.102234) (xy 291.805721 -64.102234) (xy 291.820999 -64.125326) (xy 291.844671 -64.175823)
			(xy 291.860739 -64.22923) (xy 291.868859 -64.284406) (xy 291.869368 -64.312292) (xy 291.868859 -64.340178)
			(xy 291.860739 -64.395354) (xy 291.844671 -64.448761) (xy 291.820999 -64.499258) (xy 291.790226 -64.545771)
			(xy 291.753009 -64.587308) (xy 291.710141 -64.622983) (xy 291.662535 -64.652037) (xy 291.611206 -64.673849)
			(xy 291.557249 -64.687955) (xy 291.501812 -64.694055) (xy 291.446078 -64.692018) (xy 291.391235 -64.681888)
			(xy 291.338451 -64.663881) (xy 291.288851 -64.63838) (xy 291.243493 -64.605929) (xy 291.203344 -64.56722)
			(xy 291.169258 -64.523077) (xy 291.141962 -64.474442) (xy 291.122039 -64.422351) (xy 291.109913 -64.367914)
			(xy 291.105842 -64.312292) (xy 290.029392 -64.312292) (xy 290.028883 -64.340178) (xy 290.020763 -64.395354)
			(xy 290.004695 -64.448761) (xy 289.981023 -64.499258) (xy 289.95025 -64.545771) (xy 289.913033 -64.587308)
			(xy 289.870165 -64.622983) (xy 289.822559 -64.652037) (xy 289.77123 -64.673849) (xy 289.717273 -64.687955)
			(xy 289.661836 -64.694055) (xy 289.606102 -64.692018) (xy 289.551259 -64.681888) (xy 289.498475 -64.663881)
			(xy 289.448875 -64.63838) (xy 289.403517 -64.605929) (xy 289.363368 -64.56722) (xy 289.329282 -64.523077)
			(xy 289.301986 -64.474442) (xy 289.282063 -64.422351) (xy 289.269937 -64.367914) (xy 289.265866 -64.312292)
			(xy 286.287317 -64.312292) (xy 286.271822 -64.335713) (xy 286.234605 -64.37725) (xy 286.191737 -64.412925)
			(xy 286.144131 -64.441979) (xy 286.092802 -64.463791) (xy 286.038845 -64.477897) (xy 285.983408 -64.483997)
			(xy 285.927674 -64.48196) (xy 285.872831 -64.47183) (xy 285.820047 -64.453823) (xy 285.770447 -64.428322)
			(xy 285.725089 -64.395871) (xy 285.68494 -64.357162) (xy 285.650854 -64.313019) (xy 285.623558 -64.264384)
			(xy 285.603635 -64.212293) (xy 285.591509 -64.157856) (xy 285.587438 -64.102234) (xy 263.965797 -64.102234)
			(xy 263.981075 -64.125326) (xy 264.004747 -64.175823) (xy 264.020815 -64.22923) (xy 264.028935 -64.284406)
			(xy 264.029444 -64.312292) (xy 264.028935 -64.340178) (xy 264.020815 -64.395354) (xy 264.004747 -64.448761)
			(xy 263.981075 -64.499258) (xy 263.950302 -64.545771) (xy 263.913085 -64.587308) (xy 263.870217 -64.622983)
			(xy 263.822611 -64.652037) (xy 263.771282 -64.673849) (xy 263.717325 -64.687955) (xy 263.661888 -64.694055)
			(xy 263.606154 -64.692018) (xy 263.551311 -64.681888) (xy 263.498527 -64.663881) (xy 263.448927 -64.63838)
			(xy 263.403569 -64.605929) (xy 263.36342 -64.56722) (xy 263.329334 -64.523077) (xy 263.302038 -64.474442)
			(xy 263.282115 -64.422351) (xy 263.269989 -64.367914) (xy 263.265918 -64.312292) (xy 260.287369 -64.312292)
			(xy 260.271874 -64.335713) (xy 260.234657 -64.37725) (xy 260.191789 -64.412925) (xy 260.144183 -64.441979)
			(xy 260.092854 -64.463791) (xy 260.038897 -64.477897) (xy 259.98346 -64.483997) (xy 259.927726 -64.48196)
			(xy 259.872883 -64.47183) (xy 259.820099 -64.453823) (xy 259.770499 -64.428322) (xy 259.725141 -64.395871)
			(xy 259.684992 -64.357162) (xy 259.650906 -64.313019) (xy 259.62361 -64.264384) (xy 259.603687 -64.212293)
			(xy 259.591561 -64.157856) (xy 259.58749 -64.102234) (xy 240.6464 -64.102234) (xy 240.658167 -64.127998)
			(xy 240.673522 -64.180293) (xy 240.681278 -64.234241) (xy 240.681764 -64.261492) (xy 240.681224 -64.290301)
			(xy 240.67255 -64.347262) (xy 240.655411 -64.402272) (xy 240.630199 -64.454081) (xy 240.597485 -64.501511)
			(xy 240.578132 -64.522858) (xy 240.570004 -64.531494) (xy 240.563146 -64.553338) (xy 240.575592 -64.643254)
			(xy 240.577725 -64.654607) (xy 240.590542 -64.673794) (xy 240.60023 -64.680084) (xy 240.624355 -64.69489)
			(xy 240.668318 -64.730546) (xy 240.706533 -64.772302) (xy 240.738163 -64.819244) (xy 240.762515 -64.870342)
			(xy 240.779055 -64.924475) (xy 240.787419 -64.980458) (xy 240.787936 -65.00876) (xy 240.78745 -65.036011)
			(xy 240.779694 -65.089959) (xy 240.764339 -65.142254) (xy 240.756285 -65.15989) (xy 251.316488 -65.15989)
			(xy 251.320559 -65.104268) (xy 251.332685 -65.049831) (xy 251.352608 -64.99774) (xy 251.379904 -64.949105)
			(xy 251.41399 -64.904962) (xy 251.454139 -64.866253) (xy 251.499497 -64.833802) (xy 251.549097 -64.808301)
			(xy 251.601881 -64.790294) (xy 251.656724 -64.780164) (xy 251.712458 -64.778127) (xy 251.767895 -64.784227)
			(xy 251.821852 -64.798333) (xy 251.873181 -64.820145) (xy 251.920787 -64.849199) (xy 251.963655 -64.884874)
			(xy 252.000872 -64.926411) (xy 252.031645 -64.972924) (xy 252.055317 -65.023421) (xy 252.071385 -65.076828)
			(xy 252.074937 -65.100962) (xy 252.332488 -65.100962) (xy 252.336559 -65.04534) (xy 252.348685 -64.990903)
			(xy 252.368608 -64.938812) (xy 252.395904 -64.890177) (xy 252.42999 -64.846034) (xy 252.470139 -64.807325)
			(xy 252.515497 -64.774874) (xy 252.565097 -64.749373) (xy 252.617881 -64.731366) (xy 252.672724 -64.721236)
			(xy 252.728458 -64.719199) (xy 252.783895 -64.725299) (xy 252.837852 -64.739405) (xy 252.889181 -64.761217)
			(xy 252.936787 -64.790271) (xy 252.979655 -64.825946) (xy 253.016872 -64.867483) (xy 253.047645 -64.913996)
			(xy 253.071317 -64.964493) (xy 253.087385 -65.0179) (xy 253.095505 -65.073076) (xy 253.096014 -65.100962)
			(xy 253.095505 -65.128848) (xy 253.090937 -65.15989) (xy 253.348488 -65.15989) (xy 253.352559 -65.104268)
			(xy 253.364685 -65.049831) (xy 253.384608 -64.99774) (xy 253.411904 -64.949105) (xy 253.44599 -64.904962)
			(xy 253.486139 -64.866253) (xy 253.531497 -64.833802) (xy 253.581097 -64.808301) (xy 253.633881 -64.790294)
			(xy 253.688724 -64.780164) (xy 253.744458 -64.778127) (xy 253.799895 -64.784227) (xy 253.853852 -64.798333)
			(xy 253.905181 -64.820145) (xy 253.952787 -64.849199) (xy 253.995655 -64.884874) (xy 254.032872 -64.926411)
			(xy 254.063645 -64.972924) (xy 254.087317 -65.023421) (xy 254.103385 -65.076828) (xy 254.110338 -65.124076)
			(xy 264.307318 -65.124076) (xy 264.311389 -65.068454) (xy 264.323515 -65.014017) (xy 264.343438 -64.961926)
			(xy 264.370734 -64.913291) (xy 264.40482 -64.869148) (xy 264.444969 -64.830439) (xy 264.490327 -64.797988)
			(xy 264.539927 -64.772487) (xy 264.592711 -64.75448) (xy 264.647554 -64.74435) (xy 264.703288 -64.742313)
			(xy 264.758725 -64.748413) (xy 264.812682 -64.762519) (xy 264.864011 -64.784331) (xy 264.911617 -64.813385)
			(xy 264.954485 -64.84906) (xy 264.991702 -64.890597) (xy 265.022475 -64.93711) (xy 265.046147 -64.987607)
			(xy 265.062215 -65.041014) (xy 265.070335 -65.09619) (xy 265.070844 -65.124076) (xy 265.070335 -65.151962)
			(xy 265.069168 -65.15989) (xy 277.316436 -65.15989) (xy 277.320507 -65.104268) (xy 277.332633 -65.049831)
			(xy 277.352556 -64.99774) (xy 277.379852 -64.949105) (xy 277.413938 -64.904962) (xy 277.454087 -64.866253)
			(xy 277.499445 -64.833802) (xy 277.549045 -64.808301) (xy 277.601829 -64.790294) (xy 277.656672 -64.780164)
			(xy 277.712406 -64.778127) (xy 277.767843 -64.784227) (xy 277.8218 -64.798333) (xy 277.873129 -64.820145)
			(xy 277.920735 -64.849199) (xy 277.963603 -64.884874) (xy 278.00082 -64.926411) (xy 278.031593 -64.972924)
			(xy 278.055265 -65.023421) (xy 278.071333 -65.076828) (xy 278.074885 -65.100962) (xy 278.332436 -65.100962)
			(xy 278.336507 -65.04534) (xy 278.348633 -64.990903) (xy 278.368556 -64.938812) (xy 278.395852 -64.890177)
			(xy 278.429938 -64.846034) (xy 278.470087 -64.807325) (xy 278.515445 -64.774874) (xy 278.565045 -64.749373)
			(xy 278.617829 -64.731366) (xy 278.672672 -64.721236) (xy 278.728406 -64.719199) (xy 278.783843 -64.725299)
			(xy 278.8378 -64.739405) (xy 278.889129 -64.761217) (xy 278.936735 -64.790271) (xy 278.979603 -64.825946)
			(xy 279.01682 -64.867483) (xy 279.047593 -64.913996) (xy 279.071265 -64.964493) (xy 279.087333 -65.0179)
			(xy 279.095453 -65.073076) (xy 279.095962 -65.100962) (xy 279.095453 -65.128848) (xy 279.090885 -65.15989)
			(xy 279.348436 -65.15989) (xy 279.352507 -65.104268) (xy 279.364633 -65.049831) (xy 279.384556 -64.99774)
			(xy 279.411852 -64.949105) (xy 279.445938 -64.904962) (xy 279.486087 -64.866253) (xy 279.531445 -64.833802)
			(xy 279.581045 -64.808301) (xy 279.633829 -64.790294) (xy 279.688672 -64.780164) (xy 279.744406 -64.778127)
			(xy 279.799843 -64.784227) (xy 279.8538 -64.798333) (xy 279.905129 -64.820145) (xy 279.952735 -64.849199)
			(xy 279.995603 -64.884874) (xy 280.03282 -64.926411) (xy 280.063593 -64.972924) (xy 280.087265 -65.023421)
			(xy 280.103333 -65.076828) (xy 280.111453 -65.132004) (xy 280.111962 -65.15989) (xy 280.111453 -65.187776)
			(xy 280.103333 -65.242952) (xy 280.087265 -65.296359) (xy 280.063593 -65.346856) (xy 280.03282 -65.393369)
			(xy 279.995603 -65.434906) (xy 279.952735 -65.470581) (xy 279.905129 -65.499635) (xy 279.877382 -65.511426)
			(xy 298.584872 -65.511426) (xy 298.588943 -65.455804) (xy 298.601069 -65.401367) (xy 298.620992 -65.349276)
			(xy 298.648288 -65.300641) (xy 298.682374 -65.256498) (xy 298.722523 -65.217789) (xy 298.767881 -65.185338)
			(xy 298.817481 -65.159837) (xy 298.870265 -65.14183) (xy 298.925108 -65.1317) (xy 298.980842 -65.129663)
			(xy 299.036279 -65.135763) (xy 299.090236 -65.149869) (xy 299.113818 -65.15989) (xy 303.316384 -65.15989)
			(xy 303.320455 -65.104268) (xy 303.332581 -65.049831) (xy 303.352504 -64.99774) (xy 303.3798 -64.949105)
			(xy 303.413886 -64.904962) (xy 303.454035 -64.866253) (xy 303.499393 -64.833802) (xy 303.548993 -64.808301)
			(xy 303.601777 -64.790294) (xy 303.65662 -64.780164) (xy 303.712354 -64.778127) (xy 303.767791 -64.784227)
			(xy 303.821748 -64.798333) (xy 303.873077 -64.820145) (xy 303.920683 -64.849199) (xy 303.963551 -64.884874)
			(xy 304.000768 -64.926411) (xy 304.031541 -64.972924) (xy 304.055213 -65.023421) (xy 304.071281 -65.076828)
			(xy 304.074833 -65.100962) (xy 304.332384 -65.100962) (xy 304.336455 -65.04534) (xy 304.348581 -64.990903)
			(xy 304.368504 -64.938812) (xy 304.3958 -64.890177) (xy 304.429886 -64.846034) (xy 304.470035 -64.807325)
			(xy 304.515393 -64.774874) (xy 304.564993 -64.749373) (xy 304.617777 -64.731366) (xy 304.67262 -64.721236)
			(xy 304.728354 -64.719199) (xy 304.783791 -64.725299) (xy 304.837748 -64.739405) (xy 304.889077 -64.761217)
			(xy 304.936683 -64.790271) (xy 304.979551 -64.825946) (xy 305.016768 -64.867483) (xy 305.047541 -64.913996)
			(xy 305.071213 -64.964493) (xy 305.087281 -65.0179) (xy 305.095401 -65.073076) (xy 305.09591 -65.100962)
			(xy 305.095401 -65.128848) (xy 305.090833 -65.15989) (xy 305.348384 -65.15989) (xy 305.352455 -65.104268)
			(xy 305.364581 -65.049831) (xy 305.384504 -64.99774) (xy 305.4118 -64.949105) (xy 305.445886 -64.904962)
			(xy 305.486035 -64.866253) (xy 305.531393 -64.833802) (xy 305.580993 -64.808301) (xy 305.633777 -64.790294)
			(xy 305.68862 -64.780164) (xy 305.744354 -64.778127) (xy 305.799791 -64.784227) (xy 305.853748 -64.798333)
			(xy 305.905077 -64.820145) (xy 305.952683 -64.849199) (xy 305.995551 -64.884874) (xy 306.032768 -64.926411)
			(xy 306.063541 -64.972924) (xy 306.087213 -65.023421) (xy 306.103281 -65.076828) (xy 306.110234 -65.124076)
			(xy 316.307214 -65.124076) (xy 316.311285 -65.068454) (xy 316.323411 -65.014017) (xy 316.343334 -64.961926)
			(xy 316.37063 -64.913291) (xy 316.404716 -64.869148) (xy 316.444865 -64.830439) (xy 316.490223 -64.797988)
			(xy 316.539823 -64.772487) (xy 316.592607 -64.75448) (xy 316.64745 -64.74435) (xy 316.703184 -64.742313)
			(xy 316.758621 -64.748413) (xy 316.812578 -64.762519) (xy 316.863907 -64.784331) (xy 316.911513 -64.813385)
			(xy 316.954381 -64.84906) (xy 316.991598 -64.890597) (xy 317.022371 -64.93711) (xy 317.046043 -64.987607)
			(xy 317.062111 -65.041014) (xy 317.070231 -65.09619) (xy 317.07074 -65.124076) (xy 317.070231 -65.151962)
			(xy 317.069064 -65.15989) (xy 329.316332 -65.15989) (xy 329.320403 -65.104268) (xy 329.332529 -65.049831)
			(xy 329.352452 -64.99774) (xy 329.379748 -64.949105) (xy 329.413834 -64.904962) (xy 329.453983 -64.866253)
			(xy 329.499341 -64.833802) (xy 329.548941 -64.808301) (xy 329.601725 -64.790294) (xy 329.656568 -64.780164)
			(xy 329.712302 -64.778127) (xy 329.767739 -64.784227) (xy 329.821696 -64.798333) (xy 329.873025 -64.820145)
			(xy 329.920631 -64.849199) (xy 329.963499 -64.884874) (xy 330.000716 -64.926411) (xy 330.031489 -64.972924)
			(xy 330.055161 -65.023421) (xy 330.071229 -65.076828) (xy 330.074781 -65.100962) (xy 330.332332 -65.100962)
			(xy 330.336403 -65.04534) (xy 330.348529 -64.990903) (xy 330.368452 -64.938812) (xy 330.395748 -64.890177)
			(xy 330.429834 -64.846034) (xy 330.469983 -64.807325) (xy 330.515341 -64.774874) (xy 330.564941 -64.749373)
			(xy 330.617725 -64.731366) (xy 330.672568 -64.721236) (xy 330.728302 -64.719199) (xy 330.783739 -64.725299)
			(xy 330.837696 -64.739405) (xy 330.889025 -64.761217) (xy 330.936631 -64.790271) (xy 330.979499 -64.825946)
			(xy 331.016716 -64.867483) (xy 331.047489 -64.913996) (xy 331.071161 -64.964493) (xy 331.087229 -65.0179)
			(xy 331.095349 -65.073076) (xy 331.095858 -65.100962) (xy 331.095349 -65.128848) (xy 331.090781 -65.15989)
			(xy 331.348332 -65.15989) (xy 331.352403 -65.104268) (xy 331.364529 -65.049831) (xy 331.384452 -64.99774)
			(xy 331.411748 -64.949105) (xy 331.445834 -64.904962) (xy 331.485983 -64.866253) (xy 331.531341 -64.833802)
			(xy 331.580941 -64.808301) (xy 331.633725 -64.790294) (xy 331.688568 -64.780164) (xy 331.744302 -64.778127)
			(xy 331.799739 -64.784227) (xy 331.853696 -64.798333) (xy 331.905025 -64.820145) (xy 331.952631 -64.849199)
			(xy 331.995499 -64.884874) (xy 332.032716 -64.926411) (xy 332.063489 -64.972924) (xy 332.087161 -65.023421)
			(xy 332.103229 -65.076828) (xy 332.110182 -65.124076) (xy 354.407468 -65.124076) (xy 354.411539 -65.068454)
			(xy 354.423665 -65.014017) (xy 354.443588 -64.961926) (xy 354.470884 -64.913291) (xy 354.50497 -64.869148)
			(xy 354.545119 -64.830439) (xy 354.590477 -64.797988) (xy 354.640077 -64.772487) (xy 354.692861 -64.75448)
			(xy 354.747704 -64.74435) (xy 354.803438 -64.742313) (xy 354.858875 -64.748413) (xy 354.912832 -64.762519)
			(xy 354.964161 -64.784331) (xy 355.011767 -64.813385) (xy 355.054635 -64.84906) (xy 355.091852 -64.890597)
			(xy 355.122625 -64.93711) (xy 355.146297 -64.987607) (xy 355.162365 -65.041014) (xy 355.170485 -65.09619)
			(xy 355.170994 -65.124076) (xy 355.170485 -65.151962) (xy 355.169318 -65.15989) (xy 367.416586 -65.15989)
			(xy 367.420657 -65.104268) (xy 367.432783 -65.049831) (xy 367.452706 -64.99774) (xy 367.480002 -64.949105)
			(xy 367.514088 -64.904962) (xy 367.554237 -64.866253) (xy 367.599595 -64.833802) (xy 367.649195 -64.808301)
			(xy 367.701979 -64.790294) (xy 367.756822 -64.780164) (xy 367.812556 -64.778127) (xy 367.867993 -64.784227)
			(xy 367.92195 -64.798333) (xy 367.973279 -64.820145) (xy 368.020885 -64.849199) (xy 368.063753 -64.884874)
			(xy 368.10097 -64.926411) (xy 368.131743 -64.972924) (xy 368.155415 -65.023421) (xy 368.171483 -65.076828)
			(xy 368.175035 -65.100962) (xy 368.432586 -65.100962) (xy 368.436657 -65.04534) (xy 368.448783 -64.990903)
			(xy 368.468706 -64.938812) (xy 368.496002 -64.890177) (xy 368.530088 -64.846034) (xy 368.570237 -64.807325)
			(xy 368.615595 -64.774874) (xy 368.665195 -64.749373) (xy 368.717979 -64.731366) (xy 368.772822 -64.721236)
			(xy 368.828556 -64.719199) (xy 368.883993 -64.725299) (xy 368.93795 -64.739405) (xy 368.989279 -64.761217)
			(xy 369.036885 -64.790271) (xy 369.079753 -64.825946) (xy 369.11697 -64.867483) (xy 369.147743 -64.913996)
			(xy 369.171415 -64.964493) (xy 369.187483 -65.0179) (xy 369.195603 -65.073076) (xy 369.196112 -65.100962)
			(xy 369.195603 -65.128848) (xy 369.191035 -65.15989) (xy 369.448586 -65.15989) (xy 369.452657 -65.104268)
			(xy 369.464783 -65.049831) (xy 369.484706 -64.99774) (xy 369.512002 -64.949105) (xy 369.546088 -64.904962)
			(xy 369.586237 -64.866253) (xy 369.631595 -64.833802) (xy 369.681195 -64.808301) (xy 369.733979 -64.790294)
			(xy 369.788822 -64.780164) (xy 369.844556 -64.778127) (xy 369.899993 -64.784227) (xy 369.95395 -64.798333)
			(xy 370.005279 -64.820145) (xy 370.052885 -64.849199) (xy 370.095753 -64.884874) (xy 370.13297 -64.926411)
			(xy 370.163743 -64.972924) (xy 370.187415 -65.023421) (xy 370.203483 -65.076828) (xy 370.210436 -65.124076)
			(xy 380.407416 -65.124076) (xy 380.411487 -65.068454) (xy 380.423613 -65.014017) (xy 380.443536 -64.961926)
			(xy 380.470832 -64.913291) (xy 380.504918 -64.869148) (xy 380.545067 -64.830439) (xy 380.590425 -64.797988)
			(xy 380.640025 -64.772487) (xy 380.692809 -64.75448) (xy 380.747652 -64.74435) (xy 380.803386 -64.742313)
			(xy 380.858823 -64.748413) (xy 380.91278 -64.762519) (xy 380.964109 -64.784331) (xy 381.011715 -64.813385)
			(xy 381.054583 -64.84906) (xy 381.0918 -64.890597) (xy 381.122573 -64.93711) (xy 381.146245 -64.987607)
			(xy 381.162313 -65.041014) (xy 381.170433 -65.09619) (xy 381.170942 -65.124076) (xy 381.170433 -65.151962)
			(xy 381.169266 -65.15989) (xy 393.416534 -65.15989) (xy 393.420605 -65.104268) (xy 393.432731 -65.049831)
			(xy 393.452654 -64.99774) (xy 393.47995 -64.949105) (xy 393.514036 -64.904962) (xy 393.554185 -64.866253)
			(xy 393.599543 -64.833802) (xy 393.649143 -64.808301) (xy 393.701927 -64.790294) (xy 393.75677 -64.780164)
			(xy 393.812504 -64.778127) (xy 393.867941 -64.784227) (xy 393.921898 -64.798333) (xy 393.973227 -64.820145)
			(xy 394.020833 -64.849199) (xy 394.063701 -64.884874) (xy 394.100918 -64.926411) (xy 394.131691 -64.972924)
			(xy 394.155363 -65.023421) (xy 394.171431 -65.076828) (xy 394.174983 -65.100962) (xy 394.432534 -65.100962)
			(xy 394.436605 -65.04534) (xy 394.448731 -64.990903) (xy 394.468654 -64.938812) (xy 394.49595 -64.890177)
			(xy 394.530036 -64.846034) (xy 394.570185 -64.807325) (xy 394.615543 -64.774874) (xy 394.665143 -64.749373)
			(xy 394.717927 -64.731366) (xy 394.77277 -64.721236) (xy 394.828504 -64.719199) (xy 394.883941 -64.725299)
			(xy 394.937898 -64.739405) (xy 394.989227 -64.761217) (xy 395.036833 -64.790271) (xy 395.079701 -64.825946)
			(xy 395.116918 -64.867483) (xy 395.147691 -64.913996) (xy 395.171363 -64.964493) (xy 395.187431 -65.0179)
			(xy 395.195551 -65.073076) (xy 395.19606 -65.100962) (xy 395.195551 -65.128848) (xy 395.190983 -65.15989)
			(xy 395.448534 -65.15989) (xy 395.452605 -65.104268) (xy 395.464731 -65.049831) (xy 395.484654 -64.99774)
			(xy 395.51195 -64.949105) (xy 395.546036 -64.904962) (xy 395.586185 -64.866253) (xy 395.631543 -64.833802)
			(xy 395.681143 -64.808301) (xy 395.733927 -64.790294) (xy 395.78877 -64.780164) (xy 395.844504 -64.778127)
			(xy 395.899941 -64.784227) (xy 395.953898 -64.798333) (xy 396.005227 -64.820145) (xy 396.052833 -64.849199)
			(xy 396.095701 -64.884874) (xy 396.132918 -64.926411) (xy 396.163691 -64.972924) (xy 396.187363 -65.023421)
			(xy 396.203431 -65.076828) (xy 396.211551 -65.132004) (xy 396.21206 -65.15989) (xy 419.416482 -65.15989)
			(xy 419.420553 -65.104268) (xy 419.432679 -65.049831) (xy 419.452602 -64.99774) (xy 419.479898 -64.949105)
			(xy 419.513984 -64.904962) (xy 419.554133 -64.866253) (xy 419.599491 -64.833802) (xy 419.649091 -64.808301)
			(xy 419.701875 -64.790294) (xy 419.756718 -64.780164) (xy 419.812452 -64.778127) (xy 419.867889 -64.784227)
			(xy 419.921846 -64.798333) (xy 419.973175 -64.820145) (xy 420.020781 -64.849199) (xy 420.063649 -64.884874)
			(xy 420.100866 -64.926411) (xy 420.131639 -64.972924) (xy 420.155311 -65.023421) (xy 420.171379 -65.076828)
			(xy 420.174931 -65.100962) (xy 420.432482 -65.100962) (xy 420.436553 -65.04534) (xy 420.448679 -64.990903)
			(xy 420.468602 -64.938812) (xy 420.495898 -64.890177) (xy 420.529984 -64.846034) (xy 420.570133 -64.807325)
			(xy 420.615491 -64.774874) (xy 420.665091 -64.749373) (xy 420.717875 -64.731366) (xy 420.772718 -64.721236)
			(xy 420.828452 -64.719199) (xy 420.883889 -64.725299) (xy 420.937846 -64.739405) (xy 420.989175 -64.761217)
			(xy 421.036781 -64.790271) (xy 421.079649 -64.825946) (xy 421.116866 -64.867483) (xy 421.147639 -64.913996)
			(xy 421.171311 -64.964493) (xy 421.187379 -65.0179) (xy 421.195499 -65.073076) (xy 421.196008 -65.100962)
			(xy 421.195499 -65.128848) (xy 421.190931 -65.15989) (xy 421.448482 -65.15989) (xy 421.452553 -65.104268)
			(xy 421.464679 -65.049831) (xy 421.484602 -64.99774) (xy 421.511898 -64.949105) (xy 421.545984 -64.904962)
			(xy 421.586133 -64.866253) (xy 421.631491 -64.833802) (xy 421.681091 -64.808301) (xy 421.733875 -64.790294)
			(xy 421.788718 -64.780164) (xy 421.844452 -64.778127) (xy 421.899889 -64.784227) (xy 421.953846 -64.798333)
			(xy 422.005175 -64.820145) (xy 422.052781 -64.849199) (xy 422.095649 -64.884874) (xy 422.132866 -64.926411)
			(xy 422.163639 -64.972924) (xy 422.187311 -65.023421) (xy 422.203379 -65.076828) (xy 422.210332 -65.124076)
			(xy 432.407312 -65.124076) (xy 432.411383 -65.068454) (xy 432.423509 -65.014017) (xy 432.443432 -64.961926)
			(xy 432.470728 -64.913291) (xy 432.504814 -64.869148) (xy 432.544963 -64.830439) (xy 432.590321 -64.797988)
			(xy 432.639921 -64.772487) (xy 432.692705 -64.75448) (xy 432.747548 -64.74435) (xy 432.803282 -64.742313)
			(xy 432.858719 -64.748413) (xy 432.912676 -64.762519) (xy 432.964005 -64.784331) (xy 433.011611 -64.813385)
			(xy 433.054479 -64.84906) (xy 433.091696 -64.890597) (xy 433.122469 -64.93711) (xy 433.146141 -64.987607)
			(xy 433.162209 -65.041014) (xy 433.170329 -65.09619) (xy 433.170838 -65.124076) (xy 433.170329 -65.151962)
			(xy 433.169162 -65.15989) (xy 445.41643 -65.15989) (xy 445.420501 -65.104268) (xy 445.432627 -65.049831)
			(xy 445.45255 -64.99774) (xy 445.479846 -64.949105) (xy 445.513932 -64.904962) (xy 445.554081 -64.866253)
			(xy 445.599439 -64.833802) (xy 445.649039 -64.808301) (xy 445.701823 -64.790294) (xy 445.756666 -64.780164)
			(xy 445.8124 -64.778127) (xy 445.867837 -64.784227) (xy 445.921794 -64.798333) (xy 445.973123 -64.820145)
			(xy 446.020729 -64.849199) (xy 446.063597 -64.884874) (xy 446.100814 -64.926411) (xy 446.131587 -64.972924)
			(xy 446.155259 -65.023421) (xy 446.171327 -65.076828) (xy 446.174879 -65.100962) (xy 446.43243 -65.100962)
			(xy 446.436501 -65.04534) (xy 446.448627 -64.990903) (xy 446.46855 -64.938812) (xy 446.495846 -64.890177)
			(xy 446.529932 -64.846034) (xy 446.570081 -64.807325) (xy 446.615439 -64.774874) (xy 446.665039 -64.749373)
			(xy 446.717823 -64.731366) (xy 446.772666 -64.721236) (xy 446.8284 -64.719199) (xy 446.883837 -64.725299)
			(xy 446.937794 -64.739405) (xy 446.989123 -64.761217) (xy 447.036729 -64.790271) (xy 447.079597 -64.825946)
			(xy 447.116814 -64.867483) (xy 447.147587 -64.913996) (xy 447.171259 -64.964493) (xy 447.187327 -65.0179)
			(xy 447.195447 -65.073076) (xy 447.195956 -65.100962) (xy 447.195447 -65.128848) (xy 447.190879 -65.15989)
			(xy 447.44843 -65.15989) (xy 447.452501 -65.104268) (xy 447.464627 -65.049831) (xy 447.48455 -64.99774)
			(xy 447.511846 -64.949105) (xy 447.545932 -64.904962) (xy 447.586081 -64.866253) (xy 447.631439 -64.833802)
			(xy 447.681039 -64.808301) (xy 447.733823 -64.790294) (xy 447.788666 -64.780164) (xy 447.8444 -64.778127)
			(xy 447.899837 -64.784227) (xy 447.953794 -64.798333) (xy 448.005123 -64.820145) (xy 448.052729 -64.849199)
			(xy 448.095597 -64.884874) (xy 448.132814 -64.926411) (xy 448.163587 -64.972924) (xy 448.187259 -65.023421)
			(xy 448.203327 -65.076828) (xy 448.211447 -65.132004) (xy 448.211956 -65.15989) (xy 448.211447 -65.187776)
			(xy 448.203327 -65.242952) (xy 448.187259 -65.296359) (xy 448.163587 -65.346856) (xy 448.132814 -65.393369)
			(xy 448.095597 -65.434906) (xy 448.052729 -65.470581) (xy 448.005123 -65.499635) (xy 447.953794 -65.521447)
			(xy 447.899837 -65.535553) (xy 447.8444 -65.541653) (xy 447.788666 -65.539616) (xy 447.733823 -65.529486)
			(xy 447.681039 -65.511479) (xy 447.631439 -65.485978) (xy 447.586081 -65.453527) (xy 447.545932 -65.414818)
			(xy 447.511846 -65.370675) (xy 447.48455 -65.32204) (xy 447.464627 -65.269949) (xy 447.452501 -65.215512)
			(xy 447.44843 -65.15989) (xy 447.190879 -65.15989) (xy 447.187327 -65.184024) (xy 447.171259 -65.237431)
			(xy 447.147587 -65.287928) (xy 447.116814 -65.334441) (xy 447.079597 -65.375978) (xy 447.036729 -65.411653)
			(xy 446.989123 -65.440707) (xy 446.937794 -65.462519) (xy 446.883837 -65.476625) (xy 446.8284 -65.482725)
			(xy 446.772666 -65.480688) (xy 446.717823 -65.470558) (xy 446.665039 -65.452551) (xy 446.615439 -65.42705)
			(xy 446.570081 -65.394599) (xy 446.529932 -65.35589) (xy 446.495846 -65.311747) (xy 446.46855 -65.263112)
			(xy 446.448627 -65.211021) (xy 446.436501 -65.156584) (xy 446.43243 -65.100962) (xy 446.174879 -65.100962)
			(xy 446.179447 -65.132004) (xy 446.179956 -65.15989) (xy 446.179447 -65.187776) (xy 446.171327 -65.242952)
			(xy 446.155259 -65.296359) (xy 446.131587 -65.346856) (xy 446.100814 -65.393369) (xy 446.063597 -65.434906)
			(xy 446.020729 -65.470581) (xy 445.973123 -65.499635) (xy 445.921794 -65.521447) (xy 445.867837 -65.535553)
			(xy 445.8124 -65.541653) (xy 445.756666 -65.539616) (xy 445.701823 -65.529486) (xy 445.649039 -65.511479)
			(xy 445.599439 -65.485978) (xy 445.554081 -65.453527) (xy 445.513932 -65.414818) (xy 445.479846 -65.370675)
			(xy 445.45255 -65.32204) (xy 445.432627 -65.269949) (xy 445.420501 -65.215512) (xy 445.41643 -65.15989)
			(xy 433.169162 -65.15989) (xy 433.162209 -65.207138) (xy 433.146141 -65.260545) (xy 433.122469 -65.311042)
			(xy 433.091696 -65.357555) (xy 433.054479 -65.399092) (xy 433.011611 -65.434767) (xy 432.964005 -65.463821)
			(xy 432.912676 -65.485633) (xy 432.858719 -65.499739) (xy 432.803282 -65.505839) (xy 432.747548 -65.503802)
			(xy 432.692705 -65.493672) (xy 432.639921 -65.475665) (xy 432.590321 -65.450164) (xy 432.544963 -65.417713)
			(xy 432.504814 -65.379004) (xy 432.470728 -65.334861) (xy 432.443432 -65.286226) (xy 432.423509 -65.234135)
			(xy 432.411383 -65.179698) (xy 432.407312 -65.124076) (xy 422.210332 -65.124076) (xy 422.211499 -65.132004)
			(xy 422.212008 -65.15989) (xy 422.211499 -65.187776) (xy 422.203379 -65.242952) (xy 422.187311 -65.296359)
			(xy 422.163639 -65.346856) (xy 422.132866 -65.393369) (xy 422.095649 -65.434906) (xy 422.052781 -65.470581)
			(xy 422.005175 -65.499635) (xy 421.953846 -65.521447) (xy 421.899889 -65.535553) (xy 421.844452 -65.541653)
			(xy 421.788718 -65.539616) (xy 421.733875 -65.529486) (xy 421.681091 -65.511479) (xy 421.631491 -65.485978)
			(xy 421.586133 -65.453527) (xy 421.545984 -65.414818) (xy 421.511898 -65.370675) (xy 421.484602 -65.32204)
			(xy 421.464679 -65.269949) (xy 421.452553 -65.215512) (xy 421.448482 -65.15989) (xy 421.190931 -65.15989)
			(xy 421.187379 -65.184024) (xy 421.171311 -65.237431) (xy 421.147639 -65.287928) (xy 421.116866 -65.334441)
			(xy 421.079649 -65.375978) (xy 421.036781 -65.411653) (xy 420.989175 -65.440707) (xy 420.937846 -65.462519)
			(xy 420.883889 -65.476625) (xy 420.828452 -65.482725) (xy 420.772718 -65.480688) (xy 420.717875 -65.470558)
			(xy 420.665091 -65.452551) (xy 420.615491 -65.42705) (xy 420.570133 -65.394599) (xy 420.529984 -65.35589)
			(xy 420.495898 -65.311747) (xy 420.468602 -65.263112) (xy 420.448679 -65.211021) (xy 420.436553 -65.156584)
			(xy 420.432482 -65.100962) (xy 420.174931 -65.100962) (xy 420.179499 -65.132004) (xy 420.180008 -65.15989)
			(xy 420.179499 -65.187776) (xy 420.171379 -65.242952) (xy 420.155311 -65.296359) (xy 420.131639 -65.346856)
			(xy 420.100866 -65.393369) (xy 420.063649 -65.434906) (xy 420.020781 -65.470581) (xy 419.973175 -65.499635)
			(xy 419.921846 -65.521447) (xy 419.867889 -65.535553) (xy 419.812452 -65.541653) (xy 419.756718 -65.539616)
			(xy 419.701875 -65.529486) (xy 419.649091 -65.511479) (xy 419.599491 -65.485978) (xy 419.554133 -65.453527)
			(xy 419.513984 -65.414818) (xy 419.479898 -65.370675) (xy 419.452602 -65.32204) (xy 419.432679 -65.269949)
			(xy 419.420553 -65.215512) (xy 419.416482 -65.15989) (xy 396.21206 -65.15989) (xy 396.211551 -65.187776)
			(xy 396.203431 -65.242952) (xy 396.187363 -65.296359) (xy 396.163691 -65.346856) (xy 396.132918 -65.393369)
			(xy 396.095701 -65.434906) (xy 396.052833 -65.470581) (xy 396.005227 -65.499635) (xy 395.953898 -65.521447)
			(xy 395.899941 -65.535553) (xy 395.844504 -65.541653) (xy 395.78877 -65.539616) (xy 395.733927 -65.529486)
			(xy 395.681143 -65.511479) (xy 395.631543 -65.485978) (xy 395.586185 -65.453527) (xy 395.546036 -65.414818)
			(xy 395.51195 -65.370675) (xy 395.484654 -65.32204) (xy 395.464731 -65.269949) (xy 395.452605 -65.215512)
			(xy 395.448534 -65.15989) (xy 395.190983 -65.15989) (xy 395.187431 -65.184024) (xy 395.171363 -65.237431)
			(xy 395.147691 -65.287928) (xy 395.116918 -65.334441) (xy 395.079701 -65.375978) (xy 395.036833 -65.411653)
			(xy 394.989227 -65.440707) (xy 394.937898 -65.462519) (xy 394.883941 -65.476625) (xy 394.828504 -65.482725)
			(xy 394.77277 -65.480688) (xy 394.717927 -65.470558) (xy 394.665143 -65.452551) (xy 394.615543 -65.42705)
			(xy 394.570185 -65.394599) (xy 394.530036 -65.35589) (xy 394.49595 -65.311747) (xy 394.468654 -65.263112)
			(xy 394.448731 -65.211021) (xy 394.436605 -65.156584) (xy 394.432534 -65.100962) (xy 394.174983 -65.100962)
			(xy 394.179551 -65.132004) (xy 394.18006 -65.15989) (xy 394.179551 -65.187776) (xy 394.171431 -65.242952)
			(xy 394.155363 -65.296359) (xy 394.131691 -65.346856) (xy 394.100918 -65.393369) (xy 394.063701 -65.434906)
			(xy 394.020833 -65.470581) (xy 393.973227 -65.499635) (xy 393.921898 -65.521447) (xy 393.867941 -65.535553)
			(xy 393.812504 -65.541653) (xy 393.75677 -65.539616) (xy 393.701927 -65.529486) (xy 393.649143 -65.511479)
			(xy 393.599543 -65.485978) (xy 393.554185 -65.453527) (xy 393.514036 -65.414818) (xy 393.47995 -65.370675)
			(xy 393.452654 -65.32204) (xy 393.432731 -65.269949) (xy 393.420605 -65.215512) (xy 393.416534 -65.15989)
			(xy 381.169266 -65.15989) (xy 381.162313 -65.207138) (xy 381.146245 -65.260545) (xy 381.122573 -65.311042)
			(xy 381.0918 -65.357555) (xy 381.054583 -65.399092) (xy 381.011715 -65.434767) (xy 380.964109 -65.463821)
			(xy 380.91278 -65.485633) (xy 380.858823 -65.499739) (xy 380.803386 -65.505839) (xy 380.747652 -65.503802)
			(xy 380.692809 -65.493672) (xy 380.640025 -65.475665) (xy 380.590425 -65.450164) (xy 380.545067 -65.417713)
			(xy 380.504918 -65.379004) (xy 380.470832 -65.334861) (xy 380.443536 -65.286226) (xy 380.423613 -65.234135)
			(xy 380.411487 -65.179698) (xy 380.407416 -65.124076) (xy 370.210436 -65.124076) (xy 370.211603 -65.132004)
			(xy 370.212112 -65.15989) (xy 370.211603 -65.187776) (xy 370.203483 -65.242952) (xy 370.187415 -65.296359)
			(xy 370.163743 -65.346856) (xy 370.13297 -65.393369) (xy 370.095753 -65.434906) (xy 370.052885 -65.470581)
			(xy 370.005279 -65.499635) (xy 369.95395 -65.521447) (xy 369.899993 -65.535553) (xy 369.844556 -65.541653)
			(xy 369.788822 -65.539616) (xy 369.733979 -65.529486) (xy 369.681195 -65.511479) (xy 369.631595 -65.485978)
			(xy 369.586237 -65.453527) (xy 369.546088 -65.414818) (xy 369.512002 -65.370675) (xy 369.484706 -65.32204)
			(xy 369.464783 -65.269949) (xy 369.452657 -65.215512) (xy 369.448586 -65.15989) (xy 369.191035 -65.15989)
			(xy 369.187483 -65.184024) (xy 369.171415 -65.237431) (xy 369.147743 -65.287928) (xy 369.11697 -65.334441)
			(xy 369.079753 -65.375978) (xy 369.036885 -65.411653) (xy 368.989279 -65.440707) (xy 368.93795 -65.462519)
			(xy 368.883993 -65.476625) (xy 368.828556 -65.482725) (xy 368.772822 -65.480688) (xy 368.717979 -65.470558)
			(xy 368.665195 -65.452551) (xy 368.615595 -65.42705) (xy 368.570237 -65.394599) (xy 368.530088 -65.35589)
			(xy 368.496002 -65.311747) (xy 368.468706 -65.263112) (xy 368.448783 -65.211021) (xy 368.436657 -65.156584)
			(xy 368.432586 -65.100962) (xy 368.175035 -65.100962) (xy 368.179603 -65.132004) (xy 368.180112 -65.15989)
			(xy 368.179603 -65.187776) (xy 368.171483 -65.242952) (xy 368.155415 -65.296359) (xy 368.131743 -65.346856)
			(xy 368.10097 -65.393369) (xy 368.063753 -65.434906) (xy 368.020885 -65.470581) (xy 367.973279 -65.499635)
			(xy 367.92195 -65.521447) (xy 367.867993 -65.535553) (xy 367.812556 -65.541653) (xy 367.756822 -65.539616)
			(xy 367.701979 -65.529486) (xy 367.649195 -65.511479) (xy 367.599595 -65.485978) (xy 367.554237 -65.453527)
			(xy 367.514088 -65.414818) (xy 367.480002 -65.370675) (xy 367.452706 -65.32204) (xy 367.432783 -65.269949)
			(xy 367.420657 -65.215512) (xy 367.416586 -65.15989) (xy 355.169318 -65.15989) (xy 355.162365 -65.207138)
			(xy 355.146297 -65.260545) (xy 355.122625 -65.311042) (xy 355.091852 -65.357555) (xy 355.054635 -65.399092)
			(xy 355.011767 -65.434767) (xy 354.964161 -65.463821) (xy 354.912832 -65.485633) (xy 354.858875 -65.499739)
			(xy 354.803438 -65.505839) (xy 354.747704 -65.503802) (xy 354.692861 -65.493672) (xy 354.640077 -65.475665)
			(xy 354.590477 -65.450164) (xy 354.545119 -65.417713) (xy 354.50497 -65.379004) (xy 354.470884 -65.334861)
			(xy 354.443588 -65.286226) (xy 354.423665 -65.234135) (xy 354.411539 -65.179698) (xy 354.407468 -65.124076)
			(xy 332.110182 -65.124076) (xy 332.111349 -65.132004) (xy 332.111858 -65.15989) (xy 332.111349 -65.187776)
			(xy 332.103229 -65.242952) (xy 332.087161 -65.296359) (xy 332.063489 -65.346856) (xy 332.032716 -65.393369)
			(xy 331.995499 -65.434906) (xy 331.952631 -65.470581) (xy 331.905025 -65.499635) (xy 331.853696 -65.521447)
			(xy 331.799739 -65.535553) (xy 331.744302 -65.541653) (xy 331.688568 -65.539616) (xy 331.633725 -65.529486)
			(xy 331.580941 -65.511479) (xy 331.531341 -65.485978) (xy 331.485983 -65.453527) (xy 331.445834 -65.414818)
			(xy 331.411748 -65.370675) (xy 331.384452 -65.32204) (xy 331.364529 -65.269949) (xy 331.352403 -65.215512)
			(xy 331.348332 -65.15989) (xy 331.090781 -65.15989) (xy 331.087229 -65.184024) (xy 331.071161 -65.237431)
			(xy 331.047489 -65.287928) (xy 331.016716 -65.334441) (xy 330.979499 -65.375978) (xy 330.936631 -65.411653)
			(xy 330.889025 -65.440707) (xy 330.837696 -65.462519) (xy 330.783739 -65.476625) (xy 330.728302 -65.482725)
			(xy 330.672568 -65.480688) (xy 330.617725 -65.470558) (xy 330.564941 -65.452551) (xy 330.515341 -65.42705)
			(xy 330.469983 -65.394599) (xy 330.429834 -65.35589) (xy 330.395748 -65.311747) (xy 330.368452 -65.263112)
			(xy 330.348529 -65.211021) (xy 330.336403 -65.156584) (xy 330.332332 -65.100962) (xy 330.074781 -65.100962)
			(xy 330.079349 -65.132004) (xy 330.079858 -65.15989) (xy 330.079349 -65.187776) (xy 330.071229 -65.242952)
			(xy 330.055161 -65.296359) (xy 330.031489 -65.346856) (xy 330.000716 -65.393369) (xy 329.963499 -65.434906)
			(xy 329.920631 -65.470581) (xy 329.873025 -65.499635) (xy 329.821696 -65.521447) (xy 329.767739 -65.535553)
			(xy 329.712302 -65.541653) (xy 329.656568 -65.539616) (xy 329.601725 -65.529486) (xy 329.548941 -65.511479)
			(xy 329.499341 -65.485978) (xy 329.453983 -65.453527) (xy 329.413834 -65.414818) (xy 329.379748 -65.370675)
			(xy 329.352452 -65.32204) (xy 329.332529 -65.269949) (xy 329.320403 -65.215512) (xy 329.316332 -65.15989)
			(xy 317.069064 -65.15989) (xy 317.062111 -65.207138) (xy 317.046043 -65.260545) (xy 317.022371 -65.311042)
			(xy 316.991598 -65.357555) (xy 316.954381 -65.399092) (xy 316.911513 -65.434767) (xy 316.863907 -65.463821)
			(xy 316.812578 -65.485633) (xy 316.758621 -65.499739) (xy 316.703184 -65.505839) (xy 316.64745 -65.503802)
			(xy 316.592607 -65.493672) (xy 316.539823 -65.475665) (xy 316.490223 -65.450164) (xy 316.444865 -65.417713)
			(xy 316.404716 -65.379004) (xy 316.37063 -65.334861) (xy 316.343334 -65.286226) (xy 316.323411 -65.234135)
			(xy 316.311285 -65.179698) (xy 316.307214 -65.124076) (xy 306.110234 -65.124076) (xy 306.111401 -65.132004)
			(xy 306.11191 -65.15989) (xy 306.111401 -65.187776) (xy 306.103281 -65.242952) (xy 306.087213 -65.296359)
			(xy 306.063541 -65.346856) (xy 306.032768 -65.393369) (xy 305.995551 -65.434906) (xy 305.952683 -65.470581)
			(xy 305.905077 -65.499635) (xy 305.853748 -65.521447) (xy 305.799791 -65.535553) (xy 305.744354 -65.541653)
			(xy 305.68862 -65.539616) (xy 305.633777 -65.529486) (xy 305.580993 -65.511479) (xy 305.531393 -65.485978)
			(xy 305.486035 -65.453527) (xy 305.445886 -65.414818) (xy 305.4118 -65.370675) (xy 305.384504 -65.32204)
			(xy 305.364581 -65.269949) (xy 305.352455 -65.215512) (xy 305.348384 -65.15989) (xy 305.090833 -65.15989)
			(xy 305.087281 -65.184024) (xy 305.071213 -65.237431) (xy 305.047541 -65.287928) (xy 305.016768 -65.334441)
			(xy 304.979551 -65.375978) (xy 304.936683 -65.411653) (xy 304.889077 -65.440707) (xy 304.837748 -65.462519)
			(xy 304.783791 -65.476625) (xy 304.728354 -65.482725) (xy 304.67262 -65.480688) (xy 304.617777 -65.470558)
			(xy 304.564993 -65.452551) (xy 304.515393 -65.42705) (xy 304.470035 -65.394599) (xy 304.429886 -65.35589)
			(xy 304.3958 -65.311747) (xy 304.368504 -65.263112) (xy 304.348581 -65.211021) (xy 304.336455 -65.156584)
			(xy 304.332384 -65.100962) (xy 304.074833 -65.100962) (xy 304.079401 -65.132004) (xy 304.07991 -65.15989)
			(xy 304.079401 -65.187776) (xy 304.071281 -65.242952) (xy 304.055213 -65.296359) (xy 304.031541 -65.346856)
			(xy 304.000768 -65.393369) (xy 303.963551 -65.434906) (xy 303.920683 -65.470581) (xy 303.873077 -65.499635)
			(xy 303.821748 -65.521447) (xy 303.767791 -65.535553) (xy 303.712354 -65.541653) (xy 303.65662 -65.539616)
			(xy 303.601777 -65.529486) (xy 303.548993 -65.511479) (xy 303.499393 -65.485978) (xy 303.454035 -65.453527)
			(xy 303.413886 -65.414818) (xy 303.3798 -65.370675) (xy 303.352504 -65.32204) (xy 303.332581 -65.269949)
			(xy 303.320455 -65.215512) (xy 303.316384 -65.15989) (xy 299.113818 -65.15989) (xy 299.141565 -65.171681)
			(xy 299.189171 -65.200735) (xy 299.232039 -65.23641) (xy 299.269256 -65.277947) (xy 299.300029 -65.32446)
			(xy 299.323701 -65.374957) (xy 299.339769 -65.428364) (xy 299.347889 -65.48354) (xy 299.348398 -65.511426)
			(xy 299.347889 -65.539312) (xy 299.339769 -65.594488) (xy 299.323701 -65.647895) (xy 299.300029 -65.698392)
			(xy 299.269256 -65.744905) (xy 299.259745 -65.75552) (xy 324.546466 -65.75552) (xy 324.550537 -65.699898)
			(xy 324.562663 -65.645461) (xy 324.582586 -65.59337) (xy 324.609882 -65.544735) (xy 324.643968 -65.500592)
			(xy 324.684117 -65.461883) (xy 324.729475 -65.429432) (xy 324.779075 -65.403931) (xy 324.831859 -65.385924)
			(xy 324.886702 -65.375794) (xy 324.942436 -65.373757) (xy 324.997873 -65.379857) (xy 325.05183 -65.393963)
			(xy 325.103159 -65.415775) (xy 325.150765 -65.444829) (xy 325.193633 -65.480504) (xy 325.23085 -65.522041)
			(xy 325.261623 -65.568554) (xy 325.285295 -65.619051) (xy 325.301363 -65.672458) (xy 325.309483 -65.727634)
			(xy 325.309992 -65.75552) (xy 362.64672 -65.75552) (xy 362.650791 -65.699898) (xy 362.662917 -65.645461)
			(xy 362.68284 -65.59337) (xy 362.710136 -65.544735) (xy 362.744222 -65.500592) (xy 362.784371 -65.461883)
			(xy 362.829729 -65.429432) (xy 362.879329 -65.403931) (xy 362.932113 -65.385924) (xy 362.986956 -65.375794)
			(xy 363.04269 -65.373757) (xy 363.098127 -65.379857) (xy 363.152084 -65.393963) (xy 363.203413 -65.415775)
			(xy 363.251019 -65.444829) (xy 363.293887 -65.480504) (xy 363.331104 -65.522041) (xy 363.361877 -65.568554)
			(xy 363.385549 -65.619051) (xy 363.401617 -65.672458) (xy 363.409737 -65.727634) (xy 363.410246 -65.75552)
			(xy 388.646668 -65.75552) (xy 388.650739 -65.699898) (xy 388.662865 -65.645461) (xy 388.682788 -65.59337)
			(xy 388.710084 -65.544735) (xy 388.74417 -65.500592) (xy 388.784319 -65.461883) (xy 388.829677 -65.429432)
			(xy 388.879277 -65.403931) (xy 388.932061 -65.385924) (xy 388.986904 -65.375794) (xy 389.042638 -65.373757)
			(xy 389.098075 -65.379857) (xy 389.152032 -65.393963) (xy 389.203361 -65.415775) (xy 389.250967 -65.444829)
			(xy 389.293835 -65.480504) (xy 389.331052 -65.522041) (xy 389.361825 -65.568554) (xy 389.385497 -65.619051)
			(xy 389.401565 -65.672458) (xy 389.409685 -65.727634) (xy 389.410194 -65.75552) (xy 414.646616 -65.75552)
			(xy 414.650687 -65.699898) (xy 414.662813 -65.645461) (xy 414.682736 -65.59337) (xy 414.710032 -65.544735)
			(xy 414.744118 -65.500592) (xy 414.784267 -65.461883) (xy 414.829625 -65.429432) (xy 414.879225 -65.403931)
			(xy 414.932009 -65.385924) (xy 414.986852 -65.375794) (xy 415.042586 -65.373757) (xy 415.098023 -65.379857)
			(xy 415.15198 -65.393963) (xy 415.203309 -65.415775) (xy 415.250915 -65.444829) (xy 415.293783 -65.480504)
			(xy 415.331 -65.522041) (xy 415.361773 -65.568554) (xy 415.385445 -65.619051) (xy 415.401513 -65.672458)
			(xy 415.409633 -65.727634) (xy 415.410142 -65.75552) (xy 440.646564 -65.75552) (xy 440.650635 -65.699898)
			(xy 440.662761 -65.645461) (xy 440.682684 -65.59337) (xy 440.70998 -65.544735) (xy 440.744066 -65.500592)
			(xy 440.784215 -65.461883) (xy 440.829573 -65.429432) (xy 440.879173 -65.403931) (xy 440.931957 -65.385924)
			(xy 440.9868 -65.375794) (xy 441.042534 -65.373757) (xy 441.097971 -65.379857) (xy 441.151928 -65.393963)
			(xy 441.203257 -65.415775) (xy 441.250863 -65.444829) (xy 441.293731 -65.480504) (xy 441.330948 -65.522041)
			(xy 441.361721 -65.568554) (xy 441.385393 -65.619051) (xy 441.401461 -65.672458) (xy 441.409581 -65.727634)
			(xy 441.41009 -65.75552) (xy 441.409581 -65.783406) (xy 441.401461 -65.838582) (xy 441.385393 -65.891989)
			(xy 441.361721 -65.942486) (xy 441.330948 -65.988999) (xy 441.293731 -66.030536) (xy 441.250863 -66.066211)
			(xy 441.203257 -66.095265) (xy 441.151928 -66.117077) (xy 441.097971 -66.131183) (xy 441.042534 -66.137283)
			(xy 440.9868 -66.135246) (xy 440.931957 -66.125116) (xy 440.879173 -66.107109) (xy 440.829573 -66.081608)
			(xy 440.784215 -66.049157) (xy 440.744066 -66.010448) (xy 440.70998 -65.966305) (xy 440.682684 -65.91767)
			(xy 440.662761 -65.865579) (xy 440.650635 -65.811142) (xy 440.646564 -65.75552) (xy 415.410142 -65.75552)
			(xy 415.409633 -65.783406) (xy 415.401513 -65.838582) (xy 415.385445 -65.891989) (xy 415.361773 -65.942486)
			(xy 415.331 -65.988999) (xy 415.293783 -66.030536) (xy 415.250915 -66.066211) (xy 415.203309 -66.095265)
			(xy 415.15198 -66.117077) (xy 415.098023 -66.131183) (xy 415.042586 -66.137283) (xy 414.986852 -66.135246)
			(xy 414.932009 -66.125116) (xy 414.879225 -66.107109) (xy 414.829625 -66.081608) (xy 414.784267 -66.049157)
			(xy 414.744118 -66.010448) (xy 414.710032 -65.966305) (xy 414.682736 -65.91767) (xy 414.662813 -65.865579)
			(xy 414.650687 -65.811142) (xy 414.646616 -65.75552) (xy 389.410194 -65.75552) (xy 389.409685 -65.783406)
			(xy 389.401565 -65.838582) (xy 389.385497 -65.891989) (xy 389.361825 -65.942486) (xy 389.331052 -65.988999)
			(xy 389.293835 -66.030536) (xy 389.250967 -66.066211) (xy 389.203361 -66.095265) (xy 389.152032 -66.117077)
			(xy 389.098075 -66.131183) (xy 389.042638 -66.137283) (xy 388.986904 -66.135246) (xy 388.932061 -66.125116)
			(xy 388.879277 -66.107109) (xy 388.829677 -66.081608) (xy 388.784319 -66.049157) (xy 388.74417 -66.010448)
			(xy 388.710084 -65.966305) (xy 388.682788 -65.91767) (xy 388.662865 -65.865579) (xy 388.650739 -65.811142)
			(xy 388.646668 -65.75552) (xy 363.410246 -65.75552) (xy 363.409737 -65.783406) (xy 363.401617 -65.838582)
			(xy 363.385549 -65.891989) (xy 363.361877 -65.942486) (xy 363.331104 -65.988999) (xy 363.293887 -66.030536)
			(xy 363.251019 -66.066211) (xy 363.203413 -66.095265) (xy 363.152084 -66.117077) (xy 363.098127 -66.131183)
			(xy 363.04269 -66.137283) (xy 362.986956 -66.135246) (xy 362.932113 -66.125116) (xy 362.879329 -66.107109)
			(xy 362.829729 -66.081608) (xy 362.784371 -66.049157) (xy 362.744222 -66.010448) (xy 362.710136 -65.966305)
			(xy 362.68284 -65.91767) (xy 362.662917 -65.865579) (xy 362.650791 -65.811142) (xy 362.64672 -65.75552)
			(xy 325.309992 -65.75552) (xy 325.309483 -65.783406) (xy 325.301363 -65.838582) (xy 325.285295 -65.891989)
			(xy 325.261623 -65.942486) (xy 325.23085 -65.988999) (xy 325.193633 -66.030536) (xy 325.150765 -66.066211)
			(xy 325.103159 -66.095265) (xy 325.05183 -66.117077) (xy 324.997873 -66.131183) (xy 324.942436 -66.137283)
			(xy 324.886702 -66.135246) (xy 324.831859 -66.125116) (xy 324.779075 -66.107109) (xy 324.729475 -66.081608)
			(xy 324.684117 -66.049157) (xy 324.643968 -66.010448) (xy 324.609882 -65.966305) (xy 324.582586 -65.91767)
			(xy 324.562663 -65.865579) (xy 324.550537 -65.811142) (xy 324.546466 -65.75552) (xy 299.259745 -65.75552)
			(xy 299.232039 -65.786442) (xy 299.189171 -65.822117) (xy 299.141565 -65.851171) (xy 299.090236 -65.872983)
			(xy 299.036279 -65.887089) (xy 298.980842 -65.893189) (xy 298.925108 -65.891152) (xy 298.870265 -65.881022)
			(xy 298.817481 -65.863015) (xy 298.767881 -65.837514) (xy 298.722523 -65.805063) (xy 298.682374 -65.766354)
			(xy 298.648288 -65.722211) (xy 298.620992 -65.673576) (xy 298.601069 -65.621485) (xy 298.588943 -65.567048)
			(xy 298.584872 -65.511426) (xy 279.877382 -65.511426) (xy 279.8538 -65.521447) (xy 279.799843 -65.535553)
			(xy 279.744406 -65.541653) (xy 279.688672 -65.539616) (xy 279.633829 -65.529486) (xy 279.581045 -65.511479)
			(xy 279.531445 -65.485978) (xy 279.486087 -65.453527) (xy 279.445938 -65.414818) (xy 279.411852 -65.370675)
			(xy 279.384556 -65.32204) (xy 279.364633 -65.269949) (xy 279.352507 -65.215512) (xy 279.348436 -65.15989)
			(xy 279.090885 -65.15989) (xy 279.087333 -65.184024) (xy 279.071265 -65.237431) (xy 279.047593 -65.287928)
			(xy 279.01682 -65.334441) (xy 278.979603 -65.375978) (xy 278.936735 -65.411653) (xy 278.889129 -65.440707)
			(xy 278.8378 -65.462519) (xy 278.783843 -65.476625) (xy 278.728406 -65.482725) (xy 278.672672 -65.480688)
			(xy 278.617829 -65.470558) (xy 278.565045 -65.452551) (xy 278.515445 -65.42705) (xy 278.470087 -65.394599)
			(xy 278.429938 -65.35589) (xy 278.395852 -65.311747) (xy 278.368556 -65.263112) (xy 278.348633 -65.211021)
			(xy 278.336507 -65.156584) (xy 278.332436 -65.100962) (xy 278.074885 -65.100962) (xy 278.079453 -65.132004)
			(xy 278.079962 -65.15989) (xy 278.079453 -65.187776) (xy 278.071333 -65.242952) (xy 278.055265 -65.296359)
			(xy 278.031593 -65.346856) (xy 278.00082 -65.393369) (xy 277.963603 -65.434906) (xy 277.920735 -65.470581)
			(xy 277.873129 -65.499635) (xy 277.8218 -65.521447) (xy 277.767843 -65.535553) (xy 277.712406 -65.541653)
			(xy 277.656672 -65.539616) (xy 277.601829 -65.529486) (xy 277.549045 -65.511479) (xy 277.499445 -65.485978)
			(xy 277.454087 -65.453527) (xy 277.413938 -65.414818) (xy 277.379852 -65.370675) (xy 277.352556 -65.32204)
			(xy 277.332633 -65.269949) (xy 277.320507 -65.215512) (xy 277.316436 -65.15989) (xy 265.069168 -65.15989)
			(xy 265.062215 -65.207138) (xy 265.046147 -65.260545) (xy 265.022475 -65.311042) (xy 264.991702 -65.357555)
			(xy 264.954485 -65.399092) (xy 264.911617 -65.434767) (xy 264.864011 -65.463821) (xy 264.812682 -65.485633)
			(xy 264.758725 -65.499739) (xy 264.703288 -65.505839) (xy 264.647554 -65.503802) (xy 264.592711 -65.493672)
			(xy 264.539927 -65.475665) (xy 264.490327 -65.450164) (xy 264.444969 -65.417713) (xy 264.40482 -65.379004)
			(xy 264.370734 -65.334861) (xy 264.343438 -65.286226) (xy 264.323515 -65.234135) (xy 264.311389 -65.179698)
			(xy 264.307318 -65.124076) (xy 254.110338 -65.124076) (xy 254.111505 -65.132004) (xy 254.112014 -65.15989)
			(xy 254.111505 -65.187776) (xy 254.103385 -65.242952) (xy 254.087317 -65.296359) (xy 254.063645 -65.346856)
			(xy 254.032872 -65.393369) (xy 253.995655 -65.434906) (xy 253.952787 -65.470581) (xy 253.905181 -65.499635)
			(xy 253.853852 -65.521447) (xy 253.799895 -65.535553) (xy 253.744458 -65.541653) (xy 253.688724 -65.539616)
			(xy 253.633881 -65.529486) (xy 253.581097 -65.511479) (xy 253.531497 -65.485978) (xy 253.486139 -65.453527)
			(xy 253.44599 -65.414818) (xy 253.411904 -65.370675) (xy 253.384608 -65.32204) (xy 253.364685 -65.269949)
			(xy 253.352559 -65.215512) (xy 253.348488 -65.15989) (xy 253.090937 -65.15989) (xy 253.087385 -65.184024)
			(xy 253.071317 -65.237431) (xy 253.047645 -65.287928) (xy 253.016872 -65.334441) (xy 252.979655 -65.375978)
			(xy 252.936787 -65.411653) (xy 252.889181 -65.440707) (xy 252.837852 -65.462519) (xy 252.783895 -65.476625)
			(xy 252.728458 -65.482725) (xy 252.672724 -65.480688) (xy 252.617881 -65.470558) (xy 252.565097 -65.452551)
			(xy 252.515497 -65.42705) (xy 252.470139 -65.394599) (xy 252.42999 -65.35589) (xy 252.395904 -65.311747)
			(xy 252.368608 -65.263112) (xy 252.348685 -65.211021) (xy 252.336559 -65.156584) (xy 252.332488 -65.100962)
			(xy 252.074937 -65.100962) (xy 252.079505 -65.132004) (xy 252.080014 -65.15989) (xy 252.079505 -65.187776)
			(xy 252.071385 -65.242952) (xy 252.055317 -65.296359) (xy 252.031645 -65.346856) (xy 252.000872 -65.393369)
			(xy 251.963655 -65.434906) (xy 251.920787 -65.470581) (xy 251.873181 -65.499635) (xy 251.821852 -65.521447)
			(xy 251.767895 -65.535553) (xy 251.712458 -65.541653) (xy 251.656724 -65.539616) (xy 251.601881 -65.529486)
			(xy 251.549097 -65.511479) (xy 251.499497 -65.485978) (xy 251.454139 -65.453527) (xy 251.41399 -65.414818)
			(xy 251.379904 -65.370675) (xy 251.352608 -65.32204) (xy 251.332685 -65.269949) (xy 251.320559 -65.215512)
			(xy 251.316488 -65.15989) (xy 240.756285 -65.15989) (xy 240.741697 -65.191831) (xy 240.712231 -65.237681)
			(xy 240.67654 -65.278872) (xy 240.635349 -65.314563) (xy 240.589499 -65.344029) (xy 240.539922 -65.366671)
			(xy 240.487627 -65.382026) (xy 240.433679 -65.389782) (xy 240.379177 -65.389782) (xy 240.325229 -65.382026)
			(xy 240.272934 -65.366671) (xy 240.223357 -65.344029) (xy 240.177507 -65.314563) (xy 240.136316 -65.278872)
			(xy 240.100625 -65.237681) (xy 240.071159 -65.191831) (xy 240.048517 -65.142254) (xy 240.033162 -65.089959)
			(xy 240.025406 -65.036011) (xy 240.02492 -65.00876) (xy 240.025435 -64.97995) (xy 240.034116 -64.922988)
			(xy 240.051261 -64.867978) (xy 240.076479 -64.81617) (xy 240.109197 -64.768741) (xy 240.128552 -64.747394)
			(xy 240.13668 -64.738758) (xy 240.143538 -64.716914) (xy 240.131092 -64.626998) (xy 240.12899 -64.615636)
			(xy 240.116151 -64.596453) (xy 240.106454 -64.590168) (xy 240.082371 -64.575296) (xy 240.038405 -64.539654)
			(xy 240.000184 -64.497911) (xy 239.968547 -64.45098) (xy 239.944188 -64.399892) (xy 239.927641 -64.345767)
			(xy 239.919269 -64.289791) (xy 239.918748 -64.261492) (xy 231.764215 -64.261492) (xy 231.761037 -64.283086)
			(xy 231.744969 -64.336493) (xy 231.721297 -64.38699) (xy 231.690524 -64.433503) (xy 231.653307 -64.47504)
			(xy 231.610439 -64.510715) (xy 231.562833 -64.539769) (xy 231.511504 -64.561581) (xy 231.457547 -64.575687)
			(xy 231.40211 -64.581787) (xy 231.346376 -64.57975) (xy 231.291533 -64.56962) (xy 231.238749 -64.551613)
			(xy 231.189149 -64.526112) (xy 231.143791 -64.493661) (xy 231.103642 -64.454952) (xy 231.069556 -64.410809)
			(xy 231.04226 -64.362174) (xy 231.022337 -64.310083) (xy 231.010211 -64.255646) (xy 231.00614 -64.200024)
			(xy 228.612193 -64.200024) (xy 228.619303 -64.248338) (xy 228.619812 -64.276224) (xy 228.619303 -64.30411)
			(xy 228.611183 -64.359286) (xy 228.595115 -64.412693) (xy 228.571443 -64.46319) (xy 228.54067 -64.509703)
			(xy 228.503453 -64.55124) (xy 228.460585 -64.586915) (xy 228.412979 -64.615969) (xy 228.36165 -64.637781)
			(xy 228.307693 -64.651887) (xy 228.252256 -64.657987) (xy 228.196522 -64.65595) (xy 228.141679 -64.64582)
			(xy 228.088895 -64.627813) (xy 228.039295 -64.602312) (xy 227.993937 -64.569861) (xy 227.953788 -64.531152)
			(xy 227.919702 -64.487009) (xy 227.892406 -64.438374) (xy 227.872483 -64.386283) (xy 227.860357 -64.331846)
			(xy 227.856286 -64.276224) (xy 225.402451 -64.276224) (xy 225.36848 -64.312413) (xy 225.323269 -64.347955)
			(xy 225.298508 -64.362584) (xy 225.298254 -64.362838) (xy 225.293341 -64.36585) (xy 225.284883 -64.373674)
			(xy 225.28149 -64.378332) (xy 225.28149 -64.378586) (xy 225.278267 -64.383617) (xy 225.274023 -64.39478)
			(xy 225.273108 -64.400684) (xy 225.263202 -64.481456) (xy 225.262614 -64.487368) (xy 225.2639 -64.499176)
			(xy 225.265742 -64.504824) (xy 225.267832 -64.510238) (xy 225.274121 -64.519988) (xy 225.278188 -64.524128)
			(xy 225.278442 -64.524382) (xy 225.296661 -64.54247) (xy 225.328637 -64.582634) (xy 225.35494 -64.626722)
			(xy 225.375095 -64.673937) (xy 225.388739 -64.723429) (xy 225.395625 -64.774303) (xy 225.396044 -64.799972)
			(xy 233.19054 -64.799972) (xy 233.194611 -64.74435) (xy 233.206737 -64.689913) (xy 233.22666 -64.637822)
			(xy 233.253956 -64.589187) (xy 233.288042 -64.545044) (xy 233.328191 -64.506335) (xy 233.373549 -64.473884)
			(xy 233.423149 -64.448383) (xy 233.475933 -64.430376) (xy 233.530776 -64.420246) (xy 233.58651 -64.418209)
			(xy 233.641947 -64.424309) (xy 233.695904 -64.438415) (xy 233.747233 -64.460227) (xy 233.794839 -64.489281)
			(xy 233.837707 -64.524956) (xy 233.874924 -64.566493) (xy 233.905697 -64.613006) (xy 233.929369 -64.663503)
			(xy 233.945437 -64.71691) (xy 233.953557 -64.772086) (xy 233.954066 -64.799972) (xy 233.953557 -64.827858)
			(xy 233.945437 -64.883034) (xy 233.929369 -64.936441) (xy 233.905697 -64.986938) (xy 233.874924 -65.033451)
			(xy 233.837707 -65.074988) (xy 233.794839 -65.110663) (xy 233.747233 -65.139717) (xy 233.695904 -65.161529)
			(xy 233.641947 -65.175635) (xy 233.58651 -65.181735) (xy 233.530776 -65.179698) (xy 233.475933 -65.169568)
			(xy 233.423149 -65.151561) (xy 233.373549 -65.12606) (xy 233.328191 -65.093609) (xy 233.288042 -65.0549)
			(xy 233.253956 -65.010757) (xy 233.22666 -64.962122) (xy 233.206737 -64.910031) (xy 233.194611 -64.855594)
			(xy 233.19054 -64.799972) (xy 225.396044 -64.799972) (xy 225.395558 -64.827223) (xy 225.387802 -64.881171)
			(xy 225.372447 -64.933466) (xy 225.349805 -64.983043) (xy 225.320339 -65.028893) (xy 225.284648 -65.070084)
			(xy 225.243457 -65.105775) (xy 225.197607 -65.135241) (xy 225.14803 -65.157883) (xy 225.095735 -65.173238)
			(xy 225.041787 -65.180994) (xy 224.987285 -65.180994) (xy 224.933337 -65.173238) (xy 224.881042 -65.157883)
			(xy 224.831465 -65.135241) (xy 224.785615 -65.105775) (xy 224.744424 -65.070084) (xy 224.708733 -65.028893)
			(xy 224.679267 -64.983043) (xy 224.656625 -64.933466) (xy 224.64127 -64.881171) (xy 224.633514 -64.827223)
			(xy 224.633028 -64.799972) (xy 215.757709 -64.799972) (xy 215.805181 -64.820145) (xy 215.852787 -64.849199)
			(xy 215.895655 -64.884874) (xy 215.932872 -64.926411) (xy 215.963645 -64.972924) (xy 215.987317 -65.023421)
			(xy 216.003385 -65.076828) (xy 216.011505 -65.132004) (xy 216.012014 -65.15989) (xy 216.011505 -65.187776)
			(xy 216.003385 -65.242952) (xy 215.987317 -65.296359) (xy 215.963645 -65.346856) (xy 215.932872 -65.393369)
			(xy 215.895655 -65.434906) (xy 215.852787 -65.470581) (xy 215.805181 -65.499635) (xy 215.753852 -65.521447)
			(xy 215.699895 -65.535553) (xy 215.644458 -65.541653) (xy 215.588724 -65.539616) (xy 215.533881 -65.529486)
			(xy 215.481097 -65.511479) (xy 215.431497 -65.485978) (xy 215.386139 -65.453527) (xy 215.34599 -65.414818)
			(xy 215.311904 -65.370675) (xy 215.284608 -65.32204) (xy 215.264685 -65.269949) (xy 215.252559 -65.215512)
			(xy 215.248488 -65.15989) (xy 214.990937 -65.15989) (xy 214.987385 -65.184024) (xy 214.971317 -65.237431)
			(xy 214.947645 -65.287928) (xy 214.916872 -65.334441) (xy 214.879655 -65.375978) (xy 214.836787 -65.411653)
			(xy 214.789181 -65.440707) (xy 214.737852 -65.462519) (xy 214.683895 -65.476625) (xy 214.628458 -65.482725)
			(xy 214.572724 -65.480688) (xy 214.517881 -65.470558) (xy 214.465097 -65.452551) (xy 214.415497 -65.42705)
			(xy 214.370139 -65.394599) (xy 214.32999 -65.35589) (xy 214.295904 -65.311747) (xy 214.268608 -65.263112)
			(xy 214.248685 -65.211021) (xy 214.236559 -65.156584) (xy 214.232488 -65.100962) (xy 213.974937 -65.100962)
			(xy 213.979505 -65.132004) (xy 213.980014 -65.15989) (xy 213.979505 -65.187776) (xy 213.971385 -65.242952)
			(xy 213.955317 -65.296359) (xy 213.931645 -65.346856) (xy 213.900872 -65.393369) (xy 213.863655 -65.434906)
			(xy 213.820787 -65.470581) (xy 213.773181 -65.499635) (xy 213.721852 -65.521447) (xy 213.667895 -65.535553)
			(xy 213.612458 -65.541653) (xy 213.556724 -65.539616) (xy 213.501881 -65.529486) (xy 213.449097 -65.511479)
			(xy 213.399497 -65.485978) (xy 213.354139 -65.453527) (xy 213.31399 -65.414818) (xy 213.279904 -65.370675)
			(xy 213.252608 -65.32204) (xy 213.232685 -65.269949) (xy 213.220559 -65.215512) (xy 213.216488 -65.15989)
			(xy 200.96922 -65.15989) (xy 200.962267 -65.207138) (xy 200.946199 -65.260545) (xy 200.922527 -65.311042)
			(xy 200.891754 -65.357555) (xy 200.854537 -65.399092) (xy 200.811669 -65.434767) (xy 200.764063 -65.463821)
			(xy 200.712734 -65.485633) (xy 200.658777 -65.499739) (xy 200.60334 -65.505839) (xy 200.547606 -65.503802)
			(xy 200.492763 -65.493672) (xy 200.439979 -65.475665) (xy 200.390379 -65.450164) (xy 200.345021 -65.417713)
			(xy 200.304872 -65.379004) (xy 200.270786 -65.334861) (xy 200.24349 -65.286226) (xy 200.223567 -65.234135)
			(xy 200.211441 -65.179698) (xy 200.20737 -65.124076) (xy 190.01039 -65.124076) (xy 190.011557 -65.132004)
			(xy 190.012066 -65.15989) (xy 190.011557 -65.187776) (xy 190.003437 -65.242952) (xy 189.987369 -65.296359)
			(xy 189.963697 -65.346856) (xy 189.932924 -65.393369) (xy 189.895707 -65.434906) (xy 189.852839 -65.470581)
			(xy 189.805233 -65.499635) (xy 189.753904 -65.521447) (xy 189.699947 -65.535553) (xy 189.64451 -65.541653)
			(xy 189.588776 -65.539616) (xy 189.533933 -65.529486) (xy 189.481149 -65.511479) (xy 189.431549 -65.485978)
			(xy 189.386191 -65.453527) (xy 189.346042 -65.414818) (xy 189.311956 -65.370675) (xy 189.28466 -65.32204)
			(xy 189.264737 -65.269949) (xy 189.252611 -65.215512) (xy 189.24854 -65.15989) (xy 188.990989 -65.15989)
			(xy 188.987437 -65.184024) (xy 188.971369 -65.237431) (xy 188.947697 -65.287928) (xy 188.916924 -65.334441)
			(xy 188.879707 -65.375978) (xy 188.836839 -65.411653) (xy 188.789233 -65.440707) (xy 188.737904 -65.462519)
			(xy 188.683947 -65.476625) (xy 188.62851 -65.482725) (xy 188.572776 -65.480688) (xy 188.517933 -65.470558)
			(xy 188.465149 -65.452551) (xy 188.415549 -65.42705) (xy 188.370191 -65.394599) (xy 188.330042 -65.35589)
			(xy 188.295956 -65.311747) (xy 188.26866 -65.263112) (xy 188.248737 -65.211021) (xy 188.236611 -65.156584)
			(xy 188.23254 -65.100962) (xy 187.974989 -65.100962) (xy 187.979557 -65.132004) (xy 187.980066 -65.15989)
			(xy 187.979557 -65.187776) (xy 187.971437 -65.242952) (xy 187.955369 -65.296359) (xy 187.931697 -65.346856)
			(xy 187.900924 -65.393369) (xy 187.863707 -65.434906) (xy 187.820839 -65.470581) (xy 187.773233 -65.499635)
			(xy 187.721904 -65.521447) (xy 187.667947 -65.535553) (xy 187.61251 -65.541653) (xy 187.556776 -65.539616)
			(xy 187.501933 -65.529486) (xy 187.449149 -65.511479) (xy 187.399549 -65.485978) (xy 187.354191 -65.453527)
			(xy 187.314042 -65.414818) (xy 187.279956 -65.370675) (xy 187.25266 -65.32204) (xy 187.232737 -65.269949)
			(xy 187.220611 -65.215512) (xy 187.21654 -65.15989) (xy 164.012118 -65.15989) (xy 164.011609 -65.187776)
			(xy 164.003489 -65.242952) (xy 163.987421 -65.296359) (xy 163.963749 -65.346856) (xy 163.932976 -65.393369)
			(xy 163.895759 -65.434906) (xy 163.852891 -65.470581) (xy 163.805285 -65.499635) (xy 163.753956 -65.521447)
			(xy 163.699999 -65.535553) (xy 163.644562 -65.541653) (xy 163.588828 -65.539616) (xy 163.533985 -65.529486)
			(xy 163.481201 -65.511479) (xy 163.431601 -65.485978) (xy 163.386243 -65.453527) (xy 163.346094 -65.414818)
			(xy 163.312008 -65.370675) (xy 163.284712 -65.32204) (xy 163.264789 -65.269949) (xy 163.252663 -65.215512)
			(xy 163.248592 -65.15989) (xy 162.991041 -65.15989) (xy 162.987489 -65.184024) (xy 162.971421 -65.237431)
			(xy 162.947749 -65.287928) (xy 162.916976 -65.334441) (xy 162.879759 -65.375978) (xy 162.836891 -65.411653)
			(xy 162.789285 -65.440707) (xy 162.737956 -65.462519) (xy 162.683999 -65.476625) (xy 162.628562 -65.482725)
			(xy 162.572828 -65.480688) (xy 162.517985 -65.470558) (xy 162.465201 -65.452551) (xy 162.415601 -65.42705)
			(xy 162.370243 -65.394599) (xy 162.330094 -65.35589) (xy 162.296008 -65.311747) (xy 162.268712 -65.263112)
			(xy 162.248789 -65.211021) (xy 162.236663 -65.156584) (xy 162.232592 -65.100962) (xy 161.975041 -65.100962)
			(xy 161.979609 -65.132004) (xy 161.980118 -65.15989) (xy 161.979609 -65.187776) (xy 161.971489 -65.242952)
			(xy 161.955421 -65.296359) (xy 161.931749 -65.346856) (xy 161.900976 -65.393369) (xy 161.863759 -65.434906)
			(xy 161.820891 -65.470581) (xy 161.773285 -65.499635) (xy 161.721956 -65.521447) (xy 161.667999 -65.535553)
			(xy 161.612562 -65.541653) (xy 161.556828 -65.539616) (xy 161.501985 -65.529486) (xy 161.449201 -65.511479)
			(xy 161.399601 -65.485978) (xy 161.354243 -65.453527) (xy 161.314094 -65.414818) (xy 161.280008 -65.370675)
			(xy 161.252712 -65.32204) (xy 161.232789 -65.269949) (xy 161.220663 -65.215512) (xy 161.216592 -65.15989)
			(xy 148.969324 -65.15989) (xy 148.962371 -65.207138) (xy 148.946303 -65.260545) (xy 148.922631 -65.311042)
			(xy 148.891858 -65.357555) (xy 148.854641 -65.399092) (xy 148.811773 -65.434767) (xy 148.764167 -65.463821)
			(xy 148.712838 -65.485633) (xy 148.658881 -65.499739) (xy 148.603444 -65.505839) (xy 148.54771 -65.503802)
			(xy 148.492867 -65.493672) (xy 148.440083 -65.475665) (xy 148.390483 -65.450164) (xy 148.345125 -65.417713)
			(xy 148.304976 -65.379004) (xy 148.27089 -65.334861) (xy 148.243594 -65.286226) (xy 148.223671 -65.234135)
			(xy 148.211545 -65.179698) (xy 148.207474 -65.124076) (xy 138.010494 -65.124076) (xy 138.011661 -65.132004)
			(xy 138.01217 -65.15989) (xy 138.011661 -65.187776) (xy 138.003541 -65.242952) (xy 137.987473 -65.296359)
			(xy 137.963801 -65.346856) (xy 137.933028 -65.393369) (xy 137.895811 -65.434906) (xy 137.852943 -65.470581)
			(xy 137.805337 -65.499635) (xy 137.754008 -65.521447) (xy 137.700051 -65.535553) (xy 137.644614 -65.541653)
			(xy 137.58888 -65.539616) (xy 137.534037 -65.529486) (xy 137.481253 -65.511479) (xy 137.431653 -65.485978)
			(xy 137.386295 -65.453527) (xy 137.346146 -65.414818) (xy 137.31206 -65.370675) (xy 137.284764 -65.32204)
			(xy 137.264841 -65.269949) (xy 137.252715 -65.215512) (xy 137.248644 -65.15989) (xy 136.991093 -65.15989)
			(xy 136.987541 -65.184024) (xy 136.971473 -65.237431) (xy 136.947801 -65.287928) (xy 136.917028 -65.334441)
			(xy 136.879811 -65.375978) (xy 136.836943 -65.411653) (xy 136.789337 -65.440707) (xy 136.738008 -65.462519)
			(xy 136.684051 -65.476625) (xy 136.628614 -65.482725) (xy 136.57288 -65.480688) (xy 136.518037 -65.470558)
			(xy 136.465253 -65.452551) (xy 136.415653 -65.42705) (xy 136.370295 -65.394599) (xy 136.330146 -65.35589)
			(xy 136.29606 -65.311747) (xy 136.268764 -65.263112) (xy 136.248841 -65.211021) (xy 136.236715 -65.156584)
			(xy 136.232644 -65.100962) (xy 135.975093 -65.100962) (xy 135.979661 -65.132004) (xy 135.98017 -65.15989)
			(xy 135.979661 -65.187776) (xy 135.971541 -65.242952) (xy 135.955473 -65.296359) (xy 135.931801 -65.346856)
			(xy 135.901028 -65.393369) (xy 135.863811 -65.434906) (xy 135.820943 -65.470581) (xy 135.773337 -65.499635)
			(xy 135.722008 -65.521447) (xy 135.668051 -65.535553) (xy 135.612614 -65.541653) (xy 135.55688 -65.539616)
			(xy 135.502037 -65.529486) (xy 135.449253 -65.511479) (xy 135.399653 -65.485978) (xy 135.354295 -65.453527)
			(xy 135.314146 -65.414818) (xy 135.28006 -65.370675) (xy 135.252764 -65.32204) (xy 135.232841 -65.269949)
			(xy 135.220715 -65.215512) (xy 135.216644 -65.15989) (xy 122.969376 -65.15989) (xy 122.962423 -65.207138)
			(xy 122.946355 -65.260545) (xy 122.922683 -65.311042) (xy 122.89191 -65.357555) (xy 122.854693 -65.399092)
			(xy 122.811825 -65.434767) (xy 122.764219 -65.463821) (xy 122.71289 -65.485633) (xy 122.658933 -65.499739)
			(xy 122.603496 -65.505839) (xy 122.547762 -65.503802) (xy 122.492919 -65.493672) (xy 122.440135 -65.475665)
			(xy 122.390535 -65.450164) (xy 122.345177 -65.417713) (xy 122.305028 -65.379004) (xy 122.270942 -65.334861)
			(xy 122.243646 -65.286226) (xy 122.223723 -65.234135) (xy 122.211597 -65.179698) (xy 122.207526 -65.124076)
			(xy 99.91024 -65.124076) (xy 99.911407 -65.132004) (xy 99.911916 -65.15989) (xy 99.911407 -65.187776)
			(xy 99.903287 -65.242952) (xy 99.887219 -65.296359) (xy 99.863547 -65.346856) (xy 99.832774 -65.393369)
			(xy 99.795557 -65.434906) (xy 99.752689 -65.470581) (xy 99.705083 -65.499635) (xy 99.653754 -65.521447)
			(xy 99.599797 -65.535553) (xy 99.54436 -65.541653) (xy 99.488626 -65.539616) (xy 99.433783 -65.529486)
			(xy 99.380999 -65.511479) (xy 99.331399 -65.485978) (xy 99.286041 -65.453527) (xy 99.245892 -65.414818)
			(xy 99.211806 -65.370675) (xy 99.18451 -65.32204) (xy 99.164587 -65.269949) (xy 99.152461 -65.215512)
			(xy 99.14839 -65.15989) (xy 98.890839 -65.15989) (xy 98.887287 -65.184024) (xy 98.871219 -65.237431)
			(xy 98.847547 -65.287928) (xy 98.816774 -65.334441) (xy 98.779557 -65.375978) (xy 98.736689 -65.411653)
			(xy 98.689083 -65.440707) (xy 98.637754 -65.462519) (xy 98.583797 -65.476625) (xy 98.52836 -65.482725)
			(xy 98.472626 -65.480688) (xy 98.417783 -65.470558) (xy 98.364999 -65.452551) (xy 98.315399 -65.42705)
			(xy 98.270041 -65.394599) (xy 98.229892 -65.35589) (xy 98.195806 -65.311747) (xy 98.16851 -65.263112)
			(xy 98.148587 -65.211021) (xy 98.136461 -65.156584) (xy 98.13239 -65.100962) (xy 97.874839 -65.100962)
			(xy 97.879407 -65.132004) (xy 97.879916 -65.15989) (xy 97.879407 -65.187776) (xy 97.871287 -65.242952)
			(xy 97.855219 -65.296359) (xy 97.831547 -65.346856) (xy 97.800774 -65.393369) (xy 97.763557 -65.434906)
			(xy 97.720689 -65.470581) (xy 97.673083 -65.499635) (xy 97.621754 -65.521447) (xy 97.567797 -65.535553)
			(xy 97.51236 -65.541653) (xy 97.456626 -65.539616) (xy 97.401783 -65.529486) (xy 97.348999 -65.511479)
			(xy 97.299399 -65.485978) (xy 97.254041 -65.453527) (xy 97.213892 -65.414818) (xy 97.179806 -65.370675)
			(xy 97.15251 -65.32204) (xy 97.132587 -65.269949) (xy 97.120461 -65.215512) (xy 97.11639 -65.15989)
			(xy 84.869122 -65.15989) (xy 84.862169 -65.207138) (xy 84.846101 -65.260545) (xy 84.822429 -65.311042)
			(xy 84.791656 -65.357555) (xy 84.754439 -65.399092) (xy 84.711571 -65.434767) (xy 84.663965 -65.463821)
			(xy 84.612636 -65.485633) (xy 84.558679 -65.499739) (xy 84.503242 -65.505839) (xy 84.447508 -65.503802)
			(xy 84.392665 -65.493672) (xy 84.339881 -65.475665) (xy 84.290281 -65.450164) (xy 84.244923 -65.417713)
			(xy 84.204774 -65.379004) (xy 84.170688 -65.334861) (xy 84.143392 -65.286226) (xy 84.123469 -65.234135)
			(xy 84.111343 -65.179698) (xy 84.107272 -65.124076) (xy 73.910292 -65.124076) (xy 73.911459 -65.132004)
			(xy 73.911968 -65.15989) (xy 73.911459 -65.187776) (xy 73.903339 -65.242952) (xy 73.887271 -65.296359)
			(xy 73.863599 -65.346856) (xy 73.832826 -65.393369) (xy 73.795609 -65.434906) (xy 73.752741 -65.470581)
			(xy 73.705135 -65.499635) (xy 73.653806 -65.521447) (xy 73.599849 -65.535553) (xy 73.544412 -65.541653)
			(xy 73.488678 -65.539616) (xy 73.433835 -65.529486) (xy 73.381051 -65.511479) (xy 73.331451 -65.485978)
			(xy 73.286093 -65.453527) (xy 73.245944 -65.414818) (xy 73.211858 -65.370675) (xy 73.184562 -65.32204)
			(xy 73.164639 -65.269949) (xy 73.152513 -65.215512) (xy 73.148442 -65.15989) (xy 72.890891 -65.15989)
			(xy 72.887339 -65.184024) (xy 72.871271 -65.237431) (xy 72.847599 -65.287928) (xy 72.816826 -65.334441)
			(xy 72.779609 -65.375978) (xy 72.736741 -65.411653) (xy 72.689135 -65.440707) (xy 72.637806 -65.462519)
			(xy 72.583849 -65.476625) (xy 72.528412 -65.482725) (xy 72.472678 -65.480688) (xy 72.417835 -65.470558)
			(xy 72.365051 -65.452551) (xy 72.315451 -65.42705) (xy 72.270093 -65.394599) (xy 72.229944 -65.35589)
			(xy 72.195858 -65.311747) (xy 72.168562 -65.263112) (xy 72.148639 -65.211021) (xy 72.136513 -65.156584)
			(xy 72.132442 -65.100962) (xy 71.874891 -65.100962) (xy 71.879459 -65.132004) (xy 71.879968 -65.15989)
			(xy 71.879459 -65.187776) (xy 71.871339 -65.242952) (xy 71.855271 -65.296359) (xy 71.831599 -65.346856)
			(xy 71.800826 -65.393369) (xy 71.763609 -65.434906) (xy 71.720741 -65.470581) (xy 71.673135 -65.499635)
			(xy 71.621806 -65.521447) (xy 71.567849 -65.535553) (xy 71.512412 -65.541653) (xy 71.456678 -65.539616)
			(xy 71.401835 -65.529486) (xy 71.349051 -65.511479) (xy 71.299451 -65.485978) (xy 71.254093 -65.453527)
			(xy 71.213944 -65.414818) (xy 71.179858 -65.370675) (xy 71.152562 -65.32204) (xy 71.132639 -65.269949)
			(xy 71.120513 -65.215512) (xy 71.116442 -65.15989) (xy 47.91202 -65.15989) (xy 47.911511 -65.187776)
			(xy 47.903391 -65.242952) (xy 47.887323 -65.296359) (xy 47.863651 -65.346856) (xy 47.832878 -65.393369)
			(xy 47.795661 -65.434906) (xy 47.752793 -65.470581) (xy 47.705187 -65.499635) (xy 47.653858 -65.521447)
			(xy 47.599901 -65.535553) (xy 47.544464 -65.541653) (xy 47.48873 -65.539616) (xy 47.433887 -65.529486)
			(xy 47.381103 -65.511479) (xy 47.331503 -65.485978) (xy 47.286145 -65.453527) (xy 47.245996 -65.414818)
			(xy 47.21191 -65.370675) (xy 47.184614 -65.32204) (xy 47.164691 -65.269949) (xy 47.152565 -65.215512)
			(xy 47.148494 -65.15989) (xy 46.890943 -65.15989) (xy 46.887391 -65.184024) (xy 46.871323 -65.237431)
			(xy 46.847651 -65.287928) (xy 46.816878 -65.334441) (xy 46.779661 -65.375978) (xy 46.736793 -65.411653)
			(xy 46.689187 -65.440707) (xy 46.637858 -65.462519) (xy 46.583901 -65.476625) (xy 46.528464 -65.482725)
			(xy 46.47273 -65.480688) (xy 46.417887 -65.470558) (xy 46.365103 -65.452551) (xy 46.315503 -65.42705)
			(xy 46.270145 -65.394599) (xy 46.229996 -65.35589) (xy 46.19591 -65.311747) (xy 46.168614 -65.263112)
			(xy 46.148691 -65.211021) (xy 46.136565 -65.156584) (xy 46.132494 -65.100962) (xy 45.874943 -65.100962)
			(xy 45.879511 -65.132004) (xy 45.88002 -65.15989) (xy 45.879511 -65.187776) (xy 45.871391 -65.242952)
			(xy 45.855323 -65.296359) (xy 45.831651 -65.346856) (xy 45.800878 -65.393369) (xy 45.763661 -65.434906)
			(xy 45.720793 -65.470581) (xy 45.673187 -65.499635) (xy 45.621858 -65.521447) (xy 45.567901 -65.535553)
			(xy 45.512464 -65.541653) (xy 45.45673 -65.539616) (xy 45.401887 -65.529486) (xy 45.349103 -65.511479)
			(xy 45.299503 -65.485978) (xy 45.254145 -65.453527) (xy 45.213996 -65.414818) (xy 45.17991 -65.370675)
			(xy 45.152614 -65.32204) (xy 45.132691 -65.269949) (xy 45.120565 -65.215512) (xy 45.116494 -65.15989)
			(xy 32.869226 -65.15989) (xy 32.862273 -65.207138) (xy 32.846205 -65.260545) (xy 32.822533 -65.311042)
			(xy 32.79176 -65.357555) (xy 32.754543 -65.399092) (xy 32.711675 -65.434767) (xy 32.664069 -65.463821)
			(xy 32.61274 -65.485633) (xy 32.558783 -65.499739) (xy 32.503346 -65.505839) (xy 32.447612 -65.503802)
			(xy 32.392769 -65.493672) (xy 32.339985 -65.475665) (xy 32.290385 -65.450164) (xy 32.245027 -65.417713)
			(xy 32.204878 -65.379004) (xy 32.170792 -65.334861) (xy 32.143496 -65.286226) (xy 32.123573 -65.234135)
			(xy 32.111447 -65.179698) (xy 32.107376 -65.124076) (xy 21.910396 -65.124076) (xy 21.911563 -65.132004)
			(xy 21.912072 -65.15989) (xy 21.911563 -65.187776) (xy 21.903443 -65.242952) (xy 21.887375 -65.296359)
			(xy 21.863703 -65.346856) (xy 21.83293 -65.393369) (xy 21.795713 -65.434906) (xy 21.752845 -65.470581)
			(xy 21.705239 -65.499635) (xy 21.65391 -65.521447) (xy 21.599953 -65.535553) (xy 21.544516 -65.541653)
			(xy 21.488782 -65.539616) (xy 21.433939 -65.529486) (xy 21.381155 -65.511479) (xy 21.331555 -65.485978)
			(xy 21.286197 -65.453527) (xy 21.246048 -65.414818) (xy 21.211962 -65.370675) (xy 21.184666 -65.32204)
			(xy 21.164743 -65.269949) (xy 21.152617 -65.215512) (xy 21.148546 -65.15989) (xy 20.891059 -65.15989)
			(xy 20.887858 -65.182169) (xy 20.872505 -65.234469) (xy 20.849865 -65.284052) (xy 20.820397 -65.329907)
			(xy 20.784703 -65.371101) (xy 20.743509 -65.406796) (xy 20.697654 -65.436264) (xy 20.648071 -65.458905)
			(xy 20.595771 -65.474258) (xy 20.541818 -65.482011) (xy 20.514564 -65.48247) (xy 20.488402 -65.481708)
			(xy 20.477937 -65.481539) (xy 20.45827 -65.488634) (xy 20.450302 -65.495424) (xy 20.396454 -65.54597)
			(xy 20.389185 -65.553469) (xy 20.38091 -65.572621) (xy 20.380452 -65.583054) (xy 20.380452 -65.75552)
			(xy 40.346628 -65.75552) (xy 40.350699 -65.699898) (xy 40.362825 -65.645461) (xy 40.382748 -65.59337)
			(xy 40.410044 -65.544735) (xy 40.44413 -65.500592) (xy 40.484279 -65.461883) (xy 40.529637 -65.429432)
			(xy 40.579237 -65.403931) (xy 40.632021 -65.385924) (xy 40.686864 -65.375794) (xy 40.742598 -65.373757)
			(xy 40.798035 -65.379857) (xy 40.851992 -65.393963) (xy 40.903321 -65.415775) (xy 40.950927 -65.444829)
			(xy 40.993795 -65.480504) (xy 41.031012 -65.522041) (xy 41.061785 -65.568554) (xy 41.085457 -65.619051)
			(xy 41.101525 -65.672458) (xy 41.109645 -65.727634) (xy 41.110154 -65.75552) (xy 66.346576 -65.75552)
			(xy 66.350647 -65.699898) (xy 66.362773 -65.645461) (xy 66.382696 -65.59337) (xy 66.409992 -65.544735)
			(xy 66.444078 -65.500592) (xy 66.484227 -65.461883) (xy 66.529585 -65.429432) (xy 66.579185 -65.403931)
			(xy 66.631969 -65.385924) (xy 66.686812 -65.375794) (xy 66.742546 -65.373757) (xy 66.797983 -65.379857)
			(xy 66.85194 -65.393963) (xy 66.903269 -65.415775) (xy 66.950875 -65.444829) (xy 66.993743 -65.480504)
			(xy 67.03096 -65.522041) (xy 67.061733 -65.568554) (xy 67.085405 -65.619051) (xy 67.101473 -65.672458)
			(xy 67.109593 -65.727634) (xy 67.110102 -65.75552) (xy 92.346524 -65.75552) (xy 92.350595 -65.699898)
			(xy 92.362721 -65.645461) (xy 92.382644 -65.59337) (xy 92.40994 -65.544735) (xy 92.444026 -65.500592)
			(xy 92.484175 -65.461883) (xy 92.529533 -65.429432) (xy 92.579133 -65.403931) (xy 92.631917 -65.385924)
			(xy 92.68676 -65.375794) (xy 92.742494 -65.373757) (xy 92.797931 -65.379857) (xy 92.851888 -65.393963)
			(xy 92.903217 -65.415775) (xy 92.950823 -65.444829) (xy 92.993691 -65.480504) (xy 93.030908 -65.522041)
			(xy 93.061681 -65.568554) (xy 93.085353 -65.619051) (xy 93.101421 -65.672458) (xy 93.109541 -65.727634)
			(xy 93.11005 -65.75552) (xy 130.446778 -65.75552) (xy 130.450849 -65.699898) (xy 130.462975 -65.645461)
			(xy 130.482898 -65.59337) (xy 130.510194 -65.544735) (xy 130.54428 -65.500592) (xy 130.584429 -65.461883)
			(xy 130.629787 -65.429432) (xy 130.679387 -65.403931) (xy 130.732171 -65.385924) (xy 130.787014 -65.375794)
			(xy 130.842748 -65.373757) (xy 130.898185 -65.379857) (xy 130.952142 -65.393963) (xy 131.003471 -65.415775)
			(xy 131.051077 -65.444829) (xy 131.093945 -65.480504) (xy 131.131162 -65.522041) (xy 131.161935 -65.568554)
			(xy 131.185607 -65.619051) (xy 131.201675 -65.672458) (xy 131.209795 -65.727634) (xy 131.210304 -65.75552)
			(xy 156.446726 -65.75552) (xy 156.450797 -65.699898) (xy 156.462923 -65.645461) (xy 156.482846 -65.59337)
			(xy 156.510142 -65.544735) (xy 156.544228 -65.500592) (xy 156.584377 -65.461883) (xy 156.629735 -65.429432)
			(xy 156.679335 -65.403931) (xy 156.732119 -65.385924) (xy 156.786962 -65.375794) (xy 156.842696 -65.373757)
			(xy 156.898133 -65.379857) (xy 156.95209 -65.393963) (xy 157.003419 -65.415775) (xy 157.051025 -65.444829)
			(xy 157.093893 -65.480504) (xy 157.13111 -65.522041) (xy 157.161883 -65.568554) (xy 157.185555 -65.619051)
			(xy 157.201623 -65.672458) (xy 157.209743 -65.727634) (xy 157.210252 -65.75552) (xy 182.446674 -65.75552)
			(xy 182.450745 -65.699898) (xy 182.462871 -65.645461) (xy 182.482794 -65.59337) (xy 182.51009 -65.544735)
			(xy 182.544176 -65.500592) (xy 182.584325 -65.461883) (xy 182.629683 -65.429432) (xy 182.679283 -65.403931)
			(xy 182.732067 -65.385924) (xy 182.78691 -65.375794) (xy 182.842644 -65.373757) (xy 182.898081 -65.379857)
			(xy 182.952038 -65.393963) (xy 183.003367 -65.415775) (xy 183.050973 -65.444829) (xy 183.093841 -65.480504)
			(xy 183.131058 -65.522041) (xy 183.161831 -65.568554) (xy 183.185503 -65.619051) (xy 183.201571 -65.672458)
			(xy 183.209691 -65.727634) (xy 183.2102 -65.75552) (xy 208.446622 -65.75552) (xy 208.450693 -65.699898)
			(xy 208.462819 -65.645461) (xy 208.482742 -65.59337) (xy 208.510038 -65.544735) (xy 208.544124 -65.500592)
			(xy 208.584273 -65.461883) (xy 208.629631 -65.429432) (xy 208.679231 -65.403931) (xy 208.732015 -65.385924)
			(xy 208.786858 -65.375794) (xy 208.842592 -65.373757) (xy 208.898029 -65.379857) (xy 208.951986 -65.393963)
			(xy 209.003315 -65.415775) (xy 209.050921 -65.444829) (xy 209.093789 -65.480504) (xy 209.131006 -65.522041)
			(xy 209.161779 -65.568554) (xy 209.185451 -65.619051) (xy 209.201519 -65.672458) (xy 209.209639 -65.727634)
			(xy 209.210148 -65.75552) (xy 209.209639 -65.783406) (xy 209.201519 -65.838582) (xy 209.185451 -65.891989)
			(xy 209.161779 -65.942486) (xy 209.131006 -65.988999) (xy 209.093789 -66.030536) (xy 209.050921 -66.066211)
			(xy 209.003315 -66.095265) (xy 208.951986 -66.117077) (xy 208.898029 -66.131183) (xy 208.842592 -66.137283)
			(xy 208.786858 -66.135246) (xy 208.732015 -66.125116) (xy 208.679231 -66.107109) (xy 208.629631 -66.081608)
			(xy 208.584273 -66.049157) (xy 208.544124 -66.010448) (xy 208.510038 -65.966305) (xy 208.482742 -65.91767)
			(xy 208.462819 -65.865579) (xy 208.450693 -65.811142) (xy 208.446622 -65.75552) (xy 183.2102 -65.75552)
			(xy 183.209691 -65.783406) (xy 183.201571 -65.838582) (xy 183.185503 -65.891989) (xy 183.161831 -65.942486)
			(xy 183.131058 -65.988999) (xy 183.093841 -66.030536) (xy 183.050973 -66.066211) (xy 183.003367 -66.095265)
			(xy 182.952038 -66.117077) (xy 182.898081 -66.131183) (xy 182.842644 -66.137283) (xy 182.78691 -66.135246)
			(xy 182.732067 -66.125116) (xy 182.679283 -66.107109) (xy 182.629683 -66.081608) (xy 182.584325 -66.049157)
			(xy 182.544176 -66.010448) (xy 182.51009 -65.966305) (xy 182.482794 -65.91767) (xy 182.462871 -65.865579)
			(xy 182.450745 -65.811142) (xy 182.446674 -65.75552) (xy 157.210252 -65.75552) (xy 157.209743 -65.783406)
			(xy 157.201623 -65.838582) (xy 157.185555 -65.891989) (xy 157.161883 -65.942486) (xy 157.13111 -65.988999)
			(xy 157.093893 -66.030536) (xy 157.051025 -66.066211) (xy 157.003419 -66.095265) (xy 156.95209 -66.117077)
			(xy 156.898133 -66.131183) (xy 156.842696 -66.137283) (xy 156.786962 -66.135246) (xy 156.732119 -66.125116)
			(xy 156.679335 -66.107109) (xy 156.629735 -66.081608) (xy 156.584377 -66.049157) (xy 156.544228 -66.010448)
			(xy 156.510142 -65.966305) (xy 156.482846 -65.91767) (xy 156.462923 -65.865579) (xy 156.450797 -65.811142)
			(xy 156.446726 -65.75552) (xy 131.210304 -65.75552) (xy 131.209795 -65.783406) (xy 131.201675 -65.838582)
			(xy 131.185607 -65.891989) (xy 131.161935 -65.942486) (xy 131.131162 -65.988999) (xy 131.093945 -66.030536)
			(xy 131.051077 -66.066211) (xy 131.003471 -66.095265) (xy 130.952142 -66.117077) (xy 130.898185 -66.131183)
			(xy 130.842748 -66.137283) (xy 130.787014 -66.135246) (xy 130.732171 -66.125116) (xy 130.679387 -66.107109)
			(xy 130.629787 -66.081608) (xy 130.584429 -66.049157) (xy 130.54428 -66.010448) (xy 130.510194 -65.966305)
			(xy 130.482898 -65.91767) (xy 130.462975 -65.865579) (xy 130.450849 -65.811142) (xy 130.446778 -65.75552)
			(xy 93.11005 -65.75552) (xy 93.109541 -65.783406) (xy 93.101421 -65.838582) (xy 93.085353 -65.891989)
			(xy 93.061681 -65.942486) (xy 93.030908 -65.988999) (xy 92.993691 -66.030536) (xy 92.950823 -66.066211)
			(xy 92.903217 -66.095265) (xy 92.851888 -66.117077) (xy 92.797931 -66.131183) (xy 92.742494 -66.137283)
			(xy 92.68676 -66.135246) (xy 92.631917 -66.125116) (xy 92.579133 -66.107109) (xy 92.529533 -66.081608)
			(xy 92.484175 -66.049157) (xy 92.444026 -66.010448) (xy 92.40994 -65.966305) (xy 92.382644 -65.91767)
			(xy 92.362721 -65.865579) (xy 92.350595 -65.811142) (xy 92.346524 -65.75552) (xy 67.110102 -65.75552)
			(xy 67.109593 -65.783406) (xy 67.101473 -65.838582) (xy 67.085405 -65.891989) (xy 67.061733 -65.942486)
			(xy 67.03096 -65.988999) (xy 66.993743 -66.030536) (xy 66.950875 -66.066211) (xy 66.903269 -66.095265)
			(xy 66.85194 -66.117077) (xy 66.797983 -66.131183) (xy 66.742546 -66.137283) (xy 66.686812 -66.135246)
			(xy 66.631969 -66.125116) (xy 66.579185 -66.107109) (xy 66.529585 -66.081608) (xy 66.484227 -66.049157)
			(xy 66.444078 -66.010448) (xy 66.409992 -65.966305) (xy 66.382696 -65.91767) (xy 66.362773 -65.865579)
			(xy 66.350647 -65.811142) (xy 66.346576 -65.75552) (xy 41.110154 -65.75552) (xy 41.109645 -65.783406)
			(xy 41.101525 -65.838582) (xy 41.085457 -65.891989) (xy 41.061785 -65.942486) (xy 41.031012 -65.988999)
			(xy 40.993795 -66.030536) (xy 40.950927 -66.066211) (xy 40.903321 -66.095265) (xy 40.851992 -66.117077)
			(xy 40.798035 -66.131183) (xy 40.742598 -66.137283) (xy 40.686864 -66.135246) (xy 40.632021 -66.125116)
			(xy 40.579237 -66.107109) (xy 40.529637 -66.081608) (xy 40.484279 -66.049157) (xy 40.44413 -66.010448)
			(xy 40.410044 -65.966305) (xy 40.382748 -65.91767) (xy 40.362825 -65.865579) (xy 40.350699 -65.811142)
			(xy 40.346628 -65.75552) (xy 20.380452 -65.75552) (xy 20.380452 -67.055492) (xy 20.380887 -67.065188)
			(xy 20.388072 -67.083202) (xy 20.394422 -67.090544) (xy 20.430878 -67.12895) (xy 40.366698 -67.12895)
			(xy 40.366698 -67.07445) (xy 40.374454 -67.020506) (xy 40.389808 -66.968214) (xy 40.412448 -66.91864)
			(xy 40.441912 -66.872792) (xy 40.477601 -66.831604) (xy 40.518789 -66.795915) (xy 40.564636 -66.76645)
			(xy 40.614211 -66.74381) (xy 40.666502 -66.728455) (xy 40.720446 -66.720699) (xy 40.747696 -66.720212)
			(xy 40.775066 -66.720677) (xy 40.829246 -66.728495) (xy 40.881749 -66.743984) (xy 40.931496 -66.766826)
			(xy 40.977462 -66.796551) (xy 40.998394 -66.814192) (xy 40.998648 -66.814446) (xy 41.005741 -66.820023)
			(xy 41.022653 -66.826274) (xy 41.031668 -66.826638) (xy 41.098724 -66.826638) (xy 41.107741 -66.826284)
			(xy 41.124658 -66.820034) (xy 41.131744 -66.814446) (xy 41.132252 -66.813938) (xy 41.15319 -66.79636)
			(xy 41.199123 -66.766719) (xy 41.248818 -66.743939) (xy 41.301256 -66.728488) (xy 41.355362 -66.720682)
			(xy 41.382696 -66.720212) (xy 41.409951 -66.720635) (xy 41.463905 -66.728392) (xy 41.516206 -66.743748)
			(xy 41.565789 -66.766392) (xy 41.611645 -66.795861) (xy 41.652841 -66.831557) (xy 41.688537 -66.872752)
			(xy 41.718007 -66.918607) (xy 41.740651 -66.96819) (xy 41.756008 -67.020491) (xy 41.763765 -67.074446)
			(xy 41.763765 -67.128954) (xy 41.756008 -67.182909) (xy 41.740651 -67.23521) (xy 41.718007 -67.284793)
			(xy 41.688537 -67.330648) (xy 41.652841 -67.371843) (xy 41.611645 -67.407539) (xy 41.565789 -67.437008)
			(xy 41.516206 -67.459652) (xy 41.463905 -67.475008) (xy 41.409951 -67.482765) (xy 41.382696 -67.483228)
			(xy 41.355325 -67.482782) (xy 41.301144 -67.474962) (xy 41.24864 -67.459469) (xy 41.198894 -67.436623)
			(xy 41.152928 -67.406892) (xy 41.131998 -67.389248) (xy 41.131744 -67.388994) (xy 41.124649 -67.383419)
			(xy 41.107739 -67.377166) (xy 41.098724 -67.376802) (xy 41.031668 -67.376802) (xy 41.02265 -67.377143)
			(xy 41.005733 -67.383402) (xy 40.998648 -67.388994) (xy 40.99814 -67.389502) (xy 40.97721 -67.407089)
			(xy 40.931274 -67.436728) (xy 40.881578 -67.459506) (xy 40.829138 -67.474955) (xy 40.77503 -67.482759)
			(xy 40.747696 -67.483228) (xy 40.720446 -67.482701) (xy 40.666502 -67.474945) (xy 40.614211 -67.45959)
			(xy 40.564636 -67.43695) (xy 40.518789 -67.407485) (xy 40.477601 -67.371796) (xy 40.441912 -67.330608)
			(xy 40.412448 -67.28476) (xy 40.389808 -67.235186) (xy 40.374454 -67.182894) (xy 40.366698 -67.12895)
			(xy 20.430878 -67.12895) (xy 20.44192 -67.140582) (xy 20.442428 -67.14109) (xy 20.448524 -67.147694)
			(xy 20.465542 -67.156076) (xy 20.47621 -67.156838) (xy 20.476718 -67.156838) (xy 20.50407 -67.158994)
			(xy 20.557786 -67.170166) (xy 20.609347 -67.188918) (xy 20.657689 -67.214864) (xy 20.701816 -67.247469)
			(xy 20.740816 -67.286058) (xy 20.773885 -67.329837) (xy 20.800341 -67.377903) (xy 20.819638 -67.429262)
			(xy 20.831378 -67.482857) (xy 20.835318 -67.53758) (xy 20.831378 -67.592304) (xy 20.831235 -67.592956)
			(xy 21.345396 -67.592956) (xy 21.349467 -67.537334) (xy 21.361593 -67.482897) (xy 21.381516 -67.430806)
			(xy 21.408812 -67.382171) (xy 21.442898 -67.338028) (xy 21.483047 -67.299319) (xy 21.528405 -67.266868)
			(xy 21.578005 -67.241367) (xy 21.630789 -67.22336) (xy 21.685632 -67.21323) (xy 21.741366 -67.211193)
			(xy 21.796803 -67.217293) (xy 21.85076 -67.231399) (xy 21.902089 -67.253211) (xy 21.949695 -67.282265)
			(xy 21.992563 -67.31794) (xy 22.02978 -67.359477) (xy 22.060553 -67.40599) (xy 22.084225 -67.456487)
			(xy 22.093722 -67.488054) (xy 44.779182 -67.488054) (xy 44.783253 -67.432432) (xy 44.795379 -67.377995)
			(xy 44.815302 -67.325904) (xy 44.842598 -67.277269) (xy 44.876684 -67.233126) (xy 44.916833 -67.194417)
			(xy 44.962191 -67.161966) (xy 45.011791 -67.136465) (xy 45.064575 -67.118458) (xy 45.119418 -67.108328)
			(xy 45.175152 -67.106291) (xy 45.230589 -67.112391) (xy 45.284546 -67.126497) (xy 45.290326 -67.128953)
			(xy 66.366575 -67.128953) (xy 66.366575 -67.074447) (xy 66.374333 -67.020495) (xy 66.389691 -66.968196)
			(xy 66.412335 -66.918616) (xy 66.441806 -66.872763) (xy 66.477502 -66.831571) (xy 66.518698 -66.795879)
			(xy 66.564554 -66.766414) (xy 66.614137 -66.743775) (xy 66.666438 -66.728424) (xy 66.720391 -66.720672)
			(xy 66.747644 -66.720212) (xy 66.775013 -66.720708) (xy 66.829191 -66.728518) (xy 66.881694 -66.744)
			(xy 66.931441 -66.766835) (xy 66.977409 -66.796554) (xy 66.998342 -66.814192) (xy 66.998596 -66.814446)
			(xy 67.005676 -66.820043) (xy 67.022598 -66.826282) (xy 67.031616 -66.826638) (xy 67.098672 -66.826638)
			(xy 67.107686 -66.826259) (xy 67.124603 -66.820026) (xy 67.131692 -66.814446) (xy 67.1322 -66.813938)
			(xy 67.15312 -66.796338) (xy 67.199058 -66.766699) (xy 67.248757 -66.743924) (xy 67.301199 -66.728478)
			(xy 67.355309 -66.720678) (xy 67.382644 -66.720212) (xy 67.409895 -66.720661) (xy 67.46384 -66.728423)
			(xy 67.516133 -66.743783) (xy 67.565707 -66.766427) (xy 67.611554 -66.795896) (xy 67.652741 -66.83159)
			(xy 67.68843 -66.872781) (xy 67.717894 -66.918632) (xy 67.740533 -66.968209) (xy 67.755887 -67.020503)
			(xy 67.763642 -67.074449) (xy 67.763642 -67.128951) (xy 67.755887 -67.182897) (xy 67.740533 -67.235191)
			(xy 67.717894 -67.284768) (xy 67.68843 -67.330619) (xy 67.652741 -67.37181) (xy 67.611554 -67.407504)
			(xy 67.565707 -67.436973) (xy 67.516133 -67.459617) (xy 67.46384 -67.474977) (xy 67.409895 -67.482739)
			(xy 67.382644 -67.483228) (xy 67.355274 -67.482754) (xy 67.301094 -67.474941) (xy 67.248591 -67.459454)
			(xy 67.198844 -67.436614) (xy 67.152877 -67.40689) (xy 67.131946 -67.389248) (xy 67.131692 -67.388994)
			(xy 67.124612 -67.383397) (xy 67.10769 -67.377157) (xy 67.098672 -67.376802) (xy 67.031616 -67.376802)
			(xy 67.0226 -67.377166) (xy 67.005683 -67.383409) (xy 66.998596 -67.388994) (xy 66.998088 -67.389502)
			(xy 66.977178 -67.407114) (xy 66.931237 -67.436749) (xy 66.881535 -67.459522) (xy 66.829091 -67.474965)
			(xy 66.774979 -67.482763) (xy 66.747644 -67.483228) (xy 66.720391 -67.482728) (xy 66.666438 -67.474976)
			(xy 66.614137 -67.459625) (xy 66.564554 -67.436986) (xy 66.518698 -67.407521) (xy 66.477502 -67.371829)
			(xy 66.441806 -67.330637) (xy 66.412335 -67.284784) (xy 66.389691 -67.235204) (xy 66.374333 -67.182905)
			(xy 66.366575 -67.128953) (xy 45.290326 -67.128953) (xy 45.335875 -67.148309) (xy 45.383481 -67.177363)
			(xy 45.426349 -67.213038) (xy 45.463566 -67.254575) (xy 45.494339 -67.301088) (xy 45.518011 -67.351585)
			(xy 45.534079 -67.404992) (xy 45.542199 -67.460168) (xy 45.542708 -67.488054) (xy 45.542199 -67.51594)
			(xy 45.539014 -67.537584) (xy 46.07128 -67.537584) (xy 46.075351 -67.481962) (xy 46.087477 -67.427525)
			(xy 46.1074 -67.375434) (xy 46.134696 -67.326799) (xy 46.168782 -67.282656) (xy 46.208931 -67.243947)
			(xy 46.254289 -67.211496) (xy 46.303889 -67.185995) (xy 46.356673 -67.167988) (xy 46.411516 -67.157858)
			(xy 46.46725 -67.155821) (xy 46.522687 -67.161921) (xy 46.576644 -67.176027) (xy 46.627973 -67.197839)
			(xy 46.675579 -67.226893) (xy 46.718447 -67.262568) (xy 46.755664 -67.304105) (xy 46.786437 -67.350618)
			(xy 46.810109 -67.401115) (xy 46.826177 -67.454522) (xy 46.834297 -67.509698) (xy 46.834806 -67.537584)
			(xy 46.834297 -67.56547) (xy 46.830252 -67.592956) (xy 47.345344 -67.592956) (xy 47.349415 -67.537334)
			(xy 47.361541 -67.482897) (xy 47.381464 -67.430806) (xy 47.40876 -67.382171) (xy 47.442846 -67.338028)
			(xy 47.482995 -67.299319) (xy 47.528353 -67.266868) (xy 47.577953 -67.241367) (xy 47.630737 -67.22336)
			(xy 47.68558 -67.21323) (xy 47.741314 -67.211193) (xy 47.796751 -67.217293) (xy 47.850708 -67.231399)
			(xy 47.902037 -67.253211) (xy 47.949643 -67.282265) (xy 47.992511 -67.31794) (xy 48.029728 -67.359477)
			(xy 48.060501 -67.40599) (xy 48.084173 -67.456487) (xy 48.09367 -67.488054) (xy 70.77913 -67.488054)
			(xy 70.783201 -67.432432) (xy 70.795327 -67.377995) (xy 70.81525 -67.325904) (xy 70.842546 -67.277269)
			(xy 70.876632 -67.233126) (xy 70.916781 -67.194417) (xy 70.962139 -67.161966) (xy 71.011739 -67.136465)
			(xy 71.064523 -67.118458) (xy 71.119366 -67.108328) (xy 71.1751 -67.106291) (xy 71.230537 -67.112391)
			(xy 71.284494 -67.126497) (xy 71.290264 -67.128949) (xy 92.366598 -67.128949) (xy 92.366598 -67.074451)
			(xy 92.374354 -67.020506) (xy 92.389708 -66.968215) (xy 92.412347 -66.918641) (xy 92.441811 -66.872794)
			(xy 92.4775 -66.831606) (xy 92.518687 -66.795916) (xy 92.564534 -66.766451) (xy 92.614108 -66.743811)
			(xy 92.666399 -66.728456) (xy 92.720343 -66.720699) (xy 92.747592 -66.720212) (xy 92.774962 -66.72068)
			(xy 92.829141 -66.728497) (xy 92.881645 -66.743985) (xy 92.931391 -66.766827) (xy 92.977358 -66.796551)
			(xy 92.99829 -66.814192) (xy 92.998544 -66.814446) (xy 93.005638 -66.820021) (xy 93.022549 -66.826273)
			(xy 93.031564 -66.826638) (xy 93.09862 -66.826638) (xy 93.107637 -66.826282) (xy 93.124553 -66.820033)
			(xy 93.13164 -66.814446) (xy 93.132148 -66.813938) (xy 93.153087 -66.796362) (xy 93.19902 -66.76672)
			(xy 93.248714 -66.74394) (xy 93.301152 -66.728488) (xy 93.355259 -66.720682) (xy 93.382592 -66.720212)
			(xy 93.409847 -66.720634) (xy 93.463801 -66.728391) (xy 93.516103 -66.743747) (xy 93.565687 -66.76639)
			(xy 93.611543 -66.79586) (xy 93.652739 -66.831555) (xy 93.688436 -66.87275) (xy 93.717906 -66.918606)
			(xy 93.74055 -66.96819) (xy 93.755907 -67.020491) (xy 93.763665 -67.074445) (xy 93.763665 -67.128955)
			(xy 93.755907 -67.182909) (xy 93.74055 -67.23521) (xy 93.717906 -67.284794) (xy 93.688436 -67.33065)
			(xy 93.652739 -67.371845) (xy 93.611543 -67.40754) (xy 93.565687 -67.43701) (xy 93.516103 -67.459653)
			(xy 93.463801 -67.475009) (xy 93.409847 -67.482766) (xy 93.382592 -67.483228) (xy 93.355221 -67.482784)
			(xy 93.30104 -67.474964) (xy 93.248536 -67.45947) (xy 93.198789 -67.436623) (xy 93.152824 -67.406892)
			(xy 93.131894 -67.389248) (xy 93.13164 -67.388994) (xy 93.124547 -67.383417) (xy 93.107635 -67.377165)
			(xy 93.09862 -67.376802) (xy 93.031564 -67.376802) (xy 93.022545 -67.377142) (xy 93.005629 -67.383401)
			(xy 92.998544 -67.388994) (xy 92.998036 -67.389502) (xy 92.977108 -67.407091) (xy 92.931171 -67.43673)
			(xy 92.881474 -67.459507) (xy 92.829034 -67.474956) (xy 92.774926 -67.482759) (xy 92.747592 -67.483228)
			(xy 92.720343 -67.482701) (xy 92.666399 -67.474944) (xy 92.614108 -67.459589) (xy 92.564534 -67.436949)
			(xy 92.518687 -67.407484) (xy 92.4775 -67.371794) (xy 92.441811 -67.330606) (xy 92.412347 -67.284759)
			(xy 92.389708 -67.235185) (xy 92.374354 -67.182894) (xy 92.366598 -67.128949) (xy 71.290264 -67.128949)
			(xy 71.335823 -67.148309) (xy 71.383429 -67.177363) (xy 71.426297 -67.213038) (xy 71.463514 -67.254575)
			(xy 71.494287 -67.301088) (xy 71.517959 -67.351585) (xy 71.534027 -67.404992) (xy 71.542147 -67.460168)
			(xy 71.542656 -67.488054) (xy 71.542147 -67.51594) (xy 71.538962 -67.537584) (xy 72.071228 -67.537584)
			(xy 72.075299 -67.481962) (xy 72.087425 -67.427525) (xy 72.107348 -67.375434) (xy 72.134644 -67.326799)
			(xy 72.16873 -67.282656) (xy 72.208879 -67.243947) (xy 72.254237 -67.211496) (xy 72.303837 -67.185995)
			(xy 72.356621 -67.167988) (xy 72.411464 -67.157858) (xy 72.467198 -67.155821) (xy 72.522635 -67.161921)
			(xy 72.576592 -67.176027) (xy 72.627921 -67.197839) (xy 72.675527 -67.226893) (xy 72.718395 -67.262568)
			(xy 72.755612 -67.304105) (xy 72.786385 -67.350618) (xy 72.810057 -67.401115) (xy 72.826125 -67.454522)
			(xy 72.834245 -67.509698) (xy 72.834754 -67.537584) (xy 72.834245 -67.56547) (xy 72.8302 -67.592956)
			(xy 73.345292 -67.592956) (xy 73.349363 -67.537334) (xy 73.361489 -67.482897) (xy 73.381412 -67.430806)
			(xy 73.408708 -67.382171) (xy 73.442794 -67.338028) (xy 73.482943 -67.299319) (xy 73.528301 -67.266868)
			(xy 73.577901 -67.241367) (xy 73.630685 -67.22336) (xy 73.685528 -67.21323) (xy 73.741262 -67.211193)
			(xy 73.796699 -67.217293) (xy 73.850656 -67.231399) (xy 73.901985 -67.253211) (xy 73.949591 -67.282265)
			(xy 73.992459 -67.31794) (xy 74.029676 -67.359477) (xy 74.060449 -67.40599) (xy 74.084121 -67.456487)
			(xy 74.093618 -67.488054) (xy 96.779078 -67.488054) (xy 96.783149 -67.432432) (xy 96.795275 -67.377995)
			(xy 96.815198 -67.325904) (xy 96.842494 -67.277269) (xy 96.87658 -67.233126) (xy 96.916729 -67.194417)
			(xy 96.962087 -67.161966) (xy 97.011687 -67.136465) (xy 97.064471 -67.118458) (xy 97.119314 -67.108328)
			(xy 97.175048 -67.106291) (xy 97.230485 -67.112391) (xy 97.284442 -67.126497) (xy 97.290224 -67.128954)
			(xy 130.466775 -67.128954) (xy 130.466775 -67.074446) (xy 130.474533 -67.020494) (xy 130.489891 -66.968196)
			(xy 130.512535 -66.918615) (xy 130.542006 -66.872762) (xy 130.577703 -66.83157) (xy 130.618899 -66.795879)
			(xy 130.664755 -66.766413) (xy 130.714339 -66.743775) (xy 130.766639 -66.728423) (xy 130.820592 -66.720672)
			(xy 130.847846 -66.720212) (xy 130.875215 -66.720707) (xy 130.929393 -66.728517) (xy 130.981896 -66.743999)
			(xy 131.031643 -66.766835) (xy 131.077611 -66.796553) (xy 131.098544 -66.814192) (xy 131.098798 -66.814446)
			(xy 131.105877 -66.820043) (xy 131.1228 -66.826282) (xy 131.131818 -66.826638) (xy 131.198874 -66.826638)
			(xy 131.207889 -66.82626) (xy 131.224805 -66.820026) (xy 131.231894 -66.814446) (xy 131.232402 -66.813938)
			(xy 131.253321 -66.796337) (xy 131.299259 -66.766699) (xy 131.348959 -66.743923) (xy 131.401401 -66.728478)
			(xy 131.455511 -66.720678) (xy 131.482846 -66.720212) (xy 131.510097 -66.720661) (xy 131.564042 -66.728423)
			(xy 131.616334 -66.743783) (xy 131.665908 -66.766428) (xy 131.711755 -66.795897) (xy 131.752942 -66.831591)
			(xy 131.78863 -66.872782) (xy 131.818094 -66.918632) (xy 131.840733 -66.968209) (xy 131.856087 -67.020503)
			(xy 131.863842 -67.074449) (xy 131.863842 -67.128951) (xy 131.856087 -67.182897) (xy 131.840733 -67.235191)
			(xy 131.818094 -67.284768) (xy 131.78863 -67.330618) (xy 131.752942 -67.371809) (xy 131.711755 -67.407503)
			(xy 131.665908 -67.436972) (xy 131.616334 -67.459617) (xy 131.564042 -67.474977) (xy 131.510097 -67.482739)
			(xy 131.482846 -67.483228) (xy 131.455476 -67.482753) (xy 131.401297 -67.47494) (xy 131.348793 -67.459454)
			(xy 131.299046 -67.436614) (xy 131.253079 -67.406889) (xy 131.232148 -67.389248) (xy 131.231894 -67.388994)
			(xy 131.224814 -67.383398) (xy 131.207892 -67.377157) (xy 131.198874 -67.376802) (xy 131.131818 -67.376802)
			(xy 131.122802 -67.377167) (xy 131.105885 -67.383409) (xy 131.098798 -67.388994) (xy 131.09829 -67.389502)
			(xy 131.077379 -67.407113) (xy 131.031438 -67.436748) (xy 130.981736 -67.459521) (xy 130.929293 -67.474965)
			(xy 130.875181 -67.482762) (xy 130.847846 -67.483228) (xy 130.820592 -67.482728) (xy 130.766639 -67.474977)
			(xy 130.714339 -67.459625) (xy 130.664755 -67.436987) (xy 130.618899 -67.407521) (xy 130.577703 -67.37183)
			(xy 130.542006 -67.330638) (xy 130.512535 -67.284785) (xy 130.489891 -67.235204) (xy 130.474533 -67.182906)
			(xy 130.466775 -67.128954) (xy 97.290224 -67.128954) (xy 97.335771 -67.148309) (xy 97.383377 -67.177363)
			(xy 97.426245 -67.213038) (xy 97.463462 -67.254575) (xy 97.494235 -67.301088) (xy 97.517907 -67.351585)
			(xy 97.533975 -67.404992) (xy 97.542095 -67.460168) (xy 97.542604 -67.488054) (xy 97.542095 -67.51594)
			(xy 97.53891 -67.537584) (xy 98.071176 -67.537584) (xy 98.075247 -67.481962) (xy 98.087373 -67.427525)
			(xy 98.107296 -67.375434) (xy 98.134592 -67.326799) (xy 98.168678 -67.282656) (xy 98.208827 -67.243947)
			(xy 98.254185 -67.211496) (xy 98.303785 -67.185995) (xy 98.356569 -67.167988) (xy 98.411412 -67.157858)
			(xy 98.467146 -67.155821) (xy 98.522583 -67.161921) (xy 98.57654 -67.176027) (xy 98.627869 -67.197839)
			(xy 98.675475 -67.226893) (xy 98.718343 -67.262568) (xy 98.75556 -67.304105) (xy 98.786333 -67.350618)
			(xy 98.810005 -67.401115) (xy 98.826073 -67.454522) (xy 98.834193 -67.509698) (xy 98.834702 -67.537584)
			(xy 98.834193 -67.56547) (xy 98.830148 -67.592956) (xy 99.34524 -67.592956) (xy 99.349311 -67.537334)
			(xy 99.361437 -67.482897) (xy 99.38136 -67.430806) (xy 99.408656 -67.382171) (xy 99.442742 -67.338028)
			(xy 99.482891 -67.299319) (xy 99.528249 -67.266868) (xy 99.577849 -67.241367) (xy 99.630633 -67.22336)
			(xy 99.685476 -67.21323) (xy 99.74121 -67.211193) (xy 99.796647 -67.217293) (xy 99.850604 -67.231399)
			(xy 99.901933 -67.253211) (xy 99.949539 -67.282265) (xy 99.992407 -67.31794) (xy 100.029624 -67.359477)
			(xy 100.060397 -67.40599) (xy 100.084069 -67.456487) (xy 100.100137 -67.509894) (xy 100.108257 -67.56507)
			(xy 100.108766 -67.592956) (xy 100.108257 -67.620842) (xy 100.100137 -67.676018) (xy 100.084069 -67.729425)
			(xy 100.060397 -67.779922) (xy 100.029624 -67.826435) (xy 99.992407 -67.867972) (xy 99.949539 -67.903647)
			(xy 99.901933 -67.932701) (xy 99.850604 -67.954513) (xy 99.796647 -67.968619) (xy 99.74121 -67.974719)
			(xy 99.685476 -67.972682) (xy 99.630633 -67.962552) (xy 99.577849 -67.944545) (xy 99.528249 -67.919044)
			(xy 99.482891 -67.886593) (xy 99.442742 -67.847884) (xy 99.408656 -67.803741) (xy 99.38136 -67.755106)
			(xy 99.361437 -67.703015) (xy 99.349311 -67.648578) (xy 99.34524 -67.592956) (xy 98.830148 -67.592956)
			(xy 98.826073 -67.620646) (xy 98.810005 -67.674053) (xy 98.786333 -67.72455) (xy 98.75556 -67.771063)
			(xy 98.718343 -67.8126) (xy 98.675475 -67.848275) (xy 98.627869 -67.877329) (xy 98.57654 -67.899141)
			(xy 98.522583 -67.913247) (xy 98.467146 -67.919347) (xy 98.411412 -67.91731) (xy 98.356569 -67.90718)
			(xy 98.303785 -67.889173) (xy 98.254185 -67.863672) (xy 98.208827 -67.831221) (xy 98.168678 -67.792512)
			(xy 98.134592 -67.748369) (xy 98.107296 -67.699734) (xy 98.087373 -67.647643) (xy 98.075247 -67.593206)
			(xy 98.071176 -67.537584) (xy 97.53891 -67.537584) (xy 97.533975 -67.571116) (xy 97.517907 -67.624523)
			(xy 97.494235 -67.67502) (xy 97.463462 -67.721533) (xy 97.426245 -67.76307) (xy 97.383377 -67.798745)
			(xy 97.335771 -67.827799) (xy 97.284442 -67.849611) (xy 97.230485 -67.863717) (xy 97.175048 -67.869817)
			(xy 97.119314 -67.86778) (xy 97.064471 -67.85765) (xy 97.011687 -67.839643) (xy 96.962087 -67.814142)
			(xy 96.916729 -67.781691) (xy 96.87658 -67.742982) (xy 96.842494 -67.698839) (xy 96.815198 -67.650204)
			(xy 96.795275 -67.598113) (xy 96.783149 -67.543676) (xy 96.779078 -67.488054) (xy 74.093618 -67.488054)
			(xy 74.100189 -67.509894) (xy 74.108309 -67.56507) (xy 74.108818 -67.592956) (xy 74.108309 -67.620842)
			(xy 74.100189 -67.676018) (xy 74.084121 -67.729425) (xy 74.060449 -67.779922) (xy 74.029676 -67.826435)
			(xy 73.992459 -67.867972) (xy 73.949591 -67.903647) (xy 73.901985 -67.932701) (xy 73.850656 -67.954513)
			(xy 73.796699 -67.968619) (xy 73.741262 -67.974719) (xy 73.685528 -67.972682) (xy 73.630685 -67.962552)
			(xy 73.577901 -67.944545) (xy 73.528301 -67.919044) (xy 73.482943 -67.886593) (xy 73.442794 -67.847884)
			(xy 73.408708 -67.803741) (xy 73.381412 -67.755106) (xy 73.361489 -67.703015) (xy 73.349363 -67.648578)
			(xy 73.345292 -67.592956) (xy 72.8302 -67.592956) (xy 72.826125 -67.620646) (xy 72.810057 -67.674053)
			(xy 72.786385 -67.72455) (xy 72.755612 -67.771063) (xy 72.718395 -67.8126) (xy 72.675527 -67.848275)
			(xy 72.627921 -67.877329) (xy 72.576592 -67.899141) (xy 72.522635 -67.913247) (xy 72.467198 -67.919347)
			(xy 72.411464 -67.91731) (xy 72.356621 -67.90718) (xy 72.303837 -67.889173) (xy 72.254237 -67.863672)
			(xy 72.208879 -67.831221) (xy 72.16873 -67.792512) (xy 72.134644 -67.748369) (xy 72.107348 -67.699734)
			(xy 72.087425 -67.647643) (xy 72.075299 -67.593206) (xy 72.071228 -67.537584) (xy 71.538962 -67.537584)
			(xy 71.534027 -67.571116) (xy 71.517959 -67.624523) (xy 71.494287 -67.67502) (xy 71.463514 -67.721533)
			(xy 71.426297 -67.76307) (xy 71.383429 -67.798745) (xy 71.335823 -67.827799) (xy 71.284494 -67.849611)
			(xy 71.230537 -67.863717) (xy 71.1751 -67.869817) (xy 71.119366 -67.86778) (xy 71.064523 -67.85765)
			(xy 71.011739 -67.839643) (xy 70.962139 -67.814142) (xy 70.916781 -67.781691) (xy 70.876632 -67.742982)
			(xy 70.842546 -67.698839) (xy 70.81525 -67.650204) (xy 70.795327 -67.598113) (xy 70.783201 -67.543676)
			(xy 70.77913 -67.488054) (xy 48.09367 -67.488054) (xy 48.100241 -67.509894) (xy 48.108361 -67.56507)
			(xy 48.10887 -67.592956) (xy 48.108361 -67.620842) (xy 48.100241 -67.676018) (xy 48.084173 -67.729425)
			(xy 48.060501 -67.779922) (xy 48.029728 -67.826435) (xy 47.992511 -67.867972) (xy 47.949643 -67.903647)
			(xy 47.902037 -67.932701) (xy 47.850708 -67.954513) (xy 47.796751 -67.968619) (xy 47.741314 -67.974719)
			(xy 47.68558 -67.972682) (xy 47.630737 -67.962552) (xy 47.577953 -67.944545) (xy 47.528353 -67.919044)
			(xy 47.482995 -67.886593) (xy 47.442846 -67.847884) (xy 47.40876 -67.803741) (xy 47.381464 -67.755106)
			(xy 47.361541 -67.703015) (xy 47.349415 -67.648578) (xy 47.345344 -67.592956) (xy 46.830252 -67.592956)
			(xy 46.826177 -67.620646) (xy 46.810109 -67.674053) (xy 46.786437 -67.72455) (xy 46.755664 -67.771063)
			(xy 46.718447 -67.8126) (xy 46.675579 -67.848275) (xy 46.627973 -67.877329) (xy 46.576644 -67.899141)
			(xy 46.522687 -67.913247) (xy 46.46725 -67.919347) (xy 46.411516 -67.91731) (xy 46.356673 -67.90718)
			(xy 46.303889 -67.889173) (xy 46.254289 -67.863672) (xy 46.208931 -67.831221) (xy 46.168782 -67.792512)
			(xy 46.134696 -67.748369) (xy 46.1074 -67.699734) (xy 46.087477 -67.647643) (xy 46.075351 -67.593206)
			(xy 46.07128 -67.537584) (xy 45.539014 -67.537584) (xy 45.534079 -67.571116) (xy 45.518011 -67.624523)
			(xy 45.494339 -67.67502) (xy 45.463566 -67.721533) (xy 45.426349 -67.76307) (xy 45.383481 -67.798745)
			(xy 45.335875 -67.827799) (xy 45.284546 -67.849611) (xy 45.230589 -67.863717) (xy 45.175152 -67.869817)
			(xy 45.119418 -67.86778) (xy 45.064575 -67.85765) (xy 45.011791 -67.839643) (xy 44.962191 -67.814142)
			(xy 44.916833 -67.781691) (xy 44.876684 -67.742982) (xy 44.842598 -67.698839) (xy 44.815302 -67.650204)
			(xy 44.795379 -67.598113) (xy 44.783253 -67.543676) (xy 44.779182 -67.488054) (xy 22.093722 -67.488054)
			(xy 22.100293 -67.509894) (xy 22.108413 -67.56507) (xy 22.108922 -67.592956) (xy 22.108413 -67.620842)
			(xy 22.100293 -67.676018) (xy 22.084225 -67.729425) (xy 22.060553 -67.779922) (xy 22.02978 -67.826435)
			(xy 21.992563 -67.867972) (xy 21.949695 -67.903647) (xy 21.902089 -67.932701) (xy 21.85076 -67.954513)
			(xy 21.796803 -67.968619) (xy 21.741366 -67.974719) (xy 21.685632 -67.972682) (xy 21.630789 -67.962552)
			(xy 21.578005 -67.944545) (xy 21.528405 -67.919044) (xy 21.483047 -67.886593) (xy 21.442898 -67.847884)
			(xy 21.408812 -67.803741) (xy 21.381516 -67.755106) (xy 21.361593 -67.703015) (xy 21.349467 -67.648578)
			(xy 21.345396 -67.592956) (xy 20.831235 -67.592956) (xy 20.819638 -67.645898) (xy 20.800341 -67.697258)
			(xy 20.773885 -67.745323) (xy 20.740816 -67.789102) (xy 20.701815 -67.827692) (xy 20.657689 -67.860296)
			(xy 20.609346 -67.886242) (xy 20.557785 -67.904994) (xy 20.504069 -67.916166) (xy 20.476718 -67.91833)
			(xy 20.47621 -67.91833) (xy 20.465542 -67.919092) (xy 20.448524 -67.927474) (xy 20.442174 -67.934332)
			(xy 20.394422 -67.984624) (xy 20.388042 -67.991946) (xy 20.380862 -68.009973) (xy 20.380452 -68.019676)
			(xy 20.380452 -68.586604) (xy 42.625264 -68.586604) (xy 42.625752 -68.559271) (xy 42.633554 -68.505164)
			(xy 42.648999 -68.452725) (xy 42.67177 -68.403027) (xy 42.701401 -68.357088) (xy 42.71899 -68.33616)
			(xy 42.719244 -68.335906) (xy 42.719498 -68.335652) (xy 42.725069 -68.328555) (xy 42.731325 -68.311646)
			(xy 42.73169 -68.302632) (xy 42.73169 -68.235576) (xy 42.731347 -68.226558) (xy 42.72509 -68.209641)
			(xy 42.719498 -68.202556) (xy 42.719244 -68.202302) (xy 42.71899 -68.202048) (xy 42.701405 -68.181116)
			(xy 42.671766 -68.135181) (xy 42.648988 -68.085484) (xy 42.633539 -68.033045) (xy 42.625734 -67.978938)
			(xy 42.625264 -67.951604) (xy 42.625781 -67.924354) (xy 42.633537 -67.870409) (xy 42.64889 -67.818117)
			(xy 42.671529 -67.768541) (xy 42.700992 -67.722692) (xy 42.73668 -67.681503) (xy 42.777866 -67.645811)
			(xy 42.823713 -67.616344) (xy 42.873287 -67.593701) (xy 42.925578 -67.578343) (xy 42.979522 -67.570584)
			(xy 43.006772 -67.570096) (xy 43.007026 -67.570096) (xy 43.033321 -67.570539) (xy 43.085411 -67.577787)
			(xy 43.136012 -67.592117) (xy 43.184168 -67.613255) (xy 43.228968 -67.640803) (xy 43.269562 -67.674238)
			(xy 43.287696 -67.693286) (xy 43.295272 -67.700722) (xy 43.314687 -67.709251) (xy 43.325288 -67.709796)
			(xy 43.399456 -67.709796) (xy 43.410091 -67.70941) (xy 43.429555 -67.700844) (xy 43.437048 -67.693286)
			(xy 43.455141 -67.674195) (xy 43.495731 -67.640743) (xy 43.540535 -67.613188) (xy 43.588702 -67.592055)
			(xy 43.639317 -67.577745) (xy 43.691418 -67.57053) (xy 43.717718 -67.570096) (xy 43.717972 -67.570096)
			(xy 43.745342 -67.570579) (xy 43.79952 -67.578393) (xy 43.852023 -67.593878) (xy 43.90177 -67.616716)
			(xy 43.947738 -67.646437) (xy 43.96867 -67.664076) (xy 43.968924 -67.66433) (xy 43.975997 -67.669936)
			(xy 43.992924 -67.67617) (xy 44.001944 -67.676522) (xy 44.069 -67.676522) (xy 44.078016 -67.67616)
			(xy 44.094933 -67.669915) (xy 44.10202 -67.66433) (xy 44.102528 -67.663822) (xy 44.123473 -67.646253)
			(xy 44.169404 -67.616611) (xy 44.219097 -67.593829) (xy 44.271534 -67.578376) (xy 44.325639 -67.570567)
			(xy 44.352972 -67.570096) (xy 44.380224 -67.570581) (xy 44.434175 -67.578335) (xy 44.486472 -67.593687)
			(xy 44.536053 -67.616327) (xy 44.581906 -67.645792) (xy 44.623099 -67.681484) (xy 44.658793 -67.722675)
			(xy 44.688262 -67.768526) (xy 44.710904 -67.818105) (xy 44.72626 -67.870402) (xy 44.734017 -67.924352)
			(xy 44.73448 -67.951604) (xy 44.733986 -67.978937) (xy 44.726184 -68.033043) (xy 44.71074 -68.085482)
			(xy 44.687971 -68.13518) (xy 44.658342 -68.18112) (xy 44.640754 -68.202048) (xy 44.6405 -68.202302)
			(xy 44.640246 -68.202556) (xy 44.634665 -68.209646) (xy 44.628416 -68.22656) (xy 44.628054 -68.235576)
			(xy 44.628054 -68.302632) (xy 44.628384 -68.311652) (xy 44.634649 -68.328569) (xy 44.640246 -68.335652)
			(xy 44.6405 -68.335906) (xy 44.640754 -68.33616) (xy 44.658334 -68.357096) (xy 44.687976 -68.403029)
			(xy 44.710755 -68.452725) (xy 44.726206 -68.505163) (xy 44.734011 -68.55927) (xy 44.73448 -68.586604)
			(xy 68.625212 -68.586604) (xy 68.625712 -68.559271) (xy 68.633513 -68.505166) (xy 68.648956 -68.452727)
			(xy 68.671724 -68.403029) (xy 68.701351 -68.357088) (xy 68.718938 -68.33616) (xy 68.719192 -68.335906)
			(xy 68.719446 -68.335652) (xy 68.725023 -68.328559) (xy 68.731274 -68.311647) (xy 68.731638 -68.302632)
			(xy 68.731638 -68.235576) (xy 68.731284 -68.226559) (xy 68.725034 -68.209642) (xy 68.719446 -68.202556)
			(xy 68.719192 -68.202302) (xy 68.718938 -68.202048) (xy 68.70136 -68.18111) (xy 68.671719 -68.135177)
			(xy 68.648939 -68.085482) (xy 68.633488 -68.033044) (xy 68.625682 -67.978938) (xy 68.625212 -67.951604)
			(xy 68.625659 -67.92435) (xy 68.633416 -67.870398) (xy 68.648773 -67.818098) (xy 68.671416 -67.768517)
			(xy 68.700886 -67.722663) (xy 68.736581 -67.68147) (xy 68.777776 -67.645776) (xy 68.823631 -67.616308)
			(xy 68.873213 -67.593667) (xy 68.925513 -67.578313) (xy 68.979466 -67.570558) (xy 69.00672 -67.570096)
			(xy 69.006974 -67.570096) (xy 69.033268 -67.570573) (xy 69.085356 -67.577815) (xy 69.135957 -67.592137)
			(xy 69.184113 -67.613269) (xy 69.228913 -67.640811) (xy 69.269509 -67.674241) (xy 69.287644 -67.693286)
			(xy 69.295202 -67.700743) (xy 69.31463 -67.70926) (xy 69.325236 -67.709796) (xy 69.399404 -67.709796)
			(xy 69.410035 -67.709382) (xy 69.4295 -67.700836) (xy 69.436996 -67.693286) (xy 69.455115 -67.674221)
			(xy 69.495699 -67.640766) (xy 69.540498 -67.613208) (xy 69.58866 -67.59207) (xy 69.63927 -67.577755)
			(xy 69.691368 -67.570533) (xy 69.717666 -67.570096) (xy 69.71792 -67.570096) (xy 69.745291 -67.570551)
			(xy 69.79947 -67.578372) (xy 69.851973 -67.593864) (xy 69.90172 -67.616708) (xy 69.947686 -67.646434)
			(xy 69.968618 -67.664076) (xy 69.968872 -67.66433) (xy 69.97596 -67.669914) (xy 69.992876 -67.676161)
			(xy 70.001892 -67.676522) (xy 70.068948 -67.676522) (xy 70.077962 -67.676135) (xy 70.094879 -67.669908)
			(xy 70.101968 -67.66433) (xy 70.102476 -67.663822) (xy 70.123403 -67.646231) (xy 70.169339 -67.616591)
			(xy 70.219037 -67.593815) (xy 70.271477 -67.578367) (xy 70.325586 -67.570564) (xy 70.35292 -67.570096)
			(xy 70.380172 -67.570559) (xy 70.434121 -67.578319) (xy 70.486416 -67.593676) (xy 70.535994 -67.61632)
			(xy 70.581844 -67.645789) (xy 70.623034 -67.681483) (xy 70.658725 -67.722675) (xy 70.688191 -67.768527)
			(xy 70.710832 -67.818106) (xy 70.726187 -67.870403) (xy 70.733943 -67.924352) (xy 70.734428 -67.951604)
			(xy 70.733946 -67.978937) (xy 70.726143 -68.033045) (xy 70.710697 -68.085484) (xy 70.687924 -68.135182)
			(xy 70.658291 -68.181121) (xy 70.640702 -68.202048) (xy 70.640448 -68.202302) (xy 70.640194 -68.202556)
			(xy 70.634619 -68.209651) (xy 70.628366 -68.226561) (xy 70.628002 -68.235576) (xy 70.628002 -68.302632)
			(xy 70.628343 -68.31165) (xy 70.634602 -68.328567) (xy 70.640194 -68.335652) (xy 70.640448 -68.335906)
			(xy 70.640702 -68.33616) (xy 70.658289 -68.35709) (xy 70.687928 -68.403026) (xy 70.710706 -68.452722)
			(xy 70.726155 -68.505162) (xy 70.733959 -68.55927) (xy 70.734428 -68.586604) (xy 94.62516 -68.586604)
			(xy 94.625649 -68.559271) (xy 94.633451 -68.505164) (xy 94.648895 -68.452725) (xy 94.671666 -68.403027)
			(xy 94.701297 -68.357087) (xy 94.718886 -68.33616) (xy 94.71914 -68.335906) (xy 94.719394 -68.335652)
			(xy 94.724964 -68.328554) (xy 94.731221 -68.311646) (xy 94.731586 -68.302632) (xy 94.731586 -68.235576)
			(xy 94.731243 -68.226558) (xy 94.724986 -68.209641) (xy 94.719394 -68.202556) (xy 94.71914 -68.202302)
			(xy 94.718886 -68.202048) (xy 94.7013 -68.181117) (xy 94.671662 -68.135181) (xy 94.648884 -68.085485)
			(xy 94.633435 -68.033045) (xy 94.62563 -67.978938) (xy 94.62516 -67.951604) (xy 94.625681 -67.924354)
			(xy 94.633437 -67.87041) (xy 94.64879 -67.818117) (xy 94.671428 -67.768542) (xy 94.700891 -67.722693)
			(xy 94.736578 -67.681504) (xy 94.777765 -67.645812) (xy 94.823611 -67.616345) (xy 94.873184 -67.593702)
			(xy 94.925474 -67.578344) (xy 94.979418 -67.570584) (xy 95.006668 -67.570096) (xy 95.006922 -67.570096)
			(xy 95.033217 -67.570541) (xy 95.085307 -67.57779) (xy 95.135908 -67.592118) (xy 95.184064 -67.613256)
			(xy 95.228863 -67.640804) (xy 95.269458 -67.674239) (xy 95.287592 -67.693286) (xy 95.295169 -67.70072)
			(xy 95.314583 -67.70925) (xy 95.325184 -67.709796) (xy 95.399352 -67.709796) (xy 95.409986 -67.709408)
			(xy 95.429451 -67.700844) (xy 95.436944 -67.693286) (xy 95.455039 -67.674197) (xy 95.495629 -67.640744)
			(xy 95.540432 -67.61319) (xy 95.588599 -67.592056) (xy 95.639213 -67.577746) (xy 95.691315 -67.57053)
			(xy 95.717614 -67.570096) (xy 95.717868 -67.570096) (xy 95.745238 -67.570582) (xy 95.799416 -67.578395)
			(xy 95.851919 -67.59388) (xy 95.901666 -67.616717) (xy 95.947634 -67.646437) (xy 95.968566 -67.664076)
			(xy 95.96882 -67.66433) (xy 95.975894 -67.669934) (xy 95.992821 -67.676169) (xy 96.00184 -67.676522)
			(xy 96.068896 -67.676522) (xy 96.077912 -67.676158) (xy 96.094829 -67.669915) (xy 96.101916 -67.66433)
			(xy 96.102424 -67.663822) (xy 96.12337 -67.646255) (xy 96.169301 -67.616612) (xy 96.218994 -67.593831)
			(xy 96.27143 -67.578377) (xy 96.325535 -67.570568) (xy 96.352868 -67.570096) (xy 96.38012 -67.570585)
			(xy 96.43407 -67.578338) (xy 96.486368 -67.59369) (xy 96.535948 -67.616329) (xy 96.581802 -67.645794)
			(xy 96.622995 -67.681485) (xy 96.658689 -67.722676) (xy 96.688158 -67.768527) (xy 96.7108 -67.818106)
			(xy 96.726156 -67.870402) (xy 96.733913 -67.924352) (xy 96.734376 -67.951604) (xy 96.733883 -67.978937)
			(xy 96.726081 -68.033043) (xy 96.710637 -68.085482) (xy 96.687867 -68.13518) (xy 96.658238 -68.18112)
			(xy 96.64065 -68.202048) (xy 96.640396 -68.202302) (xy 96.640142 -68.202556) (xy 96.634561 -68.209646)
			(xy 96.628312 -68.22656) (xy 96.62795 -68.235576) (xy 96.62795 -68.302632) (xy 96.628281 -68.311652)
			(xy 96.634545 -68.328569) (xy 96.640142 -68.335652) (xy 96.640396 -68.335906) (xy 96.64065 -68.33616)
			(xy 96.658245 -68.357084) (xy 96.687881 -68.403022) (xy 96.710656 -68.45272) (xy 96.726104 -68.505161)
			(xy 96.733907 -68.55927) (xy 96.734376 -68.586604) (xy 96.733948 -68.613858) (xy 96.72619 -68.667812)
			(xy 96.710832 -68.720113) (xy 96.688186 -68.769695) (xy 96.658715 -68.81555) (xy 96.623018 -68.856743)
			(xy 96.581821 -68.892437) (xy 96.535963 -68.921904) (xy 96.486379 -68.944544) (xy 96.434077 -68.959898)
			(xy 96.380122 -68.967651) (xy 96.352868 -68.968112) (xy 96.325497 -68.967662) (xy 96.271318 -68.95984)
			(xy 96.218814 -68.944347) (xy 96.169068 -68.921502) (xy 96.123101 -68.891774) (xy 96.10217 -68.874132)
			(xy 96.101916 -68.873878) (xy 96.094831 -68.86829) (xy 96.077913 -68.862045) (xy 96.068896 -68.861686)
			(xy 96.00184 -68.861686) (xy 95.992825 -68.862065) (xy 95.975908 -68.868298) (xy 95.96882 -68.873878)
			(xy 95.968312 -68.874386) (xy 95.947391 -68.891984) (xy 95.901453 -68.921622) (xy 95.851754 -68.944398)
			(xy 95.799312 -68.959844) (xy 95.745203 -68.967645) (xy 95.717868 -68.968112) (xy 95.717614 -68.968112)
			(xy 95.69132 -68.96764) (xy 95.639232 -68.960397) (xy 95.588631 -68.946073) (xy 95.540475 -68.92494)
			(xy 95.495675 -68.897398) (xy 95.455079 -68.863967) (xy 95.436944 -68.844922) (xy 95.429389 -68.83746)
			(xy 95.409959 -68.828946) (xy 95.399352 -68.828412) (xy 95.325184 -68.828412) (xy 95.314551 -68.828818)
			(xy 95.295087 -68.837369) (xy 95.287592 -68.844922) (xy 95.269481 -68.863995) (xy 95.228894 -68.897449)
			(xy 95.184094 -68.925006) (xy 95.135931 -68.946142) (xy 95.085319 -68.960456) (xy 95.033221 -68.967676)
			(xy 95.006922 -68.968112) (xy 95.006668 -68.968112) (xy 94.979416 -68.967652) (xy 94.925468 -68.959891)
			(xy 94.873173 -68.944532) (xy 94.823596 -68.921888) (xy 94.777746 -68.892418) (xy 94.736556 -68.856724)
			(xy 94.700865 -68.815532) (xy 94.671399 -68.76968) (xy 94.648758 -68.720101) (xy 94.633403 -68.667805)
			(xy 94.625646 -68.613856) (xy 94.62516 -68.586604) (xy 70.734428 -68.586604) (xy 70.733926 -68.613854)
			(xy 70.726169 -68.667801) (xy 70.710815 -68.720094) (xy 70.688175 -68.76967) (xy 70.65871 -68.815519)
			(xy 70.62302 -68.856709) (xy 70.581832 -68.8924) (xy 70.535984 -68.921867) (xy 70.486409 -68.944509)
			(xy 70.434116 -68.959866) (xy 70.38017 -68.967625) (xy 70.35292 -68.968112) (xy 70.32555 -68.967631)
			(xy 70.271372 -68.959817) (xy 70.218869 -68.944331) (xy 70.169122 -68.921492) (xy 70.123154 -68.891771)
			(xy 70.102222 -68.874132) (xy 70.101968 -68.873878) (xy 70.094868 -68.868311) (xy 70.077961 -68.862053)
			(xy 70.068948 -68.861686) (xy 70.001892 -68.861686) (xy 69.992875 -68.862042) (xy 69.975958 -68.868291)
			(xy 69.968872 -68.873878) (xy 69.968364 -68.874386) (xy 69.947423 -68.89196) (xy 69.901491 -68.921601)
			(xy 69.851797 -68.944382) (xy 69.799359 -68.959834) (xy 69.745253 -68.967641) (xy 69.71792 -68.968112)
			(xy 69.717666 -68.968112) (xy 69.691371 -68.967672) (xy 69.639281 -68.960422) (xy 69.58868 -68.946092)
			(xy 69.540524 -68.924953) (xy 69.495725 -68.897405) (xy 69.45513 -68.86397) (xy 69.436996 -68.844922)
			(xy 69.429422 -68.837483) (xy 69.410006 -68.828956) (xy 69.399404 -68.828412) (xy 69.325236 -68.828412)
			(xy 69.3146 -68.828791) (xy 69.295136 -68.837361) (xy 69.287644 -68.844922) (xy 69.269507 -68.86397)
			(xy 69.228927 -68.897426) (xy 69.184132 -68.924986) (xy 69.135973 -68.946126) (xy 69.085366 -68.960446)
			(xy 69.033271 -68.967672) (xy 69.006974 -68.968112) (xy 69.00672 -68.968112) (xy 68.979468 -68.967626)
			(xy 68.925518 -68.959872) (xy 68.873221 -68.944519) (xy 68.823641 -68.921879) (xy 68.777788 -68.892413)
			(xy 68.736595 -68.856722) (xy 68.700901 -68.815531) (xy 68.671433 -68.76968) (xy 68.64879 -68.720102)
			(xy 68.633433 -68.667806) (xy 68.625676 -68.613856) (xy 68.625212 -68.586604) (xy 44.73448 -68.586604)
			(xy 44.734048 -68.613858) (xy 44.72629 -68.667812) (xy 44.710932 -68.720112) (xy 44.688287 -68.769694)
			(xy 44.658816 -68.815548) (xy 44.623119 -68.856742) (xy 44.581923 -68.892435) (xy 44.536066 -68.921902)
			(xy 44.486482 -68.944543) (xy 44.43418 -68.959897) (xy 44.380226 -68.967651) (xy 44.352972 -68.968112)
			(xy 44.325601 -68.967659) (xy 44.271422 -68.959838) (xy 44.218919 -68.944345) (xy 44.169172 -68.921501)
			(xy 44.123206 -68.891774) (xy 44.102274 -68.874132) (xy 44.10202 -68.873878) (xy 44.094934 -68.868291)
			(xy 44.078017 -68.862045) (xy 44.069 -68.861686) (xy 44.001944 -68.861686) (xy 43.99293 -68.862067)
			(xy 43.976013 -68.868298) (xy 43.968924 -68.873878) (xy 43.968416 -68.874386) (xy 43.947493 -68.891982)
			(xy 43.901556 -68.92162) (xy 43.851857 -68.944396) (xy 43.799416 -68.959843) (xy 43.745306 -68.967645)
			(xy 43.717972 -68.968112) (xy 43.717718 -68.968112) (xy 43.691424 -68.967637) (xy 43.639336 -68.960395)
			(xy 43.588735 -68.946072) (xy 43.540579 -68.924939) (xy 43.495779 -68.897397) (xy 43.455183 -68.863967)
			(xy 43.437048 -68.844922) (xy 43.429492 -68.837462) (xy 43.410062 -68.828947) (xy 43.399456 -68.828412)
			(xy 43.325288 -68.828412) (xy 43.314656 -68.82882) (xy 43.295191 -68.83737) (xy 43.287696 -68.844922)
			(xy 43.269583 -68.863993) (xy 43.228997 -68.897447) (xy 43.184197 -68.925004) (xy 43.136034 -68.94614)
			(xy 43.085423 -68.960455) (xy 43.033324 -68.967676) (xy 43.007026 -68.968112) (xy 43.006772 -68.968112)
			(xy 42.97952 -68.967648) (xy 42.925572 -68.959888) (xy 42.873277 -68.94453) (xy 42.8237 -68.921885)
			(xy 42.77785 -68.892417) (xy 42.73666 -68.856723) (xy 42.700969 -68.815531) (xy 42.671503 -68.769679)
			(xy 42.648862 -68.7201) (xy 42.633507 -68.667805) (xy 42.62575 -68.613856) (xy 42.625264 -68.586604)
			(xy 20.380452 -68.586604) (xy 20.380452 -68.658994) (xy 20.380924 -68.668866) (xy 20.388382 -68.687149)
			(xy 20.39493 -68.694554) (xy 20.395184 -68.694808) (xy 21.972016 -70.27164) (xy 21.972524 -70.272148)
			(xy 21.979904 -70.278735) (xy 21.998202 -70.286197) (xy 22.008084 -70.286626) (xy 112.997742 -70.286626)
		)
		(stroke
			(width 0)
			(type solid)
		)
		(fill yes)
		(layer "In15.Cu")
		(net "P12V_AUX")
	)
	(gr_poly
		(pts
			(xy 24.410162 -184.768236) (xy 24.420226 -184.7678) (xy 24.438808 -184.760062) (xy 24.44623 -184.75325)
			(xy 27.1399 -182.05958) (xy 27.146743 -182.05218) (xy 27.15447 -182.033582) (xy 27.154886 -182.023512)
			(xy 27.154886 -138.537442) (xy 27.155319 -138.527376) (xy 27.163047 -138.508786) (xy 27.169872 -138.501374)
			(xy 32.952182 -132.719064) (xy 32.959582 -132.712224) (xy 32.978181 -132.704509) (xy 32.98825 -132.704078)
			(xy 37.25926 -132.704078) (xy 37.269285 -132.703665) (xy 37.287812 -132.696001) (xy 37.301991 -132.681827)
			(xy 37.309661 -132.663303) (xy 37.31006 -132.653278) (xy 37.31006 -132.520436) (xy 37.309529 -132.509412)
			(xy 37.300326 -132.489379) (xy 37.29228 -132.481828) (xy 37.233606 -132.43179) (xy 37.224878 -132.425041)
			(xy 37.203687 -132.41898) (xy 37.192712 -132.420106) (xy 37.178075 -132.422254) (xy 37.148577 -132.424543)
			(xy 37.133784 -132.424678) (xy 37.106536 -132.424191) (xy 37.052594 -132.416433) (xy 37.000305 -132.401078)
			(xy 36.950734 -132.378437) (xy 36.904889 -132.348973) (xy 36.863704 -132.313284) (xy 36.828017 -132.272098)
			(xy 36.798555 -132.226252) (xy 36.775917 -132.17668) (xy 36.760564 -132.12439) (xy 36.752808 -132.070448)
			(xy 36.752808 -132.015952) (xy 36.760564 -131.96201) (xy 36.775917 -131.90972) (xy 36.798555 -131.860148)
			(xy 36.828017 -131.814302) (xy 36.863704 -131.773116) (xy 36.904889 -131.737427) (xy 36.950734 -131.707963)
			(xy 37.000305 -131.685322) (xy 37.052594 -131.669967) (xy 37.106536 -131.662209) (xy 37.133784 -131.661662)
			(xy 37.159693 -131.662096) (xy 37.211034 -131.669112) (xy 37.260951 -131.683018) (xy 37.308525 -131.703557)
			(xy 37.352878 -131.730351) (xy 37.393193 -131.762905) (xy 37.428728 -131.80062) (xy 37.444172 -131.821428)
			(xy 37.449897 -131.828779) (xy 37.465398 -131.839087) (xy 37.474398 -131.841494) (xy 37.504878 -131.848352)
			(xy 37.514158 -131.850003) (xy 37.532791 -131.847273) (xy 37.5412 -131.843018) (xy 37.567186 -131.828748)
			(xy 37.622047 -131.806277) (xy 37.679345 -131.791058) (xy 37.738126 -131.783343) (xy 37.767768 -131.78282)
			(xy 37.797415 -131.783296) (xy 37.856208 -131.790976) (xy 37.913515 -131.806196) (xy 37.968371 -131.828703)
			(xy 37.994336 -131.843018) (xy 38.002719 -131.847356) (xy 38.021381 -131.850094) (xy 38.030658 -131.848352)
			(xy 38.061138 -131.841494) (xy 38.070115 -131.839036) (xy 38.0856 -131.828737) (xy 38.091364 -131.821428)
			(xy 38.106779 -131.800599) (xy 38.142331 -131.7629) (xy 38.182656 -131.730358) (xy 38.227014 -131.703572)
			(xy 38.274588 -131.683033) (xy 38.324504 -131.669121) (xy 38.375843 -131.662089) (xy 38.401752 -131.661662)
			(xy 38.429009 -131.662122) (xy 38.48297 -131.669874) (xy 38.535277 -131.685227) (xy 38.584868 -131.707868)
			(xy 38.63073 -131.737337) (xy 38.662705 -131.76504) (xy 44.669708 -131.76504) (xy 44.673779 -131.709418)
			(xy 44.685905 -131.654981) (xy 44.705828 -131.60289) (xy 44.733124 -131.554255) (xy 44.76721 -131.510112)
			(xy 44.807359 -131.471403) (xy 44.852717 -131.438952) (xy 44.902317 -131.413451) (xy 44.955101 -131.395444)
			(xy 45.009944 -131.385314) (xy 45.065678 -131.383277) (xy 45.121115 -131.389377) (xy 45.175072 -131.403483)
			(xy 45.226401 -131.425295) (xy 45.274007 -131.454349) (xy 45.316875 -131.490024) (xy 45.354092 -131.531561)
			(xy 45.384865 -131.578074) (xy 45.408537 -131.628571) (xy 45.424605 -131.681978) (xy 45.432725 -131.737154)
			(xy 45.433234 -131.76504) (xy 46.650908 -131.76504) (xy 46.654979 -131.709418) (xy 46.667105 -131.654981)
			(xy 46.687028 -131.60289) (xy 46.714324 -131.554255) (xy 46.74841 -131.510112) (xy 46.788559 -131.471403)
			(xy 46.833917 -131.438952) (xy 46.883517 -131.413451) (xy 46.936301 -131.395444) (xy 46.991144 -131.385314)
			(xy 47.046878 -131.383277) (xy 47.102315 -131.389377) (xy 47.156272 -131.403483) (xy 47.207601 -131.425295)
			(xy 47.255207 -131.454349) (xy 47.298075 -131.490024) (xy 47.335292 -131.531561) (xy 47.366065 -131.578074)
			(xy 47.389737 -131.628571) (xy 47.405805 -131.681978) (xy 47.413925 -131.737154) (xy 47.414434 -131.76504)
			(xy 47.413925 -131.792926) (xy 47.405805 -131.848102) (xy 47.389737 -131.901509) (xy 47.366065 -131.952006)
			(xy 47.335292 -131.998519) (xy 47.298075 -132.040056) (xy 47.255207 -132.075731) (xy 47.207601 -132.104785)
			(xy 47.156272 -132.126597) (xy 47.102315 -132.140703) (xy 47.046878 -132.146803) (xy 46.991144 -132.144766)
			(xy 46.936301 -132.134636) (xy 46.883517 -132.116629) (xy 46.833917 -132.091128) (xy 46.788559 -132.058677)
			(xy 46.74841 -132.019968) (xy 46.714324 -131.975825) (xy 46.687028 -131.92719) (xy 46.667105 -131.875099)
			(xy 46.654979 -131.820662) (xy 46.650908 -131.76504) (xy 45.433234 -131.76504) (xy 45.432725 -131.792926)
			(xy 45.424605 -131.848102) (xy 45.408537 -131.901509) (xy 45.384865 -131.952006) (xy 45.354092 -131.998519)
			(xy 45.316875 -132.040056) (xy 45.274007 -132.075731) (xy 45.226401 -132.104785) (xy 45.175072 -132.126597)
			(xy 45.121115 -132.140703) (xy 45.065678 -132.146803) (xy 45.009944 -132.144766) (xy 44.955101 -132.134636)
			(xy 44.902317 -132.116629) (xy 44.852717 -132.091128) (xy 44.807359 -132.058677) (xy 44.76721 -132.019968)
			(xy 44.733124 -131.975825) (xy 44.705828 -131.92719) (xy 44.685905 -131.875099) (xy 44.673779 -131.820662)
			(xy 44.669708 -131.76504) (xy 38.662705 -131.76504) (xy 38.671932 -131.773034) (xy 38.707634 -131.814231)
			(xy 38.737109 -131.86009) (xy 38.759756 -131.909678) (xy 38.775116 -131.961983) (xy 38.782875 -132.015943)
			(xy 38.782875 -132.070457) (xy 38.775116 -132.124417) (xy 38.759756 -132.176723) (xy 38.737109 -132.22631)
			(xy 38.707634 -132.272169) (xy 38.671932 -132.313366) (xy 38.63073 -132.349063) (xy 38.584868 -132.378532)
			(xy 38.535277 -132.401173) (xy 38.48297 -132.416526) (xy 38.429009 -132.424278) (xy 38.401752 -132.424678)
			(xy 38.386959 -132.424534) (xy 38.357462 -132.422244) (xy 38.342824 -132.420106) (xy 38.331842 -132.418923)
			(xy 38.310628 -132.424982) (xy 38.30193 -132.43179) (xy 38.243256 -132.481828) (xy 38.235242 -132.489404)
			(xy 38.226041 -132.509421) (xy 38.225476 -132.520436) (xy 38.225476 -132.653278) (xy 38.22596 -132.66329)
			(xy 38.233615 -132.681794) (xy 38.247767 -132.69596) (xy 38.266264 -132.703631) (xy 38.276276 -132.704078)
			(xy 51.734212 -132.704078) (xy 51.74423 -132.703656) (xy 51.762739 -132.695983) (xy 51.776902 -132.68181)
			(xy 51.784563 -132.663296) (xy 51.785012 -132.653278) (xy 51.785012 -132.232654) (xy 51.78552 -132.213858)
			(xy 51.785434 -132.202294) (xy 51.776173 -132.181131) (xy 51.76774 -132.173218) (xy 51.743356 -132.152136)
			(xy 51.734371 -132.145168) (xy 51.712485 -132.139116) (xy 51.701192 -132.140452) (xy 51.684319 -132.143303)
			(xy 51.650232 -132.146351) (xy 51.63312 -132.146548) (xy 51.605863 -132.146086) (xy 51.551905 -132.138331)
			(xy 51.499599 -132.122975) (xy 51.450011 -132.100331) (xy 51.40415 -132.070861) (xy 51.362951 -132.035163)
			(xy 51.327251 -131.993966) (xy 51.297778 -131.948107) (xy 51.275132 -131.89852) (xy 51.259773 -131.846215)
			(xy 51.252015 -131.792257) (xy 51.252015 -131.737743) (xy 51.259773 -131.683785) (xy 51.275132 -131.63148)
			(xy 51.297778 -131.581893) (xy 51.327251 -131.536034) (xy 51.362951 -131.494837) (xy 51.40415 -131.459139)
			(xy 51.450011 -131.429669) (xy 51.499599 -131.407025) (xy 51.551905 -131.391669) (xy 51.605863 -131.383914)
			(xy 51.63312 -131.383532) (xy 51.660096 -131.384) (xy 51.713509 -131.391605) (xy 51.765318 -131.40666)
			(xy 51.814489 -131.428864) (xy 51.860041 -131.457775) (xy 51.901065 -131.492816) (xy 51.936743 -131.533287)
			(xy 51.966362 -131.578382) (xy 51.989331 -131.6272) (xy 52.005194 -131.678768) (xy 52.009802 -131.70535)
			(xy 52.01158 -131.716018) (xy 52.022756 -131.733544) (xy 52.10302 -131.786884) (xy 52.124102 -131.790694)
			(xy 52.134262 -131.788154) (xy 52.160962 -131.782072) (xy 52.215338 -131.775583) (xy 52.24272 -131.7752)
			(xy 52.270101 -131.775586) (xy 52.324477 -131.782079) (xy 52.351178 -131.788154) (xy 52.361338 -131.790694)
			(xy 52.38242 -131.786884) (xy 52.453794 -131.739386) (xy 52.462197 -131.73316) (xy 52.473488 -131.715584)
			(xy 52.475638 -131.70535) (xy 52.480301 -131.678776) (xy 52.496135 -131.6272) (xy 52.519084 -131.578373)
			(xy 52.54869 -131.53327) (xy 52.58436 -131.492794) (xy 52.625383 -131.457752) (xy 52.670937 -131.428846)
			(xy 52.720113 -131.406654) (xy 52.771927 -131.391618) (xy 52.825344 -131.384041) (xy 52.85232 -131.383532)
			(xy 52.879689 -131.384005) (xy 52.933866 -131.391832) (xy 52.986367 -131.407322) (xy 53.036115 -131.430158)
			(xy 53.082088 -131.45987) (xy 53.103018 -131.477512) (xy 53.103272 -131.477512) (xy 53.103272 -131.477766)
			(xy 53.110356 -131.483359) (xy 53.127274 -131.489614) (xy 53.136292 -131.489958) (xy 53.203348 -131.489958)
			(xy 53.212362 -131.489592) (xy 53.229272 -131.483338) (xy 53.236368 -131.477766) (xy 53.236622 -131.477512)
			(xy 53.257554 -131.459871) (xy 53.30352 -131.430146) (xy 53.353267 -131.407305) (xy 53.405771 -131.391818)
			(xy 53.45995 -131.384002) (xy 53.48732 -131.383532) (xy 53.504369 -131.383715) (xy 53.538329 -131.386771)
			(xy 53.555138 -131.389628) (xy 53.566477 -131.391244) (xy 53.588574 -131.385303) (xy 53.597556 -131.378198)
			(xy 53.622194 -131.356862) (xy 53.630418 -131.348895) (xy 53.639531 -131.327923) (xy 53.63972 -131.316476)
			(xy 53.639212 -131.29641) (xy 53.639212 -130.432556) (xy 53.63972 -130.41376) (xy 53.639634 -130.402196)
			(xy 53.630374 -130.381032) (xy 53.62194 -130.37312) (xy 53.597556 -130.352038) (xy 53.588571 -130.34507)
			(xy 53.566685 -130.339018) (xy 53.555392 -130.340354) (xy 53.538519 -130.343205) (xy 53.504432 -130.346253)
			(xy 53.48732 -130.34645) (xy 53.460063 -130.345988) (xy 53.406104 -130.338233) (xy 53.353798 -130.322877)
			(xy 53.30421 -130.300233) (xy 53.258349 -130.270762) (xy 53.21715 -130.235065) (xy 53.18145 -130.193867)
			(xy 53.151977 -130.148008) (xy 53.12933 -130.098421) (xy 53.113971 -130.046115) (xy 53.106213 -129.992157)
			(xy 53.106213 -129.937643) (xy 53.113971 -129.883685) (xy 53.12933 -129.831379) (xy 53.151977 -129.781792)
			(xy 53.18145 -129.735933) (xy 53.21715 -129.694735) (xy 53.258349 -129.659038) (xy 53.30421 -129.629567)
			(xy 53.353798 -129.606923) (xy 53.406104 -129.591567) (xy 53.460063 -129.583812) (xy 53.48732 -129.583434)
			(xy 53.514296 -129.583902) (xy 53.567709 -129.591507) (xy 53.619518 -129.606562) (xy 53.668689 -129.628766)
			(xy 53.714241 -129.657677) (xy 53.755265 -129.692718) (xy 53.790942 -129.733189) (xy 53.820561 -129.778284)
			(xy 53.84353 -129.827102) (xy 53.859392 -129.87867) (xy 53.864002 -129.905252) (xy 53.86578 -129.91592)
			(xy 53.876956 -129.933446) (xy 53.95722 -129.986786) (xy 53.978302 -129.990596) (xy 53.988462 -129.988056)
			(xy 54.015156 -129.981913) (xy 54.069532 -129.975292) (xy 54.09692 -129.974848) (xy 54.124308 -129.975296)
			(xy 54.178682 -129.981922) (xy 54.205378 -129.988056) (xy 54.215538 -129.990596) (xy 54.23662 -129.986786)
			(xy 54.307994 -129.939288) (xy 54.316398 -129.933063) (xy 54.32769 -129.915486) (xy 54.329838 -129.905252)
			(xy 54.334501 -129.878678) (xy 54.350334 -129.827102) (xy 54.373283 -129.778275) (xy 54.402889 -129.733172)
			(xy 54.43856 -129.692695) (xy 54.479582 -129.657653) (xy 54.525137 -129.628747) (xy 54.574313 -129.606554)
			(xy 54.626127 -129.591519) (xy 54.679544 -129.583941) (xy 54.70652 -129.583434) (xy 54.733767 -129.583922)
			(xy 54.787707 -129.591679) (xy 54.839993 -129.607035) (xy 54.889563 -129.629674) (xy 54.935405 -129.659138)
			(xy 54.976589 -129.694826) (xy 55.012274 -129.736011) (xy 55.041735 -129.781855) (xy 55.064372 -129.831425)
			(xy 55.079725 -129.883713) (xy 55.08748 -129.937653) (xy 55.08748 -129.992147) (xy 55.079725 -130.046087)
			(xy 55.064372 -130.098375) (xy 55.041735 -130.147945) (xy 55.012274 -130.193789) (xy 54.976589 -130.234974)
			(xy 54.935405 -130.270662) (xy 54.889563 -130.300126) (xy 54.839993 -130.322765) (xy 54.787707 -130.338121)
			(xy 54.733767 -130.345878) (xy 54.70652 -130.34645) (xy 54.689408 -130.346275) (xy 54.65532 -130.343219)
			(xy 54.638448 -130.340354) (xy 54.62715 -130.33896) (xy 54.605235 -130.345009) (xy 54.596284 -130.352038)
			(xy 54.5719 -130.37312) (xy 54.563494 -130.381048) (xy 54.55426 -130.402204) (xy 54.55412 -130.41376)
			(xy 54.554628 -130.432556) (xy 54.554628 -131.29641) (xy 54.55412 -131.316476) (xy 54.554179 -131.327953)
			(xy 54.563295 -131.348991) (xy 54.571646 -131.356862) (xy 54.596284 -131.378198) (xy 54.605356 -131.385134)
			(xy 54.627376 -131.39108) (xy 54.638702 -131.389628) (xy 54.655512 -131.386783) (xy 54.689472 -131.383727)
			(xy 54.70652 -131.383532) (xy 54.733767 -131.38402) (xy 54.787707 -131.391778) (xy 54.839994 -131.407133)
			(xy 54.889564 -131.429773) (xy 54.935407 -131.459236) (xy 54.97659 -131.494924) (xy 55.012276 -131.536109)
			(xy 55.041737 -131.581954) (xy 55.064374 -131.631525) (xy 55.079727 -131.683812) (xy 55.087482 -131.737753)
			(xy 55.087482 -131.792247) (xy 55.079727 -131.846188) (xy 55.064374 -131.898475) (xy 55.041737 -131.948046)
			(xy 55.012276 -131.993891) (xy 54.97659 -132.035076) (xy 54.935407 -132.070764) (xy 54.889564 -132.100227)
			(xy 54.839994 -132.122867) (xy 54.787707 -132.138222) (xy 54.733767 -132.14598) (xy 54.70652 -132.146548)
			(xy 54.679516 -132.146074) (xy 54.626048 -132.138449) (xy 54.574189 -132.123362) (xy 54.524975 -132.101114)
			(xy 54.47939 -132.072151) (xy 54.438343 -132.03705) (xy 54.402654 -131.996512) (xy 54.373037 -131.951349)
			(xy 54.350083 -131.90246) (xy 54.33425 -131.850824) (xy 54.329584 -131.824222) (xy 54.32806 -131.813554)
			(xy 54.31663 -131.795774) (xy 54.245256 -131.748276) (xy 54.236307 -131.742985) (xy 54.215864 -131.739322)
			(xy 54.205632 -131.741164) (xy 54.205124 -131.741164) (xy 54.178492 -131.747294) (xy 54.124244 -131.753913)
			(xy 54.09692 -131.754372) (xy 54.069659 -131.753904) (xy 54.015538 -131.747286) (xy 53.98897 -131.741164)
			(xy 53.988208 -131.741164) (xy 53.977975 -131.739242) (xy 53.9575 -131.742902) (xy 53.948584 -131.748276)
			(xy 53.87721 -131.795774) (xy 53.86578 -131.813554) (xy 53.864256 -131.824222) (xy 53.859607 -131.850831)
			(xy 53.843791 -131.90248) (xy 53.820847 -131.951381) (xy 53.791235 -131.996557) (xy 53.755545 -132.037103)
			(xy 53.714493 -132.07221) (xy 53.668899 -132.101174) (xy 53.619675 -132.123417) (xy 53.567806 -132.138493)
			(xy 53.514328 -132.146102) (xy 53.48732 -132.146548) (xy 53.459952 -132.146071) (xy 53.40578 -132.138236)
			(xy 53.353285 -132.122738) (xy 53.303543 -132.099896) (xy 53.257577 -132.070179) (xy 53.236622 -132.052568)
			(xy 53.236368 -132.052568) (xy 53.236368 -132.052314) (xy 53.22928 -132.046732) (xy 53.212363 -132.040499)
			(xy 53.203348 -132.040122) (xy 53.136292 -132.040122) (xy 53.127276 -132.040483) (xy 53.110364 -132.046735)
			(xy 53.103272 -132.052314) (xy 53.103018 -132.052568) (xy 53.082088 -132.070212) (xy 53.036122 -132.099943)
			(xy 52.986376 -132.12279) (xy 52.933872 -132.138285) (xy 52.879691 -132.146106) (xy 52.85232 -132.146548)
			(xy 52.835208 -132.146373) (xy 52.80112 -132.143317) (xy 52.784248 -132.140452) (xy 52.772951 -132.139058)
			(xy 52.751042 -132.145115) (xy 52.742084 -132.152136) (xy 52.7177 -132.173218) (xy 52.709294 -132.181146)
			(xy 52.700059 -132.202302) (xy 52.69992 -132.213858) (xy 52.700428 -132.232654) (xy 52.700428 -132.653278)
			(xy 52.700844 -132.6633) (xy 52.708511 -132.68182) (xy 52.722685 -132.695992) (xy 52.741206 -132.703657)
			(xy 52.751228 -132.704078) (xy 64.422274 -132.704078) (xy 64.432434 -132.699252) (xy 64.457779 -132.688022)
			(xy 64.5109 -132.672175) (xy 64.565753 -132.664173) (xy 64.59347 -132.663692) (xy 64.610582 -132.663867)
			(xy 64.64467 -132.666922) (xy 64.661542 -132.669788) (xy 64.672833 -132.671162) (xy 64.694718 -132.665079)
			(xy 64.703706 -132.658104) (xy 64.72809 -132.637276) (xy 64.736466 -132.629263) (xy 64.745581 -132.607974)
			(xy 64.745616 -132.596382) (xy 64.745108 -132.577332) (xy 64.745108 -131.713732) (xy 64.745616 -131.69392)
			(xy 64.745645 -131.682314) (xy 64.736521 -131.661001) (xy 64.72809 -131.653026) (xy 64.703706 -131.631944)
			(xy 64.694631 -131.625016) (xy 64.672615 -131.619081) (xy 64.661288 -131.620514) (xy 64.644478 -131.623359)
			(xy 64.610518 -131.626415) (xy 64.59347 -131.62661) (xy 64.56622 -131.626122) (xy 64.512275 -131.618362)
			(xy 64.459984 -131.603004) (xy 64.41041 -131.580361) (xy 64.364563 -131.550894) (xy 64.323376 -131.515202)
			(xy 64.287688 -131.474013) (xy 64.258224 -131.428164) (xy 64.235585 -131.378588) (xy 64.220231 -131.326295)
			(xy 64.212476 -131.27235) (xy 64.212476 -131.21785) (xy 64.220231 -131.163905) (xy 64.235585 -131.111612)
			(xy 64.258224 -131.062036) (xy 64.287688 -131.016187) (xy 64.323376 -130.974998) (xy 64.364563 -130.939306)
			(xy 64.41041 -130.909839) (xy 64.459984 -130.887196) (xy 64.512275 -130.871838) (xy 64.56622 -130.864078)
			(xy 64.59347 -130.863594) (xy 64.620474 -130.864067) (xy 64.673941 -130.871691) (xy 64.725799 -130.886778)
			(xy 64.775011 -130.909026) (xy 64.820595 -130.93799) (xy 64.86164 -130.973092) (xy 64.897326 -131.013631)
			(xy 64.92694 -131.058796) (xy 64.94989 -131.107685) (xy 64.965718 -131.159322) (xy 64.970406 -131.18592)
			(xy 64.97193 -131.196588) (xy 64.98336 -131.214368) (xy 65.054734 -131.261866) (xy 65.063681 -131.267163)
			(xy 65.084128 -131.270835) (xy 65.094358 -131.268978) (xy 65.094866 -131.268978) (xy 65.121504 -131.262908)
			(xy 65.175752 -131.256418) (xy 65.20307 -131.256024) (xy 65.230323 -131.256435) (xy 65.284442 -131.262934)
			(xy 65.31102 -131.268978) (xy 65.311782 -131.268978) (xy 65.322011 -131.270881) (xy 65.342467 -131.267194)
			(xy 65.351406 -131.261866) (xy 65.42278 -131.214368) (xy 65.43421 -131.196588) (xy 65.435734 -131.18592)
			(xy 65.440387 -131.159314) (xy 65.456208 -131.107671) (xy 65.479156 -131.058775) (xy 65.50877 -131.013606)
			(xy 65.54446 -130.973065) (xy 65.585511 -130.937964) (xy 65.631103 -130.909003) (xy 65.680324 -130.886763)
			(xy 65.73219 -130.871688) (xy 65.785664 -130.86408) (xy 65.81267 -130.863594) (xy 65.840038 -130.864071)
			(xy 65.894212 -130.871903) (xy 65.94671 -130.887398) (xy 65.996454 -130.910236) (xy 66.042424 -130.939949)
			(xy 66.063368 -130.957574) (xy 66.063622 -130.957574) (xy 66.063622 -130.957828) (xy 66.070711 -130.963408)
			(xy 66.087628 -130.969639) (xy 66.096642 -130.97002) (xy 66.163698 -130.97002) (xy 66.172715 -130.969661)
			(xy 66.189633 -130.963416) (xy 66.196718 -130.957828) (xy 66.196972 -130.957574) (xy 66.217903 -130.939932)
			(xy 66.26387 -130.910204) (xy 66.313616 -130.887359) (xy 66.366119 -130.871866) (xy 66.420299 -130.864044)
			(xy 66.44767 -130.863594) (xy 66.464782 -130.863769) (xy 66.49887 -130.866824) (xy 66.515742 -130.86969)
			(xy 66.527033 -130.871064) (xy 66.548919 -130.864981) (xy 66.557906 -130.858006) (xy 66.58229 -130.837178)
			(xy 66.590667 -130.829165) (xy 66.599782 -130.807877) (xy 66.599816 -130.796284) (xy 66.599308 -130.777234)
			(xy 66.599308 -129.913634) (xy 66.599816 -129.893822) (xy 66.599846 -129.882216) (xy 66.590722 -129.860902)
			(xy 66.58229 -129.852928) (xy 66.557906 -129.831846) (xy 66.548831 -129.824918) (xy 66.526815 -129.818983)
			(xy 66.515488 -129.820416) (xy 66.498678 -129.823261) (xy 66.464718 -129.826317) (xy 66.44767 -129.826512)
			(xy 66.42042 -129.826024) (xy 66.366475 -129.818264) (xy 66.314183 -129.802906) (xy 66.264609 -129.780263)
			(xy 66.218762 -129.750796) (xy 66.177575 -129.715104) (xy 66.141886 -129.673914) (xy 66.112422 -129.628064)
			(xy 66.089783 -129.578489) (xy 66.07443 -129.526196) (xy 66.066674 -129.47225) (xy 66.066674 -129.41775)
			(xy 66.07443 -129.363804) (xy 66.089783 -129.311511) (xy 66.112422 -129.261936) (xy 66.141886 -129.216086)
			(xy 66.177575 -129.174896) (xy 66.218762 -129.139204) (xy 66.264609 -129.109737) (xy 66.314183 -129.087094)
			(xy 66.366475 -129.071736) (xy 66.42042 -129.063976) (xy 66.44767 -129.063496) (xy 66.474674 -129.063969)
			(xy 66.528141 -129.071593) (xy 66.579998 -129.08668) (xy 66.629211 -129.108928) (xy 66.674795 -129.137893)
			(xy 66.71584 -129.172995) (xy 66.751525 -129.213533) (xy 66.781139 -129.258698) (xy 66.804089 -129.307587)
			(xy 66.819916 -129.359224) (xy 66.824606 -129.385822) (xy 66.82613 -129.39649) (xy 66.83756 -129.41427)
			(xy 66.908934 -129.461768) (xy 66.917881 -129.467065) (xy 66.938328 -129.470736) (xy 66.948558 -129.46888)
			(xy 66.949066 -129.46888) (xy 66.975697 -129.462749) (xy 67.029946 -129.456128) (xy 67.05727 -129.455672)
			(xy 67.084531 -129.456139) (xy 67.138652 -129.462755) (xy 67.16522 -129.46888) (xy 67.165982 -129.46888)
			(xy 67.176211 -129.470783) (xy 67.196667 -129.467096) (xy 67.205606 -129.461768) (xy 67.27698 -129.41427)
			(xy 67.28841 -129.39649) (xy 67.289934 -129.385822) (xy 67.294587 -129.359215) (xy 67.310408 -129.307572)
			(xy 67.333355 -129.258677) (xy 67.36297 -129.213507) (xy 67.39866 -129.172966) (xy 67.439711 -129.137864)
			(xy 67.485303 -129.108904) (xy 67.534524 -129.086664) (xy 67.58639 -129.071589) (xy 67.639864 -129.06398)
			(xy 67.66687 -129.063496) (xy 67.694124 -129.063957) (xy 67.748078 -129.071711) (xy 67.800378 -129.087064)
			(xy 67.849962 -129.109705) (xy 67.895818 -129.139171) (xy 67.937014 -129.174865) (xy 67.972711 -129.216058)
			(xy 68.002181 -129.261912) (xy 68.024826 -129.311493) (xy 68.040183 -129.363793) (xy 68.047941 -129.417746)
			(xy 68.047941 -129.445004) (xy 69.266052 -129.445004) (xy 69.270123 -129.389382) (xy 69.282249 -129.334945)
			(xy 69.302172 -129.282854) (xy 69.329468 -129.234219) (xy 69.363554 -129.190076) (xy 69.403703 -129.151367)
			(xy 69.449061 -129.118916) (xy 69.498661 -129.093415) (xy 69.551445 -129.075408) (xy 69.606288 -129.065278)
			(xy 69.662022 -129.063241) (xy 69.717459 -129.069341) (xy 69.771416 -129.083447) (xy 69.822745 -129.105259)
			(xy 69.870351 -129.134313) (xy 69.913219 -129.169988) (xy 69.950436 -129.211525) (xy 69.981209 -129.258038)
			(xy 70.004881 -129.308535) (xy 70.020949 -129.361942) (xy 70.029069 -129.417118) (xy 70.029578 -129.445004)
			(xy 71.885046 -129.445004) (xy 71.889117 -129.389382) (xy 71.901243 -129.334945) (xy 71.921166 -129.282854)
			(xy 71.948462 -129.234219) (xy 71.982548 -129.190076) (xy 72.022697 -129.151367) (xy 72.068055 -129.118916)
			(xy 72.117655 -129.093415) (xy 72.170439 -129.075408) (xy 72.225282 -129.065278) (xy 72.281016 -129.063241)
			(xy 72.336453 -129.069341) (xy 72.39041 -129.083447) (xy 72.441739 -129.105259) (xy 72.489345 -129.134313)
			(xy 72.532213 -129.169988) (xy 72.56943 -129.211525) (xy 72.600203 -129.258038) (xy 72.623875 -129.308535)
			(xy 72.639943 -129.361942) (xy 72.648063 -129.417118) (xy 72.648572 -129.445004) (xy 73.866246 -129.445004)
			(xy 73.870317 -129.389382) (xy 73.882443 -129.334945) (xy 73.902366 -129.282854) (xy 73.929662 -129.234219)
			(xy 73.963748 -129.190076) (xy 74.003897 -129.151367) (xy 74.049255 -129.118916) (xy 74.098855 -129.093415)
			(xy 74.151639 -129.075408) (xy 74.206482 -129.065278) (xy 74.262216 -129.063241) (xy 74.317653 -129.069341)
			(xy 74.37161 -129.083447) (xy 74.422939 -129.105259) (xy 74.470545 -129.134313) (xy 74.513413 -129.169988)
			(xy 74.55063 -129.211525) (xy 74.581403 -129.258038) (xy 74.605075 -129.308535) (xy 74.621143 -129.361942)
			(xy 74.629263 -129.417118) (xy 74.629772 -129.445004) (xy 74.629263 -129.47289) (xy 74.621143 -129.528066)
			(xy 74.605075 -129.581473) (xy 74.581403 -129.63197) (xy 74.55063 -129.678483) (xy 74.513413 -129.72002)
			(xy 74.495226 -129.735155) (xy 80.517149 -129.735155) (xy 80.517149 -129.680645) (xy 80.524908 -129.62669)
			(xy 80.540266 -129.574388) (xy 80.562911 -129.524805) (xy 80.592383 -129.478949) (xy 80.628082 -129.437755)
			(xy 80.66928 -129.402061) (xy 80.715138 -129.372593) (xy 80.764724 -129.349952) (xy 80.817027 -129.334599)
			(xy 80.870983 -129.326847) (xy 80.898238 -129.326386) (xy 80.924145 -129.326853) (xy 80.975481 -129.333881)
			(xy 81.025395 -129.347789) (xy 81.072968 -129.368322) (xy 81.117326 -129.395102) (xy 81.157653 -129.427636)
			(xy 81.193209 -129.465327) (xy 81.208626 -129.486152) (xy 81.214389 -129.493462) (xy 81.229875 -129.50376)
			(xy 81.238852 -129.506218) (xy 81.269332 -129.513076) (xy 81.278609 -129.514822) (xy 81.297272 -129.512084)
			(xy 81.305654 -129.507742) (xy 81.331623 -129.493433) (xy 81.386477 -129.470924) (xy 81.443782 -129.455702)
			(xy 81.502576 -129.448021) (xy 81.532222 -129.447544) (xy 81.561864 -129.448068) (xy 81.620645 -129.455782)
			(xy 81.677943 -129.471001) (xy 81.732804 -129.493472) (xy 81.75879 -129.507742) (xy 81.767201 -129.511993)
			(xy 81.785833 -129.514724) (xy 81.795112 -129.513076) (xy 81.825592 -129.506218) (xy 81.834588 -129.503799)
			(xy 81.85009 -129.493499) (xy 81.855818 -129.486152) (xy 81.871246 -129.465332) (xy 81.906786 -129.42762)
			(xy 81.947105 -129.39507) (xy 81.991461 -129.368279) (xy 82.039036 -129.347742) (xy 82.088955 -129.333837)
			(xy 82.140297 -129.32682) (xy 82.166206 -129.326386) (xy 82.193457 -129.326884) (xy 82.247403 -129.334641)
			(xy 82.299696 -129.349997) (xy 82.349272 -129.372638) (xy 82.395121 -129.402104) (xy 82.436309 -129.437795)
			(xy 82.472 -129.478984) (xy 82.501465 -129.524834) (xy 82.524105 -129.57441) (xy 82.53946 -129.626703)
			(xy 82.547216 -129.680649) (xy 82.547216 -129.735151) (xy 82.53946 -129.789097) (xy 82.524105 -129.84139)
			(xy 82.501465 -129.890966) (xy 82.472 -129.936816) (xy 82.436309 -129.978005) (xy 82.395121 -130.013696)
			(xy 82.349272 -130.043162) (xy 82.299696 -130.065803) (xy 82.247403 -130.081159) (xy 82.193457 -130.088916)
			(xy 82.166206 -130.089402) (xy 82.151413 -130.089268) (xy 82.121915 -130.086978) (xy 82.107278 -130.08483)
			(xy 82.096303 -130.083692) (xy 82.07511 -130.08976) (xy 82.066384 -130.096514) (xy 82.007964 -130.146552)
			(xy 81.999959 -130.15414) (xy 81.990732 -130.174145) (xy 81.990184 -130.18516) (xy 81.990184 -130.489452)
			(xy 81.990753 -130.500467) (xy 81.999951 -130.520484) (xy 82.007964 -130.52806) (xy 82.07502 -130.585464)
			(xy 82.096102 -130.59156) (xy 82.107278 -130.589782) (xy 82.121915 -130.587637) (xy 82.151413 -130.585352)
			(xy 82.166206 -130.58521) (xy 82.193458 -130.58566) (xy 82.247408 -130.593418) (xy 82.299704 -130.608774)
			(xy 82.349283 -130.631417) (xy 82.395135 -130.660885) (xy 82.436326 -130.696578) (xy 82.472019 -130.73777)
			(xy 82.501486 -130.783622) (xy 82.524128 -130.833201) (xy 82.539483 -130.885498) (xy 82.54724 -130.939448)
			(xy 82.54724 -130.992118) (xy 104.844342 -130.992118) (xy 104.844808 -130.964748) (xy 104.852625 -130.910568)
			(xy 104.868113 -130.858065) (xy 104.890955 -130.808318) (xy 104.92068 -130.762351) (xy 104.938322 -130.74142)
			(xy 104.938576 -130.741166) (xy 104.94415 -130.734071) (xy 104.950402 -130.71716) (xy 104.950768 -130.708146)
			(xy 104.950768 -130.64109) (xy 104.950423 -130.632072) (xy 104.944168 -130.615154) (xy 104.938576 -130.60807)
			(xy 104.938322 -130.60807) (xy 104.938322 -130.607816) (xy 104.920699 -130.586869) (xy 104.890974 -130.540903)
			(xy 104.868128 -130.49116) (xy 104.85263 -130.43866) (xy 104.8448 -130.384483) (xy 104.844798 -130.329744)
			(xy 104.852625 -130.275567) (xy 104.868118 -130.223066) (xy 104.890961 -130.17332) (xy 104.920683 -130.127353)
			(xy 104.938322 -130.10642) (xy 104.938576 -130.106166) (xy 104.94415 -130.099071) (xy 104.950402 -130.08216)
			(xy 104.950768 -130.073146) (xy 104.950768 -130.00609) (xy 104.950423 -129.997072) (xy 104.944168 -129.980154)
			(xy 104.938576 -129.97307) (xy 104.938322 -129.97307) (xy 104.938322 -129.972816) (xy 104.920699 -129.951869)
			(xy 104.890974 -129.905903) (xy 104.868128 -129.85616) (xy 104.85263 -129.80366) (xy 104.8448 -129.749483)
			(xy 104.844798 -129.694744) (xy 104.852625 -129.640567) (xy 104.868118 -129.588066) (xy 104.890961 -129.53832)
			(xy 104.920683 -129.492353) (xy 104.938322 -129.47142) (xy 104.938576 -129.471166) (xy 104.94415 -129.464071)
			(xy 104.950402 -129.44716) (xy 104.950768 -129.438146) (xy 104.950768 -129.37109) (xy 104.950423 -129.362072)
			(xy 104.944168 -129.345154) (xy 104.938576 -129.33807) (xy 104.938322 -129.33807) (xy 104.938322 -129.337816)
			(xy 104.92068 -129.316886) (xy 104.890968 -129.270913) (xy 104.868132 -129.221165) (xy 104.852642 -129.168664)
			(xy 104.844815 -129.114487) (xy 104.844342 -129.087118) (xy 104.844828 -129.059867) (xy 104.852584 -129.005919)
			(xy 104.867939 -128.953624) (xy 104.890581 -128.904047) (xy 104.920047 -128.858197) (xy 104.955738 -128.817006)
			(xy 104.996929 -128.781315) (xy 105.042779 -128.751849) (xy 105.092356 -128.729207) (xy 105.144651 -128.713852)
			(xy 105.198599 -128.706096) (xy 105.253101 -128.706096) (xy 105.307049 -128.713852) (xy 105.359344 -128.729207)
			(xy 105.408921 -128.751849) (xy 105.454771 -128.781315) (xy 105.495962 -128.817006) (xy 105.531653 -128.858197)
			(xy 105.561119 -128.904047) (xy 105.583761 -128.953624) (xy 105.599116 -129.005919) (xy 105.606872 -129.059867)
			(xy 105.607358 -129.087118) (xy 105.606913 -129.114489) (xy 105.599091 -129.168669) (xy 105.583598 -129.221173)
			(xy 105.560751 -129.27092) (xy 105.531022 -129.316885) (xy 105.513378 -129.337816) (xy 105.513124 -129.33807)
			(xy 105.507535 -129.345155) (xy 105.501292 -129.362073) (xy 105.500932 -129.37109) (xy 105.500932 -129.438146)
			(xy 105.501308 -129.447161) (xy 105.507542 -129.464079) (xy 105.513124 -129.471166) (xy 105.513378 -129.471166)
			(xy 105.513378 -129.47142) (xy 105.531036 -129.492339) (xy 105.56076 -129.538309) (xy 105.583604 -129.588058)
			(xy 105.599098 -129.640562) (xy 105.606925 -129.694742) (xy 105.606923 -129.749485) (xy 105.599093 -129.803665)
			(xy 105.583594 -129.856168) (xy 105.560747 -129.905915) (xy 105.53102 -129.951883) (xy 105.513378 -129.972816)
			(xy 105.513124 -129.97307) (xy 105.507535 -129.980155) (xy 105.501292 -129.997073) (xy 105.500932 -130.00609)
			(xy 105.500932 -130.073146) (xy 105.501308 -130.082161) (xy 105.507542 -130.099079) (xy 105.513124 -130.106166)
			(xy 105.513378 -130.106166) (xy 105.513378 -130.10642) (xy 105.531036 -130.127339) (xy 105.56076 -130.173309)
			(xy 105.583604 -130.223058) (xy 105.599098 -130.275562) (xy 105.606925 -130.329742) (xy 105.606923 -130.384485)
			(xy 105.599093 -130.438665) (xy 105.583594 -130.491168) (xy 105.560747 -130.540915) (xy 105.53102 -130.586883)
			(xy 105.513378 -130.607816) (xy 105.513124 -130.60807) (xy 105.507535 -130.615155) (xy 105.501292 -130.632073)
			(xy 105.500932 -130.64109) (xy 105.500932 -130.708146) (xy 105.501308 -130.717161) (xy 105.507542 -130.734079)
			(xy 105.513124 -130.741166) (xy 105.513378 -130.741166) (xy 105.513378 -130.74142) (xy 105.53099 -130.762374)
			(xy 105.560706 -130.808341) (xy 105.583548 -130.858082) (xy 105.599045 -130.910578) (xy 105.60688 -130.96475)
			(xy 105.607358 -130.992118) (xy 105.606872 -131.019369) (xy 105.602208 -131.051808) (xy 107.500166 -131.051808)
			(xy 107.500621 -131.024437) (xy 107.508439 -130.970257) (xy 107.52393 -130.917753) (xy 107.546774 -130.868006)
			(xy 107.576503 -130.822041) (xy 107.594146 -130.80111) (xy 107.5944 -130.800856) (xy 107.599969 -130.793758)
			(xy 107.606226 -130.77685) (xy 107.606592 -130.767836) (xy 107.606592 -130.70078) (xy 107.606246 -130.691762)
			(xy 107.599991 -130.674845) (xy 107.5944 -130.66776) (xy 107.594146 -130.66776) (xy 107.594146 -130.667506)
			(xy 107.576512 -130.646567) (xy 107.546786 -130.600601) (xy 107.523939 -130.550856) (xy 107.508441 -130.498355)
			(xy 107.500611 -130.444176) (xy 107.50061 -130.389436) (xy 107.508439 -130.335257) (xy 107.523935 -130.282755)
			(xy 107.54678 -130.23301) (xy 107.576505 -130.187042) (xy 107.594146 -130.16611) (xy 107.5944 -130.165856)
			(xy 107.599969 -130.158758) (xy 107.606226 -130.14185) (xy 107.606592 -130.132836) (xy 107.606592 -130.06578)
			(xy 107.606246 -130.056762) (xy 107.599991 -130.039845) (xy 107.5944 -130.03276) (xy 107.594146 -130.03276)
			(xy 107.594146 -130.032506) (xy 107.576503 -130.011577) (xy 107.546791 -129.965604) (xy 107.523955 -129.915856)
			(xy 107.508464 -129.863354) (xy 107.500638 -129.809177) (xy 107.500166 -129.781808) (xy 107.50065 -129.755495)
			(xy 107.507883 -129.703367) (xy 107.522199 -129.652725) (xy 107.543329 -129.604527) (xy 107.570871 -129.559683)
			(xy 107.604306 -129.519042) (xy 107.623356 -129.500884) (xy 107.63076 -129.493364) (xy 107.639284 -129.474083)
			(xy 107.639866 -129.463546) (xy 107.639866 -129.38887) (xy 107.639323 -129.378322) (xy 107.630799 -129.359026)
			(xy 107.623356 -129.351532) (xy 107.604266 -129.333411) (xy 107.570814 -129.292773) (xy 107.54326 -129.247925)
			(xy 107.522128 -129.199718) (xy 107.507818 -129.149065) (xy 107.500601 -129.096926) (xy 107.500166 -129.070608)
			(xy 107.500685 -129.043358) (xy 107.50844 -128.989413) (xy 107.523793 -128.93712) (xy 107.546431 -128.887545)
			(xy 107.575894 -128.841696) (xy 107.611582 -128.800506) (xy 107.652768 -128.764814) (xy 107.698615 -128.735347)
			(xy 107.748188 -128.712705) (xy 107.80048 -128.697347) (xy 107.854424 -128.689588) (xy 107.881674 -128.6891)
			(xy 107.881928 -128.6891) (xy 107.910131 -128.689598) (xy 107.965919 -128.697928) (xy 108.019875 -128.714372)
			(xy 108.070826 -128.738574) (xy 108.094526 -128.75387) (xy 108.106464 -128.761998) (xy 108.134658 -128.763268)
			(xy 108.226606 -128.712722) (xy 108.234549 -128.707863) (xy 108.246531 -128.693631) (xy 108.252641 -128.676059)
			(xy 108.252768 -128.666748) (xy 108.252514 -128.656334) (xy 108.252514 -128.655826) (xy 108.252977 -128.628585)
			(xy 108.260766 -128.574662) (xy 108.276147 -128.522396) (xy 108.298806 -128.472849) (xy 108.328283 -128.42703)
			(xy 108.363979 -128.385869) (xy 108.405167 -128.350206) (xy 108.451009 -128.320764) (xy 108.500574 -128.298143)
			(xy 108.552852 -128.282803) (xy 108.606781 -128.275055) (xy 108.634022 -128.274572) (xy 108.661273 -128.275057)
			(xy 108.71522 -128.282816) (xy 108.767513 -128.298173) (xy 108.817089 -128.320815) (xy 108.862938 -128.350282)
			(xy 108.904128 -128.385974) (xy 108.939819 -128.427163) (xy 108.969286 -128.473013) (xy 108.991928 -128.522589)
			(xy 109.007284 -128.574882) (xy 109.015043 -128.628829) (xy 109.01553 -128.65608) (xy 109.015468 -128.659757)
			(xy 112.065713 -128.659757) (xy 112.065713 -128.605243) (xy 112.073471 -128.551285) (xy 112.08883 -128.49898)
			(xy 112.111476 -128.449393) (xy 112.140949 -128.403534) (xy 112.176648 -128.362337) (xy 112.217847 -128.326639)
			(xy 112.263707 -128.297168) (xy 112.313295 -128.274524) (xy 112.365601 -128.259168) (xy 112.419559 -128.251412)
			(xy 112.446816 -128.25095) (xy 112.474761 -128.251422) (xy 112.530052 -128.259585) (xy 112.583563 -128.275721)
			(xy 112.63415 -128.299484) (xy 112.680732 -128.330367) (xy 112.722316 -128.36771) (xy 112.758013 -128.410716)
			(xy 112.772952 -128.434338) (xy 112.777728 -128.441604) (xy 112.791113 -128.452676) (xy 112.807448 -128.458587)
			(xy 112.816132 -128.458976) (xy 112.915954 -128.459738) (xy 112.938814 -128.447038) (xy 112.945926 -128.435608)
			(xy 112.960922 -128.412462) (xy 112.996616 -128.370417) (xy 113.037993 -128.333951) (xy 113.08419 -128.303823)
			(xy 113.134244 -128.280663) (xy 113.187112 -128.264953) (xy 113.241692 -128.25702) (xy 113.269268 -128.256538)
			(xy 113.296638 -128.257014) (xy 113.350817 -128.264828) (xy 113.40332 -128.280314) (xy 113.453067 -128.303154)
			(xy 113.499034 -128.332877) (xy 113.519966 -128.350518) (xy 113.52022 -128.350772) (xy 113.527291 -128.356382)
			(xy 113.54422 -128.362612) (xy 113.55324 -128.362964) (xy 113.620296 -128.362964) (xy 113.629314 -128.362613)
			(xy 113.646231 -128.356362) (xy 113.653316 -128.350772) (xy 113.653316 -128.350518) (xy 113.65357 -128.350518)
			(xy 113.674503 -128.332877) (xy 113.720471 -128.303153) (xy 113.770217 -128.280307) (xy 113.822719 -128.264811)
			(xy 113.876897 -128.256982) (xy 113.931639 -128.256982) (xy 113.985817 -128.264811) (xy 114.038319 -128.280307)
			(xy 114.088065 -128.303153) (xy 114.134033 -128.332877) (xy 114.154966 -128.350518) (xy 114.15522 -128.350772)
			(xy 114.162291 -128.356382) (xy 114.17922 -128.362612) (xy 114.18824 -128.362964) (xy 114.255296 -128.362964)
			(xy 114.264314 -128.362613) (xy 114.281231 -128.356362) (xy 114.288316 -128.350772) (xy 114.288316 -128.350518)
			(xy 114.28857 -128.350518) (xy 114.309505 -128.332882) (xy 114.355477 -128.303169) (xy 114.405223 -128.280332)
			(xy 114.457724 -128.264841) (xy 114.511899 -128.257012) (xy 114.539268 -128.256538) (xy 114.566526 -128.256907)
			(xy 114.620487 -128.264661) (xy 114.672795 -128.280016) (xy 114.722385 -128.30266) (xy 114.768248 -128.33213)
			(xy 114.809449 -128.367828) (xy 114.845151 -128.409027) (xy 114.874625 -128.454887) (xy 114.897273 -128.504475)
			(xy 114.912632 -128.556782) (xy 114.920391 -128.610742) (xy 114.920391 -128.665258) (xy 114.912632 -128.719218)
			(xy 114.897273 -128.771525) (xy 114.874625 -128.821113) (xy 114.845151 -128.866973) (xy 114.809449 -128.908172)
			(xy 114.768248 -128.94387) (xy 114.761936 -128.947926) (xy 118.631714 -128.947926) (xy 118.635785 -128.892304)
			(xy 118.647911 -128.837867) (xy 118.667834 -128.785776) (xy 118.69513 -128.737141) (xy 118.729216 -128.692998)
			(xy 118.769365 -128.654289) (xy 118.814723 -128.621838) (xy 118.864323 -128.596337) (xy 118.917107 -128.57833)
			(xy 118.97195 -128.5682) (xy 119.027684 -128.566163) (xy 119.083121 -128.572263) (xy 119.137078 -128.586369)
			(xy 119.188407 -128.608181) (xy 119.236013 -128.637235) (xy 119.278881 -128.67291) (xy 119.316098 -128.714447)
			(xy 119.346871 -128.76096) (xy 119.370543 -128.811457) (xy 119.386611 -128.864864) (xy 119.394731 -128.92004)
			(xy 119.39524 -128.947926) (xy 119.394731 -128.975812) (xy 119.386611 -129.030988) (xy 119.370543 -129.084395)
			(xy 119.346871 -129.134892) (xy 119.316098 -129.181405) (xy 119.278881 -129.222942) (xy 119.236013 -129.258617)
			(xy 119.188407 -129.287671) (xy 119.137078 -129.309483) (xy 119.083121 -129.323589) (xy 119.027684 -129.329689)
			(xy 118.97195 -129.327652) (xy 118.917107 -129.317522) (xy 118.864323 -129.299515) (xy 118.814723 -129.274014)
			(xy 118.769365 -129.241563) (xy 118.729216 -129.202854) (xy 118.69513 -129.158711) (xy 118.667834 -129.110076)
			(xy 118.647911 -129.057985) (xy 118.635785 -129.003548) (xy 118.631714 -128.947926) (xy 114.761936 -128.947926)
			(xy 114.722385 -128.97334) (xy 114.672795 -128.995984) (xy 114.620487 -129.011339) (xy 114.566526 -129.019093)
			(xy 114.539268 -129.019554) (xy 114.511897 -129.019118) (xy 114.457716 -129.011295) (xy 114.405212 -128.995799)
			(xy 114.355465 -128.97295) (xy 114.3095 -128.943219) (xy 114.28857 -128.925574) (xy 114.288316 -128.92532)
			(xy 114.281236 -128.919725) (xy 114.264314 -128.913485) (xy 114.255296 -128.913128) (xy 114.18824 -128.913128)
			(xy 114.179224 -128.913498) (xy 114.162307 -128.919736) (xy 114.15522 -128.92532) (xy 114.15522 -128.925574)
			(xy 114.154966 -128.925574) (xy 114.134033 -128.943215) (xy 114.088065 -128.972939) (xy 114.038319 -128.995785)
			(xy 113.985817 -129.011281) (xy 113.931639 -129.01911) (xy 113.876897 -129.01911) (xy 113.822719 -129.011281)
			(xy 113.770217 -128.995785) (xy 113.720471 -128.972939) (xy 113.674503 -128.943215) (xy 113.65357 -128.925574)
			(xy 113.653316 -128.92532) (xy 113.646236 -128.919725) (xy 113.629314 -128.913485) (xy 113.620296 -128.913128)
			(xy 113.55324 -128.913128) (xy 113.544224 -128.913498) (xy 113.527307 -128.919736) (xy 113.52022 -128.92532)
			(xy 113.52022 -128.925574) (xy 113.519966 -128.925574) (xy 113.499017 -128.943192) (xy 113.453049 -128.972908)
			(xy 113.403306 -128.995748) (xy 113.350809 -129.011244) (xy 113.296636 -129.019077) (xy 113.269268 -129.019554)
			(xy 113.241323 -129.019093) (xy 113.186031 -129.010927) (xy 113.132521 -128.994789) (xy 113.081934 -128.971024)
			(xy 113.035351 -128.94014) (xy 112.993767 -128.902795) (xy 112.958071 -128.859788) (xy 112.943132 -128.836166)
			(xy 112.938395 -128.828873) (xy 112.924988 -128.817813) (xy 112.908641 -128.811913) (xy 112.899952 -128.811528)
			(xy 112.80013 -128.810766) (xy 112.77727 -128.823466) (xy 112.770158 -128.834896) (xy 112.755073 -128.857982)
			(xy 112.719397 -128.900032) (xy 112.678037 -128.936506) (xy 112.631855 -128.966642) (xy 112.581814 -128.989812)
			(xy 112.528958 -129.005533) (xy 112.474388 -129.013478) (xy 112.446816 -129.013966) (xy 112.419559 -129.013588)
			(xy 112.365601 -129.005832) (xy 112.313295 -128.990476) (xy 112.263707 -128.967832) (xy 112.217847 -128.938361)
			(xy 112.176648 -128.902663) (xy 112.140949 -128.861466) (xy 112.111476 -128.815607) (xy 112.08883 -128.76602)
			(xy 112.073471 -128.713715) (xy 112.065713 -128.659757) (xy 109.015468 -128.659757) (xy 109.015069 -128.683451)
			(xy 109.007253 -128.737631) (xy 108.991763 -128.790134) (xy 108.96892 -128.839881) (xy 108.939193 -128.885847)
			(xy 108.92155 -128.906778) (xy 108.921296 -128.907032) (xy 108.915731 -128.914134) (xy 108.909472 -128.931039)
			(xy 108.909104 -128.940052) (xy 108.909104 -129.007108) (xy 108.909456 -129.016125) (xy 108.915707 -129.033042)
			(xy 108.921296 -129.040128) (xy 108.92155 -129.040128) (xy 108.92155 -129.040382) (xy 108.939186 -129.061316)
			(xy 108.9689 -129.107288) (xy 108.991738 -129.157035) (xy 109.007229 -129.209535) (xy 109.015057 -129.263711)
			(xy 109.01553 -129.29108) (xy 109.015003 -129.31833) (xy 109.00725 -129.372275) (xy 108.991899 -129.424567)
			(xy 108.975467 -129.460553) (xy 110.320775 -129.460553) (xy 110.320775 -129.406047) (xy 110.328533 -129.352096)
			(xy 110.34389 -129.299798) (xy 110.366534 -129.250218) (xy 110.396004 -129.204365) (xy 110.431699 -129.163174)
			(xy 110.472894 -129.127482) (xy 110.518749 -129.098017) (xy 110.568331 -129.075377) (xy 110.620631 -129.060025)
			(xy 110.674583 -129.052273) (xy 110.701836 -129.051812) (xy 110.729697 -129.052353) (xy 110.784822 -129.060485)
			(xy 110.838185 -129.076528) (xy 110.863634 -129.08788) (xy 110.872524 -129.092198) (xy 110.89259 -129.093214)
			(xy 110.97895 -129.062226) (xy 110.993936 -129.049018) (xy 110.998254 -129.040382) (xy 110.998254 -129.039874)
			(xy 111.010259 -129.015994) (xy 111.040017 -128.971594) (xy 111.075682 -128.931785) (xy 111.116556 -128.897344)
			(xy 111.161839 -128.868947) (xy 111.210642 -128.84715) (xy 111.26201 -128.83238) (xy 111.314937 -128.824927)
			(xy 111.341662 -128.824482) (xy 111.368913 -128.824991) (xy 111.422862 -128.832742) (xy 111.475159 -128.848093)
			(xy 111.524738 -128.87073) (xy 111.570591 -128.900193) (xy 111.611784 -128.935882) (xy 111.647478 -128.977071)
			(xy 111.676947 -129.02292) (xy 111.69959 -129.072496) (xy 111.714948 -129.124791) (xy 111.722706 -129.178739)
			(xy 111.72317 -129.20599) (xy 111.722706 -129.23191) (xy 111.715676 -129.283272) (xy 111.701759 -129.33321)
			(xy 111.68121 -129.380804) (xy 111.663911 -129.409444) (xy 116.367812 -129.409444) (xy 116.371883 -129.353822)
			(xy 116.384009 -129.299385) (xy 116.403932 -129.247294) (xy 116.431228 -129.198659) (xy 116.465314 -129.154516)
			(xy 116.505463 -129.115807) (xy 116.550821 -129.083356) (xy 116.600421 -129.057855) (xy 116.653205 -129.039848)
			(xy 116.708048 -129.029718) (xy 116.763782 -129.027681) (xy 116.819219 -129.033781) (xy 116.873176 -129.047887)
			(xy 116.924505 -129.069699) (xy 116.972111 -129.098753) (xy 117.014979 -129.134428) (xy 117.052196 -129.175965)
			(xy 117.082969 -129.222478) (xy 117.106641 -129.272975) (xy 117.122709 -129.326382) (xy 117.130829 -129.381558)
			(xy 117.131338 -129.409444) (xy 117.130829 -129.43733) (xy 117.122709 -129.492506) (xy 117.106641 -129.545913)
			(xy 117.082969 -129.59641) (xy 117.052196 -129.642923) (xy 117.014979 -129.68446) (xy 116.972111 -129.720135)
			(xy 116.924505 -129.749189) (xy 116.873176 -129.771001) (xy 116.819219 -129.785107) (xy 116.763782 -129.791207)
			(xy 116.708048 -129.78917) (xy 116.653205 -129.77904) (xy 116.600421 -129.761033) (xy 116.550821 -129.735532)
			(xy 116.505463 -129.703081) (xy 116.465314 -129.664372) (xy 116.431228 -129.620229) (xy 116.403932 -129.571594)
			(xy 116.384009 -129.519503) (xy 116.371883 -129.465066) (xy 116.367812 -129.409444) (xy 111.663911 -129.409444)
			(xy 111.654408 -129.425178) (xy 111.621846 -129.465517) (xy 111.603282 -129.483612) (xy 111.603028 -129.483866)
			(xy 111.595801 -129.491449) (xy 111.587679 -129.510736) (xy 111.58728 -129.521204) (xy 111.58855 -129.596388)
			(xy 111.589251 -129.606881) (xy 111.597888 -129.626028) (xy 111.605314 -129.633472) (xy 111.605568 -129.633726)
			(xy 111.625388 -129.651915) (xy 111.660244 -129.692887) (xy 111.689 -129.738349) (xy 111.711084 -129.7874)
			(xy 111.726058 -129.839067) (xy 111.733625 -129.892326) (xy 111.734092 -129.919222) (xy 111.733643 -129.946475)
			(xy 111.732957 -129.951246) (xy 112.909426 -129.951246) (xy 112.909426 -129.896754) (xy 112.91718 -129.842818)
			(xy 112.932531 -129.790534) (xy 112.955166 -129.740966) (xy 112.984623 -129.695124) (xy 113.020305 -129.65394)
			(xy 113.061484 -129.618253) (xy 113.107322 -129.58879) (xy 113.156887 -129.566148) (xy 113.209169 -129.550791)
			(xy 113.263105 -129.54303) (xy 113.29035 -129.54254) (xy 113.31772 -129.543026) (xy 113.371898 -129.550837)
			(xy 113.424402 -129.566321) (xy 113.474149 -129.589159) (xy 113.520116 -129.61888) (xy 113.541048 -129.63652)
			(xy 113.541302 -129.636774) (xy 113.548378 -129.642376) (xy 113.565303 -129.648612) (xy 113.574322 -129.648966)
			(xy 113.641378 -129.648966) (xy 113.650395 -129.648606) (xy 113.667312 -129.642361) (xy 113.674398 -129.636774)
			(xy 113.674398 -129.63652) (xy 113.674652 -129.63652) (xy 113.695594 -129.618893) (xy 113.741564 -129.589179)
			(xy 113.791309 -129.56634) (xy 113.843807 -129.550846) (xy 113.897981 -129.543015) (xy 113.92535 -129.54254)
			(xy 113.952609 -129.542904) (xy 114.006572 -129.550656) (xy 114.058882 -129.566009) (xy 114.108475 -129.588652)
			(xy 114.15434 -129.618122) (xy 114.195544 -129.65382) (xy 114.231248 -129.69502) (xy 114.260724 -129.740881)
			(xy 114.283373 -129.790471) (xy 114.298734 -129.842779) (xy 114.306493 -129.896741) (xy 114.306493 -129.951259)
			(xy 114.298734 -130.005221) (xy 114.283373 -130.057529) (xy 114.260724 -130.107119) (xy 114.231248 -130.15298)
			(xy 114.195544 -130.19418) (xy 114.168135 -130.217926) (xy 118.631714 -130.217926) (xy 118.635785 -130.162304)
			(xy 118.647911 -130.107867) (xy 118.667834 -130.055776) (xy 118.69513 -130.007141) (xy 118.729216 -129.962998)
			(xy 118.769365 -129.924289) (xy 118.814723 -129.891838) (xy 118.864323 -129.866337) (xy 118.917107 -129.84833)
			(xy 118.97195 -129.8382) (xy 119.027684 -129.836163) (xy 119.083121 -129.842263) (xy 119.137078 -129.856369)
			(xy 119.188407 -129.878181) (xy 119.236013 -129.907235) (xy 119.278881 -129.94291) (xy 119.316098 -129.984447)
			(xy 119.346871 -130.03096) (xy 119.370543 -130.081457) (xy 119.386611 -130.134864) (xy 119.394731 -130.19004)
			(xy 119.39524 -130.217926) (xy 119.394731 -130.245812) (xy 119.386611 -130.300988) (xy 119.370543 -130.354395)
			(xy 119.346871 -130.404892) (xy 119.316098 -130.451405) (xy 119.278881 -130.492942) (xy 119.236013 -130.528617)
			(xy 119.188407 -130.557671) (xy 119.137078 -130.579483) (xy 119.083121 -130.593589) (xy 119.027684 -130.599689)
			(xy 118.97195 -130.597652) (xy 118.917107 -130.587522) (xy 118.864323 -130.569515) (xy 118.814723 -130.544014)
			(xy 118.769365 -130.511563) (xy 118.729216 -130.472854) (xy 118.69513 -130.428711) (xy 118.667834 -130.380076)
			(xy 118.647911 -130.327985) (xy 118.635785 -130.273548) (xy 118.631714 -130.217926) (xy 114.168135 -130.217926)
			(xy 114.15434 -130.229878) (xy 114.108475 -130.259348) (xy 114.058882 -130.281991) (xy 114.006572 -130.297344)
			(xy 113.952609 -130.305096) (xy 113.92535 -130.305556) (xy 113.89798 -130.305071) (xy 113.843802 -130.29726)
			(xy 113.791298 -130.281776) (xy 113.741551 -130.258938) (xy 113.695584 -130.229216) (xy 113.674652 -130.211576)
			(xy 113.674398 -130.211322) (xy 113.667323 -130.205719) (xy 113.650397 -130.199484) (xy 113.641378 -130.19913)
			(xy 113.574322 -130.19913) (xy 113.565305 -130.199491) (xy 113.548388 -130.205735) (xy 113.541302 -130.211322)
			(xy 113.541302 -130.211576) (xy 113.541048 -130.211576) (xy 113.520106 -130.229202) (xy 113.474136 -130.258917)
			(xy 113.424391 -130.281756) (xy 113.371893 -130.29725) (xy 113.317719 -130.305081) (xy 113.29035 -130.305556)
			(xy 113.263105 -130.30497) (xy 113.209169 -130.297209) (xy 113.156887 -130.281852) (xy 113.107322 -130.259211)
			(xy 113.061484 -130.229747) (xy 113.020305 -130.19406) (xy 112.984623 -130.152876) (xy 112.955166 -130.107034)
			(xy 112.932531 -130.057466) (xy 112.91718 -130.005182) (xy 112.909426 -129.951246) (xy 111.732957 -129.951246)
			(xy 111.725883 -130.000424) (xy 111.710524 -130.052721) (xy 111.687879 -130.102299) (xy 111.658409 -130.14815)
			(xy 111.622714 -130.189341) (xy 111.58152 -130.225032) (xy 111.535666 -130.254497) (xy 111.486085 -130.277137)
			(xy 111.433787 -130.292491) (xy 111.379837 -130.300245) (xy 111.352584 -130.30073) (xy 111.325345 -130.300238)
			(xy 111.271421 -130.292487) (xy 111.219148 -130.277143) (xy 111.169589 -130.25452) (xy 111.123752 -130.225078)
			(xy 111.082569 -130.189415) (xy 111.046878 -130.148256) (xy 111.017404 -130.10244) (xy 110.994748 -130.052896)
			(xy 110.979369 -130.000633) (xy 110.971581 -129.946715) (xy 110.971076 -129.919476) (xy 110.971076 -129.918968)
			(xy 110.972092 -129.89306) (xy 110.972092 -129.892806) (xy 110.972165 -129.880091) (xy 110.96151 -129.85704)
			(xy 110.951772 -129.848864) (xy 110.872778 -129.789936) (xy 110.847378 -129.786126) (xy 110.835186 -129.790698)
			(xy 110.802993 -129.801912) (xy 110.735918 -129.814051) (xy 110.701836 -129.814828) (xy 110.674583 -129.814327)
			(xy 110.620631 -129.806575) (xy 110.568331 -129.791223) (xy 110.518749 -129.768583) (xy 110.472894 -129.739118)
			(xy 110.431699 -129.703426) (xy 110.396004 -129.662235) (xy 110.366534 -129.616382) (xy 110.34389 -129.566802)
			(xy 110.328533 -129.514504) (xy 110.320775 -129.460553) (xy 108.975467 -129.460553) (xy 108.969261 -129.474143)
			(xy 108.939799 -129.519992) (xy 108.904112 -129.561182) (xy 108.862926 -129.596874) (xy 108.81708 -129.626341)
			(xy 108.767507 -129.648984) (xy 108.715216 -129.664341) (xy 108.661272 -129.6721) (xy 108.634022 -129.672588)
			(xy 108.606916 -129.672096) (xy 108.553249 -129.664424) (xy 108.501209 -129.649231) (xy 108.451844 -129.626824)
			(xy 108.406149 -129.597653) (xy 108.365043 -129.562308) (xy 108.329356 -129.521498) (xy 108.299806 -129.476047)
			(xy 108.276988 -129.426871) (xy 108.261362 -129.374959) (xy 108.256832 -129.34823) (xy 108.255014 -129.338753)
			(xy 108.245248 -129.322122) (xy 108.230039 -129.310262) (xy 108.211529 -129.304843) (xy 108.192325 -129.306628)
			(xy 108.175132 -129.315366) (xy 108.16844 -129.322322) (xy 108.161675 -129.329954) (xy 108.14744 -129.344565)
			(xy 108.139992 -129.351532) (xy 108.132573 -129.359039) (xy 108.124059 -129.37833) (xy 108.123482 -129.38887)
			(xy 108.123482 -129.463546) (xy 108.124032 -129.474093) (xy 108.132553 -129.493388) (xy 108.139992 -129.500884)
			(xy 108.159031 -129.519056) (xy 108.19249 -129.559682) (xy 108.220052 -129.604519) (xy 108.241193 -129.652716)
			(xy 108.255513 -129.703361) (xy 108.262742 -129.755493) (xy 108.263182 -129.781808) (xy 108.262725 -129.809179)
			(xy 108.254906 -129.863358) (xy 108.239415 -129.915862) (xy 108.216571 -129.965608) (xy 108.186844 -130.011575)
			(xy 108.169202 -130.032506) (xy 108.168948 -130.03276) (xy 108.163366 -130.039849) (xy 108.157118 -130.056764)
			(xy 108.156756 -130.06578) (xy 108.156756 -130.132836) (xy 108.157083 -130.141856) (xy 108.16335 -130.158774)
			(xy 108.168948 -130.165856) (xy 108.169202 -130.165856) (xy 108.169202 -130.16611) (xy 108.186849 -130.187037)
			(xy 108.216572 -130.233006) (xy 108.239415 -130.282754) (xy 108.254909 -130.335257) (xy 108.262736 -130.389435)
			(xy 108.262735 -130.444177) (xy 108.254907 -130.498355) (xy 108.23941 -130.550857) (xy 108.216566 -130.600604)
			(xy 108.186842 -130.646573) (xy 108.169202 -130.667506) (xy 108.168948 -130.66776) (xy 108.163366 -130.674849)
			(xy 108.157118 -130.691764) (xy 108.156756 -130.70078) (xy 108.156756 -130.767836) (xy 108.157083 -130.776856)
			(xy 108.16335 -130.793774) (xy 108.168948 -130.800856) (xy 108.169202 -130.800856) (xy 108.169202 -130.80111)
			(xy 108.18686 -130.822027) (xy 108.216569 -130.868004) (xy 108.239401 -130.917755) (xy 108.254888 -130.970259)
			(xy 108.262711 -131.024438) (xy 108.263182 -131.051808) (xy 108.262696 -131.079059) (xy 108.25494 -131.133007)
			(xy 108.254543 -131.134358) (xy 109.523782 -131.134358) (xy 109.527853 -131.078736) (xy 109.539979 -131.024299)
			(xy 109.559902 -130.972208) (xy 109.587198 -130.923573) (xy 109.621284 -130.87943) (xy 109.661433 -130.840721)
			(xy 109.706791 -130.80827) (xy 109.756391 -130.782769) (xy 109.809175 -130.764762) (xy 109.864018 -130.754632)
			(xy 109.919752 -130.752595) (xy 109.975189 -130.758695) (xy 110.029146 -130.772801) (xy 110.080475 -130.794613)
			(xy 110.128081 -130.823667) (xy 110.170949 -130.859342) (xy 110.208166 -130.900879) (xy 110.238939 -130.947392)
			(xy 110.262611 -130.997889) (xy 110.278679 -131.051296) (xy 110.286799 -131.106472) (xy 110.287308 -131.134358)
			(xy 110.286799 -131.162244) (xy 110.278679 -131.21742) (xy 110.278298 -131.218686) (xy 118.631714 -131.218686)
			(xy 118.635785 -131.163064) (xy 118.647911 -131.108627) (xy 118.667834 -131.056536) (xy 118.69513 -131.007901)
			(xy 118.729216 -130.963758) (xy 118.769365 -130.925049) (xy 118.814723 -130.892598) (xy 118.864323 -130.867097)
			(xy 118.917107 -130.84909) (xy 118.97195 -130.83896) (xy 119.027684 -130.836923) (xy 119.083121 -130.843023)
			(xy 119.137078 -130.857129) (xy 119.188407 -130.878941) (xy 119.236013 -130.907995) (xy 119.278881 -130.94367)
			(xy 119.316098 -130.985207) (xy 119.346871 -131.03172) (xy 119.370543 -131.082217) (xy 119.386611 -131.135624)
			(xy 119.394731 -131.1908) (xy 119.39524 -131.218686) (xy 119.394731 -131.246572) (xy 119.386611 -131.301748)
			(xy 119.370543 -131.355155) (xy 119.346871 -131.405652) (xy 119.316098 -131.452165) (xy 119.278881 -131.493702)
			(xy 119.236013 -131.529377) (xy 119.188407 -131.558431) (xy 119.137078 -131.580243) (xy 119.083121 -131.594349)
			(xy 119.027684 -131.600449) (xy 118.97195 -131.598412) (xy 118.917107 -131.588282) (xy 118.864323 -131.570275)
			(xy 118.814723 -131.544774) (xy 118.769365 -131.512323) (xy 118.729216 -131.473614) (xy 118.69513 -131.429471)
			(xy 118.667834 -131.380836) (xy 118.647911 -131.328745) (xy 118.635785 -131.274308) (xy 118.631714 -131.218686)
			(xy 110.278298 -131.218686) (xy 110.262611 -131.270827) (xy 110.238939 -131.321324) (xy 110.208166 -131.367837)
			(xy 110.170949 -131.409374) (xy 110.128081 -131.445049) (xy 110.080475 -131.474103) (xy 110.029146 -131.495915)
			(xy 109.975189 -131.510021) (xy 109.919752 -131.516121) (xy 109.864018 -131.514084) (xy 109.809175 -131.503954)
			(xy 109.756391 -131.485947) (xy 109.706791 -131.460446) (xy 109.661433 -131.427995) (xy 109.621284 -131.389286)
			(xy 109.587198 -131.345143) (xy 109.559902 -131.296508) (xy 109.539979 -131.244417) (xy 109.527853 -131.18998)
			(xy 109.523782 -131.134358) (xy 108.254543 -131.134358) (xy 108.239585 -131.185302) (xy 108.216943 -131.234879)
			(xy 108.187477 -131.280729) (xy 108.151786 -131.32192) (xy 108.110595 -131.357611) (xy 108.064745 -131.387077)
			(xy 108.015168 -131.409719) (xy 107.962873 -131.425074) (xy 107.908925 -131.43283) (xy 107.854423 -131.43283)
			(xy 107.800475 -131.425074) (xy 107.74818 -131.409719) (xy 107.698603 -131.387077) (xy 107.652753 -131.357611)
			(xy 107.611562 -131.32192) (xy 107.575871 -131.280729) (xy 107.546405 -131.234879) (xy 107.523763 -131.185302)
			(xy 107.508408 -131.133007) (xy 107.500652 -131.079059) (xy 107.500166 -131.051808) (xy 105.602208 -131.051808)
			(xy 105.599116 -131.073317) (xy 105.583761 -131.125612) (xy 105.561119 -131.175189) (xy 105.531653 -131.221039)
			(xy 105.495962 -131.26223) (xy 105.454771 -131.297921) (xy 105.408921 -131.327387) (xy 105.359344 -131.350029)
			(xy 105.307049 -131.365384) (xy 105.253101 -131.37314) (xy 105.198599 -131.37314) (xy 105.144651 -131.365384)
			(xy 105.092356 -131.350029) (xy 105.042779 -131.327387) (xy 104.996929 -131.297921) (xy 104.955738 -131.26223)
			(xy 104.920047 -131.221039) (xy 104.890581 -131.175189) (xy 104.867939 -131.125612) (xy 104.852584 -131.073317)
			(xy 104.844828 -131.019369) (xy 104.844342 -130.992118) (xy 82.54724 -130.992118) (xy 82.54724 -130.993952)
			(xy 82.539483 -131.047902) (xy 82.524128 -131.100199) (xy 82.501486 -131.149778) (xy 82.472019 -131.19563)
			(xy 82.436326 -131.236822) (xy 82.395135 -131.272515) (xy 82.349283 -131.301983) (xy 82.299704 -131.324626)
			(xy 82.247408 -131.339982) (xy 82.193458 -131.34774) (xy 82.166206 -131.348226) (xy 82.140298 -131.347796)
			(xy 82.08896 -131.340761) (xy 82.039046 -131.326846) (xy 81.991473 -131.306307) (xy 81.947116 -131.279522)
			(xy 81.906789 -131.246982) (xy 81.871235 -131.209287) (xy 81.855818 -131.18846) (xy 81.850072 -131.181134)
			(xy 81.834574 -131.170845) (xy 81.825592 -131.168394) (xy 81.795112 -131.161536) (xy 81.785838 -131.159771)
			(xy 81.767172 -131.162524) (xy 81.75879 -131.16687) (xy 81.732813 -131.181163) (xy 81.677962 -131.203675)
			(xy 81.620659 -131.218902) (xy 81.561868 -131.226588) (xy 81.532222 -131.227068) (xy 81.502579 -131.226566)
			(xy 81.443798 -131.218845) (xy 81.3865 -131.20362) (xy 81.331639 -131.181143) (xy 81.305654 -131.16687)
			(xy 81.297233 -131.162642) (xy 81.27861 -131.159896) (xy 81.269332 -131.161536) (xy 81.238852 -131.168394)
			(xy 81.229861 -131.170827) (xy 81.214355 -131.181117) (xy 81.208626 -131.18846) (xy 81.193236 -131.20931)
			(xy 81.157689 -131.247019) (xy 81.117363 -131.279567) (xy 81.073001 -131.306354) (xy 81.025419 -131.326886)
			(xy 80.975495 -131.340785) (xy 80.924149 -131.347795) (xy 80.898238 -131.348226) (xy 80.870985 -131.347729)
			(xy 80.817032 -131.339977) (xy 80.764732 -131.324625) (xy 80.71515 -131.301986) (xy 80.669294 -131.27252)
			(xy 80.628099 -131.236828) (xy 80.592403 -131.195637) (xy 80.562932 -131.149784) (xy 80.540288 -131.100203)
			(xy 80.524931 -131.047905) (xy 80.517173 -130.993953) (xy 80.517173 -130.939447) (xy 80.524931 -130.885495)
			(xy 80.540288 -130.833197) (xy 80.562932 -130.783616) (xy 80.592403 -130.737763) (xy 80.628099 -130.696572)
			(xy 80.669294 -130.66088) (xy 80.71515 -130.631414) (xy 80.764732 -130.608775) (xy 80.817032 -130.593423)
			(xy 80.870985 -130.585671) (xy 80.898238 -130.58521) (xy 80.913031 -130.585351) (xy 80.942529 -130.587636)
			(xy 80.957166 -130.589782) (xy 80.968141 -130.590884) (xy 80.989331 -130.58484) (xy 80.99806 -130.578098)
			(xy 81.05648 -130.52806) (xy 81.064487 -130.520474) (xy 81.073711 -130.500467) (xy 81.07426 -130.489452)
			(xy 81.07426 -130.18516) (xy 81.073757 -130.174136) (xy 81.064514 -130.15412) (xy 81.05648 -130.146552)
			(xy 80.989424 -130.089148) (xy 80.968342 -130.083052) (xy 80.957166 -130.08483) (xy 80.942528 -130.08697)
			(xy 80.913031 -130.089258) (xy 80.898238 -130.089402) (xy 80.870983 -130.088953) (xy 80.817027 -130.081201)
			(xy 80.764724 -130.065848) (xy 80.715138 -130.043207) (xy 80.66928 -130.013739) (xy 80.628082 -129.978045)
			(xy 80.592383 -129.936851) (xy 80.562911 -129.890995) (xy 80.540266 -129.841412) (xy 80.524908 -129.78911)
			(xy 80.517149 -129.735155) (xy 74.495226 -129.735155) (xy 74.470545 -129.755695) (xy 74.422939 -129.784749)
			(xy 74.37161 -129.806561) (xy 74.317653 -129.820667) (xy 74.262216 -129.826767) (xy 74.206482 -129.82473)
			(xy 74.151639 -129.8146) (xy 74.098855 -129.796593) (xy 74.049255 -129.771092) (xy 74.003897 -129.738641)
			(xy 73.963748 -129.699932) (xy 73.929662 -129.655789) (xy 73.902366 -129.607154) (xy 73.882443 -129.555063)
			(xy 73.870317 -129.500626) (xy 73.866246 -129.445004) (xy 72.648572 -129.445004) (xy 72.648063 -129.47289)
			(xy 72.639943 -129.528066) (xy 72.623875 -129.581473) (xy 72.600203 -129.63197) (xy 72.56943 -129.678483)
			(xy 72.532213 -129.72002) (xy 72.489345 -129.755695) (xy 72.441739 -129.784749) (xy 72.39041 -129.806561)
			(xy 72.336453 -129.820667) (xy 72.281016 -129.826767) (xy 72.225282 -129.82473) (xy 72.170439 -129.8146)
			(xy 72.117655 -129.796593) (xy 72.068055 -129.771092) (xy 72.022697 -129.738641) (xy 71.982548 -129.699932)
			(xy 71.948462 -129.655789) (xy 71.921166 -129.607154) (xy 71.901243 -129.555063) (xy 71.889117 -129.500626)
			(xy 71.885046 -129.445004) (xy 70.029578 -129.445004) (xy 70.029069 -129.47289) (xy 70.020949 -129.528066)
			(xy 70.004881 -129.581473) (xy 69.981209 -129.63197) (xy 69.950436 -129.678483) (xy 69.913219 -129.72002)
			(xy 69.870351 -129.755695) (xy 69.822745 -129.784749) (xy 69.771416 -129.806561) (xy 69.717459 -129.820667)
			(xy 69.662022 -129.826767) (xy 69.606288 -129.82473) (xy 69.551445 -129.8146) (xy 69.498661 -129.796593)
			(xy 69.449061 -129.771092) (xy 69.403703 -129.738641) (xy 69.363554 -129.699932) (xy 69.329468 -129.655789)
			(xy 69.302172 -129.607154) (xy 69.282249 -129.555063) (xy 69.270123 -129.500626) (xy 69.266052 -129.445004)
			(xy 68.047941 -129.445004) (xy 68.047941 -129.472254) (xy 68.040183 -129.526207) (xy 68.024826 -129.578507)
			(xy 68.002181 -129.628088) (xy 67.972711 -129.673942) (xy 67.937014 -129.715135) (xy 67.895818 -129.750829)
			(xy 67.849962 -129.780295) (xy 67.800378 -129.802936) (xy 67.748078 -129.818289) (xy 67.694124 -129.826043)
			(xy 67.66687 -129.826512) (xy 67.649821 -129.826328) (xy 67.615861 -129.823272) (xy 67.599052 -129.820416)
			(xy 67.587713 -129.818802) (xy 67.565616 -129.824741) (xy 67.556634 -129.831846) (xy 67.53225 -129.852928)
			(xy 67.523882 -129.860945) (xy 67.51478 -129.882232) (xy 67.514724 -129.893822) (xy 67.515232 -129.913634)
			(xy 67.515232 -130.710432) (xy 69.442074 -130.710432) (xy 69.446145 -130.65481) (xy 69.458271 -130.600373)
			(xy 69.478194 -130.548282) (xy 69.50549 -130.499647) (xy 69.539576 -130.455504) (xy 69.579725 -130.416795)
			(xy 69.625083 -130.384344) (xy 69.674683 -130.358843) (xy 69.727467 -130.340836) (xy 69.78231 -130.330706)
			(xy 69.838044 -130.328669) (xy 69.893481 -130.334769) (xy 69.947438 -130.348875) (xy 69.998767 -130.370687)
			(xy 70.046373 -130.399741) (xy 70.089241 -130.435416) (xy 70.126458 -130.476953) (xy 70.157231 -130.523466)
			(xy 70.180903 -130.573963) (xy 70.196971 -130.62737) (xy 70.205091 -130.682546) (xy 70.2056 -130.710432)
			(xy 70.205091 -130.738318) (xy 70.196971 -130.793494) (xy 70.180903 -130.846901) (xy 70.157231 -130.897398)
			(xy 70.126458 -130.943911) (xy 70.089241 -130.985448) (xy 70.046373 -131.021123) (xy 69.998767 -131.050177)
			(xy 69.947438 -131.071989) (xy 69.893481 -131.086095) (xy 69.838044 -131.092195) (xy 69.78231 -131.090158)
			(xy 69.727467 -131.080028) (xy 69.674683 -131.062021) (xy 69.625083 -131.03652) (xy 69.579725 -131.004069)
			(xy 69.539576 -130.96536) (xy 69.50549 -130.921217) (xy 69.478194 -130.872582) (xy 69.458271 -130.820491)
			(xy 69.446145 -130.766054) (xy 69.442074 -130.710432) (xy 67.515232 -130.710432) (xy 67.515232 -130.777234)
			(xy 67.514724 -130.796284) (xy 67.514696 -130.807889) (xy 67.523827 -130.829196) (xy 67.53225 -130.837178)
			(xy 67.556634 -130.858006) (xy 67.56562 -130.864971) (xy 67.587505 -130.871022) (xy 67.598798 -130.86969)
			(xy 67.615671 -130.866839) (xy 67.649758 -130.86379) (xy 67.66687 -130.863594) (xy 67.694124 -130.864055)
			(xy 67.748078 -130.871809) (xy 67.800379 -130.887162) (xy 67.849963 -130.909803) (xy 67.895819 -130.93927)
			(xy 67.937015 -130.974963) (xy 67.972712 -131.016157) (xy 68.002183 -131.062011) (xy 68.024827 -131.111593)
			(xy 68.040185 -131.163893) (xy 68.047943 -131.217846) (xy 68.047943 -131.245102) (xy 71.885046 -131.245102)
			(xy 71.889117 -131.18948) (xy 71.901243 -131.135043) (xy 71.921166 -131.082952) (xy 71.948462 -131.034317)
			(xy 71.982548 -130.990174) (xy 72.022697 -130.951465) (xy 72.068055 -130.919014) (xy 72.117655 -130.893513)
			(xy 72.170439 -130.875506) (xy 72.225282 -130.865376) (xy 72.281016 -130.863339) (xy 72.336453 -130.869439)
			(xy 72.39041 -130.883545) (xy 72.441739 -130.905357) (xy 72.489345 -130.934411) (xy 72.532213 -130.970086)
			(xy 72.56943 -131.011623) (xy 72.600203 -131.058136) (xy 72.623875 -131.108633) (xy 72.639943 -131.16204)
			(xy 72.648063 -131.217216) (xy 72.648572 -131.245102) (xy 73.866246 -131.245102) (xy 73.870317 -131.18948)
			(xy 73.882443 -131.135043) (xy 73.902366 -131.082952) (xy 73.929662 -131.034317) (xy 73.963748 -130.990174)
			(xy 74.003897 -130.951465) (xy 74.049255 -130.919014) (xy 74.098855 -130.893513) (xy 74.151639 -130.875506)
			(xy 74.206482 -130.865376) (xy 74.262216 -130.863339) (xy 74.317653 -130.869439) (xy 74.37161 -130.883545)
			(xy 74.422939 -130.905357) (xy 74.470545 -130.934411) (xy 74.513413 -130.970086) (xy 74.55063 -131.011623)
			(xy 74.581403 -131.058136) (xy 74.605075 -131.108633) (xy 74.621143 -131.16204) (xy 74.629263 -131.217216)
			(xy 74.629772 -131.245102) (xy 74.629263 -131.272988) (xy 74.621143 -131.328164) (xy 74.605075 -131.381571)
			(xy 74.581403 -131.432068) (xy 74.55063 -131.478581) (xy 74.513413 -131.520118) (xy 74.470545 -131.555793)
			(xy 74.422939 -131.584847) (xy 74.37161 -131.606659) (xy 74.317653 -131.620765) (xy 74.262216 -131.626865)
			(xy 74.206482 -131.624828) (xy 74.151639 -131.614698) (xy 74.098855 -131.596691) (xy 74.049255 -131.57119)
			(xy 74.003897 -131.538739) (xy 73.963748 -131.50003) (xy 73.929662 -131.455887) (xy 73.902366 -131.407252)
			(xy 73.882443 -131.355161) (xy 73.870317 -131.300724) (xy 73.866246 -131.245102) (xy 72.648572 -131.245102)
			(xy 72.648063 -131.272988) (xy 72.639943 -131.328164) (xy 72.623875 -131.381571) (xy 72.600203 -131.432068)
			(xy 72.56943 -131.478581) (xy 72.532213 -131.520118) (xy 72.489345 -131.555793) (xy 72.441739 -131.584847)
			(xy 72.39041 -131.606659) (xy 72.336453 -131.620765) (xy 72.281016 -131.626865) (xy 72.225282 -131.624828)
			(xy 72.170439 -131.614698) (xy 72.117655 -131.596691) (xy 72.068055 -131.57119) (xy 72.022697 -131.538739)
			(xy 71.982548 -131.50003) (xy 71.948462 -131.455887) (xy 71.921166 -131.407252) (xy 71.901243 -131.355161)
			(xy 71.889117 -131.300724) (xy 71.885046 -131.245102) (xy 68.047943 -131.245102) (xy 68.047943 -131.272354)
			(xy 68.040185 -131.326307) (xy 68.024827 -131.378607) (xy 68.002183 -131.428189) (xy 67.972712 -131.474043)
			(xy 67.937015 -131.515237) (xy 67.895819 -131.55093) (xy 67.849963 -131.580397) (xy 67.800379 -131.603038)
			(xy 67.748078 -131.618391) (xy 67.694124 -131.626145) (xy 67.66687 -131.62661) (xy 67.639896 -131.626141)
			(xy 67.586486 -131.618535) (xy 67.534681 -131.603478) (xy 67.485514 -131.581272) (xy 67.439967 -131.552359)
			(xy 67.398949 -131.517317) (xy 67.363278 -131.476844) (xy 67.333666 -131.431749) (xy 67.310704 -131.382931)
			(xy 67.29485 -131.331364) (xy 67.290188 -131.304792) (xy 67.28841 -131.294124) (xy 67.277234 -131.276598)
			(xy 67.19697 -131.223258) (xy 67.175888 -131.219448) (xy 67.165728 -131.221988) (xy 67.139034 -131.22813)
			(xy 67.084658 -131.234749) (xy 67.05727 -131.235196) (xy 67.029882 -131.234747) (xy 66.975508 -131.228121)
			(xy 66.948812 -131.221988) (xy 66.938652 -131.219448) (xy 66.91757 -131.223258) (xy 66.846196 -131.270756)
			(xy 66.837799 -131.276985) (xy 66.826525 -131.294565) (xy 66.824352 -131.304792) (xy 66.819693 -131.331371)
			(xy 66.803867 -131.382959) (xy 66.780923 -131.431799) (xy 66.751321 -131.476916) (xy 66.715653 -131.517407)
			(xy 66.67463 -131.552463) (xy 66.629074 -131.581384) (xy 66.579895 -131.603591) (xy 66.528075 -131.618641)
			(xy 66.474651 -131.626233) (xy 66.44767 -131.62661) (xy 66.420301 -131.626136) (xy 66.366124 -131.618309)
			(xy 66.313623 -131.602819) (xy 66.263874 -131.579984) (xy 66.2179 -131.550274) (xy 66.196972 -131.53263)
			(xy 66.196718 -131.53263) (xy 66.196718 -131.532376) (xy 66.189631 -131.52679) (xy 66.172714 -131.520546)
			(xy 66.163698 -131.520184) (xy 66.096642 -131.520184) (xy 66.087623 -131.520536) (xy 66.070696 -131.526771)
			(xy 66.063622 -131.532376) (xy 66.063368 -131.53263) (xy 66.042435 -131.550269) (xy 65.996468 -131.579989)
			(xy 65.94672 -131.602826) (xy 65.894218 -131.618311) (xy 65.840039 -131.626124) (xy 65.81267 -131.62661)
			(xy 65.795621 -131.626426) (xy 65.761661 -131.62337) (xy 65.744852 -131.620514) (xy 65.733513 -131.6189)
			(xy 65.711416 -131.624839) (xy 65.702434 -131.631944) (xy 65.67805 -131.653026) (xy 65.669682 -131.661043)
			(xy 65.660579 -131.68233) (xy 65.660524 -131.69392) (xy 65.661032 -131.713732) (xy 65.661032 -132.577332)
			(xy 65.660524 -132.596382) (xy 65.660496 -132.607987) (xy 65.669626 -132.629295) (xy 65.67805 -132.637276)
			(xy 65.702434 -132.658104) (xy 65.71142 -132.665069) (xy 65.733305 -132.671121) (xy 65.744598 -132.669788)
			(xy 65.761471 -132.666937) (xy 65.795558 -132.663888) (xy 65.81267 -132.663692) (xy 65.840388 -132.664167)
			(xy 65.895246 -132.672153) (xy 65.948368 -132.688005) (xy 65.973706 -132.699252) (xy 65.983866 -132.704078)
			(xy 66.276474 -132.704078) (xy 66.286634 -132.699252) (xy 66.311979 -132.688022) (xy 66.3651 -132.672175)
			(xy 66.419953 -132.664173) (xy 66.44767 -132.663692) (xy 66.475388 -132.664167) (xy 66.530246 -132.672153)
			(xy 66.583368 -132.688005) (xy 66.608706 -132.699252) (xy 66.618866 -132.704078) (xy 67.495166 -132.704078)
			(xy 67.505326 -132.699252) (xy 67.530742 -132.687951) (xy 67.584026 -132.671995) (xy 67.639059 -132.66393)
			(xy 67.66687 -132.663438) (xy 67.694682 -132.663921) (xy 67.749721 -132.671966) (xy 67.803004 -132.687935)
			(xy 67.828414 -132.699252) (xy 67.838574 -132.704078) (xy 69.32168 -132.704078) (xy 69.331404 -132.7036)
			(xy 69.349434 -132.696296) (xy 69.356732 -132.689854) (xy 69.407532 -132.64134) (xy 69.414274 -132.634217)
			(xy 69.422245 -132.616318) (xy 69.423026 -132.606542) (xy 69.424658 -132.57877) (xy 69.434965 -132.524101)
			(xy 69.453102 -132.471509) (xy 69.478683 -132.422108) (xy 69.511168 -132.376945) (xy 69.549866 -132.336978)
			(xy 69.593957 -132.303055) (xy 69.642508 -132.275894) (xy 69.694488 -132.256071) (xy 69.748796 -132.244007)
			(xy 69.80428 -132.239957) (xy 69.859764 -132.244007) (xy 69.914072 -132.256071) (xy 69.966052 -132.275894)
			(xy 70.014603 -132.303055) (xy 70.058694 -132.336978) (xy 70.097392 -132.376945) (xy 70.129877 -132.422108)
			(xy 70.155458 -132.471509) (xy 70.173595 -132.524101) (xy 70.183902 -132.57877) (xy 70.185534 -132.606542)
			(xy 70.186314 -132.616321) (xy 70.194268 -132.634233) (xy 70.201028 -132.64134) (xy 70.251828 -132.689854)
			(xy 70.259125 -132.696302) (xy 70.277153 -132.703621) (xy 70.28688 -132.704078) (xy 74.07656 -132.704078)
			(xy 74.08672 -132.699252) (xy 74.112136 -132.68795) (xy 74.16542 -132.671994) (xy 74.220453 -132.663928)
			(xy 74.248264 -132.663438) (xy 74.276076 -132.66392) (xy 74.331116 -132.671965) (xy 74.384399 -132.687933)
			(xy 74.409808 -132.699252) (xy 74.419968 -132.704078) (xy 83.125056 -132.704078) (xy 83.136013 -132.70356)
			(xy 83.155944 -132.694456) (xy 83.170277 -132.67788) (xy 83.173824 -132.667502) (xy 83.181866 -132.641364)
			(xy 83.204395 -132.591532) (xy 83.233808 -132.545428) (xy 83.269504 -132.503997) (xy 83.31075 -132.468088)
			(xy 83.356701 -132.438438) (xy 83.406416 -132.415652) (xy 83.458875 -132.4002) (xy 83.513002 -132.392397)
			(xy 83.540346 -132.391912) (xy 83.555139 -132.392056) (xy 83.584636 -132.394345) (xy 83.599274 -132.396484)
			(xy 83.61045 -132.398262) (xy 83.631532 -132.392166) (xy 83.698588 -132.334762) (xy 83.706607 -132.327189)
			(xy 83.715815 -132.307171) (xy 83.716368 -132.296154) (xy 83.716368 -131.991862) (xy 83.715819 -131.980848)
			(xy 83.706587 -131.960848) (xy 83.698588 -131.953254) (xy 83.640168 -131.903216) (xy 83.63144 -131.896471)
			(xy 83.610249 -131.890422) (xy 83.599274 -131.891532) (xy 83.584637 -131.893678) (xy 83.555139 -131.895964)
			(xy 83.540346 -131.896104) (xy 83.513091 -131.895644) (xy 83.459136 -131.887892) (xy 83.406833 -131.87254)
			(xy 83.357248 -131.849901) (xy 83.311389 -131.820434) (xy 83.270192 -131.784741) (xy 83.234493 -131.743548)
			(xy 83.205021 -131.697693) (xy 83.182376 -131.64811) (xy 83.167018 -131.595809) (xy 83.159259 -131.541855)
			(xy 83.159259 -131.487345) (xy 83.167018 -131.433391) (xy 83.182376 -131.38109) (xy 83.205021 -131.331507)
			(xy 83.234493 -131.285652) (xy 83.270192 -131.244459) (xy 83.311389 -131.208766) (xy 83.357248 -131.179299)
			(xy 83.406833 -131.15666) (xy 83.459136 -131.141308) (xy 83.513091 -131.133556) (xy 83.540346 -131.133088)
			(xy 83.566257 -131.133519) (xy 83.617602 -131.14053) (xy 83.667525 -131.15443) (xy 83.715105 -131.174964)
			(xy 83.759466 -131.201752) (xy 83.79979 -131.234301) (xy 83.835335 -131.272011) (xy 83.850734 -131.292854)
			(xy 83.856465 -131.300195) (xy 83.871972 -131.310479) (xy 83.88096 -131.31292) (xy 83.91144 -131.319778)
			(xy 83.920718 -131.321417) (xy 83.93934 -131.318669) (xy 83.947762 -131.314444) (xy 83.973749 -131.300189)
			(xy 84.028614 -131.277757) (xy 84.085915 -131.26259) (xy 84.144693 -131.254943) (xy 84.203967 -131.254943)
			(xy 84.262745 -131.26259) (xy 84.320046 -131.277757) (xy 84.374911 -131.300189) (xy 84.400898 -131.314444)
			(xy 84.409279 -131.318794) (xy 84.427946 -131.321549) (xy 84.43722 -131.319778) (xy 84.4677 -131.31292)
			(xy 84.476682 -131.310469) (xy 84.49218 -131.30018) (xy 84.497926 -131.292854) (xy 84.513342 -131.272027)
			(xy 84.548896 -131.234331) (xy 84.589223 -131.201791) (xy 84.63358 -131.175006) (xy 84.681154 -131.154467)
			(xy 84.731068 -131.140553) (xy 84.782405 -131.133518) (xy 84.808314 -131.133088) (xy 84.835565 -131.133575)
			(xy 84.889512 -131.141333) (xy 84.941805 -131.156689) (xy 84.991381 -131.179332) (xy 85.03723 -131.208799)
			(xy 85.078419 -131.244491) (xy 85.11411 -131.285681) (xy 85.143575 -131.331531) (xy 85.166215 -131.381108)
			(xy 85.18157 -131.433402) (xy 85.189326 -131.487349) (xy 85.189326 -131.541851) (xy 85.186671 -131.560316)
			(xy 94.487998 -131.560316) (xy 94.492069 -131.504694) (xy 94.504195 -131.450257) (xy 94.524118 -131.398166)
			(xy 94.551414 -131.349531) (xy 94.5855 -131.305388) (xy 94.625649 -131.266679) (xy 94.671007 -131.234228)
			(xy 94.720607 -131.208727) (xy 94.773391 -131.19072) (xy 94.828234 -131.18059) (xy 94.883968 -131.178553)
			(xy 94.939405 -131.184653) (xy 94.993362 -131.198759) (xy 95.044691 -131.220571) (xy 95.092297 -131.249625)
			(xy 95.135165 -131.2853) (xy 95.172382 -131.326837) (xy 95.203155 -131.37335) (xy 95.226827 -131.423847)
			(xy 95.242895 -131.477254) (xy 95.251015 -131.53243) (xy 95.251524 -131.560316) (xy 95.251015 -131.588202)
			(xy 95.242895 -131.643378) (xy 95.226827 -131.696785) (xy 95.218168 -131.715256) (xy 95.345756 -131.715256)
			(xy 95.349827 -131.659634) (xy 95.361953 -131.605197) (xy 95.381876 -131.553106) (xy 95.409172 -131.504471)
			(xy 95.443258 -131.460328) (xy 95.483407 -131.421619) (xy 95.528765 -131.389168) (xy 95.578365 -131.363667)
			(xy 95.631149 -131.34566) (xy 95.685992 -131.33553) (xy 95.741726 -131.333493) (xy 95.797163 -131.339593)
			(xy 95.85112 -131.353699) (xy 95.902449 -131.375511) (xy 95.950055 -131.404565) (xy 95.992923 -131.44024)
			(xy 96.03014 -131.481777) (xy 96.060913 -131.52829) (xy 96.084585 -131.578787) (xy 96.100653 -131.632194)
			(xy 96.108773 -131.68737) (xy 96.109282 -131.715256) (xy 96.108773 -131.743142) (xy 96.100653 -131.798318)
			(xy 96.084585 -131.851725) (xy 96.060913 -131.902222) (xy 96.03014 -131.948735) (xy 95.992923 -131.990272)
			(xy 95.950055 -132.025947) (xy 95.942192 -132.030746) (xy 112.909424 -132.030746) (xy 112.909424 -131.976254)
			(xy 112.917178 -131.922318) (xy 112.932529 -131.870033) (xy 112.955164 -131.820465) (xy 112.984622 -131.774623)
			(xy 113.020304 -131.733439) (xy 113.061483 -131.697752) (xy 113.107321 -131.668288) (xy 113.156886 -131.645647)
			(xy 113.209169 -131.630289) (xy 113.263104 -131.622528) (xy 113.29035 -131.622038) (xy 113.31772 -131.622524)
			(xy 113.371898 -131.630336) (xy 113.424401 -131.64582) (xy 113.474149 -131.668657) (xy 113.520116 -131.698378)
			(xy 113.541048 -131.716018) (xy 113.541302 -131.716272) (xy 113.548378 -131.721874) (xy 113.565303 -131.728109)
			(xy 113.574322 -131.728464) (xy 113.641378 -131.728464) (xy 113.650395 -131.728104) (xy 113.667312 -131.721859)
			(xy 113.674398 -131.716272) (xy 113.674398 -131.716018) (xy 113.674652 -131.716018) (xy 113.695594 -131.698391)
			(xy 113.741564 -131.668677) (xy 113.791309 -131.645838) (xy 113.843807 -131.630344) (xy 113.897981 -131.622513)
			(xy 113.92535 -131.622038) (xy 113.952608 -131.622406) (xy 114.006571 -131.630158) (xy 114.058882 -131.645511)
			(xy 114.108474 -131.668154) (xy 114.154339 -131.697624) (xy 114.195543 -131.733322) (xy 114.231246 -131.774521)
			(xy 114.260722 -131.820382) (xy 114.283371 -131.869971) (xy 114.298732 -131.92228) (xy 114.306491 -131.976242)
			(xy 114.306491 -132.030758) (xy 114.298732 -132.08472) (xy 114.283371 -132.137029) (xy 114.260722 -132.186618)
			(xy 114.231246 -132.232479) (xy 114.195543 -132.273678) (xy 114.154339 -132.309376) (xy 114.108474 -132.338846)
			(xy 114.058882 -132.361489) (xy 114.006571 -132.376842) (xy 113.952609 -132.384594) (xy 113.92535 -132.385054)
			(xy 113.89798 -132.38457) (xy 113.843802 -132.376758) (xy 113.791298 -132.361274) (xy 113.741551 -132.338436)
			(xy 113.695584 -132.308714) (xy 113.674652 -132.291074) (xy 113.674398 -132.29082) (xy 113.667323 -132.285217)
			(xy 113.650397 -132.278982) (xy 113.641378 -132.278628) (xy 113.574322 -132.278628) (xy 113.565305 -132.27899)
			(xy 113.548388 -132.285233) (xy 113.541302 -132.29082) (xy 113.541302 -132.291074) (xy 113.541048 -132.291074)
			(xy 113.520105 -132.3087) (xy 113.474136 -132.338415) (xy 113.424391 -132.361254) (xy 113.371893 -132.376748)
			(xy 113.317719 -132.384579) (xy 113.29035 -132.385054) (xy 113.263104 -132.384472) (xy 113.209169 -132.376711)
			(xy 113.156886 -132.361353) (xy 113.107321 -132.338712) (xy 113.061483 -132.309248) (xy 113.020304 -132.273561)
			(xy 112.984622 -132.232377) (xy 112.955164 -132.186535) (xy 112.932529 -132.136967) (xy 112.917178 -132.084682)
			(xy 112.909424 -132.030746) (xy 95.942192 -132.030746) (xy 95.902449 -132.055001) (xy 95.85112 -132.076813)
			(xy 95.797163 -132.090919) (xy 95.741726 -132.097019) (xy 95.685992 -132.094982) (xy 95.631149 -132.084852)
			(xy 95.578365 -132.066845) (xy 95.528765 -132.041344) (xy 95.483407 -132.008893) (xy 95.443258 -131.970184)
			(xy 95.409172 -131.926041) (xy 95.381876 -131.877406) (xy 95.361953 -131.825315) (xy 95.349827 -131.770878)
			(xy 95.345756 -131.715256) (xy 95.218168 -131.715256) (xy 95.203155 -131.747282) (xy 95.172382 -131.793795)
			(xy 95.135165 -131.835332) (xy 95.092297 -131.871007) (xy 95.044691 -131.900061) (xy 94.993362 -131.921873)
			(xy 94.939405 -131.935979) (xy 94.883968 -131.942079) (xy 94.828234 -131.940042) (xy 94.773391 -131.929912)
			(xy 94.720607 -131.911905) (xy 94.671007 -131.886404) (xy 94.625649 -131.853953) (xy 94.5855 -131.815244)
			(xy 94.551414 -131.771101) (xy 94.524118 -131.722466) (xy 94.504195 -131.670375) (xy 94.492069 -131.615938)
			(xy 94.487998 -131.560316) (xy 85.186671 -131.560316) (xy 85.18157 -131.595798) (xy 85.166215 -131.648092)
			(xy 85.143575 -131.697669) (xy 85.11411 -131.743519) (xy 85.078419 -131.784709) (xy 85.03723 -131.820401)
			(xy 84.991381 -131.849868) (xy 84.941805 -131.872511) (xy 84.889512 -131.887867) (xy 84.835565 -131.895625)
			(xy 84.808314 -131.896104) (xy 84.793521 -131.895962) (xy 84.764023 -131.893678) (xy 84.749386 -131.891532)
			(xy 84.73821 -131.889754) (xy 84.717128 -131.89585) (xy 84.650072 -131.953254) (xy 84.642044 -131.960825)
			(xy 84.632812 -131.980841) (xy 84.632292 -131.991862) (xy 84.632292 -132.296154) (xy 84.632823 -132.307177)
			(xy 84.642029 -132.327208) (xy 84.650072 -132.334762) (xy 84.708492 -132.3848) (xy 84.717219 -132.391551)
			(xy 84.738411 -132.397614) (xy 84.749386 -132.396484) (xy 84.764023 -132.394336) (xy 84.793521 -132.392047)
			(xy 84.808314 -132.391912) (xy 84.835657 -132.392383) (xy 84.889781 -132.400193) (xy 84.942236 -132.415652)
			(xy 84.991946 -132.438442) (xy 85.037892 -132.468097) (xy 85.079133 -132.504008) (xy 85.114824 -132.54544)
			(xy 85.144233 -132.591544) (xy 85.166758 -132.641375) (xy 85.174836 -132.667502) (xy 85.179662 -132.683758)
			(xy 85.206586 -132.704078) (xy 119.810022 -132.704078) (xy 119.820091 -132.704504) (xy 119.838692 -132.712222)
			(xy 119.84609 -132.719064) (xy 120.464834 -133.337808) (xy 120.471686 -133.345204) (xy 120.479428 -133.363803)
			(xy 120.47982 -133.373876) (xy 120.47982 -134.042404) (xy 122.275852 -134.042404) (xy 122.279923 -133.986782)
			(xy 122.292049 -133.932345) (xy 122.311972 -133.880254) (xy 122.339268 -133.831619) (xy 122.373354 -133.787476)
			(xy 122.413503 -133.748767) (xy 122.458861 -133.716316) (xy 122.508461 -133.690815) (xy 122.561245 -133.672808)
			(xy 122.616088 -133.662678) (xy 122.671822 -133.660641) (xy 122.727259 -133.666741) (xy 122.781216 -133.680847)
			(xy 122.832545 -133.702659) (xy 122.880151 -133.731713) (xy 122.923019 -133.767388) (xy 122.960236 -133.808925)
			(xy 122.991009 -133.855438) (xy 123.014681 -133.905935) (xy 123.030749 -133.959342) (xy 123.038869 -134.014518)
			(xy 123.039378 -134.042404) (xy 123.038869 -134.07029) (xy 123.030749 -134.125466) (xy 123.014681 -134.178873)
			(xy 122.991009 -134.22937) (xy 122.960236 -134.275883) (xy 122.923019 -134.31742) (xy 122.880151 -134.353095)
			(xy 122.832545 -134.382149) (xy 122.781216 -134.403961) (xy 122.727259 -134.418067) (xy 122.671822 -134.424167)
			(xy 122.616088 -134.42213) (xy 122.561245 -134.412) (xy 122.508461 -134.393993) (xy 122.458861 -134.368492)
			(xy 122.413503 -134.336041) (xy 122.373354 -134.297332) (xy 122.339268 -134.253189) (xy 122.311972 -134.204554)
			(xy 122.292049 -134.152463) (xy 122.279923 -134.098026) (xy 122.275852 -134.042404) (xy 120.47982 -134.042404)
			(xy 120.47982 -134.668514) (xy 120.480074 -134.673848) (xy 120.481266 -134.682027) (xy 120.48814 -134.69705)
			(xy 120.493536 -134.703312) (xy 120.494552 -134.704328) (xy 120.848749 -135.058404) (xy 122.275852 -135.058404)
			(xy 122.279923 -135.002782) (xy 122.292049 -134.948345) (xy 122.311972 -134.896254) (xy 122.339268 -134.847619)
			(xy 122.373354 -134.803476) (xy 122.413503 -134.764767) (xy 122.458861 -134.732316) (xy 122.508461 -134.706815)
			(xy 122.561245 -134.688808) (xy 122.616088 -134.678678) (xy 122.671822 -134.676641) (xy 122.727259 -134.682741)
			(xy 122.781216 -134.696847) (xy 122.832545 -134.718659) (xy 122.880151 -134.747713) (xy 122.923019 -134.783388)
			(xy 122.960236 -134.824925) (xy 122.991009 -134.871438) (xy 123.014681 -134.921935) (xy 123.030749 -134.975342)
			(xy 123.038869 -135.030518) (xy 123.039378 -135.058404) (xy 123.038869 -135.08629) (xy 123.030749 -135.141466)
			(xy 123.014681 -135.194873) (xy 122.991009 -135.24537) (xy 122.960236 -135.291883) (xy 122.923019 -135.33342)
			(xy 122.880151 -135.369095) (xy 122.832545 -135.398149) (xy 122.781216 -135.419961) (xy 122.727259 -135.434067)
			(xy 122.671822 -135.440167) (xy 122.616088 -135.43813) (xy 122.561245 -135.428) (xy 122.508461 -135.409993)
			(xy 122.458861 -135.384492) (xy 122.413503 -135.352041) (xy 122.373354 -135.313332) (xy 122.339268 -135.269189)
			(xy 122.311972 -135.220554) (xy 122.292049 -135.168463) (xy 122.279923 -135.114026) (xy 122.275852 -135.058404)
			(xy 120.848749 -135.058404) (xy 121.23674 -135.446262) (xy 121.730262 -135.939784) (xy 121.735762 -135.944769)
			(xy 121.74893 -135.951606) (xy 121.75617 -135.953246) (xy 121.765822 -135.954262) (xy 122.265186 -135.954262)
			(xy 122.273952 -135.953844) (xy 122.290438 -135.947864) (xy 122.297444 -135.942578) (xy 122.304556 -135.935974)
			(xy 122.3137 -135.932164) (xy 122.318439 -135.930292) (xy 122.328419 -135.928244) (xy 122.333512 -135.9281)
			(xy 123.260104 -135.9281) (xy 123.270111 -135.927611) (xy 123.288601 -135.919951) (xy 123.302753 -135.905798)
			(xy 123.310412 -135.887307) (xy 123.310904 -135.8773) (xy 123.310904 -125.798072) (xy 123.311332 -125.788004)
			(xy 123.319054 -125.769408) (xy 123.32589 -125.762004) (xy 124.845064 -124.24283) (xy 124.851304 -124.23617)
			(xy 124.858999 -124.219637) (xy 124.86005 -124.210572) (xy 124.860365 -124.201484) (xy 124.855281 -124.18404)
			(xy 124.850144 -124.176536) (xy 124.84989 -124.176282) (xy 124.831943 -124.151362) (xy 124.803407 -124.096986)
			(xy 124.78395 -124.038741) (xy 124.774076 -123.978132) (xy 124.773436 -123.947428) (xy 124.773897 -123.920175)
			(xy 124.781651 -123.866223) (xy 124.797005 -123.813925) (xy 124.819647 -123.764344) (xy 124.849115 -123.71849)
			(xy 124.884809 -123.677298) (xy 124.926003 -123.641605) (xy 124.971858 -123.612139) (xy 125.02144 -123.5895)
			(xy 125.073739 -123.574148) (xy 125.127691 -123.566396) (xy 125.154944 -123.56592) (xy 125.185616 -123.566575)
			(xy 125.24616 -123.576471) (xy 125.304341 -123.595921) (xy 125.358664 -123.624425) (xy 125.383544 -123.642374)
			(xy 125.384052 -123.642374) (xy 125.384052 -123.642628) (xy 125.391574 -123.647724) (xy 125.409007 -123.652798)
			(xy 125.418088 -123.652534) (xy 125.427137 -123.651428) (xy 125.443654 -123.643741) (xy 125.450346 -123.637548)
			(xy 126.50216 -122.585734) (xy 126.50956 -122.578893) (xy 126.528159 -122.571175) (xy 126.538228 -122.570748)
			(xy 126.587504 -122.570748) (xy 126.597573 -122.570323) (xy 126.616171 -122.562601) (xy 126.623572 -122.555762)
			(xy 126.686056 -122.493278) (xy 126.692904 -122.485881) (xy 126.700637 -122.467282) (xy 126.701042 -122.45721)
			(xy 126.701042 -122.13844) (xy 126.693422 -122.119898) (xy 126.68758 -122.114056) (xy 126.68758 -116.684044)
			(xy 126.688013 -116.673978) (xy 126.695739 -116.655386) (xy 126.702566 -116.647976) (xy 127.546354 -115.804188)
			(xy 127.554494 -115.794946) (xy 127.56178 -115.771461) (xy 127.560324 -115.75923) (xy 127.560324 -115.758976)
			(xy 127.55724 -115.741486) (xy 127.553936 -115.706123) (xy 127.55372 -115.688364) (xy 127.554209 -115.661115)
			(xy 127.56197 -115.607173) (xy 127.577328 -115.554884) (xy 127.599972 -115.505313) (xy 127.629439 -115.459469)
			(xy 127.665131 -115.418286) (xy 127.706321 -115.382601) (xy 127.75217 -115.353141) (xy 127.801744 -115.330506)
			(xy 127.854036 -115.315156) (xy 127.907979 -115.307404) (xy 127.935228 -115.306856) (xy 127.952923 -115.30707)
			(xy 127.988159 -115.310381) (xy 128.005586 -115.31346) (xy 128.006094 -115.31346) (xy 128.018323 -115.314948)
			(xy 128.041803 -115.307631) (xy 128.051052 -115.29949) (xy 128.31826 -115.032282) (xy 128.325658 -115.025436)
			(xy 128.344257 -115.017711) (xy 128.354328 -115.017296) (xy 154.039824 -115.017296) (xy 154.051273 -115.016612)
			(xy 154.071872 -115.0066) (xy 154.079448 -114.997992) (xy 154.097652 -114.975877) (xy 154.139562 -114.936834)
			(xy 154.186836 -114.904492) (xy 154.238412 -114.879577) (xy 154.293132 -114.86265) (xy 154.349767 -114.854091)
			(xy 154.407045 -114.854091) (xy 154.46368 -114.86265) (xy 154.5184 -114.879577) (xy 154.569976 -114.904492)
			(xy 154.61725 -114.936834) (xy 154.65916 -114.975877) (xy 154.677364 -114.997992) (xy 154.684888 -115.006673)
			(xy 154.705515 -115.016734) (xy 154.716988 -115.017296) (xy 159.58058 -115.017296) (xy 159.590023 -115.016801)
			(xy 159.607605 -115.009888) (xy 159.61487 -115.003834) (xy 159.647398 -114.974502) (xy 159.717018 -114.921345)
			(xy 159.791281 -114.874894) (xy 159.869543 -114.835553) (xy 159.951126 -114.803662) (xy 160.035321 -114.779499)
			(xy 160.121399 -114.763274) (xy 160.208613 -114.755125) (xy 160.296207 -114.755125) (xy 160.383421 -114.763274)
			(xy 160.469499 -114.779499) (xy 160.553694 -114.803662) (xy 160.635277 -114.835553) (xy 160.713539 -114.874894)
			(xy 160.787802 -114.921345) (xy 160.857422 -114.974502) (xy 160.88995 -115.003834) (xy 160.897157 -115.009979)
			(xy 160.914777 -115.016884) (xy 160.92424 -115.017296) (xy 162.843464 -115.017296) (xy 162.852908 -115.016804)
			(xy 162.870494 -115.009895) (xy 162.877754 -115.003834) (xy 162.910287 -114.974512) (xy 162.979915 -114.921372)
			(xy 163.054183 -114.874937) (xy 163.132446 -114.835608) (xy 163.214026 -114.803725) (xy 163.298218 -114.779566)
			(xy 163.384291 -114.76334) (xy 163.471499 -114.755186) (xy 163.515294 -114.75466) (xy 165.369494 -114.75466)
			(xy 165.413289 -114.755163) (xy 165.5005 -114.76331) (xy 165.586574 -114.779535) (xy 165.670766 -114.803697)
			(xy 165.752346 -114.835586) (xy 165.830605 -114.874926) (xy 165.904865 -114.921375) (xy 165.974482 -114.974531)
			(xy 166.007034 -115.003834) (xy 166.01424 -115.009981) (xy 166.03186 -115.016891) (xy 166.041324 -115.017296)
			(xy 166.95039 -115.017296) (xy 166.959832 -115.016799) (xy 166.977412 -115.009884) (xy 166.98468 -115.003834)
			(xy 167.017208 -114.974502) (xy 167.086828 -114.921345) (xy 167.161091 -114.874894) (xy 167.239353 -114.835553)
			(xy 167.320936 -114.803662) (xy 167.405131 -114.779499) (xy 167.491209 -114.763274) (xy 167.578423 -114.755125)
			(xy 167.666017 -114.755125) (xy 167.753231 -114.763274) (xy 167.839309 -114.779499) (xy 167.923504 -114.803662)
			(xy 168.005087 -114.835553) (xy 168.083349 -114.874894) (xy 168.157612 -114.921345) (xy 168.227232 -114.974502)
			(xy 168.25976 -115.003834) (xy 168.266967 -115.009977) (xy 168.284588 -115.016879) (xy 168.29405 -115.017296)
			(xy 182.432706 -115.017296) (xy 182.442603 -115.016815) (xy 182.46092 -115.009309) (xy 182.475053 -114.995447)
			(xy 182.479442 -114.986562) (xy 182.516018 -114.900456) (xy 182.519487 -114.891215) (xy 182.519862 -114.8715)
			(xy 182.512777 -114.853097) (xy 182.506366 -114.845592) (xy 182.506112 -114.845338) (xy 182.486316 -114.823912)
			(xy 182.452807 -114.776165) (xy 182.426965 -114.72387) (xy 182.409392 -114.668248) (xy 182.400499 -114.610598)
			(xy 182.39994 -114.581432) (xy 182.400426 -114.554181) (xy 182.408182 -114.500233) (xy 182.423537 -114.447938)
			(xy 182.446179 -114.398361) (xy 182.475645 -114.352511) (xy 182.511336 -114.31132) (xy 182.552527 -114.275629)
			(xy 182.598377 -114.246163) (xy 182.647954 -114.223521) (xy 182.700249 -114.208166) (xy 182.754197 -114.20041)
			(xy 182.808699 -114.20041) (xy 182.862647 -114.208166) (xy 182.914942 -114.223521) (xy 182.964519 -114.246163)
			(xy 183.010369 -114.275629) (xy 183.05156 -114.31132) (xy 183.087251 -114.352511) (xy 183.116717 -114.398361)
			(xy 183.139359 -114.447938) (xy 183.154714 -114.500233) (xy 183.16247 -114.554181) (xy 183.162956 -114.581432)
			(xy 183.16252 -114.607646) (xy 183.155341 -114.65958) (xy 183.141123 -114.710043) (xy 183.120133 -114.758086)
			(xy 183.092767 -114.802804) (xy 183.059538 -114.843357) (xy 183.021073 -114.878981) (xy 182.978094 -114.909007)
			(xy 182.95493 -114.921284) (xy 182.946814 -114.925898) (xy 182.934337 -114.939763) (xy 182.927637 -114.95717)
			(xy 182.927244 -114.966496) (xy 182.927244 -114.987578) (xy 182.956962 -115.017296) (xy 183.1213 -115.017296)
			(xy 183.130654 -115.016817) (xy 183.148098 -115.010035) (xy 183.155336 -115.004088) (xy 183.174692 -114.987008)
			(xy 183.21717 -114.957674) (xy 183.263214 -114.934333) (xy 183.311983 -114.91741) (xy 183.3372 -114.911886)
			(xy 183.337454 -114.911886) (xy 183.348165 -114.909082) (xy 183.365938 -114.895915) (xy 183.371744 -114.886486)
			(xy 183.409082 -114.817906) (xy 183.413953 -114.807849) (xy 183.41542 -114.785576) (xy 183.411876 -114.77498)
			(xy 183.403439 -114.752622) (xy 183.391571 -114.706332) (xy 183.385588 -114.65892) (xy 183.385206 -114.635026)
			(xy 183.385804 -114.604055) (xy 183.395791 -114.542924) (xy 183.415509 -114.484204) (xy 183.444439 -114.429433)
			(xy 183.462676 -114.404394) (xy 183.467811 -114.397159) (xy 183.473133 -114.380247) (xy 183.47309 -114.371374)
			(xy 183.471566 -114.341656) (xy 183.470799 -114.332216) (xy 183.463218 -114.314873) (xy 183.456834 -114.307874)
			(xy 182.998364 -113.849404) (xy 182.975418 -113.825849) (xy 182.934399 -113.774451) (xy 182.899396 -113.718779)
			(xy 182.870852 -113.659537) (xy 182.849125 -113.597469) (xy 182.834489 -113.533358) (xy 182.827129 -113.46801)
			(xy 182.82666 -113.43513) (xy 182.827203 -113.399851) (xy 182.83571 -113.329809) (xy 182.852568 -113.261295)
			(xy 182.877534 -113.195302) (xy 182.910245 -113.132785) (xy 182.929784 -113.103406) (xy 182.940198 -113.088166)
			(xy 182.936896 -113.051844) (xy 182.914036 -113.028984) (xy 182.904892 -113.02492) (xy 182.87349 -113.011113)
			(xy 182.813859 -112.977201) (xy 182.758598 -112.936557) (xy 182.708462 -112.889735) (xy 182.664139 -112.837378)
			(xy 182.626235 -112.780202) (xy 182.595268 -112.71899) (xy 182.571664 -112.654579) (xy 182.555746 -112.587853)
			(xy 182.54773 -112.519724) (xy 182.54726 -112.485424) (xy 182.547772 -112.450024) (xy 182.556303 -112.37974)
			(xy 182.573244 -112.310996) (xy 182.598347 -112.244796) (xy 182.631247 -112.182105) (xy 182.671464 -112.123836)
			(xy 182.718412 -112.07084) (xy 182.771405 -112.023889) (xy 182.829671 -111.983668) (xy 182.89236 -111.950764)
			(xy 182.958558 -111.925656) (xy 183.0273 -111.90871) (xy 183.097584 -111.900174) (xy 183.132984 -111.8997)
			(xy 183.19877 -111.8997) (xy 183.199278 -111.8997) (xy 183.220614 -111.899954) (xy 183.257444 -111.858806)
			(xy 183.264045 -111.850632) (xy 183.270603 -111.830695) (xy 183.270144 -111.820198) (xy 183.268366 -111.784892)
			(xy 183.268838 -111.757523) (xy 183.276664 -111.703346) (xy 183.292155 -111.650844) (xy 183.314991 -111.601096)
			(xy 183.344703 -111.555123) (xy 183.362346 -111.534194) (xy 183.362346 -111.53394) (xy 183.3626 -111.53394)
			(xy 183.368191 -111.526855) (xy 183.374446 -111.509938) (xy 183.374792 -111.50092) (xy 183.374792 -111.433864)
			(xy 183.374426 -111.42485) (xy 183.368169 -111.407942) (xy 183.3626 -111.400844) (xy 183.362346 -111.40059)
			(xy 183.344705 -111.379658) (xy 183.31498 -111.33369) (xy 183.292135 -111.283945) (xy 183.276639 -111.231443)
			(xy 183.26881 -111.177264) (xy 183.268811 -111.122524) (xy 183.276641 -111.068345) (xy 183.292139 -111.015844)
			(xy 183.314986 -110.966099) (xy 183.344712 -110.920133) (xy 183.362346 -110.899194) (xy 183.362346 -110.89894)
			(xy 183.3626 -110.89894) (xy 183.368191 -110.891855) (xy 183.374446 -110.874938) (xy 183.374792 -110.86592)
			(xy 183.374792 -110.798864) (xy 183.374426 -110.78985) (xy 183.368169 -110.772942) (xy 183.3626 -110.765844)
			(xy 183.362346 -110.76559) (xy 183.344705 -110.744658) (xy 183.31498 -110.69869) (xy 183.292135 -110.648945)
			(xy 183.276639 -110.596443) (xy 183.26881 -110.542264) (xy 183.268811 -110.487524) (xy 183.276641 -110.433345)
			(xy 183.292139 -110.380844) (xy 183.314986 -110.331099) (xy 183.344712 -110.285133) (xy 183.362346 -110.264194)
			(xy 183.362346 -110.26394) (xy 183.3626 -110.26394) (xy 183.368191 -110.256855) (xy 183.374446 -110.239938)
			(xy 183.374792 -110.23092) (xy 183.374792 -110.163864) (xy 183.374426 -110.15485) (xy 183.368169 -110.137942)
			(xy 183.3626 -110.130844) (xy 183.362346 -110.13059) (xy 183.344705 -110.109658) (xy 183.31498 -110.06369)
			(xy 183.292135 -110.013945) (xy 183.276639 -109.961443) (xy 183.26881 -109.907264) (xy 183.268811 -109.852524)
			(xy 183.276641 -109.798345) (xy 183.292139 -109.745844) (xy 183.314986 -109.696099) (xy 183.344712 -109.650133)
			(xy 183.362346 -109.629194) (xy 183.362346 -109.62894) (xy 183.3626 -109.62894) (xy 183.368191 -109.621855)
			(xy 183.374446 -109.604938) (xy 183.374792 -109.59592) (xy 183.374792 -109.528864) (xy 183.374426 -109.51985)
			(xy 183.368169 -109.502942) (xy 183.3626 -109.495844) (xy 183.362346 -109.49559) (xy 183.344703 -109.474659)
			(xy 183.314974 -109.428694) (xy 183.29213 -109.378947) (xy 183.276639 -109.326443) (xy 183.268821 -109.272263)
			(xy 183.268366 -109.244892) (xy 183.268852 -109.217641) (xy 183.276608 -109.163693) (xy 183.291963 -109.111398)
			(xy 183.314605 -109.061821) (xy 183.344071 -109.015971) (xy 183.379762 -108.97478) (xy 183.420953 -108.939089)
			(xy 183.466803 -108.909623) (xy 183.51638 -108.886981) (xy 183.568675 -108.871626) (xy 183.622623 -108.86387)
			(xy 183.677125 -108.86387) (xy 183.731073 -108.871626) (xy 183.783368 -108.886981) (xy 183.832945 -108.909623)
			(xy 183.878795 -108.939089) (xy 183.919986 -108.97478) (xy 183.955677 -109.015971) (xy 183.985143 -109.061821)
			(xy 184.007785 -109.111398) (xy 184.02314 -109.163693) (xy 184.030896 -109.217641) (xy 184.031382 -109.244892)
			(xy 184.030911 -109.272262) (xy 184.023088 -109.326441) (xy 184.007601 -109.378945) (xy 183.991954 -109.41304)
			(xy 187.929266 -109.41304) (xy 187.929752 -109.385789) (xy 187.937508 -109.331841) (xy 187.952863 -109.279546)
			(xy 187.975505 -109.229969) (xy 188.004971 -109.184119) (xy 188.040662 -109.142928) (xy 188.081853 -109.107237)
			(xy 188.127703 -109.077771) (xy 188.17728 -109.055129) (xy 188.229575 -109.039774) (xy 188.283523 -109.032018)
			(xy 188.338025 -109.032018) (xy 188.391973 -109.039774) (xy 188.444268 -109.055129) (xy 188.493845 -109.077771)
			(xy 188.539695 -109.107237) (xy 188.580886 -109.142928) (xy 188.616577 -109.184119) (xy 188.646043 -109.229969)
			(xy 188.668685 -109.279546) (xy 188.68404 -109.331841) (xy 188.691796 -109.385789) (xy 188.692282 -109.41304)
			(xy 188.691859 -109.439235) (xy 188.68469 -109.491133) (xy 188.670493 -109.541563) (xy 188.649533 -109.589579)
			(xy 188.622205 -109.634277) (xy 188.589021 -109.674819) (xy 188.570108 -109.692948) (xy 188.562754 -109.700564)
			(xy 188.554344 -109.719966) (xy 188.553852 -109.73054) (xy 188.55436 -109.816392) (xy 188.562996 -109.83595)
			(xy 188.571124 -109.843062) (xy 188.590683 -109.861205) (xy 188.625012 -109.902043) (xy 188.653313 -109.947267)
			(xy 188.675034 -109.995995) (xy 188.68975 -110.047275) (xy 188.697176 -110.100105) (xy 188.697616 -110.12678)
			(xy 188.69713 -110.154031) (xy 188.689374 -110.207979) (xy 188.674019 -110.260274) (xy 188.651377 -110.309851)
			(xy 188.621911 -110.355701) (xy 188.58622 -110.396892) (xy 188.545029 -110.432583) (xy 188.499179 -110.462049)
			(xy 188.449602 -110.484691) (xy 188.397307 -110.500046) (xy 188.343359 -110.507802) (xy 188.288857 -110.507802)
			(xy 188.234909 -110.500046) (xy 188.182614 -110.484691) (xy 188.133037 -110.462049) (xy 188.087187 -110.432583)
			(xy 188.045996 -110.396892) (xy 188.010305 -110.355701) (xy 187.980839 -110.309851) (xy 187.958197 -110.260274)
			(xy 187.942842 -110.207979) (xy 187.935086 -110.154031) (xy 187.9346 -110.12678) (xy 187.935042 -110.100585)
			(xy 187.942208 -110.048689) (xy 187.956402 -109.998259) (xy 187.977358 -109.950244) (xy 188.004683 -109.905545)
			(xy 188.037862 -109.865002) (xy 188.056774 -109.846872) (xy 188.064176 -109.839296) (xy 188.072556 -109.819863)
			(xy 188.07303 -109.80928) (xy 188.072522 -109.723428) (xy 188.063886 -109.70387) (xy 188.055758 -109.696758)
			(xy 188.036205 -109.678609) (xy 188.001877 -109.637772) (xy 187.973575 -109.592548) (xy 187.951854 -109.543822)
			(xy 187.937135 -109.492544) (xy 187.929708 -109.439714) (xy 187.929266 -109.41304) (xy 183.991954 -109.41304)
			(xy 183.984769 -109.428696) (xy 183.95506 -109.474673) (xy 183.937402 -109.49559) (xy 183.937402 -109.495844)
			(xy 183.937148 -109.495844) (xy 183.93155 -109.502926) (xy 183.925283 -109.519844) (xy 183.924956 -109.528864)
			(xy 183.924956 -109.59592) (xy 183.925318 -109.604936) (xy 183.931566 -109.621851) (xy 183.937148 -109.62894)
			(xy 183.937402 -109.629194) (xy 183.955042 -109.650127) (xy 183.984766 -109.696096) (xy 184.00761 -109.745843)
			(xy 184.023107 -109.798345) (xy 184.030935 -109.852523) (xy 184.030936 -109.907265) (xy 184.023109 -109.961443)
			(xy 184.007615 -110.013946) (xy 183.984772 -110.063694) (xy 183.955049 -110.109663) (xy 183.937402 -110.13059)
			(xy 183.937402 -110.130844) (xy 183.937148 -110.130844) (xy 183.93155 -110.137926) (xy 183.925283 -110.154844)
			(xy 183.924956 -110.163864) (xy 183.924956 -110.23092) (xy 183.925318 -110.239936) (xy 183.931566 -110.256851)
			(xy 183.937148 -110.26394) (xy 183.937402 -110.264194) (xy 183.955042 -110.285127) (xy 183.984766 -110.331096)
			(xy 184.00761 -110.380843) (xy 184.023107 -110.433345) (xy 184.030935 -110.487523) (xy 184.030936 -110.542265)
			(xy 184.023109 -110.596443) (xy 184.007615 -110.648946) (xy 183.984772 -110.698694) (xy 183.955049 -110.744663)
			(xy 183.937402 -110.76559) (xy 183.937402 -110.765844) (xy 183.937148 -110.765844) (xy 183.93155 -110.772926)
			(xy 183.925283 -110.789844) (xy 183.924956 -110.798864) (xy 183.924956 -110.86592) (xy 183.925318 -110.874936)
			(xy 183.931566 -110.891851) (xy 183.937148 -110.89894) (xy 183.937402 -110.899194) (xy 183.955042 -110.920127)
			(xy 183.984766 -110.966096) (xy 184.00761 -111.015843) (xy 184.007741 -111.016288) (xy 187.887864 -111.016288)
			(xy 187.88835 -110.989037) (xy 187.896106 -110.935089) (xy 187.911461 -110.882794) (xy 187.934103 -110.833217)
			(xy 187.963569 -110.787367) (xy 187.99926 -110.746176) (xy 188.040451 -110.710485) (xy 188.086301 -110.681019)
			(xy 188.135878 -110.658377) (xy 188.188173 -110.643022) (xy 188.242121 -110.635266) (xy 188.296623 -110.635266)
			(xy 188.350571 -110.643022) (xy 188.402866 -110.658377) (xy 188.452443 -110.681019) (xy 188.498293 -110.710485)
			(xy 188.539484 -110.746176) (xy 188.575175 -110.787367) (xy 188.604641 -110.833217) (xy 188.627283 -110.882794)
			(xy 188.642638 -110.935089) (xy 188.650394 -110.989037) (xy 188.65088 -111.016288) (xy 188.650415 -111.043308)
			(xy 188.642802 -111.09681) (xy 188.627713 -111.148701) (xy 188.60545 -111.197942) (xy 188.576459 -111.243548)
			(xy 188.541321 -111.284604) (xy 188.52134 -111.3028) (xy 188.513377 -111.310452) (xy 188.504433 -111.330622)
			(xy 188.504068 -111.341662) (xy 188.505338 -111.418878) (xy 188.506008 -111.429889) (xy 188.515494 -111.449778)
			(xy 188.523626 -111.457232) (xy 188.544755 -111.475468) (xy 188.582034 -111.517001) (xy 188.61286 -111.563525)
			(xy 188.636575 -111.614045) (xy 188.652672 -111.667483) (xy 188.660808 -111.722697) (xy 188.661294 -111.750602)
			(xy 188.660671 -111.780394) (xy 188.651421 -111.839255) (xy 188.633132 -111.895962) (xy 188.606248 -111.949135)
			(xy 188.583491 -111.980726) (xy 190.001398 -111.980726) (xy 190.001938 -111.951988) (xy 190.010557 -111.895161)
			(xy 190.027603 -111.840271) (xy 190.052691 -111.788559) (xy 190.085253 -111.741195) (xy 190.104522 -111.719868)
			(xy 190.111126 -111.71301) (xy 190.118238 -111.694976) (xy 190.118238 -111.606076) (xy 190.111126 -111.588042)
			(xy 190.104522 -111.581184) (xy 190.085277 -111.559835) (xy 190.052711 -111.512476) (xy 190.027618 -111.460768)
			(xy 190.010566 -111.405881) (xy 190.001941 -111.349056) (xy 190.001939 -111.291581) (xy 190.010558 -111.234756)
			(xy 190.027604 -111.179867) (xy 190.052692 -111.128157) (xy 190.085253 -111.080795) (xy 190.104522 -111.059468)
			(xy 190.111126 -111.05261) (xy 190.118238 -111.034576) (xy 190.118238 -110.945676) (xy 190.111126 -110.927642)
			(xy 190.104522 -110.920784) (xy 190.085277 -110.899435) (xy 190.052711 -110.852076) (xy 190.027618 -110.800368)
			(xy 190.010566 -110.745481) (xy 190.001941 -110.688656) (xy 190.001939 -110.631181) (xy 190.010558 -110.574356)
			(xy 190.027604 -110.519467) (xy 190.052692 -110.467757) (xy 190.085253 -110.420395) (xy 190.104522 -110.399068)
			(xy 190.111126 -110.39221) (xy 190.118238 -110.374176) (xy 190.118238 -110.285276) (xy 190.111126 -110.267242)
			(xy 190.104522 -110.260384) (xy 190.085277 -110.239035) (xy 190.052711 -110.191676) (xy 190.027618 -110.139968)
			(xy 190.010566 -110.085081) (xy 190.001941 -110.028256) (xy 190.001939 -109.970781) (xy 190.010558 -109.913956)
			(xy 190.027604 -109.859067) (xy 190.052692 -109.807357) (xy 190.085253 -109.759995) (xy 190.104522 -109.738668)
			(xy 190.111126 -109.73181) (xy 190.118238 -109.713776) (xy 190.118238 -109.624876) (xy 190.111126 -109.606842)
			(xy 190.104522 -109.599984) (xy 190.085261 -109.578649) (xy 190.052694 -109.531289) (xy 190.0276 -109.479579)
			(xy 190.010547 -109.42469) (xy 190.001921 -109.367864) (xy 190.001398 -109.339126) (xy 190.00188 -109.311874)
			(xy 190.009633 -109.257923) (xy 190.024986 -109.205625) (xy 190.047626 -109.156045) (xy 190.077092 -109.110191)
			(xy 190.112784 -109.068998) (xy 190.153975 -109.033304) (xy 190.199827 -109.003836) (xy 190.249406 -108.981193)
			(xy 190.301703 -108.965837) (xy 190.355654 -108.958081) (xy 190.382906 -108.957618) (xy 190.40922 -108.958076)
			(xy 190.46135 -108.965312) (xy 190.511993 -108.979632) (xy 190.560192 -109.000767) (xy 190.605035 -109.028315)
			(xy 190.645674 -109.061755) (xy 190.66383 -109.080808) (xy 190.671338 -109.088226) (xy 190.690628 -109.09674)
			(xy 190.701168 -109.097318) (xy 190.775844 -109.097318) (xy 190.786391 -109.096767) (xy 190.805686 -109.088247)
			(xy 190.813182 -109.080808) (xy 190.831355 -109.06177) (xy 190.871981 -109.028311) (xy 190.916817 -109.000749)
			(xy 190.965015 -108.979608) (xy 191.015659 -108.965287) (xy 191.067791 -108.958058) (xy 191.094106 -108.957618)
			(xy 191.12136 -108.95805) (xy 191.175314 -108.965808) (xy 191.227614 -108.981166) (xy 191.277195 -109.003811)
			(xy 191.32305 -109.033283) (xy 191.364243 -109.06898) (xy 191.399937 -109.110176) (xy 191.429404 -109.156033)
			(xy 191.452045 -109.205616) (xy 191.467399 -109.257918) (xy 191.475152 -109.311872) (xy 191.475614 -109.339126)
			(xy 191.475102 -109.367865) (xy 191.466476 -109.424693) (xy 191.449423 -109.479584) (xy 191.424329 -109.531295)
			(xy 191.391762 -109.578657) (xy 191.37249 -109.599984) (xy 191.365886 -109.606842) (xy 191.358774 -109.624876)
			(xy 191.358774 -109.713776) (xy 191.365886 -109.73181) (xy 191.37249 -109.738668) (xy 191.391786 -109.759973)
			(xy 191.424349 -109.807339) (xy 191.449438 -109.859055) (xy 191.466486 -109.913949) (xy 191.475106 -109.970779)
			(xy 191.475103 -110.028259) (xy 191.466477 -110.085088) (xy 191.449424 -110.13998) (xy 191.42433 -110.191693)
			(xy 191.391762 -110.239057) (xy 191.37249 -110.260384) (xy 191.365886 -110.267242) (xy 191.358774 -110.285276)
			(xy 191.358774 -110.374176) (xy 191.365886 -110.39221) (xy 191.37249 -110.399068) (xy 191.391786 -110.420373)
			(xy 191.424349 -110.467739) (xy 191.449438 -110.519455) (xy 191.466486 -110.574349) (xy 191.475106 -110.631179)
			(xy 191.475106 -110.631732) (xy 209.194654 -110.631732) (xy 209.195149 -110.602992) (xy 209.20378 -110.546164)
			(xy 209.220838 -110.491273) (xy 209.245935 -110.439562) (xy 209.278505 -110.392201) (xy 209.297778 -110.370874)
			(xy 209.304382 -110.364016) (xy 209.311494 -110.345982) (xy 209.311494 -110.257082) (xy 209.304382 -110.239048)
			(xy 209.297778 -110.23219) (xy 209.278541 -110.210835) (xy 209.245979 -110.163476) (xy 209.220888 -110.111768)
			(xy 209.203838 -110.056882) (xy 209.195214 -110.00006) (xy 209.19521 -109.942587) (xy 209.203828 -109.885763)
			(xy 209.220871 -109.830875) (xy 209.245955 -109.779165) (xy 209.278512 -109.731802) (xy 209.297778 -109.710474)
			(xy 209.304382 -109.703616) (xy 209.311494 -109.685582) (xy 209.311494 -109.596682) (xy 209.304382 -109.578648)
			(xy 209.297778 -109.57179) (xy 209.278529 -109.550444) (xy 209.245958 -109.503088) (xy 209.220861 -109.451381)
			(xy 209.203805 -109.396494) (xy 209.195177 -109.33967) (xy 209.194654 -109.310932) (xy 209.19514 -109.283681)
			(xy 209.202896 -109.229733) (xy 209.218251 -109.177438) (xy 209.240893 -109.127861) (xy 209.270359 -109.082011)
			(xy 209.30605 -109.04082) (xy 209.347241 -109.005129) (xy 209.393091 -108.975663) (xy 209.442668 -108.953021)
			(xy 209.494963 -108.937666) (xy 209.548911 -108.92991) (xy 209.603413 -108.92991) (xy 209.657361 -108.937666)
			(xy 209.709656 -108.953021) (xy 209.759233 -108.975663) (xy 209.805083 -109.005129) (xy 209.846274 -109.04082)
			(xy 209.881965 -109.082011) (xy 209.911431 -109.127861) (xy 209.934073 -109.177438) (xy 209.949428 -109.229733)
			(xy 209.957184 -109.283681) (xy 209.95767 -109.310932) (xy 209.957147 -109.339671) (xy 209.948521 -109.396497)
			(xy 209.93147 -109.451387) (xy 209.906379 -109.503099) (xy 209.873815 -109.550462) (xy 209.854546 -109.57179)
			(xy 209.847942 -109.578648) (xy 209.84083 -109.596682) (xy 209.84083 -109.685582) (xy 209.847942 -109.703616)
			(xy 209.854546 -109.710474) (xy 209.87385 -109.731773) (xy 209.906417 -109.779139) (xy 209.931508 -109.830855)
			(xy 209.948558 -109.885751) (xy 209.957178 -109.942582) (xy 209.957174 -110.000064) (xy 209.948547 -110.056895)
			(xy 209.931491 -110.111788) (xy 209.906393 -110.163501) (xy 209.873821 -110.210864) (xy 209.854546 -110.23219)
			(xy 209.847942 -110.239048) (xy 209.84083 -110.257082) (xy 209.84083 -110.345982) (xy 209.847942 -110.364016)
			(xy 209.854546 -110.370874) (xy 209.873829 -110.39219) (xy 209.906394 -110.439555) (xy 209.931485 -110.491269)
			(xy 209.948532 -110.546163) (xy 209.957151 -110.602992) (xy 209.95767 -110.631732) (xy 209.957184 -110.658983)
			(xy 209.956428 -110.664244) (xy 210.788504 -110.664244) (xy 210.788993 -110.635504) (xy 210.797624 -110.578675)
			(xy 210.814682 -110.523784) (xy 210.839781 -110.472072) (xy 210.872354 -110.424712) (xy 210.891628 -110.403386)
			(xy 210.898232 -110.396528) (xy 210.905344 -110.378494) (xy 210.905344 -110.289594) (xy 210.898232 -110.27156)
			(xy 210.891628 -110.264702) (xy 210.872401 -110.243337) (xy 210.839834 -110.195982) (xy 210.814739 -110.144276)
			(xy 210.797686 -110.089391) (xy 210.789059 -110.032569) (xy 210.789054 -109.975095) (xy 210.797671 -109.918272)
			(xy 210.814716 -109.863384) (xy 210.839801 -109.811674) (xy 210.87236 -109.764313) (xy 210.891628 -109.742986)
			(xy 210.898232 -109.736128) (xy 210.905344 -109.718094) (xy 210.905344 -109.629194) (xy 210.898232 -109.61116)
			(xy 210.891628 -109.604302) (xy 210.872329 -109.582999) (xy 210.839767 -109.535631) (xy 210.81468 -109.483913)
			(xy 210.797636 -109.429017) (xy 210.789021 -109.372185) (xy 210.788504 -109.343444) (xy 210.78899 -109.316193)
			(xy 210.796746 -109.262245) (xy 210.812101 -109.20995) (xy 210.834743 -109.160373) (xy 210.864209 -109.114523)
			(xy 210.8999 -109.073332) (xy 210.941091 -109.037641) (xy 210.986941 -109.008175) (xy 211.036518 -108.985533)
			(xy 211.088813 -108.970178) (xy 211.142761 -108.962422) (xy 211.197263 -108.962422) (xy 211.251211 -108.970178)
			(xy 211.303506 -108.985533) (xy 211.353083 -109.008175) (xy 211.398933 -109.037641) (xy 211.440124 -109.073332)
			(xy 211.475815 -109.114523) (xy 211.505281 -109.160373) (xy 211.527923 -109.20995) (xy 211.543278 -109.262245)
			(xy 211.551034 -109.316193) (xy 211.55152 -109.343444) (xy 211.551018 -109.372184) (xy 211.542389 -109.429012)
			(xy 211.525334 -109.483902) (xy 211.500238 -109.535614) (xy 211.467668 -109.582976) (xy 211.448396 -109.604302)
			(xy 211.441792 -109.61116) (xy 211.43468 -109.629194) (xy 211.43468 -109.718094) (xy 211.441792 -109.736128)
			(xy 211.448396 -109.742986) (xy 211.46771 -109.764275) (xy 211.500272 -109.811645) (xy 211.52536 -109.863363)
			(xy 211.542405 -109.918259) (xy 211.546301 -109.943952) (xy 268.952677 -109.943952) (xy 268.952677 -109.889448)
			(xy 268.960435 -109.835497) (xy 268.975791 -109.783201) (xy 268.998434 -109.733622) (xy 269.027903 -109.68777)
			(xy 269.063597 -109.646579) (xy 269.104791 -109.610887) (xy 269.150644 -109.581422) (xy 269.200225 -109.558782)
			(xy 269.252523 -109.543429) (xy 269.306474 -109.535676) (xy 269.333726 -109.535214) (xy 269.359634 -109.535678)
			(xy 269.41097 -109.542705) (xy 269.460884 -109.556613) (xy 269.508458 -109.577146) (xy 269.552816 -109.603926)
			(xy 269.593143 -109.636462) (xy 269.628697 -109.674154) (xy 269.644114 -109.69498) (xy 269.649841 -109.702323)
			(xy 269.665353 -109.712601) (xy 269.67434 -109.715046) (xy 269.70482 -109.721904) (xy 269.714098 -109.72364)
			(xy 269.73276 -109.720908) (xy 269.741142 -109.71657) (xy 269.76711 -109.702259) (xy 269.821965 -109.679753)
			(xy 269.87927 -109.664531) (xy 269.938064 -109.65685) (xy 269.96771 -109.656372) (xy 269.997352 -109.656898)
			(xy 270.056133 -109.664611) (xy 270.113431 -109.679829) (xy 270.168292 -109.7023) (xy 270.194278 -109.71657)
			(xy 270.202691 -109.720815) (xy 270.221321 -109.723549) (xy 270.2306 -109.721904) (xy 270.26108 -109.715046)
			(xy 270.270071 -109.712614) (xy 270.285576 -109.702323) (xy 270.291306 -109.69498) (xy 270.306688 -109.674124)
			(xy 270.342235 -109.636413) (xy 270.382562 -109.603864) (xy 270.426926 -109.577077) (xy 270.474509 -109.556546)
			(xy 270.524434 -109.542649) (xy 270.575782 -109.535643) (xy 270.601694 -109.535214) (xy 270.628949 -109.535632)
			(xy 270.682903 -109.543389) (xy 270.735205 -109.558746) (xy 270.784789 -109.581389) (xy 270.830645 -109.610859)
			(xy 270.869981 -109.644942) (xy 276.86965 -109.644942) (xy 276.873721 -109.58932) (xy 276.885847 -109.534883)
			(xy 276.90577 -109.482792) (xy 276.933066 -109.434157) (xy 276.967152 -109.390014) (xy 277.007301 -109.351305)
			(xy 277.052659 -109.318854) (xy 277.102259 -109.293353) (xy 277.155043 -109.275346) (xy 277.209886 -109.265216)
			(xy 277.26562 -109.263179) (xy 277.321057 -109.269279) (xy 277.375014 -109.283385) (xy 277.426343 -109.305197)
			(xy 277.473949 -109.334251) (xy 277.516817 -109.369926) (xy 277.554034 -109.411463) (xy 277.584807 -109.457976)
			(xy 277.608479 -109.508473) (xy 277.624547 -109.56188) (xy 277.632667 -109.617056) (xy 277.633176 -109.644942)
			(xy 277.632667 -109.672828) (xy 277.624547 -109.728004) (xy 277.608479 -109.781411) (xy 277.584807 -109.831908)
			(xy 277.554034 -109.878421) (xy 277.516817 -109.919958) (xy 277.473949 -109.955633) (xy 277.426343 -109.984687)
			(xy 277.375014 -110.006499) (xy 277.321057 -110.020605) (xy 277.26562 -110.026705) (xy 277.209886 -110.024668)
			(xy 277.155043 -110.014538) (xy 277.102259 -109.996531) (xy 277.052659 -109.97103) (xy 277.007301 -109.938579)
			(xy 276.967152 -109.89987) (xy 276.933066 -109.855727) (xy 276.90577 -109.807092) (xy 276.885847 -109.755001)
			(xy 276.873721 -109.700564) (xy 276.86965 -109.644942) (xy 270.869981 -109.644942) (xy 270.871841 -109.646554)
			(xy 270.907538 -109.68775) (xy 270.937008 -109.733606) (xy 270.959652 -109.783189) (xy 270.97501 -109.835491)
			(xy 270.982767 -109.889445) (xy 270.982767 -109.943955) (xy 270.97501 -109.997909) (xy 270.959652 -110.050211)
			(xy 270.937008 -110.099794) (xy 270.907538 -110.14565) (xy 270.871841 -110.186846) (xy 270.830645 -110.222541)
			(xy 270.784789 -110.252011) (xy 270.735205 -110.274654) (xy 270.682903 -110.290011) (xy 270.628949 -110.297768)
			(xy 270.601694 -110.29823) (xy 270.586901 -110.298098) (xy 270.557403 -110.295807) (xy 270.542766 -110.293658)
			(xy 270.531792 -110.29253) (xy 270.510601 -110.298594) (xy 270.501872 -110.305342) (xy 270.443452 -110.35538)
			(xy 270.435432 -110.362955) (xy 270.426214 -110.38297) (xy 270.425672 -110.393988) (xy 270.425672 -110.69828)
			(xy 270.42623 -110.709296) (xy 270.435436 -110.729313) (xy 270.443452 -110.736888) (xy 270.510508 -110.794292)
			(xy 270.53159 -110.800388) (xy 270.542766 -110.79861) (xy 270.557404 -110.796467) (xy 270.586901 -110.79418)
			(xy 270.601694 -110.794038) (xy 270.62895 -110.794409) (xy 270.682909 -110.802166) (xy 270.735214 -110.817523)
			(xy 270.7848 -110.840168) (xy 270.81183 -110.857538) (xy 281.164536 -110.857538) (xy 281.168607 -110.801916)
			(xy 281.180733 -110.747479) (xy 281.200656 -110.695388) (xy 281.227952 -110.646753) (xy 281.262038 -110.60261)
			(xy 281.302187 -110.563901) (xy 281.347545 -110.53145) (xy 281.397145 -110.505949) (xy 281.449929 -110.487942)
			(xy 281.504772 -110.477812) (xy 281.560506 -110.475775) (xy 281.615943 -110.481875) (xy 281.6699 -110.495981)
			(xy 281.721229 -110.517793) (xy 281.768835 -110.546847) (xy 281.811703 -110.582522) (xy 281.84892 -110.624059)
			(xy 281.879693 -110.670572) (xy 281.903365 -110.721069) (xy 281.919433 -110.774476) (xy 281.927553 -110.829652)
			(xy 281.928062 -110.857538) (xy 281.927553 -110.885424) (xy 281.919433 -110.9406) (xy 281.903365 -110.994007)
			(xy 281.879693 -111.044504) (xy 281.84892 -111.091017) (xy 281.811703 -111.132554) (xy 281.768835 -111.168229)
			(xy 281.721229 -111.197283) (xy 281.6699 -111.219095) (xy 281.615943 -111.233201) (xy 281.560506 -111.239301)
			(xy 281.504772 -111.237264) (xy 281.449929 -111.227134) (xy 281.397145 -111.209127) (xy 281.347545 -111.183626)
			(xy 281.302187 -111.151175) (xy 281.262038 -111.112466) (xy 281.227952 -111.068323) (xy 281.200656 -111.019688)
			(xy 281.180733 -110.967597) (xy 281.168607 -110.91316) (xy 281.164536 -110.857538) (xy 270.81183 -110.857538)
			(xy 270.83066 -110.869639) (xy 270.871858 -110.905337) (xy 270.907557 -110.946535) (xy 270.937029 -110.992394)
			(xy 270.959675 -111.041981) (xy 270.975033 -111.094286) (xy 270.982791 -111.148244) (xy 270.982791 -111.202756)
			(xy 270.975033 -111.256714) (xy 270.959675 -111.309019) (xy 270.937029 -111.358606) (xy 270.907557 -111.404465)
			(xy 270.872398 -111.44504) (xy 276.86965 -111.44504) (xy 276.873721 -111.389418) (xy 276.885847 -111.334981)
			(xy 276.90577 -111.28289) (xy 276.933066 -111.234255) (xy 276.967152 -111.190112) (xy 277.007301 -111.151403)
			(xy 277.052659 -111.118952) (xy 277.102259 -111.093451) (xy 277.155043 -111.075444) (xy 277.209886 -111.065314)
			(xy 277.26562 -111.063277) (xy 277.321057 -111.069377) (xy 277.375014 -111.083483) (xy 277.426343 -111.105295)
			(xy 277.473949 -111.134349) (xy 277.516817 -111.170024) (xy 277.554034 -111.211561) (xy 277.584807 -111.258074)
			(xy 277.608479 -111.308571) (xy 277.624547 -111.361978) (xy 277.632667 -111.417154) (xy 277.633176 -111.44504)
			(xy 277.632667 -111.472926) (xy 277.624547 -111.528102) (xy 277.608479 -111.581509) (xy 277.584807 -111.632006)
			(xy 277.554034 -111.678519) (xy 277.516817 -111.720056) (xy 277.473949 -111.755731) (xy 277.426343 -111.784785)
			(xy 277.375014 -111.806597) (xy 277.321057 -111.820703) (xy 277.26562 -111.826803) (xy 277.209886 -111.824766)
			(xy 277.155043 -111.814636) (xy 277.102259 -111.796629) (xy 277.052659 -111.771128) (xy 277.007301 -111.738677)
			(xy 276.967152 -111.699968) (xy 276.933066 -111.655825) (xy 276.90577 -111.60719) (xy 276.885847 -111.555099)
			(xy 276.873721 -111.500662) (xy 276.86965 -111.44504) (xy 270.872398 -111.44504) (xy 270.871858 -111.445663)
			(xy 270.83066 -111.481361) (xy 270.7848 -111.510832) (xy 270.735214 -111.533477) (xy 270.682909 -111.548834)
			(xy 270.62895 -111.556591) (xy 270.601694 -111.557054) (xy 270.575786 -111.556589) (xy 270.524449 -111.549563)
			(xy 270.474535 -111.535657) (xy 270.426961 -111.515124) (xy 270.382603 -111.488344) (xy 270.342276 -111.455808)
			(xy 270.306722 -111.418115) (xy 270.291306 -111.397288) (xy 270.285559 -111.389963) (xy 270.270062 -111.379673)
			(xy 270.26108 -111.377222) (xy 270.2306 -111.370364) (xy 270.22132 -111.368643) (xy 270.202661 -111.371366)
			(xy 270.194278 -111.375698) (xy 270.168305 -111.389998) (xy 270.113452 -111.412508) (xy 270.056148 -111.427733)
			(xy 269.997356 -111.435417) (xy 269.96771 -111.435896) (xy 269.938067 -111.435396) (xy 269.879286 -111.427674)
			(xy 269.821988 -111.412448) (xy 269.767127 -111.389971) (xy 269.741142 -111.375698) (xy 269.732723 -111.371465)
			(xy 269.714098 -111.368721) (xy 269.70482 -111.370364) (xy 269.67434 -111.377222) (xy 269.665344 -111.379641)
			(xy 269.649841 -111.38994) (xy 269.644114 -111.397288) (xy 269.62871 -111.418127) (xy 269.593168 -111.45584)
			(xy 269.552846 -111.488392) (xy 269.508485 -111.515181) (xy 269.460905 -111.535715) (xy 269.410983 -111.549615)
			(xy 269.359637 -111.556624) (xy 269.333726 -111.557054) (xy 269.306475 -111.556501) (xy 269.252528 -111.548748)
			(xy 269.200233 -111.533396) (xy 269.150656 -111.510757) (xy 269.104805 -111.481294) (xy 269.063614 -111.445604)
			(xy 269.027922 -111.404416) (xy 268.998455 -111.358567) (xy 268.975814 -111.308991) (xy 268.960458 -111.256697)
			(xy 268.952701 -111.202751) (xy 268.952701 -111.148249) (xy 268.960458 -111.094303) (xy 268.975814 -111.042009)
			(xy 268.998455 -110.992433) (xy 269.027922 -110.946584) (xy 269.063614 -110.905396) (xy 269.104805 -110.869706)
			(xy 269.150656 -110.840243) (xy 269.200233 -110.817604) (xy 269.252528 -110.802252) (xy 269.306475 -110.794499)
			(xy 269.333726 -110.794038) (xy 269.348519 -110.794168) (xy 269.378017 -110.796461) (xy 269.392654 -110.79861)
			(xy 269.40363 -110.799698) (xy 269.424817 -110.793663) (xy 269.433548 -110.786926) (xy 269.491968 -110.736888)
			(xy 269.500005 -110.729329) (xy 269.509213 -110.709302) (xy 269.509748 -110.69828) (xy 269.509748 -110.393988)
			(xy 269.509233 -110.382966) (xy 269.499999 -110.362949) (xy 269.491968 -110.35538) (xy 269.424912 -110.297976)
			(xy 269.40383 -110.29188) (xy 269.392654 -110.293658) (xy 269.378016 -110.295799) (xy 269.348519 -110.298087)
			(xy 269.333726 -110.29823) (xy 269.306474 -110.297724) (xy 269.252523 -110.289971) (xy 269.200225 -110.274618)
			(xy 269.150644 -110.251978) (xy 269.104791 -110.222513) (xy 269.063597 -110.186821) (xy 269.027903 -110.14563)
			(xy 268.998434 -110.099778) (xy 268.975791 -110.050199) (xy 268.960435 -109.997903) (xy 268.952677 -109.943952)
			(xy 211.546301 -109.943952) (xy 211.551023 -109.975091) (xy 211.551018 -110.032573) (xy 211.542391 -110.089404)
			(xy 211.525336 -110.144297) (xy 211.500239 -110.196011) (xy 211.467669 -110.243375) (xy 211.448396 -110.264702)
			(xy 211.441792 -110.27156) (xy 211.43468 -110.289594) (xy 211.43468 -110.378494) (xy 211.441792 -110.396528)
			(xy 211.448396 -110.403386) (xy 211.467676 -110.424705) (xy 211.500244 -110.472068) (xy 211.525335 -110.523782)
			(xy 211.542383 -110.578675) (xy 211.551002 -110.635504) (xy 211.55152 -110.664244) (xy 211.551034 -110.691495)
			(xy 211.543278 -110.745443) (xy 211.527923 -110.797738) (xy 211.505281 -110.847315) (xy 211.475815 -110.893165)
			(xy 211.440124 -110.934356) (xy 211.398933 -110.970047) (xy 211.353083 -110.999513) (xy 211.303506 -111.022155)
			(xy 211.251211 -111.03751) (xy 211.197263 -111.045266) (xy 211.142761 -111.045266) (xy 211.088813 -111.03751)
			(xy 211.036518 -111.022155) (xy 210.986941 -110.999513) (xy 210.941091 -110.970047) (xy 210.8999 -110.934356)
			(xy 210.864209 -110.893165) (xy 210.834743 -110.847315) (xy 210.812101 -110.797738) (xy 210.796746 -110.745443)
			(xy 210.78899 -110.691495) (xy 210.788504 -110.664244) (xy 209.956428 -110.664244) (xy 209.949428 -110.712931)
			(xy 209.934073 -110.765226) (xy 209.911431 -110.814803) (xy 209.881965 -110.860653) (xy 209.846274 -110.901844)
			(xy 209.805083 -110.937535) (xy 209.759233 -110.967001) (xy 209.709656 -110.989643) (xy 209.657361 -111.004998)
			(xy 209.603413 -111.012754) (xy 209.548911 -111.012754) (xy 209.494963 -111.004998) (xy 209.442668 -110.989643)
			(xy 209.393091 -110.967001) (xy 209.347241 -110.937535) (xy 209.30605 -110.901844) (xy 209.270359 -110.860653)
			(xy 209.240893 -110.814803) (xy 209.218251 -110.765226) (xy 209.202896 -110.712931) (xy 209.19514 -110.658983)
			(xy 209.194654 -110.631732) (xy 191.475106 -110.631732) (xy 191.475103 -110.688659) (xy 191.466477 -110.745488)
			(xy 191.449424 -110.80038) (xy 191.42433 -110.852093) (xy 191.391762 -110.899457) (xy 191.37249 -110.920784)
			(xy 191.365886 -110.927642) (xy 191.358774 -110.945676) (xy 191.358774 -111.034576) (xy 191.365886 -111.05261)
			(xy 191.37249 -111.059468) (xy 191.391786 -111.080773) (xy 191.424349 -111.128139) (xy 191.424695 -111.128853)
			(xy 221.497087 -111.128853) (xy 221.497087 -111.074347) (xy 221.504845 -111.020397) (xy 221.520202 -110.9681)
			(xy 221.542846 -110.918521) (xy 221.572315 -110.87267) (xy 221.608011 -110.83148) (xy 221.649205 -110.795789)
			(xy 221.69506 -110.766325) (xy 221.744641 -110.743686) (xy 221.79694 -110.728335) (xy 221.850891 -110.720584)
			(xy 221.878144 -110.720124) (xy 221.905513 -110.720617) (xy 221.959691 -110.728427) (xy 222.012195 -110.74391)
			(xy 222.061942 -110.766746) (xy 222.10791 -110.796465) (xy 222.128842 -110.814104) (xy 222.129096 -110.814358)
			(xy 222.136175 -110.819956) (xy 222.153098 -110.826194) (xy 222.162116 -110.82655) (xy 222.229172 -110.82655)
			(xy 222.238189 -110.82619) (xy 222.255106 -110.819946) (xy 222.262192 -110.814358) (xy 222.262192 -110.814104)
			(xy 222.262446 -110.814104) (xy 222.283379 -110.796463) (xy 222.329347 -110.766739) (xy 222.379093 -110.743893)
			(xy 222.431595 -110.728397) (xy 222.485773 -110.720568) (xy 222.540515 -110.720568) (xy 222.594693 -110.728397)
			(xy 222.647195 -110.743893) (xy 222.696941 -110.766739) (xy 222.742909 -110.796463) (xy 222.763842 -110.814104)
			(xy 222.764096 -110.814358) (xy 222.771175 -110.819956) (xy 222.788098 -110.826194) (xy 222.797116 -110.82655)
			(xy 222.864172 -110.82655) (xy 222.873189 -110.82619) (xy 222.890106 -110.819946) (xy 222.897192 -110.814358)
			(xy 222.897192 -110.814104) (xy 222.897446 -110.814104) (xy 222.918379 -110.796463) (xy 222.964347 -110.766739)
			(xy 223.014093 -110.743893) (xy 223.066595 -110.728397) (xy 223.120773 -110.720568) (xy 223.175515 -110.720568)
			(xy 223.229693 -110.728397) (xy 223.282195 -110.743893) (xy 223.331941 -110.766739) (xy 223.377909 -110.796463)
			(xy 223.398842 -110.814104) (xy 223.399096 -110.814358) (xy 223.406175 -110.819956) (xy 223.423098 -110.826194)
			(xy 223.432116 -110.82655) (xy 223.499172 -110.82655) (xy 223.508189 -110.82619) (xy 223.525106 -110.819946)
			(xy 223.532192 -110.814358) (xy 223.532192 -110.814104) (xy 223.532446 -110.814104) (xy 223.553388 -110.796477)
			(xy 223.599358 -110.766764) (xy 223.649103 -110.743925) (xy 223.701602 -110.728431) (xy 223.755776 -110.7206)
			(xy 223.783144 -110.720124) (xy 223.810395 -110.720549) (xy 223.864343 -110.728311) (xy 223.916637 -110.743671)
			(xy 223.966213 -110.766317) (xy 224.012061 -110.795787) (xy 224.05325 -110.831481) (xy 224.08894 -110.872674)
			(xy 224.118404 -110.918526) (xy 224.141044 -110.968104) (xy 224.156398 -111.0204) (xy 224.164154 -111.074348)
			(xy 224.164154 -111.092354) (xy 224.941334 -111.092354) (xy 224.941334 -111.037846) (xy 224.949091 -110.983894)
			(xy 224.964447 -110.931594) (xy 224.98709 -110.882012) (xy 225.016558 -110.836158) (xy 225.052252 -110.794963)
			(xy 225.093445 -110.759267) (xy 225.139298 -110.729797) (xy 225.188879 -110.707153) (xy 225.241178 -110.691794)
			(xy 225.29513 -110.684035) (xy 225.322384 -110.683548) (xy 225.349754 -110.684012) (xy 225.403934 -110.691828)
			(xy 225.456438 -110.707317) (xy 225.506185 -110.73016) (xy 225.552151 -110.759886) (xy 225.573082 -110.777528)
			(xy 225.573336 -110.777782) (xy 225.580438 -110.783345) (xy 225.597343 -110.789606) (xy 225.606356 -110.789974)
			(xy 225.673412 -110.789974) (xy 225.68243 -110.789628) (xy 225.699347 -110.783374) (xy 225.706432 -110.777782)
			(xy 225.706432 -110.777528) (xy 225.706686 -110.777528) (xy 225.727616 -110.759886) (xy 225.773589 -110.730174)
			(xy 225.823337 -110.707338) (xy 225.875838 -110.691848) (xy 225.930015 -110.684021) (xy 225.957384 -110.683548)
			(xy 225.984634 -110.684098) (xy 226.038581 -110.691852) (xy 226.090875 -110.707205) (xy 226.140451 -110.729844)
			(xy 226.186301 -110.759308) (xy 226.227491 -110.794998) (xy 226.263182 -110.836186) (xy 226.292648 -110.882035)
			(xy 226.315289 -110.93161) (xy 226.330644 -110.983903) (xy 226.338401 -111.03785) (xy 226.338401 -111.09235)
			(xy 226.330644 -111.146297) (xy 226.32038 -111.181252) (xy 227.301534 -111.181252) (xy 227.301534 -111.126748)
			(xy 227.30929 -111.072798) (xy 227.324644 -111.020501) (xy 227.347285 -110.970921) (xy 227.37675 -110.925068)
			(xy 227.41244 -110.883874) (xy 227.45363 -110.848179) (xy 227.499479 -110.818708) (xy 227.549056 -110.796061)
			(xy 227.601351 -110.7807) (xy 227.6553 -110.772937) (xy 227.682552 -110.772448) (xy 227.709922 -110.772931)
			(xy 227.764101 -110.780743) (xy 227.816604 -110.796227) (xy 227.866351 -110.819066) (xy 227.912318 -110.848788)
			(xy 227.93325 -110.866428) (xy 227.933504 -110.866682) (xy 227.940587 -110.872274) (xy 227.957506 -110.878518)
			(xy 227.966524 -110.878874) (xy 228.03358 -110.878874) (xy 228.042597 -110.878513) (xy 228.059514 -110.872269)
			(xy 228.0666 -110.866682) (xy 228.0666 -110.866428) (xy 228.066854 -110.866428) (xy 228.087796 -110.848801)
			(xy 228.133766 -110.819087) (xy 228.183511 -110.796248) (xy 228.236009 -110.780754) (xy 228.290183 -110.772923)
			(xy 228.317552 -110.772448) (xy 228.344804 -110.772996) (xy 228.398754 -110.780746) (xy 228.451051 -110.796097)
			(xy 228.500632 -110.818734) (xy 228.546486 -110.848197) (xy 228.587679 -110.883887) (xy 228.623374 -110.925076)
			(xy 228.644311 -110.957652) (xy 228.907791 -110.957652) (xy 228.907791 -110.903148) (xy 228.915549 -110.849197)
			(xy 228.930906 -110.796901) (xy 228.95355 -110.747322) (xy 228.983019 -110.701471) (xy 229.018715 -110.660281)
			(xy 229.059909 -110.624591) (xy 229.105764 -110.595127) (xy 229.155346 -110.572489) (xy 229.207644 -110.557139)
			(xy 229.261595 -110.549388) (xy 229.288848 -110.548928) (xy 229.316217 -110.549418) (xy 229.370396 -110.557229)
			(xy 229.422899 -110.572712) (xy 229.472646 -110.595549) (xy 229.518614 -110.625269) (xy 229.539546 -110.642908)
			(xy 229.5398 -110.643162) (xy 229.546877 -110.648762) (xy 229.563801 -110.654999) (xy 229.57282 -110.655354)
			(xy 229.639876 -110.655354) (xy 229.648893 -110.654995) (xy 229.66581 -110.64875) (xy 229.672896 -110.643162)
			(xy 229.672896 -110.642908) (xy 229.67315 -110.642908) (xy 229.694083 -110.625267) (xy 229.740051 -110.595543)
			(xy 229.789797 -110.572697) (xy 229.842299 -110.557201) (xy 229.896477 -110.549372) (xy 229.951219 -110.549372)
			(xy 230.005397 -110.557201) (xy 230.057899 -110.572697) (xy 230.107645 -110.595543) (xy 230.153613 -110.625267)
			(xy 230.174546 -110.642908) (xy 230.1748 -110.643162) (xy 230.181877 -110.648762) (xy 230.198801 -110.654999)
			(xy 230.20782 -110.655354) (xy 230.274876 -110.655354) (xy 230.283893 -110.654995) (xy 230.30081 -110.64875)
			(xy 230.307896 -110.643162) (xy 230.307896 -110.642908) (xy 230.30815 -110.642908) (xy 230.329091 -110.62528)
			(xy 230.375061 -110.595566) (xy 230.424807 -110.572728) (xy 230.477305 -110.557234) (xy 230.531479 -110.549403)
			(xy 230.558848 -110.548928) (xy 230.5861 -110.549345) (xy 230.640047 -110.557108) (xy 230.692341 -110.572469)
			(xy 230.741917 -110.595115) (xy 230.787766 -110.624585) (xy 230.828954 -110.66028) (xy 230.864644 -110.701473)
			(xy 230.894108 -110.747325) (xy 230.916748 -110.796904) (xy 230.932102 -110.8492) (xy 230.939858 -110.903148)
			(xy 230.939858 -110.953156) (xy 233.725619 -110.953156) (xy 233.725619 -110.898644) (xy 233.733377 -110.844686)
			(xy 233.748736 -110.792381) (xy 233.771382 -110.742795) (xy 233.800855 -110.696937) (xy 233.836554 -110.65574)
			(xy 233.877753 -110.620043) (xy 233.923613 -110.590572) (xy 233.9732 -110.567929) (xy 234.025505 -110.552573)
			(xy 234.079464 -110.544818) (xy 234.10672 -110.544356) (xy 234.133035 -110.544792) (xy 234.185166 -110.552031)
			(xy 234.23581 -110.566355) (xy 234.284009 -110.587493) (xy 234.328852 -110.615046) (xy 234.369489 -110.648491)
			(xy 234.387644 -110.667546) (xy 234.395155 -110.674961) (xy 234.414443 -110.68348) (xy 234.424982 -110.684056)
			(xy 234.499658 -110.684056) (xy 234.510208 -110.683531) (xy 234.529505 -110.674994) (xy 234.536996 -110.667546)
			(xy 234.556816 -110.646758) (xy 234.601588 -110.610783) (xy 234.651246 -110.581923) (xy 234.704668 -110.56083)
			(xy 234.760647 -110.547981) (xy 234.81792 -110.543666) (xy 234.875193 -110.547981) (xy 234.931172 -110.56083)
			(xy 234.984594 -110.581923) (xy 235.034252 -110.610783) (xy 235.079024 -110.646758) (xy 235.098844 -110.667546)
			(xy 235.106355 -110.674961) (xy 235.125643 -110.68348) (xy 235.136182 -110.684056) (xy 235.210858 -110.684056)
			(xy 235.221408 -110.683531) (xy 235.240705 -110.674994) (xy 235.248196 -110.667546) (xy 235.26635 -110.648489)
			(xy 235.306981 -110.615034) (xy 235.351822 -110.587477) (xy 235.400023 -110.566339) (xy 235.45067 -110.552021)
			(xy 235.502804 -110.544795) (xy 235.52912 -110.544356) (xy 235.556368 -110.544916) (xy 235.610308 -110.552674)
			(xy 235.662595 -110.568029) (xy 235.712165 -110.590669) (xy 235.758009 -110.620133) (xy 235.799193 -110.655821)
			(xy 235.834879 -110.697007) (xy 235.86434 -110.742852) (xy 235.886978 -110.792423) (xy 235.902331 -110.844711)
			(xy 235.910086 -110.898652) (xy 235.910086 -110.953148) (xy 235.902331 -111.007089) (xy 235.886978 -111.059377)
			(xy 235.86434 -111.108948) (xy 235.852719 -111.127032) (xy 246.48871 -111.127032) (xy 246.492781 -111.07141)
			(xy 246.504907 -111.016973) (xy 246.52483 -110.964882) (xy 246.552126 -110.916247) (xy 246.586212 -110.872104)
			(xy 246.626361 -110.833395) (xy 246.671719 -110.800944) (xy 246.721319 -110.775443) (xy 246.774103 -110.757436)
			(xy 246.828946 -110.747306) (xy 246.88468 -110.745269) (xy 246.940117 -110.751369) (xy 246.994074 -110.765475)
			(xy 247.045403 -110.787287) (xy 247.093009 -110.816341) (xy 247.135877 -110.852016) (xy 247.173094 -110.893553)
			(xy 247.203867 -110.940066) (xy 247.227539 -110.990563) (xy 247.243607 -111.04397) (xy 247.251727 -111.099146)
			(xy 247.252236 -111.127032) (xy 247.50471 -111.127032) (xy 247.508781 -111.07141) (xy 247.520907 -111.016973)
			(xy 247.54083 -110.964882) (xy 247.568126 -110.916247) (xy 247.602212 -110.872104) (xy 247.642361 -110.833395)
			(xy 247.687719 -110.800944) (xy 247.737319 -110.775443) (xy 247.790103 -110.757436) (xy 247.844946 -110.747306)
			(xy 247.90068 -110.745269) (xy 247.956117 -110.751369) (xy 248.010074 -110.765475) (xy 248.061403 -110.787287)
			(xy 248.109009 -110.816341) (xy 248.151877 -110.852016) (xy 248.189094 -110.893553) (xy 248.219867 -110.940066)
			(xy 248.243539 -110.990563) (xy 248.259607 -111.04397) (xy 248.267727 -111.099146) (xy 248.268236 -111.127032)
			(xy 248.52071 -111.127032) (xy 248.524781 -111.07141) (xy 248.536907 -111.016973) (xy 248.55683 -110.964882)
			(xy 248.584126 -110.916247) (xy 248.618212 -110.872104) (xy 248.658361 -110.833395) (xy 248.703719 -110.800944)
			(xy 248.753319 -110.775443) (xy 248.806103 -110.757436) (xy 248.860946 -110.747306) (xy 248.91668 -110.745269)
			(xy 248.972117 -110.751369) (xy 249.026074 -110.765475) (xy 249.077403 -110.787287) (xy 249.125009 -110.816341)
			(xy 249.167877 -110.852016) (xy 249.205094 -110.893553) (xy 249.235867 -110.940066) (xy 249.259539 -110.990563)
			(xy 249.275607 -111.04397) (xy 249.283727 -111.099146) (xy 249.284236 -111.127032) (xy 249.283727 -111.154918)
			(xy 249.275607 -111.210094) (xy 249.259539 -111.263501) (xy 249.235867 -111.313998) (xy 249.205094 -111.360511)
			(xy 249.167877 -111.402048) (xy 249.125009 -111.437723) (xy 249.077403 -111.466777) (xy 249.026074 -111.488589)
			(xy 248.972117 -111.502695) (xy 248.91668 -111.508795) (xy 248.860946 -111.506758) (xy 248.806103 -111.496628)
			(xy 248.753319 -111.478621) (xy 248.703719 -111.45312) (xy 248.658361 -111.420669) (xy 248.618212 -111.38196)
			(xy 248.584126 -111.337817) (xy 248.55683 -111.289182) (xy 248.536907 -111.237091) (xy 248.524781 -111.182654)
			(xy 248.52071 -111.127032) (xy 248.268236 -111.127032) (xy 248.267727 -111.154918) (xy 248.259607 -111.210094)
			(xy 248.243539 -111.263501) (xy 248.219867 -111.313998) (xy 248.189094 -111.360511) (xy 248.151877 -111.402048)
			(xy 248.109009 -111.437723) (xy 248.061403 -111.466777) (xy 248.010074 -111.488589) (xy 247.956117 -111.502695)
			(xy 247.90068 -111.508795) (xy 247.844946 -111.506758) (xy 247.790103 -111.496628) (xy 247.737319 -111.478621)
			(xy 247.687719 -111.45312) (xy 247.642361 -111.420669) (xy 247.602212 -111.38196) (xy 247.568126 -111.337817)
			(xy 247.54083 -111.289182) (xy 247.520907 -111.237091) (xy 247.508781 -111.182654) (xy 247.50471 -111.127032)
			(xy 247.252236 -111.127032) (xy 247.251727 -111.154918) (xy 247.243607 -111.210094) (xy 247.227539 -111.263501)
			(xy 247.203867 -111.313998) (xy 247.173094 -111.360511) (xy 247.135877 -111.402048) (xy 247.093009 -111.437723)
			(xy 247.045403 -111.466777) (xy 246.994074 -111.488589) (xy 246.940117 -111.502695) (xy 246.88468 -111.508795)
			(xy 246.828946 -111.506758) (xy 246.774103 -111.496628) (xy 246.721319 -111.478621) (xy 246.671719 -111.45312)
			(xy 246.626361 -111.420669) (xy 246.586212 -111.38196) (xy 246.552126 -111.337817) (xy 246.52483 -111.289182)
			(xy 246.504907 -111.237091) (xy 246.492781 -111.182654) (xy 246.48871 -111.127032) (xy 235.852719 -111.127032)
			(xy 235.834879 -111.154793) (xy 235.799193 -111.195979) (xy 235.758009 -111.231667) (xy 235.712165 -111.261131)
			(xy 235.662595 -111.283771) (xy 235.610308 -111.299126) (xy 235.556368 -111.306884) (xy 235.52912 -111.307372)
			(xy 235.502806 -111.3069) (xy 235.450677 -111.299667) (xy 235.400034 -111.28535) (xy 235.351835 -111.264218)
			(xy 235.306992 -111.236673) (xy 235.266352 -111.203234) (xy 235.248196 -111.184182) (xy 235.24068 -111.176774)
			(xy 235.221396 -111.168254) (xy 235.210858 -111.167672) (xy 235.136182 -111.167672) (xy 235.125637 -111.16824)
			(xy 235.106342 -111.176749) (xy 235.098844 -111.184182) (xy 235.079024 -111.20497) (xy 235.034252 -111.240945)
			(xy 234.984594 -111.269805) (xy 234.931172 -111.290898) (xy 234.875193 -111.303747) (xy 234.81792 -111.308062)
			(xy 234.760647 -111.303747) (xy 234.704668 -111.290898) (xy 234.651246 -111.269805) (xy 234.601588 -111.240945)
			(xy 234.556816 -111.20497) (xy 234.536996 -111.184182) (xy 234.52948 -111.176774) (xy 234.510196 -111.168254)
			(xy 234.499658 -111.167672) (xy 234.424982 -111.167672) (xy 234.414437 -111.16824) (xy 234.395142 -111.176749)
			(xy 234.387644 -111.184182) (xy 234.369505 -111.203254) (xy 234.328872 -111.236711) (xy 234.284029 -111.264268)
			(xy 234.235824 -111.285404) (xy 234.185174 -111.299717) (xy 234.133037 -111.306936) (xy 234.10672 -111.307372)
			(xy 234.079464 -111.306982) (xy 234.025505 -111.299227) (xy 233.9732 -111.283871) (xy 233.923613 -111.261228)
			(xy 233.877753 -111.231757) (xy 233.836554 -111.19606) (xy 233.800855 -111.154863) (xy 233.771382 -111.109005)
			(xy 233.748736 -111.059419) (xy 233.733377 -111.007114) (xy 233.725619 -110.953156) (xy 230.939858 -110.953156)
			(xy 230.939858 -110.957652) (xy 230.932102 -111.0116) (xy 230.916748 -111.063896) (xy 230.894108 -111.113475)
			(xy 230.864644 -111.159327) (xy 230.828954 -111.20052) (xy 230.787766 -111.236215) (xy 230.741917 -111.265685)
			(xy 230.692341 -111.288331) (xy 230.640047 -111.303692) (xy 230.5861 -111.311455) (xy 230.558848 -111.311944)
			(xy 230.531478 -111.311463) (xy 230.477299 -111.303651) (xy 230.424796 -111.288166) (xy 230.375048 -111.265327)
			(xy 230.329082 -111.235605) (xy 230.30815 -111.217964) (xy 230.307896 -111.21771) (xy 230.300814 -111.212117)
			(xy 230.283894 -111.205874) (xy 230.274876 -111.205518) (xy 230.20782 -111.205518) (xy 230.198804 -111.20588)
			(xy 230.181886 -111.212124) (xy 230.1748 -111.21771) (xy 230.174546 -111.217964) (xy 230.153613 -111.235605)
			(xy 230.107645 -111.265329) (xy 230.057899 -111.288175) (xy 230.005397 -111.303671) (xy 229.951219 -111.3115)
			(xy 229.896477 -111.3115) (xy 229.842299 -111.303671) (xy 229.789797 -111.288175) (xy 229.740051 -111.265329)
			(xy 229.694083 -111.235605) (xy 229.67315 -111.217964) (xy 229.672896 -111.21771) (xy 229.665814 -111.212117)
			(xy 229.648894 -111.205874) (xy 229.639876 -111.205518) (xy 229.57282 -111.205518) (xy 229.563804 -111.20588)
			(xy 229.546886 -111.212124) (xy 229.5398 -111.21771) (xy 229.5398 -111.217964) (xy 229.539546 -111.217964)
			(xy 229.518603 -111.235589) (xy 229.472634 -111.265305) (xy 229.422889 -111.288144) (xy 229.370391 -111.303638)
			(xy 229.316217 -111.311469) (xy 229.288848 -111.311944) (xy 229.261595 -111.311412) (xy 229.207644 -111.303661)
			(xy 229.155346 -111.288311) (xy 229.105764 -111.265673) (xy 229.059909 -111.236209) (xy 229.018715 -111.200519)
			(xy 228.983019 -111.159329) (xy 228.95355 -111.113478) (xy 228.930906 -111.063899) (xy 228.915549 -111.011603)
			(xy 228.907791 -110.957652) (xy 228.644311 -110.957652) (xy 228.652843 -110.970926) (xy 228.675487 -111.020504)
			(xy 228.690843 -111.072799) (xy 228.698601 -111.126748) (xy 228.698601 -111.181252) (xy 228.690843 -111.235201)
			(xy 228.675487 -111.287496) (xy 228.652843 -111.337074) (xy 228.623374 -111.382924) (xy 228.587679 -111.424113)
			(xy 228.546486 -111.459803) (xy 228.500632 -111.489266) (xy 228.451051 -111.511903) (xy 228.398754 -111.527254)
			(xy 228.344804 -111.535004) (xy 228.317552 -111.535464) (xy 228.290182 -111.534976) (xy 228.236004 -111.527165)
			(xy 228.183501 -111.511681) (xy 228.133753 -111.488844) (xy 228.087786 -111.459124) (xy 228.066854 -111.441484)
			(xy 228.0666 -111.44123) (xy 228.059524 -111.435629) (xy 228.042599 -111.429393) (xy 228.03358 -111.429038)
			(xy 227.966524 -111.429038) (xy 227.957507 -111.429398) (xy 227.94059 -111.435643) (xy 227.933504 -111.44123)
			(xy 227.933504 -111.441484) (xy 227.93325 -111.441484) (xy 227.912308 -111.459111) (xy 227.866338 -111.488825)
			(xy 227.816593 -111.511663) (xy 227.764095 -111.527157) (xy 227.709921 -111.534989) (xy 227.682552 -111.535464)
			(xy 227.6553 -111.535063) (xy 227.601351 -111.5273) (xy 227.549056 -111.511939) (xy 227.499479 -111.489292)
			(xy 227.45363 -111.459821) (xy 227.41244 -111.424126) (xy 227.37675 -111.382932) (xy 227.347285 -111.337079)
			(xy 227.324644 -111.287499) (xy 227.30929 -111.235202) (xy 227.301534 -111.181252) (xy 226.32038 -111.181252)
			(xy 226.315289 -111.19859) (xy 226.292648 -111.248165) (xy 226.263182 -111.294014) (xy 226.227491 -111.335202)
			(xy 226.186301 -111.370892) (xy 226.140451 -111.400356) (xy 226.090875 -111.422995) (xy 226.038581 -111.438348)
			(xy 225.984634 -111.446102) (xy 225.957384 -111.446564) (xy 225.930013 -111.446116) (xy 225.875833 -111.438295)
			(xy 225.823329 -111.422802) (xy 225.773583 -111.399956) (xy 225.727617 -111.370227) (xy 225.706686 -111.352584)
			(xy 225.706432 -111.35233) (xy 225.699346 -111.346742) (xy 225.682429 -111.340498) (xy 225.673412 -111.340138)
			(xy 225.606356 -111.340138) (xy 225.597341 -111.340514) (xy 225.580423 -111.346747) (xy 225.573336 -111.35233)
			(xy 225.573336 -111.352584) (xy 225.573082 -111.352584) (xy 225.552128 -111.370196) (xy 225.506161 -111.399912)
			(xy 225.456419 -111.422754) (xy 225.403924 -111.438251) (xy 225.349752 -111.446086) (xy 225.322384 -111.446564)
			(xy 225.29513 -111.446165) (xy 225.241178 -111.438406) (xy 225.188879 -111.423047) (xy 225.139298 -111.400403)
			(xy 225.093445 -111.370933) (xy 225.052252 -111.335237) (xy 225.016558 -111.294042) (xy 224.98709 -111.248188)
			(xy 224.964447 -111.198606) (xy 224.949091 -111.146306) (xy 224.941334 -111.092354) (xy 224.164154 -111.092354)
			(xy 224.164154 -111.128852) (xy 224.156398 -111.1828) (xy 224.141044 -111.235096) (xy 224.118404 -111.284674)
			(xy 224.08894 -111.330526) (xy 224.05325 -111.371719) (xy 224.012061 -111.407413) (xy 223.966213 -111.436883)
			(xy 223.916637 -111.459529) (xy 223.864343 -111.474889) (xy 223.810395 -111.482651) (xy 223.783144 -111.48314)
			(xy 223.755774 -111.482663) (xy 223.701595 -111.47485) (xy 223.649091 -111.459364) (xy 223.599344 -111.436525)
			(xy 223.553377 -111.406801) (xy 223.532446 -111.38916) (xy 223.532192 -111.388906) (xy 223.525111 -111.383311)
			(xy 223.50819 -111.377069) (xy 223.499172 -111.376714) (xy 223.432116 -111.376714) (xy 223.4231 -111.377075)
			(xy 223.406182 -111.38332) (xy 223.399096 -111.388906) (xy 223.398842 -111.38916) (xy 223.377909 -111.406801)
			(xy 223.331941 -111.436525) (xy 223.282195 -111.459371) (xy 223.229693 -111.474867) (xy 223.175515 -111.482696)
			(xy 223.120773 -111.482696) (xy 223.066595 -111.474867) (xy 223.014093 -111.459371) (xy 222.964347 -111.436525)
			(xy 222.918379 -111.406801) (xy 222.897446 -111.38916) (xy 222.897192 -111.388906) (xy 222.890111 -111.383311)
			(xy 222.87319 -111.377069) (xy 222.864172 -111.376714) (xy 222.797116 -111.376714) (xy 222.7881 -111.377075)
			(xy 222.771182 -111.38332) (xy 222.764096 -111.388906) (xy 222.764096 -111.38916) (xy 222.763842 -111.38916)
			(xy 222.742909 -111.406801) (xy 222.696941 -111.436525) (xy 222.647195 -111.459371) (xy 222.594693 -111.474867)
			(xy 222.540515 -111.482696) (xy 222.485773 -111.482696) (xy 222.431595 -111.474867) (xy 222.379093 -111.459371)
			(xy 222.329347 -111.436525) (xy 222.283379 -111.406801) (xy 222.262446 -111.38916) (xy 222.262192 -111.388906)
			(xy 222.255111 -111.383311) (xy 222.23819 -111.377069) (xy 222.229172 -111.376714) (xy 222.162116 -111.376714)
			(xy 222.1531 -111.377075) (xy 222.136182 -111.38332) (xy 222.129096 -111.388906) (xy 222.129096 -111.38916)
			(xy 222.128842 -111.38916) (xy 222.1079 -111.406787) (xy 222.06193 -111.436502) (xy 222.012186 -111.459341)
			(xy 221.959687 -111.474835) (xy 221.905513 -111.482665) (xy 221.878144 -111.48314) (xy 221.850891 -111.482616)
			(xy 221.79694 -111.474865) (xy 221.744641 -111.459514) (xy 221.69506 -111.436875) (xy 221.649205 -111.407411)
			(xy 221.608011 -111.37172) (xy 221.572315 -111.33053) (xy 221.542846 -111.284679) (xy 221.520202 -111.2351)
			(xy 221.504845 -111.182803) (xy 221.497087 -111.128853) (xy 191.424695 -111.128853) (xy 191.449438 -111.179855)
			(xy 191.466486 -111.234749) (xy 191.475106 -111.291579) (xy 191.475103 -111.349059) (xy 191.466477 -111.405888)
			(xy 191.449424 -111.46078) (xy 191.42433 -111.512493) (xy 191.391762 -111.559857) (xy 191.37249 -111.581184)
			(xy 191.365886 -111.588042) (xy 191.358774 -111.606076) (xy 191.358774 -111.694976) (xy 191.365886 -111.71301)
			(xy 191.37249 -111.719868) (xy 191.391778 -111.74118) (xy 191.424341 -111.788547) (xy 191.449429 -111.840262)
			(xy 191.466476 -111.895156) (xy 191.475095 -111.951986) (xy 191.475614 -111.980726) (xy 191.475146 -112.007978)
			(xy 191.467387 -112.061926) (xy 191.452028 -112.11422) (xy 191.429385 -112.163797) (xy 191.399916 -112.209647)
			(xy 191.364223 -112.250837) (xy 191.323031 -112.286528) (xy 191.27718 -112.315994) (xy 191.227602 -112.338635)
			(xy 191.175306 -112.353991) (xy 191.121358 -112.361748) (xy 191.094106 -112.362234) (xy 191.067793 -112.361752)
			(xy 191.015665 -112.354518) (xy 190.965023 -112.340201) (xy 190.916824 -112.319072) (xy 190.87198 -112.291529)
			(xy 190.83134 -112.258094) (xy 190.813182 -112.239044) (xy 190.805663 -112.231639) (xy 190.786381 -112.223115)
			(xy 190.775844 -112.222534) (xy 190.701168 -112.222534) (xy 190.69062 -112.223076) (xy 190.671323 -112.231601)
			(xy 190.66383 -112.239044) (xy 190.645661 -112.258086) (xy 190.605034 -112.291543) (xy 190.560196 -112.319103)
			(xy 190.511998 -112.340243) (xy 190.461353 -112.354564) (xy 190.409221 -112.361793) (xy 190.382906 -112.362234)
			(xy 190.355656 -112.361717) (xy 190.301711 -112.353962) (xy 190.249418 -112.338609) (xy 190.199843 -112.31597)
			(xy 190.153994 -112.286507) (xy 190.112804 -112.250819) (xy 190.077112 -112.209632) (xy 190.047645 -112.163785)
			(xy 190.025003 -112.114212) (xy 190.009645 -112.06192) (xy 190.001886 -112.007976) (xy 190.001398 -111.980726)
			(xy 188.583491 -111.980726) (xy 188.571422 -111.997481) (xy 188.529503 -112.039825) (xy 188.505846 -112.057942)
			(xy 188.499066 -112.063299) (xy 188.489336 -112.077569) (xy 188.484917 -112.094265) (xy 188.485272 -112.1029)
			(xy 188.491876 -112.188752) (xy 188.492789 -112.197267) (xy 188.499564 -112.212984) (xy 188.511152 -112.225579)
			(xy 188.518546 -112.2299) (xy 188.5188 -112.2299) (xy 188.541614 -112.242281) (xy 188.583906 -112.272376)
			(xy 188.621726 -112.30793) (xy 188.654374 -112.348285) (xy 188.681247 -112.392695) (xy 188.682024 -112.394492)
			(xy 197.480172 -112.394492) (xy 197.484243 -112.33887) (xy 197.496369 -112.284433) (xy 197.516292 -112.232342)
			(xy 197.543588 -112.183707) (xy 197.577674 -112.139564) (xy 197.617823 -112.100855) (xy 197.663181 -112.068404)
			(xy 197.712781 -112.042903) (xy 197.765565 -112.024896) (xy 197.820408 -112.014766) (xy 197.876142 -112.012729)
			(xy 197.931579 -112.018829) (xy 197.985536 -112.032935) (xy 198.036865 -112.054747) (xy 198.084471 -112.083801)
			(xy 198.127339 -112.119476) (xy 198.143438 -112.137444) (xy 203.970126 -112.137444) (xy 203.974197 -112.081822)
			(xy 203.986323 -112.027385) (xy 204.006246 -111.975294) (xy 204.033542 -111.926659) (xy 204.067628 -111.882516)
			(xy 204.107777 -111.843807) (xy 204.153135 -111.811356) (xy 204.202735 -111.785855) (xy 204.255519 -111.767848)
			(xy 204.310362 -111.757718) (xy 204.366096 -111.755681) (xy 204.421533 -111.761781) (xy 204.47549 -111.775887)
			(xy 204.526819 -111.797699) (xy 204.574425 -111.826753) (xy 204.617293 -111.862428) (xy 204.65451 -111.903965)
			(xy 204.685283 -111.950478) (xy 204.708955 -112.000975) (xy 204.725023 -112.054382) (xy 204.733143 -112.109558)
			(xy 204.733652 -112.137444) (xy 204.733143 -112.16533) (xy 204.725023 -112.220506) (xy 204.708955 -112.273913)
			(xy 204.685283 -112.32441) (xy 204.65451 -112.370923) (xy 204.617293 -112.41246) (xy 204.574425 -112.448135)
			(xy 204.526819 -112.477189) (xy 204.47549 -112.499001) (xy 204.421533 -112.513107) (xy 204.366096 -112.519207)
			(xy 204.310362 -112.51717) (xy 204.255519 -112.50704) (xy 204.202735 -112.489033) (xy 204.153135 -112.463532)
			(xy 204.107777 -112.431081) (xy 204.067628 -112.392372) (xy 204.033542 -112.348229) (xy 204.006246 -112.299594)
			(xy 203.986323 -112.247503) (xy 203.974197 -112.193066) (xy 203.970126 -112.137444) (xy 198.143438 -112.137444)
			(xy 198.164556 -112.161013) (xy 198.195329 -112.207526) (xy 198.219001 -112.258023) (xy 198.235069 -112.31143)
			(xy 198.243189 -112.366606) (xy 198.243698 -112.394492) (xy 198.243189 -112.422378) (xy 198.235069 -112.477554)
			(xy 198.219001 -112.530961) (xy 198.205082 -112.560653) (xy 205.549185 -112.560653) (xy 205.549185 -112.506147)
			(xy 205.556943 -112.452196) (xy 205.5723 -112.399899) (xy 205.594944 -112.35032) (xy 205.624414 -112.304468)
			(xy 205.66011 -112.263277) (xy 205.701305 -112.227587) (xy 205.74716 -112.198122) (xy 205.796742 -112.175484)
			(xy 205.849041 -112.160133) (xy 205.902993 -112.152382) (xy 205.930246 -112.151922) (xy 205.9305 -112.151922)
			(xy 205.95846 -112.152404) (xy 206.013778 -112.160584) (xy 206.067304 -112.17677) (xy 206.092806 -112.188244)
			(xy 206.104265 -112.193019) (xy 206.12904 -112.191947) (xy 206.14005 -112.186212) (xy 206.21244 -112.144302)
			(xy 206.222682 -112.137528) (xy 206.235819 -112.116829) (xy 206.237586 -112.104678) (xy 206.237586 -112.10417)
			(xy 206.240354 -112.075838) (xy 206.253235 -112.020389) (xy 206.274214 -111.967471) (xy 206.302826 -111.918258)
			(xy 206.338433 -111.873844) (xy 206.380246 -111.835216) (xy 206.427336 -111.803231) (xy 206.478657 -111.7786)
			(xy 206.533068 -111.761871) (xy 206.589361 -111.753414) (xy 206.617824 -111.752888) (xy 206.647802 -111.753455)
			(xy 206.707019 -111.76285) (xy 206.764038 -111.78139) (xy 206.817456 -111.808618) (xy 206.865959 -111.843864)
			(xy 206.887572 -111.864648) (xy 206.887826 -111.864902) (xy 206.895317 -111.871548) (xy 206.913886 -111.878995)
			(xy 206.923894 -111.87938) (xy 207.007206 -111.878364) (xy 207.025748 -111.87049) (xy 207.03286 -111.86287)
			(xy 207.050958 -111.844577) (xy 207.09117 -111.812468) (xy 207.13533 -111.786052) (xy 207.182639 -111.765808)
			(xy 207.232238 -111.752102) (xy 207.283229 -111.745184) (xy 207.308958 -111.74476) (xy 207.336208 -111.745294)
			(xy 207.390155 -111.753045) (xy 207.44245 -111.768394) (xy 207.492028 -111.791029) (xy 207.537879 -111.82049)
			(xy 207.579072 -111.856176) (xy 207.614766 -111.897361) (xy 207.644235 -111.943207) (xy 207.66688 -111.992781)
			(xy 207.68224 -112.045073) (xy 207.69 -112.099018) (xy 207.690466 -112.126268) (xy 207.690035 -112.152714)
			(xy 207.682721 -112.205097) (xy 207.668242 -112.255968) (xy 207.646877 -112.304352) (xy 207.619034 -112.349322)
			(xy 207.585248 -112.390016) (xy 207.546165 -112.425653) (xy 207.524604 -112.440974) (xy 207.51593 -112.447449)
			(xy 207.504608 -112.46587) (xy 207.50276 -112.476534) (xy 207.49895 -112.508792) (xy 207.498044 -112.519483)
			(xy 207.504222 -112.540009) (xy 207.510888 -112.548416) (xy 207.52435 -112.564672) (xy 207.531976 -112.573458)
			(xy 207.552863 -112.58365) (xy 207.564482 -112.58423) (xy 207.644238 -112.58423) (xy 207.655875 -112.583723)
			(xy 207.676785 -112.573514) (xy 207.68437 -112.564672) (xy 207.702571 -112.542197) (xy 207.744589 -112.502463)
			(xy 207.792123 -112.469523) (xy 207.844082 -112.444134) (xy 207.899277 -112.426875) (xy 207.956445 -112.418143)
			(xy 207.98536 -112.417606) (xy 208.012605 -112.418051) (xy 208.066539 -112.425816) (xy 208.118819 -112.441179)
			(xy 208.16838 -112.463828) (xy 208.214212 -112.4933) (xy 208.255382 -112.528997) (xy 208.291051 -112.570191)
			(xy 208.306162 -112.592866) (xy 208.311039 -112.599868) (xy 208.324434 -112.610417) (xy 208.340561 -112.615954)
			(xy 208.349088 -112.616234) (xy 208.434432 -112.616234) (xy 208.442951 -112.615906) (xy 208.45906 -112.610359)
			(xy 208.472471 -112.599851) (xy 208.477358 -112.592866) (xy 208.492507 -112.570218) (xy 208.528167 -112.529022)
			(xy 208.56933 -112.493323) (xy 208.615156 -112.463848) (xy 208.664711 -112.441199) (xy 208.716987 -112.425836)
			(xy 208.770917 -112.418072) (xy 208.79816 -112.417606) (xy 208.825416 -112.418038) (xy 208.879373 -112.425791)
			(xy 208.931678 -112.441144) (xy 208.981265 -112.463785) (xy 209.027125 -112.493253) (xy 209.068324 -112.528948)
			(xy 209.080132 -112.542574) (xy 230.040434 -112.542574) (xy 230.040877 -112.515203) (xy 230.048699 -112.461022)
			(xy 230.064193 -112.408519) (xy 230.08704 -112.358772) (xy 230.11677 -112.312807) (xy 230.134414 -112.291876)
			(xy 230.134668 -112.291622) (xy 230.140259 -112.284539) (xy 230.146501 -112.267619) (xy 230.14686 -112.258602)
			(xy 230.14686 -112.191546) (xy 230.14649 -112.18253) (xy 230.140252 -112.165613) (xy 230.134668 -112.158526)
			(xy 230.134414 -112.158526) (xy 230.134414 -112.158272) (xy 230.116797 -112.137322) (xy 230.087082 -112.091354)
			(xy 230.064241 -112.041611) (xy 230.048745 -111.989115) (xy 230.040911 -111.934942) (xy 230.040434 -111.907574)
			(xy 230.04092 -111.880323) (xy 230.048676 -111.826375) (xy 230.064031 -111.77408) (xy 230.086673 -111.724503)
			(xy 230.116139 -111.678653) (xy 230.15183 -111.637462) (xy 230.193021 -111.601771) (xy 230.238871 -111.572305)
			(xy 230.288448 -111.549663) (xy 230.340743 -111.534308) (xy 230.394691 -111.526552) (xy 230.449193 -111.526552)
			(xy 230.503141 -111.534308) (xy 230.555436 -111.549663) (xy 230.605013 -111.572305) (xy 230.650863 -111.601771)
			(xy 230.692054 -111.637462) (xy 230.727745 -111.678653) (xy 230.757211 -111.724503) (xy 230.779853 -111.77408)
			(xy 230.795208 -111.826375) (xy 230.802964 -111.880323) (xy 230.80345 -111.907574) (xy 230.802981 -111.934944)
			(xy 230.795166 -111.989124) (xy 230.779678 -112.041627) (xy 230.756837 -112.091374) (xy 230.727112 -112.137341)
			(xy 230.70947 -112.158272) (xy 230.709216 -112.158526) (xy 230.703656 -112.165631) (xy 230.697393 -112.182534)
			(xy 230.697024 -112.191546) (xy 230.697024 -112.258602) (xy 230.697375 -112.26762) (xy 230.703626 -112.284537)
			(xy 230.709216 -112.291622) (xy 230.70947 -112.291622) (xy 230.70947 -112.291876) (xy 230.727107 -112.31281)
			(xy 230.75682 -112.358782) (xy 230.779657 -112.408529) (xy 230.795148 -112.461029) (xy 230.802976 -112.515205)
			(xy 230.80345 -112.542574) (xy 230.802964 -112.569825) (xy 230.795208 -112.623773) (xy 230.779853 -112.676068)
			(xy 230.759734 -112.72012) (xy 232.673906 -112.72012) (xy 232.674382 -112.69275) (xy 232.682197 -112.638571)
			(xy 232.697684 -112.586068) (xy 232.720524 -112.536321) (xy 232.750246 -112.490354) (xy 232.767886 -112.469422)
			(xy 232.76814 -112.469168) (xy 232.773709 -112.46207) (xy 232.779965 -112.445162) (xy 232.780332 -112.436148)
			(xy 232.780332 -112.369092) (xy 232.779972 -112.360076) (xy 232.773726 -112.343159) (xy 232.76814 -112.336072)
			(xy 232.767886 -112.336072) (xy 232.767886 -112.335818) (xy 232.75024 -112.314892) (xy 232.720529 -112.268917)
			(xy 232.697695 -112.219168) (xy 232.682206 -112.166666) (xy 232.674379 -112.11249) (xy 232.673906 -112.08512)
			(xy 232.674392 -112.057869) (xy 232.682148 -112.003921) (xy 232.697503 -111.951626) (xy 232.720145 -111.902049)
			(xy 232.749611 -111.856199) (xy 232.785302 -111.815008) (xy 232.826493 -111.779317) (xy 232.872343 -111.749851)
			(xy 232.92192 -111.727209) (xy 232.974215 -111.711854) (xy 233.028163 -111.704098) (xy 233.082665 -111.704098)
			(xy 233.136613 -111.711854) (xy 233.188908 -111.727209) (xy 233.238485 -111.749851) (xy 233.284335 -111.779317)
			(xy 233.325526 -111.815008) (xy 233.361217 -111.856199) (xy 233.390683 -111.902049) (xy 233.413325 -111.951626)
			(xy 233.427314 -111.999268) (xy 238.85347 -111.999268) (xy 238.857541 -111.943646) (xy 238.869667 -111.889209)
			(xy 238.88959 -111.837118) (xy 238.916886 -111.788483) (xy 238.950972 -111.74434) (xy 238.991121 -111.705631)
			(xy 239.036479 -111.67318) (xy 239.086079 -111.647679) (xy 239.138863 -111.629672) (xy 239.193706 -111.619542)
			(xy 239.24944 -111.617505) (xy 239.304877 -111.623605) (xy 239.358834 -111.637711) (xy 239.410163 -111.659523)
			(xy 239.457769 -111.688577) (xy 239.500637 -111.724252) (xy 239.524116 -111.750456) (xy 266.310525 -111.750456)
			(xy 266.310525 -111.695944) (xy 266.318283 -111.641987) (xy 266.333641 -111.589684) (xy 266.356287 -111.540099)
			(xy 266.385759 -111.494241) (xy 266.421457 -111.453045) (xy 266.462655 -111.417348) (xy 266.508514 -111.387878)
			(xy 266.558101 -111.365235) (xy 266.610405 -111.349879) (xy 266.664362 -111.342124) (xy 266.691618 -111.341662)
			(xy 266.717526 -111.342112) (xy 266.768864 -111.349139) (xy 266.818779 -111.363048) (xy 266.866354 -111.383582)
			(xy 266.910712 -111.410366) (xy 266.951038 -111.442904) (xy 266.986591 -111.4806) (xy 267.002006 -111.501428)
			(xy 267.007746 -111.508759) (xy 267.023248 -111.519046) (xy 267.032232 -111.521494) (xy 267.062712 -111.528352)
			(xy 267.071991 -111.530078) (xy 267.090651 -111.527351) (xy 267.099034 -111.523018) (xy 267.125006 -111.508715)
			(xy 267.179859 -111.486205) (xy 267.237164 -111.470981) (xy 267.295956 -111.463298) (xy 267.325602 -111.46282)
			(xy 267.355245 -111.463313) (xy 267.414027 -111.471037) (xy 267.471325 -111.486265) (xy 267.526185 -111.508744)
			(xy 267.55217 -111.523018) (xy 267.560586 -111.527258) (xy 267.579213 -111.529997) (xy 267.588492 -111.528352)
			(xy 267.618972 -111.521494) (xy 267.627968 -111.519075) (xy 267.643471 -111.508775) (xy 267.649198 -111.501428)
			(xy 267.664599 -111.480586) (xy 267.700141 -111.442873) (xy 267.740464 -111.410321) (xy 267.784825 -111.383532)
			(xy 267.832405 -111.362998) (xy 267.882329 -111.349099) (xy 267.933675 -111.342091) (xy 267.959586 -111.341662)
			(xy 267.986837 -111.342184) (xy 268.040786 -111.349939) (xy 268.093081 -111.365293) (xy 268.142659 -111.387933)
			(xy 268.18851 -111.417398) (xy 268.229701 -111.453089) (xy 268.265394 -111.494279) (xy 268.294861 -111.540129)
			(xy 268.317502 -111.589706) (xy 268.332858 -111.642001) (xy 268.340615 -111.695949) (xy 268.340615 -111.750451)
			(xy 268.332858 -111.804399) (xy 268.317502 -111.856694) (xy 268.294861 -111.906271) (xy 268.265394 -111.952121)
			(xy 268.229701 -111.993311) (xy 268.18851 -112.029002) (xy 268.142659 -112.058467) (xy 268.093081 -112.081107)
			(xy 268.040786 -112.096461) (xy 267.986837 -112.104216) (xy 267.959586 -112.104678) (xy 267.944793 -112.104546)
			(xy 267.915295 -112.102255) (xy 267.900658 -112.100106) (xy 267.889684 -112.098962) (xy 267.86849 -112.105035)
			(xy 267.859764 -112.11179) (xy 267.801344 -112.161828) (xy 267.793302 -112.169382) (xy 267.784096 -112.189413)
			(xy 267.783564 -112.200436) (xy 267.783564 -112.504728) (xy 267.784098 -112.515747) (xy 267.793321 -112.535763)
			(xy 267.801344 -112.543336) (xy 267.8684 -112.60074) (xy 267.889482 -112.606836) (xy 267.900658 -112.605058)
			(xy 267.915296 -112.602915) (xy 267.944793 -112.600629) (xy 267.959586 -112.600486) (xy 267.986839 -112.60096)
			(xy 268.040791 -112.608716) (xy 268.093089 -112.62407) (xy 268.14267 -112.646712) (xy 268.188525 -112.676179)
			(xy 268.229718 -112.711872) (xy 268.265413 -112.753064) (xy 268.294882 -112.798917) (xy 268.317525 -112.848498)
			(xy 268.332881 -112.900796) (xy 268.340639 -112.954747) (xy 268.340639 -113.009253) (xy 268.332881 -113.063204)
			(xy 268.317525 -113.115502) (xy 268.294882 -113.165083) (xy 268.265413 -113.210936) (xy 268.235775 -113.245138)
			(xy 276.86965 -113.245138) (xy 276.873721 -113.189516) (xy 276.885847 -113.135079) (xy 276.90577 -113.082988)
			(xy 276.933066 -113.034353) (xy 276.967152 -112.99021) (xy 277.007301 -112.951501) (xy 277.052659 -112.91905)
			(xy 277.102259 -112.893549) (xy 277.155043 -112.875542) (xy 277.209886 -112.865412) (xy 277.26562 -112.863375)
			(xy 277.321057 -112.869475) (xy 277.375014 -112.883581) (xy 277.426343 -112.905393) (xy 277.473949 -112.934447)
			(xy 277.516817 -112.970122) (xy 277.554034 -113.011659) (xy 277.584807 -113.058172) (xy 277.608479 -113.108669)
			(xy 277.624547 -113.162076) (xy 277.632667 -113.217252) (xy 277.633176 -113.245138) (xy 279.290524 -113.245138)
			(xy 279.294595 -113.189516) (xy 279.306721 -113.135079) (xy 279.326644 -113.082988) (xy 279.35394 -113.034353)
			(xy 279.388026 -112.99021) (xy 279.428175 -112.951501) (xy 279.473533 -112.91905) (xy 279.523133 -112.893549)
			(xy 279.575917 -112.875542) (xy 279.63076 -112.865412) (xy 279.686494 -112.863375) (xy 279.741931 -112.869475)
			(xy 279.795888 -112.883581) (xy 279.847217 -112.905393) (xy 279.894823 -112.934447) (xy 279.937691 -112.970122)
			(xy 279.974908 -113.011659) (xy 280.005681 -113.058172) (xy 280.029353 -113.108669) (xy 280.045421 -113.162076)
			(xy 280.053541 -113.217252) (xy 280.05405 -113.245138) (xy 280.053541 -113.273024) (xy 280.045421 -113.3282)
			(xy 280.029353 -113.381607) (xy 280.005681 -113.432104) (xy 279.974908 -113.478617) (xy 279.937691 -113.520154)
			(xy 279.894823 -113.555829) (xy 279.847217 -113.584883) (xy 279.795888 -113.606695) (xy 279.741931 -113.620801)
			(xy 279.686494 -113.626901) (xy 279.63076 -113.624864) (xy 279.575917 -113.614734) (xy 279.523133 -113.596727)
			(xy 279.473533 -113.571226) (xy 279.428175 -113.538775) (xy 279.388026 -113.500066) (xy 279.35394 -113.455923)
			(xy 279.326644 -113.407288) (xy 279.306721 -113.355197) (xy 279.294595 -113.30076) (xy 279.290524 -113.245138)
			(xy 277.633176 -113.245138) (xy 277.632667 -113.273024) (xy 277.624547 -113.3282) (xy 277.608479 -113.381607)
			(xy 277.584807 -113.432104) (xy 277.554034 -113.478617) (xy 277.516817 -113.520154) (xy 277.473949 -113.555829)
			(xy 277.426343 -113.584883) (xy 277.375014 -113.606695) (xy 277.321057 -113.620801) (xy 277.26562 -113.626901)
			(xy 277.209886 -113.624864) (xy 277.155043 -113.614734) (xy 277.102259 -113.596727) (xy 277.052659 -113.571226)
			(xy 277.007301 -113.538775) (xy 276.967152 -113.500066) (xy 276.933066 -113.455923) (xy 276.90577 -113.407288)
			(xy 276.885847 -113.355197) (xy 276.873721 -113.30076) (xy 276.86965 -113.245138) (xy 268.235775 -113.245138)
			(xy 268.229718 -113.252128) (xy 268.188525 -113.287821) (xy 268.14267 -113.317288) (xy 268.093089 -113.33993)
			(xy 268.040791 -113.355284) (xy 267.986839 -113.36304) (xy 267.959586 -113.363502) (xy 267.933679 -113.363023)
			(xy 267.882343 -113.355997) (xy 267.83243 -113.342092) (xy 267.784857 -113.321561) (xy 267.740499 -113.294783)
			(xy 267.700171 -113.26225) (xy 267.664615 -113.224561) (xy 267.649198 -113.203736) (xy 267.643464 -113.1964)
			(xy 267.627957 -113.186117) (xy 267.618972 -113.18367) (xy 267.588492 -113.176812) (xy 267.579213 -113.17508)
			(xy 267.560552 -113.177809) (xy 267.55217 -113.182146) (xy 267.526201 -113.196454) (xy 267.471346 -113.218961)
			(xy 267.414041 -113.234183) (xy 267.355248 -113.241866) (xy 267.325602 -113.242344) (xy 267.295959 -113.241854)
			(xy 267.237177 -113.23413) (xy 267.179879 -113.218901) (xy 267.125018 -113.196421) (xy 267.099034 -113.182146)
			(xy 267.090618 -113.177907) (xy 267.071991 -113.175168) (xy 267.062712 -113.176812) (xy 267.032232 -113.18367)
			(xy 267.023241 -113.186103) (xy 267.007736 -113.196393) (xy 267.002006 -113.203736) (xy 266.986621 -113.22459)
			(xy 266.951074 -113.2623) (xy 266.910748 -113.294849) (xy 266.866384 -113.321636) (xy 266.818802 -113.342167)
			(xy 266.768877 -113.356065) (xy 266.71753 -113.363073) (xy 266.691618 -113.363502) (xy 266.664364 -113.363052)
			(xy 266.61041 -113.355297) (xy 266.558109 -113.339942) (xy 266.508526 -113.3173) (xy 266.46267 -113.287832)
			(xy 266.421475 -113.252138) (xy 266.385778 -113.210944) (xy 266.356308 -113.16509) (xy 266.333664 -113.115508)
			(xy 266.318307 -113.063207) (xy 266.310549 -113.009254) (xy 266.310549 -112.954746) (xy 266.318307 -112.900793)
			(xy 266.333664 -112.848492) (xy 266.356308 -112.79891) (xy 266.385778 -112.753056) (xy 266.421475 -112.711862)
			(xy 266.46267 -112.676168) (xy 266.508526 -112.6467) (xy 266.558109 -112.624058) (xy 266.61041 -112.608703)
			(xy 266.664364 -112.600948) (xy 266.691618 -112.600486) (xy 266.706411 -112.600618) (xy 266.735909 -112.602909)
			(xy 266.750546 -112.605058) (xy 266.76152 -112.606213) (xy 266.782715 -112.600134) (xy 266.79144 -112.593374)
			(xy 266.84986 -112.543336) (xy 266.857874 -112.535756) (xy 266.867095 -112.515745) (xy 266.86764 -112.504728)
			(xy 266.86764 -112.200436) (xy 266.867069 -112.189421) (xy 266.857872 -112.169405) (xy 266.84986 -112.161828)
			(xy 266.782804 -112.104424) (xy 266.761722 -112.098328) (xy 266.750546 -112.100106) (xy 266.735908 -112.102248)
			(xy 266.706411 -112.104535) (xy 266.691618 -112.104678) (xy 266.664362 -112.104276) (xy 266.610405 -112.096521)
			(xy 266.558101 -112.081165) (xy 266.508514 -112.058522) (xy 266.462655 -112.029052) (xy 266.421457 -111.993355)
			(xy 266.385759 -111.952159) (xy 266.356287 -111.906301) (xy 266.333641 -111.856716) (xy 266.318283 -111.804413)
			(xy 266.310525 -111.750456) (xy 239.524116 -111.750456) (xy 239.537854 -111.765789) (xy 239.568627 -111.812302)
			(xy 239.592299 -111.862799) (xy 239.608367 -111.916206) (xy 239.616487 -111.971382) (xy 239.616996 -111.999268)
			(xy 239.616487 -112.027154) (xy 239.608367 -112.08233) (xy 239.592299 -112.135737) (xy 239.568627 -112.186234)
			(xy 239.537854 -112.232747) (xy 239.500637 -112.274284) (xy 239.457769 -112.309959) (xy 239.410163 -112.339013)
			(xy 239.358834 -112.360825) (xy 239.304877 -112.374931) (xy 239.24944 -112.381031) (xy 239.193706 -112.378994)
			(xy 239.138863 -112.368864) (xy 239.086079 -112.350857) (xy 239.036479 -112.325356) (xy 238.991121 -112.292905)
			(xy 238.950972 -112.254196) (xy 238.916886 -112.210053) (xy 238.88959 -112.161418) (xy 238.869667 -112.109327)
			(xy 238.857541 -112.05489) (xy 238.85347 -111.999268) (xy 233.427314 -111.999268) (xy 233.42868 -112.003921)
			(xy 233.436436 -112.057869) (xy 233.436922 -112.08512) (xy 233.436487 -112.112492) (xy 233.428664 -112.166673)
			(xy 233.413169 -112.219177) (xy 233.39032 -112.268923) (xy 233.360587 -112.314888) (xy 233.342942 -112.335818)
			(xy 233.342688 -112.336072) (xy 233.337106 -112.343161) (xy 233.330857 -112.360076) (xy 233.330496 -112.369092)
			(xy 233.330496 -112.436148) (xy 233.330879 -112.445162) (xy 233.337109 -112.462079) (xy 233.342688 -112.469168)
			(xy 233.342942 -112.469168) (xy 233.342942 -112.469422) (xy 233.360565 -112.490367) (xy 233.390278 -112.536337)
			(xy 233.413116 -112.586081) (xy 233.425764 -112.628934) (xy 256.713734 -112.628934) (xy 256.717805 -112.573312)
			(xy 256.729931 -112.518875) (xy 256.749854 -112.466784) (xy 256.77715 -112.418149) (xy 256.811236 -112.374006)
			(xy 256.851385 -112.335297) (xy 256.896743 -112.302846) (xy 256.946343 -112.277345) (xy 256.999127 -112.259338)
			(xy 257.05397 -112.249208) (xy 257.109704 -112.247171) (xy 257.165141 -112.253271) (xy 257.219098 -112.267377)
			(xy 257.270427 -112.289189) (xy 257.318033 -112.318243) (xy 257.360901 -112.353918) (xy 257.398118 -112.395455)
			(xy 257.428891 -112.441968) (xy 257.452563 -112.492465) (xy 257.468631 -112.545872) (xy 257.476751 -112.601048)
			(xy 257.47726 -112.628934) (xy 257.476751 -112.65682) (xy 257.468631 -112.711996) (xy 257.452563 -112.765403)
			(xy 257.428891 -112.8159) (xy 257.398118 -112.862413) (xy 257.360901 -112.90395) (xy 257.318033 -112.939625)
			(xy 257.270427 -112.968679) (xy 257.219098 -112.990491) (xy 257.165141 -113.004597) (xy 257.109704 -113.010697)
			(xy 257.05397 -113.00866) (xy 256.999127 -112.99853) (xy 256.946343 -112.980523) (xy 256.896743 -112.955022)
			(xy 256.851385 -112.922571) (xy 256.811236 -112.883862) (xy 256.77715 -112.839719) (xy 256.749854 -112.791084)
			(xy 256.729931 -112.738993) (xy 256.717805 -112.684556) (xy 256.713734 -112.628934) (xy 233.425764 -112.628934)
			(xy 233.428611 -112.638579) (xy 233.436445 -112.692752) (xy 233.436922 -112.72012) (xy 233.436436 -112.747371)
			(xy 233.42868 -112.801319) (xy 233.413325 -112.853614) (xy 233.390683 -112.903191) (xy 233.361217 -112.949041)
			(xy 233.325526 -112.990232) (xy 233.284335 -113.025923) (xy 233.238485 -113.055389) (xy 233.188908 -113.078031)
			(xy 233.136613 -113.093386) (xy 233.082665 -113.101142) (xy 233.028163 -113.101142) (xy 232.974215 -113.093386)
			(xy 232.92192 -113.078031) (xy 232.872343 -113.055389) (xy 232.826493 -113.025923) (xy 232.785302 -112.990232)
			(xy 232.749611 -112.949041) (xy 232.720145 -112.903191) (xy 232.697503 -112.853614) (xy 232.682148 -112.801319)
			(xy 232.674392 -112.747371) (xy 232.673906 -112.72012) (xy 230.759734 -112.72012) (xy 230.757211 -112.725645)
			(xy 230.727745 -112.771495) (xy 230.692054 -112.812686) (xy 230.650863 -112.848377) (xy 230.605013 -112.877843)
			(xy 230.555436 -112.900485) (xy 230.503141 -112.91584) (xy 230.449193 -112.923596) (xy 230.394691 -112.923596)
			(xy 230.340743 -112.91584) (xy 230.288448 -112.900485) (xy 230.238871 -112.877843) (xy 230.193021 -112.848377)
			(xy 230.15183 -112.812686) (xy 230.116139 -112.771495) (xy 230.086673 -112.725645) (xy 230.064031 -112.676068)
			(xy 230.048676 -112.623773) (xy 230.04092 -112.569825) (xy 230.040434 -112.542574) (xy 209.080132 -112.542574)
			(xy 209.104023 -112.570143) (xy 209.133496 -112.616) (xy 209.156142 -112.665585) (xy 209.171501 -112.717888)
			(xy 209.179259 -112.771844) (xy 209.179259 -112.826356) (xy 209.171501 -112.880312) (xy 209.156142 -112.932615)
			(xy 209.133496 -112.9822) (xy 209.104023 -113.028057) (xy 209.068324 -113.069252) (xy 209.027125 -113.104947)
			(xy 208.981265 -113.134415) (xy 208.931678 -113.157056) (xy 208.879373 -113.172409) (xy 208.825416 -113.180162)
			(xy 208.79816 -113.180622) (xy 208.770916 -113.180149) (xy 208.716983 -113.172387) (xy 208.664705 -113.157028)
			(xy 208.615145 -113.134384) (xy 208.569313 -113.104916) (xy 208.528142 -113.069224) (xy 208.49247 -113.028035)
			(xy 208.477358 -113.005362) (xy 208.472521 -112.998329) (xy 208.459109 -112.987783) (xy 208.442965 -112.982262)
			(xy 208.434432 -112.981994) (xy 208.349088 -112.981994) (xy 208.340569 -112.982324) (xy 208.324459 -112.987868)
			(xy 208.311048 -112.998376) (xy 208.306162 -113.005362) (xy 208.291074 -113.028054) (xy 208.255403 -113.069247)
			(xy 208.21423 -113.104943) (xy 208.168393 -113.134412) (xy 208.118828 -113.157054) (xy 208.066544 -113.172408)
			(xy 208.012606 -113.180161) (xy 207.98536 -113.180622) (xy 207.956443 -113.18009) (xy 207.899271 -113.171368)
			(xy 207.844072 -113.154115) (xy 207.792109 -113.128726) (xy 207.744575 -113.095783) (xy 207.702559 -113.056042)
			(xy 207.68437 -113.033556) (xy 207.676774 -113.024738) (xy 207.655864 -113.014562) (xy 207.644238 -113.013998)
			(xy 207.564482 -113.013998) (xy 207.552851 -113.014542) (xy 207.531941 -113.024727) (xy 207.52435 -113.033556)
			(xy 207.50612 -113.056006) (xy 207.464109 -113.095746) (xy 207.416583 -113.12869) (xy 207.364629 -113.154084)
			(xy 207.309438 -113.171347) (xy 207.252274 -113.180083) (xy 207.22336 -113.180622) (xy 207.196108 -113.180159)
			(xy 207.142161 -113.172398) (xy 207.089866 -113.157038) (xy 207.04029 -113.134394) (xy 206.99444 -113.104924)
			(xy 206.953251 -113.069231) (xy 206.91756 -113.028039) (xy 206.888094 -112.982187) (xy 206.865453 -112.932609)
			(xy 206.850097 -112.880314) (xy 206.842339 -112.826366) (xy 206.841852 -112.799114) (xy 206.842337 -112.77267)
			(xy 206.849641 -112.720289) (xy 206.864109 -112.669418) (xy 206.885465 -112.621034) (xy 206.9133 -112.576063)
			(xy 206.94708 -112.535369) (xy 206.986156 -112.49973) (xy 207.007714 -112.484408) (xy 207.016398 -112.477945)
			(xy 207.027714 -112.459515) (xy 207.029558 -112.448848) (xy 207.033622 -112.41659) (xy 207.034441 -112.405878)
			(xy 207.028135 -112.38536) (xy 207.02143 -112.376966) (xy 207.021176 -112.376712) (xy 207.013541 -112.368696)
			(xy 206.993377 -112.359614) (xy 206.982314 -112.359186) (xy 206.949802 -112.359694) (xy 206.938787 -112.360335)
			(xy 206.918897 -112.36984) (xy 206.911448 -112.377982) (xy 206.893221 -112.399159) (xy 206.851659 -112.436499)
			(xy 206.805096 -112.467377) (xy 206.754527 -112.491135) (xy 206.701033 -112.507262) (xy 206.64576 -112.515414)
			(xy 206.617824 -112.515904) (xy 206.61757 -112.515904) (xy 206.58961 -112.515431) (xy 206.534291 -112.507246)
			(xy 206.480765 -112.491058) (xy 206.455264 -112.479582) (xy 206.44381 -112.474794) (xy 206.419032 -112.475877)
			(xy 206.40802 -112.481614) (xy 206.33563 -112.523524) (xy 206.325391 -112.530303) (xy 206.312249 -112.550997)
			(xy 206.310484 -112.563148) (xy 206.310484 -112.563656) (xy 206.307683 -112.591985) (xy 206.294811 -112.647435)
			(xy 206.273839 -112.700356) (xy 206.245234 -112.749571) (xy 206.20963 -112.793987) (xy 206.16782 -112.832616)
			(xy 206.120732 -112.864602) (xy 206.069412 -112.889232) (xy 206.015001 -112.90596) (xy 205.958708 -112.914414)
			(xy 205.930246 -112.914938) (xy 205.902993 -112.914418) (xy 205.849041 -112.906667) (xy 205.796742 -112.891316)
			(xy 205.74716 -112.868678) (xy 205.701305 -112.839213) (xy 205.66011 -112.803523) (xy 205.624414 -112.762332)
			(xy 205.594944 -112.71648) (xy 205.5723 -112.666901) (xy 205.556943 -112.614604) (xy 205.549185 -112.560653)
			(xy 198.205082 -112.560653) (xy 198.195329 -112.581458) (xy 198.164556 -112.627971) (xy 198.127339 -112.669508)
			(xy 198.084471 -112.705183) (xy 198.036865 -112.734237) (xy 197.985536 -112.756049) (xy 197.931579 -112.770155)
			(xy 197.876142 -112.776255) (xy 197.820408 -112.774218) (xy 197.765565 -112.764088) (xy 197.712781 -112.746081)
			(xy 197.663181 -112.72058) (xy 197.617823 -112.688129) (xy 197.577674 -112.64942) (xy 197.543588 -112.605277)
			(xy 197.516292 -112.556642) (xy 197.496369 -112.504551) (xy 197.484243 -112.450114) (xy 197.480172 -112.394492)
			(xy 188.682024 -112.394492) (xy 188.701848 -112.440339) (xy 188.715796 -112.490338) (xy 188.722834 -112.541766)
			(xy 188.72327 -112.56772) (xy 188.722784 -112.594971) (xy 188.715028 -112.648919) (xy 188.699673 -112.701214)
			(xy 188.677031 -112.750791) (xy 188.647565 -112.796641) (xy 188.611874 -112.837832) (xy 188.570683 -112.873523)
			(xy 188.524833 -112.902989) (xy 188.475256 -112.925631) (xy 188.422961 -112.940986) (xy 188.369013 -112.948742)
			(xy 188.314511 -112.948742) (xy 188.260563 -112.940986) (xy 188.208268 -112.925631) (xy 188.158691 -112.902989)
			(xy 188.112841 -112.873523) (xy 188.07165 -112.837832) (xy 188.035959 -112.796641) (xy 188.006493 -112.750791)
			(xy 187.983851 -112.701214) (xy 187.968496 -112.648919) (xy 187.96074 -112.594971) (xy 187.960254 -112.56772)
			(xy 187.9608 -112.537925) (xy 187.970063 -112.479059) (xy 187.988367 -112.42235) (xy 188.015265 -112.369177)
			(xy 188.050105 -112.320832) (xy 188.092038 -112.278494) (xy 188.115702 -112.26038) (xy 188.122461 -112.254998)
			(xy 188.1322 -112.240742) (xy 188.136627 -112.224054) (xy 188.136276 -112.215422) (xy 188.129672 -112.12957)
			(xy 188.12877 -112.121053) (xy 188.121994 -112.105333) (xy 188.1104 -112.09274) (xy 188.103002 -112.088422)
			(xy 188.102748 -112.088422) (xy 188.079955 -112.076005) (xy 188.037661 -112.045916) (xy 187.999839 -112.010369)
			(xy 187.967188 -111.97002) (xy 187.940312 -111.925615) (xy 187.919708 -111.877974) (xy 187.905757 -111.82798)
			(xy 187.898716 -111.776554) (xy 187.898278 -111.750602) (xy 187.898717 -111.723581) (xy 187.906332 -111.670077)
			(xy 187.921425 -111.618185) (xy 187.943693 -111.568943) (xy 187.972689 -111.523338) (xy 188.007834 -111.482284)
			(xy 188.027818 -111.46409) (xy 188.03578 -111.456436) (xy 188.044726 -111.436268) (xy 188.04509 -111.425228)
			(xy 188.04382 -111.348012) (xy 188.043169 -111.336998) (xy 188.033671 -111.317109) (xy 188.025532 -111.309658)
			(xy 188.00439 -111.291437) (xy 187.967114 -111.2499) (xy 187.93629 -111.203372) (xy 187.912578 -111.152849)
			(xy 187.896483 -111.099409) (xy 187.88835 -111.044194) (xy 187.887864 -111.016288) (xy 184.007741 -111.016288)
			(xy 184.023107 -111.068345) (xy 184.030935 -111.122523) (xy 184.030936 -111.177265) (xy 184.023109 -111.231443)
			(xy 184.007615 -111.283946) (xy 183.984772 -111.333694) (xy 183.955049 -111.379663) (xy 183.937402 -111.40059)
			(xy 183.937402 -111.400844) (xy 183.937148 -111.400844) (xy 183.93155 -111.407926) (xy 183.925283 -111.424844)
			(xy 183.924956 -111.433864) (xy 183.924956 -111.50092) (xy 183.925318 -111.509936) (xy 183.931566 -111.526851)
			(xy 183.937148 -111.53394) (xy 183.937402 -111.534194) (xy 183.955044 -111.555125) (xy 183.984771 -111.601092)
			(xy 184.007615 -111.650838) (xy 184.023106 -111.703342) (xy 184.030925 -111.757521) (xy 184.031382 -111.784892)
			(xy 184.030868 -111.813513) (xy 184.022308 -111.87011) (xy 184.005379 -111.924791) (xy 183.980463 -111.976325)
			(xy 183.948119 -112.023553) (xy 183.909075 -112.065411) (xy 183.86421 -112.10096) (xy 183.839612 -112.1156)
			(xy 183.839104 -112.116108) (xy 183.829404 -112.12239) (xy 183.816565 -112.141575) (xy 183.814466 -112.152938)
			(xy 183.803544 -112.233202) (xy 183.802603 -112.244921) (xy 183.810126 -112.267167) (xy 183.818022 -112.275874)
			(xy 183.964038 -112.421924) (xy 185.554872 -112.421924) (xy 185.558943 -112.366302) (xy 185.571069 -112.311865)
			(xy 185.590992 -112.259774) (xy 185.618288 -112.211139) (xy 185.652374 -112.166996) (xy 185.692523 -112.128287)
			(xy 185.737881 -112.095836) (xy 185.787481 -112.070335) (xy 185.840265 -112.052328) (xy 185.895108 -112.042198)
			(xy 185.950842 -112.040161) (xy 186.006279 -112.046261) (xy 186.060236 -112.060367) (xy 186.111565 -112.082179)
			(xy 186.159171 -112.111233) (xy 186.202039 -112.146908) (xy 186.239256 -112.188445) (xy 186.270029 -112.234958)
			(xy 186.293701 -112.285455) (xy 186.309769 -112.338862) (xy 186.317889 -112.394038) (xy 186.318398 -112.421924)
			(xy 186.317889 -112.44981) (xy 186.309769 -112.504986) (xy 186.293701 -112.558393) (xy 186.270029 -112.60889)
			(xy 186.239256 -112.655403) (xy 186.202039 -112.69694) (xy 186.159171 -112.732615) (xy 186.111565 -112.761669)
			(xy 186.060236 -112.783481) (xy 186.006279 -112.797587) (xy 185.950842 -112.803687) (xy 185.895108 -112.80165)
			(xy 185.840265 -112.79152) (xy 185.787481 -112.773513) (xy 185.737881 -112.748012) (xy 185.692523 -112.715561)
			(xy 185.652374 -112.676852) (xy 185.618288 -112.632709) (xy 185.590992 -112.584074) (xy 185.571069 -112.531983)
			(xy 185.558943 -112.477546) (xy 185.554872 -112.421924) (xy 183.964038 -112.421924) (xy 184.910984 -113.36909)
			(xy 184.918387 -113.375924) (xy 184.936985 -113.38363) (xy 184.947052 -113.384076) (xy 185.496454 -113.384076)
			(xy 185.507708 -113.383474) (xy 185.52806 -113.373857) (xy 185.542371 -113.356481) (xy 185.54573 -113.345722)
			(xy 185.54573 -113.345468) (xy 185.553034 -113.318315) (xy 185.574527 -113.266357) (xy 185.603413 -113.218117)
			(xy 185.639066 -113.174638) (xy 185.680714 -113.136862) (xy 185.727454 -113.105607) (xy 185.778276 -113.081551)
			(xy 185.832077 -113.065213) (xy 185.887694 -113.056948) (xy 185.915808 -113.056416) (xy 185.944922 -113.056964)
			(xy 186.002475 -113.065805) (xy 186.058019 -113.083281) (xy 186.110266 -113.108985) (xy 186.158005 -113.142324)
			(xy 186.20013 -113.182523) (xy 186.218322 -113.20526) (xy 186.224418 -113.213388) (xy 186.241944 -113.223548)
			(xy 186.322716 -113.234216) (xy 186.332703 -113.235158) (xy 186.352086 -113.230055) (xy 186.360308 -113.22431)
			(xy 186.385842 -113.2054) (xy 186.440275 -113.172616) (xy 186.497936 -113.145915) (xy 186.558148 -113.125612)
			(xy 186.620204 -113.111944) (xy 186.683374 -113.105072) (xy 186.715146 -113.104676) (xy 191.540892 -113.104676)
			(xy 191.550001 -113.104295) (xy 191.567079 -113.097947) (xy 191.580895 -113.08607) (xy 191.585596 -113.07826)
			(xy 191.600066 -113.052855) (xy 191.635529 -113.006376) (xy 191.677664 -112.965848) (xy 191.725488 -112.93222)
			(xy 191.77788 -112.906279) (xy 191.833616 -112.88863) (xy 191.891391 -112.879688) (xy 191.920622 -112.879124)
			(xy 191.947873 -112.879589) (xy 192.00182 -112.887349) (xy 192.054113 -112.902707) (xy 192.103689 -112.925351)
			(xy 192.149537 -112.95482) (xy 192.190724 -112.990514) (xy 192.226412 -113.031707) (xy 192.255875 -113.077559)
			(xy 192.278512 -113.127137) (xy 192.293863 -113.179433) (xy 192.301115 -113.229898) (xy 192.541904 -113.229898)
			(xy 192.545975 -113.174276) (xy 192.558101 -113.119839) (xy 192.578024 -113.067748) (xy 192.60532 -113.019113)
			(xy 192.639406 -112.97497) (xy 192.679555 -112.936261) (xy 192.724913 -112.90381) (xy 192.774513 -112.878309)
			(xy 192.827297 -112.860302) (xy 192.88214 -112.850172) (xy 192.937874 -112.848135) (xy 192.993311 -112.854235)
			(xy 193.047268 -112.868341) (xy 193.098597 -112.890153) (xy 193.146203 -112.919207) (xy 193.189071 -112.954882)
			(xy 193.226288 -112.996419) (xy 193.257061 -113.042932) (xy 193.280733 -113.093429) (xy 193.296801 -113.146836)
			(xy 193.304921 -113.202012) (xy 193.30543 -113.229898) (xy 193.304921 -113.257784) (xy 193.296801 -113.31296)
			(xy 193.280733 -113.366367) (xy 193.258619 -113.41354) (xy 197.453756 -113.41354) (xy 197.457827 -113.357918)
			(xy 197.469953 -113.303481) (xy 197.489876 -113.25139) (xy 197.517172 -113.202755) (xy 197.551258 -113.158612)
			(xy 197.591407 -113.119903) (xy 197.636765 -113.087452) (xy 197.686365 -113.061951) (xy 197.739149 -113.043944)
			(xy 197.793992 -113.033814) (xy 197.849726 -113.031777) (xy 197.905163 -113.037877) (xy 197.95912 -113.051983)
			(xy 198.010449 -113.073795) (xy 198.058055 -113.102849) (xy 198.100923 -113.138524) (xy 198.13814 -113.180061)
			(xy 198.168913 -113.226574) (xy 198.192585 -113.277071) (xy 198.208653 -113.330478) (xy 198.216773 -113.385654)
			(xy 198.217282 -113.41354) (xy 198.216773 -113.441426) (xy 198.208653 -113.496602) (xy 198.192585 -113.550009)
			(xy 198.168913 -113.600506) (xy 198.13814 -113.647019) (xy 198.100923 -113.688556) (xy 198.058055 -113.724231)
			(xy 198.010449 -113.753285) (xy 197.95912 -113.775097) (xy 197.905163 -113.789203) (xy 197.849726 -113.795303)
			(xy 197.793992 -113.793266) (xy 197.739149 -113.783136) (xy 197.686365 -113.765129) (xy 197.636765 -113.739628)
			(xy 197.591407 -113.707177) (xy 197.551258 -113.668468) (xy 197.517172 -113.624325) (xy 197.489876 -113.57569)
			(xy 197.469953 -113.523599) (xy 197.457827 -113.469162) (xy 197.453756 -113.41354) (xy 193.258619 -113.41354)
			(xy 193.257061 -113.416864) (xy 193.226288 -113.463377) (xy 193.189071 -113.504914) (xy 193.146203 -113.540589)
			(xy 193.098597 -113.569643) (xy 193.047268 -113.591455) (xy 192.993311 -113.605561) (xy 192.937874 -113.611661)
			(xy 192.88214 -113.609624) (xy 192.827297 -113.599494) (xy 192.774513 -113.581487) (xy 192.724913 -113.555986)
			(xy 192.679555 -113.523535) (xy 192.639406 -113.484826) (xy 192.60532 -113.440683) (xy 192.578024 -113.392048)
			(xy 192.558101 -113.339957) (xy 192.545975 -113.28552) (xy 192.541904 -113.229898) (xy 192.301115 -113.229898)
			(xy 192.301615 -113.233381) (xy 192.30213 -113.260632) (xy 192.301572 -113.289955) (xy 192.292568 -113.347908)
			(xy 192.274822 -113.403806) (xy 192.262252 -113.430304) (xy 192.258023 -113.440061) (xy 192.257083 -113.461281)
			(xy 192.264787 -113.481075) (xy 192.271904 -113.488978) (xy 193.367914 -114.585242) (xy 193.37531 -114.592093)
			(xy 193.393909 -114.599831) (xy 193.403982 -114.600228) (xy 197.395084 -114.600228) (xy 197.40608 -114.599755)
			(xy 197.426103 -114.590673) (xy 197.433692 -114.582702) (xy 197.48373 -114.524536) (xy 197.490492 -114.515955)
			(xy 197.496686 -114.495027) (xy 197.495668 -114.48415) (xy 197.495668 -114.483896) (xy 197.49386 -114.47038)
			(xy 197.491951 -114.443176) (xy 197.491858 -114.42954) (xy 197.492344 -114.402289) (xy 197.5001 -114.348341)
			(xy 197.515455 -114.296046) (xy 197.538097 -114.246469) (xy 197.567563 -114.200619) (xy 197.603254 -114.159428)
			(xy 197.644445 -114.123737) (xy 197.690295 -114.094271) (xy 197.739872 -114.071629) (xy 197.792167 -114.056274)
			(xy 197.846115 -114.048518) (xy 197.900617 -114.048518) (xy 197.954565 -114.056274) (xy 198.00686 -114.071629)
			(xy 198.056437 -114.094271) (xy 198.102287 -114.123737) (xy 198.143478 -114.159428) (xy 198.179169 -114.200619)
			(xy 198.208635 -114.246469) (xy 198.231277 -114.296046) (xy 198.246632 -114.348341) (xy 198.254388 -114.402289)
			(xy 198.254874 -114.42954) (xy 198.25477 -114.443175) (xy 198.252865 -114.47038) (xy 198.251064 -114.483896)
			(xy 198.251064 -114.48415) (xy 198.250041 -114.495031) (xy 198.256215 -114.515972) (xy 198.263002 -114.524536)
			(xy 198.31304 -114.582702) (xy 198.320645 -114.590652) (xy 198.340657 -114.599743) (xy 198.351648 -114.600228)
			(xy 201.24166 -114.600228) (xy 201.252649 -114.59974) (xy 201.272648 -114.590638) (xy 201.280268 -114.582702)
			(xy 201.330306 -114.524536) (xy 201.337071 -114.515956) (xy 201.343267 -114.495027) (xy 201.342244 -114.48415)
			(xy 201.342244 -114.483896) (xy 201.340436 -114.47038) (xy 201.338527 -114.443176) (xy 201.338434 -114.42954)
			(xy 201.33892 -114.402289) (xy 201.346676 -114.348341) (xy 201.362031 -114.296046) (xy 201.384673 -114.246469)
			(xy 201.414139 -114.200619) (xy 201.44983 -114.159428) (xy 201.491021 -114.123737) (xy 201.536871 -114.094271)
			(xy 201.586448 -114.071629) (xy 201.638743 -114.056274) (xy 201.692691 -114.048518) (xy 201.747193 -114.048518)
			(xy 201.801141 -114.056274) (xy 201.853436 -114.071629) (xy 201.903013 -114.094271) (xy 201.948863 -114.123737)
			(xy 201.990054 -114.159428) (xy 202.025745 -114.200619) (xy 202.055211 -114.246469) (xy 202.077853 -114.296046)
			(xy 202.093208 -114.348341) (xy 202.100964 -114.402289) (xy 202.10145 -114.42954) (xy 202.101346 -114.443175)
			(xy 202.09944 -114.47038) (xy 202.09764 -114.483896) (xy 202.09764 -114.48415) (xy 202.096617 -114.49503)
			(xy 202.102798 -114.515967) (xy 202.109578 -114.524536) (xy 202.159616 -114.582702) (xy 202.16722 -114.590656)
			(xy 202.187231 -114.599756) (xy 202.198224 -114.600228) (xy 202.691746 -114.600228) (xy 202.701813 -114.599797)
			(xy 202.720408 -114.592074) (xy 202.727814 -114.585242) (xy 202.766168 -114.546888) (xy 202.773566 -114.540043)
			(xy 202.792165 -114.532319) (xy 202.802236 -114.531902) (xy 203.618592 -114.531902) (xy 203.626212 -114.529362)
			(xy 203.642779 -114.524277) (xy 203.676613 -114.516775) (xy 203.693776 -114.514376) (xy 203.701142 -114.51336)
			(xy 203.714096 -114.508026) (xy 203.719684 -114.503454) (xy 203.724863 -114.498814) (xy 203.732727 -114.487355)
			(xy 203.735178 -114.480848) (xy 203.751942 -114.43208) (xy 203.764896 -114.394234) (xy 203.766668 -114.388572)
			(xy 203.767812 -114.376766) (xy 203.767182 -114.370866) (xy 203.641198 -114.244882) (xy 203.631292 -114.24158)
			(xy 203.605573 -114.233261) (xy 203.556602 -114.210379) (xy 203.511354 -114.180811) (xy 203.470734 -114.145148)
			(xy 203.435558 -114.104107) (xy 203.406531 -114.058509) (xy 203.384235 -114.009269) (xy 203.369115 -113.957373)
			(xy 203.361477 -113.903863) (xy 203.361036 -113.876836) (xy 203.361497 -113.849583) (xy 203.36925 -113.79563)
			(xy 203.384603 -113.74333) (xy 203.407244 -113.693749) (xy 203.436712 -113.647894) (xy 203.472406 -113.606701)
			(xy 203.513601 -113.571007) (xy 203.559456 -113.541541) (xy 203.609038 -113.518901) (xy 203.661338 -113.503548)
			(xy 203.715291 -113.495796) (xy 203.742544 -113.495328) (xy 203.769568 -113.495802) (xy 203.823074 -113.503441)
			(xy 203.874964 -113.518559) (xy 203.9242 -113.540854) (xy 203.969793 -113.569879) (xy 204.010831 -113.605052)
			(xy 204.04649 -113.645667) (xy 204.076056 -113.690912) (xy 204.098936 -113.739878) (xy 204.107288 -113.765584)
			(xy 204.11059 -113.77549) (xy 204.181456 -113.846356) (xy 205.461106 -113.846356) (xy 205.465177 -113.790734)
			(xy 205.477303 -113.736297) (xy 205.497226 -113.684206) (xy 205.524522 -113.635571) (xy 205.558608 -113.591428)
			(xy 205.598757 -113.552719) (xy 205.644115 -113.520268) (xy 205.693715 -113.494767) (xy 205.746499 -113.47676)
			(xy 205.801342 -113.46663) (xy 205.857076 -113.464593) (xy 205.912513 -113.470693) (xy 205.96647 -113.484799)
			(xy 206.017799 -113.506611) (xy 206.065405 -113.535665) (xy 206.108273 -113.57134) (xy 206.14549 -113.612877)
			(xy 206.176263 -113.65939) (xy 206.199935 -113.709887) (xy 206.216003 -113.763294) (xy 206.224123 -113.81847)
			(xy 206.224632 -113.846356) (xy 206.224123 -113.874242) (xy 206.216003 -113.929418) (xy 206.199935 -113.982825)
			(xy 206.176263 -114.033322) (xy 206.14549 -114.079835) (xy 206.108273 -114.121372) (xy 206.065405 -114.157047)
			(xy 206.017799 -114.186101) (xy 205.96647 -114.207913) (xy 205.912513 -114.222019) (xy 205.857076 -114.228119)
			(xy 205.801342 -114.226082) (xy 205.746499 -114.215952) (xy 205.693715 -114.197945) (xy 205.644115 -114.172444)
			(xy 205.598757 -114.139993) (xy 205.558608 -114.101284) (xy 205.524522 -114.057141) (xy 205.497226 -114.008506)
			(xy 205.477303 -113.956415) (xy 205.465177 -113.901978) (xy 205.461106 -113.846356) (xy 204.181456 -113.846356)
			(xy 204.476096 -114.140996) (xy 204.494126 -114.159768) (xy 204.524703 -114.201885) (xy 204.548327 -114.248262)
			(xy 204.564417 -114.297759) (xy 204.572579 -114.349161) (xy 204.573124 -114.375184) (xy 204.573124 -114.529362)
			(xy 204.576959 -114.530521) (xy 204.584867 -114.531792) (xy 204.588872 -114.531902) (xy 208.99374 -114.531902)
			(xy 209.001868 -114.53114) (xy 209.011249 -114.529203) (xy 209.027698 -114.519414) (xy 209.033872 -114.51209)
			(xy 209.082894 -114.44859) (xy 209.08634 -114.443855) (xy 209.091218 -114.433211) (xy 209.092546 -114.427508)
			(xy 209.094832 -114.416332) (xy 209.091784 -114.404648) (xy 209.086092 -114.381247) (xy 209.079973 -114.333478)
			(xy 209.079592 -114.309398) (xy 209.079592 -114.308636) (xy 209.080106 -114.279962) (xy 209.088689 -114.223259)
			(xy 209.105667 -114.168482) (xy 209.130656 -114.116864) (xy 209.163093 -114.069571) (xy 209.202247 -114.027669)
			(xy 209.247234 -113.992102) (xy 209.27187 -113.97742) (xy 209.281936 -113.970285) (xy 209.294414 -113.949046)
			(xy 209.295746 -113.93678) (xy 209.295746 -113.846356) (xy 209.295746 -113.843816) (xy 209.294401 -113.831554)
			(xy 209.281929 -113.810316) (xy 209.27187 -113.803176) (xy 209.247229 -113.788504) (xy 209.202252 -113.752924)
			(xy 209.163105 -113.711015) (xy 209.130669 -113.663721) (xy 209.105674 -113.612107) (xy 209.088683 -113.557333)
			(xy 209.080079 -113.500634) (xy 209.079592 -113.47196) (xy 209.080078 -113.444709) (xy 209.087834 -113.390761)
			(xy 209.103189 -113.338466) (xy 209.125831 -113.288889) (xy 209.155297 -113.243039) (xy 209.190988 -113.201848)
			(xy 209.232179 -113.166157) (xy 209.278029 -113.136691) (xy 209.327606 -113.114049) (xy 209.379901 -113.098694)
			(xy 209.433849 -113.090938) (xy 209.488351 -113.090938) (xy 209.542299 -113.098694) (xy 209.594594 -113.114049)
			(xy 209.644171 -113.136691) (xy 209.690021 -113.166157) (xy 209.731212 -113.201848) (xy 209.766903 -113.243039)
			(xy 209.796369 -113.288889) (xy 209.819011 -113.338466) (xy 209.834366 -113.390761) (xy 209.842122 -113.444709)
			(xy 209.842608 -113.47196) (xy 209.842094 -113.500634) (xy 209.833512 -113.557337) (xy 209.816535 -113.612115)
			(xy 209.791546 -113.663733) (xy 209.759109 -113.711027) (xy 209.719955 -113.75293) (xy 209.674968 -113.788497)
			(xy 209.65033 -113.803176) (xy 209.640263 -113.810311) (xy 209.627784 -113.831549) (xy 209.626454 -113.843816)
			(xy 209.626454 -113.870486) (xy 211.246972 -113.870486) (xy 211.251043 -113.814864) (xy 211.263169 -113.760427)
			(xy 211.283092 -113.708336) (xy 211.310388 -113.659701) (xy 211.344474 -113.615558) (xy 211.384623 -113.576849)
			(xy 211.429981 -113.544398) (xy 211.479581 -113.518897) (xy 211.532365 -113.50089) (xy 211.587208 -113.49076)
			(xy 211.642942 -113.488723) (xy 211.698379 -113.494823) (xy 211.752336 -113.508929) (xy 211.803665 -113.530741)
			(xy 211.851271 -113.559795) (xy 211.894139 -113.59547) (xy 211.931356 -113.637007) (xy 211.941978 -113.653062)
			(xy 235.227876 -113.653062) (xy 235.228362 -113.625811) (xy 235.236118 -113.571863) (xy 235.251473 -113.519568)
			(xy 235.274115 -113.469991) (xy 235.303581 -113.424141) (xy 235.339272 -113.38295) (xy 235.380463 -113.347259)
			(xy 235.426313 -113.317793) (xy 235.47589 -113.295151) (xy 235.528185 -113.279796) (xy 235.582133 -113.27204)
			(xy 235.636635 -113.27204) (xy 235.690583 -113.279796) (xy 235.742878 -113.295151) (xy 235.757949 -113.302034)
			(xy 246.514112 -113.302034) (xy 246.514598 -113.274783) (xy 246.522354 -113.220835) (xy 246.537709 -113.16854)
			(xy 246.560351 -113.118963) (xy 246.589817 -113.073113) (xy 246.625508 -113.031922) (xy 246.666699 -112.996231)
			(xy 246.712549 -112.966765) (xy 246.762126 -112.944123) (xy 246.814421 -112.928768) (xy 246.868369 -112.921012)
			(xy 246.922871 -112.921012) (xy 246.976819 -112.928768) (xy 247.029114 -112.944123) (xy 247.078691 -112.966765)
			(xy 247.124541 -112.996231) (xy 247.165732 -113.031922) (xy 247.201423 -113.073113) (xy 247.230889 -113.118963)
			(xy 247.253531 -113.16854) (xy 247.268886 -113.220835) (xy 247.276642 -113.274783) (xy 247.277128 -113.302034)
			(xy 247.277128 -113.302542) (xy 247.27647 -113.333872) (xy 247.266181 -113.395683) (xy 247.245935 -113.454984)
			(xy 247.231662 -113.482882) (xy 247.225017 -113.496303) (xy 247.219079 -113.525643) (xy 247.221908 -113.555444)
			(xy 247.233263 -113.583142) (xy 247.252164 -113.606354) (xy 247.276988 -113.623084) (xy 247.305597 -113.631893)
			(xy 247.320562 -113.632488) (xy 247.347719 -113.633094) (xy 247.401446 -113.641088) (xy 247.453497 -113.656622)
			(xy 247.502819 -113.679381) (xy 247.548414 -113.708905) (xy 247.58936 -113.744597) (xy 247.624831 -113.785736)
			(xy 247.654109 -113.831489) (xy 247.676601 -113.880933) (xy 247.691854 -113.933066) (xy 247.699559 -113.986836)
			(xy 247.700038 -114.013996) (xy 247.699552 -114.041247) (xy 247.691796 -114.095195) (xy 247.676441 -114.14749)
			(xy 247.653799 -114.197067) (xy 247.624333 -114.242917) (xy 247.588642 -114.284108) (xy 247.547451 -114.319799)
			(xy 247.501601 -114.349265) (xy 247.452024 -114.371907) (xy 247.399729 -114.387262) (xy 247.345781 -114.395018)
			(xy 247.291279 -114.395018) (xy 247.237331 -114.387262) (xy 247.185036 -114.371907) (xy 247.135459 -114.349265)
			(xy 247.089609 -114.319799) (xy 247.048418 -114.284108) (xy 247.012727 -114.242917) (xy 246.983261 -114.197067)
			(xy 246.960619 -114.14749) (xy 246.945264 -114.095195) (xy 246.937508 -114.041247) (xy 246.937022 -114.013996)
			(xy 246.937022 -114.013488) (xy 246.937685 -113.982158) (xy 246.947971 -113.920347) (xy 246.968215 -113.861046)
			(xy 246.982488 -113.833148) (xy 246.98914 -113.819727) (xy 246.99509 -113.790384) (xy 246.992266 -113.760577)
			(xy 246.980912 -113.732874) (xy 246.962005 -113.709658) (xy 246.937174 -113.69293) (xy 246.908556 -113.68413)
			(xy 246.893588 -113.683542) (xy 246.866434 -113.68286) (xy 246.812711 -113.674873) (xy 246.760663 -113.659347)
			(xy 246.711344 -113.636596) (xy 246.66575 -113.60708) (xy 246.624804 -113.571396) (xy 246.589332 -113.530265)
			(xy 246.560053 -113.484519) (xy 246.537558 -113.435082) (xy 246.522302 -113.382955) (xy 246.514594 -113.329191)
			(xy 246.514112 -113.302034) (xy 235.757949 -113.302034) (xy 235.792455 -113.317793) (xy 235.838305 -113.347259)
			(xy 235.879496 -113.38295) (xy 235.915187 -113.424141) (xy 235.944653 -113.469991) (xy 235.967295 -113.519568)
			(xy 235.98265 -113.571863) (xy 235.990406 -113.625811) (xy 235.990892 -113.653062) (xy 235.99047 -113.678594)
			(xy 235.983663 -113.729201) (xy 235.970166 -113.778448) (xy 235.95022 -113.825455) (xy 235.937552 -113.847626)
			(xy 235.930948 -113.858802) (xy 235.929932 -113.88471) (xy 235.974636 -113.972848) (xy 235.978759 -113.980331)
			(xy 235.991063 -113.992176) (xy 236.006559 -113.999355) (xy 236.015022 -114.000534) (xy 236.015276 -114.000534)
			(xy 236.043255 -114.00365) (xy 236.097891 -114.017226) (xy 236.149939 -114.038683) (xy 236.198268 -114.067556)
			(xy 236.24183 -114.103217) (xy 236.279678 -114.144894) (xy 236.31099 -114.19168) (xy 236.335087 -114.242559)
			(xy 236.351445 -114.296428) (xy 236.359709 -114.352115) (xy 236.360208 -114.380264) (xy 236.359678 -114.408426)
			(xy 236.351402 -114.464138) (xy 236.335023 -114.518028) (xy 236.310899 -114.568924) (xy 236.279554 -114.615719)
			(xy 236.241669 -114.657397) (xy 236.230821 -114.666268) (xy 236.640876 -114.666268) (xy 236.644947 -114.610646)
			(xy 236.657073 -114.556209) (xy 236.676996 -114.504118) (xy 236.704292 -114.455483) (xy 236.738378 -114.41134)
			(xy 236.778527 -114.372631) (xy 236.823885 -114.34018) (xy 236.873485 -114.314679) (xy 236.926269 -114.296672)
			(xy 236.981112 -114.286542) (xy 237.036846 -114.284505) (xy 237.092283 -114.290605) (xy 237.14624 -114.304711)
			(xy 237.197569 -114.326523) (xy 237.245175 -114.355577) (xy 237.288043 -114.391252) (xy 237.32526 -114.432789)
			(xy 237.356033 -114.479302) (xy 237.379705 -114.529799) (xy 237.395773 -114.583206) (xy 237.403893 -114.638382)
			(xy 237.404402 -114.666268) (xy 237.404291 -114.672364) (xy 242.661184 -114.672364) (xy 242.665255 -114.616742)
			(xy 242.677381 -114.562305) (xy 242.697304 -114.510214) (xy 242.7246 -114.461579) (xy 242.758686 -114.417436)
			(xy 242.798835 -114.378727) (xy 242.844193 -114.346276) (xy 242.893793 -114.320775) (xy 242.946577 -114.302768)
			(xy 243.00142 -114.292638) (xy 243.057154 -114.290601) (xy 243.112591 -114.296701) (xy 243.166548 -114.310807)
			(xy 243.217877 -114.332619) (xy 243.265483 -114.361673) (xy 243.308351 -114.397348) (xy 243.345568 -114.438885)
			(xy 243.376341 -114.485398) (xy 243.400013 -114.535895) (xy 243.416081 -114.589302) (xy 243.424201 -114.644478)
			(xy 243.42471 -114.672364) (xy 243.424201 -114.70025) (xy 243.416081 -114.755426) (xy 243.400013 -114.808833)
			(xy 243.376341 -114.85933) (xy 243.345568 -114.905843) (xy 243.308351 -114.94738) (xy 243.265483 -114.983055)
			(xy 243.217877 -115.012109) (xy 243.166548 -115.033921) (xy 243.112591 -115.048027) (xy 243.057154 -115.054127)
			(xy 243.00142 -115.05209) (xy 242.946577 -115.04196) (xy 242.893793 -115.023953) (xy 242.844193 -114.998452)
			(xy 242.798835 -114.966001) (xy 242.758686 -114.927292) (xy 242.7246 -114.883149) (xy 242.697304 -114.834514)
			(xy 242.677381 -114.782423) (xy 242.665255 -114.727986) (xy 242.661184 -114.672364) (xy 237.404291 -114.672364)
			(xy 237.403893 -114.694154) (xy 237.395773 -114.74933) (xy 237.379705 -114.802737) (xy 237.356033 -114.853234)
			(xy 237.32526 -114.899747) (xy 237.288043 -114.941284) (xy 237.245175 -114.976959) (xy 237.197569 -115.006013)
			(xy 237.14624 -115.027825) (xy 237.092283 -115.041931) (xy 237.036846 -115.048031) (xy 236.981112 -115.045994)
			(xy 236.926269 -115.035864) (xy 236.873485 -115.017857) (xy 236.823885 -114.992356) (xy 236.778527 -114.959905)
			(xy 236.738378 -114.921196) (xy 236.704292 -114.877053) (xy 236.676996 -114.828418) (xy 236.657073 -114.776327)
			(xy 236.644947 -114.72189) (xy 236.640876 -114.666268) (xy 236.230821 -114.666268) (xy 236.198067 -114.693052)
			(xy 236.149696 -114.721907) (xy 236.097609 -114.743337) (xy 236.070394 -114.750596) (xy 236.061134 -114.753304)
			(xy 236.045472 -114.764552) (xy 236.039914 -114.77244) (xy 235.996734 -114.838988) (xy 235.992924 -114.85753)
			(xy 235.994702 -114.867436) (xy 235.997654 -114.884492) (xy 236.000834 -114.918962) (xy 236.001052 -114.93627)
			(xy 236.000566 -114.963521) (xy 235.99281 -115.017469) (xy 235.977455 -115.069764) (xy 235.954813 -115.119341)
			(xy 235.925347 -115.165191) (xy 235.889656 -115.206382) (xy 235.848465 -115.242073) (xy 235.802615 -115.271539)
			(xy 235.753038 -115.294181) (xy 235.700743 -115.309536) (xy 235.646795 -115.317292) (xy 235.592293 -115.317292)
			(xy 235.538345 -115.309536) (xy 235.48605 -115.294181) (xy 235.436473 -115.271539) (xy 235.390623 -115.242073)
			(xy 235.349432 -115.206382) (xy 235.313741 -115.165191) (xy 235.284275 -115.119341) (xy 235.261633 -115.069764)
			(xy 235.246278 -115.017469) (xy 235.238522 -114.963521) (xy 235.238036 -114.93627) (xy 235.238473 -114.908105)
			(xy 235.24676 -114.852387) (xy 235.26315 -114.798493) (xy 235.287285 -114.747595) (xy 235.318642 -114.700799)
			(xy 235.356539 -114.659122) (xy 235.400152 -114.62347) (xy 235.448533 -114.594618) (xy 235.500631 -114.573194)
			(xy 235.52785 -114.565938) (xy 235.537097 -114.563196) (xy 235.552765 -114.551972) (xy 235.55833 -114.544094)
			(xy 235.60151 -114.477546) (xy 235.60532 -114.459004) (xy 235.603542 -114.449098) (xy 235.600595 -114.432041)
			(xy 235.597412 -114.397572) (xy 235.597192 -114.380264) (xy 235.597583 -114.354731) (xy 235.604399 -114.304123)
			(xy 235.617906 -114.254876) (xy 235.63786 -114.20787) (xy 235.650532 -114.1857) (xy 235.657136 -114.174524)
			(xy 235.658152 -114.148616) (xy 235.613448 -114.060478) (xy 235.609325 -114.052995) (xy 235.597023 -114.041148)
			(xy 235.581526 -114.033969) (xy 235.573062 -114.032792) (xy 235.572808 -114.032792) (xy 235.544841 -114.029581)
			(xy 235.490209 -114.016019) (xy 235.438162 -113.994574) (xy 235.389833 -113.965713) (xy 235.346271 -113.930062)
			(xy 235.308421 -113.888396) (xy 235.277106 -113.84162) (xy 235.253006 -113.790749) (xy 235.236644 -113.736888)
			(xy 235.228377 -113.681208) (xy 235.227876 -113.653062) (xy 211.941978 -113.653062) (xy 211.962129 -113.68352)
			(xy 211.985801 -113.734017) (xy 212.001869 -113.787424) (xy 212.009989 -113.8426) (xy 212.010498 -113.870486)
			(xy 212.009989 -113.898372) (xy 212.001869 -113.953548) (xy 211.985801 -114.006955) (xy 211.962129 -114.057452)
			(xy 211.931356 -114.103965) (xy 211.894139 -114.145502) (xy 211.851271 -114.181177) (xy 211.803665 -114.210231)
			(xy 211.752336 -114.232043) (xy 211.698379 -114.246149) (xy 211.642942 -114.252249) (xy 211.587208 -114.250212)
			(xy 211.532365 -114.240082) (xy 211.479581 -114.222075) (xy 211.429981 -114.196574) (xy 211.384623 -114.164123)
			(xy 211.344474 -114.125414) (xy 211.310388 -114.081271) (xy 211.283092 -114.032636) (xy 211.263169 -113.980545)
			(xy 211.251043 -113.926108) (xy 211.246972 -113.870486) (xy 209.626454 -113.870486) (xy 209.626454 -113.93424)
			(xy 209.626833 -113.942803) (xy 209.632555 -113.95895) (xy 209.643253 -113.97233) (xy 209.65033 -113.977166)
			(xy 209.674696 -113.991664) (xy 209.719239 -114.026742) (xy 209.758093 -114.068032) (xy 209.790401 -114.114623)
			(xy 209.81545 -114.165486) (xy 209.832687 -114.219499) (xy 209.841732 -114.27547) (xy 209.842608 -114.30381)
			(xy 209.842608 -114.3127) (xy 209.842031 -114.335949) (xy 209.835919 -114.382053) (xy 209.830416 -114.404648)
			(xy 209.827368 -114.416332) (xy 209.829654 -114.427508) (xy 209.830946 -114.433223) (xy 209.835831 -114.443871)
			(xy 209.839306 -114.44859) (xy 209.888328 -114.51209) (xy 209.894496 -114.519422) (xy 209.910946 -114.529218)
			(xy 209.920332 -114.53114) (xy 209.92846 -114.531902) (xy 211.48802 -114.531902) (xy 211.496402 -114.528854)
			(xy 211.528418 -114.51774) (xy 211.595108 -114.505721) (xy 211.62899 -114.504978) (xy 211.66287 -114.505737)
			(xy 211.729559 -114.517751) (xy 211.761578 -114.528854) (xy 211.76996 -114.531902) (xy 212.847174 -114.531902)
			(xy 212.857238 -114.532339) (xy 212.875823 -114.540072) (xy 212.883242 -114.546888) (xy 213.361524 -115.02517)
			(xy 213.368368 -115.032569) (xy 213.376088 -115.051168) (xy 213.37651 -115.061238) (xy 213.37651 -116.188224)
			(xy 223.368955 -116.188224) (xy 223.373268 -116.130954) (xy 223.386114 -116.074977) (xy 223.407204 -116.021557)
			(xy 223.436062 -115.971901) (xy 223.472035 -115.927131) (xy 223.492822 -115.907312) (xy 223.500224 -115.899791)
			(xy 223.508747 -115.88051) (xy 223.509332 -115.869974) (xy 223.509332 -115.795298) (xy 223.508808 -115.784748)
			(xy 223.500268 -115.765453) (xy 223.492822 -115.75796) (xy 223.473758 -115.739813) (xy 223.440301 -115.699182)
			(xy 223.412743 -115.65434) (xy 223.391605 -115.606137) (xy 223.37729 -115.555488) (xy 223.370069 -115.503353)
			(xy 223.369632 -115.477036) (xy 223.370118 -115.449785) (xy 223.377874 -115.395837) (xy 223.393229 -115.343542)
			(xy 223.415871 -115.293965) (xy 223.445337 -115.248115) (xy 223.481028 -115.206924) (xy 223.522219 -115.171233)
			(xy 223.568069 -115.141767) (xy 223.617646 -115.119125) (xy 223.669941 -115.10377) (xy 223.723889 -115.096014)
			(xy 223.778391 -115.096014) (xy 223.832339 -115.10377) (xy 223.884634 -115.119125) (xy 223.934211 -115.141767)
			(xy 223.980061 -115.171233) (xy 224.021252 -115.206924) (xy 224.056943 -115.248115) (xy 224.086409 -115.293965)
			(xy 224.109051 -115.343542) (xy 224.124406 -115.395837) (xy 224.132162 -115.449785) (xy 224.132648 -115.477036)
			(xy 224.132221 -115.503352) (xy 224.12498 -115.555482) (xy 224.110654 -115.606127) (xy 224.089514 -115.654326)
			(xy 224.06196 -115.699168) (xy 224.028514 -115.739805) (xy 224.009458 -115.75796) (xy 224.002081 -115.765502)
			(xy 223.99354 -115.784766) (xy 223.992948 -115.795298) (xy 223.992948 -115.869974) (xy 223.993464 -115.880526)
			(xy 224.002007 -115.899822) (xy 224.009458 -115.907312) (xy 224.03028 -115.927097) (xy 224.066251 -115.971876)
			(xy 224.095107 -116.021539) (xy 224.116195 -116.074966) (xy 224.12904 -116.130949) (xy 224.133352 -116.188224)
			(xy 225.907203 -116.188224) (xy 225.911514 -116.130957) (xy 225.924357 -116.074981) (xy 225.945443 -116.021562)
			(xy 225.974294 -115.971906) (xy 226.010261 -115.927133) (xy 226.031044 -115.907312) (xy 226.038434 -115.89978)
			(xy 226.046967 -115.880508) (xy 226.047554 -115.869974) (xy 226.047554 -115.795298) (xy 226.047053 -115.784745)
			(xy 226.0385 -115.765449) (xy 226.031044 -115.75796) (xy 226.011965 -115.739828) (xy 225.978512 -115.699192)
			(xy 225.950958 -115.654346) (xy 225.929824 -115.606141) (xy 225.915511 -115.55549) (xy 225.90829 -115.503353)
			(xy 225.907854 -115.477036) (xy 225.90834 -115.449785) (xy 225.916096 -115.395837) (xy 225.931451 -115.343542)
			(xy 225.954093 -115.293965) (xy 225.983559 -115.248115) (xy 226.01925 -115.206924) (xy 226.060441 -115.171233)
			(xy 226.106291 -115.141767) (xy 226.155868 -115.119125) (xy 226.208163 -115.10377) (xy 226.262111 -115.096014)
			(xy 226.316613 -115.096014) (xy 226.370561 -115.10377) (xy 226.422856 -115.119125) (xy 226.472433 -115.141767)
			(xy 226.518283 -115.171233) (xy 226.559474 -115.206924) (xy 226.595165 -115.248115) (xy 226.624631 -115.293965)
			(xy 226.647273 -115.343542) (xy 226.662628 -115.395837) (xy 226.670384 -115.449785) (xy 226.67087 -115.477036)
			(xy 226.670436 -115.503351) (xy 226.663196 -115.555482) (xy 226.648871 -115.606125) (xy 226.627732 -115.654324)
			(xy 226.60018 -115.699167) (xy 226.566735 -115.739805) (xy 226.54768 -115.75796) (xy 226.540291 -115.765492)
			(xy 226.53176 -115.784764) (xy 226.53117 -115.795298) (xy 226.53117 -115.869974) (xy 226.531708 -115.880522)
			(xy 226.540238 -115.899817) (xy 226.54768 -115.907312) (xy 226.568506 -115.927095) (xy 226.604484 -115.971871)
			(xy 226.633345 -116.021534) (xy 226.654438 -116.074961) (xy 226.667286 -116.130946) (xy 226.668309 -116.144533)
			(xy 230.110137 -116.144533) (xy 230.114448 -116.087265) (xy 230.127291 -116.03129) (xy 230.148377 -115.977871)
			(xy 230.17723 -115.928215) (xy 230.213198 -115.883444) (xy 230.233982 -115.863624) (xy 230.241372 -115.856093)
			(xy 230.249904 -115.83682) (xy 230.250492 -115.826286) (xy 230.250492 -115.75161) (xy 230.249973 -115.741059)
			(xy 230.241431 -115.721764) (xy 230.233982 -115.714272) (xy 230.213242 -115.694404) (xy 230.177267 -115.649638)
			(xy 230.148405 -115.599988) (xy 230.12731 -115.546573) (xy 230.114457 -115.4906) (xy 230.110137 -115.433333)
			(xy 230.114448 -115.376065) (xy 230.127291 -115.32009) (xy 230.148377 -115.266671) (xy 230.17723 -115.217015)
			(xy 230.213198 -115.172244) (xy 230.233982 -115.152424) (xy 230.241372 -115.144893) (xy 230.249904 -115.12562)
			(xy 230.250492 -115.115086) (xy 230.250492 -115.04041) (xy 230.249973 -115.029859) (xy 230.241431 -115.010564)
			(xy 230.233982 -115.003072) (xy 230.214916 -114.984927) (xy 230.181461 -114.944294) (xy 230.153904 -114.899452)
			(xy 230.132767 -114.851249) (xy 230.118452 -114.8006) (xy 230.111229 -114.748465) (xy 230.110792 -114.722148)
			(xy 230.1113 -114.694896) (xy 230.11905 -114.640947) (xy 230.1344 -114.58865) (xy 230.157037 -114.53907)
			(xy 230.1865 -114.493217) (xy 230.222189 -114.452023) (xy 230.263378 -114.416329) (xy 230.309228 -114.38686)
			(xy 230.358805 -114.364217) (xy 230.4111 -114.348861) (xy 230.465048 -114.341103) (xy 230.4923 -114.34064)
			(xy 230.518615 -114.341095) (xy 230.570744 -114.34833) (xy 230.621388 -114.362651) (xy 230.669587 -114.383786)
			(xy 230.71443 -114.411335) (xy 230.755068 -114.444777) (xy 230.773224 -114.46383) (xy 230.780744 -114.471234)
			(xy 230.800025 -114.479759) (xy 230.810562 -114.48034) (xy 230.885238 -114.48034) (xy 230.895784 -114.479779)
			(xy 230.915079 -114.471265) (xy 230.922576 -114.46383) (xy 230.940756 -114.444799) (xy 230.98138 -114.411338)
			(xy 231.026215 -114.383775) (xy 231.074411 -114.362632) (xy 231.125054 -114.34831) (xy 231.177185 -114.341081)
			(xy 231.2035 -114.34064) (xy 231.230755 -114.341055) (xy 231.28471 -114.348814) (xy 231.337012 -114.364172)
			(xy 231.386595 -114.386818) (xy 231.426389 -114.412395) (xy 232.727135 -114.412395) (xy 232.727135 -114.360405)
			(xy 232.735269 -114.309056) (xy 232.751336 -114.259612) (xy 232.774941 -114.21329) (xy 232.805502 -114.171231)
			(xy 232.842266 -114.134472) (xy 232.884329 -114.103917) (xy 232.930654 -114.080318) (xy 232.980101 -114.064258)
			(xy 233.031451 -114.056132) (xy 233.057446 -114.055652) (xy 233.084091 -114.056131) (xy 233.136694 -114.064663)
			(xy 233.187244 -114.081529) (xy 233.234431 -114.106293) (xy 233.277029 -114.138312) (xy 233.313934 -114.176754)
			(xy 233.32948 -114.1984) (xy 233.337844 -114.209686) (xy 233.359517 -114.227541) (xy 233.385231 -114.238824)
			(xy 233.413046 -114.242682) (xy 233.440861 -114.238824) (xy 233.466575 -114.227541) (xy 233.488248 -114.209686)
			(xy 233.496612 -114.1984) (xy 233.512202 -114.176793) (xy 233.549115 -114.138375) (xy 233.59171 -114.106373)
			(xy 233.638886 -114.081616) (xy 233.689421 -114.064743) (xy 233.742007 -114.056191) (xy 233.768646 -114.055652)
			(xy 233.794628 -114.056245) (xy 233.84595 -114.064381) (xy 233.895369 -114.080444) (xy 233.941666 -114.104039)
			(xy 233.983703 -114.134586) (xy 234.020444 -114.171332) (xy 234.050985 -114.213373) (xy 234.074574 -114.259674)
			(xy 234.09063 -114.309095) (xy 234.098758 -114.360418) (xy 234.098758 -114.412382) (xy 234.09063 -114.463705)
			(xy 234.074574 -114.513126) (xy 234.050985 -114.559427) (xy 234.020444 -114.601468) (xy 233.983703 -114.638214)
			(xy 233.941666 -114.668761) (xy 233.895369 -114.692356) (xy 233.84595 -114.708419) (xy 233.794628 -114.716555)
			(xy 233.768646 -114.717068) (xy 233.742001 -114.716586) (xy 233.689399 -114.708054) (xy 233.638849 -114.691187)
			(xy 233.591663 -114.666424) (xy 233.549064 -114.634406) (xy 233.512158 -114.595965) (xy 233.496612 -114.57432)
			(xy 233.488248 -114.563034) (xy 233.466575 -114.545179) (xy 233.440861 -114.533896) (xy 233.413046 -114.530038)
			(xy 233.385231 -114.533896) (xy 233.359517 -114.545179) (xy 233.337844 -114.563034) (xy 233.32948 -114.57432)
			(xy 233.3139 -114.595935) (xy 233.276985 -114.634351) (xy 233.234387 -114.666352) (xy 233.18721 -114.691108)
			(xy 233.136673 -114.707979) (xy 233.084085 -114.716529) (xy 233.057446 -114.717068) (xy 233.031451 -114.716668)
			(xy 232.980101 -114.708542) (xy 232.930654 -114.692482) (xy 232.884329 -114.668883) (xy 232.842266 -114.638328)
			(xy 232.805502 -114.601569) (xy 232.774941 -114.55951) (xy 232.751336 -114.513188) (xy 232.735269 -114.463744)
			(xy 232.727135 -114.412395) (xy 231.426389 -114.412395) (xy 231.432451 -114.416291) (xy 231.473645 -114.451989)
			(xy 231.509338 -114.493188) (xy 231.538805 -114.539047) (xy 231.561445 -114.588633) (xy 231.576797 -114.640937)
			(xy 231.584548 -114.694893) (xy 231.585008 -114.722148) (xy 231.58457 -114.748463) (xy 231.577329 -114.800593)
			(xy 231.563004 -114.851236) (xy 231.541866 -114.899435) (xy 231.514315 -114.944277) (xy 231.480872 -114.984916)
			(xy 231.461818 -115.003072) (xy 231.454429 -115.010604) (xy 231.445897 -115.029876) (xy 231.445308 -115.04041)
			(xy 231.445308 -115.115086) (xy 231.445829 -115.125637) (xy 231.45437 -115.144932) (xy 231.461818 -115.152424)
			(xy 231.482654 -115.172196) (xy 231.518629 -115.216975) (xy 231.547487 -115.26664) (xy 231.565585 -115.312489)
			(xy 232.727211 -115.312489) (xy 232.727211 -115.260511) (xy 232.735343 -115.209174) (xy 232.751406 -115.159741)
			(xy 232.775005 -115.113429) (xy 232.805559 -115.071381) (xy 232.842316 -115.034629) (xy 232.884369 -115.004081)
			(xy 232.930683 -114.980489) (xy 232.980119 -114.964432) (xy 233.031457 -114.956308) (xy 233.057446 -114.955828)
			(xy 233.084091 -114.956318) (xy 233.136692 -114.964848) (xy 233.187242 -114.981713) (xy 233.234428 -115.006475)
			(xy 233.277027 -115.038492) (xy 233.313933 -115.076932) (xy 233.32948 -115.098576) (xy 233.337844 -115.109862)
			(xy 233.359517 -115.127717) (xy 233.385231 -115.139) (xy 233.413046 -115.142858) (xy 233.440861 -115.139)
			(xy 233.466575 -115.127717) (xy 233.488248 -115.109862) (xy 233.496612 -115.098576) (xy 233.512195 -115.076964)
			(xy 233.54911 -115.038547) (xy 233.591707 -115.006547) (xy 233.638884 -114.98179) (xy 233.68942 -114.964918)
			(xy 233.742007 -114.956367) (xy 233.768646 -114.955828) (xy 233.794634 -114.956269) (xy 233.845968 -114.964406)
			(xy 233.895398 -114.980473) (xy 233.941706 -115.004074) (xy 233.983753 -115.034628) (xy 234.020502 -115.071383)
			(xy 234.05105 -115.113433) (xy 234.074645 -115.159745) (xy 234.090705 -115.209177) (xy 234.098835 -115.260512)
			(xy 234.098835 -115.312488) (xy 234.090704 -115.363823) (xy 234.074645 -115.413255) (xy 234.05105 -115.459567)
			(xy 234.020502 -115.501617) (xy 233.983753 -115.538372) (xy 233.941706 -115.568926) (xy 233.895398 -115.592527)
			(xy 233.845968 -115.608594) (xy 233.794634 -115.616731) (xy 233.768646 -115.617244) (xy 233.742 -115.616772)
			(xy 233.689397 -115.608239) (xy 233.638847 -115.591372) (xy 233.59166 -115.566606) (xy 233.549062 -115.534586)
			(xy 233.512158 -115.496142) (xy 233.496612 -115.474496) (xy 233.488248 -115.46321) (xy 233.466575 -115.445355)
			(xy 233.440861 -115.434072) (xy 233.413046 -115.430214) (xy 233.385231 -115.434072) (xy 233.359517 -115.445355)
			(xy 233.337844 -115.46321) (xy 233.32948 -115.474496) (xy 233.313923 -115.496128) (xy 233.277 -115.53454)
			(xy 233.234397 -115.566536) (xy 233.187215 -115.591288) (xy 233.136676 -115.608157) (xy 233.084086 -115.616705)
			(xy 233.057446 -115.617244) (xy 233.031457 -115.616692) (xy 232.980119 -115.608568) (xy 232.930683 -115.592511)
			(xy 232.884369 -115.568919) (xy 232.842316 -115.538371) (xy 232.805559 -115.501619) (xy 232.775005 -115.45957)
			(xy 232.751406 -115.413259) (xy 232.735343 -115.363826) (xy 232.727211 -115.312489) (xy 231.565585 -115.312489)
			(xy 231.568577 -115.320069) (xy 231.581422 -115.376054) (xy 231.585733 -115.433333) (xy 231.581413 -115.49061)
			(xy 231.568557 -115.546594) (xy 231.547458 -115.600018) (xy 231.518592 -115.649678) (xy 231.482609 -115.694452)
			(xy 231.461818 -115.714272) (xy 231.454429 -115.721804) (xy 231.445897 -115.741076) (xy 231.445308 -115.75161)
			(xy 231.445308 -115.826286) (xy 231.445829 -115.836837) (xy 231.45437 -115.856132) (xy 231.461818 -115.863624)
			(xy 231.482654 -115.883396) (xy 231.518629 -115.928175) (xy 231.547487 -115.97784) (xy 231.568577 -116.031269)
			(xy 231.581422 -116.087254) (xy 231.585733 -116.144533) (xy 231.581413 -116.20181) (xy 231.578959 -116.212495)
			(xy 232.727133 -116.212495) (xy 232.727133 -116.160505) (xy 232.735267 -116.109156) (xy 232.751334 -116.059711)
			(xy 232.774939 -116.013389) (xy 232.8055 -115.97133) (xy 232.842265 -115.93457) (xy 232.884328 -115.904015)
			(xy 232.930653 -115.880417) (xy 232.9801 -115.864356) (xy 233.031451 -115.85623) (xy 233.057446 -115.85575)
			(xy 233.084091 -115.85623) (xy 233.136694 -115.864762) (xy 233.187244 -115.881628) (xy 233.23443 -115.906392)
			(xy 233.277029 -115.93841) (xy 233.313934 -115.976852) (xy 233.32948 -115.998498) (xy 233.337844 -116.009784)
			(xy 233.359517 -116.027639) (xy 233.385231 -116.038922) (xy 233.413046 -116.04278) (xy 233.440861 -116.038922)
			(xy 233.466575 -116.027639) (xy 233.488248 -116.009784) (xy 233.496612 -115.998498) (xy 233.512202 -115.976891)
			(xy 233.549115 -115.938473) (xy 233.59171 -115.906471) (xy 233.638886 -115.881714) (xy 233.689421 -115.864841)
			(xy 233.742007 -115.856289) (xy 233.768646 -115.85575) (xy 233.794627 -115.856347) (xy 233.84595 -115.864483)
			(xy 233.895368 -115.880546) (xy 233.941665 -115.904141) (xy 233.983702 -115.934687) (xy 233.985283 -115.936268)
			(xy 235.270546 -115.936268) (xy 235.274617 -115.880646) (xy 235.286743 -115.826209) (xy 235.306666 -115.774118)
			(xy 235.333962 -115.725483) (xy 235.368048 -115.68134) (xy 235.408197 -115.642631) (xy 235.453555 -115.61018)
			(xy 235.503155 -115.584679) (xy 235.555939 -115.566672) (xy 235.610782 -115.556542) (xy 235.666516 -115.554505)
			(xy 235.721953 -115.560605) (xy 235.77591 -115.574711) (xy 235.827239 -115.596523) (xy 235.874845 -115.625577)
			(xy 235.917713 -115.661252) (xy 235.95493 -115.702789) (xy 235.985703 -115.749302) (xy 236.009375 -115.799799)
			(xy 236.025443 -115.853206) (xy 236.033563 -115.908382) (xy 236.034072 -115.936268) (xy 236.033563 -115.964154)
			(xy 236.025443 -116.01933) (xy 236.009375 -116.072737) (xy 235.985703 -116.123234) (xy 235.95493 -116.169747)
			(xy 235.917713 -116.211284) (xy 235.874845 -116.246959) (xy 235.827239 -116.276013) (xy 235.77591 -116.297825)
			(xy 235.721953 -116.311931) (xy 235.666516 -116.318031) (xy 235.610782 -116.315994) (xy 235.555939 -116.305864)
			(xy 235.503155 -116.287857) (xy 235.453555 -116.262356) (xy 235.408197 -116.229905) (xy 235.368048 -116.191196)
			(xy 235.333962 -116.147053) (xy 235.306666 -116.098418) (xy 235.286743 -116.046327) (xy 235.274617 -115.99189)
			(xy 235.270546 -115.936268) (xy 233.985283 -115.936268) (xy 234.020442 -115.971434) (xy 234.050983 -116.013474)
			(xy 234.074572 -116.059775) (xy 234.090628 -116.109195) (xy 234.098756 -116.160518) (xy 234.098756 -116.212482)
			(xy 234.090628 -116.263805) (xy 234.074572 -116.313225) (xy 234.050983 -116.359526) (xy 234.020442 -116.401566)
			(xy 233.983702 -116.438313) (xy 233.970963 -116.44757) (xy 236.707678 -116.44757) (xy 236.711749 -116.391948)
			(xy 236.723875 -116.337511) (xy 236.743798 -116.28542) (xy 236.771094 -116.236785) (xy 236.80518 -116.192642)
			(xy 236.845329 -116.153933) (xy 236.890687 -116.121482) (xy 236.940287 -116.095981) (xy 236.993071 -116.077974)
			(xy 237.047914 -116.067844) (xy 237.103648 -116.065807) (xy 237.159085 -116.071907) (xy 237.213042 -116.086013)
			(xy 237.264371 -116.107825) (xy 237.311977 -116.136879) (xy 237.354845 -116.172554) (xy 237.392062 -116.214091)
			(xy 237.422835 -116.260604) (xy 237.446507 -116.311101) (xy 237.462575 -116.364508) (xy 237.470695 -116.419684)
			(xy 237.471204 -116.44757) (xy 237.470695 -116.475456) (xy 237.462575 -116.530632) (xy 237.446507 -116.584039)
			(xy 237.422835 -116.634536) (xy 237.392062 -116.681049) (xy 237.354845 -116.722586) (xy 237.311977 -116.758261)
			(xy 237.264371 -116.787315) (xy 237.213042 -116.809127) (xy 237.159085 -116.823233) (xy 237.103648 -116.829333)
			(xy 237.047914 -116.827296) (xy 236.993071 -116.817166) (xy 236.940287 -116.799159) (xy 236.890687 -116.773658)
			(xy 236.845329 -116.741207) (xy 236.80518 -116.702498) (xy 236.771094 -116.658355) (xy 236.743798 -116.60972)
			(xy 236.723875 -116.557629) (xy 236.711749 -116.503192) (xy 236.707678 -116.44757) (xy 233.970963 -116.44757)
			(xy 233.941665 -116.468859) (xy 233.895368 -116.492454) (xy 233.84595 -116.508517) (xy 233.794627 -116.516653)
			(xy 233.768646 -116.517166) (xy 233.742001 -116.516685) (xy 233.689399 -116.508153) (xy 233.638849 -116.491286)
			(xy 233.591663 -116.466523) (xy 233.549064 -116.434505) (xy 233.512158 -116.396063) (xy 233.496612 -116.374418)
			(xy 233.488248 -116.363132) (xy 233.466575 -116.345277) (xy 233.440861 -116.333994) (xy 233.413046 -116.330136)
			(xy 233.385231 -116.333994) (xy 233.359517 -116.345277) (xy 233.337844 -116.363132) (xy 233.32948 -116.374418)
			(xy 233.3139 -116.396033) (xy 233.276984 -116.434449) (xy 233.234387 -116.46645) (xy 233.187209 -116.491206)
			(xy 233.136673 -116.508077) (xy 233.084085 -116.516627) (xy 233.057446 -116.517166) (xy 233.031451 -116.51677)
			(xy 232.9801 -116.508644) (xy 232.930654 -116.492583) (xy 232.884328 -116.468985) (xy 232.842265 -116.43843)
			(xy 232.8055 -116.40167) (xy 232.774939 -116.359611) (xy 232.751334 -116.313289) (xy 232.735267 -116.263844)
			(xy 232.727133 -116.212495) (xy 231.578959 -116.212495) (xy 231.568557 -116.257794) (xy 231.547458 -116.311218)
			(xy 231.518592 -116.360878) (xy 231.482609 -116.405652) (xy 231.461818 -116.425472) (xy 231.454429 -116.433004)
			(xy 231.445897 -116.452276) (xy 231.445308 -116.46281) (xy 231.445308 -116.537486) (xy 231.445829 -116.548037)
			(xy 231.45437 -116.567332) (xy 231.461818 -116.574824) (xy 231.480882 -116.592971) (xy 231.514337 -116.633603)
			(xy 231.541895 -116.678445) (xy 231.563032 -116.726648) (xy 231.577347 -116.777296) (xy 231.58457 -116.829431)
			(xy 231.585008 -116.855748) (xy 231.584567 -116.883) (xy 231.576804 -116.93695) (xy 231.561443 -116.989245)
			(xy 231.538796 -117.038823) (xy 231.509325 -117.084673) (xy 231.485302 -117.112393) (xy 232.727155 -117.112393)
			(xy 232.727155 -117.060407) (xy 232.735289 -117.009061) (xy 232.751355 -116.959619) (xy 232.774958 -116.9133)
			(xy 232.805517 -116.871244) (xy 232.842279 -116.834487) (xy 232.88434 -116.803934) (xy 232.930662 -116.780337)
			(xy 232.980106 -116.764278) (xy 233.031453 -116.756152) (xy 233.057446 -116.755672) (xy 233.084092 -116.756143)
			(xy 233.136695 -116.764675) (xy 233.187246 -116.781542) (xy 233.234433 -116.806308) (xy 233.277031 -116.838328)
			(xy 233.313935 -116.876773) (xy 233.32948 -116.89842) (xy 233.337844 -116.909706) (xy 233.359517 -116.927561)
			(xy 233.385231 -116.938844) (xy 233.413046 -116.942702) (xy 233.440861 -116.938844) (xy 233.466575 -116.927561)
			(xy 233.488248 -116.909706) (xy 233.496612 -116.89842) (xy 233.512179 -116.876796) (xy 233.549099 -116.838383)
			(xy 233.5917 -116.806385) (xy 233.63888 -116.781631) (xy 233.689418 -116.764761) (xy 233.742006 -116.756211)
			(xy 233.768646 -116.755672) (xy 233.794629 -116.756225) (xy 233.845955 -116.764361) (xy 233.895376 -116.780425)
			(xy 233.941677 -116.804022) (xy 233.983716 -116.83457) (xy 234.02046 -116.871319) (xy 234.051002 -116.913362)
			(xy 234.074593 -116.959666) (xy 234.09065 -117.00909) (xy 234.098779 -117.060417) (xy 234.098779 -117.112383)
			(xy 234.09065 -117.16371) (xy 234.074593 -117.213134) (xy 234.051002 -117.259438) (xy 234.02046 -117.301481)
			(xy 233.983716 -117.33823) (xy 233.941677 -117.368778) (xy 233.895376 -117.392375) (xy 233.845955 -117.408439)
			(xy 233.794629 -117.416575) (xy 233.768646 -117.417088) (xy 233.742001 -117.416597) (xy 233.6894 -117.408066)
			(xy 233.638851 -117.391201) (xy 233.591665 -117.366439) (xy 233.549066 -117.334423) (xy 233.512159 -117.295984)
			(xy 233.496612 -117.27434) (xy 233.488248 -117.263054) (xy 233.466575 -117.245199) (xy 233.440861 -117.233916)
			(xy 233.413046 -117.230058) (xy 233.385231 -117.233916) (xy 233.359517 -117.245199) (xy 233.337844 -117.263054)
			(xy 233.32948 -117.27434) (xy 233.313906 -117.295959) (xy 233.276989 -117.334375) (xy 233.23439 -117.366374)
			(xy 233.187211 -117.391129) (xy 233.136674 -117.408) (xy 233.084085 -117.416549) (xy 233.057446 -117.417088)
			(xy 233.031453 -117.416648) (xy 232.980106 -117.408522) (xy 232.930662 -117.392463) (xy 232.88434 -117.368866)
			(xy 232.842279 -117.338313) (xy 232.805517 -117.301556) (xy 232.774958 -117.2595) (xy 232.751355 -117.213181)
			(xy 232.735289 -117.163739) (xy 232.727155 -117.112393) (xy 231.485302 -117.112393) (xy 231.473629 -117.125863)
			(xy 231.432434 -117.161553) (xy 231.386581 -117.191019) (xy 231.337 -117.213659) (xy 231.284703 -117.229014)
			(xy 231.230752 -117.23677) (xy 231.2035 -117.237256) (xy 231.177185 -117.236803) (xy 231.125056 -117.229567)
			(xy 231.074412 -117.215246) (xy 231.026213 -117.194111) (xy 230.98137 -117.166562) (xy 230.940732 -117.133119)
			(xy 230.922576 -117.114066) (xy 230.915056 -117.106662) (xy 230.895775 -117.098136) (xy 230.885238 -117.097556)
			(xy 230.810562 -117.097556) (xy 230.800017 -117.098118) (xy 230.780722 -117.106632) (xy 230.773224 -117.114066)
			(xy 230.755063 -117.133116) (xy 230.714433 -117.166571) (xy 230.669593 -117.194129) (xy 230.621394 -117.215268)
			(xy 230.570748 -117.229587) (xy 230.518616 -117.236815) (xy 230.4923 -117.237256) (xy 230.465051 -117.236722)
			(xy 230.411107 -117.228967) (xy 230.358816 -117.213614) (xy 230.309242 -117.190977) (xy 230.263394 -117.161515)
			(xy 230.222205 -117.125829) (xy 230.186514 -117.084644) (xy 230.157046 -117.0388) (xy 230.134402 -116.989229)
			(xy 230.119043 -116.93694) (xy 230.111281 -116.882997) (xy 230.110792 -116.855748) (xy 230.111227 -116.829433)
			(xy 230.118469 -116.777303) (xy 230.132795 -116.72666) (xy 230.153933 -116.678461) (xy 230.181485 -116.633618)
			(xy 230.214928 -116.59298) (xy 230.233982 -116.574824) (xy 230.241372 -116.567293) (xy 230.249904 -116.54802)
			(xy 230.250492 -116.537486) (xy 230.250492 -116.46281) (xy 230.249973 -116.452259) (xy 230.241431 -116.432964)
			(xy 230.233982 -116.425472) (xy 230.213242 -116.405604) (xy 230.177267 -116.360838) (xy 230.148405 -116.311188)
			(xy 230.12731 -116.257773) (xy 230.114457 -116.2018) (xy 230.110137 -116.144533) (xy 226.668309 -116.144533)
			(xy 226.671599 -116.188224) (xy 226.667279 -116.245502) (xy 226.654424 -116.301485) (xy 226.633324 -116.35491)
			(xy 226.604456 -116.404569) (xy 226.568472 -116.449341) (xy 226.54768 -116.46916) (xy 226.540291 -116.476692)
			(xy 226.53176 -116.495964) (xy 226.53117 -116.506498) (xy 226.53117 -116.581174) (xy 226.531708 -116.591722)
			(xy 226.540238 -116.611017) (xy 226.54768 -116.618512) (xy 226.566731 -116.636673) (xy 226.600189 -116.677301)
			(xy 226.627749 -116.72214) (xy 226.648889 -116.77034) (xy 226.663207 -116.820987) (xy 226.670432 -116.87312)
			(xy 226.67087 -116.899436) (xy 226.670384 -116.926687) (xy 226.662628 -116.980635) (xy 226.647273 -117.03293)
			(xy 226.624631 -117.082507) (xy 226.595165 -117.128357) (xy 226.559474 -117.169548) (xy 226.518283 -117.205239)
			(xy 226.472433 -117.234705) (xy 226.422856 -117.257347) (xy 226.370561 -117.272702) (xy 226.316613 -117.280458)
			(xy 226.262111 -117.280458) (xy 226.208163 -117.272702) (xy 226.155868 -117.257347) (xy 226.106291 -117.234705)
			(xy 226.060441 -117.205239) (xy 226.01925 -117.169548) (xy 225.983559 -117.128357) (xy 225.954093 -117.082507)
			(xy 225.931451 -117.03293) (xy 225.916096 -116.980635) (xy 225.90834 -116.926687) (xy 225.907854 -116.899436)
			(xy 225.908262 -116.87312) (xy 225.915506 -116.820988) (xy 225.929836 -116.770343) (xy 225.950979 -116.722144)
			(xy 225.978537 -116.677302) (xy 226.011987 -116.636666) (xy 226.031044 -116.618512) (xy 226.038434 -116.61098)
			(xy 226.046967 -116.591708) (xy 226.047554 -116.581174) (xy 226.047554 -116.506498) (xy 226.047053 -116.495945)
			(xy 226.0385 -116.476649) (xy 226.031044 -116.46916) (xy 226.010294 -116.449303) (xy 225.974322 -116.404534)
			(xy 225.945464 -116.354882) (xy 225.924372 -116.301465) (xy 225.911521 -116.245492) (xy 225.907203 -116.188224)
			(xy 224.133352 -116.188224) (xy 224.129033 -116.2455) (xy 224.11618 -116.301481) (xy 224.095085 -116.354905)
			(xy 224.066223 -116.404564) (xy 224.030247 -116.449339) (xy 224.009458 -116.46916) (xy 224.002081 -116.476702)
			(xy 223.99354 -116.495966) (xy 223.992948 -116.506498) (xy 223.992948 -116.581174) (xy 223.993464 -116.591726)
			(xy 224.002007 -116.611022) (xy 224.009458 -116.618512) (xy 224.028523 -116.636657) (xy 224.061977 -116.677291)
			(xy 224.089534 -116.722133) (xy 224.11067 -116.770336) (xy 224.124986 -116.820985) (xy 224.13221 -116.873119)
			(xy 224.132648 -116.899436) (xy 224.132162 -116.926687) (xy 224.124406 -116.980635) (xy 224.109051 -117.03293)
			(xy 224.086409 -117.082507) (xy 224.056943 -117.128357) (xy 224.021252 -117.169548) (xy 223.980061 -117.205239)
			(xy 223.934211 -117.234705) (xy 223.884634 -117.257347) (xy 223.832339 -117.272702) (xy 223.778391 -117.280458)
			(xy 223.723889 -117.280458) (xy 223.669941 -117.272702) (xy 223.617646 -117.257347) (xy 223.568069 -117.234705)
			(xy 223.522219 -117.205239) (xy 223.481028 -117.169548) (xy 223.445337 -117.128357) (xy 223.415871 -117.082507)
			(xy 223.393229 -117.03293) (xy 223.377874 -116.980635) (xy 223.370118 -116.926687) (xy 223.369632 -116.899436)
			(xy 223.370047 -116.87312) (xy 223.377291 -116.820989) (xy 223.39162 -116.770345) (xy 223.412762 -116.722146)
			(xy 223.440318 -116.677304) (xy 223.473766 -116.636667) (xy 223.492822 -116.618512) (xy 223.500224 -116.610991)
			(xy 223.508747 -116.59171) (xy 223.509332 -116.581174) (xy 223.509332 -116.506498) (xy 223.508808 -116.495948)
			(xy 223.500268 -116.476653) (xy 223.492822 -116.46916) (xy 223.472068 -116.449305) (xy 223.436089 -116.404539)
			(xy 223.407225 -116.354887) (xy 223.386128 -116.30147) (xy 223.373275 -116.245494) (xy 223.368955 -116.188224)
			(xy 213.37651 -116.188224) (xy 213.37651 -117.191028) (xy 213.616792 -117.191028) (xy 213.620863 -117.135406)
			(xy 213.632989 -117.080969) (xy 213.652912 -117.028878) (xy 213.680208 -116.980243) (xy 213.714294 -116.9361)
			(xy 213.754443 -116.897391) (xy 213.799801 -116.86494) (xy 213.849401 -116.839439) (xy 213.902185 -116.821432)
			(xy 213.957028 -116.811302) (xy 214.012762 -116.809265) (xy 214.068199 -116.815365) (xy 214.122156 -116.829471)
			(xy 214.173485 -116.851283) (xy 214.221091 -116.880337) (xy 214.263959 -116.916012) (xy 214.301176 -116.957549)
			(xy 214.331949 -117.004062) (xy 214.355621 -117.054559) (xy 214.371689 -117.107966) (xy 214.379809 -117.163142)
			(xy 214.380318 -117.191028) (xy 215.704164 -117.191028) (xy 215.708235 -117.135406) (xy 215.720361 -117.080969)
			(xy 215.740284 -117.028878) (xy 215.76758 -116.980243) (xy 215.801666 -116.9361) (xy 215.841815 -116.897391)
			(xy 215.887173 -116.86494) (xy 215.936773 -116.839439) (xy 215.989557 -116.821432) (xy 216.0444 -116.811302)
			(xy 216.100134 -116.809265) (xy 216.155571 -116.815365) (xy 216.209528 -116.829471) (xy 216.260857 -116.851283)
			(xy 216.308463 -116.880337) (xy 216.351331 -116.916012) (xy 216.388548 -116.957549) (xy 216.419321 -117.004062)
			(xy 216.442993 -117.054559) (xy 216.459061 -117.107966) (xy 216.467181 -117.163142) (xy 216.46769 -117.191028)
			(xy 216.467181 -117.218914) (xy 216.459061 -117.27409) (xy 216.452796 -117.294914) (xy 216.75852 -117.294914)
			(xy 216.75899 -117.2686) (xy 216.766224 -117.216471) (xy 216.780542 -117.165828) (xy 216.801674 -117.117629)
			(xy 216.82922 -117.072786) (xy 216.862658 -117.032146) (xy 216.88171 -117.01399) (xy 216.88912 -117.006475)
			(xy 216.897639 -116.98719) (xy 216.89822 -116.976652) (xy 216.89822 -116.901976) (xy 216.897658 -116.89143)
			(xy 216.889145 -116.872135) (xy 216.88171 -116.864638) (xy 216.862633 -116.846504) (xy 216.829178 -116.80587)
			(xy 216.801621 -116.761025) (xy 216.780486 -116.71282) (xy 216.766174 -116.662169) (xy 216.758955 -116.610031)
			(xy 216.75852 -116.583714) (xy 216.759006 -116.556463) (xy 216.766762 -116.502515) (xy 216.782117 -116.45022)
			(xy 216.804759 -116.400643) (xy 216.834225 -116.354793) (xy 216.869916 -116.313602) (xy 216.911107 -116.277911)
			(xy 216.956957 -116.248445) (xy 217.006534 -116.225803) (xy 217.058829 -116.210448) (xy 217.112777 -116.202692)
			(xy 217.167279 -116.202692) (xy 217.221227 -116.210448) (xy 217.273522 -116.225803) (xy 217.323099 -116.248445)
			(xy 217.368949 -116.277911) (xy 217.41014 -116.313602) (xy 217.445831 -116.354793) (xy 217.475297 -116.400643)
			(xy 217.497939 -116.45022) (xy 217.513294 -116.502515) (xy 217.52105 -116.556463) (xy 217.521536 -116.583714)
			(xy 217.521066 -116.610028) (xy 217.51383 -116.662156) (xy 217.499511 -116.712798) (xy 217.478379 -116.760997)
			(xy 217.450834 -116.80584) (xy 217.417397 -116.846481) (xy 217.398346 -116.864638) (xy 217.390933 -116.87215)
			(xy 217.382413 -116.891437) (xy 217.381836 -116.901976) (xy 217.381836 -116.976652) (xy 217.382367 -116.987202)
			(xy 217.3909 -117.006498) (xy 217.398346 -117.01399) (xy 217.417398 -117.032148) (xy 217.450854 -117.072779)
			(xy 217.478412 -117.117619) (xy 217.499551 -117.165819) (xy 217.513869 -117.216465) (xy 217.521096 -117.268598)
			(xy 217.521536 -117.294914) (xy 218.79052 -117.294914) (xy 218.79099 -117.2686) (xy 218.798224 -117.216471)
			(xy 218.812542 -117.165828) (xy 218.833674 -117.117629) (xy 218.86122 -117.072786) (xy 218.894658 -117.032146)
			(xy 218.91371 -117.01399) (xy 218.92112 -117.006475) (xy 218.929639 -116.98719) (xy 218.93022 -116.976652)
			(xy 218.93022 -116.901976) (xy 218.929658 -116.89143) (xy 218.921145 -116.872135) (xy 218.91371 -116.864638)
			(xy 218.894633 -116.846504) (xy 218.861178 -116.80587) (xy 218.833621 -116.761025) (xy 218.812486 -116.71282)
			(xy 218.798174 -116.662169) (xy 218.790955 -116.610031) (xy 218.79052 -116.583714) (xy 218.791006 -116.556463)
			(xy 218.798762 -116.502515) (xy 218.814117 -116.45022) (xy 218.836759 -116.400643) (xy 218.866225 -116.354793)
			(xy 218.901916 -116.313602) (xy 218.943107 -116.277911) (xy 218.988957 -116.248445) (xy 219.038534 -116.225803)
			(xy 219.090829 -116.210448) (xy 219.144777 -116.202692) (xy 219.199279 -116.202692) (xy 219.253227 -116.210448)
			(xy 219.305522 -116.225803) (xy 219.355099 -116.248445) (xy 219.400949 -116.277911) (xy 219.44214 -116.313602)
			(xy 219.477831 -116.354793) (xy 219.507297 -116.400643) (xy 219.529939 -116.45022) (xy 219.545294 -116.502515)
			(xy 219.55305 -116.556463) (xy 219.553536 -116.583714) (xy 219.553066 -116.610028) (xy 219.54583 -116.662156)
			(xy 219.531511 -116.712798) (xy 219.510379 -116.760997) (xy 219.482834 -116.80584) (xy 219.449397 -116.846481)
			(xy 219.430346 -116.864638) (xy 219.422933 -116.87215) (xy 219.414413 -116.891437) (xy 219.413836 -116.901976)
			(xy 219.413836 -116.976652) (xy 219.414367 -116.987202) (xy 219.4229 -117.006498) (xy 219.430346 -117.01399)
			(xy 219.449398 -117.032148) (xy 219.482854 -117.072779) (xy 219.510412 -117.117619) (xy 219.531551 -117.165819)
			(xy 219.545869 -117.216465) (xy 219.553096 -117.268598) (xy 219.553536 -117.294914) (xy 220.82252 -117.294914)
			(xy 220.82299 -117.2686) (xy 220.830224 -117.216471) (xy 220.844542 -117.165828) (xy 220.865674 -117.117629)
			(xy 220.89322 -117.072786) (xy 220.926658 -117.032146) (xy 220.94571 -117.01399) (xy 220.95312 -117.006475)
			(xy 220.961639 -116.98719) (xy 220.96222 -116.976652) (xy 220.96222 -116.901976) (xy 220.961658 -116.89143)
			(xy 220.953145 -116.872135) (xy 220.94571 -116.864638) (xy 220.926633 -116.846504) (xy 220.893178 -116.80587)
			(xy 220.865621 -116.761025) (xy 220.844486 -116.71282) (xy 220.830174 -116.662169) (xy 220.822955 -116.610031)
			(xy 220.82252 -116.583714) (xy 220.823006 -116.556463) (xy 220.830762 -116.502515) (xy 220.846117 -116.45022)
			(xy 220.868759 -116.400643) (xy 220.898225 -116.354793) (xy 220.933916 -116.313602) (xy 220.975107 -116.277911)
			(xy 221.020957 -116.248445) (xy 221.070534 -116.225803) (xy 221.122829 -116.210448) (xy 221.176777 -116.202692)
			(xy 221.231279 -116.202692) (xy 221.285227 -116.210448) (xy 221.337522 -116.225803) (xy 221.387099 -116.248445)
			(xy 221.432949 -116.277911) (xy 221.47414 -116.313602) (xy 221.509831 -116.354793) (xy 221.539297 -116.400643)
			(xy 221.561939 -116.45022) (xy 221.577294 -116.502515) (xy 221.58505 -116.556463) (xy 221.585536 -116.583714)
			(xy 221.585066 -116.610028) (xy 221.57783 -116.662156) (xy 221.563511 -116.712798) (xy 221.542379 -116.760997)
			(xy 221.514834 -116.80584) (xy 221.481397 -116.846481) (xy 221.462346 -116.864638) (xy 221.454933 -116.87215)
			(xy 221.446413 -116.891437) (xy 221.445836 -116.901976) (xy 221.445836 -116.976652) (xy 221.446367 -116.987202)
			(xy 221.4549 -117.006498) (xy 221.462346 -117.01399) (xy 221.481398 -117.032148) (xy 221.514854 -117.072779)
			(xy 221.542412 -117.117619) (xy 221.563551 -117.165819) (xy 221.577869 -117.216465) (xy 221.585096 -117.268598)
			(xy 221.585536 -117.294914) (xy 221.58505 -117.322165) (xy 221.577294 -117.376113) (xy 221.561939 -117.428408)
			(xy 221.539297 -117.477985) (xy 221.509831 -117.523835) (xy 221.47414 -117.565026) (xy 221.432949 -117.600717)
			(xy 221.387099 -117.630183) (xy 221.337522 -117.652825) (xy 221.285227 -117.66818) (xy 221.231279 -117.675936)
			(xy 221.176777 -117.675936) (xy 221.122829 -117.66818) (xy 221.070534 -117.652825) (xy 221.020957 -117.630183)
			(xy 220.975107 -117.600717) (xy 220.933916 -117.565026) (xy 220.898225 -117.523835) (xy 220.868759 -117.477985)
			(xy 220.846117 -117.428408) (xy 220.830762 -117.376113) (xy 220.823006 -117.322165) (xy 220.82252 -117.294914)
			(xy 219.553536 -117.294914) (xy 219.55305 -117.322165) (xy 219.545294 -117.376113) (xy 219.529939 -117.428408)
			(xy 219.507297 -117.477985) (xy 219.477831 -117.523835) (xy 219.44214 -117.565026) (xy 219.400949 -117.600717)
			(xy 219.355099 -117.630183) (xy 219.305522 -117.652825) (xy 219.253227 -117.66818) (xy 219.199279 -117.675936)
			(xy 219.144777 -117.675936) (xy 219.090829 -117.66818) (xy 219.038534 -117.652825) (xy 218.988957 -117.630183)
			(xy 218.943107 -117.600717) (xy 218.901916 -117.565026) (xy 218.866225 -117.523835) (xy 218.836759 -117.477985)
			(xy 218.814117 -117.428408) (xy 218.798762 -117.376113) (xy 218.791006 -117.322165) (xy 218.79052 -117.294914)
			(xy 217.521536 -117.294914) (xy 217.52105 -117.322165) (xy 217.513294 -117.376113) (xy 217.497939 -117.428408)
			(xy 217.475297 -117.477985) (xy 217.445831 -117.523835) (xy 217.41014 -117.565026) (xy 217.368949 -117.600717)
			(xy 217.323099 -117.630183) (xy 217.273522 -117.652825) (xy 217.221227 -117.66818) (xy 217.167279 -117.675936)
			(xy 217.112777 -117.675936) (xy 217.058829 -117.66818) (xy 217.006534 -117.652825) (xy 216.956957 -117.630183)
			(xy 216.911107 -117.600717) (xy 216.869916 -117.565026) (xy 216.834225 -117.523835) (xy 216.804759 -117.477985)
			(xy 216.782117 -117.428408) (xy 216.766762 -117.376113) (xy 216.759006 -117.322165) (xy 216.75852 -117.294914)
			(xy 216.452796 -117.294914) (xy 216.442993 -117.327497) (xy 216.419321 -117.377994) (xy 216.388548 -117.424507)
			(xy 216.351331 -117.466044) (xy 216.308463 -117.501719) (xy 216.260857 -117.530773) (xy 216.209528 -117.552585)
			(xy 216.155571 -117.566691) (xy 216.100134 -117.572791) (xy 216.0444 -117.570754) (xy 215.989557 -117.560624)
			(xy 215.936773 -117.542617) (xy 215.887173 -117.517116) (xy 215.841815 -117.484665) (xy 215.801666 -117.445956)
			(xy 215.76758 -117.401813) (xy 215.740284 -117.353178) (xy 215.720361 -117.301087) (xy 215.708235 -117.24665)
			(xy 215.704164 -117.191028) (xy 214.380318 -117.191028) (xy 214.379809 -117.218914) (xy 214.371689 -117.27409)
			(xy 214.355621 -117.327497) (xy 214.331949 -117.377994) (xy 214.301176 -117.424507) (xy 214.263959 -117.466044)
			(xy 214.221091 -117.501719) (xy 214.173485 -117.530773) (xy 214.122156 -117.552585) (xy 214.068199 -117.566691)
			(xy 214.012762 -117.572791) (xy 213.957028 -117.570754) (xy 213.902185 -117.560624) (xy 213.849401 -117.542617)
			(xy 213.799801 -117.517116) (xy 213.754443 -117.484665) (xy 213.714294 -117.445956) (xy 213.680208 -117.401813)
			(xy 213.652912 -117.353178) (xy 213.632989 -117.301087) (xy 213.620863 -117.24665) (xy 213.616792 -117.191028)
			(xy 213.37651 -117.191028) (xy 213.37651 -117.719348) (xy 236.702598 -117.719348) (xy 236.706669 -117.663726)
			(xy 236.718795 -117.609289) (xy 236.738718 -117.557198) (xy 236.766014 -117.508563) (xy 236.8001 -117.46442)
			(xy 236.840249 -117.425711) (xy 236.885607 -117.39326) (xy 236.935207 -117.367759) (xy 236.987991 -117.349752)
			(xy 237.042834 -117.339622) (xy 237.098568 -117.337585) (xy 237.154005 -117.343685) (xy 237.207962 -117.357791)
			(xy 237.259291 -117.379603) (xy 237.306897 -117.408657) (xy 237.349765 -117.444332) (xy 237.386982 -117.485869)
			(xy 237.417755 -117.532382) (xy 237.441427 -117.582879) (xy 237.457495 -117.636286) (xy 237.465615 -117.691462)
			(xy 237.466031 -117.714268) (xy 238.760252 -117.714268) (xy 238.764323 -117.658646) (xy 238.776449 -117.604209)
			(xy 238.796372 -117.552118) (xy 238.823668 -117.503483) (xy 238.857754 -117.45934) (xy 238.897903 -117.420631)
			(xy 238.943261 -117.38818) (xy 238.992861 -117.362679) (xy 239.045645 -117.344672) (xy 239.100488 -117.334542)
			(xy 239.156222 -117.332505) (xy 239.211659 -117.338605) (xy 239.265616 -117.352711) (xy 239.316945 -117.374523)
			(xy 239.364551 -117.403577) (xy 239.407419 -117.439252) (xy 239.444636 -117.480789) (xy 239.475409 -117.527302)
			(xy 239.499081 -117.577799) (xy 239.515149 -117.631206) (xy 239.523269 -117.686382) (xy 239.523778 -117.714268)
			(xy 239.523269 -117.742154) (xy 239.515149 -117.79733) (xy 239.499081 -117.850737) (xy 239.475409 -117.901234)
			(xy 239.444636 -117.947747) (xy 239.407419 -117.989284) (xy 239.364551 -118.024959) (xy 239.316945 -118.054013)
			(xy 239.274255 -118.072154) (xy 240.997992 -118.072154) (xy 241.002063 -118.016532) (xy 241.014189 -117.962095)
			(xy 241.034112 -117.910004) (xy 241.061408 -117.861369) (xy 241.095494 -117.817226) (xy 241.135643 -117.778517)
			(xy 241.181001 -117.746066) (xy 241.230601 -117.720565) (xy 241.283385 -117.702558) (xy 241.338228 -117.692428)
			(xy 241.393962 -117.690391) (xy 241.449399 -117.696491) (xy 241.503356 -117.710597) (xy 241.554685 -117.732409)
			(xy 241.602291 -117.761463) (xy 241.645159 -117.797138) (xy 241.682376 -117.838675) (xy 241.713149 -117.885188)
			(xy 241.736821 -117.935685) (xy 241.752889 -117.989092) (xy 241.761009 -118.044268) (xy 241.761518 -118.072154)
			(xy 241.761009 -118.10004) (xy 241.752889 -118.155216) (xy 241.736821 -118.208623) (xy 241.713149 -118.25912)
			(xy 241.682376 -118.305633) (xy 241.645159 -118.34717) (xy 241.602291 -118.382845) (xy 241.554685 -118.411899)
			(xy 241.503356 -118.433711) (xy 241.449399 -118.447817) (xy 241.393962 -118.453917) (xy 241.338228 -118.45188)
			(xy 241.283385 -118.44175) (xy 241.230601 -118.423743) (xy 241.181001 -118.398242) (xy 241.135643 -118.365791)
			(xy 241.095494 -118.327082) (xy 241.061408 -118.282939) (xy 241.034112 -118.234304) (xy 241.014189 -118.182213)
			(xy 241.002063 -118.127776) (xy 240.997992 -118.072154) (xy 239.274255 -118.072154) (xy 239.265616 -118.075825)
			(xy 239.211659 -118.089931) (xy 239.156222 -118.096031) (xy 239.100488 -118.093994) (xy 239.045645 -118.083864)
			(xy 238.992861 -118.065857) (xy 238.943261 -118.040356) (xy 238.897903 -118.007905) (xy 238.857754 -117.969196)
			(xy 238.823668 -117.925053) (xy 238.796372 -117.876418) (xy 238.776449 -117.824327) (xy 238.764323 -117.76989)
			(xy 238.760252 -117.714268) (xy 237.466031 -117.714268) (xy 237.466124 -117.719348) (xy 237.465615 -117.747234)
			(xy 237.457495 -117.80241) (xy 237.441427 -117.855817) (xy 237.417755 -117.906314) (xy 237.386982 -117.952827)
			(xy 237.349765 -117.994364) (xy 237.306897 -118.030039) (xy 237.259291 -118.059093) (xy 237.207962 -118.080905)
			(xy 237.154005 -118.095011) (xy 237.098568 -118.101111) (xy 237.042834 -118.099074) (xy 236.987991 -118.088944)
			(xy 236.935207 -118.070937) (xy 236.885607 -118.045436) (xy 236.840249 -118.012985) (xy 236.8001 -117.974276)
			(xy 236.766014 -117.930133) (xy 236.738718 -117.881498) (xy 236.718795 -117.829407) (xy 236.706669 -117.77497)
			(xy 236.702598 -117.719348) (xy 213.37651 -117.719348) (xy 213.37651 -118.207028) (xy 215.707974 -118.207028)
			(xy 215.712045 -118.151406) (xy 215.724171 -118.096969) (xy 215.744094 -118.044878) (xy 215.77139 -117.996243)
			(xy 215.805476 -117.9521) (xy 215.845625 -117.913391) (xy 215.890983 -117.88094) (xy 215.940583 -117.855439)
			(xy 215.993367 -117.837432) (xy 216.04821 -117.827302) (xy 216.103944 -117.825265) (xy 216.159381 -117.831365)
			(xy 216.213338 -117.845471) (xy 216.264667 -117.867283) (xy 216.312273 -117.896337) (xy 216.355141 -117.932012)
			(xy 216.392358 -117.973549) (xy 216.423131 -118.020062) (xy 216.446803 -118.070559) (xy 216.462871 -118.123966)
			(xy 216.470991 -118.179142) (xy 216.4715 -118.207028) (xy 216.470991 -118.234914) (xy 216.462871 -118.29009)
			(xy 216.446803 -118.343497) (xy 216.423131 -118.393994) (xy 216.392358 -118.440507) (xy 216.355141 -118.482044)
			(xy 216.312273 -118.517719) (xy 216.264667 -118.546773) (xy 216.213338 -118.568585) (xy 216.159381 -118.582691)
			(xy 216.103944 -118.588791) (xy 216.04821 -118.586754) (xy 215.993367 -118.576624) (xy 215.940583 -118.558617)
			(xy 215.890983 -118.533116) (xy 215.845625 -118.500665) (xy 215.805476 -118.461956) (xy 215.77139 -118.417813)
			(xy 215.744094 -118.369178) (xy 215.724171 -118.317087) (xy 215.712045 -118.26265) (xy 215.707974 -118.207028)
			(xy 213.37651 -118.207028) (xy 213.37651 -118.620286) (xy 213.718646 -118.620286) (xy 213.722717 -118.564664)
			(xy 213.734843 -118.510227) (xy 213.754766 -118.458136) (xy 213.782062 -118.409501) (xy 213.816148 -118.365358)
			(xy 213.856297 -118.326649) (xy 213.901655 -118.294198) (xy 213.951255 -118.268697) (xy 214.004039 -118.25069)
			(xy 214.058882 -118.24056) (xy 214.114616 -118.238523) (xy 214.170053 -118.244623) (xy 214.22401 -118.258729)
			(xy 214.275339 -118.280541) (xy 214.322945 -118.309595) (xy 214.365813 -118.34527) (xy 214.40303 -118.386807)
			(xy 214.433803 -118.43332) (xy 214.457475 -118.483817) (xy 214.473543 -118.537224) (xy 214.481663 -118.5924)
			(xy 214.482172 -118.620286) (xy 214.481663 -118.648172) (xy 214.473543 -118.703348) (xy 214.457475 -118.756755)
			(xy 214.433803 -118.807252) (xy 214.40303 -118.853765) (xy 214.365813 -118.895302) (xy 214.322945 -118.930977)
			(xy 214.275339 -118.960031) (xy 214.22401 -118.981843) (xy 214.170053 -118.995949) (xy 214.114616 -119.002049)
			(xy 214.058882 -119.000012) (xy 214.004039 -118.989882) (xy 213.951255 -118.971875) (xy 213.901655 -118.946374)
			(xy 213.856297 -118.913923) (xy 213.816148 -118.875214) (xy 213.782062 -118.831071) (xy 213.754766 -118.782436)
			(xy 213.734843 -118.730345) (xy 213.722717 -118.675908) (xy 213.718646 -118.620286) (xy 213.37651 -118.620286)
			(xy 213.37651 -119.223028) (xy 215.70391 -119.223028) (xy 215.707981 -119.167406) (xy 215.720107 -119.112969)
			(xy 215.74003 -119.060878) (xy 215.767326 -119.012243) (xy 215.801412 -118.9681) (xy 215.841561 -118.929391)
			(xy 215.886919 -118.89694) (xy 215.936519 -118.871439) (xy 215.989303 -118.853432) (xy 216.044146 -118.843302)
			(xy 216.09988 -118.841265) (xy 216.155317 -118.847365) (xy 216.209274 -118.861471) (xy 216.260603 -118.883283)
			(xy 216.308209 -118.912337) (xy 216.351077 -118.948012) (xy 216.388294 -118.989549) (xy 216.419067 -119.036062)
			(xy 216.436342 -119.072914) (xy 216.75852 -119.072914) (xy 216.75899 -119.0466) (xy 216.766224 -118.994471)
			(xy 216.780542 -118.943828) (xy 216.801674 -118.895629) (xy 216.82922 -118.850786) (xy 216.862658 -118.810146)
			(xy 216.88171 -118.79199) (xy 216.88912 -118.784475) (xy 216.897639 -118.76519) (xy 216.89822 -118.754652)
			(xy 216.89822 -118.679976) (xy 216.897658 -118.66943) (xy 216.889145 -118.650135) (xy 216.88171 -118.642638)
			(xy 216.862633 -118.624504) (xy 216.829178 -118.58387) (xy 216.801621 -118.539025) (xy 216.780486 -118.49082)
			(xy 216.766174 -118.440169) (xy 216.758955 -118.388031) (xy 216.75852 -118.361714) (xy 216.759006 -118.334463)
			(xy 216.766762 -118.280515) (xy 216.782117 -118.22822) (xy 216.804759 -118.178643) (xy 216.834225 -118.132793)
			(xy 216.869916 -118.091602) (xy 216.911107 -118.055911) (xy 216.956957 -118.026445) (xy 217.006534 -118.003803)
			(xy 217.058829 -117.988448) (xy 217.112777 -117.980692) (xy 217.167279 -117.980692) (xy 217.221227 -117.988448)
			(xy 217.273522 -118.003803) (xy 217.323099 -118.026445) (xy 217.368949 -118.055911) (xy 217.41014 -118.091602)
			(xy 217.445831 -118.132793) (xy 217.475297 -118.178643) (xy 217.497939 -118.22822) (xy 217.513294 -118.280515)
			(xy 217.52105 -118.334463) (xy 217.521536 -118.361714) (xy 217.521066 -118.388028) (xy 217.51383 -118.440156)
			(xy 217.499511 -118.490798) (xy 217.478379 -118.538997) (xy 217.450834 -118.58384) (xy 217.417397 -118.624481)
			(xy 217.398346 -118.642638) (xy 217.390933 -118.65015) (xy 217.382413 -118.669437) (xy 217.381836 -118.679976)
			(xy 217.381836 -118.754652) (xy 217.382367 -118.765202) (xy 217.3909 -118.784498) (xy 217.398346 -118.79199)
			(xy 217.417398 -118.810148) (xy 217.450854 -118.850779) (xy 217.478412 -118.895619) (xy 217.499551 -118.943819)
			(xy 217.513869 -118.994465) (xy 217.521096 -119.046598) (xy 217.521536 -119.072914) (xy 218.79052 -119.072914)
			(xy 218.79099 -119.0466) (xy 218.798224 -118.994471) (xy 218.812542 -118.943828) (xy 218.833674 -118.895629)
			(xy 218.86122 -118.850786) (xy 218.894658 -118.810146) (xy 218.91371 -118.79199) (xy 218.92112 -118.784475)
			(xy 218.929639 -118.76519) (xy 218.93022 -118.754652) (xy 218.93022 -118.679976) (xy 218.929658 -118.66943)
			(xy 218.921145 -118.650135) (xy 218.91371 -118.642638) (xy 218.894633 -118.624504) (xy 218.861178 -118.58387)
			(xy 218.833621 -118.539025) (xy 218.812486 -118.49082) (xy 218.798174 -118.440169) (xy 218.790955 -118.388031)
			(xy 218.79052 -118.361714) (xy 218.791006 -118.334463) (xy 218.798762 -118.280515) (xy 218.814117 -118.22822)
			(xy 218.836759 -118.178643) (xy 218.866225 -118.132793) (xy 218.901916 -118.091602) (xy 218.943107 -118.055911)
			(xy 218.988957 -118.026445) (xy 219.038534 -118.003803) (xy 219.090829 -117.988448) (xy 219.144777 -117.980692)
			(xy 219.199279 -117.980692) (xy 219.253227 -117.988448) (xy 219.305522 -118.003803) (xy 219.355099 -118.026445)
			(xy 219.400949 -118.055911) (xy 219.44214 -118.091602) (xy 219.477831 -118.132793) (xy 219.507297 -118.178643)
			(xy 219.529939 -118.22822) (xy 219.545294 -118.280515) (xy 219.55305 -118.334463) (xy 219.553536 -118.361714)
			(xy 219.553066 -118.388028) (xy 219.54583 -118.440156) (xy 219.531511 -118.490798) (xy 219.510379 -118.538997)
			(xy 219.482834 -118.58384) (xy 219.449397 -118.624481) (xy 219.430346 -118.642638) (xy 219.422933 -118.65015)
			(xy 219.414413 -118.669437) (xy 219.413836 -118.679976) (xy 219.413836 -118.754652) (xy 219.414367 -118.765202)
			(xy 219.4229 -118.784498) (xy 219.430346 -118.79199) (xy 219.449398 -118.810148) (xy 219.482854 -118.850779)
			(xy 219.510412 -118.895619) (xy 219.531551 -118.943819) (xy 219.545869 -118.994465) (xy 219.553096 -119.046598)
			(xy 219.553536 -119.072914) (xy 220.82252 -119.072914) (xy 220.82299 -119.0466) (xy 220.830224 -118.994471)
			(xy 220.844542 -118.943828) (xy 220.865674 -118.895629) (xy 220.89322 -118.850786) (xy 220.926658 -118.810146)
			(xy 220.94571 -118.79199) (xy 220.95312 -118.784475) (xy 220.961639 -118.76519) (xy 220.96222 -118.754652)
			(xy 220.96222 -118.679976) (xy 220.961658 -118.66943) (xy 220.953145 -118.650135) (xy 220.94571 -118.642638)
			(xy 220.926633 -118.624504) (xy 220.893178 -118.58387) (xy 220.865621 -118.539025) (xy 220.844486 -118.49082)
			(xy 220.830174 -118.440169) (xy 220.822955 -118.388031) (xy 220.82252 -118.361714) (xy 220.823006 -118.334463)
			(xy 220.830762 -118.280515) (xy 220.846117 -118.22822) (xy 220.868759 -118.178643) (xy 220.898225 -118.132793)
			(xy 220.933916 -118.091602) (xy 220.975107 -118.055911) (xy 221.020957 -118.026445) (xy 221.070534 -118.003803)
			(xy 221.122829 -117.988448) (xy 221.176777 -117.980692) (xy 221.231279 -117.980692) (xy 221.285227 -117.988448)
			(xy 221.337522 -118.003803) (xy 221.387099 -118.026445) (xy 221.432949 -118.055911) (xy 221.47414 -118.091602)
			(xy 221.509831 -118.132793) (xy 221.539297 -118.178643) (xy 221.561939 -118.22822) (xy 221.577294 -118.280515)
			(xy 221.58505 -118.334463) (xy 221.585536 -118.361714) (xy 221.585066 -118.388028) (xy 221.57783 -118.440156)
			(xy 221.563511 -118.490798) (xy 221.542379 -118.538997) (xy 221.514834 -118.58384) (xy 221.481397 -118.624481)
			(xy 221.462346 -118.642638) (xy 221.454933 -118.65015) (xy 221.446413 -118.669437) (xy 221.445836 -118.679976)
			(xy 221.445836 -118.754652) (xy 221.446367 -118.765202) (xy 221.4549 -118.784498) (xy 221.462346 -118.79199)
			(xy 221.481398 -118.810148) (xy 221.514854 -118.850779) (xy 221.542412 -118.895619) (xy 221.563551 -118.943819)
			(xy 221.577869 -118.994465) (xy 221.585096 -119.046598) (xy 221.585536 -119.072914) (xy 221.58505 -119.100165)
			(xy 221.577294 -119.154113) (xy 221.571978 -119.172219) (xy 223.36895 -119.172219) (xy 223.373263 -119.114948)
			(xy 223.38611 -119.05897) (xy 223.407201 -119.00555) (xy 223.43606 -118.955893) (xy 223.472034 -118.911123)
			(xy 223.492822 -118.891304) (xy 223.500227 -118.883786) (xy 223.508749 -118.864503) (xy 223.509332 -118.853966)
			(xy 223.509332 -118.77929) (xy 223.508812 -118.768739) (xy 223.500269 -118.749445) (xy 223.492822 -118.741952)
			(xy 223.473754 -118.723808) (xy 223.440297 -118.683177) (xy 223.41274 -118.638334) (xy 223.391603 -118.590131)
			(xy 223.377289 -118.539481) (xy 223.370068 -118.487345) (xy 223.369632 -118.461028) (xy 223.370118 -118.433777)
			(xy 223.377874 -118.379829) (xy 223.393229 -118.327534) (xy 223.415871 -118.277957) (xy 223.445337 -118.232107)
			(xy 223.481028 -118.190916) (xy 223.522219 -118.155225) (xy 223.568069 -118.125759) (xy 223.617646 -118.103117)
			(xy 223.669941 -118.087762) (xy 223.723889 -118.080006) (xy 223.778391 -118.080006) (xy 223.832339 -118.087762)
			(xy 223.884634 -118.103117) (xy 223.934211 -118.125759) (xy 223.980061 -118.155225) (xy 224.021252 -118.190916)
			(xy 224.056943 -118.232107) (xy 224.086409 -118.277957) (xy 224.109051 -118.327534) (xy 224.124406 -118.379829)
			(xy 224.132162 -118.433777) (xy 224.132648 -118.461028) (xy 224.132216 -118.487343) (xy 224.124976 -118.539474)
			(xy 224.110651 -118.590118) (xy 224.089512 -118.638317) (xy 224.061959 -118.68316) (xy 224.028513 -118.723797)
			(xy 224.009458 -118.741952) (xy 224.00204 -118.74946) (xy 223.993523 -118.76875) (xy 223.992948 -118.77929)
			(xy 223.992948 -118.853966) (xy 223.993468 -118.864517) (xy 224.002008 -118.883813) (xy 224.009458 -118.891304)
			(xy 224.030272 -118.911097) (xy 224.066243 -118.955875) (xy 224.095099 -119.005537) (xy 224.116188 -119.058962)
			(xy 224.129033 -119.114944) (xy 224.133346 -119.172219) (xy 225.907197 -119.172219) (xy 225.911509 -119.11495)
			(xy 225.924353 -119.058974) (xy 225.94544 -119.005555) (xy 225.974293 -118.955898) (xy 226.01026 -118.911125)
			(xy 226.031044 -118.891304) (xy 226.038438 -118.883775) (xy 226.046968 -118.864501) (xy 226.047554 -118.853966)
			(xy 226.047554 -118.77929) (xy 226.047057 -118.768736) (xy 226.038501 -118.74944) (xy 226.031044 -118.741952)
			(xy 226.011962 -118.723824) (xy 225.978509 -118.683187) (xy 225.950955 -118.638341) (xy 225.929821 -118.590135)
			(xy 225.915509 -118.539483) (xy 225.90829 -118.487346) (xy 225.907854 -118.461028) (xy 225.90834 -118.433777)
			(xy 225.916096 -118.379829) (xy 225.931451 -118.327534) (xy 225.954093 -118.277957) (xy 225.983559 -118.232107)
			(xy 226.01925 -118.190916) (xy 226.060441 -118.155225) (xy 226.106291 -118.125759) (xy 226.155868 -118.103117)
			(xy 226.208163 -118.087762) (xy 226.262111 -118.080006) (xy 226.316613 -118.080006) (xy 226.370561 -118.087762)
			(xy 226.422856 -118.103117) (xy 226.472433 -118.125759) (xy 226.518283 -118.155225) (xy 226.545823 -118.179088)
			(xy 230.817926 -118.179088) (xy 230.821997 -118.123466) (xy 230.834123 -118.069029) (xy 230.854046 -118.016938)
			(xy 230.881342 -117.968303) (xy 230.915428 -117.92416) (xy 230.955577 -117.885451) (xy 231.000935 -117.853)
			(xy 231.050535 -117.827499) (xy 231.103319 -117.809492) (xy 231.158162 -117.799362) (xy 231.213896 -117.797325)
			(xy 231.269333 -117.803425) (xy 231.32329 -117.817531) (xy 231.374619 -117.839343) (xy 231.422225 -117.868397)
			(xy 231.465093 -117.904072) (xy 231.50231 -117.945609) (xy 231.533083 -117.992122) (xy 231.556755 -118.042619)
			(xy 231.572823 -118.096026) (xy 231.580943 -118.151202) (xy 231.581452 -118.179088) (xy 231.580943 -118.206974)
			(xy 231.572823 -118.26215) (xy 231.556755 -118.315557) (xy 231.533083 -118.366054) (xy 231.50231 -118.412567)
			(xy 231.465093 -118.454104) (xy 231.422225 -118.489779) (xy 231.374619 -118.518833) (xy 231.32329 -118.540645)
			(xy 231.269333 -118.554751) (xy 231.213896 -118.560851) (xy 231.158162 -118.558814) (xy 231.103319 -118.548684)
			(xy 231.050535 -118.530677) (xy 231.000935 -118.505176) (xy 230.955577 -118.472725) (xy 230.915428 -118.434016)
			(xy 230.881342 -118.389873) (xy 230.854046 -118.341238) (xy 230.834123 -118.289147) (xy 230.821997 -118.23471)
			(xy 230.817926 -118.179088) (xy 226.545823 -118.179088) (xy 226.559474 -118.190916) (xy 226.595165 -118.232107)
			(xy 226.624631 -118.277957) (xy 226.647273 -118.327534) (xy 226.662628 -118.379829) (xy 226.670384 -118.433777)
			(xy 226.67087 -118.461028) (xy 226.670431 -118.487343) (xy 226.663192 -118.539473) (xy 226.648868 -118.590117)
			(xy 226.62773 -118.638316) (xy 226.600178 -118.683159) (xy 226.566734 -118.723797) (xy 226.54768 -118.741952)
			(xy 226.54025 -118.74945) (xy 226.531743 -118.768748) (xy 226.53117 -118.77929) (xy 226.53117 -118.853966)
			(xy 226.531713 -118.864514) (xy 226.54024 -118.883809) (xy 226.54768 -118.891304) (xy 226.568498 -118.911095)
			(xy 226.604476 -118.95587) (xy 226.633338 -119.005532) (xy 226.654431 -119.058958) (xy 226.66728 -119.114942)
			(xy 226.67079 -119.16156) (xy 232.432604 -119.16156) (xy 232.436675 -119.105938) (xy 232.448801 -119.051501)
			(xy 232.468724 -118.99941) (xy 232.49602 -118.950775) (xy 232.530106 -118.906632) (xy 232.570255 -118.867923)
			(xy 232.615613 -118.835472) (xy 232.665213 -118.809971) (xy 232.717997 -118.791964) (xy 232.77284 -118.781834)
			(xy 232.828574 -118.779797) (xy 232.884011 -118.785897) (xy 232.937968 -118.800003) (xy 232.989297 -118.821815)
			(xy 233.036903 -118.850869) (xy 233.079771 -118.886544) (xy 233.116988 -118.928081) (xy 233.147761 -118.974594)
			(xy 233.171433 -119.025091) (xy 233.187501 -119.078498) (xy 233.195621 -119.133674) (xy 233.19613 -119.16156)
			(xy 233.195621 -119.189446) (xy 233.192697 -119.209312) (xy 233.799124 -119.209312) (xy 233.803195 -119.15369)
			(xy 233.815321 -119.099253) (xy 233.835244 -119.047162) (xy 233.86254 -118.998527) (xy 233.896626 -118.954384)
			(xy 233.936775 -118.915675) (xy 233.982133 -118.883224) (xy 234.031733 -118.857723) (xy 234.084517 -118.839716)
			(xy 234.13936 -118.829586) (xy 234.195094 -118.827549) (xy 234.250531 -118.833649) (xy 234.304488 -118.847755)
			(xy 234.355817 -118.869567) (xy 234.403423 -118.898621) (xy 234.446291 -118.934296) (xy 234.483508 -118.975833)
			(xy 234.514281 -119.022346) (xy 234.537953 -119.072843) (xy 234.554021 -119.12625) (xy 234.55619 -119.140986)
			(xy 235.177836 -119.140986) (xy 235.181907 -119.085364) (xy 235.194033 -119.030927) (xy 235.213956 -118.978836)
			(xy 235.241252 -118.930201) (xy 235.275338 -118.886058) (xy 235.315487 -118.847349) (xy 235.360845 -118.814898)
			(xy 235.410445 -118.789397) (xy 235.463229 -118.77139) (xy 235.518072 -118.76126) (xy 235.573806 -118.759223)
			(xy 235.629243 -118.765323) (xy 235.6832 -118.779429) (xy 235.734529 -118.801241) (xy 235.782135 -118.830295)
			(xy 235.825003 -118.86597) (xy 235.86222 -118.907507) (xy 235.892993 -118.95402) (xy 235.916665 -119.004517)
			(xy 235.932733 -119.057924) (xy 235.940583 -119.111268) (xy 236.70463 -119.111268) (xy 236.708701 -119.055646)
			(xy 236.720827 -119.001209) (xy 236.74075 -118.949118) (xy 236.768046 -118.900483) (xy 236.802132 -118.85634)
			(xy 236.842281 -118.817631) (xy 236.887639 -118.78518) (xy 236.937239 -118.759679) (xy 236.990023 -118.741672)
			(xy 237.044866 -118.731542) (xy 237.1006 -118.729505) (xy 237.156037 -118.735605) (xy 237.209994 -118.749711)
			(xy 237.261323 -118.771523) (xy 237.308929 -118.800577) (xy 237.351797 -118.836252) (xy 237.389014 -118.877789)
			(xy 237.419787 -118.924302) (xy 237.443459 -118.974799) (xy 237.459527 -119.028206) (xy 237.467647 -119.083382)
			(xy 237.468156 -119.111268) (xy 237.467647 -119.139154) (xy 237.459527 -119.19433) (xy 237.443459 -119.247737)
			(xy 237.419787 -119.298234) (xy 237.389014 -119.344747) (xy 237.351797 -119.386284) (xy 237.308929 -119.421959)
			(xy 237.261323 -119.451013) (xy 237.209994 -119.472825) (xy 237.156037 -119.486931) (xy 237.1006 -119.493031)
			(xy 237.044866 -119.490994) (xy 236.990023 -119.480864) (xy 236.937239 -119.462857) (xy 236.887639 -119.437356)
			(xy 236.842281 -119.404905) (xy 236.802132 -119.366196) (xy 236.768046 -119.322053) (xy 236.74075 -119.273418)
			(xy 236.720827 -119.221327) (xy 236.708701 -119.16689) (xy 236.70463 -119.111268) (xy 235.940583 -119.111268)
			(xy 235.940853 -119.1131) (xy 235.941362 -119.140986) (xy 235.940853 -119.168872) (xy 235.932733 -119.224048)
			(xy 235.916665 -119.277455) (xy 235.892993 -119.327952) (xy 235.86222 -119.374465) (xy 235.825003 -119.416002)
			(xy 235.782135 -119.451677) (xy 235.734529 -119.480731) (xy 235.6832 -119.502543) (xy 235.629243 -119.516649)
			(xy 235.573806 -119.522749) (xy 235.518072 -119.520712) (xy 235.463229 -119.510582) (xy 235.410445 -119.492575)
			(xy 235.360845 -119.467074) (xy 235.315487 -119.434623) (xy 235.275338 -119.395914) (xy 235.241252 -119.351771)
			(xy 235.213956 -119.303136) (xy 235.194033 -119.251045) (xy 235.181907 -119.196608) (xy 235.177836 -119.140986)
			(xy 234.55619 -119.140986) (xy 234.562141 -119.181426) (xy 234.56265 -119.209312) (xy 234.562141 -119.237198)
			(xy 234.554021 -119.292374) (xy 234.537953 -119.345781) (xy 234.514281 -119.396278) (xy 234.483508 -119.442791)
			(xy 234.446291 -119.484328) (xy 234.403423 -119.520003) (xy 234.355817 -119.549057) (xy 234.304488 -119.570869)
			(xy 234.250531 -119.584975) (xy 234.195094 -119.591075) (xy 234.13936 -119.589038) (xy 234.084517 -119.578908)
			(xy 234.031733 -119.560901) (xy 233.982133 -119.5354) (xy 233.936775 -119.502949) (xy 233.896626 -119.46424)
			(xy 233.86254 -119.420097) (xy 233.835244 -119.371462) (xy 233.815321 -119.319371) (xy 233.803195 -119.264934)
			(xy 233.799124 -119.209312) (xy 233.192697 -119.209312) (xy 233.187501 -119.244622) (xy 233.171433 -119.298029)
			(xy 233.147761 -119.348526) (xy 233.116988 -119.395039) (xy 233.079771 -119.436576) (xy 233.036903 -119.472251)
			(xy 232.989297 -119.501305) (xy 232.937968 -119.523117) (xy 232.884011 -119.537223) (xy 232.828574 -119.543323)
			(xy 232.77284 -119.541286) (xy 232.717997 -119.531156) (xy 232.665213 -119.513149) (xy 232.615613 -119.487648)
			(xy 232.570255 -119.455197) (xy 232.530106 -119.416488) (xy 232.49602 -119.372345) (xy 232.468724 -119.32371)
			(xy 232.448801 -119.271619) (xy 232.436675 -119.217182) (xy 232.432604 -119.16156) (xy 226.67079 -119.16156)
			(xy 226.671593 -119.172219) (xy 226.667274 -119.229496) (xy 226.65442 -119.285478) (xy 226.633321 -119.338902)
			(xy 226.604454 -119.388561) (xy 226.568472 -119.433333) (xy 226.54768 -119.453152) (xy 226.54025 -119.46065)
			(xy 226.531743 -119.479948) (xy 226.53117 -119.49049) (xy 226.53117 -119.565166) (xy 226.531713 -119.575714)
			(xy 226.54024 -119.595009) (xy 226.54768 -119.602504) (xy 226.566727 -119.620669) (xy 226.600185 -119.661296)
			(xy 226.627746 -119.706134) (xy 226.638442 -119.73052) (xy 230.955848 -119.73052) (xy 230.959919 -119.674898)
			(xy 230.972045 -119.620461) (xy 230.991968 -119.56837) (xy 231.019264 -119.519735) (xy 231.05335 -119.475592)
			(xy 231.093499 -119.436883) (xy 231.138857 -119.404432) (xy 231.188457 -119.378931) (xy 231.241241 -119.360924)
			(xy 231.296084 -119.350794) (xy 231.351818 -119.348757) (xy 231.407255 -119.354857) (xy 231.461212 -119.368963)
			(xy 231.512541 -119.390775) (xy 231.560147 -119.419829) (xy 231.603015 -119.455504) (xy 231.640232 -119.497041)
			(xy 231.671005 -119.543554) (xy 231.694677 -119.594051) (xy 231.710745 -119.647458) (xy 231.718865 -119.702634)
			(xy 231.719374 -119.73052) (xy 231.718865 -119.758406) (xy 231.710745 -119.813582) (xy 231.694677 -119.866989)
			(xy 231.671005 -119.917486) (xy 231.640232 -119.963999) (xy 231.603015 -120.005536) (xy 231.560147 -120.041211)
			(xy 231.512541 -120.070265) (xy 231.461212 -120.092077) (xy 231.407255 -120.106183) (xy 231.351818 -120.112283)
			(xy 231.296084 -120.110246) (xy 231.241241 -120.100116) (xy 231.188457 -120.082109) (xy 231.138857 -120.056608)
			(xy 231.093499 -120.024157) (xy 231.05335 -119.985448) (xy 231.019264 -119.941305) (xy 230.991968 -119.89267)
			(xy 230.972045 -119.840579) (xy 230.959919 -119.786142) (xy 230.955848 -119.73052) (xy 226.638442 -119.73052)
			(xy 226.648886 -119.754333) (xy 226.663205 -119.804979) (xy 226.670431 -119.857112) (xy 226.67087 -119.883428)
			(xy 226.670384 -119.910679) (xy 226.662628 -119.964627) (xy 226.647273 -120.016922) (xy 226.624631 -120.066499)
			(xy 226.595165 -120.112349) (xy 226.559474 -120.15354) (xy 226.518283 -120.189231) (xy 226.472433 -120.218697)
			(xy 226.422856 -120.241339) (xy 226.370561 -120.256694) (xy 226.316613 -120.26445) (xy 226.262111 -120.26445)
			(xy 226.208163 -120.256694) (xy 226.155868 -120.241339) (xy 226.106291 -120.218697) (xy 226.060441 -120.189231)
			(xy 226.01925 -120.15354) (xy 225.983559 -120.112349) (xy 225.954093 -120.066499) (xy 225.931451 -120.016922)
			(xy 225.916096 -119.964627) (xy 225.90834 -119.910679) (xy 225.907854 -119.883428) (xy 225.908256 -119.857112)
			(xy 225.915502 -119.80498) (xy 225.929833 -119.754335) (xy 225.950977 -119.706136) (xy 225.978536 -119.661294)
			(xy 226.011987 -119.620658) (xy 226.031044 -119.602504) (xy 226.038438 -119.594975) (xy 226.046968 -119.575701)
			(xy 226.047554 -119.565166) (xy 226.047554 -119.49049) (xy 226.047057 -119.479936) (xy 226.038501 -119.46064)
			(xy 226.031044 -119.453152) (xy 226.010286 -119.433303) (xy 225.974314 -119.388533) (xy 225.945456 -119.338879)
			(xy 225.924364 -119.285462) (xy 225.911514 -119.229487) (xy 225.907197 -119.172219) (xy 224.133346 -119.172219)
			(xy 224.129028 -119.229493) (xy 224.116176 -119.285474) (xy 224.095082 -119.338897) (xy 224.066222 -119.388557)
			(xy 224.030246 -119.433331) (xy 224.009458 -119.453152) (xy 224.00204 -119.46066) (xy 223.993523 -119.47995)
			(xy 223.992948 -119.49049) (xy 223.992948 -119.565166) (xy 223.993468 -119.575717) (xy 224.002008 -119.595013)
			(xy 224.009458 -119.602504) (xy 224.02852 -119.620653) (xy 224.061974 -119.661286) (xy 224.089531 -119.706128)
			(xy 224.110668 -119.754329) (xy 224.124984 -119.804977) (xy 224.132209 -119.857112) (xy 224.132648 -119.883428)
			(xy 224.132162 -119.910679) (xy 224.124406 -119.964627) (xy 224.109051 -120.016922) (xy 224.086409 -120.066499)
			(xy 224.056943 -120.112349) (xy 224.021252 -120.15354) (xy 223.980061 -120.189231) (xy 223.934211 -120.218697)
			(xy 223.884634 -120.241339) (xy 223.832339 -120.256694) (xy 223.778391 -120.26445) (xy 223.723889 -120.26445)
			(xy 223.669941 -120.256694) (xy 223.617646 -120.241339) (xy 223.568069 -120.218697) (xy 223.522219 -120.189231)
			(xy 223.481028 -120.15354) (xy 223.445337 -120.112349) (xy 223.415871 -120.066499) (xy 223.393229 -120.016922)
			(xy 223.377874 -119.964627) (xy 223.370118 -119.910679) (xy 223.369632 -119.883428) (xy 223.370041 -119.857112)
			(xy 223.377287 -119.80498) (xy 223.391616 -119.754336) (xy 223.41276 -119.706137) (xy 223.440316 -119.661295)
			(xy 223.473765 -119.620659) (xy 223.492822 -119.602504) (xy 223.500227 -119.594986) (xy 223.508749 -119.575703)
			(xy 223.509332 -119.565166) (xy 223.509332 -119.49049) (xy 223.508812 -119.479939) (xy 223.500269 -119.460645)
			(xy 223.492822 -119.453152) (xy 223.47206 -119.433305) (xy 223.436081 -119.388538) (xy 223.407217 -119.338885)
			(xy 223.386121 -119.285466) (xy 223.373268 -119.22949) (xy 223.36895 -119.172219) (xy 221.571978 -119.172219)
			(xy 221.561939 -119.206408) (xy 221.539297 -119.255985) (xy 221.509831 -119.301835) (xy 221.47414 -119.343026)
			(xy 221.432949 -119.378717) (xy 221.387099 -119.408183) (xy 221.337522 -119.430825) (xy 221.285227 -119.44618)
			(xy 221.231279 -119.453936) (xy 221.176777 -119.453936) (xy 221.122829 -119.44618) (xy 221.070534 -119.430825)
			(xy 221.020957 -119.408183) (xy 220.975107 -119.378717) (xy 220.933916 -119.343026) (xy 220.898225 -119.301835)
			(xy 220.868759 -119.255985) (xy 220.846117 -119.206408) (xy 220.830762 -119.154113) (xy 220.823006 -119.100165)
			(xy 220.82252 -119.072914) (xy 219.553536 -119.072914) (xy 219.55305 -119.100165) (xy 219.545294 -119.154113)
			(xy 219.529939 -119.206408) (xy 219.507297 -119.255985) (xy 219.477831 -119.301835) (xy 219.44214 -119.343026)
			(xy 219.400949 -119.378717) (xy 219.355099 -119.408183) (xy 219.305522 -119.430825) (xy 219.253227 -119.44618)
			(xy 219.199279 -119.453936) (xy 219.144777 -119.453936) (xy 219.090829 -119.44618) (xy 219.038534 -119.430825)
			(xy 218.988957 -119.408183) (xy 218.943107 -119.378717) (xy 218.901916 -119.343026) (xy 218.866225 -119.301835)
			(xy 218.836759 -119.255985) (xy 218.814117 -119.206408) (xy 218.798762 -119.154113) (xy 218.791006 -119.100165)
			(xy 218.79052 -119.072914) (xy 217.521536 -119.072914) (xy 217.52105 -119.100165) (xy 217.513294 -119.154113)
			(xy 217.497939 -119.206408) (xy 217.475297 -119.255985) (xy 217.445831 -119.301835) (xy 217.41014 -119.343026)
			(xy 217.368949 -119.378717) (xy 217.323099 -119.408183) (xy 217.273522 -119.430825) (xy 217.221227 -119.44618)
			(xy 217.167279 -119.453936) (xy 217.112777 -119.453936) (xy 217.058829 -119.44618) (xy 217.006534 -119.430825)
			(xy 216.956957 -119.408183) (xy 216.911107 -119.378717) (xy 216.869916 -119.343026) (xy 216.834225 -119.301835)
			(xy 216.804759 -119.255985) (xy 216.782117 -119.206408) (xy 216.766762 -119.154113) (xy 216.759006 -119.100165)
			(xy 216.75852 -119.072914) (xy 216.436342 -119.072914) (xy 216.442739 -119.086559) (xy 216.458807 -119.139966)
			(xy 216.466927 -119.195142) (xy 216.467436 -119.223028) (xy 216.466927 -119.250914) (xy 216.458807 -119.30609)
			(xy 216.442739 -119.359497) (xy 216.419067 -119.409994) (xy 216.388294 -119.456507) (xy 216.351077 -119.498044)
			(xy 216.308209 -119.533719) (xy 216.260603 -119.562773) (xy 216.209274 -119.584585) (xy 216.155317 -119.598691)
			(xy 216.09988 -119.604791) (xy 216.044146 -119.602754) (xy 215.989303 -119.592624) (xy 215.936519 -119.574617)
			(xy 215.886919 -119.549116) (xy 215.841561 -119.516665) (xy 215.801412 -119.477956) (xy 215.767326 -119.433813)
			(xy 215.74003 -119.385178) (xy 215.720107 -119.333087) (xy 215.707981 -119.27865) (xy 215.70391 -119.223028)
			(xy 213.37651 -119.223028) (xy 213.37651 -120.161304) (xy 213.683848 -120.161304) (xy 213.687919 -120.105682)
			(xy 213.700045 -120.051245) (xy 213.719968 -119.999154) (xy 213.747264 -119.950519) (xy 213.78135 -119.906376)
			(xy 213.821499 -119.867667) (xy 213.866857 -119.835216) (xy 213.916457 -119.809715) (xy 213.969241 -119.791708)
			(xy 214.024084 -119.781578) (xy 214.079818 -119.779541) (xy 214.135255 -119.785641) (xy 214.189212 -119.799747)
			(xy 214.240541 -119.821559) (xy 214.288147 -119.850613) (xy 214.331015 -119.886288) (xy 214.368232 -119.927825)
			(xy 214.399005 -119.974338) (xy 214.422677 -120.024835) (xy 214.438745 -120.078242) (xy 214.446865 -120.133418)
			(xy 214.447374 -120.161304) (xy 214.446865 -120.18919) (xy 214.439531 -120.239028) (xy 215.72931 -120.239028)
			(xy 215.733381 -120.183406) (xy 215.745507 -120.128969) (xy 215.76543 -120.076878) (xy 215.792726 -120.028243)
			(xy 215.826812 -119.9841) (xy 215.866961 -119.945391) (xy 215.912319 -119.91294) (xy 215.961919 -119.887439)
			(xy 216.014703 -119.869432) (xy 216.069546 -119.859302) (xy 216.12528 -119.857265) (xy 216.180717 -119.863365)
			(xy 216.234674 -119.877471) (xy 216.286003 -119.899283) (xy 216.333609 -119.928337) (xy 216.376477 -119.964012)
			(xy 216.413694 -120.005549) (xy 216.444467 -120.052062) (xy 216.468139 -120.102559) (xy 216.484207 -120.155966)
			(xy 216.492327 -120.211142) (xy 216.492836 -120.239028) (xy 216.492327 -120.266914) (xy 216.484207 -120.32209)
			(xy 216.468139 -120.375497) (xy 216.444467 -120.425994) (xy 216.413694 -120.472507) (xy 216.376477 -120.514044)
			(xy 216.333609 -120.549719) (xy 216.286003 -120.578773) (xy 216.234674 -120.600585) (xy 216.180717 -120.614691)
			(xy 216.12528 -120.620791) (xy 216.069546 -120.618754) (xy 216.014703 -120.608624) (xy 215.961919 -120.590617)
			(xy 215.912319 -120.565116) (xy 215.866961 -120.532665) (xy 215.826812 -120.493956) (xy 215.792726 -120.449813)
			(xy 215.76543 -120.401178) (xy 215.745507 -120.349087) (xy 215.733381 -120.29465) (xy 215.72931 -120.239028)
			(xy 214.439531 -120.239028) (xy 214.438745 -120.244366) (xy 214.422677 -120.297773) (xy 214.399005 -120.34827)
			(xy 214.368232 -120.394783) (xy 214.331015 -120.43632) (xy 214.288147 -120.471995) (xy 214.240541 -120.501049)
			(xy 214.189212 -120.522861) (xy 214.135255 -120.536967) (xy 214.079818 -120.543067) (xy 214.024084 -120.54103)
			(xy 213.969241 -120.5309) (xy 213.916457 -120.512893) (xy 213.866857 -120.487392) (xy 213.821499 -120.454941)
			(xy 213.78135 -120.416232) (xy 213.747264 -120.372089) (xy 213.719968 -120.323454) (xy 213.700045 -120.271363)
			(xy 213.687919 -120.216926) (xy 213.683848 -120.161304) (xy 213.37651 -120.161304) (xy 213.37651 -120.779794)
			(xy 230.950768 -120.779794) (xy 230.954839 -120.724172) (xy 230.966965 -120.669735) (xy 230.986888 -120.617644)
			(xy 231.014184 -120.569009) (xy 231.04827 -120.524866) (xy 231.088419 -120.486157) (xy 231.133777 -120.453706)
			(xy 231.183377 -120.428205) (xy 231.236161 -120.410198) (xy 231.291004 -120.400068) (xy 231.346738 -120.398031)
			(xy 231.402175 -120.404131) (xy 231.456132 -120.418237) (xy 231.507461 -120.440049) (xy 231.555067 -120.469103)
			(xy 231.597935 -120.504778) (xy 231.635152 -120.546315) (xy 231.665925 -120.592828) (xy 231.689597 -120.643325)
			(xy 231.705665 -120.696732) (xy 231.713785 -120.751908) (xy 231.714294 -120.779794) (xy 231.713785 -120.80768)
			(xy 231.705665 -120.862856) (xy 231.689597 -120.916263) (xy 231.665925 -120.96676) (xy 231.635152 -121.013273)
			(xy 231.597935 -121.05481) (xy 231.555067 -121.090485) (xy 231.507461 -121.119539) (xy 231.456132 -121.141351)
			(xy 231.402175 -121.155457) (xy 231.346738 -121.161557) (xy 231.291004 -121.15952) (xy 231.236161 -121.14939)
			(xy 231.183377 -121.131383) (xy 231.133777 -121.105882) (xy 231.088419 -121.073431) (xy 231.04827 -121.034722)
			(xy 231.014184 -120.990579) (xy 230.986888 -120.941944) (xy 230.966965 -120.889853) (xy 230.954839 -120.835416)
			(xy 230.950768 -120.779794) (xy 213.37651 -120.779794) (xy 213.37651 -121.255028) (xy 215.705434 -121.255028)
			(xy 215.709505 -121.199406) (xy 215.721631 -121.144969) (xy 215.741554 -121.092878) (xy 215.76885 -121.044243)
			(xy 215.802936 -121.0001) (xy 215.843085 -120.961391) (xy 215.888443 -120.92894) (xy 215.938043 -120.903439)
			(xy 215.990827 -120.885432) (xy 216.04567 -120.875302) (xy 216.101404 -120.873265) (xy 216.156841 -120.879365)
			(xy 216.210798 -120.893471) (xy 216.262127 -120.915283) (xy 216.309733 -120.944337) (xy 216.352601 -120.980012)
			(xy 216.389818 -121.021549) (xy 216.420591 -121.068062) (xy 216.444263 -121.118559) (xy 216.460331 -121.171966)
			(xy 216.468451 -121.227142) (xy 216.46896 -121.255028) (xy 216.468451 -121.282914) (xy 216.460331 -121.33809)
			(xy 216.444263 -121.391497) (xy 216.420591 -121.441994) (xy 216.389818 -121.488507) (xy 216.352601 -121.530044)
			(xy 216.309733 -121.565719) (xy 216.262127 -121.594773) (xy 216.210798 -121.616585) (xy 216.156841 -121.630691)
			(xy 216.101404 -121.636791) (xy 216.04567 -121.634754) (xy 215.990827 -121.624624) (xy 215.938043 -121.606617)
			(xy 215.888443 -121.581116) (xy 215.843085 -121.548665) (xy 215.802936 -121.509956) (xy 215.76885 -121.465813)
			(xy 215.741554 -121.417178) (xy 215.721631 -121.365087) (xy 215.709505 -121.31065) (xy 215.705434 -121.255028)
			(xy 213.37651 -121.255028) (xy 213.37651 -121.742962) (xy 220.459298 -121.742962) (xy 220.463369 -121.68734)
			(xy 220.475495 -121.632903) (xy 220.495418 -121.580812) (xy 220.522714 -121.532177) (xy 220.5568 -121.488034)
			(xy 220.596949 -121.449325) (xy 220.642307 -121.416874) (xy 220.691907 -121.391373) (xy 220.744691 -121.373366)
			(xy 220.799534 -121.363236) (xy 220.855268 -121.361199) (xy 220.910705 -121.367299) (xy 220.964662 -121.381405)
			(xy 221.005578 -121.398792) (xy 233.551728 -121.398792) (xy 233.555799 -121.34317) (xy 233.567925 -121.288733)
			(xy 233.587848 -121.236642) (xy 233.615144 -121.188007) (xy 233.64923 -121.143864) (xy 233.689379 -121.105155)
			(xy 233.734737 -121.072704) (xy 233.784337 -121.047203) (xy 233.837121 -121.029196) (xy 233.891964 -121.019066)
			(xy 233.947698 -121.017029) (xy 234.003135 -121.023129) (xy 234.057092 -121.037235) (xy 234.108421 -121.059047)
			(xy 234.156027 -121.088101) (xy 234.198895 -121.123776) (xy 234.236112 -121.165313) (xy 234.266885 -121.211826)
			(xy 234.290557 -121.262323) (xy 234.306625 -121.31573) (xy 234.314745 -121.370906) (xy 234.315254 -121.398792)
			(xy 234.567728 -121.398792) (xy 234.571799 -121.34317) (xy 234.583925 -121.288733) (xy 234.603848 -121.236642)
			(xy 234.631144 -121.188007) (xy 234.66523 -121.143864) (xy 234.705379 -121.105155) (xy 234.750737 -121.072704)
			(xy 234.800337 -121.047203) (xy 234.853121 -121.029196) (xy 234.907964 -121.019066) (xy 234.963698 -121.017029)
			(xy 235.019135 -121.023129) (xy 235.073092 -121.037235) (xy 235.124421 -121.059047) (xy 235.172027 -121.088101)
			(xy 235.214895 -121.123776) (xy 235.252112 -121.165313) (xy 235.282885 -121.211826) (xy 235.306557 -121.262323)
			(xy 235.322625 -121.31573) (xy 235.330745 -121.370906) (xy 235.331254 -121.398792) (xy 235.583728 -121.398792)
			(xy 235.587799 -121.34317) (xy 235.599925 -121.288733) (xy 235.619848 -121.236642) (xy 235.647144 -121.188007)
			(xy 235.68123 -121.143864) (xy 235.721379 -121.105155) (xy 235.766737 -121.072704) (xy 235.816337 -121.047203)
			(xy 235.869121 -121.029196) (xy 235.923964 -121.019066) (xy 235.979698 -121.017029) (xy 236.035135 -121.023129)
			(xy 236.089092 -121.037235) (xy 236.140421 -121.059047) (xy 236.188027 -121.088101) (xy 236.230895 -121.123776)
			(xy 236.268112 -121.165313) (xy 236.298885 -121.211826) (xy 236.322557 -121.262323) (xy 236.338625 -121.31573)
			(xy 236.346745 -121.370906) (xy 236.347254 -121.398792) (xy 236.346745 -121.426678) (xy 236.338625 -121.481854)
			(xy 236.322557 -121.535261) (xy 236.322471 -121.535444) (xy 240.886486 -121.535444) (xy 240.890557 -121.479822)
			(xy 240.902683 -121.425385) (xy 240.922606 -121.373294) (xy 240.949902 -121.324659) (xy 240.983988 -121.280516)
			(xy 241.024137 -121.241807) (xy 241.069495 -121.209356) (xy 241.119095 -121.183855) (xy 241.171879 -121.165848)
			(xy 241.226722 -121.155718) (xy 241.282456 -121.153681) (xy 241.337893 -121.159781) (xy 241.39185 -121.173887)
			(xy 241.443179 -121.195699) (xy 241.490785 -121.224753) (xy 241.533653 -121.260428) (xy 241.57087 -121.301965)
			(xy 241.601643 -121.348478) (xy 241.625315 -121.398975) (xy 241.641383 -121.452382) (xy 241.649503 -121.507558)
			(xy 241.650012 -121.535444) (xy 241.649503 -121.56333) (xy 241.641383 -121.618506) (xy 241.625315 -121.671913)
			(xy 241.601643 -121.72241) (xy 241.57087 -121.768923) (xy 241.533653 -121.81046) (xy 241.490785 -121.846135)
			(xy 241.443179 -121.875189) (xy 241.39185 -121.897001) (xy 241.337893 -121.911107) (xy 241.282456 -121.917207)
			(xy 241.226722 -121.91517) (xy 241.171879 -121.90504) (xy 241.119095 -121.887033) (xy 241.069495 -121.861532)
			(xy 241.024137 -121.829081) (xy 240.983988 -121.790372) (xy 240.949902 -121.746229) (xy 240.922606 -121.697594)
			(xy 240.902683 -121.645503) (xy 240.890557 -121.591066) (xy 240.886486 -121.535444) (xy 236.322471 -121.535444)
			(xy 236.298885 -121.585758) (xy 236.268112 -121.632271) (xy 236.230895 -121.673808) (xy 236.188027 -121.709483)
			(xy 236.140421 -121.738537) (xy 236.089092 -121.760349) (xy 236.035135 -121.774455) (xy 235.979698 -121.780555)
			(xy 235.923964 -121.778518) (xy 235.869121 -121.768388) (xy 235.816337 -121.750381) (xy 235.766737 -121.72488)
			(xy 235.721379 -121.692429) (xy 235.68123 -121.65372) (xy 235.647144 -121.609577) (xy 235.619848 -121.560942)
			(xy 235.599925 -121.508851) (xy 235.587799 -121.454414) (xy 235.583728 -121.398792) (xy 235.331254 -121.398792)
			(xy 235.330745 -121.426678) (xy 235.322625 -121.481854) (xy 235.306557 -121.535261) (xy 235.282885 -121.585758)
			(xy 235.252112 -121.632271) (xy 235.214895 -121.673808) (xy 235.172027 -121.709483) (xy 235.124421 -121.738537)
			(xy 235.073092 -121.760349) (xy 235.019135 -121.774455) (xy 234.963698 -121.780555) (xy 234.907964 -121.778518)
			(xy 234.853121 -121.768388) (xy 234.800337 -121.750381) (xy 234.750737 -121.72488) (xy 234.705379 -121.692429)
			(xy 234.66523 -121.65372) (xy 234.631144 -121.609577) (xy 234.603848 -121.560942) (xy 234.583925 -121.508851)
			(xy 234.571799 -121.454414) (xy 234.567728 -121.398792) (xy 234.315254 -121.398792) (xy 234.314745 -121.426678)
			(xy 234.306625 -121.481854) (xy 234.290557 -121.535261) (xy 234.266885 -121.585758) (xy 234.236112 -121.632271)
			(xy 234.198895 -121.673808) (xy 234.156027 -121.709483) (xy 234.108421 -121.738537) (xy 234.057092 -121.760349)
			(xy 234.003135 -121.774455) (xy 233.947698 -121.780555) (xy 233.891964 -121.778518) (xy 233.837121 -121.768388)
			(xy 233.784337 -121.750381) (xy 233.734737 -121.72488) (xy 233.689379 -121.692429) (xy 233.64923 -121.65372)
			(xy 233.615144 -121.609577) (xy 233.587848 -121.560942) (xy 233.567925 -121.508851) (xy 233.555799 -121.454414)
			(xy 233.551728 -121.398792) (xy 221.005578 -121.398792) (xy 221.015991 -121.403217) (xy 221.063597 -121.432271)
			(xy 221.106465 -121.467946) (xy 221.143682 -121.509483) (xy 221.174455 -121.555996) (xy 221.198127 -121.606493)
			(xy 221.214195 -121.6599) (xy 221.222315 -121.715076) (xy 221.222824 -121.742962) (xy 221.222315 -121.770848)
			(xy 221.214195 -121.826024) (xy 221.198127 -121.879431) (xy 221.174455 -121.929928) (xy 221.143682 -121.976441)
			(xy 221.114599 -122.0089) (xy 223.87636 -122.0089) (xy 223.880431 -121.953278) (xy 223.892557 -121.898841)
			(xy 223.91248 -121.84675) (xy 223.939776 -121.798115) (xy 223.973862 -121.753972) (xy 224.014011 -121.715263)
			(xy 224.059369 -121.682812) (xy 224.108969 -121.657311) (xy 224.161753 -121.639304) (xy 224.216596 -121.629174)
			(xy 224.27233 -121.627137) (xy 224.327767 -121.633237) (xy 224.381724 -121.647343) (xy 224.433053 -121.669155)
			(xy 224.480659 -121.698209) (xy 224.523527 -121.733884) (xy 224.560744 -121.775421) (xy 224.591517 -121.821934)
			(xy 224.615189 -121.872431) (xy 224.631257 -121.925838) (xy 224.639377 -121.981014) (xy 224.639886 -122.0089)
			(xy 224.639377 -122.036786) (xy 224.631257 -122.091962) (xy 224.615189 -122.145369) (xy 224.591517 -122.195866)
			(xy 224.560744 -122.242379) (xy 224.523527 -122.283916) (xy 224.480659 -122.319591) (xy 224.433053 -122.348645)
			(xy 224.381724 -122.370457) (xy 224.327767 -122.384563) (xy 224.27233 -122.390663) (xy 224.216596 -122.388626)
			(xy 224.161753 -122.378496) (xy 224.108969 -122.360489) (xy 224.059369 -122.334988) (xy 224.014011 -122.302537)
			(xy 223.973862 -122.263828) (xy 223.939776 -122.219685) (xy 223.91248 -122.17105) (xy 223.892557 -122.118959)
			(xy 223.880431 -122.064522) (xy 223.87636 -122.0089) (xy 221.114599 -122.0089) (xy 221.106465 -122.017978)
			(xy 221.063597 -122.053653) (xy 221.015991 -122.082707) (xy 220.964662 -122.104519) (xy 220.910705 -122.118625)
			(xy 220.855268 -122.124725) (xy 220.799534 -122.122688) (xy 220.744691 -122.112558) (xy 220.691907 -122.094551)
			(xy 220.642307 -122.06905) (xy 220.596949 -122.036599) (xy 220.5568 -121.99789) (xy 220.522714 -121.953747)
			(xy 220.495418 -121.905112) (xy 220.475495 -121.853021) (xy 220.463369 -121.798584) (xy 220.459298 -121.742962)
			(xy 213.37651 -121.742962) (xy 213.37651 -122.525028) (xy 213.606886 -122.525028) (xy 213.610957 -122.469406)
			(xy 213.623083 -122.414969) (xy 213.643006 -122.362878) (xy 213.670302 -122.314243) (xy 213.704388 -122.2701)
			(xy 213.744537 -122.231391) (xy 213.789895 -122.19894) (xy 213.839495 -122.173439) (xy 213.892279 -122.155432)
			(xy 213.947122 -122.145302) (xy 214.002856 -122.143265) (xy 214.058293 -122.149365) (xy 214.11225 -122.163471)
			(xy 214.163579 -122.185283) (xy 214.211185 -122.214337) (xy 214.254053 -122.250012) (xy 214.29127 -122.291549)
			(xy 214.322043 -122.338062) (xy 214.345715 -122.388559) (xy 214.361783 -122.441966) (xy 214.369903 -122.497142)
			(xy 214.370412 -122.525028) (xy 215.748868 -122.525028) (xy 215.752939 -122.469406) (xy 215.765065 -122.414969)
			(xy 215.784988 -122.362878) (xy 215.812284 -122.314243) (xy 215.84637 -122.2701) (xy 215.886519 -122.231391)
			(xy 215.931877 -122.19894) (xy 215.981477 -122.173439) (xy 216.034261 -122.155432) (xy 216.089104 -122.145302)
			(xy 216.144838 -122.143265) (xy 216.200275 -122.149365) (xy 216.254232 -122.163471) (xy 216.305561 -122.185283)
			(xy 216.353167 -122.214337) (xy 216.396035 -122.250012) (xy 216.433252 -122.291549) (xy 216.464025 -122.338062)
			(xy 216.487697 -122.388559) (xy 216.503765 -122.441966) (xy 216.511885 -122.497142) (xy 216.512394 -122.525028)
			(xy 216.511885 -122.552914) (xy 216.503765 -122.60809) (xy 216.487697 -122.661497) (xy 216.464025 -122.711994)
			(xy 216.433252 -122.758507) (xy 216.432844 -122.758962) (xy 218.430854 -122.758962) (xy 218.434925 -122.70334)
			(xy 218.447051 -122.648903) (xy 218.466974 -122.596812) (xy 218.49427 -122.548177) (xy 218.528356 -122.504034)
			(xy 218.568505 -122.465325) (xy 218.613863 -122.432874) (xy 218.663463 -122.407373) (xy 218.716247 -122.389366)
			(xy 218.77109 -122.379236) (xy 218.826824 -122.377199) (xy 218.882261 -122.383299) (xy 218.936218 -122.397405)
			(xy 218.987547 -122.419217) (xy 219.035153 -122.448271) (xy 219.078021 -122.483946) (xy 219.115238 -122.525483)
			(xy 219.146011 -122.571996) (xy 219.169683 -122.622493) (xy 219.185751 -122.6759) (xy 219.193871 -122.731076)
			(xy 219.19438 -122.758962) (xy 219.193871 -122.786848) (xy 219.185751 -122.842024) (xy 219.169683 -122.895431)
			(xy 219.152808 -122.931428) (xy 240.873024 -122.931428) (xy 240.877095 -122.875806) (xy 240.889221 -122.821369)
			(xy 240.909144 -122.769278) (xy 240.93644 -122.720643) (xy 240.970526 -122.6765) (xy 241.010675 -122.637791)
			(xy 241.056033 -122.60534) (xy 241.105633 -122.579839) (xy 241.158417 -122.561832) (xy 241.21326 -122.551702)
			(xy 241.268994 -122.549665) (xy 241.324431 -122.555765) (xy 241.378388 -122.569871) (xy 241.429717 -122.591683)
			(xy 241.477323 -122.620737) (xy 241.520191 -122.656412) (xy 241.557408 -122.697949) (xy 241.588181 -122.744462)
			(xy 241.611853 -122.794959) (xy 241.627921 -122.848366) (xy 241.636041 -122.903542) (xy 241.63655 -122.931428)
			(xy 241.636041 -122.959314) (xy 241.627921 -123.01449) (xy 241.611853 -123.067897) (xy 241.588181 -123.118394)
			(xy 241.557408 -123.164907) (xy 241.520191 -123.206444) (xy 241.477323 -123.242119) (xy 241.429717 -123.271173)
			(xy 241.378388 -123.292985) (xy 241.324431 -123.307091) (xy 241.268994 -123.313191) (xy 241.21326 -123.311154)
			(xy 241.158417 -123.301024) (xy 241.105633 -123.283017) (xy 241.056033 -123.257516) (xy 241.010675 -123.225065)
			(xy 240.970526 -123.186356) (xy 240.93644 -123.142213) (xy 240.909144 -123.093578) (xy 240.889221 -123.041487)
			(xy 240.877095 -122.98705) (xy 240.873024 -122.931428) (xy 219.152808 -122.931428) (xy 219.146011 -122.945928)
			(xy 219.115238 -122.992441) (xy 219.078021 -123.033978) (xy 219.035153 -123.069653) (xy 218.987547 -123.098707)
			(xy 218.936218 -123.120519) (xy 218.882261 -123.134625) (xy 218.826824 -123.140725) (xy 218.77109 -123.138688)
			(xy 218.716247 -123.128558) (xy 218.663463 -123.110551) (xy 218.613863 -123.08505) (xy 218.568505 -123.052599)
			(xy 218.528356 -123.01389) (xy 218.49427 -122.969747) (xy 218.466974 -122.921112) (xy 218.447051 -122.869021)
			(xy 218.434925 -122.814584) (xy 218.430854 -122.758962) (xy 216.432844 -122.758962) (xy 216.396035 -122.800044)
			(xy 216.353167 -122.835719) (xy 216.305561 -122.864773) (xy 216.254232 -122.886585) (xy 216.200275 -122.900691)
			(xy 216.144838 -122.906791) (xy 216.089104 -122.904754) (xy 216.034261 -122.894624) (xy 215.981477 -122.876617)
			(xy 215.931877 -122.851116) (xy 215.886519 -122.818665) (xy 215.84637 -122.779956) (xy 215.812284 -122.735813)
			(xy 215.784988 -122.687178) (xy 215.765065 -122.635087) (xy 215.752939 -122.58065) (xy 215.748868 -122.525028)
			(xy 214.370412 -122.525028) (xy 214.369903 -122.552914) (xy 214.361783 -122.60809) (xy 214.345715 -122.661497)
			(xy 214.322043 -122.711994) (xy 214.29127 -122.758507) (xy 214.254053 -122.800044) (xy 214.211185 -122.835719)
			(xy 214.163579 -122.864773) (xy 214.11225 -122.886585) (xy 214.058293 -122.900691) (xy 214.002856 -122.906791)
			(xy 213.947122 -122.904754) (xy 213.892279 -122.894624) (xy 213.839495 -122.876617) (xy 213.789895 -122.851116)
			(xy 213.744537 -122.818665) (xy 213.704388 -122.779956) (xy 213.670302 -122.735813) (xy 213.643006 -122.687178)
			(xy 213.623083 -122.635087) (xy 213.610957 -122.58065) (xy 213.606886 -122.525028) (xy 213.37651 -122.525028)
			(xy 213.37651 -123.774962) (xy 218.430854 -123.774962) (xy 218.434925 -123.71934) (xy 218.447051 -123.664903)
			(xy 218.466974 -123.612812) (xy 218.49427 -123.564177) (xy 218.528356 -123.520034) (xy 218.568505 -123.481325)
			(xy 218.613863 -123.448874) (xy 218.663463 -123.423373) (xy 218.716247 -123.405366) (xy 218.77109 -123.395236)
			(xy 218.826824 -123.393199) (xy 218.882261 -123.399299) (xy 218.936218 -123.413405) (xy 218.987547 -123.435217)
			(xy 219.035153 -123.464271) (xy 219.078021 -123.499946) (xy 219.115238 -123.541483) (xy 219.146011 -123.587996)
			(xy 219.169683 -123.638493) (xy 219.185751 -123.6919) (xy 219.193871 -123.747076) (xy 219.19438 -123.774962)
			(xy 220.586298 -123.774962) (xy 220.590369 -123.71934) (xy 220.602495 -123.664903) (xy 220.622418 -123.612812)
			(xy 220.649714 -123.564177) (xy 220.6838 -123.520034) (xy 220.723949 -123.481325) (xy 220.769307 -123.448874)
			(xy 220.818907 -123.423373) (xy 220.871691 -123.405366) (xy 220.926534 -123.395236) (xy 220.982268 -123.393199)
			(xy 221.037705 -123.399299) (xy 221.091662 -123.413405) (xy 221.142991 -123.435217) (xy 221.190597 -123.464271)
			(xy 221.233465 -123.499946) (xy 221.241599 -123.509024) (xy 222.09836 -123.509024) (xy 222.102431 -123.453402)
			(xy 222.114557 -123.398965) (xy 222.13448 -123.346874) (xy 222.161776 -123.298239) (xy 222.195862 -123.254096)
			(xy 222.236011 -123.215387) (xy 222.281369 -123.182936) (xy 222.330969 -123.157435) (xy 222.383753 -123.139428)
			(xy 222.438596 -123.129298) (xy 222.49433 -123.127261) (xy 222.549767 -123.133361) (xy 222.603724 -123.147467)
			(xy 222.655053 -123.169279) (xy 222.702659 -123.198333) (xy 222.745527 -123.234008) (xy 222.782744 -123.275545)
			(xy 222.813517 -123.322058) (xy 222.837189 -123.372555) (xy 222.853257 -123.425962) (xy 222.861377 -123.481138)
			(xy 222.861886 -123.509024) (xy 223.888298 -123.509024) (xy 223.892369 -123.453402) (xy 223.904495 -123.398965)
			(xy 223.924418 -123.346874) (xy 223.951714 -123.298239) (xy 223.9858 -123.254096) (xy 224.025949 -123.215387)
			(xy 224.071307 -123.182936) (xy 224.120907 -123.157435) (xy 224.173691 -123.139428) (xy 224.228534 -123.129298)
			(xy 224.284268 -123.127261) (xy 224.339705 -123.133361) (xy 224.393662 -123.147467) (xy 224.444991 -123.169279)
			(xy 224.492597 -123.198333) (xy 224.535465 -123.234008) (xy 224.572682 -123.275545) (xy 224.603455 -123.322058)
			(xy 224.627127 -123.372555) (xy 224.643195 -123.425962) (xy 224.651315 -123.481138) (xy 224.651824 -123.509024)
			(xy 224.651315 -123.53691) (xy 224.643195 -123.592086) (xy 224.627127 -123.645493) (xy 224.603455 -123.69599)
			(xy 224.572682 -123.742503) (xy 224.535465 -123.78404) (xy 224.492597 -123.819715) (xy 224.444991 -123.848769)
			(xy 224.393662 -123.870581) (xy 224.339705 -123.884687) (xy 224.284268 -123.890787) (xy 224.228534 -123.88875)
			(xy 224.173691 -123.87862) (xy 224.120907 -123.860613) (xy 224.071307 -123.835112) (xy 224.025949 -123.802661)
			(xy 223.9858 -123.763952) (xy 223.951714 -123.719809) (xy 223.924418 -123.671174) (xy 223.904495 -123.619083)
			(xy 223.892369 -123.564646) (xy 223.888298 -123.509024) (xy 222.861886 -123.509024) (xy 222.861377 -123.53691)
			(xy 222.853257 -123.592086) (xy 222.837189 -123.645493) (xy 222.813517 -123.69599) (xy 222.782744 -123.742503)
			(xy 222.745527 -123.78404) (xy 222.702659 -123.819715) (xy 222.655053 -123.848769) (xy 222.603724 -123.870581)
			(xy 222.549767 -123.884687) (xy 222.49433 -123.890787) (xy 222.438596 -123.88875) (xy 222.383753 -123.87862)
			(xy 222.330969 -123.860613) (xy 222.281369 -123.835112) (xy 222.236011 -123.802661) (xy 222.195862 -123.763952)
			(xy 222.161776 -123.719809) (xy 222.13448 -123.671174) (xy 222.114557 -123.619083) (xy 222.102431 -123.564646)
			(xy 222.09836 -123.509024) (xy 221.241599 -123.509024) (xy 221.270682 -123.541483) (xy 221.301455 -123.587996)
			(xy 221.325127 -123.638493) (xy 221.341195 -123.6919) (xy 221.349315 -123.747076) (xy 221.349824 -123.774962)
			(xy 221.349315 -123.802848) (xy 221.341195 -123.858024) (xy 221.325127 -123.911431) (xy 221.308252 -123.947428)
			(xy 240.873024 -123.947428) (xy 240.877095 -123.891806) (xy 240.889221 -123.837369) (xy 240.909144 -123.785278)
			(xy 240.93644 -123.736643) (xy 240.970526 -123.6925) (xy 241.010675 -123.653791) (xy 241.056033 -123.62134)
			(xy 241.105633 -123.595839) (xy 241.158417 -123.577832) (xy 241.21326 -123.567702) (xy 241.268994 -123.565665)
			(xy 241.324431 -123.571765) (xy 241.378388 -123.585871) (xy 241.429717 -123.607683) (xy 241.477323 -123.636737)
			(xy 241.520191 -123.672412) (xy 241.557408 -123.713949) (xy 241.588181 -123.760462) (xy 241.611853 -123.810959)
			(xy 241.627921 -123.864366) (xy 241.636041 -123.919542) (xy 241.63655 -123.947428) (xy 241.636041 -123.975314)
			(xy 241.627921 -124.03049) (xy 241.611853 -124.083897) (xy 241.588181 -124.134394) (xy 241.557408 -124.180907)
			(xy 241.520191 -124.222444) (xy 241.477323 -124.258119) (xy 241.429717 -124.287173) (xy 241.378388 -124.308985)
			(xy 241.324431 -124.323091) (xy 241.268994 -124.329191) (xy 241.21326 -124.327154) (xy 241.158417 -124.317024)
			(xy 241.105633 -124.299017) (xy 241.056033 -124.273516) (xy 241.010675 -124.241065) (xy 240.970526 -124.202356)
			(xy 240.93644 -124.158213) (xy 240.909144 -124.109578) (xy 240.889221 -124.057487) (xy 240.877095 -124.00305)
			(xy 240.873024 -123.947428) (xy 221.308252 -123.947428) (xy 221.301455 -123.961928) (xy 221.270682 -124.008441)
			(xy 221.233465 -124.049978) (xy 221.190597 -124.085653) (xy 221.142991 -124.114707) (xy 221.091662 -124.136519)
			(xy 221.037705 -124.150625) (xy 220.982268 -124.156725) (xy 220.926534 -124.154688) (xy 220.871691 -124.144558)
			(xy 220.818907 -124.126551) (xy 220.769307 -124.10105) (xy 220.723949 -124.068599) (xy 220.6838 -124.02989)
			(xy 220.649714 -123.985747) (xy 220.622418 -123.937112) (xy 220.602495 -123.885021) (xy 220.590369 -123.830584)
			(xy 220.586298 -123.774962) (xy 219.19438 -123.774962) (xy 219.193871 -123.802848) (xy 219.185751 -123.858024)
			(xy 219.169683 -123.911431) (xy 219.146011 -123.961928) (xy 219.115238 -124.008441) (xy 219.078021 -124.049978)
			(xy 219.035153 -124.085653) (xy 218.987547 -124.114707) (xy 218.936218 -124.136519) (xy 218.882261 -124.150625)
			(xy 218.826824 -124.156725) (xy 218.77109 -124.154688) (xy 218.716247 -124.144558) (xy 218.663463 -124.126551)
			(xy 218.613863 -124.10105) (xy 218.568505 -124.068599) (xy 218.528356 -124.02989) (xy 218.49427 -123.985747)
			(xy 218.466974 -123.937112) (xy 218.447051 -123.885021) (xy 218.434925 -123.830584) (xy 218.430854 -123.774962)
			(xy 213.37651 -123.774962) (xy 213.37651 -124.790962) (xy 218.430854 -124.790962) (xy 218.434925 -124.73534)
			(xy 218.447051 -124.680903) (xy 218.466974 -124.628812) (xy 218.49427 -124.580177) (xy 218.528356 -124.536034)
			(xy 218.568505 -124.497325) (xy 218.613863 -124.464874) (xy 218.663463 -124.439373) (xy 218.716247 -124.421366)
			(xy 218.77109 -124.411236) (xy 218.826824 -124.409199) (xy 218.882261 -124.415299) (xy 218.936218 -124.429405)
			(xy 218.987547 -124.451217) (xy 219.035153 -124.480271) (xy 219.078021 -124.515946) (xy 219.115238 -124.557483)
			(xy 219.146011 -124.603996) (xy 219.169683 -124.654493) (xy 219.185751 -124.7079) (xy 219.193871 -124.763076)
			(xy 219.19438 -124.790962) (xy 219.193871 -124.818848) (xy 219.185751 -124.874024) (xy 219.169683 -124.927431)
			(xy 219.152808 -124.963428) (xy 240.873024 -124.963428) (xy 240.877095 -124.907806) (xy 240.889221 -124.853369)
			(xy 240.909144 -124.801278) (xy 240.93644 -124.752643) (xy 240.970526 -124.7085) (xy 241.010675 -124.669791)
			(xy 241.056033 -124.63734) (xy 241.105633 -124.611839) (xy 241.158417 -124.593832) (xy 241.21326 -124.583702)
			(xy 241.268994 -124.581665) (xy 241.324431 -124.587765) (xy 241.378388 -124.601871) (xy 241.429717 -124.623683)
			(xy 241.477323 -124.652737) (xy 241.520191 -124.688412) (xy 241.557408 -124.729949) (xy 241.588181 -124.776462)
			(xy 241.611853 -124.826959) (xy 241.627921 -124.880366) (xy 241.636041 -124.935542) (xy 241.63655 -124.963428)
			(xy 241.636041 -124.991314) (xy 241.627921 -125.04649) (xy 241.611853 -125.099897) (xy 241.588181 -125.150394)
			(xy 241.557408 -125.196907) (xy 241.520191 -125.238444) (xy 241.477323 -125.274119) (xy 241.429717 -125.303173)
			(xy 241.378388 -125.324985) (xy 241.324431 -125.339091) (xy 241.268994 -125.345191) (xy 241.21326 -125.343154)
			(xy 241.158417 -125.333024) (xy 241.105633 -125.315017) (xy 241.056033 -125.289516) (xy 241.010675 -125.257065)
			(xy 240.970526 -125.218356) (xy 240.93644 -125.174213) (xy 240.909144 -125.125578) (xy 240.889221 -125.073487)
			(xy 240.877095 -125.01905) (xy 240.873024 -124.963428) (xy 219.152808 -124.963428) (xy 219.146011 -124.977928)
			(xy 219.115238 -125.024441) (xy 219.078021 -125.065978) (xy 219.035153 -125.101653) (xy 218.987547 -125.130707)
			(xy 218.936218 -125.152519) (xy 218.882261 -125.166625) (xy 218.826824 -125.172725) (xy 218.77109 -125.170688)
			(xy 218.716247 -125.160558) (xy 218.663463 -125.142551) (xy 218.613863 -125.11705) (xy 218.568505 -125.084599)
			(xy 218.528356 -125.04589) (xy 218.49427 -125.001747) (xy 218.466974 -124.953112) (xy 218.447051 -124.901021)
			(xy 218.434925 -124.846584) (xy 218.430854 -124.790962) (xy 213.37651 -124.790962) (xy 213.37651 -125.738128)
			(xy 217.592908 -125.738128) (xy 217.596979 -125.682506) (xy 217.609105 -125.628069) (xy 217.629028 -125.575978)
			(xy 217.656324 -125.527343) (xy 217.69041 -125.4832) (xy 217.730559 -125.444491) (xy 217.775917 -125.41204)
			(xy 217.825517 -125.386539) (xy 217.878301 -125.368532) (xy 217.933144 -125.358402) (xy 217.988878 -125.356365)
			(xy 218.044315 -125.362465) (xy 218.098272 -125.376571) (xy 218.149601 -125.398383) (xy 218.197207 -125.427437)
			(xy 218.240075 -125.463112) (xy 218.277292 -125.504649) (xy 218.308065 -125.551162) (xy 218.331737 -125.601659)
			(xy 218.347805 -125.655066) (xy 218.355925 -125.710242) (xy 218.356434 -125.738128) (xy 218.355925 -125.766014)
			(xy 218.347805 -125.82119) (xy 218.331737 -125.874597) (xy 218.308065 -125.925094) (xy 218.277292 -125.971607)
			(xy 218.270284 -125.979428) (xy 240.873024 -125.979428) (xy 240.877095 -125.923806) (xy 240.889221 -125.869369)
			(xy 240.909144 -125.817278) (xy 240.93644 -125.768643) (xy 240.970526 -125.7245) (xy 241.010675 -125.685791)
			(xy 241.056033 -125.65334) (xy 241.105633 -125.627839) (xy 241.158417 -125.609832) (xy 241.21326 -125.599702)
			(xy 241.268994 -125.597665) (xy 241.324431 -125.603765) (xy 241.378388 -125.617871) (xy 241.429717 -125.639683)
			(xy 241.477323 -125.668737) (xy 241.520191 -125.704412) (xy 241.557408 -125.745949) (xy 241.588181 -125.792462)
			(xy 241.611853 -125.842959) (xy 241.627921 -125.896366) (xy 241.636041 -125.951542) (xy 241.63655 -125.979428)
			(xy 241.636041 -126.007314) (xy 241.627921 -126.06249) (xy 241.611853 -126.115897) (xy 241.588181 -126.166394)
			(xy 241.557408 -126.212907) (xy 241.520191 -126.254444) (xy 241.477323 -126.290119) (xy 241.429717 -126.319173)
			(xy 241.378388 -126.340985) (xy 241.324431 -126.355091) (xy 241.268994 -126.361191) (xy 241.21326 -126.359154)
			(xy 241.158417 -126.349024) (xy 241.105633 -126.331017) (xy 241.056033 -126.305516) (xy 241.010675 -126.273065)
			(xy 240.970526 -126.234356) (xy 240.93644 -126.190213) (xy 240.909144 -126.141578) (xy 240.889221 -126.089487)
			(xy 240.877095 -126.03505) (xy 240.873024 -125.979428) (xy 218.270284 -125.979428) (xy 218.240075 -126.013144)
			(xy 218.197207 -126.048819) (xy 218.149601 -126.077873) (xy 218.098272 -126.099685) (xy 218.044315 -126.113791)
			(xy 217.988878 -126.119891) (xy 217.933144 -126.117854) (xy 217.878301 -126.107724) (xy 217.825517 -126.089717)
			(xy 217.775917 -126.064216) (xy 217.730559 -126.031765) (xy 217.69041 -125.993056) (xy 217.656324 -125.948913)
			(xy 217.629028 -125.900278) (xy 217.609105 -125.848187) (xy 217.596979 -125.79375) (xy 217.592908 -125.738128)
			(xy 213.37651 -125.738128) (xy 213.37651 -126.995428) (xy 240.873024 -126.995428) (xy 240.877095 -126.939806)
			(xy 240.889221 -126.885369) (xy 240.909144 -126.833278) (xy 240.93644 -126.784643) (xy 240.970526 -126.7405)
			(xy 241.010675 -126.701791) (xy 241.056033 -126.66934) (xy 241.105633 -126.643839) (xy 241.158417 -126.625832)
			(xy 241.21326 -126.615702) (xy 241.268994 -126.613665) (xy 241.324431 -126.619765) (xy 241.378388 -126.633871)
			(xy 241.429717 -126.655683) (xy 241.477323 -126.684737) (xy 241.520191 -126.720412) (xy 241.557408 -126.761949)
			(xy 241.588181 -126.808462) (xy 241.611853 -126.858959) (xy 241.627921 -126.912366) (xy 241.636041 -126.967542)
			(xy 241.63655 -126.995428) (xy 241.636041 -127.023314) (xy 241.627921 -127.07849) (xy 241.611853 -127.131897)
			(xy 241.588181 -127.182394) (xy 241.557408 -127.228907) (xy 241.520191 -127.270444) (xy 241.477323 -127.306119)
			(xy 241.429717 -127.335173) (xy 241.378388 -127.356985) (xy 241.324431 -127.371091) (xy 241.268994 -127.377191)
			(xy 241.21326 -127.375154) (xy 241.158417 -127.365024) (xy 241.105633 -127.347017) (xy 241.056033 -127.321516)
			(xy 241.010675 -127.289065) (xy 240.970526 -127.250356) (xy 240.93644 -127.206213) (xy 240.909144 -127.157578)
			(xy 240.889221 -127.105487) (xy 240.877095 -127.05105) (xy 240.873024 -126.995428) (xy 213.37651 -126.995428)
			(xy 213.37651 -129.444242) (xy 213.377526 -129.453894) (xy 213.379159 -129.461135) (xy 213.386007 -129.474297)
			(xy 213.390988 -129.479802) (xy 214.159084 -130.247898) (xy 214.165932 -130.255296) (xy 214.17367 -130.273894)
			(xy 214.17407 -130.283966) (xy 214.17407 -130.318764) (xy 214.174573 -130.328816) (xy 214.18229 -130.347381)
			(xy 214.189056 -130.354832) (xy 216.409524 -132.5753) (xy 216.416924 -132.582143) (xy 216.435522 -132.589868)
			(xy 216.445592 -132.590286) (xy 216.904316 -132.590286) (xy 216.913485 -132.589945) (xy 216.930671 -132.583562)
			(xy 216.937844 -132.57784) (xy 216.964531 -132.55531) (xy 217.022316 -132.516078) (xy 217.084355 -132.483993)
			(xy 217.149768 -132.45951) (xy 217.217627 -132.442976) (xy 217.28697 -132.434626) (xy 217.321892 -132.434076)
			(xy 235.4834 -132.434076) (xy 235.518346 -132.434578) (xy 235.587743 -132.44289) (xy 235.655656 -132.459406)
			(xy 235.721118 -132.483893) (xy 235.783199 -132.516) (xy 235.841015 -132.555273) (xy 235.867702 -132.57784)
			(xy 235.87456 -132.583936) (xy 235.891578 -132.590286) (xy 235.919772 -132.590286) (xy 235.929837 -132.590722)
			(xy 235.948424 -132.598453) (xy 235.95584 -132.605272) (xy 237.661196 -134.310628) (xy 237.661658 -134.320504)
			(xy 237.669103 -134.338801) (xy 237.675674 -134.346188) (xy 238.177578 -134.848092) (xy 238.180728 -134.851106)
			(xy 238.187881 -134.856092) (xy 238.191802 -134.857998) (xy 238.19739 -134.860284) (xy 238.203953 -134.862198)
			(xy 238.217603 -134.862851) (xy 238.224314 -134.861554) (xy 238.31169 -134.838186) (xy 238.318088 -134.836234)
			(xy 238.329669 -134.82955) (xy 238.33455 -134.824978) (xy 238.343948 -134.81558) (xy 238.344456 -134.813294)
			(xy 238.347504 -134.802118) (xy 238.35541 -134.774491) (xy 238.378363 -134.721811) (xy 238.393224 -134.697216)
			(xy 238.408438 -134.673927) (xy 238.44455 -134.631616) (xy 238.486435 -134.595009) (xy 238.533201 -134.564888)
			(xy 238.558324 -134.552944) (xy 238.57077 -134.547356) (xy 238.571278 -134.547102) (xy 238.579152 -134.535672)
			(xy 238.582899 -134.529751) (xy 238.587394 -134.516487) (xy 238.588042 -134.50951) (xy 238.590836 -134.452868)
			(xy 238.59236 -134.419086) (xy 238.592485 -134.412) (xy 238.589261 -134.398205) (xy 238.58601 -134.391908)
			(xy 238.582708 -134.386066) (xy 238.573564 -134.376414) (xy 238.56696 -134.372604) (xy 238.542538 -134.357858)
			(xy 238.497965 -134.322252) (xy 238.459188 -134.280409) (xy 238.427073 -134.233259) (xy 238.402335 -134.181853)
			(xy 238.385525 -134.127338) (xy 238.377017 -134.070928) (xy 238.37646 -134.042404) (xy 238.376946 -134.015153)
			(xy 238.384702 -133.961205) (xy 238.400057 -133.90891) (xy 238.422699 -133.859333) (xy 238.452165 -133.813483)
			(xy 238.487856 -133.772292) (xy 238.529047 -133.736601) (xy 238.574897 -133.707135) (xy 238.624474 -133.684493)
			(xy 238.676769 -133.669138) (xy 238.730717 -133.661382) (xy 238.785219 -133.661382) (xy 238.839167 -133.669138)
			(xy 238.891462 -133.684493) (xy 238.941039 -133.707135) (xy 238.986889 -133.736601) (xy 239.02808 -133.772292)
			(xy 239.063771 -133.813483) (xy 239.093237 -133.859333) (xy 239.115879 -133.90891) (xy 239.131234 -133.961205)
			(xy 239.13899 -134.015153) (xy 239.139476 -134.042404) (xy 239.139016 -134.069716) (xy 239.131241 -134.123782)
			(xy 239.115835 -134.176187) (xy 239.093115 -134.225861) (xy 239.063543 -134.271786) (xy 239.027725 -134.313026)
			(xy 238.986393 -134.348737) (xy 238.94039 -134.378189) (xy 238.915702 -134.389876) (xy 238.903256 -134.395464)
			(xy 238.902748 -134.395718) (xy 238.894874 -134.407148) (xy 238.891117 -134.413065) (xy 238.886599 -134.426328)
			(xy 238.885984 -134.43331) (xy 238.88319 -134.489952) (xy 238.881666 -134.523734) (xy 238.881544 -134.530819)
			(xy 238.884774 -134.54461) (xy 238.888016 -134.550912) (xy 238.891318 -134.556754) (xy 238.900462 -134.566406)
			(xy 238.907066 -134.570216) (xy 238.931486 -134.584964) (xy 238.976054 -134.620571) (xy 239.014826 -134.662416)
			(xy 239.046936 -134.709566) (xy 239.07167 -134.760971) (xy 239.088476 -134.815485) (xy 239.09698 -134.871893)
			(xy 239.097566 -134.900416) (xy 239.09707 -134.928198) (xy 239.089019 -134.983175) (xy 239.073075 -135.036402)
			(xy 239.049576 -135.086752) (xy 239.019019 -135.133159) (xy 238.982051 -135.17464) (xy 238.939454 -135.210317)
			(xy 238.892132 -135.239436) (xy 238.841084 -135.261378) (xy 238.814356 -135.26897) (xy 238.80318 -135.272018)
			(xy 238.800894 -135.272526) (xy 238.791496 -135.281924) (xy 238.786889 -135.28678) (xy 238.780197 -135.298368)
			(xy 238.778288 -135.304784) (xy 238.75492 -135.39216) (xy 238.753634 -135.398873) (xy 238.754284 -135.41252)
			(xy 238.75619 -135.419084) (xy 238.758476 -135.424672) (xy 238.760417 -135.428573) (xy 238.765398 -135.435721)
			(xy 238.768382 -135.438896) (xy 239.196372 -135.866886) (xy 240.639852 -135.866886) (xy 240.643923 -135.811264)
			(xy 240.656049 -135.756827) (xy 240.675972 -135.704736) (xy 240.703268 -135.656101) (xy 240.737354 -135.611958)
			(xy 240.777503 -135.573249) (xy 240.822861 -135.540798) (xy 240.872461 -135.515297) (xy 240.925245 -135.49729)
			(xy 240.980088 -135.48716) (xy 241.035822 -135.485123) (xy 241.091259 -135.491223) (xy 241.145216 -135.505329)
			(xy 241.196545 -135.527141) (xy 241.244151 -135.556195) (xy 241.287019 -135.59187) (xy 241.324236 -135.633407)
			(xy 241.355009 -135.67992) (xy 241.378681 -135.730417) (xy 241.394749 -135.783824) (xy 241.402869 -135.839)
			(xy 241.403378 -135.866886) (xy 241.402869 -135.894772) (xy 241.394749 -135.949948) (xy 241.378681 -136.003355)
			(xy 241.355009 -136.053852) (xy 241.324236 -136.100365) (xy 241.287019 -136.141902) (xy 241.244151 -136.177577)
			(xy 241.196545 -136.206631) (xy 241.145216 -136.228443) (xy 241.091259 -136.242549) (xy 241.035822 -136.248649)
			(xy 240.980088 -136.246612) (xy 240.925245 -136.236482) (xy 240.872461 -136.218475) (xy 240.822861 -136.192974)
			(xy 240.777503 -136.160523) (xy 240.737354 -136.121814) (xy 240.703268 -136.077671) (xy 240.675972 -136.029036)
			(xy 240.656049 -135.976945) (xy 240.643923 -135.922508) (xy 240.639852 -135.866886) (xy 239.196372 -135.866886)
			(xy 239.683036 -136.35355) (xy 239.688537 -136.358533) (xy 239.701706 -136.365367) (xy 239.708944 -136.367012)
			(xy 239.718596 -136.368028) (xy 241.712496 -136.368028) (xy 241.722148 -136.367012) (xy 241.729393 -136.365386)
			(xy 241.742567 -136.35855) (xy 241.748056 -136.35355) (xy 242.526566 -135.57504) (xy 242.534119 -135.566579)
			(xy 242.541647 -135.545216) (xy 242.541044 -135.533892) (xy 242.532916 -135.455406) (xy 242.532136 -135.449761)
			(xy 242.528427 -135.438988) (xy 242.52555 -135.43407) (xy 242.522756 -135.429498) (xy 242.514882 -135.42137)
			(xy 242.509802 -135.418068) (xy 242.483467 -135.400217) (xy 242.436609 -135.357191) (xy 242.416584 -135.33247)
			(xy 242.412774 -135.327644) (xy 242.403884 -135.320532) (xy 242.398296 -135.317738) (xy 242.392822 -135.315364)
			(xy 242.381148 -135.312924) (xy 242.375182 -135.312912) (xy 242.293902 -135.31469) (xy 242.288009 -135.314967)
			(xy 242.276592 -135.31793) (xy 242.271296 -135.320532) (xy 242.265962 -135.323326) (xy 242.25758 -135.330946)
			(xy 242.25377 -135.336026) (xy 242.238347 -135.356914) (xy 242.202762 -135.394723) (xy 242.162381 -135.427362)
			(xy 242.117951 -135.454229) (xy 242.070289 -135.474827) (xy 242.020277 -135.488778) (xy 241.968835 -135.495823)
			(xy 241.942874 -135.4963) (xy 241.915625 -135.495812) (xy 241.861681 -135.488053) (xy 241.80939 -135.472696)
			(xy 241.759817 -135.450054) (xy 241.713971 -135.420588) (xy 241.672785 -135.384897) (xy 241.637097 -135.343708)
			(xy 241.607634 -135.29786) (xy 241.584995 -135.248285) (xy 241.569641 -135.195994) (xy 241.561886 -135.142049)
			(xy 241.561886 -135.087551) (xy 241.569641 -135.033606) (xy 241.584995 -134.981315) (xy 241.607634 -134.93174)
			(xy 241.637097 -134.885892) (xy 241.672785 -134.844703) (xy 241.713971 -134.809012) (xy 241.759817 -134.779546)
			(xy 241.80939 -134.756904) (xy 241.861681 -134.741547) (xy 241.915625 -134.733788) (xy 241.942874 -134.733284)
			(xy 241.971792 -134.733816) (xy 242.028965 -134.742539) (xy 242.084168 -134.75979) (xy 242.136136 -134.785173)
			(xy 242.183678 -134.818108) (xy 242.225706 -134.857839) (xy 242.243864 -134.88035) (xy 242.247674 -134.885176)
			(xy 242.256564 -134.892288) (xy 242.262152 -134.895082) (xy 242.267627 -134.89745) (xy 242.279301 -134.899878)
			(xy 242.285266 -134.899908) (xy 242.366546 -134.89813) (xy 242.372441 -134.897859) (xy 242.383864 -134.894907)
			(xy 242.389152 -134.892288) (xy 242.394232 -134.889748) (xy 242.402868 -134.882128) (xy 242.406678 -134.876794)
			(xy 242.422073 -134.855894) (xy 242.457608 -134.818054) (xy 242.497942 -134.785378) (xy 242.542332 -134.75847)
			(xy 242.589959 -134.737824) (xy 242.639945 -134.723823) (xy 242.691366 -134.716725) (xy 242.71732 -134.716266)
			(xy 242.717828 -134.716266) (xy 242.72875 -134.71652) (xy 242.73383 -134.716774) (xy 242.771422 -134.72033)
			(xy 242.782344 -134.721854) (xy 242.792504 -134.718806) (xy 242.797726 -134.717147) (xy 242.807342 -134.711897)
			(xy 242.811554 -134.708392) (xy 242.86464 -134.662418) (xy 242.870482 -134.657338) (xy 242.877994 -134.649794)
			(xy 242.886664 -134.630375) (xy 242.887246 -134.619746) (xy 242.887246 -131.842002) (xy 242.886945 -131.833334)
			(xy 242.881231 -131.81697) (xy 242.87607 -131.809998) (xy 242.870736 -131.803394) (xy 242.856004 -131.79425)
			(xy 242.847368 -131.792472) (xy 242.81641 -131.785011) (xy 242.75736 -131.761183) (xy 242.703101 -131.727857)
			(xy 242.678712 -131.707382) (xy 242.6716 -131.701286) (xy 242.663218 -131.698238) (xy 242.65893 -131.696716)
			(xy 242.649986 -131.69505) (xy 242.645438 -131.694936) (xy 242.578382 -131.694936) (xy 242.573835 -131.695064)
			(xy 242.564895 -131.696733) (xy 242.560602 -131.698238) (xy 242.55222 -131.701286) (xy 242.545108 -131.707382)
			(xy 242.524177 -131.725025) (xy 242.478211 -131.754754) (xy 242.428465 -131.777599) (xy 242.375961 -131.793091)
			(xy 242.321781 -131.800911) (xy 242.29441 -131.801362) (xy 242.26716 -131.800899) (xy 242.213214 -131.793145)
			(xy 242.160922 -131.777791) (xy 242.111346 -131.755152) (xy 242.065497 -131.725688) (xy 242.024309 -131.689999)
			(xy 241.988618 -131.648811) (xy 241.959153 -131.602962) (xy 241.936512 -131.553388) (xy 241.921158 -131.501095)
			(xy 241.913401 -131.44715) (xy 241.913401 -131.39265) (xy 241.921158 -131.338705) (xy 241.936512 -131.286412)
			(xy 241.959153 -131.236838) (xy 241.988618 -131.190989) (xy 242.024309 -131.149801) (xy 242.065497 -131.114112)
			(xy 242.111346 -131.084648) (xy 242.160922 -131.062009) (xy 242.213214 -131.046655) (xy 242.26716 -131.038901)
			(xy 242.29441 -131.038346) (xy 242.32178 -131.038819) (xy 242.375956 -131.046644) (xy 242.428458 -131.062134)
			(xy 242.478207 -131.084969) (xy 242.52418 -131.114681) (xy 242.545108 -131.132326) (xy 242.55222 -131.138422)
			(xy 242.560602 -131.14147) (xy 242.56489 -131.14299) (xy 242.573834 -131.144652) (xy 242.578382 -131.144772)
			(xy 242.645438 -131.144772) (xy 242.649986 -131.144651) (xy 242.658932 -131.142995) (xy 242.663218 -131.14147)
			(xy 242.6716 -131.138422) (xy 242.678712 -131.132326) (xy 242.703131 -131.111894) (xy 242.757398 -131.0786)
			(xy 242.816427 -131.054748) (xy 242.847368 -131.047236) (xy 242.855723 -131.045049) (xy 242.870407 -131.035975)
			(xy 242.87607 -131.029456) (xy 242.881404 -131.022852) (xy 242.887246 -131.006596) (xy 242.887246 -128.643888)
			(xy 242.88687 -128.635529) (xy 242.881435 -128.619713) (xy 242.876578 -128.6129) (xy 242.871498 -128.606296)
			(xy 242.857782 -128.597152) (xy 242.849146 -128.594866) (xy 242.820657 -128.586969) (xy 242.766364 -128.563585)
			(xy 242.716336 -128.53209) (xy 242.693698 -128.513078) (xy 242.686586 -128.506982) (xy 242.678204 -128.503934)
			(xy 242.673916 -128.502413) (xy 242.664972 -128.50075) (xy 242.660424 -128.500632) (xy 242.593368 -128.500632)
			(xy 242.58882 -128.500753) (xy 242.579874 -128.502408) (xy 242.575588 -128.503934) (xy 242.567206 -128.506982)
			(xy 242.560094 -128.513078) (xy 242.539163 -128.530721) (xy 242.493197 -128.560448) (xy 242.44345 -128.583291)
			(xy 242.390946 -128.598782) (xy 242.336767 -128.6066) (xy 242.309396 -128.607058) (xy 242.282141 -128.606572)
			(xy 242.228187 -128.598814) (xy 242.175886 -128.583456) (xy 242.126303 -128.560812) (xy 242.080447 -128.531342)
			(xy 242.039252 -128.495646) (xy 242.003556 -128.45445) (xy 241.974086 -128.408594) (xy 241.951442 -128.35901)
			(xy 241.936085 -128.306709) (xy 241.928328 -128.252755) (xy 241.928328 -128.198245) (xy 241.936085 -128.144291)
			(xy 241.951442 -128.09199) (xy 241.974086 -128.042406) (xy 242.003556 -127.99655) (xy 242.039252 -127.955354)
			(xy 242.080447 -127.919658) (xy 242.126303 -127.890188) (xy 242.175886 -127.867544) (xy 242.228187 -127.852186)
			(xy 242.282141 -127.844428) (xy 242.309396 -127.844042) (xy 242.336766 -127.844514) (xy 242.390944 -127.852338)
			(xy 242.443447 -127.867826) (xy 242.493197 -127.890659) (xy 242.539172 -127.92037) (xy 242.560094 -127.938022)
			(xy 242.567206 -127.944118) (xy 242.575588 -127.947166) (xy 242.579876 -127.948688) (xy 242.58882 -127.950352)
			(xy 242.593368 -127.950468) (xy 242.660424 -127.950468) (xy 242.664972 -127.950348) (xy 242.673919 -127.948694)
			(xy 242.678204 -127.947166) (xy 242.686586 -127.944118) (xy 242.693698 -127.938022) (xy 242.716309 -127.919038)
			(xy 242.766252 -127.887559) (xy 242.820451 -127.864154) (xy 242.848892 -127.856234) (xy 242.8494 -127.856234)
			(xy 242.849654 -127.85598) (xy 242.857533 -127.853573) (xy 242.87127 -127.8445) (xy 242.876578 -127.8382)
			(xy 242.881912 -127.831596) (xy 242.887246 -127.815594) (xy 242.887246 -120.731534) (xy 242.886794 -120.721379)
			(xy 242.878934 -120.702651) (xy 242.872006 -120.695212) (xy 242.820444 -120.644412) (xy 242.816713 -120.640892)
			(xy 242.808137 -120.635266) (xy 242.803426 -120.633236) (xy 242.794282 -120.62968) (xy 242.783868 -120.629934)
			(xy 242.777264 -120.629934) (xy 242.750013 -120.629446) (xy 242.696065 -120.621684) (xy 242.643771 -120.606325)
			(xy 242.594195 -120.58368) (xy 242.548346 -120.554211) (xy 242.507157 -120.518517) (xy 242.471467 -120.477325)
			(xy 242.442002 -120.431473) (xy 242.419362 -120.381895) (xy 242.404008 -120.3296) (xy 242.396252 -120.275651)
			(xy 242.396252 -120.221149) (xy 242.404008 -120.1672) (xy 242.419362 -120.114905) (xy 242.442002 -120.065327)
			(xy 242.471467 -120.019475) (xy 242.507157 -119.978283) (xy 242.548346 -119.942589) (xy 242.594195 -119.91312)
			(xy 242.643771 -119.890475) (xy 242.696065 -119.875116) (xy 242.750013 -119.867354) (xy 242.777264 -119.866918)
			(xy 242.783868 -119.866918) (xy 242.794282 -119.867172) (xy 242.803426 -119.863616) (xy 242.80815 -119.86161)
			(xy 242.816727 -119.855978) (xy 242.820444 -119.85244) (xy 242.872006 -119.80164) (xy 242.878958 -119.794216)
			(xy 242.886829 -119.77548) (xy 242.887246 -119.765318) (xy 242.887246 -118.572534) (xy 242.886794 -118.562379)
			(xy 242.878934 -118.543651) (xy 242.872006 -118.536212) (xy 242.820444 -118.485412) (xy 242.816713 -118.481892)
			(xy 242.808137 -118.476266) (xy 242.803426 -118.474236) (xy 242.794282 -118.47068) (xy 242.783868 -118.470934)
			(xy 242.777264 -118.470934) (xy 242.750013 -118.470446) (xy 242.696065 -118.462684) (xy 242.643771 -118.447325)
			(xy 242.594195 -118.42468) (xy 242.548346 -118.395211) (xy 242.507157 -118.359517) (xy 242.471467 -118.318325)
			(xy 242.442002 -118.272473) (xy 242.419362 -118.222895) (xy 242.404008 -118.1706) (xy 242.396252 -118.116651)
			(xy 242.396252 -118.062149) (xy 242.404008 -118.0082) (xy 242.419362 -117.955905) (xy 242.442002 -117.906327)
			(xy 242.471467 -117.860475) (xy 242.507157 -117.819283) (xy 242.548346 -117.783589) (xy 242.594195 -117.75412)
			(xy 242.643771 -117.731475) (xy 242.696065 -117.716116) (xy 242.750013 -117.708354) (xy 242.777264 -117.707918)
			(xy 242.783868 -117.707918) (xy 242.794282 -117.708172) (xy 242.803426 -117.704616) (xy 242.80815 -117.70261)
			(xy 242.816727 -117.696978) (xy 242.820444 -117.69344) (xy 242.872006 -117.64264) (xy 242.878958 -117.635216)
			(xy 242.886829 -117.61648) (xy 242.887246 -117.606318) (xy 242.887246 -115.772184) (xy 242.887673 -115.762116)
			(xy 242.895397 -115.74352) (xy 242.902232 -115.736116) (xy 244.09146 -114.546888) (xy 244.098858 -114.540042)
			(xy 244.117457 -114.532315) (xy 244.127528 -114.531902) (xy 244.150134 -114.531902) (xy 244.157457 -114.531629)
			(xy 244.171509 -114.527498) (xy 244.17782 -114.523774) (xy 244.183662 -114.519964) (xy 244.192806 -114.509296)
			(xy 244.196108 -114.502184) (xy 244.207842 -114.477556) (xy 244.237304 -114.431643) (xy 244.273005 -114.390394)
			(xy 244.314215 -114.35465) (xy 244.360097 -114.325138) (xy 244.409713 -114.302462) (xy 244.462053 -114.287082)
			(xy 244.51605 -114.279314) (xy 244.570602 -114.279314) (xy 244.624599 -114.287082) (xy 244.676939 -114.302462)
			(xy 244.726555 -114.325138) (xy 244.772437 -114.35465) (xy 244.813647 -114.390394) (xy 244.849348 -114.431643)
			(xy 244.87881 -114.477556) (xy 244.890544 -114.502184) (xy 244.890798 -114.502692) (xy 244.893985 -114.509025)
			(xy 244.903258 -114.51974) (xy 244.909086 -114.523774) (xy 244.915182 -114.527838) (xy 244.929152 -114.531902)
			(xy 245.771162 -114.531902) (xy 245.780595 -114.531407) (xy 245.798154 -114.524489) (xy 245.812046 -114.511715)
			(xy 245.816628 -114.503454) (xy 245.85676 -114.42192) (xy 245.859744 -114.415355) (xy 245.862326 -114.401174)
			(xy 245.86184 -114.39398) (xy 245.861078 -114.387122) (xy 245.855744 -114.373914) (xy 245.851426 -114.368326)
			(xy 245.836439 -114.348235) (xy 245.811305 -114.304869) (xy 245.792077 -114.258579) (xy 245.779089 -114.210168)
			(xy 245.772564 -114.16047) (xy 245.772178 -114.135408) (xy 245.772178 -114.127788) (xy 245.773247 -114.09961)
			(xy 245.782657 -114.044014) (xy 245.800147 -113.990408) (xy 245.825334 -113.93996) (xy 245.857671 -113.893767)
			(xy 245.896455 -113.852836) (xy 245.940839 -113.818058) (xy 245.989858 -113.79019) (xy 246.042444 -113.76984)
			(xy 246.097453 -113.757449) (xy 246.153686 -113.753289) (xy 246.209919 -113.757449) (xy 246.264928 -113.76984)
			(xy 246.317514 -113.79019) (xy 246.366533 -113.818058) (xy 246.410917 -113.852836) (xy 246.449701 -113.893767)
			(xy 246.482038 -113.93996) (xy 246.507225 -113.990408) (xy 246.524715 -114.044014) (xy 246.534125 -114.09961)
			(xy 246.535194 -114.127788) (xy 246.535194 -114.135408) (xy 246.534794 -114.160467) (xy 246.52823 -114.210154)
			(xy 246.515231 -114.258558) (xy 246.496018 -114.304847) (xy 246.470921 -114.348229) (xy 246.455946 -114.368326)
			(xy 246.451628 -114.373914) (xy 246.446294 -114.387122) (xy 246.445532 -114.39398) (xy 246.445 -114.401177)
			(xy 246.447588 -114.415367) (xy 246.450612 -114.42192) (xy 246.490744 -114.503454) (xy 246.495235 -114.511784)
			(xy 246.509139 -114.524602) (xy 246.526754 -114.531482) (xy 246.53621 -114.531902) (xy 249.121676 -114.531902)
			(xy 249.132721 -114.531303) (xy 249.152746 -114.521962) (xy 249.160284 -114.513868) (xy 249.17527 -114.496342)
			(xy 249.210576 -114.454432) (xy 249.214098 -114.450089) (xy 249.219356 -114.440222) (xy 249.22099 -114.434874)
			(xy 249.22353 -114.425222) (xy 249.221752 -114.413792) (xy 249.21939 -114.398471) (xy 249.216849 -114.367571)
			(xy 249.216672 -114.35207) (xy 249.216672 -114.351054) (xy 249.217212 -114.321746) (xy 249.226189 -114.263823)
			(xy 249.243923 -114.207955) (xy 249.269998 -114.155458) (xy 249.303799 -114.107571) (xy 249.344529 -114.065419)
			(xy 249.367548 -114.04727) (xy 249.368056 -114.046762) (xy 249.36831 -114.046762) (xy 249.372508 -114.043338)
			(xy 249.379429 -114.035007) (xy 249.382026 -114.030252) (xy 249.38482 -114.024918) (xy 249.387614 -114.014504)
			(xy 249.389392 -113.969546) (xy 249.389392 -113.969038) (xy 249.39117 -113.930176) (xy 249.391256 -113.924584)
			(xy 249.389325 -113.913569) (xy 249.38736 -113.908332) (xy 249.383042 -113.898172) (xy 249.37466 -113.890552)
			(xy 249.374152 -113.890298) (xy 249.3546 -113.87212) (xy 249.320261 -113.831242) (xy 249.291954 -113.785977)
			(xy 249.270233 -113.737209) (xy 249.25552 -113.685889) (xy 249.248103 -113.63302) (xy 249.24766 -113.606326)
			(xy 249.24766 -113.59896) (xy 249.247914 -113.585244) (xy 249.24131 -113.573306) (xy 249.237798 -113.567386)
			(xy 249.228132 -113.557594) (xy 249.22226 -113.554002) (xy 249.145298 -113.509552) (xy 249.139303 -113.506386)
			(xy 249.126169 -113.503045) (xy 249.11939 -113.502948) (xy 249.105674 -113.502948) (xy 249.093736 -113.51006)
			(xy 249.071383 -113.52301) (xy 249.02393 -113.543428) (xy 248.974155 -113.557252) (xy 248.92297 -113.564231)
			(xy 248.89714 -113.56467) (xy 248.86989 -113.56421) (xy 248.815943 -113.556459) (xy 248.763649 -113.54111)
			(xy 248.714071 -113.518475) (xy 248.66822 -113.489015) (xy 248.627027 -113.453329) (xy 248.591333 -113.412144)
			(xy 248.561863 -113.366298) (xy 248.539218 -113.316725) (xy 248.523858 -113.264434) (xy 248.516096 -113.210489)
			(xy 248.51609 -113.155989) (xy 248.523841 -113.102043) (xy 248.53919 -113.049748) (xy 248.561825 -113.000171)
			(xy 248.591286 -112.954319) (xy 248.626972 -112.913127) (xy 248.668157 -112.877433) (xy 248.714002 -112.847963)
			(xy 248.763575 -112.825318) (xy 248.815866 -112.809958) (xy 248.869811 -112.802196) (xy 248.924312 -112.80219)
			(xy 248.978258 -112.809941) (xy 249.030552 -112.82529) (xy 249.08013 -112.847926) (xy 249.125981 -112.877386)
			(xy 249.167174 -112.913072) (xy 249.202868 -112.954257) (xy 249.232337 -113.000103) (xy 249.254983 -113.049676)
			(xy 249.270342 -113.101967) (xy 249.278104 -113.155912) (xy 249.278648 -113.183162) (xy 249.278648 -113.190528)
			(xy 249.278394 -113.204244) (xy 249.284998 -113.216182) (xy 249.288509 -113.222103) (xy 249.298175 -113.231896)
			(xy 249.304048 -113.235486) (xy 249.38101 -113.279936) (xy 249.387005 -113.283101) (xy 249.400139 -113.286442)
			(xy 249.406918 -113.28654) (xy 249.420634 -113.28654) (xy 249.432572 -113.279428) (xy 249.454925 -113.266479)
			(xy 249.502378 -113.246063) (xy 249.552153 -113.23224) (xy 249.603339 -113.225262) (xy 249.629168 -113.224818)
			(xy 249.656422 -113.225279) (xy 249.710375 -113.233033) (xy 249.762675 -113.248386) (xy 249.812257 -113.271027)
			(xy 249.858113 -113.300495) (xy 249.899307 -113.336189) (xy 249.935002 -113.377383) (xy 249.96447 -113.423237)
			(xy 249.987112 -113.47282) (xy 250.002466 -113.525119) (xy 250.01022 -113.579072) (xy 250.010676 -113.606326)
			(xy 250.010137 -113.635634) (xy 250.001162 -113.693558) (xy 249.983428 -113.749426) (xy 249.968211 -113.780062)
			(xy 281.681426 -113.780062) (xy 281.685497 -113.72444) (xy 281.697623 -113.670003) (xy 281.717546 -113.617912)
			(xy 281.744842 -113.569277) (xy 281.778928 -113.525134) (xy 281.819077 -113.486425) (xy 281.864435 -113.453974)
			(xy 281.914035 -113.428473) (xy 281.966819 -113.410466) (xy 282.021662 -113.400336) (xy 282.077396 -113.398299)
			(xy 282.132833 -113.404399) (xy 282.18679 -113.418505) (xy 282.238119 -113.440317) (xy 282.285725 -113.469371)
			(xy 282.328593 -113.505046) (xy 282.36581 -113.546583) (xy 282.396583 -113.593096) (xy 282.420255 -113.643593)
			(xy 282.436323 -113.697) (xy 282.444443 -113.752176) (xy 282.444952 -113.780062) (xy 282.444443 -113.807948)
			(xy 282.436323 -113.863124) (xy 282.420255 -113.916531) (xy 282.396583 -113.967028) (xy 282.36581 -114.013541)
			(xy 282.328593 -114.055078) (xy 282.285725 -114.090753) (xy 282.238119 -114.119807) (xy 282.18679 -114.141619)
			(xy 282.132833 -114.155725) (xy 282.077396 -114.161825) (xy 282.021662 -114.159788) (xy 281.966819 -114.149658)
			(xy 281.914035 -114.131651) (xy 281.864435 -114.10615) (xy 281.819077 -114.073699) (xy 281.778928 -114.03499)
			(xy 281.744842 -113.990847) (xy 281.717546 -113.942212) (xy 281.697623 -113.890121) (xy 281.685497 -113.835684)
			(xy 281.681426 -113.780062) (xy 249.968211 -113.780062) (xy 249.957353 -113.801922) (xy 249.92355 -113.849809)
			(xy 249.882817 -113.891959) (xy 249.8598 -113.91011) (xy 249.859292 -113.910618) (xy 249.859038 -113.910618)
			(xy 249.854842 -113.914044) (xy 249.847925 -113.922377) (xy 249.845322 -113.927128) (xy 249.845322 -113.927382)
			(xy 249.842834 -113.93238) (xy 249.839895 -113.943149) (xy 249.83948 -113.948718) (xy 249.837702 -113.988088)
			(xy 249.836178 -114.027458) (xy 249.836067 -114.032991) (xy 249.837993 -114.043886) (xy 249.839988 -114.049048)
			(xy 249.844306 -114.059208) (xy 249.852688 -114.066828) (xy 249.853196 -114.067082) (xy 249.872752 -114.085259)
			(xy 249.907097 -114.126134) (xy 249.93541 -114.171398) (xy 249.957137 -114.220167) (xy 249.971855 -114.271488)
			(xy 249.979275 -114.324359) (xy 249.979688 -114.351054) (xy 249.979688 -114.35207) (xy 249.979527 -114.367572)
			(xy 249.976984 -114.398472) (xy 249.974608 -114.413792) (xy 249.97283 -114.425222) (xy 249.97537 -114.434874)
			(xy 249.976989 -114.440229) (xy 249.982244 -114.450101) (xy 249.985784 -114.454432) (xy 250.02109 -114.496342)
			(xy 250.036076 -114.513868) (xy 250.043619 -114.521955) (xy 250.063641 -114.531286) (xy 250.074684 -114.531902)
			(xy 266.465304 -114.531902) (xy 266.475113 -114.5314) (xy 266.493269 -114.523951) (xy 266.50061 -114.517424)
			(xy 266.507722 -114.510566) (xy 266.51585 -114.492024) (xy 266.51585 -114.481864) (xy 266.51699 -114.453736)
			(xy 266.526518 -114.398255) (xy 266.544093 -114.344775) (xy 266.569335 -114.294458) (xy 266.601695 -114.248395)
			(xy 266.64047 -114.207586) (xy 266.684821 -114.172916) (xy 266.733783 -114.145138) (xy 266.786295 -114.124855)
			(xy 266.841218 -114.112506) (xy 266.897358 -114.108359) (xy 266.953498 -114.112506) (xy 267.008421 -114.124855)
			(xy 267.060933 -114.145138) (xy 267.109895 -114.172916) (xy 267.154246 -114.207586) (xy 267.193021 -114.248395)
			(xy 267.225381 -114.294458) (xy 267.250623 -114.344775) (xy 267.268198 -114.398255) (xy 267.277726 -114.453736)
			(xy 267.278866 -114.481864) (xy 267.278866 -114.492024) (xy 267.286994 -114.510566) (xy 267.294106 -114.517424)
			(xy 267.301435 -114.523966) (xy 267.319599 -114.5314) (xy 267.329412 -114.531902) (xy 296.43324 -114.531902)
			(xy 296.433494 -114.531902) (xy 296.44527 -114.53123) (xy 296.466309 -114.520629) (xy 296.47388 -114.511582)
			(xy 296.522648 -114.44224) (xy 296.526027 -114.437183) (xy 296.530514 -114.425883) (xy 296.531538 -114.419888)
			(xy 296.533062 -114.40795) (xy 296.528744 -114.396012) (xy 296.518433 -114.365083) (xy 296.507328 -114.300845)
			(xy 296.506646 -114.26825) (xy 296.506646 -114.267742) (xy 296.507132 -114.240491) (xy 296.514888 -114.186543)
			(xy 296.530243 -114.134248) (xy 296.552885 -114.084671) (xy 296.582351 -114.038821) (xy 296.618042 -113.99763)
			(xy 296.659233 -113.961939) (xy 296.705083 -113.932473) (xy 296.75466 -113.909831) (xy 296.806955 -113.894476)
			(xy 296.860903 -113.88672) (xy 296.915405 -113.88672) (xy 296.969353 -113.894476) (xy 297.021648 -113.909831)
			(xy 297.071225 -113.932473) (xy 297.117075 -113.961939) (xy 297.158266 -113.99763) (xy 297.193957 -114.038821)
			(xy 297.223423 -114.084671) (xy 297.246065 -114.134248) (xy 297.26142 -114.186543) (xy 297.269176 -114.240491)
			(xy 297.269662 -114.267742) (xy 297.269662 -114.26825) (xy 297.268972 -114.300844) (xy 297.257855 -114.365078)
			(xy 297.247564 -114.396012) (xy 297.247564 -114.396266) (xy 297.245628 -114.402092) (xy 297.244331 -114.414297)
			(xy 297.245024 -114.420396) (xy 297.246548 -114.43208) (xy 297.302428 -114.511582) (xy 297.30998 -114.520651)
			(xy 297.331031 -114.531256) (xy 297.342814 -114.531902) (xy 298.461176 -114.531902) (xy 298.469627 -114.531547)
			(xy 298.485585 -114.525965) (xy 298.492418 -114.52098) (xy 298.49953 -114.515646) (xy 298.50842 -114.501422)
			(xy 298.510452 -114.492786) (xy 298.517539 -114.465343) (xy 298.538718 -114.412771) (xy 298.567441 -114.363911)
			(xy 298.603076 -114.319837) (xy 298.644838 -114.28152) (xy 298.69181 -114.249803) (xy 298.742957 -114.225384)
			(xy 298.797154 -114.208799) (xy 298.853207 -114.200415) (xy 298.909885 -114.200415) (xy 298.965938 -114.208799)
			(xy 299.020135 -114.225384) (xy 299.071282 -114.249803) (xy 299.118254 -114.28152) (xy 299.160016 -114.319837)
			(xy 299.195651 -114.363911) (xy 299.224374 -114.412771) (xy 299.245553 -114.465343) (xy 299.25264 -114.492786)
			(xy 299.25494 -114.501028) (xy 299.264158 -114.515433) (xy 299.270674 -114.52098) (xy 299.277532 -114.526314)
			(xy 299.29328 -114.531902) (xy 299.462698 -114.531902) (xy 299.470429 -114.531634) (xy 299.485172 -114.526979)
			(xy 299.491654 -114.522758) (xy 299.498004 -114.518694) (xy 299.507148 -114.506756) (xy 299.510196 -114.499136)
			(xy 299.520305 -114.473999) (xy 299.546599 -114.426629) (xy 299.579324 -114.383451) (xy 299.617824 -114.345332)
			(xy 299.661326 -114.313038) (xy 299.708955 -114.287217) (xy 299.759756 -114.268387) (xy 299.812709 -114.256927)
			(xy 299.86675 -114.253068) (xy 299.920794 -114.256885) (xy 299.973755 -114.268303) (xy 300.024571 -114.287093)
			(xy 300.072221 -114.312876) (xy 300.115748 -114.345136) (xy 300.154278 -114.383225) (xy 300.187037 -114.426377)
			(xy 300.213368 -114.473727) (xy 300.223428 -114.498882) (xy 300.223428 -114.49939) (xy 300.223682 -114.499644)
			(xy 300.226641 -114.50659) (xy 300.235932 -114.51848) (xy 300.24197 -114.523012) (xy 300.248574 -114.52733)
			(xy 300.262798 -114.531902) (xy 302.479964 -114.531902) (xy 302.482504 -114.531902) (xy 302.493451 -114.530831)
			(xy 302.51295 -114.520703) (xy 302.520096 -114.512344) (xy 302.520858 -114.511328) (xy 302.569372 -114.445796)
			(xy 302.57273 -114.440917) (xy 302.577349 -114.430013) (xy 302.578516 -114.424206) (xy 302.580548 -114.412522)
			(xy 302.577246 -114.400838) (xy 302.569549 -114.373801) (xy 302.561262 -114.318201) (xy 302.560736 -114.290094)
			(xy 302.561222 -114.262843) (xy 302.568978 -114.208895) (xy 302.584333 -114.1566) (xy 302.606975 -114.107023)
			(xy 302.636441 -114.061173) (xy 302.672132 -114.019982) (xy 302.713323 -113.984291) (xy 302.759173 -113.954825)
			(xy 302.80875 -113.932183) (xy 302.861045 -113.916828) (xy 302.914993 -113.909072) (xy 302.969495 -113.909072)
			(xy 303.023443 -113.916828) (xy 303.075738 -113.932183) (xy 303.125315 -113.954825) (xy 303.171165 -113.984291)
			(xy 303.212356 -114.019982) (xy 303.248047 -114.061173) (xy 303.277513 -114.107023) (xy 303.300155 -114.1566)
			(xy 303.31551 -114.208895) (xy 303.323266 -114.262843) (xy 303.323752 -114.290094) (xy 303.323236 -114.318202)
			(xy 303.314953 -114.373804) (xy 303.307242 -114.400838) (xy 303.30394 -114.412522) (xy 303.305972 -114.424206)
			(xy 303.307106 -114.430023) (xy 303.311728 -114.440933) (xy 303.315116 -114.445796) (xy 303.36363 -114.511328)
			(xy 303.364392 -114.512344) (xy 303.371558 -114.52068) (xy 303.391045 -114.530806) (xy 303.401984 -114.531902)
			(xy 304.145696 -114.531902) (xy 304.150107 -114.531818) (xy 304.158797 -114.530292) (xy 304.162968 -114.528854)
			(xy 304.186844 -114.520218) (xy 304.193194 -114.514884) (xy 304.215907 -114.497312) (xy 304.265562 -114.468473)
			(xy 304.318978 -114.447395) (xy 304.374947 -114.434556) (xy 304.432208 -114.430244) (xy 304.489469 -114.434556)
			(xy 304.545438 -114.447395) (xy 304.598854 -114.468473) (xy 304.648509 -114.497312) (xy 304.671222 -114.514884)
			(xy 304.677572 -114.520218) (xy 304.701448 -114.528854) (xy 304.705627 -114.530263) (xy 304.714311 -114.531795)
			(xy 304.71872 -114.531902) (xy 306.331112 -114.531902) (xy 306.337264 -114.531728) (xy 306.349206 -114.528767)
			(xy 306.354734 -114.52606) (xy 306.385214 -114.510058) (xy 306.386738 -114.508026) (xy 306.402089 -114.486725)
			(xy 306.437701 -114.448144) (xy 306.478269 -114.414814) (xy 306.523026 -114.387363) (xy 306.571125 -114.366312)
			(xy 306.621658 -114.352059) (xy 306.673668 -114.344873) (xy 306.69992 -114.34445) (xy 306.727289 -114.344923)
			(xy 306.781465 -114.352751) (xy 306.833966 -114.368241) (xy 306.883714 -114.391078) (xy 306.929686 -114.420791)
			(xy 306.950618 -114.43843) (xy 306.95773 -114.444526) (xy 306.966112 -114.447574) (xy 306.9704 -114.449094)
			(xy 306.979344 -114.450753) (xy 306.983892 -114.450876) (xy 307.050948 -114.450876) (xy 307.055496 -114.450754)
			(xy 307.064441 -114.449097) (xy 307.068728 -114.447574) (xy 307.07711 -114.444526) (xy 307.084222 -114.43843)
			(xy 307.105153 -114.420788) (xy 307.15112 -114.391062) (xy 307.200866 -114.36822) (xy 307.25337 -114.352732)
			(xy 307.30755 -114.344916) (xy 307.33492 -114.34445) (xy 307.347658 -114.344529) (xy 307.373079 -114.346184)
			(xy 307.38572 -114.347752) (xy 307.411074 -114.351585) (xy 307.46052 -114.365164) (xy 307.507706 -114.385233)
			(xy 307.551785 -114.411431) (xy 307.591965 -114.443288) (xy 307.627525 -114.480231) (xy 307.643022 -114.50066)
			(xy 307.646324 -114.505232) (xy 307.65496 -114.512852) (xy 307.680106 -114.52606) (xy 307.685692 -114.528792)
			(xy 307.697766 -114.531744) (xy 307.703982 -114.531902) (xy 313.072272 -114.531902) (xy 313.082336 -114.532338)
			(xy 313.100922 -114.540071) (xy 313.10834 -114.546888) (xy 313.288172 -114.72672) (xy 313.295571 -114.733564)
			(xy 313.31417 -114.741285) (xy 313.32424 -114.741706) (xy 322.958714 -114.741706) (xy 322.968425 -114.741273)
			(xy 322.986454 -114.734048) (xy 323.000505 -114.720638) (xy 323.004942 -114.711988) (xy 323.049646 -114.614198)
			(xy 323.045582 -114.584988) (xy 323.035676 -114.573558) (xy 323.018087 -114.552631) (xy 322.988454 -114.506692)
			(xy 322.965681 -114.456994) (xy 322.950235 -114.404554) (xy 322.942431 -114.350447) (xy 322.94195 -114.323114)
			(xy 322.942511 -114.293573) (xy 322.951633 -114.235199) (xy 322.969648 -114.178929) (xy 322.996123 -114.126111)
			(xy 323.030425 -114.078005) (xy 323.071735 -114.035765) (xy 323.119063 -114.000398) (xy 323.144896 -113.986056)
			(xy 323.155564 -113.980214) (xy 323.16928 -113.961164) (xy 323.18579 -113.856516) (xy 323.178424 -113.833656)
			(xy 323.170042 -113.825274) (xy 323.162606 -113.817556) (xy 323.148501 -113.801418) (xy 323.141848 -113.793016)
			(xy 323.134261 -113.784179) (xy 323.11335 -113.773982) (xy 323.101716 -113.773458) (xy 323.02196 -113.773458)
			(xy 323.010332 -113.774021) (xy 322.989418 -113.784192) (xy 322.981828 -113.793016) (xy 322.963637 -113.815499)
			(xy 322.921619 -113.855234) (xy 322.874084 -113.888171) (xy 322.822122 -113.913556) (xy 322.766923 -113.930806)
			(xy 322.709754 -113.939526) (xy 322.680838 -113.940082) (xy 322.646612 -113.939343) (xy 322.579268 -113.927075)
			(xy 322.54698 -113.915698) (xy 322.538798 -113.912994) (xy 322.52158 -113.912655) (xy 322.505231 -113.918064)
			(xy 322.498212 -113.923064) (xy 322.419218 -113.983516) (xy 322.408804 -114.007646) (xy 322.410074 -114.0206)
			(xy 322.411852 -114.05743) (xy 322.411387 -114.084686) (xy 322.403625 -114.138643) (xy 322.388262 -114.190946)
			(xy 322.365613 -114.240531) (xy 322.336138 -114.286387) (xy 322.300436 -114.327582) (xy 322.259235 -114.363276)
			(xy 322.213374 -114.392744) (xy 322.163786 -114.415385) (xy 322.11148 -114.430738) (xy 322.057522 -114.438492)
			(xy 322.003009 -114.438487) (xy 321.949052 -114.430724) (xy 321.896749 -114.415361) (xy 321.847165 -114.392711)
			(xy 321.801309 -114.363235) (xy 321.760115 -114.327533) (xy 321.724421 -114.286332) (xy 321.694954 -114.24047)
			(xy 321.672313 -114.190881) (xy 321.656961 -114.138575) (xy 321.649208 -114.084617) (xy 321.649214 -114.030104)
			(xy 321.656977 -113.976148) (xy 321.672341 -113.923845) (xy 321.694991 -113.874261) (xy 321.724468 -113.828405)
			(xy 321.760171 -113.787212) (xy 321.801372 -113.751518) (xy 321.847234 -113.722051) (xy 321.896823 -113.699412)
			(xy 321.949129 -113.68406) (xy 322.003088 -113.676308) (xy 322.030344 -113.675922) (xy 322.06457 -113.676659)
			(xy 322.131915 -113.688924) (xy 322.164202 -113.700306) (xy 322.172385 -113.703013) (xy 322.189605 -113.703357)
			(xy 322.20596 -113.697953) (xy 322.21297 -113.69294) (xy 322.291964 -113.632488) (xy 322.302378 -113.608358)
			(xy 322.301108 -113.595404) (xy 322.29933 -113.558574) (xy 322.299795 -113.531323) (xy 322.307555 -113.477377)
			(xy 322.322914 -113.425085) (xy 322.345558 -113.37551) (xy 322.375028 -113.329663) (xy 322.410722 -113.288477)
			(xy 322.451914 -113.252789) (xy 322.497767 -113.223328) (xy 322.547345 -113.200692) (xy 322.59964 -113.185342)
			(xy 322.653587 -113.177591) (xy 322.680838 -113.177066) (xy 322.709753 -113.177603) (xy 322.766919 -113.186336)
			(xy 322.822113 -113.203596) (xy 322.87407 -113.228988) (xy 322.921599 -113.261931) (xy 322.963613 -113.301669)
			(xy 322.981828 -113.324132) (xy 322.989417 -113.332966) (xy 323.010327 -113.343163) (xy 323.02196 -113.34369)
			(xy 323.101716 -113.34369) (xy 323.113334 -113.34311) (xy 323.134216 -113.332913) (xy 323.141848 -113.324132)
			(xy 323.160037 -113.301645) (xy 323.202053 -113.261903) (xy 323.249586 -113.228958) (xy 323.301549 -113.203567)
			(xy 323.356749 -113.186311) (xy 323.413921 -113.177586) (xy 323.442838 -113.177066) (xy 323.470088 -113.177554)
			(xy 323.524033 -113.185315) (xy 323.576325 -113.200673) (xy 323.625899 -113.223316) (xy 323.671746 -113.252783)
			(xy 323.712934 -113.288474) (xy 323.748624 -113.329663) (xy 323.77809 -113.375512) (xy 323.800731 -113.425086)
			(xy 323.816087 -113.477379) (xy 323.823847 -113.531324) (xy 323.824346 -113.558574) (xy 323.823786 -113.588116)
			(xy 323.814665 -113.646491) (xy 323.796652 -113.702761) (xy 323.770177 -113.755581) (xy 323.735875 -113.803688)
			(xy 323.694566 -113.84593) (xy 323.647237 -113.881297) (xy 323.6214 -113.895632) (xy 323.610732 -113.901474)
			(xy 323.597016 -113.920524) (xy 323.580506 -114.025172) (xy 323.587872 -114.048032) (xy 323.596254 -114.056414)
			(xy 323.60369 -114.064131) (xy 323.617796 -114.080269) (xy 323.624448 -114.088672) (xy 323.632034 -114.097511)
			(xy 323.652945 -114.107713) (xy 323.66458 -114.10823) (xy 323.744336 -114.10823) (xy 323.755964 -114.107667)
			(xy 323.776877 -114.097496) (xy 323.784468 -114.088672) (xy 323.802659 -114.06619) (xy 323.844678 -114.026455)
			(xy 323.892213 -113.993518) (xy 323.944175 -113.968134) (xy 323.999373 -113.950884) (xy 324.056543 -113.942164)
			(xy 324.085458 -113.941606) (xy 324.112704 -113.942067) (xy 324.166641 -113.94982) (xy 324.218925 -113.965175)
			(xy 324.268489 -113.987818) (xy 324.314324 -114.017288) (xy 324.355495 -114.052985) (xy 324.391165 -114.09418)
			(xy 324.40626 -114.116866) (xy 324.411147 -114.123849) (xy 324.424559 -114.134352) (xy 324.440668 -114.139894)
			(xy 324.449186 -114.140234) (xy 324.53453 -114.140234) (xy 324.543064 -114.139967) (xy 324.55921 -114.134448)
			(xy 324.572628 -114.123906) (xy 324.577456 -114.116866) (xy 324.592567 -114.094191) (xy 324.628237 -114.053)
			(xy 324.669408 -114.017305) (xy 324.71524 -113.987834) (xy 324.7648 -113.965188) (xy 324.81708 -113.949827)
			(xy 324.871013 -113.942065) (xy 324.898258 -113.941606) (xy 324.929041 -113.942192) (xy 324.989808 -113.952076)
			(xy 325.048198 -113.971596) (xy 325.102693 -114.000243) (xy 325.12762 -114.018314) (xy 325.137526 -114.02568)
			(xy 325.16191 -114.029744) (xy 325.265034 -113.995962) (xy 325.282306 -113.978182) (xy 325.285862 -113.966244)
			(xy 325.293608 -113.94188) (xy 325.314716 -113.895316) (xy 325.341849 -113.851985) (xy 325.37452 -113.812661)
			(xy 325.39305 -113.795048) (xy 325.400506 -113.787559) (xy 325.409062 -113.768264) (xy 325.40956 -113.75771)
			(xy 325.40956 -113.683034) (xy 325.408975 -113.672499) (xy 325.400444 -113.653224) (xy 325.39305 -113.645696)
			(xy 325.373992 -113.627542) (xy 325.340541 -113.586906) (xy 325.312982 -113.542065) (xy 325.291837 -113.493865)
			(xy 325.277506 -113.443221) (xy 325.27026 -113.391088) (xy 325.26986 -113.364772) (xy 325.270346 -113.337521)
			(xy 325.278102 -113.283573) (xy 325.293457 -113.231278) (xy 325.316099 -113.181701) (xy 325.345565 -113.135851)
			(xy 325.381256 -113.09466) (xy 325.422447 -113.058969) (xy 325.468297 -113.029503) (xy 325.517874 -113.006861)
			(xy 325.570169 -112.991506) (xy 325.624117 -112.98375) (xy 325.678619 -112.98375) (xy 325.732567 -112.991506)
			(xy 325.784862 -113.006861) (xy 325.834439 -113.029503) (xy 325.880289 -113.058969) (xy 325.92148 -113.09466)
			(xy 325.957171 -113.135851) (xy 325.986637 -113.181701) (xy 326.009279 -113.231278) (xy 326.024634 -113.283573)
			(xy 326.03239 -113.337521) (xy 326.032876 -113.364772) (xy 326.032437 -113.391088) (xy 326.025211 -113.443221)
			(xy 326.010892 -113.493867) (xy 325.989753 -113.542066) (xy 325.962192 -113.586905) (xy 325.928734 -113.627533)
			(xy 325.909686 -113.645696) (xy 325.902245 -113.653191) (xy 325.893717 -113.672486) (xy 325.893176 -113.683034)
			(xy 325.893176 -113.75771) (xy 325.893749 -113.768252) (xy 325.902257 -113.78755) (xy 325.909686 -113.795048)
			(xy 325.92874 -113.813204) (xy 325.962184 -113.853842) (xy 325.989735 -113.898684) (xy 326.010872 -113.946884)
			(xy 326.025196 -113.997527) (xy 326.032435 -114.049657) (xy 326.032876 -114.075972) (xy 327.30186 -114.075972)
			(xy 327.30229 -114.049657) (xy 327.309529 -113.997526) (xy 327.323855 -113.946881) (xy 327.344994 -113.898682)
			(xy 327.372548 -113.85384) (xy 327.405994 -113.813203) (xy 327.42505 -113.795048) (xy 327.432469 -113.787541)
			(xy 327.440985 -113.76825) (xy 327.44156 -113.75771) (xy 327.44156 -113.683034) (xy 327.441038 -113.672483)
			(xy 327.432499 -113.653187) (xy 327.42505 -113.645696) (xy 327.40599 -113.627545) (xy 327.372535 -113.586913)
			(xy 327.344978 -113.542072) (xy 327.323841 -113.49387) (xy 327.309524 -113.443222) (xy 327.302299 -113.391088)
			(xy 327.30186 -113.364772) (xy 327.302346 -113.337521) (xy 327.310102 -113.283573) (xy 327.325457 -113.231278)
			(xy 327.348099 -113.181701) (xy 327.377565 -113.135851) (xy 327.413256 -113.09466) (xy 327.454447 -113.058969)
			(xy 327.500297 -113.029503) (xy 327.549874 -113.006861) (xy 327.602169 -112.991506) (xy 327.656117 -112.98375)
			(xy 327.710619 -112.98375) (xy 327.764567 -112.991506) (xy 327.816862 -113.006861) (xy 327.866439 -113.029503)
			(xy 327.912289 -113.058969) (xy 327.95348 -113.09466) (xy 327.989171 -113.135851) (xy 328.018637 -113.181701)
			(xy 328.041279 -113.231278) (xy 328.056634 -113.283573) (xy 328.06439 -113.337521) (xy 328.064876 -113.364772)
			(xy 328.064464 -113.391088) (xy 328.057219 -113.443219) (xy 328.04289 -113.493863) (xy 328.021747 -113.542062)
			(xy 328.005357 -113.568734) (xy 343.089736 -113.568734) (xy 343.093807 -113.513112) (xy 343.105933 -113.458675)
			(xy 343.125856 -113.406584) (xy 343.153152 -113.357949) (xy 343.187238 -113.313806) (xy 343.227387 -113.275097)
			(xy 343.272745 -113.242646) (xy 343.322345 -113.217145) (xy 343.375129 -113.199138) (xy 343.429972 -113.189008)
			(xy 343.485706 -113.186971) (xy 343.541143 -113.193071) (xy 343.5951 -113.207177) (xy 343.646429 -113.228989)
			(xy 343.694035 -113.258043) (xy 343.736903 -113.293718) (xy 343.77412 -113.335255) (xy 343.804893 -113.381768)
			(xy 343.828565 -113.432265) (xy 343.844633 -113.485672) (xy 343.852753 -113.540848) (xy 343.853169 -113.563654)
			(xy 345.14739 -113.563654) (xy 345.151461 -113.508032) (xy 345.163587 -113.453595) (xy 345.18351 -113.401504)
			(xy 345.210806 -113.352869) (xy 345.244892 -113.308726) (xy 345.285041 -113.270017) (xy 345.330399 -113.237566)
			(xy 345.379999 -113.212065) (xy 345.432783 -113.194058) (xy 345.487626 -113.183928) (xy 345.54336 -113.181891)
			(xy 345.598797 -113.187991) (xy 345.652754 -113.202097) (xy 345.704083 -113.223909) (xy 345.751689 -113.252963)
			(xy 345.794557 -113.288638) (xy 345.831774 -113.330175) (xy 345.860377 -113.373408) (xy 361.363766 -113.373408)
			(xy 361.367837 -113.317786) (xy 361.379963 -113.263349) (xy 361.399886 -113.211258) (xy 361.427182 -113.162623)
			(xy 361.461268 -113.11848) (xy 361.501417 -113.079771) (xy 361.546775 -113.04732) (xy 361.596375 -113.021819)
			(xy 361.649159 -113.003812) (xy 361.704002 -112.993682) (xy 361.759736 -112.991645) (xy 361.815173 -112.997745)
			(xy 361.86913 -113.011851) (xy 361.920459 -113.033663) (xy 361.968065 -113.062717) (xy 362.010933 -113.098392)
			(xy 362.04815 -113.139929) (xy 362.078923 -113.186442) (xy 362.102595 -113.236939) (xy 362.118663 -113.290346)
			(xy 362.126783 -113.345522) (xy 362.127292 -113.373408) (xy 362.126783 -113.401294) (xy 362.118663 -113.45647)
			(xy 362.102595 -113.509877) (xy 362.078923 -113.560374) (xy 362.04815 -113.606887) (xy 362.010933 -113.648424)
			(xy 361.968065 -113.684099) (xy 361.920459 -113.713153) (xy 361.86913 -113.734965) (xy 361.815173 -113.749071)
			(xy 361.759736 -113.755171) (xy 361.704002 -113.753134) (xy 361.649159 -113.743004) (xy 361.596375 -113.724997)
			(xy 361.546775 -113.699496) (xy 361.501417 -113.667045) (xy 361.461268 -113.628336) (xy 361.427182 -113.584193)
			(xy 361.399886 -113.535558) (xy 361.379963 -113.483467) (xy 361.367837 -113.42903) (xy 361.363766 -113.373408)
			(xy 345.860377 -113.373408) (xy 345.862547 -113.376688) (xy 345.886219 -113.427185) (xy 345.902287 -113.480592)
			(xy 345.910407 -113.535768) (xy 345.910916 -113.563654) (xy 345.910407 -113.59154) (xy 345.902287 -113.646716)
			(xy 345.886219 -113.700123) (xy 345.862547 -113.75062) (xy 345.831774 -113.797133) (xy 345.794557 -113.83867)
			(xy 345.751689 -113.874345) (xy 345.704083 -113.903399) (xy 345.687693 -113.910364) (xy 358.253282 -113.910364)
			(xy 358.257353 -113.854742) (xy 358.269479 -113.800305) (xy 358.289402 -113.748214) (xy 358.316698 -113.699579)
			(xy 358.350784 -113.655436) (xy 358.390933 -113.616727) (xy 358.436291 -113.584276) (xy 358.485891 -113.558775)
			(xy 358.538675 -113.540768) (xy 358.593518 -113.530638) (xy 358.649252 -113.528601) (xy 358.704689 -113.534701)
			(xy 358.758646 -113.548807) (xy 358.809975 -113.570619) (xy 358.857581 -113.599673) (xy 358.900449 -113.635348)
			(xy 358.937666 -113.676885) (xy 358.968439 -113.723398) (xy 358.992111 -113.773895) (xy 359.008179 -113.827302)
			(xy 359.016299 -113.882478) (xy 359.01659 -113.898426) (xy 359.753406 -113.898426) (xy 359.757477 -113.842804)
			(xy 359.769603 -113.788367) (xy 359.789526 -113.736276) (xy 359.816822 -113.687641) (xy 359.850908 -113.643498)
			(xy 359.891057 -113.604789) (xy 359.936415 -113.572338) (xy 359.986015 -113.546837) (xy 360.038799 -113.52883)
			(xy 360.093642 -113.5187) (xy 360.149376 -113.516663) (xy 360.204813 -113.522763) (xy 360.25877 -113.536869)
			(xy 360.310099 -113.558681) (xy 360.357705 -113.587735) (xy 360.400573 -113.62341) (xy 360.43779 -113.664947)
			(xy 360.468563 -113.71146) (xy 360.492235 -113.761957) (xy 360.508303 -113.815364) (xy 360.516423 -113.87054)
			(xy 360.516932 -113.898426) (xy 360.516423 -113.926312) (xy 360.508303 -113.981488) (xy 360.492235 -114.034895)
			(xy 360.468563 -114.085392) (xy 360.43779 -114.131905) (xy 360.400573 -114.173442) (xy 360.357705 -114.209117)
			(xy 360.310099 -114.238171) (xy 360.25877 -114.259983) (xy 360.204813 -114.274089) (xy 360.149376 -114.280189)
			(xy 360.093642 -114.278152) (xy 360.038799 -114.268022) (xy 359.986015 -114.250015) (xy 359.936415 -114.224514)
			(xy 359.891057 -114.192063) (xy 359.850908 -114.153354) (xy 359.816822 -114.109211) (xy 359.789526 -114.060576)
			(xy 359.769603 -114.008485) (xy 359.757477 -113.954048) (xy 359.753406 -113.898426) (xy 359.01659 -113.898426)
			(xy 359.016808 -113.910364) (xy 359.016299 -113.93825) (xy 359.008179 -113.993426) (xy 358.992111 -114.046833)
			(xy 358.968439 -114.09733) (xy 358.937666 -114.143843) (xy 358.900449 -114.18538) (xy 358.857581 -114.221055)
			(xy 358.809975 -114.250109) (xy 358.758646 -114.271921) (xy 358.704689 -114.286027) (xy 358.649252 -114.292127)
			(xy 358.593518 -114.29009) (xy 358.538675 -114.27996) (xy 358.485891 -114.261953) (xy 358.436291 -114.236452)
			(xy 358.390933 -114.204001) (xy 358.350784 -114.165292) (xy 358.316698 -114.121149) (xy 358.289402 -114.072514)
			(xy 358.269479 -114.020423) (xy 358.257353 -113.965986) (xy 358.253282 -113.910364) (xy 345.687693 -113.910364)
			(xy 345.652754 -113.925211) (xy 345.598797 -113.939317) (xy 345.54336 -113.945417) (xy 345.487626 -113.94338)
			(xy 345.432783 -113.93325) (xy 345.379999 -113.915243) (xy 345.330399 -113.889742) (xy 345.285041 -113.857291)
			(xy 345.244892 -113.818582) (xy 345.210806 -113.774439) (xy 345.18351 -113.725804) (xy 345.163587 -113.673713)
			(xy 345.151461 -113.619276) (xy 345.14739 -113.563654) (xy 343.853169 -113.563654) (xy 343.853262 -113.568734)
			(xy 343.852753 -113.59662) (xy 343.844633 -113.651796) (xy 343.828565 -113.705203) (xy 343.804893 -113.7557)
			(xy 343.77412 -113.802213) (xy 343.736903 -113.84375) (xy 343.694035 -113.879425) (xy 343.646429 -113.908479)
			(xy 343.5951 -113.930291) (xy 343.541143 -113.944397) (xy 343.485706 -113.950497) (xy 343.429972 -113.94846)
			(xy 343.375129 -113.93833) (xy 343.322345 -113.920323) (xy 343.272745 -113.894822) (xy 343.227387 -113.862371)
			(xy 343.187238 -113.823662) (xy 343.153152 -113.779519) (xy 343.125856 -113.730884) (xy 343.105933 -113.678793)
			(xy 343.093807 -113.624356) (xy 343.089736 -113.568734) (xy 328.005357 -113.568734) (xy 327.994191 -113.586904)
			(xy 327.960742 -113.627541) (xy 327.941686 -113.645696) (xy 327.934282 -113.653215) (xy 327.925759 -113.672497)
			(xy 327.925176 -113.683034) (xy 327.925176 -113.75771) (xy 327.925693 -113.768261) (xy 327.934238 -113.787556)
			(xy 327.941686 -113.795048) (xy 327.960755 -113.81319) (xy 327.994212 -113.853822) (xy 328.021769 -113.898665)
			(xy 328.042905 -113.946869) (xy 328.057219 -113.997519) (xy 328.06444 -114.049655) (xy 328.064876 -114.075972)
			(xy 328.06439 -114.103223) (xy 328.056634 -114.157171) (xy 328.041279 -114.209466) (xy 328.018637 -114.259043)
			(xy 327.989171 -114.304893) (xy 327.95348 -114.346084) (xy 327.912289 -114.381775) (xy 327.866439 -114.411241)
			(xy 327.816862 -114.433883) (xy 327.764567 -114.449238) (xy 327.710619 -114.456994) (xy 327.656117 -114.456994)
			(xy 327.602169 -114.449238) (xy 327.549874 -114.433883) (xy 327.500297 -114.411241) (xy 327.454447 -114.381775)
			(xy 327.413256 -114.346084) (xy 327.377565 -114.304893) (xy 327.348099 -114.259043) (xy 327.325457 -114.209466)
			(xy 327.310102 -114.157171) (xy 327.302346 -114.103223) (xy 327.30186 -114.075972) (xy 326.032876 -114.075972)
			(xy 326.032415 -114.103225) (xy 326.024661 -114.157178) (xy 326.009307 -114.209477) (xy 325.986665 -114.259059)
			(xy 325.957198 -114.304913) (xy 325.921503 -114.346106) (xy 325.88031 -114.3818) (xy 325.834455 -114.411267)
			(xy 325.784873 -114.433908) (xy 325.732574 -114.449261) (xy 325.678621 -114.457015) (xy 325.651368 -114.45748)
			(xy 325.620587 -114.456889) (xy 325.559825 -114.446993) (xy 325.501443 -114.427464) (xy 325.446957 -114.398808)
			(xy 325.422006 -114.380772) (xy 325.4121 -114.373406) (xy 325.387716 -114.369342) (xy 325.284592 -114.403124)
			(xy 325.26732 -114.420904) (xy 325.263764 -114.432842) (xy 325.255301 -114.459237) (xy 325.231817 -114.509445)
			(xy 325.201318 -114.555728) (xy 325.164447 -114.597115) (xy 325.121979 -114.632734) (xy 325.098664 -114.647726)
			(xy 325.087234 -114.654584) (xy 325.074534 -114.677444) (xy 325.074534 -114.690906) (xy 325.074955 -114.700924)
			(xy 325.082627 -114.719433) (xy 325.096801 -114.733595) (xy 325.115316 -114.741253) (xy 325.125334 -114.741706)
			(xy 325.254874 -114.741706) (xy 325.264938 -114.74127) (xy 325.283524 -114.733537) (xy 325.290942 -114.72672)
			(xy 325.310553 -114.707698) (xy 325.354238 -114.674891) (xy 325.402156 -114.648651) (xy 325.453327 -114.629515)
			(xy 325.506705 -114.617875) (xy 325.561198 -114.613968) (xy 325.615691 -114.617875) (xy 325.669069 -114.629515)
			(xy 325.72024 -114.648651) (xy 325.768158 -114.674891) (xy 325.811843 -114.707698) (xy 325.831454 -114.72672)
			(xy 325.838851 -114.733567) (xy 325.857451 -114.741294) (xy 325.867522 -114.741706) (xy 329.859894 -114.741706)
			(xy 329.868749 -114.74128) (xy 329.885376 -114.73517) (xy 329.892406 -114.729768) (xy 329.901804 -114.722148)
			(xy 329.910597 -114.714609) (xy 329.920787 -114.693838) (xy 329.921362 -114.68227) (xy 329.921362 -114.649758)
			(xy 329.920809 -114.638228) (xy 329.910751 -114.617477) (xy 329.902058 -114.60988) (xy 329.879821 -114.591698)
			(xy 329.840544 -114.549785) (xy 329.808 -114.502454) (xy 329.782924 -114.450777) (xy 329.765883 -114.395923)
			(xy 329.757265 -114.339134) (xy 329.75677 -114.310414) (xy 329.757256 -114.283163) (xy 329.765012 -114.229215)
			(xy 329.780367 -114.17692) (xy 329.803009 -114.127343) (xy 329.832475 -114.081493) (xy 329.868166 -114.040302)
			(xy 329.909357 -114.004611) (xy 329.955207 -113.975145) (xy 330.004784 -113.952503) (xy 330.057079 -113.937148)
			(xy 330.111027 -113.929392) (xy 330.165529 -113.929392) (xy 330.219477 -113.937148) (xy 330.271772 -113.952503)
			(xy 330.321349 -113.975145) (xy 330.367199 -114.004611) (xy 330.40839 -114.040302) (xy 330.444081 -114.081493)
			(xy 330.473547 -114.127343) (xy 330.496189 -114.17692) (xy 330.511544 -114.229215) (xy 330.5193 -114.283163)
			(xy 330.519786 -114.310414) (xy 330.519264 -114.339132) (xy 330.510647 -114.395919) (xy 330.49361 -114.450771)
			(xy 330.468538 -114.502447) (xy 330.435999 -114.549777) (xy 330.396729 -114.591692) (xy 330.374498 -114.60988)
			(xy 330.365781 -114.617456) (xy 330.355725 -114.638221) (xy 330.355194 -114.649758) (xy 330.355194 -114.68227)
			(xy 330.355817 -114.693823) (xy 330.366008 -114.714569) (xy 330.374752 -114.722148) (xy 330.38415 -114.729768)
			(xy 330.391144 -114.735232) (xy 330.407794 -114.741346) (xy 330.416662 -114.741706) (xy 332.398116 -114.741706)
			(xy 332.406969 -114.741276) (xy 332.423592 -114.735161) (xy 332.430628 -114.729768) (xy 332.440026 -114.722148)
			(xy 332.448816 -114.714608) (xy 332.459002 -114.693836) (xy 332.459584 -114.68227) (xy 332.459584 -114.649758)
			(xy 332.459032 -114.638227) (xy 332.448977 -114.617473) (xy 332.44028 -114.60988) (xy 332.418041 -114.591698)
			(xy 332.378763 -114.549786) (xy 332.346217 -114.502456) (xy 332.321139 -114.450779) (xy 332.304098 -114.395924)
			(xy 332.295478 -114.339134) (xy 332.294992 -114.310414) (xy 332.295478 -114.283163) (xy 332.303234 -114.229215)
			(xy 332.318589 -114.17692) (xy 332.341231 -114.127343) (xy 332.370697 -114.081493) (xy 332.406388 -114.040302)
			(xy 332.447579 -114.004611) (xy 332.493429 -113.975145) (xy 332.543006 -113.952503) (xy 332.595301 -113.937148)
			(xy 332.649249 -113.929392) (xy 332.703751 -113.929392) (xy 332.757699 -113.937148) (xy 332.809994 -113.952503)
			(xy 332.859571 -113.975145) (xy 332.905421 -114.004611) (xy 332.932961 -114.028474) (xy 337.205064 -114.028474)
			(xy 337.209135 -113.972852) (xy 337.221261 -113.918415) (xy 337.241184 -113.866324) (xy 337.26848 -113.817689)
			(xy 337.302566 -113.773546) (xy 337.342715 -113.734837) (xy 337.388073 -113.702386) (xy 337.437673 -113.676885)
			(xy 337.490457 -113.658878) (xy 337.5453 -113.648748) (xy 337.601034 -113.646711) (xy 337.656471 -113.652811)
			(xy 337.710428 -113.666917) (xy 337.761757 -113.688729) (xy 337.809363 -113.717783) (xy 337.852231 -113.753458)
			(xy 337.889448 -113.794995) (xy 337.920221 -113.841508) (xy 337.943893 -113.892005) (xy 337.959961 -113.945412)
			(xy 337.968081 -114.000588) (xy 337.96859 -114.028474) (xy 337.968081 -114.05636) (xy 337.959961 -114.111536)
			(xy 337.943893 -114.164943) (xy 337.920221 -114.21544) (xy 337.889448 -114.261953) (xy 337.852231 -114.30349)
			(xy 337.809363 -114.339165) (xy 337.761757 -114.368219) (xy 337.710428 -114.390031) (xy 337.656471 -114.404137)
			(xy 337.601034 -114.410237) (xy 337.5453 -114.4082) (xy 337.490457 -114.39807) (xy 337.437673 -114.380063)
			(xy 337.388073 -114.354562) (xy 337.342715 -114.322111) (xy 337.302566 -114.283402) (xy 337.26848 -114.239259)
			(xy 337.241184 -114.190624) (xy 337.221261 -114.138533) (xy 337.209135 -114.084096) (xy 337.205064 -114.028474)
			(xy 332.932961 -114.028474) (xy 332.946612 -114.040302) (xy 332.982303 -114.081493) (xy 333.011769 -114.127343)
			(xy 333.034411 -114.17692) (xy 333.049766 -114.229215) (xy 333.057522 -114.283163) (xy 333.058008 -114.310414)
			(xy 333.057487 -114.339133) (xy 333.04887 -114.39592) (xy 333.031833 -114.450772) (xy 333.012559 -114.4905)
			(xy 382.615438 -114.4905) (xy 382.619509 -114.434878) (xy 382.631635 -114.380441) (xy 382.651558 -114.32835)
			(xy 382.678854 -114.279715) (xy 382.71294 -114.235572) (xy 382.753089 -114.196863) (xy 382.798447 -114.164412)
			(xy 382.848047 -114.138911) (xy 382.900831 -114.120904) (xy 382.955674 -114.110774) (xy 383.011408 -114.108737)
			(xy 383.066845 -114.114837) (xy 383.120802 -114.128943) (xy 383.172131 -114.150755) (xy 383.219737 -114.179809)
			(xy 383.262605 -114.215484) (xy 383.299822 -114.257021) (xy 383.330595 -114.303534) (xy 383.354267 -114.354031)
			(xy 383.370335 -114.407438) (xy 383.378455 -114.462614) (xy 383.378964 -114.4905) (xy 383.378455 -114.518386)
			(xy 383.370335 -114.573562) (xy 383.354267 -114.626969) (xy 383.330595 -114.677466) (xy 383.299822 -114.723979)
			(xy 383.262605 -114.765516) (xy 383.219737 -114.801191) (xy 383.172131 -114.830245) (xy 383.120802 -114.852057)
			(xy 383.066845 -114.866163) (xy 383.011408 -114.872263) (xy 382.955674 -114.870226) (xy 382.900831 -114.860096)
			(xy 382.848047 -114.842089) (xy 382.798447 -114.816588) (xy 382.753089 -114.784137) (xy 382.71294 -114.745428)
			(xy 382.678854 -114.701285) (xy 382.651558 -114.65265) (xy 382.631635 -114.600559) (xy 382.619509 -114.546122)
			(xy 382.615438 -114.4905) (xy 333.012559 -114.4905) (xy 333.006762 -114.502449) (xy 332.974224 -114.549781)
			(xy 332.934955 -114.591697) (xy 332.91272 -114.60988) (xy 332.904 -114.617454) (xy 332.89394 -114.63822)
			(xy 332.893416 -114.649758) (xy 332.893416 -114.68227) (xy 332.894039 -114.693822) (xy 332.904234 -114.714565)
			(xy 332.912974 -114.722148) (xy 332.922372 -114.729768) (xy 332.929367 -114.735228) (xy 332.946017 -114.741336)
			(xy 332.954884 -114.741706) (xy 334.047592 -114.741706) (xy 334.057663 -114.742128) (xy 334.076269 -114.749841)
			(xy 334.08366 -114.756692) (xy 334.097884 -114.770916) (xy 334.10473 -114.778315) (xy 334.112461 -114.796913)
			(xy 334.11287 -114.806984) (xy 334.11287 -115.010946) (xy 338.819742 -115.010946) (xy 338.823813 -114.955324)
			(xy 338.835939 -114.900887) (xy 338.855862 -114.848796) (xy 338.883158 -114.800161) (xy 338.917244 -114.756018)
			(xy 338.957393 -114.717309) (xy 339.002751 -114.684858) (xy 339.052351 -114.659357) (xy 339.105135 -114.64135)
			(xy 339.159978 -114.63122) (xy 339.215712 -114.629183) (xy 339.271149 -114.635283) (xy 339.325106 -114.649389)
			(xy 339.376435 -114.671201) (xy 339.424041 -114.700255) (xy 339.466909 -114.73593) (xy 339.504126 -114.777467)
			(xy 339.534899 -114.82398) (xy 339.558571 -114.874477) (xy 339.574639 -114.927884) (xy 339.582759 -114.98306)
			(xy 339.583268 -115.010946) (xy 339.582759 -115.038832) (xy 339.579835 -115.058698) (xy 340.186262 -115.058698)
			(xy 340.190333 -115.003076) (xy 340.202459 -114.948639) (xy 340.222382 -114.896548) (xy 340.249678 -114.847913)
			(xy 340.283764 -114.80377) (xy 340.323913 -114.765061) (xy 340.369271 -114.73261) (xy 340.418871 -114.707109)
			(xy 340.471655 -114.689102) (xy 340.526498 -114.678972) (xy 340.582232 -114.676935) (xy 340.637669 -114.683035)
			(xy 340.691626 -114.697141) (xy 340.742955 -114.718953) (xy 340.790561 -114.748007) (xy 340.833429 -114.783682)
			(xy 340.870646 -114.825219) (xy 340.901419 -114.871732) (xy 340.925091 -114.922229) (xy 340.941159 -114.975636)
			(xy 340.943328 -114.990372) (xy 341.564974 -114.990372) (xy 341.569045 -114.93475) (xy 341.581171 -114.880313)
			(xy 341.601094 -114.828222) (xy 341.62839 -114.779587) (xy 341.662476 -114.735444) (xy 341.702625 -114.696735)
			(xy 341.747983 -114.664284) (xy 341.797583 -114.638783) (xy 341.850367 -114.620776) (xy 341.90521 -114.610646)
			(xy 341.960944 -114.608609) (xy 342.016381 -114.614709) (xy 342.070338 -114.628815) (xy 342.121667 -114.650627)
			(xy 342.169273 -114.679681) (xy 342.212141 -114.715356) (xy 342.249358 -114.756893) (xy 342.280131 -114.803406)
			(xy 342.303803 -114.853903) (xy 342.319871 -114.90731) (xy 342.327721 -114.960654) (xy 343.091768 -114.960654)
			(xy 343.095839 -114.905032) (xy 343.107965 -114.850595) (xy 343.127888 -114.798504) (xy 343.155184 -114.749869)
			(xy 343.18927 -114.705726) (xy 343.229419 -114.667017) (xy 343.274777 -114.634566) (xy 343.324377 -114.609065)
			(xy 343.377161 -114.591058) (xy 343.432004 -114.580928) (xy 343.487738 -114.578891) (xy 343.543175 -114.584991)
			(xy 343.597132 -114.599097) (xy 343.648461 -114.620909) (xy 343.696067 -114.649963) (xy 343.738935 -114.685638)
			(xy 343.776152 -114.727175) (xy 343.806925 -114.773688) (xy 343.830597 -114.824185) (xy 343.846665 -114.877592)
			(xy 343.854785 -114.932768) (xy 343.855294 -114.960654) (xy 343.854785 -114.98854) (xy 343.846665 -115.043716)
			(xy 343.830597 -115.097123) (xy 343.806925 -115.14762) (xy 343.776152 -115.194133) (xy 343.738935 -115.23567)
			(xy 343.696067 -115.271345) (xy 343.648461 -115.300399) (xy 343.597132 -115.322211) (xy 343.543175 -115.336317)
			(xy 343.487738 -115.342417) (xy 343.432004 -115.34038) (xy 343.377161 -115.33025) (xy 343.324377 -115.312243)
			(xy 343.274777 -115.286742) (xy 343.229419 -115.254291) (xy 343.18927 -115.215582) (xy 343.155184 -115.171439)
			(xy 343.127888 -115.122804) (xy 343.107965 -115.070713) (xy 343.095839 -115.016276) (xy 343.091768 -114.960654)
			(xy 342.327721 -114.960654) (xy 342.327991 -114.962486) (xy 342.3285 -114.990372) (xy 342.327991 -115.018258)
			(xy 342.319871 -115.073434) (xy 342.303803 -115.126841) (xy 342.280131 -115.177338) (xy 342.249358 -115.223851)
			(xy 342.212141 -115.265388) (xy 342.169273 -115.301063) (xy 342.121667 -115.330117) (xy 342.070338 -115.351929)
			(xy 342.016381 -115.366035) (xy 341.960944 -115.372135) (xy 341.90521 -115.370098) (xy 341.850367 -115.359968)
			(xy 341.797583 -115.341961) (xy 341.747983 -115.31646) (xy 341.702625 -115.284009) (xy 341.662476 -115.2453)
			(xy 341.62839 -115.201157) (xy 341.601094 -115.152522) (xy 341.581171 -115.100431) (xy 341.569045 -115.045994)
			(xy 341.564974 -114.990372) (xy 340.943328 -114.990372) (xy 340.949279 -115.030812) (xy 340.949788 -115.058698)
			(xy 340.949279 -115.086584) (xy 340.941159 -115.14176) (xy 340.925091 -115.195167) (xy 340.901419 -115.245664)
			(xy 340.870646 -115.292177) (xy 340.833429 -115.333714) (xy 340.790561 -115.369389) (xy 340.742955 -115.398443)
			(xy 340.691626 -115.420255) (xy 340.637669 -115.434361) (xy 340.582232 -115.440461) (xy 340.526498 -115.438424)
			(xy 340.471655 -115.428294) (xy 340.418871 -115.410287) (xy 340.369271 -115.384786) (xy 340.323913 -115.352335)
			(xy 340.283764 -115.313626) (xy 340.249678 -115.269483) (xy 340.222382 -115.220848) (xy 340.202459 -115.168757)
			(xy 340.190333 -115.11432) (xy 340.186262 -115.058698) (xy 339.579835 -115.058698) (xy 339.574639 -115.094008)
			(xy 339.558571 -115.147415) (xy 339.534899 -115.197912) (xy 339.504126 -115.244425) (xy 339.466909 -115.285962)
			(xy 339.424041 -115.321637) (xy 339.376435 -115.350691) (xy 339.325106 -115.372503) (xy 339.271149 -115.386609)
			(xy 339.215712 -115.392709) (xy 339.159978 -115.390672) (xy 339.105135 -115.380542) (xy 339.052351 -115.362535)
			(xy 339.002751 -115.337034) (xy 338.957393 -115.304583) (xy 338.917244 -115.265874) (xy 338.883158 -115.221731)
			(xy 338.855862 -115.173096) (xy 338.835939 -115.121005) (xy 338.823813 -115.066568) (xy 338.819742 -115.010946)
			(xy 334.11287 -115.010946) (xy 334.11287 -115.579906) (xy 337.342986 -115.579906) (xy 337.347057 -115.524284)
			(xy 337.359183 -115.469847) (xy 337.379106 -115.417756) (xy 337.406402 -115.369121) (xy 337.440488 -115.324978)
			(xy 337.480637 -115.286269) (xy 337.525995 -115.253818) (xy 337.575595 -115.228317) (xy 337.628379 -115.21031)
			(xy 337.683222 -115.20018) (xy 337.738956 -115.198143) (xy 337.794393 -115.204243) (xy 337.84835 -115.218349)
			(xy 337.899679 -115.240161) (xy 337.947285 -115.269215) (xy 337.990153 -115.30489) (xy 338.02737 -115.346427)
			(xy 338.058143 -115.39294) (xy 338.081815 -115.443437) (xy 338.097883 -115.496844) (xy 338.106003 -115.55202)
			(xy 338.106512 -115.579906) (xy 338.106003 -115.607792) (xy 338.097883 -115.662968) (xy 338.090242 -115.688364)
			(xy 359.753406 -115.688364) (xy 359.757477 -115.632742) (xy 359.769603 -115.578305) (xy 359.789526 -115.526214)
			(xy 359.816822 -115.477579) (xy 359.850908 -115.433436) (xy 359.891057 -115.394727) (xy 359.936415 -115.362276)
			(xy 359.986015 -115.336775) (xy 360.038799 -115.318768) (xy 360.093642 -115.308638) (xy 360.149376 -115.306601)
			(xy 360.204813 -115.312701) (xy 360.25877 -115.326807) (xy 360.310099 -115.348619) (xy 360.357705 -115.377673)
			(xy 360.400573 -115.413348) (xy 360.43779 -115.454885) (xy 360.468563 -115.501398) (xy 360.492235 -115.551895)
			(xy 360.508303 -115.605302) (xy 360.516423 -115.660478) (xy 360.516932 -115.688364) (xy 360.516423 -115.71625)
			(xy 360.508303 -115.771426) (xy 360.492235 -115.824833) (xy 360.468563 -115.87533) (xy 360.43779 -115.921843)
			(xy 360.400573 -115.96338) (xy 360.357705 -115.999055) (xy 360.310099 -116.028109) (xy 360.25877 -116.049921)
			(xy 360.204813 -116.064027) (xy 360.149376 -116.070127) (xy 360.093642 -116.06809) (xy 360.038799 -116.05796)
			(xy 359.986015 -116.039953) (xy 359.936415 -116.014452) (xy 359.891057 -115.982001) (xy 359.850908 -115.943292)
			(xy 359.816822 -115.899149) (xy 359.789526 -115.850514) (xy 359.769603 -115.798423) (xy 359.757477 -115.743986)
			(xy 359.753406 -115.688364) (xy 338.090242 -115.688364) (xy 338.081815 -115.716375) (xy 338.058143 -115.766872)
			(xy 338.02737 -115.813385) (xy 337.990153 -115.854922) (xy 337.947285 -115.890597) (xy 337.899679 -115.919651)
			(xy 337.84835 -115.941463) (xy 337.794393 -115.955569) (xy 337.738956 -115.961669) (xy 337.683222 -115.959632)
			(xy 337.628379 -115.949502) (xy 337.575595 -115.931495) (xy 337.525995 -115.905994) (xy 337.480637 -115.873543)
			(xy 337.440488 -115.834834) (xy 337.406402 -115.790691) (xy 337.379106 -115.742056) (xy 337.359183 -115.689965)
			(xy 337.347057 -115.635528) (xy 337.342986 -115.579906) (xy 334.11287 -115.579906) (xy 334.11287 -116.62918)
			(xy 337.337906 -116.62918) (xy 337.341977 -116.573558) (xy 337.354103 -116.519121) (xy 337.374026 -116.46703)
			(xy 337.401322 -116.418395) (xy 337.435408 -116.374252) (xy 337.475557 -116.335543) (xy 337.520915 -116.303092)
			(xy 337.570515 -116.277591) (xy 337.623299 -116.259584) (xy 337.678142 -116.249454) (xy 337.733876 -116.247417)
			(xy 337.789313 -116.253517) (xy 337.84327 -116.267623) (xy 337.894599 -116.289435) (xy 337.942205 -116.318489)
			(xy 337.985073 -116.354164) (xy 338.02229 -116.395701) (xy 338.053063 -116.442214) (xy 338.076735 -116.492711)
			(xy 338.092803 -116.546118) (xy 338.100923 -116.601294) (xy 338.101432 -116.62918) (xy 338.100923 -116.657066)
			(xy 338.092803 -116.712242) (xy 338.076735 -116.765649) (xy 338.053063 -116.816146) (xy 338.02229 -116.862659)
			(xy 337.985073 -116.904196) (xy 337.942205 -116.939871) (xy 337.894599 -116.968925) (xy 337.84327 -116.990737)
			(xy 337.789313 -117.004843) (xy 337.733876 -117.010943) (xy 337.678142 -117.008906) (xy 337.623299 -116.998776)
			(xy 337.570515 -116.980769) (xy 337.520915 -116.955268) (xy 337.475557 -116.922817) (xy 337.435408 -116.884108)
			(xy 337.401322 -116.839965) (xy 337.374026 -116.79133) (xy 337.354103 -116.739239) (xy 337.341977 -116.684802)
			(xy 337.337906 -116.62918) (xy 334.11287 -116.62918) (xy 334.11287 -117.248178) (xy 339.938866 -117.248178)
			(xy 339.942937 -117.192556) (xy 339.955063 -117.138119) (xy 339.974986 -117.086028) (xy 340.002282 -117.037393)
			(xy 340.036368 -116.99325) (xy 340.076517 -116.954541) (xy 340.121875 -116.92209) (xy 340.171475 -116.896589)
			(xy 340.224259 -116.878582) (xy 340.279102 -116.868452) (xy 340.334836 -116.866415) (xy 340.390273 -116.872515)
			(xy 340.44423 -116.886621) (xy 340.495559 -116.908433) (xy 340.543165 -116.937487) (xy 340.586033 -116.973162)
			(xy 340.62325 -117.014699) (xy 340.654023 -117.061212) (xy 340.677695 -117.111709) (xy 340.693763 -117.165116)
			(xy 340.701883 -117.220292) (xy 340.702392 -117.248178) (xy 340.954866 -117.248178) (xy 340.958937 -117.192556)
			(xy 340.971063 -117.138119) (xy 340.990986 -117.086028) (xy 341.018282 -117.037393) (xy 341.052368 -116.99325)
			(xy 341.092517 -116.954541) (xy 341.137875 -116.92209) (xy 341.187475 -116.896589) (xy 341.240259 -116.878582)
			(xy 341.295102 -116.868452) (xy 341.350836 -116.866415) (xy 341.406273 -116.872515) (xy 341.46023 -116.886621)
			(xy 341.511559 -116.908433) (xy 341.559165 -116.937487) (xy 341.602033 -116.973162) (xy 341.63925 -117.014699)
			(xy 341.670023 -117.061212) (xy 341.693695 -117.111709) (xy 341.709763 -117.165116) (xy 341.717883 -117.220292)
			(xy 341.718392 -117.248178) (xy 341.970866 -117.248178) (xy 341.974937 -117.192556) (xy 341.987063 -117.138119)
			(xy 342.006986 -117.086028) (xy 342.034282 -117.037393) (xy 342.068368 -116.99325) (xy 342.108517 -116.954541)
			(xy 342.153875 -116.92209) (xy 342.203475 -116.896589) (xy 342.256259 -116.878582) (xy 342.311102 -116.868452)
			(xy 342.366836 -116.866415) (xy 342.422273 -116.872515) (xy 342.47623 -116.886621) (xy 342.527559 -116.908433)
			(xy 342.575165 -116.937487) (xy 342.618033 -116.973162) (xy 342.627305 -116.98351) (xy 356.001572 -116.98351)
			(xy 356.005643 -116.927888) (xy 356.017769 -116.873451) (xy 356.037692 -116.82136) (xy 356.064988 -116.772725)
			(xy 356.099074 -116.728582) (xy 356.139223 -116.689873) (xy 356.184581 -116.657422) (xy 356.234181 -116.631921)
			(xy 356.286965 -116.613914) (xy 356.341808 -116.603784) (xy 356.397542 -116.601747) (xy 356.452979 -116.607847)
			(xy 356.506936 -116.621953) (xy 356.558265 -116.643765) (xy 356.605871 -116.672819) (xy 356.648739 -116.708494)
			(xy 356.685956 -116.750031) (xy 356.716729 -116.796544) (xy 356.740401 -116.847041) (xy 356.756469 -116.900448)
			(xy 356.764589 -116.955624) (xy 356.765098 -116.98351) (xy 356.764589 -117.011396) (xy 356.756469 -117.066572)
			(xy 356.740401 -117.119979) (xy 356.716729 -117.170476) (xy 356.685956 -117.216989) (xy 356.648739 -117.258526)
			(xy 356.605871 -117.294201) (xy 356.558265 -117.323255) (xy 356.54845 -117.327426) (xy 357.987344 -117.327426)
			(xy 357.991415 -117.271804) (xy 358.003541 -117.217367) (xy 358.023464 -117.165276) (xy 358.05076 -117.116641)
			(xy 358.084846 -117.072498) (xy 358.124995 -117.033789) (xy 358.170353 -117.001338) (xy 358.219953 -116.975837)
			(xy 358.272737 -116.95783) (xy 358.32758 -116.9477) (xy 358.383314 -116.945663) (xy 358.438751 -116.951763)
			(xy 358.492708 -116.965869) (xy 358.544037 -116.987681) (xy 358.591643 -117.016735) (xy 358.634511 -117.05241)
			(xy 358.671728 -117.093947) (xy 358.702501 -117.14046) (xy 358.726173 -117.190957) (xy 358.742241 -117.244364)
			(xy 358.750361 -117.29954) (xy 358.75087 -117.327426) (xy 358.750361 -117.355312) (xy 358.742241 -117.410488)
			(xy 358.726173 -117.463895) (xy 358.702501 -117.514392) (xy 358.671728 -117.560905) (xy 358.634511 -117.602442)
			(xy 358.591643 -117.638117) (xy 358.544037 -117.667171) (xy 358.492708 -117.688983) (xy 358.438751 -117.703089)
			(xy 358.383314 -117.709189) (xy 358.32758 -117.707152) (xy 358.272737 -117.697022) (xy 358.219953 -117.679015)
			(xy 358.170353 -117.653514) (xy 358.124995 -117.621063) (xy 358.084846 -117.582354) (xy 358.05076 -117.538211)
			(xy 358.023464 -117.489576) (xy 358.003541 -117.437485) (xy 357.991415 -117.383048) (xy 357.987344 -117.327426)
			(xy 356.54845 -117.327426) (xy 356.506936 -117.345067) (xy 356.452979 -117.359173) (xy 356.397542 -117.365273)
			(xy 356.341808 -117.363236) (xy 356.286965 -117.353106) (xy 356.234181 -117.335099) (xy 356.184581 -117.309598)
			(xy 356.139223 -117.277147) (xy 356.099074 -117.238438) (xy 356.064988 -117.194295) (xy 356.037692 -117.14566)
			(xy 356.017769 -117.093569) (xy 356.005643 -117.039132) (xy 356.001572 -116.98351) (xy 342.627305 -116.98351)
			(xy 342.65525 -117.014699) (xy 342.686023 -117.061212) (xy 342.709695 -117.111709) (xy 342.725763 -117.165116)
			(xy 342.733883 -117.220292) (xy 342.734392 -117.248178) (xy 342.733883 -117.276064) (xy 342.725763 -117.33124)
			(xy 342.709695 -117.384647) (xy 342.686023 -117.435144) (xy 342.65525 -117.481657) (xy 342.618033 -117.523194)
			(xy 342.575165 -117.558869) (xy 342.527559 -117.587923) (xy 342.47623 -117.609735) (xy 342.422273 -117.623841)
			(xy 342.366836 -117.629941) (xy 342.311102 -117.627904) (xy 342.256259 -117.617774) (xy 342.203475 -117.599767)
			(xy 342.153875 -117.574266) (xy 342.108517 -117.541815) (xy 342.068368 -117.503106) (xy 342.034282 -117.458963)
			(xy 342.006986 -117.410328) (xy 341.987063 -117.358237) (xy 341.974937 -117.3038) (xy 341.970866 -117.248178)
			(xy 341.718392 -117.248178) (xy 341.717883 -117.276064) (xy 341.709763 -117.33124) (xy 341.693695 -117.384647)
			(xy 341.670023 -117.435144) (xy 341.63925 -117.481657) (xy 341.602033 -117.523194) (xy 341.559165 -117.558869)
			(xy 341.511559 -117.587923) (xy 341.46023 -117.609735) (xy 341.406273 -117.623841) (xy 341.350836 -117.629941)
			(xy 341.295102 -117.627904) (xy 341.240259 -117.617774) (xy 341.187475 -117.599767) (xy 341.137875 -117.574266)
			(xy 341.092517 -117.541815) (xy 341.052368 -117.503106) (xy 341.018282 -117.458963) (xy 340.990986 -117.410328)
			(xy 340.971063 -117.358237) (xy 340.958937 -117.3038) (xy 340.954866 -117.248178) (xy 340.702392 -117.248178)
			(xy 340.701883 -117.276064) (xy 340.693763 -117.33124) (xy 340.677695 -117.384647) (xy 340.654023 -117.435144)
			(xy 340.62325 -117.481657) (xy 340.586033 -117.523194) (xy 340.543165 -117.558869) (xy 340.495559 -117.587923)
			(xy 340.44423 -117.609735) (xy 340.390273 -117.623841) (xy 340.334836 -117.629941) (xy 340.279102 -117.627904)
			(xy 340.224259 -117.617774) (xy 340.171475 -117.599767) (xy 340.121875 -117.574266) (xy 340.076517 -117.541815)
			(xy 340.036368 -117.503106) (xy 340.002282 -117.458963) (xy 339.974986 -117.410328) (xy 339.955063 -117.358237)
			(xy 339.942937 -117.3038) (xy 339.938866 -117.248178) (xy 334.11287 -117.248178) (xy 334.11287 -117.439948)
			(xy 334.113037 -117.445958) (xy 334.115859 -117.457641) (xy 334.118458 -117.463062) (xy 334.133698 -117.493034)
			(xy 334.136746 -117.49532) (xy 334.142588 -117.499892) (xy 334.142842 -117.499892) (xy 334.163945 -117.516643)
			(xy 334.201683 -117.555099) (xy 334.233637 -117.59848) (xy 334.259174 -117.645923) (xy 334.277786 -117.696486)
			(xy 334.289103 -117.749163) (xy 334.292899 -117.802909) (xy 334.2891 -117.856654) (xy 334.277781 -117.909331)
			(xy 334.259167 -117.959893) (xy 334.233628 -118.007334) (xy 334.201672 -118.050714) (xy 334.163933 -118.089168)
			(xy 334.142842 -118.105936) (xy 334.142588 -118.105936) (xy 334.136746 -118.110508) (xy 334.133698 -118.112794)
			(xy 334.118458 -118.142766) (xy 334.115875 -118.148193) (xy 334.113053 -118.159872) (xy 334.11287 -118.16588)
			(xy 334.11287 -118.725188) (xy 334.113022 -118.730912) (xy 334.115593 -118.742067) (xy 334.11795 -118.747286)
			(xy 334.1242 -118.76024) (xy 334.764378 -118.76024) (xy 334.768449 -118.704618) (xy 334.780575 -118.650181)
			(xy 334.800498 -118.59809) (xy 334.827794 -118.549455) (xy 334.86188 -118.505312) (xy 334.902029 -118.466603)
			(xy 334.947387 -118.434152) (xy 334.996987 -118.408651) (xy 335.049771 -118.390644) (xy 335.104614 -118.380514)
			(xy 335.160348 -118.378477) (xy 335.215785 -118.384577) (xy 335.269742 -118.398683) (xy 335.321071 -118.420495)
			(xy 335.368677 -118.449549) (xy 335.411545 -118.485224) (xy 335.448762 -118.526761) (xy 335.479535 -118.573274)
			(xy 335.503207 -118.623771) (xy 335.519275 -118.677178) (xy 335.527395 -118.732354) (xy 335.527904 -118.76024)
			(xy 335.527395 -118.788126) (xy 335.519275 -118.843302) (xy 335.503207 -118.896709) (xy 335.479535 -118.947206)
			(xy 335.448762 -118.993719) (xy 335.419679 -119.026178) (xy 338.18144 -119.026178) (xy 338.185511 -118.970556)
			(xy 338.197637 -118.916119) (xy 338.21756 -118.864028) (xy 338.244856 -118.815393) (xy 338.278942 -118.77125)
			(xy 338.319091 -118.732541) (xy 338.364449 -118.70009) (xy 338.414049 -118.674589) (xy 338.466833 -118.656582)
			(xy 338.521676 -118.646452) (xy 338.57741 -118.644415) (xy 338.632847 -118.650515) (xy 338.686804 -118.664621)
			(xy 338.738133 -118.686433) (xy 338.785739 -118.715487) (xy 338.828607 -118.751162) (xy 338.865824 -118.792699)
			(xy 338.896597 -118.839212) (xy 338.920269 -118.889709) (xy 338.936337 -118.943116) (xy 338.944457 -118.998292)
			(xy 338.944966 -119.026178) (xy 338.944457 -119.054064) (xy 338.936337 -119.10924) (xy 338.920269 -119.162647)
			(xy 338.896597 -119.213144) (xy 338.865824 -119.259657) (xy 338.828607 -119.301194) (xy 338.785739 -119.336869)
			(xy 338.738133 -119.365923) (xy 338.686804 -119.387735) (xy 338.632847 -119.401841) (xy 338.57741 -119.407941)
			(xy 338.521676 -119.405904) (xy 338.466833 -119.395774) (xy 338.414049 -119.377767) (xy 338.364449 -119.352266)
			(xy 338.319091 -119.319815) (xy 338.278942 -119.281106) (xy 338.244856 -119.236963) (xy 338.21756 -119.188328)
			(xy 338.197637 -119.136237) (xy 338.185511 -119.0818) (xy 338.18144 -119.026178) (xy 335.419679 -119.026178)
			(xy 335.411545 -119.035256) (xy 335.368677 -119.070931) (xy 335.321071 -119.099985) (xy 335.269742 -119.121797)
			(xy 335.215785 -119.135903) (xy 335.160348 -119.142003) (xy 335.104614 -119.139966) (xy 335.049771 -119.129836)
			(xy 334.996987 -119.111829) (xy 334.947387 -119.086328) (xy 334.902029 -119.053877) (xy 334.86188 -119.015168)
			(xy 334.827794 -118.971025) (xy 334.800498 -118.92239) (xy 334.780575 -118.870299) (xy 334.768449 -118.815862)
			(xy 334.764378 -118.76024) (xy 334.1242 -118.76024) (xy 334.13192 -118.776242) (xy 334.134968 -118.778782)
			(xy 334.138016 -118.781068) (xy 334.140302 -118.7831) (xy 334.161204 -118.801309) (xy 334.198041 -118.842734)
			(xy 334.228497 -118.889051) (xy 334.251931 -118.939288) (xy 334.267851 -118.992386) (xy 334.275922 -119.04723)
			(xy 334.276446 -119.074946) (xy 334.276446 -119.075454) (xy 334.276446 -119.075962) (xy 334.27593 -119.103679)
			(xy 334.267866 -119.158523) (xy 334.251946 -119.211622) (xy 334.228506 -119.261857) (xy 334.19804 -119.308168)
			(xy 334.161189 -119.349581) (xy 334.140302 -119.367808) (xy 334.138016 -119.36984) (xy 334.134968 -119.372126)
			(xy 334.13192 -119.374666) (xy 334.11795 -119.403622) (xy 334.1156 -119.408843) (xy 334.113023 -119.419997)
			(xy 334.11287 -119.42572) (xy 334.11287 -119.486426) (xy 357.987344 -119.486426) (xy 357.991415 -119.430804)
			(xy 358.003541 -119.376367) (xy 358.023464 -119.324276) (xy 358.05076 -119.275641) (xy 358.084846 -119.231498)
			(xy 358.124995 -119.192789) (xy 358.170353 -119.160338) (xy 358.219953 -119.134837) (xy 358.272737 -119.11683)
			(xy 358.32758 -119.1067) (xy 358.383314 -119.104663) (xy 358.438751 -119.110763) (xy 358.492708 -119.124869)
			(xy 358.544037 -119.146681) (xy 358.591643 -119.175735) (xy 358.634511 -119.21141) (xy 358.671728 -119.252947)
			(xy 358.702501 -119.29946) (xy 358.726173 -119.349957) (xy 358.727952 -119.35587) (xy 359.003344 -119.35587)
			(xy 359.007415 -119.300248) (xy 359.019541 -119.245811) (xy 359.039464 -119.19372) (xy 359.06676 -119.145085)
			(xy 359.100846 -119.100942) (xy 359.140995 -119.062233) (xy 359.186353 -119.029782) (xy 359.235953 -119.004281)
			(xy 359.288737 -118.986274) (xy 359.34358 -118.976144) (xy 359.399314 -118.974107) (xy 359.454751 -118.980207)
			(xy 359.508708 -118.994313) (xy 359.560037 -119.016125) (xy 359.607643 -119.045179) (xy 359.650511 -119.080854)
			(xy 359.687728 -119.122391) (xy 359.718501 -119.168904) (xy 359.742173 -119.219401) (xy 359.758241 -119.272808)
			(xy 359.766361 -119.327984) (xy 359.76687 -119.35587) (xy 359.766361 -119.383756) (xy 359.758241 -119.438932)
			(xy 359.742173 -119.492339) (xy 359.718501 -119.542836) (xy 359.687728 -119.589349) (xy 359.650511 -119.630886)
			(xy 359.607643 -119.666561) (xy 359.560037 -119.695615) (xy 359.508708 -119.717427) (xy 359.454751 -119.731533)
			(xy 359.399314 -119.737633) (xy 359.34358 -119.735596) (xy 359.288737 -119.725466) (xy 359.235953 -119.707459)
			(xy 359.186353 -119.681958) (xy 359.140995 -119.649507) (xy 359.100846 -119.610798) (xy 359.06676 -119.566655)
			(xy 359.039464 -119.51802) (xy 359.019541 -119.465929) (xy 359.007415 -119.411492) (xy 359.003344 -119.35587)
			(xy 358.727952 -119.35587) (xy 358.742241 -119.403364) (xy 358.750361 -119.45854) (xy 358.75087 -119.486426)
			(xy 358.750361 -119.514312) (xy 358.742241 -119.569488) (xy 358.726173 -119.622895) (xy 358.702501 -119.673392)
			(xy 358.671728 -119.719905) (xy 358.634511 -119.761442) (xy 358.591643 -119.797117) (xy 358.544037 -119.826171)
			(xy 358.492708 -119.847983) (xy 358.438751 -119.862089) (xy 358.383314 -119.868189) (xy 358.32758 -119.866152)
			(xy 358.272737 -119.856022) (xy 358.219953 -119.838015) (xy 358.170353 -119.812514) (xy 358.124995 -119.780063)
			(xy 358.084846 -119.741354) (xy 358.05076 -119.697211) (xy 358.023464 -119.648576) (xy 358.003541 -119.596485)
			(xy 357.991415 -119.542048) (xy 357.987344 -119.486426) (xy 334.11287 -119.486426) (xy 334.11287 -120.774968)
			(xy 334.113212 -120.783661) (xy 334.116271 -120.79224) (xy 334.891378 -120.79224) (xy 334.895449 -120.736618)
			(xy 334.907575 -120.682181) (xy 334.927498 -120.63009) (xy 334.954794 -120.581455) (xy 334.98888 -120.537312)
			(xy 335.029029 -120.498603) (xy 335.074387 -120.466152) (xy 335.123987 -120.440651) (xy 335.176771 -120.422644)
			(xy 335.231614 -120.412514) (xy 335.287348 -120.410477) (xy 335.342785 -120.416577) (xy 335.396742 -120.430683)
			(xy 335.448071 -120.452495) (xy 335.495677 -120.481549) (xy 335.538545 -120.517224) (xy 335.546679 -120.526302)
			(xy 336.40344 -120.526302) (xy 336.407511 -120.47068) (xy 336.419637 -120.416243) (xy 336.43956 -120.364152)
			(xy 336.466856 -120.315517) (xy 336.500942 -120.271374) (xy 336.541091 -120.232665) (xy 336.586449 -120.200214)
			(xy 336.636049 -120.174713) (xy 336.688833 -120.156706) (xy 336.743676 -120.146576) (xy 336.79941 -120.144539)
			(xy 336.854847 -120.150639) (xy 336.908804 -120.164745) (xy 336.960133 -120.186557) (xy 337.007739 -120.215611)
			(xy 337.050607 -120.251286) (xy 337.087824 -120.292823) (xy 337.118597 -120.339336) (xy 337.142269 -120.389833)
			(xy 337.158337 -120.44324) (xy 337.166457 -120.498416) (xy 337.166966 -120.526302) (xy 338.193378 -120.526302)
			(xy 338.197449 -120.47068) (xy 338.209575 -120.416243) (xy 338.229498 -120.364152) (xy 338.256794 -120.315517)
			(xy 338.29088 -120.271374) (xy 338.331029 -120.232665) (xy 338.376387 -120.200214) (xy 338.425987 -120.174713)
			(xy 338.478771 -120.156706) (xy 338.533614 -120.146576) (xy 338.589348 -120.144539) (xy 338.644785 -120.150639)
			(xy 338.698742 -120.164745) (xy 338.750071 -120.186557) (xy 338.797677 -120.215611) (xy 338.840545 -120.251286)
			(xy 338.877762 -120.292823) (xy 338.908535 -120.339336) (xy 338.932207 -120.389833) (xy 338.948275 -120.44324)
			(xy 338.956395 -120.498416) (xy 338.956904 -120.526302) (xy 338.956395 -120.554188) (xy 338.948275 -120.609364)
			(xy 338.932207 -120.662771) (xy 338.908535 -120.713268) (xy 338.877762 -120.759781) (xy 338.840545 -120.801318)
			(xy 338.797677 -120.836993) (xy 338.750071 -120.866047) (xy 338.698742 -120.887859) (xy 338.644785 -120.901965)
			(xy 338.589348 -120.908065) (xy 338.533614 -120.906028) (xy 338.478771 -120.895898) (xy 338.425987 -120.877891)
			(xy 338.376387 -120.85239) (xy 338.331029 -120.819939) (xy 338.29088 -120.78123) (xy 338.256794 -120.737087)
			(xy 338.229498 -120.688452) (xy 338.209575 -120.636361) (xy 338.197449 -120.581924) (xy 338.193378 -120.526302)
			(xy 337.166966 -120.526302) (xy 337.166457 -120.554188) (xy 337.158337 -120.609364) (xy 337.142269 -120.662771)
			(xy 337.118597 -120.713268) (xy 337.087824 -120.759781) (xy 337.050607 -120.801318) (xy 337.007739 -120.836993)
			(xy 336.960133 -120.866047) (xy 336.908804 -120.887859) (xy 336.854847 -120.901965) (xy 336.79941 -120.908065)
			(xy 336.743676 -120.906028) (xy 336.688833 -120.895898) (xy 336.636049 -120.877891) (xy 336.586449 -120.85239)
			(xy 336.541091 -120.819939) (xy 336.500942 -120.78123) (xy 336.466856 -120.737087) (xy 336.43956 -120.688452)
			(xy 336.419637 -120.636361) (xy 336.407511 -120.581924) (xy 336.40344 -120.526302) (xy 335.546679 -120.526302)
			(xy 335.575762 -120.558761) (xy 335.606535 -120.605274) (xy 335.630207 -120.655771) (xy 335.646275 -120.709178)
			(xy 335.654395 -120.764354) (xy 335.654904 -120.79224) (xy 335.654395 -120.820126) (xy 335.646275 -120.875302)
			(xy 335.630207 -120.928709) (xy 335.606535 -120.979206) (xy 335.575762 -121.025719) (xy 335.538545 -121.067256)
			(xy 335.495677 -121.102931) (xy 335.448071 -121.131985) (xy 335.396742 -121.153797) (xy 335.342785 -121.167903)
			(xy 335.287348 -121.174003) (xy 335.231614 -121.171966) (xy 335.176771 -121.161836) (xy 335.123987 -121.143829)
			(xy 335.074387 -121.118328) (xy 335.029029 -121.085877) (xy 334.98888 -121.047168) (xy 334.954794 -121.003025)
			(xy 334.927498 -120.95439) (xy 334.907575 -120.902299) (xy 334.895449 -120.847862) (xy 334.891378 -120.79224)
			(xy 334.116271 -120.79224) (xy 334.11905 -120.800036) (xy 334.1243 -120.806972) (xy 334.129634 -120.813576)
			(xy 334.144366 -120.822466) (xy 334.15351 -120.824498) (xy 334.180316 -120.830513) (xy 334.231974 -120.849207)
			(xy 334.280416 -120.875119) (xy 334.32464 -120.907713) (xy 334.363731 -120.946313) (xy 334.39688 -120.990121)
			(xy 334.423402 -121.038232) (xy 334.442747 -121.08965) (xy 334.454517 -121.143312) (xy 334.458466 -121.198106)
			(xy 334.454515 -121.252901) (xy 334.442744 -121.306562) (xy 334.423396 -121.357979) (xy 334.396873 -121.406089)
			(xy 334.363722 -121.449897) (xy 334.32463 -121.488496) (xy 334.280405 -121.521088) (xy 334.231962 -121.546998)
			(xy 334.180304 -121.565691) (xy 334.15351 -121.571766) (xy 334.153002 -121.571766) (xy 334.144581 -121.573922)
			(xy 334.129773 -121.583007) (xy 334.124046 -121.589546) (xy 334.118712 -121.59615) (xy 334.11287 -121.612406)
			(xy 334.11287 -121.661428) (xy 356.973122 -121.661428) (xy 356.977193 -121.605806) (xy 356.989319 -121.551369)
			(xy 357.009242 -121.499278) (xy 357.036538 -121.450643) (xy 357.070624 -121.4065) (xy 357.110773 -121.367791)
			(xy 357.156131 -121.33534) (xy 357.205731 -121.309839) (xy 357.258515 -121.291832) (xy 357.313358 -121.281702)
			(xy 357.369092 -121.279665) (xy 357.424529 -121.285765) (xy 357.478486 -121.299871) (xy 357.529815 -121.321683)
			(xy 357.577421 -121.350737) (xy 357.620289 -121.386412) (xy 357.657506 -121.427949) (xy 357.688279 -121.474462)
			(xy 357.711951 -121.524959) (xy 357.728019 -121.578366) (xy 357.736139 -121.633542) (xy 357.736648 -121.661428)
			(xy 357.736139 -121.689314) (xy 357.728019 -121.74449) (xy 357.711951 -121.797897) (xy 357.688279 -121.848394)
			(xy 357.657506 -121.894907) (xy 357.620289 -121.936444) (xy 357.577421 -121.972119) (xy 357.529815 -122.001173)
			(xy 357.478486 -122.022985) (xy 357.424529 -122.037091) (xy 357.369092 -122.043191) (xy 357.313358 -122.041154)
			(xy 357.258515 -122.031024) (xy 357.205731 -122.013017) (xy 357.156131 -121.987516) (xy 357.110773 -121.955065)
			(xy 357.070624 -121.916356) (xy 357.036538 -121.872213) (xy 357.009242 -121.823578) (xy 356.989319 -121.771487)
			(xy 356.977193 -121.71705) (xy 356.973122 -121.661428) (xy 334.11287 -121.661428) (xy 334.11287 -122.46991)
			(xy 359.237024 -122.46991) (xy 359.241095 -122.414288) (xy 359.253221 -122.359851) (xy 359.273144 -122.30776)
			(xy 359.30044 -122.259125) (xy 359.334526 -122.214982) (xy 359.374675 -122.176273) (xy 359.420033 -122.143822)
			(xy 359.469633 -122.118321) (xy 359.522417 -122.100314) (xy 359.57726 -122.090184) (xy 359.632994 -122.088147)
			(xy 359.688431 -122.094247) (xy 359.742388 -122.108353) (xy 359.793717 -122.130165) (xy 359.841323 -122.159219)
			(xy 359.884191 -122.194894) (xy 359.921408 -122.236431) (xy 359.952181 -122.282944) (xy 359.975853 -122.333441)
			(xy 359.991921 -122.386848) (xy 360.000041 -122.442024) (xy 360.00055 -122.46991) (xy 360.000041 -122.497796)
			(xy 359.991921 -122.552972) (xy 359.975853 -122.606379) (xy 359.952181 -122.656876) (xy 359.921408 -122.703389)
			(xy 359.884191 -122.744926) (xy 359.841323 -122.780601) (xy 359.793717 -122.809655) (xy 359.742388 -122.831467)
			(xy 359.688431 -122.845573) (xy 359.632994 -122.851673) (xy 359.57726 -122.849636) (xy 359.522417 -122.839506)
			(xy 359.469633 -122.821499) (xy 359.420033 -122.795998) (xy 359.374675 -122.763547) (xy 359.334526 -122.724838)
			(xy 359.30044 -122.680695) (xy 359.273144 -122.63206) (xy 359.253221 -122.579969) (xy 359.241095 -122.525532)
			(xy 359.237024 -122.46991) (xy 334.11287 -122.46991) (xy 334.11287 -122.931428) (xy 356.973122 -122.931428)
			(xy 356.977193 -122.875806) (xy 356.989319 -122.821369) (xy 357.009242 -122.769278) (xy 357.036538 -122.720643)
			(xy 357.070624 -122.6765) (xy 357.110773 -122.637791) (xy 357.156131 -122.60534) (xy 357.205731 -122.579839)
			(xy 357.258515 -122.561832) (xy 357.313358 -122.551702) (xy 357.369092 -122.549665) (xy 357.424529 -122.555765)
			(xy 357.478486 -122.569871) (xy 357.529815 -122.591683) (xy 357.577421 -122.620737) (xy 357.620289 -122.656412)
			(xy 357.657506 -122.697949) (xy 357.688279 -122.744462) (xy 357.711951 -122.794959) (xy 357.728019 -122.848366)
			(xy 357.736139 -122.903542) (xy 357.736648 -122.931428) (xy 357.736139 -122.959314) (xy 357.728019 -123.01449)
			(xy 357.711951 -123.067897) (xy 357.688279 -123.118394) (xy 357.657506 -123.164907) (xy 357.620289 -123.206444)
			(xy 357.577421 -123.242119) (xy 357.529815 -123.271173) (xy 357.478486 -123.292985) (xy 357.424529 -123.307091)
			(xy 357.369092 -123.313191) (xy 357.313358 -123.311154) (xy 357.258515 -123.301024) (xy 357.205731 -123.283017)
			(xy 357.156131 -123.257516) (xy 357.110773 -123.225065) (xy 357.070624 -123.186356) (xy 357.036538 -123.142213)
			(xy 357.009242 -123.093578) (xy 356.989319 -123.041487) (xy 356.977193 -122.98705) (xy 356.973122 -122.931428)
			(xy 334.11287 -122.931428) (xy 334.11287 -123.947428) (xy 356.973122 -123.947428) (xy 356.977193 -123.891806)
			(xy 356.989319 -123.837369) (xy 357.009242 -123.785278) (xy 357.036538 -123.736643) (xy 357.070624 -123.6925)
			(xy 357.110773 -123.653791) (xy 357.156131 -123.62134) (xy 357.205731 -123.595839) (xy 357.258515 -123.577832)
			(xy 357.313358 -123.567702) (xy 357.369092 -123.565665) (xy 357.424529 -123.571765) (xy 357.478486 -123.585871)
			(xy 357.529815 -123.607683) (xy 357.577421 -123.636737) (xy 357.620289 -123.672412) (xy 357.657506 -123.713949)
			(xy 357.688279 -123.760462) (xy 357.711951 -123.810959) (xy 357.728019 -123.864366) (xy 357.736139 -123.919542)
			(xy 357.736648 -123.947428) (xy 357.736139 -123.975314) (xy 357.728019 -124.03049) (xy 357.711951 -124.083897)
			(xy 357.688279 -124.134394) (xy 357.657506 -124.180907) (xy 357.620289 -124.222444) (xy 357.577421 -124.258119)
			(xy 357.529815 -124.287173) (xy 357.478486 -124.308985) (xy 357.424529 -124.323091) (xy 357.369092 -124.329191)
			(xy 357.313358 -124.327154) (xy 357.258515 -124.317024) (xy 357.205731 -124.299017) (xy 357.156131 -124.273516)
			(xy 357.110773 -124.241065) (xy 357.070624 -124.202356) (xy 357.036538 -124.158213) (xy 357.009242 -124.109578)
			(xy 356.989319 -124.057487) (xy 356.977193 -124.00305) (xy 356.973122 -123.947428) (xy 334.11287 -123.947428)
			(xy 334.11287 -125.260862) (xy 336.65363 -125.260862) (xy 336.657701 -125.20524) (xy 336.669827 -125.150803)
			(xy 336.68975 -125.098712) (xy 336.717046 -125.050077) (xy 336.751132 -125.005934) (xy 336.791281 -124.967225)
			(xy 336.836639 -124.934774) (xy 336.886239 -124.909273) (xy 336.939023 -124.891266) (xy 336.993866 -124.881136)
			(xy 337.0496 -124.879099) (xy 337.105037 -124.885199) (xy 337.158994 -124.899305) (xy 337.210323 -124.921117)
			(xy 337.257929 -124.950171) (xy 337.273859 -124.963428) (xy 356.973122 -124.963428) (xy 356.977193 -124.907806)
			(xy 356.989319 -124.853369) (xy 357.009242 -124.801278) (xy 357.036538 -124.752643) (xy 357.070624 -124.7085)
			(xy 357.110773 -124.669791) (xy 357.156131 -124.63734) (xy 357.205731 -124.611839) (xy 357.258515 -124.593832)
			(xy 357.313358 -124.583702) (xy 357.369092 -124.581665) (xy 357.424529 -124.587765) (xy 357.478486 -124.601871)
			(xy 357.529815 -124.623683) (xy 357.577421 -124.652737) (xy 357.620289 -124.688412) (xy 357.657506 -124.729949)
			(xy 357.688279 -124.776462) (xy 357.711951 -124.826959) (xy 357.728019 -124.880366) (xy 357.736139 -124.935542)
			(xy 357.736648 -124.963428) (xy 357.736139 -124.991314) (xy 357.729552 -125.036072) (xy 359.186224 -125.036072)
			(xy 359.190295 -124.98045) (xy 359.202421 -124.926013) (xy 359.222344 -124.873922) (xy 359.24964 -124.825287)
			(xy 359.283726 -124.781144) (xy 359.323875 -124.742435) (xy 359.369233 -124.709984) (xy 359.418833 -124.684483)
			(xy 359.471617 -124.666476) (xy 359.52646 -124.656346) (xy 359.582194 -124.654309) (xy 359.637631 -124.660409)
			(xy 359.691588 -124.674515) (xy 359.742917 -124.696327) (xy 359.790523 -124.725381) (xy 359.833391 -124.761056)
			(xy 359.870608 -124.802593) (xy 359.901381 -124.849106) (xy 359.925053 -124.899603) (xy 359.941121 -124.95301)
			(xy 359.949241 -125.008186) (xy 359.94975 -125.036072) (xy 359.949241 -125.063958) (xy 359.941121 -125.119134)
			(xy 359.925053 -125.172541) (xy 359.901381 -125.223038) (xy 359.870608 -125.269551) (xy 359.833391 -125.311088)
			(xy 359.790523 -125.346763) (xy 359.742917 -125.375817) (xy 359.691588 -125.397629) (xy 359.637631 -125.411735)
			(xy 359.582194 -125.417835) (xy 359.52646 -125.415798) (xy 359.471617 -125.405668) (xy 359.418833 -125.387661)
			(xy 359.369233 -125.36216) (xy 359.323875 -125.329709) (xy 359.283726 -125.291) (xy 359.24964 -125.246857)
			(xy 359.222344 -125.198222) (xy 359.202421 -125.146131) (xy 359.190295 -125.091694) (xy 359.186224 -125.036072)
			(xy 357.729552 -125.036072) (xy 357.728019 -125.04649) (xy 357.711951 -125.099897) (xy 357.688279 -125.150394)
			(xy 357.657506 -125.196907) (xy 357.620289 -125.238444) (xy 357.577421 -125.274119) (xy 357.529815 -125.303173)
			(xy 357.478486 -125.324985) (xy 357.424529 -125.339091) (xy 357.369092 -125.345191) (xy 357.313358 -125.343154)
			(xy 357.258515 -125.333024) (xy 357.205731 -125.315017) (xy 357.156131 -125.289516) (xy 357.110773 -125.257065)
			(xy 357.070624 -125.218356) (xy 357.036538 -125.174213) (xy 357.009242 -125.125578) (xy 356.989319 -125.073487)
			(xy 356.977193 -125.01905) (xy 356.973122 -124.963428) (xy 337.273859 -124.963428) (xy 337.300797 -124.985846)
			(xy 337.338014 -125.027383) (xy 337.368787 -125.073896) (xy 337.392459 -125.124393) (xy 337.408527 -125.1778)
			(xy 337.416647 -125.232976) (xy 337.417156 -125.260862) (xy 337.416647 -125.288748) (xy 337.408527 -125.343924)
			(xy 337.392459 -125.397331) (xy 337.368787 -125.447828) (xy 337.338014 -125.494341) (xy 337.300797 -125.535878)
			(xy 337.257929 -125.571553) (xy 337.210323 -125.600607) (xy 337.158994 -125.622419) (xy 337.105037 -125.636525)
			(xy 337.0496 -125.642625) (xy 336.993866 -125.640588) (xy 336.939023 -125.630458) (xy 336.886239 -125.612451)
			(xy 336.836639 -125.58695) (xy 336.791281 -125.554499) (xy 336.751132 -125.51579) (xy 336.717046 -125.471647)
			(xy 336.68975 -125.423012) (xy 336.669827 -125.370921) (xy 336.657701 -125.316484) (xy 336.65363 -125.260862)
			(xy 334.11287 -125.260862) (xy 334.11287 -125.979428) (xy 356.973122 -125.979428) (xy 356.977193 -125.923806)
			(xy 356.989319 -125.869369) (xy 357.009242 -125.817278) (xy 357.036538 -125.768643) (xy 357.070624 -125.7245)
			(xy 357.110773 -125.685791) (xy 357.156131 -125.65334) (xy 357.205731 -125.627839) (xy 357.258515 -125.609832)
			(xy 357.313358 -125.599702) (xy 357.369092 -125.597665) (xy 357.424529 -125.603765) (xy 357.478486 -125.617871)
			(xy 357.529815 -125.639683) (xy 357.577421 -125.668737) (xy 357.620289 -125.704412) (xy 357.657506 -125.745949)
			(xy 357.688279 -125.792462) (xy 357.711951 -125.842959) (xy 357.727562 -125.894846) (xy 359.386884 -125.894846)
			(xy 359.390955 -125.839224) (xy 359.403081 -125.784787) (xy 359.423004 -125.732696) (xy 359.4503 -125.684061)
			(xy 359.484386 -125.639918) (xy 359.524535 -125.601209) (xy 359.569893 -125.568758) (xy 359.619493 -125.543257)
			(xy 359.672277 -125.52525) (xy 359.72712 -125.51512) (xy 359.782854 -125.513083) (xy 359.838291 -125.519183)
			(xy 359.892248 -125.533289) (xy 359.943577 -125.555101) (xy 359.991183 -125.584155) (xy 360.034051 -125.61983)
			(xy 360.071268 -125.661367) (xy 360.102041 -125.70788) (xy 360.125713 -125.758377) (xy 360.141781 -125.811784)
			(xy 360.149901 -125.86696) (xy 360.15041 -125.894846) (xy 360.149901 -125.922732) (xy 360.141781 -125.977908)
			(xy 360.125713 -126.031315) (xy 360.102041 -126.081812) (xy 360.071268 -126.128325) (xy 360.034051 -126.169862)
			(xy 359.991183 -126.205537) (xy 359.943577 -126.234591) (xy 359.892248 -126.256403) (xy 359.838291 -126.270509)
			(xy 359.782854 -126.276609) (xy 359.72712 -126.274572) (xy 359.672277 -126.264442) (xy 359.619493 -126.246435)
			(xy 359.569893 -126.220934) (xy 359.524535 -126.188483) (xy 359.484386 -126.149774) (xy 359.4503 -126.105631)
			(xy 359.423004 -126.056996) (xy 359.403081 -126.004905) (xy 359.390955 -125.950468) (xy 359.386884 -125.894846)
			(xy 357.727562 -125.894846) (xy 357.728019 -125.896366) (xy 357.736139 -125.951542) (xy 357.736648 -125.979428)
			(xy 357.736139 -126.007314) (xy 357.728019 -126.06249) (xy 357.711951 -126.115897) (xy 357.688279 -126.166394)
			(xy 357.657506 -126.212907) (xy 357.620289 -126.254444) (xy 357.577421 -126.290119) (xy 357.529815 -126.319173)
			(xy 357.478486 -126.340985) (xy 357.424529 -126.355091) (xy 357.369092 -126.361191) (xy 357.313358 -126.359154)
			(xy 357.258515 -126.349024) (xy 357.205731 -126.331017) (xy 357.156131 -126.305516) (xy 357.110773 -126.273065)
			(xy 357.070624 -126.234356) (xy 357.036538 -126.190213) (xy 357.009242 -126.141578) (xy 356.989319 -126.089487)
			(xy 356.977193 -126.03505) (xy 356.973122 -125.979428) (xy 334.11287 -125.979428) (xy 334.11287 -126.995428)
			(xy 356.973122 -126.995428) (xy 356.977193 -126.939806) (xy 356.989319 -126.885369) (xy 357.009242 -126.833278)
			(xy 357.036538 -126.784643) (xy 357.070624 -126.7405) (xy 357.110773 -126.701791) (xy 357.156131 -126.66934)
			(xy 357.205731 -126.643839) (xy 357.258515 -126.625832) (xy 357.313358 -126.615702) (xy 357.369092 -126.613665)
			(xy 357.424529 -126.619765) (xy 357.478486 -126.633871) (xy 357.529815 -126.655683) (xy 357.577421 -126.684737)
			(xy 357.620289 -126.720412) (xy 357.657506 -126.761949) (xy 357.688279 -126.808462) (xy 357.711951 -126.858959)
			(xy 357.728019 -126.912366) (xy 357.736139 -126.967542) (xy 357.736648 -126.995428) (xy 357.736139 -127.023314)
			(xy 357.732019 -127.051308) (xy 359.044238 -127.051308) (xy 359.048309 -126.995686) (xy 359.060435 -126.941249)
			(xy 359.080358 -126.889158) (xy 359.107654 -126.840523) (xy 359.14174 -126.79638) (xy 359.181889 -126.757671)
			(xy 359.227247 -126.72522) (xy 359.276847 -126.699719) (xy 359.329631 -126.681712) (xy 359.384474 -126.671582)
			(xy 359.440208 -126.669545) (xy 359.495645 -126.675645) (xy 359.549602 -126.689751) (xy 359.600931 -126.711563)
			(xy 359.648537 -126.740617) (xy 359.691405 -126.776292) (xy 359.728622 -126.817829) (xy 359.759395 -126.864342)
			(xy 359.783067 -126.914839) (xy 359.799135 -126.968246) (xy 359.807255 -127.023422) (xy 359.807764 -127.051308)
			(xy 359.807255 -127.079194) (xy 359.799135 -127.13437) (xy 359.783067 -127.187777) (xy 359.759395 -127.238274)
			(xy 359.728622 -127.284787) (xy 359.691405 -127.326324) (xy 359.648537 -127.361999) (xy 359.600931 -127.391053)
			(xy 359.549602 -127.412865) (xy 359.495645 -127.426971) (xy 359.440208 -127.433071) (xy 359.384474 -127.431034)
			(xy 359.329631 -127.420904) (xy 359.276847 -127.402897) (xy 359.227247 -127.377396) (xy 359.181889 -127.344945)
			(xy 359.14174 -127.306236) (xy 359.107654 -127.262093) (xy 359.080358 -127.213458) (xy 359.060435 -127.161367)
			(xy 359.048309 -127.10693) (xy 359.044238 -127.051308) (xy 357.732019 -127.051308) (xy 357.728019 -127.07849)
			(xy 357.711951 -127.131897) (xy 357.688279 -127.182394) (xy 357.657506 -127.228907) (xy 357.620289 -127.270444)
			(xy 357.577421 -127.306119) (xy 357.529815 -127.335173) (xy 357.478486 -127.356985) (xy 357.424529 -127.371091)
			(xy 357.369092 -127.377191) (xy 357.313358 -127.375154) (xy 357.258515 -127.365024) (xy 357.205731 -127.347017)
			(xy 357.156131 -127.321516) (xy 357.110773 -127.289065) (xy 357.070624 -127.250356) (xy 357.036538 -127.206213)
			(xy 357.009242 -127.157578) (xy 356.989319 -127.105487) (xy 356.977193 -127.05105) (xy 356.973122 -126.995428)
			(xy 334.11287 -126.995428) (xy 334.11287 -128.252747) (xy 358.028528 -128.252747) (xy 358.028528 -128.198253)
			(xy 358.036283 -128.144313) (xy 358.051636 -128.092025) (xy 358.074274 -128.042455) (xy 358.103736 -127.996611)
			(xy 358.139422 -127.955426) (xy 358.180606 -127.919739) (xy 358.22645 -127.890277) (xy 358.27602 -127.867638)
			(xy 358.328307 -127.852285) (xy 358.382247 -127.844529) (xy 358.409494 -127.844042) (xy 358.436865 -127.844501)
			(xy 358.491044 -127.852319) (xy 358.543548 -127.867809) (xy 358.593295 -127.890653) (xy 358.639261 -127.92038)
			(xy 358.660192 -127.938022) (xy 358.660446 -127.938276) (xy 358.667537 -127.943855) (xy 358.684451 -127.950104)
			(xy 358.693466 -127.950468) (xy 358.760522 -127.950468) (xy 358.769541 -127.950129) (xy 358.786458 -127.94387)
			(xy 358.793542 -127.938276) (xy 358.793542 -127.938022) (xy 358.793796 -127.938022) (xy 358.814729 -127.920381)
			(xy 358.860697 -127.890657) (xy 358.910443 -127.867811) (xy 358.962945 -127.852315) (xy 359.017123 -127.844486)
			(xy 359.071865 -127.844486) (xy 359.126043 -127.852315) (xy 359.178545 -127.867811) (xy 359.228291 -127.890657)
			(xy 359.274259 -127.920381) (xy 359.295192 -127.938022) (xy 359.295446 -127.938276) (xy 359.302537 -127.943855)
			(xy 359.319451 -127.950104) (xy 359.328466 -127.950468) (xy 359.395522 -127.950468) (xy 359.404541 -127.950129)
			(xy 359.421458 -127.94387) (xy 359.428542 -127.938276) (xy 359.428542 -127.938022) (xy 359.428796 -127.938022)
			(xy 359.449722 -127.920375) (xy 359.495696 -127.890663) (xy 359.545445 -127.867829) (xy 359.597947 -127.85234)
			(xy 359.652124 -127.844514) (xy 359.679494 -127.844042) (xy 359.706751 -127.844405) (xy 359.760709 -127.852162)
			(xy 359.813015 -127.867519) (xy 359.862602 -127.890165) (xy 359.908462 -127.919636) (xy 359.949661 -127.955335)
			(xy 359.98536 -127.996533) (xy 360.014833 -128.042392) (xy 360.037478 -128.091979) (xy 360.052837 -128.144285)
			(xy 360.060595 -128.198243) (xy 360.060595 -128.252757) (xy 360.052837 -128.306715) (xy 360.037478 -128.359021)
			(xy 360.014833 -128.408608) (xy 359.98536 -128.454467) (xy 359.949661 -128.495665) (xy 359.908462 -128.531364)
			(xy 359.862602 -128.560835) (xy 359.813015 -128.583481) (xy 359.760709 -128.598838) (xy 359.706751 -128.606595)
			(xy 359.679494 -128.607058) (xy 359.652123 -128.606606) (xy 359.597943 -128.598786) (xy 359.545439 -128.583294)
			(xy 359.495693 -128.560449) (xy 359.449727 -128.530721) (xy 359.428796 -128.513078) (xy 359.428542 -128.512824)
			(xy 359.421454 -128.50724) (xy 359.404538 -128.500994) (xy 359.395522 -128.500632) (xy 359.328466 -128.500632)
			(xy 359.319447 -128.500966) (xy 359.302529 -128.507229) (xy 359.295446 -128.512824) (xy 359.295192 -128.513078)
			(xy 359.274259 -128.530719) (xy 359.228291 -128.560443) (xy 359.178545 -128.583289) (xy 359.126043 -128.598785)
			(xy 359.071865 -128.606614) (xy 359.017123 -128.606614) (xy 358.962945 -128.598785) (xy 358.910443 -128.583289)
			(xy 358.860697 -128.560443) (xy 358.814729 -128.530719) (xy 358.793796 -128.513078) (xy 358.793542 -128.512824)
			(xy 358.786454 -128.50724) (xy 358.769538 -128.500994) (xy 358.760522 -128.500632) (xy 358.693466 -128.500632)
			(xy 358.684447 -128.500966) (xy 358.667529 -128.507229) (xy 358.660446 -128.512824) (xy 358.660446 -128.513078)
			(xy 358.660192 -128.513078) (xy 358.639271 -128.530731) (xy 358.593295 -128.560441) (xy 358.543545 -128.583275)
			(xy 358.491042 -128.598763) (xy 358.436864 -128.606587) (xy 358.409494 -128.607058) (xy 358.382247 -128.606471)
			(xy 358.328307 -128.598715) (xy 358.27602 -128.583362) (xy 358.22645 -128.560723) (xy 358.180606 -128.531261)
			(xy 358.139422 -128.495574) (xy 358.103736 -128.454389) (xy 358.074274 -128.408545) (xy 358.051636 -128.358975)
			(xy 358.036283 -128.306687) (xy 358.028528 -128.252747) (xy 334.11287 -128.252747) (xy 334.11287 -129.089912)
			(xy 350.987104 -129.089912) (xy 350.991175 -129.03429) (xy 351.003301 -128.979853) (xy 351.023224 -128.927762)
			(xy 351.05052 -128.879127) (xy 351.084606 -128.834984) (xy 351.124755 -128.796275) (xy 351.170113 -128.763824)
			(xy 351.219713 -128.738323) (xy 351.272497 -128.720316) (xy 351.32734 -128.710186) (xy 351.383074 -128.708149)
			(xy 351.438511 -128.714249) (xy 351.492468 -128.728355) (xy 351.543797 -128.750167) (xy 351.591403 -128.779221)
			(xy 351.634271 -128.814896) (xy 351.671488 -128.856433) (xy 351.702261 -128.902946) (xy 351.725933 -128.953443)
			(xy 351.738563 -128.995424) (xy 353.680268 -128.995424) (xy 353.680754 -128.968173) (xy 353.68851 -128.914225)
			(xy 353.703865 -128.86193) (xy 353.726507 -128.812353) (xy 353.755973 -128.766503) (xy 353.791664 -128.725312)
			(xy 353.832855 -128.689621) (xy 353.878705 -128.660155) (xy 353.928282 -128.637513) (xy 353.980577 -128.622158)
			(xy 354.034525 -128.614402) (xy 354.089027 -128.614402) (xy 354.142975 -128.622158) (xy 354.19527 -128.637513)
			(xy 354.244847 -128.660155) (xy 354.290697 -128.689621) (xy 354.331888 -128.725312) (xy 354.367579 -128.766503)
			(xy 354.397045 -128.812353) (xy 354.419687 -128.86193) (xy 354.435042 -128.914225) (xy 354.442798 -128.968173)
			(xy 354.443284 -128.995424) (xy 354.442716 -129.02523) (xy 354.433422 -129.084112) (xy 354.415081 -129.140832)
			(xy 354.388139 -129.194007) (xy 354.353252 -129.242344) (xy 354.311269 -129.284664) (xy 354.287582 -129.302764)
			(xy 354.276455 -129.31143) (xy 354.25915 -129.333688) (xy 354.248595 -129.359833) (xy 354.245596 -129.387867)
			(xy 354.250383 -129.415652) (xy 354.262589 -129.441068) (xy 354.281284 -129.462173) (xy 354.292916 -129.47015)
			(xy 354.315638 -129.485287) (xy 354.356946 -129.520983) (xy 354.392746 -129.562203) (xy 354.422305 -129.608104)
			(xy 354.44502 -129.657749) (xy 354.460429 -129.710125) (xy 354.468215 -129.764162) (xy 354.468684 -129.79146)
			(xy 354.468198 -129.818711) (xy 354.460442 -129.872659) (xy 354.445087 -129.924954) (xy 354.422445 -129.974531)
			(xy 354.392979 -130.020381) (xy 354.357288 -130.061572) (xy 354.316097 -130.097263) (xy 354.270247 -130.126729)
			(xy 354.22067 -130.149371) (xy 354.168375 -130.164726) (xy 354.114427 -130.172482) (xy 354.059925 -130.172482)
			(xy 354.005977 -130.164726) (xy 353.953682 -130.149371) (xy 353.904105 -130.126729) (xy 353.858255 -130.097263)
			(xy 353.817064 -130.061572) (xy 353.781373 -130.020381) (xy 353.751907 -129.974531) (xy 353.729265 -129.924954)
			(xy 353.71391 -129.872659) (xy 353.706154 -129.818711) (xy 353.705668 -129.79146) (xy 353.706203 -129.761653)
			(xy 353.715501 -129.702768) (xy 353.733847 -129.646047) (xy 353.760795 -129.592871) (xy 353.795689 -129.544535)
			(xy 353.837679 -129.502218) (xy 353.86137 -129.48412) (xy 353.872506 -129.475469) (xy 353.889803 -129.453204)
			(xy 353.900351 -129.427058) (xy 353.903345 -129.399023) (xy 353.898558 -129.371239) (xy 353.886355 -129.345823)
			(xy 353.867666 -129.324714) (xy 353.856036 -129.316734) (xy 353.833296 -129.301624) (xy 353.79199 -129.265921)
			(xy 353.756194 -129.224696) (xy 353.726638 -129.17879) (xy 353.703925 -129.129141) (xy 353.688519 -129.076762)
			(xy 353.680736 -129.022723) (xy 353.680268 -128.995424) (xy 351.738563 -128.995424) (xy 351.742001 -129.00685)
			(xy 351.750121 -129.062026) (xy 351.75063 -129.089912) (xy 351.750121 -129.117798) (xy 351.742001 -129.172974)
			(xy 351.725933 -129.226381) (xy 351.702261 -129.276878) (xy 351.671488 -129.323391) (xy 351.634271 -129.364928)
			(xy 351.591403 -129.400603) (xy 351.543797 -129.429657) (xy 351.492468 -129.451469) (xy 351.438511 -129.465575)
			(xy 351.383074 -129.471675) (xy 351.32734 -129.469638) (xy 351.272497 -129.459508) (xy 351.219713 -129.441501)
			(xy 351.170113 -129.416) (xy 351.124755 -129.383549) (xy 351.084606 -129.34484) (xy 351.05052 -129.300697)
			(xy 351.023224 -129.252062) (xy 351.003301 -129.199971) (xy 350.991175 -129.145534) (xy 350.987104 -129.089912)
			(xy 334.11287 -129.089912) (xy 334.11287 -130.362452) (xy 336.328002 -130.362452) (xy 336.332073 -130.30683)
			(xy 336.344199 -130.252393) (xy 336.364122 -130.200302) (xy 336.391418 -130.151667) (xy 336.425504 -130.107524)
			(xy 336.465653 -130.068815) (xy 336.511011 -130.036364) (xy 336.560611 -130.010863) (xy 336.613395 -129.992856)
			(xy 336.668238 -129.982726) (xy 336.723972 -129.980689) (xy 336.779409 -129.986789) (xy 336.833366 -130.000895)
			(xy 336.884695 -130.022707) (xy 336.932301 -130.051761) (xy 336.975169 -130.087436) (xy 337.012386 -130.128973)
			(xy 337.043159 -130.175486) (xy 337.066831 -130.225983) (xy 337.082899 -130.27939) (xy 337.091019 -130.334566)
			(xy 337.091528 -130.362452) (xy 337.091019 -130.390338) (xy 337.082899 -130.445514) (xy 337.066831 -130.498921)
			(xy 337.043159 -130.549418) (xy 337.012386 -130.595931) (xy 336.975169 -130.637468) (xy 336.932301 -130.673143)
			(xy 336.884695 -130.702197) (xy 336.833366 -130.724009) (xy 336.779409 -130.738115) (xy 336.723972 -130.744215)
			(xy 336.668238 -130.742178) (xy 336.613395 -130.732048) (xy 336.560611 -130.714041) (xy 336.511011 -130.68854)
			(xy 336.465653 -130.656089) (xy 336.425504 -130.61738) (xy 336.391418 -130.573237) (xy 336.364122 -130.524602)
			(xy 336.344199 -130.472511) (xy 336.332073 -130.418074) (xy 336.328002 -130.362452) (xy 334.11287 -130.362452)
			(xy 334.11287 -131.214114) (xy 351.13036 -131.214114) (xy 351.134431 -131.158492) (xy 351.146557 -131.104055)
			(xy 351.16648 -131.051964) (xy 351.193776 -131.003329) (xy 351.227862 -130.959186) (xy 351.268011 -130.920477)
			(xy 351.313369 -130.888026) (xy 351.362969 -130.862525) (xy 351.415753 -130.844518) (xy 351.470596 -130.834388)
			(xy 351.52633 -130.832351) (xy 351.581767 -130.838451) (xy 351.635724 -130.852557) (xy 351.687053 -130.874369)
			(xy 351.734659 -130.903423) (xy 351.777527 -130.939098) (xy 351.814744 -130.980635) (xy 351.845517 -131.027148)
			(xy 351.869189 -131.077645) (xy 351.885257 -131.131052) (xy 351.893377 -131.186228) (xy 351.893886 -131.214114)
			(xy 351.893377 -131.242) (xy 351.885257 -131.297176) (xy 351.869189 -131.350583) (xy 351.845517 -131.40108)
			(xy 351.815032 -131.447157) (xy 358.013409 -131.447157) (xy 358.013409 -131.392643) (xy 358.021167 -131.338685)
			(xy 358.036525 -131.28638) (xy 358.059171 -131.236794) (xy 358.088644 -131.190935) (xy 358.124342 -131.149737)
			(xy 358.165541 -131.114039) (xy 358.211401 -131.084567) (xy 358.260988 -131.061923) (xy 358.313293 -131.046565)
			(xy 358.367251 -131.038808) (xy 358.394508 -131.038346) (xy 358.421879 -131.038796) (xy 358.476059 -131.046616)
			(xy 358.528563 -131.062108) (xy 358.57831 -131.084954) (xy 358.624275 -131.114683) (xy 358.645206 -131.132326)
			(xy 358.64546 -131.13258) (xy 358.652547 -131.138165) (xy 358.669464 -131.144411) (xy 358.67848 -131.144772)
			(xy 358.745536 -131.144772) (xy 358.754555 -131.144438) (xy 358.771472 -131.138175) (xy 358.778556 -131.13258)
			(xy 358.778556 -131.132326) (xy 358.77881 -131.132326) (xy 358.799743 -131.114685) (xy 358.845711 -131.084961)
			(xy 358.895457 -131.062115) (xy 358.947959 -131.046619) (xy 359.002137 -131.03879) (xy 359.056879 -131.03879)
			(xy 359.111057 -131.046619) (xy 359.163559 -131.062115) (xy 359.213305 -131.084961) (xy 359.259273 -131.114685)
			(xy 359.280206 -131.132326) (xy 359.28046 -131.13258) (xy 359.287547 -131.138165) (xy 359.304464 -131.144411)
			(xy 359.31348 -131.144772) (xy 359.380536 -131.144772) (xy 359.389555 -131.144438) (xy 359.406472 -131.138175)
			(xy 359.413556 -131.13258) (xy 359.413556 -131.132326) (xy 359.41381 -131.132326) (xy 359.434731 -131.114673)
			(xy 359.480706 -131.084962) (xy 359.530457 -131.062129) (xy 359.58296 -131.046641) (xy 359.637138 -131.038817)
			(xy 359.664508 -131.038346) (xy 359.691756 -131.038925) (xy 359.745696 -131.046681) (xy 359.797983 -131.062035)
			(xy 359.847553 -131.084674) (xy 359.893397 -131.114137) (xy 359.934582 -131.149824) (xy 359.970268 -131.191009)
			(xy 359.99973 -131.236854) (xy 360.022368 -131.286424) (xy 360.037721 -131.338712) (xy 360.045476 -131.392652)
			(xy 360.045476 -131.447148) (xy 360.037721 -131.501088) (xy 360.022368 -131.553376) (xy 359.99973 -131.602946)
			(xy 359.970268 -131.648791) (xy 359.934582 -131.689976) (xy 359.893397 -131.725663) (xy 359.847553 -131.755126)
			(xy 359.797983 -131.777765) (xy 359.745696 -131.793119) (xy 359.691756 -131.800875) (xy 359.664508 -131.801362)
			(xy 359.637137 -131.800901) (xy 359.582958 -131.793083) (xy 359.530454 -131.777593) (xy 359.480708 -131.75475)
			(xy 359.434741 -131.725024) (xy 359.41381 -131.707382) (xy 359.413556 -131.707128) (xy 359.406464 -131.70155)
			(xy 359.389551 -131.6953) (xy 359.380536 -131.694936) (xy 359.31348 -131.694936) (xy 359.304461 -131.695276)
			(xy 359.287544 -131.701534) (xy 359.28046 -131.707128) (xy 359.280206 -131.707382) (xy 359.259273 -131.725023)
			(xy 359.213305 -131.754747) (xy 359.163559 -131.777593) (xy 359.111057 -131.793089) (xy 359.056879 -131.800918)
			(xy 359.002137 -131.800918) (xy 358.947959 -131.793089) (xy 358.895457 -131.777593) (xy 358.845711 -131.754747)
			(xy 358.799743 -131.725023) (xy 358.77881 -131.707382) (xy 358.778556 -131.707128) (xy 358.771464 -131.70155)
			(xy 358.754551 -131.6953) (xy 358.745536 -131.694936) (xy 358.67848 -131.694936) (xy 358.669461 -131.695276)
			(xy 358.652544 -131.701534) (xy 358.64546 -131.707128) (xy 358.64546 -131.707382) (xy 358.645206 -131.707382)
			(xy 358.62428 -131.725029) (xy 358.578306 -131.75474) (xy 358.528557 -131.777575) (xy 358.476055 -131.793064)
			(xy 358.421878 -131.80089) (xy 358.394508 -131.801362) (xy 358.367251 -131.800992) (xy 358.313293 -131.793235)
			(xy 358.260988 -131.777877) (xy 358.211401 -131.755233) (xy 358.165541 -131.725761) (xy 358.124342 -131.690063)
			(xy 358.088644 -131.648865) (xy 358.059171 -131.603006) (xy 358.036525 -131.55342) (xy 358.021167 -131.501115)
			(xy 358.013409 -131.447157) (xy 351.815032 -131.447157) (xy 351.814744 -131.447593) (xy 351.777527 -131.48913)
			(xy 351.734659 -131.524805) (xy 351.687053 -131.553859) (xy 351.635724 -131.575671) (xy 351.581767 -131.589777)
			(xy 351.52633 -131.595877) (xy 351.470596 -131.59384) (xy 351.415753 -131.58371) (xy 351.362969 -131.565703)
			(xy 351.313369 -131.540202) (xy 351.268011 -131.507751) (xy 351.227862 -131.469042) (xy 351.193776 -131.424899)
			(xy 351.16648 -131.376264) (xy 351.146557 -131.324173) (xy 351.134431 -131.269736) (xy 351.13036 -131.214114)
			(xy 334.11287 -131.214114) (xy 334.11287 -134.042404) (xy 354.476048 -134.042404) (xy 354.480119 -133.986782)
			(xy 354.492245 -133.932345) (xy 354.512168 -133.880254) (xy 354.539464 -133.831619) (xy 354.57355 -133.787476)
			(xy 354.613699 -133.748767) (xy 354.659057 -133.716316) (xy 354.708657 -133.690815) (xy 354.761441 -133.672808)
			(xy 354.816284 -133.662678) (xy 354.872018 -133.660641) (xy 354.927455 -133.666741) (xy 354.981412 -133.680847)
			(xy 355.032741 -133.702659) (xy 355.080347 -133.731713) (xy 355.123215 -133.767388) (xy 355.160432 -133.808925)
			(xy 355.191205 -133.855438) (xy 355.214877 -133.905935) (xy 355.230945 -133.959342) (xy 355.239065 -134.014518)
			(xy 355.239574 -134.042404) (xy 355.239065 -134.07029) (xy 355.230945 -134.125466) (xy 355.214877 -134.178873)
			(xy 355.191205 -134.22937) (xy 355.160432 -134.275883) (xy 355.123215 -134.31742) (xy 355.080347 -134.353095)
			(xy 355.032741 -134.382149) (xy 354.981412 -134.403961) (xy 354.927455 -134.418067) (xy 354.872018 -134.424167)
			(xy 354.816284 -134.42213) (xy 354.761441 -134.412) (xy 354.708657 -134.393993) (xy 354.659057 -134.368492)
			(xy 354.613699 -134.336041) (xy 354.57355 -134.297332) (xy 354.539464 -134.253189) (xy 354.512168 -134.204554)
			(xy 354.492245 -134.152463) (xy 354.480119 -134.098026) (xy 354.476048 -134.042404) (xy 334.11287 -134.042404)
			(xy 334.11287 -134.083044) (xy 334.1133 -134.093111) (xy 334.121023 -134.111707) (xy 334.127856 -134.119112)
			(xy 335.067148 -135.058404) (xy 354.476048 -135.058404) (xy 354.480119 -135.002782) (xy 354.492245 -134.948345)
			(xy 354.512168 -134.896254) (xy 354.539464 -134.847619) (xy 354.57355 -134.803476) (xy 354.613699 -134.764767)
			(xy 354.659057 -134.732316) (xy 354.708657 -134.706815) (xy 354.761441 -134.688808) (xy 354.816284 -134.678678)
			(xy 354.872018 -134.676641) (xy 354.927455 -134.682741) (xy 354.981412 -134.696847) (xy 355.032741 -134.718659)
			(xy 355.080347 -134.747713) (xy 355.123215 -134.783388) (xy 355.160432 -134.824925) (xy 355.191205 -134.871438)
			(xy 355.214877 -134.921935) (xy 355.230945 -134.975342) (xy 355.239065 -135.030518) (xy 355.239574 -135.058404)
			(xy 355.239065 -135.08629) (xy 355.230945 -135.141466) (xy 355.214877 -135.194873) (xy 355.191205 -135.24537)
			(xy 355.160432 -135.291883) (xy 355.123215 -135.33342) (xy 355.080347 -135.369095) (xy 355.032741 -135.398149)
			(xy 354.981412 -135.419961) (xy 354.927455 -135.434067) (xy 354.872018 -135.440167) (xy 354.816284 -135.43813)
			(xy 354.761441 -135.428) (xy 354.708657 -135.409993) (xy 354.659057 -135.384492) (xy 354.613699 -135.352041)
			(xy 354.57355 -135.313332) (xy 354.539464 -135.269189) (xy 354.512168 -135.220554) (xy 354.492245 -135.168463)
			(xy 354.480119 -135.114026) (xy 354.476048 -135.058404) (xy 335.067148 -135.058404) (xy 336.011266 -136.002522)
			(xy 336.018664 -136.009366) (xy 336.037264 -136.017089) (xy 336.047334 -136.017508) (xy 354.613718 -136.017508)
			(xy 354.617525 -136.017442) (xy 354.625051 -136.016293) (xy 354.628704 -136.015222) (xy 354.64877 -136.009126)
			(xy 354.653342 -136.006332) (xy 354.666352 -135.99828) (xy 354.693436 -135.984039) (xy 354.707444 -135.977884)
			(xy 354.731226 -135.968126) (xy 354.780751 -135.954356) (xy 354.831675 -135.947345) (xy 354.88308 -135.947221)
			(xy 354.908612 -135.950198) (xy 354.93706 -135.955024) (xy 354.969963 -135.962724) (xy 355.032563 -135.988152)
			(xy 355.06152 -136.00557) (xy 355.073966 -136.011158) (xy 355.087682 -136.015222) (xy 355.091279 -136.016255)
			(xy 355.098674 -136.017396) (xy 355.102414 -136.017508) (xy 356.44074 -136.017508) (xy 356.450392 -136.016492)
			(xy 356.457634 -136.01486) (xy 356.470798 -136.008014) (xy 356.4763 -136.00303) (xy 356.778306 -135.701024)
			(xy 356.781862 -135.693912) (xy 356.79599 -135.667376) (xy 356.831305 -135.618729) (xy 356.87381 -135.57622)
			(xy 356.922455 -135.540902) (xy 356.948994 -135.52678) (xy 356.956106 -135.523224) (xy 359.123996 -133.355334)
			(xy 359.131393 -133.348483) (xy 359.149991 -133.340742) (xy 359.160064 -133.340348) (xy 359.400602 -133.340348)
			(xy 359.410876 -133.339879) (xy 359.429782 -133.331832) (xy 359.444028 -133.317025) (xy 359.4481 -133.307582)
			(xy 359.459083 -133.280283) (xy 359.488225 -133.229166) (xy 359.52487 -133.18313) (xy 359.546144 -133.162802)
			(xy 359.553593 -133.155311) (xy 359.562132 -133.136015) (xy 359.562654 -133.125464) (xy 359.562654 -133.050788)
			(xy 359.562079 -133.040248) (xy 359.553561 -133.020959) (xy 359.546144 -133.01345) (xy 359.527089 -132.995295)
			(xy 359.493643 -132.954658) (xy 359.46609 -132.909815) (xy 359.444951 -132.861616) (xy 359.430626 -132.810972)
			(xy 359.423387 -132.758841) (xy 359.422954 -132.732526) (xy 359.423438 -132.705273) (xy 359.431191 -132.65132)
			(xy 359.446544 -132.59902) (xy 359.469183 -132.549437) (xy 359.498648 -132.503581) (xy 359.534339 -132.462384)
			(xy 359.575529 -132.426686) (xy 359.621381 -132.397214) (xy 359.67096 -132.374566) (xy 359.723257 -132.359205)
			(xy 359.777209 -132.351443) (xy 359.804462 -132.351018) (xy 359.831126 -132.35146) (xy 359.883935 -132.358882)
			(xy 359.935196 -132.373586) (xy 359.983909 -132.395287) (xy 360.029125 -132.42356) (xy 360.069963 -132.457855)
			(xy 360.105626 -132.497503) (xy 360.13542 -132.541732) (xy 360.158763 -132.58968) (xy 360.175202 -132.640411)
			(xy 360.184415 -132.692937) (xy 360.185716 -132.719572) (xy 360.185716 -132.719826) (xy 360.186552 -132.729598)
			(xy 360.194615 -132.747458) (xy 360.208784 -132.760995) (xy 360.21772 -132.765038) (xy 360.304588 -132.799328)
			(xy 360.313954 -132.802506) (xy 360.333712 -132.802259) (xy 360.351925 -132.794596) (xy 360.359198 -132.787898)
			(xy 360.374692 -132.772404) (xy 360.38154 -132.765006) (xy 360.389277 -132.746408) (xy 360.389678 -132.736336)
			(xy 360.389678 -123.573794) (xy 360.389052 -123.56166) (xy 360.378036 -123.540043) (xy 360.368596 -123.532392)
			(xy 360.346295 -123.515738) (xy 360.306304 -123.477028) (xy 360.272358 -123.432921) (xy 360.245179 -123.384351)
			(xy 360.225343 -123.332349) (xy 360.21327 -123.278017) (xy 360.209216 -123.222507) (xy 360.213268 -123.166997)
			(xy 360.225339 -123.112665) (xy 360.245173 -123.060662) (xy 360.272351 -123.012091) (xy 360.306294 -122.967982)
			(xy 360.346285 -122.929271) (xy 360.368596 -122.912632) (xy 360.37801 -122.904967) (xy 360.388991 -122.883354)
			(xy 360.389678 -122.87123) (xy 360.389678 -119.764556) (xy 360.36504 -119.736108) (xy 360.346244 -119.733314)
			(xy 360.319398 -119.728903) (xy 360.267232 -119.713467) (xy 360.217787 -119.690776) (xy 360.172069 -119.661289)
			(xy 360.131004 -119.625606) (xy 360.095426 -119.58445) (xy 360.066056 -119.538656) (xy 360.043491 -119.489154)
			(xy 360.028189 -119.436948) (xy 360.02046 -119.383097) (xy 360.02046 -119.328694) (xy 360.028191 -119.274844)
			(xy 360.043494 -119.222638) (xy 360.06606 -119.173137) (xy 360.095431 -119.127343) (xy 360.13101 -119.086188)
			(xy 360.172076 -119.050506) (xy 360.217795 -119.02102) (xy 360.26724 -118.99833) (xy 360.319407 -118.982895)
			(xy 360.346244 -118.978426) (xy 360.36504 -118.975632) (xy 360.389678 -118.947184) (xy 360.389678 -117.609112)
			(xy 360.36504 -117.580664) (xy 360.346244 -117.57787) (xy 360.319394 -117.573459) (xy 360.26722 -117.558022)
			(xy 360.217768 -117.535328) (xy 360.172042 -117.505838) (xy 360.13097 -117.470151) (xy 360.095386 -117.428989)
			(xy 360.066011 -117.383189) (xy 360.043442 -117.333681) (xy 360.028136 -117.281467) (xy 360.020405 -117.227609)
			(xy 360.020404 -117.173199) (xy 360.028135 -117.11934) (xy 360.043439 -117.067126) (xy 360.066008 -117.017617)
			(xy 360.095382 -116.971817) (xy 360.130965 -116.930655) (xy 360.172036 -116.894966) (xy 360.217761 -116.865476)
			(xy 360.267213 -116.842781) (xy 360.319387 -116.827343) (xy 360.346244 -116.822982) (xy 360.36504 -116.820188)
			(xy 360.389678 -116.79174) (xy 360.389678 -116.360956) (xy 360.390108 -116.350889) (xy 360.397832 -116.332294)
			(xy 360.404664 -116.324888) (xy 361.170982 -115.55857) (xy 361.177166 -115.551921) (xy 361.184769 -115.535445)
			(xy 361.186109 -115.517349) (xy 361.183936 -115.508532) (xy 361.183936 -115.508278) (xy 361.176937 -115.482425)
			(xy 361.169418 -115.429394) (xy 361.16895 -115.402614) (xy 361.16895 -115.402106) (xy 361.169435 -115.374853)
			(xy 361.177191 -115.320903) (xy 361.192545 -115.268605) (xy 361.215185 -115.219024) (xy 361.244651 -115.17317)
			(xy 361.280342 -115.131976) (xy 361.321532 -115.09628) (xy 361.367382 -115.066808) (xy 361.41696 -115.044162)
			(xy 361.469256 -115.028801) (xy 361.523205 -115.021039) (xy 361.550458 -115.020598) (xy 361.577827 -115.021074)
			(xy 361.632001 -115.028905) (xy 361.6845 -115.044398) (xy 361.734245 -115.067236) (xy 361.780216 -115.096948)
			(xy 361.801156 -115.114578) (xy 361.80141 -115.114578) (xy 361.80141 -115.114832) (xy 361.808498 -115.120413)
			(xy 361.825415 -115.126647) (xy 361.83443 -115.127024) (xy 361.901486 -115.127024) (xy 361.910504 -115.126667)
			(xy 361.927425 -115.120426) (xy 361.934506 -115.114832) (xy 361.93476 -115.114578) (xy 361.955693 -115.09694)
			(xy 362.001661 -115.067223) (xy 362.051409 -115.044389) (xy 362.103911 -115.028908) (xy 362.158089 -115.021099)
			(xy 362.185458 -115.020598) (xy 362.213076 -115.021085) (xy 362.267736 -115.029049) (xy 362.320674 -115.044817)
			(xy 362.370783 -115.068058) (xy 362.417014 -115.098286) (xy 362.4584 -115.134868) (xy 362.494074 -115.177039)
			(xy 362.52329 -115.223916) (xy 362.545437 -115.274519) (xy 362.55325 -115.301014) (xy 362.55325 -115.301268)
			(xy 362.556751 -115.311771) (xy 362.571105 -115.328595) (xy 362.591211 -115.337805) (xy 362.602272 -115.338352)
			(xy 383.77368 -115.338352) (xy 383.783743 -115.337913) (xy 383.802321 -115.330173) (xy 383.809748 -115.323366)
			(xy 384.586226 -114.546888) (xy 384.593622 -114.540036) (xy 384.612221 -114.532297) (xy 384.622294 -114.531902)
			(xy 412.533338 -114.531902) (xy 412.533592 -114.531902) (xy 412.545368 -114.531231) (xy 412.566408 -114.52063)
			(xy 412.573978 -114.511582) (xy 412.622746 -114.44224) (xy 412.626125 -114.437183) (xy 412.630613 -114.425884)
			(xy 412.631636 -114.419888) (xy 412.63316 -114.40795) (xy 412.628842 -114.396012) (xy 412.618532 -114.365083)
			(xy 412.607426 -114.300845) (xy 412.606744 -114.26825) (xy 412.606744 -114.267742) (xy 412.607227 -114.240488)
			(xy 412.614978 -114.186533) (xy 412.630329 -114.13423) (xy 412.652967 -114.084645) (xy 412.682432 -114.038785)
			(xy 412.718123 -113.997586) (xy 412.759313 -113.961886) (xy 412.805166 -113.932411) (xy 412.854746 -113.909761)
			(xy 412.907045 -113.894397) (xy 412.960998 -113.886633) (xy 412.988252 -113.886234) (xy 413.00099 -113.886311)
			(xy 413.026412 -113.887961) (xy 413.039052 -113.889536) (xy 413.060544 -113.892703) (xy 413.102682 -113.903273)
			(xy 413.123126 -113.910618) (xy 413.133032 -113.914428) (xy 413.154368 -113.913412) (xy 413.231076 -113.874296)
			(xy 413.240233 -113.869064) (xy 413.253613 -113.852793) (xy 413.256984 -113.8428) (xy 413.256984 -113.842292)
			(xy 413.267583 -113.80577) (xy 413.296926 -113.735612) (xy 413.335087 -113.669833) (xy 413.381424 -113.609533)
			(xy 413.40786 -113.582196) (xy 414.918906 -112.07115) (xy 414.942471 -112.048255) (xy 414.993856 -112.007306)
			(xy 415.049499 -111.972364) (xy 415.108703 -111.943867) (xy 415.170724 -111.922173) (xy 415.234782 -111.907554)
			(xy 415.300073 -111.900195) (xy 415.332926 -111.8997) (xy 415.333434 -111.8997) (xy 415.362136 -111.900208)
			(xy 415.37255 -111.900716) (xy 415.392616 -111.89335) (xy 415.453576 -111.83366) (xy 415.460703 -111.825967)
			(xy 415.468571 -111.806552) (xy 415.468816 -111.796068) (xy 415.468816 -111.795814) (xy 415.468562 -111.785146)
			(xy 415.468562 -111.784638) (xy 415.469051 -111.757294) (xy 415.476898 -111.703172) (xy 415.492395 -111.650725)
			(xy 415.515223 -111.601029) (xy 415.544914 -111.555103) (xy 415.562542 -111.534194) (xy 415.562542 -111.53394)
			(xy 415.562796 -111.53394) (xy 415.568387 -111.526855) (xy 415.574643 -111.509938) (xy 415.574988 -111.50092)
			(xy 415.574988 -111.433864) (xy 415.574622 -111.42485) (xy 415.568365 -111.407943) (xy 415.562796 -111.400844)
			(xy 415.562542 -111.40059) (xy 415.544901 -111.379658) (xy 415.515176 -111.33369) (xy 415.492331 -111.283944)
			(xy 415.476835 -111.231443) (xy 415.469007 -111.177264) (xy 415.469008 -111.122524) (xy 415.476838 -111.068346)
			(xy 415.492336 -111.015844) (xy 415.515182 -110.966099) (xy 415.544909 -110.920133) (xy 415.562542 -110.899194)
			(xy 415.562542 -110.89894) (xy 415.562796 -110.89894) (xy 415.568387 -110.891855) (xy 415.574643 -110.874938)
			(xy 415.574988 -110.86592) (xy 415.574988 -110.798864) (xy 415.574622 -110.78985) (xy 415.568365 -110.772943)
			(xy 415.562796 -110.765844) (xy 415.562542 -110.76559) (xy 415.544901 -110.744658) (xy 415.515176 -110.69869)
			(xy 415.492331 -110.648944) (xy 415.476835 -110.596443) (xy 415.469007 -110.542264) (xy 415.469008 -110.487524)
			(xy 415.476838 -110.433346) (xy 415.492336 -110.380844) (xy 415.515182 -110.331099) (xy 415.544909 -110.285133)
			(xy 415.562542 -110.264194) (xy 415.562542 -110.26394) (xy 415.562796 -110.26394) (xy 415.568387 -110.256855)
			(xy 415.574643 -110.239938) (xy 415.574988 -110.23092) (xy 415.574988 -110.163864) (xy 415.574622 -110.15485)
			(xy 415.568365 -110.137943) (xy 415.562796 -110.130844) (xy 415.562542 -110.13059) (xy 415.544901 -110.109658)
			(xy 415.515176 -110.06369) (xy 415.492331 -110.013944) (xy 415.476835 -109.961443) (xy 415.469007 -109.907264)
			(xy 415.469008 -109.852524) (xy 415.476838 -109.798346) (xy 415.492336 -109.745844) (xy 415.515182 -109.696099)
			(xy 415.544909 -109.650133) (xy 415.562542 -109.629194) (xy 415.562542 -109.62894) (xy 415.562796 -109.62894)
			(xy 415.568387 -109.621855) (xy 415.574643 -109.604938) (xy 415.574988 -109.59592) (xy 415.574988 -109.528864)
			(xy 415.574622 -109.51985) (xy 415.568365 -109.502943) (xy 415.562796 -109.495844) (xy 415.562542 -109.49559)
			(xy 415.544899 -109.474659) (xy 415.515171 -109.428693) (xy 415.492326 -109.378947) (xy 415.476836 -109.326443)
			(xy 415.469018 -109.272263) (xy 415.468562 -109.244892) (xy 415.469048 -109.217641) (xy 415.476804 -109.163693)
			(xy 415.492159 -109.111398) (xy 415.514801 -109.061821) (xy 415.544267 -109.015971) (xy 415.579958 -108.97478)
			(xy 415.621149 -108.939089) (xy 415.666999 -108.909623) (xy 415.716576 -108.886981) (xy 415.768871 -108.871626)
			(xy 415.822819 -108.86387) (xy 415.877321 -108.86387) (xy 415.931269 -108.871626) (xy 415.983564 -108.886981)
			(xy 416.033141 -108.909623) (xy 416.078991 -108.939089) (xy 416.120182 -108.97478) (xy 416.155873 -109.015971)
			(xy 416.185339 -109.061821) (xy 416.207981 -109.111398) (xy 416.223336 -109.163693) (xy 416.231092 -109.217641)
			(xy 416.231578 -109.244892) (xy 416.231107 -109.272262) (xy 416.223284 -109.326441) (xy 416.207797 -109.378944)
			(xy 416.192149 -109.41304) (xy 420.129462 -109.41304) (xy 420.129948 -109.385789) (xy 420.137704 -109.331841)
			(xy 420.153059 -109.279546) (xy 420.175701 -109.229969) (xy 420.205167 -109.184119) (xy 420.240858 -109.142928)
			(xy 420.282049 -109.107237) (xy 420.327899 -109.077771) (xy 420.377476 -109.055129) (xy 420.429771 -109.039774)
			(xy 420.483719 -109.032018) (xy 420.538221 -109.032018) (xy 420.592169 -109.039774) (xy 420.644464 -109.055129)
			(xy 420.694041 -109.077771) (xy 420.739891 -109.107237) (xy 420.781082 -109.142928) (xy 420.816773 -109.184119)
			(xy 420.846239 -109.229969) (xy 420.868881 -109.279546) (xy 420.884236 -109.331841) (xy 420.891992 -109.385789)
			(xy 420.892478 -109.41304) (xy 420.892057 -109.439235) (xy 420.884888 -109.491133) (xy 420.87069 -109.541564)
			(xy 420.84973 -109.589579) (xy 420.822401 -109.634277) (xy 420.789218 -109.674819) (xy 420.770304 -109.692948)
			(xy 420.762949 -109.700564) (xy 420.75454 -109.719966) (xy 420.754048 -109.73054) (xy 420.754556 -109.816392)
			(xy 420.763192 -109.83595) (xy 420.77132 -109.843062) (xy 420.790878 -109.861206) (xy 420.825207 -109.902044)
			(xy 420.853508 -109.947268) (xy 420.875229 -109.995995) (xy 420.889946 -110.047275) (xy 420.897372 -110.100105)
			(xy 420.897812 -110.12678) (xy 420.897326 -110.154031) (xy 420.88957 -110.207979) (xy 420.874215 -110.260274)
			(xy 420.851573 -110.309851) (xy 420.822107 -110.355701) (xy 420.786416 -110.396892) (xy 420.745225 -110.432583)
			(xy 420.699375 -110.462049) (xy 420.649798 -110.484691) (xy 420.597503 -110.500046) (xy 420.543555 -110.507802)
			(xy 420.489053 -110.507802) (xy 420.435105 -110.500046) (xy 420.38281 -110.484691) (xy 420.333233 -110.462049)
			(xy 420.287383 -110.432583) (xy 420.246192 -110.396892) (xy 420.210501 -110.355701) (xy 420.181035 -110.309851)
			(xy 420.158393 -110.260274) (xy 420.143038 -110.207979) (xy 420.135282 -110.154031) (xy 420.134796 -110.12678)
			(xy 420.135239 -110.100585) (xy 420.142405 -110.048689) (xy 420.156599 -109.998259) (xy 420.177555 -109.950244)
			(xy 420.204879 -109.905545) (xy 420.238059 -109.865002) (xy 420.25697 -109.846872) (xy 420.264371 -109.839295)
			(xy 420.272751 -109.819863) (xy 420.273226 -109.80928) (xy 420.272718 -109.723428) (xy 420.264082 -109.70387)
			(xy 420.255954 -109.696758) (xy 420.2364 -109.678609) (xy 420.202072 -109.637772) (xy 420.173771 -109.592549)
			(xy 420.152049 -109.543822) (xy 420.137331 -109.492544) (xy 420.129904 -109.439715) (xy 420.129462 -109.41304)
			(xy 416.192149 -109.41304) (xy 416.184964 -109.428696) (xy 416.155255 -109.474672) (xy 416.137598 -109.49559)
			(xy 416.137598 -109.495844) (xy 416.137344 -109.495844) (xy 416.131746 -109.502927) (xy 416.12548 -109.519844)
			(xy 416.125152 -109.528864) (xy 416.125152 -109.59592) (xy 416.125514 -109.604936) (xy 416.131761 -109.621851)
			(xy 416.137344 -109.62894) (xy 416.137598 -109.629194) (xy 416.155238 -109.650127) (xy 416.184962 -109.696096)
			(xy 416.207807 -109.745842) (xy 416.223303 -109.798345) (xy 416.231132 -109.852523) (xy 416.231133 -109.907265)
			(xy 416.223306 -109.961444) (xy 416.207811 -110.013946) (xy 416.184968 -110.063694) (xy 416.155245 -110.109663)
			(xy 416.137598 -110.13059) (xy 416.137598 -110.130844) (xy 416.137344 -110.130844) (xy 416.131746 -110.137927)
			(xy 416.12548 -110.154844) (xy 416.125152 -110.163864) (xy 416.125152 -110.23092) (xy 416.125514 -110.239936)
			(xy 416.131761 -110.256851) (xy 416.137344 -110.26394) (xy 416.137598 -110.264194) (xy 416.155238 -110.285127)
			(xy 416.184962 -110.331096) (xy 416.207807 -110.380842) (xy 416.223303 -110.433345) (xy 416.231132 -110.487523)
			(xy 416.231133 -110.530132) (xy 418.729158 -110.530132) (xy 418.733229 -110.47451) (xy 418.745355 -110.420073)
			(xy 418.765278 -110.367982) (xy 418.792574 -110.319347) (xy 418.82666 -110.275204) (xy 418.866809 -110.236495)
			(xy 418.912167 -110.204044) (xy 418.961767 -110.178543) (xy 419.014551 -110.160536) (xy 419.069394 -110.150406)
			(xy 419.125128 -110.148369) (xy 419.180565 -110.154469) (xy 419.234522 -110.168575) (xy 419.285851 -110.190387)
			(xy 419.333457 -110.219441) (xy 419.376325 -110.255116) (xy 419.413542 -110.296653) (xy 419.444315 -110.343166)
			(xy 419.467987 -110.393663) (xy 419.484055 -110.44707) (xy 419.492175 -110.502246) (xy 419.492684 -110.530132)
			(xy 419.492175 -110.558018) (xy 419.484055 -110.613194) (xy 419.467987 -110.666601) (xy 419.444315 -110.717098)
			(xy 419.413542 -110.763611) (xy 419.376325 -110.805148) (xy 419.333457 -110.840823) (xy 419.285851 -110.869877)
			(xy 419.234522 -110.891689) (xy 419.180565 -110.905795) (xy 419.125128 -110.911895) (xy 419.069394 -110.909858)
			(xy 419.014551 -110.899728) (xy 418.961767 -110.881721) (xy 418.912167 -110.85622) (xy 418.866809 -110.823769)
			(xy 418.82666 -110.78506) (xy 418.792574 -110.740917) (xy 418.765278 -110.692282) (xy 418.745355 -110.640191)
			(xy 418.733229 -110.585754) (xy 418.729158 -110.530132) (xy 416.231133 -110.530132) (xy 416.231133 -110.542265)
			(xy 416.223306 -110.596444) (xy 416.207811 -110.648946) (xy 416.184968 -110.698694) (xy 416.155245 -110.744663)
			(xy 416.137598 -110.76559) (xy 416.137598 -110.765844) (xy 416.137344 -110.765844) (xy 416.131746 -110.772927)
			(xy 416.12548 -110.789844) (xy 416.125152 -110.798864) (xy 416.125152 -110.86592) (xy 416.125514 -110.874936)
			(xy 416.131761 -110.891851) (xy 416.137344 -110.89894) (xy 416.137598 -110.899194) (xy 416.155238 -110.920127)
			(xy 416.184962 -110.966096) (xy 416.207807 -111.015842) (xy 416.207939 -111.016288) (xy 420.08806 -111.016288)
			(xy 420.088546 -110.989037) (xy 420.096302 -110.935089) (xy 420.111657 -110.882794) (xy 420.134299 -110.833217)
			(xy 420.163765 -110.787367) (xy 420.199456 -110.746176) (xy 420.240647 -110.710485) (xy 420.286497 -110.681019)
			(xy 420.336074 -110.658377) (xy 420.388369 -110.643022) (xy 420.442317 -110.635266) (xy 420.496819 -110.635266)
			(xy 420.550767 -110.643022) (xy 420.603062 -110.658377) (xy 420.652639 -110.681019) (xy 420.698489 -110.710485)
			(xy 420.73968 -110.746176) (xy 420.775371 -110.787367) (xy 420.804837 -110.833217) (xy 420.827479 -110.882794)
			(xy 420.842834 -110.935089) (xy 420.85059 -110.989037) (xy 420.851076 -111.016288) (xy 420.850612 -111.043308)
			(xy 420.842999 -111.09681) (xy 420.82791 -111.148701) (xy 420.805647 -111.197942) (xy 420.776656 -111.243548)
			(xy 420.741517 -111.284604) (xy 420.721536 -111.3028) (xy 420.713572 -111.310452) (xy 420.704629 -111.330622)
			(xy 420.704264 -111.341662) (xy 420.705534 -111.418878) (xy 420.706205 -111.429889) (xy 420.71569 -111.449778)
			(xy 420.723822 -111.457232) (xy 420.74495 -111.475468) (xy 420.782229 -111.517001) (xy 420.813056 -111.563525)
			(xy 420.836771 -111.614046) (xy 420.852868 -111.667484) (xy 420.861004 -111.722697) (xy 420.86149 -111.750602)
			(xy 420.860869 -111.780394) (xy 420.851619 -111.839255) (xy 420.833329 -111.895962) (xy 420.806445 -111.949136)
			(xy 420.783689 -111.980726) (xy 422.201594 -111.980726) (xy 422.202135 -111.951988) (xy 422.210754 -111.895161)
			(xy 422.2278 -111.840271) (xy 422.252887 -111.788559) (xy 422.285449 -111.741195) (xy 422.304718 -111.719868)
			(xy 422.311322 -111.71301) (xy 422.318434 -111.694976) (xy 422.318434 -111.606076) (xy 422.311322 -111.588042)
			(xy 422.304718 -111.581184) (xy 422.285473 -111.559835) (xy 422.252908 -111.512476) (xy 422.227815 -111.460768)
			(xy 422.210763 -111.405881) (xy 422.202139 -111.349056) (xy 422.202136 -111.291581) (xy 422.210755 -111.234756)
			(xy 422.227801 -111.179868) (xy 422.252889 -111.128157) (xy 422.285449 -111.080795) (xy 422.304718 -111.059468)
			(xy 422.311322 -111.05261) (xy 422.318434 -111.034576) (xy 422.318434 -110.945676) (xy 422.311322 -110.927642)
			(xy 422.304718 -110.920784) (xy 422.285473 -110.899435) (xy 422.252908 -110.852076) (xy 422.227815 -110.800368)
			(xy 422.210763 -110.745481) (xy 422.202139 -110.688656) (xy 422.202136 -110.631181) (xy 422.210755 -110.574356)
			(xy 422.227801 -110.519468) (xy 422.252889 -110.467757) (xy 422.285449 -110.420395) (xy 422.304718 -110.399068)
			(xy 422.311322 -110.39221) (xy 422.318434 -110.374176) (xy 422.318434 -110.285276) (xy 422.311322 -110.267242)
			(xy 422.304718 -110.260384) (xy 422.285473 -110.239035) (xy 422.252908 -110.191676) (xy 422.227815 -110.139968)
			(xy 422.210763 -110.085081) (xy 422.202139 -110.028256) (xy 422.202136 -109.970781) (xy 422.210755 -109.913956)
			(xy 422.227801 -109.859068) (xy 422.252889 -109.807357) (xy 422.285449 -109.759995) (xy 422.304718 -109.738668)
			(xy 422.311322 -109.73181) (xy 422.318434 -109.713776) (xy 422.318434 -109.624876) (xy 422.311322 -109.606842)
			(xy 422.304718 -109.599984) (xy 422.285456 -109.578649) (xy 422.252889 -109.531289) (xy 422.227796 -109.479579)
			(xy 422.210743 -109.42469) (xy 422.202117 -109.367864) (xy 422.201594 -109.339126) (xy 422.20208 -109.311874)
			(xy 422.209833 -109.257923) (xy 422.225186 -109.205626) (xy 422.247825 -109.156046) (xy 422.277291 -109.110192)
			(xy 422.312982 -109.068999) (xy 422.354173 -109.033305) (xy 422.400025 -109.003837) (xy 422.449603 -108.981194)
			(xy 422.5019 -108.965838) (xy 422.55585 -108.958081) (xy 422.583102 -108.957618) (xy 422.609416 -108.958078)
			(xy 422.661545 -108.965314) (xy 422.712188 -108.979634) (xy 422.760388 -109.000768) (xy 422.805231 -109.028315)
			(xy 422.84587 -109.061756) (xy 422.864026 -109.080808) (xy 422.871535 -109.088224) (xy 422.890825 -109.09674)
			(xy 422.901364 -109.097318) (xy 422.97604 -109.097318) (xy 422.986587 -109.096765) (xy 423.005882 -109.088246)
			(xy 423.013378 -109.080808) (xy 423.031553 -109.061772) (xy 423.072178 -109.028312) (xy 423.117014 -109.000751)
			(xy 423.165211 -108.979609) (xy 423.215856 -108.965288) (xy 423.267987 -108.958059) (xy 423.294302 -108.957618)
			(xy 423.321556 -108.958054) (xy 423.375509 -108.965811) (xy 423.427809 -108.981169) (xy 423.477391 -109.003814)
			(xy 423.523246 -109.033284) (xy 423.564439 -109.068981) (xy 423.600132 -109.110177) (xy 423.6296 -109.156033)
			(xy 423.652241 -109.205617) (xy 423.667594 -109.257918) (xy 423.675348 -109.311872) (xy 423.67581 -109.339126)
			(xy 423.675299 -109.367865) (xy 423.666673 -109.424693) (xy 423.64962 -109.479584) (xy 423.638525 -109.502448)
			(xy 457.715112 -109.502448) (xy 457.715598 -109.475197) (xy 457.723354 -109.421249) (xy 457.738709 -109.368954)
			(xy 457.761351 -109.319377) (xy 457.790817 -109.273527) (xy 457.826508 -109.232336) (xy 457.867699 -109.196645)
			(xy 457.913549 -109.167179) (xy 457.963126 -109.144537) (xy 458.015421 -109.129182) (xy 458.069369 -109.121426)
			(xy 458.123871 -109.121426) (xy 458.177819 -109.129182) (xy 458.230114 -109.144537) (xy 458.279691 -109.167179)
			(xy 458.325541 -109.196645) (xy 458.366732 -109.232336) (xy 458.402423 -109.273527) (xy 458.431889 -109.319377)
			(xy 458.454531 -109.368954) (xy 458.469886 -109.421249) (xy 458.477642 -109.475197) (xy 458.478128 -109.502448)
			(xy 458.477695 -109.527979) (xy 458.47089 -109.578586) (xy 458.457396 -109.627833) (xy 458.437454 -109.67484)
			(xy 458.424788 -109.697012) (xy 458.418184 -109.708188) (xy 458.417168 -109.734096) (xy 458.461872 -109.822234)
			(xy 458.466038 -109.829689) (xy 458.478322 -109.841539) (xy 458.493801 -109.848732) (xy 458.502258 -109.84992)
			(xy 458.502512 -109.84992) (xy 458.530482 -109.853103) (xy 458.585116 -109.866669) (xy 458.637163 -109.888116)
			(xy 458.685493 -109.916981) (xy 458.729056 -109.952635) (xy 458.766905 -109.994304) (xy 458.798219 -110.041084)
			(xy 458.822318 -110.091957) (xy 458.838678 -110.145821) (xy 458.846944 -110.201503) (xy 458.847444 -110.22965)
			(xy 458.846874 -110.25781) (xy 458.838601 -110.313519) (xy 458.822226 -110.367407) (xy 458.798107 -110.418301)
			(xy 458.766766 -110.465096) (xy 458.728886 -110.506774) (xy 458.718028 -110.515654) (xy 459.128112 -110.515654)
			(xy 459.132183 -110.460032) (xy 459.144309 -110.405595) (xy 459.164232 -110.353504) (xy 459.191528 -110.304869)
			(xy 459.225614 -110.260726) (xy 459.265763 -110.222017) (xy 459.311121 -110.189566) (xy 459.360721 -110.164065)
			(xy 459.413505 -110.146058) (xy 459.468348 -110.135928) (xy 459.524082 -110.133891) (xy 459.579519 -110.139991)
			(xy 459.633476 -110.154097) (xy 459.684805 -110.175909) (xy 459.732411 -110.204963) (xy 459.775279 -110.240638)
			(xy 459.812496 -110.282175) (xy 459.843269 -110.328688) (xy 459.866941 -110.379185) (xy 459.883009 -110.432592)
			(xy 459.891129 -110.487768) (xy 459.891638 -110.515654) (xy 459.891129 -110.54354) (xy 459.883009 -110.598716)
			(xy 459.866941 -110.652123) (xy 459.843269 -110.70262) (xy 459.812496 -110.749133) (xy 459.775279 -110.79067)
			(xy 459.732411 -110.826345) (xy 459.684805 -110.855399) (xy 459.633476 -110.877211) (xy 459.579519 -110.891317)
			(xy 459.524082 -110.897417) (xy 459.468348 -110.89538) (xy 459.413505 -110.88525) (xy 459.360721 -110.867243)
			(xy 459.311121 -110.841742) (xy 459.265763 -110.809291) (xy 459.225614 -110.770582) (xy 459.191528 -110.726439)
			(xy 459.164232 -110.677804) (xy 459.144309 -110.625713) (xy 459.132183 -110.571276) (xy 459.128112 -110.515654)
			(xy 458.718028 -110.515654) (xy 458.68529 -110.542429) (xy 458.636925 -110.571288) (xy 458.584843 -110.592721)
			(xy 458.55763 -110.599982) (xy 458.548377 -110.60271) (xy 458.532712 -110.613944) (xy 458.52715 -110.621826)
			(xy 458.48397 -110.688374) (xy 458.48016 -110.706916) (xy 458.481938 -110.716822) (xy 458.484889 -110.733878)
			(xy 458.488069 -110.768348) (xy 458.488288 -110.785656) (xy 458.487802 -110.812907) (xy 458.480046 -110.866855)
			(xy 458.464691 -110.91915) (xy 458.442049 -110.968727) (xy 458.412583 -111.014577) (xy 458.376892 -111.055768)
			(xy 458.335701 -111.091459) (xy 458.289851 -111.120925) (xy 458.240274 -111.143567) (xy 458.187979 -111.158922)
			(xy 458.134031 -111.166678) (xy 458.079529 -111.166678) (xy 458.025581 -111.158922) (xy 457.973286 -111.143567)
			(xy 457.923709 -111.120925) (xy 457.877859 -111.091459) (xy 457.836668 -111.055768) (xy 457.800977 -111.014577)
			(xy 457.771511 -110.968727) (xy 457.748869 -110.91915) (xy 457.733514 -110.866855) (xy 457.725758 -110.812907)
			(xy 457.725272 -110.785656) (xy 457.725835 -110.757495) (xy 457.734108 -110.701785) (xy 457.750483 -110.647897)
			(xy 457.774603 -110.597002) (xy 457.805944 -110.550207) (xy 457.843825 -110.508529) (xy 457.887423 -110.472874)
			(xy 457.935789 -110.444016) (xy 457.987873 -110.422584) (xy 458.015086 -110.415324) (xy 458.024341 -110.412601)
			(xy 458.040005 -110.401364) (xy 458.045566 -110.39348) (xy 458.088746 -110.326932) (xy 458.092556 -110.30839)
			(xy 458.090778 -110.298484) (xy 458.087828 -110.281428) (xy 458.084647 -110.246958) (xy 458.084428 -110.22965)
			(xy 458.084853 -110.204118) (xy 458.091658 -110.153511) (xy 458.105155 -110.104264) (xy 458.1251 -110.057257)
			(xy 458.137768 -110.035086) (xy 458.144372 -110.02391) (xy 458.145388 -109.998002) (xy 458.100684 -109.909864)
			(xy 458.096545 -109.902392) (xy 458.084249 -109.890544) (xy 458.068759 -109.88336) (xy 458.060298 -109.882178)
			(xy 458.060044 -109.882178) (xy 458.032069 -109.879033) (xy 457.977434 -109.865462) (xy 457.925387 -109.844008)
			(xy 457.877058 -109.815138) (xy 457.833496 -109.77948) (xy 457.795648 -109.737807) (xy 457.764334 -109.691024)
			(xy 457.740237 -109.640147) (xy 457.723877 -109.586281) (xy 457.715612 -109.530596) (xy 457.715112 -109.502448)
			(xy 423.638525 -109.502448) (xy 423.624526 -109.531295) (xy 423.591958 -109.578657) (xy 423.572686 -109.599984)
			(xy 423.566082 -109.606842) (xy 423.55897 -109.624876) (xy 423.55897 -109.713776) (xy 423.566082 -109.73181)
			(xy 423.572686 -109.738668) (xy 423.591982 -109.759973) (xy 423.624546 -109.807339) (xy 423.649635 -109.859055)
			(xy 423.666683 -109.913949) (xy 423.675303 -109.970779) (xy 423.6753 -110.028259) (xy 423.666674 -110.085088)
			(xy 423.649621 -110.139981) (xy 423.624527 -110.191694) (xy 423.591958 -110.239057) (xy 423.572686 -110.260384)
			(xy 423.566082 -110.267242) (xy 423.55897 -110.285276) (xy 423.55897 -110.374176) (xy 423.566082 -110.39221)
			(xy 423.572686 -110.399068) (xy 423.591982 -110.420373) (xy 423.624546 -110.467739) (xy 423.649635 -110.519455)
			(xy 423.666683 -110.574349) (xy 423.673846 -110.621572) (xy 438.8612 -110.621572) (xy 438.861649 -110.595257)
			(xy 438.868887 -110.543128) (xy 438.88321 -110.492485) (xy 438.904346 -110.444286) (xy 438.931895 -110.399443)
			(xy 438.965337 -110.358804) (xy 438.98439 -110.340648) (xy 438.991815 -110.333146) (xy 439.000326 -110.313851)
			(xy 439.0009 -110.30331) (xy 439.0009 -110.228634) (xy 439.000366 -110.218085) (xy 438.991834 -110.198789)
			(xy 438.98439 -110.191296) (xy 438.965338 -110.173137) (xy 438.931881 -110.132508) (xy 438.904321 -110.087668)
			(xy 438.883182 -110.039468) (xy 438.868864 -109.988821) (xy 438.861639 -109.936688) (xy 438.8612 -109.910372)
			(xy 438.861686 -109.883121) (xy 438.869442 -109.829173) (xy 438.884797 -109.776878) (xy 438.907439 -109.727301)
			(xy 438.936905 -109.681451) (xy 438.972596 -109.64026) (xy 439.013787 -109.604569) (xy 439.059637 -109.575103)
			(xy 439.109214 -109.552461) (xy 439.161509 -109.537106) (xy 439.215457 -109.52935) (xy 439.269959 -109.52935)
			(xy 439.323907 -109.537106) (xy 439.376202 -109.552461) (xy 439.425779 -109.575103) (xy 439.471629 -109.604569)
			(xy 439.51282 -109.64026) (xy 439.548511 -109.681451) (xy 439.577977 -109.727301) (xy 439.600619 -109.776878)
			(xy 439.615974 -109.829173) (xy 439.62373 -109.883121) (xy 439.624216 -109.910372) (xy 439.623791 -109.936687)
			(xy 439.616547 -109.988818) (xy 439.602219 -110.039461) (xy 439.581079 -110.08766) (xy 439.553525 -110.132502)
			(xy 439.52008 -110.17314) (xy 439.501026 -110.191296) (xy 439.493628 -110.198821) (xy 439.485101 -110.218098)
			(xy 439.484516 -110.228634) (xy 439.484516 -110.30331) (xy 439.485022 -110.313863) (xy 439.493573 -110.333158)
			(xy 439.501026 -110.340648) (xy 439.520103 -110.358782) (xy 439.553557 -110.399417) (xy 439.581113 -110.444262)
			(xy 439.602247 -110.492467) (xy 439.61656 -110.543118) (xy 439.62378 -110.595255) (xy 439.624216 -110.621572)
			(xy 439.62373 -110.648823) (xy 439.615974 -110.702771) (xy 439.600619 -110.755066) (xy 439.577977 -110.804643)
			(xy 439.548511 -110.850493) (xy 439.51282 -110.891684) (xy 439.471629 -110.927375) (xy 439.425779 -110.956841)
			(xy 439.376202 -110.979483) (xy 439.323907 -110.994838) (xy 439.269959 -111.002594) (xy 439.215457 -111.002594)
			(xy 439.161509 -110.994838) (xy 439.109214 -110.979483) (xy 439.059637 -110.956841) (xy 439.013787 -110.927375)
			(xy 438.972596 -110.891684) (xy 438.936905 -110.850493) (xy 438.907439 -110.804643) (xy 438.884797 -110.755066)
			(xy 438.869442 -110.702771) (xy 438.861686 -110.648823) (xy 438.8612 -110.621572) (xy 423.673846 -110.621572)
			(xy 423.675303 -110.631179) (xy 423.6753 -110.688659) (xy 423.666674 -110.745488) (xy 423.649621 -110.800381)
			(xy 423.624527 -110.852094) (xy 423.591958 -110.899457) (xy 423.572686 -110.920784) (xy 423.566082 -110.927642)
			(xy 423.55897 -110.945676) (xy 423.55897 -111.034576) (xy 423.566082 -111.05261) (xy 423.572686 -111.059468)
			(xy 423.591982 -111.080773) (xy 423.624546 -111.128139) (xy 423.649635 -111.179855) (xy 423.666683 -111.234749)
			(xy 423.675303 -111.291579) (xy 423.6753 -111.349059) (xy 423.666674 -111.405888) (xy 423.649621 -111.460781)
			(xy 423.624527 -111.512494) (xy 423.591958 -111.559857) (xy 423.572686 -111.581184) (xy 423.566082 -111.588042)
			(xy 423.55897 -111.606076) (xy 423.55897 -111.694976) (xy 423.566082 -111.71301) (xy 423.572686 -111.719868)
			(xy 423.591973 -111.741181) (xy 423.624536 -111.788547) (xy 423.649625 -111.840262) (xy 423.666672 -111.895156)
			(xy 423.675291 -111.951986) (xy 423.67581 -111.980726) (xy 423.675346 -112.007978) (xy 423.667586 -112.061926)
			(xy 423.652228 -112.114221) (xy 423.629584 -112.163798) (xy 423.600115 -112.209649) (xy 423.564421 -112.250838)
			(xy 423.523229 -112.28653) (xy 423.477377 -112.315996) (xy 423.427799 -112.338636) (xy 423.375503 -112.353991)
			(xy 423.321554 -112.361748) (xy 423.294302 -112.362234) (xy 423.267989 -112.361754) (xy 423.215861 -112.35452)
			(xy 423.165219 -112.340203) (xy 423.11702 -112.319073) (xy 423.072176 -112.291529) (xy 423.031536 -112.258094)
			(xy 423.013378 -112.239044) (xy 423.005861 -112.231637) (xy 422.986578 -112.223114) (xy 422.97604 -112.222534)
			(xy 422.901364 -112.222534) (xy 422.890815 -112.223074) (xy 422.871519 -112.2316) (xy 422.864026 -112.239044)
			(xy 422.845859 -112.258088) (xy 422.805231 -112.291545) (xy 422.760393 -112.319104) (xy 422.712194 -112.340244)
			(xy 422.661549 -112.354564) (xy 422.609417 -112.361793) (xy 422.583102 -112.362234) (xy 422.555852 -112.36172)
			(xy 422.501907 -112.353965) (xy 422.449614 -112.338611) (xy 422.400038 -112.315972) (xy 422.354189 -112.286509)
			(xy 422.313 -112.25082) (xy 422.277308 -112.209633) (xy 422.247841 -112.163786) (xy 422.225198 -112.114212)
			(xy 422.209841 -112.061921) (xy 422.202082 -112.007976) (xy 422.201594 -111.980726) (xy 420.783689 -111.980726)
			(xy 420.771619 -111.997482) (xy 420.729699 -112.039825) (xy 420.706042 -112.057942) (xy 420.699261 -112.063298)
			(xy 420.689532 -112.077568) (xy 420.685113 -112.094265) (xy 420.685468 -112.1029) (xy 420.692072 -112.188752)
			(xy 420.692987 -112.197266) (xy 420.699761 -112.212983) (xy 420.711349 -112.225578) (xy 420.718742 -112.2299)
			(xy 420.718996 -112.2299) (xy 420.741809 -112.242283) (xy 420.784101 -112.272378) (xy 420.821921 -112.307931)
			(xy 420.85457 -112.348285) (xy 420.881443 -112.392695) (xy 420.884417 -112.399572) (xy 438.8612 -112.399572)
			(xy 438.861649 -112.373257) (xy 438.868887 -112.321128) (xy 438.88321 -112.270485) (xy 438.904346 -112.222286)
			(xy 438.931895 -112.177443) (xy 438.965337 -112.136804) (xy 438.98439 -112.118648) (xy 438.991815 -112.111146)
			(xy 439.000326 -112.091851) (xy 439.0009 -112.08131) (xy 439.0009 -112.006634) (xy 439.000366 -111.996085)
			(xy 438.991834 -111.976789) (xy 438.98439 -111.969296) (xy 438.965338 -111.951137) (xy 438.931881 -111.910508)
			(xy 438.904321 -111.865668) (xy 438.883182 -111.817468) (xy 438.868864 -111.766821) (xy 438.861639 -111.714688)
			(xy 438.8612 -111.688372) (xy 438.861686 -111.661121) (xy 438.869442 -111.607173) (xy 438.884797 -111.554878)
			(xy 438.907439 -111.505301) (xy 438.936905 -111.459451) (xy 438.972596 -111.41826) (xy 439.013787 -111.382569)
			(xy 439.059637 -111.353103) (xy 439.109214 -111.330461) (xy 439.161509 -111.315106) (xy 439.215457 -111.30735)
			(xy 439.269959 -111.30735) (xy 439.323907 -111.315106) (xy 439.376202 -111.330461) (xy 439.425779 -111.353103)
			(xy 439.471629 -111.382569) (xy 439.51282 -111.41826) (xy 439.548511 -111.459451) (xy 439.577977 -111.505301)
			(xy 439.600619 -111.554878) (xy 439.615974 -111.607173) (xy 439.62373 -111.661121) (xy 439.624216 -111.688372)
			(xy 439.623791 -111.714687) (xy 439.616547 -111.766818) (xy 439.602219 -111.817461) (xy 439.581079 -111.86566)
			(xy 439.553525 -111.910502) (xy 439.52008 -111.95114) (xy 439.501026 -111.969296) (xy 439.493628 -111.976821)
			(xy 439.485101 -111.996098) (xy 439.484516 -112.006634) (xy 439.484516 -112.08131) (xy 439.485022 -112.091863)
			(xy 439.493573 -112.111158) (xy 439.501026 -112.118648) (xy 439.520103 -112.136782) (xy 439.553557 -112.177417)
			(xy 439.581113 -112.222262) (xy 439.602247 -112.270467) (xy 439.610019 -112.297972) (xy 441.369958 -112.297972)
			(xy 441.370388 -112.271657) (xy 441.377628 -112.219526) (xy 441.391953 -112.168882) (xy 441.413093 -112.120682)
			(xy 441.440646 -112.07584) (xy 441.474093 -112.035203) (xy 441.493148 -112.017048) (xy 441.500567 -112.009541)
			(xy 441.509083 -111.99025) (xy 441.509658 -111.97971) (xy 441.509658 -111.905034) (xy 441.509136 -111.894483)
			(xy 441.500597 -111.875187) (xy 441.493148 -111.867696) (xy 441.474088 -111.849546) (xy 441.440633 -111.808914)
			(xy 441.413076 -111.764072) (xy 441.391939 -111.71587) (xy 441.377622 -111.665222) (xy 441.370397 -111.613088)
			(xy 441.369958 -111.586772) (xy 441.370444 -111.559521) (xy 441.3782 -111.505573) (xy 441.393555 -111.453278)
			(xy 441.416197 -111.403701) (xy 441.445663 -111.357851) (xy 441.481354 -111.31666) (xy 441.522545 -111.280969)
			(xy 441.568395 -111.251503) (xy 441.617972 -111.228861) (xy 441.670267 -111.213506) (xy 441.724215 -111.20575)
			(xy 441.778717 -111.20575) (xy 441.832665 -111.213506) (xy 441.88496 -111.228861) (xy 441.934537 -111.251503)
			(xy 441.980387 -111.280969) (xy 442.021578 -111.31666) (xy 442.057269 -111.357851) (xy 442.086735 -111.403701)
			(xy 442.109377 -111.453278) (xy 442.124732 -111.505573) (xy 442.132488 -111.559521) (xy 442.132974 -111.586772)
			(xy 442.132563 -111.613088) (xy 442.125318 -111.665219) (xy 442.110988 -111.715863) (xy 442.089845 -111.764062)
			(xy 442.062289 -111.808904) (xy 442.02884 -111.849541) (xy 442.009784 -111.867696) (xy 442.00238 -111.875215)
			(xy 441.993857 -111.894497) (xy 441.993274 -111.905034) (xy 441.993274 -111.97971) (xy 441.993792 -111.990261)
			(xy 442.002336 -112.009556) (xy 442.009784 -112.017048) (xy 442.028853 -112.03519) (xy 442.062309 -112.075823)
			(xy 442.089867 -112.120665) (xy 442.111003 -112.168869) (xy 442.125317 -112.219519) (xy 442.132538 -112.271655)
			(xy 442.132974 -112.297972) (xy 443.401958 -112.297972) (xy 443.402388 -112.271657) (xy 443.409628 -112.219526)
			(xy 443.423953 -112.168882) (xy 443.445093 -112.120682) (xy 443.472646 -112.07584) (xy 443.506093 -112.035203)
			(xy 443.525148 -112.017048) (xy 443.532567 -112.009541) (xy 443.541083 -111.99025) (xy 443.541658 -111.97971)
			(xy 443.541658 -111.905034) (xy 443.541136 -111.894483) (xy 443.532597 -111.875187) (xy 443.525148 -111.867696)
			(xy 443.506088 -111.849546) (xy 443.472633 -111.808914) (xy 443.445076 -111.764072) (xy 443.423939 -111.71587)
			(xy 443.409622 -111.665222) (xy 443.402397 -111.613088) (xy 443.401958 -111.586772) (xy 443.402444 -111.559521)
			(xy 443.4102 -111.505573) (xy 443.425555 -111.453278) (xy 443.448197 -111.403701) (xy 443.477663 -111.357851)
			(xy 443.513354 -111.31666) (xy 443.554545 -111.280969) (xy 443.600395 -111.251503) (xy 443.649972 -111.228861)
			(xy 443.702267 -111.213506) (xy 443.756215 -111.20575) (xy 443.810717 -111.20575) (xy 443.864665 -111.213506)
			(xy 443.91696 -111.228861) (xy 443.966537 -111.251503) (xy 444.012387 -111.280969) (xy 444.053578 -111.31666)
			(xy 444.089269 -111.357851) (xy 444.118735 -111.403701) (xy 444.141377 -111.453278) (xy 444.156732 -111.505573)
			(xy 444.164488 -111.559521) (xy 444.164974 -111.586772) (xy 444.164563 -111.613088) (xy 444.157318 -111.665219)
			(xy 444.142988 -111.715863) (xy 444.121845 -111.764062) (xy 444.094289 -111.808904) (xy 444.06084 -111.849541)
			(xy 444.041784 -111.867696) (xy 444.03438 -111.875215) (xy 444.025857 -111.894497) (xy 444.025274 -111.905034)
			(xy 444.025274 -111.97971) (xy 444.025792 -111.990261) (xy 444.034336 -112.009556) (xy 444.041784 -112.017048)
			(xy 444.060853 -112.03519) (xy 444.06285 -112.037615) (xy 445.856202 -112.037615) (xy 445.860515 -111.980345)
			(xy 445.87336 -111.924368) (xy 445.894448 -111.870948) (xy 445.923303 -111.821291) (xy 445.959273 -111.776519)
			(xy 445.980058 -111.756698) (xy 445.987456 -111.749173) (xy 445.995984 -111.729896) (xy 445.996568 -111.71936)
			(xy 445.996568 -111.644684) (xy 445.99607 -111.63413) (xy 445.987514 -111.614835) (xy 445.980058 -111.607346)
			(xy 445.960975 -111.589218) (xy 445.927522 -111.548581) (xy 445.899968 -111.503735) (xy 445.878834 -111.455529)
			(xy 445.864523 -111.404877) (xy 445.857304 -111.35274) (xy 445.856868 -111.326422) (xy 445.857354 -111.299171)
			(xy 445.86511 -111.245223) (xy 445.880465 -111.192928) (xy 445.903107 -111.143351) (xy 445.932573 -111.097501)
			(xy 445.968264 -111.05631) (xy 446.009455 -111.020619) (xy 446.055305 -110.991153) (xy 446.104882 -110.968511)
			(xy 446.157177 -110.953156) (xy 446.211125 -110.9454) (xy 446.265627 -110.9454) (xy 446.319575 -110.953156)
			(xy 446.37187 -110.968511) (xy 446.421447 -110.991153) (xy 446.467297 -111.020619) (xy 446.508488 -111.05631)
			(xy 446.544179 -111.097501) (xy 446.573645 -111.143351) (xy 446.596287 -111.192928) (xy 446.611642 -111.245223)
			(xy 446.619398 -111.299171) (xy 446.619884 -111.326422) (xy 446.619436 -111.352737) (xy 446.612198 -111.404866)
			(xy 446.597876 -111.45551) (xy 446.576739 -111.503709) (xy 446.54919 -111.548552) (xy 446.515747 -111.58919)
			(xy 446.496694 -111.607346) (xy 446.489269 -111.614848) (xy 446.480759 -111.634143) (xy 446.480184 -111.644684)
			(xy 446.480184 -111.71936) (xy 446.480726 -111.729908) (xy 446.489253 -111.749203) (xy 446.496694 -111.756698)
			(xy 446.517505 -111.776495) (xy 446.553482 -111.82127) (xy 446.582343 -111.870931) (xy 446.603436 -111.924356)
			(xy 446.616284 -111.980339) (xy 446.620598 -112.037615) (xy 448.394417 -112.037615) (xy 448.39873 -111.980345)
			(xy 448.411576 -111.924367) (xy 448.432666 -111.870947) (xy 448.461522 -111.82129) (xy 448.497494 -111.776518)
			(xy 448.51828 -111.756698) (xy 448.525682 -111.749176) (xy 448.534207 -111.729896) (xy 448.53479 -111.71936)
			(xy 448.53479 -111.644684) (xy 448.534286 -111.634131) (xy 448.525734 -111.614836) (xy 448.51828 -111.607346)
			(xy 448.499201 -111.589214) (xy 448.465747 -111.548578) (xy 448.438192 -111.503733) (xy 448.417057 -111.455528)
			(xy 448.402745 -111.404877) (xy 448.395526 -111.352739) (xy 448.39509 -111.326422) (xy 448.395576 -111.299171)
			(xy 448.403332 -111.245223) (xy 448.418687 -111.192928) (xy 448.441329 -111.143351) (xy 448.470795 -111.097501)
			(xy 448.506486 -111.05631) (xy 448.547677 -111.020619) (xy 448.593527 -110.991153) (xy 448.643104 -110.968511)
			(xy 448.695399 -110.953156) (xy 448.749347 -110.9454) (xy 448.803849 -110.9454) (xy 448.857797 -110.953156)
			(xy 448.910092 -110.968511) (xy 448.959669 -110.991153) (xy 449.005519 -111.020619) (xy 449.04671 -111.05631)
			(xy 449.082401 -111.097501) (xy 449.111867 -111.143351) (xy 449.134509 -111.192928) (xy 449.149864 -111.245223)
			(xy 449.15762 -111.299171) (xy 449.158106 -111.326422) (xy 449.157651 -111.352736) (xy 449.150414 -111.404865)
			(xy 449.136092 -111.455508) (xy 449.114957 -111.503707) (xy 449.087409 -111.54855) (xy 449.053968 -111.58919)
			(xy 449.034916 -111.607346) (xy 449.027494 -111.614851) (xy 449.018981 -111.634143) (xy 449.018406 -111.644684)
			(xy 449.018406 -111.71936) (xy 449.018941 -111.729909) (xy 449.027472 -111.749205) (xy 449.034916 -111.756698)
			(xy 449.055726 -111.776496) (xy 449.091701 -111.821271) (xy 449.12056 -111.870932) (xy 449.141652 -111.924357)
			(xy 449.154499 -111.98034) (xy 449.155522 -111.993923) (xy 452.597351 -111.993923) (xy 452.601664 -111.936653)
			(xy 452.61451 -111.880675) (xy 452.6356 -111.827255) (xy 452.664458 -111.777599) (xy 452.700431 -111.732829)
			(xy 452.721218 -111.71301) (xy 452.72862 -111.705489) (xy 452.737144 -111.686208) (xy 452.737728 -111.675672)
			(xy 452.737728 -111.600996) (xy 452.737206 -111.590446) (xy 452.728665 -111.571151) (xy 452.721218 -111.563658)
			(xy 452.700462 -111.543805) (xy 452.664484 -111.499039) (xy 452.63562 -111.449386) (xy 452.614523 -111.395969)
			(xy 452.60167 -111.339993) (xy 452.597351 -111.282723) (xy 452.601664 -111.225453) (xy 452.61451 -111.169475)
			(xy 452.6356 -111.116055) (xy 452.664458 -111.066399) (xy 452.700431 -111.021629) (xy 452.721218 -111.00181)
			(xy 452.72862 -110.994289) (xy 452.737144 -110.975008) (xy 452.737728 -110.964472) (xy 452.737728 -110.889796)
			(xy 452.737206 -110.879246) (xy 452.728665 -110.859951) (xy 452.721218 -110.852458) (xy 452.702153 -110.834312)
			(xy 452.668696 -110.793681) (xy 452.641137 -110.748839) (xy 452.620001 -110.700636) (xy 452.605686 -110.649986)
			(xy 452.598464 -110.597851) (xy 452.598028 -110.571534) (xy 452.598487 -110.54428) (xy 452.60624 -110.490327)
			(xy 452.621594 -110.438027) (xy 452.644235 -110.388445) (xy 452.673703 -110.34259) (xy 452.709397 -110.301396)
			(xy 452.750591 -110.265702) (xy 452.796447 -110.236234) (xy 452.846029 -110.213593) (xy 452.898329 -110.19824)
			(xy 452.952282 -110.190487) (xy 452.979536 -110.190026) (xy 453.005851 -110.190461) (xy 453.057981 -110.197701)
			(xy 453.108625 -110.212026) (xy 453.156824 -110.233165) (xy 453.201667 -110.260717) (xy 453.242305 -110.294162)
			(xy 453.26046 -110.313216) (xy 453.267992 -110.320604) (xy 453.287264 -110.329136) (xy 453.297798 -110.329726)
			(xy 453.372474 -110.329726) (xy 453.383022 -110.329188) (xy 453.402317 -110.320658) (xy 453.409812 -110.313216)
			(xy 453.427972 -110.294165) (xy 453.4686 -110.260707) (xy 453.51344 -110.233147) (xy 453.56164 -110.212007)
			(xy 453.612286 -110.197689) (xy 453.66442 -110.190464) (xy 453.690736 -110.190026) (xy 453.71799 -110.190444)
			(xy 453.771942 -110.198207) (xy 453.82424 -110.213568) (xy 453.873819 -110.236216) (xy 453.913439 -110.261683)
			(xy 455.214548 -110.261683) (xy 455.214548 -110.209717) (xy 455.222677 -110.158392) (xy 455.238734 -110.10897)
			(xy 455.262325 -110.062668) (xy 455.292869 -110.020627) (xy 455.329613 -109.983881) (xy 455.371653 -109.953335)
			(xy 455.417953 -109.929741) (xy 455.467374 -109.913681) (xy 455.518699 -109.905549) (xy 455.544682 -109.905038)
			(xy 455.571328 -109.905497) (xy 455.623931 -109.914033) (xy 455.674482 -109.930904) (xy 455.721668 -109.955672)
			(xy 455.764266 -109.987694) (xy 455.80117 -110.026139) (xy 455.816716 -110.047786) (xy 455.82508 -110.059072)
			(xy 455.846753 -110.076927) (xy 455.872467 -110.08821) (xy 455.900282 -110.092068) (xy 455.928097 -110.08821)
			(xy 455.953811 -110.076927) (xy 455.975484 -110.059072) (xy 455.983848 -110.047786) (xy 455.999412 -110.026159)
			(xy 456.036331 -109.987743) (xy 456.078931 -109.955744) (xy 456.126112 -109.930989) (xy 456.176652 -109.914121)
			(xy 456.229242 -109.905575) (xy 456.255882 -109.905038) (xy 456.281876 -109.905428) (xy 456.333224 -109.913558)
			(xy 456.382667 -109.929621) (xy 456.42899 -109.953221) (xy 456.471049 -109.983777) (xy 456.507811 -110.020537)
			(xy 456.53837 -110.062595) (xy 456.561972 -110.108916) (xy 456.578038 -110.158359) (xy 456.586171 -110.209706)
			(xy 456.586171 -110.261694) (xy 456.578038 -110.313041) (xy 456.561972 -110.362484) (xy 456.53837 -110.408805)
			(xy 456.507811 -110.450863) (xy 456.471049 -110.487623) (xy 456.42899 -110.518179) (xy 456.382667 -110.541779)
			(xy 456.333224 -110.557842) (xy 456.281876 -110.565972) (xy 456.255882 -110.566454) (xy 456.229238 -110.565951)
			(xy 456.176636 -110.557424) (xy 456.126087 -110.540563) (xy 456.0789 -110.515803) (xy 456.036301 -110.483789)
			(xy 455.999395 -110.44535) (xy 455.983848 -110.423706) (xy 455.975484 -110.41242) (xy 455.953811 -110.394565)
			(xy 455.928097 -110.383282) (xy 455.900282 -110.379424) (xy 455.872467 -110.383282) (xy 455.846753 -110.394565)
			(xy 455.82508 -110.41242) (xy 455.816716 -110.423706) (xy 455.80111 -110.445301) (xy 455.7642 -110.483719)
			(xy 455.721608 -110.515722) (xy 455.674436 -110.540482) (xy 455.623904 -110.557357) (xy 455.57132 -110.565912)
			(xy 455.544682 -110.566454) (xy 455.518699 -110.565851) (xy 455.467374 -110.557719) (xy 455.417953 -110.541659)
			(xy 455.371653 -110.518065) (xy 455.329613 -110.487519) (xy 455.292869 -110.450773) (xy 455.262325 -110.408732)
			(xy 455.238734 -110.36243) (xy 455.222677 -110.313008) (xy 455.214548 -110.261683) (xy 453.913439 -110.261683)
			(xy 453.919671 -110.265689) (xy 453.960862 -110.301388) (xy 453.996553 -110.342585) (xy 454.026018 -110.388442)
			(xy 454.048656 -110.438026) (xy 454.064008 -110.490327) (xy 454.071761 -110.54428) (xy 454.072244 -110.571534)
			(xy 454.071817 -110.59785) (xy 454.064577 -110.649981) (xy 454.050251 -110.700625) (xy 454.029111 -110.748824)
			(xy 454.001557 -110.793666) (xy 453.96811 -110.834303) (xy 453.949054 -110.852458) (xy 453.941677 -110.860001)
			(xy 453.933137 -110.879264) (xy 453.932544 -110.889796) (xy 453.932544 -110.964472) (xy 453.933062 -110.975023)
			(xy 453.941604 -110.994319) (xy 453.949054 -111.00181) (xy 453.969874 -111.021597) (xy 454.005846 -111.066375)
			(xy 454.034702 -111.116038) (xy 454.052798 -111.161885) (xy 455.214523 -111.161885) (xy 455.214523 -111.109915)
			(xy 455.222653 -111.058586) (xy 455.238712 -111.00916) (xy 455.262304 -110.962855) (xy 455.29285 -110.920811)
			(xy 455.329597 -110.884062) (xy 455.37164 -110.853514) (xy 455.417944 -110.829919) (xy 455.467369 -110.813857)
			(xy 455.518697 -110.805725) (xy 455.544682 -110.805214) (xy 455.571327 -110.805683) (xy 455.62393 -110.814219)
			(xy 455.674479 -110.831089) (xy 455.721665 -110.855854) (xy 455.764264 -110.887874) (xy 455.801169 -110.926316)
			(xy 455.816716 -110.947962) (xy 455.82508 -110.959248) (xy 455.846753 -110.977103) (xy 455.872467 -110.988386)
			(xy 455.900282 -110.992244) (xy 455.928097 -110.988386) (xy 455.953811 -110.977103) (xy 455.975484 -110.959248)
			(xy 455.983848 -110.947962) (xy 455.999405 -110.92633) (xy 456.036326 -110.887915) (xy 456.078928 -110.855917)
			(xy 456.12611 -110.831164) (xy 456.176651 -110.814296) (xy 456.229242 -110.805751) (xy 456.255882 -110.805214)
			(xy 456.281874 -110.805652) (xy 456.333218 -110.813781) (xy 456.382658 -110.829843) (xy 456.428977 -110.853441)
			(xy 456.471034 -110.883995) (xy 456.507793 -110.920752) (xy 456.538349 -110.962808) (xy 456.56195 -111.009125)
			(xy 456.578014 -111.058564) (xy 456.586147 -111.109908) (xy 456.586147 -111.161892) (xy 456.578014 -111.213236)
			(xy 456.56195 -111.262675) (xy 456.538349 -111.308992) (xy 456.507793 -111.351048) (xy 456.471034 -111.387805)
			(xy 456.428977 -111.418359) (xy 456.382658 -111.441957) (xy 456.333218 -111.458019) (xy 456.281874 -111.466148)
			(xy 456.255882 -111.46663) (xy 456.229237 -111.466138) (xy 456.176635 -111.45761) (xy 456.126084 -111.440747)
			(xy 456.078897 -111.415985) (xy 456.036299 -111.383969) (xy 455.999394 -111.345527) (xy 455.983848 -111.323882)
			(xy 455.975484 -111.312596) (xy 455.953811 -111.294741) (xy 455.928097 -111.283458) (xy 455.900282 -111.2796)
			(xy 455.872467 -111.283458) (xy 455.846753 -111.294741) (xy 455.82508 -111.312596) (xy 455.816716 -111.323882)
			(xy 455.801133 -111.345494) (xy 455.764215 -111.383907) (xy 455.721618 -111.415906) (xy 455.674441 -111.440662)
			(xy 455.623907 -111.457535) (xy 455.571321 -111.466089) (xy 455.544682 -111.46663) (xy 455.518697 -111.466075)
			(xy 455.467369 -111.457943) (xy 455.417944 -111.441881) (xy 455.37164 -111.418286) (xy 455.329597 -111.387738)
			(xy 455.29285 -111.350989) (xy 455.262304 -111.308945) (xy 455.238712 -111.26264) (xy 455.222653 -111.213214)
			(xy 455.214523 -111.161885) (xy 454.052798 -111.161885) (xy 454.05579 -111.169465) (xy 454.068636 -111.225447)
			(xy 454.072947 -111.282723) (xy 454.068629 -111.339998) (xy 454.055777 -111.395979) (xy 454.034681 -111.449403)
			(xy 454.00582 -111.499063) (xy 453.969843 -111.543837) (xy 453.949054 -111.563658) (xy 453.941677 -111.571201)
			(xy 453.933137 -111.590464) (xy 453.932544 -111.600996) (xy 453.932544 -111.675672) (xy 453.933062 -111.686223)
			(xy 453.941604 -111.705519) (xy 453.949054 -111.71301) (xy 453.969874 -111.732797) (xy 454.005846 -111.777575)
			(xy 454.034702 -111.827238) (xy 454.05579 -111.880665) (xy 454.068636 -111.936647) (xy 454.072947 -111.993923)
			(xy 454.068629 -112.051198) (xy 454.066199 -112.061783) (xy 455.214546 -112.061783) (xy 455.214546 -112.009817)
			(xy 455.222675 -111.958491) (xy 455.238732 -111.909069) (xy 455.262324 -111.862767) (xy 455.292867 -111.820725)
			(xy 455.329612 -111.783979) (xy 455.371652 -111.753433) (xy 455.417952 -111.729839) (xy 455.467374 -111.713779)
			(xy 455.518699 -111.705647) (xy 455.544682 -111.705136) (xy 455.571328 -111.705595) (xy 455.623931 -111.714132)
			(xy 455.674481 -111.731003) (xy 455.721668 -111.755771) (xy 455.764266 -111.787792) (xy 455.80117 -111.826237)
			(xy 455.816716 -111.847884) (xy 455.82508 -111.85917) (xy 455.846753 -111.877025) (xy 455.872467 -111.888308)
			(xy 455.900282 -111.892166) (xy 455.928097 -111.888308) (xy 455.953811 -111.877025) (xy 455.975484 -111.85917)
			(xy 455.983848 -111.847884) (xy 455.999411 -111.826257) (xy 456.03633 -111.787841) (xy 456.078931 -111.755841)
			(xy 456.126112 -111.731087) (xy 456.176651 -111.714219) (xy 456.229242 -111.705673) (xy 456.255882 -111.705136)
			(xy 456.281876 -111.70553) (xy 456.333223 -111.71366) (xy 456.382667 -111.729723) (xy 456.428989 -111.753323)
			(xy 456.471048 -111.783879) (xy 456.472823 -111.785654) (xy 457.757782 -111.785654) (xy 457.761853 -111.730032)
			(xy 457.773979 -111.675595) (xy 457.793902 -111.623504) (xy 457.821198 -111.574869) (xy 457.855284 -111.530726)
			(xy 457.895433 -111.492017) (xy 457.940791 -111.459566) (xy 457.990391 -111.434065) (xy 458.043175 -111.416058)
			(xy 458.098018 -111.405928) (xy 458.153752 -111.403891) (xy 458.209189 -111.409991) (xy 458.263146 -111.424097)
			(xy 458.314475 -111.445909) (xy 458.362081 -111.474963) (xy 458.404949 -111.510638) (xy 458.442166 -111.552175)
			(xy 458.472939 -111.598688) (xy 458.496611 -111.649185) (xy 458.512679 -111.702592) (xy 458.520799 -111.757768)
			(xy 458.521308 -111.785654) (xy 458.520799 -111.81354) (xy 458.512679 -111.868716) (xy 458.496611 -111.922123)
			(xy 458.472939 -111.97262) (xy 458.442166 -112.019133) (xy 458.404949 -112.06067) (xy 458.362081 -112.096345)
			(xy 458.314475 -112.125399) (xy 458.263146 -112.147211) (xy 458.209189 -112.161317) (xy 458.153752 -112.167417)
			(xy 458.098018 -112.16538) (xy 458.043175 -112.15525) (xy 457.990391 -112.137243) (xy 457.940791 -112.111742)
			(xy 457.895433 -112.079291) (xy 457.855284 -112.040582) (xy 457.821198 -111.996439) (xy 457.793902 -111.947804)
			(xy 457.773979 -111.895713) (xy 457.761853 -111.841276) (xy 457.757782 -111.785654) (xy 456.472823 -111.785654)
			(xy 456.50781 -111.820638) (xy 456.538368 -111.862696) (xy 456.56197 -111.909017) (xy 456.578036 -111.958459)
			(xy 456.586169 -112.009806) (xy 456.586169 -112.061794) (xy 456.578036 -112.113141) (xy 456.56197 -112.162583)
			(xy 456.538368 -112.208904) (xy 456.50781 -112.250962) (xy 456.471048 -112.287721) (xy 456.458336 -112.296956)
			(xy 459.194914 -112.296956) (xy 459.198985 -112.241334) (xy 459.211111 -112.186897) (xy 459.231034 -112.134806)
			(xy 459.25833 -112.086171) (xy 459.292416 -112.042028) (xy 459.332565 -112.003319) (xy 459.377923 -111.970868)
			(xy 459.427523 -111.945367) (xy 459.480307 -111.92736) (xy 459.53515 -111.91723) (xy 459.590884 -111.915193)
			(xy 459.646321 -111.921293) (xy 459.700278 -111.935399) (xy 459.751607 -111.957211) (xy 459.799213 -111.986265)
			(xy 459.842081 -112.02194) (xy 459.879298 -112.063477) (xy 459.910071 -112.10999) (xy 459.933743 -112.160487)
			(xy 459.949811 -112.213894) (xy 459.957931 -112.26907) (xy 459.95844 -112.296956) (xy 459.957931 -112.324842)
			(xy 459.949811 -112.380018) (xy 459.933743 -112.433425) (xy 459.910071 -112.483922) (xy 459.879298 -112.530435)
			(xy 459.842081 -112.571972) (xy 459.799213 -112.607647) (xy 459.751607 -112.636701) (xy 459.700278 -112.658513)
			(xy 459.646321 -112.672619) (xy 459.590884 -112.678719) (xy 459.53515 -112.676682) (xy 459.480307 -112.666552)
			(xy 459.427523 -112.648545) (xy 459.377923 -112.623044) (xy 459.332565 -112.590593) (xy 459.292416 -112.551884)
			(xy 459.25833 -112.507741) (xy 459.231034 -112.459106) (xy 459.211111 -112.407015) (xy 459.198985 -112.352578)
			(xy 459.194914 -112.296956) (xy 456.458336 -112.296956) (xy 456.428989 -112.318277) (xy 456.382667 -112.341877)
			(xy 456.333223 -112.35794) (xy 456.281876 -112.36607) (xy 456.255882 -112.366552) (xy 456.229238 -112.36605)
			(xy 456.176636 -112.357523) (xy 456.126086 -112.340661) (xy 456.0789 -112.315902) (xy 456.036301 -112.283887)
			(xy 455.999395 -112.245448) (xy 455.983848 -112.223804) (xy 455.975484 -112.212518) (xy 455.953811 -112.194663)
			(xy 455.928097 -112.18338) (xy 455.900282 -112.179522) (xy 455.872467 -112.18338) (xy 455.846753 -112.194663)
			(xy 455.82508 -112.212518) (xy 455.816716 -112.223804) (xy 455.801109 -112.245399) (xy 455.7642 -112.283817)
			(xy 455.721608 -112.31582) (xy 455.674436 -112.340579) (xy 455.623904 -112.357455) (xy 455.57132 -112.36601)
			(xy 455.544682 -112.366552) (xy 455.518699 -112.365953) (xy 455.467374 -112.357821) (xy 455.417952 -112.341761)
			(xy 455.371652 -112.318167) (xy 455.329612 -112.287621) (xy 455.292867 -112.250875) (xy 455.262324 -112.208833)
			(xy 455.238732 -112.162531) (xy 455.222675 -112.113109) (xy 455.214546 -112.061783) (xy 454.066199 -112.061783)
			(xy 454.055777 -112.107179) (xy 454.034681 -112.160603) (xy 454.00582 -112.210263) (xy 453.969843 -112.255037)
			(xy 453.949054 -112.274858) (xy 453.941677 -112.282401) (xy 453.933137 -112.301664) (xy 453.932544 -112.312196)
			(xy 453.932544 -112.386872) (xy 453.933062 -112.397423) (xy 453.941604 -112.416719) (xy 453.949054 -112.42421)
			(xy 453.968118 -112.442357) (xy 454.001572 -112.48299) (xy 454.029129 -112.527832) (xy 454.050265 -112.576034)
			(xy 454.064581 -112.626683) (xy 454.071806 -112.678818) (xy 454.072244 -112.705134) (xy 454.071754 -112.732384)
			(xy 454.063994 -112.78633) (xy 454.048636 -112.838623) (xy 454.025994 -112.888198) (xy 453.996527 -112.934046)
			(xy 453.972487 -112.961789) (xy 455.214468 -112.961789) (xy 455.214468 -112.909811) (xy 455.222598 -112.858473)
			(xy 455.23866 -112.809039) (xy 455.262257 -112.762726) (xy 455.292808 -112.720674) (xy 455.329561 -112.683919)
			(xy 455.371611 -112.653366) (xy 455.417922 -112.629767) (xy 455.467356 -112.613703) (xy 455.518693 -112.605569)
			(xy 455.544682 -112.605058) (xy 455.571328 -112.605508) (xy 455.623932 -112.614045) (xy 455.674484 -112.630917)
			(xy 455.72167 -112.655687) (xy 455.764268 -112.687711) (xy 455.801171 -112.726158) (xy 455.816716 -112.747806)
			(xy 455.82508 -112.759092) (xy 455.846753 -112.776947) (xy 455.872467 -112.78823) (xy 455.900282 -112.792088)
			(xy 455.928097 -112.78823) (xy 455.953811 -112.776947) (xy 455.975484 -112.759092) (xy 455.983848 -112.747806)
			(xy 455.999388 -112.726162) (xy 456.036315 -112.68775) (xy 456.078921 -112.655755) (xy 456.126106 -112.631005)
			(xy 456.176648 -112.614139) (xy 456.229241 -112.605594) (xy 456.255882 -112.605058) (xy 456.28187 -112.605608)
			(xy 456.333205 -112.613736) (xy 456.382637 -112.629795) (xy 456.428948 -112.653389) (xy 456.470997 -112.683938)
			(xy 456.50775 -112.720689) (xy 456.538301 -112.762737) (xy 456.561898 -112.809046) (xy 456.57796 -112.858477)
			(xy 456.586091 -112.909813) (xy 456.586091 -112.961787) (xy 456.57796 -113.013123) (xy 456.561898 -113.062554)
			(xy 456.538301 -113.108863) (xy 456.50775 -113.150911) (xy 456.470997 -113.187662) (xy 456.428948 -113.218211)
			(xy 456.382637 -113.241805) (xy 456.333205 -113.257864) (xy 456.28187 -113.265992) (xy 456.255882 -113.266474)
			(xy 456.229238 -113.265963) (xy 456.176638 -113.257436) (xy 456.126088 -113.240576) (xy 456.078902 -113.215818)
			(xy 456.036303 -113.183805) (xy 455.999395 -113.145369) (xy 455.983848 -113.123726) (xy 455.975484 -113.11244)
			(xy 455.953811 -113.094585) (xy 455.928097 -113.083302) (xy 455.900282 -113.079444) (xy 455.872467 -113.083302)
			(xy 455.846753 -113.094585) (xy 455.82508 -113.11244) (xy 455.816716 -113.123726) (xy 455.801116 -113.145325)
			(xy 455.764204 -113.183742) (xy 455.721611 -113.215744) (xy 455.674437 -113.240503) (xy 455.623904 -113.257378)
			(xy 455.57132 -113.265932) (xy 455.544682 -113.266474) (xy 455.518693 -113.266031) (xy 455.467356 -113.257897)
			(xy 455.417922 -113.241833) (xy 455.371611 -113.218234) (xy 455.329561 -113.187681) (xy 455.292808 -113.150926)
			(xy 455.262257 -113.108874) (xy 455.23866 -113.062561) (xy 455.222598 -113.013127) (xy 455.214468 -112.961789)
			(xy 453.972487 -112.961789) (xy 453.960836 -112.975235) (xy 453.919648 -113.010926) (xy 453.873799 -113.040393)
			(xy 453.824224 -113.063035) (xy 453.771932 -113.078393) (xy 453.717986 -113.086154) (xy 453.690736 -113.086642)
			(xy 453.66442 -113.086236) (xy 453.612288 -113.078991) (xy 453.561643 -113.064661) (xy 453.513444 -113.043517)
			(xy 453.468602 -113.01596) (xy 453.427966 -112.982509) (xy 453.409812 -112.963452) (xy 453.402281 -112.956061)
			(xy 453.383008 -112.947529) (xy 453.372474 -112.946942) (xy 453.297798 -112.946942) (xy 453.287245 -112.947444)
			(xy 453.267949 -112.955997) (xy 453.26046 -112.963452) (xy 453.242327 -112.98253) (xy 453.201691 -113.015983)
			(xy 453.156846 -113.043538) (xy 453.108641 -113.064672) (xy 453.05799 -113.078985) (xy 453.005853 -113.086206)
			(xy 452.979536 -113.086642) (xy 452.952286 -113.086111) (xy 452.898339 -113.07836) (xy 452.846044 -113.06301)
			(xy 452.796467 -113.040375) (xy 452.750615 -113.010913) (xy 452.709423 -112.975227) (xy 452.673729 -112.934041)
			(xy 452.644259 -112.888195) (xy 452.621614 -112.838621) (xy 452.606255 -112.78633) (xy 452.598494 -112.732384)
			(xy 452.598028 -112.705134) (xy 452.598442 -112.678818) (xy 452.605687 -112.626687) (xy 452.620016 -112.576043)
			(xy 452.641158 -112.527844) (xy 452.668714 -112.483002) (xy 452.702162 -112.442365) (xy 452.721218 -112.42421)
			(xy 452.72862 -112.416689) (xy 452.737144 -112.397408) (xy 452.737728 -112.386872) (xy 452.737728 -112.312196)
			(xy 452.737206 -112.301646) (xy 452.728665 -112.282351) (xy 452.721218 -112.274858) (xy 452.700462 -112.255005)
			(xy 452.664484 -112.210239) (xy 452.63562 -112.160586) (xy 452.614523 -112.107169) (xy 452.60167 -112.051193)
			(xy 452.597351 -111.993923) (xy 449.155522 -111.993923) (xy 449.158813 -112.037615) (xy 449.154495 -112.09489)
			(xy 449.141643 -112.150871) (xy 449.120547 -112.204294) (xy 449.091684 -112.253953) (xy 449.055706 -112.298726)
			(xy 449.034916 -112.318546) (xy 449.027494 -112.326051) (xy 449.018981 -112.345343) (xy 449.018406 -112.355884)
			(xy 449.018406 -112.43056) (xy 449.018941 -112.441109) (xy 449.027472 -112.460405) (xy 449.034916 -112.467898)
			(xy 449.053967 -112.486058) (xy 449.087424 -112.526687) (xy 449.114983 -112.571527) (xy 449.136122 -112.619727)
			(xy 449.15044 -112.670373) (xy 449.157667 -112.722506) (xy 449.158106 -112.748822) (xy 449.15762 -112.776073)
			(xy 449.149864 -112.830021) (xy 449.134509 -112.882316) (xy 449.111867 -112.931893) (xy 449.082401 -112.977743)
			(xy 449.04671 -113.018934) (xy 449.005519 -113.054625) (xy 448.959669 -113.084091) (xy 448.910092 -113.106733)
			(xy 448.857797 -113.122088) (xy 448.803849 -113.129844) (xy 448.749347 -113.129844) (xy 448.695399 -113.122088)
			(xy 448.643104 -113.106733) (xy 448.593527 -113.084091) (xy 448.547677 -113.054625) (xy 448.506486 -113.018934)
			(xy 448.470795 -112.977743) (xy 448.441329 -112.931893) (xy 448.418687 -112.882316) (xy 448.403332 -112.830021)
			(xy 448.395576 -112.776073) (xy 448.39509 -112.748822) (xy 448.395575 -112.722509) (xy 448.402807 -112.670381)
			(xy 448.417123 -112.619739) (xy 448.438252 -112.57154) (xy 448.465795 -112.526696) (xy 448.49923 -112.486055)
			(xy 448.51828 -112.467898) (xy 448.525682 -112.460376) (xy 448.534207 -112.441096) (xy 448.53479 -112.43056)
			(xy 448.53479 -112.355884) (xy 448.534286 -112.345331) (xy 448.525734 -112.326036) (xy 448.51828 -112.318546)
			(xy 448.497514 -112.298704) (xy 448.461539 -112.253935) (xy 448.432679 -112.20428) (xy 448.411585 -112.150861)
			(xy 448.398734 -112.094885) (xy 448.394417 -112.037615) (xy 446.620598 -112.037615) (xy 446.61628 -112.094891)
			(xy 446.603427 -112.150872) (xy 446.58233 -112.204296) (xy 446.553465 -112.253954) (xy 446.517485 -112.298727)
			(xy 446.496694 -112.318546) (xy 446.489269 -112.326048) (xy 446.480759 -112.345343) (xy 446.480184 -112.355884)
			(xy 446.480184 -112.43056) (xy 446.480726 -112.441108) (xy 446.489253 -112.460403) (xy 446.496694 -112.467898)
			(xy 446.51574 -112.486063) (xy 446.549199 -112.52669) (xy 446.576759 -112.571529) (xy 446.597899 -112.619728)
			(xy 446.612218 -112.670374) (xy 446.619445 -112.722506) (xy 446.619884 -112.748822) (xy 446.619398 -112.776073)
			(xy 446.611642 -112.830021) (xy 446.596287 -112.882316) (xy 446.573645 -112.931893) (xy 446.544179 -112.977743)
			(xy 446.508488 -113.018934) (xy 446.467297 -113.054625) (xy 446.421447 -113.084091) (xy 446.37187 -113.106733)
			(xy 446.319575 -113.122088) (xy 446.265627 -113.129844) (xy 446.211125 -113.129844) (xy 446.157177 -113.122088)
			(xy 446.104882 -113.106733) (xy 446.055305 -113.084091) (xy 446.009455 -113.054625) (xy 445.968264 -113.018934)
			(xy 445.932573 -112.977743) (xy 445.903107 -112.931893) (xy 445.880465 -112.882316) (xy 445.86511 -112.830021)
			(xy 445.857354 -112.776073) (xy 445.856868 -112.748822) (xy 445.85736 -112.722509) (xy 445.864592 -112.670382)
			(xy 445.878906 -112.61974) (xy 445.900034 -112.571541) (xy 445.927575 -112.526697) (xy 445.961009 -112.486056)
			(xy 445.980058 -112.467898) (xy 445.987456 -112.460373) (xy 445.995984 -112.441096) (xy 445.996568 -112.43056)
			(xy 445.996568 -112.355884) (xy 445.99607 -112.34533) (xy 445.987514 -112.326035) (xy 445.980058 -112.318546)
			(xy 445.959293 -112.298703) (xy 445.92332 -112.253933) (xy 445.894462 -112.204279) (xy 445.873369 -112.15086)
			(xy 445.860519 -112.094884) (xy 445.856202 -112.037615) (xy 444.06285 -112.037615) (xy 444.094309 -112.075823)
			(xy 444.121867 -112.120665) (xy 444.143003 -112.168869) (xy 444.157317 -112.219519) (xy 444.164538 -112.271655)
			(xy 444.164974 -112.297972) (xy 444.164488 -112.325223) (xy 444.156732 -112.379171) (xy 444.141377 -112.431466)
			(xy 444.118735 -112.481043) (xy 444.089269 -112.526893) (xy 444.053578 -112.568084) (xy 444.012387 -112.603775)
			(xy 443.966537 -112.633241) (xy 443.91696 -112.655883) (xy 443.864665 -112.671238) (xy 443.810717 -112.678994)
			(xy 443.756215 -112.678994) (xy 443.702267 -112.671238) (xy 443.649972 -112.655883) (xy 443.600395 -112.633241)
			(xy 443.554545 -112.603775) (xy 443.513354 -112.568084) (xy 443.477663 -112.526893) (xy 443.448197 -112.481043)
			(xy 443.425555 -112.431466) (xy 443.4102 -112.379171) (xy 443.402444 -112.325223) (xy 443.401958 -112.297972)
			(xy 442.132974 -112.297972) (xy 442.132488 -112.325223) (xy 442.124732 -112.379171) (xy 442.109377 -112.431466)
			(xy 442.086735 -112.481043) (xy 442.057269 -112.526893) (xy 442.021578 -112.568084) (xy 441.980387 -112.603775)
			(xy 441.934537 -112.633241) (xy 441.88496 -112.655883) (xy 441.832665 -112.671238) (xy 441.778717 -112.678994)
			(xy 441.724215 -112.678994) (xy 441.670267 -112.671238) (xy 441.617972 -112.655883) (xy 441.568395 -112.633241)
			(xy 441.522545 -112.603775) (xy 441.481354 -112.568084) (xy 441.445663 -112.526893) (xy 441.416197 -112.481043)
			(xy 441.393555 -112.431466) (xy 441.3782 -112.379171) (xy 441.370444 -112.325223) (xy 441.369958 -112.297972)
			(xy 439.610019 -112.297972) (xy 439.61656 -112.321118) (xy 439.62378 -112.373255) (xy 439.624216 -112.399572)
			(xy 439.62373 -112.426823) (xy 439.615974 -112.480771) (xy 439.600619 -112.533066) (xy 439.577977 -112.582643)
			(xy 439.548511 -112.628493) (xy 439.51282 -112.669684) (xy 439.471629 -112.705375) (xy 439.425779 -112.734841)
			(xy 439.376202 -112.757483) (xy 439.323907 -112.772838) (xy 439.269959 -112.780594) (xy 439.215457 -112.780594)
			(xy 439.161509 -112.772838) (xy 439.109214 -112.757483) (xy 439.059637 -112.734841) (xy 439.013787 -112.705375)
			(xy 438.972596 -112.669684) (xy 438.936905 -112.628493) (xy 438.907439 -112.582643) (xy 438.884797 -112.533066)
			(xy 438.869442 -112.480771) (xy 438.861686 -112.426823) (xy 438.8612 -112.399572) (xy 420.884417 -112.399572)
			(xy 420.902044 -112.44034) (xy 420.915992 -112.490338) (xy 420.92303 -112.541766) (xy 420.923466 -112.56772)
			(xy 420.92298 -112.594971) (xy 420.915224 -112.648919) (xy 420.899869 -112.701214) (xy 420.877227 -112.750791)
			(xy 420.847761 -112.796641) (xy 420.81207 -112.837832) (xy 420.770879 -112.873523) (xy 420.725029 -112.902989)
			(xy 420.675452 -112.925631) (xy 420.623157 -112.940986) (xy 420.569209 -112.948742) (xy 420.514707 -112.948742)
			(xy 420.460759 -112.940986) (xy 420.408464 -112.925631) (xy 420.358887 -112.902989) (xy 420.313037 -112.873523)
			(xy 420.271846 -112.837832) (xy 420.236155 -112.796641) (xy 420.206689 -112.750791) (xy 420.184047 -112.701214)
			(xy 420.168692 -112.648919) (xy 420.160936 -112.594971) (xy 420.16045 -112.56772) (xy 420.160998 -112.537925)
			(xy 420.170261 -112.47906) (xy 420.188564 -112.42235) (xy 420.215462 -112.369177) (xy 420.250302 -112.320833)
			(xy 420.292235 -112.278494) (xy 420.315898 -112.26038) (xy 420.322656 -112.254997) (xy 420.332395 -112.240742)
			(xy 420.336823 -112.224054) (xy 420.336472 -112.215422) (xy 420.329868 -112.12957) (xy 420.328919 -112.121062)
			(xy 420.322158 -112.105347) (xy 420.310585 -112.092748) (xy 420.303198 -112.088422) (xy 420.302944 -112.088422)
			(xy 420.28015 -112.076006) (xy 420.237856 -112.045918) (xy 420.200034 -112.01037) (xy 420.167383 -111.97002)
			(xy 420.140508 -111.925615) (xy 420.119904 -111.877975) (xy 420.105953 -111.82798) (xy 420.098912 -111.776555)
			(xy 420.098474 -111.750602) (xy 420.098914 -111.723581) (xy 420.10653 -111.670077) (xy 420.121622 -111.618185)
			(xy 420.14389 -111.568943) (xy 420.172886 -111.523338) (xy 420.20803 -111.482284) (xy 420.228014 -111.46409)
			(xy 420.235975 -111.456435) (xy 420.244922 -111.436268) (xy 420.245286 -111.425228) (xy 420.244016 -111.348012)
			(xy 420.243366 -111.336998) (xy 420.233868 -111.317108) (xy 420.225728 -111.309658) (xy 420.204585 -111.291438)
			(xy 420.167309 -111.2499) (xy 420.136486 -111.203373) (xy 420.112774 -111.152849) (xy 420.096679 -111.099409)
			(xy 420.088546 -111.044194) (xy 420.08806 -111.016288) (xy 416.207939 -111.016288) (xy 416.223303 -111.068345)
			(xy 416.231132 -111.122523) (xy 416.231133 -111.177265) (xy 416.223306 -111.231444) (xy 416.207811 -111.283946)
			(xy 416.184968 -111.333694) (xy 416.155245 -111.379663) (xy 416.137598 -111.40059) (xy 416.137598 -111.400844)
			(xy 416.137344 -111.400844) (xy 416.131746 -111.407927) (xy 416.12548 -111.424844) (xy 416.125152 -111.433864)
			(xy 416.125152 -111.50092) (xy 416.125514 -111.509936) (xy 416.131761 -111.526851) (xy 416.137344 -111.53394)
			(xy 416.137598 -111.534194) (xy 416.15524 -111.555125) (xy 416.184967 -111.601091) (xy 416.207811 -111.650838)
			(xy 416.223303 -111.703342) (xy 416.231122 -111.757521) (xy 416.231578 -111.784892) (xy 416.231093 -111.812452)
			(xy 416.223159 -111.866999) (xy 416.218045 -111.884206) (xy 418.664388 -111.884206) (xy 418.668459 -111.828584)
			(xy 418.680585 -111.774147) (xy 418.700508 -111.722056) (xy 418.727804 -111.673421) (xy 418.76189 -111.629278)
			(xy 418.802039 -111.590569) (xy 418.847397 -111.558118) (xy 418.896997 -111.532617) (xy 418.949781 -111.51461)
			(xy 419.004624 -111.50448) (xy 419.060358 -111.502443) (xy 419.115795 -111.508543) (xy 419.169752 -111.522649)
			(xy 419.221081 -111.544461) (xy 419.268687 -111.573515) (xy 419.311555 -111.60919) (xy 419.348772 -111.650727)
			(xy 419.379545 -111.69724) (xy 419.403217 -111.747737) (xy 419.419285 -111.801144) (xy 419.427405 -111.85632)
			(xy 419.427914 -111.884206) (xy 419.427405 -111.912092) (xy 419.419285 -111.967268) (xy 419.403217 -112.020675)
			(xy 419.379545 -112.071172) (xy 419.348772 -112.117685) (xy 419.311555 -112.159222) (xy 419.268687 -112.194897)
			(xy 419.221081 -112.223951) (xy 419.169752 -112.245763) (xy 419.115795 -112.259869) (xy 419.060358 -112.265969)
			(xy 419.004624 -112.263932) (xy 418.949781 -112.253802) (xy 418.896997 -112.235795) (xy 418.847397 -112.210294)
			(xy 418.802039 -112.177843) (xy 418.76189 -112.139134) (xy 418.727804 -112.094991) (xy 418.700508 -112.046356)
			(xy 418.680585 -111.994265) (xy 418.668459 -111.939828) (xy 418.664388 -111.884206) (xy 416.218045 -111.884206)
			(xy 416.207455 -111.919834) (xy 416.184308 -111.969859) (xy 416.154201 -112.016031) (xy 416.117761 -112.057387)
			(xy 416.075747 -112.093067) (xy 416.029034 -112.122327) (xy 415.978595 -112.144557) (xy 415.952178 -112.15243)
			(xy 415.95167 -112.15243) (xy 415.94151 -112.155478) (xy 415.925254 -112.168686) (xy 415.881566 -112.25403)
			(xy 415.880042 -112.274858) (xy 415.883852 -112.285018) (xy 415.895019 -112.317232) (xy 415.91065 -112.383599)
			(xy 415.915075 -112.421924) (xy 417.755068 -112.421924) (xy 417.759139 -112.366302) (xy 417.771265 -112.311865)
			(xy 417.791188 -112.259774) (xy 417.818484 -112.211139) (xy 417.85257 -112.166996) (xy 417.892719 -112.128287)
			(xy 417.938077 -112.095836) (xy 417.987677 -112.070335) (xy 418.040461 -112.052328) (xy 418.095304 -112.042198)
			(xy 418.151038 -112.040161) (xy 418.206475 -112.046261) (xy 418.260432 -112.060367) (xy 418.311761 -112.082179)
			(xy 418.359367 -112.111233) (xy 418.402235 -112.146908) (xy 418.439452 -112.188445) (xy 418.470225 -112.234958)
			(xy 418.493897 -112.285455) (xy 418.509965 -112.338862) (xy 418.518085 -112.394038) (xy 418.518594 -112.421924)
			(xy 418.518085 -112.44981) (xy 418.509965 -112.504986) (xy 418.493897 -112.558393) (xy 418.470225 -112.60889)
			(xy 418.439452 -112.655403) (xy 418.402235 -112.69694) (xy 418.359367 -112.732615) (xy 418.311761 -112.761669)
			(xy 418.260432 -112.783481) (xy 418.206475 -112.797587) (xy 418.151038 -112.803687) (xy 418.095304 -112.80165)
			(xy 418.040461 -112.79152) (xy 417.987677 -112.773513) (xy 417.938077 -112.748012) (xy 417.892719 -112.715561)
			(xy 417.85257 -112.676852) (xy 417.818484 -112.632709) (xy 417.791188 -112.584074) (xy 417.771265 -112.531983)
			(xy 417.759139 -112.477546) (xy 417.755068 -112.421924) (xy 415.915075 -112.421924) (xy 415.91847 -112.451332)
			(xy 415.918904 -112.485424) (xy 415.918475 -112.518297) (xy 415.91114 -112.583633) (xy 415.896533 -112.647736)
			(xy 415.874837 -112.7098) (xy 415.846325 -112.769042) (xy 415.811356 -112.824717) (xy 415.770371 -112.876125)
			(xy 415.747454 -112.899698) (xy 415.723832 -112.92332) (xy 415.717005 -112.930646) (xy 415.709244 -112.94909)
			(xy 415.709162 -112.969099) (xy 415.716771 -112.987606) (xy 415.718633 -112.989614) (xy 418.74008 -112.989614)
			(xy 418.744151 -112.933992) (xy 418.756277 -112.879555) (xy 418.7762 -112.827464) (xy 418.803496 -112.778829)
			(xy 418.837582 -112.734686) (xy 418.877731 -112.695977) (xy 418.923089 -112.663526) (xy 418.972689 -112.638025)
			(xy 419.025473 -112.620018) (xy 419.080316 -112.609888) (xy 419.13605 -112.607851) (xy 419.191487 -112.613951)
			(xy 419.245444 -112.628057) (xy 419.296773 -112.649869) (xy 419.344379 -112.678923) (xy 419.387247 -112.714598)
			(xy 419.424464 -112.756135) (xy 419.455237 -112.802648) (xy 419.478909 -112.853145) (xy 419.494977 -112.906552)
			(xy 419.503097 -112.961728) (xy 419.503606 -112.989614) (xy 419.503097 -113.0175) (xy 419.494977 -113.072676)
			(xy 419.478909 -113.126083) (xy 419.455237 -113.17658) (xy 419.424464 -113.223093) (xy 419.390829 -113.260632)
			(xy 423.7388 -113.260632) (xy 423.742871 -113.20501) (xy 423.754997 -113.150573) (xy 423.77492 -113.098482)
			(xy 423.802216 -113.049847) (xy 423.836302 -113.005704) (xy 423.876451 -112.966995) (xy 423.921809 -112.934544)
			(xy 423.971409 -112.909043) (xy 424.024193 -112.891036) (xy 424.079036 -112.880906) (xy 424.13477 -112.878869)
			(xy 424.190207 -112.884969) (xy 424.244164 -112.899075) (xy 424.295493 -112.920887) (xy 424.343099 -112.949941)
			(xy 424.385967 -112.985616) (xy 424.423184 -113.027153) (xy 424.453957 -113.073666) (xy 424.477629 -113.124163)
			(xy 424.493697 -113.17757) (xy 424.501398 -113.229898) (xy 424.7421 -113.229898) (xy 424.746171 -113.174276)
			(xy 424.758297 -113.119839) (xy 424.77822 -113.067748) (xy 424.805516 -113.019113) (xy 424.839602 -112.97497)
			(xy 424.879751 -112.936261) (xy 424.925109 -112.90381) (xy 424.974709 -112.878309) (xy 425.027493 -112.860302)
			(xy 425.082336 -112.850172) (xy 425.13807 -112.848135) (xy 425.193507 -112.854235) (xy 425.247464 -112.868341)
			(xy 425.298793 -112.890153) (xy 425.346399 -112.919207) (xy 425.389267 -112.954882) (xy 425.426484 -112.996419)
			(xy 425.457257 -113.042932) (xy 425.480929 -113.093429) (xy 425.496997 -113.146836) (xy 425.505117 -113.202012)
			(xy 425.505626 -113.229898) (xy 425.505117 -113.257784) (xy 425.496997 -113.31296) (xy 425.480929 -113.366367)
			(xy 425.457257 -113.416864) (xy 425.426484 -113.463377) (xy 425.389267 -113.504914) (xy 425.346399 -113.540589)
			(xy 425.298793 -113.569643) (xy 425.247464 -113.591455) (xy 425.193507 -113.605561) (xy 425.13807 -113.611661)
			(xy 425.082336 -113.609624) (xy 425.027493 -113.599494) (xy 424.974709 -113.581487) (xy 424.925109 -113.555986)
			(xy 424.879751 -113.523535) (xy 424.839602 -113.484826) (xy 424.805516 -113.440683) (xy 424.77822 -113.392048)
			(xy 424.758297 -113.339957) (xy 424.746171 -113.28552) (xy 424.7421 -113.229898) (xy 424.501398 -113.229898)
			(xy 424.501817 -113.232746) (xy 424.502326 -113.260632) (xy 424.501817 -113.288518) (xy 424.493697 -113.343694)
			(xy 424.477629 -113.397101) (xy 424.453957 -113.447598) (xy 424.423184 -113.494111) (xy 424.385967 -113.535648)
			(xy 424.343099 -113.571323) (xy 424.295493 -113.600377) (xy 424.244164 -113.622189) (xy 424.190207 -113.636295)
			(xy 424.13477 -113.642395) (xy 424.079036 -113.640358) (xy 424.024193 -113.630228) (xy 423.971409 -113.612221)
			(xy 423.921809 -113.58672) (xy 423.876451 -113.554269) (xy 423.836302 -113.51556) (xy 423.802216 -113.471417)
			(xy 423.77492 -113.422782) (xy 423.754997 -113.370691) (xy 423.742871 -113.316254) (xy 423.7388 -113.260632)
			(xy 419.390829 -113.260632) (xy 419.387247 -113.26463) (xy 419.344379 -113.300305) (xy 419.296773 -113.329359)
			(xy 419.245444 -113.351171) (xy 419.191487 -113.365277) (xy 419.13605 -113.371377) (xy 419.080316 -113.36934)
			(xy 419.025473 -113.35921) (xy 418.972689 -113.341203) (xy 418.923089 -113.315702) (xy 418.877731 -113.283251)
			(xy 418.837582 -113.244542) (xy 418.803496 -113.200399) (xy 418.7762 -113.151764) (xy 418.756277 -113.099673)
			(xy 418.744151 -113.045236) (xy 418.74008 -112.989614) (xy 415.718633 -112.989614) (xy 415.723578 -112.994948)
			(xy 415.724848 -112.996218) (xy 415.726118 -112.997234) (xy 415.755063 -113.023769) (xy 415.806289 -113.083284)
			(xy 415.828226 -113.115852) (xy 415.830795 -113.119626) (xy 415.837063 -113.126263) (xy 415.840672 -113.12906)
			(xy 415.862316 -113.14576) (xy 415.901055 -113.184331) (xy 415.933892 -113.228035) (xy 415.960157 -113.275979)
			(xy 415.97931 -113.327181) (xy 415.99096 -113.380591) (xy 415.994868 -113.435118) (xy 415.994667 -113.437924)
			(xy 417.657786 -113.437924) (xy 417.661857 -113.382302) (xy 417.673983 -113.327865) (xy 417.693906 -113.275774)
			(xy 417.721202 -113.227139) (xy 417.755288 -113.182996) (xy 417.795437 -113.144287) (xy 417.840795 -113.111836)
			(xy 417.890395 -113.086335) (xy 417.943179 -113.068328) (xy 417.998022 -113.058198) (xy 418.053756 -113.056161)
			(xy 418.109193 -113.062261) (xy 418.16315 -113.076367) (xy 418.214479 -113.098179) (xy 418.262085 -113.127233)
			(xy 418.304953 -113.162908) (xy 418.34217 -113.204445) (xy 418.372943 -113.250958) (xy 418.396615 -113.301455)
			(xy 418.412683 -113.354862) (xy 418.420803 -113.410038) (xy 418.421312 -113.437924) (xy 418.420803 -113.46581)
			(xy 418.412683 -113.520986) (xy 418.396615 -113.574393) (xy 418.372943 -113.62489) (xy 418.348759 -113.661444)
			(xy 436.170322 -113.661444) (xy 436.174393 -113.605822) (xy 436.186519 -113.551385) (xy 436.206442 -113.499294)
			(xy 436.233738 -113.450659) (xy 436.267824 -113.406516) (xy 436.307973 -113.367807) (xy 436.353331 -113.335356)
			(xy 436.402931 -113.309855) (xy 436.455715 -113.291848) (xy 436.510558 -113.281718) (xy 436.566292 -113.279681)
			(xy 436.621729 -113.285781) (xy 436.675686 -113.299887) (xy 436.727015 -113.321699) (xy 436.774621 -113.350753)
			(xy 436.817489 -113.386428) (xy 436.854706 -113.427965) (xy 436.885479 -113.474478) (xy 436.909151 -113.524975)
			(xy 436.925219 -113.578382) (xy 436.933339 -113.633558) (xy 436.933848 -113.661444) (xy 436.933339 -113.68933)
			(xy 436.925219 -113.744506) (xy 436.909151 -113.797913) (xy 436.885479 -113.84841) (xy 436.854706 -113.894923)
			(xy 436.817489 -113.93646) (xy 436.774621 -113.972135) (xy 436.727015 -114.001189) (xy 436.675686 -114.023001)
			(xy 436.621729 -114.037107) (xy 436.566292 -114.043207) (xy 436.510558 -114.04117) (xy 436.455715 -114.03104)
			(xy 436.402931 -114.013033) (xy 436.353331 -113.987532) (xy 436.307973 -113.955081) (xy 436.267824 -113.916372)
			(xy 436.233738 -113.872229) (xy 436.206442 -113.823594) (xy 436.186519 -113.771503) (xy 436.174393 -113.717066)
			(xy 436.170322 -113.661444) (xy 418.348759 -113.661444) (xy 418.34217 -113.671403) (xy 418.304953 -113.71294)
			(xy 418.262085 -113.748615) (xy 418.214479 -113.777669) (xy 418.16315 -113.799481) (xy 418.109193 -113.813587)
			(xy 418.053756 -113.819687) (xy 417.998022 -113.81765) (xy 417.943179 -113.80752) (xy 417.890395 -113.789513)
			(xy 417.840795 -113.764012) (xy 417.795437 -113.731561) (xy 417.755288 -113.692852) (xy 417.721202 -113.648709)
			(xy 417.693906 -113.600074) (xy 417.673983 -113.547983) (xy 417.661857 -113.493546) (xy 417.657786 -113.437924)
			(xy 415.994667 -113.437924) (xy 415.990955 -113.489644) (xy 415.9793 -113.543054) (xy 415.960142 -113.594253)
			(xy 415.933873 -113.642195) (xy 415.901031 -113.685896) (xy 415.862289 -113.724464) (xy 415.840672 -113.7412)
			(xy 415.837064 -113.743997) (xy 415.830808 -113.750643) (xy 415.828226 -113.754408) (xy 415.811203 -113.779872)
			(xy 415.772645 -113.827471) (xy 415.751264 -113.849404) (xy 415.287968 -114.3127) (xy 415.28492 -114.349022)
			(xy 415.292794 -114.360706) (xy 415.293302 -114.361214) (xy 415.306957 -114.381217) (xy 415.329651 -114.424004)
			(xy 415.34675 -114.469318) (xy 415.352738 -114.492786) (xy 415.355042 -114.501024) (xy 415.364272 -114.515416)
			(xy 415.370772 -114.52098) (xy 415.37763 -114.526314) (xy 415.393378 -114.531902) (xy 415.562796 -114.531902)
			(xy 415.570527 -114.531634) (xy 415.58527 -114.52698) (xy 415.591752 -114.522758) (xy 415.598102 -114.518694)
			(xy 415.607246 -114.506756) (xy 415.610294 -114.499136) (xy 415.620403 -114.473999) (xy 415.646697 -114.426629)
			(xy 415.679422 -114.38345) (xy 415.717923 -114.345331) (xy 415.761424 -114.313037) (xy 415.809054 -114.287215)
			(xy 415.859855 -114.268386) (xy 415.912808 -114.256926) (xy 415.966849 -114.253066) (xy 416.020893 -114.256883)
			(xy 416.073855 -114.268301) (xy 416.124671 -114.287091) (xy 416.172321 -114.312874) (xy 416.215848 -114.345134)
			(xy 416.254379 -114.383223) (xy 416.287138 -114.426376) (xy 416.313469 -114.473725) (xy 416.323526 -114.498882)
			(xy 416.323526 -114.49939) (xy 416.32378 -114.499644) (xy 416.326739 -114.50659) (xy 416.33603 -114.51848)
			(xy 416.342068 -114.523012) (xy 416.348672 -114.52733) (xy 416.362896 -114.531902) (xy 418.580062 -114.531902)
			(xy 418.582602 -114.531902) (xy 418.593549 -114.530831) (xy 418.613048 -114.520704) (xy 418.620194 -114.512344)
			(xy 418.620956 -114.511328) (xy 418.66947 -114.445796) (xy 418.672828 -114.440917) (xy 418.677447 -114.430013)
			(xy 418.678614 -114.424206) (xy 418.680646 -114.412522) (xy 418.677344 -114.400838) (xy 418.669647 -114.373801)
			(xy 418.661361 -114.318201) (xy 418.660834 -114.290094) (xy 418.66132 -114.262843) (xy 418.669076 -114.208895)
			(xy 418.684431 -114.1566) (xy 418.707073 -114.107023) (xy 418.736539 -114.061173) (xy 418.77223 -114.019982)
			(xy 418.813421 -113.984291) (xy 418.859271 -113.954825) (xy 418.908848 -113.932183) (xy 418.961143 -113.916828)
			(xy 419.015091 -113.909072) (xy 419.069593 -113.909072) (xy 419.123541 -113.916828) (xy 419.175836 -113.932183)
			(xy 419.225413 -113.954825) (xy 419.271263 -113.984291) (xy 419.312454 -114.019982) (xy 419.348145 -114.061173)
			(xy 419.377611 -114.107023) (xy 419.400253 -114.1566) (xy 419.415608 -114.208895) (xy 419.423364 -114.262843)
			(xy 419.42385 -114.290094) (xy 419.423334 -114.318202) (xy 419.415051 -114.373804) (xy 419.40734 -114.400838)
			(xy 419.404038 -114.412522) (xy 419.40607 -114.424206) (xy 419.407204 -114.430023) (xy 419.411826 -114.440933)
			(xy 419.415214 -114.445796) (xy 419.463728 -114.511328) (xy 419.46449 -114.512344) (xy 419.471656 -114.52068)
			(xy 419.491143 -114.530807) (xy 419.502082 -114.531902) (xy 420.245794 -114.531902) (xy 420.250205 -114.531819)
			(xy 420.258895 -114.530293) (xy 420.263066 -114.528854) (xy 420.286942 -114.520218) (xy 420.293292 -114.514884)
			(xy 420.316005 -114.497312) (xy 420.36566 -114.468473) (xy 420.419076 -114.447395) (xy 420.475045 -114.434556)
			(xy 420.532306 -114.430244) (xy 420.589567 -114.434556) (xy 420.645536 -114.447395) (xy 420.698952 -114.468473)
			(xy 420.748607 -114.497312) (xy 420.77132 -114.514884) (xy 420.77767 -114.520218) (xy 420.801546 -114.528854)
			(xy 420.805725 -114.530263) (xy 420.814409 -114.531796) (xy 420.818818 -114.531902) (xy 422.43121 -114.531902)
			(xy 422.437362 -114.531728) (xy 422.449305 -114.528768) (xy 422.454832 -114.52606) (xy 422.485312 -114.510058)
			(xy 422.486836 -114.508026) (xy 422.502187 -114.486725) (xy 422.537799 -114.448144) (xy 422.578367 -114.414813)
			(xy 422.623123 -114.387363) (xy 422.671223 -114.366311) (xy 422.721755 -114.352058) (xy 422.773766 -114.344871)
			(xy 422.800018 -114.34445) (xy 422.827387 -114.344923) (xy 422.881564 -114.35275) (xy 422.934065 -114.368241)
			(xy 422.983812 -114.391077) (xy 423.029785 -114.42079) (xy 423.050716 -114.43843) (xy 423.057828 -114.444526)
			(xy 423.06621 -114.447574) (xy 423.070498 -114.449094) (xy 423.079442 -114.450754) (xy 423.08399 -114.450876)
			(xy 423.151046 -114.450876) (xy 423.155594 -114.450754) (xy 423.164539 -114.449097) (xy 423.168826 -114.447574)
			(xy 423.177208 -114.444526) (xy 423.18432 -114.43843) (xy 423.205251 -114.420788) (xy 423.251217 -114.391062)
			(xy 423.300964 -114.36822) (xy 423.353468 -114.352731) (xy 423.407648 -114.344914) (xy 423.435018 -114.34445)
			(xy 423.461268 -114.344888) (xy 423.513274 -114.352087) (xy 423.563801 -114.366346) (xy 423.611897 -114.387397)
			(xy 423.656654 -114.414841) (xy 423.697226 -114.448161) (xy 423.732848 -114.486728) (xy 423.7482 -114.508026)
			(xy 423.749724 -114.510058) (xy 423.780204 -114.52606) (xy 423.785735 -114.528755) (xy 423.797676 -114.531707)
			(xy 423.803826 -114.531902) (xy 429.590454 -114.531902) (xy 429.599713 -114.531552) (xy 429.617044 -114.525043)
			(xy 429.624236 -114.519202) (xy 429.625506 -114.517932) (xy 429.626268 -114.51717) (xy 429.677068 -114.46637)
			(xy 429.680591 -114.462641) (xy 429.686223 -114.454067) (xy 429.688244 -114.449352) (xy 429.692054 -114.440208)
			(xy 429.692054 -114.430048) (xy 429.692483 -114.402771) (xy 429.700181 -114.348765) (xy 429.715493 -114.296407)
			(xy 429.738106 -114.246763) (xy 429.767561 -114.200846) (xy 429.803254 -114.159592) (xy 429.84446 -114.123843)
			(xy 429.890338 -114.094328) (xy 429.939952 -114.071648) (xy 429.99229 -114.056267) (xy 430.046286 -114.048497)
			(xy 430.100838 -114.048497) (xy 430.154834 -114.056267) (xy 430.207172 -114.071648) (xy 430.256786 -114.094328)
			(xy 430.302664 -114.123843) (xy 430.34387 -114.159592) (xy 430.379563 -114.200846) (xy 430.409018 -114.246763)
			(xy 430.431631 -114.296407) (xy 430.446943 -114.348765) (xy 430.454641 -114.402771) (xy 430.45507 -114.430048)
			(xy 430.45507 -114.430302) (xy 430.45888 -114.449352) (xy 430.46269 -114.459004) (xy 430.520856 -114.51717)
			(xy 430.521618 -114.517932) (xy 430.522888 -114.519202) (xy 430.5301 -114.525009) (xy 430.547419 -114.531518)
			(xy 430.55667 -114.531902) (xy 433.43703 -114.531902) (xy 433.446291 -114.531556) (xy 433.463627 -114.525053)
			(xy 433.470812 -114.519202) (xy 433.472082 -114.517932) (xy 433.472844 -114.51717) (xy 433.523644 -114.46637)
			(xy 433.527163 -114.462638) (xy 433.532787 -114.454062) (xy 433.53482 -114.449352) (xy 433.53863 -114.440208)
			(xy 433.53863 -114.430048) (xy 433.539059 -114.402771) (xy 433.546757 -114.348765) (xy 433.562069 -114.296407)
			(xy 433.584682 -114.246763) (xy 433.614137 -114.200846) (xy 433.64983 -114.159592) (xy 433.691036 -114.123843)
			(xy 433.736914 -114.094328) (xy 433.786528 -114.071648) (xy 433.838866 -114.056267) (xy 433.892862 -114.048497)
			(xy 433.947414 -114.048497) (xy 434.00141 -114.056267) (xy 434.053748 -114.071648) (xy 434.08211 -114.084613)
			(xy 437.749383 -114.084613) (xy 437.749388 -114.030111) (xy 437.75715 -113.976165) (xy 437.77251 -113.923872)
			(xy 437.795156 -113.874298) (xy 437.824627 -113.828451) (xy 437.860322 -113.787265) (xy 437.901515 -113.751579)
			(xy 437.947368 -113.722118) (xy 437.996947 -113.699482) (xy 438.049243 -113.684133) (xy 438.103191 -113.676382)
			(xy 438.130442 -113.675922) (xy 438.130696 -113.675922) (xy 438.160133 -113.676472) (xy 438.218307 -113.685537)
			(xy 438.24652 -113.693956) (xy 438.258458 -113.697766) (xy 438.282334 -113.693956) (xy 438.358534 -113.637568)
			(xy 438.367806 -113.629826) (xy 438.37855 -113.608231) (xy 438.379108 -113.596166) (xy 438.379108 -113.591086)
			(xy 438.379542 -113.563832) (xy 438.387301 -113.509879) (xy 438.40266 -113.45758) (xy 438.425305 -113.407998)
			(xy 438.454776 -113.362145) (xy 438.490473 -113.320952) (xy 438.531669 -113.285258) (xy 438.577525 -113.255791)
			(xy 438.627108 -113.233149) (xy 438.679409 -113.217795) (xy 438.733362 -113.21004) (xy 438.760616 -113.209578)
			(xy 438.789532 -113.210127) (xy 438.846703 -113.218846) (xy 438.901903 -113.236096) (xy 438.953865 -113.261481)
			(xy 439.0014 -113.294421) (xy 439.043416 -113.33416) (xy 439.061606 -113.356644) (xy 439.069213 -113.365451)
			(xy 439.090114 -113.375633) (xy 439.101738 -113.376202) (xy 439.181494 -113.376202) (xy 439.193124 -113.375645)
			(xy 439.214033 -113.365469) (xy 439.221626 -113.356644) (xy 439.239813 -113.334157) (xy 439.281833 -113.29442)
			(xy 439.329368 -113.26148) (xy 439.38133 -113.236092) (xy 439.436529 -113.218837) (xy 439.4937 -113.210111)
			(xy 439.522616 -113.209578) (xy 439.549867 -113.210063) (xy 439.603814 -113.217821) (xy 439.656108 -113.233178)
			(xy 439.705684 -113.25582) (xy 439.751534 -113.285286) (xy 439.792724 -113.320978) (xy 439.828415 -113.362168)
			(xy 439.857881 -113.408017) (xy 439.880523 -113.457594) (xy 439.895879 -113.509888) (xy 439.903637 -113.563835)
			(xy 439.904124 -113.591086) (xy 439.903696 -113.618491) (xy 439.895842 -113.672735) (xy 439.880307 -113.725297)
			(xy 439.857412 -113.775095) (xy 439.827627 -113.821106) (xy 439.791566 -113.862381) (xy 439.74997 -113.898072)
			(xy 439.727086 -113.913158) (xy 439.718067 -113.919608) (xy 439.706213 -113.938317) (xy 439.704226 -113.949226)
			(xy 439.692034 -114.037364) (xy 439.698638 -114.0587) (xy 439.706258 -114.067082) (xy 439.724546 -114.088672)
			(xy 439.73208 -114.097462) (xy 439.75286 -114.107627) (xy 439.764424 -114.10823) (xy 439.844434 -114.10823)
			(xy 439.85607 -114.107721) (xy 439.876981 -114.097513) (xy 439.884566 -114.088672) (xy 439.902769 -114.066199)
			(xy 439.944787 -114.026464) (xy 439.99232 -113.993525) (xy 440.044279 -113.968135) (xy 440.099474 -113.950876)
			(xy 440.156641 -113.942143) (xy 440.185556 -113.941606) (xy 440.212801 -113.942054) (xy 440.266735 -113.949818)
			(xy 440.319015 -113.965181) (xy 440.368575 -113.987829) (xy 440.414407 -114.017302) (xy 440.455577 -114.052998)
			(xy 440.491247 -114.094191) (xy 440.506358 -114.116866) (xy 440.511237 -114.123866) (xy 440.524631 -114.134416)
			(xy 440.540757 -114.139953) (xy 440.549284 -114.140234) (xy 440.634628 -114.140234) (xy 440.643147 -114.139903)
			(xy 440.659256 -114.134357) (xy 440.672667 -114.123851) (xy 440.677554 -114.116866) (xy 440.69264 -114.094173)
			(xy 440.728311 -114.052978) (xy 440.769484 -114.017282) (xy 440.815321 -113.987813) (xy 440.864886 -113.965171)
			(xy 440.917171 -113.949817) (xy 440.97111 -113.942066) (xy 440.998356 -113.941606) (xy 441.029136 -113.942225)
			(xy 441.089898 -113.952109) (xy 441.148283 -113.971626) (xy 441.202774 -114.000271) (xy 441.227718 -114.018314)
			(xy 441.237624 -114.02568) (xy 441.262008 -114.029744) (xy 441.365132 -113.995962) (xy 441.382404 -113.978182)
			(xy 441.38596 -113.966244) (xy 441.393711 -113.941881) (xy 441.414807 -113.89531) (xy 441.441935 -113.851975)
			(xy 441.474609 -113.812653) (xy 441.493148 -113.795048) (xy 441.500567 -113.787541) (xy 441.509083 -113.76825)
			(xy 441.509658 -113.75771) (xy 441.509658 -113.683034) (xy 441.509136 -113.672483) (xy 441.500597 -113.653187)
			(xy 441.493148 -113.645696) (xy 441.474088 -113.627546) (xy 441.440633 -113.586914) (xy 441.413076 -113.542072)
			(xy 441.391939 -113.49387) (xy 441.377622 -113.443222) (xy 441.370397 -113.391088) (xy 441.369958 -113.364772)
			(xy 441.370444 -113.337521) (xy 441.3782 -113.283573) (xy 441.393555 -113.231278) (xy 441.416197 -113.181701)
			(xy 441.445663 -113.135851) (xy 441.481354 -113.09466) (xy 441.522545 -113.058969) (xy 441.568395 -113.029503)
			(xy 441.617972 -113.006861) (xy 441.670267 -112.991506) (xy 441.724215 -112.98375) (xy 441.778717 -112.98375)
			(xy 441.832665 -112.991506) (xy 441.88496 -113.006861) (xy 441.934537 -113.029503) (xy 441.980387 -113.058969)
			(xy 442.021578 -113.09466) (xy 442.057269 -113.135851) (xy 442.086735 -113.181701) (xy 442.109377 -113.231278)
			(xy 442.124732 -113.283573) (xy 442.132488 -113.337521) (xy 442.132974 -113.364772) (xy 442.132563 -113.391088)
			(xy 442.125318 -113.443219) (xy 442.110988 -113.493863) (xy 442.089845 -113.542062) (xy 442.062289 -113.586904)
			(xy 442.02884 -113.627541) (xy 442.009784 -113.645696) (xy 442.00238 -113.653215) (xy 441.993857 -113.672497)
			(xy 441.993274 -113.683034) (xy 441.993274 -113.75771) (xy 441.993792 -113.768261) (xy 442.002336 -113.787556)
			(xy 442.009784 -113.795048) (xy 442.028853 -113.81319) (xy 442.062309 -113.853823) (xy 442.089867 -113.898665)
			(xy 442.111003 -113.946869) (xy 442.125317 -113.997519) (xy 442.132538 -114.049655) (xy 442.132974 -114.075972)
			(xy 443.401958 -114.075972) (xy 443.402388 -114.049657) (xy 443.409628 -113.997526) (xy 443.423953 -113.946882)
			(xy 443.445093 -113.898682) (xy 443.472646 -113.85384) (xy 443.506093 -113.813203) (xy 443.525148 -113.795048)
			(xy 443.532567 -113.787541) (xy 443.541083 -113.76825) (xy 443.541658 -113.75771) (xy 443.541658 -113.683034)
			(xy 443.541136 -113.672483) (xy 443.532597 -113.653187) (xy 443.525148 -113.645696) (xy 443.506088 -113.627546)
			(xy 443.472633 -113.586914) (xy 443.445076 -113.542072) (xy 443.423939 -113.49387) (xy 443.409622 -113.443222)
			(xy 443.402397 -113.391088) (xy 443.401958 -113.364772) (xy 443.402444 -113.337521) (xy 443.4102 -113.283573)
			(xy 443.425555 -113.231278) (xy 443.448197 -113.181701) (xy 443.477663 -113.135851) (xy 443.513354 -113.09466)
			(xy 443.554545 -113.058969) (xy 443.600395 -113.029503) (xy 443.649972 -113.006861) (xy 443.702267 -112.991506)
			(xy 443.756215 -112.98375) (xy 443.810717 -112.98375) (xy 443.864665 -112.991506) (xy 443.91696 -113.006861)
			(xy 443.966537 -113.029503) (xy 444.012387 -113.058969) (xy 444.053578 -113.09466) (xy 444.089269 -113.135851)
			(xy 444.118735 -113.181701) (xy 444.141377 -113.231278) (xy 444.156732 -113.283573) (xy 444.164488 -113.337521)
			(xy 444.164974 -113.364772) (xy 444.164563 -113.391088) (xy 444.157318 -113.443219) (xy 444.142988 -113.493863)
			(xy 444.121845 -113.542062) (xy 444.105455 -113.568734) (xy 459.189834 -113.568734) (xy 459.193905 -113.513112)
			(xy 459.206031 -113.458675) (xy 459.225954 -113.406584) (xy 459.25325 -113.357949) (xy 459.287336 -113.313806)
			(xy 459.327485 -113.275097) (xy 459.372843 -113.242646) (xy 459.422443 -113.217145) (xy 459.475227 -113.199138)
			(xy 459.53007 -113.189008) (xy 459.585804 -113.186971) (xy 459.641241 -113.193071) (xy 459.695198 -113.207177)
			(xy 459.746527 -113.228989) (xy 459.794133 -113.258043) (xy 459.837001 -113.293718) (xy 459.874218 -113.335255)
			(xy 459.904991 -113.381768) (xy 459.928663 -113.432265) (xy 459.944731 -113.485672) (xy 459.952851 -113.540848)
			(xy 459.953267 -113.563654) (xy 461.247488 -113.563654) (xy 461.251559 -113.508032) (xy 461.263685 -113.453595)
			(xy 461.283608 -113.401504) (xy 461.310904 -113.352869) (xy 461.34499 -113.308726) (xy 461.385139 -113.270017)
			(xy 461.430497 -113.237566) (xy 461.480097 -113.212065) (xy 461.532881 -113.194058) (xy 461.587724 -113.183928)
			(xy 461.643458 -113.181891) (xy 461.698895 -113.187991) (xy 461.752852 -113.202097) (xy 461.804181 -113.223909)
			(xy 461.851787 -113.252963) (xy 461.894655 -113.288638) (xy 461.931872 -113.330175) (xy 461.962645 -113.376688)
			(xy 461.986317 -113.427185) (xy 462.002385 -113.480592) (xy 462.010505 -113.535768) (xy 462.011014 -113.563654)
			(xy 462.010505 -113.59154) (xy 462.002385 -113.646716) (xy 461.986317 -113.700123) (xy 461.962645 -113.75062)
			(xy 461.931872 -113.797133) (xy 461.894655 -113.83867) (xy 461.851787 -113.874345) (xy 461.804181 -113.903399)
			(xy 461.752852 -113.925211) (xy 461.698895 -113.939317) (xy 461.643458 -113.945417) (xy 461.587724 -113.94338)
			(xy 461.532881 -113.93325) (xy 461.480097 -113.915243) (xy 461.430497 -113.889742) (xy 461.385139 -113.857291)
			(xy 461.34499 -113.818582) (xy 461.310904 -113.774439) (xy 461.283608 -113.725804) (xy 461.263685 -113.673713)
			(xy 461.251559 -113.619276) (xy 461.247488 -113.563654) (xy 459.953267 -113.563654) (xy 459.95336 -113.568734)
			(xy 459.952851 -113.59662) (xy 459.944731 -113.651796) (xy 459.928663 -113.705203) (xy 459.904991 -113.7557)
			(xy 459.874218 -113.802213) (xy 459.837001 -113.84375) (xy 459.794133 -113.879425) (xy 459.746527 -113.908479)
			(xy 459.695198 -113.930291) (xy 459.641241 -113.944397) (xy 459.585804 -113.950497) (xy 459.53007 -113.94846)
			(xy 459.475227 -113.93833) (xy 459.422443 -113.920323) (xy 459.372843 -113.894822) (xy 459.327485 -113.862371)
			(xy 459.287336 -113.823662) (xy 459.25325 -113.779519) (xy 459.225954 -113.730884) (xy 459.206031 -113.678793)
			(xy 459.193905 -113.624356) (xy 459.189834 -113.568734) (xy 444.105455 -113.568734) (xy 444.094289 -113.586904)
			(xy 444.06084 -113.627541) (xy 444.041784 -113.645696) (xy 444.03438 -113.653215) (xy 444.025857 -113.672497)
			(xy 444.025274 -113.683034) (xy 444.025274 -113.75771) (xy 444.025792 -113.768261) (xy 444.034336 -113.787556)
			(xy 444.041784 -113.795048) (xy 444.060853 -113.81319) (xy 444.094309 -113.853823) (xy 444.121867 -113.898665)
			(xy 444.143003 -113.946869) (xy 444.157317 -113.997519) (xy 444.164538 -114.049655) (xy 444.164974 -114.075972)
			(xy 444.164488 -114.103223) (xy 444.156732 -114.157171) (xy 444.141377 -114.209466) (xy 444.118735 -114.259043)
			(xy 444.089269 -114.304893) (xy 444.053578 -114.346084) (xy 444.012387 -114.381775) (xy 443.966537 -114.411241)
			(xy 443.91696 -114.433883) (xy 443.864665 -114.449238) (xy 443.810717 -114.456994) (xy 443.756215 -114.456994)
			(xy 443.702267 -114.449238) (xy 443.649972 -114.433883) (xy 443.600395 -114.411241) (xy 443.554545 -114.381775)
			(xy 443.513354 -114.346084) (xy 443.477663 -114.304893) (xy 443.448197 -114.259043) (xy 443.425555 -114.209466)
			(xy 443.4102 -114.157171) (xy 443.402444 -114.103223) (xy 443.401958 -114.075972) (xy 442.132974 -114.075972)
			(xy 442.132519 -114.103226) (xy 442.124764 -114.157179) (xy 442.10941 -114.209479) (xy 442.086769 -114.259061)
			(xy 442.0573 -114.304916) (xy 442.021606 -114.34611) (xy 441.980411 -114.381804) (xy 441.934556 -114.411271)
			(xy 441.884973 -114.433912) (xy 441.832673 -114.449266) (xy 441.77872 -114.457019) (xy 441.751466 -114.45748)
			(xy 441.720684 -114.456904) (xy 441.65992 -114.447008) (xy 441.601535 -114.427478) (xy 441.547047 -114.398821)
			(xy 441.522104 -114.380772) (xy 441.512198 -114.373406) (xy 441.487814 -114.369342) (xy 441.38469 -114.403124)
			(xy 441.367418 -114.420904) (xy 441.363862 -114.432842) (xy 441.355607 -114.458687) (xy 441.332789 -114.507909)
			(xy 441.303231 -114.553404) (xy 441.267527 -114.594254) (xy 441.226397 -114.629635) (xy 441.180671 -114.658835)
			(xy 441.13127 -114.681264) (xy 441.079191 -114.696471) (xy 441.025483 -114.704149) (xy 440.998356 -114.704622)
			(xy 440.971112 -114.704152) (xy 440.917179 -114.69639) (xy 440.864901 -114.68103) (xy 440.815341 -114.658385)
			(xy 440.769508 -114.628917) (xy 440.728338 -114.593224) (xy 440.692666 -114.552035) (xy 440.677554 -114.529362)
			(xy 440.672719 -114.522327) (xy 440.659306 -114.511782) (xy 440.643161 -114.506262) (xy 440.634628 -114.505994)
			(xy 440.549284 -114.505994) (xy 440.540764 -114.506321) (xy 440.524654 -114.511867) (xy 440.511244 -114.522376)
			(xy 440.506358 -114.529362) (xy 440.491273 -114.552055) (xy 440.455601 -114.593249) (xy 440.414427 -114.628944)
			(xy 440.368591 -114.658413) (xy 440.319025 -114.681055) (xy 440.26674 -114.696409) (xy 440.212802 -114.704162)
			(xy 440.185556 -114.704622) (xy 440.156639 -114.704093) (xy 440.099467 -114.69537) (xy 440.044267 -114.678116)
			(xy 439.992305 -114.652727) (xy 439.944771 -114.619784) (xy 439.902755 -114.580042) (xy 439.884566 -114.557556)
			(xy 439.876971 -114.548736) (xy 439.856061 -114.538561) (xy 439.844434 -114.537998) (xy 439.764678 -114.537998)
			(xy 439.753046 -114.53854) (xy 439.732137 -114.548727) (xy 439.724546 -114.557556) (xy 439.706318 -114.580008)
			(xy 439.664307 -114.619747) (xy 439.61678 -114.652691) (xy 439.564826 -114.678086) (xy 439.509635 -114.695348)
			(xy 439.45247 -114.704084) (xy 439.423556 -114.704622) (xy 439.396304 -114.704163) (xy 439.342356 -114.696401)
			(xy 439.290062 -114.681041) (xy 439.240486 -114.658396) (xy 439.194636 -114.628926) (xy 439.153447 -114.593232)
			(xy 439.117756 -114.55204) (xy 439.08829 -114.506188) (xy 439.065648 -114.45661) (xy 439.050293 -114.404314)
			(xy 439.042535 -114.350366) (xy 439.042048 -114.323114) (xy 439.042489 -114.29571) (xy 439.050342 -114.241467)
			(xy 439.065876 -114.188906) (xy 439.088769 -114.139108) (xy 439.118552 -114.093098) (xy 439.154611 -114.051822)
			(xy 439.196204 -114.016129) (xy 439.219086 -114.001042) (xy 439.228118 -113.994609) (xy 439.239962 -113.975886)
			(xy 439.241946 -113.964974) (xy 439.254138 -113.876836) (xy 439.247534 -113.8555) (xy 439.239914 -113.847118)
			(xy 439.221626 -113.825528) (xy 439.214061 -113.81677) (xy 439.193304 -113.806588) (xy 439.181748 -113.80597)
			(xy 439.101738 -113.80597) (xy 439.0901 -113.806463) (xy 439.069189 -113.816682) (xy 439.061606 -113.825528)
			(xy 439.043419 -113.848014) (xy 439.001397 -113.887748) (xy 438.953861 -113.920686) (xy 438.9019 -113.946074)
			(xy 438.846702 -113.96333) (xy 438.789532 -113.972059) (xy 438.760616 -113.972594) (xy 438.760362 -113.972594)
			(xy 438.730925 -113.97203) (xy 438.672752 -113.962975) (xy 438.644538 -113.95456) (xy 438.6326 -113.95075)
			(xy 438.608724 -113.95456) (xy 438.532524 -114.010948) (xy 438.523238 -114.018675) (xy 438.512503 -114.040282)
			(xy 438.51195 -114.05235) (xy 438.51195 -114.05743) (xy 438.511413 -114.084681) (xy 438.503652 -114.138627)
			(xy 438.488293 -114.19092) (xy 438.465648 -114.240495) (xy 438.436178 -114.286342) (xy 438.400484 -114.327529)
			(xy 438.359291 -114.363217) (xy 438.313439 -114.392679) (xy 438.26386 -114.415315) (xy 438.211565 -114.430665)
			(xy 438.157617 -114.438417) (xy 438.103115 -114.438412) (xy 438.049169 -114.430651) (xy 437.996876 -114.415291)
			(xy 437.947302 -114.392646) (xy 437.901455 -114.363176) (xy 437.860268 -114.327481) (xy 437.824581 -114.286288)
			(xy 437.79512 -114.240435) (xy 437.772483 -114.190856) (xy 437.757134 -114.138561) (xy 437.749383 -114.084613)
			(xy 434.08211 -114.084613) (xy 434.103362 -114.094328) (xy 434.14924 -114.123843) (xy 434.190446 -114.159592)
			(xy 434.226139 -114.200846) (xy 434.255594 -114.246763) (xy 434.278207 -114.296407) (xy 434.293519 -114.348765)
			(xy 434.301217 -114.402771) (xy 434.301646 -114.430048) (xy 434.301646 -114.430302) (xy 434.305456 -114.449352)
			(xy 434.309266 -114.459004) (xy 434.367432 -114.51717) (xy 434.368194 -114.517932) (xy 434.369464 -114.519202)
			(xy 434.376675 -114.525012) (xy 434.393994 -114.53153) (xy 434.403246 -114.531902) (xy 436.224426 -114.531902)
			(xy 436.234494 -114.53233) (xy 436.253091 -114.540051) (xy 436.260494 -114.546888) (xy 437.083962 -115.370356)
			(xy 437.661302 -115.370356) (xy 437.665373 -115.314734) (xy 437.677499 -115.260297) (xy 437.697422 -115.208206)
			(xy 437.724718 -115.159571) (xy 437.758804 -115.115428) (xy 437.798953 -115.076719) (xy 437.844311 -115.044268)
			(xy 437.893911 -115.018767) (xy 437.946695 -115.00076) (xy 438.001538 -114.99063) (xy 438.057272 -114.988593)
			(xy 438.112709 -114.994693) (xy 438.166666 -115.008799) (xy 438.217995 -115.030611) (xy 438.265601 -115.059665)
			(xy 438.308469 -115.09534) (xy 438.345686 -115.136877) (xy 438.376459 -115.18339) (xy 438.400131 -115.233887)
			(xy 438.416199 -115.287294) (xy 438.424319 -115.34247) (xy 438.424828 -115.370356) (xy 438.424319 -115.398242)
			(xy 438.416199 -115.453418) (xy 438.400131 -115.506825) (xy 438.376459 -115.557322) (xy 438.345686 -115.603835)
			(xy 438.308469 -115.645372) (xy 438.265601 -115.681047) (xy 438.217995 -115.710101) (xy 438.166666 -115.731913)
			(xy 438.112709 -115.746019) (xy 438.057272 -115.752119) (xy 438.001538 -115.750082) (xy 437.946695 -115.739952)
			(xy 437.893911 -115.721945) (xy 437.844311 -115.696444) (xy 437.798953 -115.663993) (xy 437.758804 -115.625284)
			(xy 437.724718 -115.581141) (xy 437.697422 -115.532506) (xy 437.677499 -115.480415) (xy 437.665373 -115.425978)
			(xy 437.661302 -115.370356) (xy 437.083962 -115.370356) (xy 437.546242 -115.832636) (xy 441.279788 -115.832636)
			(xy 441.280305 -115.80408) (xy 441.288801 -115.747602) (xy 441.305623 -115.693023) (xy 441.330395 -115.641563)
			(xy 441.362564 -115.594371) (xy 441.40141 -115.552504) (xy 441.446064 -115.516897) (xy 441.470542 -115.502182)
			(xy 441.483422 -115.494082) (xy 441.504093 -115.471776) (xy 441.517278 -115.444371) (xy 441.521806 -115.414299)
			(xy 441.517277 -115.384227) (xy 441.504092 -115.356823) (xy 441.483421 -115.334517) (xy 441.470542 -115.326414)
			(xy 441.446086 -115.311668) (xy 441.401448 -115.276053) (xy 441.362613 -115.234185) (xy 441.33045 -115.186999)
			(xy 441.305675 -115.135547) (xy 441.288842 -115.080979) (xy 441.280325 -115.024513) (xy 441.279788 -114.99596)
			(xy 441.280274 -114.968709) (xy 441.28803 -114.914761) (xy 441.303385 -114.862466) (xy 441.326027 -114.812889)
			(xy 441.355493 -114.767039) (xy 441.391184 -114.725848) (xy 441.432375 -114.690157) (xy 441.478225 -114.660691)
			(xy 441.527802 -114.638049) (xy 441.580097 -114.622694) (xy 441.634045 -114.614938) (xy 441.688547 -114.614938)
			(xy 441.742495 -114.622694) (xy 441.79479 -114.638049) (xy 441.844367 -114.660691) (xy 441.890217 -114.690157)
			(xy 441.931408 -114.725848) (xy 441.967099 -114.767039) (xy 441.996565 -114.812889) (xy 442.019207 -114.862466)
			(xy 442.034562 -114.914761) (xy 442.042318 -114.968709) (xy 442.042804 -114.99596) (xy 442.042288 -115.024517)
			(xy 442.033792 -115.080994) (xy 442.01697 -115.135573) (xy 441.992198 -115.187034) (xy 441.960029 -115.234225)
			(xy 441.921183 -115.276092) (xy 441.876528 -115.311699) (xy 441.85205 -115.326414) (xy 441.839164 -115.334513)
			(xy 441.818475 -115.356813) (xy 441.805278 -115.38422) (xy 441.803731 -115.394486) (xy 443.447168 -115.394486)
			(xy 443.451239 -115.338864) (xy 443.463365 -115.284427) (xy 443.483288 -115.232336) (xy 443.510584 -115.183701)
			(xy 443.54467 -115.139558) (xy 443.584819 -115.100849) (xy 443.630177 -115.068398) (xy 443.679777 -115.042897)
			(xy 443.732561 -115.02489) (xy 443.787404 -115.01476) (xy 443.843138 -115.012723) (xy 443.898575 -115.018823)
			(xy 443.909232 -115.021609) (xy 445.856196 -115.021609) (xy 445.86051 -114.964339) (xy 445.873356 -114.908361)
			(xy 445.894446 -114.854941) (xy 445.923301 -114.805283) (xy 445.959272 -114.760511) (xy 445.980058 -114.74069)
			(xy 445.98746 -114.733168) (xy 445.995985 -114.713889) (xy 445.996568 -114.703352) (xy 445.996568 -114.628676)
			(xy 445.996021 -114.618128) (xy 445.987499 -114.598832) (xy 445.980058 -114.591338) (xy 445.960971 -114.573214)
			(xy 445.927519 -114.532576) (xy 445.899965 -114.487729) (xy 445.878832 -114.439522) (xy 445.864521 -114.38887)
			(xy 445.857303 -114.336732) (xy 445.856868 -114.310414) (xy 445.857354 -114.283163) (xy 445.86511 -114.229215)
			(xy 445.880465 -114.17692) (xy 445.903107 -114.127343) (xy 445.932573 -114.081493) (xy 445.968264 -114.040302)
			(xy 446.009455 -114.004611) (xy 446.055305 -113.975145) (xy 446.104882 -113.952503) (xy 446.157177 -113.937148)
			(xy 446.211125 -113.929392) (xy 446.265627 -113.929392) (xy 446.319575 -113.937148) (xy 446.37187 -113.952503)
			(xy 446.421447 -113.975145) (xy 446.467297 -114.004611) (xy 446.508488 -114.040302) (xy 446.544179 -114.081493)
			(xy 446.573645 -114.127343) (xy 446.596287 -114.17692) (xy 446.611642 -114.229215) (xy 446.619398 -114.283163)
			(xy 446.619884 -114.310414) (xy 446.619431 -114.336729) (xy 446.612194 -114.388858) (xy 446.597872 -114.439501)
			(xy 446.576737 -114.4877) (xy 446.549188 -114.532543) (xy 446.515747 -114.573182) (xy 446.496694 -114.591338)
			(xy 446.489273 -114.598843) (xy 446.48076 -114.618136) (xy 446.480184 -114.628676) (xy 446.480184 -114.703352)
			(xy 446.48073 -114.7139) (xy 446.489254 -114.733195) (xy 446.496694 -114.74069) (xy 446.517497 -114.760495)
			(xy 446.553474 -114.805269) (xy 446.582335 -114.854929) (xy 446.603429 -114.908353) (xy 446.616278 -114.964334)
			(xy 446.620592 -115.021609) (xy 448.394411 -115.021609) (xy 448.398725 -114.964338) (xy 448.411572 -114.90836)
			(xy 448.432663 -114.854939) (xy 448.46152 -114.805282) (xy 448.497493 -114.76051) (xy 448.51828 -114.74069)
			(xy 448.525685 -114.733171) (xy 448.534208 -114.713889) (xy 448.53479 -114.703352) (xy 448.53479 -114.628676)
			(xy 448.534236 -114.618129) (xy 448.525719 -114.598833) (xy 448.51828 -114.591338) (xy 448.499198 -114.57321)
			(xy 448.465744 -114.532574) (xy 448.438189 -114.487727) (xy 448.417055 -114.439521) (xy 448.402743 -114.388869)
			(xy 448.395525 -114.336732) (xy 448.39509 -114.310414) (xy 448.395576 -114.283163) (xy 448.403332 -114.229215)
			(xy 448.418687 -114.17692) (xy 448.441329 -114.127343) (xy 448.470795 -114.081493) (xy 448.506486 -114.040302)
			(xy 448.547677 -114.004611) (xy 448.593527 -113.975145) (xy 448.643104 -113.952503) (xy 448.695399 -113.937148)
			(xy 448.749347 -113.929392) (xy 448.803849 -113.929392) (xy 448.857797 -113.937148) (xy 448.910092 -113.952503)
			(xy 448.959669 -113.975145) (xy 449.005519 -114.004611) (xy 449.033059 -114.028474) (xy 453.305162 -114.028474)
			(xy 453.309233 -113.972852) (xy 453.321359 -113.918415) (xy 453.341282 -113.866324) (xy 453.368578 -113.817689)
			(xy 453.402664 -113.773546) (xy 453.442813 -113.734837) (xy 453.488171 -113.702386) (xy 453.537771 -113.676885)
			(xy 453.590555 -113.658878) (xy 453.645398 -113.648748) (xy 453.701132 -113.646711) (xy 453.756569 -113.652811)
			(xy 453.810526 -113.666917) (xy 453.861855 -113.688729) (xy 453.909461 -113.717783) (xy 453.952329 -113.753458)
			(xy 453.989546 -113.794995) (xy 454.020319 -113.841508) (xy 454.043991 -113.892005) (xy 454.060059 -113.945412)
			(xy 454.068179 -114.000588) (xy 454.068688 -114.028474) (xy 454.068179 -114.05636) (xy 454.060059 -114.111536)
			(xy 454.043991 -114.164943) (xy 454.020319 -114.21544) (xy 453.989546 -114.261953) (xy 453.952329 -114.30349)
			(xy 453.909461 -114.339165) (xy 453.861855 -114.368219) (xy 453.810526 -114.390031) (xy 453.756569 -114.404137)
			(xy 453.701132 -114.410237) (xy 453.645398 -114.4082) (xy 453.590555 -114.39807) (xy 453.537771 -114.380063)
			(xy 453.488171 -114.354562) (xy 453.442813 -114.322111) (xy 453.402664 -114.283402) (xy 453.368578 -114.239259)
			(xy 453.341282 -114.190624) (xy 453.321359 -114.138533) (xy 453.309233 -114.084096) (xy 453.305162 -114.028474)
			(xy 449.033059 -114.028474) (xy 449.04671 -114.040302) (xy 449.082401 -114.081493) (xy 449.111867 -114.127343)
			(xy 449.134509 -114.17692) (xy 449.149864 -114.229215) (xy 449.15762 -114.283163) (xy 449.158106 -114.310414)
			(xy 449.157646 -114.336728) (xy 449.150409 -114.388857) (xy 449.136089 -114.4395) (xy 449.114955 -114.487699)
			(xy 449.087408 -114.532542) (xy 449.053968 -114.573181) (xy 449.034916 -114.591338) (xy 449.027498 -114.598846)
			(xy 449.018982 -114.618136) (xy 449.018406 -114.628676) (xy 449.018406 -114.703352) (xy 449.018946 -114.713901)
			(xy 449.027473 -114.733196) (xy 449.034916 -114.74069) (xy 449.055718 -114.760496) (xy 449.091693 -114.80527)
			(xy 449.120553 -114.85493) (xy 449.141645 -114.908354) (xy 449.154493 -114.964335) (xy 449.158004 -115.010946)
			(xy 454.91984 -115.010946) (xy 454.923911 -114.955324) (xy 454.936037 -114.900887) (xy 454.95596 -114.848796)
			(xy 454.983256 -114.800161) (xy 455.017342 -114.756018) (xy 455.057491 -114.717309) (xy 455.102849 -114.684858)
			(xy 455.152449 -114.659357) (xy 455.205233 -114.64135) (xy 455.260076 -114.63122) (xy 455.31581 -114.629183)
			(xy 455.371247 -114.635283) (xy 455.425204 -114.649389) (xy 455.476533 -114.671201) (xy 455.524139 -114.700255)
			(xy 455.567007 -114.73593) (xy 455.604224 -114.777467) (xy 455.634997 -114.82398) (xy 455.658669 -114.874477)
			(xy 455.674737 -114.927884) (xy 455.682857 -114.98306) (xy 455.683366 -115.010946) (xy 455.682857 -115.038832)
			(xy 455.679933 -115.058698) (xy 456.28636 -115.058698) (xy 456.290431 -115.003076) (xy 456.302557 -114.948639)
			(xy 456.32248 -114.896548) (xy 456.349776 -114.847913) (xy 456.383862 -114.80377) (xy 456.424011 -114.765061)
			(xy 456.469369 -114.73261) (xy 456.518969 -114.707109) (xy 456.571753 -114.689102) (xy 456.626596 -114.678972)
			(xy 456.68233 -114.676935) (xy 456.737767 -114.683035) (xy 456.791724 -114.697141) (xy 456.843053 -114.718953)
			(xy 456.890659 -114.748007) (xy 456.933527 -114.783682) (xy 456.970744 -114.825219) (xy 457.001517 -114.871732)
			(xy 457.025189 -114.922229) (xy 457.041257 -114.975636) (xy 457.043426 -114.990372) (xy 457.665072 -114.990372)
			(xy 457.669143 -114.93475) (xy 457.681269 -114.880313) (xy 457.701192 -114.828222) (xy 457.728488 -114.779587)
			(xy 457.762574 -114.735444) (xy 457.802723 -114.696735) (xy 457.848081 -114.664284) (xy 457.897681 -114.638783)
			(xy 457.950465 -114.620776) (xy 458.005308 -114.610646) (xy 458.061042 -114.608609) (xy 458.116479 -114.614709)
			(xy 458.170436 -114.628815) (xy 458.221765 -114.650627) (xy 458.269371 -114.679681) (xy 458.312239 -114.715356)
			(xy 458.349456 -114.756893) (xy 458.380229 -114.803406) (xy 458.403901 -114.853903) (xy 458.419969 -114.90731)
			(xy 458.427819 -114.960654) (xy 459.191866 -114.960654) (xy 459.195937 -114.905032) (xy 459.208063 -114.850595)
			(xy 459.227986 -114.798504) (xy 459.255282 -114.749869) (xy 459.289368 -114.705726) (xy 459.329517 -114.667017)
			(xy 459.374875 -114.634566) (xy 459.424475 -114.609065) (xy 459.477259 -114.591058) (xy 459.532102 -114.580928)
			(xy 459.587836 -114.578891) (xy 459.643273 -114.584991) (xy 459.69723 -114.599097) (xy 459.748559 -114.620909)
			(xy 459.796165 -114.649963) (xy 459.839033 -114.685638) (xy 459.87625 -114.727175) (xy 459.907023 -114.773688)
			(xy 459.930695 -114.824185) (xy 459.946763 -114.877592) (xy 459.954883 -114.932768) (xy 459.955392 -114.960654)
			(xy 459.954883 -114.98854) (xy 459.946763 -115.043716) (xy 459.930695 -115.097123) (xy 459.907023 -115.14762)
			(xy 459.87625 -115.194133) (xy 459.839033 -115.23567) (xy 459.796165 -115.271345) (xy 459.748559 -115.300399)
			(xy 459.69723 -115.322211) (xy 459.643273 -115.336317) (xy 459.587836 -115.342417) (xy 459.532102 -115.34038)
			(xy 459.477259 -115.33025) (xy 459.424475 -115.312243) (xy 459.374875 -115.286742) (xy 459.329517 -115.254291)
			(xy 459.289368 -115.215582) (xy 459.255282 -115.171439) (xy 459.227986 -115.122804) (xy 459.208063 -115.070713)
			(xy 459.195937 -115.016276) (xy 459.191866 -114.960654) (xy 458.427819 -114.960654) (xy 458.428089 -114.962486)
			(xy 458.428598 -114.990372) (xy 458.428089 -115.018258) (xy 458.419969 -115.073434) (xy 458.403901 -115.126841)
			(xy 458.380229 -115.177338) (xy 458.349456 -115.223851) (xy 458.312239 -115.265388) (xy 458.269371 -115.301063)
			(xy 458.221765 -115.330117) (xy 458.170436 -115.351929) (xy 458.116479 -115.366035) (xy 458.061042 -115.372135)
			(xy 458.005308 -115.370098) (xy 457.950465 -115.359968) (xy 457.897681 -115.341961) (xy 457.848081 -115.31646)
			(xy 457.802723 -115.284009) (xy 457.762574 -115.2453) (xy 457.728488 -115.201157) (xy 457.701192 -115.152522)
			(xy 457.681269 -115.100431) (xy 457.669143 -115.045994) (xy 457.665072 -114.990372) (xy 457.043426 -114.990372)
			(xy 457.049377 -115.030812) (xy 457.049886 -115.058698) (xy 457.049377 -115.086584) (xy 457.041257 -115.14176)
			(xy 457.025189 -115.195167) (xy 457.001517 -115.245664) (xy 456.970744 -115.292177) (xy 456.933527 -115.333714)
			(xy 456.890659 -115.369389) (xy 456.843053 -115.398443) (xy 456.791724 -115.420255) (xy 456.737767 -115.434361)
			(xy 456.68233 -115.440461) (xy 456.626596 -115.438424) (xy 456.571753 -115.428294) (xy 456.518969 -115.410287)
			(xy 456.469369 -115.384786) (xy 456.424011 -115.352335) (xy 456.383862 -115.313626) (xy 456.349776 -115.269483)
			(xy 456.32248 -115.220848) (xy 456.302557 -115.168757) (xy 456.290431 -115.11432) (xy 456.28636 -115.058698)
			(xy 455.679933 -115.058698) (xy 455.674737 -115.094008) (xy 455.658669 -115.147415) (xy 455.634997 -115.197912)
			(xy 455.604224 -115.244425) (xy 455.567007 -115.285962) (xy 455.524139 -115.321637) (xy 455.476533 -115.350691)
			(xy 455.425204 -115.372503) (xy 455.371247 -115.386609) (xy 455.31581 -115.392709) (xy 455.260076 -115.390672)
			(xy 455.205233 -115.380542) (xy 455.152449 -115.362535) (xy 455.102849 -115.337034) (xy 455.057491 -115.304583)
			(xy 455.017342 -115.265874) (xy 454.983256 -115.221731) (xy 454.95596 -115.173096) (xy 454.936037 -115.121005)
			(xy 454.923911 -115.066568) (xy 454.91984 -115.010946) (xy 449.158004 -115.010946) (xy 449.158807 -115.021609)
			(xy 449.15449 -115.078884) (xy 449.141639 -115.134864) (xy 449.120544 -115.188287) (xy 449.091682 -115.237945)
			(xy 449.055705 -115.282718) (xy 449.034916 -115.302538) (xy 449.027498 -115.310046) (xy 449.018982 -115.329336)
			(xy 449.018406 -115.339876) (xy 449.018406 -115.414552) (xy 449.018946 -115.425101) (xy 449.027473 -115.444396)
			(xy 449.034916 -115.45189) (xy 449.053963 -115.470054) (xy 449.08742 -115.510683) (xy 449.11498 -115.555521)
			(xy 449.125675 -115.579906) (xy 453.443084 -115.579906) (xy 453.447155 -115.524284) (xy 453.459281 -115.469847)
			(xy 453.479204 -115.417756) (xy 453.5065 -115.369121) (xy 453.540586 -115.324978) (xy 453.580735 -115.286269)
			(xy 453.626093 -115.253818) (xy 453.675693 -115.228317) (xy 453.728477 -115.21031) (xy 453.78332 -115.20018)
			(xy 453.839054 -115.198143) (xy 453.894491 -115.204243) (xy 453.948448 -115.218349) (xy 453.999777 -115.240161)
			(xy 454.047383 -115.269215) (xy 454.090251 -115.30489) (xy 454.127468 -115.346427) (xy 454.158241 -115.39294)
			(xy 454.181913 -115.443437) (xy 454.197981 -115.496844) (xy 454.206101 -115.55202) (xy 454.20661 -115.579906)
			(xy 454.206101 -115.607792) (xy 454.197981 -115.662968) (xy 454.181913 -115.716375) (xy 454.158241 -115.766872)
			(xy 454.127468 -115.813385) (xy 454.090251 -115.854922) (xy 454.047383 -115.890597) (xy 453.999777 -115.919651)
			(xy 453.948448 -115.941463) (xy 453.894491 -115.955569) (xy 453.839054 -115.961669) (xy 453.78332 -115.959632)
			(xy 453.728477 -115.949502) (xy 453.675693 -115.931495) (xy 453.626093 -115.905994) (xy 453.580735 -115.873543)
			(xy 453.540586 -115.834834) (xy 453.5065 -115.790691) (xy 453.479204 -115.742056) (xy 453.459281 -115.689965)
			(xy 453.447155 -115.635528) (xy 453.443084 -115.579906) (xy 449.125675 -115.579906) (xy 449.13612 -115.60372)
			(xy 449.150439 -115.654366) (xy 449.157666 -115.706498) (xy 449.158106 -115.732814) (xy 449.15762 -115.760065)
			(xy 449.149864 -115.814013) (xy 449.134509 -115.866308) (xy 449.111867 -115.915885) (xy 449.082401 -115.961735)
			(xy 449.04671 -116.002926) (xy 449.005519 -116.038617) (xy 448.959669 -116.068083) (xy 448.910092 -116.090725)
			(xy 448.857797 -116.10608) (xy 448.803849 -116.113836) (xy 448.749347 -116.113836) (xy 448.695399 -116.10608)
			(xy 448.643104 -116.090725) (xy 448.593527 -116.068083) (xy 448.547677 -116.038617) (xy 448.506486 -116.002926)
			(xy 448.470795 -115.961735) (xy 448.441329 -115.915885) (xy 448.418687 -115.866308) (xy 448.403332 -115.814013)
			(xy 448.395576 -115.760065) (xy 448.39509 -115.732814) (xy 448.39557 -115.706501) (xy 448.402803 -115.654373)
			(xy 448.41712 -115.60373) (xy 448.43825 -115.555531) (xy 448.465793 -115.510688) (xy 448.49923 -115.470047)
			(xy 448.51828 -115.45189) (xy 448.525685 -115.444371) (xy 448.534208 -115.425089) (xy 448.53479 -115.414552)
			(xy 448.53479 -115.339876) (xy 448.534236 -115.329329) (xy 448.525719 -115.310033) (xy 448.51828 -115.302538)
			(xy 448.497506 -115.282704) (xy 448.461531 -115.237933) (xy 448.432671 -115.188278) (xy 448.411578 -115.134858)
			(xy 448.398728 -115.07888) (xy 448.394411 -115.021609) (xy 446.620592 -115.021609) (xy 446.616275 -115.078884)
			(xy 446.603423 -115.134865) (xy 446.582327 -115.188288) (xy 446.553463 -115.237947) (xy 446.517484 -115.282719)
			(xy 446.496694 -115.302538) (xy 446.489273 -115.310043) (xy 446.48076 -115.329336) (xy 446.480184 -115.339876)
			(xy 446.480184 -115.414552) (xy 446.48073 -115.4251) (xy 446.489254 -115.444395) (xy 446.496694 -115.45189)
			(xy 446.515737 -115.470059) (xy 446.549195 -115.510685) (xy 446.576756 -115.555523) (xy 446.597897 -115.603721)
			(xy 446.612217 -115.654366) (xy 446.619444 -115.706499) (xy 446.619884 -115.732814) (xy 446.619398 -115.760065)
			(xy 446.611642 -115.814013) (xy 446.596287 -115.866308) (xy 446.573645 -115.915885) (xy 446.544179 -115.961735)
			(xy 446.508488 -116.002926) (xy 446.467297 -116.038617) (xy 446.421447 -116.068083) (xy 446.37187 -116.090725)
			(xy 446.319575 -116.10608) (xy 446.265627 -116.113836) (xy 446.211125 -116.113836) (xy 446.157177 -116.10608)
			(xy 446.104882 -116.090725) (xy 446.055305 -116.068083) (xy 446.009455 -116.038617) (xy 445.968264 -116.002926)
			(xy 445.932573 -115.961735) (xy 445.903107 -115.915885) (xy 445.880465 -115.866308) (xy 445.86511 -115.814013)
			(xy 445.857354 -115.760065) (xy 445.856868 -115.732814) (xy 445.857355 -115.706501) (xy 445.864587 -115.654374)
			(xy 445.878903 -115.603732) (xy 445.900032 -115.555533) (xy 445.927574 -115.510689) (xy 445.961009 -115.470048)
			(xy 445.980058 -115.45189) (xy 445.98746 -115.444368) (xy 445.995985 -115.425089) (xy 445.996568 -115.414552)
			(xy 445.996568 -115.339876) (xy 445.996021 -115.329328) (xy 445.987499 -115.310032) (xy 445.980058 -115.302538)
			(xy 445.959285 -115.282703) (xy 445.923312 -115.237932) (xy 445.894454 -115.188276) (xy 445.873362 -115.134857)
			(xy 445.860513 -115.07888) (xy 445.856196 -115.021609) (xy 443.909232 -115.021609) (xy 443.952532 -115.032929)
			(xy 444.003861 -115.054741) (xy 444.051467 -115.083795) (xy 444.094335 -115.11947) (xy 444.131552 -115.161007)
			(xy 444.162325 -115.20752) (xy 444.185997 -115.258017) (xy 444.202065 -115.311424) (xy 444.210185 -115.3666)
			(xy 444.210694 -115.394486) (xy 444.210185 -115.422372) (xy 444.202065 -115.477548) (xy 444.185997 -115.530955)
			(xy 444.162325 -115.581452) (xy 444.131552 -115.627965) (xy 444.094335 -115.669502) (xy 444.051467 -115.705177)
			(xy 444.003861 -115.734231) (xy 443.952532 -115.756043) (xy 443.898575 -115.770149) (xy 443.843138 -115.776249)
			(xy 443.787404 -115.774212) (xy 443.732561 -115.764082) (xy 443.679777 -115.746075) (xy 443.630177 -115.720574)
			(xy 443.584819 -115.688123) (xy 443.54467 -115.649414) (xy 443.510584 -115.605271) (xy 443.483288 -115.556636)
			(xy 443.463365 -115.504545) (xy 443.451239 -115.450108) (xy 443.447168 -115.394486) (xy 441.803731 -115.394486)
			(xy 441.800744 -115.414299) (xy 441.805277 -115.444378) (xy 441.818474 -115.471785) (xy 441.839162 -115.494085)
			(xy 441.85205 -115.502182) (xy 441.876503 -115.516934) (xy 441.921141 -115.552548) (xy 441.959976 -115.594415)
			(xy 441.99214 -115.6416) (xy 442.016915 -115.69305) (xy 442.033749 -115.747617) (xy 442.042266 -115.804084)
			(xy 442.042804 -115.832636) (xy 442.042318 -115.859887) (xy 442.034562 -115.913835) (xy 442.019207 -115.96613)
			(xy 441.996565 -116.015707) (xy 441.967099 -116.061557) (xy 441.931408 -116.102748) (xy 441.890217 -116.138439)
			(xy 441.844367 -116.167905) (xy 441.79479 -116.190547) (xy 441.742495 -116.205902) (xy 441.688547 -116.213658)
			(xy 441.634045 -116.213658) (xy 441.580097 -116.205902) (xy 441.527802 -116.190547) (xy 441.478225 -116.167905)
			(xy 441.432375 -116.138439) (xy 441.391184 -116.102748) (xy 441.355493 -116.061557) (xy 441.326027 -116.015707)
			(xy 441.303385 -115.96613) (xy 441.28803 -115.913835) (xy 441.280274 -115.859887) (xy 441.279788 -115.832636)
			(xy 437.546242 -115.832636) (xy 437.996076 -116.28247) (xy 438.016904 -116.29009) (xy 438.027826 -116.289328)
			(xy 438.055258 -116.288312) (xy 438.082512 -116.288772) (xy 438.136467 -116.296525) (xy 438.188768 -116.311877)
			(xy 438.238353 -116.334518) (xy 438.28421 -116.363985) (xy 438.325406 -116.399679) (xy 438.334771 -116.410486)
			(xy 443.447168 -116.410486) (xy 443.451239 -116.354864) (xy 443.463365 -116.300427) (xy 443.483288 -116.248336)
			(xy 443.510584 -116.199701) (xy 443.54467 -116.155558) (xy 443.584819 -116.116849) (xy 443.630177 -116.084398)
			(xy 443.679777 -116.058897) (xy 443.732561 -116.04089) (xy 443.787404 -116.03076) (xy 443.843138 -116.028723)
			(xy 443.898575 -116.034823) (xy 443.952532 -116.048929) (xy 444.003861 -116.070741) (xy 444.051467 -116.099795)
			(xy 444.094335 -116.13547) (xy 444.131552 -116.177007) (xy 444.162325 -116.22352) (xy 444.185997 -116.274017)
			(xy 444.202065 -116.327424) (xy 444.210185 -116.3826) (xy 444.210694 -116.410486) (xy 444.210185 -116.438372)
			(xy 444.202065 -116.493548) (xy 444.185997 -116.546955) (xy 444.162325 -116.597452) (xy 444.141334 -116.62918)
			(xy 453.438004 -116.62918) (xy 453.442075 -116.573558) (xy 453.454201 -116.519121) (xy 453.474124 -116.46703)
			(xy 453.50142 -116.418395) (xy 453.535506 -116.374252) (xy 453.575655 -116.335543) (xy 453.621013 -116.303092)
			(xy 453.670613 -116.277591) (xy 453.723397 -116.259584) (xy 453.77824 -116.249454) (xy 453.833974 -116.247417)
			(xy 453.889411 -116.253517) (xy 453.943368 -116.267623) (xy 453.994697 -116.289435) (xy 454.042303 -116.318489)
			(xy 454.085171 -116.354164) (xy 454.122388 -116.395701) (xy 454.153161 -116.442214) (xy 454.176833 -116.492711)
			(xy 454.192901 -116.546118) (xy 454.201021 -116.601294) (xy 454.20153 -116.62918) (xy 454.201021 -116.657066)
			(xy 454.192901 -116.712242) (xy 454.176833 -116.765649) (xy 454.153161 -116.816146) (xy 454.122388 -116.862659)
			(xy 454.085171 -116.904196) (xy 454.042303 -116.939871) (xy 453.994697 -116.968925) (xy 453.943368 -116.990737)
			(xy 453.889411 -117.004843) (xy 453.833974 -117.010943) (xy 453.77824 -117.008906) (xy 453.723397 -116.998776)
			(xy 453.670613 -116.980769) (xy 453.621013 -116.955268) (xy 453.575655 -116.922817) (xy 453.535506 -116.884108)
			(xy 453.50142 -116.839965) (xy 453.474124 -116.79133) (xy 453.454201 -116.739239) (xy 453.442075 -116.684802)
			(xy 453.438004 -116.62918) (xy 444.141334 -116.62918) (xy 444.131552 -116.643965) (xy 444.094335 -116.685502)
			(xy 444.051467 -116.721177) (xy 444.003861 -116.750231) (xy 443.952532 -116.772043) (xy 443.898575 -116.786149)
			(xy 443.843138 -116.792249) (xy 443.787404 -116.790212) (xy 443.732561 -116.780082) (xy 443.679777 -116.762075)
			(xy 443.630177 -116.736574) (xy 443.584819 -116.704123) (xy 443.54467 -116.665414) (xy 443.510584 -116.621271)
			(xy 443.483288 -116.572636) (xy 443.463365 -116.520545) (xy 443.451239 -116.466108) (xy 443.447168 -116.410486)
			(xy 438.334771 -116.410486) (xy 438.361102 -116.440873) (xy 438.390572 -116.486728) (xy 438.413215 -116.536311)
			(xy 438.428571 -116.588612) (xy 438.436326 -116.642566) (xy 438.436766 -116.66982) (xy 438.43575 -116.697252)
			(xy 438.434988 -116.708174) (xy 438.442608 -116.729002) (xy 438.849516 -117.13591) (xy 438.85637 -117.143305)
			(xy 438.864114 -117.161904) (xy 438.864502 -117.171978) (xy 438.864502 -117.390446) (xy 439.042618 -117.390446)
			(xy 439.042618 -117.335954) (xy 439.050373 -117.282015) (xy 439.065724 -117.22973) (xy 439.088359 -117.180161)
			(xy 439.117818 -117.134317) (xy 439.153501 -117.093133) (xy 439.194682 -117.057445) (xy 439.240522 -117.027981)
			(xy 439.290089 -117.005339) (xy 439.342372 -116.989982) (xy 439.39631 -116.982221) (xy 439.423556 -116.981732)
			(xy 439.452472 -116.98227) (xy 439.509643 -116.990993) (xy 439.564842 -117.008246) (xy 439.616804 -117.033634)
			(xy 439.664339 -117.066575) (xy 439.706356 -117.106314) (xy 439.724546 -117.128798) (xy 439.732143 -117.137616)
			(xy 439.753051 -117.147794) (xy 439.764678 -117.148356) (xy 439.844434 -117.148356) (xy 439.856069 -117.147838)
			(xy 439.876979 -117.137636) (xy 439.884566 -117.128798) (xy 439.902776 -117.10633) (xy 439.944792 -117.066594)
			(xy 439.992323 -117.033653) (xy 440.04428 -117.008262) (xy 440.099474 -116.991003) (xy 440.156641 -116.982269)
			(xy 440.185556 -116.981732) (xy 440.212814 -116.982112) (xy 440.266775 -116.989865) (xy 440.319084 -117.005218)
			(xy 440.368675 -117.027861) (xy 440.414538 -117.057331) (xy 440.455741 -117.093028) (xy 440.464067 -117.102636)
			(xy 441.279278 -117.102636) (xy 441.283349 -117.047014) (xy 441.295475 -116.992577) (xy 441.315398 -116.940486)
			(xy 441.342694 -116.891851) (xy 441.37678 -116.847708) (xy 441.416929 -116.808999) (xy 441.462287 -116.776548)
			(xy 441.511887 -116.751047) (xy 441.564671 -116.73304) (xy 441.619514 -116.72291) (xy 441.675248 -116.720873)
			(xy 441.730685 -116.726973) (xy 441.784642 -116.741079) (xy 441.835971 -116.762891) (xy 441.883577 -116.791945)
			(xy 441.926445 -116.82762) (xy 441.963662 -116.869157) (xy 441.994435 -116.91567) (xy 442.018107 -116.966167)
			(xy 442.034175 -117.019574) (xy 442.042295 -117.07475) (xy 442.042804 -117.102636) (xy 442.042295 -117.130522)
			(xy 442.034175 -117.185698) (xy 442.018107 -117.239105) (xy 441.994435 -117.289602) (xy 441.963662 -117.336115)
			(xy 441.926445 -117.377652) (xy 441.883577 -117.413327) (xy 441.862016 -117.426486) (xy 443.447168 -117.426486)
			(xy 443.451239 -117.370864) (xy 443.463365 -117.316427) (xy 443.483288 -117.264336) (xy 443.510584 -117.215701)
			(xy 443.54467 -117.171558) (xy 443.584819 -117.132849) (xy 443.630177 -117.100398) (xy 443.679777 -117.074897)
			(xy 443.732561 -117.05689) (xy 443.787404 -117.04676) (xy 443.843138 -117.044723) (xy 443.898575 -117.050823)
			(xy 443.952532 -117.064929) (xy 444.003861 -117.086741) (xy 444.051467 -117.115795) (xy 444.094335 -117.15147)
			(xy 444.131552 -117.193007) (xy 444.162325 -117.23952) (xy 444.166384 -117.248178) (xy 456.038964 -117.248178)
			(xy 456.043035 -117.192556) (xy 456.055161 -117.138119) (xy 456.075084 -117.086028) (xy 456.10238 -117.037393)
			(xy 456.136466 -116.99325) (xy 456.176615 -116.954541) (xy 456.221973 -116.92209) (xy 456.271573 -116.896589)
			(xy 456.324357 -116.878582) (xy 456.3792 -116.868452) (xy 456.434934 -116.866415) (xy 456.490371 -116.872515)
			(xy 456.544328 -116.886621) (xy 456.595657 -116.908433) (xy 456.643263 -116.937487) (xy 456.686131 -116.973162)
			(xy 456.723348 -117.014699) (xy 456.754121 -117.061212) (xy 456.777793 -117.111709) (xy 456.793861 -117.165116)
			(xy 456.801981 -117.220292) (xy 456.80249 -117.248178) (xy 457.054964 -117.248178) (xy 457.059035 -117.192556)
			(xy 457.071161 -117.138119) (xy 457.091084 -117.086028) (xy 457.11838 -117.037393) (xy 457.152466 -116.99325)
			(xy 457.192615 -116.954541) (xy 457.237973 -116.92209) (xy 457.287573 -116.896589) (xy 457.340357 -116.878582)
			(xy 457.3952 -116.868452) (xy 457.450934 -116.866415) (xy 457.506371 -116.872515) (xy 457.560328 -116.886621)
			(xy 457.611657 -116.908433) (xy 457.659263 -116.937487) (xy 457.702131 -116.973162) (xy 457.739348 -117.014699)
			(xy 457.770121 -117.061212) (xy 457.793793 -117.111709) (xy 457.809861 -117.165116) (xy 457.817981 -117.220292)
			(xy 457.81849 -117.248178) (xy 458.070964 -117.248178) (xy 458.075035 -117.192556) (xy 458.087161 -117.138119)
			(xy 458.107084 -117.086028) (xy 458.13438 -117.037393) (xy 458.168466 -116.99325) (xy 458.208615 -116.954541)
			(xy 458.253973 -116.92209) (xy 458.303573 -116.896589) (xy 458.356357 -116.878582) (xy 458.4112 -116.868452)
			(xy 458.466934 -116.866415) (xy 458.522371 -116.872515) (xy 458.576328 -116.886621) (xy 458.627657 -116.908433)
			(xy 458.675263 -116.937487) (xy 458.718131 -116.973162) (xy 458.755348 -117.014699) (xy 458.786121 -117.061212)
			(xy 458.809793 -117.111709) (xy 458.825861 -117.165116) (xy 458.833981 -117.220292) (xy 458.83449 -117.248178)
			(xy 458.833981 -117.276064) (xy 458.825861 -117.33124) (xy 458.809793 -117.384647) (xy 458.786121 -117.435144)
			(xy 458.755348 -117.481657) (xy 458.718131 -117.523194) (xy 458.675263 -117.558869) (xy 458.627657 -117.587923)
			(xy 458.576328 -117.609735) (xy 458.522371 -117.623841) (xy 458.466934 -117.629941) (xy 458.4112 -117.627904)
			(xy 458.356357 -117.617774) (xy 458.303573 -117.599767) (xy 458.253973 -117.574266) (xy 458.208615 -117.541815)
			(xy 458.168466 -117.503106) (xy 458.13438 -117.458963) (xy 458.107084 -117.410328) (xy 458.087161 -117.358237)
			(xy 458.075035 -117.3038) (xy 458.070964 -117.248178) (xy 457.81849 -117.248178) (xy 457.817981 -117.276064)
			(xy 457.809861 -117.33124) (xy 457.793793 -117.384647) (xy 457.770121 -117.435144) (xy 457.739348 -117.481657)
			(xy 457.702131 -117.523194) (xy 457.659263 -117.558869) (xy 457.611657 -117.587923) (xy 457.560328 -117.609735)
			(xy 457.506371 -117.623841) (xy 457.450934 -117.629941) (xy 457.3952 -117.627904) (xy 457.340357 -117.617774)
			(xy 457.287573 -117.599767) (xy 457.237973 -117.574266) (xy 457.192615 -117.541815) (xy 457.152466 -117.503106)
			(xy 457.11838 -117.458963) (xy 457.091084 -117.410328) (xy 457.071161 -117.358237) (xy 457.059035 -117.3038)
			(xy 457.054964 -117.248178) (xy 456.80249 -117.248178) (xy 456.801981 -117.276064) (xy 456.793861 -117.33124)
			(xy 456.777793 -117.384647) (xy 456.754121 -117.435144) (xy 456.723348 -117.481657) (xy 456.686131 -117.523194)
			(xy 456.643263 -117.558869) (xy 456.595657 -117.587923) (xy 456.544328 -117.609735) (xy 456.490371 -117.623841)
			(xy 456.434934 -117.629941) (xy 456.3792 -117.627904) (xy 456.324357 -117.617774) (xy 456.271573 -117.599767)
			(xy 456.221973 -117.574266) (xy 456.176615 -117.541815) (xy 456.136466 -117.503106) (xy 456.10238 -117.458963)
			(xy 456.075084 -117.410328) (xy 456.055161 -117.358237) (xy 456.043035 -117.3038) (xy 456.038964 -117.248178)
			(xy 444.166384 -117.248178) (xy 444.185997 -117.290017) (xy 444.202065 -117.343424) (xy 444.210185 -117.3986)
			(xy 444.210694 -117.426486) (xy 444.210185 -117.454372) (xy 444.202065 -117.509548) (xy 444.185997 -117.562955)
			(xy 444.162325 -117.613452) (xy 444.131552 -117.659965) (xy 444.094335 -117.701502) (xy 444.051467 -117.737177)
			(xy 444.003861 -117.766231) (xy 443.952532 -117.788043) (xy 443.898575 -117.802149) (xy 443.843138 -117.808249)
			(xy 443.787404 -117.806212) (xy 443.732561 -117.796082) (xy 443.679777 -117.778075) (xy 443.630177 -117.752574)
			(xy 443.584819 -117.720123) (xy 443.54467 -117.681414) (xy 443.510584 -117.637271) (xy 443.483288 -117.588636)
			(xy 443.463365 -117.536545) (xy 443.451239 -117.482108) (xy 443.447168 -117.426486) (xy 441.862016 -117.426486)
			(xy 441.835971 -117.442381) (xy 441.784642 -117.464193) (xy 441.730685 -117.478299) (xy 441.675248 -117.484399)
			(xy 441.619514 -117.482362) (xy 441.564671 -117.472232) (xy 441.511887 -117.454225) (xy 441.462287 -117.428724)
			(xy 441.416929 -117.396273) (xy 441.37678 -117.357564) (xy 441.342694 -117.313421) (xy 441.315398 -117.264786)
			(xy 441.295475 -117.212695) (xy 441.283349 -117.158258) (xy 441.279278 -117.102636) (xy 440.464067 -117.102636)
			(xy 440.491443 -117.134226) (xy 440.520918 -117.180087) (xy 440.543566 -117.229675) (xy 440.558926 -117.281982)
			(xy 440.566685 -117.335942) (xy 440.566685 -117.390458) (xy 440.558926 -117.444418) (xy 440.543566 -117.496725)
			(xy 440.520918 -117.546313) (xy 440.491443 -117.592174) (xy 440.455741 -117.633372) (xy 440.414538 -117.669069)
			(xy 440.368675 -117.698539) (xy 440.319084 -117.721182) (xy 440.266775 -117.736535) (xy 440.212814 -117.744288)
			(xy 440.185556 -117.744748) (xy 440.15664 -117.744209) (xy 440.099468 -117.735487) (xy 440.044269 -117.718235)
			(xy 439.992307 -117.692847) (xy 439.944773 -117.659906) (xy 439.902756 -117.620167) (xy 439.884566 -117.597682)
			(xy 439.876967 -117.588866) (xy 439.85606 -117.578688) (xy 439.844434 -117.578124) (xy 439.764678 -117.578124)
			(xy 439.753045 -117.578656) (xy 439.732135 -117.588849) (xy 439.724546 -117.597682) (xy 439.706324 -117.62014)
			(xy 439.664312 -117.659877) (xy 439.616783 -117.69282) (xy 439.564828 -117.718213) (xy 439.509635 -117.735475)
			(xy 439.45247 -117.74421) (xy 439.423556 -117.744748) (xy 439.39631 -117.744179) (xy 439.342372 -117.736418)
			(xy 439.290089 -117.721061) (xy 439.240522 -117.698419) (xy 439.194682 -117.668955) (xy 439.153501 -117.633267)
			(xy 439.117818 -117.592083) (xy 439.088359 -117.546239) (xy 439.065724 -117.49667) (xy 439.050373 -117.444385)
			(xy 439.042618 -117.390446) (xy 438.864502 -117.390446) (xy 438.864502 -118.894352) (xy 441.71616 -118.894352)
			(xy 441.716576 -118.868036) (xy 441.723819 -118.815905) (xy 441.738147 -118.76526) (xy 441.759289 -118.717061)
			(xy 441.786845 -118.672219) (xy 441.820293 -118.631582) (xy 441.83935 -118.613428) (xy 441.846734 -118.605891)
			(xy 441.85527 -118.586623) (xy 441.85586 -118.57609) (xy 441.85586 -118.501414) (xy 441.855349 -118.490862)
			(xy 441.846802 -118.471566) (xy 441.83935 -118.464076) (xy 441.82028 -118.445935) (xy 441.786826 -118.405301)
			(xy 441.75927 -118.360457) (xy 441.738135 -118.312254) (xy 441.72382 -118.261604) (xy 441.716598 -118.209469)
			(xy 441.71616 -118.183152) (xy 441.716646 -118.155901) (xy 441.724402 -118.101953) (xy 441.739757 -118.049658)
			(xy 441.762399 -118.000081) (xy 441.791865 -117.954231) (xy 441.827556 -117.91304) (xy 441.868747 -117.877349)
			(xy 441.914597 -117.847883) (xy 441.964174 -117.825241) (xy 442.016469 -117.809886) (xy 442.070417 -117.80213)
			(xy 442.124919 -117.80213) (xy 442.178867 -117.809886) (xy 442.231162 -117.825241) (xy 442.280739 -117.847883)
			(xy 442.326589 -117.877349) (xy 442.36778 -117.91304) (xy 442.403471 -117.954231) (xy 442.432937 -118.000081)
			(xy 442.455579 -118.049658) (xy 442.470934 -118.101953) (xy 442.47869 -118.155901) (xy 442.479176 -118.183152)
			(xy 442.478751 -118.209467) (xy 442.471508 -118.261598) (xy 442.457182 -118.312242) (xy 442.436041 -118.360441)
			(xy 442.408487 -118.405283) (xy 442.375041 -118.445921) (xy 442.355986 -118.464076) (xy 442.352243 -118.467886)
			(xy 445.782444 -118.467886) (xy 445.786515 -118.412264) (xy 445.798641 -118.357827) (xy 445.818564 -118.305736)
			(xy 445.84586 -118.257101) (xy 445.879946 -118.212958) (xy 445.920095 -118.174249) (xy 445.965453 -118.141798)
			(xy 446.015053 -118.116297) (xy 446.067837 -118.09829) (xy 446.12268 -118.08816) (xy 446.178414 -118.086123)
			(xy 446.233851 -118.092223) (xy 446.287808 -118.106329) (xy 446.339137 -118.128141) (xy 446.386743 -118.157195)
			(xy 446.429611 -118.19287) (xy 446.466828 -118.234407) (xy 446.497601 -118.28092) (xy 446.521273 -118.331417)
			(xy 446.537341 -118.384824) (xy 446.545461 -118.44) (xy 446.54597 -118.467886) (xy 447.95262 -118.467886)
			(xy 447.956691 -118.412264) (xy 447.968817 -118.357827) (xy 447.98874 -118.305736) (xy 448.016036 -118.257101)
			(xy 448.050122 -118.212958) (xy 448.090271 -118.174249) (xy 448.135629 -118.141798) (xy 448.185229 -118.116297)
			(xy 448.238013 -118.09829) (xy 448.292856 -118.08816) (xy 448.34859 -118.086123) (xy 448.404027 -118.092223)
			(xy 448.457984 -118.106329) (xy 448.509313 -118.128141) (xy 448.556919 -118.157195) (xy 448.599787 -118.19287)
			(xy 448.637004 -118.234407) (xy 448.667777 -118.28092) (xy 448.691449 -118.331417) (xy 448.707517 -118.384824)
			(xy 448.715637 -118.44) (xy 448.716146 -118.467886) (xy 448.715637 -118.495772) (xy 448.707517 -118.550948)
			(xy 448.691449 -118.604355) (xy 448.667777 -118.654852) (xy 448.637004 -118.701365) (xy 448.599787 -118.742902)
			(xy 448.578953 -118.76024) (xy 448.838826 -118.76024) (xy 448.842897 -118.704618) (xy 448.855023 -118.650181)
			(xy 448.874946 -118.59809) (xy 448.902242 -118.549455) (xy 448.936328 -118.505312) (xy 448.976477 -118.466603)
			(xy 449.021835 -118.434152) (xy 449.071435 -118.408651) (xy 449.124219 -118.390644) (xy 449.179062 -118.380514)
			(xy 449.234796 -118.378477) (xy 449.290233 -118.384577) (xy 449.34419 -118.398683) (xy 449.395519 -118.420495)
			(xy 449.443125 -118.449549) (xy 449.485993 -118.485224) (xy 449.52321 -118.526761) (xy 449.553983 -118.573274)
			(xy 449.577655 -118.623771) (xy 449.593723 -118.677178) (xy 449.601843 -118.732354) (xy 449.602352 -118.76024)
			(xy 450.864476 -118.76024) (xy 450.868547 -118.704618) (xy 450.880673 -118.650181) (xy 450.900596 -118.59809)
			(xy 450.927892 -118.549455) (xy 450.961978 -118.505312) (xy 451.002127 -118.466603) (xy 451.047485 -118.434152)
			(xy 451.097085 -118.408651) (xy 451.149869 -118.390644) (xy 451.204712 -118.380514) (xy 451.260446 -118.378477)
			(xy 451.315883 -118.384577) (xy 451.36984 -118.398683) (xy 451.421169 -118.420495) (xy 451.468775 -118.449549)
			(xy 451.511643 -118.485224) (xy 451.54886 -118.526761) (xy 451.579633 -118.573274) (xy 451.603305 -118.623771)
			(xy 451.619373 -118.677178) (xy 451.627493 -118.732354) (xy 451.628002 -118.76024) (xy 451.627493 -118.788126)
			(xy 451.619373 -118.843302) (xy 451.603305 -118.896709) (xy 451.579633 -118.947206) (xy 451.54886 -118.993719)
			(xy 451.519777 -119.026178) (xy 454.281538 -119.026178) (xy 454.285609 -118.970556) (xy 454.297735 -118.916119)
			(xy 454.317658 -118.864028) (xy 454.344954 -118.815393) (xy 454.37904 -118.77125) (xy 454.419189 -118.732541)
			(xy 454.464547 -118.70009) (xy 454.514147 -118.674589) (xy 454.566931 -118.656582) (xy 454.621774 -118.646452)
			(xy 454.677508 -118.644415) (xy 454.732945 -118.650515) (xy 454.786902 -118.664621) (xy 454.838231 -118.686433)
			(xy 454.885837 -118.715487) (xy 454.928705 -118.751162) (xy 454.965922 -118.792699) (xy 454.996695 -118.839212)
			(xy 455.020367 -118.889709) (xy 455.036435 -118.943116) (xy 455.044555 -118.998292) (xy 455.045064 -119.026178)
			(xy 455.044555 -119.054064) (xy 455.036435 -119.10924) (xy 455.020367 -119.162647) (xy 454.996695 -119.213144)
			(xy 454.965922 -119.259657) (xy 454.928705 -119.301194) (xy 454.885837 -119.336869) (xy 454.838231 -119.365923)
			(xy 454.786902 -119.387735) (xy 454.732945 -119.401841) (xy 454.677508 -119.407941) (xy 454.621774 -119.405904)
			(xy 454.566931 -119.395774) (xy 454.514147 -119.377767) (xy 454.464547 -119.352266) (xy 454.419189 -119.319815)
			(xy 454.37904 -119.281106) (xy 454.344954 -119.236963) (xy 454.317658 -119.188328) (xy 454.297735 -119.136237)
			(xy 454.285609 -119.0818) (xy 454.281538 -119.026178) (xy 451.519777 -119.026178) (xy 451.511643 -119.035256)
			(xy 451.468775 -119.070931) (xy 451.421169 -119.099985) (xy 451.36984 -119.121797) (xy 451.315883 -119.135903)
			(xy 451.260446 -119.142003) (xy 451.204712 -119.139966) (xy 451.149869 -119.129836) (xy 451.097085 -119.111829)
			(xy 451.047485 -119.086328) (xy 451.002127 -119.053877) (xy 450.961978 -119.015168) (xy 450.927892 -118.971025)
			(xy 450.900596 -118.92239) (xy 450.880673 -118.870299) (xy 450.868547 -118.815862) (xy 450.864476 -118.76024)
			(xy 449.602352 -118.76024) (xy 449.601843 -118.788126) (xy 449.593723 -118.843302) (xy 449.577655 -118.896709)
			(xy 449.553983 -118.947206) (xy 449.52321 -118.993719) (xy 449.485993 -119.035256) (xy 449.443125 -119.070931)
			(xy 449.395519 -119.099985) (xy 449.34419 -119.121797) (xy 449.290233 -119.135903) (xy 449.234796 -119.142003)
			(xy 449.179062 -119.139966) (xy 449.124219 -119.129836) (xy 449.071435 -119.111829) (xy 449.021835 -119.086328)
			(xy 448.976477 -119.053877) (xy 448.936328 -119.015168) (xy 448.902242 -118.971025) (xy 448.874946 -118.92239)
			(xy 448.855023 -118.870299) (xy 448.842897 -118.815862) (xy 448.838826 -118.76024) (xy 448.578953 -118.76024)
			(xy 448.556919 -118.778577) (xy 448.509313 -118.807631) (xy 448.457984 -118.829443) (xy 448.404027 -118.843549)
			(xy 448.34859 -118.849649) (xy 448.292856 -118.847612) (xy 448.238013 -118.837482) (xy 448.185229 -118.819475)
			(xy 448.135629 -118.793974) (xy 448.090271 -118.761523) (xy 448.050122 -118.722814) (xy 448.016036 -118.678671)
			(xy 447.98874 -118.630036) (xy 447.968817 -118.577945) (xy 447.956691 -118.523508) (xy 447.95262 -118.467886)
			(xy 446.54597 -118.467886) (xy 446.545461 -118.495772) (xy 446.537341 -118.550948) (xy 446.521273 -118.604355)
			(xy 446.497601 -118.654852) (xy 446.466828 -118.701365) (xy 446.429611 -118.742902) (xy 446.386743 -118.778577)
			(xy 446.339137 -118.807631) (xy 446.287808 -118.829443) (xy 446.233851 -118.843549) (xy 446.178414 -118.849649)
			(xy 446.12268 -118.847612) (xy 446.067837 -118.837482) (xy 446.015053 -118.819475) (xy 445.965453 -118.793974)
			(xy 445.920095 -118.761523) (xy 445.879946 -118.722814) (xy 445.84586 -118.678671) (xy 445.818564 -118.630036)
			(xy 445.798641 -118.577945) (xy 445.786515 -118.523508) (xy 445.782444 -118.467886) (xy 442.352243 -118.467886)
			(xy 442.348591 -118.471603) (xy 442.340063 -118.490879) (xy 442.339476 -118.501414) (xy 442.339476 -118.57609)
			(xy 442.340004 -118.58664) (xy 442.348541 -118.605935) (xy 442.355986 -118.613428) (xy 442.375045 -118.63158)
			(xy 442.408503 -118.67221) (xy 442.436062 -118.717051) (xy 442.4572 -118.765252) (xy 442.471516 -118.815901)
			(xy 442.478739 -118.868036) (xy 442.479176 -118.894352) (xy 442.47869 -118.921603) (xy 442.470934 -118.975551)
			(xy 442.455579 -119.027846) (xy 442.432937 -119.077423) (xy 442.403471 -119.123273) (xy 442.36778 -119.164464)
			(xy 442.326589 -119.200155) (xy 442.280739 -119.229621) (xy 442.231162 -119.252263) (xy 442.178867 -119.267618)
			(xy 442.124919 -119.275374) (xy 442.070417 -119.275374) (xy 442.016469 -119.267618) (xy 441.964174 -119.252263)
			(xy 441.914597 -119.229621) (xy 441.868747 -119.200155) (xy 441.827556 -119.164464) (xy 441.791865 -119.123273)
			(xy 441.762399 -119.077423) (xy 441.739757 -119.027846) (xy 441.724402 -118.975551) (xy 441.716646 -118.921603)
			(xy 441.71616 -118.894352) (xy 438.864502 -118.894352) (xy 438.864502 -119.407557) (xy 442.799609 -119.407557)
			(xy 442.799609 -119.353043) (xy 442.807368 -119.299083) (xy 442.822727 -119.246777) (xy 442.845374 -119.197189)
			(xy 442.874848 -119.151329) (xy 442.910548 -119.110131) (xy 442.951749 -119.074433) (xy 442.99761 -119.044962)
			(xy 443.0472 -119.022318) (xy 443.099507 -119.006962) (xy 443.153467 -118.999207) (xy 443.180724 -118.998746)
			(xy 443.208095 -118.999187) (xy 443.262276 -119.007009) (xy 443.31478 -119.022503) (xy 443.364526 -119.045351)
			(xy 443.410492 -119.075082) (xy 443.431422 -119.092726) (xy 443.431676 -119.09298) (xy 443.438758 -119.098572)
			(xy 443.455679 -119.104813) (xy 443.464696 -119.105172) (xy 443.531752 -119.105172) (xy 443.540767 -119.104798)
			(xy 443.557685 -119.098563) (xy 443.564772 -119.09298) (xy 443.564772 -119.092726) (xy 443.565026 -119.092726)
			(xy 443.585979 -119.075112) (xy 443.631945 -119.045396) (xy 443.681688 -119.022554) (xy 443.734184 -119.007058)
			(xy 443.788356 -118.999223) (xy 443.815724 -118.998746) (xy 443.842971 -118.999326) (xy 443.896909 -119.007084)
			(xy 443.949195 -119.022439) (xy 443.998763 -119.045079) (xy 444.044605 -119.074543) (xy 444.085787 -119.11023)
			(xy 444.121472 -119.151414) (xy 444.150932 -119.197258) (xy 444.173569 -119.246828) (xy 444.188921 -119.299114)
			(xy 444.196676 -119.353053) (xy 444.196676 -119.407547) (xy 444.188921 -119.461486) (xy 444.184358 -119.477028)
			(xy 447.903344 -119.477028) (xy 447.907415 -119.421406) (xy 447.919541 -119.366969) (xy 447.939464 -119.314878)
			(xy 447.96676 -119.266243) (xy 448.000846 -119.2221) (xy 448.040995 -119.183391) (xy 448.086353 -119.15094)
			(xy 448.135953 -119.125439) (xy 448.188737 -119.107432) (xy 448.24358 -119.097302) (xy 448.299314 -119.095265)
			(xy 448.354751 -119.101365) (xy 448.408708 -119.115471) (xy 448.460037 -119.137283) (xy 448.507643 -119.166337)
			(xy 448.550511 -119.202012) (xy 448.587728 -119.243549) (xy 448.618501 -119.290062) (xy 448.642173 -119.340559)
			(xy 448.658241 -119.393966) (xy 448.666361 -119.449142) (xy 448.66687 -119.477028) (xy 448.666361 -119.504914)
			(xy 448.658241 -119.56009) (xy 448.642173 -119.613497) (xy 448.618501 -119.663994) (xy 448.587728 -119.710507)
			(xy 448.550511 -119.752044) (xy 448.507643 -119.787719) (xy 448.460037 -119.816773) (xy 448.408708 -119.838585)
			(xy 448.354751 -119.852691) (xy 448.299314 -119.858791) (xy 448.24358 -119.856754) (xy 448.188737 -119.846624)
			(xy 448.135953 -119.828617) (xy 448.086353 -119.803116) (xy 448.040995 -119.770665) (xy 448.000846 -119.731956)
			(xy 447.96676 -119.687813) (xy 447.939464 -119.639178) (xy 447.919541 -119.587087) (xy 447.907415 -119.53265)
			(xy 447.903344 -119.477028) (xy 444.184358 -119.477028) (xy 444.173569 -119.513772) (xy 444.150932 -119.563342)
			(xy 444.121472 -119.609186) (xy 444.085787 -119.65037) (xy 444.044605 -119.686057) (xy 443.998763 -119.715521)
			(xy 443.949195 -119.738161) (xy 443.896909 -119.753516) (xy 443.842971 -119.761274) (xy 443.815724 -119.761762)
			(xy 443.788354 -119.761291) (xy 443.734175 -119.753476) (xy 443.681671 -119.737988) (xy 443.631924 -119.715148)
			(xy 443.585957 -119.685423) (xy 443.565026 -119.667782) (xy 443.564772 -119.667528) (xy 443.557675 -119.661957)
			(xy 443.540766 -119.655703) (xy 443.531752 -119.655336) (xy 443.464696 -119.655336) (xy 443.455678 -119.655683)
			(xy 443.438761 -119.661937) (xy 443.431676 -119.667528) (xy 443.431676 -119.667782) (xy 443.431422 -119.667782)
			(xy 443.41049 -119.685421) (xy 443.364518 -119.715134) (xy 443.31477 -119.73797) (xy 443.262269 -119.753461)
			(xy 443.208093 -119.761288) (xy 443.180724 -119.761762) (xy 443.153467 -119.761393) (xy 443.099507 -119.753638)
			(xy 443.0472 -119.738282) (xy 442.99761 -119.715638) (xy 442.951749 -119.686167) (xy 442.910548 -119.650469)
			(xy 442.874848 -119.609271) (xy 442.845374 -119.563411) (xy 442.822727 -119.513823) (xy 442.807368 -119.461517)
			(xy 442.799609 -119.407557) (xy 438.864502 -119.407557) (xy 438.864502 -119.936006) (xy 440.994544 -119.936006)
			(xy 440.998615 -119.880384) (xy 441.010741 -119.825947) (xy 441.030664 -119.773856) (xy 441.05796 -119.725221)
			(xy 441.092046 -119.681078) (xy 441.132195 -119.642369) (xy 441.177553 -119.609918) (xy 441.227153 -119.584417)
			(xy 441.279937 -119.56641) (xy 441.33478 -119.55628) (xy 441.390514 -119.554243) (xy 441.445951 -119.560343)
			(xy 441.499908 -119.574449) (xy 441.551237 -119.596261) (xy 441.598843 -119.625315) (xy 441.641711 -119.66099)
			(xy 441.678928 -119.702527) (xy 441.709701 -119.74904) (xy 441.733373 -119.799537) (xy 441.749441 -119.852944)
			(xy 441.755348 -119.89308) (xy 445.869058 -119.89308) (xy 445.873129 -119.837458) (xy 445.885255 -119.783021)
			(xy 445.905178 -119.73093) (xy 445.932474 -119.682295) (xy 445.96656 -119.638152) (xy 446.006709 -119.599443)
			(xy 446.052067 -119.566992) (xy 446.101667 -119.541491) (xy 446.154451 -119.523484) (xy 446.209294 -119.513354)
			(xy 446.265028 -119.511317) (xy 446.320465 -119.517417) (xy 446.374422 -119.531523) (xy 446.425751 -119.553335)
			(xy 446.473357 -119.582389) (xy 446.516225 -119.618064) (xy 446.553442 -119.659601) (xy 446.584215 -119.706114)
			(xy 446.607887 -119.756611) (xy 446.623955 -119.810018) (xy 446.632075 -119.865194) (xy 446.632584 -119.89308)
			(xy 446.632075 -119.920966) (xy 446.623955 -119.976142) (xy 446.607887 -120.029549) (xy 446.584215 -120.080046)
			(xy 446.553442 -120.126559) (xy 446.516225 -120.168096) (xy 446.473357 -120.203771) (xy 446.425751 -120.232825)
			(xy 446.374422 -120.254637) (xy 446.320465 -120.268743) (xy 446.265028 -120.274843) (xy 446.209294 -120.272806)
			(xy 446.154451 -120.262676) (xy 446.101667 -120.244669) (xy 446.052067 -120.219168) (xy 446.006709 -120.186717)
			(xy 445.96656 -120.148008) (xy 445.932474 -120.103865) (xy 445.905178 -120.05523) (xy 445.885255 -120.003139)
			(xy 445.873129 -119.948702) (xy 445.869058 -119.89308) (xy 441.755348 -119.89308) (xy 441.757561 -119.90812)
			(xy 441.75807 -119.936006) (xy 441.757561 -119.963892) (xy 441.749441 -120.019068) (xy 441.733373 -120.072475)
			(xy 441.709701 -120.122972) (xy 441.678928 -120.169485) (xy 441.641711 -120.211022) (xy 441.598843 -120.246697)
			(xy 441.551237 -120.275751) (xy 441.499908 -120.297563) (xy 441.445951 -120.311669) (xy 441.390514 -120.317769)
			(xy 441.33478 -120.315732) (xy 441.279937 -120.305602) (xy 441.227153 -120.287595) (xy 441.177553 -120.262094)
			(xy 441.132195 -120.229643) (xy 441.092046 -120.190934) (xy 441.05796 -120.146791) (xy 441.030664 -120.098156)
			(xy 441.010741 -120.046065) (xy 440.998615 -119.991628) (xy 440.994544 -119.936006) (xy 438.864502 -119.936006)
			(xy 438.864502 -120.493028) (xy 447.904106 -120.493028) (xy 447.908177 -120.437406) (xy 447.920303 -120.382969)
			(xy 447.940226 -120.330878) (xy 447.967522 -120.282243) (xy 448.001608 -120.2381) (xy 448.041757 -120.199391)
			(xy 448.087115 -120.16694) (xy 448.136715 -120.141439) (xy 448.189499 -120.123432) (xy 448.244342 -120.113302)
			(xy 448.300076 -120.111265) (xy 448.355513 -120.117365) (xy 448.40947 -120.131471) (xy 448.460799 -120.153283)
			(xy 448.508405 -120.182337) (xy 448.551273 -120.218012) (xy 448.58849 -120.259549) (xy 448.619263 -120.306062)
			(xy 448.642935 -120.356559) (xy 448.659003 -120.409966) (xy 448.667123 -120.465142) (xy 448.667632 -120.493028)
			(xy 448.667123 -120.520914) (xy 448.659003 -120.57609) (xy 448.642935 -120.629497) (xy 448.619263 -120.679994)
			(xy 448.58849 -120.726507) (xy 448.551273 -120.768044) (xy 448.522198 -120.79224) (xy 448.836032 -120.79224)
			(xy 448.840103 -120.736618) (xy 448.852229 -120.682181) (xy 448.872152 -120.63009) (xy 448.899448 -120.581455)
			(xy 448.933534 -120.537312) (xy 448.973683 -120.498603) (xy 449.019041 -120.466152) (xy 449.068641 -120.440651)
			(xy 449.121425 -120.422644) (xy 449.176268 -120.412514) (xy 449.232002 -120.410477) (xy 449.287439 -120.416577)
			(xy 449.341396 -120.430683) (xy 449.392725 -120.452495) (xy 449.440331 -120.481549) (xy 449.483199 -120.517224)
			(xy 449.520416 -120.558761) (xy 449.551189 -120.605274) (xy 449.574861 -120.655771) (xy 449.590929 -120.709178)
			(xy 449.599049 -120.764354) (xy 449.599558 -120.79224) (xy 450.991476 -120.79224) (xy 450.995547 -120.736618)
			(xy 451.007673 -120.682181) (xy 451.027596 -120.63009) (xy 451.054892 -120.581455) (xy 451.088978 -120.537312)
			(xy 451.129127 -120.498603) (xy 451.174485 -120.466152) (xy 451.224085 -120.440651) (xy 451.276869 -120.422644)
			(xy 451.331712 -120.412514) (xy 451.387446 -120.410477) (xy 451.442883 -120.416577) (xy 451.49684 -120.430683)
			(xy 451.548169 -120.452495) (xy 451.595775 -120.481549) (xy 451.638643 -120.517224) (xy 451.646777 -120.526302)
			(xy 452.503538 -120.526302) (xy 452.507609 -120.47068) (xy 452.519735 -120.416243) (xy 452.539658 -120.364152)
			(xy 452.566954 -120.315517) (xy 452.60104 -120.271374) (xy 452.641189 -120.232665) (xy 452.686547 -120.200214)
			(xy 452.736147 -120.174713) (xy 452.788931 -120.156706) (xy 452.843774 -120.146576) (xy 452.899508 -120.144539)
			(xy 452.954945 -120.150639) (xy 453.008902 -120.164745) (xy 453.060231 -120.186557) (xy 453.107837 -120.215611)
			(xy 453.150705 -120.251286) (xy 453.187922 -120.292823) (xy 453.218695 -120.339336) (xy 453.242367 -120.389833)
			(xy 453.258435 -120.44324) (xy 453.266555 -120.498416) (xy 453.267064 -120.526302) (xy 454.293476 -120.526302)
			(xy 454.297547 -120.47068) (xy 454.309673 -120.416243) (xy 454.329596 -120.364152) (xy 454.356892 -120.315517)
			(xy 454.390978 -120.271374) (xy 454.431127 -120.232665) (xy 454.476485 -120.200214) (xy 454.526085 -120.174713)
			(xy 454.578869 -120.156706) (xy 454.633712 -120.146576) (xy 454.689446 -120.144539) (xy 454.744883 -120.150639)
			(xy 454.79884 -120.164745) (xy 454.850169 -120.186557) (xy 454.897775 -120.215611) (xy 454.940643 -120.251286)
			(xy 454.97786 -120.292823) (xy 455.008633 -120.339336) (xy 455.032305 -120.389833) (xy 455.048373 -120.44324)
			(xy 455.056493 -120.498416) (xy 455.057002 -120.526302) (xy 455.056493 -120.554188) (xy 455.048373 -120.609364)
			(xy 455.032305 -120.662771) (xy 455.008633 -120.713268) (xy 454.97786 -120.759781) (xy 454.940643 -120.801318)
			(xy 454.897775 -120.836993) (xy 454.850169 -120.866047) (xy 454.79884 -120.887859) (xy 454.744883 -120.901965)
			(xy 454.689446 -120.908065) (xy 454.633712 -120.906028) (xy 454.578869 -120.895898) (xy 454.526085 -120.877891)
			(xy 454.476485 -120.85239) (xy 454.431127 -120.819939) (xy 454.390978 -120.78123) (xy 454.356892 -120.737087)
			(xy 454.329596 -120.688452) (xy 454.309673 -120.636361) (xy 454.297547 -120.581924) (xy 454.293476 -120.526302)
			(xy 453.267064 -120.526302) (xy 453.266555 -120.554188) (xy 453.258435 -120.609364) (xy 453.242367 -120.662771)
			(xy 453.218695 -120.713268) (xy 453.187922 -120.759781) (xy 453.150705 -120.801318) (xy 453.107837 -120.836993)
			(xy 453.060231 -120.866047) (xy 453.008902 -120.887859) (xy 452.954945 -120.901965) (xy 452.899508 -120.908065)
			(xy 452.843774 -120.906028) (xy 452.788931 -120.895898) (xy 452.736147 -120.877891) (xy 452.686547 -120.85239)
			(xy 452.641189 -120.819939) (xy 452.60104 -120.78123) (xy 452.566954 -120.737087) (xy 452.539658 -120.688452)
			(xy 452.519735 -120.636361) (xy 452.507609 -120.581924) (xy 452.503538 -120.526302) (xy 451.646777 -120.526302)
			(xy 451.67586 -120.558761) (xy 451.706633 -120.605274) (xy 451.730305 -120.655771) (xy 451.746373 -120.709178)
			(xy 451.754493 -120.764354) (xy 451.755002 -120.79224) (xy 451.754493 -120.820126) (xy 451.746373 -120.875302)
			(xy 451.730305 -120.928709) (xy 451.706633 -120.979206) (xy 451.67586 -121.025719) (xy 451.638643 -121.067256)
			(xy 451.595775 -121.102931) (xy 451.548169 -121.131985) (xy 451.49684 -121.153797) (xy 451.442883 -121.167903)
			(xy 451.387446 -121.174003) (xy 451.331712 -121.171966) (xy 451.276869 -121.161836) (xy 451.224085 -121.143829)
			(xy 451.174485 -121.118328) (xy 451.129127 -121.085877) (xy 451.088978 -121.047168) (xy 451.054892 -121.003025)
			(xy 451.027596 -120.95439) (xy 451.007673 -120.902299) (xy 450.995547 -120.847862) (xy 450.991476 -120.79224)
			(xy 449.599558 -120.79224) (xy 449.599049 -120.820126) (xy 449.590929 -120.875302) (xy 449.574861 -120.928709)
			(xy 449.551189 -120.979206) (xy 449.520416 -121.025719) (xy 449.483199 -121.067256) (xy 449.440331 -121.102931)
			(xy 449.392725 -121.131985) (xy 449.341396 -121.153797) (xy 449.287439 -121.167903) (xy 449.232002 -121.174003)
			(xy 449.176268 -121.171966) (xy 449.121425 -121.161836) (xy 449.068641 -121.143829) (xy 449.019041 -121.118328)
			(xy 448.973683 -121.085877) (xy 448.933534 -121.047168) (xy 448.899448 -121.003025) (xy 448.872152 -120.95439)
			(xy 448.852229 -120.902299) (xy 448.840103 -120.847862) (xy 448.836032 -120.79224) (xy 448.522198 -120.79224)
			(xy 448.508405 -120.803719) (xy 448.460799 -120.832773) (xy 448.40947 -120.854585) (xy 448.355513 -120.868691)
			(xy 448.300076 -120.874791) (xy 448.244342 -120.872754) (xy 448.189499 -120.862624) (xy 448.136715 -120.844617)
			(xy 448.087115 -120.819116) (xy 448.041757 -120.786665) (xy 448.001608 -120.747956) (xy 447.967522 -120.703813)
			(xy 447.940226 -120.655178) (xy 447.920303 -120.603087) (xy 447.908177 -120.54865) (xy 447.904106 -120.493028)
			(xy 438.864502 -120.493028) (xy 438.864502 -120.732042) (xy 438.864815 -120.740526) (xy 438.870375 -120.756557)
			(xy 438.880897 -120.769869) (xy 438.88787 -120.774714) (xy 438.970674 -120.828054) (xy 438.996582 -120.829832)
			(xy 439.008266 -120.824244) (xy 439.033188 -120.813435) (xy 439.085323 -120.798175) (xy 439.139093 -120.790449)
			(xy 439.166254 -120.789954) (xy 439.166508 -120.789954) (xy 439.193878 -120.790426) (xy 439.248054 -120.798252)
			(xy 439.300556 -120.813742) (xy 439.350305 -120.836577) (xy 439.396278 -120.86629) (xy 439.417206 -120.883934)
			(xy 439.41746 -120.883934) (xy 439.41746 -120.884188) (xy 439.424545 -120.88978) (xy 439.441462 -120.896037)
			(xy 439.45048 -120.89638) (xy 439.517536 -120.89638) (xy 439.52655 -120.896014) (xy 439.543457 -120.889756)
			(xy 439.550556 -120.884188) (xy 439.55081 -120.883934) (xy 439.571741 -120.866291) (xy 439.617707 -120.836564)
			(xy 439.667454 -120.81372) (xy 439.719957 -120.798229) (xy 439.774137 -120.790412) (xy 439.801508 -120.789954)
			(xy 439.828762 -120.79044) (xy 439.882714 -120.798199) (xy 439.935013 -120.813556) (xy 439.984594 -120.8362)
			(xy 440.030448 -120.865669) (xy 440.071641 -120.901364) (xy 440.107336 -120.942558) (xy 440.136804 -120.988413)
			(xy 440.159447 -121.037995) (xy 440.174803 -121.090294) (xy 440.18256 -121.144246) (xy 440.18256 -121.198754)
			(xy 440.174803 -121.252706) (xy 440.159447 -121.305005) (xy 440.136804 -121.354587) (xy 440.107336 -121.400442)
			(xy 440.071641 -121.441636) (xy 440.030448 -121.477331) (xy 439.984594 -121.5068) (xy 439.935013 -121.529444)
			(xy 439.882714 -121.544801) (xy 439.828762 -121.55256) (xy 439.801508 -121.55297) (xy 439.774138 -121.552499)
			(xy 439.71996 -121.544675) (xy 439.667456 -121.529188) (xy 439.617705 -121.506355) (xy 439.571729 -121.476646)
			(xy 439.55081 -121.45899) (xy 439.550556 -121.45899) (xy 439.550556 -121.458736) (xy 439.543473 -121.453139)
			(xy 439.526556 -121.446874) (xy 439.517536 -121.446544) (xy 439.45048 -121.446544) (xy 439.441464 -121.446906)
			(xy 439.424548 -121.453152) (xy 439.41746 -121.458736) (xy 439.417206 -121.45899) (xy 439.396275 -121.476633)
			(xy 439.350309 -121.50636) (xy 439.300562 -121.529205) (xy 439.248059 -121.544696) (xy 439.193879 -121.552516)
			(xy 439.166508 -121.55297) (xy 439.166254 -121.55297) (xy 439.139092 -121.552492) (xy 439.085317 -121.544778)
			(xy 439.033185 -121.5295) (xy 439.008266 -121.51868) (xy 438.996582 -121.513092) (xy 438.970674 -121.51487)
			(xy 438.88787 -121.56821) (xy 438.880909 -121.573064) (xy 438.870415 -121.586389) (xy 438.864828 -121.602403)
			(xy 438.864502 -121.610882) (xy 438.864502 -121.721118) (xy 440.2963 -121.721118) (xy 440.296777 -121.693748)
			(xy 440.304592 -121.63957) (xy 440.320079 -121.587067) (xy 440.342918 -121.537319) (xy 440.37264 -121.491352)
			(xy 440.39028 -121.47042) (xy 440.390534 -121.470166) (xy 440.396103 -121.463067) (xy 440.402359 -121.44616)
			(xy 440.402726 -121.437146) (xy 440.402726 -121.37009) (xy 440.402368 -121.361073) (xy 440.39612 -121.344157)
			(xy 440.390534 -121.33707) (xy 440.39028 -121.33707) (xy 440.39028 -121.336816) (xy 440.372632 -121.315891)
			(xy 440.342922 -121.269916) (xy 440.320088 -121.220167) (xy 440.304599 -121.167665) (xy 440.296773 -121.113488)
			(xy 440.2963 -121.086118) (xy 440.296772 -121.058865) (xy 440.304527 -121.004914) (xy 440.319881 -120.952616)
			(xy 440.342522 -120.903035) (xy 440.371989 -120.857182) (xy 440.407682 -120.815989) (xy 440.448874 -120.780295)
			(xy 440.494727 -120.750827) (xy 440.544307 -120.728184) (xy 440.596604 -120.712829) (xy 440.650555 -120.705073)
			(xy 440.677808 -120.70461) (xy 440.704687 -120.705028) (xy 440.757911 -120.712581) (xy 440.809546 -120.727536)
			(xy 440.858568 -120.749596) (xy 440.904005 -120.778325) (xy 440.944956 -120.813151) (xy 440.980608 -120.853384)
			(xy 440.995816 -120.875552) (xy 441.001846 -120.883889) (xy 441.019046 -120.895152) (xy 441.02909 -120.897396)
			(xy 441.111386 -120.912636) (xy 441.131452 -120.908064) (xy 441.139834 -120.901968) (xy 441.164289 -120.885159)
			(xy 441.217296 -120.858489) (xy 441.273792 -120.840343) (xy 441.332415 -120.831158) (xy 441.362084 -120.830594)
			(xy 441.389337 -120.83107) (xy 441.443287 -120.838825) (xy 441.495585 -120.854179) (xy 441.545165 -120.87682)
			(xy 441.591018 -120.906286) (xy 441.632211 -120.941979) (xy 441.667905 -120.98317) (xy 441.697373 -121.029023)
			(xy 441.720016 -121.078602) (xy 441.735372 -121.130899) (xy 441.743129 -121.184849) (xy 441.743592 -121.212102)
			(xy 441.743141 -121.238772) (xy 445.884298 -121.238772) (xy 445.888369 -121.18315) (xy 445.900495 -121.128713)
			(xy 445.920418 -121.076622) (xy 445.947714 -121.027987) (xy 445.9818 -120.983844) (xy 446.021949 -120.945135)
			(xy 446.067307 -120.912684) (xy 446.116907 -120.887183) (xy 446.169691 -120.869176) (xy 446.224534 -120.859046)
			(xy 446.280268 -120.857009) (xy 446.335705 -120.863109) (xy 446.389662 -120.877215) (xy 446.440991 -120.899027)
			(xy 446.488597 -120.928081) (xy 446.531465 -120.963756) (xy 446.568682 -121.005293) (xy 446.599455 -121.051806)
			(xy 446.623127 -121.102303) (xy 446.639195 -121.15571) (xy 446.647315 -121.210886) (xy 446.647824 -121.238772)
			(xy 446.647315 -121.266658) (xy 446.639195 -121.321834) (xy 446.623127 -121.375241) (xy 446.599455 -121.425738)
			(xy 446.568682 -121.472251) (xy 446.53573 -121.509028) (xy 447.929506 -121.509028) (xy 447.933577 -121.453406)
			(xy 447.945703 -121.398969) (xy 447.965626 -121.346878) (xy 447.992922 -121.298243) (xy 448.027008 -121.2541)
			(xy 448.067157 -121.215391) (xy 448.112515 -121.18294) (xy 448.162115 -121.157439) (xy 448.214899 -121.139432)
			(xy 448.269742 -121.129302) (xy 448.325476 -121.127265) (xy 448.380913 -121.133365) (xy 448.43487 -121.147471)
			(xy 448.486199 -121.169283) (xy 448.533805 -121.198337) (xy 448.576673 -121.234012) (xy 448.61389 -121.275549)
			(xy 448.644663 -121.322062) (xy 448.668335 -121.372559) (xy 448.684403 -121.425966) (xy 448.692523 -121.481142)
			(xy 448.693032 -121.509028) (xy 448.692523 -121.536914) (xy 448.684403 -121.59209) (xy 448.668335 -121.645497)
			(xy 448.644663 -121.695994) (xy 448.61389 -121.742507) (xy 448.576673 -121.784044) (xy 448.547598 -121.80824)
			(xy 448.836032 -121.80824) (xy 448.840103 -121.752618) (xy 448.852229 -121.698181) (xy 448.872152 -121.64609)
			(xy 448.899448 -121.597455) (xy 448.933534 -121.553312) (xy 448.973683 -121.514603) (xy 449.019041 -121.482152)
			(xy 449.068641 -121.456651) (xy 449.121425 -121.438644) (xy 449.176268 -121.428514) (xy 449.232002 -121.426477)
			(xy 449.287439 -121.432577) (xy 449.341396 -121.446683) (xy 449.392725 -121.468495) (xy 449.440331 -121.497549)
			(xy 449.483199 -121.533224) (xy 449.520416 -121.574761) (xy 449.551189 -121.621274) (xy 449.574861 -121.671771)
			(xy 449.590929 -121.725178) (xy 449.599049 -121.780354) (xy 449.599558 -121.80824) (xy 449.599049 -121.836126)
			(xy 449.590929 -121.891302) (xy 449.574861 -121.944709) (xy 449.551189 -121.995206) (xy 449.520416 -122.041719)
			(xy 449.483199 -122.083256) (xy 449.440331 -122.118931) (xy 449.392725 -122.147985) (xy 449.341396 -122.169797)
			(xy 449.287439 -122.183903) (xy 449.232002 -122.190003) (xy 449.176268 -122.187966) (xy 449.121425 -122.177836)
			(xy 449.068641 -122.159829) (xy 449.019041 -122.134328) (xy 448.973683 -122.101877) (xy 448.933534 -122.063168)
			(xy 448.899448 -122.019025) (xy 448.872152 -121.97039) (xy 448.852229 -121.918299) (xy 448.840103 -121.863862)
			(xy 448.836032 -121.80824) (xy 448.547598 -121.80824) (xy 448.533805 -121.819719) (xy 448.486199 -121.848773)
			(xy 448.43487 -121.870585) (xy 448.380913 -121.884691) (xy 448.325476 -121.890791) (xy 448.269742 -121.888754)
			(xy 448.214899 -121.878624) (xy 448.162115 -121.860617) (xy 448.112515 -121.835116) (xy 448.067157 -121.802665)
			(xy 448.027008 -121.763956) (xy 447.992922 -121.719813) (xy 447.965626 -121.671178) (xy 447.945703 -121.619087)
			(xy 447.933577 -121.56465) (xy 447.929506 -121.509028) (xy 446.53573 -121.509028) (xy 446.531465 -121.513788)
			(xy 446.488597 -121.549463) (xy 446.440991 -121.578517) (xy 446.389662 -121.600329) (xy 446.335705 -121.614435)
			(xy 446.280268 -121.620535) (xy 446.224534 -121.618498) (xy 446.169691 -121.608368) (xy 446.116907 -121.590361)
			(xy 446.067307 -121.56486) (xy 446.021949 -121.532409) (xy 445.9818 -121.4937) (xy 445.947714 -121.449557)
			(xy 445.920418 -121.400922) (xy 445.900495 -121.348831) (xy 445.888369 -121.294394) (xy 445.884298 -121.238772)
			(xy 441.743141 -121.238772) (xy 441.743129 -121.239472) (xy 441.735311 -121.293652) (xy 441.719821 -121.346155)
			(xy 441.696979 -121.395902) (xy 441.667253 -121.441868) (xy 441.649612 -121.4628) (xy 441.649358 -121.463054)
			(xy 441.643779 -121.470146) (xy 441.637529 -121.487059) (xy 441.637166 -121.496074) (xy 441.637166 -121.56313)
			(xy 441.637516 -121.572147) (xy 441.643769 -121.589064) (xy 441.649358 -121.59615) (xy 441.649612 -121.59615)
			(xy 441.649612 -121.596404) (xy 441.667268 -121.617322) (xy 441.696977 -121.663299) (xy 441.71981 -121.71305)
			(xy 441.735297 -121.765554) (xy 441.74312 -121.819732) (xy 441.743592 -121.847102) (xy 441.743146 -121.874356)
			(xy 441.735389 -121.928308) (xy 441.720032 -121.980607) (xy 441.697388 -122.030188) (xy 441.667918 -122.076042)
			(xy 441.632223 -122.117235) (xy 441.591028 -122.152929) (xy 441.545173 -122.182396) (xy 441.49559 -122.205038)
			(xy 441.44329 -122.220393) (xy 441.389338 -122.228148) (xy 441.362084 -122.22861) (xy 441.335206 -122.228189)
			(xy 441.281982 -122.220635) (xy 441.230347 -122.20568) (xy 441.181325 -122.18362) (xy 441.135888 -122.154893)
			(xy 441.094937 -122.120067) (xy 441.059284 -122.079835) (xy 441.044076 -122.057668) (xy 441.038004 -122.049367)
			(xy 441.020834 -122.038085) (xy 441.010802 -122.035824) (xy 440.928506 -122.020584) (xy 440.90844 -122.025156)
			(xy 440.900058 -122.031252) (xy 440.875599 -122.048055) (xy 440.822594 -122.074728) (xy 440.7661 -122.092877)
			(xy 440.707477 -122.102062) (xy 440.677808 -122.102626) (xy 440.650558 -122.102115) (xy 440.596612 -122.09436)
			(xy 440.544319 -122.079007) (xy 440.494743 -122.056368) (xy 440.448893 -122.026904) (xy 440.407703 -121.991215)
			(xy 440.372012 -121.950028) (xy 440.342545 -121.90418) (xy 440.319902 -121.854606) (xy 440.304546 -121.802314)
			(xy 440.296787 -121.748368) (xy 440.2963 -121.721118) (xy 438.864502 -121.721118) (xy 438.864502 -122.525028)
			(xy 447.90563 -122.525028) (xy 447.909701 -122.469406) (xy 447.921827 -122.414969) (xy 447.94175 -122.362878)
			(xy 447.969046 -122.314243) (xy 448.003132 -122.2701) (xy 448.043281 -122.231391) (xy 448.088639 -122.19894)
			(xy 448.138239 -122.173439) (xy 448.191023 -122.155432) (xy 448.245866 -122.145302) (xy 448.3016 -122.143265)
			(xy 448.357037 -122.149365) (xy 448.410994 -122.163471) (xy 448.462323 -122.185283) (xy 448.509929 -122.214337)
			(xy 448.552797 -122.250012) (xy 448.590014 -122.291549) (xy 448.620787 -122.338062) (xy 448.644459 -122.388559)
			(xy 448.660527 -122.441966) (xy 448.668647 -122.497142) (xy 448.669156 -122.525028) (xy 448.668647 -122.552914)
			(xy 448.660527 -122.60809) (xy 448.644459 -122.661497) (xy 448.620787 -122.711994) (xy 448.590014 -122.758507)
			(xy 448.552797 -122.800044) (xy 448.509929 -122.835719) (xy 448.462323 -122.864773) (xy 448.410994 -122.886585)
			(xy 448.357037 -122.900691) (xy 448.3016 -122.906791) (xy 448.245866 -122.904754) (xy 448.191023 -122.894624)
			(xy 448.138239 -122.876617) (xy 448.088639 -122.851116) (xy 448.043281 -122.818665) (xy 448.003132 -122.779956)
			(xy 447.969046 -122.735813) (xy 447.94175 -122.687178) (xy 447.921827 -122.635087) (xy 447.909701 -122.58065)
			(xy 447.90563 -122.525028) (xy 438.864502 -122.525028) (xy 438.864502 -123.364548) (xy 442.364398 -123.364548)
			(xy 442.364398 -123.310052) (xy 442.372153 -123.25611) (xy 442.387506 -123.20382) (xy 442.410144 -123.154248)
			(xy 442.439605 -123.108401) (xy 442.475292 -123.067214) (xy 442.516476 -123.031525) (xy 442.56232 -123.002059)
			(xy 442.61189 -122.979417) (xy 442.664178 -122.96406) (xy 442.71812 -122.9563) (xy 442.745368 -122.955812)
			(xy 442.772738 -122.956294) (xy 442.826916 -122.964107) (xy 442.879419 -122.979593) (xy 442.929166 -123.002431)
			(xy 442.975134 -123.032152) (xy 442.996066 -123.049792) (xy 442.99632 -123.050046) (xy 443.003393 -123.055653)
			(xy 443.02032 -123.061886) (xy 443.02934 -123.062238) (xy 443.096396 -123.062238) (xy 443.105412 -123.061871)
			(xy 443.122328 -123.055629) (xy 443.129416 -123.050046) (xy 443.129416 -123.049792) (xy 443.12967 -123.049792)
			(xy 443.150603 -123.032151) (xy 443.196571 -123.002427) (xy 443.246317 -122.979581) (xy 443.298819 -122.964085)
			(xy 443.352997 -122.956256) (xy 443.407739 -122.956256) (xy 443.461917 -122.964085) (xy 443.514419 -122.979581)
			(xy 443.564165 -123.002427) (xy 443.610133 -123.032151) (xy 443.631066 -123.049792) (xy 443.63132 -123.050046)
			(xy 443.638393 -123.055653) (xy 443.65532 -123.061886) (xy 443.66434 -123.062238) (xy 443.731396 -123.062238)
			(xy 443.740412 -123.061871) (xy 443.757328 -123.055629) (xy 443.764416 -123.050046) (xy 443.764416 -123.049792)
			(xy 443.76467 -123.049792) (xy 443.785602 -123.032152) (xy 443.831575 -123.002441) (xy 443.881322 -122.979605)
			(xy 443.933823 -122.964114) (xy 443.987999 -122.956286) (xy 444.015368 -122.955812) (xy 444.042624 -122.956233)
			(xy 444.096581 -122.963986) (xy 444.148886 -122.97934) (xy 444.198472 -123.001982) (xy 444.244332 -123.031451)
			(xy 444.285531 -123.067147) (xy 444.32123 -123.108342) (xy 444.350702 -123.154199) (xy 444.373348 -123.203784)
			(xy 444.388707 -123.256088) (xy 444.396465 -123.310044) (xy 444.396465 -123.364556) (xy 444.388707 -123.418512)
			(xy 444.373348 -123.470816) (xy 444.350702 -123.520401) (xy 444.32123 -123.566258) (xy 444.285531 -123.607453)
			(xy 444.244332 -123.643149) (xy 444.198472 -123.672618) (xy 444.148886 -123.69526) (xy 444.096581 -123.710614)
			(xy 444.042624 -123.718367) (xy 444.015368 -123.718828) (xy 443.987996 -123.718398) (xy 443.933815 -123.710574)
			(xy 443.881311 -123.695078) (xy 443.831564 -123.672227) (xy 443.7856 -123.642494) (xy 443.76467 -123.624848)
			(xy 443.764416 -123.624594) (xy 443.75733 -123.619007) (xy 443.740413 -123.612761) (xy 443.731396 -123.612402)
			(xy 443.66434 -123.612402) (xy 443.655325 -123.612778) (xy 443.638408 -123.619012) (xy 443.63132 -123.624594)
			(xy 443.631066 -123.624848) (xy 443.610133 -123.642489) (xy 443.564165 -123.672213) (xy 443.514419 -123.695059)
			(xy 443.461917 -123.710555) (xy 443.407739 -123.718384) (xy 443.352997 -123.718384) (xy 443.298819 -123.710555)
			(xy 443.246317 -123.695059) (xy 443.196571 -123.672213) (xy 443.150603 -123.642489) (xy 443.12967 -123.624848)
			(xy 443.129416 -123.624594) (xy 443.12233 -123.619007) (xy 443.105413 -123.612761) (xy 443.096396 -123.612402)
			(xy 443.02934 -123.612402) (xy 443.020325 -123.612778) (xy 443.003408 -123.619012) (xy 442.99632 -123.624594)
			(xy 442.99632 -123.624848) (xy 442.996066 -123.624848) (xy 442.975113 -123.642462) (xy 442.929147 -123.672179)
			(xy 442.879405 -123.695021) (xy 442.826908 -123.710518) (xy 442.772736 -123.718351) (xy 442.745368 -123.718828)
			(xy 442.71812 -123.7183) (xy 442.664178 -123.71054) (xy 442.61189 -123.695183) (xy 442.56232 -123.672541)
			(xy 442.516476 -123.643075) (xy 442.475292 -123.607386) (xy 442.439605 -123.566199) (xy 442.410144 -123.520352)
			(xy 442.387506 -123.47078) (xy 442.372153 -123.41849) (xy 442.364398 -123.364548) (xy 438.864502 -123.364548)
			(xy 438.864502 -124.47778) (xy 440.71286 -124.47778) (xy 440.7133 -124.450409) (xy 440.721122 -124.396228)
			(xy 440.736616 -124.343724) (xy 440.759464 -124.293977) (xy 440.789195 -124.248012) (xy 440.80684 -124.227082)
			(xy 440.807094 -124.226828) (xy 440.812674 -124.219737) (xy 440.818925 -124.202824) (xy 440.819286 -124.193808)
			(xy 440.819286 -124.126752) (xy 440.818907 -124.117737) (xy 440.812675 -124.10082) (xy 440.807094 -124.093732)
			(xy 440.80684 -124.093732) (xy 440.80684 -124.093478) (xy 440.78923 -124.072522) (xy 440.759513 -124.026557)
			(xy 440.73667 -123.976815) (xy 440.721173 -123.924319) (xy 440.713337 -123.870148) (xy 440.71286 -123.84278)
			(xy 440.713346 -123.815529) (xy 440.721102 -123.761581) (xy 440.736457 -123.709286) (xy 440.759099 -123.659709)
			(xy 440.788565 -123.613859) (xy 440.824256 -123.572668) (xy 440.865447 -123.536977) (xy 440.911297 -123.507511)
			(xy 440.960874 -123.484869) (xy 441.013169 -123.469514) (xy 441.067117 -123.461758) (xy 441.121619 -123.461758)
			(xy 441.175567 -123.469514) (xy 441.227862 -123.484869) (xy 441.277439 -123.507511) (xy 441.323289 -123.536977)
			(xy 441.36448 -123.572668) (xy 441.400171 -123.613859) (xy 441.429637 -123.659709) (xy 441.452279 -123.709286)
			(xy 441.467634 -123.761581) (xy 441.472443 -123.795028) (xy 445.741296 -123.795028) (xy 445.745367 -123.739406)
			(xy 445.757493 -123.684969) (xy 445.777416 -123.632878) (xy 445.804712 -123.584243) (xy 445.838798 -123.5401)
			(xy 445.878947 -123.501391) (xy 445.924305 -123.46894) (xy 445.973905 -123.443439) (xy 446.026689 -123.425432)
			(xy 446.081532 -123.415302) (xy 446.137266 -123.413265) (xy 446.192703 -123.419365) (xy 446.24666 -123.433471)
			(xy 446.297989 -123.455283) (xy 446.345595 -123.484337) (xy 446.388463 -123.520012) (xy 446.42568 -123.561549)
			(xy 446.456453 -123.608062) (xy 446.480125 -123.658559) (xy 446.496193 -123.711966) (xy 446.504313 -123.767142)
			(xy 446.504822 -123.795028) (xy 447.949064 -123.795028) (xy 447.953135 -123.739406) (xy 447.965261 -123.684969)
			(xy 447.985184 -123.632878) (xy 448.01248 -123.584243) (xy 448.046566 -123.5401) (xy 448.086715 -123.501391)
			(xy 448.132073 -123.46894) (xy 448.181673 -123.443439) (xy 448.234457 -123.425432) (xy 448.2893 -123.415302)
			(xy 448.345034 -123.413265) (xy 448.400471 -123.419365) (xy 448.454428 -123.433471) (xy 448.505757 -123.455283)
			(xy 448.553363 -123.484337) (xy 448.596231 -123.520012) (xy 448.633448 -123.561549) (xy 448.664221 -123.608062)
			(xy 448.687893 -123.658559) (xy 448.703961 -123.711966) (xy 448.712081 -123.767142) (xy 448.71259 -123.795028)
			(xy 448.712081 -123.822914) (xy 448.703961 -123.87809) (xy 448.687893 -123.931497) (xy 448.664221 -123.981994)
			(xy 448.633448 -124.028507) (xy 448.596231 -124.070044) (xy 448.553363 -124.105719) (xy 448.505757 -124.134773)
			(xy 448.454428 -124.156585) (xy 448.400471 -124.170691) (xy 448.345034 -124.176791) (xy 448.2893 -124.174754)
			(xy 448.234457 -124.164624) (xy 448.181673 -124.146617) (xy 448.132073 -124.121116) (xy 448.086715 -124.088665)
			(xy 448.046566 -124.049956) (xy 448.01248 -124.005813) (xy 447.985184 -123.957178) (xy 447.965261 -123.905087)
			(xy 447.953135 -123.85065) (xy 447.949064 -123.795028) (xy 446.504822 -123.795028) (xy 446.504313 -123.822914)
			(xy 446.496193 -123.87809) (xy 446.480125 -123.931497) (xy 446.456453 -123.981994) (xy 446.42568 -124.028507)
			(xy 446.388463 -124.070044) (xy 446.345595 -124.105719) (xy 446.297989 -124.134773) (xy 446.24666 -124.156585)
			(xy 446.192703 -124.170691) (xy 446.137266 -124.176791) (xy 446.081532 -124.174754) (xy 446.026689 -124.164624)
			(xy 445.973905 -124.146617) (xy 445.924305 -124.121116) (xy 445.878947 -124.088665) (xy 445.838798 -124.049956)
			(xy 445.804712 -124.005813) (xy 445.777416 -123.957178) (xy 445.757493 -123.905087) (xy 445.745367 -123.85065)
			(xy 445.741296 -123.795028) (xy 441.472443 -123.795028) (xy 441.47539 -123.815529) (xy 441.475876 -123.84278)
			(xy 441.475404 -123.87015) (xy 441.467589 -123.924329) (xy 441.452101 -123.976832) (xy 441.429261 -124.026579)
			(xy 441.399537 -124.072546) (xy 441.381896 -124.093478) (xy 441.381642 -124.093732) (xy 441.376071 -124.100829)
			(xy 441.369816 -124.117738) (xy 441.36945 -124.126752) (xy 441.36945 -124.193808) (xy 441.369793 -124.202827)
			(xy 441.374348 -124.215144) (xy 442.906656 -124.215144) (xy 442.910727 -124.159522) (xy 442.922853 -124.105085)
			(xy 442.942776 -124.052994) (xy 442.970072 -124.004359) (xy 443.004158 -123.960216) (xy 443.044307 -123.921507)
			(xy 443.089665 -123.889056) (xy 443.139265 -123.863555) (xy 443.192049 -123.845548) (xy 443.246892 -123.835418)
			(xy 443.302626 -123.833381) (xy 443.358063 -123.839481) (xy 443.41202 -123.853587) (xy 443.463349 -123.875399)
			(xy 443.510955 -123.904453) (xy 443.553823 -123.940128) (xy 443.59104 -123.981665) (xy 443.621813 -124.028178)
			(xy 443.645485 -124.078675) (xy 443.661553 -124.132082) (xy 443.669673 -124.187258) (xy 443.670182 -124.215144)
			(xy 443.669673 -124.24303) (xy 443.661553 -124.298206) (xy 443.645485 -124.351613) (xy 443.621813 -124.40211)
			(xy 443.59104 -124.448623) (xy 443.553823 -124.49016) (xy 443.510955 -124.525835) (xy 443.463349 -124.554889)
			(xy 443.41202 -124.576701) (xy 443.358063 -124.590807) (xy 443.302626 -124.596907) (xy 443.246892 -124.59487)
			(xy 443.192049 -124.58474) (xy 443.139265 -124.566733) (xy 443.089665 -124.541232) (xy 443.044307 -124.508781)
			(xy 443.004158 -124.470072) (xy 442.970072 -124.425929) (xy 442.942776 -124.377294) (xy 442.922853 -124.325203)
			(xy 442.910727 -124.270766) (xy 442.906656 -124.215144) (xy 441.374348 -124.215144) (xy 441.376049 -124.219744)
			(xy 441.381642 -124.226828) (xy 441.381896 -124.226828) (xy 441.381896 -124.227082) (xy 441.399539 -124.248011)
			(xy 441.429251 -124.293984) (xy 441.452086 -124.343733) (xy 441.467576 -124.396234) (xy 441.475403 -124.450411)
			(xy 441.475876 -124.47778) (xy 441.47539 -124.505031) (xy 441.467634 -124.558979) (xy 441.452279 -124.611274)
			(xy 441.438888 -124.640594) (xy 449.232272 -124.640594) (xy 449.236343 -124.584972) (xy 449.248469 -124.530535)
			(xy 449.268392 -124.478444) (xy 449.295688 -124.429809) (xy 449.329774 -124.385666) (xy 449.369923 -124.346957)
			(xy 449.415281 -124.314506) (xy 449.464881 -124.289005) (xy 449.517665 -124.270998) (xy 449.572508 -124.260868)
			(xy 449.628242 -124.258831) (xy 449.683679 -124.264931) (xy 449.737636 -124.279037) (xy 449.788965 -124.300849)
			(xy 449.836571 -124.329903) (xy 449.879439 -124.365578) (xy 449.916656 -124.407115) (xy 449.947429 -124.453628)
			(xy 449.971101 -124.504125) (xy 449.987169 -124.557532) (xy 449.995289 -124.612708) (xy 449.995798 -124.640594)
			(xy 449.995289 -124.66848) (xy 449.987169 -124.723656) (xy 449.971101 -124.777063) (xy 449.947429 -124.82756)
			(xy 449.916656 -124.874073) (xy 449.879439 -124.91561) (xy 449.836571 -124.951285) (xy 449.788965 -124.980339)
			(xy 449.737636 -125.002151) (xy 449.683679 -125.016257) (xy 449.628242 -125.022357) (xy 449.572508 -125.02032)
			(xy 449.517665 -125.01019) (xy 449.464881 -124.992183) (xy 449.415281 -124.966682) (xy 449.369923 -124.934231)
			(xy 449.329774 -124.895522) (xy 449.295688 -124.851379) (xy 449.268392 -124.802744) (xy 449.248469 -124.750653)
			(xy 449.236343 -124.696216) (xy 449.232272 -124.640594) (xy 441.438888 -124.640594) (xy 441.429637 -124.660851)
			(xy 441.400171 -124.706701) (xy 441.36448 -124.747892) (xy 441.323289 -124.783583) (xy 441.277439 -124.813049)
			(xy 441.227862 -124.835691) (xy 441.175567 -124.851046) (xy 441.121619 -124.858802) (xy 441.067117 -124.858802)
			(xy 441.013169 -124.851046) (xy 440.960874 -124.835691) (xy 440.911297 -124.813049) (xy 440.865447 -124.783583)
			(xy 440.824256 -124.747892) (xy 440.788565 -124.706701) (xy 440.759099 -124.660851) (xy 440.736457 -124.611274)
			(xy 440.721102 -124.558979) (xy 440.713346 -124.505031) (xy 440.71286 -124.47778) (xy 438.864502 -124.47778)
			(xy 438.864502 -124.481336) (xy 438.86495 -124.491492) (xy 438.872808 -124.510224) (xy 438.879742 -124.517658)
			(xy 438.916064 -124.553472) (xy 438.921652 -124.553472) (xy 438.94902 -124.553948) (xy 439.003194 -124.561779)
			(xy 439.055692 -124.577274) (xy 439.105435 -124.600115) (xy 439.151403 -124.629831) (xy 439.17235 -124.647452)
			(xy 439.172604 -124.647452) (xy 439.172604 -124.647706) (xy 439.179691 -124.65329) (xy 439.196608 -124.65953)
			(xy 439.205624 -124.659898) (xy 439.27268 -124.659898) (xy 439.281698 -124.659542) (xy 439.298618 -124.653299)
			(xy 439.3057 -124.647706) (xy 439.305954 -124.647452) (xy 439.326885 -124.629811) (xy 439.372852 -124.600087)
			(xy 439.422599 -124.577248) (xy 439.475103 -124.561763) (xy 439.529282 -124.553951) (xy 439.556652 -124.553472)
			(xy 439.583908 -124.553932) (xy 439.637865 -124.561683) (xy 439.69017 -124.577035) (xy 439.739757 -124.599674)
			(xy 439.785618 -124.62914) (xy 439.826818 -124.664834) (xy 439.862519 -124.706028) (xy 439.891993 -124.751883)
			(xy 439.914642 -124.801466) (xy 439.930003 -124.853769) (xy 439.937764 -124.907724) (xy 439.93816 -124.93498)
			(xy 439.937398 -124.959872) (xy 439.936636 -124.97308) (xy 439.947558 -124.996448) (xy 440.038744 -125.062488)
			(xy 440.064398 -125.065536) (xy 440.07659 -125.06071) (xy 440.099357 -125.051946) (xy 440.146558 -125.039616)
			(xy 440.194946 -125.033403) (xy 440.219338 -125.033024) (xy 440.246587 -125.033513) (xy 440.300528 -125.041274)
			(xy 440.352817 -125.056633) (xy 440.402387 -125.079276) (xy 440.44823 -125.108744) (xy 440.489413 -125.144436)
			(xy 440.525098 -125.185626) (xy 440.554557 -125.231474) (xy 440.577192 -125.281049) (xy 440.592541 -125.33334)
			(xy 440.600292 -125.387283) (xy 440.600846 -125.414532) (xy 440.600372 -125.441901) (xy 440.592543 -125.496076)
			(xy 440.577051 -125.548576) (xy 440.554213 -125.598322) (xy 440.524499 -125.644293) (xy 440.506866 -125.66523)
			(xy 440.506866 -125.665484) (xy 440.506612 -125.665484) (xy 440.501023 -125.67257) (xy 440.494774 -125.689487)
			(xy 440.49442 -125.698504) (xy 440.49442 -125.76556) (xy 440.494773 -125.774579) (xy 440.501012 -125.791502)
			(xy 440.506612 -125.79858) (xy 440.506866 -125.798834) (xy 440.524507 -125.819765) (xy 440.554232 -125.865732)
			(xy 440.566083 -125.891544) (xy 443.47511 -125.891544) (xy 443.475537 -125.865229) (xy 443.48278 -125.813098)
			(xy 443.497106 -125.762455) (xy 443.518246 -125.714256) (xy 443.5458 -125.669413) (xy 443.579245 -125.628775)
			(xy 443.5983 -125.61062) (xy 443.605695 -125.603093) (xy 443.614223 -125.583817) (xy 443.61481 -125.573282)
			(xy 443.61481 -125.498606) (xy 443.614288 -125.488056) (xy 443.605748 -125.46876) (xy 443.5983 -125.461268)
			(xy 443.579236 -125.443121) (xy 443.54578 -125.402489) (xy 443.518222 -125.357647) (xy 443.497085 -125.309445)
			(xy 443.482769 -125.258796) (xy 443.475547 -125.206661) (xy 443.47511 -125.180344) (xy 443.475596 -125.153093)
			(xy 443.483352 -125.099145) (xy 443.498707 -125.04685) (xy 443.521349 -124.997273) (xy 443.550815 -124.951423)
			(xy 443.586506 -124.910232) (xy 443.627697 -124.874541) (xy 443.673547 -124.845075) (xy 443.723124 -124.822433)
			(xy 443.775419 -124.807078) (xy 443.829367 -124.799322) (xy 443.883869 -124.799322) (xy 443.937817 -124.807078)
			(xy 443.990112 -124.822433) (xy 444.039689 -124.845075) (xy 444.085539 -124.874541) (xy 444.12673 -124.910232)
			(xy 444.162421 -124.951423) (xy 444.191887 -124.997273) (xy 444.214529 -125.04685) (xy 444.229884 -125.099145)
			(xy 444.23764 -125.153093) (xy 444.238126 -125.180344) (xy 444.23768 -125.206659) (xy 444.230439 -125.258788)
			(xy 444.216115 -125.30943) (xy 444.194979 -125.357629) (xy 444.16743 -125.402472) (xy 444.133989 -125.443111)
			(xy 444.114936 -125.461268) (xy 444.107552 -125.468804) (xy 444.099016 -125.488073) (xy 444.098426 -125.498606)
			(xy 444.098426 -125.573282) (xy 444.098944 -125.583833) (xy 444.107486 -125.603129) (xy 444.114936 -125.61062)
			(xy 444.134001 -125.628766) (xy 444.167456 -125.669398) (xy 444.195013 -125.714241) (xy 444.216149 -125.762444)
			(xy 444.230465 -125.813092) (xy 444.237688 -125.865227) (xy 444.238126 -125.891544) (xy 444.23764 -125.918795)
			(xy 444.229884 -125.972743) (xy 444.214529 -126.025038) (xy 444.191887 -126.074615) (xy 444.162421 -126.120465)
			(xy 444.12673 -126.161656) (xy 444.085539 -126.197347) (xy 444.039689 -126.226813) (xy 443.990112 -126.249455)
			(xy 443.937817 -126.26481) (xy 443.883869 -126.272566) (xy 443.829367 -126.272566) (xy 443.775419 -126.26481)
			(xy 443.723124 -126.249455) (xy 443.673547 -126.226813) (xy 443.627697 -126.197347) (xy 443.586506 -126.161656)
			(xy 443.550815 -126.120465) (xy 443.521349 -126.074615) (xy 443.498707 -126.025038) (xy 443.483352 -125.972743)
			(xy 443.475596 -125.918795) (xy 443.47511 -125.891544) (xy 440.566083 -125.891544) (xy 440.577073 -125.915479)
			(xy 440.59256 -125.967982) (xy 440.600374 -126.022162) (xy 440.600846 -126.049532) (xy 440.60036 -126.076783)
			(xy 440.592604 -126.130731) (xy 440.577249 -126.183026) (xy 440.554607 -126.232603) (xy 440.525141 -126.278453)
			(xy 440.48945 -126.319644) (xy 440.448259 -126.355335) (xy 440.402409 -126.384801) (xy 440.352832 -126.407443)
			(xy 440.300537 -126.422798) (xy 440.246589 -126.430554) (xy 440.192087 -126.430554) (xy 440.138139 -126.422798)
			(xy 440.085844 -126.407443) (xy 440.036267 -126.384801) (xy 439.990417 -126.355335) (xy 439.949226 -126.319644)
			(xy 439.913535 -126.278453) (xy 439.884069 -126.232603) (xy 439.861427 -126.183026) (xy 439.846072 -126.130731)
			(xy 439.838316 -126.076783) (xy 439.83783 -126.049532) (xy 439.838307 -126.022164) (xy 439.84614 -125.967991)
			(xy 439.861635 -125.915493) (xy 439.884475 -125.86575) (xy 439.91419 -125.819781) (xy 439.93181 -125.798834)
			(xy 439.93181 -125.79858) (xy 439.932064 -125.79858) (xy 439.93765 -125.791494) (xy 439.943889 -125.774576)
			(xy 439.944256 -125.76556) (xy 439.944256 -125.698504) (xy 439.943898 -125.689486) (xy 439.937658 -125.672565)
			(xy 439.932064 -125.665484) (xy 439.93181 -125.66523) (xy 439.914166 -125.644299) (xy 439.884435 -125.598334)
			(xy 439.861588 -125.548587) (xy 439.846093 -125.496084) (xy 439.83827 -125.441903) (xy 439.83783 -125.414532)
			(xy 439.838592 -125.38964) (xy 439.839354 -125.376432) (xy 439.828432 -125.353064) (xy 439.737246 -125.287024)
			(xy 439.711592 -125.283976) (xy 439.6994 -125.288802) (xy 439.676633 -125.297565) (xy 439.629432 -125.309893)
			(xy 439.581044 -125.316105) (xy 439.556652 -125.316488) (xy 439.529283 -125.316013) (xy 439.475109 -125.308183)
			(xy 439.422609 -125.29269) (xy 439.372863 -125.269853) (xy 439.326892 -125.24014) (xy 439.305954 -125.222508)
			(xy 439.3057 -125.222508) (xy 439.3057 -125.222254) (xy 439.298611 -125.216673) (xy 439.281695 -125.210437)
			(xy 439.27268 -125.210062) (xy 439.205624 -125.210062) (xy 439.196605 -125.210417) (xy 439.179681 -125.216654)
			(xy 439.172604 -125.222254) (xy 439.17235 -125.222508) (xy 439.151418 -125.240147) (xy 439.10545 -125.269866)
			(xy 439.055702 -125.292702) (xy 439.003199 -125.308185) (xy 438.949021 -125.315997) (xy 438.921652 -125.316488)
			(xy 438.916064 -125.316488) (xy 438.879742 -125.352302) (xy 438.872791 -125.359726) (xy 438.864928 -125.378463)
			(xy 438.864502 -125.388624) (xy 438.864502 -132.658104) (xy 438.864926 -132.668174) (xy 438.872642 -132.686777)
			(xy 438.879488 -132.694172) (xy 440.95543 -134.770114) (xy 440.962826 -134.776965) (xy 440.981425 -134.784702)
			(xy 440.991498 -134.7851) (xy 461.918304 -134.7851) (xy 461.928374 -134.784676) (xy 461.946977 -134.776961)
			(xy 461.954372 -134.770114) (xy 462.495646 -134.22884) (xy 462.502489 -134.221441) (xy 462.51021 -134.202842)
			(xy 462.510632 -134.192772) (xy 462.510632 -85.509354) (xy 462.511064 -85.499288) (xy 462.518794 -85.480699)
			(xy 462.525618 -85.473286) (xy 466.071712 -81.927192) (xy 466.076701 -81.921694) (xy 466.083548 -81.908528)
			(xy 466.085174 -81.901284) (xy 466.08619 -81.891632) (xy 466.08619 -34.886392) (xy 466.086028 -34.880381)
			(xy 466.083212 -34.868695) (xy 466.080602 -34.863278) (xy 466.078762 -34.859804) (xy 466.074169 -34.853425)
			(xy 466.071458 -34.850578) (xy 464.371944 -33.151064) (xy 464.369095 -33.148355) (xy 464.362721 -33.143755)
			(xy 464.359244 -33.14192) (xy 464.353817 -33.139337) (xy 464.342137 -33.136515) (xy 464.33613 -33.136332)
			(xy 450.790056 -33.136332) (xy 450.784046 -33.136499) (xy 450.772364 -33.139323) (xy 450.766942 -33.14192)
			(xy 450.763466 -33.143757) (xy 450.757083 -33.148346) (xy 450.754242 -33.151064) (xy 450.10197 -33.803336)
			(xy 450.095295 -33.810749) (xy 450.08773 -33.829185) (xy 450.087238 -33.83915) (xy 450.080888 -33.8455)
			(xy 450.073489 -33.852344) (xy 450.054891 -33.860074) (xy 450.04482 -33.860486) (xy 448.756024 -33.860486)
			(xy 448.745999 -33.860901) (xy 448.727471 -33.868566) (xy 448.713288 -33.882739) (xy 448.705609 -33.901261)
			(xy 448.705224 -33.911286) (xy 448.705224 -34.24174) (xy 448.705835 -34.252117) (xy 448.714238 -34.27111)
			(xy 448.72148 -34.27857) (xy 448.781932 -34.330132) (xy 448.786114 -34.333531) (xy 448.795594 -34.338654)
			(xy 448.800728 -34.340292) (xy 448.811142 -34.34334) (xy 448.822318 -34.341562) (xy 448.837144 -34.339387)
			(xy 448.867024 -34.337095) (xy 448.882008 -34.33699) (xy 448.882262 -34.33699) (xy 448.909464 -34.337548)
			(xy 448.963297 -34.345427) (xy 449.015464 -34.360874) (xy 449.064908 -34.383575) (xy 449.110626 -34.413071)
			(xy 449.151689 -34.448761) (xy 449.187266 -34.489924) (xy 449.216634 -34.535723) (xy 449.239198 -34.58523)
			(xy 449.2545 -34.63744) (xy 449.262229 -34.691295) (xy 449.262754 -34.718498) (xy 449.262268 -34.745751)
			(xy 449.254512 -34.799701) (xy 449.239158 -34.851999) (xy 449.216517 -34.901579) (xy 449.187052 -34.947433)
			(xy 449.151361 -34.988627) (xy 449.110171 -35.024323) (xy 449.064321 -35.053794) (xy 449.014744 -35.076441)
			(xy 448.962448 -35.091802) (xy 448.908498 -35.099565) (xy 448.881246 -35.100006) (xy 448.880992 -35.100006)
			(xy 448.851488 -35.099447) (xy 448.793185 -35.09035) (xy 448.736977 -35.072389) (xy 448.684203 -35.045992)
			(xy 448.636119 -35.011787) (xy 448.593872 -34.970591) (xy 448.575684 -34.947352) (xy 448.570604 -34.94024)
			(xy 448.548252 -34.925508) (xy 448.54433 -34.922976) (xy 448.535766 -34.919263) (xy 448.531234 -34.918142)
			(xy 448.509644 -34.913316) (xy 448.500632 -34.911716) (xy 448.482528 -34.914311) (xy 448.474338 -34.918396)
			(xy 448.47383 -34.91865) (xy 448.455449 -34.928877) (xy 448.417162 -34.946306) (xy 448.397376 -34.953448)
			(xy 448.373176 -34.961492) (xy 448.323442 -34.972787) (xy 448.272762 -34.978489) (xy 448.247262 -34.978848)
			(xy 448.221762 -34.978485) (xy 448.171082 -34.972787) (xy 448.12135 -34.961489) (xy 448.097148 -34.953448)
			(xy 448.077364 -34.946302) (xy 448.039077 -34.928874) (xy 448.020694 -34.91865) (xy 448.020186 -34.918396)
			(xy 448.011987 -34.914329) (xy 447.993888 -34.911708) (xy 447.98488 -34.913316) (xy 447.96329 -34.918142)
			(xy 447.958768 -34.919293) (xy 447.950204 -34.922995) (xy 447.946272 -34.925508) (xy 447.92392 -34.94024)
			(xy 447.91884 -34.947352) (xy 447.900689 -34.970651) (xy 447.858409 -35.011888) (xy 447.810277 -35.046113)
			(xy 447.757444 -35.072508) (xy 447.701172 -35.09044) (xy 447.642808 -35.099482) (xy 447.613278 -35.100006)
			(xy 447.602356 -35.100006) (xy 447.602102 -35.099752) (xy 447.575385 -35.098518) (xy 447.522668 -35.0895)
			(xy 447.471726 -35.073209) (xy 447.423558 -35.049965) (xy 447.379108 -35.020223) (xy 447.339245 -34.984566)
			(xy 447.304752 -34.943692) (xy 447.276304 -34.898403) (xy 447.254458 -34.849585) (xy 447.239642 -34.798195)
			(xy 447.232147 -34.745239) (xy 447.23177 -34.718498) (xy 447.232256 -34.691246) (xy 447.240013 -34.637298)
			(xy 447.255368 -34.585002) (xy 447.278009 -34.535423) (xy 447.307475 -34.489572) (xy 447.343166 -34.44838)
			(xy 447.384356 -34.412687) (xy 447.430206 -34.383218) (xy 447.479783 -34.360575) (xy 447.532078 -34.345217)
			(xy 447.586026 -34.337457) (xy 447.613278 -34.33699) (xy 447.628071 -34.337135) (xy 447.657567 -34.339427)
			(xy 447.672206 -34.341562) (xy 447.683382 -34.34334) (xy 447.693796 -34.340292) (xy 447.698927 -34.338648)
			(xy 447.708398 -34.333515) (xy 447.712592 -34.330132) (xy 447.773044 -34.27857) (xy 447.780334 -34.271148)
			(xy 447.788711 -34.252128) (xy 447.7893 -34.24174) (xy 447.7893 -33.911286) (xy 447.788809 -33.90128)
			(xy 447.781147 -33.882793) (xy 447.766995 -33.868645) (xy 447.748506 -33.860988) (xy 447.7385 -33.860486)
			(xy 434.018944 -33.860486) (xy 434.008916 -33.860898) (xy 433.990382 -33.868559) (xy 433.976192 -33.882733)
			(xy 433.968509 -33.901258) (xy 433.968144 -33.911286) (xy 433.968144 -34.522156) (xy 433.968144 -34.522664)
			(xy 433.96789 -34.54146) (xy 433.96789 -34.541968) (xy 433.968037 -34.553197) (xy 433.976745 -34.57387)
			(xy 433.984654 -34.581846) (xy 433.992274 -34.58845) (xy 434.0098 -34.603436) (xy 434.018815 -34.610338)
			(xy 434.040699 -34.616276) (xy 434.051964 -34.614866) (xy 434.068774 -34.612023) (xy 434.102734 -34.608972)
			(xy 434.119782 -34.60877) (xy 434.122068 -34.60877) (xy 434.149223 -34.609396) (xy 434.202948 -34.617391)
			(xy 434.254997 -34.632924) (xy 434.304316 -34.655682) (xy 434.349909 -34.685204) (xy 434.390854 -34.720894)
			(xy 434.426324 -34.76203) (xy 434.455602 -34.807781) (xy 434.478095 -34.857222) (xy 434.493349 -34.909352)
			(xy 434.501055 -34.96312) (xy 434.501539 -34.990024) (xy 435.566818 -34.990024) (xy 435.570889 -34.934402)
			(xy 435.583015 -34.879965) (xy 435.602938 -34.827874) (xy 435.630234 -34.779239) (xy 435.66432 -34.735096)
			(xy 435.704469 -34.696387) (xy 435.749827 -34.663936) (xy 435.799427 -34.638435) (xy 435.852211 -34.620428)
			(xy 435.907054 -34.610298) (xy 435.962788 -34.608261) (xy 436.018225 -34.614361) (xy 436.072182 -34.628467)
			(xy 436.123511 -34.650279) (xy 436.171117 -34.679333) (xy 436.213985 -34.715008) (xy 436.251202 -34.756545)
			(xy 436.281975 -34.803058) (xy 436.305647 -34.853555) (xy 436.321715 -34.906962) (xy 436.329835 -34.962138)
			(xy 436.330344 -34.990024) (xy 437.972706 -34.990024) (xy 437.976777 -34.934402) (xy 437.988903 -34.879965)
			(xy 438.008826 -34.827874) (xy 438.036122 -34.779239) (xy 438.070208 -34.735096) (xy 438.110357 -34.696387)
			(xy 438.155715 -34.663936) (xy 438.205315 -34.638435) (xy 438.258099 -34.620428) (xy 438.312942 -34.610298)
			(xy 438.368676 -34.608261) (xy 438.424113 -34.614361) (xy 438.47807 -34.628467) (xy 438.529399 -34.650279)
			(xy 438.577005 -34.679333) (xy 438.619873 -34.715008) (xy 438.65709 -34.756545) (xy 438.687863 -34.803058)
			(xy 438.711535 -34.853555) (xy 438.727603 -34.906962) (xy 438.735723 -34.962138) (xy 438.736232 -34.990024)
			(xy 439.20232 -34.990024) (xy 439.206391 -34.934402) (xy 439.218517 -34.879965) (xy 439.23844 -34.827874)
			(xy 439.265736 -34.779239) (xy 439.299822 -34.735096) (xy 439.339971 -34.696387) (xy 439.385329 -34.663936)
			(xy 439.434929 -34.638435) (xy 439.487713 -34.620428) (xy 439.542556 -34.610298) (xy 439.59829 -34.608261)
			(xy 439.653727 -34.614361) (xy 439.707684 -34.628467) (xy 439.759013 -34.650279) (xy 439.806619 -34.679333)
			(xy 439.849487 -34.715008) (xy 439.886704 -34.756545) (xy 439.917477 -34.803058) (xy 439.941149 -34.853555)
			(xy 439.957217 -34.906962) (xy 439.965337 -34.962138) (xy 439.965846 -34.990024) (xy 442.198758 -34.990024)
			(xy 442.202829 -34.934402) (xy 442.214955 -34.879965) (xy 442.234878 -34.827874) (xy 442.262174 -34.779239)
			(xy 442.29626 -34.735096) (xy 442.336409 -34.696387) (xy 442.381767 -34.663936) (xy 442.431367 -34.638435)
			(xy 442.484151 -34.620428) (xy 442.538994 -34.610298) (xy 442.594728 -34.608261) (xy 442.650165 -34.614361)
			(xy 442.704122 -34.628467) (xy 442.755451 -34.650279) (xy 442.803057 -34.679333) (xy 442.845925 -34.715008)
			(xy 442.883142 -34.756545) (xy 442.913915 -34.803058) (xy 442.937587 -34.853555) (xy 442.953655 -34.906962)
			(xy 442.961775 -34.962138) (xy 442.962284 -34.990024) (xy 442.961775 -35.01791) (xy 442.953655 -35.073086)
			(xy 442.937587 -35.126493) (xy 442.913915 -35.17699) (xy 442.883142 -35.223503) (xy 442.845925 -35.26504)
			(xy 442.803057 -35.300715) (xy 442.755451 -35.329769) (xy 442.704122 -35.351581) (xy 442.650165 -35.365687)
			(xy 442.594728 -35.371787) (xy 442.538994 -35.36975) (xy 442.484151 -35.35962) (xy 442.431367 -35.341613)
			(xy 442.381767 -35.316112) (xy 442.336409 -35.283661) (xy 442.29626 -35.244952) (xy 442.262174 -35.200809)
			(xy 442.234878 -35.152174) (xy 442.214955 -35.100083) (xy 442.202829 -35.045646) (xy 442.198758 -34.990024)
			(xy 439.965846 -34.990024) (xy 439.965337 -35.01791) (xy 439.957217 -35.073086) (xy 439.941149 -35.126493)
			(xy 439.917477 -35.17699) (xy 439.886704 -35.223503) (xy 439.849487 -35.26504) (xy 439.806619 -35.300715)
			(xy 439.759013 -35.329769) (xy 439.707684 -35.351581) (xy 439.653727 -35.365687) (xy 439.59829 -35.371787)
			(xy 439.542556 -35.36975) (xy 439.487713 -35.35962) (xy 439.434929 -35.341613) (xy 439.385329 -35.316112)
			(xy 439.339971 -35.283661) (xy 439.299822 -35.244952) (xy 439.265736 -35.200809) (xy 439.23844 -35.152174)
			(xy 439.218517 -35.100083) (xy 439.206391 -35.045646) (xy 439.20232 -34.990024) (xy 438.736232 -34.990024)
			(xy 438.735723 -35.01791) (xy 438.727603 -35.073086) (xy 438.711535 -35.126493) (xy 438.687863 -35.17699)
			(xy 438.65709 -35.223503) (xy 438.619873 -35.26504) (xy 438.577005 -35.300715) (xy 438.529399 -35.329769)
			(xy 438.47807 -35.351581) (xy 438.424113 -35.365687) (xy 438.368676 -35.371787) (xy 438.312942 -35.36975)
			(xy 438.258099 -35.35962) (xy 438.205315 -35.341613) (xy 438.155715 -35.316112) (xy 438.110357 -35.283661)
			(xy 438.070208 -35.244952) (xy 438.036122 -35.200809) (xy 438.008826 -35.152174) (xy 437.988903 -35.100083)
			(xy 437.976777 -35.045646) (xy 437.972706 -34.990024) (xy 436.330344 -34.990024) (xy 436.329835 -35.01791)
			(xy 436.321715 -35.073086) (xy 436.305647 -35.126493) (xy 436.281975 -35.17699) (xy 436.251202 -35.223503)
			(xy 436.213985 -35.26504) (xy 436.171117 -35.300715) (xy 436.123511 -35.329769) (xy 436.072182 -35.351581)
			(xy 436.018225 -35.365687) (xy 435.962788 -35.371787) (xy 435.907054 -35.36975) (xy 435.852211 -35.35962)
			(xy 435.799427 -35.341613) (xy 435.749827 -35.316112) (xy 435.704469 -35.283661) (xy 435.66432 -35.244952)
			(xy 435.630234 -35.200809) (xy 435.602938 -35.152174) (xy 435.583015 -35.100083) (xy 435.570889 -35.045646)
			(xy 435.566818 -34.990024) (xy 434.501539 -34.990024) (xy 434.501544 -34.990278) (xy 434.50106 -35.017531)
			(xy 434.493306 -35.071483) (xy 434.477953 -35.123783) (xy 434.455314 -35.173365) (xy 434.425849 -35.219221)
			(xy 434.390158 -35.260417) (xy 434.348967 -35.296114) (xy 434.303116 -35.325586) (xy 434.253537 -35.348233)
			(xy 434.20124 -35.363594) (xy 434.147289 -35.371356) (xy 434.120036 -35.371786) (xy 434.093074 -35.371322)
			(xy 434.039687 -35.36373) (xy 433.987903 -35.348691) (xy 433.938754 -35.326507) (xy 433.893221 -35.297618)
			(xy 433.852212 -35.262603) (xy 433.816546 -35.222159) (xy 433.786933 -35.177094) (xy 433.763966 -35.128305)
			(xy 433.748102 -35.076768) (xy 433.743354 -35.050222) (xy 433.742084 -35.042856) (xy 433.741576 -35.0393)
			(xy 433.735734 -35.03041) (xy 433.732844 -35.026191) (xy 433.725675 -35.0189) (xy 433.72151 -35.015932)
			(xy 433.658772 -34.974276) (xy 433.654276 -34.971444) (xy 433.644417 -34.967482) (xy 433.639214 -34.966402)
			(xy 433.629308 -34.964624) (xy 433.618894 -34.967164) (xy 433.5922 -34.97331) (xy 433.537824 -34.979937)
			(xy 433.510436 -34.980372) (xy 433.483048 -34.979927) (xy 433.428672 -34.973308) (xy 433.401978 -34.967164)
			(xy 433.391564 -34.964624) (xy 433.381658 -34.966402) (xy 433.376438 -34.967425) (xy 433.366569 -34.97139)
			(xy 433.3621 -34.974276) (xy 433.299362 -35.015932) (xy 433.295194 -35.018896) (xy 433.288028 -35.02619)
			(xy 433.285138 -35.03041) (xy 433.279296 -35.0393) (xy 433.278788 -35.042856) (xy 433.277518 -35.050222)
			(xy 433.272818 -35.076773) (xy 433.256924 -35.128297) (xy 433.233936 -35.177071) (xy 433.20431 -35.222122)
			(xy 433.168636 -35.262554) (xy 433.127626 -35.297562) (xy 433.082096 -35.326447) (xy 433.032953 -35.348635)
			(xy 432.981176 -35.363684) (xy 432.927796 -35.371294) (xy 432.900836 -35.371786) (xy 432.873583 -35.371325)
			(xy 432.819631 -35.363573) (xy 432.767332 -35.348221) (xy 432.71775 -35.325582) (xy 432.671895 -35.296116)
			(xy 432.630701 -35.260425) (xy 432.595005 -35.219233) (xy 432.565536 -35.173381) (xy 432.542892 -35.123802)
			(xy 432.527535 -35.071504) (xy 432.519777 -35.017553) (xy 432.519777 -34.963047) (xy 432.527535 -34.909096)
			(xy 432.542892 -34.856798) (xy 432.565536 -34.807219) (xy 432.595005 -34.761367) (xy 432.630701 -34.720175)
			(xy 432.671895 -34.684484) (xy 432.71775 -34.655018) (xy 432.767332 -34.632379) (xy 432.819631 -34.617027)
			(xy 432.873583 -34.609275) (xy 432.900836 -34.60877) (xy 432.90109 -34.60877) (xy 432.918139 -34.608952)
			(xy 432.9521 -34.612005) (xy 432.968908 -34.614866) (xy 432.97959 -34.616336) (xy 433.000516 -34.611219)
			(xy 433.009294 -34.60496) (xy 433.03698 -34.581084) (xy 433.044611 -34.573207) (xy 433.052914 -34.552934)
			(xy 433.052982 -34.541968) (xy 433.052982 -34.54146) (xy 433.052728 -34.522664) (xy 433.052728 -33.911286)
			(xy 433.052238 -33.901278) (xy 433.044577 -33.882786) (xy 433.030425 -33.868631) (xy 433.011936 -33.860965)
			(xy 433.001928 -33.860486) (xy 430.600866 -33.860486) (xy 430.591605 -33.860832) (xy 430.574269 -33.867336)
			(xy 430.567084 -33.873186) (xy 430.560226 -33.879282) (xy 430.551844 -33.895284) (xy 430.550574 -33.904936)
			(xy 430.546685 -33.932268) (xy 430.532049 -33.985497) (xy 430.509891 -34.036061) (xy 430.480675 -34.082901)
			(xy 430.445011 -34.12504) (xy 430.403644 -34.161596) (xy 430.357439 -34.191807) (xy 430.307361 -34.21504)
			(xy 430.254456 -34.23081) (xy 430.19983 -34.238787) (xy 430.144625 -34.238806) (xy 430.089994 -34.230865)
			(xy 430.037079 -34.21513) (xy 429.986985 -34.191931) (xy 429.940759 -34.161751) (xy 429.899368 -34.125223)
			(xy 429.863675 -34.083108) (xy 429.834428 -34.036287) (xy 429.812237 -33.985738) (xy 429.797565 -33.932518)
			(xy 429.793654 -33.90519) (xy 429.793654 -33.904428) (xy 429.792098 -33.895407) (xy 429.783507 -33.879258)
			(xy 429.77689 -33.872932) (xy 429.770032 -33.86709) (xy 429.75276 -33.860486) (xy 429.114966 -33.860486)
			(xy 429.102413 -33.861135) (xy 429.080287 -33.872994) (xy 429.072802 -33.883092) (xy 429.055022 -33.912048)
			(xy 429.02632 -33.959292) (xy 429.023135 -33.9649) (xy 429.019414 -33.977243) (xy 429.018954 -33.983676)
			(xy 429.018446 -33.996376) (xy 429.024796 -34.008568) (xy 429.038084 -34.035716) (xy 429.056874 -34.09316)
			(xy 429.06639 -34.152846) (xy 429.06696 -34.183066) (xy 429.06696 -34.188654) (xy 429.066032 -34.216931)
			(xy 429.05686 -34.272757) (xy 429.039544 -34.326617) (xy 429.014465 -34.37733) (xy 428.982173 -34.423783)
			(xy 428.943375 -34.464959) (xy 428.898923 -34.499955) (xy 428.84979 -34.528002) (xy 428.797054 -34.548488)
			(xy 428.741872 -34.560961) (xy 428.685452 -34.56515) (xy 428.629032 -34.560961) (xy 428.57385 -34.548488)
			(xy 428.521114 -34.528002) (xy 428.471981 -34.499955) (xy 428.427529 -34.464959) (xy 428.388731 -34.423783)
			(xy 428.356439 -34.37733) (xy 428.33136 -34.326617) (xy 428.314044 -34.272757) (xy 428.304872 -34.216931)
			(xy 428.303944 -34.188654) (xy 428.303944 -34.183066) (xy 428.304495 -34.152843) (xy 428.313987 -34.093149)
			(xy 428.332791 -34.035704) (xy 428.346108 -34.008568) (xy 428.346108 -34.008314) (xy 428.348983 -34.002374)
			(xy 428.351929 -33.989514) (xy 428.35195 -33.982914) (xy 428.351442 -33.970468) (xy 428.315882 -33.912048)
			(xy 428.298102 -33.883092) (xy 428.290589 -33.873024) (xy 428.268481 -33.861158) (xy 428.255938 -33.860486)
			(xy 422.756076 -33.860486) (xy 422.74607 -33.860978) (xy 422.727584 -33.868641) (xy 422.713435 -33.882793)
			(xy 422.705776 -33.90128) (xy 422.705276 -33.911286) (xy 422.705276 -34.24174) (xy 422.705885 -34.252119)
			(xy 422.714283 -34.271116) (xy 422.721532 -34.27857) (xy 422.781984 -34.330132) (xy 422.786165 -34.333534)
			(xy 422.795641 -34.338666) (xy 422.80078 -34.340292) (xy 422.811194 -34.34334) (xy 422.82237 -34.341562)
			(xy 422.837196 -34.339389) (xy 422.867076 -34.337101) (xy 422.88206 -34.33699) (xy 422.882314 -34.33699)
			(xy 422.909518 -34.337545) (xy 422.963356 -34.345418) (xy 423.015529 -34.360861) (xy 423.064979 -34.38356)
			(xy 423.110703 -34.413054) (xy 423.151772 -34.448745) (xy 423.187354 -34.489908) (xy 423.216726 -34.53571)
			(xy 423.239294 -34.58522) (xy 423.254598 -34.637434) (xy 423.262329 -34.691293) (xy 423.262806 -34.718498)
			(xy 423.262343 -34.745751) (xy 423.254586 -34.799702) (xy 423.23923 -34.852) (xy 423.216588 -34.90158)
			(xy 423.18712 -34.947433) (xy 423.151426 -34.988626) (xy 423.110233 -35.02432) (xy 423.06438 -35.053788)
			(xy 423.0148 -35.07643) (xy 422.962502 -35.091786) (xy 422.908551 -35.099543) (xy 422.881298 -35.100006)
			(xy 422.881044 -35.100006) (xy 422.851538 -35.099451) (xy 422.793231 -35.090361) (xy 422.737018 -35.072405)
			(xy 422.684237 -35.046012) (xy 422.636147 -35.011811) (xy 422.593894 -34.970615) (xy 422.575736 -34.947352)
			(xy 422.570656 -34.94024) (xy 422.548304 -34.925508) (xy 422.54438 -34.92298) (xy 422.535814 -34.919275)
			(xy 422.531286 -34.918142) (xy 422.509696 -34.913316) (xy 422.500686 -34.911725) (xy 422.48259 -34.914335)
			(xy 422.47439 -34.918396) (xy 422.473882 -34.91865) (xy 422.4555 -34.928876) (xy 422.417211 -34.946301)
			(xy 422.397428 -34.953448) (xy 422.373227 -34.96149) (xy 422.323493 -34.972779) (xy 422.272813 -34.978476)
			(xy 422.247314 -34.978848) (xy 422.221814 -34.978488) (xy 422.171132 -34.972795) (xy 422.121397 -34.961503)
			(xy 422.0972 -34.953448) (xy 422.077415 -34.946304) (xy 422.039126 -34.92888) (xy 422.020746 -34.91865)
			(xy 422.020238 -34.918396) (xy 422.012039 -34.914337) (xy 421.993943 -34.911733) (xy 421.984932 -34.913316)
			(xy 421.963342 -34.918142) (xy 421.958822 -34.919297) (xy 421.950262 -34.923006) (xy 421.946324 -34.925508)
			(xy 421.923972 -34.94024) (xy 421.918892 -34.947352) (xy 421.900742 -34.970654) (xy 421.858464 -35.011897)
			(xy 421.810333 -35.046128) (xy 421.757499 -35.07253) (xy 421.701227 -35.09047) (xy 421.642862 -35.099519)
			(xy 421.61333 -35.100006) (xy 421.602408 -35.100006) (xy 421.602154 -35.099752) (xy 421.575439 -35.098515)
			(xy 421.522727 -35.089491) (xy 421.471791 -35.073196) (xy 421.423629 -35.04995) (xy 421.379184 -35.020206)
			(xy 421.339328 -34.984549) (xy 421.304839 -34.943677) (xy 421.276395 -34.89839) (xy 421.254553 -34.849575)
			(xy 421.239739 -34.798188) (xy 421.232245 -34.745237) (xy 421.231822 -34.718498) (xy 421.232285 -34.691246)
			(xy 421.240043 -34.637297) (xy 421.255399 -34.585001) (xy 421.278042 -34.535423) (xy 421.307511 -34.489572)
			(xy 421.343205 -34.448382) (xy 421.384398 -34.412692) (xy 421.430251 -34.383227) (xy 421.479831 -34.360588)
			(xy 421.532128 -34.345236) (xy 421.586078 -34.337483) (xy 421.61333 -34.33699) (xy 421.628123 -34.337133)
			(xy 421.65762 -34.339421) (xy 421.672258 -34.341562) (xy 421.683434 -34.34334) (xy 421.693848 -34.340292)
			(xy 421.698981 -34.338652) (xy 421.708458 -34.333526) (xy 421.712644 -34.330132) (xy 421.773096 -34.27857)
			(xy 421.780392 -34.271151) (xy 421.788777 -34.252131) (xy 421.789352 -34.24174) (xy 421.789352 -33.911286)
			(xy 421.788929 -33.90127) (xy 421.781255 -33.882766) (xy 421.767082 -33.86861) (xy 421.748568 -33.860958)
			(xy 421.738552 -33.860486) (xy 408.018996 -33.860486) (xy 408.008988 -33.860974) (xy 407.990495 -33.868634)
			(xy 407.97634 -33.882786) (xy 407.968676 -33.901278) (xy 407.968196 -33.911286) (xy 407.968196 -34.522156)
			(xy 407.968196 -34.522664) (xy 407.967942 -34.54146) (xy 407.967942 -34.541968) (xy 407.968088 -34.553199)
			(xy 407.97679 -34.573877) (xy 407.984706 -34.581846) (xy 407.992326 -34.58845) (xy 408.009852 -34.603436)
			(xy 408.018869 -34.610328) (xy 408.040749 -34.616244) (xy 408.052016 -34.614866) (xy 408.068826 -34.612021)
			(xy 408.102786 -34.608966) (xy 408.119834 -34.60877) (xy 408.12212 -34.60877) (xy 408.149278 -34.609393)
			(xy 408.203008 -34.617382) (xy 408.255062 -34.632911) (xy 408.304387 -34.655666) (xy 408.349986 -34.685187)
			(xy 408.390937 -34.720877) (xy 408.426412 -34.762015) (xy 408.455694 -34.807768) (xy 408.478191 -34.857212)
			(xy 408.493447 -34.909346) (xy 408.501155 -34.963118) (xy 408.501592 -34.990024) (xy 409.56687 -34.990024)
			(xy 409.570941 -34.934402) (xy 409.583067 -34.879965) (xy 409.60299 -34.827874) (xy 409.630286 -34.779239)
			(xy 409.664372 -34.735096) (xy 409.704521 -34.696387) (xy 409.749879 -34.663936) (xy 409.799479 -34.638435)
			(xy 409.852263 -34.620428) (xy 409.907106 -34.610298) (xy 409.96284 -34.608261) (xy 410.018277 -34.614361)
			(xy 410.072234 -34.628467) (xy 410.123563 -34.650279) (xy 410.171169 -34.679333) (xy 410.214037 -34.715008)
			(xy 410.251254 -34.756545) (xy 410.282027 -34.803058) (xy 410.305699 -34.853555) (xy 410.321767 -34.906962)
			(xy 410.329887 -34.962138) (xy 410.330396 -34.990024) (xy 411.972758 -34.990024) (xy 411.976829 -34.934402)
			(xy 411.988955 -34.879965) (xy 412.008878 -34.827874) (xy 412.036174 -34.779239) (xy 412.07026 -34.735096)
			(xy 412.110409 -34.696387) (xy 412.155767 -34.663936) (xy 412.205367 -34.638435) (xy 412.258151 -34.620428)
			(xy 412.312994 -34.610298) (xy 412.368728 -34.608261) (xy 412.424165 -34.614361) (xy 412.478122 -34.628467)
			(xy 412.529451 -34.650279) (xy 412.577057 -34.679333) (xy 412.619925 -34.715008) (xy 412.657142 -34.756545)
			(xy 412.687915 -34.803058) (xy 412.711587 -34.853555) (xy 412.727655 -34.906962) (xy 412.735775 -34.962138)
			(xy 412.736284 -34.990024) (xy 413.300924 -34.990024) (xy 413.304995 -34.934402) (xy 413.317121 -34.879965)
			(xy 413.337044 -34.827874) (xy 413.36434 -34.779239) (xy 413.398426 -34.735096) (xy 413.438575 -34.696387)
			(xy 413.483933 -34.663936) (xy 413.533533 -34.638435) (xy 413.586317 -34.620428) (xy 413.64116 -34.610298)
			(xy 413.696894 -34.608261) (xy 413.752331 -34.614361) (xy 413.806288 -34.628467) (xy 413.857617 -34.650279)
			(xy 413.905223 -34.679333) (xy 413.948091 -34.715008) (xy 413.985308 -34.756545) (xy 414.016081 -34.803058)
			(xy 414.039753 -34.853555) (xy 414.055821 -34.906962) (xy 414.063941 -34.962138) (xy 414.06445 -34.990024)
			(xy 416.19881 -34.990024) (xy 416.202881 -34.934402) (xy 416.215007 -34.879965) (xy 416.23493 -34.827874)
			(xy 416.262226 -34.779239) (xy 416.296312 -34.735096) (xy 416.336461 -34.696387) (xy 416.381819 -34.663936)
			(xy 416.431419 -34.638435) (xy 416.484203 -34.620428) (xy 416.539046 -34.610298) (xy 416.59478 -34.608261)
			(xy 416.650217 -34.614361) (xy 416.704174 -34.628467) (xy 416.755503 -34.650279) (xy 416.803109 -34.679333)
			(xy 416.845977 -34.715008) (xy 416.883194 -34.756545) (xy 416.913967 -34.803058) (xy 416.937639 -34.853555)
			(xy 416.953707 -34.906962) (xy 416.961827 -34.962138) (xy 416.962336 -34.990024) (xy 416.961827 -35.01791)
			(xy 416.953707 -35.073086) (xy 416.937639 -35.126493) (xy 416.913967 -35.17699) (xy 416.883194 -35.223503)
			(xy 416.846145 -35.264852) (xy 430.202338 -35.264852) (xy 430.206409 -35.20923) (xy 430.218535 -35.154793)
			(xy 430.238458 -35.102702) (xy 430.265754 -35.054067) (xy 430.29984 -35.009924) (xy 430.339989 -34.971215)
			(xy 430.385347 -34.938764) (xy 430.434947 -34.913263) (xy 430.487731 -34.895256) (xy 430.542574 -34.885126)
			(xy 430.598308 -34.883089) (xy 430.653745 -34.889189) (xy 430.707702 -34.903295) (xy 430.759031 -34.925107)
			(xy 430.806637 -34.954161) (xy 430.849505 -34.989836) (xy 430.886722 -35.031373) (xy 430.917495 -35.077886)
			(xy 430.941167 -35.128383) (xy 430.957235 -35.18179) (xy 430.965355 -35.236966) (xy 430.965864 -35.264852)
			(xy 430.965355 -35.292738) (xy 430.957235 -35.347914) (xy 430.941167 -35.401321) (xy 430.917495 -35.451818)
			(xy 430.886722 -35.498331) (xy 430.849505 -35.539868) (xy 430.806637 -35.575543) (xy 430.759031 -35.604597)
			(xy 430.707702 -35.626409) (xy 430.653745 -35.640515) (xy 430.598308 -35.646615) (xy 430.542574 -35.644578)
			(xy 430.487731 -35.634448) (xy 430.434947 -35.616441) (xy 430.385347 -35.59094) (xy 430.339989 -35.558489)
			(xy 430.29984 -35.51978) (xy 430.265754 -35.475637) (xy 430.238458 -35.427002) (xy 430.218535 -35.374911)
			(xy 430.206409 -35.320474) (xy 430.202338 -35.264852) (xy 416.846145 -35.264852) (xy 416.845977 -35.26504)
			(xy 416.803109 -35.300715) (xy 416.755503 -35.329769) (xy 416.704174 -35.351581) (xy 416.650217 -35.365687)
			(xy 416.59478 -35.371787) (xy 416.539046 -35.36975) (xy 416.484203 -35.35962) (xy 416.431419 -35.341613)
			(xy 416.381819 -35.316112) (xy 416.336461 -35.283661) (xy 416.296312 -35.244952) (xy 416.262226 -35.200809)
			(xy 416.23493 -35.152174) (xy 416.215007 -35.100083) (xy 416.202881 -35.045646) (xy 416.19881 -34.990024)
			(xy 414.06445 -34.990024) (xy 414.063941 -35.01791) (xy 414.055821 -35.073086) (xy 414.039753 -35.126493)
			(xy 414.016081 -35.17699) (xy 413.985308 -35.223503) (xy 413.948091 -35.26504) (xy 413.905223 -35.300715)
			(xy 413.857617 -35.329769) (xy 413.806288 -35.351581) (xy 413.752331 -35.365687) (xy 413.696894 -35.371787)
			(xy 413.64116 -35.36975) (xy 413.586317 -35.35962) (xy 413.533533 -35.341613) (xy 413.483933 -35.316112)
			(xy 413.438575 -35.283661) (xy 413.398426 -35.244952) (xy 413.36434 -35.200809) (xy 413.337044 -35.152174)
			(xy 413.317121 -35.100083) (xy 413.304995 -35.045646) (xy 413.300924 -34.990024) (xy 412.736284 -34.990024)
			(xy 412.735775 -35.01791) (xy 412.727655 -35.073086) (xy 412.711587 -35.126493) (xy 412.687915 -35.17699)
			(xy 412.657142 -35.223503) (xy 412.619925 -35.26504) (xy 412.577057 -35.300715) (xy 412.529451 -35.329769)
			(xy 412.478122 -35.351581) (xy 412.424165 -35.365687) (xy 412.368728 -35.371787) (xy 412.312994 -35.36975)
			(xy 412.258151 -35.35962) (xy 412.205367 -35.341613) (xy 412.155767 -35.316112) (xy 412.110409 -35.283661)
			(xy 412.07026 -35.244952) (xy 412.036174 -35.200809) (xy 412.008878 -35.152174) (xy 411.988955 -35.100083)
			(xy 411.976829 -35.045646) (xy 411.972758 -34.990024) (xy 410.330396 -34.990024) (xy 410.329887 -35.01791)
			(xy 410.321767 -35.073086) (xy 410.305699 -35.126493) (xy 410.282027 -35.17699) (xy 410.251254 -35.223503)
			(xy 410.214037 -35.26504) (xy 410.171169 -35.300715) (xy 410.123563 -35.329769) (xy 410.072234 -35.351581)
			(xy 410.018277 -35.365687) (xy 409.96284 -35.371787) (xy 409.907106 -35.36975) (xy 409.852263 -35.35962)
			(xy 409.799479 -35.341613) (xy 409.749879 -35.316112) (xy 409.704521 -35.283661) (xy 409.664372 -35.244952)
			(xy 409.630286 -35.200809) (xy 409.60299 -35.152174) (xy 409.583067 -35.100083) (xy 409.570941 -35.045646)
			(xy 409.56687 -34.990024) (xy 408.501592 -34.990024) (xy 408.501596 -34.990278) (xy 408.501134 -35.017532)
			(xy 408.49338 -35.071484) (xy 408.478025 -35.123784) (xy 408.455384 -35.173366) (xy 408.425916 -35.219221)
			(xy 408.390223 -35.260415) (xy 408.349029 -35.29611) (xy 408.303175 -35.325579) (xy 408.253593 -35.348222)
			(xy 408.201294 -35.363578) (xy 408.147342 -35.371333) (xy 408.120088 -35.371786) (xy 408.093124 -35.371326)
			(xy 408.039732 -35.363739) (xy 407.987941 -35.348705) (xy 407.938786 -35.326524) (xy 407.893247 -35.297638)
			(xy 407.852232 -35.262623) (xy 407.81656 -35.222178) (xy 407.786943 -35.17711) (xy 407.763971 -35.128319)
			(xy 407.748104 -35.076778) (xy 407.743406 -35.050222) (xy 407.742136 -35.042856) (xy 407.741628 -35.0393)
			(xy 407.735786 -35.03041) (xy 407.732894 -35.026193) (xy 407.725721 -35.018908) (xy 407.721562 -35.015932)
			(xy 407.658824 -34.974276) (xy 407.654329 -34.971439) (xy 407.644473 -34.967467) (xy 407.639266 -34.966402)
			(xy 407.62936 -34.964624) (xy 407.618946 -34.967164) (xy 407.592252 -34.973307) (xy 407.537876 -34.979929)
			(xy 407.510488 -34.980372) (xy 407.4831 -34.979924) (xy 407.428725 -34.9733) (xy 407.40203 -34.967164)
			(xy 407.391616 -34.964624) (xy 407.38171 -34.966402) (xy 407.376492 -34.96743) (xy 407.366628 -34.971403)
			(xy 407.362152 -34.974276) (xy 407.299414 -35.015932) (xy 407.295243 -35.018893) (xy 407.28807 -35.026183)
			(xy 407.28519 -35.03041) (xy 407.279348 -35.0393) (xy 407.27884 -35.042856) (xy 407.27757 -35.050222)
			(xy 407.27287 -35.076775) (xy 407.256978 -35.128302) (xy 407.23399 -35.177079) (xy 407.204365 -35.222135)
			(xy 407.168692 -35.262571) (xy 407.127683 -35.297584) (xy 407.082153 -35.326475) (xy 407.033009 -35.348669)
			(xy 406.981231 -35.363725) (xy 406.927849 -35.371342) (xy 406.900888 -35.371786) (xy 406.873639 -35.371299)
			(xy 406.819696 -35.363542) (xy 406.767405 -35.348186) (xy 406.717833 -35.325546) (xy 406.671986 -35.296081)
			(xy 406.6308 -35.260391) (xy 406.595112 -35.219204) (xy 406.565648 -35.173357) (xy 406.54301 -35.123783)
			(xy 406.527656 -35.071493) (xy 406.5199 -35.017549) (xy 406.5199 -34.963051) (xy 406.527656 -34.909107)
			(xy 406.54301 -34.856817) (xy 406.565648 -34.807243) (xy 406.595112 -34.761396) (xy 406.6308 -34.720209)
			(xy 406.671986 -34.684519) (xy 406.717833 -34.655054) (xy 406.767405 -34.632414) (xy 406.819696 -34.617058)
			(xy 406.873639 -34.609301) (xy 406.900888 -34.60877) (xy 406.901142 -34.60877) (xy 406.918191 -34.60895)
			(xy 406.952153 -34.611999) (xy 406.96896 -34.614866) (xy 406.979639 -34.616325) (xy 407.000551 -34.611191)
			(xy 407.009346 -34.60496) (xy 407.037032 -34.581084) (xy 407.044669 -34.57321) (xy 407.052981 -34.552935)
			(xy 407.053034 -34.541968) (xy 407.053034 -34.54146) (xy 407.05278 -34.522664) (xy 407.05278 -33.911286)
			(xy 407.052357 -33.901268) (xy 407.044684 -33.882759) (xy 407.030512 -33.868597) (xy 407.011998 -33.860936)
			(xy 407.00198 -33.860486) (xy 404.600918 -33.860486) (xy 404.591661 -33.86084) (xy 404.574336 -33.867356)
			(xy 404.567136 -33.873186) (xy 404.560278 -33.879282) (xy 404.551896 -33.895284) (xy 404.550626 -33.904936)
			(xy 404.546737 -33.932264) (xy 404.532102 -33.985487) (xy 404.509946 -34.036044) (xy 404.480733 -34.082878)
			(xy 404.445073 -34.125011) (xy 404.403711 -34.161562) (xy 404.357511 -34.191768) (xy 404.307438 -34.214997)
			(xy 404.25454 -34.230765) (xy 404.199921 -34.23874) (xy 404.144723 -34.238758) (xy 404.090098 -34.230817)
			(xy 404.03719 -34.215084) (xy 403.987103 -34.191886) (xy 403.940883 -34.16171) (xy 403.899498 -34.125185)
			(xy 403.86381 -34.083075) (xy 403.834567 -34.036259) (xy 403.81238 -33.985717) (xy 403.797711 -33.932503)
			(xy 403.793706 -33.90519) (xy 403.793706 -33.904428) (xy 403.792148 -33.895408) (xy 403.783551 -33.879265)
			(xy 403.776942 -33.872932) (xy 403.770084 -33.86709) (xy 403.752812 -33.860486) (xy 403.115018 -33.860486)
			(xy 403.102459 -33.861123) (xy 403.080313 -33.872971) (xy 403.072854 -33.883092) (xy 403.055074 -33.912048)
			(xy 403.026372 -33.959292) (xy 403.02319 -33.9649) (xy 403.019472 -33.977244) (xy 403.019006 -33.983676)
			(xy 403.018498 -33.996376) (xy 403.024848 -34.008568) (xy 403.038137 -34.035715) (xy 403.056929 -34.09316)
			(xy 403.066447 -34.152846) (xy 403.067012 -34.183066) (xy 403.067012 -34.188654) (xy 403.06615 -34.215644)
			(xy 403.057758 -34.268986) (xy 403.041926 -34.320612) (xy 403.018972 -34.36949) (xy 402.989354 -34.414641)
			(xy 402.953664 -34.455165) (xy 402.912617 -34.49025) (xy 402.867031 -34.519196) (xy 402.81782 -34.541424)
			(xy 402.765965 -34.556489) (xy 402.712504 -34.564091) (xy 402.685504 -34.564574) (xy 402.658894 -34.564119)
			(xy 402.606189 -34.556738) (xy 402.55502 -34.542104) (xy 402.506382 -34.520501) (xy 402.461218 -34.492349)
			(xy 402.420404 -34.458194) (xy 402.384733 -34.418699) (xy 402.354896 -34.37463) (xy 402.331473 -34.326842)
			(xy 402.322792 -34.301684) (xy 402.319744 -34.292286) (xy 402.314156 -34.285428) (xy 402.31132 -34.282071)
			(xy 402.30468 -34.276317) (xy 402.300948 -34.273998) (xy 402.242782 -34.2392) (xy 402.238925 -34.236982)
			(xy 402.230623 -34.233782) (xy 402.226272 -34.23285) (xy 402.21789 -34.231326) (xy 402.208238 -34.233104)
			(xy 402.191365 -34.235956) (xy 402.157278 -34.239008) (xy 402.140166 -34.2392) (xy 402.138134 -34.2392)
			(xy 402.110645 -34.238577) (xy 402.056273 -34.230399) (xy 402.003639 -34.214497) (xy 401.953835 -34.191199)
			(xy 401.907894 -34.160989) (xy 401.866768 -34.124494) (xy 401.831311 -34.082471) (xy 401.802257 -34.03579)
			(xy 401.780209 -33.98542) (xy 401.765625 -33.932406) (xy 401.761706 -33.90519) (xy 401.761706 -33.904428)
			(xy 401.760148 -33.895408) (xy 401.751551 -33.879265) (xy 401.744942 -33.872932) (xy 401.738084 -33.86709)
			(xy 401.720812 -33.860486) (xy 396.756128 -33.860486) (xy 396.746102 -33.860901) (xy 396.727573 -33.868565)
			(xy 396.713389 -33.882738) (xy 396.705709 -33.90126) (xy 396.705328 -33.911286) (xy 396.705328 -34.24174)
			(xy 396.705939 -34.252117) (xy 396.714343 -34.271109) (xy 396.721584 -34.27857) (xy 396.782036 -34.330132)
			(xy 396.786219 -34.33353) (xy 396.795698 -34.338653) (xy 396.800832 -34.340292) (xy 396.811246 -34.34334)
			(xy 396.822422 -34.341562) (xy 396.837248 -34.339387) (xy 396.867128 -34.337095) (xy 396.882112 -34.33699)
			(xy 396.882366 -34.33699) (xy 396.909572 -34.337542) (xy 396.963415 -34.34541) (xy 397.015594 -34.360848)
			(xy 397.06505 -34.383544) (xy 397.11078 -34.413037) (xy 397.151855 -34.448728) (xy 397.187442 -34.489893)
			(xy 397.216819 -34.535696) (xy 397.23939 -34.58521) (xy 397.254697 -34.637428) (xy 397.262428 -34.69129)
			(xy 397.262858 -34.718498) (xy 397.262395 -34.74575) (xy 397.254638 -34.799698) (xy 397.239281 -34.851993)
			(xy 397.216638 -34.901571) (xy 397.18717 -34.94742) (xy 397.151475 -34.988609) (xy 397.110282 -35.024298)
			(xy 397.064428 -35.053761) (xy 397.014848 -35.076398) (xy 396.962551 -35.091748) (xy 396.908602 -35.099498)
			(xy 396.88135 -35.100006) (xy 396.881096 -35.100006) (xy 396.851592 -35.099448) (xy 396.793289 -35.090351)
			(xy 396.73708 -35.07239) (xy 396.684306 -35.045993) (xy 396.636222 -35.011789) (xy 396.593974 -34.970593)
			(xy 396.575788 -34.947352) (xy 396.570708 -34.94024) (xy 396.548356 -34.925508) (xy 396.544431 -34.922983)
			(xy 396.535863 -34.919286) (xy 396.531338 -34.918142) (xy 396.509748 -34.913316) (xy 396.500736 -34.911716)
			(xy 396.482631 -34.914309) (xy 396.474442 -34.918396) (xy 396.473934 -34.91865) (xy 396.455553 -34.928877)
			(xy 396.417266 -34.946307) (xy 396.39748 -34.953448) (xy 396.37328 -34.961492) (xy 396.323546 -34.972787)
			(xy 396.272866 -34.97849) (xy 396.247366 -34.978848) (xy 396.221866 -34.978485) (xy 396.171186 -34.972788)
			(xy 396.121453 -34.96149) (xy 396.097252 -34.953448) (xy 396.077468 -34.946302) (xy 396.039181 -34.928874)
			(xy 396.020798 -34.91865) (xy 396.02029 -34.918396) (xy 396.01209 -34.914346) (xy 395.993998 -34.911758)
			(xy 395.984984 -34.913316) (xy 395.963394 -34.918142) (xy 395.958872 -34.919293) (xy 395.950307 -34.922994)
			(xy 395.946376 -34.925508) (xy 395.924024 -34.94024) (xy 395.918944 -34.947352) (xy 395.900793 -34.970651)
			(xy 395.858514 -35.011889) (xy 395.810381 -35.046114) (xy 395.757548 -35.072509) (xy 395.701276 -35.090442)
			(xy 395.642913 -35.099485) (xy 395.613382 -35.100006) (xy 395.60246 -35.100006) (xy 395.602206 -35.099752)
			(xy 395.575494 -35.098512) (xy 395.522787 -35.089483) (xy 395.471856 -35.073184) (xy 395.4237 -35.049935)
			(xy 395.379261 -35.02019) (xy 395.33941 -34.984533) (xy 395.304927 -34.943662) (xy 395.276487 -34.898377)
			(xy 395.254648 -34.849565) (xy 395.239837 -34.798182) (xy 395.232344 -34.745235) (xy 395.231874 -34.718498)
			(xy 395.23236 -34.691246) (xy 395.240117 -34.637298) (xy 395.255472 -34.585002) (xy 395.278113 -34.535424)
			(xy 395.307579 -34.489573) (xy 395.34327 -34.448381) (xy 395.38446 -34.412688) (xy 395.43031 -34.38322)
			(xy 395.479887 -34.360577) (xy 395.532182 -34.34522) (xy 395.58613 -34.337461) (xy 395.613382 -34.33699)
			(xy 395.628175 -34.337135) (xy 395.657671 -34.339427) (xy 395.67231 -34.341562) (xy 395.683486 -34.34334)
			(xy 395.6939 -34.340292) (xy 395.699031 -34.338647) (xy 395.708501 -34.333514) (xy 395.712696 -34.330132)
			(xy 395.773148 -34.27857) (xy 395.780437 -34.271147) (xy 395.788813 -34.252128) (xy 395.789404 -34.24174)
			(xy 395.789404 -33.911286) (xy 395.788913 -33.90128) (xy 395.781252 -33.882792) (xy 395.767099 -33.868643)
			(xy 395.74861 -33.860985) (xy 395.738604 -33.860486) (xy 382.019048 -33.860486) (xy 382.009019 -33.860897)
			(xy 381.990484 -33.868558) (xy 381.976293 -33.882731) (xy 381.968609 -33.901258) (xy 381.968248 -33.911286)
			(xy 381.968248 -34.522156) (xy 381.968248 -34.522664) (xy 381.967994 -34.54146) (xy 381.967994 -34.541968)
			(xy 381.968141 -34.553197) (xy 381.97685 -34.573869) (xy 381.984758 -34.581846) (xy 381.992378 -34.58845)
			(xy 382.009904 -34.603436) (xy 382.018919 -34.610337) (xy 382.040803 -34.616273) (xy 382.052068 -34.614866)
			(xy 382.068878 -34.612023) (xy 382.102838 -34.608973) (xy 382.119886 -34.60877) (xy 382.122172 -34.60877)
			(xy 382.149327 -34.609397) (xy 382.203052 -34.617392) (xy 382.2551 -34.632925) (xy 382.304418 -34.655683)
			(xy 382.350011 -34.685206) (xy 382.390956 -34.720896) (xy 382.426425 -34.762032) (xy 382.455702 -34.807782)
			(xy 382.478195 -34.857223) (xy 382.493449 -34.909353) (xy 382.501155 -34.96312) (xy 382.501643 -34.990024)
			(xy 383.566922 -34.990024) (xy 383.570993 -34.934402) (xy 383.583119 -34.879965) (xy 383.603042 -34.827874)
			(xy 383.630338 -34.779239) (xy 383.664424 -34.735096) (xy 383.704573 -34.696387) (xy 383.749931 -34.663936)
			(xy 383.799531 -34.638435) (xy 383.852315 -34.620428) (xy 383.907158 -34.610298) (xy 383.962892 -34.608261)
			(xy 384.018329 -34.614361) (xy 384.072286 -34.628467) (xy 384.123615 -34.650279) (xy 384.171221 -34.679333)
			(xy 384.214089 -34.715008) (xy 384.251306 -34.756545) (xy 384.282079 -34.803058) (xy 384.305751 -34.853555)
			(xy 384.321819 -34.906962) (xy 384.329939 -34.962138) (xy 384.330448 -34.990024) (xy 385.97281 -34.990024)
			(xy 385.976881 -34.934402) (xy 385.989007 -34.879965) (xy 386.00893 -34.827874) (xy 386.036226 -34.779239)
			(xy 386.070312 -34.735096) (xy 386.110461 -34.696387) (xy 386.155819 -34.663936) (xy 386.205419 -34.638435)
			(xy 386.258203 -34.620428) (xy 386.313046 -34.610298) (xy 386.36878 -34.608261) (xy 386.424217 -34.614361)
			(xy 386.478174 -34.628467) (xy 386.529503 -34.650279) (xy 386.577109 -34.679333) (xy 386.619977 -34.715008)
			(xy 386.657194 -34.756545) (xy 386.687967 -34.803058) (xy 386.711639 -34.853555) (xy 386.727707 -34.906962)
			(xy 386.735827 -34.962138) (xy 386.736336 -34.990024) (xy 387.300976 -34.990024) (xy 387.305047 -34.934402)
			(xy 387.317173 -34.879965) (xy 387.337096 -34.827874) (xy 387.364392 -34.779239) (xy 387.398478 -34.735096)
			(xy 387.438627 -34.696387) (xy 387.483985 -34.663936) (xy 387.533585 -34.638435) (xy 387.586369 -34.620428)
			(xy 387.641212 -34.610298) (xy 387.696946 -34.608261) (xy 387.752383 -34.614361) (xy 387.80634 -34.628467)
			(xy 387.857669 -34.650279) (xy 387.905275 -34.679333) (xy 387.948143 -34.715008) (xy 387.98536 -34.756545)
			(xy 388.016133 -34.803058) (xy 388.039805 -34.853555) (xy 388.055873 -34.906962) (xy 388.063993 -34.962138)
			(xy 388.064502 -34.990024) (xy 390.198862 -34.990024) (xy 390.202933 -34.934402) (xy 390.215059 -34.879965)
			(xy 390.234982 -34.827874) (xy 390.262278 -34.779239) (xy 390.296364 -34.735096) (xy 390.336513 -34.696387)
			(xy 390.381871 -34.663936) (xy 390.431471 -34.638435) (xy 390.484255 -34.620428) (xy 390.539098 -34.610298)
			(xy 390.594832 -34.608261) (xy 390.650269 -34.614361) (xy 390.704226 -34.628467) (xy 390.755555 -34.650279)
			(xy 390.803161 -34.679333) (xy 390.846029 -34.715008) (xy 390.883246 -34.756545) (xy 390.914019 -34.803058)
			(xy 390.937691 -34.853555) (xy 390.953759 -34.906962) (xy 390.961879 -34.962138) (xy 390.962388 -34.990024)
			(xy 390.961879 -35.01791) (xy 390.953759 -35.073086) (xy 390.937691 -35.126493) (xy 390.914019 -35.17699)
			(xy 390.883246 -35.223503) (xy 390.846197 -35.264852) (xy 404.20239 -35.264852) (xy 404.206461 -35.20923)
			(xy 404.218587 -35.154793) (xy 404.23851 -35.102702) (xy 404.265806 -35.054067) (xy 404.299892 -35.009924)
			(xy 404.340041 -34.971215) (xy 404.385399 -34.938764) (xy 404.434999 -34.913263) (xy 404.487783 -34.895256)
			(xy 404.542626 -34.885126) (xy 404.59836 -34.883089) (xy 404.653797 -34.889189) (xy 404.707754 -34.903295)
			(xy 404.759083 -34.925107) (xy 404.806689 -34.954161) (xy 404.849557 -34.989836) (xy 404.886774 -35.031373)
			(xy 404.917547 -35.077886) (xy 404.941219 -35.128383) (xy 404.957287 -35.18179) (xy 404.965407 -35.236966)
			(xy 404.965916 -35.264852) (xy 404.965407 -35.292738) (xy 404.957287 -35.347914) (xy 404.941219 -35.401321)
			(xy 404.917547 -35.451818) (xy 404.886774 -35.498331) (xy 404.849557 -35.539868) (xy 404.806689 -35.575543)
			(xy 404.759083 -35.604597) (xy 404.707754 -35.626409) (xy 404.653797 -35.640515) (xy 404.59836 -35.646615)
			(xy 404.542626 -35.644578) (xy 404.487783 -35.634448) (xy 404.434999 -35.616441) (xy 404.385399 -35.59094)
			(xy 404.340041 -35.558489) (xy 404.299892 -35.51978) (xy 404.265806 -35.475637) (xy 404.23851 -35.427002)
			(xy 404.218587 -35.374911) (xy 404.206461 -35.320474) (xy 404.20239 -35.264852) (xy 390.846197 -35.264852)
			(xy 390.846029 -35.26504) (xy 390.803161 -35.300715) (xy 390.755555 -35.329769) (xy 390.704226 -35.351581)
			(xy 390.650269 -35.365687) (xy 390.594832 -35.371787) (xy 390.539098 -35.36975) (xy 390.484255 -35.35962)
			(xy 390.431471 -35.341613) (xy 390.381871 -35.316112) (xy 390.336513 -35.283661) (xy 390.296364 -35.244952)
			(xy 390.262278 -35.200809) (xy 390.234982 -35.152174) (xy 390.215059 -35.100083) (xy 390.202933 -35.045646)
			(xy 390.198862 -34.990024) (xy 388.064502 -34.990024) (xy 388.063993 -35.01791) (xy 388.055873 -35.073086)
			(xy 388.039805 -35.126493) (xy 388.016133 -35.17699) (xy 387.98536 -35.223503) (xy 387.948143 -35.26504)
			(xy 387.905275 -35.300715) (xy 387.857669 -35.329769) (xy 387.80634 -35.351581) (xy 387.752383 -35.365687)
			(xy 387.696946 -35.371787) (xy 387.641212 -35.36975) (xy 387.586369 -35.35962) (xy 387.533585 -35.341613)
			(xy 387.483985 -35.316112) (xy 387.438627 -35.283661) (xy 387.398478 -35.244952) (xy 387.364392 -35.200809)
			(xy 387.337096 -35.152174) (xy 387.317173 -35.100083) (xy 387.305047 -35.045646) (xy 387.300976 -34.990024)
			(xy 386.736336 -34.990024) (xy 386.735827 -35.01791) (xy 386.727707 -35.073086) (xy 386.711639 -35.126493)
			(xy 386.687967 -35.17699) (xy 386.657194 -35.223503) (xy 386.619977 -35.26504) (xy 386.577109 -35.300715)
			(xy 386.529503 -35.329769) (xy 386.478174 -35.351581) (xy 386.424217 -35.365687) (xy 386.36878 -35.371787)
			(xy 386.313046 -35.36975) (xy 386.258203 -35.35962) (xy 386.205419 -35.341613) (xy 386.155819 -35.316112)
			(xy 386.110461 -35.283661) (xy 386.070312 -35.244952) (xy 386.036226 -35.200809) (xy 386.00893 -35.152174)
			(xy 385.989007 -35.100083) (xy 385.976881 -35.045646) (xy 385.97281 -34.990024) (xy 384.330448 -34.990024)
			(xy 384.329939 -35.01791) (xy 384.321819 -35.073086) (xy 384.305751 -35.126493) (xy 384.282079 -35.17699)
			(xy 384.251306 -35.223503) (xy 384.214089 -35.26504) (xy 384.171221 -35.300715) (xy 384.123615 -35.329769)
			(xy 384.072286 -35.351581) (xy 384.018329 -35.365687) (xy 383.962892 -35.371787) (xy 383.907158 -35.36975)
			(xy 383.852315 -35.35962) (xy 383.799531 -35.341613) (xy 383.749931 -35.316112) (xy 383.704573 -35.283661)
			(xy 383.664424 -35.244952) (xy 383.630338 -35.200809) (xy 383.603042 -35.152174) (xy 383.583119 -35.100083)
			(xy 383.570993 -35.045646) (xy 383.566922 -34.990024) (xy 382.501643 -34.990024) (xy 382.501648 -34.990278)
			(xy 382.501164 -35.017531) (xy 382.49341 -35.071484) (xy 382.478057 -35.123783) (xy 382.455418 -35.173366)
			(xy 382.425953 -35.219222) (xy 382.390262 -35.260418) (xy 382.349072 -35.296116) (xy 382.30322 -35.325588)
			(xy 382.253641 -35.348235) (xy 382.201344 -35.363597) (xy 382.147393 -35.371359) (xy 382.12014 -35.371786)
			(xy 382.093178 -35.371323) (xy 382.039791 -35.363731) (xy 381.988006 -35.348692) (xy 381.938856 -35.326508)
			(xy 381.893323 -35.29762) (xy 381.852313 -35.262605) (xy 381.816647 -35.222161) (xy 381.787034 -35.177095)
			(xy 381.764066 -35.128307) (xy 381.748202 -35.076769) (xy 381.743458 -35.050222) (xy 381.742188 -35.042856)
			(xy 381.74168 -35.0393) (xy 381.735838 -35.03041) (xy 381.732948 -35.026191) (xy 381.725779 -35.0189)
			(xy 381.721614 -35.015932) (xy 381.658876 -34.974276) (xy 381.65438 -34.971444) (xy 381.644522 -34.967481)
			(xy 381.639318 -34.966402) (xy 381.629412 -34.964624) (xy 381.618998 -34.967164) (xy 381.592304 -34.973304)
			(xy 381.537928 -34.97992) (xy 381.51054 -34.980372) (xy 381.483152 -34.979927) (xy 381.428776 -34.973309)
			(xy 381.402082 -34.967164) (xy 381.391668 -34.964624) (xy 381.381762 -34.966402) (xy 381.376541 -34.967425)
			(xy 381.366672 -34.971389) (xy 381.362204 -34.974276) (xy 381.299466 -35.015932) (xy 381.295298 -35.018896)
			(xy 381.288131 -35.02619) (xy 381.285242 -35.03041) (xy 381.2794 -35.0393) (xy 381.278892 -35.042856)
			(xy 381.277622 -35.050222) (xy 381.272922 -35.076773) (xy 381.257029 -35.128298) (xy 381.23404 -35.177072)
			(xy 381.204414 -35.222123) (xy 381.16874 -35.262556) (xy 381.12773 -35.297564) (xy 381.0822 -35.326449)
			(xy 381.033057 -35.348638) (xy 380.98128 -35.363687) (xy 380.9279 -35.371298) (xy 380.90094 -35.371786)
			(xy 380.873687 -35.371325) (xy 380.819735 -35.363574) (xy 380.767435 -35.348222) (xy 380.717853 -35.325583)
			(xy 380.671997 -35.296118) (xy 380.630802 -35.260426) (xy 380.595106 -35.219235) (xy 380.565636 -35.173382)
			(xy 380.542992 -35.123802) (xy 380.527635 -35.071504) (xy 380.519877 -35.017553) (xy 380.519877 -34.963047)
			(xy 380.527635 -34.909096) (xy 380.542992 -34.856798) (xy 380.565636 -34.807218) (xy 380.595106 -34.761365)
			(xy 380.630802 -34.720174) (xy 380.671997 -34.684482) (xy 380.717853 -34.655017) (xy 380.767435 -34.632378)
			(xy 380.819735 -34.617026) (xy 380.873687 -34.609275) (xy 380.90094 -34.60877) (xy 380.901194 -34.60877)
			(xy 380.918243 -34.608952) (xy 380.952204 -34.612005) (xy 380.969012 -34.614866) (xy 380.979693 -34.616335)
			(xy 381.000618 -34.611216) (xy 381.009398 -34.60496) (xy 381.037084 -34.581084) (xy 381.044715 -34.573207)
			(xy 381.053018 -34.552934) (xy 381.053086 -34.541968) (xy 381.053086 -34.54146) (xy 381.052832 -34.522664)
			(xy 381.052832 -33.911286) (xy 381.052342 -33.901278) (xy 381.044681 -33.882785) (xy 381.03053 -33.868629)
			(xy 381.01204 -33.860961) (xy 381.002032 -33.860486) (xy 378.60097 -33.860486) (xy 378.591709 -33.860831)
			(xy 378.574372 -33.867334) (xy 378.567188 -33.873186) (xy 378.56033 -33.879282) (xy 378.551948 -33.895284)
			(xy 378.550678 -33.904936) (xy 378.546789 -33.932268) (xy 378.532153 -33.985498) (xy 378.509995 -34.036062)
			(xy 378.480779 -34.082903) (xy 378.445114 -34.125042) (xy 378.403747 -34.161599) (xy 378.357541 -34.19181)
			(xy 378.307462 -34.215043) (xy 378.254557 -34.230814) (xy 378.199931 -34.238791) (xy 378.144725 -34.23881)
			(xy 378.090094 -34.230869) (xy 378.037178 -34.215134) (xy 377.987083 -34.191935) (xy 377.940857 -34.161755)
			(xy 377.899465 -34.125226) (xy 377.863773 -34.08311) (xy 377.834525 -34.036289) (xy 377.812333 -33.98574)
			(xy 377.797661 -33.93252) (xy 377.793758 -33.90519) (xy 377.793758 -33.904428) (xy 377.792202 -33.895407)
			(xy 377.783612 -33.879257) (xy 377.776994 -33.872932) (xy 377.770136 -33.86709) (xy 377.752864 -33.860486)
			(xy 377.11507 -33.860486) (xy 377.102517 -33.861134) (xy 377.080389 -33.872993) (xy 377.072906 -33.883092)
			(xy 377.055126 -33.912048) (xy 377.026424 -33.959292) (xy 377.023239 -33.964899) (xy 377.019517 -33.977243)
			(xy 377.019058 -33.983676) (xy 377.01855 -33.996376) (xy 377.0249 -34.008568) (xy 377.038188 -34.035716)
			(xy 377.056978 -34.09316) (xy 377.066494 -34.152846) (xy 377.067064 -34.183066) (xy 377.067064 -34.188654)
			(xy 377.066136 -34.216931) (xy 377.056964 -34.272757) (xy 377.039648 -34.326617) (xy 377.014569 -34.37733)
			(xy 376.982277 -34.423783) (xy 376.943479 -34.464959) (xy 376.899027 -34.499955) (xy 376.849894 -34.528002)
			(xy 376.797158 -34.548488) (xy 376.741976 -34.560961) (xy 376.685556 -34.56515) (xy 376.629136 -34.560961)
			(xy 376.573954 -34.548488) (xy 376.521218 -34.528002) (xy 376.472085 -34.499955) (xy 376.427633 -34.464959)
			(xy 376.388835 -34.423783) (xy 376.356543 -34.37733) (xy 376.331464 -34.326617) (xy 376.314148 -34.272757)
			(xy 376.304976 -34.216931) (xy 376.304048 -34.188654) (xy 376.304048 -34.183066) (xy 376.304599 -34.152843)
			(xy 376.314091 -34.093149) (xy 376.332896 -34.035704) (xy 376.346212 -34.008568) (xy 376.346212 -34.008314)
			(xy 376.349087 -34.002374) (xy 376.352033 -33.989514) (xy 376.352054 -33.982914) (xy 376.351546 -33.970468)
			(xy 376.315986 -33.912048) (xy 376.298206 -33.883092) (xy 376.290694 -33.873023) (xy 376.268585 -33.861156)
			(xy 376.256042 -33.860486) (xy 370.75618 -33.860486) (xy 370.746174 -33.860977) (xy 370.727686 -33.86864)
			(xy 370.713536 -33.882792) (xy 370.705876 -33.90128) (xy 370.70538 -33.911286) (xy 370.70538 -34.24174)
			(xy 370.70599 -34.252118) (xy 370.714388 -34.271116) (xy 370.721636 -34.27857) (xy 370.782088 -34.330132)
			(xy 370.786269 -34.333534) (xy 370.795746 -34.338665) (xy 370.800884 -34.340292) (xy 370.811298 -34.34334)
			(xy 370.822474 -34.341562) (xy 370.8373 -34.339389) (xy 370.86718 -34.337101) (xy 370.882164 -34.33699)
			(xy 370.882418 -34.33699) (xy 370.909622 -34.337545) (xy 370.963459 -34.345419) (xy 371.015632 -34.360862)
			(xy 371.065082 -34.383561) (xy 371.110805 -34.413055) (xy 371.151873 -34.448746) (xy 371.187455 -34.48991)
			(xy 371.216827 -34.535711) (xy 371.239394 -34.585221) (xy 371.254698 -34.637434) (xy 371.262429 -34.691293)
			(xy 371.26291 -34.718498) (xy 371.262424 -34.745749) (xy 371.254668 -34.799697) (xy 371.239313 -34.851993)
			(xy 371.216672 -34.90157) (xy 371.187206 -34.947421) (xy 371.151514 -34.988612) (xy 371.110324 -35.024304)
			(xy 371.064474 -35.05377) (xy 371.014896 -35.076412) (xy 370.962601 -35.091767) (xy 370.908653 -35.099524)
			(xy 370.881402 -35.100006) (xy 370.881148 -35.100006) (xy 370.851642 -35.099452) (xy 370.793335 -35.090362)
			(xy 370.737121 -35.072406) (xy 370.68434 -35.046014) (xy 370.63625 -35.011812) (xy 370.593996 -34.970617)
			(xy 370.57584 -34.947352) (xy 370.57076 -34.94024) (xy 370.548408 -34.925508) (xy 370.544485 -34.922979)
			(xy 370.535919 -34.919274) (xy 370.53139 -34.918142) (xy 370.5098 -34.913316) (xy 370.500789 -34.911724)
			(xy 370.482693 -34.914333) (xy 370.474494 -34.918396) (xy 370.473986 -34.91865) (xy 370.455604 -34.928876)
			(xy 370.417316 -34.946301) (xy 370.397532 -34.953448) (xy 370.373331 -34.96149) (xy 370.323597 -34.97278)
			(xy 370.272917 -34.978477) (xy 370.247418 -34.978848) (xy 370.221918 -34.978488) (xy 370.171236 -34.972796)
			(xy 370.121501 -34.961504) (xy 370.097304 -34.953448) (xy 370.077519 -34.946304) (xy 370.03923 -34.92888)
			(xy 370.02085 -34.91865) (xy 370.020342 -34.918396) (xy 370.012143 -34.914337) (xy 369.994047 -34.911731)
			(xy 369.985036 -34.913316) (xy 369.963446 -34.918142) (xy 369.958926 -34.919297) (xy 369.950365 -34.923005)
			(xy 369.946428 -34.925508) (xy 369.924076 -34.94024) (xy 369.918996 -34.947352) (xy 369.900846 -34.970654)
			(xy 369.858568 -35.011898) (xy 369.810437 -35.04613) (xy 369.757604 -35.072532) (xy 369.701331 -35.090472)
			(xy 369.642966 -35.099522) (xy 369.613434 -35.100006) (xy 369.602512 -35.100006) (xy 369.602258 -35.099752)
			(xy 369.575543 -35.098515) (xy 369.522831 -35.089492) (xy 369.471894 -35.073197) (xy 369.423732 -35.049951)
			(xy 369.379286 -35.020208) (xy 369.339429 -34.984551) (xy 369.30494 -34.943678) (xy 369.276496 -34.898391)
			(xy 369.254653 -34.849576) (xy 369.23984 -34.798189) (xy 369.232346 -34.745237) (xy 369.231926 -34.718498)
			(xy 369.232389 -34.691246) (xy 369.240147 -34.637297) (xy 369.255503 -34.585002) (xy 369.278147 -34.535424)
			(xy 369.307615 -34.489573) (xy 369.343309 -34.448384) (xy 369.384502 -34.412694) (xy 369.430355 -34.383229)
			(xy 369.479935 -34.360591) (xy 369.532232 -34.345239) (xy 369.586182 -34.337487) (xy 369.613434 -34.33699)
			(xy 369.628227 -34.337133) (xy 369.657724 -34.339422) (xy 369.672362 -34.341562) (xy 369.683538 -34.34334)
			(xy 369.693952 -34.340292) (xy 369.699085 -34.338652) (xy 369.708561 -34.333525) (xy 369.712748 -34.330132)
			(xy 369.7732 -34.27857) (xy 369.780495 -34.27115) (xy 369.78888 -34.25213) (xy 369.789456 -34.24174)
			(xy 369.789456 -33.911286) (xy 369.789033 -33.90127) (xy 369.781359 -33.882765) (xy 369.767186 -33.868608)
			(xy 369.748673 -33.860955) (xy 369.738656 -33.860486) (xy 356.0191 -33.860486) (xy 356.009091 -33.860974)
			(xy 355.990597 -33.868633) (xy 355.976441 -33.882785) (xy 355.968776 -33.901277) (xy 355.9683 -33.911286)
			(xy 355.9683 -34.522156) (xy 355.9683 -34.522664) (xy 355.968046 -34.54146) (xy 355.968046 -34.541968)
			(xy 355.968192 -34.553199) (xy 355.976895 -34.573876) (xy 355.98481 -34.581846) (xy 355.99243 -34.58845)
			(xy 356.009956 -34.603436) (xy 356.018973 -34.610327) (xy 356.040853 -34.616241) (xy 356.05212 -34.614866)
			(xy 356.06893 -34.612021) (xy 356.10289 -34.608966) (xy 356.119938 -34.60877) (xy 356.122224 -34.60877)
			(xy 356.149381 -34.609393) (xy 356.203111 -34.617383) (xy 356.255165 -34.632912) (xy 356.304489 -34.655668)
			(xy 356.350088 -34.685189) (xy 356.391039 -34.720879) (xy 356.426513 -34.762016) (xy 356.455795 -34.807769)
			(xy 356.478291 -34.857212) (xy 356.493547 -34.909347) (xy 356.501255 -34.963118) (xy 356.501696 -34.990024)
			(xy 357.566974 -34.990024) (xy 357.571045 -34.934402) (xy 357.583171 -34.879965) (xy 357.603094 -34.827874)
			(xy 357.63039 -34.779239) (xy 357.664476 -34.735096) (xy 357.704625 -34.696387) (xy 357.749983 -34.663936)
			(xy 357.799583 -34.638435) (xy 357.852367 -34.620428) (xy 357.90721 -34.610298) (xy 357.962944 -34.608261)
			(xy 358.018381 -34.614361) (xy 358.072338 -34.628467) (xy 358.123667 -34.650279) (xy 358.171273 -34.679333)
			(xy 358.214141 -34.715008) (xy 358.251358 -34.756545) (xy 358.282131 -34.803058) (xy 358.305803 -34.853555)
			(xy 358.321871 -34.906962) (xy 358.329991 -34.962138) (xy 358.3305 -34.990024) (xy 359.972862 -34.990024)
			(xy 359.976933 -34.934402) (xy 359.989059 -34.879965) (xy 360.008982 -34.827874) (xy 360.036278 -34.779239)
			(xy 360.070364 -34.735096) (xy 360.110513 -34.696387) (xy 360.155871 -34.663936) (xy 360.205471 -34.638435)
			(xy 360.258255 -34.620428) (xy 360.313098 -34.610298) (xy 360.368832 -34.608261) (xy 360.424269 -34.614361)
			(xy 360.478226 -34.628467) (xy 360.529555 -34.650279) (xy 360.577161 -34.679333) (xy 360.620029 -34.715008)
			(xy 360.657246 -34.756545) (xy 360.688019 -34.803058) (xy 360.711691 -34.853555) (xy 360.727759 -34.906962)
			(xy 360.735879 -34.962138) (xy 360.736388 -34.990024) (xy 361.190792 -34.990024) (xy 361.194863 -34.934402)
			(xy 361.206989 -34.879965) (xy 361.226912 -34.827874) (xy 361.254208 -34.779239) (xy 361.288294 -34.735096)
			(xy 361.328443 -34.696387) (xy 361.373801 -34.663936) (xy 361.423401 -34.638435) (xy 361.476185 -34.620428)
			(xy 361.531028 -34.610298) (xy 361.586762 -34.608261) (xy 361.642199 -34.614361) (xy 361.696156 -34.628467)
			(xy 361.747485 -34.650279) (xy 361.795091 -34.679333) (xy 361.837959 -34.715008) (xy 361.875176 -34.756545)
			(xy 361.905949 -34.803058) (xy 361.929621 -34.853555) (xy 361.945689 -34.906962) (xy 361.953809 -34.962138)
			(xy 361.954318 -34.990024) (xy 364.198914 -34.990024) (xy 364.202985 -34.934402) (xy 364.215111 -34.879965)
			(xy 364.235034 -34.827874) (xy 364.26233 -34.779239) (xy 364.296416 -34.735096) (xy 364.336565 -34.696387)
			(xy 364.381923 -34.663936) (xy 364.431523 -34.638435) (xy 364.484307 -34.620428) (xy 364.53915 -34.610298)
			(xy 364.594884 -34.608261) (xy 364.650321 -34.614361) (xy 364.704278 -34.628467) (xy 364.755607 -34.650279)
			(xy 364.803213 -34.679333) (xy 364.846081 -34.715008) (xy 364.883298 -34.756545) (xy 364.914071 -34.803058)
			(xy 364.937743 -34.853555) (xy 364.953811 -34.906962) (xy 364.961931 -34.962138) (xy 364.96244 -34.990024)
			(xy 364.961931 -35.01791) (xy 364.953811 -35.073086) (xy 364.937743 -35.126493) (xy 364.914071 -35.17699)
			(xy 364.883298 -35.223503) (xy 364.846249 -35.264852) (xy 378.202442 -35.264852) (xy 378.206513 -35.20923)
			(xy 378.218639 -35.154793) (xy 378.238562 -35.102702) (xy 378.265858 -35.054067) (xy 378.299944 -35.009924)
			(xy 378.340093 -34.971215) (xy 378.385451 -34.938764) (xy 378.435051 -34.913263) (xy 378.487835 -34.895256)
			(xy 378.542678 -34.885126) (xy 378.598412 -34.883089) (xy 378.653849 -34.889189) (xy 378.707806 -34.903295)
			(xy 378.759135 -34.925107) (xy 378.806741 -34.954161) (xy 378.849609 -34.989836) (xy 378.886826 -35.031373)
			(xy 378.917599 -35.077886) (xy 378.941271 -35.128383) (xy 378.957339 -35.18179) (xy 378.965459 -35.236966)
			(xy 378.965968 -35.264852) (xy 378.965459 -35.292738) (xy 378.957339 -35.347914) (xy 378.941271 -35.401321)
			(xy 378.917599 -35.451818) (xy 378.886826 -35.498331) (xy 378.849609 -35.539868) (xy 378.806741 -35.575543)
			(xy 378.759135 -35.604597) (xy 378.707806 -35.626409) (xy 378.653849 -35.640515) (xy 378.598412 -35.646615)
			(xy 378.542678 -35.644578) (xy 378.487835 -35.634448) (xy 378.435051 -35.616441) (xy 378.385451 -35.59094)
			(xy 378.340093 -35.558489) (xy 378.299944 -35.51978) (xy 378.265858 -35.475637) (xy 378.238562 -35.427002)
			(xy 378.218639 -35.374911) (xy 378.206513 -35.320474) (xy 378.202442 -35.264852) (xy 364.846249 -35.264852)
			(xy 364.846081 -35.26504) (xy 364.803213 -35.300715) (xy 364.755607 -35.329769) (xy 364.704278 -35.351581)
			(xy 364.650321 -35.365687) (xy 364.594884 -35.371787) (xy 364.53915 -35.36975) (xy 364.484307 -35.35962)
			(xy 364.431523 -35.341613) (xy 364.381923 -35.316112) (xy 364.336565 -35.283661) (xy 364.296416 -35.244952)
			(xy 364.26233 -35.200809) (xy 364.235034 -35.152174) (xy 364.215111 -35.100083) (xy 364.202985 -35.045646)
			(xy 364.198914 -34.990024) (xy 361.954318 -34.990024) (xy 361.953809 -35.01791) (xy 361.945689 -35.073086)
			(xy 361.929621 -35.126493) (xy 361.905949 -35.17699) (xy 361.875176 -35.223503) (xy 361.837959 -35.26504)
			(xy 361.795091 -35.300715) (xy 361.747485 -35.329769) (xy 361.696156 -35.351581) (xy 361.642199 -35.365687)
			(xy 361.586762 -35.371787) (xy 361.531028 -35.36975) (xy 361.476185 -35.35962) (xy 361.423401 -35.341613)
			(xy 361.373801 -35.316112) (xy 361.328443 -35.283661) (xy 361.288294 -35.244952) (xy 361.254208 -35.200809)
			(xy 361.226912 -35.152174) (xy 361.206989 -35.100083) (xy 361.194863 -35.045646) (xy 361.190792 -34.990024)
			(xy 360.736388 -34.990024) (xy 360.735879 -35.01791) (xy 360.727759 -35.073086) (xy 360.711691 -35.126493)
			(xy 360.688019 -35.17699) (xy 360.657246 -35.223503) (xy 360.620029 -35.26504) (xy 360.577161 -35.300715)
			(xy 360.529555 -35.329769) (xy 360.478226 -35.351581) (xy 360.424269 -35.365687) (xy 360.368832 -35.371787)
			(xy 360.313098 -35.36975) (xy 360.258255 -35.35962) (xy 360.205471 -35.341613) (xy 360.155871 -35.316112)
			(xy 360.110513 -35.283661) (xy 360.070364 -35.244952) (xy 360.036278 -35.200809) (xy 360.008982 -35.152174)
			(xy 359.989059 -35.100083) (xy 359.976933 -35.045646) (xy 359.972862 -34.990024) (xy 358.3305 -34.990024)
			(xy 358.329991 -35.01791) (xy 358.321871 -35.073086) (xy 358.305803 -35.126493) (xy 358.282131 -35.17699)
			(xy 358.251358 -35.223503) (xy 358.214141 -35.26504) (xy 358.171273 -35.300715) (xy 358.123667 -35.329769)
			(xy 358.072338 -35.351581) (xy 358.018381 -35.365687) (xy 357.962944 -35.371787) (xy 357.90721 -35.36975)
			(xy 357.852367 -35.35962) (xy 357.799583 -35.341613) (xy 357.749983 -35.316112) (xy 357.704625 -35.283661)
			(xy 357.664476 -35.244952) (xy 357.63039 -35.200809) (xy 357.603094 -35.152174) (xy 357.583171 -35.100083)
			(xy 357.571045 -35.045646) (xy 357.566974 -34.990024) (xy 356.501696 -34.990024) (xy 356.5017 -34.990278)
			(xy 356.501238 -35.017532) (xy 356.493484 -35.071485) (xy 356.478129 -35.123785) (xy 356.455488 -35.173367)
			(xy 356.426021 -35.219222) (xy 356.390327 -35.260417) (xy 356.349133 -35.296112) (xy 356.303279 -35.325581)
			(xy 356.253698 -35.348225) (xy 356.201398 -35.363581) (xy 356.147446 -35.371337) (xy 356.120192 -35.371786)
			(xy 356.093228 -35.371326) (xy 356.039835 -35.36374) (xy 355.988044 -35.348707) (xy 355.938888 -35.326525)
			(xy 355.893349 -35.297639) (xy 355.852333 -35.262624) (xy 355.816661 -35.222179) (xy 355.787043 -35.177112)
			(xy 355.764072 -35.12832) (xy 355.748204 -35.076779) (xy 355.74351 -35.050222) (xy 355.74224 -35.042856)
			(xy 355.741732 -35.0393) (xy 355.73589 -35.03041) (xy 355.732998 -35.026193) (xy 355.725825 -35.018907)
			(xy 355.721666 -35.015932) (xy 355.658928 -34.974276) (xy 355.654434 -34.971439) (xy 355.644577 -34.967466)
			(xy 355.63937 -34.966402) (xy 355.629464 -34.964624) (xy 355.61905 -34.967164) (xy 355.592356 -34.973307)
			(xy 355.53798 -34.979929) (xy 355.510592 -34.980372) (xy 355.483204 -34.979924) (xy 355.428829 -34.9733)
			(xy 355.402134 -34.967164) (xy 355.39172 -34.964624) (xy 355.381814 -34.966402) (xy 355.376595 -34.96743)
			(xy 355.366731 -34.971402) (xy 355.362256 -34.974276) (xy 355.299518 -35.015932) (xy 355.295347 -35.018893)
			(xy 355.288174 -35.026183) (xy 355.285294 -35.03041) (xy 355.279452 -35.0393) (xy 355.278944 -35.042856)
			(xy 355.277674 -35.050222) (xy 355.272974 -35.076775) (xy 355.257082 -35.128302) (xy 355.234094 -35.17708)
			(xy 355.204469 -35.222136) (xy 355.168796 -35.262573) (xy 355.127787 -35.297586) (xy 355.082257 -35.326477)
			(xy 355.033114 -35.348672) (xy 354.981335 -35.363728) (xy 354.927953 -35.371345) (xy 354.900992 -35.371786)
			(xy 354.873743 -35.371299) (xy 354.819799 -35.363542) (xy 354.767508 -35.348187) (xy 354.717935 -35.325547)
			(xy 354.672088 -35.296082) (xy 354.630901 -35.260393) (xy 354.595213 -35.219205) (xy 354.565749 -35.173358)
			(xy 354.54311 -35.123784) (xy 354.527756 -35.071493) (xy 354.52 -35.017549) (xy 354.52 -34.963051)
			(xy 354.527756 -34.909107) (xy 354.54311 -34.856816) (xy 354.565749 -34.807242) (xy 354.595213 -34.761395)
			(xy 354.630901 -34.720207) (xy 354.672088 -34.684518) (xy 354.717935 -34.655053) (xy 354.767508 -34.632413)
			(xy 354.819799 -34.617058) (xy 354.873743 -34.609301) (xy 354.900992 -34.60877) (xy 354.901246 -34.60877)
			(xy 354.918295 -34.60895) (xy 354.952257 -34.611999) (xy 354.969064 -34.614866) (xy 354.979742 -34.616324)
			(xy 355.000654 -34.611189) (xy 355.00945 -34.60496) (xy 355.037136 -34.581084) (xy 355.044772 -34.57321)
			(xy 355.053083 -34.552935) (xy 355.053138 -34.541968) (xy 355.053138 -34.54146) (xy 355.052884 -34.522664)
			(xy 355.052884 -33.911286) (xy 355.052462 -33.901268) (xy 355.044789 -33.882758) (xy 355.030617 -33.868594)
			(xy 355.012103 -33.860932) (xy 355.002084 -33.860486) (xy 352.601022 -33.860486) (xy 352.591764 -33.86084)
			(xy 352.574439 -33.867354) (xy 352.56724 -33.873186) (xy 352.560382 -33.879282) (xy 352.552 -33.895284)
			(xy 352.55073 -33.904936) (xy 352.546841 -33.932264) (xy 352.532206 -33.985488) (xy 352.51005 -34.036045)
			(xy 352.480837 -34.08288) (xy 352.445176 -34.125013) (xy 352.403813 -34.161565) (xy 352.357613 -34.191771)
			(xy 352.30754 -34.215001) (xy 352.254641 -34.230768) (xy 352.200022 -34.238744) (xy 352.144823 -34.238762)
			(xy 352.090198 -34.230821) (xy 352.037289 -34.215088) (xy 351.987201 -34.19189) (xy 351.940981 -34.161713)
			(xy 351.899595 -34.125188) (xy 351.863908 -34.083078) (xy 351.834664 -34.036262) (xy 351.812476 -33.985719)
			(xy 351.797807 -33.932505) (xy 351.79381 -33.90519) (xy 351.79381 -33.904428) (xy 351.792252 -33.895408)
			(xy 351.783656 -33.879264) (xy 351.777046 -33.872932) (xy 351.770188 -33.86709) (xy 351.752916 -33.860486)
			(xy 351.115122 -33.860486) (xy 351.102562 -33.861122) (xy 351.080415 -33.872969) (xy 351.072958 -33.883092)
			(xy 351.055178 -33.912048) (xy 351.026476 -33.959292) (xy 351.023294 -33.9649) (xy 351.019576 -33.977244)
			(xy 351.01911 -33.983676) (xy 351.018602 -33.996376) (xy 351.024952 -34.008568) (xy 351.038241 -34.035715)
			(xy 351.057033 -34.09316) (xy 351.06655 -34.152846) (xy 351.067116 -34.183066) (xy 351.067116 -34.188654)
			(xy 351.066254 -34.215644) (xy 351.057862 -34.268987) (xy 351.04203 -34.320613) (xy 351.019076 -34.36949)
			(xy 350.989458 -34.414642) (xy 350.953769 -34.455166) (xy 350.912721 -34.490252) (xy 350.867136 -34.519198)
			(xy 350.817924 -34.541426) (xy 350.766069 -34.556492) (xy 350.712608 -34.564094) (xy 350.685608 -34.564574)
			(xy 350.658998 -34.56412) (xy 350.606292 -34.556739) (xy 350.555124 -34.542105) (xy 350.506485 -34.520503)
			(xy 350.46132 -34.492351) (xy 350.420506 -34.458196) (xy 350.384834 -34.4187) (xy 350.354997 -34.374631)
			(xy 350.331574 -34.326843) (xy 350.322896 -34.301684) (xy 350.319848 -34.292286) (xy 350.31426 -34.285428)
			(xy 350.311424 -34.282071) (xy 350.304784 -34.276317) (xy 350.301052 -34.273998) (xy 350.242886 -34.2392)
			(xy 350.239029 -34.236981) (xy 350.230727 -34.233781) (xy 350.226376 -34.23285) (xy 350.217994 -34.231326)
			(xy 350.208342 -34.233104) (xy 350.191469 -34.235956) (xy 350.157382 -34.239009) (xy 350.14027 -34.2392)
			(xy 350.138238 -34.2392) (xy 350.110749 -34.238577) (xy 350.056376 -34.2304) (xy 350.003742 -34.214498)
			(xy 349.953938 -34.1912) (xy 349.907996 -34.160991) (xy 349.86687 -34.124496) (xy 349.831412 -34.082472)
			(xy 349.802358 -34.035791) (xy 349.78031 -33.985421) (xy 349.765725 -33.932407) (xy 349.76181 -33.90519)
			(xy 349.76181 -33.904428) (xy 349.760252 -33.895408) (xy 349.751656 -33.879264) (xy 349.745046 -33.872932)
			(xy 349.738188 -33.86709) (xy 349.720916 -33.860486) (xy 332.655672 -33.860486) (xy 332.645667 -33.860978)
			(xy 332.627182 -33.868642) (xy 332.613035 -33.882794) (xy 332.605376 -33.901281) (xy 332.604872 -33.911286)
			(xy 332.604872 -34.241232) (xy 332.604872 -34.241994) (xy 332.605566 -34.252336) (xy 332.614081 -34.271213)
			(xy 332.621382 -34.27857) (xy 332.622652 -34.27984) (xy 332.65745 -34.309558) (xy 332.682088 -34.330386)
			(xy 332.686224 -34.333703) (xy 332.695577 -34.338687) (xy 332.70063 -34.340292) (xy 332.711044 -34.34334)
			(xy 332.72222 -34.341562) (xy 332.737046 -34.339387) (xy 332.766926 -34.337095) (xy 332.78191 -34.33699)
			(xy 332.782164 -34.33699) (xy 332.809366 -34.337548) (xy 332.863198 -34.345427) (xy 332.915366 -34.360875)
			(xy 332.964809 -34.383576) (xy 333.010526 -34.413071) (xy 333.05159 -34.448762) (xy 333.087166 -34.489925)
			(xy 333.116534 -34.535724) (xy 333.139098 -34.58523) (xy 333.1544 -34.637441) (xy 333.162129 -34.691295)
			(xy 333.162656 -34.718498) (xy 333.16217 -34.745751) (xy 333.154414 -34.799701) (xy 333.13906 -34.851999)
			(xy 333.11642 -34.901579) (xy 333.086954 -34.947433) (xy 333.051263 -34.988628) (xy 333.010074 -35.024324)
			(xy 332.964223 -35.053796) (xy 332.914646 -35.076442) (xy 332.86235 -35.091804) (xy 332.808401 -35.099567)
			(xy 332.781148 -35.100006) (xy 332.780894 -35.100006) (xy 332.75139 -35.099448) (xy 332.693087 -35.090351)
			(xy 332.636879 -35.072389) (xy 332.584104 -35.045992) (xy 332.536021 -35.011788) (xy 332.493773 -34.970592)
			(xy 332.475586 -34.947352) (xy 332.470506 -34.94024) (xy 332.448154 -34.925508) (xy 332.444232 -34.922976)
			(xy 332.435668 -34.919262) (xy 332.431136 -34.918142) (xy 332.409546 -34.913316) (xy 332.400534 -34.911716)
			(xy 332.382429 -34.91431) (xy 332.37424 -34.918396) (xy 332.373732 -34.91865) (xy 332.355351 -34.928877)
			(xy 332.317064 -34.946307) (xy 332.297278 -34.953448) (xy 332.273078 -34.961492) (xy 332.223344 -34.972787)
			(xy 332.172664 -34.97849) (xy 332.147164 -34.978848) (xy 332.121664 -34.978485) (xy 332.070984 -34.972787)
			(xy 332.021251 -34.961489) (xy 331.99705 -34.953448) (xy 331.977266 -34.946302) (xy 331.938979 -34.928874)
			(xy 331.920596 -34.91865) (xy 331.920088 -34.918396) (xy 331.911888 -34.914346) (xy 331.893796 -34.911759)
			(xy 331.884782 -34.913316) (xy 331.863192 -34.918142) (xy 331.85867 -34.919293) (xy 331.850105 -34.922995)
			(xy 331.846174 -34.925508) (xy 331.823822 -34.94024) (xy 331.818742 -34.947352) (xy 331.800591 -34.970651)
			(xy 331.758311 -35.011889) (xy 331.710179 -35.046114) (xy 331.657346 -35.072509) (xy 331.601074 -35.090441)
			(xy 331.542711 -35.099483) (xy 331.51318 -35.100006) (xy 331.502258 -35.100006) (xy 331.502004 -35.099752)
			(xy 331.475287 -35.098518) (xy 331.42257 -35.0895) (xy 331.371628 -35.073209) (xy 331.32346 -35.049965)
			(xy 331.279009 -35.020223) (xy 331.239146 -34.984566) (xy 331.204653 -34.943693) (xy 331.176204 -34.898403)
			(xy 331.154358 -34.849585) (xy 331.139542 -34.798195) (xy 331.132047 -34.745239) (xy 331.131672 -34.718498)
			(xy 331.132158 -34.691246) (xy 331.139915 -34.637298) (xy 331.15527 -34.585002) (xy 331.177911 -34.535424)
			(xy 331.207377 -34.489572) (xy 331.243068 -34.448381) (xy 331.284258 -34.412687) (xy 331.330108 -34.383219)
			(xy 331.379685 -34.360576) (xy 331.43198 -34.345218) (xy 331.485928 -34.337459) (xy 331.51318 -34.33699)
			(xy 331.527973 -34.337135) (xy 331.557469 -34.339427) (xy 331.572108 -34.341562) (xy 331.583284 -34.34334)
			(xy 331.593698 -34.340292) (xy 331.598746 -34.338678) (xy 331.608095 -34.333688) (xy 331.61224 -34.330386)
			(xy 331.636878 -34.309558) (xy 331.671676 -34.27984) (xy 331.672946 -34.27857) (xy 331.680281 -34.271233)
			(xy 331.688818 -34.252348) (xy 331.689456 -34.241994) (xy 331.689456 -33.911286) (xy 331.689033 -33.90127)
			(xy 331.681359 -33.882765) (xy 331.667186 -33.868608) (xy 331.648673 -33.860955) (xy 331.638656 -33.860486)
			(xy 317.9191 -33.860486) (xy 317.909091 -33.860974) (xy 317.890597 -33.868633) (xy 317.876441 -33.882785)
			(xy 317.868776 -33.901277) (xy 317.8683 -33.911286) (xy 317.8683 -34.52241) (xy 317.867792 -34.541714)
			(xy 317.867792 -34.544762) (xy 317.868433 -34.555078) (xy 317.876821 -34.573948) (xy 317.884048 -34.581338)
			(xy 317.90132 -34.59607) (xy 317.901828 -34.596578) (xy 317.909702 -34.603436) (xy 317.918717 -34.610337)
			(xy 317.940601 -34.616275) (xy 317.951866 -34.614866) (xy 317.968676 -34.612023) (xy 318.002636 -34.608973)
			(xy 318.019684 -34.60877) (xy 318.02197 -34.60877) (xy 318.049125 -34.609396) (xy 318.10285 -34.617391)
			(xy 318.154898 -34.632925) (xy 318.204217 -34.655683) (xy 318.24981 -34.685205) (xy 318.290755 -34.720895)
			(xy 318.326225 -34.762031) (xy 318.355502 -34.807782) (xy 318.377995 -34.857222) (xy 318.393249 -34.909353)
			(xy 318.400955 -34.96312) (xy 318.401441 -34.990024) (xy 319.46672 -34.990024) (xy 319.470791 -34.934402)
			(xy 319.482917 -34.879965) (xy 319.50284 -34.827874) (xy 319.530136 -34.779239) (xy 319.564222 -34.735096)
			(xy 319.604371 -34.696387) (xy 319.649729 -34.663936) (xy 319.699329 -34.638435) (xy 319.752113 -34.620428)
			(xy 319.806956 -34.610298) (xy 319.86269 -34.608261) (xy 319.918127 -34.614361) (xy 319.972084 -34.628467)
			(xy 320.023413 -34.650279) (xy 320.071019 -34.679333) (xy 320.113887 -34.715008) (xy 320.151104 -34.756545)
			(xy 320.181877 -34.803058) (xy 320.205549 -34.853555) (xy 320.221617 -34.906962) (xy 320.229737 -34.962138)
			(xy 320.230246 -34.990024) (xy 321.872608 -34.990024) (xy 321.876679 -34.934402) (xy 321.888805 -34.879965)
			(xy 321.908728 -34.827874) (xy 321.936024 -34.779239) (xy 321.97011 -34.735096) (xy 322.010259 -34.696387)
			(xy 322.055617 -34.663936) (xy 322.105217 -34.638435) (xy 322.158001 -34.620428) (xy 322.212844 -34.610298)
			(xy 322.268578 -34.608261) (xy 322.324015 -34.614361) (xy 322.377972 -34.628467) (xy 322.429301 -34.650279)
			(xy 322.476907 -34.679333) (xy 322.519775 -34.715008) (xy 322.556992 -34.756545) (xy 322.587765 -34.803058)
			(xy 322.611437 -34.853555) (xy 322.627505 -34.906962) (xy 322.635625 -34.962138) (xy 322.636134 -34.990024)
			(xy 323.100952 -34.990024) (xy 323.105023 -34.934402) (xy 323.117149 -34.879965) (xy 323.137072 -34.827874)
			(xy 323.164368 -34.779239) (xy 323.198454 -34.735096) (xy 323.238603 -34.696387) (xy 323.283961 -34.663936)
			(xy 323.333561 -34.638435) (xy 323.386345 -34.620428) (xy 323.441188 -34.610298) (xy 323.496922 -34.608261)
			(xy 323.552359 -34.614361) (xy 323.606316 -34.628467) (xy 323.657645 -34.650279) (xy 323.705251 -34.679333)
			(xy 323.748119 -34.715008) (xy 323.785336 -34.756545) (xy 323.816109 -34.803058) (xy 323.839781 -34.853555)
			(xy 323.855849 -34.906962) (xy 323.863969 -34.962138) (xy 323.864478 -34.990024) (xy 326.09866 -34.990024)
			(xy 326.102731 -34.934402) (xy 326.114857 -34.879965) (xy 326.13478 -34.827874) (xy 326.162076 -34.779239)
			(xy 326.196162 -34.735096) (xy 326.236311 -34.696387) (xy 326.281669 -34.663936) (xy 326.331269 -34.638435)
			(xy 326.384053 -34.620428) (xy 326.438896 -34.610298) (xy 326.49463 -34.608261) (xy 326.550067 -34.614361)
			(xy 326.604024 -34.628467) (xy 326.655353 -34.650279) (xy 326.702959 -34.679333) (xy 326.745827 -34.715008)
			(xy 326.783044 -34.756545) (xy 326.813817 -34.803058) (xy 326.837489 -34.853555) (xy 326.853557 -34.906962)
			(xy 326.861677 -34.962138) (xy 326.862186 -34.990024) (xy 326.861677 -35.01791) (xy 326.853557 -35.073086)
			(xy 326.837489 -35.126493) (xy 326.813817 -35.17699) (xy 326.783044 -35.223503) (xy 326.745995 -35.264852)
			(xy 352.202494 -35.264852) (xy 352.206565 -35.20923) (xy 352.218691 -35.154793) (xy 352.238614 -35.102702)
			(xy 352.26591 -35.054067) (xy 352.299996 -35.009924) (xy 352.340145 -34.971215) (xy 352.385503 -34.938764)
			(xy 352.435103 -34.913263) (xy 352.487887 -34.895256) (xy 352.54273 -34.885126) (xy 352.598464 -34.883089)
			(xy 352.653901 -34.889189) (xy 352.707858 -34.903295) (xy 352.759187 -34.925107) (xy 352.806793 -34.954161)
			(xy 352.849661 -34.989836) (xy 352.886878 -35.031373) (xy 352.917651 -35.077886) (xy 352.941323 -35.128383)
			(xy 352.957391 -35.18179) (xy 352.965511 -35.236966) (xy 352.96602 -35.264852) (xy 352.965511 -35.292738)
			(xy 352.957391 -35.347914) (xy 352.941323 -35.401321) (xy 352.917651 -35.451818) (xy 352.886878 -35.498331)
			(xy 352.849661 -35.539868) (xy 352.806793 -35.575543) (xy 352.759187 -35.604597) (xy 352.707858 -35.626409)
			(xy 352.653901 -35.640515) (xy 352.598464 -35.646615) (xy 352.54273 -35.644578) (xy 352.487887 -35.634448)
			(xy 352.435103 -35.616441) (xy 352.385503 -35.59094) (xy 352.340145 -35.558489) (xy 352.299996 -35.51978)
			(xy 352.26591 -35.475637) (xy 352.238614 -35.427002) (xy 352.218691 -35.374911) (xy 352.206565 -35.320474)
			(xy 352.202494 -35.264852) (xy 326.745995 -35.264852) (xy 326.745827 -35.26504) (xy 326.702959 -35.300715)
			(xy 326.655353 -35.329769) (xy 326.604024 -35.351581) (xy 326.550067 -35.365687) (xy 326.49463 -35.371787)
			(xy 326.438896 -35.36975) (xy 326.384053 -35.35962) (xy 326.331269 -35.341613) (xy 326.281669 -35.316112)
			(xy 326.236311 -35.283661) (xy 326.196162 -35.244952) (xy 326.162076 -35.200809) (xy 326.13478 -35.152174)
			(xy 326.114857 -35.100083) (xy 326.102731 -35.045646) (xy 326.09866 -34.990024) (xy 323.864478 -34.990024)
			(xy 323.863969 -35.01791) (xy 323.855849 -35.073086) (xy 323.839781 -35.126493) (xy 323.816109 -35.17699)
			(xy 323.785336 -35.223503) (xy 323.748119 -35.26504) (xy 323.705251 -35.300715) (xy 323.657645 -35.329769)
			(xy 323.606316 -35.351581) (xy 323.552359 -35.365687) (xy 323.496922 -35.371787) (xy 323.441188 -35.36975)
			(xy 323.386345 -35.35962) (xy 323.333561 -35.341613) (xy 323.283961 -35.316112) (xy 323.238603 -35.283661)
			(xy 323.198454 -35.244952) (xy 323.164368 -35.200809) (xy 323.137072 -35.152174) (xy 323.117149 -35.100083)
			(xy 323.105023 -35.045646) (xy 323.100952 -34.990024) (xy 322.636134 -34.990024) (xy 322.635625 -35.01791)
			(xy 322.627505 -35.073086) (xy 322.611437 -35.126493) (xy 322.587765 -35.17699) (xy 322.556992 -35.223503)
			(xy 322.519775 -35.26504) (xy 322.476907 -35.300715) (xy 322.429301 -35.329769) (xy 322.377972 -35.351581)
			(xy 322.324015 -35.365687) (xy 322.268578 -35.371787) (xy 322.212844 -35.36975) (xy 322.158001 -35.35962)
			(xy 322.105217 -35.341613) (xy 322.055617 -35.316112) (xy 322.010259 -35.283661) (xy 321.97011 -35.244952)
			(xy 321.936024 -35.200809) (xy 321.908728 -35.152174) (xy 321.888805 -35.100083) (xy 321.876679 -35.045646)
			(xy 321.872608 -34.990024) (xy 320.230246 -34.990024) (xy 320.229737 -35.01791) (xy 320.221617 -35.073086)
			(xy 320.205549 -35.126493) (xy 320.181877 -35.17699) (xy 320.151104 -35.223503) (xy 320.113887 -35.26504)
			(xy 320.071019 -35.300715) (xy 320.023413 -35.329769) (xy 319.972084 -35.351581) (xy 319.918127 -35.365687)
			(xy 319.86269 -35.371787) (xy 319.806956 -35.36975) (xy 319.752113 -35.35962) (xy 319.699329 -35.341613)
			(xy 319.649729 -35.316112) (xy 319.604371 -35.283661) (xy 319.564222 -35.244952) (xy 319.530136 -35.200809)
			(xy 319.50284 -35.152174) (xy 319.482917 -35.100083) (xy 319.470791 -35.045646) (xy 319.46672 -34.990024)
			(xy 318.401441 -34.990024) (xy 318.401446 -34.990278) (xy 318.401001 -35.017058) (xy 318.393524 -35.070092)
			(xy 318.3787 -35.121559) (xy 318.35682 -35.170445) (xy 318.328315 -35.215789) (xy 318.293745 -35.256698)
			(xy 318.253792 -35.292368) (xy 318.209241 -35.322096) (xy 318.160968 -35.345298) (xy 318.109923 -35.361518)
			(xy 318.057112 -35.370435) (xy 318.030352 -35.371532) (xy 318.017906 -35.37204) (xy 318.007492 -35.377628)
			(xy 318.00234 -35.380695) (xy 317.993491 -35.38878) (xy 317.989966 -35.39363) (xy 317.974726 -35.415728)
			(xy 317.94323 -35.461702) (xy 317.94001 -35.466803) (xy 317.935768 -35.478092) (xy 317.934848 -35.484054)
			(xy 317.933324 -35.495484) (xy 317.936372 -35.50412) (xy 317.947123 -35.535751) (xy 317.958749 -35.601531)
			(xy 317.959486 -35.63493) (xy 317.959486 -35.635184) (xy 317.959 -35.662435) (xy 317.951244 -35.716383)
			(xy 317.935889 -35.768678) (xy 317.913247 -35.818255) (xy 317.883781 -35.864105) (xy 317.84809 -35.905296)
			(xy 317.806899 -35.940987) (xy 317.761049 -35.970453) (xy 317.711472 -35.993095) (xy 317.659177 -36.00845)
			(xy 317.605229 -36.016206) (xy 317.550727 -36.016206) (xy 317.496779 -36.00845) (xy 317.444484 -35.993095)
			(xy 317.394907 -35.970453) (xy 317.349057 -35.940987) (xy 317.307866 -35.905296) (xy 317.272175 -35.864105)
			(xy 317.242709 -35.818255) (xy 317.220067 -35.768678) (xy 317.204712 -35.716383) (xy 317.196956 -35.662435)
			(xy 317.19647 -35.635184) (xy 317.196917 -35.608406) (xy 317.204399 -35.555376) (xy 317.219227 -35.503915)
			(xy 317.241109 -35.455034) (xy 317.269616 -35.409697) (xy 317.304185 -35.368793) (xy 317.344138 -35.333129)
			(xy 317.388688 -35.303406) (xy 317.436958 -35.280209) (xy 317.488 -35.263993) (xy 317.540808 -35.255079)
			(xy 317.567564 -35.25393) (xy 317.58001 -35.253422) (xy 317.595758 -35.244786) (xy 317.604648 -35.236912)
			(xy 317.607442 -35.232848) (xy 317.654686 -35.163252) (xy 317.657896 -35.158286) (xy 317.662128 -35.147247)
			(xy 317.663068 -35.141408) (xy 317.664592 -35.129978) (xy 317.660528 -35.118294) (xy 317.656863 -35.107666)
			(xy 317.650634 -35.086063) (xy 317.648082 -35.075114) (xy 317.643256 -35.050222) (xy 317.641986 -35.042856)
			(xy 317.641478 -35.0393) (xy 317.635636 -35.03041) (xy 317.632746 -35.026191) (xy 317.625577 -35.0189)
			(xy 317.621412 -35.015932) (xy 317.558674 -34.974276) (xy 317.554178 -34.971444) (xy 317.544319 -34.967481)
			(xy 317.539116 -34.966402) (xy 317.52921 -34.964624) (xy 317.518796 -34.967164) (xy 317.492102 -34.97331)
			(xy 317.437726 -34.979938) (xy 317.410338 -34.980372) (xy 317.38295 -34.979927) (xy 317.328574 -34.973308)
			(xy 317.30188 -34.967164) (xy 317.291466 -34.964624) (xy 317.28156 -34.966402) (xy 317.27634 -34.967425)
			(xy 317.26647 -34.97139) (xy 317.262002 -34.974276) (xy 317.199264 -35.015932) (xy 317.195096 -35.018896)
			(xy 317.187929 -35.02619) (xy 317.18504 -35.03041) (xy 317.179198 -35.0393) (xy 317.17869 -35.042856)
			(xy 317.17742 -35.050222) (xy 317.17272 -35.076773) (xy 317.156826 -35.128297) (xy 317.133838 -35.177071)
			(xy 317.104212 -35.222123) (xy 317.068538 -35.262555) (xy 317.027528 -35.297563) (xy 316.981998 -35.326448)
			(xy 316.932855 -35.348637) (xy 316.881078 -35.363686) (xy 316.827698 -35.371296) (xy 316.800738 -35.371786)
			(xy 316.773485 -35.371325) (xy 316.719533 -35.363573) (xy 316.667234 -35.348221) (xy 316.617652 -35.325582)
			(xy 316.571796 -35.296117) (xy 316.530601 -35.260425) (xy 316.494906 -35.219234) (xy 316.465436 -35.173382)
			(xy 316.442792 -35.123802) (xy 316.427435 -35.071504) (xy 316.419677 -35.017553) (xy 316.419677 -34.963047)
			(xy 316.427435 -34.909096) (xy 316.442792 -34.856798) (xy 316.465436 -34.807218) (xy 316.494906 -34.761366)
			(xy 316.530601 -34.720175) (xy 316.571796 -34.684483) (xy 316.617652 -34.655018) (xy 316.667234 -34.632379)
			(xy 316.719533 -34.617027) (xy 316.773485 -34.609275) (xy 316.800738 -34.60877) (xy 316.800992 -34.60877)
			(xy 316.818041 -34.608952) (xy 316.852002 -34.612005) (xy 316.86881 -34.614866) (xy 316.879424 -34.616187)
			(xy 316.900165 -34.611071) (xy 316.908942 -34.60496) (xy 316.937136 -34.580576) (xy 316.944649 -34.57272)
			(xy 316.952791 -34.552586) (xy 316.952884 -34.541714) (xy 316.952376 -34.52241) (xy 316.952376 -33.911286)
			(xy 316.951953 -33.901268) (xy 316.94428 -33.88276) (xy 316.930108 -33.868598) (xy 316.911594 -33.860939)
			(xy 316.901576 -33.860486) (xy 314.500768 -33.860486) (xy 314.491507 -33.860832) (xy 314.474171 -33.867335)
			(xy 314.466986 -33.873186) (xy 314.460128 -33.879282) (xy 314.451746 -33.895284) (xy 314.450476 -33.904936)
			(xy 314.446587 -33.932268) (xy 314.431951 -33.985498) (xy 314.409793 -34.036061) (xy 314.380577 -34.082902)
			(xy 314.344913 -34.125041) (xy 314.303546 -34.161598) (xy 314.25734 -34.191808) (xy 314.207261 -34.215042)
			(xy 314.154356 -34.230812) (xy 314.099731 -34.238789) (xy 314.044525 -34.238808) (xy 313.989894 -34.230867)
			(xy 313.936978 -34.215132) (xy 313.886884 -34.191933) (xy 313.840658 -34.161753) (xy 313.799267 -34.125224)
			(xy 313.763574 -34.083109) (xy 313.734326 -34.036288) (xy 313.712135 -33.985739) (xy 313.697463 -33.932519)
			(xy 313.693556 -33.90519) (xy 313.693556 -33.904428) (xy 313.692 -33.895407) (xy 313.683409 -33.879257)
			(xy 313.676792 -33.872932) (xy 313.669934 -33.86709) (xy 313.652662 -33.860486) (xy 313.014868 -33.860486)
			(xy 313.002315 -33.861134) (xy 312.980188 -33.872993) (xy 312.972704 -33.883092) (xy 312.954924 -33.912048)
			(xy 312.926222 -33.959292) (xy 312.923037 -33.964899) (xy 312.919316 -33.977243) (xy 312.918856 -33.983676)
			(xy 312.918348 -33.996376) (xy 312.924698 -34.008568) (xy 312.937986 -34.035716) (xy 312.956776 -34.09316)
			(xy 312.966292 -34.152846) (xy 312.966862 -34.183066) (xy 312.966862 -34.188654) (xy 312.965934 -34.216931)
			(xy 312.956762 -34.272757) (xy 312.939446 -34.326617) (xy 312.914367 -34.37733) (xy 312.882075 -34.423783)
			(xy 312.843277 -34.464959) (xy 312.798825 -34.499955) (xy 312.749692 -34.528002) (xy 312.696956 -34.548488)
			(xy 312.641774 -34.560961) (xy 312.585354 -34.56515) (xy 312.528934 -34.560961) (xy 312.473752 -34.548488)
			(xy 312.421016 -34.528002) (xy 312.371883 -34.499955) (xy 312.327431 -34.464959) (xy 312.288633 -34.423783)
			(xy 312.256341 -34.37733) (xy 312.231262 -34.326617) (xy 312.213946 -34.272757) (xy 312.204774 -34.216931)
			(xy 312.203846 -34.188654) (xy 312.203846 -34.183066) (xy 312.204397 -34.152843) (xy 312.213889 -34.093149)
			(xy 312.232694 -34.035704) (xy 312.24601 -34.008568) (xy 312.24601 -34.008314) (xy 312.248885 -34.002374)
			(xy 312.251831 -33.989514) (xy 312.251852 -33.982914) (xy 312.251344 -33.970468) (xy 312.215784 -33.912048)
			(xy 312.198004 -33.883092) (xy 312.190491 -33.873024) (xy 312.168383 -33.861157) (xy 312.15584 -33.860486)
			(xy 306.655724 -33.860486) (xy 306.645699 -33.860901) (xy 306.627171 -33.868566) (xy 306.612988 -33.882739)
			(xy 306.605309 -33.901261) (xy 306.604924 -33.911286) (xy 306.604924 -34.241232) (xy 306.604924 -34.241994)
			(xy 306.605616 -34.252337) (xy 306.614126 -34.27122) (xy 306.621434 -34.27857) (xy 306.622704 -34.27984)
			(xy 306.657502 -34.309558) (xy 306.68214 -34.330386) (xy 306.686273 -34.333707) (xy 306.695624 -34.3387)
			(xy 306.700682 -34.340292) (xy 306.711096 -34.34334) (xy 306.722272 -34.341562) (xy 306.737098 -34.339389)
			(xy 306.766978 -34.337101) (xy 306.781962 -34.33699) (xy 306.782216 -34.33699) (xy 306.80942 -34.337545)
			(xy 306.863258 -34.345419) (xy 306.915431 -34.360862) (xy 306.96488 -34.38356) (xy 307.010604 -34.413054)
			(xy 307.051673 -34.448745) (xy 307.087254 -34.489909) (xy 307.116627 -34.53571) (xy 307.139194 -34.58522)
			(xy 307.154498 -34.637434) (xy 307.162229 -34.691293) (xy 307.162708 -34.718498) (xy 307.162245 -34.745751)
			(xy 307.154488 -34.799702) (xy 307.139132 -34.852) (xy 307.11649 -34.901581) (xy 307.087022 -34.947434)
			(xy 307.051328 -34.988627) (xy 307.010136 -35.024321) (xy 306.964282 -35.053789) (xy 306.914702 -35.076432)
			(xy 306.862404 -35.091788) (xy 306.808453 -35.099545) (xy 306.7812 -35.100006) (xy 306.780946 -35.100006)
			(xy 306.75144 -35.099451) (xy 306.693133 -35.090361) (xy 306.636919 -35.072406) (xy 306.584138 -35.046013)
			(xy 306.536049 -35.011811) (xy 306.493795 -34.970616) (xy 306.475638 -34.947352) (xy 306.470558 -34.94024)
			(xy 306.448206 -34.925508) (xy 306.444283 -34.922979) (xy 306.435716 -34.919274) (xy 306.431188 -34.918142)
			(xy 306.409598 -34.913316) (xy 306.400587 -34.911725) (xy 306.382491 -34.914334) (xy 306.374292 -34.918396)
			(xy 306.373784 -34.91865) (xy 306.355402 -34.928876) (xy 306.317114 -34.946301) (xy 306.29733 -34.953448)
			(xy 306.273129 -34.96149) (xy 306.223395 -34.972779) (xy 306.172715 -34.978477) (xy 306.147216 -34.978848)
			(xy 306.121716 -34.978488) (xy 306.071034 -34.972796) (xy 306.021299 -34.961503) (xy 305.997102 -34.953448)
			(xy 305.977317 -34.946304) (xy 305.939028 -34.92888) (xy 305.920648 -34.91865) (xy 305.92014 -34.918396)
			(xy 305.911941 -34.914337) (xy 305.893845 -34.911732) (xy 305.884834 -34.913316) (xy 305.863244 -34.918142)
			(xy 305.858724 -34.919297) (xy 305.850164 -34.923005) (xy 305.846226 -34.925508) (xy 305.823874 -34.94024)
			(xy 305.818794 -34.947352) (xy 305.800644 -34.970654) (xy 305.758366 -35.011897) (xy 305.710235 -35.046129)
			(xy 305.657402 -35.072531) (xy 305.601129 -35.090471) (xy 305.542764 -35.099521) (xy 305.513232 -35.100006)
			(xy 305.50231 -35.100006) (xy 305.502056 -35.099752) (xy 305.475341 -35.098515) (xy 305.422629 -35.089492)
			(xy 305.371693 -35.073197) (xy 305.32353 -35.04995) (xy 305.279085 -35.020207) (xy 305.239228 -34.98455)
			(xy 305.20474 -34.943678) (xy 305.176296 -34.89839) (xy 305.154453 -34.849575) (xy 305.13964 -34.798189)
			(xy 305.132146 -34.745237) (xy 305.131724 -34.718498) (xy 305.132187 -34.691246) (xy 305.139945 -34.637297)
			(xy 305.155301 -34.585001) (xy 305.177944 -34.535423) (xy 305.207413 -34.489573) (xy 305.243107 -34.448383)
			(xy 305.2843 -34.412693) (xy 305.330153 -34.383228) (xy 305.379733 -34.36059) (xy 305.43203 -34.345238)
			(xy 305.48598 -34.337485) (xy 305.513232 -34.33699) (xy 305.528025 -34.337133) (xy 305.557522 -34.339422)
			(xy 305.57216 -34.341562) (xy 305.583336 -34.34334) (xy 305.59375 -34.340292) (xy 305.598796 -34.338673)
			(xy 305.608138 -34.333677) (xy 305.612292 -34.330386) (xy 305.63693 -34.309558) (xy 305.671728 -34.27984)
			(xy 305.672998 -34.27857) (xy 305.680339 -34.271236) (xy 305.688884 -34.25235) (xy 305.689508 -34.241994)
			(xy 305.689508 -33.911286) (xy 305.689017 -33.90128) (xy 305.681356 -33.882791) (xy 305.667204 -33.868641)
			(xy 305.648714 -33.860981) (xy 305.638708 -33.860486) (xy 291.919152 -33.860486) (xy 291.90915 -33.860982)
			(xy 291.890672 -33.86865) (xy 291.87653 -33.8828) (xy 291.868875 -33.901283) (xy 291.868352 -33.911286)
			(xy 291.868352 -34.52241) (xy 291.867844 -34.541714) (xy 291.867844 -34.544762) (xy 291.868487 -34.555077)
			(xy 291.876881 -34.573941) (xy 291.8841 -34.581338) (xy 291.901372 -34.59607) (xy 291.90188 -34.596578)
			(xy 291.909754 -34.603436) (xy 291.918771 -34.610327) (xy 291.940651 -34.616242) (xy 291.951918 -34.614866)
			(xy 291.968728 -34.612021) (xy 292.002688 -34.608966) (xy 292.019736 -34.60877) (xy 292.022022 -34.60877)
			(xy 292.049179 -34.609393) (xy 292.10291 -34.617382) (xy 292.154963 -34.632912) (xy 292.204288 -34.655667)
			(xy 292.249887 -34.685188) (xy 292.290838 -34.720878) (xy 292.326313 -34.762015) (xy 292.355595 -34.807768)
			(xy 292.378091 -34.857212) (xy 292.393347 -34.909346) (xy 292.401055 -34.963118) (xy 292.401494 -34.990024)
			(xy 293.466772 -34.990024) (xy 293.470843 -34.934402) (xy 293.482969 -34.879965) (xy 293.502892 -34.827874)
			(xy 293.530188 -34.779239) (xy 293.564274 -34.735096) (xy 293.604423 -34.696387) (xy 293.649781 -34.663936)
			(xy 293.699381 -34.638435) (xy 293.752165 -34.620428) (xy 293.807008 -34.610298) (xy 293.862742 -34.608261)
			(xy 293.918179 -34.614361) (xy 293.972136 -34.628467) (xy 294.023465 -34.650279) (xy 294.071071 -34.679333)
			(xy 294.113939 -34.715008) (xy 294.151156 -34.756545) (xy 294.181929 -34.803058) (xy 294.205601 -34.853555)
			(xy 294.221669 -34.906962) (xy 294.229789 -34.962138) (xy 294.230298 -34.990024) (xy 295.87266 -34.990024)
			(xy 295.876731 -34.934402) (xy 295.888857 -34.879965) (xy 295.90878 -34.827874) (xy 295.936076 -34.779239)
			(xy 295.970162 -34.735096) (xy 296.010311 -34.696387) (xy 296.055669 -34.663936) (xy 296.105269 -34.638435)
			(xy 296.158053 -34.620428) (xy 296.212896 -34.610298) (xy 296.26863 -34.608261) (xy 296.324067 -34.614361)
			(xy 296.378024 -34.628467) (xy 296.429353 -34.650279) (xy 296.476959 -34.679333) (xy 296.519827 -34.715008)
			(xy 296.557044 -34.756545) (xy 296.587817 -34.803058) (xy 296.611489 -34.853555) (xy 296.627557 -34.906962)
			(xy 296.635677 -34.962138) (xy 296.636186 -34.990024) (xy 297.200826 -34.990024) (xy 297.204897 -34.934402)
			(xy 297.217023 -34.879965) (xy 297.236946 -34.827874) (xy 297.264242 -34.779239) (xy 297.298328 -34.735096)
			(xy 297.338477 -34.696387) (xy 297.383835 -34.663936) (xy 297.433435 -34.638435) (xy 297.486219 -34.620428)
			(xy 297.541062 -34.610298) (xy 297.596796 -34.608261) (xy 297.652233 -34.614361) (xy 297.70619 -34.628467)
			(xy 297.757519 -34.650279) (xy 297.805125 -34.679333) (xy 297.847993 -34.715008) (xy 297.88521 -34.756545)
			(xy 297.915983 -34.803058) (xy 297.939655 -34.853555) (xy 297.955723 -34.906962) (xy 297.963843 -34.962138)
			(xy 297.964352 -34.990024) (xy 300.098712 -34.990024) (xy 300.102783 -34.934402) (xy 300.114909 -34.879965)
			(xy 300.134832 -34.827874) (xy 300.162128 -34.779239) (xy 300.196214 -34.735096) (xy 300.236363 -34.696387)
			(xy 300.281721 -34.663936) (xy 300.331321 -34.638435) (xy 300.384105 -34.620428) (xy 300.438948 -34.610298)
			(xy 300.494682 -34.608261) (xy 300.550119 -34.614361) (xy 300.604076 -34.628467) (xy 300.655405 -34.650279)
			(xy 300.703011 -34.679333) (xy 300.745879 -34.715008) (xy 300.783096 -34.756545) (xy 300.813869 -34.803058)
			(xy 300.837541 -34.853555) (xy 300.853609 -34.906962) (xy 300.861729 -34.962138) (xy 300.862238 -34.990024)
			(xy 300.861729 -35.01791) (xy 300.853609 -35.073086) (xy 300.837541 -35.126493) (xy 300.813869 -35.17699)
			(xy 300.783096 -35.223503) (xy 300.746047 -35.264852) (xy 314.10224 -35.264852) (xy 314.106311 -35.20923)
			(xy 314.118437 -35.154793) (xy 314.13836 -35.102702) (xy 314.165656 -35.054067) (xy 314.199742 -35.009924)
			(xy 314.239891 -34.971215) (xy 314.285249 -34.938764) (xy 314.334849 -34.913263) (xy 314.387633 -34.895256)
			(xy 314.442476 -34.885126) (xy 314.49821 -34.883089) (xy 314.553647 -34.889189) (xy 314.607604 -34.903295)
			(xy 314.658933 -34.925107) (xy 314.706539 -34.954161) (xy 314.749407 -34.989836) (xy 314.786624 -35.031373)
			(xy 314.817397 -35.077886) (xy 314.841069 -35.128383) (xy 314.857137 -35.18179) (xy 314.865257 -35.236966)
			(xy 314.865766 -35.264852) (xy 314.865257 -35.292738) (xy 314.857137 -35.347914) (xy 314.841069 -35.401321)
			(xy 314.817397 -35.451818) (xy 314.786624 -35.498331) (xy 314.749407 -35.539868) (xy 314.706539 -35.575543)
			(xy 314.658933 -35.604597) (xy 314.607604 -35.626409) (xy 314.553647 -35.640515) (xy 314.49821 -35.646615)
			(xy 314.442476 -35.644578) (xy 314.387633 -35.634448) (xy 314.334849 -35.616441) (xy 314.285249 -35.59094)
			(xy 314.239891 -35.558489) (xy 314.199742 -35.51978) (xy 314.165656 -35.475637) (xy 314.13836 -35.427002)
			(xy 314.118437 -35.374911) (xy 314.106311 -35.320474) (xy 314.10224 -35.264852) (xy 300.746047 -35.264852)
			(xy 300.745879 -35.26504) (xy 300.703011 -35.300715) (xy 300.655405 -35.329769) (xy 300.604076 -35.351581)
			(xy 300.550119 -35.365687) (xy 300.494682 -35.371787) (xy 300.438948 -35.36975) (xy 300.384105 -35.35962)
			(xy 300.331321 -35.341613) (xy 300.281721 -35.316112) (xy 300.236363 -35.283661) (xy 300.196214 -35.244952)
			(xy 300.162128 -35.200809) (xy 300.134832 -35.152174) (xy 300.114909 -35.100083) (xy 300.102783 -35.045646)
			(xy 300.098712 -34.990024) (xy 297.964352 -34.990024) (xy 297.963843 -35.01791) (xy 297.955723 -35.073086)
			(xy 297.939655 -35.126493) (xy 297.915983 -35.17699) (xy 297.88521 -35.223503) (xy 297.847993 -35.26504)
			(xy 297.805125 -35.300715) (xy 297.757519 -35.329769) (xy 297.70619 -35.351581) (xy 297.652233 -35.365687)
			(xy 297.596796 -35.371787) (xy 297.541062 -35.36975) (xy 297.486219 -35.35962) (xy 297.433435 -35.341613)
			(xy 297.383835 -35.316112) (xy 297.338477 -35.283661) (xy 297.298328 -35.244952) (xy 297.264242 -35.200809)
			(xy 297.236946 -35.152174) (xy 297.217023 -35.100083) (xy 297.204897 -35.045646) (xy 297.200826 -34.990024)
			(xy 296.636186 -34.990024) (xy 296.635677 -35.01791) (xy 296.627557 -35.073086) (xy 296.611489 -35.126493)
			(xy 296.587817 -35.17699) (xy 296.557044 -35.223503) (xy 296.519827 -35.26504) (xy 296.476959 -35.300715)
			(xy 296.429353 -35.329769) (xy 296.378024 -35.351581) (xy 296.324067 -35.365687) (xy 296.26863 -35.371787)
			(xy 296.212896 -35.36975) (xy 296.158053 -35.35962) (xy 296.105269 -35.341613) (xy 296.055669 -35.316112)
			(xy 296.010311 -35.283661) (xy 295.970162 -35.244952) (xy 295.936076 -35.200809) (xy 295.90878 -35.152174)
			(xy 295.888857 -35.100083) (xy 295.876731 -35.045646) (xy 295.87266 -34.990024) (xy 294.230298 -34.990024)
			(xy 294.229789 -35.01791) (xy 294.221669 -35.073086) (xy 294.205601 -35.126493) (xy 294.181929 -35.17699)
			(xy 294.151156 -35.223503) (xy 294.113939 -35.26504) (xy 294.071071 -35.300715) (xy 294.023465 -35.329769)
			(xy 293.972136 -35.351581) (xy 293.918179 -35.365687) (xy 293.862742 -35.371787) (xy 293.807008 -35.36975)
			(xy 293.752165 -35.35962) (xy 293.699381 -35.341613) (xy 293.649781 -35.316112) (xy 293.604423 -35.283661)
			(xy 293.564274 -35.244952) (xy 293.530188 -35.200809) (xy 293.502892 -35.152174) (xy 293.482969 -35.100083)
			(xy 293.470843 -35.045646) (xy 293.466772 -34.990024) (xy 292.401494 -34.990024) (xy 292.401498 -34.990278)
			(xy 292.401036 -35.017532) (xy 292.393282 -35.071484) (xy 292.377927 -35.123784) (xy 292.355286 -35.173367)
			(xy 292.325819 -35.219222) (xy 292.290125 -35.260416) (xy 292.248931 -35.296111) (xy 292.203077 -35.32558)
			(xy 292.153496 -35.348223) (xy 292.101196 -35.363579) (xy 292.047244 -35.371335) (xy 292.01999 -35.371786)
			(xy 291.993026 -35.371326) (xy 291.939633 -35.36374) (xy 291.887843 -35.348706) (xy 291.838687 -35.326525)
			(xy 291.793148 -35.297638) (xy 291.752132 -35.262623) (xy 291.71646 -35.222179) (xy 291.686843 -35.177111)
			(xy 291.663871 -35.12832) (xy 291.648004 -35.076778) (xy 291.643308 -35.050222) (xy 291.642038 -35.042856)
			(xy 291.64153 -35.0393) (xy 291.635688 -35.03041) (xy 291.632796 -35.026193) (xy 291.625623 -35.018908)
			(xy 291.621464 -35.015932) (xy 291.558726 -34.974276) (xy 291.554232 -34.971439) (xy 291.544375 -34.967467)
			(xy 291.539168 -34.966402) (xy 291.529262 -34.964624) (xy 291.518848 -34.967164) (xy 291.492154 -34.973307)
			(xy 291.437778 -34.979929) (xy 291.41039 -34.980372) (xy 291.383002 -34.979924) (xy 291.328627 -34.9733)
			(xy 291.301932 -34.967164) (xy 291.291518 -34.964624) (xy 291.281612 -34.966402) (xy 291.276394 -34.96743)
			(xy 291.26653 -34.971402) (xy 291.262054 -34.974276) (xy 291.199316 -35.015932) (xy 291.195145 -35.018893)
			(xy 291.187972 -35.026183) (xy 291.185092 -35.03041) (xy 291.17925 -35.0393) (xy 291.178742 -35.042856)
			(xy 291.177472 -35.050222) (xy 291.172772 -35.076775) (xy 291.15688 -35.128302) (xy 291.133892 -35.17708)
			(xy 291.104267 -35.222135) (xy 291.068594 -35.262572) (xy 291.027585 -35.297585) (xy 290.982055 -35.326476)
			(xy 290.932912 -35.348671) (xy 290.881133 -35.363726) (xy 290.827751 -35.371343) (xy 290.80079 -35.371786)
			(xy 290.773541 -35.371299) (xy 290.719597 -35.363542) (xy 290.667307 -35.348187) (xy 290.617734 -35.325546)
			(xy 290.571887 -35.296082) (xy 290.530701 -35.260392) (xy 290.495012 -35.219205) (xy 290.465549 -35.173357)
			(xy 290.44291 -35.123784) (xy 290.427556 -35.071493) (xy 290.4198 -35.017549) (xy 290.4198 -34.963051)
			(xy 290.427556 -34.909107) (xy 290.44291 -34.856816) (xy 290.465549 -34.807243) (xy 290.495012 -34.761395)
			(xy 290.530701 -34.720208) (xy 290.571887 -34.684518) (xy 290.617734 -34.655054) (xy 290.667307 -34.632413)
			(xy 290.719597 -34.617058) (xy 290.773541 -34.609301) (xy 290.80079 -34.60877) (xy 290.801044 -34.60877)
			(xy 290.818093 -34.60895) (xy 290.852055 -34.611999) (xy 290.868862 -34.614866) (xy 290.879472 -34.616177)
			(xy 290.9002 -34.611044) (xy 290.908994 -34.60496) (xy 290.937188 -34.580576) (xy 290.944707 -34.572722)
			(xy 290.952857 -34.552587) (xy 290.952936 -34.541714) (xy 290.952428 -34.52241) (xy 290.952428 -33.911286)
			(xy 290.951938 -33.901278) (xy 290.944277 -33.882786) (xy 290.930125 -33.868631) (xy 290.911636 -33.860965)
			(xy 290.901628 -33.860486) (xy 288.50082 -33.860486) (xy 288.491563 -33.86084) (xy 288.474237 -33.867355)
			(xy 288.467038 -33.873186) (xy 288.46018 -33.879282) (xy 288.451798 -33.895284) (xy 288.450528 -33.904936)
			(xy 288.446639 -33.932264) (xy 288.432004 -33.985487) (xy 288.409848 -34.036044) (xy 288.380635 -34.082879)
			(xy 288.344975 -34.125012) (xy 288.303612 -34.161564) (xy 288.257412 -34.19177) (xy 288.207339 -34.214999)
			(xy 288.15444 -34.230766) (xy 288.099821 -34.238742) (xy 288.044623 -34.23876) (xy 287.989998 -34.230819)
			(xy 287.93709 -34.215086) (xy 287.887002 -34.191888) (xy 287.840782 -34.161712) (xy 287.799396 -34.125187)
			(xy 287.763709 -34.083076) (xy 287.734466 -34.03626) (xy 287.712278 -33.985718) (xy 287.697609 -33.932504)
			(xy 287.693608 -33.90519) (xy 287.693608 -33.904428) (xy 287.69205 -33.895408) (xy 287.683454 -33.879264)
			(xy 287.676844 -33.872932) (xy 287.669986 -33.86709) (xy 287.652714 -33.860486) (xy 287.01492 -33.860486)
			(xy 287.00236 -33.861123) (xy 286.980214 -33.87297) (xy 286.972756 -33.883092) (xy 286.954976 -33.912048)
			(xy 286.926274 -33.959292) (xy 286.923092 -33.9649) (xy 286.919374 -33.977244) (xy 286.918908 -33.983676)
			(xy 286.9184 -33.996376) (xy 286.92475 -34.008568) (xy 286.938039 -34.035715) (xy 286.956831 -34.09316)
			(xy 286.966349 -34.152846) (xy 286.966914 -34.183066) (xy 286.966914 -34.188654) (xy 286.966052 -34.215644)
			(xy 286.95766 -34.268987) (xy 286.941828 -34.320613) (xy 286.918874 -34.36949) (xy 286.889256 -34.414642)
			(xy 286.853567 -34.455165) (xy 286.812519 -34.490251) (xy 286.766934 -34.519197) (xy 286.717722 -34.541425)
			(xy 286.665867 -34.55649) (xy 286.612406 -34.564093) (xy 286.585406 -34.564574) (xy 286.558796 -34.56412)
			(xy 286.50609 -34.556738) (xy 286.454922 -34.542105) (xy 286.406284 -34.520502) (xy 286.361119 -34.49235)
			(xy 286.320305 -34.458195) (xy 286.284634 -34.4187) (xy 286.254797 -34.37463) (xy 286.231373 -34.326842)
			(xy 286.222694 -34.301684) (xy 286.219646 -34.292286) (xy 286.214058 -34.285428) (xy 286.211222 -34.282071)
			(xy 286.204582 -34.276317) (xy 286.20085 -34.273998) (xy 286.142684 -34.2392) (xy 286.138827 -34.236981)
			(xy 286.130525 -34.233782) (xy 286.126174 -34.23285) (xy 286.117792 -34.231326) (xy 286.10814 -34.233104)
			(xy 286.091267 -34.235956) (xy 286.05718 -34.239009) (xy 286.040068 -34.2392) (xy 286.038036 -34.2392)
			(xy 286.010547 -34.238577) (xy 285.956174 -34.2304) (xy 285.90354 -34.214497) (xy 285.853736 -34.1912)
			(xy 285.807795 -34.16099) (xy 285.766669 -34.124495) (xy 285.731211 -34.082471) (xy 285.702157 -34.035791)
			(xy 285.680109 -33.985421) (xy 285.665525 -33.932406) (xy 285.661608 -33.90519) (xy 285.661608 -33.904428)
			(xy 285.66005 -33.895408) (xy 285.651454 -33.879264) (xy 285.644844 -33.872932) (xy 285.637986 -33.86709)
			(xy 285.620714 -33.860486) (xy 280.655776 -33.860486) (xy 280.64577 -33.860978) (xy 280.627284 -33.868641)
			(xy 280.613135 -33.882793) (xy 280.605476 -33.90128) (xy 280.604976 -33.911286) (xy 280.604976 -34.241232)
			(xy 280.604976 -34.241994) (xy 280.60567 -34.252336) (xy 280.614185 -34.271213) (xy 280.621486 -34.27857)
			(xy 280.622756 -34.27984) (xy 280.657554 -34.309558) (xy 280.682192 -34.330386) (xy 280.686324 -34.33371)
			(xy 280.695672 -34.338712) (xy 280.700734 -34.340292) (xy 280.711148 -34.34334) (xy 280.722324 -34.341562)
			(xy 280.73715 -34.339387) (xy 280.76703 -34.337095) (xy 280.782014 -34.33699) (xy 280.782268 -34.33699)
			(xy 280.809474 -34.337542) (xy 280.863317 -34.34541) (xy 280.915496 -34.360849) (xy 280.964952 -34.383545)
			(xy 281.010681 -34.413037) (xy 281.051756 -34.448728) (xy 281.087342 -34.489893) (xy 281.116719 -34.535697)
			(xy 281.13929 -34.58521) (xy 281.154597 -34.637428) (xy 281.162328 -34.691291) (xy 281.16276 -34.718498)
			(xy 281.162297 -34.74575) (xy 281.15454 -34.799698) (xy 281.139183 -34.851994) (xy 281.11654 -34.901571)
			(xy 281.087072 -34.947421) (xy 281.051377 -34.98861) (xy 281.010184 -35.024299) (xy 280.964331 -35.053762)
			(xy 280.91475 -35.0764) (xy 280.862453 -35.09175) (xy 280.808504 -35.0995) (xy 280.781252 -35.100006)
			(xy 280.780998 -35.100006) (xy 280.751494 -35.099448) (xy 280.693191 -35.090351) (xy 280.636982 -35.072391)
			(xy 280.584207 -35.045994) (xy 280.536123 -35.01179) (xy 280.493875 -34.970594) (xy 280.47569 -34.947352)
			(xy 280.47061 -34.94024) (xy 280.448258 -34.925508) (xy 280.444333 -34.922983) (xy 280.435765 -34.919286)
			(xy 280.43124 -34.918142) (xy 280.40965 -34.913316) (xy 280.400638 -34.911715) (xy 280.382532 -34.914308)
			(xy 280.374344 -34.918396) (xy 280.373836 -34.91865) (xy 280.355455 -34.928878) (xy 280.317168 -34.946307)
			(xy 280.297382 -34.953448) (xy 280.273182 -34.961492) (xy 280.223448 -34.972788) (xy 280.172768 -34.978491)
			(xy 280.147268 -34.978848) (xy 280.121768 -34.978485) (xy 280.071088 -34.972788) (xy 280.021355 -34.961491)
			(xy 279.997154 -34.953448) (xy 279.97737 -34.946302) (xy 279.939083 -34.928875) (xy 279.9207 -34.91865)
			(xy 279.920192 -34.918396) (xy 279.911992 -34.914345) (xy 279.8939 -34.911757) (xy 279.884886 -34.913316)
			(xy 279.863296 -34.918142) (xy 279.858774 -34.919293) (xy 279.850209 -34.922994) (xy 279.846278 -34.925508)
			(xy 279.823926 -34.94024) (xy 279.818846 -34.947352) (xy 279.800695 -34.970652) (xy 279.758416 -35.011889)
			(xy 279.710284 -35.046115) (xy 279.65745 -35.07251) (xy 279.601178 -35.090444) (xy 279.542815 -35.099486)
			(xy 279.513284 -35.100006) (xy 279.502362 -35.100006) (xy 279.502108 -35.099752) (xy 279.475396 -35.098512)
			(xy 279.422688 -35.089483) (xy 279.371758 -35.073184) (xy 279.323601 -35.049935) (xy 279.279162 -35.020191)
			(xy 279.239311 -34.984534) (xy 279.204827 -34.943663) (xy 279.176387 -34.898377) (xy 279.154548 -34.849565)
			(xy 279.139737 -34.798183) (xy 279.132244 -34.745235) (xy 279.131776 -34.718498) (xy 279.132262 -34.691246)
			(xy 279.140019 -34.637298) (xy 279.155374 -34.585003) (xy 279.178015 -34.535425) (xy 279.207481 -34.489573)
			(xy 279.243172 -34.448382) (xy 279.284362 -34.412689) (xy 279.330212 -34.383221) (xy 279.379789 -34.360579)
			(xy 279.432084 -34.345222) (xy 279.486032 -34.337463) (xy 279.513284 -34.33699) (xy 279.528077 -34.337135)
			(xy 279.557573 -34.339428) (xy 279.572212 -34.341562) (xy 279.583388 -34.34334) (xy 279.593802 -34.340292)
			(xy 279.59885 -34.338677) (xy 279.608198 -34.333687) (xy 279.612344 -34.330386) (xy 279.636982 -34.309558)
			(xy 279.67178 -34.27984) (xy 279.67305 -34.27857) (xy 279.680385 -34.271233) (xy 279.688921 -34.252348)
			(xy 279.68956 -34.241994) (xy 279.68956 -33.911286) (xy 279.689137 -33.901269) (xy 279.681464 -33.882764)
			(xy 279.66729 -33.868606) (xy 279.648777 -33.860952) (xy 279.63876 -33.860486) (xy 265.919204 -33.860486)
			(xy 265.909195 -33.860973) (xy 265.890699 -33.868631) (xy 265.876541 -33.882784) (xy 265.868876 -33.901277)
			(xy 265.868404 -33.911286) (xy 265.868404 -34.52241) (xy 265.867896 -34.541714) (xy 265.867896 -34.544762)
			(xy 265.868538 -34.555078) (xy 265.876926 -34.573948) (xy 265.884152 -34.581338) (xy 265.901424 -34.59607)
			(xy 265.901932 -34.596578) (xy 265.909806 -34.603436) (xy 265.918821 -34.610337) (xy 265.940705 -34.616272)
			(xy 265.95197 -34.614866) (xy 265.96878 -34.612023) (xy 266.00274 -34.608973) (xy 266.019788 -34.60877)
			(xy 266.022074 -34.60877) (xy 266.049229 -34.609397) (xy 266.102954 -34.617392) (xy 266.155001 -34.632926)
			(xy 266.20432 -34.655684) (xy 266.249912 -34.685206) (xy 266.290857 -34.720896) (xy 266.326326 -34.762032)
			(xy 266.355603 -34.807783) (xy 266.378095 -34.857223) (xy 266.393349 -34.909353) (xy 266.401055 -34.96312)
			(xy 266.401545 -34.990024) (xy 267.466824 -34.990024) (xy 267.470895 -34.934402) (xy 267.483021 -34.879965)
			(xy 267.502944 -34.827874) (xy 267.53024 -34.779239) (xy 267.564326 -34.735096) (xy 267.604475 -34.696387)
			(xy 267.649833 -34.663936) (xy 267.699433 -34.638435) (xy 267.752217 -34.620428) (xy 267.80706 -34.610298)
			(xy 267.862794 -34.608261) (xy 267.918231 -34.614361) (xy 267.972188 -34.628467) (xy 268.023517 -34.650279)
			(xy 268.071123 -34.679333) (xy 268.113991 -34.715008) (xy 268.151208 -34.756545) (xy 268.181981 -34.803058)
			(xy 268.205653 -34.853555) (xy 268.221721 -34.906962) (xy 268.229841 -34.962138) (xy 268.23035 -34.990024)
			(xy 269.872712 -34.990024) (xy 269.876783 -34.934402) (xy 269.888909 -34.879965) (xy 269.908832 -34.827874)
			(xy 269.936128 -34.779239) (xy 269.970214 -34.735096) (xy 270.010363 -34.696387) (xy 270.055721 -34.663936)
			(xy 270.105321 -34.638435) (xy 270.158105 -34.620428) (xy 270.212948 -34.610298) (xy 270.268682 -34.608261)
			(xy 270.324119 -34.614361) (xy 270.378076 -34.628467) (xy 270.429405 -34.650279) (xy 270.477011 -34.679333)
			(xy 270.519879 -34.715008) (xy 270.557096 -34.756545) (xy 270.587869 -34.803058) (xy 270.611541 -34.853555)
			(xy 270.627609 -34.906962) (xy 270.635729 -34.962138) (xy 270.636238 -34.990024) (xy 271.200878 -34.990024)
			(xy 271.204949 -34.934402) (xy 271.217075 -34.879965) (xy 271.236998 -34.827874) (xy 271.264294 -34.779239)
			(xy 271.29838 -34.735096) (xy 271.338529 -34.696387) (xy 271.383887 -34.663936) (xy 271.433487 -34.638435)
			(xy 271.486271 -34.620428) (xy 271.541114 -34.610298) (xy 271.596848 -34.608261) (xy 271.652285 -34.614361)
			(xy 271.706242 -34.628467) (xy 271.757571 -34.650279) (xy 271.805177 -34.679333) (xy 271.848045 -34.715008)
			(xy 271.885262 -34.756545) (xy 271.916035 -34.803058) (xy 271.939707 -34.853555) (xy 271.955775 -34.906962)
			(xy 271.963895 -34.962138) (xy 271.964404 -34.990024) (xy 274.098764 -34.990024) (xy 274.102835 -34.934402)
			(xy 274.114961 -34.879965) (xy 274.134884 -34.827874) (xy 274.16218 -34.779239) (xy 274.196266 -34.735096)
			(xy 274.236415 -34.696387) (xy 274.281773 -34.663936) (xy 274.331373 -34.638435) (xy 274.384157 -34.620428)
			(xy 274.439 -34.610298) (xy 274.494734 -34.608261) (xy 274.550171 -34.614361) (xy 274.604128 -34.628467)
			(xy 274.655457 -34.650279) (xy 274.703063 -34.679333) (xy 274.745931 -34.715008) (xy 274.783148 -34.756545)
			(xy 274.813921 -34.803058) (xy 274.837593 -34.853555) (xy 274.853661 -34.906962) (xy 274.861781 -34.962138)
			(xy 274.86229 -34.990024) (xy 274.861781 -35.01791) (xy 274.853661 -35.073086) (xy 274.837593 -35.126493)
			(xy 274.813921 -35.17699) (xy 274.783148 -35.223503) (xy 274.746099 -35.264852) (xy 288.102292 -35.264852)
			(xy 288.106363 -35.20923) (xy 288.118489 -35.154793) (xy 288.138412 -35.102702) (xy 288.165708 -35.054067)
			(xy 288.199794 -35.009924) (xy 288.239943 -34.971215) (xy 288.285301 -34.938764) (xy 288.334901 -34.913263)
			(xy 288.387685 -34.895256) (xy 288.442528 -34.885126) (xy 288.498262 -34.883089) (xy 288.553699 -34.889189)
			(xy 288.607656 -34.903295) (xy 288.658985 -34.925107) (xy 288.706591 -34.954161) (xy 288.749459 -34.989836)
			(xy 288.786676 -35.031373) (xy 288.817449 -35.077886) (xy 288.841121 -35.128383) (xy 288.857189 -35.18179)
			(xy 288.865309 -35.236966) (xy 288.865818 -35.264852) (xy 288.865309 -35.292738) (xy 288.857189 -35.347914)
			(xy 288.841121 -35.401321) (xy 288.817449 -35.451818) (xy 288.786676 -35.498331) (xy 288.749459 -35.539868)
			(xy 288.706591 -35.575543) (xy 288.658985 -35.604597) (xy 288.607656 -35.626409) (xy 288.553699 -35.640515)
			(xy 288.498262 -35.646615) (xy 288.442528 -35.644578) (xy 288.387685 -35.634448) (xy 288.334901 -35.616441)
			(xy 288.285301 -35.59094) (xy 288.239943 -35.558489) (xy 288.199794 -35.51978) (xy 288.165708 -35.475637)
			(xy 288.138412 -35.427002) (xy 288.118489 -35.374911) (xy 288.106363 -35.320474) (xy 288.102292 -35.264852)
			(xy 274.746099 -35.264852) (xy 274.745931 -35.26504) (xy 274.703063 -35.300715) (xy 274.655457 -35.329769)
			(xy 274.604128 -35.351581) (xy 274.550171 -35.365687) (xy 274.494734 -35.371787) (xy 274.439 -35.36975)
			(xy 274.384157 -35.35962) (xy 274.331373 -35.341613) (xy 274.281773 -35.316112) (xy 274.236415 -35.283661)
			(xy 274.196266 -35.244952) (xy 274.16218 -35.200809) (xy 274.134884 -35.152174) (xy 274.114961 -35.100083)
			(xy 274.102835 -35.045646) (xy 274.098764 -34.990024) (xy 271.964404 -34.990024) (xy 271.963895 -35.01791)
			(xy 271.955775 -35.073086) (xy 271.939707 -35.126493) (xy 271.916035 -35.17699) (xy 271.885262 -35.223503)
			(xy 271.848045 -35.26504) (xy 271.805177 -35.300715) (xy 271.757571 -35.329769) (xy 271.706242 -35.351581)
			(xy 271.652285 -35.365687) (xy 271.596848 -35.371787) (xy 271.541114 -35.36975) (xy 271.486271 -35.35962)
			(xy 271.433487 -35.341613) (xy 271.383887 -35.316112) (xy 271.338529 -35.283661) (xy 271.29838 -35.244952)
			(xy 271.264294 -35.200809) (xy 271.236998 -35.152174) (xy 271.217075 -35.100083) (xy 271.204949 -35.045646)
			(xy 271.200878 -34.990024) (xy 270.636238 -34.990024) (xy 270.635729 -35.01791) (xy 270.627609 -35.073086)
			(xy 270.611541 -35.126493) (xy 270.587869 -35.17699) (xy 270.557096 -35.223503) (xy 270.519879 -35.26504)
			(xy 270.477011 -35.300715) (xy 270.429405 -35.329769) (xy 270.378076 -35.351581) (xy 270.324119 -35.365687)
			(xy 270.268682 -35.371787) (xy 270.212948 -35.36975) (xy 270.158105 -35.35962) (xy 270.105321 -35.341613)
			(xy 270.055721 -35.316112) (xy 270.010363 -35.283661) (xy 269.970214 -35.244952) (xy 269.936128 -35.200809)
			(xy 269.908832 -35.152174) (xy 269.888909 -35.100083) (xy 269.876783 -35.045646) (xy 269.872712 -34.990024)
			(xy 268.23035 -34.990024) (xy 268.229841 -35.01791) (xy 268.221721 -35.073086) (xy 268.205653 -35.126493)
			(xy 268.181981 -35.17699) (xy 268.151208 -35.223503) (xy 268.113991 -35.26504) (xy 268.071123 -35.300715)
			(xy 268.023517 -35.329769) (xy 267.972188 -35.351581) (xy 267.918231 -35.365687) (xy 267.862794 -35.371787)
			(xy 267.80706 -35.36975) (xy 267.752217 -35.35962) (xy 267.699433 -35.341613) (xy 267.649833 -35.316112)
			(xy 267.604475 -35.283661) (xy 267.564326 -35.244952) (xy 267.53024 -35.200809) (xy 267.502944 -35.152174)
			(xy 267.483021 -35.100083) (xy 267.470895 -35.045646) (xy 267.466824 -34.990024) (xy 266.401545 -34.990024)
			(xy 266.40155 -34.990278) (xy 266.401066 -35.017531) (xy 266.393312 -35.071484) (xy 266.377959 -35.123784)
			(xy 266.35532 -35.173366) (xy 266.325855 -35.219222) (xy 266.290164 -35.260419) (xy 266.248974 -35.296116)
			(xy 266.203122 -35.325589) (xy 266.153544 -35.348237) (xy 266.101246 -35.363598) (xy 266.047295 -35.371361)
			(xy 266.020042 -35.371786) (xy 265.99308 -35.371323) (xy 265.939692 -35.363731) (xy 265.887907 -35.348693)
			(xy 265.838757 -35.326509) (xy 265.793224 -35.297621) (xy 265.752214 -35.262605) (xy 265.716547 -35.222161)
			(xy 265.686934 -35.177096) (xy 265.663967 -35.128307) (xy 265.648102 -35.076769) (xy 265.64336 -35.050222)
			(xy 265.64209 -35.042856) (xy 265.641582 -35.0393) (xy 265.63574 -35.03041) (xy 265.63285 -35.026191)
			(xy 265.625681 -35.018899) (xy 265.621516 -35.015932) (xy 265.558778 -34.974276) (xy 265.554282 -34.971443)
			(xy 265.544424 -34.96748) (xy 265.53922 -34.966402) (xy 265.529314 -34.964624) (xy 265.5189 -34.967164)
			(xy 265.492206 -34.973304) (xy 265.43783 -34.979921) (xy 265.410442 -34.980372) (xy 265.383054 -34.979927)
			(xy 265.328677 -34.973309) (xy 265.301984 -34.967164) (xy 265.29157 -34.964624) (xy 265.281664 -34.966402)
			(xy 265.276448 -34.967435) (xy 265.266589 -34.971415) (xy 265.262106 -34.974276) (xy 265.199368 -35.015932)
			(xy 265.1952 -35.018896) (xy 265.188033 -35.026189) (xy 265.185144 -35.03041) (xy 265.179302 -35.0393)
			(xy 265.178794 -35.042856) (xy 265.177524 -35.050222) (xy 265.172824 -35.076773) (xy 265.156931 -35.128298)
			(xy 265.133942 -35.177072) (xy 265.104316 -35.222124) (xy 265.068643 -35.262556) (xy 265.027633 -35.297564)
			(xy 264.982103 -35.32645) (xy 264.93296 -35.348639) (xy 264.881182 -35.363689) (xy 264.827802 -35.371299)
			(xy 264.800842 -35.371786) (xy 264.773589 -35.371326) (xy 264.719636 -35.363574) (xy 264.667337 -35.348222)
			(xy 264.617754 -35.325584) (xy 264.571898 -35.296118) (xy 264.530703 -35.260427) (xy 264.495007 -35.219235)
			(xy 264.465537 -35.173383) (xy 264.442892 -35.123803) (xy 264.427535 -35.071505) (xy 264.419777 -35.017553)
			(xy 264.419777 -34.963047) (xy 264.427535 -34.909095) (xy 264.442892 -34.856797) (xy 264.465537 -34.807217)
			(xy 264.495007 -34.761365) (xy 264.530703 -34.720173) (xy 264.571898 -34.684482) (xy 264.617754 -34.655016)
			(xy 264.667337 -34.632378) (xy 264.719636 -34.617026) (xy 264.773589 -34.609274) (xy 264.800842 -34.60877)
			(xy 264.801096 -34.60877) (xy 264.818145 -34.608952) (xy 264.852106 -34.612006) (xy 264.868914 -34.614866)
			(xy 264.879527 -34.616186) (xy 264.900267 -34.611069) (xy 264.909046 -34.60496) (xy 264.93724 -34.580576)
			(xy 264.944753 -34.572719) (xy 264.952894 -34.552586) (xy 264.952988 -34.541714) (xy 264.95248 -34.52241)
			(xy 264.95248 -33.911286) (xy 264.952057 -33.901268) (xy 264.944384 -33.882759) (xy 264.930212 -33.868597)
			(xy 264.911698 -33.860936) (xy 264.90168 -33.860486) (xy 262.500872 -33.860486) (xy 262.491618 -33.860848)
			(xy 262.474304 -33.867376) (xy 262.46709 -33.873186) (xy 262.460232 -33.879282) (xy 262.45185 -33.895284)
			(xy 262.45058 -33.904936) (xy 262.446691 -33.932268) (xy 262.432055 -33.985499) (xy 262.409897 -34.036063)
			(xy 262.380681 -34.082904) (xy 262.345016 -34.125043) (xy 262.303648 -34.161601) (xy 262.257442 -34.191812)
			(xy 262.207363 -34.215045) (xy 262.154458 -34.230815) (xy 262.099831 -34.238793) (xy 262.044625 -34.238812)
			(xy 261.989993 -34.230871) (xy 261.937077 -34.215136) (xy 261.886983 -34.191936) (xy 261.840756 -34.161757)
			(xy 261.799364 -34.125227) (xy 261.763671 -34.083112) (xy 261.734423 -34.03629) (xy 261.712231 -33.985741)
			(xy 261.69756 -33.93252) (xy 261.69366 -33.90519) (xy 261.69366 -33.904428) (xy 261.692104 -33.895407)
			(xy 261.683514 -33.879257) (xy 261.676896 -33.872932) (xy 261.670038 -33.86709) (xy 261.652766 -33.860486)
			(xy 261.014972 -33.860486) (xy 261.002418 -33.861133) (xy 260.98029 -33.872992) (xy 260.972808 -33.883092)
			(xy 260.955028 -33.912048) (xy 260.926326 -33.959292) (xy 260.923141 -33.964899) (xy 260.919419 -33.977243)
			(xy 260.91896 -33.983676) (xy 260.918452 -33.996376) (xy 260.924802 -34.008568) (xy 260.93809 -34.035716)
			(xy 260.95688 -34.09316) (xy 260.966395 -34.152846) (xy 260.966966 -34.183066) (xy 260.966966 -34.188654)
			(xy 260.966038 -34.216931) (xy 260.956866 -34.272757) (xy 260.93955 -34.326617) (xy 260.914471 -34.37733)
			(xy 260.882179 -34.423783) (xy 260.843381 -34.464959) (xy 260.798929 -34.499955) (xy 260.749796 -34.528002)
			(xy 260.69706 -34.548488) (xy 260.641878 -34.560961) (xy 260.585458 -34.56515) (xy 260.529038 -34.560961)
			(xy 260.473856 -34.548488) (xy 260.42112 -34.528002) (xy 260.371987 -34.499955) (xy 260.327535 -34.464959)
			(xy 260.288737 -34.423783) (xy 260.256445 -34.37733) (xy 260.231366 -34.326617) (xy 260.21405 -34.272757)
			(xy 260.204878 -34.216931) (xy 260.20395 -34.188654) (xy 260.20395 -34.183066) (xy 260.204501 -34.152843)
			(xy 260.213993 -34.093149) (xy 260.232798 -34.035704) (xy 260.246114 -34.008568) (xy 260.246114 -34.008314)
			(xy 260.248989 -34.002374) (xy 260.251934 -33.989514) (xy 260.251956 -33.982914) (xy 260.251448 -33.970468)
			(xy 260.215888 -33.912048) (xy 260.198108 -33.883092) (xy 260.190596 -33.873023) (xy 260.168487 -33.861154)
			(xy 260.155944 -33.860486) (xy 254.655828 -33.860486) (xy 254.645802 -33.860901) (xy 254.627273 -33.868565)
			(xy 254.613089 -33.882738) (xy 254.605409 -33.90126) (xy 254.605028 -33.911286) (xy 254.605028 -34.241232)
			(xy 254.605028 -34.241994) (xy 254.60572 -34.252337) (xy 254.61423 -34.271219) (xy 254.621538 -34.27857)
			(xy 254.622808 -34.27984) (xy 254.657606 -34.309558) (xy 254.682244 -34.330386) (xy 254.686378 -34.333706)
			(xy 254.695729 -34.338699) (xy 254.700786 -34.340292) (xy 254.7112 -34.34334) (xy 254.722376 -34.341562)
			(xy 254.737202 -34.339389) (xy 254.767082 -34.337101) (xy 254.782066 -34.33699) (xy 254.78232 -34.33699)
			(xy 254.809524 -34.337545) (xy 254.863361 -34.345419) (xy 254.915534 -34.360863) (xy 254.964983 -34.383562)
			(xy 255.010706 -34.413056) (xy 255.051774 -34.448747) (xy 255.087355 -34.48991) (xy 255.116727 -34.535712)
			(xy 255.139294 -34.585221) (xy 255.154598 -34.637435) (xy 255.162329 -34.691293) (xy 255.162812 -34.718498)
			(xy 255.162326 -34.745749) (xy 255.15457 -34.799698) (xy 255.139215 -34.851993) (xy 255.116574 -34.901571)
			(xy 255.087108 -34.947422) (xy 255.051417 -34.988612) (xy 255.010226 -35.024304) (xy 254.964376 -35.053771)
			(xy 254.914798 -35.076413) (xy 254.862503 -35.091769) (xy 254.808555 -35.099526) (xy 254.781304 -35.100006)
			(xy 254.78105 -35.100006) (xy 254.751544 -35.099452) (xy 254.693236 -35.090362) (xy 254.637022 -35.072407)
			(xy 254.584241 -35.046015) (xy 254.536151 -35.011813) (xy 254.493897 -34.970618) (xy 254.475742 -34.947352)
			(xy 254.470662 -34.94024) (xy 254.44831 -34.925508) (xy 254.444387 -34.922979) (xy 254.435821 -34.919273)
			(xy 254.431292 -34.918142) (xy 254.409702 -34.913316) (xy 254.400691 -34.911724) (xy 254.382594 -34.914332)
			(xy 254.374396 -34.918396) (xy 254.373888 -34.91865) (xy 254.355506 -34.928876) (xy 254.317218 -34.946302)
			(xy 254.297434 -34.953448) (xy 254.273233 -34.96149) (xy 254.223499 -34.97278) (xy 254.172819 -34.978478)
			(xy 254.14732 -34.978848) (xy 254.12182 -34.978488) (xy 254.071138 -34.972796) (xy 254.021403 -34.961504)
			(xy 253.997206 -34.953448) (xy 253.977421 -34.946304) (xy 253.939132 -34.92888) (xy 253.920752 -34.91865)
			(xy 253.920244 -34.918396) (xy 253.912045 -34.914336) (xy 253.893949 -34.91173) (xy 253.884938 -34.913316)
			(xy 253.863348 -34.918142) (xy 253.858828 -34.919296) (xy 253.850267 -34.923004) (xy 253.84633 -34.925508)
			(xy 253.823978 -34.94024) (xy 253.818898 -34.947352) (xy 253.800748 -34.970654) (xy 253.75847 -35.011898)
			(xy 253.710339 -35.04613) (xy 253.657506 -35.072532) (xy 253.601234 -35.090473) (xy 253.542868 -35.099524)
			(xy 253.513336 -35.100006) (xy 253.502414 -35.100006) (xy 253.50216 -35.099752) (xy 253.475445 -35.098515)
			(xy 253.422732 -35.089492) (xy 253.371796 -35.073198) (xy 253.323633 -35.049952) (xy 253.279187 -35.020208)
			(xy 253.23933 -34.984551) (xy 253.204841 -34.943679) (xy 253.176396 -34.898391) (xy 253.154553 -34.849576)
			(xy 253.13974 -34.798189) (xy 253.132246 -34.745238) (xy 253.131828 -34.718498) (xy 253.132291 -34.691246)
			(xy 253.140049 -34.637297) (xy 253.155405 -34.585002) (xy 253.178049 -34.535424) (xy 253.207517 -34.489574)
			(xy 253.243211 -34.448384) (xy 253.284404 -34.412694) (xy 253.330258 -34.38323) (xy 253.379837 -34.360592)
			(xy 253.432135 -34.345241) (xy 253.486084 -34.337489) (xy 253.513336 -34.33699) (xy 253.528129 -34.337133)
			(xy 253.557626 -34.339422) (xy 253.572264 -34.341562) (xy 253.58344 -34.34334) (xy 253.593854 -34.340292)
			(xy 253.598899 -34.338673) (xy 253.608242 -34.333676) (xy 253.612396 -34.330386) (xy 253.637034 -34.309558)
			(xy 253.671832 -34.27984) (xy 253.673102 -34.27857) (xy 253.680442 -34.271236) (xy 253.688987 -34.25235)
			(xy 253.689612 -34.241994) (xy 253.689612 -33.911286) (xy 253.689121 -33.901279) (xy 253.68146 -33.88279)
			(xy 253.667308 -33.868639) (xy 253.648819 -33.860978) (xy 253.638812 -33.860486) (xy 239.919256 -33.860486)
			(xy 239.909253 -33.860981) (xy 239.890774 -33.868648) (xy 239.876631 -33.882799) (xy 239.868975 -33.901283)
			(xy 239.868456 -33.911286) (xy 239.868456 -34.52241) (xy 239.867948 -34.541714) (xy 239.867948 -34.544762)
			(xy 239.868591 -34.555077) (xy 239.876986 -34.573941) (xy 239.884204 -34.581338) (xy 239.901476 -34.59607)
			(xy 239.901984 -34.596578) (xy 239.909858 -34.603436) (xy 239.918875 -34.610326) (xy 239.940755 -34.61624)
			(xy 239.952022 -34.614866) (xy 239.968832 -34.612021) (xy 240.002792 -34.608967) (xy 240.01984 -34.60877)
			(xy 240.022126 -34.60877) (xy 240.049283 -34.609393) (xy 240.103013 -34.617383) (xy 240.155066 -34.632913)
			(xy 240.204391 -34.655668) (xy 240.249989 -34.685189) (xy 240.290939 -34.720879) (xy 240.326414 -34.762017)
			(xy 240.355695 -34.807769) (xy 240.378191 -34.857213) (xy 240.393447 -34.909347) (xy 240.401155 -34.963118)
			(xy 240.401598 -34.990024) (xy 241.466876 -34.990024) (xy 241.470947 -34.934402) (xy 241.483073 -34.879965)
			(xy 241.502996 -34.827874) (xy 241.530292 -34.779239) (xy 241.564378 -34.735096) (xy 241.604527 -34.696387)
			(xy 241.649885 -34.663936) (xy 241.699485 -34.638435) (xy 241.752269 -34.620428) (xy 241.807112 -34.610298)
			(xy 241.862846 -34.608261) (xy 241.918283 -34.614361) (xy 241.97224 -34.628467) (xy 242.023569 -34.650279)
			(xy 242.071175 -34.679333) (xy 242.114043 -34.715008) (xy 242.15126 -34.756545) (xy 242.182033 -34.803058)
			(xy 242.205705 -34.853555) (xy 242.221773 -34.906962) (xy 242.229893 -34.962138) (xy 242.230402 -34.990024)
			(xy 243.872764 -34.990024) (xy 243.876835 -34.934402) (xy 243.888961 -34.879965) (xy 243.908884 -34.827874)
			(xy 243.93618 -34.779239) (xy 243.970266 -34.735096) (xy 244.010415 -34.696387) (xy 244.055773 -34.663936)
			(xy 244.105373 -34.638435) (xy 244.158157 -34.620428) (xy 244.213 -34.610298) (xy 244.268734 -34.608261)
			(xy 244.324171 -34.614361) (xy 244.378128 -34.628467) (xy 244.429457 -34.650279) (xy 244.477063 -34.679333)
			(xy 244.519931 -34.715008) (xy 244.557148 -34.756545) (xy 244.587921 -34.803058) (xy 244.611593 -34.853555)
			(xy 244.627661 -34.906962) (xy 244.635781 -34.962138) (xy 244.63629 -34.990024) (xy 245.07012 -34.990024)
			(xy 245.074191 -34.934402) (xy 245.086317 -34.879965) (xy 245.10624 -34.827874) (xy 245.133536 -34.779239)
			(xy 245.167622 -34.735096) (xy 245.207771 -34.696387) (xy 245.253129 -34.663936) (xy 245.302729 -34.638435)
			(xy 245.355513 -34.620428) (xy 245.410356 -34.610298) (xy 245.46609 -34.608261) (xy 245.521527 -34.614361)
			(xy 245.575484 -34.628467) (xy 245.626813 -34.650279) (xy 245.674419 -34.679333) (xy 245.717287 -34.715008)
			(xy 245.754504 -34.756545) (xy 245.785277 -34.803058) (xy 245.808949 -34.853555) (xy 245.825017 -34.906962)
			(xy 245.833137 -34.962138) (xy 245.833646 -34.990024) (xy 248.098816 -34.990024) (xy 248.102887 -34.934402)
			(xy 248.115013 -34.879965) (xy 248.134936 -34.827874) (xy 248.162232 -34.779239) (xy 248.196318 -34.735096)
			(xy 248.236467 -34.696387) (xy 248.281825 -34.663936) (xy 248.331425 -34.638435) (xy 248.384209 -34.620428)
			(xy 248.439052 -34.610298) (xy 248.494786 -34.608261) (xy 248.550223 -34.614361) (xy 248.60418 -34.628467)
			(xy 248.655509 -34.650279) (xy 248.703115 -34.679333) (xy 248.745983 -34.715008) (xy 248.7832 -34.756545)
			(xy 248.813973 -34.803058) (xy 248.837645 -34.853555) (xy 248.853713 -34.906962) (xy 248.861833 -34.962138)
			(xy 248.862342 -34.990024) (xy 248.861833 -35.01791) (xy 248.853713 -35.073086) (xy 248.837645 -35.126493)
			(xy 248.813973 -35.17699) (xy 248.7832 -35.223503) (xy 248.746151 -35.264852) (xy 262.102344 -35.264852)
			(xy 262.106415 -35.20923) (xy 262.118541 -35.154793) (xy 262.138464 -35.102702) (xy 262.16576 -35.054067)
			(xy 262.199846 -35.009924) (xy 262.239995 -34.971215) (xy 262.285353 -34.938764) (xy 262.334953 -34.913263)
			(xy 262.387737 -34.895256) (xy 262.44258 -34.885126) (xy 262.498314 -34.883089) (xy 262.553751 -34.889189)
			(xy 262.607708 -34.903295) (xy 262.659037 -34.925107) (xy 262.706643 -34.954161) (xy 262.749511 -34.989836)
			(xy 262.786728 -35.031373) (xy 262.817501 -35.077886) (xy 262.841173 -35.128383) (xy 262.857241 -35.18179)
			(xy 262.865361 -35.236966) (xy 262.86587 -35.264852) (xy 262.865361 -35.292738) (xy 262.857241 -35.347914)
			(xy 262.841173 -35.401321) (xy 262.817501 -35.451818) (xy 262.786728 -35.498331) (xy 262.749511 -35.539868)
			(xy 262.706643 -35.575543) (xy 262.659037 -35.604597) (xy 262.607708 -35.626409) (xy 262.553751 -35.640515)
			(xy 262.498314 -35.646615) (xy 262.44258 -35.644578) (xy 262.387737 -35.634448) (xy 262.334953 -35.616441)
			(xy 262.285353 -35.59094) (xy 262.239995 -35.558489) (xy 262.199846 -35.51978) (xy 262.16576 -35.475637)
			(xy 262.138464 -35.427002) (xy 262.118541 -35.374911) (xy 262.106415 -35.320474) (xy 262.102344 -35.264852)
			(xy 248.746151 -35.264852) (xy 248.745983 -35.26504) (xy 248.703115 -35.300715) (xy 248.655509 -35.329769)
			(xy 248.60418 -35.351581) (xy 248.550223 -35.365687) (xy 248.494786 -35.371787) (xy 248.439052 -35.36975)
			(xy 248.384209 -35.35962) (xy 248.331425 -35.341613) (xy 248.281825 -35.316112) (xy 248.236467 -35.283661)
			(xy 248.196318 -35.244952) (xy 248.162232 -35.200809) (xy 248.134936 -35.152174) (xy 248.115013 -35.100083)
			(xy 248.102887 -35.045646) (xy 248.098816 -34.990024) (xy 245.833646 -34.990024) (xy 245.833137 -35.01791)
			(xy 245.825017 -35.073086) (xy 245.808949 -35.126493) (xy 245.785277 -35.17699) (xy 245.754504 -35.223503)
			(xy 245.717287 -35.26504) (xy 245.674419 -35.300715) (xy 245.626813 -35.329769) (xy 245.575484 -35.351581)
			(xy 245.521527 -35.365687) (xy 245.46609 -35.371787) (xy 245.410356 -35.36975) (xy 245.355513 -35.35962)
			(xy 245.302729 -35.341613) (xy 245.253129 -35.316112) (xy 245.207771 -35.283661) (xy 245.167622 -35.244952)
			(xy 245.133536 -35.200809) (xy 245.10624 -35.152174) (xy 245.086317 -35.100083) (xy 245.074191 -35.045646)
			(xy 245.07012 -34.990024) (xy 244.63629 -34.990024) (xy 244.635781 -35.01791) (xy 244.627661 -35.073086)
			(xy 244.611593 -35.126493) (xy 244.587921 -35.17699) (xy 244.557148 -35.223503) (xy 244.519931 -35.26504)
			(xy 244.477063 -35.300715) (xy 244.429457 -35.329769) (xy 244.378128 -35.351581) (xy 244.324171 -35.365687)
			(xy 244.268734 -35.371787) (xy 244.213 -35.36975) (xy 244.158157 -35.35962) (xy 244.105373 -35.341613)
			(xy 244.055773 -35.316112) (xy 244.010415 -35.283661) (xy 243.970266 -35.244952) (xy 243.93618 -35.200809)
			(xy 243.908884 -35.152174) (xy 243.888961 -35.100083) (xy 243.876835 -35.045646) (xy 243.872764 -34.990024)
			(xy 242.230402 -34.990024) (xy 242.229893 -35.01791) (xy 242.221773 -35.073086) (xy 242.205705 -35.126493)
			(xy 242.182033 -35.17699) (xy 242.15126 -35.223503) (xy 242.114043 -35.26504) (xy 242.071175 -35.300715)
			(xy 242.023569 -35.329769) (xy 241.97224 -35.351581) (xy 241.918283 -35.365687) (xy 241.862846 -35.371787)
			(xy 241.807112 -35.36975) (xy 241.752269 -35.35962) (xy 241.699485 -35.341613) (xy 241.649885 -35.316112)
			(xy 241.604527 -35.283661) (xy 241.564378 -35.244952) (xy 241.530292 -35.200809) (xy 241.502996 -35.152174)
			(xy 241.483073 -35.100083) (xy 241.470947 -35.045646) (xy 241.466876 -34.990024) (xy 240.401598 -34.990024)
			(xy 240.401602 -34.990278) (xy 240.40114 -35.017532) (xy 240.393386 -35.071485) (xy 240.378032 -35.123785)
			(xy 240.35539 -35.173367) (xy 240.325923 -35.219223) (xy 240.290229 -35.260418) (xy 240.249036 -35.296113)
			(xy 240.203181 -35.325583) (xy 240.1536 -35.348226) (xy 240.1013 -35.363582) (xy 240.047348 -35.371339)
			(xy 240.020094 -35.371786) (xy 239.993129 -35.371326) (xy 239.939737 -35.36374) (xy 239.887946 -35.348707)
			(xy 239.83879 -35.326526) (xy 239.79325 -35.29764) (xy 239.752234 -35.262625) (xy 239.716561 -35.22218)
			(xy 239.686944 -35.177112) (xy 239.663972 -35.128321) (xy 239.648104 -35.076779) (xy 239.643412 -35.050222)
			(xy 239.642142 -35.042856) (xy 239.641634 -35.0393) (xy 239.635792 -35.03041) (xy 239.6329 -35.026193)
			(xy 239.625728 -35.018907) (xy 239.621568 -35.015932) (xy 239.55883 -34.974276) (xy 239.554336 -34.971439)
			(xy 239.544479 -34.967466) (xy 239.539272 -34.966402) (xy 239.529366 -34.964624) (xy 239.518952 -34.967164)
			(xy 239.492258 -34.973307) (xy 239.437882 -34.97993) (xy 239.410494 -34.980372) (xy 239.383106 -34.979925)
			(xy 239.328731 -34.973301) (xy 239.302036 -34.967164) (xy 239.291622 -34.964624) (xy 239.281716 -34.966402)
			(xy 239.276497 -34.967429) (xy 239.266633 -34.971401) (xy 239.262158 -34.974276) (xy 239.19942 -35.015932)
			(xy 239.195249 -35.018893) (xy 239.188075 -35.026183) (xy 239.185196 -35.03041) (xy 239.179354 -35.0393)
			(xy 239.178846 -35.042856) (xy 239.177576 -35.050222) (xy 239.172876 -35.076775) (xy 239.156984 -35.128303)
			(xy 239.133996 -35.17708) (xy 239.104371 -35.222136) (xy 239.068699 -35.262573) (xy 239.027689 -35.297586)
			(xy 238.982159 -35.326478) (xy 238.933016 -35.348673) (xy 238.881237 -35.363729) (xy 238.827855 -35.371347)
			(xy 238.800894 -35.371786) (xy 238.773645 -35.371299) (xy 238.719701 -35.363543) (xy 238.66741 -35.348188)
			(xy 238.617836 -35.325548) (xy 238.571989 -35.296083) (xy 238.530802 -35.260394) (xy 238.495113 -35.219206)
			(xy 238.465649 -35.173358) (xy 238.44301 -35.123785) (xy 238.427656 -35.071493) (xy 238.4199 -35.017549)
			(xy 238.4199 -34.963051) (xy 238.427656 -34.909107) (xy 238.44301 -34.856815) (xy 238.465649 -34.807242)
			(xy 238.495113 -34.761394) (xy 238.530802 -34.720206) (xy 238.571989 -34.684517) (xy 238.617836 -34.655052)
			(xy 238.66741 -34.632412) (xy 238.719701 -34.617057) (xy 238.773645 -34.609301) (xy 238.800894 -34.60877)
			(xy 238.801148 -34.60877) (xy 238.818197 -34.60895) (xy 238.852159 -34.611999) (xy 238.868966 -34.614866)
			(xy 238.879576 -34.616176) (xy 238.900303 -34.611042) (xy 238.909098 -34.60496) (xy 238.937292 -34.580576)
			(xy 238.94481 -34.572722) (xy 238.952959 -34.552587) (xy 238.95304 -34.541714) (xy 238.952532 -34.52241)
			(xy 238.952532 -33.911286) (xy 238.952042 -33.901278) (xy 238.944381 -33.882785) (xy 238.93023 -33.868629)
			(xy 238.91174 -33.860961) (xy 238.901732 -33.860486) (xy 236.500924 -33.860486) (xy 236.491666 -33.860839)
			(xy 236.47434 -33.867354) (xy 236.467142 -33.873186) (xy 236.460284 -33.879282) (xy 236.451902 -33.895284)
			(xy 236.450632 -33.904936) (xy 236.446743 -33.932265) (xy 236.432108 -33.985488) (xy 236.409952 -34.036046)
			(xy 236.380739 -34.082881) (xy 236.345078 -34.125014) (xy 236.303715 -34.161566) (xy 236.257514 -34.191773)
			(xy 236.207441 -34.215003) (xy 236.154542 -34.23077) (xy 236.099922 -34.238746) (xy 236.044723 -34.238764)
			(xy 235.990098 -34.230823) (xy 235.937189 -34.215089) (xy 235.887101 -34.191892) (xy 235.84088 -34.161715)
			(xy 235.799494 -34.12519) (xy 235.763806 -34.083079) (xy 235.734562 -34.036263) (xy 235.712374 -33.985719)
			(xy 235.697705 -33.932505) (xy 235.693712 -33.90519) (xy 235.693712 -33.904428) (xy 235.692154 -33.895408)
			(xy 235.683558 -33.879264) (xy 235.676948 -33.872932) (xy 235.67009 -33.86709) (xy 235.652818 -33.860486)
			(xy 235.015024 -33.860486) (xy 235.002464 -33.861122) (xy 234.980316 -33.872968) (xy 234.97286 -33.883092)
			(xy 234.95508 -33.912048) (xy 234.926378 -33.959292) (xy 234.923195 -33.9649) (xy 234.919477 -33.977244)
			(xy 234.919012 -33.983676) (xy 234.918504 -33.996376) (xy 234.924854 -34.008568) (xy 234.938143 -34.035715)
			(xy 234.956935 -34.09316) (xy 234.966452 -34.152846) (xy 234.967018 -34.183066) (xy 234.967018 -34.188654)
			(xy 234.966156 -34.215644) (xy 234.957764 -34.268987) (xy 234.941932 -34.320613) (xy 234.918978 -34.369491)
			(xy 234.88936 -34.414643) (xy 234.853671 -34.455167) (xy 234.812623 -34.490253) (xy 234.767038 -34.519199)
			(xy 234.717826 -34.541428) (xy 234.665971 -34.556494) (xy 234.61251 -34.564096) (xy 234.58551 -34.564574)
			(xy 234.558904 -34.564113) (xy 234.506207 -34.556721) (xy 234.455049 -34.542078) (xy 234.406422 -34.520469)
			(xy 234.361268 -34.492313) (xy 234.320465 -34.458157) (xy 234.284804 -34.418662) (xy 234.254976 -34.374595)
			(xy 234.231561 -34.326811) (xy 234.222798 -34.301684) (xy 234.21975 -34.292286) (xy 234.214162 -34.285428)
			(xy 234.211323 -34.282076) (xy 234.204676 -34.276332) (xy 234.200954 -34.273998) (xy 234.142788 -34.2392)
			(xy 234.138931 -34.236981) (xy 234.130629 -34.233781) (xy 234.126278 -34.23285) (xy 234.117896 -34.231326)
			(xy 234.108244 -34.233104) (xy 234.091371 -34.235957) (xy 234.057284 -34.239009) (xy 234.040172 -34.2392)
			(xy 234.03814 -34.2392) (xy 234.010651 -34.238578) (xy 233.956278 -34.2304) (xy 233.903643 -34.214498)
			(xy 233.853839 -34.191201) (xy 233.807897 -34.160991) (xy 233.76677 -34.124496) (xy 233.731312 -34.082473)
			(xy 233.702258 -34.035792) (xy 233.68021 -33.985422) (xy 233.665625 -33.932407) (xy 233.661712 -33.90519)
			(xy 233.661712 -33.904428) (xy 233.660154 -33.895408) (xy 233.651558 -33.879264) (xy 233.644948 -33.872932)
			(xy 233.63809 -33.86709) (xy 233.620818 -33.860486) (xy 216.555828 -33.860486) (xy 216.545802 -33.860901)
			(xy 216.527273 -33.868565) (xy 216.513089 -33.882738) (xy 216.505409 -33.90126) (xy 216.505028 -33.911286)
			(xy 216.505028 -34.241232) (xy 216.505028 -34.241994) (xy 216.50572 -34.252337) (xy 216.51423 -34.271219)
			(xy 216.521538 -34.27857) (xy 216.522808 -34.27984) (xy 216.557606 -34.309558) (xy 216.582244 -34.330386)
			(xy 216.586378 -34.333706) (xy 216.595729 -34.338699) (xy 216.600786 -34.340292) (xy 216.6112 -34.34334)
			(xy 216.622376 -34.341562) (xy 216.637202 -34.339389) (xy 216.667082 -34.337101) (xy 216.682066 -34.33699)
			(xy 216.68232 -34.33699) (xy 216.709524 -34.337545) (xy 216.763361 -34.345419) (xy 216.815534 -34.360863)
			(xy 216.864983 -34.383562) (xy 216.910706 -34.413056) (xy 216.951774 -34.448747) (xy 216.987355 -34.48991)
			(xy 217.016727 -34.535712) (xy 217.039294 -34.585221) (xy 217.054598 -34.637435) (xy 217.062329 -34.691293)
			(xy 217.062812 -34.718498) (xy 217.062326 -34.745749) (xy 217.05457 -34.799698) (xy 217.039215 -34.851993)
			(xy 217.016574 -34.901571) (xy 216.987108 -34.947422) (xy 216.951417 -34.988612) (xy 216.910226 -35.024304)
			(xy 216.864376 -35.053771) (xy 216.814798 -35.076413) (xy 216.762503 -35.091769) (xy 216.708555 -35.099526)
			(xy 216.681304 -35.100006) (xy 216.68105 -35.100006) (xy 216.651544 -35.099452) (xy 216.593236 -35.090362)
			(xy 216.537022 -35.072407) (xy 216.484241 -35.046015) (xy 216.436151 -35.011813) (xy 216.393897 -34.970618)
			(xy 216.375742 -34.947352) (xy 216.370662 -34.94024) (xy 216.34831 -34.925508) (xy 216.344387 -34.922979)
			(xy 216.335821 -34.919273) (xy 216.331292 -34.918142) (xy 216.309702 -34.913316) (xy 216.300691 -34.911724)
			(xy 216.282594 -34.914332) (xy 216.274396 -34.918396) (xy 216.273888 -34.91865) (xy 216.255506 -34.928876)
			(xy 216.217218 -34.946302) (xy 216.197434 -34.953448) (xy 216.173233 -34.96149) (xy 216.123499 -34.97278)
			(xy 216.072819 -34.978478) (xy 216.04732 -34.978848) (xy 216.02182 -34.978488) (xy 215.971138 -34.972796)
			(xy 215.921403 -34.961504) (xy 215.897206 -34.953448) (xy 215.877421 -34.946304) (xy 215.839132 -34.92888)
			(xy 215.820752 -34.91865) (xy 215.820244 -34.918396) (xy 215.812045 -34.914336) (xy 215.793949 -34.91173)
			(xy 215.784938 -34.913316) (xy 215.763348 -34.918142) (xy 215.758828 -34.919296) (xy 215.750267 -34.923004)
			(xy 215.74633 -34.925508) (xy 215.723978 -34.94024) (xy 215.718898 -34.947352) (xy 215.700748 -34.970654)
			(xy 215.65847 -35.011898) (xy 215.610339 -35.04613) (xy 215.557506 -35.072532) (xy 215.501234 -35.090473)
			(xy 215.442868 -35.099524) (xy 215.413336 -35.100006) (xy 215.402414 -35.100006) (xy 215.40216 -35.099752)
			(xy 215.375445 -35.098515) (xy 215.322732 -35.089492) (xy 215.271796 -35.073198) (xy 215.223633 -35.049952)
			(xy 215.179187 -35.020208) (xy 215.13933 -34.984551) (xy 215.104841 -34.943679) (xy 215.076396 -34.898391)
			(xy 215.054553 -34.849576) (xy 215.03974 -34.798189) (xy 215.032246 -34.745238) (xy 215.031828 -34.718498)
			(xy 215.032291 -34.691246) (xy 215.040049 -34.637297) (xy 215.055405 -34.585002) (xy 215.078049 -34.535424)
			(xy 215.107517 -34.489574) (xy 215.143211 -34.448384) (xy 215.184404 -34.412694) (xy 215.230258 -34.38323)
			(xy 215.279837 -34.360592) (xy 215.332135 -34.345241) (xy 215.386084 -34.337489) (xy 215.413336 -34.33699)
			(xy 215.428129 -34.337133) (xy 215.457626 -34.339422) (xy 215.472264 -34.341562) (xy 215.48344 -34.34334)
			(xy 215.493854 -34.340292) (xy 215.498899 -34.338673) (xy 215.508242 -34.333676) (xy 215.512396 -34.330386)
			(xy 215.537034 -34.309558) (xy 215.571832 -34.27984) (xy 215.573102 -34.27857) (xy 215.580442 -34.271236)
			(xy 215.588987 -34.25235) (xy 215.589612 -34.241994) (xy 215.589612 -33.911286) (xy 215.589121 -33.901279)
			(xy 215.58146 -33.88279) (xy 215.567308 -33.868639) (xy 215.548819 -33.860978) (xy 215.538812 -33.860486)
			(xy 201.819256 -33.860486) (xy 201.809253 -33.860981) (xy 201.790774 -33.868648) (xy 201.776631 -33.882799)
			(xy 201.768975 -33.901283) (xy 201.768456 -33.911286) (xy 201.768456 -34.52241) (xy 201.767948 -34.541714)
			(xy 201.767948 -34.543492) (xy 201.768343 -34.554333) (xy 201.77702 -34.574196) (xy 201.784712 -34.581846)
			(xy 201.788268 -34.584894) (xy 201.809858 -34.603436) (xy 201.810874 -34.604452) (xy 201.819767 -34.610958)
			(xy 201.841105 -34.616358) (xy 201.852022 -34.614866) (xy 201.868832 -34.612021) (xy 201.902792 -34.608967)
			(xy 201.91984 -34.60877) (xy 201.922126 -34.60877) (xy 201.949283 -34.609393) (xy 202.003013 -34.617383)
			(xy 202.055066 -34.632913) (xy 202.104391 -34.655668) (xy 202.149989 -34.685189) (xy 202.190939 -34.720879)
			(xy 202.226414 -34.762017) (xy 202.255695 -34.807769) (xy 202.278191 -34.857213) (xy 202.293447 -34.909347)
			(xy 202.301155 -34.963118) (xy 202.301598 -34.990024) (xy 203.366876 -34.990024) (xy 203.370947 -34.934402)
			(xy 203.383073 -34.879965) (xy 203.402996 -34.827874) (xy 203.430292 -34.779239) (xy 203.464378 -34.735096)
			(xy 203.504527 -34.696387) (xy 203.549885 -34.663936) (xy 203.599485 -34.638435) (xy 203.652269 -34.620428)
			(xy 203.707112 -34.610298) (xy 203.762846 -34.608261) (xy 203.818283 -34.614361) (xy 203.87224 -34.628467)
			(xy 203.923569 -34.650279) (xy 203.971175 -34.679333) (xy 204.014043 -34.715008) (xy 204.05126 -34.756545)
			(xy 204.082033 -34.803058) (xy 204.105705 -34.853555) (xy 204.121773 -34.906962) (xy 204.129893 -34.962138)
			(xy 204.130402 -34.990024) (xy 205.772764 -34.990024) (xy 205.776835 -34.934402) (xy 205.788961 -34.879965)
			(xy 205.808884 -34.827874) (xy 205.83618 -34.779239) (xy 205.870266 -34.735096) (xy 205.910415 -34.696387)
			(xy 205.955773 -34.663936) (xy 206.005373 -34.638435) (xy 206.058157 -34.620428) (xy 206.113 -34.610298)
			(xy 206.168734 -34.608261) (xy 206.224171 -34.614361) (xy 206.278128 -34.628467) (xy 206.329457 -34.650279)
			(xy 206.377063 -34.679333) (xy 206.419931 -34.715008) (xy 206.457148 -34.756545) (xy 206.487921 -34.803058)
			(xy 206.511593 -34.853555) (xy 206.527661 -34.906962) (xy 206.535781 -34.962138) (xy 206.53629 -34.990024)
			(xy 207.04378 -34.990024) (xy 207.047851 -34.934402) (xy 207.059977 -34.879965) (xy 207.0799 -34.827874)
			(xy 207.107196 -34.779239) (xy 207.141282 -34.735096) (xy 207.181431 -34.696387) (xy 207.226789 -34.663936)
			(xy 207.276389 -34.638435) (xy 207.329173 -34.620428) (xy 207.384016 -34.610298) (xy 207.43975 -34.608261)
			(xy 207.495187 -34.614361) (xy 207.549144 -34.628467) (xy 207.600473 -34.650279) (xy 207.648079 -34.679333)
			(xy 207.690947 -34.715008) (xy 207.728164 -34.756545) (xy 207.758937 -34.803058) (xy 207.782609 -34.853555)
			(xy 207.798677 -34.906962) (xy 207.806797 -34.962138) (xy 207.807306 -34.990024) (xy 209.998816 -34.990024)
			(xy 210.002887 -34.934402) (xy 210.015013 -34.879965) (xy 210.034936 -34.827874) (xy 210.062232 -34.779239)
			(xy 210.096318 -34.735096) (xy 210.136467 -34.696387) (xy 210.181825 -34.663936) (xy 210.231425 -34.638435)
			(xy 210.284209 -34.620428) (xy 210.339052 -34.610298) (xy 210.394786 -34.608261) (xy 210.450223 -34.614361)
			(xy 210.50418 -34.628467) (xy 210.555509 -34.650279) (xy 210.603115 -34.679333) (xy 210.645983 -34.715008)
			(xy 210.6832 -34.756545) (xy 210.713973 -34.803058) (xy 210.737645 -34.853555) (xy 210.753713 -34.906962)
			(xy 210.761833 -34.962138) (xy 210.762342 -34.990024) (xy 210.761833 -35.01791) (xy 210.753713 -35.073086)
			(xy 210.737645 -35.126493) (xy 210.713973 -35.17699) (xy 210.6832 -35.223503) (xy 210.646151 -35.264852)
			(xy 236.102396 -35.264852) (xy 236.106467 -35.20923) (xy 236.118593 -35.154793) (xy 236.138516 -35.102702)
			(xy 236.165812 -35.054067) (xy 236.199898 -35.009924) (xy 236.240047 -34.971215) (xy 236.285405 -34.938764)
			(xy 236.335005 -34.913263) (xy 236.387789 -34.895256) (xy 236.442632 -34.885126) (xy 236.498366 -34.883089)
			(xy 236.553803 -34.889189) (xy 236.60776 -34.903295) (xy 236.659089 -34.925107) (xy 236.706695 -34.954161)
			(xy 236.749563 -34.989836) (xy 236.78678 -35.031373) (xy 236.817553 -35.077886) (xy 236.841225 -35.128383)
			(xy 236.857293 -35.18179) (xy 236.865413 -35.236966) (xy 236.865922 -35.264852) (xy 236.865413 -35.292738)
			(xy 236.857293 -35.347914) (xy 236.841225 -35.401321) (xy 236.817553 -35.451818) (xy 236.78678 -35.498331)
			(xy 236.749563 -35.539868) (xy 236.706695 -35.575543) (xy 236.659089 -35.604597) (xy 236.60776 -35.626409)
			(xy 236.553803 -35.640515) (xy 236.498366 -35.646615) (xy 236.442632 -35.644578) (xy 236.387789 -35.634448)
			(xy 236.335005 -35.616441) (xy 236.285405 -35.59094) (xy 236.240047 -35.558489) (xy 236.199898 -35.51978)
			(xy 236.165812 -35.475637) (xy 236.138516 -35.427002) (xy 236.118593 -35.374911) (xy 236.106467 -35.320474)
			(xy 236.102396 -35.264852) (xy 210.646151 -35.264852) (xy 210.645983 -35.26504) (xy 210.603115 -35.300715)
			(xy 210.555509 -35.329769) (xy 210.50418 -35.351581) (xy 210.450223 -35.365687) (xy 210.394786 -35.371787)
			(xy 210.339052 -35.36975) (xy 210.284209 -35.35962) (xy 210.231425 -35.341613) (xy 210.181825 -35.316112)
			(xy 210.136467 -35.283661) (xy 210.096318 -35.244952) (xy 210.062232 -35.200809) (xy 210.034936 -35.152174)
			(xy 210.015013 -35.100083) (xy 210.002887 -35.045646) (xy 209.998816 -34.990024) (xy 207.807306 -34.990024)
			(xy 207.806797 -35.01791) (xy 207.798677 -35.073086) (xy 207.782609 -35.126493) (xy 207.758937 -35.17699)
			(xy 207.728164 -35.223503) (xy 207.690947 -35.26504) (xy 207.648079 -35.300715) (xy 207.600473 -35.329769)
			(xy 207.549144 -35.351581) (xy 207.495187 -35.365687) (xy 207.43975 -35.371787) (xy 207.384016 -35.36975)
			(xy 207.329173 -35.35962) (xy 207.276389 -35.341613) (xy 207.226789 -35.316112) (xy 207.181431 -35.283661)
			(xy 207.141282 -35.244952) (xy 207.107196 -35.200809) (xy 207.0799 -35.152174) (xy 207.059977 -35.100083)
			(xy 207.047851 -35.045646) (xy 207.04378 -34.990024) (xy 206.53629 -34.990024) (xy 206.535781 -35.01791)
			(xy 206.527661 -35.073086) (xy 206.511593 -35.126493) (xy 206.487921 -35.17699) (xy 206.457148 -35.223503)
			(xy 206.419931 -35.26504) (xy 206.377063 -35.300715) (xy 206.329457 -35.329769) (xy 206.278128 -35.351581)
			(xy 206.224171 -35.365687) (xy 206.168734 -35.371787) (xy 206.113 -35.36975) (xy 206.058157 -35.35962)
			(xy 206.005373 -35.341613) (xy 205.955773 -35.316112) (xy 205.910415 -35.283661) (xy 205.870266 -35.244952)
			(xy 205.83618 -35.200809) (xy 205.808884 -35.152174) (xy 205.788961 -35.100083) (xy 205.776835 -35.045646)
			(xy 205.772764 -34.990024) (xy 204.130402 -34.990024) (xy 204.129893 -35.01791) (xy 204.121773 -35.073086)
			(xy 204.105705 -35.126493) (xy 204.082033 -35.17699) (xy 204.05126 -35.223503) (xy 204.014043 -35.26504)
			(xy 203.971175 -35.300715) (xy 203.923569 -35.329769) (xy 203.87224 -35.351581) (xy 203.818283 -35.365687)
			(xy 203.762846 -35.371787) (xy 203.707112 -35.36975) (xy 203.652269 -35.35962) (xy 203.599485 -35.341613)
			(xy 203.549885 -35.316112) (xy 203.504527 -35.283661) (xy 203.464378 -35.244952) (xy 203.430292 -35.200809)
			(xy 203.402996 -35.152174) (xy 203.383073 -35.100083) (xy 203.370947 -35.045646) (xy 203.366876 -34.990024)
			(xy 202.301598 -34.990024) (xy 202.301602 -34.990278) (xy 202.301157 -35.017057) (xy 202.29368 -35.070089)
			(xy 202.278855 -35.121554) (xy 202.256974 -35.170437) (xy 202.228468 -35.215778) (xy 202.193898 -35.256683)
			(xy 202.153944 -35.292349) (xy 202.109393 -35.322073) (xy 202.06112 -35.34527) (xy 202.010076 -35.361484)
			(xy 201.957266 -35.370395) (xy 201.930508 -35.371532) (xy 201.918062 -35.37204) (xy 201.907648 -35.377628)
			(xy 201.902493 -35.380691) (xy 201.893636 -35.388771) (xy 201.890122 -35.39363) (xy 201.874882 -35.415728)
			(xy 201.843386 -35.461702) (xy 201.840168 -35.466804) (xy 201.83593 -35.478094) (xy 201.835004 -35.484054)
			(xy 201.83348 -35.495484) (xy 201.836528 -35.50412) (xy 201.847278 -35.535751) (xy 201.858902 -35.601531)
			(xy 201.859642 -35.63493) (xy 201.859642 -35.635184) (xy 201.859156 -35.662435) (xy 201.8514 -35.716383)
			(xy 201.836045 -35.768678) (xy 201.813403 -35.818255) (xy 201.783937 -35.864105) (xy 201.748246 -35.905296)
			(xy 201.707055 -35.940987) (xy 201.661205 -35.970453) (xy 201.611628 -35.993095) (xy 201.559333 -36.00845)
			(xy 201.505385 -36.016206) (xy 201.450883 -36.016206) (xy 201.396935 -36.00845) (xy 201.34464 -35.993095)
			(xy 201.295063 -35.970453) (xy 201.249213 -35.940987) (xy 201.208022 -35.905296) (xy 201.172331 -35.864105)
			(xy 201.142865 -35.818255) (xy 201.120223 -35.768678) (xy 201.104868 -35.716383) (xy 201.097112 -35.662435)
			(xy 201.096626 -35.635184) (xy 201.097073 -35.608408) (xy 201.104555 -35.555381) (xy 201.119384 -35.503922)
			(xy 201.141267 -35.455045) (xy 201.169775 -35.409711) (xy 201.204345 -35.368812) (xy 201.244299 -35.333153)
			(xy 201.288849 -35.303436) (xy 201.337119 -35.280245) (xy 201.38816 -35.264036) (xy 201.440966 -35.25513)
			(xy 201.46772 -35.25393) (xy 201.480166 -35.253422) (xy 201.495914 -35.244786) (xy 201.504804 -35.236912)
			(xy 201.507598 -35.232848) (xy 201.554842 -35.163252) (xy 201.558055 -35.158287) (xy 201.56229 -35.147248)
			(xy 201.563224 -35.141408) (xy 201.564748 -35.129978) (xy 201.560684 -35.118294) (xy 201.557018 -35.107666)
			(xy 201.550788 -35.086063) (xy 201.548238 -35.075114) (xy 201.543412 -35.050222) (xy 201.542142 -35.042856)
			(xy 201.541634 -35.0393) (xy 201.535792 -35.03041) (xy 201.5329 -35.026193) (xy 201.525728 -35.018907)
			(xy 201.521568 -35.015932) (xy 201.45883 -34.974276) (xy 201.454336 -34.971439) (xy 201.444479 -34.967466)
			(xy 201.439272 -34.966402) (xy 201.429366 -34.964624) (xy 201.418952 -34.967164) (xy 201.392258 -34.973307)
			(xy 201.337882 -34.97993) (xy 201.310494 -34.980372) (xy 201.283106 -34.979925) (xy 201.228731 -34.973301)
			(xy 201.202036 -34.967164) (xy 201.191622 -34.964624) (xy 201.181716 -34.966402) (xy 201.176497 -34.967429)
			(xy 201.166633 -34.971401) (xy 201.162158 -34.974276) (xy 201.09942 -35.015932) (xy 201.095249 -35.018893)
			(xy 201.088075 -35.026183) (xy 201.085196 -35.03041) (xy 201.079354 -35.0393) (xy 201.078846 -35.042856)
			(xy 201.077576 -35.050222) (xy 201.072876 -35.076775) (xy 201.056984 -35.128303) (xy 201.033996 -35.17708)
			(xy 201.004371 -35.222136) (xy 200.968699 -35.262573) (xy 200.927689 -35.297586) (xy 200.882159 -35.326478)
			(xy 200.833016 -35.348673) (xy 200.781237 -35.363729) (xy 200.727855 -35.371347) (xy 200.700894 -35.371786)
			(xy 200.673645 -35.371299) (xy 200.619701 -35.363543) (xy 200.56741 -35.348188) (xy 200.517836 -35.325548)
			(xy 200.471989 -35.296083) (xy 200.430802 -35.260394) (xy 200.395113 -35.219206) (xy 200.365649 -35.173358)
			(xy 200.34301 -35.123785) (xy 200.327656 -35.071493) (xy 200.3199 -35.017549) (xy 200.3199 -34.963051)
			(xy 200.327656 -34.909107) (xy 200.34301 -34.856815) (xy 200.365649 -34.807242) (xy 200.395113 -34.761394)
			(xy 200.430802 -34.720206) (xy 200.471989 -34.684517) (xy 200.517836 -34.655052) (xy 200.56741 -34.632412)
			(xy 200.619701 -34.617057) (xy 200.673645 -34.609301) (xy 200.700894 -34.60877) (xy 200.701148 -34.60877)
			(xy 200.718197 -34.60895) (xy 200.752159 -34.611999) (xy 200.768966 -34.614866) (xy 200.772877 -34.615466)
			(xy 200.780787 -34.6156) (xy 200.784714 -34.61512) (xy 200.789286 -34.614358) (xy 200.795128 -34.61258)
			(xy 200.799474 -34.610959) (xy 200.807531 -34.606363) (xy 200.81113 -34.603436) (xy 200.83272 -34.584894)
			(xy 200.836276 -34.581846) (xy 200.844017 -34.574226) (xy 200.852717 -34.554348) (xy 200.85304 -34.543492)
			(xy 200.85304 -34.541714) (xy 200.852532 -34.52241) (xy 200.852532 -33.911286) (xy 200.852042 -33.901278)
			(xy 200.844381 -33.882785) (xy 200.83023 -33.868629) (xy 200.81174 -33.860961) (xy 200.801732 -33.860486)
			(xy 198.400924 -33.860486) (xy 198.391666 -33.860839) (xy 198.37434 -33.867354) (xy 198.367142 -33.873186)
			(xy 198.360284 -33.879282) (xy 198.351902 -33.895284) (xy 198.350632 -33.904936) (xy 198.346743 -33.932265)
			(xy 198.332108 -33.985488) (xy 198.309952 -34.036046) (xy 198.280739 -34.082881) (xy 198.245078 -34.125014)
			(xy 198.203715 -34.161566) (xy 198.157514 -34.191773) (xy 198.107441 -34.215003) (xy 198.054542 -34.23077)
			(xy 197.999922 -34.238746) (xy 197.944723 -34.238764) (xy 197.890098 -34.230823) (xy 197.837189 -34.215089)
			(xy 197.787101 -34.191892) (xy 197.74088 -34.161715) (xy 197.699494 -34.12519) (xy 197.663806 -34.083079)
			(xy 197.634562 -34.036263) (xy 197.612374 -33.985719) (xy 197.597705 -33.932505) (xy 197.593712 -33.90519)
			(xy 197.593712 -33.904428) (xy 197.592154 -33.895408) (xy 197.583558 -33.879264) (xy 197.576948 -33.872932)
			(xy 197.57009 -33.86709) (xy 197.552818 -33.860486) (xy 196.915024 -33.860486) (xy 196.902464 -33.861122)
			(xy 196.880316 -33.872968) (xy 196.87286 -33.883092) (xy 196.85508 -33.912048) (xy 196.826378 -33.959292)
			(xy 196.823195 -33.9649) (xy 196.819477 -33.977244) (xy 196.819012 -33.983676) (xy 196.818504 -33.996376)
			(xy 196.824854 -34.008568) (xy 196.838143 -34.035715) (xy 196.856935 -34.09316) (xy 196.866452 -34.152846)
			(xy 196.867018 -34.183066) (xy 196.867018 -34.188654) (xy 196.86609 -34.216931) (xy 196.856918 -34.272757)
			(xy 196.839602 -34.326617) (xy 196.814523 -34.37733) (xy 196.782231 -34.423783) (xy 196.743433 -34.464959)
			(xy 196.698981 -34.499955) (xy 196.649848 -34.528002) (xy 196.597112 -34.548488) (xy 196.54193 -34.560961)
			(xy 196.48551 -34.56515) (xy 196.42909 -34.560961) (xy 196.373908 -34.548488) (xy 196.321172 -34.528002)
			(xy 196.272039 -34.499955) (xy 196.227587 -34.464959) (xy 196.188789 -34.423783) (xy 196.156497 -34.37733)
			(xy 196.131418 -34.326617) (xy 196.114102 -34.272757) (xy 196.10493 -34.216931) (xy 196.104002 -34.188654)
			(xy 196.104002 -34.183066) (xy 196.104553 -34.152843) (xy 196.114047 -34.09315) (xy 196.132853 -34.035706)
			(xy 196.146166 -34.008568) (xy 196.146166 -34.008314) (xy 196.149043 -34.002374) (xy 196.151992 -33.989514)
			(xy 196.152008 -33.982914) (xy 196.1515 -33.970468) (xy 196.11594 -33.912048) (xy 196.09816 -33.883092)
			(xy 196.090644 -33.873031) (xy 196.068535 -33.861183) (xy 196.055996 -33.860486) (xy 190.55588 -33.860486)
			(xy 190.545874 -33.860977) (xy 190.527386 -33.86864) (xy 190.513236 -33.882792) (xy 190.505576 -33.90128)
			(xy 190.50508 -33.911286) (xy 190.50508 -34.241232) (xy 190.50508 -34.241994) (xy 190.505774 -34.252336)
			(xy 190.51429 -34.271212) (xy 190.52159 -34.27857) (xy 190.52286 -34.27984) (xy 190.557658 -34.309558)
			(xy 190.582296 -34.330386) (xy 190.586428 -34.33371) (xy 190.595777 -34.338711) (xy 190.600838 -34.340292)
			(xy 190.611252 -34.34334) (xy 190.622428 -34.341562) (xy 190.637254 -34.339388) (xy 190.667134 -34.337096)
			(xy 190.682118 -34.33699) (xy 190.682372 -34.33699) (xy 190.709578 -34.337542) (xy 190.763421 -34.345411)
			(xy 190.815599 -34.36085) (xy 190.865054 -34.383546) (xy 190.910783 -34.413039) (xy 190.951857 -34.44873)
			(xy 190.987443 -34.489895) (xy 191.01682 -34.535698) (xy 191.03939 -34.585211) (xy 191.054697 -34.637428)
			(xy 191.062428 -34.691291) (xy 191.062864 -34.718498) (xy 191.062401 -34.74575) (xy 191.054644 -34.799699)
			(xy 191.039287 -34.851994) (xy 191.016644 -34.901572) (xy 190.987176 -34.947422) (xy 190.951482 -34.988611)
			(xy 190.910288 -35.024301) (xy 190.864435 -35.053765) (xy 190.814855 -35.076402) (xy 190.762558 -35.091753)
			(xy 190.708608 -35.099504) (xy 190.681356 -35.100006) (xy 190.681102 -35.100006) (xy 190.651598 -35.099448)
			(xy 190.593294 -35.090352) (xy 190.537085 -35.072392) (xy 190.484309 -35.045996) (xy 190.436225 -35.011792)
			(xy 190.393977 -34.970595) (xy 190.375794 -34.947352) (xy 190.370714 -34.94024) (xy 190.348362 -34.925508)
			(xy 190.344437 -34.922983) (xy 190.335869 -34.919285) (xy 190.331344 -34.918142) (xy 190.309754 -34.913316)
			(xy 190.300742 -34.911715) (xy 190.282636 -34.914306) (xy 190.274448 -34.918396) (xy 190.27394 -34.91865)
			(xy 190.255559 -34.928878) (xy 190.217272 -34.946308) (xy 190.197486 -34.953448) (xy 190.173286 -34.961493)
			(xy 190.123552 -34.972788) (xy 190.072872 -34.978492) (xy 190.047372 -34.978848) (xy 190.021872 -34.978485)
			(xy 189.971192 -34.972789) (xy 189.921459 -34.961492) (xy 189.897258 -34.953448) (xy 189.877474 -34.946302)
			(xy 189.839187 -34.928875) (xy 189.820804 -34.91865) (xy 189.820296 -34.918396) (xy 189.812096 -34.914344)
			(xy 189.794003 -34.911755) (xy 189.78499 -34.913316) (xy 189.7634 -34.918142) (xy 189.758878 -34.919292)
			(xy 189.750312 -34.922993) (xy 189.746382 -34.925508) (xy 189.72403 -34.94024) (xy 189.71895 -34.947352)
			(xy 189.700799 -34.970652) (xy 189.65852 -35.01189) (xy 189.610388 -35.046116) (xy 189.557554 -35.072512)
			(xy 189.501283 -35.090446) (xy 189.442919 -35.099489) (xy 189.413388 -35.100006) (xy 189.402466 -35.100006)
			(xy 189.402212 -35.099752) (xy 189.375499 -35.098512) (xy 189.322792 -35.089484) (xy 189.271861 -35.073185)
			(xy 189.223704 -35.049936) (xy 189.179264 -35.020192) (xy 189.139412 -34.984535) (xy 189.104928 -34.943664)
			(xy 189.076488 -34.898379) (xy 189.054648 -34.849566) (xy 189.039837 -34.798183) (xy 189.032344 -34.745235)
			(xy 189.03188 -34.718498) (xy 189.032366 -34.691247) (xy 189.040123 -34.637298) (xy 189.055478 -34.585003)
			(xy 189.078119 -34.535425) (xy 189.107585 -34.489574) (xy 189.143276 -34.448383) (xy 189.184466 -34.412691)
			(xy 189.230317 -34.383224) (xy 189.279894 -34.360581) (xy 189.332189 -34.345225) (xy 189.386137 -34.337467)
			(xy 189.413388 -34.33699) (xy 189.428181 -34.337132) (xy 189.457679 -34.339416) (xy 189.472316 -34.341562)
			(xy 189.483492 -34.34334) (xy 189.493906 -34.340292) (xy 189.498954 -34.338677) (xy 189.508302 -34.333686)
			(xy 189.512448 -34.330386) (xy 189.537086 -34.309558) (xy 189.571884 -34.27984) (xy 189.573154 -34.27857)
			(xy 189.580488 -34.271233) (xy 189.589024 -34.252347) (xy 189.589664 -34.241994) (xy 189.589664 -33.911286)
			(xy 189.589241 -33.901269) (xy 189.581568 -33.882763) (xy 189.567395 -33.868604) (xy 189.548881 -33.860949)
			(xy 189.538864 -33.860486) (xy 175.819308 -33.860486) (xy 175.809298 -33.860972) (xy 175.790801 -33.86863)
			(xy 175.776642 -33.882783) (xy 175.768977 -33.901276) (xy 175.768508 -33.911286) (xy 175.768508 -34.52241)
			(xy 175.768 -34.54146) (xy 175.768508 -34.552128) (xy 175.770251 -34.560712) (xy 175.778688 -34.576047)
			(xy 175.785018 -34.5821) (xy 175.785526 -34.582354) (xy 175.809656 -34.603182) (xy 175.817022 -34.608516)
			(xy 175.825066 -34.612836) (xy 175.843023 -34.616078) (xy 175.852074 -34.614866) (xy 175.868885 -34.612024)
			(xy 175.902844 -34.608974) (xy 175.919892 -34.60877) (xy 175.922178 -34.60877) (xy 175.949333 -34.609397)
			(xy 176.003057 -34.617393) (xy 176.055104 -34.632927) (xy 176.104422 -34.655685) (xy 176.150014 -34.685208)
			(xy 176.190958 -34.720898) (xy 176.226427 -34.762034) (xy 176.255703 -34.807784) (xy 176.278196 -34.857224)
			(xy 176.293449 -34.909354) (xy 176.301155 -34.96312) (xy 176.301649 -34.990024) (xy 177.366928 -34.990024)
			(xy 177.370999 -34.934402) (xy 177.383125 -34.879965) (xy 177.403048 -34.827874) (xy 177.430344 -34.779239)
			(xy 177.46443 -34.735096) (xy 177.504579 -34.696387) (xy 177.549937 -34.663936) (xy 177.599537 -34.638435)
			(xy 177.652321 -34.620428) (xy 177.707164 -34.610298) (xy 177.762898 -34.608261) (xy 177.818335 -34.614361)
			(xy 177.872292 -34.628467) (xy 177.923621 -34.650279) (xy 177.971227 -34.679333) (xy 178.014095 -34.715008)
			(xy 178.051312 -34.756545) (xy 178.082085 -34.803058) (xy 178.105757 -34.853555) (xy 178.121825 -34.906962)
			(xy 178.129945 -34.962138) (xy 178.130454 -34.990024) (xy 179.772816 -34.990024) (xy 179.776887 -34.934402)
			(xy 179.789013 -34.879965) (xy 179.808936 -34.827874) (xy 179.836232 -34.779239) (xy 179.870318 -34.735096)
			(xy 179.910467 -34.696387) (xy 179.955825 -34.663936) (xy 180.005425 -34.638435) (xy 180.058209 -34.620428)
			(xy 180.113052 -34.610298) (xy 180.168786 -34.608261) (xy 180.224223 -34.614361) (xy 180.27818 -34.628467)
			(xy 180.329509 -34.650279) (xy 180.377115 -34.679333) (xy 180.419983 -34.715008) (xy 180.4572 -34.756545)
			(xy 180.487973 -34.803058) (xy 180.511645 -34.853555) (xy 180.527713 -34.906962) (xy 180.535833 -34.962138)
			(xy 180.536342 -34.990024) (xy 181.100982 -34.990024) (xy 181.105053 -34.934402) (xy 181.117179 -34.879965)
			(xy 181.137102 -34.827874) (xy 181.164398 -34.779239) (xy 181.198484 -34.735096) (xy 181.238633 -34.696387)
			(xy 181.283991 -34.663936) (xy 181.333591 -34.638435) (xy 181.386375 -34.620428) (xy 181.441218 -34.610298)
			(xy 181.496952 -34.608261) (xy 181.552389 -34.614361) (xy 181.606346 -34.628467) (xy 181.657675 -34.650279)
			(xy 181.705281 -34.679333) (xy 181.748149 -34.715008) (xy 181.785366 -34.756545) (xy 181.816139 -34.803058)
			(xy 181.839811 -34.853555) (xy 181.855879 -34.906962) (xy 181.863999 -34.962138) (xy 181.864508 -34.990024)
			(xy 183.998868 -34.990024) (xy 184.002939 -34.934402) (xy 184.015065 -34.879965) (xy 184.034988 -34.827874)
			(xy 184.062284 -34.779239) (xy 184.09637 -34.735096) (xy 184.136519 -34.696387) (xy 184.181877 -34.663936)
			(xy 184.231477 -34.638435) (xy 184.284261 -34.620428) (xy 184.339104 -34.610298) (xy 184.394838 -34.608261)
			(xy 184.450275 -34.614361) (xy 184.504232 -34.628467) (xy 184.555561 -34.650279) (xy 184.603167 -34.679333)
			(xy 184.646035 -34.715008) (xy 184.683252 -34.756545) (xy 184.714025 -34.803058) (xy 184.737697 -34.853555)
			(xy 184.753765 -34.906962) (xy 184.761885 -34.962138) (xy 184.762394 -34.990024) (xy 184.761885 -35.01791)
			(xy 184.753765 -35.073086) (xy 184.737697 -35.126493) (xy 184.714025 -35.17699) (xy 184.683252 -35.223503)
			(xy 184.646203 -35.264852) (xy 198.002396 -35.264852) (xy 198.006467 -35.20923) (xy 198.018593 -35.154793)
			(xy 198.038516 -35.102702) (xy 198.065812 -35.054067) (xy 198.099898 -35.009924) (xy 198.140047 -34.971215)
			(xy 198.185405 -34.938764) (xy 198.235005 -34.913263) (xy 198.287789 -34.895256) (xy 198.342632 -34.885126)
			(xy 198.398366 -34.883089) (xy 198.453803 -34.889189) (xy 198.50776 -34.903295) (xy 198.559089 -34.925107)
			(xy 198.606695 -34.954161) (xy 198.649563 -34.989836) (xy 198.68678 -35.031373) (xy 198.717553 -35.077886)
			(xy 198.741225 -35.128383) (xy 198.757293 -35.18179) (xy 198.765413 -35.236966) (xy 198.765922 -35.264852)
			(xy 198.765413 -35.292738) (xy 198.757293 -35.347914) (xy 198.741225 -35.401321) (xy 198.717553 -35.451818)
			(xy 198.68678 -35.498331) (xy 198.649563 -35.539868) (xy 198.606695 -35.575543) (xy 198.559089 -35.604597)
			(xy 198.50776 -35.626409) (xy 198.453803 -35.640515) (xy 198.398366 -35.646615) (xy 198.342632 -35.644578)
			(xy 198.287789 -35.634448) (xy 198.235005 -35.616441) (xy 198.185405 -35.59094) (xy 198.140047 -35.558489)
			(xy 198.099898 -35.51978) (xy 198.065812 -35.475637) (xy 198.038516 -35.427002) (xy 198.018593 -35.374911)
			(xy 198.006467 -35.320474) (xy 198.002396 -35.264852) (xy 184.646203 -35.264852) (xy 184.646035 -35.26504)
			(xy 184.603167 -35.300715) (xy 184.555561 -35.329769) (xy 184.504232 -35.351581) (xy 184.450275 -35.365687)
			(xy 184.394838 -35.371787) (xy 184.339104 -35.36975) (xy 184.284261 -35.35962) (xy 184.231477 -35.341613)
			(xy 184.181877 -35.316112) (xy 184.136519 -35.283661) (xy 184.09637 -35.244952) (xy 184.062284 -35.200809)
			(xy 184.034988 -35.152174) (xy 184.015065 -35.100083) (xy 184.002939 -35.045646) (xy 183.998868 -34.990024)
			(xy 181.864508 -34.990024) (xy 181.863999 -35.01791) (xy 181.855879 -35.073086) (xy 181.839811 -35.126493)
			(xy 181.816139 -35.17699) (xy 181.785366 -35.223503) (xy 181.748149 -35.26504) (xy 181.705281 -35.300715)
			(xy 181.657675 -35.329769) (xy 181.606346 -35.351581) (xy 181.552389 -35.365687) (xy 181.496952 -35.371787)
			(xy 181.441218 -35.36975) (xy 181.386375 -35.35962) (xy 181.333591 -35.341613) (xy 181.283991 -35.316112)
			(xy 181.238633 -35.283661) (xy 181.198484 -35.244952) (xy 181.164398 -35.200809) (xy 181.137102 -35.152174)
			(xy 181.117179 -35.100083) (xy 181.105053 -35.045646) (xy 181.100982 -34.990024) (xy 180.536342 -34.990024)
			(xy 180.535833 -35.01791) (xy 180.527713 -35.073086) (xy 180.511645 -35.126493) (xy 180.487973 -35.17699)
			(xy 180.4572 -35.223503) (xy 180.419983 -35.26504) (xy 180.377115 -35.300715) (xy 180.329509 -35.329769)
			(xy 180.27818 -35.351581) (xy 180.224223 -35.365687) (xy 180.168786 -35.371787) (xy 180.113052 -35.36975)
			(xy 180.058209 -35.35962) (xy 180.005425 -35.341613) (xy 179.955825 -35.316112) (xy 179.910467 -35.283661)
			(xy 179.870318 -35.244952) (xy 179.836232 -35.200809) (xy 179.808936 -35.152174) (xy 179.789013 -35.100083)
			(xy 179.776887 -35.045646) (xy 179.772816 -34.990024) (xy 178.130454 -34.990024) (xy 178.129945 -35.01791)
			(xy 178.121825 -35.073086) (xy 178.105757 -35.126493) (xy 178.082085 -35.17699) (xy 178.051312 -35.223503)
			(xy 178.014095 -35.26504) (xy 177.971227 -35.300715) (xy 177.923621 -35.329769) (xy 177.872292 -35.351581)
			(xy 177.818335 -35.365687) (xy 177.762898 -35.371787) (xy 177.707164 -35.36975) (xy 177.652321 -35.35962)
			(xy 177.599537 -35.341613) (xy 177.549937 -35.316112) (xy 177.504579 -35.283661) (xy 177.46443 -35.244952)
			(xy 177.430344 -35.200809) (xy 177.403048 -35.152174) (xy 177.383125 -35.100083) (xy 177.370999 -35.045646)
			(xy 177.366928 -34.990024) (xy 176.301649 -34.990024) (xy 176.301654 -34.990278) (xy 176.30117 -35.017531)
			(xy 176.293416 -35.071484) (xy 176.278063 -35.123784) (xy 176.255424 -35.173367) (xy 176.225959 -35.219223)
			(xy 176.190268 -35.26042) (xy 176.149078 -35.296118) (xy 176.103227 -35.325591) (xy 176.053648 -35.348239)
			(xy 176.001351 -35.363602) (xy 175.947399 -35.371365) (xy 175.920146 -35.371786) (xy 175.893184 -35.371323)
			(xy 175.839796 -35.363732) (xy 175.78801 -35.348694) (xy 175.73886 -35.32651) (xy 175.693326 -35.297622)
			(xy 175.652316 -35.262607) (xy 175.616648 -35.222163) (xy 175.587035 -35.177097) (xy 175.564067 -35.128308)
			(xy 175.548202 -35.07677) (xy 175.543464 -35.050222) (xy 175.542194 -35.042856) (xy 175.541686 -35.0393)
			(xy 175.535844 -35.03041) (xy 175.532954 -35.026191) (xy 175.525786 -35.018899) (xy 175.52162 -35.015932)
			(xy 175.458882 -34.974276) (xy 175.454386 -34.971443) (xy 175.444528 -34.967479) (xy 175.439324 -34.966402)
			(xy 175.429418 -34.964624) (xy 175.419004 -34.967164) (xy 175.39231 -34.973305) (xy 175.337934 -34.979921)
			(xy 175.310546 -34.980372) (xy 175.283158 -34.979928) (xy 175.228781 -34.97331) (xy 175.202088 -34.967164)
			(xy 175.191674 -34.964624) (xy 175.181768 -34.966402) (xy 175.176551 -34.967434) (xy 175.166692 -34.971414)
			(xy 175.16221 -34.974276) (xy 175.099472 -35.015932) (xy 175.095304 -35.018896) (xy 175.088136 -35.026189)
			(xy 175.085248 -35.03041) (xy 175.079406 -35.0393) (xy 175.078898 -35.042856) (xy 175.077628 -35.050222)
			(xy 175.072928 -35.076773) (xy 175.057035 -35.128298) (xy 175.034046 -35.177072) (xy 175.00442 -35.222125)
			(xy 174.968747 -35.262558) (xy 174.927737 -35.297566) (xy 174.882207 -35.326453) (xy 174.833064 -35.348642)
			(xy 174.781286 -35.363692) (xy 174.727906 -35.371303) (xy 174.700946 -35.371786) (xy 174.673693 -35.371326)
			(xy 174.61974 -35.363575) (xy 174.567439 -35.348223) (xy 174.517856 -35.325585) (xy 174.472 -35.29612)
			(xy 174.430804 -35.260428) (xy 174.395108 -35.219237) (xy 174.365637 -35.173384) (xy 174.342993 -35.123804)
			(xy 174.327635 -35.071505) (xy 174.319877 -35.017553) (xy 174.319877 -34.963047) (xy 174.327635 -34.909095)
			(xy 174.342993 -34.856796) (xy 174.365637 -34.807216) (xy 174.395108 -34.761363) (xy 174.430804 -34.720172)
			(xy 174.472 -34.68448) (xy 174.517856 -34.655015) (xy 174.567439 -34.632377) (xy 174.61974 -34.617025)
			(xy 174.673693 -34.609274) (xy 174.700946 -34.60877) (xy 174.7012 -34.60877) (xy 174.718249 -34.608952)
			(xy 174.75221 -34.612006) (xy 174.769018 -34.614866) (xy 174.772929 -34.615462) (xy 174.780838 -34.615588)
			(xy 174.784766 -34.61512) (xy 174.789338 -34.614358) (xy 174.795317 -34.612813) (xy 174.806357 -34.60729)
			(xy 174.811182 -34.603436) (xy 174.835566 -34.582354) (xy 174.836074 -34.5821) (xy 174.842374 -34.576024)
			(xy 174.850801 -34.560698) (xy 174.852584 -34.552128) (xy 174.853092 -34.54146) (xy 174.852584 -34.52241)
			(xy 174.852584 -33.911286) (xy 174.852162 -33.901268) (xy 174.844489 -33.882758) (xy 174.830317 -33.868594)
			(xy 174.811803 -33.860932) (xy 174.801784 -33.860486) (xy 172.400976 -33.860486) (xy 172.391722 -33.860848)
			(xy 172.374407 -33.867374) (xy 172.367194 -33.873186) (xy 172.360336 -33.879282) (xy 172.351954 -33.895284)
			(xy 172.350684 -33.904936) (xy 172.346795 -33.932268) (xy 172.332159 -33.985499) (xy 172.310001 -34.036064)
			(xy 172.280784 -34.082906) (xy 172.245119 -34.125046) (xy 172.203751 -34.161604) (xy 172.157545 -34.191815)
			(xy 172.107465 -34.215049) (xy 172.054559 -34.230819) (xy 171.999932 -34.238797) (xy 171.944726 -34.238816)
			(xy 171.890093 -34.230875) (xy 171.837176 -34.21514) (xy 171.787081 -34.19194) (xy 171.740854 -34.16176)
			(xy 171.699462 -34.12523) (xy 171.663768 -34.083115) (xy 171.63452 -34.036293) (xy 171.612328 -33.985743)
			(xy 171.597656 -33.932522) (xy 171.593764 -33.90519) (xy 171.593764 -33.904428) (xy 171.592208 -33.895407)
			(xy 171.583618 -33.879256) (xy 171.577 -33.872932) (xy 171.570142 -33.86709) (xy 171.55287 -33.860486)
			(xy 170.915076 -33.860486) (xy 170.902522 -33.861132) (xy 170.880392 -33.87299) (xy 170.872912 -33.883092)
			(xy 170.855132 -33.912048) (xy 170.82643 -33.959292) (xy 170.823245 -33.964899) (xy 170.819523 -33.977243)
			(xy 170.819064 -33.983676) (xy 170.818556 -33.996376) (xy 170.824906 -34.008568) (xy 170.838194 -34.035716)
			(xy 170.856983 -34.09316) (xy 170.866499 -34.152846) (xy 170.86707 -34.183066) (xy 170.86707 -34.188654)
			(xy 170.866209 -34.215645) (xy 170.857816 -34.268991) (xy 170.841985 -34.320621) (xy 170.819032 -34.369502)
			(xy 170.789415 -34.414657) (xy 170.753726 -34.455186) (xy 170.712679 -34.490276) (xy 170.667094 -34.519228)
			(xy 170.617882 -34.541463) (xy 170.566026 -34.556535) (xy 170.512563 -34.564145) (xy 170.485562 -34.564574)
			(xy 170.458954 -34.564117) (xy 170.406252 -34.55673) (xy 170.355089 -34.542092) (xy 170.306455 -34.520487)
			(xy 170.261296 -34.492333) (xy 170.220487 -34.458177) (xy 170.18482 -34.418682) (xy 170.154987 -34.374614)
			(xy 170.131568 -34.326828) (xy 170.12285 -34.301684) (xy 170.119802 -34.292286) (xy 170.114214 -34.285428)
			(xy 170.111377 -34.282073) (xy 170.104733 -34.276324) (xy 170.101006 -34.273998) (xy 170.04284 -34.2392)
			(xy 170.038982 -34.236985) (xy 170.030678 -34.233792) (xy 170.02633 -34.23285) (xy 170.017948 -34.231326)
			(xy 170.008296 -34.233104) (xy 169.991423 -34.235954) (xy 169.957336 -34.239003) (xy 169.940224 -34.2392)
			(xy 169.938192 -34.2392) (xy 169.910705 -34.238574) (xy 169.856337 -34.230392) (xy 169.803708 -34.214485)
			(xy 169.75391 -34.191185) (xy 169.707974 -34.160974) (xy 169.666853 -34.124479) (xy 169.6314 -34.082456)
			(xy 169.60235 -34.035777) (xy 169.580305 -33.98541) (xy 169.565723 -33.932399) (xy 169.561764 -33.90519)
			(xy 169.561764 -33.904428) (xy 169.560208 -33.895407) (xy 169.551618 -33.879256) (xy 169.545 -33.872932)
			(xy 169.538142 -33.86709) (xy 169.52087 -33.860486) (xy 164.555932 -33.860486) (xy 164.545905 -33.8609)
			(xy 164.527375 -33.868564) (xy 164.51319 -33.882737) (xy 164.505509 -33.90126) (xy 164.505132 -33.911286)
			(xy 164.505132 -34.241232) (xy 164.505132 -34.241994) (xy 164.505824 -34.252337) (xy 164.514335 -34.271219)
			(xy 164.521642 -34.27857) (xy 164.522912 -34.27984) (xy 164.55771 -34.309558) (xy 164.582348 -34.330386)
			(xy 164.586482 -34.333706) (xy 164.595833 -34.338698) (xy 164.60089 -34.340292) (xy 164.611304 -34.34334)
			(xy 164.62248 -34.341562) (xy 164.637306 -34.33939) (xy 164.667186 -34.337102) (xy 164.68217 -34.33699)
			(xy 164.682424 -34.33699) (xy 164.709628 -34.337545) (xy 164.763464 -34.34542) (xy 164.815637 -34.360864)
			(xy 164.865085 -34.383563) (xy 164.910807 -34.413057) (xy 164.951876 -34.448748) (xy 164.987456 -34.489912)
			(xy 165.016828 -34.535713) (xy 165.039395 -34.585222) (xy 165.054698 -34.637435) (xy 165.062429 -34.691293)
			(xy 165.062916 -34.718498) (xy 165.06243 -34.74575) (xy 165.054674 -34.799698) (xy 165.039319 -34.851993)
			(xy 165.016678 -34.901571) (xy 164.987212 -34.947423) (xy 164.951521 -34.988614) (xy 164.910331 -35.024306)
			(xy 164.86448 -35.053774) (xy 164.814903 -35.076416) (xy 164.762608 -35.091772) (xy 164.70866 -35.09953)
			(xy 164.681408 -35.100006) (xy 164.681154 -35.100006) (xy 164.651648 -35.099452) (xy 164.59334 -35.090363)
			(xy 164.537125 -35.072408) (xy 164.484344 -35.046016) (xy 164.436253 -35.011815) (xy 164.393998 -34.97062)
			(xy 164.375846 -34.947352) (xy 164.370766 -34.94024) (xy 164.348414 -34.925508) (xy 164.344491 -34.922979)
			(xy 164.335925 -34.919272) (xy 164.331396 -34.918142) (xy 164.309806 -34.913316) (xy 164.300795 -34.911723)
			(xy 164.282697 -34.91433) (xy 164.2745 -34.918396) (xy 164.273992 -34.91865) (xy 164.25561 -34.928876)
			(xy 164.217322 -34.946302) (xy 164.197538 -34.953448) (xy 164.173337 -34.96149) (xy 164.123603 -34.97278)
			(xy 164.072923 -34.978479) (xy 164.047424 -34.978848) (xy 164.021924 -34.978488) (xy 163.971241 -34.972797)
			(xy 163.921506 -34.961505) (xy 163.89731 -34.953448) (xy 163.877525 -34.946304) (xy 163.839235 -34.928881)
			(xy 163.820856 -34.91865) (xy 163.820348 -34.918396) (xy 163.812149 -34.914336) (xy 163.794052 -34.911728)
			(xy 163.785042 -34.913316) (xy 163.763452 -34.918142) (xy 163.758931 -34.919296) (xy 163.750371 -34.923004)
			(xy 163.746434 -34.925508) (xy 163.724082 -34.94024) (xy 163.719002 -34.947352) (xy 163.70085 -34.970649)
			(xy 163.658569 -35.011882) (xy 163.610436 -35.046102) (xy 163.557603 -35.072491) (xy 163.501332 -35.090418)
			(xy 163.442969 -35.099454) (xy 163.41344 -35.100006) (xy 163.402518 -35.100006) (xy 163.402264 -35.099752)
			(xy 163.375549 -35.098516) (xy 163.322836 -35.089493) (xy 163.271899 -35.073199) (xy 163.223735 -35.049953)
			(xy 163.179289 -35.02021) (xy 163.139431 -34.984553) (xy 163.104942 -34.94368) (xy 163.076497 -34.898392)
			(xy 163.054654 -34.849577) (xy 163.03984 -34.79819) (xy 163.032346 -34.745238) (xy 163.031932 -34.718498)
			(xy 163.032396 -34.691246) (xy 163.040153 -34.637298) (xy 163.05551 -34.585002) (xy 163.078153 -34.535425)
			(xy 163.107621 -34.489575) (xy 163.143316 -34.448386) (xy 163.184509 -34.412696) (xy 163.230362 -34.383233)
			(xy 163.279942 -34.360595) (xy 163.332239 -34.345244) (xy 163.386188 -34.337493) (xy 163.41344 -34.33699)
			(xy 163.428233 -34.337134) (xy 163.45773 -34.339422) (xy 163.472368 -34.341562) (xy 163.483544 -34.34334)
			(xy 163.493958 -34.340292) (xy 163.499003 -34.338672) (xy 163.508345 -34.333675) (xy 163.5125 -34.330386)
			(xy 163.537138 -34.309558) (xy 163.571936 -34.27984) (xy 163.573206 -34.27857) (xy 163.580546 -34.271235)
			(xy 163.58909 -34.25235) (xy 163.589716 -34.241994) (xy 163.589716 -33.911286) (xy 163.589226 -33.901279)
			(xy 163.581564 -33.882789) (xy 163.567413 -33.868637) (xy 163.548923 -33.860974) (xy 163.538916 -33.860486)
			(xy 149.81936 -33.860486) (xy 149.809357 -33.86098) (xy 149.790876 -33.868647) (xy 149.776732 -33.882798)
			(xy 149.769075 -33.901282) (xy 149.76856 -33.911286) (xy 149.76856 -34.52241) (xy 149.768052 -34.54146)
			(xy 149.76856 -34.552128) (xy 149.770306 -34.56071) (xy 149.778749 -34.576039) (xy 149.78507 -34.5821)
			(xy 149.785578 -34.582354) (xy 149.809708 -34.603182) (xy 149.817074 -34.608516) (xy 149.825117 -34.612844)
			(xy 149.843077 -34.616103) (xy 149.852126 -34.614866) (xy 149.868936 -34.612022) (xy 149.902896 -34.608967)
			(xy 149.919944 -34.60877) (xy 149.92223 -34.60877) (xy 149.949387 -34.609394) (xy 150.003116 -34.617384)
			(xy 150.055169 -34.632914) (xy 150.104493 -34.65567) (xy 150.150091 -34.685191) (xy 150.191041 -34.720881)
			(xy 150.226515 -34.762018) (xy 150.255796 -34.807771) (xy 150.278291 -34.857214) (xy 150.293547 -34.909347)
			(xy 150.301255 -34.963118) (xy 150.301702 -34.990024) (xy 151.36698 -34.990024) (xy 151.371051 -34.934402)
			(xy 151.383177 -34.879965) (xy 151.4031 -34.827874) (xy 151.430396 -34.779239) (xy 151.464482 -34.735096)
			(xy 151.504631 -34.696387) (xy 151.549989 -34.663936) (xy 151.599589 -34.638435) (xy 151.652373 -34.620428)
			(xy 151.707216 -34.610298) (xy 151.76295 -34.608261) (xy 151.818387 -34.614361) (xy 151.872344 -34.628467)
			(xy 151.923673 -34.650279) (xy 151.971279 -34.679333) (xy 152.014147 -34.715008) (xy 152.051364 -34.756545)
			(xy 152.082137 -34.803058) (xy 152.105809 -34.853555) (xy 152.121877 -34.906962) (xy 152.129997 -34.962138)
			(xy 152.130506 -34.990024) (xy 153.772868 -34.990024) (xy 153.776939 -34.934402) (xy 153.789065 -34.879965)
			(xy 153.808988 -34.827874) (xy 153.836284 -34.779239) (xy 153.87037 -34.735096) (xy 153.910519 -34.696387)
			(xy 153.955877 -34.663936) (xy 154.005477 -34.638435) (xy 154.058261 -34.620428) (xy 154.113104 -34.610298)
			(xy 154.168838 -34.608261) (xy 154.224275 -34.614361) (xy 154.278232 -34.628467) (xy 154.329561 -34.650279)
			(xy 154.377167 -34.679333) (xy 154.420035 -34.715008) (xy 154.457252 -34.756545) (xy 154.488025 -34.803058)
			(xy 154.511697 -34.853555) (xy 154.527765 -34.906962) (xy 154.535885 -34.962138) (xy 154.536394 -34.990024)
			(xy 155.101034 -34.990024) (xy 155.105105 -34.934402) (xy 155.117231 -34.879965) (xy 155.137154 -34.827874)
			(xy 155.16445 -34.779239) (xy 155.198536 -34.735096) (xy 155.238685 -34.696387) (xy 155.284043 -34.663936)
			(xy 155.333643 -34.638435) (xy 155.386427 -34.620428) (xy 155.44127 -34.610298) (xy 155.497004 -34.608261)
			(xy 155.552441 -34.614361) (xy 155.606398 -34.628467) (xy 155.657727 -34.650279) (xy 155.705333 -34.679333)
			(xy 155.748201 -34.715008) (xy 155.785418 -34.756545) (xy 155.816191 -34.803058) (xy 155.839863 -34.853555)
			(xy 155.855931 -34.906962) (xy 155.864051 -34.962138) (xy 155.86456 -34.990024) (xy 157.99892 -34.990024)
			(xy 158.002991 -34.934402) (xy 158.015117 -34.879965) (xy 158.03504 -34.827874) (xy 158.062336 -34.779239)
			(xy 158.096422 -34.735096) (xy 158.136571 -34.696387) (xy 158.181929 -34.663936) (xy 158.231529 -34.638435)
			(xy 158.284313 -34.620428) (xy 158.339156 -34.610298) (xy 158.39489 -34.608261) (xy 158.450327 -34.614361)
			(xy 158.504284 -34.628467) (xy 158.555613 -34.650279) (xy 158.603219 -34.679333) (xy 158.646087 -34.715008)
			(xy 158.683304 -34.756545) (xy 158.714077 -34.803058) (xy 158.737749 -34.853555) (xy 158.753817 -34.906962)
			(xy 158.761937 -34.962138) (xy 158.762446 -34.990024) (xy 158.761937 -35.01791) (xy 158.753817 -35.073086)
			(xy 158.737749 -35.126493) (xy 158.714077 -35.17699) (xy 158.683304 -35.223503) (xy 158.646255 -35.264852)
			(xy 172.002448 -35.264852) (xy 172.006519 -35.20923) (xy 172.018645 -35.154793) (xy 172.038568 -35.102702)
			(xy 172.065864 -35.054067) (xy 172.09995 -35.009924) (xy 172.140099 -34.971215) (xy 172.185457 -34.938764)
			(xy 172.235057 -34.913263) (xy 172.287841 -34.895256) (xy 172.342684 -34.885126) (xy 172.398418 -34.883089)
			(xy 172.453855 -34.889189) (xy 172.507812 -34.903295) (xy 172.559141 -34.925107) (xy 172.606747 -34.954161)
			(xy 172.649615 -34.989836) (xy 172.686832 -35.031373) (xy 172.717605 -35.077886) (xy 172.741277 -35.128383)
			(xy 172.757345 -35.18179) (xy 172.765465 -35.236966) (xy 172.765974 -35.264852) (xy 172.765465 -35.292738)
			(xy 172.757345 -35.347914) (xy 172.741277 -35.401321) (xy 172.717605 -35.451818) (xy 172.686832 -35.498331)
			(xy 172.649615 -35.539868) (xy 172.606747 -35.575543) (xy 172.559141 -35.604597) (xy 172.507812 -35.626409)
			(xy 172.453855 -35.640515) (xy 172.398418 -35.646615) (xy 172.342684 -35.644578) (xy 172.287841 -35.634448)
			(xy 172.235057 -35.616441) (xy 172.185457 -35.59094) (xy 172.140099 -35.558489) (xy 172.09995 -35.51978)
			(xy 172.065864 -35.475637) (xy 172.038568 -35.427002) (xy 172.018645 -35.374911) (xy 172.006519 -35.320474)
			(xy 172.002448 -35.264852) (xy 158.646255 -35.264852) (xy 158.646087 -35.26504) (xy 158.603219 -35.300715)
			(xy 158.555613 -35.329769) (xy 158.504284 -35.351581) (xy 158.450327 -35.365687) (xy 158.39489 -35.371787)
			(xy 158.339156 -35.36975) (xy 158.284313 -35.35962) (xy 158.231529 -35.341613) (xy 158.181929 -35.316112)
			(xy 158.136571 -35.283661) (xy 158.096422 -35.244952) (xy 158.062336 -35.200809) (xy 158.03504 -35.152174)
			(xy 158.015117 -35.100083) (xy 158.002991 -35.045646) (xy 157.99892 -34.990024) (xy 155.86456 -34.990024)
			(xy 155.864051 -35.01791) (xy 155.855931 -35.073086) (xy 155.839863 -35.126493) (xy 155.816191 -35.17699)
			(xy 155.785418 -35.223503) (xy 155.748201 -35.26504) (xy 155.705333 -35.300715) (xy 155.657727 -35.329769)
			(xy 155.606398 -35.351581) (xy 155.552441 -35.365687) (xy 155.497004 -35.371787) (xy 155.44127 -35.36975)
			(xy 155.386427 -35.35962) (xy 155.333643 -35.341613) (xy 155.284043 -35.316112) (xy 155.238685 -35.283661)
			(xy 155.198536 -35.244952) (xy 155.16445 -35.200809) (xy 155.137154 -35.152174) (xy 155.117231 -35.100083)
			(xy 155.105105 -35.045646) (xy 155.101034 -34.990024) (xy 154.536394 -34.990024) (xy 154.535885 -35.01791)
			(xy 154.527765 -35.073086) (xy 154.511697 -35.126493) (xy 154.488025 -35.17699) (xy 154.457252 -35.223503)
			(xy 154.420035 -35.26504) (xy 154.377167 -35.300715) (xy 154.329561 -35.329769) (xy 154.278232 -35.351581)
			(xy 154.224275 -35.365687) (xy 154.168838 -35.371787) (xy 154.113104 -35.36975) (xy 154.058261 -35.35962)
			(xy 154.005477 -35.341613) (xy 153.955877 -35.316112) (xy 153.910519 -35.283661) (xy 153.87037 -35.244952)
			(xy 153.836284 -35.200809) (xy 153.808988 -35.152174) (xy 153.789065 -35.100083) (xy 153.776939 -35.045646)
			(xy 153.772868 -34.990024) (xy 152.130506 -34.990024) (xy 152.129997 -35.01791) (xy 152.121877 -35.073086)
			(xy 152.105809 -35.126493) (xy 152.082137 -35.17699) (xy 152.051364 -35.223503) (xy 152.014147 -35.26504)
			(xy 151.971279 -35.300715) (xy 151.923673 -35.329769) (xy 151.872344 -35.351581) (xy 151.818387 -35.365687)
			(xy 151.76295 -35.371787) (xy 151.707216 -35.36975) (xy 151.652373 -35.35962) (xy 151.599589 -35.341613)
			(xy 151.549989 -35.316112) (xy 151.504631 -35.283661) (xy 151.464482 -35.244952) (xy 151.430396 -35.200809)
			(xy 151.4031 -35.152174) (xy 151.383177 -35.100083) (xy 151.371051 -35.045646) (xy 151.36698 -34.990024)
			(xy 150.301702 -34.990024) (xy 150.301706 -34.990278) (xy 150.301244 -35.017532) (xy 150.29349 -35.071485)
			(xy 150.278136 -35.123785) (xy 150.255494 -35.173368) (xy 150.226027 -35.219224) (xy 150.190333 -35.260419)
			(xy 150.14914 -35.296115) (xy 150.103286 -35.325585) (xy 150.053704 -35.348229) (xy 150.001405 -35.363585)
			(xy 149.947452 -35.371343) (xy 149.920198 -35.371786) (xy 149.893233 -35.371326) (xy 149.83984 -35.363741)
			(xy 149.788049 -35.348708) (xy 149.738892 -35.326527) (xy 149.693352 -35.297641) (xy 149.652336 -35.262626)
			(xy 149.616663 -35.222182) (xy 149.587044 -35.177114) (xy 149.564072 -35.128322) (xy 149.548204 -35.07678)
			(xy 149.543516 -35.050222) (xy 149.542246 -35.042856) (xy 149.541738 -35.0393) (xy 149.535896 -35.03041)
			(xy 149.533004 -35.026193) (xy 149.525832 -35.018906) (xy 149.521672 -35.015932) (xy 149.458934 -34.974276)
			(xy 149.45444 -34.971438) (xy 149.444584 -34.967465) (xy 149.439376 -34.966402) (xy 149.42947 -34.964624)
			(xy 149.419056 -34.967164) (xy 149.392362 -34.973308) (xy 149.337986 -34.97993) (xy 149.310598 -34.980372)
			(xy 149.28321 -34.979925) (xy 149.228835 -34.973301) (xy 149.20214 -34.967164) (xy 149.191726 -34.964624)
			(xy 149.18182 -34.966402) (xy 149.176601 -34.967429) (xy 149.166736 -34.9714) (xy 149.162262 -34.974276)
			(xy 149.099524 -35.015932) (xy 149.095353 -35.018893) (xy 149.088179 -35.026182) (xy 149.0853 -35.03041)
			(xy 149.079458 -35.0393) (xy 149.07895 -35.042856) (xy 149.07768 -35.050222) (xy 149.07298 -35.076775)
			(xy 149.057088 -35.128303) (xy 149.0341 -35.177081) (xy 149.004475 -35.222137) (xy 148.968803 -35.262575)
			(xy 148.927793 -35.297588) (xy 148.882264 -35.32648) (xy 148.83312 -35.348676) (xy 148.781342 -35.363732)
			(xy 148.727959 -35.371351) (xy 148.700998 -35.371786) (xy 148.673748 -35.3713) (xy 148.619804 -35.363543)
			(xy 148.567513 -35.348189) (xy 148.517939 -35.325549) (xy 148.472091 -35.296084) (xy 148.430904 -35.260395)
			(xy 148.395214 -35.219207) (xy 148.36575 -35.17336) (xy 148.34311 -35.123785) (xy 148.327756 -35.071494)
			(xy 148.32 -35.01755) (xy 148.32 -34.96305) (xy 148.327756 -34.909106) (xy 148.34311 -34.856815)
			(xy 148.36575 -34.80724) (xy 148.395214 -34.761393) (xy 148.430904 -34.720205) (xy 148.472091 -34.684516)
			(xy 148.517939 -34.655051) (xy 148.567513 -34.632411) (xy 148.619804 -34.617057) (xy 148.673748 -34.6093)
			(xy 148.700998 -34.60877) (xy 148.701252 -34.60877) (xy 148.718301 -34.60895) (xy 148.752263 -34.612)
			(xy 148.76907 -34.614866) (xy 148.772981 -34.615466) (xy 148.780891 -34.615599) (xy 148.784818 -34.61512)
			(xy 148.78939 -34.614358) (xy 148.795371 -34.612818) (xy 148.806418 -34.607303) (xy 148.811234 -34.603436)
			(xy 148.835618 -34.582354) (xy 148.836126 -34.5821) (xy 148.842431 -34.576027) (xy 148.850866 -34.560701)
			(xy 148.852636 -34.552128) (xy 148.853144 -34.54146) (xy 148.852636 -34.52241) (xy 148.852636 -33.911286)
			(xy 148.852146 -33.901278) (xy 148.844485 -33.882784) (xy 148.830334 -33.868627) (xy 148.811844 -33.860958)
			(xy 148.801836 -33.860486) (xy 146.401028 -33.860486) (xy 146.39177 -33.860839) (xy 146.374443 -33.867352)
			(xy 146.367246 -33.873186) (xy 146.360388 -33.879282) (xy 146.352006 -33.895284) (xy 146.350736 -33.904936)
			(xy 146.346847 -33.932265) (xy 146.332212 -33.985489) (xy 146.310056 -34.036047) (xy 146.280842 -34.082883)
			(xy 146.245181 -34.125017) (xy 146.203818 -34.161569) (xy 146.157616 -34.191776) (xy 146.107543 -34.215006)
			(xy 146.054643 -34.230774) (xy 146.000023 -34.23875) (xy 145.944823 -34.238768) (xy 145.890198 -34.230827)
			(xy 145.837288 -34.215093) (xy 145.787199 -34.191896) (xy 145.740978 -34.161719) (xy 145.699591 -34.125193)
			(xy 145.663903 -34.083082) (xy 145.634659 -34.036265) (xy 145.612471 -33.985721) (xy 145.597801 -33.932507)
			(xy 145.593816 -33.90519) (xy 145.593816 -33.904428) (xy 145.592258 -33.895408) (xy 145.583663 -33.879263)
			(xy 145.577052 -33.872932) (xy 145.570194 -33.86709) (xy 145.552922 -33.860486) (xy 144.915128 -33.860486)
			(xy 144.902567 -33.861121) (xy 144.880418 -33.872966) (xy 144.872964 -33.883092) (xy 144.855184 -33.912048)
			(xy 144.826482 -33.959292) (xy 144.823299 -33.9649) (xy 144.819581 -33.977244) (xy 144.819116 -33.983676)
			(xy 144.818608 -33.996376) (xy 144.824958 -34.008568) (xy 144.838247 -34.035715) (xy 144.857039 -34.09316)
			(xy 144.866556 -34.152846) (xy 144.867122 -34.183066) (xy 144.867122 -34.188654) (xy 144.866194 -34.216931)
			(xy 144.857022 -34.272757) (xy 144.839706 -34.326617) (xy 144.814627 -34.37733) (xy 144.782335 -34.423783)
			(xy 144.743537 -34.464959) (xy 144.699085 -34.499955) (xy 144.649952 -34.528002) (xy 144.597216 -34.548488)
			(xy 144.542034 -34.560961) (xy 144.485614 -34.56515) (xy 144.429194 -34.560961) (xy 144.374012 -34.548488)
			(xy 144.321276 -34.528002) (xy 144.272143 -34.499955) (xy 144.227691 -34.464959) (xy 144.188893 -34.423783)
			(xy 144.156601 -34.37733) (xy 144.131522 -34.326617) (xy 144.114206 -34.272757) (xy 144.105034 -34.216931)
			(xy 144.104106 -34.188654) (xy 144.104106 -34.183066) (xy 144.104657 -34.152844) (xy 144.114151 -34.09315)
			(xy 144.132958 -34.035706) (xy 144.14627 -34.008568) (xy 144.14627 -34.008314) (xy 144.149147 -34.002374)
			(xy 144.152095 -33.989514) (xy 144.152112 -33.982914) (xy 144.151604 -33.970468) (xy 144.116044 -33.912048)
			(xy 144.098264 -33.883092) (xy 144.090748 -33.873031) (xy 144.068639 -33.861181) (xy 144.0561 -33.860486)
			(xy 138.555984 -33.860486) (xy 138.545977 -33.860976) (xy 138.527489 -33.868638) (xy 138.513337 -33.88279)
			(xy 138.505676 -33.901279) (xy 138.505184 -33.911286) (xy 138.505184 -34.241232) (xy 138.505184 -34.241994)
			(xy 138.505878 -34.252336) (xy 138.514395 -34.271211) (xy 138.521694 -34.27857) (xy 138.522964 -34.27984)
			(xy 138.557762 -34.309558) (xy 138.5824 -34.330386) (xy 138.586532 -34.33371) (xy 138.595881 -34.33871)
			(xy 138.600942 -34.340292) (xy 138.611356 -34.34334) (xy 138.622532 -34.341562) (xy 138.637358 -34.339388)
			(xy 138.667238 -34.337096) (xy 138.682222 -34.33699) (xy 138.682476 -34.33699) (xy 138.709682 -34.337542)
			(xy 138.763524 -34.345411) (xy 138.815702 -34.360851) (xy 138.865156 -34.383547) (xy 138.910885 -34.41304)
			(xy 138.951958 -34.448731) (xy 138.987544 -34.489896) (xy 139.016921 -34.535699) (xy 139.039491 -34.585212)
			(xy 139.054797 -34.637429) (xy 139.062528 -34.691291) (xy 139.062968 -34.718498) (xy 139.062505 -34.74575)
			(xy 139.054748 -34.799699) (xy 139.039392 -34.851995) (xy 139.016749 -34.901573) (xy 138.98728 -34.947423)
			(xy 138.951586 -34.988613) (xy 138.910393 -35.024303) (xy 138.864539 -35.053767) (xy 138.814959 -35.076405)
			(xy 138.762662 -35.091756) (xy 138.708712 -35.099507) (xy 138.68146 -35.100006) (xy 138.681206 -35.100006)
			(xy 138.651702 -35.099448) (xy 138.593398 -35.090353) (xy 138.537188 -35.072393) (xy 138.484412 -35.045997)
			(xy 138.436327 -35.011794) (xy 138.394078 -34.970597) (xy 138.375898 -34.947352) (xy 138.370818 -34.94024)
			(xy 138.348466 -34.925508) (xy 138.344541 -34.922982) (xy 138.335974 -34.919284) (xy 138.331448 -34.918142)
			(xy 138.309858 -34.913316) (xy 138.300846 -34.911714) (xy 138.282739 -34.914304) (xy 138.274552 -34.918396)
			(xy 138.274044 -34.91865) (xy 138.255663 -34.928878) (xy 138.217376 -34.946308) (xy 138.19759 -34.953448)
			(xy 138.17339 -34.961493) (xy 138.123656 -34.972789) (xy 138.072976 -34.978493) (xy 138.047476 -34.978848)
			(xy 138.021976 -34.978485) (xy 137.971295 -34.972789) (xy 137.921562 -34.961493) (xy 137.897362 -34.953448)
			(xy 137.877578 -34.946302) (xy 137.83929 -34.928875) (xy 137.820908 -34.91865) (xy 137.8204 -34.918396)
			(xy 137.8122 -34.914344) (xy 137.794107 -34.911753) (xy 137.785094 -34.913316) (xy 137.763504 -34.918142)
			(xy 137.758982 -34.919292) (xy 137.750416 -34.922992) (xy 137.746486 -34.925508) (xy 137.724134 -34.94024)
			(xy 137.719054 -34.947352) (xy 137.700903 -34.970652) (xy 137.658624 -35.011891) (xy 137.610492 -35.046117)
			(xy 137.557659 -35.072514) (xy 137.501387 -35.090448) (xy 137.443023 -35.099492) (xy 137.413492 -35.100006)
			(xy 137.40257 -35.100006) (xy 137.402316 -35.099752) (xy 137.375603 -35.098512) (xy 137.322895 -35.089484)
			(xy 137.271964 -35.073186) (xy 137.223806 -35.049938) (xy 137.179366 -35.020194) (xy 137.139514 -34.984537)
			(xy 137.105029 -34.943665) (xy 137.076589 -34.89838) (xy 137.054749 -34.849567) (xy 137.039937 -34.798184)
			(xy 137.032444 -34.745236) (xy 137.031984 -34.718498) (xy 137.03247 -34.691247) (xy 137.040227 -34.637299)
			(xy 137.055582 -34.585004) (xy 137.078223 -34.535426) (xy 137.107689 -34.489576) (xy 137.143381 -34.448385)
			(xy 137.184571 -34.412693) (xy 137.230421 -34.383226) (xy 137.279998 -34.360584) (xy 137.332293 -34.345228)
			(xy 137.386241 -34.33747) (xy 137.413492 -34.33699) (xy 137.428285 -34.337132) (xy 137.457783 -34.339417)
			(xy 137.47242 -34.341562) (xy 137.483596 -34.34334) (xy 137.49401 -34.340292) (xy 137.499058 -34.338677)
			(xy 137.508405 -34.333686) (xy 137.512552 -34.330386) (xy 137.53719 -34.309558) (xy 137.571988 -34.27984)
			(xy 137.573258 -34.27857) (xy 137.580592 -34.271232) (xy 137.589126 -34.252347) (xy 137.589768 -34.241994)
			(xy 137.589768 -33.911286) (xy 137.589345 -33.901269) (xy 137.581672 -33.882762) (xy 137.567499 -33.868602)
			(xy 137.548985 -33.860946) (xy 137.538968 -33.860486) (xy 123.819412 -33.860486) (xy 123.809402 -33.860972)
			(xy 123.790903 -33.868628) (xy 123.776743 -33.882781) (xy 123.769077 -33.901276) (xy 123.768612 -33.911286)
			(xy 123.768612 -34.52241) (xy 123.768104 -34.54146) (xy 123.768612 -34.552128) (xy 123.770356 -34.560712)
			(xy 123.778793 -34.576046) (xy 123.785122 -34.5821) (xy 123.78563 -34.582354) (xy 123.80976 -34.603182)
			(xy 123.817126 -34.608516) (xy 123.82517 -34.612835) (xy 123.843127 -34.616076) (xy 123.852178 -34.614866)
			(xy 123.868989 -34.612024) (xy 123.902948 -34.608974) (xy 123.919996 -34.60877) (xy 123.922282 -34.60877)
			(xy 123.949441 -34.60939) (xy 124.003176 -34.617375) (xy 124.055234 -34.632901) (xy 124.104564 -34.655654)
			(xy 124.150168 -34.685174) (xy 124.191124 -34.720864) (xy 124.226603 -34.762002) (xy 124.255888 -34.807757)
			(xy 124.278387 -34.857203) (xy 124.293646 -34.909341) (xy 124.301354 -34.963116) (xy 124.301754 -34.990024)
			(xy 125.367032 -34.990024) (xy 125.371103 -34.934402) (xy 125.383229 -34.879965) (xy 125.403152 -34.827874)
			(xy 125.430448 -34.779239) (xy 125.464534 -34.735096) (xy 125.504683 -34.696387) (xy 125.550041 -34.663936)
			(xy 125.599641 -34.638435) (xy 125.652425 -34.620428) (xy 125.707268 -34.610298) (xy 125.763002 -34.608261)
			(xy 125.818439 -34.614361) (xy 125.872396 -34.628467) (xy 125.923725 -34.650279) (xy 125.971331 -34.679333)
			(xy 126.014199 -34.715008) (xy 126.051416 -34.756545) (xy 126.082189 -34.803058) (xy 126.105861 -34.853555)
			(xy 126.121929 -34.906962) (xy 126.130049 -34.962138) (xy 126.130558 -34.990024) (xy 127.77292 -34.990024)
			(xy 127.776991 -34.934402) (xy 127.789117 -34.879965) (xy 127.80904 -34.827874) (xy 127.836336 -34.779239)
			(xy 127.870422 -34.735096) (xy 127.910571 -34.696387) (xy 127.955929 -34.663936) (xy 128.005529 -34.638435)
			(xy 128.058313 -34.620428) (xy 128.113156 -34.610298) (xy 128.16889 -34.608261) (xy 128.224327 -34.614361)
			(xy 128.278284 -34.628467) (xy 128.329613 -34.650279) (xy 128.377219 -34.679333) (xy 128.420087 -34.715008)
			(xy 128.457304 -34.756545) (xy 128.488077 -34.803058) (xy 128.511749 -34.853555) (xy 128.527817 -34.906962)
			(xy 128.535937 -34.962138) (xy 128.536446 -34.990024) (xy 128.967736 -34.990024) (xy 128.971807 -34.934402)
			(xy 128.983933 -34.879965) (xy 129.003856 -34.827874) (xy 129.031152 -34.779239) (xy 129.065238 -34.735096)
			(xy 129.105387 -34.696387) (xy 129.150745 -34.663936) (xy 129.200345 -34.638435) (xy 129.253129 -34.620428)
			(xy 129.307972 -34.610298) (xy 129.363706 -34.608261) (xy 129.419143 -34.614361) (xy 129.4731 -34.628467)
			(xy 129.524429 -34.650279) (xy 129.572035 -34.679333) (xy 129.614903 -34.715008) (xy 129.65212 -34.756545)
			(xy 129.682893 -34.803058) (xy 129.706565 -34.853555) (xy 129.722633 -34.906962) (xy 129.730753 -34.962138)
			(xy 129.731262 -34.990024) (xy 131.998972 -34.990024) (xy 132.003043 -34.934402) (xy 132.015169 -34.879965)
			(xy 132.035092 -34.827874) (xy 132.062388 -34.779239) (xy 132.096474 -34.735096) (xy 132.136623 -34.696387)
			(xy 132.181981 -34.663936) (xy 132.231581 -34.638435) (xy 132.284365 -34.620428) (xy 132.339208 -34.610298)
			(xy 132.394942 -34.608261) (xy 132.450379 -34.614361) (xy 132.504336 -34.628467) (xy 132.555665 -34.650279)
			(xy 132.603271 -34.679333) (xy 132.646139 -34.715008) (xy 132.683356 -34.756545) (xy 132.714129 -34.803058)
			(xy 132.737801 -34.853555) (xy 132.753869 -34.906962) (xy 132.761989 -34.962138) (xy 132.762498 -34.990024)
			(xy 132.761989 -35.01791) (xy 132.753869 -35.073086) (xy 132.737801 -35.126493) (xy 132.714129 -35.17699)
			(xy 132.683356 -35.223503) (xy 132.646307 -35.264852) (xy 146.0025 -35.264852) (xy 146.006571 -35.20923)
			(xy 146.018697 -35.154793) (xy 146.03862 -35.102702) (xy 146.065916 -35.054067) (xy 146.100002 -35.009924)
			(xy 146.140151 -34.971215) (xy 146.185509 -34.938764) (xy 146.235109 -34.913263) (xy 146.287893 -34.895256)
			(xy 146.342736 -34.885126) (xy 146.39847 -34.883089) (xy 146.453907 -34.889189) (xy 146.507864 -34.903295)
			(xy 146.559193 -34.925107) (xy 146.606799 -34.954161) (xy 146.649667 -34.989836) (xy 146.686884 -35.031373)
			(xy 146.717657 -35.077886) (xy 146.741329 -35.128383) (xy 146.757397 -35.18179) (xy 146.765517 -35.236966)
			(xy 146.766026 -35.264852) (xy 146.765517 -35.292738) (xy 146.757397 -35.347914) (xy 146.741329 -35.401321)
			(xy 146.717657 -35.451818) (xy 146.686884 -35.498331) (xy 146.649667 -35.539868) (xy 146.606799 -35.575543)
			(xy 146.559193 -35.604597) (xy 146.507864 -35.626409) (xy 146.453907 -35.640515) (xy 146.39847 -35.646615)
			(xy 146.342736 -35.644578) (xy 146.287893 -35.634448) (xy 146.235109 -35.616441) (xy 146.185509 -35.59094)
			(xy 146.140151 -35.558489) (xy 146.100002 -35.51978) (xy 146.065916 -35.475637) (xy 146.03862 -35.427002)
			(xy 146.018697 -35.374911) (xy 146.006571 -35.320474) (xy 146.0025 -35.264852) (xy 132.646307 -35.264852)
			(xy 132.646139 -35.26504) (xy 132.603271 -35.300715) (xy 132.555665 -35.329769) (xy 132.504336 -35.351581)
			(xy 132.450379 -35.365687) (xy 132.394942 -35.371787) (xy 132.339208 -35.36975) (xy 132.284365 -35.35962)
			(xy 132.231581 -35.341613) (xy 132.181981 -35.316112) (xy 132.136623 -35.283661) (xy 132.096474 -35.244952)
			(xy 132.062388 -35.200809) (xy 132.035092 -35.152174) (xy 132.015169 -35.100083) (xy 132.003043 -35.045646)
			(xy 131.998972 -34.990024) (xy 129.731262 -34.990024) (xy 129.730753 -35.01791) (xy 129.722633 -35.073086)
			(xy 129.706565 -35.126493) (xy 129.682893 -35.17699) (xy 129.65212 -35.223503) (xy 129.614903 -35.26504)
			(xy 129.572035 -35.300715) (xy 129.524429 -35.329769) (xy 129.4731 -35.351581) (xy 129.419143 -35.365687)
			(xy 129.363706 -35.371787) (xy 129.307972 -35.36975) (xy 129.253129 -35.35962) (xy 129.200345 -35.341613)
			(xy 129.150745 -35.316112) (xy 129.105387 -35.283661) (xy 129.065238 -35.244952) (xy 129.031152 -35.200809)
			(xy 129.003856 -35.152174) (xy 128.983933 -35.100083) (xy 128.971807 -35.045646) (xy 128.967736 -34.990024)
			(xy 128.536446 -34.990024) (xy 128.535937 -35.01791) (xy 128.527817 -35.073086) (xy 128.511749 -35.126493)
			(xy 128.488077 -35.17699) (xy 128.457304 -35.223503) (xy 128.420087 -35.26504) (xy 128.377219 -35.300715)
			(xy 128.329613 -35.329769) (xy 128.278284 -35.351581) (xy 128.224327 -35.365687) (xy 128.16889 -35.371787)
			(xy 128.113156 -35.36975) (xy 128.058313 -35.35962) (xy 128.005529 -35.341613) (xy 127.955929 -35.316112)
			(xy 127.910571 -35.283661) (xy 127.870422 -35.244952) (xy 127.836336 -35.200809) (xy 127.80904 -35.152174)
			(xy 127.789117 -35.100083) (xy 127.776991 -35.045646) (xy 127.77292 -34.990024) (xy 126.130558 -34.990024)
			(xy 126.130049 -35.01791) (xy 126.121929 -35.073086) (xy 126.105861 -35.126493) (xy 126.082189 -35.17699)
			(xy 126.051416 -35.223503) (xy 126.014199 -35.26504) (xy 125.971331 -35.300715) (xy 125.923725 -35.329769)
			(xy 125.872396 -35.351581) (xy 125.818439 -35.365687) (xy 125.763002 -35.371787) (xy 125.707268 -35.36975)
			(xy 125.652425 -35.35962) (xy 125.599641 -35.341613) (xy 125.550041 -35.316112) (xy 125.504683 -35.283661)
			(xy 125.464534 -35.244952) (xy 125.430448 -35.200809) (xy 125.403152 -35.152174) (xy 125.383229 -35.100083)
			(xy 125.371103 -35.045646) (xy 125.367032 -34.990024) (xy 124.301754 -34.990024) (xy 124.301758 -34.990278)
			(xy 124.301296 -35.017531) (xy 124.293541 -35.071481) (xy 124.278187 -35.123779) (xy 124.255545 -35.173359)
			(xy 124.226077 -35.219211) (xy 124.190382 -35.260402) (xy 124.149188 -35.296093) (xy 124.103334 -35.325558)
			(xy 124.053753 -35.348197) (xy 124.001454 -35.363547) (xy 123.947503 -35.371298) (xy 123.92025 -35.371786)
			(xy 123.893287 -35.371323) (xy 123.839899 -35.363732) (xy 123.788113 -35.348695) (xy 123.738962 -35.326511)
			(xy 123.693428 -35.297624) (xy 123.652417 -35.262608) (xy 123.616749 -35.222164) (xy 123.587136 -35.177098)
			(xy 123.564167 -35.128309) (xy 123.548302 -35.076771) (xy 123.543568 -35.050222) (xy 123.542298 -35.042856)
			(xy 123.54179 -35.0393) (xy 123.535948 -35.03041) (xy 123.533058 -35.026191) (xy 123.52589 -35.018898)
			(xy 123.521724 -35.015932) (xy 123.458986 -34.974276) (xy 123.45449 -34.971442) (xy 123.444632 -34.967478)
			(xy 123.439428 -34.966402) (xy 123.429522 -34.964624) (xy 123.419108 -34.967164) (xy 123.392414 -34.973305)
			(xy 123.338038 -34.979922) (xy 123.31065 -34.980372) (xy 123.283262 -34.979928) (xy 123.228885 -34.97331)
			(xy 123.202192 -34.967164) (xy 123.191778 -34.964624) (xy 123.181872 -34.966402) (xy 123.176655 -34.967434)
			(xy 123.166796 -34.971413) (xy 123.162314 -34.974276) (xy 123.099576 -35.015932) (xy 123.095408 -35.018896)
			(xy 123.088239 -35.026188) (xy 123.085352 -35.03041) (xy 123.07951 -35.0393) (xy 123.079002 -35.042856)
			(xy 123.077732 -35.050222) (xy 123.073032 -35.076774) (xy 123.057139 -35.128299) (xy 123.03415 -35.177073)
			(xy 123.004524 -35.222126) (xy 122.968851 -35.262559) (xy 122.927841 -35.297568) (xy 122.882311 -35.326455)
			(xy 122.833168 -35.348644) (xy 122.781391 -35.363695) (xy 122.72801 -35.371307) (xy 122.70105 -35.371786)
			(xy 122.673803 -35.371296) (xy 122.619864 -35.363535) (xy 122.567578 -35.348176) (xy 122.51801 -35.325533)
			(xy 122.472168 -35.296067) (xy 122.430987 -35.260378) (xy 122.395303 -35.219191) (xy 122.365843 -35.173346)
			(xy 122.343207 -35.123775) (xy 122.327855 -35.071488) (xy 122.3201 -35.017547) (xy 122.3201 -34.963053)
			(xy 122.327855 -34.909112) (xy 122.343207 -34.856825) (xy 122.365843 -34.807254) (xy 122.395303 -34.761409)
			(xy 122.430987 -34.720222) (xy 122.472168 -34.684533) (xy 122.51801 -34.655067) (xy 122.567578 -34.632424)
			(xy 122.619864 -34.617065) (xy 122.673803 -34.609304) (xy 122.70105 -34.60877) (xy 122.701304 -34.60877)
			(xy 122.718353 -34.608953) (xy 122.752314 -34.612007) (xy 122.769122 -34.614866) (xy 122.773033 -34.615462)
			(xy 122.780942 -34.615587) (xy 122.78487 -34.61512) (xy 122.789442 -34.614358) (xy 122.79542 -34.612812)
			(xy 122.80646 -34.607289) (xy 122.811286 -34.603436) (xy 122.83567 -34.582354) (xy 122.836178 -34.5821)
			(xy 122.842478 -34.576024) (xy 122.850904 -34.560698) (xy 122.852688 -34.552128) (xy 122.853196 -34.54146)
			(xy 122.852688 -34.52241) (xy 122.852688 -33.911286) (xy 122.852197 -33.901281) (xy 122.844535 -33.882796)
			(xy 122.830382 -33.868651) (xy 122.811893 -33.860998) (xy 122.801888 -33.860486) (xy 120.40108 -33.860486)
			(xy 120.391825 -33.860847) (xy 120.374509 -33.867372) (xy 120.367298 -33.873186) (xy 120.36044 -33.879282)
			(xy 120.352058 -33.895284) (xy 120.350788 -33.904936) (xy 120.346899 -33.932269) (xy 120.332263 -33.9855)
			(xy 120.310104 -34.036066) (xy 120.280888 -34.082908) (xy 120.245222 -34.125048) (xy 120.203854 -34.161606)
			(xy 120.157647 -34.191818) (xy 120.107567 -34.215052) (xy 120.054661 -34.230823) (xy 120.000033 -34.238801)
			(xy 119.944826 -34.23882) (xy 119.890193 -34.230879) (xy 119.837275 -34.215144) (xy 119.78718 -34.191944)
			(xy 119.740952 -34.161764) (xy 119.699559 -34.125234) (xy 119.663865 -34.083117) (xy 119.634617 -34.036295)
			(xy 119.612424 -33.985745) (xy 119.597752 -33.932523) (xy 119.593868 -33.90519) (xy 119.593868 -33.904428)
			(xy 119.592308 -33.89541) (xy 119.583707 -33.879271) (xy 119.577104 -33.872932) (xy 119.570246 -33.86709)
			(xy 119.552974 -33.860486) (xy 118.91518 -33.860486) (xy 118.902625 -33.861132) (xy 118.880494 -33.872988)
			(xy 118.873016 -33.883092) (xy 118.855236 -33.912048) (xy 118.826534 -33.959292) (xy 118.823348 -33.964899)
			(xy 118.819626 -33.977243) (xy 118.819168 -33.983676) (xy 118.81866 -33.996376) (xy 118.82501 -34.008568)
			(xy 118.838298 -34.035716) (xy 118.857087 -34.093161) (xy 118.866603 -34.152846) (xy 118.867174 -34.183066)
			(xy 118.867174 -34.188654) (xy 118.866313 -34.215645) (xy 118.857921 -34.268992) (xy 118.842089 -34.320621)
			(xy 118.819136 -34.369502) (xy 118.789519 -34.414659) (xy 118.753831 -34.455187) (xy 118.712784 -34.490278)
			(xy 118.667199 -34.519231) (xy 118.617986 -34.541465) (xy 118.56613 -34.556539) (xy 118.512667 -34.564149)
			(xy 118.485666 -34.564574) (xy 118.459058 -34.564117) (xy 118.406356 -34.556731) (xy 118.355192 -34.542094)
			(xy 118.306558 -34.520488) (xy 118.261398 -34.492335) (xy 118.220589 -34.458179) (xy 118.184921 -34.418684)
			(xy 118.155088 -34.374616) (xy 118.131668 -34.326829) (xy 118.122954 -34.301684) (xy 118.119906 -34.292286)
			(xy 118.114318 -34.285428) (xy 118.111481 -34.282073) (xy 118.104838 -34.276323) (xy 118.10111 -34.273998)
			(xy 118.042944 -34.2392) (xy 118.039086 -34.236984) (xy 118.030782 -34.233791) (xy 118.026434 -34.23285)
			(xy 118.018052 -34.231326) (xy 118.0084 -34.233104) (xy 117.991527 -34.235955) (xy 117.95744 -34.239003)
			(xy 117.940328 -34.2392) (xy 117.938296 -34.2392) (xy 117.910809 -34.238575) (xy 117.856441 -34.230392)
			(xy 117.803811 -34.214486) (xy 117.754012 -34.191186) (xy 117.708076 -34.160975) (xy 117.666954 -34.12448)
			(xy 117.631501 -34.082457) (xy 117.602451 -34.035778) (xy 117.580406 -33.985411) (xy 117.565823 -33.9324)
			(xy 117.561868 -33.90519) (xy 117.561868 -33.904428) (xy 117.560308 -33.89541) (xy 117.551707 -33.879271)
			(xy 117.545104 -33.872932) (xy 117.538246 -33.86709) (xy 117.520974 -33.860486) (xy 100.455984 -33.860486)
			(xy 100.445977 -33.860976) (xy 100.427489 -33.868638) (xy 100.413337 -33.88279) (xy 100.405676 -33.901279)
			(xy 100.405184 -33.911286) (xy 100.405184 -34.24174) (xy 100.405794 -34.252118) (xy 100.414192 -34.271115)
			(xy 100.42144 -34.27857) (xy 100.481892 -34.330132) (xy 100.486073 -34.333534) (xy 100.49555 -34.338664)
			(xy 100.500688 -34.340292) (xy 100.511102 -34.34334) (xy 100.522278 -34.341562) (xy 100.537104 -34.33939)
			(xy 100.566984 -34.337102) (xy 100.581968 -34.33699) (xy 100.582222 -34.33699) (xy 100.609426 -34.337545)
			(xy 100.663263 -34.34542) (xy 100.715435 -34.360863) (xy 100.764884 -34.383562) (xy 100.810607 -34.413056)
			(xy 100.851675 -34.448747) (xy 100.887256 -34.489911) (xy 100.916628 -34.535712) (xy 100.939194 -34.585222)
			(xy 100.954498 -34.637435) (xy 100.962229 -34.691293) (xy 100.962714 -34.718498) (xy 100.962228 -34.745749)
			(xy 100.954472 -34.799698) (xy 100.939117 -34.851993) (xy 100.916476 -34.901571) (xy 100.88701 -34.947422)
			(xy 100.851319 -34.988613) (xy 100.810128 -35.024305) (xy 100.764278 -35.053772) (xy 100.714701 -35.076414)
			(xy 100.662406 -35.09177) (xy 100.608457 -35.099528) (xy 100.581206 -35.100006) (xy 100.580952 -35.100006)
			(xy 100.551446 -35.099452) (xy 100.493138 -35.090363) (xy 100.436924 -35.072408) (xy 100.384142 -35.046015)
			(xy 100.336052 -35.011814) (xy 100.293798 -34.970619) (xy 100.275644 -34.947352) (xy 100.270564 -34.94024)
			(xy 100.248212 -34.925508) (xy 100.244289 -34.922979) (xy 100.235723 -34.919273) (xy 100.231194 -34.918142)
			(xy 100.209604 -34.913316) (xy 100.200593 -34.911724) (xy 100.182496 -34.914331) (xy 100.174298 -34.918396)
			(xy 100.17379 -34.91865) (xy 100.155408 -34.928876) (xy 100.11712 -34.946302) (xy 100.097336 -34.953448)
			(xy 100.073135 -34.96149) (xy 100.023401 -34.97278) (xy 99.972721 -34.978478) (xy 99.947222 -34.978848)
			(xy 99.921722 -34.978488) (xy 99.87104 -34.972797) (xy 99.821305 -34.961505) (xy 99.797108 -34.953448)
			(xy 99.777323 -34.946304) (xy 99.739034 -34.928881) (xy 99.720654 -34.91865) (xy 99.720146 -34.918396)
			(xy 99.711947 -34.914336) (xy 99.69385 -34.911729) (xy 99.68484 -34.913316) (xy 99.66325 -34.918142)
			(xy 99.658729 -34.919296) (xy 99.650169 -34.923004) (xy 99.646232 -34.925508) (xy 99.62388 -34.94024)
			(xy 99.6188 -34.947352) (xy 99.600648 -34.970649) (xy 99.558367 -35.011882) (xy 99.510234 -35.046102)
			(xy 99.457401 -35.072491) (xy 99.40113 -35.090417) (xy 99.342767 -35.099453) (xy 99.313238 -35.100006)
			(xy 99.302316 -35.100006) (xy 99.302062 -35.099752) (xy 99.275347 -35.098515) (xy 99.222634 -35.089493)
			(xy 99.171697 -35.073198) (xy 99.123534 -35.049952) (xy 99.079088 -35.020209) (xy 99.039231 -34.984552)
			(xy 99.004742 -34.943679) (xy 98.976297 -34.898392) (xy 98.954454 -34.849576) (xy 98.93964 -34.79819)
			(xy 98.932146 -34.745238) (xy 98.93173 -34.718498) (xy 98.932194 -34.691246) (xy 98.939951 -34.637298)
			(xy 98.955308 -34.585002) (xy 98.977951 -34.535425) (xy 99.007419 -34.489575) (xy 99.043114 -34.448385)
			(xy 99.084307 -34.412695) (xy 99.13016 -34.383231) (xy 99.17974 -34.360594) (xy 99.232037 -34.345242)
			(xy 99.285986 -34.337491) (xy 99.313238 -34.33699) (xy 99.328031 -34.337134) (xy 99.357528 -34.339422)
			(xy 99.372166 -34.341562) (xy 99.383342 -34.34334) (xy 99.393756 -34.340292) (xy 99.398889 -34.338651)
			(xy 99.408364 -34.333524) (xy 99.412552 -34.330132) (xy 99.473004 -34.27857) (xy 99.480299 -34.27115)
			(xy 99.488682 -34.25213) (xy 99.48926 -34.24174) (xy 99.48926 -33.911286) (xy 99.488837 -33.901269)
			(xy 99.481164 -33.882764) (xy 99.46699 -33.868606) (xy 99.448477 -33.860952) (xy 99.43846 -33.860486)
			(xy 85.718904 -33.860486) (xy 85.708895 -33.860973) (xy 85.690399 -33.868631) (xy 85.676241 -33.882784)
			(xy 85.668576 -33.901277) (xy 85.668104 -33.911286) (xy 85.668104 -34.522156) (xy 85.668104 -34.522664)
			(xy 85.66785 -34.541714) (xy 85.66785 -34.543238) (xy 85.668022 -34.552194) (xy 85.673886 -34.569106)
			(xy 85.67928 -34.576258) (xy 85.685376 -34.582354) (xy 85.709506 -34.603182) (xy 85.716872 -34.608516)
			(xy 85.724915 -34.612845) (xy 85.742875 -34.616104) (xy 85.751924 -34.614866) (xy 85.768734 -34.612021)
			(xy 85.802694 -34.608967) (xy 85.819742 -34.60877) (xy 85.822028 -34.60877) (xy 85.849185 -34.609394)
			(xy 85.902915 -34.617384) (xy 85.954968 -34.632913) (xy 86.004292 -34.655669) (xy 86.04989 -34.68519)
			(xy 86.09084 -34.72088) (xy 86.126314 -34.762017) (xy 86.155595 -34.80777) (xy 86.178091 -34.857213)
			(xy 86.193347 -34.909347) (xy 86.201055 -34.963118) (xy 86.2015 -34.990024) (xy 87.266778 -34.990024)
			(xy 87.270849 -34.934402) (xy 87.282975 -34.879965) (xy 87.302898 -34.827874) (xy 87.330194 -34.779239)
			(xy 87.36428 -34.735096) (xy 87.404429 -34.696387) (xy 87.449787 -34.663936) (xy 87.499387 -34.638435)
			(xy 87.552171 -34.620428) (xy 87.607014 -34.610298) (xy 87.662748 -34.608261) (xy 87.718185 -34.614361)
			(xy 87.772142 -34.628467) (xy 87.823471 -34.650279) (xy 87.871077 -34.679333) (xy 87.913945 -34.715008)
			(xy 87.951162 -34.756545) (xy 87.981935 -34.803058) (xy 88.005607 -34.853555) (xy 88.021675 -34.906962)
			(xy 88.029795 -34.962138) (xy 88.030304 -34.990024) (xy 89.672666 -34.990024) (xy 89.676737 -34.934402)
			(xy 89.688863 -34.879965) (xy 89.708786 -34.827874) (xy 89.736082 -34.779239) (xy 89.770168 -34.735096)
			(xy 89.810317 -34.696387) (xy 89.855675 -34.663936) (xy 89.905275 -34.638435) (xy 89.958059 -34.620428)
			(xy 90.012902 -34.610298) (xy 90.068636 -34.608261) (xy 90.124073 -34.614361) (xy 90.17803 -34.628467)
			(xy 90.229359 -34.650279) (xy 90.276965 -34.679333) (xy 90.319833 -34.715008) (xy 90.35705 -34.756545)
			(xy 90.387823 -34.803058) (xy 90.411495 -34.853555) (xy 90.427563 -34.906962) (xy 90.435683 -34.962138)
			(xy 90.436192 -34.990024) (xy 90.937332 -34.990024) (xy 90.941403 -34.934402) (xy 90.953529 -34.879965)
			(xy 90.973452 -34.827874) (xy 91.000748 -34.779239) (xy 91.034834 -34.735096) (xy 91.074983 -34.696387)
			(xy 91.120341 -34.663936) (xy 91.169941 -34.638435) (xy 91.222725 -34.620428) (xy 91.277568 -34.610298)
			(xy 91.333302 -34.608261) (xy 91.388739 -34.614361) (xy 91.442696 -34.628467) (xy 91.494025 -34.650279)
			(xy 91.541631 -34.679333) (xy 91.584499 -34.715008) (xy 91.621716 -34.756545) (xy 91.652489 -34.803058)
			(xy 91.676161 -34.853555) (xy 91.692229 -34.906962) (xy 91.700349 -34.962138) (xy 91.700858 -34.990024)
			(xy 93.898718 -34.990024) (xy 93.902789 -34.934402) (xy 93.914915 -34.879965) (xy 93.934838 -34.827874)
			(xy 93.962134 -34.779239) (xy 93.99622 -34.735096) (xy 94.036369 -34.696387) (xy 94.081727 -34.663936)
			(xy 94.131327 -34.638435) (xy 94.184111 -34.620428) (xy 94.238954 -34.610298) (xy 94.294688 -34.608261)
			(xy 94.350125 -34.614361) (xy 94.404082 -34.628467) (xy 94.455411 -34.650279) (xy 94.503017 -34.679333)
			(xy 94.545885 -34.715008) (xy 94.583102 -34.756545) (xy 94.613875 -34.803058) (xy 94.637547 -34.853555)
			(xy 94.653615 -34.906962) (xy 94.661735 -34.962138) (xy 94.662244 -34.990024) (xy 94.661735 -35.01791)
			(xy 94.653615 -35.073086) (xy 94.637547 -35.126493) (xy 94.613875 -35.17699) (xy 94.583102 -35.223503)
			(xy 94.546053 -35.264852) (xy 120.002552 -35.264852) (xy 120.006623 -35.20923) (xy 120.018749 -35.154793)
			(xy 120.038672 -35.102702) (xy 120.065968 -35.054067) (xy 120.100054 -35.009924) (xy 120.140203 -34.971215)
			(xy 120.185561 -34.938764) (xy 120.235161 -34.913263) (xy 120.287945 -34.895256) (xy 120.342788 -34.885126)
			(xy 120.398522 -34.883089) (xy 120.453959 -34.889189) (xy 120.507916 -34.903295) (xy 120.559245 -34.925107)
			(xy 120.606851 -34.954161) (xy 120.649719 -34.989836) (xy 120.686936 -35.031373) (xy 120.717709 -35.077886)
			(xy 120.741381 -35.128383) (xy 120.757449 -35.18179) (xy 120.765569 -35.236966) (xy 120.766078 -35.264852)
			(xy 120.765569 -35.292738) (xy 120.757449 -35.347914) (xy 120.741381 -35.401321) (xy 120.717709 -35.451818)
			(xy 120.686936 -35.498331) (xy 120.649719 -35.539868) (xy 120.606851 -35.575543) (xy 120.559245 -35.604597)
			(xy 120.507916 -35.626409) (xy 120.453959 -35.640515) (xy 120.398522 -35.646615) (xy 120.342788 -35.644578)
			(xy 120.287945 -35.634448) (xy 120.235161 -35.616441) (xy 120.185561 -35.59094) (xy 120.140203 -35.558489)
			(xy 120.100054 -35.51978) (xy 120.065968 -35.475637) (xy 120.038672 -35.427002) (xy 120.018749 -35.374911)
			(xy 120.006623 -35.320474) (xy 120.002552 -35.264852) (xy 94.546053 -35.264852) (xy 94.545885 -35.26504)
			(xy 94.503017 -35.300715) (xy 94.455411 -35.329769) (xy 94.404082 -35.351581) (xy 94.350125 -35.365687)
			(xy 94.294688 -35.371787) (xy 94.238954 -35.36975) (xy 94.184111 -35.35962) (xy 94.131327 -35.341613)
			(xy 94.081727 -35.316112) (xy 94.036369 -35.283661) (xy 93.99622 -35.244952) (xy 93.962134 -35.200809)
			(xy 93.934838 -35.152174) (xy 93.914915 -35.100083) (xy 93.902789 -35.045646) (xy 93.898718 -34.990024)
			(xy 91.700858 -34.990024) (xy 91.700349 -35.01791) (xy 91.692229 -35.073086) (xy 91.676161 -35.126493)
			(xy 91.652489 -35.17699) (xy 91.621716 -35.223503) (xy 91.584499 -35.26504) (xy 91.541631 -35.300715)
			(xy 91.494025 -35.329769) (xy 91.442696 -35.351581) (xy 91.388739 -35.365687) (xy 91.333302 -35.371787)
			(xy 91.277568 -35.36975) (xy 91.222725 -35.35962) (xy 91.169941 -35.341613) (xy 91.120341 -35.316112)
			(xy 91.074983 -35.283661) (xy 91.034834 -35.244952) (xy 91.000748 -35.200809) (xy 90.973452 -35.152174)
			(xy 90.953529 -35.100083) (xy 90.941403 -35.045646) (xy 90.937332 -34.990024) (xy 90.436192 -34.990024)
			(xy 90.435683 -35.01791) (xy 90.427563 -35.073086) (xy 90.411495 -35.126493) (xy 90.387823 -35.17699)
			(xy 90.35705 -35.223503) (xy 90.319833 -35.26504) (xy 90.276965 -35.300715) (xy 90.229359 -35.329769)
			(xy 90.17803 -35.351581) (xy 90.124073 -35.365687) (xy 90.068636 -35.371787) (xy 90.012902 -35.36975)
			(xy 89.958059 -35.35962) (xy 89.905275 -35.341613) (xy 89.855675 -35.316112) (xy 89.810317 -35.283661)
			(xy 89.770168 -35.244952) (xy 89.736082 -35.200809) (xy 89.708786 -35.152174) (xy 89.688863 -35.100083)
			(xy 89.676737 -35.045646) (xy 89.672666 -34.990024) (xy 88.030304 -34.990024) (xy 88.029795 -35.01791)
			(xy 88.021675 -35.073086) (xy 88.005607 -35.126493) (xy 87.981935 -35.17699) (xy 87.951162 -35.223503)
			(xy 87.913945 -35.26504) (xy 87.871077 -35.300715) (xy 87.823471 -35.329769) (xy 87.772142 -35.351581)
			(xy 87.718185 -35.365687) (xy 87.662748 -35.371787) (xy 87.607014 -35.36975) (xy 87.552171 -35.35962)
			(xy 87.499387 -35.341613) (xy 87.449787 -35.316112) (xy 87.404429 -35.283661) (xy 87.36428 -35.244952)
			(xy 87.330194 -35.200809) (xy 87.302898 -35.152174) (xy 87.282975 -35.100083) (xy 87.270849 -35.045646)
			(xy 87.266778 -34.990024) (xy 86.2015 -34.990024) (xy 86.201504 -34.990278) (xy 86.201042 -35.017532)
			(xy 86.193288 -35.071485) (xy 86.177934 -35.123785) (xy 86.155292 -35.173368) (xy 86.125825 -35.219223)
			(xy 86.090131 -35.260418) (xy 86.048938 -35.296114) (xy 86.003084 -35.325584) (xy 85.953502 -35.348227)
			(xy 85.901202 -35.363584) (xy 85.84725 -35.371341) (xy 85.819996 -35.371786) (xy 85.793031 -35.371326)
			(xy 85.739639 -35.363741) (xy 85.687847 -35.348708) (xy 85.638691 -35.326527) (xy 85.593151 -35.297641)
			(xy 85.552135 -35.262626) (xy 85.516462 -35.222181) (xy 85.486844 -35.177113) (xy 85.463872 -35.128321)
			(xy 85.448004 -35.07678) (xy 85.443314 -35.050222) (xy 85.442044 -35.042856) (xy 85.441536 -35.0393)
			(xy 85.435694 -35.03041) (xy 85.432802 -35.026193) (xy 85.42563 -35.018907) (xy 85.42147 -35.015932)
			(xy 85.358732 -34.974276) (xy 85.354238 -34.971438) (xy 85.344381 -34.967465) (xy 85.339174 -34.966402)
			(xy 85.329268 -34.964624) (xy 85.318854 -34.967164) (xy 85.29216 -34.973307) (xy 85.237784 -34.97993)
			(xy 85.210396 -34.980372) (xy 85.183008 -34.979925) (xy 85.128633 -34.973301) (xy 85.101938 -34.967164)
			(xy 85.091524 -34.964624) (xy 85.081618 -34.966402) (xy 85.076399 -34.967429) (xy 85.066535 -34.971401)
			(xy 85.06206 -34.974276) (xy 84.999322 -35.015932) (xy 84.995151 -35.018893) (xy 84.987977 -35.026182)
			(xy 84.985098 -35.03041) (xy 84.979256 -35.0393) (xy 84.978748 -35.042856) (xy 84.977478 -35.050222)
			(xy 84.972778 -35.076775) (xy 84.956886 -35.128303) (xy 84.933898 -35.177081) (xy 84.904273 -35.222137)
			(xy 84.868601 -35.262574) (xy 84.827591 -35.297587) (xy 84.782061 -35.326479) (xy 84.732918 -35.348674)
			(xy 84.68114 -35.363731) (xy 84.627757 -35.371349) (xy 84.600796 -35.371786) (xy 84.573547 -35.3713)
			(xy 84.519602 -35.363543) (xy 84.467311 -35.348188) (xy 84.417737 -35.325548) (xy 84.37189 -35.296084)
			(xy 84.330703 -35.260394) (xy 84.295014 -35.219207) (xy 84.26555 -35.173359) (xy 84.24291 -35.123785)
			(xy 84.227556 -35.071494) (xy 84.2198 -35.017549) (xy 84.2198 -34.963051) (xy 84.227556 -34.909106)
			(xy 84.24291 -34.856815) (xy 84.26555 -34.807241) (xy 84.295014 -34.761393) (xy 84.330703 -34.720206)
			(xy 84.37189 -34.684516) (xy 84.417737 -34.655052) (xy 84.467311 -34.632412) (xy 84.519602 -34.617057)
			(xy 84.573547 -34.6093) (xy 84.600796 -34.60877) (xy 84.60105 -34.60877) (xy 84.618099 -34.60895)
			(xy 84.652061 -34.612) (xy 84.668868 -34.614866) (xy 84.672779 -34.615466) (xy 84.680689 -34.6156)
			(xy 84.684616 -34.61512) (xy 84.689188 -34.614358) (xy 84.695169 -34.612818) (xy 84.706217 -34.607303)
			(xy 84.711032 -34.603436) (xy 84.735416 -34.582354) (xy 84.741512 -34.576258) (xy 84.746831 -34.569069)
			(xy 84.752663 -34.552178) (xy 84.752942 -34.543238) (xy 84.752942 -34.541714) (xy 84.752688 -34.522664)
			(xy 84.752688 -33.911286) (xy 84.752197 -33.901281) (xy 84.744535 -33.882796) (xy 84.730382 -33.868651)
			(xy 84.711893 -33.860998) (xy 84.701888 -33.860486) (xy 82.300826 -33.860486) (xy 82.291568 -33.860839)
			(xy 82.274241 -33.867353) (xy 82.267044 -33.873186) (xy 82.260186 -33.879282) (xy 82.251804 -33.895284)
			(xy 82.250534 -33.904936) (xy 82.246645 -33.932265) (xy 82.23201 -33.985489) (xy 82.209854 -34.036046)
			(xy 82.18064 -34.082882) (xy 82.144979 -34.125016) (xy 82.103616 -34.161568) (xy 82.057415 -34.191774)
			(xy 82.007342 -34.215004) (xy 81.954442 -34.230772) (xy 81.899822 -34.238748) (xy 81.844623 -34.238766)
			(xy 81.789998 -34.230825) (xy 81.737088 -34.215091) (xy 81.687 -34.191894) (xy 81.640779 -34.161717)
			(xy 81.599393 -34.125191) (xy 81.563705 -34.08308) (xy 81.534461 -34.036264) (xy 81.512272 -33.98572)
			(xy 81.497603 -33.932506) (xy 81.493614 -33.90519) (xy 81.493614 -33.904428) (xy 81.492056 -33.895408)
			(xy 81.483461 -33.879264) (xy 81.47685 -33.872932) (xy 81.469992 -33.86709) (xy 81.45272 -33.860486)
			(xy 80.814926 -33.860486) (xy 80.802366 -33.861121) (xy 80.780217 -33.872967) (xy 80.772762 -33.883092)
			(xy 80.754982 -33.912048) (xy 80.72628 -33.959292) (xy 80.723097 -33.9649) (xy 80.719379 -33.977244)
			(xy 80.718914 -33.983676) (xy 80.718406 -33.996376) (xy 80.724756 -34.008568) (xy 80.738045 -34.035715)
			(xy 80.756837 -34.09316) (xy 80.766354 -34.152846) (xy 80.76692 -34.183066) (xy 80.76692 -34.188654)
			(xy 80.765992 -34.216931) (xy 80.75682 -34.272757) (xy 80.739504 -34.326617) (xy 80.714425 -34.37733)
			(xy 80.682133 -34.423783) (xy 80.643335 -34.464959) (xy 80.598883 -34.499955) (xy 80.54975 -34.528002)
			(xy 80.497014 -34.548488) (xy 80.441832 -34.560961) (xy 80.385412 -34.56515) (xy 80.328992 -34.560961)
			(xy 80.27381 -34.548488) (xy 80.221074 -34.528002) (xy 80.171941 -34.499955) (xy 80.127489 -34.464959)
			(xy 80.088691 -34.423783) (xy 80.056399 -34.37733) (xy 80.03132 -34.326617) (xy 80.014004 -34.272757)
			(xy 80.004832 -34.216931) (xy 80.003904 -34.188654) (xy 80.003904 -34.183066) (xy 80.004455 -34.152844)
			(xy 80.013949 -34.09315) (xy 80.032756 -34.035706) (xy 80.046068 -34.008568) (xy 80.046068 -34.008314)
			(xy 80.048945 -34.002374) (xy 80.051893 -33.989514) (xy 80.05191 -33.982914) (xy 80.051402 -33.970468)
			(xy 80.015842 -33.912048) (xy 79.998062 -33.883092) (xy 79.990546 -33.873031) (xy 79.968437 -33.861182)
			(xy 79.955898 -33.860486) (xy 74.456036 -33.860486) (xy 74.446009 -33.860899) (xy 74.427477 -33.868562)
			(xy 74.41329 -33.882735) (xy 74.405609 -33.901259) (xy 74.405236 -33.911286) (xy 74.405236 -34.24174)
			(xy 74.405847 -34.252117) (xy 74.414252 -34.271108) (xy 74.421492 -34.27857) (xy 74.481944 -34.330132)
			(xy 74.486127 -34.33353) (xy 74.495607 -34.338651) (xy 74.50074 -34.340292) (xy 74.511154 -34.34334)
			(xy 74.52233 -34.341562) (xy 74.537156 -34.339388) (xy 74.567036 -34.337096) (xy 74.58202 -34.33699)
			(xy 74.582274 -34.33699) (xy 74.60948 -34.337542) (xy 74.663322 -34.345411) (xy 74.7155 -34.36085)
			(xy 74.764955 -34.383547) (xy 74.810684 -34.413039) (xy 74.851758 -34.44873) (xy 74.887344 -34.489895)
			(xy 74.91672 -34.535699) (xy 74.93929 -34.585211) (xy 74.954597 -34.637429) (xy 74.962328 -34.691291)
			(xy 74.962766 -34.718498) (xy 74.962303 -34.74575) (xy 74.954546 -34.799699) (xy 74.93919 -34.851994)
			(xy 74.916547 -34.901572) (xy 74.887078 -34.947423) (xy 74.851384 -34.988612) (xy 74.81019 -35.024302)
			(xy 74.764337 -35.053766) (xy 74.714757 -35.076404) (xy 74.66246 -35.091754) (xy 74.60851 -35.099506)
			(xy 74.581258 -35.100006) (xy 74.581004 -35.100006) (xy 74.5515 -35.099448) (xy 74.493196 -35.090353)
			(xy 74.436987 -35.072393) (xy 74.384211 -35.045996) (xy 74.336126 -35.011793) (xy 74.293878 -34.970596)
			(xy 74.275696 -34.947352) (xy 74.270616 -34.94024) (xy 74.248264 -34.925508) (xy 74.244339 -34.922982)
			(xy 74.235772 -34.919284) (xy 74.231246 -34.918142) (xy 74.209656 -34.913316) (xy 74.200644 -34.911714)
			(xy 74.182537 -34.914305) (xy 74.17435 -34.918396) (xy 74.173842 -34.91865) (xy 74.155461 -34.928878)
			(xy 74.117174 -34.946308) (xy 74.097388 -34.953448) (xy 74.073188 -34.961493) (xy 74.023454 -34.972789)
			(xy 73.972774 -34.978493) (xy 73.947274 -34.978848) (xy 73.921774 -34.978485) (xy 73.871093 -34.972789)
			(xy 73.821361 -34.961492) (xy 73.79716 -34.953448) (xy 73.777376 -34.946302) (xy 73.739088 -34.928875)
			(xy 73.720706 -34.91865) (xy 73.720198 -34.918396) (xy 73.711998 -34.914344) (xy 73.693905 -34.911754)
			(xy 73.684892 -34.913316) (xy 73.663302 -34.918142) (xy 73.65878 -34.919292) (xy 73.650214 -34.922993)
			(xy 73.646284 -34.925508) (xy 73.623932 -34.94024) (xy 73.618852 -34.947352) (xy 73.600701 -34.970652)
			(xy 73.558422 -35.01189) (xy 73.51029 -35.046117) (xy 73.457456 -35.072513) (xy 73.401185 -35.090447)
			(xy 73.342821 -35.09949) (xy 73.31329 -35.100006) (xy 73.302368 -35.100006) (xy 73.302114 -35.099752)
			(xy 73.275401 -35.098512) (xy 73.222693 -35.089484) (xy 73.171762 -35.073186) (xy 73.123605 -35.049937)
			(xy 73.079165 -35.020193) (xy 73.039313 -34.984536) (xy 73.004829 -34.943664) (xy 72.976388 -34.898379)
			(xy 72.954549 -34.849567) (xy 72.939737 -34.798183) (xy 72.932244 -34.745235) (xy 72.931782 -34.718498)
			(xy 72.932268 -34.691247) (xy 72.940025 -34.637299) (xy 72.95538 -34.585003) (xy 72.978021 -34.535426)
			(xy 73.007487 -34.489575) (xy 73.043178 -34.448384) (xy 73.084369 -34.412692) (xy 73.130219 -34.383225)
			(xy 73.179796 -34.360583) (xy 73.232091 -34.345226) (xy 73.286039 -34.337468) (xy 73.31329 -34.33699)
			(xy 73.328083 -34.337132) (xy 73.357581 -34.339417) (xy 73.372218 -34.341562) (xy 73.383394 -34.34334)
			(xy 73.393808 -34.340292) (xy 73.398943 -34.338655) (xy 73.408425 -34.333535) (xy 73.412604 -34.330132)
			(xy 73.473056 -34.27857) (xy 73.480345 -34.271147) (xy 73.48872 -34.252128) (xy 73.489312 -34.24174)
			(xy 73.489312 -33.911286) (xy 73.488821 -33.901279) (xy 73.48116 -33.88279) (xy 73.467008 -33.868639)
			(xy 73.448519 -33.860978) (xy 73.438512 -33.860486) (xy 59.718956 -33.860486) (xy 59.708953 -33.860981)
			(xy 59.690474 -33.868648) (xy 59.676331 -33.882799) (xy 59.668675 -33.901283) (xy 59.668156 -33.911286)
			(xy 59.668156 -34.522156) (xy 59.668156 -34.522664) (xy 59.667902 -34.541714) (xy 59.667902 -34.543238)
			(xy 59.668075 -34.552193) (xy 59.673944 -34.569101) (xy 59.679332 -34.576258) (xy 59.685428 -34.582354)
			(xy 59.709558 -34.603182) (xy 59.716924 -34.608516) (xy 59.724968 -34.612836) (xy 59.742925 -34.616077)
			(xy 59.751976 -34.614866) (xy 59.768787 -34.612024) (xy 59.802746 -34.608974) (xy 59.819794 -34.60877)
			(xy 59.82208 -34.60877) (xy 59.849239 -34.60939) (xy 59.902974 -34.617375) (xy 59.955033 -34.6329)
			(xy 60.004363 -34.655653) (xy 60.049967 -34.685173) (xy 60.090923 -34.720863) (xy 60.126402 -34.762002)
			(xy 60.155688 -34.807757) (xy 60.178187 -34.857203) (xy 60.193446 -34.909341) (xy 60.201154 -34.963116)
			(xy 60.201552 -34.990024) (xy 61.26683 -34.990024) (xy 61.270901 -34.934402) (xy 61.283027 -34.879965)
			(xy 61.30295 -34.827874) (xy 61.330246 -34.779239) (xy 61.364332 -34.735096) (xy 61.404481 -34.696387)
			(xy 61.449839 -34.663936) (xy 61.499439 -34.638435) (xy 61.552223 -34.620428) (xy 61.607066 -34.610298)
			(xy 61.6628 -34.608261) (xy 61.718237 -34.614361) (xy 61.772194 -34.628467) (xy 61.823523 -34.650279)
			(xy 61.871129 -34.679333) (xy 61.913997 -34.715008) (xy 61.951214 -34.756545) (xy 61.981987 -34.803058)
			(xy 62.005659 -34.853555) (xy 62.021727 -34.906962) (xy 62.029847 -34.962138) (xy 62.030356 -34.990024)
			(xy 63.672718 -34.990024) (xy 63.676789 -34.934402) (xy 63.688915 -34.879965) (xy 63.708838 -34.827874)
			(xy 63.736134 -34.779239) (xy 63.77022 -34.735096) (xy 63.810369 -34.696387) (xy 63.855727 -34.663936)
			(xy 63.905327 -34.638435) (xy 63.958111 -34.620428) (xy 64.012954 -34.610298) (xy 64.068688 -34.608261)
			(xy 64.124125 -34.614361) (xy 64.178082 -34.628467) (xy 64.229411 -34.650279) (xy 64.277017 -34.679333)
			(xy 64.319885 -34.715008) (xy 64.357102 -34.756545) (xy 64.387875 -34.803058) (xy 64.411547 -34.853555)
			(xy 64.427615 -34.906962) (xy 64.435735 -34.962138) (xy 64.436244 -34.990024) (xy 65.000884 -34.990024)
			(xy 65.004955 -34.934402) (xy 65.017081 -34.879965) (xy 65.037004 -34.827874) (xy 65.0643 -34.779239)
			(xy 65.098386 -34.735096) (xy 65.138535 -34.696387) (xy 65.183893 -34.663936) (xy 65.233493 -34.638435)
			(xy 65.286277 -34.620428) (xy 65.34112 -34.610298) (xy 65.396854 -34.608261) (xy 65.452291 -34.614361)
			(xy 65.506248 -34.628467) (xy 65.557577 -34.650279) (xy 65.605183 -34.679333) (xy 65.648051 -34.715008)
			(xy 65.685268 -34.756545) (xy 65.716041 -34.803058) (xy 65.739713 -34.853555) (xy 65.755781 -34.906962)
			(xy 65.763901 -34.962138) (xy 65.76441 -34.990024) (xy 67.89877 -34.990024) (xy 67.902841 -34.934402)
			(xy 67.914967 -34.879965) (xy 67.93489 -34.827874) (xy 67.962186 -34.779239) (xy 67.996272 -34.735096)
			(xy 68.036421 -34.696387) (xy 68.081779 -34.663936) (xy 68.131379 -34.638435) (xy 68.184163 -34.620428)
			(xy 68.239006 -34.610298) (xy 68.29474 -34.608261) (xy 68.350177 -34.614361) (xy 68.404134 -34.628467)
			(xy 68.455463 -34.650279) (xy 68.503069 -34.679333) (xy 68.545937 -34.715008) (xy 68.583154 -34.756545)
			(xy 68.613927 -34.803058) (xy 68.637599 -34.853555) (xy 68.653667 -34.906962) (xy 68.661787 -34.962138)
			(xy 68.662296 -34.990024) (xy 68.661787 -35.01791) (xy 68.653667 -35.073086) (xy 68.637599 -35.126493)
			(xy 68.613927 -35.17699) (xy 68.583154 -35.223503) (xy 68.546105 -35.264852) (xy 81.902298 -35.264852)
			(xy 81.906369 -35.20923) (xy 81.918495 -35.154793) (xy 81.938418 -35.102702) (xy 81.965714 -35.054067)
			(xy 81.9998 -35.009924) (xy 82.039949 -34.971215) (xy 82.085307 -34.938764) (xy 82.134907 -34.913263)
			(xy 82.187691 -34.895256) (xy 82.242534 -34.885126) (xy 82.298268 -34.883089) (xy 82.353705 -34.889189)
			(xy 82.407662 -34.903295) (xy 82.458991 -34.925107) (xy 82.506597 -34.954161) (xy 82.549465 -34.989836)
			(xy 82.586682 -35.031373) (xy 82.617455 -35.077886) (xy 82.641127 -35.128383) (xy 82.657195 -35.18179)
			(xy 82.665315 -35.236966) (xy 82.665824 -35.264852) (xy 82.665315 -35.292738) (xy 82.657195 -35.347914)
			(xy 82.641127 -35.401321) (xy 82.617455 -35.451818) (xy 82.586682 -35.498331) (xy 82.549465 -35.539868)
			(xy 82.506597 -35.575543) (xy 82.458991 -35.604597) (xy 82.407662 -35.626409) (xy 82.353705 -35.640515)
			(xy 82.298268 -35.646615) (xy 82.242534 -35.644578) (xy 82.187691 -35.634448) (xy 82.134907 -35.616441)
			(xy 82.085307 -35.59094) (xy 82.039949 -35.558489) (xy 81.9998 -35.51978) (xy 81.965714 -35.475637)
			(xy 81.938418 -35.427002) (xy 81.918495 -35.374911) (xy 81.906369 -35.320474) (xy 81.902298 -35.264852)
			(xy 68.546105 -35.264852) (xy 68.545937 -35.26504) (xy 68.503069 -35.300715) (xy 68.455463 -35.329769)
			(xy 68.404134 -35.351581) (xy 68.350177 -35.365687) (xy 68.29474 -35.371787) (xy 68.239006 -35.36975)
			(xy 68.184163 -35.35962) (xy 68.131379 -35.341613) (xy 68.081779 -35.316112) (xy 68.036421 -35.283661)
			(xy 67.996272 -35.244952) (xy 67.962186 -35.200809) (xy 67.93489 -35.152174) (xy 67.914967 -35.100083)
			(xy 67.902841 -35.045646) (xy 67.89877 -34.990024) (xy 65.76441 -34.990024) (xy 65.763901 -35.01791)
			(xy 65.755781 -35.073086) (xy 65.739713 -35.126493) (xy 65.716041 -35.17699) (xy 65.685268 -35.223503)
			(xy 65.648051 -35.26504) (xy 65.605183 -35.300715) (xy 65.557577 -35.329769) (xy 65.506248 -35.351581)
			(xy 65.452291 -35.365687) (xy 65.396854 -35.371787) (xy 65.34112 -35.36975) (xy 65.286277 -35.35962)
			(xy 65.233493 -35.341613) (xy 65.183893 -35.316112) (xy 65.138535 -35.283661) (xy 65.098386 -35.244952)
			(xy 65.0643 -35.200809) (xy 65.037004 -35.152174) (xy 65.017081 -35.100083) (xy 65.004955 -35.045646)
			(xy 65.000884 -34.990024) (xy 64.436244 -34.990024) (xy 64.435735 -35.01791) (xy 64.427615 -35.073086)
			(xy 64.411547 -35.126493) (xy 64.387875 -35.17699) (xy 64.357102 -35.223503) (xy 64.319885 -35.26504)
			(xy 64.277017 -35.300715) (xy 64.229411 -35.329769) (xy 64.178082 -35.351581) (xy 64.124125 -35.365687)
			(xy 64.068688 -35.371787) (xy 64.012954 -35.36975) (xy 63.958111 -35.35962) (xy 63.905327 -35.341613)
			(xy 63.855727 -35.316112) (xy 63.810369 -35.283661) (xy 63.77022 -35.244952) (xy 63.736134 -35.200809)
			(xy 63.708838 -35.152174) (xy 63.688915 -35.100083) (xy 63.676789 -35.045646) (xy 63.672718 -34.990024)
			(xy 62.030356 -34.990024) (xy 62.029847 -35.01791) (xy 62.021727 -35.073086) (xy 62.005659 -35.126493)
			(xy 61.981987 -35.17699) (xy 61.951214 -35.223503) (xy 61.913997 -35.26504) (xy 61.871129 -35.300715)
			(xy 61.823523 -35.329769) (xy 61.772194 -35.351581) (xy 61.718237 -35.365687) (xy 61.6628 -35.371787)
			(xy 61.607066 -35.36975) (xy 61.552223 -35.35962) (xy 61.499439 -35.341613) (xy 61.449839 -35.316112)
			(xy 61.404481 -35.283661) (xy 61.364332 -35.244952) (xy 61.330246 -35.200809) (xy 61.30295 -35.152174)
			(xy 61.283027 -35.100083) (xy 61.270901 -35.045646) (xy 61.26683 -34.990024) (xy 60.201552 -34.990024)
			(xy 60.201556 -34.990278) (xy 60.201072 -35.017532) (xy 60.193318 -35.071484) (xy 60.177965 -35.123784)
			(xy 60.155326 -35.173367) (xy 60.125861 -35.219224) (xy 60.09017 -35.260421) (xy 60.04898 -35.296119)
			(xy 60.003129 -35.325592) (xy 59.95355 -35.348241) (xy 59.901253 -35.363603) (xy 59.847301 -35.371367)
			(xy 59.820048 -35.371786) (xy 59.793085 -35.371323) (xy 59.739698 -35.363732) (xy 59.687912 -35.348695)
			(xy 59.638761 -35.326511) (xy 59.593227 -35.297623) (xy 59.552216 -35.262608) (xy 59.516549 -35.222164)
			(xy 59.486935 -35.177098) (xy 59.463967 -35.128309) (xy 59.448102 -35.07677) (xy 59.443366 -35.050222)
			(xy 59.442096 -35.042856) (xy 59.441588 -35.0393) (xy 59.435746 -35.03041) (xy 59.432856 -35.026191)
			(xy 59.425688 -35.018898) (xy 59.421522 -35.015932) (xy 59.358784 -34.974276) (xy 59.354288 -34.971442)
			(xy 59.34443 -34.967478) (xy 59.339226 -34.966402) (xy 59.32932 -34.964624) (xy 59.318906 -34.967164)
			(xy 59.292212 -34.973305) (xy 59.237836 -34.979922) (xy 59.210448 -34.980372) (xy 59.18306 -34.979928)
			(xy 59.128683 -34.97331) (xy 59.10199 -34.967164) (xy 59.091576 -34.964624) (xy 59.08167 -34.966402)
			(xy 59.076453 -34.967434) (xy 59.066594 -34.971413) (xy 59.062112 -34.974276) (xy 58.999374 -35.015932)
			(xy 58.995206 -35.018896) (xy 58.988037 -35.026189) (xy 58.98515 -35.03041) (xy 58.979308 -35.0393)
			(xy 58.9788 -35.042856) (xy 58.97753 -35.050222) (xy 58.97283 -35.076773) (xy 58.956937 -35.128298)
			(xy 58.933948 -35.177073) (xy 58.904322 -35.222125) (xy 58.868649 -35.262558) (xy 58.827639 -35.297567)
			(xy 58.782109 -35.326454) (xy 58.732966 -35.348643) (xy 58.681189 -35.363693) (xy 58.627808 -35.371305)
			(xy 58.600848 -35.371786) (xy 58.573594 -35.371326) (xy 58.519641 -35.363575) (xy 58.467341 -35.348224)
			(xy 58.417758 -35.325586) (xy 58.371901 -35.296121) (xy 58.330705 -35.260429) (xy 58.295008 -35.219237)
			(xy 58.265537 -35.173385) (xy 58.242893 -35.123804) (xy 58.227535 -35.071505) (xy 58.219777 -35.017553)
			(xy 58.219777 -34.963047) (xy 58.227535 -34.909095) (xy 58.242893 -34.856796) (xy 58.265537 -34.807215)
			(xy 58.295008 -34.761363) (xy 58.330705 -34.720171) (xy 58.371901 -34.684479) (xy 58.417758 -34.655014)
			(xy 58.467341 -34.632376) (xy 58.519641 -34.617025) (xy 58.573594 -34.609274) (xy 58.600848 -34.60877)
			(xy 58.601102 -34.60877) (xy 58.618151 -34.608953) (xy 58.652112 -34.612006) (xy 58.66892 -34.614866)
			(xy 58.672831 -34.615462) (xy 58.68074 -34.615588) (xy 58.684668 -34.61512) (xy 58.68924 -34.614358)
			(xy 58.695218 -34.612812) (xy 58.706259 -34.607289) (xy 58.711084 -34.603436) (xy 58.735468 -34.582354)
			(xy 58.741564 -34.576258) (xy 58.746879 -34.569067) (xy 58.752705 -34.552177) (xy 58.752994 -34.543238)
			(xy 58.752994 -34.541714) (xy 58.75274 -34.522664) (xy 58.75274 -33.911286) (xy 58.75225 -33.901277)
			(xy 58.744589 -33.882783) (xy 58.730438 -33.868625) (xy 58.711948 -33.860955) (xy 58.70194 -33.860486)
			(xy 56.300878 -33.860486) (xy 56.291624 -33.860847) (xy 56.274308 -33.867373) (xy 56.267096 -33.873186)
			(xy 56.260238 -33.879282) (xy 56.251856 -33.895284) (xy 56.250586 -33.904936) (xy 56.246697 -33.932268)
			(xy 56.232061 -33.9855) (xy 56.209903 -34.036065) (xy 56.180686 -34.082907) (xy 56.145021 -34.125047)
			(xy 56.103653 -34.161605) (xy 56.057446 -34.191816) (xy 56.007366 -34.21505) (xy 55.95446 -34.230821)
			(xy 55.899833 -34.238799) (xy 55.844626 -34.238818) (xy 55.789993 -34.230877) (xy 55.737076 -34.215142)
			(xy 55.68698 -34.191942) (xy 55.640753 -34.161762) (xy 55.59936 -34.125232) (xy 55.563667 -34.083116)
			(xy 55.534418 -34.036294) (xy 55.512226 -33.985744) (xy 55.497554 -33.932522) (xy 55.493666 -33.90519)
			(xy 55.493666 -33.904428) (xy 55.49211 -33.895406) (xy 55.483521 -33.879256) (xy 55.476902 -33.872932)
			(xy 55.470044 -33.86709) (xy 55.452772 -33.860486) (xy 54.814978 -33.860486) (xy 54.802424 -33.861132)
			(xy 54.780293 -33.872989) (xy 54.772814 -33.883092) (xy 54.755034 -33.912048) (xy 54.726332 -33.959292)
			(xy 54.723146 -33.964899) (xy 54.719424 -33.977243) (xy 54.718966 -33.983676) (xy 54.718458 -33.996376)
			(xy 54.724808 -34.008568) (xy 54.738096 -34.035716) (xy 54.756885 -34.09316) (xy 54.766401 -34.152846)
			(xy 54.766972 -34.183066) (xy 54.766972 -34.188654) (xy 54.766111 -34.215645) (xy 54.757719 -34.268991)
			(xy 54.741887 -34.320621) (xy 54.718934 -34.369502) (xy 54.689317 -34.414658) (xy 54.653629 -34.455186)
			(xy 54.612582 -34.490277) (xy 54.566996 -34.519229) (xy 54.517784 -34.541464) (xy 54.465928 -34.556537)
			(xy 54.412465 -34.564147) (xy 54.385464 -34.564574) (xy 54.358856 -34.564117) (xy 54.306154 -34.556731)
			(xy 54.25499 -34.542093) (xy 54.206356 -34.520488) (xy 54.161197 -34.492334) (xy 54.120388 -34.458178)
			(xy 54.084721 -34.418683) (xy 54.054888 -34.374615) (xy 54.031468 -34.326829) (xy 54.022752 -34.301684)
			(xy 54.019704 -34.292286) (xy 54.014116 -34.285428) (xy 54.011279 -34.282073) (xy 54.004636 -34.276324)
			(xy 54.000908 -34.273998) (xy 53.942742 -34.2392) (xy 53.938884 -34.236984) (xy 53.93058 -34.233791)
			(xy 53.926232 -34.23285) (xy 53.91785 -34.231326) (xy 53.908198 -34.233104) (xy 53.891325 -34.235955)
			(xy 53.857238 -34.239003) (xy 53.840126 -34.2392) (xy 53.838094 -34.2392) (xy 53.810607 -34.238574)
			(xy 53.756239 -34.230392) (xy 53.70361 -34.214486) (xy 53.653811 -34.191186) (xy 53.607875 -34.160975)
			(xy 53.566754 -34.12448) (xy 53.5313 -34.082457) (xy 53.50225 -34.035778) (xy 53.480206 -33.985411)
			(xy 53.465623 -33.932399) (xy 53.461666 -33.90519) (xy 53.461666 -33.904428) (xy 53.46011 -33.895406)
			(xy 53.451521 -33.879256) (xy 53.444902 -33.872932) (xy 53.438044 -33.86709) (xy 53.420772 -33.860486)
			(xy 48.456088 -33.860486) (xy 48.446081 -33.860976) (xy 48.427591 -33.868637) (xy 48.413438 -33.882789)
			(xy 48.405776 -33.901279) (xy 48.405288 -33.911286) (xy 48.405288 -34.24174) (xy 48.405898 -34.252118)
			(xy 48.414297 -34.271115) (xy 48.421544 -34.27857) (xy 48.481996 -34.330132) (xy 48.486177 -34.333533)
			(xy 48.495654 -34.338663) (xy 48.500792 -34.340292) (xy 48.511206 -34.34334) (xy 48.522382 -34.341562)
			(xy 48.537208 -34.33939) (xy 48.567088 -34.337102) (xy 48.582072 -34.33699) (xy 48.582326 -34.33699)
			(xy 48.609529 -34.337546) (xy 48.663366 -34.345421) (xy 48.715538 -34.360864) (xy 48.764986 -34.383564)
			(xy 48.810708 -34.413058) (xy 48.851776 -34.448749) (xy 48.887357 -34.489912) (xy 48.916728 -34.535713)
			(xy 48.939295 -34.585222) (xy 48.954598 -34.637435) (xy 48.962329 -34.691293) (xy 48.962818 -34.718498)
			(xy 48.962332 -34.74575) (xy 48.954576 -34.799698) (xy 48.939221 -34.851994) (xy 48.91658 -34.901572)
			(xy 48.887114 -34.947423) (xy 48.851423 -34.988614) (xy 48.810233 -35.024307) (xy 48.764382 -35.053775)
			(xy 48.714805 -35.076417) (xy 48.66251 -35.091774) (xy 48.608562 -35.099532) (xy 48.58131 -35.100006)
			(xy 48.581056 -35.100006) (xy 48.55155 -35.099452) (xy 48.493242 -35.090363) (xy 48.437027 -35.072409)
			(xy 48.384245 -35.046017) (xy 48.336154 -35.011816) (xy 48.293899 -34.970621) (xy 48.275748 -34.947352)
			(xy 48.270668 -34.94024) (xy 48.248316 -34.925508) (xy 48.244393 -34.922979) (xy 48.235827 -34.919272)
			(xy 48.231298 -34.918142) (xy 48.209708 -34.913316) (xy 48.200697 -34.911723) (xy 48.182599 -34.914329)
			(xy 48.174402 -34.918396) (xy 48.173894 -34.91865) (xy 48.155512 -34.928876) (xy 48.117224 -34.946302)
			(xy 48.09744 -34.953448) (xy 48.073239 -34.96149) (xy 48.023505 -34.972781) (xy 47.972825 -34.978479)
			(xy 47.947326 -34.978848) (xy 47.921826 -34.978488) (xy 47.871143 -34.972797) (xy 47.821408 -34.961506)
			(xy 47.797212 -34.953448) (xy 47.777427 -34.946304) (xy 47.739137 -34.928881) (xy 47.720758 -34.91865)
			(xy 47.72025 -34.918396) (xy 47.712051 -34.914335) (xy 47.693954 -34.911727) (xy 47.684944 -34.913316)
			(xy 47.663354 -34.918142) (xy 47.658833 -34.919296) (xy 47.650272 -34.923003) (xy 47.646336 -34.925508)
			(xy 47.623984 -34.94024) (xy 47.618904 -34.947352) (xy 47.600752 -34.970649) (xy 47.558471 -35.011882)
			(xy 47.510339 -35.046103) (xy 47.457505 -35.072492) (xy 47.401234 -35.090419) (xy 47.342872 -35.099456)
			(xy 47.313342 -35.100006) (xy 47.30242 -35.100006) (xy 47.302166 -35.099752) (xy 47.275451 -35.098516)
			(xy 47.222737 -35.089493) (xy 47.1718 -35.073199) (xy 47.123637 -35.049953) (xy 47.07919 -35.020211)
			(xy 47.039332 -34.984553) (xy 47.004843 -34.943681) (xy 46.976398 -34.898393) (xy 46.954554 -34.849577)
			(xy 46.93974 -34.79819) (xy 46.932246 -34.745238) (xy 46.931834 -34.718498) (xy 46.932298 -34.691246)
			(xy 46.940055 -34.637298) (xy 46.955412 -34.585003) (xy 46.978055 -34.535425) (xy 47.007523 -34.489576)
			(xy 47.043218 -34.448387) (xy 47.084411 -34.412697) (xy 47.130264 -34.383234) (xy 47.179844 -34.360596)
			(xy 47.232141 -34.345246) (xy 47.28609 -34.337494) (xy 47.313342 -34.33699) (xy 47.328135 -34.337134)
			(xy 47.357632 -34.339423) (xy 47.37227 -34.341562) (xy 47.383446 -34.34334) (xy 47.39386 -34.340292)
			(xy 47.398993 -34.338651) (xy 47.408468 -34.333523) (xy 47.412656 -34.330132) (xy 47.473108 -34.27857)
			(xy 47.480402 -34.27115) (xy 47.488785 -34.25213) (xy 47.489364 -34.24174) (xy 47.489364 -33.911286)
			(xy 47.488941 -33.901269) (xy 47.481268 -33.882763) (xy 47.467095 -33.868604) (xy 47.448581 -33.860949)
			(xy 47.438564 -33.860486) (xy 33.719008 -33.860486) (xy 33.708998 -33.860972) (xy 33.690501 -33.86863)
			(xy 33.676342 -33.882783) (xy 33.668677 -33.901276) (xy 33.668208 -33.911286) (xy 33.668208 -34.522156)
			(xy 33.668208 -34.522664) (xy 33.667954 -34.541714) (xy 33.667954 -34.543238) (xy 33.668126 -34.552194)
			(xy 33.673991 -34.569105) (xy 33.679384 -34.576258) (xy 33.68548 -34.582354) (xy 33.70961 -34.603182)
			(xy 33.716976 -34.608516) (xy 33.725019 -34.612844) (xy 33.742979 -34.616102) (xy 33.752028 -34.614866)
			(xy 33.768838 -34.612022) (xy 33.802798 -34.608968) (xy 33.819846 -34.60877) (xy 33.822132 -34.60877)
			(xy 33.849289 -34.609394) (xy 33.903018 -34.617384) (xy 33.955071 -34.632914) (xy 34.004394 -34.65567)
			(xy 34.049992 -34.685191) (xy 34.090942 -34.720881) (xy 34.126415 -34.762019) (xy 34.155696 -34.807771)
			(xy 34.178192 -34.857214) (xy 34.193447 -34.909348) (xy 34.201155 -34.963118) (xy 34.201604 -34.990024)
			(xy 35.266882 -34.990024) (xy 35.270953 -34.934402) (xy 35.283079 -34.879965) (xy 35.303002 -34.827874)
			(xy 35.330298 -34.779239) (xy 35.364384 -34.735096) (xy 35.404533 -34.696387) (xy 35.449891 -34.663936)
			(xy 35.499491 -34.638435) (xy 35.552275 -34.620428) (xy 35.607118 -34.610298) (xy 35.662852 -34.608261)
			(xy 35.718289 -34.614361) (xy 35.772246 -34.628467) (xy 35.823575 -34.650279) (xy 35.871181 -34.679333)
			(xy 35.914049 -34.715008) (xy 35.951266 -34.756545) (xy 35.982039 -34.803058) (xy 36.005711 -34.853555)
			(xy 36.021779 -34.906962) (xy 36.029899 -34.962138) (xy 36.030408 -34.990024) (xy 37.67277 -34.990024)
			(xy 37.676841 -34.934402) (xy 37.688967 -34.879965) (xy 37.70889 -34.827874) (xy 37.736186 -34.779239)
			(xy 37.770272 -34.735096) (xy 37.810421 -34.696387) (xy 37.855779 -34.663936) (xy 37.905379 -34.638435)
			(xy 37.958163 -34.620428) (xy 38.013006 -34.610298) (xy 38.06874 -34.608261) (xy 38.124177 -34.614361)
			(xy 38.178134 -34.628467) (xy 38.229463 -34.650279) (xy 38.277069 -34.679333) (xy 38.319937 -34.715008)
			(xy 38.357154 -34.756545) (xy 38.387927 -34.803058) (xy 38.411599 -34.853555) (xy 38.427667 -34.906962)
			(xy 38.435787 -34.962138) (xy 38.436296 -34.990024) (xy 39.000936 -34.990024) (xy 39.005007 -34.934402)
			(xy 39.017133 -34.879965) (xy 39.037056 -34.827874) (xy 39.064352 -34.779239) (xy 39.098438 -34.735096)
			(xy 39.138587 -34.696387) (xy 39.183945 -34.663936) (xy 39.233545 -34.638435) (xy 39.286329 -34.620428)
			(xy 39.341172 -34.610298) (xy 39.396906 -34.608261) (xy 39.452343 -34.614361) (xy 39.5063 -34.628467)
			(xy 39.557629 -34.650279) (xy 39.605235 -34.679333) (xy 39.648103 -34.715008) (xy 39.68532 -34.756545)
			(xy 39.716093 -34.803058) (xy 39.739765 -34.853555) (xy 39.755833 -34.906962) (xy 39.763953 -34.962138)
			(xy 39.764462 -34.990024) (xy 41.898822 -34.990024) (xy 41.902893 -34.934402) (xy 41.915019 -34.879965)
			(xy 41.934942 -34.827874) (xy 41.962238 -34.779239) (xy 41.996324 -34.735096) (xy 42.036473 -34.696387)
			(xy 42.081831 -34.663936) (xy 42.131431 -34.638435) (xy 42.184215 -34.620428) (xy 42.239058 -34.610298)
			(xy 42.294792 -34.608261) (xy 42.350229 -34.614361) (xy 42.404186 -34.628467) (xy 42.455515 -34.650279)
			(xy 42.503121 -34.679333) (xy 42.545989 -34.715008) (xy 42.583206 -34.756545) (xy 42.613979 -34.803058)
			(xy 42.637651 -34.853555) (xy 42.653719 -34.906962) (xy 42.661839 -34.962138) (xy 42.662348 -34.990024)
			(xy 42.661839 -35.01791) (xy 42.653719 -35.073086) (xy 42.637651 -35.126493) (xy 42.613979 -35.17699)
			(xy 42.583206 -35.223503) (xy 42.546157 -35.264852) (xy 55.90235 -35.264852) (xy 55.906421 -35.20923)
			(xy 55.918547 -35.154793) (xy 55.93847 -35.102702) (xy 55.965766 -35.054067) (xy 55.999852 -35.009924)
			(xy 56.040001 -34.971215) (xy 56.085359 -34.938764) (xy 56.134959 -34.913263) (xy 56.187743 -34.895256)
			(xy 56.242586 -34.885126) (xy 56.29832 -34.883089) (xy 56.353757 -34.889189) (xy 56.407714 -34.903295)
			(xy 56.459043 -34.925107) (xy 56.506649 -34.954161) (xy 56.549517 -34.989836) (xy 56.586734 -35.031373)
			(xy 56.617507 -35.077886) (xy 56.641179 -35.128383) (xy 56.657247 -35.18179) (xy 56.665367 -35.236966)
			(xy 56.665876 -35.264852) (xy 56.665367 -35.292738) (xy 56.657247 -35.347914) (xy 56.641179 -35.401321)
			(xy 56.617507 -35.451818) (xy 56.586734 -35.498331) (xy 56.549517 -35.539868) (xy 56.506649 -35.575543)
			(xy 56.459043 -35.604597) (xy 56.407714 -35.626409) (xy 56.353757 -35.640515) (xy 56.29832 -35.646615)
			(xy 56.242586 -35.644578) (xy 56.187743 -35.634448) (xy 56.134959 -35.616441) (xy 56.085359 -35.59094)
			(xy 56.040001 -35.558489) (xy 55.999852 -35.51978) (xy 55.965766 -35.475637) (xy 55.93847 -35.427002)
			(xy 55.918547 -35.374911) (xy 55.906421 -35.320474) (xy 55.90235 -35.264852) (xy 42.546157 -35.264852)
			(xy 42.545989 -35.26504) (xy 42.503121 -35.300715) (xy 42.455515 -35.329769) (xy 42.404186 -35.351581)
			(xy 42.350229 -35.365687) (xy 42.294792 -35.371787) (xy 42.239058 -35.36975) (xy 42.184215 -35.35962)
			(xy 42.131431 -35.341613) (xy 42.081831 -35.316112) (xy 42.036473 -35.283661) (xy 41.996324 -35.244952)
			(xy 41.962238 -35.200809) (xy 41.934942 -35.152174) (xy 41.915019 -35.100083) (xy 41.902893 -35.045646)
			(xy 41.898822 -34.990024) (xy 39.764462 -34.990024) (xy 39.763953 -35.01791) (xy 39.755833 -35.073086)
			(xy 39.739765 -35.126493) (xy 39.716093 -35.17699) (xy 39.68532 -35.223503) (xy 39.648103 -35.26504)
			(xy 39.605235 -35.300715) (xy 39.557629 -35.329769) (xy 39.5063 -35.351581) (xy 39.452343 -35.365687)
			(xy 39.396906 -35.371787) (xy 39.341172 -35.36975) (xy 39.286329 -35.35962) (xy 39.233545 -35.341613)
			(xy 39.183945 -35.316112) (xy 39.138587 -35.283661) (xy 39.098438 -35.244952) (xy 39.064352 -35.200809)
			(xy 39.037056 -35.152174) (xy 39.017133 -35.100083) (xy 39.005007 -35.045646) (xy 39.000936 -34.990024)
			(xy 38.436296 -34.990024) (xy 38.435787 -35.01791) (xy 38.427667 -35.073086) (xy 38.411599 -35.126493)
			(xy 38.387927 -35.17699) (xy 38.357154 -35.223503) (xy 38.319937 -35.26504) (xy 38.277069 -35.300715)
			(xy 38.229463 -35.329769) (xy 38.178134 -35.351581) (xy 38.124177 -35.365687) (xy 38.06874 -35.371787)
			(xy 38.013006 -35.36975) (xy 37.958163 -35.35962) (xy 37.905379 -35.341613) (xy 37.855779 -35.316112)
			(xy 37.810421 -35.283661) (xy 37.770272 -35.244952) (xy 37.736186 -35.200809) (xy 37.70889 -35.152174)
			(xy 37.688967 -35.100083) (xy 37.676841 -35.045646) (xy 37.67277 -34.990024) (xy 36.030408 -34.990024)
			(xy 36.029899 -35.01791) (xy 36.021779 -35.073086) (xy 36.005711 -35.126493) (xy 35.982039 -35.17699)
			(xy 35.951266 -35.223503) (xy 35.914049 -35.26504) (xy 35.871181 -35.300715) (xy 35.823575 -35.329769)
			(xy 35.772246 -35.351581) (xy 35.718289 -35.365687) (xy 35.662852 -35.371787) (xy 35.607118 -35.36975)
			(xy 35.552275 -35.35962) (xy 35.499491 -35.341613) (xy 35.449891 -35.316112) (xy 35.404533 -35.283661)
			(xy 35.364384 -35.244952) (xy 35.330298 -35.200809) (xy 35.303002 -35.152174) (xy 35.283079 -35.100083)
			(xy 35.270953 -35.045646) (xy 35.266882 -34.990024) (xy 34.201604 -34.990024) (xy 34.201608 -34.990278)
			(xy 34.201146 -35.017532) (xy 34.193392 -35.071485) (xy 34.178038 -35.123786) (xy 34.155396 -35.173369)
			(xy 34.125929 -35.219224) (xy 34.090235 -35.26042) (xy 34.049042 -35.296116) (xy 34.003188 -35.325586)
			(xy 33.953606 -35.34823) (xy 33.901307 -35.363587) (xy 33.847354 -35.371345) (xy 33.8201 -35.371786)
			(xy 33.793135 -35.371327) (xy 33.739742 -35.363742) (xy 33.68795 -35.348709) (xy 33.638793 -35.326528)
			(xy 33.593253 -35.297642) (xy 33.552236 -35.262627) (xy 33.516563 -35.222182) (xy 33.486945 -35.177114)
			(xy 33.463972 -35.128322) (xy 33.448104 -35.07678) (xy 33.443418 -35.050222) (xy 33.442148 -35.042856)
			(xy 33.44164 -35.0393) (xy 33.435798 -35.03041) (xy 33.432906 -35.026193) (xy 33.425734 -35.018906)
			(xy 33.421574 -35.015932) (xy 33.358836 -34.974276) (xy 33.354342 -34.971438) (xy 33.344486 -34.967464)
			(xy 33.339278 -34.966402) (xy 33.329372 -34.964624) (xy 33.318958 -34.967164) (xy 33.292264 -34.973308)
			(xy 33.237888 -34.979931) (xy 33.2105 -34.980372) (xy 33.183112 -34.979925) (xy 33.128737 -34.973302)
			(xy 33.102042 -34.967164) (xy 33.091628 -34.964624) (xy 33.081722 -34.966402) (xy 33.076503 -34.967429)
			(xy 33.066638 -34.9714) (xy 33.062164 -34.974276) (xy 32.999426 -35.015932) (xy 32.995255 -35.018893)
			(xy 32.98808 -35.026182) (xy 32.985202 -35.03041) (xy 32.97936 -35.0393) (xy 32.978852 -35.042856)
			(xy 32.977582 -35.050222) (xy 32.972882 -35.076775) (xy 32.95699 -35.128303) (xy 32.934002 -35.177081)
			(xy 32.904377 -35.222138) (xy 32.868705 -35.262575) (xy 32.827696 -35.297589) (xy 32.782166 -35.326481)
			(xy 32.733022 -35.348677) (xy 32.681244 -35.363734) (xy 32.627861 -35.371353) (xy 32.6009 -35.371786)
			(xy 32.57365 -35.3713) (xy 32.519706 -35.363544) (xy 32.467414 -35.348189) (xy 32.41784 -35.32555)
			(xy 32.371992 -35.296085) (xy 32.330804 -35.260396) (xy 32.295115 -35.219208) (xy 32.26565 -35.17336)
			(xy 32.243011 -35.123786) (xy 32.227656 -35.071494) (xy 32.2199 -35.01755) (xy 32.2199 -34.96305)
			(xy 32.227656 -34.909106) (xy 32.243011 -34.856814) (xy 32.26565 -34.80724) (xy 32.295115 -34.761392)
			(xy 32.330804 -34.720204) (xy 32.371992 -34.684515) (xy 32.41784 -34.65505) (xy 32.467414 -34.632411)
			(xy 32.519706 -34.617056) (xy 32.57365 -34.6093) (xy 32.6009 -34.60877) (xy 32.601154 -34.60877)
			(xy 32.618203 -34.60895) (xy 32.652165 -34.612) (xy 32.668972 -34.614866) (xy 32.672883 -34.615466)
			(xy 32.680793 -34.615599) (xy 32.68472 -34.61512) (xy 32.689292 -34.614358) (xy 32.695273 -34.612817)
			(xy 32.70632 -34.607302) (xy 32.711136 -34.603436) (xy 32.73552 -34.582354) (xy 32.741616 -34.576258)
			(xy 32.746935 -34.569069) (xy 32.752767 -34.552178) (xy 32.753046 -34.543238) (xy 32.753046 -34.541714)
			(xy 32.752792 -34.522664) (xy 32.752792 -33.911286) (xy 32.752301 -33.901281) (xy 32.744639 -33.882795)
			(xy 32.730486 -33.868649) (xy 32.711997 -33.860994) (xy 32.701992 -33.860486) (xy 30.30093 -33.860486)
			(xy 30.291672 -33.860838) (xy 30.274344 -33.867351) (xy 30.267148 -33.873186) (xy 30.26029 -33.879282)
			(xy 30.251908 -33.895284) (xy 30.250638 -33.904936) (xy 30.246749 -33.932265) (xy 30.232114 -33.985489)
			(xy 30.209958 -34.036048) (xy 30.180744 -34.082884) (xy 30.145083 -34.125018) (xy 30.103719 -34.161571)
			(xy 30.057518 -34.191778) (xy 30.007444 -34.215008) (xy 29.954544 -34.230776) (xy 29.899923 -34.238752)
			(xy 29.844723 -34.23877) (xy 29.790097 -34.230829) (xy 29.737187 -34.215095) (xy 29.687098 -34.191897)
			(xy 29.640877 -34.16172) (xy 29.59949 -34.125194) (xy 29.563802 -34.083083) (xy 29.534558 -34.036266)
			(xy 29.512369 -33.985722) (xy 29.497699 -33.932507) (xy 29.493718 -33.90519) (xy 29.493718 -33.904428)
			(xy 29.49216 -33.895408) (xy 29.483565 -33.879263) (xy 29.476954 -33.872932) (xy 29.470096 -33.86709)
			(xy 29.452824 -33.860486) (xy 28.81503 -33.860486) (xy 28.802469 -33.86112) (xy 28.780319 -33.872965)
			(xy 28.772866 -33.883092) (xy 28.755086 -33.912048) (xy 28.726384 -33.959292) (xy 28.723201 -33.9649)
			(xy 28.719483 -33.977244) (xy 28.719018 -33.983676) (xy 28.71851 -33.996376) (xy 28.72486 -34.008568)
			(xy 28.738149 -34.035715) (xy 28.75694 -34.09316) (xy 28.766457 -34.152846) (xy 28.767024 -34.183066)
			(xy 28.767024 -34.188654) (xy 28.766096 -34.216931) (xy 28.756924 -34.272757) (xy 28.739608 -34.326617)
			(xy 28.714529 -34.37733) (xy 28.682237 -34.423783) (xy 28.643439 -34.464959) (xy 28.598987 -34.499955)
			(xy 28.549854 -34.528002) (xy 28.497118 -34.548488) (xy 28.441936 -34.560961) (xy 28.385516 -34.56515)
			(xy 28.329096 -34.560961) (xy 28.273914 -34.548488) (xy 28.221178 -34.528002) (xy 28.172045 -34.499955)
			(xy 28.127593 -34.464959) (xy 28.088795 -34.423783) (xy 28.056503 -34.37733) (xy 28.031424 -34.326617)
			(xy 28.014108 -34.272757) (xy 28.004936 -34.216931) (xy 28.004008 -34.188654) (xy 28.004008 -34.183066)
			(xy 28.004559 -34.152844) (xy 28.014053 -34.09315) (xy 28.03286 -34.035706) (xy 28.046172 -34.008568)
			(xy 28.046172 -34.008314) (xy 28.049049 -34.002374) (xy 28.051997 -33.989514) (xy 28.052014 -33.982914)
			(xy 28.051506 -33.970468) (xy 28.015946 -33.912048) (xy 27.998166 -33.883092) (xy 27.990651 -33.87303)
			(xy 27.968542 -33.86118) (xy 27.956002 -33.860486) (xy 22.45614 -33.860486) (xy 22.446112 -33.860899)
			(xy 22.427579 -33.868561) (xy 22.413391 -33.882734) (xy 22.405709 -33.901259) (xy 22.40534 -33.911286)
			(xy 22.40534 -34.24174) (xy 22.405951 -34.252117) (xy 22.414356 -34.271108) (xy 22.421596 -34.27857)
			(xy 22.482048 -34.330132) (xy 22.486231 -34.333529) (xy 22.495711 -34.33865) (xy 22.500844 -34.340292)
			(xy 22.511258 -34.34334) (xy 22.522434 -34.341562) (xy 22.53726 -34.339388) (xy 22.56714 -34.337096)
			(xy 22.582124 -34.33699) (xy 22.582378 -34.33699) (xy 22.609584 -34.337542) (xy 22.663426 -34.345412)
			(xy 22.715603 -34.360851) (xy 22.765058 -34.383548) (xy 22.810786 -34.413041) (xy 22.851859 -34.448732)
			(xy 22.887445 -34.489897) (xy 22.916821 -34.5357) (xy 22.939391 -34.585212) (xy 22.954697 -34.637429)
			(xy 22.962429 -34.691291) (xy 22.96287 -34.718498) (xy 22.962407 -34.74575) (xy 22.95465 -34.799699)
			(xy 22.939294 -34.851995) (xy 22.916651 -34.901573) (xy 22.887182 -34.947424) (xy 22.851488 -34.988613)
			(xy 22.810295 -35.024304) (xy 22.764441 -35.053768) (xy 22.714861 -35.076406) (xy 22.662564 -35.091757)
			(xy 22.608614 -35.099509) (xy 22.581362 -35.100006) (xy 22.581108 -35.100006) (xy 22.551604 -35.099449)
			(xy 22.4933 -35.090353) (xy 22.43709 -35.072394) (xy 22.384313 -35.045998) (xy 22.336228 -35.011794)
			(xy 22.293979 -34.970598) (xy 22.2758 -34.947352) (xy 22.27072 -34.94024) (xy 22.248368 -34.925508)
			(xy 22.244443 -34.922982) (xy 22.235876 -34.919283) (xy 22.23135 -34.918142) (xy 22.20976 -34.913316)
			(xy 22.200747 -34.911714) (xy 22.18264 -34.914303) (xy 22.174454 -34.918396) (xy 22.173946 -34.91865)
			(xy 22.155565 -34.928878) (xy 22.117278 -34.946308) (xy 22.097492 -34.953448) (xy 22.073292 -34.961493)
			(xy 22.023558 -34.972789) (xy 21.972878 -34.978494) (xy 21.947378 -34.978848) (xy 21.921878 -34.978486)
			(xy 21.871197 -34.97279) (xy 21.821464 -34.961493) (xy 21.797264 -34.953448) (xy 21.77748 -34.946302)
			(xy 21.739192 -34.928876) (xy 21.72081 -34.91865) (xy 21.720302 -34.918396) (xy 21.712102 -34.914343)
			(xy 21.694009 -34.911752) (xy 21.684996 -34.913316) (xy 21.663406 -34.918142) (xy 21.658883 -34.919292)
			(xy 21.650318 -34.922992) (xy 21.646388 -34.925508) (xy 21.624036 -34.94024) (xy 21.618956 -34.947352)
			(xy 21.600805 -34.970652) (xy 21.558526 -35.011891) (xy 21.510394 -35.046118) (xy 21.457561 -35.072514)
			(xy 21.401289 -35.090449) (xy 21.342925 -35.099493) (xy 21.313394 -35.100006) (xy 21.302472 -35.100006)
			(xy 21.302218 -35.099752) (xy 21.275505 -35.098513) (xy 21.222797 -35.089485) (xy 21.171865 -35.073187)
			(xy 21.123707 -35.049938) (xy 21.079267 -35.020194) (xy 21.039414 -34.984537) (xy 21.00493 -34.943666)
			(xy 20.976489 -34.89838) (xy 20.954649 -34.849568) (xy 20.939837 -34.798184) (xy 20.932344 -34.745236)
			(xy 20.931886 -34.718498) (xy 20.932372 -34.691247) (xy 20.940129 -34.637299) (xy 20.955484 -34.585004)
			(xy 20.978125 -34.535427) (xy 21.007591 -34.489576) (xy 21.043283 -34.448386) (xy 21.084473 -34.412694)
			(xy 21.130323 -34.383227) (xy 21.1799 -34.360585) (xy 21.232195 -34.345229) (xy 21.286143 -34.337472)
			(xy 21.313394 -34.33699) (xy 21.328187 -34.337132) (xy 21.357685 -34.339417) (xy 21.372322 -34.341562)
			(xy 21.383498 -34.34334) (xy 21.393912 -34.340292) (xy 21.399047 -34.338655) (xy 21.408528 -34.333534)
			(xy 21.412708 -34.330132) (xy 21.47316 -34.27857) (xy 21.480448 -34.271147) (xy 21.488822 -34.252128)
			(xy 21.489416 -34.24174) (xy 21.489416 -33.911286) (xy 21.488926 -33.901279) (xy 21.481264 -33.882789)
			(xy 21.467113 -33.868637) (xy 21.448623 -33.860974) (xy 21.438616 -33.860486) (xy 7.71906 -33.860486)
			(xy 7.709057 -33.86098) (xy 7.690576 -33.868647) (xy 7.676432 -33.882798) (xy 7.668775 -33.901282)
			(xy 7.66826 -33.911286) (xy 7.66826 -34.522156) (xy 7.66826 -34.522664) (xy 7.668006 -34.541714)
			(xy 7.668006 -34.543238) (xy 7.668179 -34.552193) (xy 7.674049 -34.569101) (xy 7.679436 -34.576258)
			(xy 7.685532 -34.582354) (xy 7.709662 -34.603182) (xy 7.717028 -34.608516) (xy 7.725072 -34.612835)
			(xy 7.743029 -34.616075) (xy 7.75208 -34.614866) (xy 7.768891 -34.612024) (xy 7.80285 -34.608974)
			(xy 7.819898 -34.60877) (xy 7.822184 -34.60877) (xy 7.849343 -34.609391) (xy 7.903077 -34.617376)
			(xy 7.955136 -34.632902) (xy 8.004465 -34.655655) (xy 8.050069 -34.685175) (xy 8.091024 -34.720865)
			(xy 8.126503 -34.762003) (xy 8.155789 -34.807758) (xy 8.178288 -34.857204) (xy 8.193546 -34.909341)
			(xy 8.201254 -34.963116) (xy 8.201656 -34.990024) (xy 9.266934 -34.990024) (xy 9.271005 -34.934402)
			(xy 9.283131 -34.879965) (xy 9.303054 -34.827874) (xy 9.33035 -34.779239) (xy 9.364436 -34.735096)
			(xy 9.404585 -34.696387) (xy 9.449943 -34.663936) (xy 9.499543 -34.638435) (xy 9.552327 -34.620428)
			(xy 9.60717 -34.610298) (xy 9.662904 -34.608261) (xy 9.718341 -34.614361) (xy 9.772298 -34.628467)
			(xy 9.823627 -34.650279) (xy 9.871233 -34.679333) (xy 9.914101 -34.715008) (xy 9.951318 -34.756545)
			(xy 9.982091 -34.803058) (xy 10.005763 -34.853555) (xy 10.021831 -34.906962) (xy 10.029951 -34.962138)
			(xy 10.03046 -34.990024) (xy 11.53871 -34.990024) (xy 11.542781 -34.934402) (xy 11.554907 -34.879965)
			(xy 11.57483 -34.827874) (xy 11.602126 -34.779239) (xy 11.636212 -34.735096) (xy 11.676361 -34.696387)
			(xy 11.721719 -34.663936) (xy 11.771319 -34.638435) (xy 11.824103 -34.620428) (xy 11.878946 -34.610298)
			(xy 11.93468 -34.608261) (xy 11.990117 -34.614361) (xy 12.044074 -34.628467) (xy 12.095403 -34.650279)
			(xy 12.143009 -34.679333) (xy 12.185877 -34.715008) (xy 12.223094 -34.756545) (xy 12.253867 -34.803058)
			(xy 12.277539 -34.853555) (xy 12.293607 -34.906962) (xy 12.301727 -34.962138) (xy 12.302236 -34.990024)
			(xy 12.93698 -34.990024) (xy 12.941051 -34.934402) (xy 12.953177 -34.879965) (xy 12.9731 -34.827874)
			(xy 13.000396 -34.779239) (xy 13.034482 -34.735096) (xy 13.074631 -34.696387) (xy 13.119989 -34.663936)
			(xy 13.169589 -34.638435) (xy 13.222373 -34.620428) (xy 13.277216 -34.610298) (xy 13.33295 -34.608261)
			(xy 13.388387 -34.614361) (xy 13.442344 -34.628467) (xy 13.493673 -34.650279) (xy 13.541279 -34.679333)
			(xy 13.584147 -34.715008) (xy 13.621364 -34.756545) (xy 13.652137 -34.803058) (xy 13.675809 -34.853555)
			(xy 13.691877 -34.906962) (xy 13.699997 -34.962138) (xy 13.700506 -34.990024) (xy 15.898874 -34.990024)
			(xy 15.902945 -34.934402) (xy 15.915071 -34.879965) (xy 15.934994 -34.827874) (xy 15.96229 -34.779239)
			(xy 15.996376 -34.735096) (xy 16.036525 -34.696387) (xy 16.081883 -34.663936) (xy 16.131483 -34.638435)
			(xy 16.184267 -34.620428) (xy 16.23911 -34.610298) (xy 16.294844 -34.608261) (xy 16.350281 -34.614361)
			(xy 16.404238 -34.628467) (xy 16.455567 -34.650279) (xy 16.503173 -34.679333) (xy 16.546041 -34.715008)
			(xy 16.583258 -34.756545) (xy 16.614031 -34.803058) (xy 16.637703 -34.853555) (xy 16.653771 -34.906962)
			(xy 16.661891 -34.962138) (xy 16.6624 -34.990024) (xy 16.661891 -35.01791) (xy 16.653771 -35.073086)
			(xy 16.637703 -35.126493) (xy 16.614031 -35.17699) (xy 16.583258 -35.223503) (xy 16.546209 -35.264852)
			(xy 29.902402 -35.264852) (xy 29.906473 -35.20923) (xy 29.918599 -35.154793) (xy 29.938522 -35.102702)
			(xy 29.965818 -35.054067) (xy 29.999904 -35.009924) (xy 30.040053 -34.971215) (xy 30.085411 -34.938764)
			(xy 30.135011 -34.913263) (xy 30.187795 -34.895256) (xy 30.242638 -34.885126) (xy 30.298372 -34.883089)
			(xy 30.353809 -34.889189) (xy 30.407766 -34.903295) (xy 30.459095 -34.925107) (xy 30.506701 -34.954161)
			(xy 30.549569 -34.989836) (xy 30.586786 -35.031373) (xy 30.617559 -35.077886) (xy 30.641231 -35.128383)
			(xy 30.657299 -35.18179) (xy 30.665419 -35.236966) (xy 30.665928 -35.264852) (xy 30.665419 -35.292738)
			(xy 30.657299 -35.347914) (xy 30.641231 -35.401321) (xy 30.617559 -35.451818) (xy 30.586786 -35.498331)
			(xy 30.549569 -35.539868) (xy 30.506701 -35.575543) (xy 30.459095 -35.604597) (xy 30.407766 -35.626409)
			(xy 30.353809 -35.640515) (xy 30.298372 -35.646615) (xy 30.242638 -35.644578) (xy 30.187795 -35.634448)
			(xy 30.135011 -35.616441) (xy 30.085411 -35.59094) (xy 30.040053 -35.558489) (xy 29.999904 -35.51978)
			(xy 29.965818 -35.475637) (xy 29.938522 -35.427002) (xy 29.918599 -35.374911) (xy 29.906473 -35.320474)
			(xy 29.902402 -35.264852) (xy 16.546209 -35.264852) (xy 16.546041 -35.26504) (xy 16.503173 -35.300715)
			(xy 16.455567 -35.329769) (xy 16.404238 -35.351581) (xy 16.350281 -35.365687) (xy 16.294844 -35.371787)
			(xy 16.23911 -35.36975) (xy 16.184267 -35.35962) (xy 16.131483 -35.341613) (xy 16.081883 -35.316112)
			(xy 16.036525 -35.283661) (xy 15.996376 -35.244952) (xy 15.96229 -35.200809) (xy 15.934994 -35.152174)
			(xy 15.915071 -35.100083) (xy 15.902945 -35.045646) (xy 15.898874 -34.990024) (xy 13.700506 -34.990024)
			(xy 13.699997 -35.01791) (xy 13.691877 -35.073086) (xy 13.675809 -35.126493) (xy 13.652137 -35.17699)
			(xy 13.621364 -35.223503) (xy 13.584147 -35.26504) (xy 13.541279 -35.300715) (xy 13.493673 -35.329769)
			(xy 13.442344 -35.351581) (xy 13.388387 -35.365687) (xy 13.33295 -35.371787) (xy 13.277216 -35.36975)
			(xy 13.222373 -35.35962) (xy 13.169589 -35.341613) (xy 13.119989 -35.316112) (xy 13.074631 -35.283661)
			(xy 13.034482 -35.244952) (xy 13.000396 -35.200809) (xy 12.9731 -35.152174) (xy 12.953177 -35.100083)
			(xy 12.941051 -35.045646) (xy 12.93698 -34.990024) (xy 12.302236 -34.990024) (xy 12.301727 -35.01791)
			(xy 12.293607 -35.073086) (xy 12.277539 -35.126493) (xy 12.253867 -35.17699) (xy 12.223094 -35.223503)
			(xy 12.185877 -35.26504) (xy 12.143009 -35.300715) (xy 12.095403 -35.329769) (xy 12.044074 -35.351581)
			(xy 11.990117 -35.365687) (xy 11.93468 -35.371787) (xy 11.878946 -35.36975) (xy 11.824103 -35.35962)
			(xy 11.771319 -35.341613) (xy 11.721719 -35.316112) (xy 11.676361 -35.283661) (xy 11.636212 -35.244952)
			(xy 11.602126 -35.200809) (xy 11.57483 -35.152174) (xy 11.554907 -35.100083) (xy 11.542781 -35.045646)
			(xy 11.53871 -34.990024) (xy 10.03046 -34.990024) (xy 10.029951 -35.01791) (xy 10.021831 -35.073086)
			(xy 10.005763 -35.126493) (xy 9.982091 -35.17699) (xy 9.951318 -35.223503) (xy 9.914101 -35.26504)
			(xy 9.871233 -35.300715) (xy 9.823627 -35.329769) (xy 9.772298 -35.351581) (xy 9.718341 -35.365687)
			(xy 9.662904 -35.371787) (xy 9.60717 -35.36975) (xy 9.552327 -35.35962) (xy 9.499543 -35.341613)
			(xy 9.449943 -35.316112) (xy 9.404585 -35.283661) (xy 9.364436 -35.244952) (xy 9.33035 -35.200809)
			(xy 9.303054 -35.152174) (xy 9.283131 -35.100083) (xy 9.271005 -35.045646) (xy 9.266934 -34.990024)
			(xy 8.201656 -34.990024) (xy 8.20166 -34.990278) (xy 8.201198 -35.017531) (xy 8.193443 -35.071481)
			(xy 8.178089 -35.123779) (xy 8.155447 -35.173359) (xy 8.125979 -35.219211) (xy 8.090284 -35.260403)
			(xy 8.049091 -35.296094) (xy 8.003236 -35.325559) (xy 7.953655 -35.348198) (xy 7.901356 -35.363549)
			(xy 7.847405 -35.3713) (xy 7.820152 -35.371786) (xy 7.793189 -35.371323) (xy 7.739801 -35.363733)
			(xy 7.688015 -35.348696) (xy 7.638864 -35.326512) (xy 7.593329 -35.297624) (xy 7.552318 -35.262609)
			(xy 7.51665 -35.222165) (xy 7.487036 -35.177099) (xy 7.464068 -35.12831) (xy 7.448202 -35.076771)
			(xy 7.44347 -35.050222) (xy 7.4422 -35.042856) (xy 7.441692 -35.0393) (xy 7.43585 -35.03041) (xy 7.43296 -35.02619)
			(xy 7.425793 -35.018898) (xy 7.421626 -35.015932) (xy 7.358888 -34.974276) (xy 7.354392 -34.971442)
			(xy 7.344535 -34.967477) (xy 7.33933 -34.966402) (xy 7.329424 -34.964624) (xy 7.31901 -34.967164)
			(xy 7.292316 -34.973305) (xy 7.23794 -34.979922) (xy 7.210552 -34.980372) (xy 7.183164 -34.979928)
			(xy 7.128787 -34.973311) (xy 7.102094 -34.967164) (xy 7.09168 -34.964624) (xy 7.081774 -34.966402)
			(xy 7.076557 -34.967434) (xy 7.066698 -34.971412) (xy 7.062216 -34.974276) (xy 6.999478 -35.015932)
			(xy 6.995309 -35.018895) (xy 6.988141 -35.026188) (xy 6.985254 -35.03041) (xy 6.979412 -35.0393)
			(xy 6.978904 -35.042856) (xy 6.977634 -35.050222) (xy 6.972934 -35.076774) (xy 6.957041 -35.128299)
			(xy 6.934052 -35.177073) (xy 6.904426 -35.222126) (xy 6.868753 -35.26256) (xy 6.827743 -35.297569)
			(xy 6.782213 -35.326456) (xy 6.73307 -35.348646) (xy 6.681293 -35.363697) (xy 6.627912 -35.371309)
			(xy 6.600952 -35.371786) (xy 6.573699 -35.371323) (xy 6.519748 -35.363566) (xy 6.467451 -35.34821)
			(xy 6.41787 -35.325568) (xy 6.372017 -35.2961) (xy 6.330825 -35.260407) (xy 6.295131 -35.219214)
			(xy 6.265663 -35.173361) (xy 6.24302 -35.123781) (xy 6.227664 -35.071484) (xy 6.219907 -35.017533)
			(xy 6.219907 -34.963027) (xy 6.227664 -34.909076) (xy 6.24302 -34.856779) (xy 6.265663 -34.807199)
			(xy 6.295131 -34.761346) (xy 6.330825 -34.720153) (xy 6.372017 -34.68446) (xy 6.41787 -34.654992)
			(xy 6.467451 -34.63235) (xy 6.519748 -34.616994) (xy 6.573699 -34.609237) (xy 6.600952 -34.60877)
			(xy 6.601206 -34.60877) (xy 6.618255 -34.608953) (xy 6.652216 -34.612007) (xy 6.669024 -34.614866)
			(xy 6.672935 -34.615462) (xy 6.680844 -34.615587) (xy 6.684772 -34.61512) (xy 6.689344 -34.614358)
			(xy 6.695322 -34.612812) (xy 6.706362 -34.607288) (xy 6.711188 -34.603436) (xy 6.735572 -34.582354)
			(xy 6.741668 -34.576258) (xy 6.746991 -34.56907) (xy 6.752828 -34.552179) (xy 6.753098 -34.543238)
			(xy 6.753098 -34.541714) (xy 6.752844 -34.522664) (xy 6.752844 -33.911286) (xy 6.752354 -33.901277)
			(xy 6.744694 -33.882782) (xy 6.730543 -33.868623) (xy 6.712053 -33.860952) (xy 6.702044 -33.860486)
			(xy 5.455412 -33.860486) (xy 5.447373 -33.860841) (xy 5.432098 -33.865875) (xy 5.42544 -33.870392)
			(xy 5.41909 -33.874964) (xy 5.409692 -33.887918) (xy 5.407152 -33.896046) (xy 5.398146 -33.923032)
			(xy 5.373261 -33.974191) (xy 5.341055 -34.021087) (xy 5.30224 -34.062678) (xy 5.257679 -34.098044)
			(xy 5.208359 -34.126399) (xy 5.155375 -34.147113) (xy 5.099902 -34.159729) (xy 5.04317 -34.163966)
			(xy 4.986438 -34.159729) (xy 4.930965 -34.147113) (xy 4.877981 -34.126399) (xy 4.828661 -34.098044)
			(xy 4.7841 -34.062678) (xy 4.745285 -34.021087) (xy 4.713079 -33.974191) (xy 4.688194 -33.923032)
			(xy 4.679188 -33.896046) (xy 4.679188 -33.895792) (xy 4.676458 -33.888194) (xy 4.666999 -33.875121)
			(xy 4.660646 -33.870138) (xy 4.654296 -33.865566) (xy 4.639056 -33.860486) (xy 4.22402 -33.860486)
			(xy 4.215825 -33.860792) (xy 4.200275 -33.865968) (xy 4.19354 -33.870646) (xy 4.186682 -33.875726)
			(xy 4.177792 -33.888934) (xy 4.175252 -33.897062) (xy 4.167197 -33.92316) (xy 4.144659 -33.972909)
			(xy 4.115254 -34.018935) (xy 4.079585 -34.060295) (xy 4.038381 -34.096145) (xy 3.992484 -34.12575)
			(xy 3.942834 -34.148506) (xy 3.890445 -34.163946) (xy 3.83639 -34.171755) (xy 3.781773 -34.171774)
			(xy 3.727712 -34.164002) (xy 3.675313 -34.148598) (xy 3.625647 -34.125876) (xy 3.57973 -34.096303)
			(xy 3.538501 -34.060482) (xy 3.502803 -34.019146) (xy 3.473367 -33.97314) (xy 3.450794 -33.923407)
			(xy 3.442716 -33.897316) (xy 3.442716 -33.896808) (xy 3.440113 -33.889089) (xy 3.430779 -33.875749)
			(xy 3.424428 -33.870646) (xy 3.417824 -33.865566) (xy 3.40233 -33.860486) (xy 3.2893 -33.860486)
			(xy 3.28235 -33.860729) (xy 3.268961 -33.86447) (xy 3.262884 -33.867852) (xy 3.26263 -33.867852)
			(xy 3.256849 -33.871598) (xy 3.247432 -33.881643) (xy 3.244088 -33.887664) (xy 3.230813 -33.911964)
			(xy 3.198313 -33.956794) (xy 3.159671 -33.996452) (xy 3.115699 -34.030103) (xy 3.067322 -34.057039)
			(xy 3.015557 -34.076695) (xy 2.961493 -34.088656) (xy 2.906268 -34.092671) (xy 2.851043 -34.088656)
			(xy 2.796979 -34.076695) (xy 2.745214 -34.057039) (xy 2.696837 -34.030103) (xy 2.652865 -33.996452)
			(xy 2.614223 -33.956794) (xy 2.581723 -33.911964) (xy 2.568448 -33.887664) (xy 2.565146 -33.881568)
			(xy 2.555748 -33.871662) (xy 2.549652 -33.867852) (xy 2.543599 -33.864412) (xy 2.530195 -33.860664)
			(xy 2.523236 -33.860486) (xy 2.39014 -33.860486) (xy 2.384131 -33.860654) (xy 2.372449 -33.863479)
			(xy 2.367026 -33.866074) (xy 2.363549 -33.86791) (xy 2.357165 -33.872498) (xy 2.354326 -33.875218)
			(xy 2.290826 -33.938718) (xy 2.284699 -33.945401) (xy 2.277198 -33.961893) (xy 2.275914 -33.979965)
			(xy 2.278126 -33.988756) (xy 2.30886 -34.077656) (xy 2.311423 -34.084359) (xy 2.31967 -34.096096)
			(xy 2.325116 -34.10077) (xy 2.330704 -34.105342) (xy 2.343404 -34.110422) (xy 2.351024 -34.111438)
			(xy 2.378543 -34.115149) (xy 2.432181 -34.129506) (xy 2.483172 -34.151487) (xy 2.530437 -34.180629)
			(xy 2.572978 -34.216315) (xy 2.609896 -34.257791) (xy 2.64041 -34.304182) (xy 2.663876 -34.354506)
			(xy 2.679799 -34.407701) (xy 2.687841 -34.462643) (xy 2.688336 -34.490406) (xy 2.687882 -34.517233)
			(xy 2.680371 -34.570358) (xy 2.665494 -34.621908) (xy 2.643545 -34.670866) (xy 2.614957 -34.716269)
			(xy 2.580293 -34.757221) (xy 2.540235 -34.792915) (xy 2.518156 -34.80816) (xy 2.517902 -34.808414)
			(xy 2.512887 -34.811944) (xy 2.504549 -34.820935) (xy 2.501392 -34.826194) (xy 2.498598 -34.831528)
			(xy 2.49555 -34.843466) (xy 2.494788 -34.934144) (xy 2.494981 -34.940437) (xy 2.498074 -34.952639)
			(xy 2.500884 -34.958274) (xy 2.503815 -34.963461) (xy 2.511644 -34.972436) (xy 2.516378 -34.976054)
			(xy 2.516886 -34.976308) (xy 2.53836 -34.991639) (xy 2.577275 -35.027268) (xy 2.610908 -35.06792)
			(xy 2.638619 -35.112819) (xy 2.659879 -35.161108) (xy 2.674281 -35.211866) (xy 2.681551 -35.264125)
			(xy 2.681986 -35.290506) (xy 2.681523 -35.317759) (xy 2.673766 -35.37171) (xy 2.658411 -35.424008)
			(xy 2.635768 -35.473589) (xy 2.6063 -35.519442) (xy 2.570607 -35.560635) (xy 2.529414 -35.596329)
			(xy 2.483561 -35.625797) (xy 2.43398 -35.64844) (xy 2.381682 -35.663796) (xy 2.327731 -35.671553)
			(xy 2.300478 -35.672014) (xy 2.300224 -35.672014) (xy 2.270998 -35.671432) (xy 2.213234 -35.662482)
			(xy 2.157504 -35.644847) (xy 2.13106 -35.63239) (xy 2.121662 -35.627818) (xy 2.108454 -35.628326)
			(xy 2.101983 -35.628865) (xy 2.089625 -35.632839) (xy 2.08407 -35.6362) (xy 2.009648 -35.682682)
			(xy 2.002166 -35.688229) (xy 1.991494 -35.703476) (xy 1.98882 -35.7124) (xy 1.987296 -35.724846)
			(xy 1.987296 -35.91941) (xy 2.665728 -35.91941) (xy 2.669799 -35.863788) (xy 2.681925 -35.809351)
			(xy 2.701848 -35.75726) (xy 2.729144 -35.708625) (xy 2.76323 -35.664482) (xy 2.803379 -35.625773)
			(xy 2.848737 -35.593322) (xy 2.898337 -35.567821) (xy 2.951121 -35.549814) (xy 3.005964 -35.539684)
			(xy 3.061698 -35.537647) (xy 3.117135 -35.543747) (xy 3.171092 -35.557853) (xy 3.222421 -35.579665)
			(xy 3.270027 -35.608719) (xy 3.312895 -35.644394) (xy 3.350112 -35.685931) (xy 3.380885 -35.732444)
			(xy 3.404557 -35.782941) (xy 3.420625 -35.836348) (xy 3.427317 -35.881818) (xy 3.668774 -35.881818)
			(xy 3.672845 -35.826196) (xy 3.684971 -35.771759) (xy 3.704894 -35.719668) (xy 3.73219 -35.671033)
			(xy 3.766276 -35.62689) (xy 3.806425 -35.588181) (xy 3.851783 -35.55573) (xy 3.901383 -35.530229)
			(xy 3.954167 -35.512222) (xy 4.00901 -35.502092) (xy 4.064744 -35.500055) (xy 4.120181 -35.506155)
			(xy 4.174138 -35.520261) (xy 4.225467 -35.542073) (xy 4.273073 -35.571127) (xy 4.315941 -35.606802)
			(xy 4.353158 -35.648339) (xy 4.383931 -35.694852) (xy 4.407603 -35.745349) (xy 4.423671 -35.798756)
			(xy 4.431791 -35.853932) (xy 4.4323 -35.881818) (xy 4.43186 -35.905948) (xy 4.661152 -35.905948)
			(xy 4.665223 -35.850326) (xy 4.677349 -35.795889) (xy 4.697272 -35.743798) (xy 4.724568 -35.695163)
			(xy 4.758654 -35.65102) (xy 4.798803 -35.612311) (xy 4.844161 -35.57986) (xy 4.893761 -35.554359)
			(xy 4.946545 -35.536352) (xy 5.001388 -35.526222) (xy 5.057122 -35.524185) (xy 5.112559 -35.530285)
			(xy 5.166516 -35.544391) (xy 5.217845 -35.566203) (xy 5.265451 -35.595257) (xy 5.308319 -35.630932)
			(xy 5.345536 -35.672469) (xy 5.376309 -35.718982) (xy 5.399981 -35.769479) (xy 5.416049 -35.822886)
			(xy 5.424169 -35.878062) (xy 5.424678 -35.905948) (xy 5.424169 -35.933834) (xy 5.416049 -35.98901)
			(xy 5.399981 -36.042417) (xy 5.376309 -36.092914) (xy 5.345536 -36.139427) (xy 5.308319 -36.180964)
			(xy 5.265451 -36.216639) (xy 5.217845 -36.245693) (xy 5.166516 -36.267505) (xy 5.112559 -36.281611)
			(xy 5.057122 -36.287711) (xy 5.001388 -36.285674) (xy 4.946545 -36.275544) (xy 4.893761 -36.257537)
			(xy 4.844161 -36.232036) (xy 4.798803 -36.199585) (xy 4.758654 -36.160876) (xy 4.724568 -36.116733)
			(xy 4.697272 -36.068098) (xy 4.677349 -36.016007) (xy 4.665223 -35.96157) (xy 4.661152 -35.905948)
			(xy 4.43186 -35.905948) (xy 4.431791 -35.909704) (xy 4.423671 -35.96488) (xy 4.407603 -36.018287)
			(xy 4.383931 -36.068784) (xy 4.353158 -36.115297) (xy 4.315941 -36.156834) (xy 4.273073 -36.192509)
			(xy 4.225467 -36.221563) (xy 4.174138 -36.243375) (xy 4.120181 -36.257481) (xy 4.064744 -36.263581)
			(xy 4.00901 -36.261544) (xy 3.954167 -36.251414) (xy 3.901383 -36.233407) (xy 3.851783 -36.207906)
			(xy 3.806425 -36.175455) (xy 3.766276 -36.136746) (xy 3.73219 -36.092603) (xy 3.704894 -36.043968)
			(xy 3.684971 -35.991877) (xy 3.672845 -35.93744) (xy 3.668774 -35.881818) (xy 3.427317 -35.881818)
			(xy 3.428745 -35.891524) (xy 3.429254 -35.91941) (xy 3.428745 -35.947296) (xy 3.420625 -36.002472)
			(xy 3.404557 -36.055879) (xy 3.380885 -36.106376) (xy 3.350112 -36.152889) (xy 3.312895 -36.194426)
			(xy 3.270027 -36.230101) (xy 3.222421 -36.259155) (xy 3.171092 -36.280967) (xy 3.117135 -36.295073)
			(xy 3.061698 -36.301173) (xy 3.005964 -36.299136) (xy 2.951121 -36.289006) (xy 2.898337 -36.270999)
			(xy 2.848737 -36.245498) (xy 2.803379 -36.213047) (xy 2.76323 -36.174338) (xy 2.729144 -36.130195)
			(xy 2.701848 -36.08156) (xy 2.681925 -36.029469) (xy 2.669799 -35.975032) (xy 2.665728 -35.91941)
			(xy 1.987296 -35.91941) (xy 1.987296 -36.760912) (xy 3.474718 -36.760912) (xy 3.478789 -36.70529)
			(xy 3.490915 -36.650853) (xy 3.510838 -36.598762) (xy 3.538134 -36.550127) (xy 3.57222 -36.505984)
			(xy 3.612369 -36.467275) (xy 3.657727 -36.434824) (xy 3.707327 -36.409323) (xy 3.760111 -36.391316)
			(xy 3.814954 -36.381186) (xy 3.870688 -36.379149) (xy 3.926125 -36.385249) (xy 3.980082 -36.399355)
			(xy 4.031411 -36.421167) (xy 4.079017 -36.450221) (xy 4.121885 -36.485896) (xy 4.159102 -36.527433)
			(xy 4.189875 -36.573946) (xy 4.213547 -36.624443) (xy 4.229615 -36.67785) (xy 4.237735 -36.733026)
			(xy 4.238244 -36.760912) (xy 4.490718 -36.760912) (xy 4.494789 -36.70529) (xy 4.506915 -36.650853)
			(xy 4.526838 -36.598762) (xy 4.554134 -36.550127) (xy 4.58822 -36.505984) (xy 4.628369 -36.467275)
			(xy 4.673727 -36.434824) (xy 4.723327 -36.409323) (xy 4.776111 -36.391316) (xy 4.830954 -36.381186)
			(xy 4.886688 -36.379149) (xy 4.942125 -36.385249) (xy 4.996082 -36.399355) (xy 5.047411 -36.421167)
			(xy 5.095017 -36.450221) (xy 5.137885 -36.485896) (xy 5.175102 -36.527433) (xy 5.205875 -36.573946)
			(xy 5.229547 -36.624443) (xy 5.245615 -36.67785) (xy 5.253735 -36.733026) (xy 5.254244 -36.760912)
			(xy 5.506718 -36.760912) (xy 5.510789 -36.70529) (xy 5.522915 -36.650853) (xy 5.542838 -36.598762)
			(xy 5.570134 -36.550127) (xy 5.60422 -36.505984) (xy 5.644369 -36.467275) (xy 5.689727 -36.434824)
			(xy 5.739327 -36.409323) (xy 5.792111 -36.391316) (xy 5.846954 -36.381186) (xy 5.902688 -36.379149)
			(xy 5.958125 -36.385249) (xy 6.012082 -36.399355) (xy 6.063411 -36.421167) (xy 6.111017 -36.450221)
			(xy 6.153885 -36.485896) (xy 6.191102 -36.527433) (xy 6.221875 -36.573946) (xy 6.245547 -36.624443)
			(xy 6.261615 -36.67785) (xy 6.269735 -36.733026) (xy 6.270244 -36.760912) (xy 6.269735 -36.788798)
			(xy 6.261615 -36.843974) (xy 6.245547 -36.897381) (xy 6.221875 -36.947878) (xy 6.191102 -36.994391)
			(xy 6.153885 -37.035928) (xy 6.111017 -37.071603) (xy 6.063411 -37.100657) (xy 6.012082 -37.122469)
			(xy 5.958125 -37.136575) (xy 5.902688 -37.142675) (xy 5.846954 -37.140638) (xy 5.792111 -37.130508)
			(xy 5.739327 -37.112501) (xy 5.689727 -37.087) (xy 5.644369 -37.054549) (xy 5.60422 -37.01584) (xy 5.570134 -36.971697)
			(xy 5.542838 -36.923062) (xy 5.522915 -36.870971) (xy 5.510789 -36.816534) (xy 5.506718 -36.760912)
			(xy 5.254244 -36.760912) (xy 5.253735 -36.788798) (xy 5.245615 -36.843974) (xy 5.229547 -36.897381)
			(xy 5.205875 -36.947878) (xy 5.175102 -36.994391) (xy 5.137885 -37.035928) (xy 5.095017 -37.071603)
			(xy 5.047411 -37.100657) (xy 4.996082 -37.122469) (xy 4.942125 -37.136575) (xy 4.886688 -37.142675)
			(xy 4.830954 -37.140638) (xy 4.776111 -37.130508) (xy 4.723327 -37.112501) (xy 4.673727 -37.087)
			(xy 4.628369 -37.054549) (xy 4.58822 -37.01584) (xy 4.554134 -36.971697) (xy 4.526838 -36.923062)
			(xy 4.506915 -36.870971) (xy 4.494789 -36.816534) (xy 4.490718 -36.760912) (xy 4.238244 -36.760912)
			(xy 4.237735 -36.788798) (xy 4.229615 -36.843974) (xy 4.213547 -36.897381) (xy 4.189875 -36.947878)
			(xy 4.159102 -36.994391) (xy 4.121885 -37.035928) (xy 4.079017 -37.071603) (xy 4.031411 -37.100657)
			(xy 3.980082 -37.122469) (xy 3.926125 -37.136575) (xy 3.870688 -37.142675) (xy 3.814954 -37.140638)
			(xy 3.760111 -37.130508) (xy 3.707327 -37.112501) (xy 3.657727 -37.087) (xy 3.612369 -37.054549)
			(xy 3.57222 -37.01584) (xy 3.538134 -36.971697) (xy 3.510838 -36.923062) (xy 3.490915 -36.870971)
			(xy 3.478789 -36.816534) (xy 3.474718 -36.760912) (xy 1.987296 -36.760912) (xy 1.987296 -41.166542)
			(xy 2.403856 -41.166542) (xy 2.404383 -41.137625) (xy 2.413107 -41.080453) (xy 2.430362 -41.025254)
			(xy 2.455752 -40.973292) (xy 2.488695 -40.925758) (xy 2.528436 -40.883741) (xy 2.550922 -40.865552)
			(xy 2.559745 -40.85796) (xy 2.569919 -40.837048) (xy 2.57048 -40.82542) (xy 2.57048 -40.745664) (xy 2.569954 -40.73403)
			(xy 2.559757 -40.713121) (xy 2.550922 -40.705532) (xy 2.528438 -40.687342) (xy 2.488703 -40.645322)
			(xy 2.455764 -40.597787) (xy 2.430376 -40.545825) (xy 2.41312 -40.490628) (xy 2.404391 -40.433458)
			(xy 2.403856 -40.404542) (xy 2.40428 -40.377296) (xy 2.412045 -40.32336) (xy 2.427411 -40.271078)
			(xy 2.450062 -40.221517) (xy 2.479539 -40.175685) (xy 2.51524 -40.134516) (xy 2.556438 -40.098849)
			(xy 2.579116 -40.08374) (xy 2.586107 -40.078848) (xy 2.596662 -40.065462) (xy 2.602203 -40.04934)
			(xy 2.602484 -40.040814) (xy 2.602484 -39.95547) (xy 2.602176 -39.946949) (xy 2.596624 -39.930837)
			(xy 2.586106 -39.917427) (xy 2.579116 -39.912544) (xy 2.556441 -39.897433) (xy 2.515246 -39.861766)
			(xy 2.47955 -39.820596) (xy 2.450079 -39.774764) (xy 2.427434 -39.725203) (xy 2.412076 -39.672922)
			(xy 2.404319 -39.618987) (xy 2.403856 -39.591742) (xy 2.404383 -39.562825) (xy 2.413107 -39.505653)
			(xy 2.430362 -39.450454) (xy 2.455752 -39.398492) (xy 2.488695 -39.350958) (xy 2.528436 -39.308941)
			(xy 2.550922 -39.290752) (xy 2.559745 -39.28316) (xy 2.569919 -39.262248) (xy 2.57048 -39.25062)
			(xy 2.57048 -39.170864) (xy 2.569954 -39.15923) (xy 2.559757 -39.138321) (xy 2.550922 -39.130732)
			(xy 2.528438 -39.112542) (xy 2.488703 -39.070522) (xy 2.455764 -39.022987) (xy 2.430376 -38.971025)
			(xy 2.41312 -38.915828) (xy 2.404391 -38.858658) (xy 2.403856 -38.829742) (xy 2.404317 -38.802489)
			(xy 2.412074 -38.748538) (xy 2.42743 -38.69624) (xy 2.450073 -38.646659) (xy 2.479541 -38.600806)
			(xy 2.515235 -38.559613) (xy 2.556428 -38.52392) (xy 2.602281 -38.494452) (xy 2.651862 -38.471809)
			(xy 2.70416 -38.456454) (xy 2.758111 -38.448697) (xy 2.785364 -38.448234) (xy 2.81484 -38.448792)
			(xy 2.87309 -38.457856) (xy 2.929253 -38.475774) (xy 2.981991 -38.502118) (xy 3.030047 -38.536263)
			(xy 3.040664 -38.546603) (xy 6.274009 -38.546603) (xy 6.274009 -38.492097) (xy 6.281766 -38.438147)
			(xy 6.297122 -38.385849) (xy 6.319765 -38.336269) (xy 6.349233 -38.290416) (xy 6.384927 -38.249224)
			(xy 6.426119 -38.213531) (xy 6.471973 -38.184063) (xy 6.521553 -38.161421) (xy 6.57385 -38.146065)
			(xy 6.627801 -38.138309) (xy 6.655054 -38.137846) (xy 6.683971 -38.13838) (xy 6.741142 -38.147103)
			(xy 6.796341 -38.164357) (xy 6.848303 -38.189745) (xy 6.895837 -38.222687) (xy 6.937854 -38.262427)
			(xy 6.956044 -38.284912) (xy 6.96364 -38.293731) (xy 6.984549 -38.303908) (xy 6.996176 -38.30447)
			(xy 7.075932 -38.30447) (xy 7.087566 -38.303946) (xy 7.108476 -38.293747) (xy 7.116064 -38.284912)
			(xy 7.134278 -38.262448) (xy 7.176293 -38.222711) (xy 7.223823 -38.18977) (xy 7.27578 -38.164378)
			(xy 7.330973 -38.147117) (xy 7.388139 -38.138384) (xy 7.417054 -38.137846) (xy 7.444305 -38.138324)
			(xy 7.498253 -38.146081) (xy 7.550548 -38.161437) (xy 7.600125 -38.184078) (xy 7.614753 -38.193479)
			(xy 11.098251 -38.193479) (xy 11.098251 -38.106601) (xy 11.106267 -38.020094) (xy 11.122231 -37.934695)
			(xy 11.146006 -37.851134) (xy 11.17739 -37.770122) (xy 11.216115 -37.692352) (xy 11.26185 -37.618487)
			(xy 11.314206 -37.549157) (xy 11.372735 -37.484954) (xy 11.436939 -37.426425) (xy 11.506269 -37.374069)
			(xy 11.580134 -37.328334) (xy 11.657904 -37.289609) (xy 11.738915 -37.258225) (xy 11.822477 -37.23445)
			(xy 11.907876 -37.218486) (xy 11.994383 -37.210471) (xy 12.037822 -37.209984) (xy 12.1158 -37.209984)
			(xy 12.125823 -37.20958) (xy 12.144343 -37.201907) (xy 12.158516 -37.18773) (xy 12.166183 -37.169207)
			(xy 12.1666 -37.159184) (xy 12.1666 -37.151564) (xy 12.162282 -37.137594) (xy 12.158218 -37.131244)
			(xy 12.134299 -37.094009) (xy 12.092598 -37.015944) (xy 12.058213 -36.93439) (xy 12.031435 -36.850033)
			(xy 12.012486 -36.76358) (xy 12.001526 -36.675755) (xy 11.998648 -36.587297) (xy 12.003875 -36.498946)
			(xy 12.017163 -36.411443) (xy 12.038401 -36.325524) (xy 12.06741 -36.241908) (xy 12.103948 -36.161296)
			(xy 12.147709 -36.084366) (xy 12.198323 -36.011762) (xy 12.255369 -35.944093) (xy 12.318366 -35.881927)
			(xy 12.386786 -35.825786) (xy 12.460056 -35.776139) (xy 12.537561 -35.733405) (xy 12.61865 -35.69794)
			(xy 12.702644 -35.670044) (xy 12.788838 -35.649948) (xy 12.876509 -35.637824) (xy 12.964922 -35.633771)
			(xy 13.053335 -35.637824) (xy 13.141006 -35.649948) (xy 13.2272 -35.670044) (xy 13.311194 -35.69794)
			(xy 13.392283 -35.733405) (xy 13.469788 -35.776139) (xy 13.543058 -35.825786) (xy 13.605154 -35.876738)
			(xy 18.717258 -35.876738) (xy 18.721329 -35.821116) (xy 18.733455 -35.766679) (xy 18.753378 -35.714588)
			(xy 18.780674 -35.665953) (xy 18.81476 -35.62181) (xy 18.854909 -35.583101) (xy 18.900267 -35.55065)
			(xy 18.949867 -35.525149) (xy 19.002651 -35.507142) (xy 19.057494 -35.497012) (xy 19.113228 -35.494975)
			(xy 19.168665 -35.501075) (xy 19.222622 -35.515181) (xy 19.273951 -35.536993) (xy 19.321557 -35.566047)
			(xy 19.364425 -35.601722) (xy 19.401642 -35.643259) (xy 19.432415 -35.689772) (xy 19.456087 -35.740269)
			(xy 19.472155 -35.793676) (xy 19.480275 -35.848852) (xy 19.480784 -35.876738) (xy 22.789388 -35.876738)
			(xy 22.789874 -35.849487) (xy 22.79763 -35.795539) (xy 22.812985 -35.743244) (xy 22.835627 -35.693667)
			(xy 22.865093 -35.647817) (xy 22.900784 -35.606626) (xy 22.941975 -35.570935) (xy 22.987825 -35.541469)
			(xy 23.037402 -35.518827) (xy 23.089697 -35.503472) (xy 23.143645 -35.495716) (xy 23.198147 -35.495716)
			(xy 23.252095 -35.503472) (xy 23.30439 -35.518827) (xy 23.353967 -35.541469) (xy 23.399817 -35.570935)
			(xy 23.441008 -35.606626) (xy 23.476699 -35.647817) (xy 23.506165 -35.693667) (xy 23.528807 -35.743244)
			(xy 23.544162 -35.795539) (xy 23.551918 -35.849487) (xy 23.552404 -35.876738) (xy 23.551879 -35.905485)
			(xy 23.543214 -35.962323) (xy 23.526116 -36.017217) (xy 23.500973 -36.068923) (xy 23.485094 -36.092892)
			(xy 23.477483 -36.104722) (xy 23.468486 -36.131366) (xy 23.467098 -36.159453) (xy 23.473425 -36.186853)
			(xy 23.486986 -36.211489) (xy 23.506754 -36.23149) (xy 23.531228 -36.24534) (xy 23.544784 -36.249102)
			(xy 23.57205 -36.256313) (xy 23.624227 -36.277717) (xy 23.672687 -36.306568) (xy 23.716372 -36.342237)
			(xy 23.754332 -36.383948) (xy 23.785739 -36.43079) (xy 23.796546 -36.453572) (xy 23.928576 -36.453572)
			(xy 23.932647 -36.39795) (xy 23.944773 -36.343513) (xy 23.964696 -36.291422) (xy 23.991992 -36.242787)
			(xy 24.026078 -36.198644) (xy 24.066227 -36.159935) (xy 24.111585 -36.127484) (xy 24.161185 -36.101983)
			(xy 24.213969 -36.083976) (xy 24.268812 -36.073846) (xy 24.324546 -36.071809) (xy 24.379983 -36.077909)
			(xy 24.43394 -36.092015) (xy 24.485269 -36.113827) (xy 24.532875 -36.142881) (xy 24.575743 -36.178556)
			(xy 24.61296 -36.220093) (xy 24.643733 -36.266606) (xy 24.667405 -36.317103) (xy 24.683473 -36.37051)
			(xy 24.691593 -36.425686) (xy 24.692102 -36.453572) (xy 24.691593 -36.481458) (xy 24.683473 -36.536634)
			(xy 24.667405 -36.590041) (xy 24.643733 -36.640538) (xy 24.61296 -36.687051) (xy 24.575743 -36.728588)
			(xy 24.532875 -36.764263) (xy 24.485269 -36.793317) (xy 24.43394 -36.815129) (xy 24.379983 -36.829235)
			(xy 24.324546 -36.835335) (xy 24.268812 -36.833298) (xy 24.213969 -36.823168) (xy 24.161185 -36.805161)
			(xy 24.111585 -36.77966) (xy 24.066227 -36.747209) (xy 24.026078 -36.7085) (xy 23.991992 -36.664357)
			(xy 23.964696 -36.615722) (xy 23.944773 -36.563631) (xy 23.932647 -36.509194) (xy 23.928576 -36.453572)
			(xy 23.796546 -36.453572) (xy 23.80991 -36.481746) (xy 23.826318 -36.535704) (xy 23.834606 -36.591489)
			(xy 23.835106 -36.619688) (xy 23.83462 -36.646939) (xy 23.826864 -36.700887) (xy 23.811509 -36.753182)
			(xy 23.788867 -36.802759) (xy 23.759401 -36.848609) (xy 23.72371 -36.8898) (xy 23.682519 -36.925491)
			(xy 23.636669 -36.954957) (xy 23.587092 -36.977599) (xy 23.534797 -36.992954) (xy 23.480849 -37.00071)
			(xy 23.426347 -37.00071) (xy 23.372399 -36.992954) (xy 23.320104 -36.977599) (xy 23.270527 -36.954957)
			(xy 23.224677 -36.925491) (xy 23.183486 -36.8898) (xy 23.147795 -36.848609) (xy 23.118329 -36.802759)
			(xy 23.095687 -36.753182) (xy 23.080332 -36.700887) (xy 23.072576 -36.646939) (xy 23.07209 -36.619688)
			(xy 23.072629 -36.590941) (xy 23.08129 -36.534104) (xy 23.098384 -36.47921) (xy 23.123523 -36.427504)
			(xy 23.1394 -36.403534) (xy 23.146982 -36.391686) (xy 23.155984 -36.365049) (xy 23.157376 -36.336966)
			(xy 23.151054 -36.309568) (xy 23.137497 -36.284935) (xy 23.117734 -36.264935) (xy 23.093264 -36.251086)
			(xy 23.07971 -36.247324) (xy 23.05245 -36.240094) (xy 23.000274 -36.21869) (xy 22.951816 -36.189841)
			(xy 22.908131 -36.154174) (xy 22.870172 -36.112467) (xy 22.838764 -36.065626) (xy 22.814591 -36.014674)
			(xy 22.798181 -35.960719) (xy 22.78989 -35.904936) (xy 22.789388 -35.876738) (xy 19.480784 -35.876738)
			(xy 19.480275 -35.904624) (xy 19.472155 -35.9598) (xy 19.456087 -36.013207) (xy 19.432415 -36.063704)
			(xy 19.401642 -36.110217) (xy 19.364425 -36.151754) (xy 19.321557 -36.187429) (xy 19.273951 -36.216483)
			(xy 19.222622 -36.238295) (xy 19.168665 -36.252401) (xy 19.113228 -36.258501) (xy 19.057494 -36.256464)
			(xy 19.002651 -36.246334) (xy 18.949867 -36.228327) (xy 18.900267 -36.202826) (xy 18.854909 -36.170375)
			(xy 18.81476 -36.131666) (xy 18.780674 -36.087523) (xy 18.753378 -36.038888) (xy 18.733455 -35.986797)
			(xy 18.721329 -35.93236) (xy 18.717258 -35.876738) (xy 13.605154 -35.876738) (xy 13.611478 -35.881927)
			(xy 13.674475 -35.944093) (xy 13.731521 -36.011762) (xy 13.782135 -36.084366) (xy 13.825896 -36.161296)
			(xy 13.862434 -36.241908) (xy 13.891443 -36.325524) (xy 13.912681 -36.411443) (xy 13.925969 -36.498946)
			(xy 13.926621 -36.50996) (xy 20.613876 -36.50996) (xy 20.617947 -36.454338) (xy 20.630073 -36.399901)
			(xy 20.649996 -36.34781) (xy 20.677292 -36.299175) (xy 20.711378 -36.255032) (xy 20.751527 -36.216323)
			(xy 20.796885 -36.183872) (xy 20.846485 -36.158371) (xy 20.899269 -36.140364) (xy 20.954112 -36.130234)
			(xy 21.009846 -36.128197) (xy 21.065283 -36.134297) (xy 21.11924 -36.148403) (xy 21.170569 -36.170215)
			(xy 21.218175 -36.199269) (xy 21.261043 -36.234944) (xy 21.29826 -36.276481) (xy 21.329033 -36.322994)
			(xy 21.352705 -36.373491) (xy 21.368773 -36.426898) (xy 21.376893 -36.482074) (xy 21.377402 -36.50996)
			(xy 21.376893 -36.537846) (xy 21.368773 -36.593022) (xy 21.352705 -36.646429) (xy 21.329033 -36.696926)
			(xy 21.29826 -36.743439) (xy 21.261043 -36.784976) (xy 21.218175 -36.820651) (xy 21.170569 -36.849705)
			(xy 21.11924 -36.871517) (xy 21.065283 -36.885623) (xy 21.009846 -36.891723) (xy 20.954112 -36.889686)
			(xy 20.899269 -36.879556) (xy 20.846485 -36.861549) (xy 20.796885 -36.836048) (xy 20.751527 -36.803597)
			(xy 20.711378 -36.764888) (xy 20.677292 -36.720745) (xy 20.649996 -36.67211) (xy 20.630073 -36.620019)
			(xy 20.617947 -36.565582) (xy 20.613876 -36.50996) (xy 13.926621 -36.50996) (xy 13.931196 -36.587297)
			(xy 13.928318 -36.675755) (xy 13.917358 -36.76358) (xy 13.898409 -36.850033) (xy 13.871631 -36.93439)
			(xy 13.837246 -37.015944) (xy 13.795545 -37.094009) (xy 13.771626 -37.131244) (xy 13.767562 -37.137594)
			(xy 13.763244 -37.151564) (xy 13.763244 -37.159184) (xy 13.763634 -37.16921) (xy 13.771306 -37.187735)
			(xy 13.785489 -37.201909) (xy 13.804018 -37.209572) (xy 13.814044 -37.209984) (xy 13.892022 -37.209984)
			(xy 13.93546 -37.21049) (xy 14.021965 -37.218506) (xy 14.107362 -37.234469) (xy 14.190921 -37.258244)
			(xy 14.271931 -37.289628) (xy 14.349699 -37.328352) (xy 14.423562 -37.374086) (xy 14.492891 -37.426441)
			(xy 14.546333 -37.47516) (xy 17.75917 -37.47516) (xy 17.763241 -37.419538) (xy 17.775367 -37.365101)
			(xy 17.79529 -37.31301) (xy 17.822586 -37.264375) (xy 17.856672 -37.220232) (xy 17.896821 -37.181523)
			(xy 17.942179 -37.149072) (xy 17.991779 -37.123571) (xy 18.044563 -37.105564) (xy 18.099406 -37.095434)
			(xy 18.15514 -37.093397) (xy 18.210577 -37.099497) (xy 18.264534 -37.113603) (xy 18.315863 -37.135415)
			(xy 18.363469 -37.164469) (xy 18.406337 -37.200144) (xy 18.407188 -37.201094) (xy 21.71649 -37.201094)
			(xy 21.720561 -37.145472) (xy 21.732687 -37.091035) (xy 21.75261 -37.038944) (xy 21.779906 -36.990309)
			(xy 21.813992 -36.946166) (xy 21.854141 -36.907457) (xy 21.899499 -36.875006) (xy 21.949099 -36.849505)
			(xy 22.001883 -36.831498) (xy 22.056726 -36.821368) (xy 22.11246 -36.819331) (xy 22.167897 -36.825431)
			(xy 22.221854 -36.839537) (xy 22.273183 -36.861349) (xy 22.320789 -36.890403) (xy 22.363657 -36.926078)
			(xy 22.400874 -36.967615) (xy 22.431647 -37.014128) (xy 22.455319 -37.064625) (xy 22.462065 -37.087048)
			(xy 31.200852 -37.087048) (xy 31.201314 -37.060444) (xy 31.208691 -37.007751) (xy 31.223321 -36.956594)
			(xy 31.244921 -36.907969) (xy 31.273071 -36.862818) (xy 31.307224 -36.822019) (xy 31.346718 -36.786364)
			(xy 31.368492 -36.771072) (xy 31.378417 -36.763543) (xy 31.390145 -36.741598) (xy 31.390844 -36.729162)
			(xy 31.390844 -36.644834) (xy 31.39021 -36.632378) (xy 31.378477 -36.610399) (xy 31.368492 -36.602924)
			(xy 31.346736 -36.58761) (xy 31.307254 -36.551948) (xy 31.273108 -36.511149) (xy 31.24496 -36.466002)
			(xy 31.223355 -36.417384) (xy 31.208713 -36.366236) (xy 31.201316 -36.313549) (xy 31.200852 -36.286948)
			(xy 31.2014 -36.259698) (xy 31.209149 -36.205752) (xy 31.224497 -36.153458) (xy 31.247131 -36.103881)
			(xy 31.27659 -36.05803) (xy 31.312275 -36.016838) (xy 31.353459 -35.981143) (xy 31.399304 -35.951673)
			(xy 31.448876 -35.929028) (xy 31.501166 -35.913668) (xy 31.55511 -35.905906) (xy 31.58236 -35.90544)
			(xy 31.586932 -35.90544) (xy 31.596142 -35.905169) (xy 31.61346 -35.898928) (xy 31.620714 -35.893248)
			(xy 31.671514 -35.84956) (xy 31.678221 -35.843324) (xy 31.68708 -35.827315) (xy 31.688786 -35.818318)
			(xy 31.688786 -35.818064) (xy 31.69313 -35.791133) (xy 31.70844 -35.738777) (xy 31.731052 -35.689135)
			(xy 31.760503 -35.64322) (xy 31.796194 -35.601968) (xy 31.837397 -35.56622) (xy 31.883271 -35.536705)
			(xy 31.932882 -35.514025) (xy 31.985217 -35.498642) (xy 32.03921 -35.49087) (xy 32.066484 -35.490404)
			(xy 32.093738 -35.490842) (xy 32.147693 -35.498597) (xy 32.199994 -35.513952) (xy 32.249578 -35.536595)
			(xy 32.295435 -35.566063) (xy 32.336631 -35.601758) (xy 32.372327 -35.642952) (xy 32.401798 -35.688808)
			(xy 32.424442 -35.738391) (xy 32.439799 -35.790691) (xy 32.447557 -35.844646) (xy 32.447557 -35.899154)
			(xy 32.439799 -35.953109) (xy 32.424442 -36.005409) (xy 32.401798 -36.054992) (xy 32.372327 -36.100848)
			(xy 32.336631 -36.142042) (xy 32.295435 -36.177737) (xy 32.249578 -36.207205) (xy 32.199994 -36.229848)
			(xy 32.147693 -36.245203) (xy 32.093738 -36.252958) (xy 32.066484 -36.25342) (xy 32.061912 -36.25342)
			(xy 32.052698 -36.25365) (xy 32.035379 -36.259918) (xy 32.02813 -36.265612) (xy 31.97733 -36.3093)
			(xy 31.970593 -36.315507) (xy 31.961753 -36.331538) (xy 31.960058 -36.340542) (xy 31.960058 -36.340796)
			(xy 31.955858 -36.366999) (xy 31.941174 -36.417993) (xy 31.919561 -36.466459) (xy 31.891438 -36.51146)
			(xy 31.888011 -36.515548) (xy 33.014156 -36.515548) (xy 33.018227 -36.459926) (xy 33.030353 -36.405489)
			(xy 33.050276 -36.353398) (xy 33.077572 -36.304763) (xy 33.111658 -36.26062) (xy 33.151807 -36.221911)
			(xy 33.197165 -36.18946) (xy 33.246765 -36.163959) (xy 33.299549 -36.145952) (xy 33.354392 -36.135822)
			(xy 33.410126 -36.133785) (xy 33.465563 -36.139885) (xy 33.51952 -36.153991) (xy 33.570849 -36.175803)
			(xy 33.618455 -36.204857) (xy 33.661323 -36.240532) (xy 33.69854 -36.282069) (xy 33.729313 -36.328582)
			(xy 33.752985 -36.379079) (xy 33.769053 -36.432486) (xy 33.777173 -36.487662) (xy 33.777682 -36.515548)
			(xy 33.777173 -36.543434) (xy 33.769053 -36.59861) (xy 33.752985 -36.652017) (xy 33.729313 -36.702514)
			(xy 33.69854 -36.749027) (xy 33.661323 -36.790564) (xy 33.618455 -36.826239) (xy 33.570849 -36.855293)
			(xy 33.51952 -36.877105) (xy 33.465563 -36.891211) (xy 33.410126 -36.897311) (xy 33.354392 -36.895274)
			(xy 33.299549 -36.885144) (xy 33.246765 -36.867137) (xy 33.197165 -36.841636) (xy 33.151807 -36.809185)
			(xy 33.111658 -36.770476) (xy 33.077572 -36.726333) (xy 33.050276 -36.677698) (xy 33.030353 -36.625607)
			(xy 33.018227 -36.57117) (xy 33.014156 -36.515548) (xy 31.888011 -36.515548) (xy 31.857346 -36.552127)
			(xy 31.817946 -36.587674) (xy 31.796228 -36.602924) (xy 31.786308 -36.610459) (xy 31.774577 -36.632399)
			(xy 31.773876 -36.644834) (xy 31.773876 -36.729162) (xy 31.774545 -36.741612) (xy 31.786256 -36.763589)
			(xy 31.796228 -36.771072) (xy 31.817987 -36.786383) (xy 31.857468 -36.822045) (xy 31.891613 -36.862846)
			(xy 31.91976 -36.907993) (xy 31.941365 -36.956612) (xy 31.956007 -37.00776) (xy 31.963403 -37.060447)
			(xy 31.963868 -37.087048) (xy 31.963868 -37.087302) (xy 31.96325 -37.119019) (xy 31.952748 -37.181577)
			(xy 31.93202 -37.241528) (xy 31.917386 -37.269674) (xy 31.912052 -37.27958) (xy 31.910528 -37.301678)
			(xy 31.942532 -37.384482) (xy 31.947024 -37.394569) (xy 31.962812 -37.409972) (xy 31.973012 -37.4142)
			(xy 31.997548 -37.423259) (xy 32.044078 -37.447144) (xy 32.086908 -37.477161) (xy 32.125237 -37.512748)
			(xy 32.158344 -37.553238) (xy 32.18561 -37.597871) (xy 32.206523 -37.64581) (xy 32.22069 -37.696157)
			(xy 32.227846 -37.747967) (xy 32.228282 -37.774118) (xy 32.227796 -37.801369) (xy 32.22004 -37.855317)
			(xy 32.204685 -37.907612) (xy 32.182043 -37.957189) (xy 32.152577 -38.003039) (xy 32.116886 -38.04423)
			(xy 32.075695 -38.079921) (xy 32.029845 -38.109387) (xy 31.980268 -38.132029) (xy 31.927973 -38.147384)
			(xy 31.874025 -38.15514) (xy 31.819523 -38.15514) (xy 31.765575 -38.147384) (xy 31.71328 -38.132029)
			(xy 31.663703 -38.109387) (xy 31.617853 -38.079921) (xy 31.576662 -38.04423) (xy 31.540971 -38.003039)
			(xy 31.511505 -37.957189) (xy 31.488863 -37.907612) (xy 31.473508 -37.855317) (xy 31.465752 -37.801369)
			(xy 31.465266 -37.774118) (xy 31.465266 -37.773864) (xy 31.465867 -37.742146) (xy 31.476375 -37.679587)
			(xy 31.49711 -37.619637) (xy 31.511748 -37.591492) (xy 31.517082 -37.581586) (xy 31.518606 -37.559488)
			(xy 31.486602 -37.476684) (xy 31.482151 -37.466575) (xy 31.466333 -37.451183) (xy 31.456122 -37.446966)
			(xy 31.431582 -37.437916) (xy 31.38505 -37.414033) (xy 31.342218 -37.384016) (xy 31.303888 -37.348428)
			(xy 31.27078 -37.307937) (xy 31.243515 -37.263302) (xy 31.222604 -37.215361) (xy 31.208439 -37.165012)
			(xy 31.201286 -37.1132) (xy 31.200852 -37.087048) (xy 22.462065 -37.087048) (xy 22.471387 -37.118032)
			(xy 22.479507 -37.173208) (xy 22.480016 -37.201094) (xy 22.479507 -37.22898) (xy 22.471387 -37.284156)
			(xy 22.455319 -37.337563) (xy 22.431647 -37.38806) (xy 22.400874 -37.434573) (xy 22.363657 -37.47611)
			(xy 22.320789 -37.511785) (xy 22.273183 -37.540839) (xy 22.221854 -37.562651) (xy 22.167897 -37.576757)
			(xy 22.11246 -37.582857) (xy 22.056726 -37.58082) (xy 22.001883 -37.57069) (xy 21.949099 -37.552683)
			(xy 21.899499 -37.527182) (xy 21.854141 -37.494731) (xy 21.813992 -37.456022) (xy 21.779906 -37.411879)
			(xy 21.75261 -37.363244) (xy 21.732687 -37.311153) (xy 21.720561 -37.256716) (xy 21.71649 -37.201094)
			(xy 18.407188 -37.201094) (xy 18.443554 -37.241681) (xy 18.474327 -37.288194) (xy 18.497999 -37.338691)
			(xy 18.514067 -37.392098) (xy 18.522187 -37.447274) (xy 18.522696 -37.47516) (xy 18.522187 -37.503046)
			(xy 18.514067 -37.558222) (xy 18.497999 -37.611629) (xy 18.474327 -37.662126) (xy 18.474174 -37.662358)
			(xy 19.948396 -37.662358) (xy 19.952467 -37.606736) (xy 19.964593 -37.552299) (xy 19.984516 -37.500208)
			(xy 20.011812 -37.451573) (xy 20.045898 -37.40743) (xy 20.086047 -37.368721) (xy 20.131405 -37.33627)
			(xy 20.181005 -37.310769) (xy 20.233789 -37.292762) (xy 20.288632 -37.282632) (xy 20.344366 -37.280595)
			(xy 20.399803 -37.286695) (xy 20.45376 -37.300801) (xy 20.505089 -37.322613) (xy 20.552695 -37.351667)
			(xy 20.595563 -37.387342) (xy 20.63278 -37.428879) (xy 20.663553 -37.475392) (xy 20.687225 -37.525889)
			(xy 20.703293 -37.579296) (xy 20.711413 -37.634472) (xy 20.711922 -37.662358) (xy 20.711413 -37.690244)
			(xy 20.703293 -37.74542) (xy 20.687225 -37.798827) (xy 20.663553 -37.849324) (xy 20.63278 -37.895837)
			(xy 20.595563 -37.937374) (xy 20.552695 -37.973049) (xy 20.505089 -38.002103) (xy 20.45376 -38.023915)
			(xy 20.399803 -38.038021) (xy 20.344366 -38.044121) (xy 20.288632 -38.042084) (xy 20.233789 -38.031954)
			(xy 20.181005 -38.013947) (xy 20.131405 -37.988446) (xy 20.086047 -37.955995) (xy 20.045898 -37.917286)
			(xy 20.011812 -37.873143) (xy 19.984516 -37.824508) (xy 19.964593 -37.772417) (xy 19.952467 -37.71798)
			(xy 19.948396 -37.662358) (xy 18.474174 -37.662358) (xy 18.443554 -37.708639) (xy 18.406337 -37.750176)
			(xy 18.363469 -37.785851) (xy 18.315863 -37.814905) (xy 18.264534 -37.836717) (xy 18.210577 -37.850823)
			(xy 18.15514 -37.856923) (xy 18.099406 -37.854886) (xy 18.044563 -37.844756) (xy 17.991779 -37.826749)
			(xy 17.942179 -37.801248) (xy 17.896821 -37.768797) (xy 17.856672 -37.730088) (xy 17.822586 -37.685945)
			(xy 17.79529 -37.63731) (xy 17.775367 -37.585219) (xy 17.763241 -37.530782) (xy 17.75917 -37.47516)
			(xy 14.546333 -37.47516) (xy 14.557093 -37.484969) (xy 14.615621 -37.549171) (xy 14.667975 -37.618499)
			(xy 14.713709 -37.692363) (xy 14.752433 -37.770131) (xy 14.783816 -37.85114) (xy 14.807591 -37.9347)
			(xy 14.823555 -38.020097) (xy 14.83157 -38.106602) (xy 14.83157 -38.193478) (xy 14.823555 -38.279983)
			(xy 14.807591 -38.36538) (xy 14.783816 -38.44894) (xy 14.76746 -38.49116) (xy 17.75917 -38.49116)
			(xy 17.763241 -38.435538) (xy 17.775367 -38.381101) (xy 17.79529 -38.32901) (xy 17.822586 -38.280375)
			(xy 17.856672 -38.236232) (xy 17.896821 -38.197523) (xy 17.942179 -38.165072) (xy 17.991779 -38.139571)
			(xy 18.044563 -38.121564) (xy 18.099406 -38.111434) (xy 18.15514 -38.109397) (xy 18.210577 -38.115497)
			(xy 18.264534 -38.129603) (xy 18.315863 -38.151415) (xy 18.363469 -38.180469) (xy 18.406337 -38.216144)
			(xy 18.443554 -38.257681) (xy 18.474327 -38.304194) (xy 18.479457 -38.315138) (xy 32.418018 -38.315138)
			(xy 32.422089 -38.259516) (xy 32.434215 -38.205079) (xy 32.454138 -38.152988) (xy 32.481434 -38.104353)
			(xy 32.51552 -38.06021) (xy 32.555669 -38.021501) (xy 32.601027 -37.98905) (xy 32.650627 -37.963549)
			(xy 32.703411 -37.945542) (xy 32.758254 -37.935412) (xy 32.813988 -37.933375) (xy 32.869425 -37.939475)
			(xy 32.923382 -37.953581) (xy 32.974711 -37.975393) (xy 33.022317 -38.004447) (xy 33.065185 -38.040122)
			(xy 33.102402 -38.081659) (xy 33.133175 -38.128172) (xy 33.156847 -38.178669) (xy 33.161302 -38.193478)
			(xy 37.098216 -38.193478) (xy 37.098216 -38.106602) (xy 37.106232 -38.020096) (xy 37.122195 -37.934699)
			(xy 37.14597 -37.851139) (xy 37.177353 -37.770129) (xy 37.216077 -37.69236) (xy 37.261812 -37.618496)
			(xy 37.314167 -37.549168) (xy 37.372695 -37.484965) (xy 37.436898 -37.426437) (xy 37.506226 -37.374082)
			(xy 37.58009 -37.328347) (xy 37.657859 -37.289623) (xy 37.738869 -37.25824) (xy 37.822429 -37.234465)
			(xy 37.907826 -37.218502) (xy 37.994332 -37.210486) (xy 38.03777 -37.209984) (xy 38.115748 -37.209984)
			(xy 38.125761 -37.209551) (xy 38.144257 -37.201872) (xy 38.158408 -37.187703) (xy 38.166063 -37.169197)
			(xy 38.166548 -37.159184) (xy 38.166548 -37.151564) (xy 38.16223 -37.137594) (xy 38.158166 -37.131244)
			(xy 38.134247 -37.094009) (xy 38.092546 -37.015944) (xy 38.058161 -36.93439) (xy 38.031383 -36.850033)
			(xy 38.012434 -36.76358) (xy 38.001474 -36.675755) (xy 37.998596 -36.587297) (xy 38.003823 -36.498946)
			(xy 38.017111 -36.411443) (xy 38.038349 -36.325524) (xy 38.067358 -36.241908) (xy 38.103896 -36.161296)
			(xy 38.147657 -36.084366) (xy 38.198271 -36.011762) (xy 38.255317 -35.944093) (xy 38.318314 -35.881927)
			(xy 38.386734 -35.825786) (xy 38.460004 -35.776139) (xy 38.537509 -35.733405) (xy 38.618598 -35.69794)
			(xy 38.702592 -35.670044) (xy 38.788786 -35.649948) (xy 38.876457 -35.637824) (xy 38.96487 -35.633771)
			(xy 39.053283 -35.637824) (xy 39.140954 -35.649948) (xy 39.227148 -35.670044) (xy 39.311142 -35.69794)
			(xy 39.392231 -35.733405) (xy 39.469736 -35.776139) (xy 39.543006 -35.825786) (xy 39.605102 -35.876738)
			(xy 44.717206 -35.876738) (xy 44.721277 -35.821116) (xy 44.733403 -35.766679) (xy 44.753326 -35.714588)
			(xy 44.780622 -35.665953) (xy 44.814708 -35.62181) (xy 44.854857 -35.583101) (xy 44.900215 -35.55065)
			(xy 44.949815 -35.525149) (xy 45.002599 -35.507142) (xy 45.057442 -35.497012) (xy 45.113176 -35.494975)
			(xy 45.168613 -35.501075) (xy 45.22257 -35.515181) (xy 45.273899 -35.536993) (xy 45.321505 -35.566047)
			(xy 45.364373 -35.601722) (xy 45.40159 -35.643259) (xy 45.432363 -35.689772) (xy 45.456035 -35.740269)
			(xy 45.472103 -35.793676) (xy 45.480223 -35.848852) (xy 45.480732 -35.876738) (xy 48.788826 -35.876738)
			(xy 48.792897 -35.821116) (xy 48.805023 -35.766679) (xy 48.824946 -35.714588) (xy 48.852242 -35.665953)
			(xy 48.886328 -35.62181) (xy 48.926477 -35.583101) (xy 48.971835 -35.55065) (xy 49.021435 -35.525149)
			(xy 49.074219 -35.507142) (xy 49.129062 -35.497012) (xy 49.184796 -35.494975) (xy 49.240233 -35.501075)
			(xy 49.29419 -35.515181) (xy 49.345519 -35.536993) (xy 49.393125 -35.566047) (xy 49.435993 -35.601722)
			(xy 49.47321 -35.643259) (xy 49.503983 -35.689772) (xy 49.527655 -35.740269) (xy 49.543723 -35.793676)
			(xy 49.551843 -35.848852) (xy 49.552352 -35.876738) (xy 49.551843 -35.904624) (xy 49.543723 -35.9598)
			(xy 49.527655 -36.013207) (xy 49.503983 -36.063704) (xy 49.47321 -36.110217) (xy 49.435993 -36.151754)
			(xy 49.393125 -36.187429) (xy 49.345519 -36.216483) (xy 49.29419 -36.238295) (xy 49.240233 -36.252401)
			(xy 49.184796 -36.258501) (xy 49.129062 -36.256464) (xy 49.074219 -36.246334) (xy 49.021435 -36.228327)
			(xy 48.971835 -36.202826) (xy 48.926477 -36.170375) (xy 48.886328 -36.131666) (xy 48.852242 -36.087523)
			(xy 48.824946 -36.038888) (xy 48.805023 -35.986797) (xy 48.792897 -35.93236) (xy 48.788826 -35.876738)
			(xy 45.480732 -35.876738) (xy 45.480223 -35.904624) (xy 45.472103 -35.9598) (xy 45.456035 -36.013207)
			(xy 45.432363 -36.063704) (xy 45.40159 -36.110217) (xy 45.364373 -36.151754) (xy 45.321505 -36.187429)
			(xy 45.273899 -36.216483) (xy 45.22257 -36.238295) (xy 45.168613 -36.252401) (xy 45.113176 -36.258501)
			(xy 45.057442 -36.256464) (xy 45.002599 -36.246334) (xy 44.949815 -36.228327) (xy 44.900215 -36.202826)
			(xy 44.854857 -36.170375) (xy 44.814708 -36.131666) (xy 44.780622 -36.087523) (xy 44.753326 -36.038888)
			(xy 44.733403 -35.986797) (xy 44.721277 -35.93236) (xy 44.717206 -35.876738) (xy 39.605102 -35.876738)
			(xy 39.611426 -35.881927) (xy 39.674423 -35.944093) (xy 39.731469 -36.011762) (xy 39.782083 -36.084366)
			(xy 39.825844 -36.161296) (xy 39.862382 -36.241908) (xy 39.891391 -36.325524) (xy 39.912629 -36.411443)
			(xy 39.925917 -36.498946) (xy 39.926569 -36.50996) (xy 46.613824 -36.50996) (xy 46.617895 -36.454338)
			(xy 46.630021 -36.399901) (xy 46.649944 -36.34781) (xy 46.67724 -36.299175) (xy 46.711326 -36.255032)
			(xy 46.751475 -36.216323) (xy 46.796833 -36.183872) (xy 46.846433 -36.158371) (xy 46.899217 -36.140364)
			(xy 46.95406 -36.130234) (xy 47.009794 -36.128197) (xy 47.065231 -36.134297) (xy 47.119188 -36.148403)
			(xy 47.170517 -36.170215) (xy 47.218123 -36.199269) (xy 47.260991 -36.234944) (xy 47.298208 -36.276481)
			(xy 47.328981 -36.322994) (xy 47.352653 -36.373491) (xy 47.368721 -36.426898) (xy 47.372646 -36.453572)
			(xy 49.928524 -36.453572) (xy 49.932595 -36.39795) (xy 49.944721 -36.343513) (xy 49.964644 -36.291422)
			(xy 49.99194 -36.242787) (xy 50.026026 -36.198644) (xy 50.066175 -36.159935) (xy 50.111533 -36.127484)
			(xy 50.161133 -36.101983) (xy 50.213917 -36.083976) (xy 50.26876 -36.073846) (xy 50.324494 -36.071809)
			(xy 50.379931 -36.077909) (xy 50.433888 -36.092015) (xy 50.485217 -36.113827) (xy 50.532823 -36.142881)
			(xy 50.575691 -36.178556) (xy 50.612908 -36.220093) (xy 50.643681 -36.266606) (xy 50.667353 -36.317103)
			(xy 50.683421 -36.37051) (xy 50.691541 -36.425686) (xy 50.69205 -36.453572) (xy 50.691541 -36.481458)
			(xy 50.683421 -36.536634) (xy 50.667353 -36.590041) (xy 50.643681 -36.640538) (xy 50.612908 -36.687051)
			(xy 50.575691 -36.728588) (xy 50.532823 -36.764263) (xy 50.485217 -36.793317) (xy 50.433888 -36.815129)
			(xy 50.379931 -36.829235) (xy 50.324494 -36.835335) (xy 50.26876 -36.833298) (xy 50.213917 -36.823168)
			(xy 50.161133 -36.805161) (xy 50.111533 -36.77966) (xy 50.066175 -36.747209) (xy 50.026026 -36.7085)
			(xy 49.99194 -36.664357) (xy 49.964644 -36.615722) (xy 49.944721 -36.563631) (xy 49.932595 -36.509194)
			(xy 49.928524 -36.453572) (xy 47.372646 -36.453572) (xy 47.376841 -36.482074) (xy 47.37735 -36.50996)
			(xy 47.376841 -36.537846) (xy 47.368721 -36.593022) (xy 47.352653 -36.646429) (xy 47.328981 -36.696926)
			(xy 47.298208 -36.743439) (xy 47.260991 -36.784976) (xy 47.218123 -36.820651) (xy 47.170517 -36.849705)
			(xy 47.119188 -36.871517) (xy 47.065231 -36.885623) (xy 47.009794 -36.891723) (xy 46.95406 -36.889686)
			(xy 46.899217 -36.879556) (xy 46.846433 -36.861549) (xy 46.796833 -36.836048) (xy 46.751475 -36.803597)
			(xy 46.711326 -36.764888) (xy 46.67724 -36.720745) (xy 46.649944 -36.67211) (xy 46.630021 -36.620019)
			(xy 46.617895 -36.565582) (xy 46.613824 -36.50996) (xy 39.926569 -36.50996) (xy 39.931144 -36.587297)
			(xy 39.928266 -36.675755) (xy 39.917306 -36.76358) (xy 39.898357 -36.850033) (xy 39.871579 -36.93439)
			(xy 39.837194 -37.015944) (xy 39.795493 -37.094009) (xy 39.771574 -37.131244) (xy 39.76751 -37.137594)
			(xy 39.763192 -37.151564) (xy 39.763192 -37.159184) (xy 39.763632 -37.169203) (xy 39.771295 -37.187718)
			(xy 39.785461 -37.201891) (xy 39.803973 -37.209563) (xy 39.813992 -37.209984) (xy 39.89197 -37.209984)
			(xy 39.935408 -37.21049) (xy 40.021914 -37.218506) (xy 40.10731 -37.234469) (xy 40.19087 -37.258244)
			(xy 40.27188 -37.289627) (xy 40.349648 -37.328351) (xy 40.423511 -37.374085) (xy 40.49284 -37.42644)
			(xy 40.546283 -37.47516) (xy 43.759118 -37.47516) (xy 43.763189 -37.419538) (xy 43.775315 -37.365101)
			(xy 43.795238 -37.31301) (xy 43.822534 -37.264375) (xy 43.85662 -37.220232) (xy 43.896769 -37.181523)
			(xy 43.942127 -37.149072) (xy 43.991727 -37.123571) (xy 44.044511 -37.105564) (xy 44.099354 -37.095434)
			(xy 44.155088 -37.093397) (xy 44.210525 -37.099497) (xy 44.264482 -37.113603) (xy 44.315811 -37.135415)
			(xy 44.363417 -37.164469) (xy 44.406285 -37.200144) (xy 44.407136 -37.201094) (xy 47.716438 -37.201094)
			(xy 47.720509 -37.145472) (xy 47.732635 -37.091035) (xy 47.752558 -37.038944) (xy 47.779854 -36.990309)
			(xy 47.81394 -36.946166) (xy 47.854089 -36.907457) (xy 47.899447 -36.875006) (xy 47.949047 -36.849505)
			(xy 48.001831 -36.831498) (xy 48.056674 -36.821368) (xy 48.112408 -36.819331) (xy 48.167845 -36.825431)
			(xy 48.221802 -36.839537) (xy 48.273131 -36.861349) (xy 48.320737 -36.890403) (xy 48.363605 -36.926078)
			(xy 48.400822 -36.967615) (xy 48.431595 -37.014128) (xy 48.455267 -37.064625) (xy 48.462013 -37.087048)
			(xy 57.2008 -37.087048) (xy 57.201285 -37.060445) (xy 57.20866 -37.007754) (xy 57.223288 -36.956599)
			(xy 57.244885 -36.907974) (xy 57.273031 -36.862823) (xy 57.30718 -36.822023) (xy 57.346668 -36.786366)
			(xy 57.36844 -36.771072) (xy 57.378272 -36.763461) (xy 57.389962 -36.741566) (xy 57.390792 -36.729162)
			(xy 57.390792 -36.644834) (xy 57.390139 -36.632381) (xy 57.378418 -36.610404) (xy 57.36844 -36.602924)
			(xy 57.346672 -36.587626) (xy 57.307193 -36.55196) (xy 57.27305 -36.511157) (xy 57.244904 -36.466008)
			(xy 57.223301 -36.417387) (xy 57.20866 -36.366237) (xy 57.201264 -36.31355) (xy 57.2008 -36.286948)
			(xy 57.2013 -36.259696) (xy 57.209051 -36.205746) (xy 57.224401 -36.153448) (xy 57.247038 -36.103868)
			(xy 57.276502 -36.058014) (xy 57.312192 -36.016821) (xy 57.353382 -35.981126) (xy 57.399233 -35.951658)
			(xy 57.448811 -35.929015) (xy 57.501107 -35.913659) (xy 57.555056 -35.905903) (xy 57.582308 -35.90544)
			(xy 57.58688 -35.90544) (xy 57.596092 -35.905193) (xy 57.61341 -35.898935) (xy 57.620662 -35.893248)
			(xy 57.671462 -35.84956) (xy 57.678176 -35.843332) (xy 57.68703 -35.827316) (xy 57.688734 -35.818318)
			(xy 57.688734 -35.818064) (xy 57.693032 -35.791124) (xy 57.708345 -35.738765) (xy 57.73096 -35.68912)
			(xy 57.760416 -35.643203) (xy 57.796112 -35.60195) (xy 57.837321 -35.566202) (xy 57.883201 -35.536689)
			(xy 57.932817 -35.514011) (xy 57.985158 -35.498633) (xy 58.039155 -35.490867) (xy 58.066432 -35.490404)
			(xy 58.093683 -35.490868) (xy 58.147629 -35.498628) (xy 58.199921 -35.513987) (xy 58.249496 -35.536631)
			(xy 58.295344 -35.566099) (xy 58.336531 -35.601791) (xy 58.372221 -35.642982) (xy 58.401685 -35.688832)
			(xy 58.424324 -35.738409) (xy 58.439678 -35.790703) (xy 58.447434 -35.844649) (xy 58.447434 -35.899151)
			(xy 58.439678 -35.953097) (xy 58.424324 -36.005391) (xy 58.401685 -36.054968) (xy 58.372221 -36.100818)
			(xy 58.336531 -36.142009) (xy 58.295344 -36.177701) (xy 58.249496 -36.207169) (xy 58.199921 -36.229813)
			(xy 58.147629 -36.245172) (xy 58.093683 -36.252932) (xy 58.066432 -36.25342) (xy 58.06186 -36.25342)
			(xy 58.052649 -36.253673) (xy 58.035329 -36.259925) (xy 58.028078 -36.265612) (xy 57.977278 -36.3093)
			(xy 57.970549 -36.315514) (xy 57.961703 -36.33154) (xy 57.960006 -36.340542) (xy 57.960006 -36.340796)
			(xy 57.955786 -36.366995) (xy 57.941104 -36.417988) (xy 57.919494 -36.466453) (xy 57.891375 -36.511454)
			(xy 57.887944 -36.515548) (xy 59.014104 -36.515548) (xy 59.018175 -36.459926) (xy 59.030301 -36.405489)
			(xy 59.050224 -36.353398) (xy 59.07752 -36.304763) (xy 59.111606 -36.26062) (xy 59.151755 -36.221911)
			(xy 59.197113 -36.18946) (xy 59.246713 -36.163959) (xy 59.299497 -36.145952) (xy 59.35434 -36.135822)
			(xy 59.410074 -36.133785) (xy 59.465511 -36.139885) (xy 59.519468 -36.153991) (xy 59.570797 -36.175803)
			(xy 59.618403 -36.204857) (xy 59.661271 -36.240532) (xy 59.698488 -36.282069) (xy 59.729261 -36.328582)
			(xy 59.752933 -36.379079) (xy 59.769001 -36.432486) (xy 59.777121 -36.487662) (xy 59.77763 -36.515548)
			(xy 59.777121 -36.543434) (xy 59.769001 -36.59861) (xy 59.752933 -36.652017) (xy 59.729261 -36.702514)
			(xy 59.698488 -36.749027) (xy 59.661271 -36.790564) (xy 59.618403 -36.826239) (xy 59.570797 -36.855293)
			(xy 59.519468 -36.877105) (xy 59.465511 -36.891211) (xy 59.410074 -36.897311) (xy 59.35434 -36.895274)
			(xy 59.299497 -36.885144) (xy 59.246713 -36.867137) (xy 59.197113 -36.841636) (xy 59.151755 -36.809185)
			(xy 59.111606 -36.770476) (xy 59.07752 -36.726333) (xy 59.050224 -36.677698) (xy 59.030301 -36.625607)
			(xy 59.018175 -36.57117) (xy 59.014104 -36.515548) (xy 57.887944 -36.515548) (xy 57.857288 -36.552123)
			(xy 57.817892 -36.587673) (xy 57.796176 -36.602924) (xy 57.786247 -36.610448) (xy 57.774523 -36.632397)
			(xy 57.773824 -36.644834) (xy 57.773824 -36.729162) (xy 57.774474 -36.741616) (xy 57.786197 -36.763593)
			(xy 57.796176 -36.771072) (xy 57.817946 -36.786368) (xy 57.857424 -36.822034) (xy 57.891567 -36.862838)
			(xy 57.919712 -36.907988) (xy 57.941315 -36.956609) (xy 57.955956 -37.007759) (xy 57.963351 -37.060446)
			(xy 57.963816 -37.087048) (xy 57.963816 -37.087302) (xy 57.963192 -37.119019) (xy 57.952692 -37.181576)
			(xy 57.931967 -37.241528) (xy 57.917334 -37.269674) (xy 57.912 -37.27958) (xy 57.910476 -37.301678)
			(xy 57.94248 -37.384482) (xy 57.946951 -37.394581) (xy 57.962754 -37.409979) (xy 57.97296 -37.4142)
			(xy 57.997484 -37.423289) (xy 58.044015 -37.447168) (xy 58.086848 -37.477179) (xy 58.125178 -37.512762)
			(xy 58.158287 -37.553248) (xy 58.185555 -37.597878) (xy 58.206468 -37.645815) (xy 58.220637 -37.696159)
			(xy 58.227794 -37.747968) (xy 58.22823 -37.774118) (xy 58.227744 -37.801369) (xy 58.219988 -37.855317)
			(xy 58.204633 -37.907612) (xy 58.181991 -37.957189) (xy 58.152525 -38.003039) (xy 58.116834 -38.04423)
			(xy 58.075643 -38.079921) (xy 58.029793 -38.109387) (xy 57.980216 -38.132029) (xy 57.927921 -38.147384)
			(xy 57.873973 -38.15514) (xy 57.819471 -38.15514) (xy 57.765523 -38.147384) (xy 57.713228 -38.132029)
			(xy 57.663651 -38.109387) (xy 57.617801 -38.079921) (xy 57.57661 -38.04423) (xy 57.540919 -38.003039)
			(xy 57.511453 -37.957189) (xy 57.488811 -37.907612) (xy 57.473456 -37.855317) (xy 57.4657 -37.801369)
			(xy 57.465214 -37.774118) (xy 57.465214 -37.773864) (xy 57.465821 -37.742147) (xy 57.476327 -37.679588)
			(xy 57.49706 -37.619637) (xy 57.511696 -37.591492) (xy 57.51703 -37.581586) (xy 57.518554 -37.559488)
			(xy 57.48655 -37.476684) (xy 57.482078 -37.466586) (xy 57.466275 -37.451189) (xy 57.45607 -37.446966)
			(xy 57.431519 -37.437946) (xy 57.384988 -37.414057) (xy 57.342157 -37.384034) (xy 57.303829 -37.348442)
			(xy 57.270723 -37.307947) (xy 57.243459 -37.263309) (xy 57.22255 -37.215366) (xy 57.208386 -37.165015)
			(xy 57.201234 -37.113201) (xy 57.2008 -37.087048) (xy 48.462013 -37.087048) (xy 48.471335 -37.118032)
			(xy 48.479455 -37.173208) (xy 48.479964 -37.201094) (xy 48.479455 -37.22898) (xy 48.471335 -37.284156)
			(xy 48.455267 -37.337563) (xy 48.431595 -37.38806) (xy 48.400822 -37.434573) (xy 48.363605 -37.47611)
			(xy 48.320737 -37.511785) (xy 48.273131 -37.540839) (xy 48.221802 -37.562651) (xy 48.167845 -37.576757)
			(xy 48.112408 -37.582857) (xy 48.056674 -37.58082) (xy 48.001831 -37.57069) (xy 47.949047 -37.552683)
			(xy 47.899447 -37.527182) (xy 47.854089 -37.494731) (xy 47.81394 -37.456022) (xy 47.779854 -37.411879)
			(xy 47.752558 -37.363244) (xy 47.732635 -37.311153) (xy 47.720509 -37.256716) (xy 47.716438 -37.201094)
			(xy 44.407136 -37.201094) (xy 44.443502 -37.241681) (xy 44.474275 -37.288194) (xy 44.497947 -37.338691)
			(xy 44.514015 -37.392098) (xy 44.522135 -37.447274) (xy 44.522644 -37.47516) (xy 44.522135 -37.503046)
			(xy 44.514015 -37.558222) (xy 44.497947 -37.611629) (xy 44.474275 -37.662126) (xy 44.474122 -37.662358)
			(xy 45.948344 -37.662358) (xy 45.952415 -37.606736) (xy 45.964541 -37.552299) (xy 45.984464 -37.500208)
			(xy 46.01176 -37.451573) (xy 46.045846 -37.40743) (xy 46.085995 -37.368721) (xy 46.131353 -37.33627)
			(xy 46.180953 -37.310769) (xy 46.233737 -37.292762) (xy 46.28858 -37.282632) (xy 46.344314 -37.280595)
			(xy 46.399751 -37.286695) (xy 46.453708 -37.300801) (xy 46.505037 -37.322613) (xy 46.552643 -37.351667)
			(xy 46.595511 -37.387342) (xy 46.632728 -37.428879) (xy 46.663501 -37.475392) (xy 46.687173 -37.525889)
			(xy 46.703241 -37.579296) (xy 46.711361 -37.634472) (xy 46.71187 -37.662358) (xy 46.711361 -37.690244)
			(xy 46.703241 -37.74542) (xy 46.687173 -37.798827) (xy 46.663501 -37.849324) (xy 46.632728 -37.895837)
			(xy 46.595511 -37.937374) (xy 46.552643 -37.973049) (xy 46.505037 -38.002103) (xy 46.453708 -38.023915)
			(xy 46.399751 -38.038021) (xy 46.344314 -38.044121) (xy 46.28858 -38.042084) (xy 46.233737 -38.031954)
			(xy 46.180953 -38.013947) (xy 46.131353 -37.988446) (xy 46.085995 -37.955995) (xy 46.045846 -37.917286)
			(xy 46.01176 -37.873143) (xy 45.984464 -37.824508) (xy 45.964541 -37.772417) (xy 45.952415 -37.71798)
			(xy 45.948344 -37.662358) (xy 44.474122 -37.662358) (xy 44.443502 -37.708639) (xy 44.406285 -37.750176)
			(xy 44.363417 -37.785851) (xy 44.315811 -37.814905) (xy 44.264482 -37.836717) (xy 44.210525 -37.850823)
			(xy 44.155088 -37.856923) (xy 44.099354 -37.854886) (xy 44.044511 -37.844756) (xy 43.991727 -37.826749)
			(xy 43.942127 -37.801248) (xy 43.896769 -37.768797) (xy 43.85662 -37.730088) (xy 43.822534 -37.685945)
			(xy 43.795238 -37.63731) (xy 43.775315 -37.585219) (xy 43.763189 -37.530782) (xy 43.759118 -37.47516)
			(xy 40.546283 -37.47516) (xy 40.557042 -37.484968) (xy 40.61557 -37.54917) (xy 40.667925 -37.618499)
			(xy 40.713659 -37.692362) (xy 40.752383 -37.77013) (xy 40.783766 -37.85114) (xy 40.807541 -37.9347)
			(xy 40.823504 -38.020096) (xy 40.83152 -38.106602) (xy 40.83152 -38.193478) (xy 40.823504 -38.279984)
			(xy 40.807541 -38.36538) (xy 40.783766 -38.44894) (xy 40.76741 -38.49116) (xy 43.759118 -38.49116)
			(xy 43.763189 -38.435538) (xy 43.775315 -38.381101) (xy 43.795238 -38.32901) (xy 43.822534 -38.280375)
			(xy 43.85662 -38.236232) (xy 43.896769 -38.197523) (xy 43.942127 -38.165072) (xy 43.991727 -38.139571)
			(xy 44.044511 -38.121564) (xy 44.099354 -38.111434) (xy 44.155088 -38.109397) (xy 44.210525 -38.115497)
			(xy 44.264482 -38.129603) (xy 44.315811 -38.151415) (xy 44.363417 -38.180469) (xy 44.406285 -38.216144)
			(xy 44.443502 -38.257681) (xy 44.474275 -38.304194) (xy 44.479405 -38.315138) (xy 58.417966 -38.315138)
			(xy 58.422037 -38.259516) (xy 58.434163 -38.205079) (xy 58.454086 -38.152988) (xy 58.481382 -38.104353)
			(xy 58.515468 -38.06021) (xy 58.555617 -38.021501) (xy 58.600975 -37.98905) (xy 58.650575 -37.963549)
			(xy 58.703359 -37.945542) (xy 58.758202 -37.935412) (xy 58.813936 -37.933375) (xy 58.869373 -37.939475)
			(xy 58.92333 -37.953581) (xy 58.974659 -37.975393) (xy 59.022265 -38.004447) (xy 59.065133 -38.040122)
			(xy 59.10235 -38.081659) (xy 59.133123 -38.128172) (xy 59.156795 -38.178669) (xy 59.161238 -38.193438)
			(xy 63.098171 -38.193438) (xy 63.098171 -38.106562) (xy 63.106187 -38.020058) (xy 63.12215 -37.934662)
			(xy 63.145925 -37.851103) (xy 63.177308 -37.770095) (xy 63.216032 -37.692327) (xy 63.261767 -37.618465)
			(xy 63.314121 -37.549137) (xy 63.372649 -37.484936) (xy 63.436851 -37.42641) (xy 63.50618 -37.374056)
			(xy 63.580043 -37.328323) (xy 63.657811 -37.289601) (xy 63.73882 -37.258219) (xy 63.822379 -37.234446)
			(xy 63.907776 -37.218484) (xy 63.99428 -37.21047) (xy 64.037718 -37.209984) (xy 64.115696 -37.209984)
			(xy 64.125719 -37.209577) (xy 64.144239 -37.201905) (xy 64.158412 -37.187729) (xy 64.166079 -37.169207)
			(xy 64.166496 -37.159184) (xy 64.166496 -37.151564) (xy 64.162178 -37.137594) (xy 64.158114 -37.131244)
			(xy 64.134195 -37.094009) (xy 64.092494 -37.015944) (xy 64.058109 -36.93439) (xy 64.031331 -36.850033)
			(xy 64.012382 -36.76358) (xy 64.001422 -36.675755) (xy 63.998544 -36.587297) (xy 64.003771 -36.498946)
			(xy 64.017059 -36.411443) (xy 64.038297 -36.325524) (xy 64.067306 -36.241908) (xy 64.103844 -36.161296)
			(xy 64.147605 -36.084366) (xy 64.198219 -36.011762) (xy 64.255265 -35.944093) (xy 64.318262 -35.881927)
			(xy 64.386682 -35.825786) (xy 64.459952 -35.776139) (xy 64.537457 -35.733405) (xy 64.618546 -35.69794)
			(xy 64.70254 -35.670044) (xy 64.788734 -35.649948) (xy 64.876405 -35.637824) (xy 64.964818 -35.633771)
			(xy 65.053231 -35.637824) (xy 65.140902 -35.649948) (xy 65.227096 -35.670044) (xy 65.31109 -35.69794)
			(xy 65.392179 -35.733405) (xy 65.469684 -35.776139) (xy 65.542954 -35.825786) (xy 65.60505 -35.876738)
			(xy 70.717154 -35.876738) (xy 70.721225 -35.821116) (xy 70.733351 -35.766679) (xy 70.753274 -35.714588)
			(xy 70.78057 -35.665953) (xy 70.814656 -35.62181) (xy 70.854805 -35.583101) (xy 70.900163 -35.55065)
			(xy 70.949763 -35.525149) (xy 71.002547 -35.507142) (xy 71.05739 -35.497012) (xy 71.113124 -35.494975)
			(xy 71.168561 -35.501075) (xy 71.222518 -35.515181) (xy 71.273847 -35.536993) (xy 71.321453 -35.566047)
			(xy 71.364321 -35.601722) (xy 71.401538 -35.643259) (xy 71.432311 -35.689772) (xy 71.455983 -35.740269)
			(xy 71.472051 -35.793676) (xy 71.480171 -35.848852) (xy 71.48068 -35.876738) (xy 74.788774 -35.876738)
			(xy 74.792845 -35.821116) (xy 74.804971 -35.766679) (xy 74.824894 -35.714588) (xy 74.85219 -35.665953)
			(xy 74.886276 -35.62181) (xy 74.926425 -35.583101) (xy 74.971783 -35.55065) (xy 75.021383 -35.525149)
			(xy 75.074167 -35.507142) (xy 75.12901 -35.497012) (xy 75.184744 -35.494975) (xy 75.240181 -35.501075)
			(xy 75.294138 -35.515181) (xy 75.345467 -35.536993) (xy 75.393073 -35.566047) (xy 75.435941 -35.601722)
			(xy 75.473158 -35.643259) (xy 75.503931 -35.689772) (xy 75.527603 -35.740269) (xy 75.543671 -35.793676)
			(xy 75.551791 -35.848852) (xy 75.5523 -35.876738) (xy 75.551791 -35.904624) (xy 75.543671 -35.9598)
			(xy 75.527603 -36.013207) (xy 75.503931 -36.063704) (xy 75.473158 -36.110217) (xy 75.435941 -36.151754)
			(xy 75.393073 -36.187429) (xy 75.345467 -36.216483) (xy 75.294138 -36.238295) (xy 75.240181 -36.252401)
			(xy 75.184744 -36.258501) (xy 75.12901 -36.256464) (xy 75.074167 -36.246334) (xy 75.021383 -36.228327)
			(xy 74.971783 -36.202826) (xy 74.926425 -36.170375) (xy 74.886276 -36.131666) (xy 74.85219 -36.087523)
			(xy 74.824894 -36.038888) (xy 74.804971 -35.986797) (xy 74.792845 -35.93236) (xy 74.788774 -35.876738)
			(xy 71.48068 -35.876738) (xy 71.480171 -35.904624) (xy 71.472051 -35.9598) (xy 71.455983 -36.013207)
			(xy 71.432311 -36.063704) (xy 71.401538 -36.110217) (xy 71.364321 -36.151754) (xy 71.321453 -36.187429)
			(xy 71.273847 -36.216483) (xy 71.222518 -36.238295) (xy 71.168561 -36.252401) (xy 71.113124 -36.258501)
			(xy 71.05739 -36.256464) (xy 71.002547 -36.246334) (xy 70.949763 -36.228327) (xy 70.900163 -36.202826)
			(xy 70.854805 -36.170375) (xy 70.814656 -36.131666) (xy 70.78057 -36.087523) (xy 70.753274 -36.038888)
			(xy 70.733351 -35.986797) (xy 70.721225 -35.93236) (xy 70.717154 -35.876738) (xy 65.60505 -35.876738)
			(xy 65.611374 -35.881927) (xy 65.674371 -35.944093) (xy 65.731417 -36.011762) (xy 65.782031 -36.084366)
			(xy 65.825792 -36.161296) (xy 65.86233 -36.241908) (xy 65.891339 -36.325524) (xy 65.912577 -36.411443)
			(xy 65.925865 -36.498946) (xy 65.926517 -36.50996) (xy 72.613772 -36.50996) (xy 72.617843 -36.454338)
			(xy 72.629969 -36.399901) (xy 72.649892 -36.34781) (xy 72.677188 -36.299175) (xy 72.711274 -36.255032)
			(xy 72.751423 -36.216323) (xy 72.796781 -36.183872) (xy 72.846381 -36.158371) (xy 72.899165 -36.140364)
			(xy 72.954008 -36.130234) (xy 73.009742 -36.128197) (xy 73.065179 -36.134297) (xy 73.119136 -36.148403)
			(xy 73.170465 -36.170215) (xy 73.218071 -36.199269) (xy 73.260939 -36.234944) (xy 73.298156 -36.276481)
			(xy 73.328929 -36.322994) (xy 73.352601 -36.373491) (xy 73.368669 -36.426898) (xy 73.372594 -36.453572)
			(xy 75.928472 -36.453572) (xy 75.932543 -36.39795) (xy 75.944669 -36.343513) (xy 75.964592 -36.291422)
			(xy 75.991888 -36.242787) (xy 76.025974 -36.198644) (xy 76.066123 -36.159935) (xy 76.111481 -36.127484)
			(xy 76.161081 -36.101983) (xy 76.213865 -36.083976) (xy 76.268708 -36.073846) (xy 76.324442 -36.071809)
			(xy 76.379879 -36.077909) (xy 76.433836 -36.092015) (xy 76.485165 -36.113827) (xy 76.532771 -36.142881)
			(xy 76.575639 -36.178556) (xy 76.612856 -36.220093) (xy 76.643629 -36.266606) (xy 76.667301 -36.317103)
			(xy 76.683369 -36.37051) (xy 76.691489 -36.425686) (xy 76.691998 -36.453572) (xy 76.691489 -36.481458)
			(xy 76.683369 -36.536634) (xy 76.667301 -36.590041) (xy 76.643629 -36.640538) (xy 76.612856 -36.687051)
			(xy 76.575639 -36.728588) (xy 76.532771 -36.764263) (xy 76.485165 -36.793317) (xy 76.433836 -36.815129)
			(xy 76.379879 -36.829235) (xy 76.324442 -36.835335) (xy 76.268708 -36.833298) (xy 76.213865 -36.823168)
			(xy 76.161081 -36.805161) (xy 76.111481 -36.77966) (xy 76.066123 -36.747209) (xy 76.025974 -36.7085)
			(xy 75.991888 -36.664357) (xy 75.964592 -36.615722) (xy 75.944669 -36.563631) (xy 75.932543 -36.509194)
			(xy 75.928472 -36.453572) (xy 73.372594 -36.453572) (xy 73.376789 -36.482074) (xy 73.377298 -36.50996)
			(xy 73.376789 -36.537846) (xy 73.368669 -36.593022) (xy 73.352601 -36.646429) (xy 73.328929 -36.696926)
			(xy 73.298156 -36.743439) (xy 73.260939 -36.784976) (xy 73.218071 -36.820651) (xy 73.170465 -36.849705)
			(xy 73.119136 -36.871517) (xy 73.065179 -36.885623) (xy 73.009742 -36.891723) (xy 72.954008 -36.889686)
			(xy 72.899165 -36.879556) (xy 72.846381 -36.861549) (xy 72.796781 -36.836048) (xy 72.751423 -36.803597)
			(xy 72.711274 -36.764888) (xy 72.677188 -36.720745) (xy 72.649892 -36.67211) (xy 72.629969 -36.620019)
			(xy 72.617843 -36.565582) (xy 72.613772 -36.50996) (xy 65.926517 -36.50996) (xy 65.931092 -36.587297)
			(xy 65.928214 -36.675755) (xy 65.917254 -36.76358) (xy 65.898305 -36.850033) (xy 65.871527 -36.93439)
			(xy 65.837142 -37.015944) (xy 65.795441 -37.094009) (xy 65.771522 -37.131244) (xy 65.767458 -37.137594)
			(xy 65.76314 -37.151564) (xy 65.76314 -37.159184) (xy 65.763533 -37.169209) (xy 65.771206 -37.187734)
			(xy 65.785387 -37.201908) (xy 65.803915 -37.209571) (xy 65.81394 -37.209984) (xy 65.891918 -37.209984)
			(xy 65.935357 -37.21041) (xy 66.021865 -37.218428) (xy 66.107264 -37.234394) (xy 66.190826 -37.25817)
			(xy 66.271838 -37.289556) (xy 66.349608 -37.328282) (xy 66.423473 -37.374019) (xy 66.492803 -37.426376)
			(xy 66.546316 -37.47516) (xy 69.759066 -37.47516) (xy 69.763137 -37.419538) (xy 69.775263 -37.365101)
			(xy 69.795186 -37.31301) (xy 69.822482 -37.264375) (xy 69.856568 -37.220232) (xy 69.896717 -37.181523)
			(xy 69.942075 -37.149072) (xy 69.991675 -37.123571) (xy 70.044459 -37.105564) (xy 70.099302 -37.095434)
			(xy 70.155036 -37.093397) (xy 70.210473 -37.099497) (xy 70.26443 -37.113603) (xy 70.315759 -37.135415)
			(xy 70.363365 -37.164469) (xy 70.406233 -37.200144) (xy 70.407084 -37.201094) (xy 73.716386 -37.201094)
			(xy 73.720457 -37.145472) (xy 73.732583 -37.091035) (xy 73.752506 -37.038944) (xy 73.779802 -36.990309)
			(xy 73.813888 -36.946166) (xy 73.854037 -36.907457) (xy 73.899395 -36.875006) (xy 73.948995 -36.849505)
			(xy 74.001779 -36.831498) (xy 74.056622 -36.821368) (xy 74.112356 -36.819331) (xy 74.167793 -36.825431)
			(xy 74.22175 -36.839537) (xy 74.273079 -36.861349) (xy 74.320685 -36.890403) (xy 74.363553 -36.926078)
			(xy 74.40077 -36.967615) (xy 74.431543 -37.014128) (xy 74.455215 -37.064625) (xy 74.461961 -37.087048)
			(xy 83.200748 -37.087048) (xy 83.201212 -37.060444) (xy 83.208589 -37.007751) (xy 83.223218 -36.956595)
			(xy 83.244818 -36.907969) (xy 83.272968 -36.862818) (xy 83.307121 -36.822019) (xy 83.346614 -36.786364)
			(xy 83.368388 -36.771072) (xy 83.378313 -36.763542) (xy 83.39004 -36.741598) (xy 83.39074 -36.729162)
			(xy 83.39074 -36.644834) (xy 83.390068 -36.632384) (xy 83.378358 -36.610408) (xy 83.368388 -36.602924)
			(xy 83.346631 -36.587611) (xy 83.307149 -36.551949) (xy 83.273003 -36.51115) (xy 83.244855 -36.466003)
			(xy 83.223251 -36.417384) (xy 83.208609 -36.366236) (xy 83.201212 -36.313549) (xy 83.200748 -36.286948)
			(xy 83.2013 -36.259698) (xy 83.209049 -36.205753) (xy 83.224397 -36.153459) (xy 83.247031 -36.103882)
			(xy 83.276489 -36.058031) (xy 83.312174 -36.016839) (xy 83.353357 -35.981145) (xy 83.399201 -35.951675)
			(xy 83.448773 -35.929029) (xy 83.501063 -35.913669) (xy 83.555006 -35.905906) (xy 83.582256 -35.90544)
			(xy 83.586828 -35.90544) (xy 83.596037 -35.905167) (xy 83.613356 -35.898927) (xy 83.62061 -35.893248)
			(xy 83.67141 -35.84956) (xy 83.678116 -35.843324) (xy 83.686975 -35.827314) (xy 83.688682 -35.818318)
			(xy 83.688682 -35.818064) (xy 83.69303 -35.791134) (xy 83.70834 -35.738778) (xy 83.730951 -35.689136)
			(xy 83.760402 -35.643221) (xy 83.796093 -35.601969) (xy 83.837295 -35.566221) (xy 83.883169 -35.536706)
			(xy 83.932779 -35.514026) (xy 83.985114 -35.498643) (xy 84.039106 -35.49087) (xy 84.06638 -35.490404)
			(xy 84.093635 -35.490842) (xy 84.14759 -35.498596) (xy 84.199891 -35.513951) (xy 84.249476 -35.536593)
			(xy 84.295333 -35.566062) (xy 84.336529 -35.601757) (xy 84.372226 -35.642951) (xy 84.401697 -35.688807)
			(xy 84.424342 -35.73839) (xy 84.439699 -35.790691) (xy 84.447457 -35.844645) (xy 84.447457 -35.899155)
			(xy 84.439699 -35.953109) (xy 84.424342 -36.00541) (xy 84.401697 -36.054993) (xy 84.372226 -36.100849)
			(xy 84.336529 -36.142043) (xy 84.295333 -36.177738) (xy 84.249476 -36.207207) (xy 84.199891 -36.229849)
			(xy 84.14759 -36.245204) (xy 84.093635 -36.252958) (xy 84.06638 -36.25342) (xy 84.061808 -36.25342)
			(xy 84.052594 -36.253648) (xy 84.035275 -36.259918) (xy 84.028026 -36.265612) (xy 83.977226 -36.3093)
			(xy 83.970488 -36.315506) (xy 83.961649 -36.331538) (xy 83.959954 -36.340542) (xy 83.959954 -36.340796)
			(xy 83.955755 -36.366999) (xy 83.941071 -36.417993) (xy 83.919458 -36.466459) (xy 83.891334 -36.51146)
			(xy 83.887907 -36.515548) (xy 85.014052 -36.515548) (xy 85.018123 -36.459926) (xy 85.030249 -36.405489)
			(xy 85.050172 -36.353398) (xy 85.077468 -36.304763) (xy 85.111554 -36.26062) (xy 85.151703 -36.221911)
			(xy 85.197061 -36.18946) (xy 85.246661 -36.163959) (xy 85.299445 -36.145952) (xy 85.354288 -36.135822)
			(xy 85.410022 -36.133785) (xy 85.465459 -36.139885) (xy 85.519416 -36.153991) (xy 85.570745 -36.175803)
			(xy 85.618351 -36.204857) (xy 85.661219 -36.240532) (xy 85.698436 -36.282069) (xy 85.729209 -36.328582)
			(xy 85.752881 -36.379079) (xy 85.768949 -36.432486) (xy 85.777069 -36.487662) (xy 85.777578 -36.515548)
			(xy 85.777069 -36.543434) (xy 85.768949 -36.59861) (xy 85.752881 -36.652017) (xy 85.729209 -36.702514)
			(xy 85.698436 -36.749027) (xy 85.661219 -36.790564) (xy 85.618351 -36.826239) (xy 85.570745 -36.855293)
			(xy 85.519416 -36.877105) (xy 85.465459 -36.891211) (xy 85.410022 -36.897311) (xy 85.354288 -36.895274)
			(xy 85.299445 -36.885144) (xy 85.246661 -36.867137) (xy 85.197061 -36.841636) (xy 85.151703 -36.809185)
			(xy 85.111554 -36.770476) (xy 85.077468 -36.726333) (xy 85.050172 -36.677698) (xy 85.030249 -36.625607)
			(xy 85.018123 -36.57117) (xy 85.014052 -36.515548) (xy 83.887907 -36.515548) (xy 83.857243 -36.552127)
			(xy 83.817842 -36.587675) (xy 83.796124 -36.602924) (xy 83.786203 -36.610459) (xy 83.774473 -36.632399)
			(xy 83.773772 -36.644834) (xy 83.773772 -36.729162) (xy 83.774442 -36.741612) (xy 83.786153 -36.763589)
			(xy 83.796124 -36.771072) (xy 83.817882 -36.786384) (xy 83.857363 -36.822046) (xy 83.891508 -36.862846)
			(xy 83.919656 -36.907993) (xy 83.94126 -36.956612) (xy 83.955903 -37.00776) (xy 83.963299 -37.060447)
			(xy 83.963764 -37.087048) (xy 83.963764 -37.087302) (xy 83.963146 -37.119019) (xy 83.952645 -37.181577)
			(xy 83.931917 -37.241528) (xy 83.917282 -37.269674) (xy 83.911948 -37.27958) (xy 83.910424 -37.301678)
			(xy 83.942428 -37.384482) (xy 83.946921 -37.394568) (xy 83.962709 -37.409972) (xy 83.972908 -37.4142)
			(xy 83.997443 -37.423261) (xy 84.043973 -37.447146) (xy 84.086804 -37.477162) (xy 84.125132 -37.512749)
			(xy 84.15824 -37.553238) (xy 84.185506 -37.597871) (xy 84.206418 -37.64581) (xy 84.220586 -37.696157)
			(xy 84.227742 -37.747967) (xy 84.228178 -37.774118) (xy 84.227692 -37.801369) (xy 84.219936 -37.855317)
			(xy 84.204581 -37.907612) (xy 84.181939 -37.957189) (xy 84.152473 -38.003039) (xy 84.116782 -38.04423)
			(xy 84.075591 -38.079921) (xy 84.029741 -38.109387) (xy 83.980164 -38.132029) (xy 83.927869 -38.147384)
			(xy 83.873921 -38.15514) (xy 83.819419 -38.15514) (xy 83.765471 -38.147384) (xy 83.713176 -38.132029)
			(xy 83.663599 -38.109387) (xy 83.617749 -38.079921) (xy 83.576558 -38.04423) (xy 83.540867 -38.003039)
			(xy 83.511401 -37.957189) (xy 83.488759 -37.907612) (xy 83.473404 -37.855317) (xy 83.465648 -37.801369)
			(xy 83.465162 -37.774118) (xy 83.465162 -37.773864) (xy 83.465763 -37.742146) (xy 83.476271 -37.679588)
			(xy 83.497006 -37.619637) (xy 83.511644 -37.591492) (xy 83.516978 -37.581586) (xy 83.518502 -37.559488)
			(xy 83.486498 -37.476684) (xy 83.482049 -37.466574) (xy 83.46623 -37.451182) (xy 83.456018 -37.446966)
			(xy 83.431478 -37.437918) (xy 83.384945 -37.414035) (xy 83.342113 -37.384017) (xy 83.303783 -37.348429)
			(xy 83.270676 -37.307938) (xy 83.243411 -37.263303) (xy 83.2225 -37.215361) (xy 83.208335 -37.165012)
			(xy 83.201182 -37.1132) (xy 83.200748 -37.087048) (xy 74.461961 -37.087048) (xy 74.471283 -37.118032)
			(xy 74.479403 -37.173208) (xy 74.479912 -37.201094) (xy 74.479403 -37.22898) (xy 74.471283 -37.284156)
			(xy 74.455215 -37.337563) (xy 74.431543 -37.38806) (xy 74.40077 -37.434573) (xy 74.363553 -37.47611)
			(xy 74.320685 -37.511785) (xy 74.273079 -37.540839) (xy 74.22175 -37.562651) (xy 74.167793 -37.576757)
			(xy 74.112356 -37.582857) (xy 74.056622 -37.58082) (xy 74.001779 -37.57069) (xy 73.948995 -37.552683)
			(xy 73.899395 -37.527182) (xy 73.854037 -37.494731) (xy 73.813888 -37.456022) (xy 73.779802 -37.411879)
			(xy 73.752506 -37.363244) (xy 73.732583 -37.311153) (xy 73.720457 -37.256716) (xy 73.716386 -37.201094)
			(xy 70.407084 -37.201094) (xy 70.44345 -37.241681) (xy 70.474223 -37.288194) (xy 70.497895 -37.338691)
			(xy 70.513963 -37.392098) (xy 70.522083 -37.447274) (xy 70.522592 -37.47516) (xy 70.522083 -37.503046)
			(xy 70.513963 -37.558222) (xy 70.497895 -37.611629) (xy 70.474223 -37.662126) (xy 70.47407 -37.662358)
			(xy 71.948292 -37.662358) (xy 71.952363 -37.606736) (xy 71.964489 -37.552299) (xy 71.984412 -37.500208)
			(xy 72.011708 -37.451573) (xy 72.045794 -37.40743) (xy 72.085943 -37.368721) (xy 72.131301 -37.33627)
			(xy 72.180901 -37.310769) (xy 72.233685 -37.292762) (xy 72.288528 -37.282632) (xy 72.344262 -37.280595)
			(xy 72.399699 -37.286695) (xy 72.453656 -37.300801) (xy 72.504985 -37.322613) (xy 72.552591 -37.351667)
			(xy 72.595459 -37.387342) (xy 72.632676 -37.428879) (xy 72.663449 -37.475392) (xy 72.687121 -37.525889)
			(xy 72.703189 -37.579296) (xy 72.711309 -37.634472) (xy 72.711818 -37.662358) (xy 72.711309 -37.690244)
			(xy 72.703189 -37.74542) (xy 72.687121 -37.798827) (xy 72.663449 -37.849324) (xy 72.632676 -37.895837)
			(xy 72.595459 -37.937374) (xy 72.552591 -37.973049) (xy 72.504985 -38.002103) (xy 72.453656 -38.023915)
			(xy 72.399699 -38.038021) (xy 72.344262 -38.044121) (xy 72.288528 -38.042084) (xy 72.233685 -38.031954)
			(xy 72.180901 -38.013947) (xy 72.131301 -37.988446) (xy 72.085943 -37.955995) (xy 72.045794 -37.917286)
			(xy 72.011708 -37.873143) (xy 71.984412 -37.824508) (xy 71.964489 -37.772417) (xy 71.952363 -37.71798)
			(xy 71.948292 -37.662358) (xy 70.47407 -37.662358) (xy 70.44345 -37.708639) (xy 70.406233 -37.750176)
			(xy 70.363365 -37.785851) (xy 70.315759 -37.814905) (xy 70.26443 -37.836717) (xy 70.210473 -37.850823)
			(xy 70.155036 -37.856923) (xy 70.099302 -37.854886) (xy 70.044459 -37.844756) (xy 69.991675 -37.826749)
			(xy 69.942075 -37.801248) (xy 69.896717 -37.768797) (xy 69.856568 -37.730088) (xy 69.822482 -37.685945)
			(xy 69.795186 -37.63731) (xy 69.775263 -37.585219) (xy 69.763137 -37.530782) (xy 69.759066 -37.47516)
			(xy 66.546316 -37.47516) (xy 66.557007 -37.484906) (xy 66.615536 -37.549111) (xy 66.667892 -37.618442)
			(xy 66.713627 -37.692308) (xy 66.752352 -37.770079) (xy 66.783735 -37.851091) (xy 66.807511 -37.934653)
			(xy 66.823474 -38.020053) (xy 66.83149 -38.106561) (xy 66.83149 -38.193439) (xy 66.823474 -38.279947)
			(xy 66.807511 -38.365347) (xy 66.783735 -38.448909) (xy 66.767368 -38.49116) (xy 69.759066 -38.49116)
			(xy 69.763137 -38.435538) (xy 69.775263 -38.381101) (xy 69.795186 -38.32901) (xy 69.822482 -38.280375)
			(xy 69.856568 -38.236232) (xy 69.896717 -38.197523) (xy 69.942075 -38.165072) (xy 69.991675 -38.139571)
			(xy 70.044459 -38.121564) (xy 70.099302 -38.111434) (xy 70.155036 -38.109397) (xy 70.210473 -38.115497)
			(xy 70.26443 -38.129603) (xy 70.315759 -38.151415) (xy 70.363365 -38.180469) (xy 70.406233 -38.216144)
			(xy 70.44345 -38.257681) (xy 70.474223 -38.304194) (xy 70.479353 -38.315138) (xy 84.417914 -38.315138)
			(xy 84.421985 -38.259516) (xy 84.434111 -38.205079) (xy 84.454034 -38.152988) (xy 84.48133 -38.104353)
			(xy 84.515416 -38.06021) (xy 84.555565 -38.021501) (xy 84.600923 -37.98905) (xy 84.650523 -37.963549)
			(xy 84.703307 -37.945542) (xy 84.75815 -37.935412) (xy 84.813884 -37.933375) (xy 84.869321 -37.939475)
			(xy 84.923278 -37.953581) (xy 84.974607 -37.975393) (xy 85.022213 -38.004447) (xy 85.065081 -38.040122)
			(xy 85.102298 -38.081659) (xy 85.133071 -38.128172) (xy 85.156743 -38.178669) (xy 85.161185 -38.193435)
			(xy 89.098186 -38.193435) (xy 89.098186 -38.106565) (xy 89.106201 -38.020064) (xy 89.122163 -37.934673)
			(xy 89.145936 -37.851118) (xy 89.177316 -37.770113) (xy 89.216037 -37.692349) (xy 89.261768 -37.61849)
			(xy 89.314118 -37.549165) (xy 89.372641 -37.484965) (xy 89.436838 -37.42644) (xy 89.506162 -37.374087)
			(xy 89.58002 -37.328354) (xy 89.657782 -37.28963) (xy 89.738786 -37.258246) (xy 89.82234 -37.234471)
			(xy 89.907731 -37.218505) (xy 89.994231 -37.210487) (xy 90.037666 -37.209984) (xy 90.115644 -37.209984)
			(xy 90.125656 -37.209547) (xy 90.144152 -37.20187) (xy 90.158304 -37.187702) (xy 90.165959 -37.169197)
			(xy 90.166444 -37.159184) (xy 90.166444 -37.151564) (xy 90.162126 -37.137594) (xy 90.158062 -37.131244)
			(xy 90.134143 -37.094009) (xy 90.092442 -37.015944) (xy 90.058057 -36.93439) (xy 90.031279 -36.850033)
			(xy 90.01233 -36.76358) (xy 90.00137 -36.675755) (xy 89.998492 -36.587297) (xy 90.003719 -36.498946)
			(xy 90.017007 -36.411443) (xy 90.038245 -36.325524) (xy 90.067254 -36.241908) (xy 90.103792 -36.161296)
			(xy 90.147553 -36.084366) (xy 90.198167 -36.011762) (xy 90.255213 -35.944093) (xy 90.31821 -35.881927)
			(xy 90.38663 -35.825786) (xy 90.4599 -35.776139) (xy 90.537405 -35.733405) (xy 90.618494 -35.69794)
			(xy 90.702488 -35.670044) (xy 90.788682 -35.649948) (xy 90.876353 -35.637824) (xy 90.964766 -35.633771)
			(xy 91.053179 -35.637824) (xy 91.14085 -35.649948) (xy 91.227044 -35.670044) (xy 91.311038 -35.69794)
			(xy 91.392127 -35.733405) (xy 91.469632 -35.776139) (xy 91.542902 -35.825786) (xy 91.604998 -35.876738)
			(xy 108.817408 -35.876738) (xy 108.821479 -35.821116) (xy 108.833605 -35.766679) (xy 108.853528 -35.714588)
			(xy 108.880824 -35.665953) (xy 108.91491 -35.62181) (xy 108.955059 -35.583101) (xy 109.000417 -35.55065)
			(xy 109.050017 -35.525149) (xy 109.102801 -35.507142) (xy 109.157644 -35.497012) (xy 109.213378 -35.494975)
			(xy 109.268815 -35.501075) (xy 109.322772 -35.515181) (xy 109.374101 -35.536993) (xy 109.421707 -35.566047)
			(xy 109.464575 -35.601722) (xy 109.501792 -35.643259) (xy 109.532565 -35.689772) (xy 109.556237 -35.740269)
			(xy 109.572305 -35.793676) (xy 109.580425 -35.848852) (xy 109.580934 -35.876738) (xy 112.889028 -35.876738)
			(xy 112.893099 -35.821116) (xy 112.905225 -35.766679) (xy 112.925148 -35.714588) (xy 112.952444 -35.665953)
			(xy 112.98653 -35.62181) (xy 113.026679 -35.583101) (xy 113.072037 -35.55065) (xy 113.121637 -35.525149)
			(xy 113.174421 -35.507142) (xy 113.229264 -35.497012) (xy 113.284998 -35.494975) (xy 113.340435 -35.501075)
			(xy 113.394392 -35.515181) (xy 113.445721 -35.536993) (xy 113.493327 -35.566047) (xy 113.536195 -35.601722)
			(xy 113.573412 -35.643259) (xy 113.604185 -35.689772) (xy 113.627857 -35.740269) (xy 113.643925 -35.793676)
			(xy 113.652045 -35.848852) (xy 113.652554 -35.876738) (xy 113.652045 -35.904624) (xy 113.643925 -35.9598)
			(xy 113.627857 -36.013207) (xy 113.604185 -36.063704) (xy 113.573412 -36.110217) (xy 113.536195 -36.151754)
			(xy 113.493327 -36.187429) (xy 113.445721 -36.216483) (xy 113.394392 -36.238295) (xy 113.340435 -36.252401)
			(xy 113.284998 -36.258501) (xy 113.229264 -36.256464) (xy 113.174421 -36.246334) (xy 113.121637 -36.228327)
			(xy 113.072037 -36.202826) (xy 113.026679 -36.170375) (xy 112.98653 -36.131666) (xy 112.952444 -36.087523)
			(xy 112.925148 -36.038888) (xy 112.905225 -35.986797) (xy 112.893099 -35.93236) (xy 112.889028 -35.876738)
			(xy 109.580934 -35.876738) (xy 109.580425 -35.904624) (xy 109.572305 -35.9598) (xy 109.556237 -36.013207)
			(xy 109.532565 -36.063704) (xy 109.501792 -36.110217) (xy 109.464575 -36.151754) (xy 109.421707 -36.187429)
			(xy 109.374101 -36.216483) (xy 109.322772 -36.238295) (xy 109.268815 -36.252401) (xy 109.213378 -36.258501)
			(xy 109.157644 -36.256464) (xy 109.102801 -36.246334) (xy 109.050017 -36.228327) (xy 109.000417 -36.202826)
			(xy 108.955059 -36.170375) (xy 108.91491 -36.131666) (xy 108.880824 -36.087523) (xy 108.853528 -36.038888)
			(xy 108.833605 -35.986797) (xy 108.821479 -35.93236) (xy 108.817408 -35.876738) (xy 91.604998 -35.876738)
			(xy 91.611322 -35.881927) (xy 91.674319 -35.944093) (xy 91.731365 -36.011762) (xy 91.781979 -36.084366)
			(xy 91.82574 -36.161296) (xy 91.862278 -36.241908) (xy 91.891287 -36.325524) (xy 91.912525 -36.411443)
			(xy 91.925813 -36.498946) (xy 91.926465 -36.50996) (xy 110.714026 -36.50996) (xy 110.718097 -36.454338)
			(xy 110.730223 -36.399901) (xy 110.750146 -36.34781) (xy 110.777442 -36.299175) (xy 110.811528 -36.255032)
			(xy 110.851677 -36.216323) (xy 110.897035 -36.183872) (xy 110.946635 -36.158371) (xy 110.999419 -36.140364)
			(xy 111.054262 -36.130234) (xy 111.109996 -36.128197) (xy 111.165433 -36.134297) (xy 111.21939 -36.148403)
			(xy 111.270719 -36.170215) (xy 111.318325 -36.199269) (xy 111.361193 -36.234944) (xy 111.39841 -36.276481)
			(xy 111.429183 -36.322994) (xy 111.452855 -36.373491) (xy 111.468923 -36.426898) (xy 111.472848 -36.453572)
			(xy 114.028726 -36.453572) (xy 114.032797 -36.39795) (xy 114.044923 -36.343513) (xy 114.064846 -36.291422)
			(xy 114.092142 -36.242787) (xy 114.126228 -36.198644) (xy 114.166377 -36.159935) (xy 114.211735 -36.127484)
			(xy 114.261335 -36.101983) (xy 114.314119 -36.083976) (xy 114.368962 -36.073846) (xy 114.424696 -36.071809)
			(xy 114.480133 -36.077909) (xy 114.53409 -36.092015) (xy 114.585419 -36.113827) (xy 114.633025 -36.142881)
			(xy 114.675893 -36.178556) (xy 114.71311 -36.220093) (xy 114.743883 -36.266606) (xy 114.767555 -36.317103)
			(xy 114.783623 -36.37051) (xy 114.791743 -36.425686) (xy 114.792252 -36.453572) (xy 114.791743 -36.481458)
			(xy 114.783623 -36.536634) (xy 114.767555 -36.590041) (xy 114.743883 -36.640538) (xy 114.71311 -36.687051)
			(xy 114.675893 -36.728588) (xy 114.633025 -36.764263) (xy 114.585419 -36.793317) (xy 114.53409 -36.815129)
			(xy 114.480133 -36.829235) (xy 114.424696 -36.835335) (xy 114.368962 -36.833298) (xy 114.314119 -36.823168)
			(xy 114.261335 -36.805161) (xy 114.211735 -36.77966) (xy 114.166377 -36.747209) (xy 114.126228 -36.7085)
			(xy 114.092142 -36.664357) (xy 114.064846 -36.615722) (xy 114.044923 -36.563631) (xy 114.032797 -36.509194)
			(xy 114.028726 -36.453572) (xy 111.472848 -36.453572) (xy 111.477043 -36.482074) (xy 111.477552 -36.50996)
			(xy 111.477043 -36.537846) (xy 111.468923 -36.593022) (xy 111.452855 -36.646429) (xy 111.429183 -36.696926)
			(xy 111.39841 -36.743439) (xy 111.361193 -36.784976) (xy 111.318325 -36.820651) (xy 111.270719 -36.849705)
			(xy 111.21939 -36.871517) (xy 111.165433 -36.885623) (xy 111.109996 -36.891723) (xy 111.054262 -36.889686)
			(xy 110.999419 -36.879556) (xy 110.946635 -36.861549) (xy 110.897035 -36.836048) (xy 110.851677 -36.803597)
			(xy 110.811528 -36.764888) (xy 110.777442 -36.720745) (xy 110.750146 -36.67211) (xy 110.730223 -36.620019)
			(xy 110.718097 -36.565582) (xy 110.714026 -36.50996) (xy 91.926465 -36.50996) (xy 91.93104 -36.587297)
			(xy 91.928162 -36.675755) (xy 91.917202 -36.76358) (xy 91.898253 -36.850033) (xy 91.871475 -36.93439)
			(xy 91.83709 -37.015944) (xy 91.795389 -37.094009) (xy 91.77147 -37.131244) (xy 91.767406 -37.137594)
			(xy 91.763088 -37.151564) (xy 91.763088 -37.159184) (xy 91.763532 -37.169203) (xy 91.771195 -37.187717)
			(xy 91.785359 -37.20189) (xy 91.803869 -37.209562) (xy 91.813888 -37.209984) (xy 91.891866 -37.209984)
			(xy 91.935308 -37.210393) (xy 92.02182 -37.218407) (xy 92.107225 -37.234369) (xy 92.190792 -37.258143)
			(xy 92.271809 -37.289527) (xy 92.349584 -37.328252) (xy 92.423455 -37.373988) (xy 92.49279 -37.426345)
			(xy 92.54634 -37.47516) (xy 107.85932 -37.47516) (xy 107.863391 -37.419538) (xy 107.875517 -37.365101)
			(xy 107.89544 -37.31301) (xy 107.922736 -37.264375) (xy 107.956822 -37.220232) (xy 107.996971 -37.181523)
			(xy 108.042329 -37.149072) (xy 108.091929 -37.123571) (xy 108.144713 -37.105564) (xy 108.199556 -37.095434)
			(xy 108.25529 -37.093397) (xy 108.310727 -37.099497) (xy 108.364684 -37.113603) (xy 108.416013 -37.135415)
			(xy 108.463619 -37.164469) (xy 108.506487 -37.200144) (xy 108.507338 -37.201094) (xy 111.81664 -37.201094)
			(xy 111.820711 -37.145472) (xy 111.832837 -37.091035) (xy 111.85276 -37.038944) (xy 111.880056 -36.990309)
			(xy 111.914142 -36.946166) (xy 111.954291 -36.907457) (xy 111.999649 -36.875006) (xy 112.049249 -36.849505)
			(xy 112.102033 -36.831498) (xy 112.156876 -36.821368) (xy 112.21261 -36.819331) (xy 112.268047 -36.825431)
			(xy 112.322004 -36.839537) (xy 112.373333 -36.861349) (xy 112.420939 -36.890403) (xy 112.463807 -36.926078)
			(xy 112.501024 -36.967615) (xy 112.531797 -37.014128) (xy 112.555469 -37.064625) (xy 112.562215 -37.087048)
			(xy 121.301002 -37.087048) (xy 121.301486 -37.060445) (xy 121.308862 -37.007754) (xy 121.32349 -36.956599)
			(xy 121.345086 -36.907974) (xy 121.373232 -36.862823) (xy 121.407381 -36.822023) (xy 121.44687 -36.786366)
			(xy 121.468642 -36.771072) (xy 121.478475 -36.763462) (xy 121.490164 -36.741567) (xy 121.490994 -36.729162)
			(xy 121.490994 -36.644834) (xy 121.49034 -36.632381) (xy 121.478619 -36.610404) (xy 121.468642 -36.602924)
			(xy 121.446875 -36.587625) (xy 121.407395 -36.55196) (xy 121.373252 -36.511157) (xy 121.345106 -36.466008)
			(xy 121.323503 -36.417387) (xy 121.308862 -36.366237) (xy 121.301466 -36.31355) (xy 121.301002 -36.286948)
			(xy 121.3015 -36.259696) (xy 121.309251 -36.205746) (xy 121.324601 -36.153448) (xy 121.347239 -36.103867)
			(xy 121.376703 -36.058013) (xy 121.412393 -36.01682) (xy 121.453583 -35.981125) (xy 121.499434 -35.951657)
			(xy 121.549012 -35.929014) (xy 121.601308 -35.913659) (xy 121.655258 -35.905903) (xy 121.68251 -35.90544)
			(xy 121.687082 -35.90544) (xy 121.696294 -35.905194) (xy 121.713612 -35.898935) (xy 121.720864 -35.893248)
			(xy 121.771664 -35.84956) (xy 121.778379 -35.843332) (xy 121.787232 -35.827316) (xy 121.788936 -35.818318)
			(xy 121.788936 -35.818064) (xy 121.793232 -35.791124) (xy 121.808545 -35.738764) (xy 121.83116 -35.689119)
			(xy 121.860617 -35.643202) (xy 121.896313 -35.601949) (xy 121.937522 -35.566201) (xy 121.983402 -35.536688)
			(xy 122.033019 -35.514011) (xy 122.08536 -35.498633) (xy 122.139357 -35.490867) (xy 122.166634 -35.490404)
			(xy 122.193885 -35.490868) (xy 122.24783 -35.498629) (xy 122.300123 -35.513987) (xy 122.349697 -35.536631)
			(xy 122.395545 -35.566099) (xy 122.436732 -35.601792) (xy 122.472421 -35.642983) (xy 122.501885 -35.688833)
			(xy 122.524525 -35.738409) (xy 122.539878 -35.790703) (xy 122.547634 -35.844649) (xy 122.547634 -35.899151)
			(xy 122.539878 -35.953097) (xy 122.524525 -36.005391) (xy 122.501885 -36.054967) (xy 122.472421 -36.100817)
			(xy 122.436732 -36.142008) (xy 122.395545 -36.177701) (xy 122.349697 -36.207169) (xy 122.300123 -36.229813)
			(xy 122.24783 -36.245171) (xy 122.193885 -36.252932) (xy 122.166634 -36.25342) (xy 122.162062 -36.25342)
			(xy 122.152851 -36.253674) (xy 122.135531 -36.259926) (xy 122.12828 -36.265612) (xy 122.07748 -36.3093)
			(xy 122.070751 -36.315515) (xy 122.061905 -36.33154) (xy 122.060208 -36.340542) (xy 122.060208 -36.340796)
			(xy 122.055987 -36.366995) (xy 122.041305 -36.417988) (xy 122.019696 -36.466453) (xy 121.991576 -36.511454)
			(xy 121.988145 -36.515548) (xy 123.114306 -36.515548) (xy 123.118377 -36.459926) (xy 123.130503 -36.405489)
			(xy 123.150426 -36.353398) (xy 123.177722 -36.304763) (xy 123.211808 -36.26062) (xy 123.251957 -36.221911)
			(xy 123.297315 -36.18946) (xy 123.346915 -36.163959) (xy 123.399699 -36.145952) (xy 123.454542 -36.135822)
			(xy 123.510276 -36.133785) (xy 123.565713 -36.139885) (xy 123.61967 -36.153991) (xy 123.670999 -36.175803)
			(xy 123.718605 -36.204857) (xy 123.761473 -36.240532) (xy 123.79869 -36.282069) (xy 123.829463 -36.328582)
			(xy 123.853135 -36.379079) (xy 123.869203 -36.432486) (xy 123.877323 -36.487662) (xy 123.877832 -36.515548)
			(xy 123.877323 -36.543434) (xy 123.869203 -36.59861) (xy 123.853135 -36.652017) (xy 123.829463 -36.702514)
			(xy 123.79869 -36.749027) (xy 123.761473 -36.790564) (xy 123.718605 -36.826239) (xy 123.670999 -36.855293)
			(xy 123.61967 -36.877105) (xy 123.565713 -36.891211) (xy 123.510276 -36.897311) (xy 123.454542 -36.895274)
			(xy 123.399699 -36.885144) (xy 123.346915 -36.867137) (xy 123.297315 -36.841636) (xy 123.251957 -36.809185)
			(xy 123.211808 -36.770476) (xy 123.177722 -36.726333) (xy 123.150426 -36.677698) (xy 123.130503 -36.625607)
			(xy 123.118377 -36.57117) (xy 123.114306 -36.515548) (xy 121.988145 -36.515548) (xy 121.957489 -36.552123)
			(xy 121.918094 -36.587673) (xy 121.896378 -36.602924) (xy 121.886449 -36.610449) (xy 121.874725 -36.632397)
			(xy 121.874026 -36.644834) (xy 121.874026 -36.729162) (xy 121.874675 -36.741616) (xy 121.886398 -36.763593)
			(xy 121.896378 -36.771072) (xy 121.918148 -36.786367) (xy 121.957626 -36.822034) (xy 121.991769 -36.862838)
			(xy 122.019914 -36.907988) (xy 122.041517 -36.956609) (xy 122.056158 -37.007759) (xy 122.063553 -37.060446)
			(xy 122.064018 -37.087048) (xy 122.064018 -37.087302) (xy 122.063394 -37.119019) (xy 122.052894 -37.181576)
			(xy 122.032169 -37.241528) (xy 122.017536 -37.269674) (xy 122.012202 -37.27958) (xy 122.010678 -37.301678)
			(xy 122.042682 -37.384482) (xy 122.047152 -37.394581) (xy 122.062955 -37.409979) (xy 122.073162 -37.4142)
			(xy 122.097687 -37.423288) (xy 122.144218 -37.447167) (xy 122.18705 -37.477179) (xy 122.22538 -37.512762)
			(xy 122.25849 -37.553248) (xy 122.285757 -37.597878) (xy 122.306671 -37.645815) (xy 122.320839 -37.696159)
			(xy 122.327996 -37.747968) (xy 122.328432 -37.774118) (xy 122.327946 -37.801369) (xy 122.32019 -37.855317)
			(xy 122.304835 -37.907612) (xy 122.282193 -37.957189) (xy 122.252727 -38.003039) (xy 122.217036 -38.04423)
			(xy 122.175845 -38.079921) (xy 122.129995 -38.109387) (xy 122.080418 -38.132029) (xy 122.028123 -38.147384)
			(xy 121.974175 -38.15514) (xy 121.919673 -38.15514) (xy 121.865725 -38.147384) (xy 121.81343 -38.132029)
			(xy 121.763853 -38.109387) (xy 121.718003 -38.079921) (xy 121.676812 -38.04423) (xy 121.641121 -38.003039)
			(xy 121.611655 -37.957189) (xy 121.589013 -37.907612) (xy 121.573658 -37.855317) (xy 121.565902 -37.801369)
			(xy 121.565416 -37.774118) (xy 121.565416 -37.773864) (xy 121.566023 -37.742147) (xy 121.576529 -37.679588)
			(xy 121.597262 -37.619637) (xy 121.611898 -37.591492) (xy 121.617232 -37.581586) (xy 121.618756 -37.559488)
			(xy 121.586752 -37.476684) (xy 121.58228 -37.466587) (xy 121.566477 -37.451189) (xy 121.556272 -37.446966)
			(xy 121.531721 -37.437945) (xy 121.48519 -37.414056) (xy 121.442359 -37.384034) (xy 121.404031 -37.348442)
			(xy 121.370925 -37.307947) (xy 121.343661 -37.263309) (xy 121.322752 -37.215365) (xy 121.308588 -37.165014)
			(xy 121.301436 -37.113201) (xy 121.301002 -37.087048) (xy 112.562215 -37.087048) (xy 112.571537 -37.118032)
			(xy 112.579657 -37.173208) (xy 112.580166 -37.201094) (xy 112.579657 -37.22898) (xy 112.571537 -37.284156)
			(xy 112.555469 -37.337563) (xy 112.531797 -37.38806) (xy 112.501024 -37.434573) (xy 112.463807 -37.47611)
			(xy 112.420939 -37.511785) (xy 112.373333 -37.540839) (xy 112.322004 -37.562651) (xy 112.268047 -37.576757)
			(xy 112.21261 -37.582857) (xy 112.156876 -37.58082) (xy 112.102033 -37.57069) (xy 112.049249 -37.552683)
			(xy 111.999649 -37.527182) (xy 111.954291 -37.494731) (xy 111.914142 -37.456022) (xy 111.880056 -37.411879)
			(xy 111.85276 -37.363244) (xy 111.832837 -37.311153) (xy 111.820711 -37.256716) (xy 111.81664 -37.201094)
			(xy 108.507338 -37.201094) (xy 108.543704 -37.241681) (xy 108.574477 -37.288194) (xy 108.598149 -37.338691)
			(xy 108.614217 -37.392098) (xy 108.622337 -37.447274) (xy 108.622846 -37.47516) (xy 108.622337 -37.503046)
			(xy 108.614217 -37.558222) (xy 108.598149 -37.611629) (xy 108.574477 -37.662126) (xy 108.574324 -37.662358)
			(xy 110.048546 -37.662358) (xy 110.052617 -37.606736) (xy 110.064743 -37.552299) (xy 110.084666 -37.500208)
			(xy 110.111962 -37.451573) (xy 110.146048 -37.40743) (xy 110.186197 -37.368721) (xy 110.231555 -37.33627)
			(xy 110.281155 -37.310769) (xy 110.333939 -37.292762) (xy 110.388782 -37.282632) (xy 110.444516 -37.280595)
			(xy 110.499953 -37.286695) (xy 110.55391 -37.300801) (xy 110.605239 -37.322613) (xy 110.652845 -37.351667)
			(xy 110.695713 -37.387342) (xy 110.73293 -37.428879) (xy 110.763703 -37.475392) (xy 110.787375 -37.525889)
			(xy 110.803443 -37.579296) (xy 110.811563 -37.634472) (xy 110.812072 -37.662358) (xy 110.811563 -37.690244)
			(xy 110.803443 -37.74542) (xy 110.787375 -37.798827) (xy 110.763703 -37.849324) (xy 110.73293 -37.895837)
			(xy 110.695713 -37.937374) (xy 110.652845 -37.973049) (xy 110.605239 -38.002103) (xy 110.55391 -38.023915)
			(xy 110.499953 -38.038021) (xy 110.444516 -38.044121) (xy 110.388782 -38.042084) (xy 110.333939 -38.031954)
			(xy 110.281155 -38.013947) (xy 110.231555 -37.988446) (xy 110.186197 -37.955995) (xy 110.146048 -37.917286)
			(xy 110.111962 -37.873143) (xy 110.084666 -37.824508) (xy 110.064743 -37.772417) (xy 110.052617 -37.71798)
			(xy 110.048546 -37.662358) (xy 108.574324 -37.662358) (xy 108.543704 -37.708639) (xy 108.506487 -37.750176)
			(xy 108.463619 -37.785851) (xy 108.416013 -37.814905) (xy 108.364684 -37.836717) (xy 108.310727 -37.850823)
			(xy 108.25529 -37.856923) (xy 108.199556 -37.854886) (xy 108.144713 -37.844756) (xy 108.091929 -37.826749)
			(xy 108.042329 -37.801248) (xy 107.996971 -37.768797) (xy 107.956822 -37.730088) (xy 107.922736 -37.685945)
			(xy 107.89544 -37.63731) (xy 107.875517 -37.585219) (xy 107.863391 -37.530782) (xy 107.85932 -37.47516)
			(xy 92.54634 -37.47516) (xy 92.556999 -37.484877) (xy 92.615533 -37.549083) (xy 92.667893 -37.618417)
			(xy 92.713632 -37.692286) (xy 92.75236 -37.77006) (xy 92.783746 -37.851076) (xy 92.807523 -37.934642)
			(xy 92.823489 -38.020046) (xy 92.831505 -38.106558) (xy 92.831505 -38.193442) (xy 92.823489 -38.279954)
			(xy 92.807523 -38.365358) (xy 92.783746 -38.448924) (xy 92.767384 -38.49116) (xy 107.85932 -38.49116)
			(xy 107.863391 -38.435538) (xy 107.875517 -38.381101) (xy 107.89544 -38.32901) (xy 107.922736 -38.280375)
			(xy 107.956822 -38.236232) (xy 107.996971 -38.197523) (xy 108.042329 -38.165072) (xy 108.091929 -38.139571)
			(xy 108.144713 -38.121564) (xy 108.199556 -38.111434) (xy 108.25529 -38.109397) (xy 108.310727 -38.115497)
			(xy 108.364684 -38.129603) (xy 108.416013 -38.151415) (xy 108.463619 -38.180469) (xy 108.506487 -38.216144)
			(xy 108.543704 -38.257681) (xy 108.574477 -38.304194) (xy 108.579607 -38.315138) (xy 122.518168 -38.315138)
			(xy 122.522239 -38.259516) (xy 122.534365 -38.205079) (xy 122.554288 -38.152988) (xy 122.581584 -38.104353)
			(xy 122.61567 -38.06021) (xy 122.655819 -38.021501) (xy 122.701177 -37.98905) (xy 122.750777 -37.963549)
			(xy 122.803561 -37.945542) (xy 122.858404 -37.935412) (xy 122.914138 -37.933375) (xy 122.969575 -37.939475)
			(xy 123.023532 -37.953581) (xy 123.074861 -37.975393) (xy 123.122467 -38.004447) (xy 123.165335 -38.040122)
			(xy 123.202552 -38.081659) (xy 123.233325 -38.128172) (xy 123.256997 -38.178669) (xy 123.26144 -38.193438)
			(xy 127.198371 -38.193438) (xy 127.198371 -38.106562) (xy 127.206387 -38.020058) (xy 127.22235 -37.934662)
			(xy 127.246125 -37.851103) (xy 127.277508 -37.770094) (xy 127.316232 -37.692327) (xy 127.361967 -37.618464)
			(xy 127.414322 -37.549137) (xy 127.47285 -37.484936) (xy 127.537052 -37.426409) (xy 127.606381 -37.374056)
			(xy 127.680244 -37.328323) (xy 127.758012 -37.2896) (xy 127.839022 -37.258219) (xy 127.922581 -37.234445)
			(xy 128.007977 -37.218484) (xy 128.094482 -37.21047) (xy 128.13792 -37.209984) (xy 128.215898 -37.209984)
			(xy 128.225921 -37.209578) (xy 128.244441 -37.201906) (xy 128.258614 -37.187729) (xy 128.266281 -37.169207)
			(xy 128.266698 -37.159184) (xy 128.266698 -37.151564) (xy 128.26238 -37.137594) (xy 128.258316 -37.131244)
			(xy 128.234397 -37.094009) (xy 128.192696 -37.015944) (xy 128.158311 -36.93439) (xy 128.131533 -36.850033)
			(xy 128.112584 -36.76358) (xy 128.101624 -36.675755) (xy 128.098746 -36.587297) (xy 128.103973 -36.498946)
			(xy 128.117261 -36.411443) (xy 128.138499 -36.325524) (xy 128.167508 -36.241908) (xy 128.204046 -36.161296)
			(xy 128.247807 -36.084366) (xy 128.298421 -36.011762) (xy 128.355467 -35.944093) (xy 128.418464 -35.881927)
			(xy 128.486884 -35.825786) (xy 128.560154 -35.776139) (xy 128.637659 -35.733405) (xy 128.718748 -35.69794)
			(xy 128.802742 -35.670044) (xy 128.888936 -35.649948) (xy 128.976607 -35.637824) (xy 129.06502 -35.633771)
			(xy 129.153433 -35.637824) (xy 129.241104 -35.649948) (xy 129.327298 -35.670044) (xy 129.411292 -35.69794)
			(xy 129.492381 -35.733405) (xy 129.569886 -35.776139) (xy 129.643156 -35.825786) (xy 129.705252 -35.876738)
			(xy 134.817356 -35.876738) (xy 134.821427 -35.821116) (xy 134.833553 -35.766679) (xy 134.853476 -35.714588)
			(xy 134.880772 -35.665953) (xy 134.914858 -35.62181) (xy 134.955007 -35.583101) (xy 135.000365 -35.55065)
			(xy 135.049965 -35.525149) (xy 135.102749 -35.507142) (xy 135.157592 -35.497012) (xy 135.213326 -35.494975)
			(xy 135.268763 -35.501075) (xy 135.32272 -35.515181) (xy 135.374049 -35.536993) (xy 135.421655 -35.566047)
			(xy 135.464523 -35.601722) (xy 135.50174 -35.643259) (xy 135.532513 -35.689772) (xy 135.556185 -35.740269)
			(xy 135.572253 -35.793676) (xy 135.580373 -35.848852) (xy 135.580882 -35.876738) (xy 138.888976 -35.876738)
			(xy 138.893047 -35.821116) (xy 138.905173 -35.766679) (xy 138.925096 -35.714588) (xy 138.952392 -35.665953)
			(xy 138.986478 -35.62181) (xy 139.026627 -35.583101) (xy 139.071985 -35.55065) (xy 139.121585 -35.525149)
			(xy 139.174369 -35.507142) (xy 139.229212 -35.497012) (xy 139.284946 -35.494975) (xy 139.340383 -35.501075)
			(xy 139.39434 -35.515181) (xy 139.445669 -35.536993) (xy 139.493275 -35.566047) (xy 139.536143 -35.601722)
			(xy 139.57336 -35.643259) (xy 139.604133 -35.689772) (xy 139.627805 -35.740269) (xy 139.643873 -35.793676)
			(xy 139.651993 -35.848852) (xy 139.652502 -35.876738) (xy 139.651993 -35.904624) (xy 139.643873 -35.9598)
			(xy 139.627805 -36.013207) (xy 139.604133 -36.063704) (xy 139.57336 -36.110217) (xy 139.536143 -36.151754)
			(xy 139.493275 -36.187429) (xy 139.445669 -36.216483) (xy 139.39434 -36.238295) (xy 139.340383 -36.252401)
			(xy 139.284946 -36.258501) (xy 139.229212 -36.256464) (xy 139.174369 -36.246334) (xy 139.121585 -36.228327)
			(xy 139.071985 -36.202826) (xy 139.026627 -36.170375) (xy 138.986478 -36.131666) (xy 138.952392 -36.087523)
			(xy 138.925096 -36.038888) (xy 138.905173 -35.986797) (xy 138.893047 -35.93236) (xy 138.888976 -35.876738)
			(xy 135.580882 -35.876738) (xy 135.580373 -35.904624) (xy 135.572253 -35.9598) (xy 135.556185 -36.013207)
			(xy 135.532513 -36.063704) (xy 135.50174 -36.110217) (xy 135.464523 -36.151754) (xy 135.421655 -36.187429)
			(xy 135.374049 -36.216483) (xy 135.32272 -36.238295) (xy 135.268763 -36.252401) (xy 135.213326 -36.258501)
			(xy 135.157592 -36.256464) (xy 135.102749 -36.246334) (xy 135.049965 -36.228327) (xy 135.000365 -36.202826)
			(xy 134.955007 -36.170375) (xy 134.914858 -36.131666) (xy 134.880772 -36.087523) (xy 134.853476 -36.038888)
			(xy 134.833553 -35.986797) (xy 134.821427 -35.93236) (xy 134.817356 -35.876738) (xy 129.705252 -35.876738)
			(xy 129.711576 -35.881927) (xy 129.774573 -35.944093) (xy 129.831619 -36.011762) (xy 129.882233 -36.084366)
			(xy 129.925994 -36.161296) (xy 129.962532 -36.241908) (xy 129.991541 -36.325524) (xy 130.012779 -36.411443)
			(xy 130.026067 -36.498946) (xy 130.026719 -36.50996) (xy 136.713974 -36.50996) (xy 136.718045 -36.454338)
			(xy 136.730171 -36.399901) (xy 136.750094 -36.34781) (xy 136.77739 -36.299175) (xy 136.811476 -36.255032)
			(xy 136.851625 -36.216323) (xy 136.896983 -36.183872) (xy 136.946583 -36.158371) (xy 136.999367 -36.140364)
			(xy 137.05421 -36.130234) (xy 137.109944 -36.128197) (xy 137.165381 -36.134297) (xy 137.219338 -36.148403)
			(xy 137.270667 -36.170215) (xy 137.318273 -36.199269) (xy 137.361141 -36.234944) (xy 137.398358 -36.276481)
			(xy 137.429131 -36.322994) (xy 137.452803 -36.373491) (xy 137.468871 -36.426898) (xy 137.472796 -36.453572)
			(xy 140.028674 -36.453572) (xy 140.032745 -36.39795) (xy 140.044871 -36.343513) (xy 140.064794 -36.291422)
			(xy 140.09209 -36.242787) (xy 140.126176 -36.198644) (xy 140.166325 -36.159935) (xy 140.211683 -36.127484)
			(xy 140.261283 -36.101983) (xy 140.314067 -36.083976) (xy 140.36891 -36.073846) (xy 140.424644 -36.071809)
			(xy 140.480081 -36.077909) (xy 140.534038 -36.092015) (xy 140.585367 -36.113827) (xy 140.632973 -36.142881)
			(xy 140.675841 -36.178556) (xy 140.713058 -36.220093) (xy 140.743831 -36.266606) (xy 140.767503 -36.317103)
			(xy 140.783571 -36.37051) (xy 140.791691 -36.425686) (xy 140.7922 -36.453572) (xy 140.791691 -36.481458)
			(xy 140.783571 -36.536634) (xy 140.767503 -36.590041) (xy 140.743831 -36.640538) (xy 140.713058 -36.687051)
			(xy 140.675841 -36.728588) (xy 140.632973 -36.764263) (xy 140.585367 -36.793317) (xy 140.534038 -36.815129)
			(xy 140.480081 -36.829235) (xy 140.424644 -36.835335) (xy 140.36891 -36.833298) (xy 140.314067 -36.823168)
			(xy 140.261283 -36.805161) (xy 140.211683 -36.77966) (xy 140.166325 -36.747209) (xy 140.126176 -36.7085)
			(xy 140.09209 -36.664357) (xy 140.064794 -36.615722) (xy 140.044871 -36.563631) (xy 140.032745 -36.509194)
			(xy 140.028674 -36.453572) (xy 137.472796 -36.453572) (xy 137.476991 -36.482074) (xy 137.4775 -36.50996)
			(xy 137.476991 -36.537846) (xy 137.468871 -36.593022) (xy 137.452803 -36.646429) (xy 137.429131 -36.696926)
			(xy 137.398358 -36.743439) (xy 137.361141 -36.784976) (xy 137.318273 -36.820651) (xy 137.270667 -36.849705)
			(xy 137.219338 -36.871517) (xy 137.165381 -36.885623) (xy 137.109944 -36.891723) (xy 137.05421 -36.889686)
			(xy 136.999367 -36.879556) (xy 136.946583 -36.861549) (xy 136.896983 -36.836048) (xy 136.851625 -36.803597)
			(xy 136.811476 -36.764888) (xy 136.77739 -36.720745) (xy 136.750094 -36.67211) (xy 136.730171 -36.620019)
			(xy 136.718045 -36.565582) (xy 136.713974 -36.50996) (xy 130.026719 -36.50996) (xy 130.031294 -36.587297)
			(xy 130.028416 -36.675755) (xy 130.017456 -36.76358) (xy 129.998507 -36.850033) (xy 129.971729 -36.93439)
			(xy 129.937344 -37.015944) (xy 129.895643 -37.094009) (xy 129.871724 -37.131244) (xy 129.86766 -37.137594)
			(xy 129.863342 -37.151564) (xy 129.863342 -37.159184) (xy 129.863733 -37.169209) (xy 129.871406 -37.187734)
			(xy 129.885588 -37.201909) (xy 129.904116 -37.209572) (xy 129.914142 -37.209984) (xy 129.99212 -37.209984)
			(xy 130.035559 -37.210411) (xy 130.122067 -37.218428) (xy 130.207466 -37.234394) (xy 130.291028 -37.258171)
			(xy 130.372039 -37.289556) (xy 130.449809 -37.328283) (xy 130.523674 -37.374019) (xy 130.593004 -37.426376)
			(xy 130.646515 -37.47516) (xy 133.859268 -37.47516) (xy 133.863339 -37.419538) (xy 133.875465 -37.365101)
			(xy 133.895388 -37.31301) (xy 133.922684 -37.264375) (xy 133.95677 -37.220232) (xy 133.996919 -37.181523)
			(xy 134.042277 -37.149072) (xy 134.091877 -37.123571) (xy 134.144661 -37.105564) (xy 134.199504 -37.095434)
			(xy 134.255238 -37.093397) (xy 134.310675 -37.099497) (xy 134.364632 -37.113603) (xy 134.415961 -37.135415)
			(xy 134.463567 -37.164469) (xy 134.506435 -37.200144) (xy 134.507286 -37.201094) (xy 137.816588 -37.201094)
			(xy 137.820659 -37.145472) (xy 137.832785 -37.091035) (xy 137.852708 -37.038944) (xy 137.880004 -36.990309)
			(xy 137.91409 -36.946166) (xy 137.954239 -36.907457) (xy 137.999597 -36.875006) (xy 138.049197 -36.849505)
			(xy 138.101981 -36.831498) (xy 138.156824 -36.821368) (xy 138.212558 -36.819331) (xy 138.267995 -36.825431)
			(xy 138.321952 -36.839537) (xy 138.373281 -36.861349) (xy 138.420887 -36.890403) (xy 138.463755 -36.926078)
			(xy 138.500972 -36.967615) (xy 138.531745 -37.014128) (xy 138.555417 -37.064625) (xy 138.562163 -37.087048)
			(xy 147.30095 -37.087048) (xy 147.301413 -37.060444) (xy 147.30879 -37.007751) (xy 147.32342 -36.956595)
			(xy 147.345019 -36.907969) (xy 147.373169 -36.862818) (xy 147.407322 -36.822019) (xy 147.446816 -36.786364)
			(xy 147.46859 -36.771072) (xy 147.478515 -36.763542) (xy 147.490242 -36.741598) (xy 147.490942 -36.729162)
			(xy 147.490942 -36.644834) (xy 147.490308 -36.632378) (xy 147.478575 -36.610399) (xy 147.46859 -36.602924)
			(xy 147.446833 -36.58761) (xy 147.407352 -36.551949) (xy 147.373206 -36.511149) (xy 147.345058 -36.466003)
			(xy 147.323453 -36.417384) (xy 147.308811 -36.366236) (xy 147.301414 -36.313549) (xy 147.30095 -36.286948)
			(xy 147.3015 -36.259698) (xy 147.309249 -36.205753) (xy 147.324597 -36.153459) (xy 147.347231 -36.103882)
			(xy 147.37669 -36.05803) (xy 147.412375 -36.016838) (xy 147.453558 -35.981144) (xy 147.499403 -35.951674)
			(xy 147.548974 -35.929028) (xy 147.601265 -35.913668) (xy 147.655208 -35.905906) (xy 147.682458 -35.90544)
			(xy 147.68703 -35.90544) (xy 147.69624 -35.905168) (xy 147.713558 -35.898927) (xy 147.720812 -35.893248)
			(xy 147.771612 -35.84956) (xy 147.778318 -35.843324) (xy 147.787177 -35.827314) (xy 147.788884 -35.818318)
			(xy 147.788884 -35.818064) (xy 147.79323 -35.791133) (xy 147.80854 -35.738777) (xy 147.831151 -35.689136)
			(xy 147.860603 -35.643221) (xy 147.896294 -35.601968) (xy 147.937496 -35.56622) (xy 147.98337 -35.536705)
			(xy 148.032981 -35.514025) (xy 148.085315 -35.498642) (xy 148.139308 -35.49087) (xy 148.166582 -35.490404)
			(xy 148.193837 -35.490842) (xy 148.247791 -35.498597) (xy 148.300093 -35.513952) (xy 148.349677 -35.536594)
			(xy 148.395534 -35.566062) (xy 148.43673 -35.601757) (xy 148.472427 -35.642952) (xy 148.501897 -35.688807)
			(xy 148.524542 -35.73839) (xy 148.539899 -35.790691) (xy 148.547657 -35.844645) (xy 148.547657 -35.899155)
			(xy 148.539899 -35.953109) (xy 148.524542 -36.00541) (xy 148.501897 -36.054993) (xy 148.472427 -36.100848)
			(xy 148.43673 -36.142043) (xy 148.395534 -36.177738) (xy 148.349677 -36.207206) (xy 148.300093 -36.229848)
			(xy 148.247791 -36.245203) (xy 148.193837 -36.252958) (xy 148.166582 -36.25342) (xy 148.16201 -36.25342)
			(xy 148.152796 -36.253649) (xy 148.135477 -36.259918) (xy 148.128228 -36.265612) (xy 148.077428 -36.3093)
			(xy 148.070691 -36.315506) (xy 148.061851 -36.331538) (xy 148.060156 -36.340542) (xy 148.060156 -36.340796)
			(xy 148.055956 -36.366999) (xy 148.041272 -36.417993) (xy 148.01966 -36.466459) (xy 147.991536 -36.51146)
			(xy 147.988109 -36.515548) (xy 149.114254 -36.515548) (xy 149.118325 -36.459926) (xy 149.130451 -36.405489)
			(xy 149.150374 -36.353398) (xy 149.17767 -36.304763) (xy 149.211756 -36.26062) (xy 149.251905 -36.221911)
			(xy 149.297263 -36.18946) (xy 149.346863 -36.163959) (xy 149.399647 -36.145952) (xy 149.45449 -36.135822)
			(xy 149.510224 -36.133785) (xy 149.565661 -36.139885) (xy 149.619618 -36.153991) (xy 149.670947 -36.175803)
			(xy 149.718553 -36.204857) (xy 149.761421 -36.240532) (xy 149.798638 -36.282069) (xy 149.829411 -36.328582)
			(xy 149.853083 -36.379079) (xy 149.869151 -36.432486) (xy 149.877271 -36.487662) (xy 149.87778 -36.515548)
			(xy 149.877271 -36.543434) (xy 149.869151 -36.59861) (xy 149.853083 -36.652017) (xy 149.829411 -36.702514)
			(xy 149.798638 -36.749027) (xy 149.761421 -36.790564) (xy 149.718553 -36.826239) (xy 149.670947 -36.855293)
			(xy 149.619618 -36.877105) (xy 149.565661 -36.891211) (xy 149.510224 -36.897311) (xy 149.45449 -36.895274)
			(xy 149.399647 -36.885144) (xy 149.346863 -36.867137) (xy 149.297263 -36.841636) (xy 149.251905 -36.809185)
			(xy 149.211756 -36.770476) (xy 149.17767 -36.726333) (xy 149.150374 -36.677698) (xy 149.130451 -36.625607)
			(xy 149.118325 -36.57117) (xy 149.114254 -36.515548) (xy 147.988109 -36.515548) (xy 147.957445 -36.552127)
			(xy 147.918044 -36.587674) (xy 147.896326 -36.602924) (xy 147.886406 -36.610459) (xy 147.874675 -36.632399)
			(xy 147.873974 -36.644834) (xy 147.873974 -36.729162) (xy 147.874644 -36.741612) (xy 147.886354 -36.763589)
			(xy 147.896326 -36.771072) (xy 147.918084 -36.786383) (xy 147.957565 -36.822046) (xy 147.991711 -36.862846)
			(xy 148.019858 -36.907993) (xy 148.041463 -36.956612) (xy 148.056105 -37.00776) (xy 148.063501 -37.060447)
			(xy 148.063966 -37.087048) (xy 148.063966 -37.087302) (xy 148.063348 -37.119019) (xy 148.052847 -37.181577)
			(xy 148.032118 -37.241528) (xy 148.017484 -37.269674) (xy 148.01215 -37.27958) (xy 148.010626 -37.301678)
			(xy 148.04263 -37.384482) (xy 148.047122 -37.394569) (xy 148.062911 -37.409972) (xy 148.07311 -37.4142)
			(xy 148.097645 -37.42326) (xy 148.144175 -37.447145) (xy 148.187006 -37.477162) (xy 148.225335 -37.512749)
			(xy 148.258442 -37.553238) (xy 148.285708 -37.597871) (xy 148.30662 -37.64581) (xy 148.320788 -37.696157)
			(xy 148.327944 -37.747967) (xy 148.32838 -37.774118) (xy 148.327894 -37.801369) (xy 148.320138 -37.855317)
			(xy 148.304783 -37.907612) (xy 148.282141 -37.957189) (xy 148.252675 -38.003039) (xy 148.216984 -38.04423)
			(xy 148.175793 -38.079921) (xy 148.129943 -38.109387) (xy 148.080366 -38.132029) (xy 148.028071 -38.147384)
			(xy 147.974123 -38.15514) (xy 147.919621 -38.15514) (xy 147.865673 -38.147384) (xy 147.813378 -38.132029)
			(xy 147.763801 -38.109387) (xy 147.717951 -38.079921) (xy 147.67676 -38.04423) (xy 147.641069 -38.003039)
			(xy 147.611603 -37.957189) (xy 147.588961 -37.907612) (xy 147.573606 -37.855317) (xy 147.56585 -37.801369)
			(xy 147.565364 -37.774118) (xy 147.565364 -37.773864) (xy 147.565965 -37.742146) (xy 147.576473 -37.679587)
			(xy 147.597208 -37.619637) (xy 147.611846 -37.591492) (xy 147.61718 -37.581586) (xy 147.618704 -37.559488)
			(xy 147.5867 -37.476684) (xy 147.58225 -37.466574) (xy 147.566432 -37.451182) (xy 147.55622 -37.446966)
			(xy 147.53168 -37.437917) (xy 147.485148 -37.414034) (xy 147.442315 -37.384016) (xy 147.403986 -37.348429)
			(xy 147.370878 -37.307937) (xy 147.343613 -37.263302) (xy 147.322702 -37.215361) (xy 147.308537 -37.165012)
			(xy 147.301384 -37.1132) (xy 147.30095 -37.087048) (xy 138.562163 -37.087048) (xy 138.571485 -37.118032)
			(xy 138.579605 -37.173208) (xy 138.580114 -37.201094) (xy 138.579605 -37.22898) (xy 138.571485 -37.284156)
			(xy 138.555417 -37.337563) (xy 138.531745 -37.38806) (xy 138.500972 -37.434573) (xy 138.463755 -37.47611)
			(xy 138.420887 -37.511785) (xy 138.373281 -37.540839) (xy 138.321952 -37.562651) (xy 138.267995 -37.576757)
			(xy 138.212558 -37.582857) (xy 138.156824 -37.58082) (xy 138.101981 -37.57069) (xy 138.049197 -37.552683)
			(xy 137.999597 -37.527182) (xy 137.954239 -37.494731) (xy 137.91409 -37.456022) (xy 137.880004 -37.411879)
			(xy 137.852708 -37.363244) (xy 137.832785 -37.311153) (xy 137.820659 -37.256716) (xy 137.816588 -37.201094)
			(xy 134.507286 -37.201094) (xy 134.543652 -37.241681) (xy 134.574425 -37.288194) (xy 134.598097 -37.338691)
			(xy 134.614165 -37.392098) (xy 134.622285 -37.447274) (xy 134.622794 -37.47516) (xy 134.622285 -37.503046)
			(xy 134.614165 -37.558222) (xy 134.598097 -37.611629) (xy 134.574425 -37.662126) (xy 134.574272 -37.662358)
			(xy 136.048494 -37.662358) (xy 136.052565 -37.606736) (xy 136.064691 -37.552299) (xy 136.084614 -37.500208)
			(xy 136.11191 -37.451573) (xy 136.145996 -37.40743) (xy 136.186145 -37.368721) (xy 136.231503 -37.33627)
			(xy 136.281103 -37.310769) (xy 136.333887 -37.292762) (xy 136.38873 -37.282632) (xy 136.444464 -37.280595)
			(xy 136.499901 -37.286695) (xy 136.553858 -37.300801) (xy 136.605187 -37.322613) (xy 136.652793 -37.351667)
			(xy 136.695661 -37.387342) (xy 136.732878 -37.428879) (xy 136.763651 -37.475392) (xy 136.787323 -37.525889)
			(xy 136.803391 -37.579296) (xy 136.811511 -37.634472) (xy 136.81202 -37.662358) (xy 136.811511 -37.690244)
			(xy 136.803391 -37.74542) (xy 136.787323 -37.798827) (xy 136.763651 -37.849324) (xy 136.732878 -37.895837)
			(xy 136.695661 -37.937374) (xy 136.652793 -37.973049) (xy 136.605187 -38.002103) (xy 136.553858 -38.023915)
			(xy 136.499901 -38.038021) (xy 136.444464 -38.044121) (xy 136.38873 -38.042084) (xy 136.333887 -38.031954)
			(xy 136.281103 -38.013947) (xy 136.231503 -37.988446) (xy 136.186145 -37.955995) (xy 136.145996 -37.917286)
			(xy 136.11191 -37.873143) (xy 136.084614 -37.824508) (xy 136.064691 -37.772417) (xy 136.052565 -37.71798)
			(xy 136.048494 -37.662358) (xy 134.574272 -37.662358) (xy 134.543652 -37.708639) (xy 134.506435 -37.750176)
			(xy 134.463567 -37.785851) (xy 134.415961 -37.814905) (xy 134.364632 -37.836717) (xy 134.310675 -37.850823)
			(xy 134.255238 -37.856923) (xy 134.199504 -37.854886) (xy 134.144661 -37.844756) (xy 134.091877 -37.826749)
			(xy 134.042277 -37.801248) (xy 133.996919 -37.768797) (xy 133.95677 -37.730088) (xy 133.922684 -37.685945)
			(xy 133.895388 -37.63731) (xy 133.875465 -37.585219) (xy 133.863339 -37.530782) (xy 133.859268 -37.47516)
			(xy 130.646515 -37.47516) (xy 130.657207 -37.484907) (xy 130.715737 -37.549111) (xy 130.768092 -37.618442)
			(xy 130.813827 -37.692308) (xy 130.852552 -37.770079) (xy 130.883936 -37.851091) (xy 130.907711 -37.934653)
			(xy 130.923674 -38.020053) (xy 130.93169 -38.106561) (xy 130.93169 -38.193439) (xy 130.923674 -38.279947)
			(xy 130.907711 -38.365347) (xy 130.883936 -38.448909) (xy 130.867568 -38.49116) (xy 133.859268 -38.49116)
			(xy 133.863339 -38.435538) (xy 133.875465 -38.381101) (xy 133.895388 -38.32901) (xy 133.922684 -38.280375)
			(xy 133.95677 -38.236232) (xy 133.996919 -38.197523) (xy 134.042277 -38.165072) (xy 134.091877 -38.139571)
			(xy 134.144661 -38.121564) (xy 134.199504 -38.111434) (xy 134.255238 -38.109397) (xy 134.310675 -38.115497)
			(xy 134.364632 -38.129603) (xy 134.415961 -38.151415) (xy 134.463567 -38.180469) (xy 134.506435 -38.216144)
			(xy 134.543652 -38.257681) (xy 134.574425 -38.304194) (xy 134.579555 -38.315138) (xy 148.518116 -38.315138)
			(xy 148.522187 -38.259516) (xy 148.534313 -38.205079) (xy 148.554236 -38.152988) (xy 148.581532 -38.104353)
			(xy 148.615618 -38.06021) (xy 148.655767 -38.021501) (xy 148.701125 -37.98905) (xy 148.750725 -37.963549)
			(xy 148.803509 -37.945542) (xy 148.858352 -37.935412) (xy 148.914086 -37.933375) (xy 148.969523 -37.939475)
			(xy 149.02348 -37.953581) (xy 149.074809 -37.975393) (xy 149.122415 -38.004447) (xy 149.165283 -38.040122)
			(xy 149.2025 -38.081659) (xy 149.233273 -38.128172) (xy 149.256945 -38.178669) (xy 149.261387 -38.193435)
			(xy 153.198386 -38.193435) (xy 153.198386 -38.106565) (xy 153.206401 -38.020064) (xy 153.222363 -37.934672)
			(xy 153.246136 -37.851118) (xy 153.277516 -37.770113) (xy 153.316237 -37.692349) (xy 153.361968 -37.618489)
			(xy 153.414319 -37.549164) (xy 153.472842 -37.484965) (xy 153.537039 -37.426439) (xy 153.606363 -37.374086)
			(xy 153.680221 -37.328353) (xy 153.757983 -37.289629) (xy 153.838987 -37.258246) (xy 153.922541 -37.23447)
			(xy 154.007933 -37.218505) (xy 154.094433 -37.210487) (xy 154.137868 -37.209984) (xy 154.215846 -37.209984)
			(xy 154.225859 -37.209549) (xy 154.244354 -37.201871) (xy 154.258506 -37.187702) (xy 154.266161 -37.169197)
			(xy 154.266646 -37.159184) (xy 154.266646 -37.151564) (xy 154.262328 -37.137594) (xy 154.258264 -37.131244)
			(xy 154.234345 -37.094009) (xy 154.192644 -37.015944) (xy 154.158259 -36.93439) (xy 154.131481 -36.850033)
			(xy 154.112532 -36.76358) (xy 154.101572 -36.675755) (xy 154.098694 -36.587297) (xy 154.103921 -36.498946)
			(xy 154.117209 -36.411443) (xy 154.138447 -36.325524) (xy 154.167456 -36.241908) (xy 154.203994 -36.161296)
			(xy 154.247755 -36.084366) (xy 154.298369 -36.011762) (xy 154.355415 -35.944093) (xy 154.418412 -35.881927)
			(xy 154.486832 -35.825786) (xy 154.560102 -35.776139) (xy 154.637607 -35.733405) (xy 154.718696 -35.69794)
			(xy 154.80269 -35.670044) (xy 154.888884 -35.649948) (xy 154.976555 -35.637824) (xy 155.064968 -35.633771)
			(xy 155.153381 -35.637824) (xy 155.241052 -35.649948) (xy 155.327246 -35.670044) (xy 155.41124 -35.69794)
			(xy 155.492329 -35.733405) (xy 155.569834 -35.776139) (xy 155.643104 -35.825786) (xy 155.7052 -35.876738)
			(xy 160.817304 -35.876738) (xy 160.821375 -35.821116) (xy 160.833501 -35.766679) (xy 160.853424 -35.714588)
			(xy 160.88072 -35.665953) (xy 160.914806 -35.62181) (xy 160.954955 -35.583101) (xy 161.000313 -35.55065)
			(xy 161.049913 -35.525149) (xy 161.102697 -35.507142) (xy 161.15754 -35.497012) (xy 161.213274 -35.494975)
			(xy 161.268711 -35.501075) (xy 161.322668 -35.515181) (xy 161.373997 -35.536993) (xy 161.421603 -35.566047)
			(xy 161.464471 -35.601722) (xy 161.501688 -35.643259) (xy 161.532461 -35.689772) (xy 161.556133 -35.740269)
			(xy 161.572201 -35.793676) (xy 161.580321 -35.848852) (xy 161.58083 -35.876738) (xy 164.888924 -35.876738)
			(xy 164.892995 -35.821116) (xy 164.905121 -35.766679) (xy 164.925044 -35.714588) (xy 164.95234 -35.665953)
			(xy 164.986426 -35.62181) (xy 165.026575 -35.583101) (xy 165.071933 -35.55065) (xy 165.121533 -35.525149)
			(xy 165.174317 -35.507142) (xy 165.22916 -35.497012) (xy 165.284894 -35.494975) (xy 165.340331 -35.501075)
			(xy 165.394288 -35.515181) (xy 165.445617 -35.536993) (xy 165.493223 -35.566047) (xy 165.536091 -35.601722)
			(xy 165.573308 -35.643259) (xy 165.604081 -35.689772) (xy 165.627753 -35.740269) (xy 165.643821 -35.793676)
			(xy 165.651941 -35.848852) (xy 165.65245 -35.876738) (xy 165.651941 -35.904624) (xy 165.643821 -35.9598)
			(xy 165.627753 -36.013207) (xy 165.604081 -36.063704) (xy 165.573308 -36.110217) (xy 165.536091 -36.151754)
			(xy 165.493223 -36.187429) (xy 165.445617 -36.216483) (xy 165.394288 -36.238295) (xy 165.340331 -36.252401)
			(xy 165.284894 -36.258501) (xy 165.22916 -36.256464) (xy 165.174317 -36.246334) (xy 165.121533 -36.228327)
			(xy 165.071933 -36.202826) (xy 165.026575 -36.170375) (xy 164.986426 -36.131666) (xy 164.95234 -36.087523)
			(xy 164.925044 -36.038888) (xy 164.905121 -35.986797) (xy 164.892995 -35.93236) (xy 164.888924 -35.876738)
			(xy 161.58083 -35.876738) (xy 161.580321 -35.904624) (xy 161.572201 -35.9598) (xy 161.556133 -36.013207)
			(xy 161.532461 -36.063704) (xy 161.501688 -36.110217) (xy 161.464471 -36.151754) (xy 161.421603 -36.187429)
			(xy 161.373997 -36.216483) (xy 161.322668 -36.238295) (xy 161.268711 -36.252401) (xy 161.213274 -36.258501)
			(xy 161.15754 -36.256464) (xy 161.102697 -36.246334) (xy 161.049913 -36.228327) (xy 161.000313 -36.202826)
			(xy 160.954955 -36.170375) (xy 160.914806 -36.131666) (xy 160.88072 -36.087523) (xy 160.853424 -36.038888)
			(xy 160.833501 -35.986797) (xy 160.821375 -35.93236) (xy 160.817304 -35.876738) (xy 155.7052 -35.876738)
			(xy 155.711524 -35.881927) (xy 155.774521 -35.944093) (xy 155.831567 -36.011762) (xy 155.882181 -36.084366)
			(xy 155.925942 -36.161296) (xy 155.96248 -36.241908) (xy 155.991489 -36.325524) (xy 156.012727 -36.411443)
			(xy 156.026015 -36.498946) (xy 156.026667 -36.50996) (xy 162.713922 -36.50996) (xy 162.717993 -36.454338)
			(xy 162.730119 -36.399901) (xy 162.750042 -36.34781) (xy 162.777338 -36.299175) (xy 162.811424 -36.255032)
			(xy 162.851573 -36.216323) (xy 162.896931 -36.183872) (xy 162.946531 -36.158371) (xy 162.999315 -36.140364)
			(xy 163.054158 -36.130234) (xy 163.109892 -36.128197) (xy 163.165329 -36.134297) (xy 163.219286 -36.148403)
			(xy 163.270615 -36.170215) (xy 163.318221 -36.199269) (xy 163.361089 -36.234944) (xy 163.398306 -36.276481)
			(xy 163.429079 -36.322994) (xy 163.452751 -36.373491) (xy 163.468819 -36.426898) (xy 163.472744 -36.453572)
			(xy 166.028622 -36.453572) (xy 166.032693 -36.39795) (xy 166.044819 -36.343513) (xy 166.064742 -36.291422)
			(xy 166.092038 -36.242787) (xy 166.126124 -36.198644) (xy 166.166273 -36.159935) (xy 166.211631 -36.127484)
			(xy 166.261231 -36.101983) (xy 166.314015 -36.083976) (xy 166.368858 -36.073846) (xy 166.424592 -36.071809)
			(xy 166.480029 -36.077909) (xy 166.533986 -36.092015) (xy 166.585315 -36.113827) (xy 166.632921 -36.142881)
			(xy 166.675789 -36.178556) (xy 166.713006 -36.220093) (xy 166.743779 -36.266606) (xy 166.767451 -36.317103)
			(xy 166.783519 -36.37051) (xy 166.791639 -36.425686) (xy 166.792148 -36.453572) (xy 166.791639 -36.481458)
			(xy 166.783519 -36.536634) (xy 166.767451 -36.590041) (xy 166.743779 -36.640538) (xy 166.713006 -36.687051)
			(xy 166.675789 -36.728588) (xy 166.632921 -36.764263) (xy 166.585315 -36.793317) (xy 166.533986 -36.815129)
			(xy 166.480029 -36.829235) (xy 166.424592 -36.835335) (xy 166.368858 -36.833298) (xy 166.314015 -36.823168)
			(xy 166.261231 -36.805161) (xy 166.211631 -36.77966) (xy 166.166273 -36.747209) (xy 166.126124 -36.7085)
			(xy 166.092038 -36.664357) (xy 166.064742 -36.615722) (xy 166.044819 -36.563631) (xy 166.032693 -36.509194)
			(xy 166.028622 -36.453572) (xy 163.472744 -36.453572) (xy 163.476939 -36.482074) (xy 163.477448 -36.50996)
			(xy 163.476939 -36.537846) (xy 163.468819 -36.593022) (xy 163.452751 -36.646429) (xy 163.429079 -36.696926)
			(xy 163.398306 -36.743439) (xy 163.361089 -36.784976) (xy 163.318221 -36.820651) (xy 163.270615 -36.849705)
			(xy 163.219286 -36.871517) (xy 163.165329 -36.885623) (xy 163.109892 -36.891723) (xy 163.054158 -36.889686)
			(xy 162.999315 -36.879556) (xy 162.946531 -36.861549) (xy 162.896931 -36.836048) (xy 162.851573 -36.803597)
			(xy 162.811424 -36.764888) (xy 162.777338 -36.720745) (xy 162.750042 -36.67211) (xy 162.730119 -36.620019)
			(xy 162.717993 -36.565582) (xy 162.713922 -36.50996) (xy 156.026667 -36.50996) (xy 156.031242 -36.587297)
			(xy 156.028364 -36.675755) (xy 156.017404 -36.76358) (xy 155.998455 -36.850033) (xy 155.971677 -36.93439)
			(xy 155.937292 -37.015944) (xy 155.895591 -37.094009) (xy 155.871672 -37.131244) (xy 155.867608 -37.137594)
			(xy 155.86329 -37.151564) (xy 155.86329 -37.159184) (xy 155.863732 -37.169203) (xy 155.871395 -37.187718)
			(xy 155.88556 -37.20189) (xy 155.904071 -37.209563) (xy 155.91409 -37.209984) (xy 155.992068 -37.209984)
			(xy 156.03551 -37.210393) (xy 156.122022 -37.218407) (xy 156.207426 -37.234369) (xy 156.290993 -37.258143)
			(xy 156.37201 -37.289527) (xy 156.449786 -37.328252) (xy 156.523656 -37.373989) (xy 156.592991 -37.426346)
			(xy 156.646539 -37.47516) (xy 159.859216 -37.47516) (xy 159.863287 -37.419538) (xy 159.875413 -37.365101)
			(xy 159.895336 -37.31301) (xy 159.922632 -37.264375) (xy 159.956718 -37.220232) (xy 159.996867 -37.181523)
			(xy 160.042225 -37.149072) (xy 160.091825 -37.123571) (xy 160.144609 -37.105564) (xy 160.199452 -37.095434)
			(xy 160.255186 -37.093397) (xy 160.310623 -37.099497) (xy 160.36458 -37.113603) (xy 160.415909 -37.135415)
			(xy 160.463515 -37.164469) (xy 160.506383 -37.200144) (xy 160.507234 -37.201094) (xy 163.816536 -37.201094)
			(xy 163.820607 -37.145472) (xy 163.832733 -37.091035) (xy 163.852656 -37.038944) (xy 163.879952 -36.990309)
			(xy 163.914038 -36.946166) (xy 163.954187 -36.907457) (xy 163.999545 -36.875006) (xy 164.049145 -36.849505)
			(xy 164.101929 -36.831498) (xy 164.156772 -36.821368) (xy 164.212506 -36.819331) (xy 164.267943 -36.825431)
			(xy 164.3219 -36.839537) (xy 164.373229 -36.861349) (xy 164.420835 -36.890403) (xy 164.463703 -36.926078)
			(xy 164.50092 -36.967615) (xy 164.531693 -37.014128) (xy 164.555365 -37.064625) (xy 164.562111 -37.087048)
			(xy 173.300898 -37.087048) (xy 173.301384 -37.060445) (xy 173.308759 -37.007754) (xy 173.323387 -36.956599)
			(xy 173.344984 -36.907974) (xy 173.373129 -36.862823) (xy 173.407278 -36.822023) (xy 173.446766 -36.786366)
			(xy 173.468538 -36.771072) (xy 173.478471 -36.763552) (xy 173.490192 -36.7416) (xy 173.49089 -36.729162)
			(xy 173.49089 -36.644834) (xy 173.490237 -36.632381) (xy 173.478516 -36.610404) (xy 173.468538 -36.602924)
			(xy 173.44677 -36.587627) (xy 173.407291 -36.551961) (xy 173.373147 -36.511157) (xy 173.345002 -36.466008)
			(xy 173.323399 -36.417387) (xy 173.308758 -36.366237) (xy 173.301362 -36.31355) (xy 173.300898 -36.286948)
			(xy 173.3014 -36.259696) (xy 173.309151 -36.205746) (xy 173.324501 -36.153449) (xy 173.347138 -36.103868)
			(xy 173.376602 -36.058015) (xy 173.412292 -36.016821) (xy 173.453481 -35.981127) (xy 173.499331 -35.951658)
			(xy 173.548909 -35.929016) (xy 173.601205 -35.91366) (xy 173.655154 -35.905903) (xy 173.682406 -35.90544)
			(xy 173.686978 -35.90544) (xy 173.69619 -35.905192) (xy 173.713508 -35.898935) (xy 173.72076 -35.893248)
			(xy 173.77156 -35.84956) (xy 173.778274 -35.843332) (xy 173.787128 -35.827316) (xy 173.788832 -35.818318)
			(xy 173.788832 -35.818064) (xy 173.793132 -35.791125) (xy 173.808445 -35.738765) (xy 173.83106 -35.689121)
			(xy 173.860516 -35.643204) (xy 173.896212 -35.60195) (xy 173.93742 -35.566203) (xy 173.9833 -35.536689)
			(xy 174.032916 -35.514012) (xy 174.085256 -35.498633) (xy 174.139254 -35.490867) (xy 174.16653 -35.490404)
			(xy 174.193781 -35.490868) (xy 174.247727 -35.498628) (xy 174.30002 -35.513986) (xy 174.349595 -35.53663)
			(xy 174.395443 -35.566098) (xy 174.436631 -35.601791) (xy 174.47232 -35.642981) (xy 174.501785 -35.688832)
			(xy 174.524424 -35.738408) (xy 174.539778 -35.790702) (xy 174.547534 -35.844649) (xy 174.547534 -35.899151)
			(xy 174.539778 -35.953098) (xy 174.524424 -36.005392) (xy 174.501785 -36.054968) (xy 174.47232 -36.100819)
			(xy 174.436631 -36.142009) (xy 174.395443 -36.177702) (xy 174.349595 -36.20717) (xy 174.30002 -36.229814)
			(xy 174.247727 -36.245172) (xy 174.193781 -36.252932) (xy 174.16653 -36.25342) (xy 174.161958 -36.25342)
			(xy 174.152746 -36.253672) (xy 174.135427 -36.259925) (xy 174.128176 -36.265612) (xy 174.077376 -36.3093)
			(xy 174.070646 -36.315514) (xy 174.061801 -36.33154) (xy 174.060104 -36.340542) (xy 174.060104 -36.340796)
			(xy 174.055885 -36.366995) (xy 174.041203 -36.417988) (xy 174.019593 -36.466453) (xy 173.991473 -36.511455)
			(xy 173.988042 -36.515548) (xy 175.114202 -36.515548) (xy 175.118273 -36.459926) (xy 175.130399 -36.405489)
			(xy 175.150322 -36.353398) (xy 175.177618 -36.304763) (xy 175.211704 -36.26062) (xy 175.251853 -36.221911)
			(xy 175.297211 -36.18946) (xy 175.346811 -36.163959) (xy 175.399595 -36.145952) (xy 175.454438 -36.135822)
			(xy 175.510172 -36.133785) (xy 175.565609 -36.139885) (xy 175.619566 -36.153991) (xy 175.670895 -36.175803)
			(xy 175.718501 -36.204857) (xy 175.761369 -36.240532) (xy 175.798586 -36.282069) (xy 175.829359 -36.328582)
			(xy 175.853031 -36.379079) (xy 175.869099 -36.432486) (xy 175.877219 -36.487662) (xy 175.877728 -36.515548)
			(xy 175.877219 -36.543434) (xy 175.869099 -36.59861) (xy 175.853031 -36.652017) (xy 175.829359 -36.702514)
			(xy 175.798586 -36.749027) (xy 175.761369 -36.790564) (xy 175.718501 -36.826239) (xy 175.670895 -36.855293)
			(xy 175.619566 -36.877105) (xy 175.565609 -36.891211) (xy 175.510172 -36.897311) (xy 175.454438 -36.895274)
			(xy 175.399595 -36.885144) (xy 175.346811 -36.867137) (xy 175.297211 -36.841636) (xy 175.251853 -36.809185)
			(xy 175.211704 -36.770476) (xy 175.177618 -36.726333) (xy 175.150322 -36.677698) (xy 175.130399 -36.625607)
			(xy 175.118273 -36.57117) (xy 175.114202 -36.515548) (xy 173.988042 -36.515548) (xy 173.957386 -36.552123)
			(xy 173.91799 -36.587673) (xy 173.896274 -36.602924) (xy 173.886344 -36.610448) (xy 173.874621 -36.632397)
			(xy 173.873922 -36.644834) (xy 173.873922 -36.729162) (xy 173.874573 -36.741615) (xy 173.886295 -36.763593)
			(xy 173.896274 -36.771072) (xy 173.918043 -36.786368) (xy 173.957522 -36.822035) (xy 173.991665 -36.862838)
			(xy 174.01981 -36.907988) (xy 174.041413 -36.956609) (xy 174.056054 -37.007759) (xy 174.063449 -37.060446)
			(xy 174.063914 -37.087048) (xy 174.063914 -37.087302) (xy 174.06329 -37.119019) (xy 174.05279 -37.181576)
			(xy 174.032065 -37.241528) (xy 174.017432 -37.269674) (xy 174.012098 -37.27958) (xy 174.010574 -37.301678)
			(xy 174.042578 -37.384482) (xy 174.04705 -37.39458) (xy 174.062852 -37.409979) (xy 174.073058 -37.4142)
			(xy 174.097582 -37.42329) (xy 174.144113 -37.447168) (xy 174.186946 -37.47718) (xy 174.225276 -37.512763)
			(xy 174.258385 -37.553248) (xy 174.285653 -37.597878) (xy 174.306566 -37.645815) (xy 174.320735 -37.69616)
			(xy 174.327892 -37.747968) (xy 174.328328 -37.774118) (xy 174.327842 -37.801369) (xy 174.320086 -37.855317)
			(xy 174.304731 -37.907612) (xy 174.282089 -37.957189) (xy 174.252623 -38.003039) (xy 174.216932 -38.04423)
			(xy 174.175741 -38.079921) (xy 174.129891 -38.109387) (xy 174.080314 -38.132029) (xy 174.028019 -38.147384)
			(xy 173.974071 -38.15514) (xy 173.919569 -38.15514) (xy 173.865621 -38.147384) (xy 173.813326 -38.132029)
			(xy 173.763749 -38.109387) (xy 173.717899 -38.079921) (xy 173.676708 -38.04423) (xy 173.641017 -38.003039)
			(xy 173.611551 -37.957189) (xy 173.588909 -37.907612) (xy 173.573554 -37.855317) (xy 173.565798 -37.801369)
			(xy 173.565312 -37.774118) (xy 173.565312 -37.773864) (xy 173.565919 -37.742147) (xy 173.576426 -37.679588)
			(xy 173.597158 -37.619637) (xy 173.611794 -37.591492) (xy 173.617128 -37.581586) (xy 173.618652 -37.559488)
			(xy 173.586648 -37.476684) (xy 173.582177 -37.466586) (xy 173.566373 -37.451189) (xy 173.556168 -37.446966)
			(xy 173.531617 -37.437947) (xy 173.485086 -37.414057) (xy 173.442255 -37.384035) (xy 173.403927 -37.348443)
			(xy 173.370821 -37.307948) (xy 173.343557 -37.26331) (xy 173.322648 -37.215366) (xy 173.308484 -37.165015)
			(xy 173.301332 -37.113201) (xy 173.300898 -37.087048) (xy 164.562111 -37.087048) (xy 164.571433 -37.118032)
			(xy 164.579553 -37.173208) (xy 164.580062 -37.201094) (xy 164.579553 -37.22898) (xy 164.571433 -37.284156)
			(xy 164.555365 -37.337563) (xy 164.531693 -37.38806) (xy 164.50092 -37.434573) (xy 164.463703 -37.47611)
			(xy 164.420835 -37.511785) (xy 164.373229 -37.540839) (xy 164.3219 -37.562651) (xy 164.267943 -37.576757)
			(xy 164.212506 -37.582857) (xy 164.156772 -37.58082) (xy 164.101929 -37.57069) (xy 164.049145 -37.552683)
			(xy 163.999545 -37.527182) (xy 163.954187 -37.494731) (xy 163.914038 -37.456022) (xy 163.879952 -37.411879)
			(xy 163.852656 -37.363244) (xy 163.832733 -37.311153) (xy 163.820607 -37.256716) (xy 163.816536 -37.201094)
			(xy 160.507234 -37.201094) (xy 160.5436 -37.241681) (xy 160.574373 -37.288194) (xy 160.598045 -37.338691)
			(xy 160.614113 -37.392098) (xy 160.622233 -37.447274) (xy 160.622742 -37.47516) (xy 160.622233 -37.503046)
			(xy 160.614113 -37.558222) (xy 160.598045 -37.611629) (xy 160.574373 -37.662126) (xy 160.57422 -37.662358)
			(xy 162.048442 -37.662358) (xy 162.052513 -37.606736) (xy 162.064639 -37.552299) (xy 162.084562 -37.500208)
			(xy 162.111858 -37.451573) (xy 162.145944 -37.40743) (xy 162.186093 -37.368721) (xy 162.231451 -37.33627)
			(xy 162.281051 -37.310769) (xy 162.333835 -37.292762) (xy 162.388678 -37.282632) (xy 162.444412 -37.280595)
			(xy 162.499849 -37.286695) (xy 162.553806 -37.300801) (xy 162.605135 -37.322613) (xy 162.652741 -37.351667)
			(xy 162.695609 -37.387342) (xy 162.732826 -37.428879) (xy 162.763599 -37.475392) (xy 162.787271 -37.525889)
			(xy 162.803339 -37.579296) (xy 162.811459 -37.634472) (xy 162.811968 -37.662358) (xy 162.811459 -37.690244)
			(xy 162.803339 -37.74542) (xy 162.787271 -37.798827) (xy 162.763599 -37.849324) (xy 162.732826 -37.895837)
			(xy 162.695609 -37.937374) (xy 162.652741 -37.973049) (xy 162.605135 -38.002103) (xy 162.553806 -38.023915)
			(xy 162.499849 -38.038021) (xy 162.444412 -38.044121) (xy 162.388678 -38.042084) (xy 162.333835 -38.031954)
			(xy 162.281051 -38.013947) (xy 162.231451 -37.988446) (xy 162.186093 -37.955995) (xy 162.145944 -37.917286)
			(xy 162.111858 -37.873143) (xy 162.084562 -37.824508) (xy 162.064639 -37.772417) (xy 162.052513 -37.71798)
			(xy 162.048442 -37.662358) (xy 160.57422 -37.662358) (xy 160.5436 -37.708639) (xy 160.506383 -37.750176)
			(xy 160.463515 -37.785851) (xy 160.415909 -37.814905) (xy 160.36458 -37.836717) (xy 160.310623 -37.850823)
			(xy 160.255186 -37.856923) (xy 160.199452 -37.854886) (xy 160.144609 -37.844756) (xy 160.091825 -37.826749)
			(xy 160.042225 -37.801248) (xy 159.996867 -37.768797) (xy 159.956718 -37.730088) (xy 159.922632 -37.685945)
			(xy 159.895336 -37.63731) (xy 159.875413 -37.585219) (xy 159.863287 -37.530782) (xy 159.859216 -37.47516)
			(xy 156.646539 -37.47516) (xy 156.6572 -37.484878) (xy 156.715733 -37.549084) (xy 156.768093 -37.618418)
			(xy 156.813832 -37.692286) (xy 156.85256 -37.770061) (xy 156.883946 -37.851076) (xy 156.907724 -37.934642)
			(xy 156.923689 -38.020046) (xy 156.931705 -38.106558) (xy 156.931705 -38.193442) (xy 156.923689 -38.279954)
			(xy 156.907724 -38.365358) (xy 156.883946 -38.448924) (xy 156.867583 -38.49116) (xy 159.859216 -38.49116)
			(xy 159.863287 -38.435538) (xy 159.875413 -38.381101) (xy 159.895336 -38.32901) (xy 159.922632 -38.280375)
			(xy 159.956718 -38.236232) (xy 159.996867 -38.197523) (xy 160.042225 -38.165072) (xy 160.091825 -38.139571)
			(xy 160.144609 -38.121564) (xy 160.199452 -38.111434) (xy 160.255186 -38.109397) (xy 160.310623 -38.115497)
			(xy 160.36458 -38.129603) (xy 160.415909 -38.151415) (xy 160.463515 -38.180469) (xy 160.506383 -38.216144)
			(xy 160.5436 -38.257681) (xy 160.574373 -38.304194) (xy 160.579503 -38.315138) (xy 174.518064 -38.315138)
			(xy 174.522135 -38.259516) (xy 174.534261 -38.205079) (xy 174.554184 -38.152988) (xy 174.58148 -38.104353)
			(xy 174.615566 -38.06021) (xy 174.655715 -38.021501) (xy 174.701073 -37.98905) (xy 174.750673 -37.963549)
			(xy 174.803457 -37.945542) (xy 174.8583 -37.935412) (xy 174.914034 -37.933375) (xy 174.969471 -37.939475)
			(xy 175.023428 -37.953581) (xy 175.074757 -37.975393) (xy 175.122363 -38.004447) (xy 175.165231 -38.040122)
			(xy 175.202448 -38.081659) (xy 175.233221 -38.128172) (xy 175.256893 -38.178669) (xy 175.261336 -38.193438)
			(xy 179.198271 -38.193438) (xy 179.198271 -38.106562) (xy 179.206287 -38.020058) (xy 179.22225 -37.934662)
			(xy 179.246025 -37.851104) (xy 179.277408 -37.770095) (xy 179.316132 -37.692328) (xy 179.361866 -37.618466)
			(xy 179.414221 -37.549138) (xy 179.472748 -37.484937) (xy 179.53695 -37.42641) (xy 179.606279 -37.374057)
			(xy 179.680142 -37.328324) (xy 179.75791 -37.289601) (xy 179.838919 -37.25822) (xy 179.922478 -37.234446)
			(xy 180.007874 -37.218484) (xy 180.094378 -37.21047) (xy 180.137816 -37.209984) (xy 180.215794 -37.209984)
			(xy 180.225817 -37.209575) (xy 180.244337 -37.201904) (xy 180.25851 -37.187728) (xy 180.266177 -37.169207)
			(xy 180.266594 -37.159184) (xy 180.266594 -37.151564) (xy 180.262276 -37.137594) (xy 180.258212 -37.131244)
			(xy 180.234293 -37.094009) (xy 180.192592 -37.015944) (xy 180.158207 -36.93439) (xy 180.131429 -36.850033)
			(xy 180.11248 -36.76358) (xy 180.10152 -36.675755) (xy 180.098642 -36.587297) (xy 180.103869 -36.498946)
			(xy 180.117157 -36.411443) (xy 180.138395 -36.325524) (xy 180.167404 -36.241908) (xy 180.203942 -36.161296)
			(xy 180.247703 -36.084366) (xy 180.298317 -36.011762) (xy 180.355363 -35.944093) (xy 180.41836 -35.881927)
			(xy 180.48678 -35.825786) (xy 180.56005 -35.776139) (xy 180.637555 -35.733405) (xy 180.718644 -35.69794)
			(xy 180.802638 -35.670044) (xy 180.888832 -35.649948) (xy 180.976503 -35.637824) (xy 181.064916 -35.633771)
			(xy 181.153329 -35.637824) (xy 181.241 -35.649948) (xy 181.327194 -35.670044) (xy 181.411188 -35.69794)
			(xy 181.492277 -35.733405) (xy 181.569782 -35.776139) (xy 181.643052 -35.825786) (xy 181.705148 -35.876738)
			(xy 186.817252 -35.876738) (xy 186.821323 -35.821116) (xy 186.833449 -35.766679) (xy 186.853372 -35.714588)
			(xy 186.880668 -35.665953) (xy 186.914754 -35.62181) (xy 186.954903 -35.583101) (xy 187.000261 -35.55065)
			(xy 187.049861 -35.525149) (xy 187.102645 -35.507142) (xy 187.157488 -35.497012) (xy 187.213222 -35.494975)
			(xy 187.268659 -35.501075) (xy 187.322616 -35.515181) (xy 187.373945 -35.536993) (xy 187.421551 -35.566047)
			(xy 187.464419 -35.601722) (xy 187.501636 -35.643259) (xy 187.532409 -35.689772) (xy 187.556081 -35.740269)
			(xy 187.572149 -35.793676) (xy 187.580269 -35.848852) (xy 187.580778 -35.876738) (xy 190.888872 -35.876738)
			(xy 190.892943 -35.821116) (xy 190.905069 -35.766679) (xy 190.924992 -35.714588) (xy 190.952288 -35.665953)
			(xy 190.986374 -35.62181) (xy 191.026523 -35.583101) (xy 191.071881 -35.55065) (xy 191.121481 -35.525149)
			(xy 191.174265 -35.507142) (xy 191.229108 -35.497012) (xy 191.284842 -35.494975) (xy 191.340279 -35.501075)
			(xy 191.394236 -35.515181) (xy 191.445565 -35.536993) (xy 191.493171 -35.566047) (xy 191.536039 -35.601722)
			(xy 191.573256 -35.643259) (xy 191.604029 -35.689772) (xy 191.627701 -35.740269) (xy 191.643769 -35.793676)
			(xy 191.651889 -35.848852) (xy 191.652398 -35.876738) (xy 191.651889 -35.904624) (xy 191.643769 -35.9598)
			(xy 191.627701 -36.013207) (xy 191.604029 -36.063704) (xy 191.573256 -36.110217) (xy 191.536039 -36.151754)
			(xy 191.493171 -36.187429) (xy 191.445565 -36.216483) (xy 191.394236 -36.238295) (xy 191.340279 -36.252401)
			(xy 191.284842 -36.258501) (xy 191.229108 -36.256464) (xy 191.174265 -36.246334) (xy 191.121481 -36.228327)
			(xy 191.071881 -36.202826) (xy 191.026523 -36.170375) (xy 190.986374 -36.131666) (xy 190.952288 -36.087523)
			(xy 190.924992 -36.038888) (xy 190.905069 -35.986797) (xy 190.892943 -35.93236) (xy 190.888872 -35.876738)
			(xy 187.580778 -35.876738) (xy 187.580269 -35.904624) (xy 187.572149 -35.9598) (xy 187.556081 -36.013207)
			(xy 187.532409 -36.063704) (xy 187.501636 -36.110217) (xy 187.464419 -36.151754) (xy 187.421551 -36.187429)
			(xy 187.373945 -36.216483) (xy 187.322616 -36.238295) (xy 187.268659 -36.252401) (xy 187.213222 -36.258501)
			(xy 187.157488 -36.256464) (xy 187.102645 -36.246334) (xy 187.049861 -36.228327) (xy 187.000261 -36.202826)
			(xy 186.954903 -36.170375) (xy 186.914754 -36.131666) (xy 186.880668 -36.087523) (xy 186.853372 -36.038888)
			(xy 186.833449 -35.986797) (xy 186.821323 -35.93236) (xy 186.817252 -35.876738) (xy 181.705148 -35.876738)
			(xy 181.711472 -35.881927) (xy 181.774469 -35.944093) (xy 181.831515 -36.011762) (xy 181.882129 -36.084366)
			(xy 181.92589 -36.161296) (xy 181.962428 -36.241908) (xy 181.991437 -36.325524) (xy 182.012675 -36.411443)
			(xy 182.025963 -36.498946) (xy 182.026615 -36.50996) (xy 188.71387 -36.50996) (xy 188.717941 -36.454338)
			(xy 188.730067 -36.399901) (xy 188.74999 -36.34781) (xy 188.777286 -36.299175) (xy 188.811372 -36.255032)
			(xy 188.851521 -36.216323) (xy 188.896879 -36.183872) (xy 188.946479 -36.158371) (xy 188.999263 -36.140364)
			(xy 189.054106 -36.130234) (xy 189.10984 -36.128197) (xy 189.165277 -36.134297) (xy 189.219234 -36.148403)
			(xy 189.270563 -36.170215) (xy 189.318169 -36.199269) (xy 189.361037 -36.234944) (xy 189.398254 -36.276481)
			(xy 189.429027 -36.322994) (xy 189.452699 -36.373491) (xy 189.468767 -36.426898) (xy 189.472692 -36.453572)
			(xy 192.02857 -36.453572) (xy 192.032641 -36.39795) (xy 192.044767 -36.343513) (xy 192.06469 -36.291422)
			(xy 192.091986 -36.242787) (xy 192.126072 -36.198644) (xy 192.166221 -36.159935) (xy 192.211579 -36.127484)
			(xy 192.261179 -36.101983) (xy 192.313963 -36.083976) (xy 192.368806 -36.073846) (xy 192.42454 -36.071809)
			(xy 192.479977 -36.077909) (xy 192.533934 -36.092015) (xy 192.585263 -36.113827) (xy 192.632869 -36.142881)
			(xy 192.675737 -36.178556) (xy 192.712954 -36.220093) (xy 192.743727 -36.266606) (xy 192.767399 -36.317103)
			(xy 192.783467 -36.37051) (xy 192.791587 -36.425686) (xy 192.792096 -36.453572) (xy 192.791587 -36.481458)
			(xy 192.783467 -36.536634) (xy 192.767399 -36.590041) (xy 192.743727 -36.640538) (xy 192.712954 -36.687051)
			(xy 192.675737 -36.728588) (xy 192.632869 -36.764263) (xy 192.585263 -36.793317) (xy 192.533934 -36.815129)
			(xy 192.479977 -36.829235) (xy 192.42454 -36.835335) (xy 192.368806 -36.833298) (xy 192.313963 -36.823168)
			(xy 192.261179 -36.805161) (xy 192.211579 -36.77966) (xy 192.166221 -36.747209) (xy 192.126072 -36.7085)
			(xy 192.091986 -36.664357) (xy 192.06469 -36.615722) (xy 192.044767 -36.563631) (xy 192.032641 -36.509194)
			(xy 192.02857 -36.453572) (xy 189.472692 -36.453572) (xy 189.476887 -36.482074) (xy 189.477396 -36.50996)
			(xy 189.476887 -36.537846) (xy 189.468767 -36.593022) (xy 189.452699 -36.646429) (xy 189.429027 -36.696926)
			(xy 189.398254 -36.743439) (xy 189.361037 -36.784976) (xy 189.318169 -36.820651) (xy 189.270563 -36.849705)
			(xy 189.219234 -36.871517) (xy 189.165277 -36.885623) (xy 189.10984 -36.891723) (xy 189.054106 -36.889686)
			(xy 188.999263 -36.879556) (xy 188.946479 -36.861549) (xy 188.896879 -36.836048) (xy 188.851521 -36.803597)
			(xy 188.811372 -36.764888) (xy 188.777286 -36.720745) (xy 188.74999 -36.67211) (xy 188.730067 -36.620019)
			(xy 188.717941 -36.565582) (xy 188.71387 -36.50996) (xy 182.026615 -36.50996) (xy 182.03119 -36.587297)
			(xy 182.028312 -36.675755) (xy 182.017352 -36.76358) (xy 181.998403 -36.850033) (xy 181.971625 -36.93439)
			(xy 181.93724 -37.015944) (xy 181.895539 -37.094009) (xy 181.87162 -37.131244) (xy 181.867556 -37.137594)
			(xy 181.863238 -37.151564) (xy 181.863238 -37.159184) (xy 181.863633 -37.169209) (xy 181.871305 -37.187733)
			(xy 181.885486 -37.201907) (xy 181.904013 -37.209571) (xy 181.914038 -37.209984) (xy 181.992016 -37.209984)
			(xy 182.035455 -37.21041) (xy 182.121963 -37.218428) (xy 182.207363 -37.234393) (xy 182.290925 -37.25817)
			(xy 182.371936 -37.289555) (xy 182.449707 -37.328281) (xy 182.523572 -37.374018) (xy 182.592902 -37.426375)
			(xy 182.646416 -37.47516) (xy 185.859164 -37.47516) (xy 185.863235 -37.419538) (xy 185.875361 -37.365101)
			(xy 185.895284 -37.31301) (xy 185.92258 -37.264375) (xy 185.956666 -37.220232) (xy 185.996815 -37.181523)
			(xy 186.042173 -37.149072) (xy 186.091773 -37.123571) (xy 186.144557 -37.105564) (xy 186.1994 -37.095434)
			(xy 186.255134 -37.093397) (xy 186.310571 -37.099497) (xy 186.364528 -37.113603) (xy 186.415857 -37.135415)
			(xy 186.463463 -37.164469) (xy 186.506331 -37.200144) (xy 186.507182 -37.201094) (xy 189.816484 -37.201094)
			(xy 189.820555 -37.145472) (xy 189.832681 -37.091035) (xy 189.852604 -37.038944) (xy 189.8799 -36.990309)
			(xy 189.913986 -36.946166) (xy 189.954135 -36.907457) (xy 189.999493 -36.875006) (xy 190.049093 -36.849505)
			(xy 190.101877 -36.831498) (xy 190.15672 -36.821368) (xy 190.212454 -36.819331) (xy 190.267891 -36.825431)
			(xy 190.321848 -36.839537) (xy 190.373177 -36.861349) (xy 190.420783 -36.890403) (xy 190.463651 -36.926078)
			(xy 190.500868 -36.967615) (xy 190.531641 -37.014128) (xy 190.555313 -37.064625) (xy 190.562059 -37.087048)
			(xy 199.300846 -37.087048) (xy 199.301311 -37.060444) (xy 199.308687 -37.007751) (xy 199.323317 -36.956595)
			(xy 199.344917 -36.907969) (xy 199.373066 -36.862819) (xy 199.407219 -36.822019) (xy 199.446712 -36.786364)
			(xy 199.468486 -36.771072) (xy 199.47841 -36.763541) (xy 199.490138 -36.741598) (xy 199.490838 -36.729162)
			(xy 199.490838 -36.644834) (xy 199.490166 -36.632384) (xy 199.478457 -36.610408) (xy 199.468486 -36.602924)
			(xy 199.446728 -36.587612) (xy 199.407247 -36.55195) (xy 199.373101 -36.51115) (xy 199.344953 -36.466003)
			(xy 199.323349 -36.417384) (xy 199.308707 -36.366236) (xy 199.30131 -36.313549) (xy 199.300846 -36.286948)
			(xy 199.3014 -36.259698) (xy 199.309149 -36.205753) (xy 199.324497 -36.15346) (xy 199.34713 -36.103883)
			(xy 199.376589 -36.058032) (xy 199.412273 -36.01684) (xy 199.453456 -35.981145) (xy 199.4993 -35.951675)
			(xy 199.548872 -35.92903) (xy 199.601161 -35.913669) (xy 199.655105 -35.905907) (xy 199.682354 -35.90544)
			(xy 199.686926 -35.90544) (xy 199.696135 -35.905166) (xy 199.713454 -35.898927) (xy 199.720708 -35.893248)
			(xy 199.771508 -35.84956) (xy 199.778214 -35.843323) (xy 199.787073 -35.827314) (xy 199.78878 -35.818318)
			(xy 199.78878 -35.818064) (xy 199.79313 -35.791134) (xy 199.80844 -35.738778) (xy 199.831051 -35.689137)
			(xy 199.860502 -35.643222) (xy 199.896192 -35.60197) (xy 199.937394 -35.566222) (xy 199.983268 -35.536707)
			(xy 200.032878 -35.514026) (xy 200.085212 -35.498643) (xy 200.139204 -35.49087) (xy 200.166478 -35.490404)
			(xy 200.193733 -35.490841) (xy 200.247688 -35.498596) (xy 200.29999 -35.513951) (xy 200.349575 -35.536593)
			(xy 200.395432 -35.566061) (xy 200.436629 -35.601756) (xy 200.472326 -35.64295) (xy 200.501797 -35.688806)
			(xy 200.524442 -35.738389) (xy 200.539799 -35.790691) (xy 200.547557 -35.844645) (xy 200.547557 -35.899155)
			(xy 200.539799 -35.953109) (xy 200.524442 -36.005411) (xy 200.501797 -36.054994) (xy 200.472326 -36.10085)
			(xy 200.436629 -36.142044) (xy 200.395432 -36.177739) (xy 200.349575 -36.207207) (xy 200.29999 -36.229849)
			(xy 200.247688 -36.245204) (xy 200.193733 -36.252959) (xy 200.166478 -36.25342) (xy 200.161906 -36.25342)
			(xy 200.152692 -36.253647) (xy 200.135373 -36.259918) (xy 200.128124 -36.265612) (xy 200.077324 -36.3093)
			(xy 200.070602 -36.315522) (xy 200.061751 -36.331541) (xy 200.060052 -36.340542) (xy 200.060052 -36.340796)
			(xy 200.055854 -36.366999) (xy 200.04117 -36.417994) (xy 200.019557 -36.466459) (xy 199.991433 -36.51146)
			(xy 199.988006 -36.515548) (xy 201.11415 -36.515548) (xy 201.118221 -36.459926) (xy 201.130347 -36.405489)
			(xy 201.15027 -36.353398) (xy 201.177566 -36.304763) (xy 201.211652 -36.26062) (xy 201.251801 -36.221911)
			(xy 201.297159 -36.18946) (xy 201.346759 -36.163959) (xy 201.399543 -36.145952) (xy 201.454386 -36.135822)
			(xy 201.51012 -36.133785) (xy 201.565557 -36.139885) (xy 201.619514 -36.153991) (xy 201.670843 -36.175803)
			(xy 201.718449 -36.204857) (xy 201.761317 -36.240532) (xy 201.798534 -36.282069) (xy 201.829307 -36.328582)
			(xy 201.852979 -36.379079) (xy 201.869047 -36.432486) (xy 201.877167 -36.487662) (xy 201.877676 -36.515548)
			(xy 201.877167 -36.543434) (xy 201.869047 -36.59861) (xy 201.852979 -36.652017) (xy 201.829307 -36.702514)
			(xy 201.798534 -36.749027) (xy 201.761317 -36.790564) (xy 201.718449 -36.826239) (xy 201.670843 -36.855293)
			(xy 201.619514 -36.877105) (xy 201.565557 -36.891211) (xy 201.51012 -36.897311) (xy 201.454386 -36.895274)
			(xy 201.399543 -36.885144) (xy 201.346759 -36.867137) (xy 201.297159 -36.841636) (xy 201.251801 -36.809185)
			(xy 201.211652 -36.770476) (xy 201.177566 -36.726333) (xy 201.15027 -36.677698) (xy 201.130347 -36.625607)
			(xy 201.118221 -36.57117) (xy 201.11415 -36.515548) (xy 199.988006 -36.515548) (xy 199.957341 -36.552127)
			(xy 199.91794 -36.587675) (xy 199.896222 -36.602924) (xy 199.886301 -36.610458) (xy 199.874571 -36.632399)
			(xy 199.87387 -36.644834) (xy 199.87387 -36.729162) (xy 199.874541 -36.741612) (xy 199.886251 -36.763588)
			(xy 199.896222 -36.771072) (xy 199.91798 -36.786385) (xy 199.957461 -36.822047) (xy 199.991606 -36.862846)
			(xy 200.019754 -36.907993) (xy 200.041358 -36.956612) (xy 200.056001 -37.00776) (xy 200.063397 -37.060447)
			(xy 200.063862 -37.087048) (xy 200.063862 -37.087302) (xy 200.063244 -37.119019) (xy 200.052743 -37.181577)
			(xy 200.032015 -37.241528) (xy 200.01738 -37.269674) (xy 200.012046 -37.27958) (xy 200.010522 -37.301678)
			(xy 200.042526 -37.384482) (xy 200.04702 -37.394568) (xy 200.062807 -37.409971) (xy 200.073006 -37.4142)
			(xy 200.09754 -37.423263) (xy 200.14407 -37.447146) (xy 200.186902 -37.477163) (xy 200.22523 -37.51275)
			(xy 200.258338 -37.553239) (xy 200.285604 -37.597871) (xy 200.306516 -37.64581) (xy 200.320684 -37.696157)
			(xy 200.32784 -37.747967) (xy 200.328276 -37.774118) (xy 200.32779 -37.801369) (xy 200.320034 -37.855317)
			(xy 200.304679 -37.907612) (xy 200.282037 -37.957189) (xy 200.252571 -38.003039) (xy 200.21688 -38.04423)
			(xy 200.175689 -38.079921) (xy 200.129839 -38.109387) (xy 200.080262 -38.132029) (xy 200.027967 -38.147384)
			(xy 199.974019 -38.15514) (xy 199.919517 -38.15514) (xy 199.865569 -38.147384) (xy 199.813274 -38.132029)
			(xy 199.763697 -38.109387) (xy 199.717847 -38.079921) (xy 199.676656 -38.04423) (xy 199.640965 -38.003039)
			(xy 199.611499 -37.957189) (xy 199.588857 -37.907612) (xy 199.573502 -37.855317) (xy 199.565746 -37.801369)
			(xy 199.56526 -37.774118) (xy 199.56526 -37.773864) (xy 199.565862 -37.742146) (xy 199.576369 -37.679588)
			(xy 199.597104 -37.619637) (xy 199.611742 -37.591492) (xy 199.617076 -37.581586) (xy 199.6186 -37.559488)
			(xy 199.586596 -37.476684) (xy 199.582148 -37.466573) (xy 199.566328 -37.451182) (xy 199.556116 -37.446966)
			(xy 199.531575 -37.43792) (xy 199.485043 -37.414035) (xy 199.442211 -37.384018) (xy 199.403881 -37.34843)
			(xy 199.370773 -37.307938) (xy 199.343508 -37.263303) (xy 199.322598 -37.215361) (xy 199.308433 -37.165012)
			(xy 199.30128 -37.1132) (xy 199.300846 -37.087048) (xy 190.562059 -37.087048) (xy 190.571381 -37.118032)
			(xy 190.579501 -37.173208) (xy 190.58001 -37.201094) (xy 190.579501 -37.22898) (xy 190.571381 -37.284156)
			(xy 190.555313 -37.337563) (xy 190.531641 -37.38806) (xy 190.500868 -37.434573) (xy 190.463651 -37.47611)
			(xy 190.420783 -37.511785) (xy 190.373177 -37.540839) (xy 190.321848 -37.562651) (xy 190.267891 -37.576757)
			(xy 190.212454 -37.582857) (xy 190.15672 -37.58082) (xy 190.101877 -37.57069) (xy 190.049093 -37.552683)
			(xy 189.999493 -37.527182) (xy 189.954135 -37.494731) (xy 189.913986 -37.456022) (xy 189.8799 -37.411879)
			(xy 189.852604 -37.363244) (xy 189.832681 -37.311153) (xy 189.820555 -37.256716) (xy 189.816484 -37.201094)
			(xy 186.507182 -37.201094) (xy 186.543548 -37.241681) (xy 186.574321 -37.288194) (xy 186.597993 -37.338691)
			(xy 186.614061 -37.392098) (xy 186.622181 -37.447274) (xy 186.62269 -37.47516) (xy 186.622181 -37.503046)
			(xy 186.614061 -37.558222) (xy 186.597993 -37.611629) (xy 186.574321 -37.662126) (xy 186.574168 -37.662358)
			(xy 188.04839 -37.662358) (xy 188.052461 -37.606736) (xy 188.064587 -37.552299) (xy 188.08451 -37.500208)
			(xy 188.111806 -37.451573) (xy 188.145892 -37.40743) (xy 188.186041 -37.368721) (xy 188.231399 -37.33627)
			(xy 188.280999 -37.310769) (xy 188.333783 -37.292762) (xy 188.388626 -37.282632) (xy 188.44436 -37.280595)
			(xy 188.499797 -37.286695) (xy 188.553754 -37.300801) (xy 188.605083 -37.322613) (xy 188.652689 -37.351667)
			(xy 188.695557 -37.387342) (xy 188.732774 -37.428879) (xy 188.763547 -37.475392) (xy 188.787219 -37.525889)
			(xy 188.803287 -37.579296) (xy 188.811407 -37.634472) (xy 188.811916 -37.662358) (xy 188.811407 -37.690244)
			(xy 188.803287 -37.74542) (xy 188.787219 -37.798827) (xy 188.763547 -37.849324) (xy 188.732774 -37.895837)
			(xy 188.695557 -37.937374) (xy 188.652689 -37.973049) (xy 188.605083 -38.002103) (xy 188.553754 -38.023915)
			(xy 188.499797 -38.038021) (xy 188.44436 -38.044121) (xy 188.388626 -38.042084) (xy 188.333783 -38.031954)
			(xy 188.280999 -38.013947) (xy 188.231399 -37.988446) (xy 188.186041 -37.955995) (xy 188.145892 -37.917286)
			(xy 188.111806 -37.873143) (xy 188.08451 -37.824508) (xy 188.064587 -37.772417) (xy 188.052461 -37.71798)
			(xy 188.04839 -37.662358) (xy 186.574168 -37.662358) (xy 186.543548 -37.708639) (xy 186.506331 -37.750176)
			(xy 186.463463 -37.785851) (xy 186.415857 -37.814905) (xy 186.364528 -37.836717) (xy 186.310571 -37.850823)
			(xy 186.255134 -37.856923) (xy 186.1994 -37.854886) (xy 186.144557 -37.844756) (xy 186.091773 -37.826749)
			(xy 186.042173 -37.801248) (xy 185.996815 -37.768797) (xy 185.956666 -37.730088) (xy 185.92258 -37.685945)
			(xy 185.895284 -37.63731) (xy 185.875361 -37.585219) (xy 185.863235 -37.530782) (xy 185.859164 -37.47516)
			(xy 182.646416 -37.47516) (xy 182.657106 -37.484905) (xy 182.715635 -37.54911) (xy 182.767991 -37.618441)
			(xy 182.813726 -37.692307) (xy 182.852451 -37.770078) (xy 182.883835 -37.85109) (xy 182.907611 -37.934653)
			(xy 182.923574 -38.020052) (xy 182.93159 -38.106561) (xy 182.93159 -38.193439) (xy 182.923574 -38.279948)
			(xy 182.907611 -38.365347) (xy 182.883835 -38.44891) (xy 182.867467 -38.49116) (xy 185.859164 -38.49116)
			(xy 185.863235 -38.435538) (xy 185.875361 -38.381101) (xy 185.895284 -38.32901) (xy 185.92258 -38.280375)
			(xy 185.956666 -38.236232) (xy 185.996815 -38.197523) (xy 186.042173 -38.165072) (xy 186.091773 -38.139571)
			(xy 186.144557 -38.121564) (xy 186.1994 -38.111434) (xy 186.255134 -38.109397) (xy 186.310571 -38.115497)
			(xy 186.364528 -38.129603) (xy 186.415857 -38.151415) (xy 186.463463 -38.180469) (xy 186.506331 -38.216144)
			(xy 186.543548 -38.257681) (xy 186.574321 -38.304194) (xy 186.579451 -38.315138) (xy 200.518012 -38.315138)
			(xy 200.522083 -38.259516) (xy 200.534209 -38.205079) (xy 200.554132 -38.152988) (xy 200.581428 -38.104353)
			(xy 200.615514 -38.06021) (xy 200.655663 -38.021501) (xy 200.701021 -37.98905) (xy 200.750621 -37.963549)
			(xy 200.803405 -37.945542) (xy 200.858248 -37.935412) (xy 200.913982 -37.933375) (xy 200.969419 -37.939475)
			(xy 201.023376 -37.953581) (xy 201.074705 -37.975393) (xy 201.122311 -38.004447) (xy 201.165179 -38.040122)
			(xy 201.202396 -38.081659) (xy 201.233169 -38.128172) (xy 201.256841 -38.178669) (xy 201.261283 -38.193435)
			(xy 205.198286 -38.193435) (xy 205.198286 -38.106565) (xy 205.206301 -38.020065) (xy 205.222263 -37.934673)
			(xy 205.246035 -37.851118) (xy 205.277416 -37.770114) (xy 205.316137 -37.69235) (xy 205.361867 -37.61849)
			(xy 205.414217 -37.549165) (xy 205.472741 -37.484966) (xy 205.536938 -37.42644) (xy 205.606261 -37.374088)
			(xy 205.680118 -37.328354) (xy 205.757881 -37.289631) (xy 205.838884 -37.258247) (xy 205.922438 -37.234471)
			(xy 206.007829 -37.218506) (xy 206.094329 -37.210487) (xy 206.137764 -37.209984) (xy 206.215742 -37.209984)
			(xy 206.225754 -37.209546) (xy 206.24425 -37.20187) (xy 206.258402 -37.187701) (xy 206.266057 -37.169197)
			(xy 206.266542 -37.159184) (xy 206.266542 -37.151564) (xy 206.262224 -37.137594) (xy 206.25816 -37.131244)
			(xy 206.234755 -37.094771) (xy 206.193763 -37.01841) (xy 206.159777 -36.938683) (xy 206.133072 -36.856232)
			(xy 206.113861 -36.77172) (xy 206.1023 -36.685827) (xy 206.098481 -36.599243) (xy 206.102436 -36.512666)
			(xy 206.114131 -36.42679) (xy 206.133474 -36.342309) (xy 206.160309 -36.2599) (xy 206.194419 -36.180227)
			(xy 206.235531 -36.10393) (xy 206.283314 -36.031624) (xy 206.337382 -35.96389) (xy 206.397303 -35.901273)
			(xy 206.462592 -35.844276) (xy 206.532726 -35.793359) (xy 206.60714 -35.74893) (xy 206.685235 -35.711348)
			(xy 206.766384 -35.680913) (xy 206.849933 -35.657872) (xy 206.93521 -35.64241) (xy 207.02153 -35.63465)
			(xy 207.064864 -35.634168) (xy 207.065118 -35.634168) (xy 207.10845 -35.634632) (xy 207.194765 -35.642406)
			(xy 207.280036 -35.657881) (xy 207.363578 -35.680933) (xy 207.444719 -35.711376) (xy 207.522807 -35.748966)
			(xy 207.597213 -35.793399) (xy 207.66734 -35.84432) (xy 207.70447 -35.876738) (xy 224.917252 -35.876738)
			(xy 224.921323 -35.821116) (xy 224.933449 -35.766679) (xy 224.953372 -35.714588) (xy 224.980668 -35.665953)
			(xy 225.014754 -35.62181) (xy 225.054903 -35.583101) (xy 225.100261 -35.55065) (xy 225.149861 -35.525149)
			(xy 225.202645 -35.507142) (xy 225.257488 -35.497012) (xy 225.313222 -35.494975) (xy 225.368659 -35.501075)
			(xy 225.422616 -35.515181) (xy 225.473945 -35.536993) (xy 225.521551 -35.566047) (xy 225.564419 -35.601722)
			(xy 225.601636 -35.643259) (xy 225.632409 -35.689772) (xy 225.656081 -35.740269) (xy 225.672149 -35.793676)
			(xy 225.680269 -35.848852) (xy 225.680778 -35.876738) (xy 228.988872 -35.876738) (xy 228.992943 -35.821116)
			(xy 229.005069 -35.766679) (xy 229.024992 -35.714588) (xy 229.052288 -35.665953) (xy 229.086374 -35.62181)
			(xy 229.126523 -35.583101) (xy 229.171881 -35.55065) (xy 229.221481 -35.525149) (xy 229.274265 -35.507142)
			(xy 229.329108 -35.497012) (xy 229.384842 -35.494975) (xy 229.440279 -35.501075) (xy 229.494236 -35.515181)
			(xy 229.545565 -35.536993) (xy 229.593171 -35.566047) (xy 229.636039 -35.601722) (xy 229.673256 -35.643259)
			(xy 229.704029 -35.689772) (xy 229.727701 -35.740269) (xy 229.743769 -35.793676) (xy 229.751889 -35.848852)
			(xy 229.752398 -35.876738) (xy 229.751889 -35.904624) (xy 229.743769 -35.9598) (xy 229.727701 -36.013207)
			(xy 229.704029 -36.063704) (xy 229.673256 -36.110217) (xy 229.636039 -36.151754) (xy 229.593171 -36.187429)
			(xy 229.545565 -36.216483) (xy 229.494236 -36.238295) (xy 229.440279 -36.252401) (xy 229.384842 -36.258501)
			(xy 229.329108 -36.256464) (xy 229.274265 -36.246334) (xy 229.221481 -36.228327) (xy 229.171881 -36.202826)
			(xy 229.126523 -36.170375) (xy 229.086374 -36.131666) (xy 229.052288 -36.087523) (xy 229.024992 -36.038888)
			(xy 229.005069 -35.986797) (xy 228.992943 -35.93236) (xy 228.988872 -35.876738) (xy 225.680778 -35.876738)
			(xy 225.680269 -35.904624) (xy 225.672149 -35.9598) (xy 225.656081 -36.013207) (xy 225.632409 -36.063704)
			(xy 225.601636 -36.110217) (xy 225.564419 -36.151754) (xy 225.521551 -36.187429) (xy 225.473945 -36.216483)
			(xy 225.422616 -36.238295) (xy 225.368659 -36.252401) (xy 225.313222 -36.258501) (xy 225.257488 -36.256464)
			(xy 225.202645 -36.246334) (xy 225.149861 -36.228327) (xy 225.100261 -36.202826) (xy 225.054903 -36.170375)
			(xy 225.014754 -36.131666) (xy 224.980668 -36.087523) (xy 224.953372 -36.038888) (xy 224.933449 -35.986797)
			(xy 224.921323 -35.93236) (xy 224.917252 -35.876738) (xy 207.70447 -35.876738) (xy 207.732623 -35.901318)
			(xy 207.792537 -35.963935) (xy 207.846602 -36.031667) (xy 207.894381 -36.103971) (xy 207.935491 -36.180264)
			(xy 207.969601 -36.259933) (xy 207.996437 -36.342337) (xy 208.015783 -36.426815) (xy 208.027113 -36.50996)
			(xy 226.81387 -36.50996) (xy 226.817941 -36.454338) (xy 226.830067 -36.399901) (xy 226.84999 -36.34781)
			(xy 226.877286 -36.299175) (xy 226.911372 -36.255032) (xy 226.951521 -36.216323) (xy 226.996879 -36.183872)
			(xy 227.046479 -36.158371) (xy 227.099263 -36.140364) (xy 227.154106 -36.130234) (xy 227.20984 -36.128197)
			(xy 227.265277 -36.134297) (xy 227.319234 -36.148403) (xy 227.370563 -36.170215) (xy 227.418169 -36.199269)
			(xy 227.461037 -36.234944) (xy 227.498254 -36.276481) (xy 227.529027 -36.322994) (xy 227.552699 -36.373491)
			(xy 227.568767 -36.426898) (xy 227.572692 -36.453572) (xy 230.12857 -36.453572) (xy 230.132641 -36.39795)
			(xy 230.144767 -36.343513) (xy 230.16469 -36.291422) (xy 230.191986 -36.242787) (xy 230.226072 -36.198644)
			(xy 230.266221 -36.159935) (xy 230.311579 -36.127484) (xy 230.361179 -36.101983) (xy 230.413963 -36.083976)
			(xy 230.468806 -36.073846) (xy 230.52454 -36.071809) (xy 230.579977 -36.077909) (xy 230.633934 -36.092015)
			(xy 230.685263 -36.113827) (xy 230.732869 -36.142881) (xy 230.775737 -36.178556) (xy 230.812954 -36.220093)
			(xy 230.843727 -36.266606) (xy 230.867399 -36.317103) (xy 230.883467 -36.37051) (xy 230.891587 -36.425686)
			(xy 230.892096 -36.453572) (xy 230.891587 -36.481458) (xy 230.883467 -36.536634) (xy 230.867399 -36.590041)
			(xy 230.843727 -36.640538) (xy 230.812954 -36.687051) (xy 230.775737 -36.728588) (xy 230.732869 -36.764263)
			(xy 230.685263 -36.793317) (xy 230.633934 -36.815129) (xy 230.579977 -36.829235) (xy 230.52454 -36.835335)
			(xy 230.468806 -36.833298) (xy 230.413963 -36.823168) (xy 230.361179 -36.805161) (xy 230.311579 -36.77966)
			(xy 230.266221 -36.747209) (xy 230.226072 -36.7085) (xy 230.191986 -36.664357) (xy 230.16469 -36.615722)
			(xy 230.144767 -36.563631) (xy 230.132641 -36.509194) (xy 230.12857 -36.453572) (xy 227.572692 -36.453572)
			(xy 227.576887 -36.482074) (xy 227.577396 -36.50996) (xy 227.576887 -36.537846) (xy 227.568767 -36.593022)
			(xy 227.552699 -36.646429) (xy 227.529027 -36.696926) (xy 227.498254 -36.743439) (xy 227.461037 -36.784976)
			(xy 227.418169 -36.820651) (xy 227.370563 -36.849705) (xy 227.319234 -36.871517) (xy 227.265277 -36.885623)
			(xy 227.20984 -36.891723) (xy 227.154106 -36.889686) (xy 227.099263 -36.879556) (xy 227.046479 -36.861549)
			(xy 226.996879 -36.836048) (xy 226.951521 -36.803597) (xy 226.911372 -36.764888) (xy 226.877286 -36.720745)
			(xy 226.84999 -36.67211) (xy 226.830067 -36.620019) (xy 226.817941 -36.565582) (xy 226.81387 -36.50996)
			(xy 208.027113 -36.50996) (xy 208.027484 -36.512685) (xy 208.031445 -36.599259) (xy 208.027635 -36.685839)
			(xy 208.016084 -36.77173) (xy 207.996885 -36.85624) (xy 207.970192 -36.938691) (xy 207.936221 -37.01842)
			(xy 207.895244 -37.094784) (xy 207.871822 -37.131244) (xy 207.867758 -37.137594) (xy 207.86344 -37.151564)
			(xy 207.86344 -37.159184) (xy 207.863833 -37.169209) (xy 207.871506 -37.187734) (xy 207.885687 -37.201908)
			(xy 207.904215 -37.209571) (xy 207.91424 -37.209984) (xy 207.991964 -37.209984) (xy 208.035406 -37.210393)
			(xy 208.121919 -37.218406) (xy 208.207323 -37.234368) (xy 208.29089 -37.258142) (xy 208.371908 -37.289526)
			(xy 208.449683 -37.328251) (xy 208.523554 -37.373987) (xy 208.59289 -37.426345) (xy 208.64644 -37.47516)
			(xy 223.959164 -37.47516) (xy 223.963235 -37.419538) (xy 223.975361 -37.365101) (xy 223.995284 -37.31301)
			(xy 224.02258 -37.264375) (xy 224.056666 -37.220232) (xy 224.096815 -37.181523) (xy 224.142173 -37.149072)
			(xy 224.191773 -37.123571) (xy 224.244557 -37.105564) (xy 224.2994 -37.095434) (xy 224.355134 -37.093397)
			(xy 224.410571 -37.099497) (xy 224.464528 -37.113603) (xy 224.515857 -37.135415) (xy 224.563463 -37.164469)
			(xy 224.606331 -37.200144) (xy 224.607182 -37.201094) (xy 227.916484 -37.201094) (xy 227.920555 -37.145472)
			(xy 227.932681 -37.091035) (xy 227.952604 -37.038944) (xy 227.9799 -36.990309) (xy 228.013986 -36.946166)
			(xy 228.054135 -36.907457) (xy 228.099493 -36.875006) (xy 228.149093 -36.849505) (xy 228.201877 -36.831498)
			(xy 228.25672 -36.821368) (xy 228.312454 -36.819331) (xy 228.367891 -36.825431) (xy 228.421848 -36.839537)
			(xy 228.473177 -36.861349) (xy 228.520783 -36.890403) (xy 228.563651 -36.926078) (xy 228.600868 -36.967615)
			(xy 228.631641 -37.014128) (xy 228.655313 -37.064625) (xy 228.662059 -37.087048) (xy 237.400846 -37.087048)
			(xy 237.401311 -37.060444) (xy 237.408687 -37.007751) (xy 237.423317 -36.956595) (xy 237.444917 -36.907969)
			(xy 237.473066 -36.862819) (xy 237.507219 -36.822019) (xy 237.546712 -36.786364) (xy 237.568486 -36.771072)
			(xy 237.57841 -36.763541) (xy 237.590138 -36.741598) (xy 237.590838 -36.729162) (xy 237.590838 -36.644834)
			(xy 237.590166 -36.632384) (xy 237.578457 -36.610408) (xy 237.568486 -36.602924) (xy 237.546728 -36.587612)
			(xy 237.507247 -36.55195) (xy 237.473101 -36.51115) (xy 237.444953 -36.466003) (xy 237.423349 -36.417384)
			(xy 237.408707 -36.366236) (xy 237.40131 -36.313549) (xy 237.400846 -36.286948) (xy 237.4014 -36.259698)
			(xy 237.409149 -36.205753) (xy 237.424497 -36.15346) (xy 237.44713 -36.103883) (xy 237.476589 -36.058032)
			(xy 237.512273 -36.01684) (xy 237.553456 -35.981145) (xy 237.5993 -35.951675) (xy 237.648872 -35.92903)
			(xy 237.701161 -35.913669) (xy 237.755105 -35.905907) (xy 237.782354 -35.90544) (xy 237.786926 -35.90544)
			(xy 237.796135 -35.905166) (xy 237.813454 -35.898927) (xy 237.820708 -35.893248) (xy 237.871508 -35.84956)
			(xy 237.878214 -35.843323) (xy 237.887073 -35.827314) (xy 237.88878 -35.818318) (xy 237.88878 -35.818064)
			(xy 237.89313 -35.791134) (xy 237.90844 -35.738778) (xy 237.931051 -35.689137) (xy 237.960502 -35.643222)
			(xy 237.996192 -35.60197) (xy 238.037394 -35.566222) (xy 238.083268 -35.536707) (xy 238.132878 -35.514026)
			(xy 238.185212 -35.498643) (xy 238.239204 -35.49087) (xy 238.266478 -35.490404) (xy 238.293733 -35.490841)
			(xy 238.347688 -35.498596) (xy 238.39999 -35.513951) (xy 238.449575 -35.536593) (xy 238.495432 -35.566061)
			(xy 238.536629 -35.601756) (xy 238.572326 -35.64295) (xy 238.601797 -35.688806) (xy 238.624442 -35.738389)
			(xy 238.639799 -35.790691) (xy 238.647557 -35.844645) (xy 238.647557 -35.899155) (xy 238.639799 -35.953109)
			(xy 238.624442 -36.005411) (xy 238.601797 -36.054994) (xy 238.572326 -36.10085) (xy 238.536629 -36.142044)
			(xy 238.495432 -36.177739) (xy 238.449575 -36.207207) (xy 238.39999 -36.229849) (xy 238.347688 -36.245204)
			(xy 238.293733 -36.252959) (xy 238.266478 -36.25342) (xy 238.261906 -36.25342) (xy 238.252692 -36.253647)
			(xy 238.235373 -36.259918) (xy 238.228124 -36.265612) (xy 238.177324 -36.3093) (xy 238.170602 -36.315522)
			(xy 238.161751 -36.331541) (xy 238.160052 -36.340542) (xy 238.160052 -36.340796) (xy 238.155854 -36.366999)
			(xy 238.14117 -36.417994) (xy 238.119557 -36.466459) (xy 238.091433 -36.51146) (xy 238.088006 -36.515548)
			(xy 239.21415 -36.515548) (xy 239.218221 -36.459926) (xy 239.230347 -36.405489) (xy 239.25027 -36.353398)
			(xy 239.277566 -36.304763) (xy 239.311652 -36.26062) (xy 239.351801 -36.221911) (xy 239.397159 -36.18946)
			(xy 239.446759 -36.163959) (xy 239.499543 -36.145952) (xy 239.554386 -36.135822) (xy 239.61012 -36.133785)
			(xy 239.665557 -36.139885) (xy 239.719514 -36.153991) (xy 239.770843 -36.175803) (xy 239.818449 -36.204857)
			(xy 239.861317 -36.240532) (xy 239.898534 -36.282069) (xy 239.929307 -36.328582) (xy 239.952979 -36.379079)
			(xy 239.969047 -36.432486) (xy 239.977167 -36.487662) (xy 239.977676 -36.515548) (xy 239.977167 -36.543434)
			(xy 239.969047 -36.59861) (xy 239.952979 -36.652017) (xy 239.929307 -36.702514) (xy 239.898534 -36.749027)
			(xy 239.861317 -36.790564) (xy 239.818449 -36.826239) (xy 239.770843 -36.855293) (xy 239.719514 -36.877105)
			(xy 239.665557 -36.891211) (xy 239.61012 -36.897311) (xy 239.554386 -36.895274) (xy 239.499543 -36.885144)
			(xy 239.446759 -36.867137) (xy 239.397159 -36.841636) (xy 239.351801 -36.809185) (xy 239.311652 -36.770476)
			(xy 239.277566 -36.726333) (xy 239.25027 -36.677698) (xy 239.230347 -36.625607) (xy 239.218221 -36.57117)
			(xy 239.21415 -36.515548) (xy 238.088006 -36.515548) (xy 238.057341 -36.552127) (xy 238.01794 -36.587675)
			(xy 237.996222 -36.602924) (xy 237.986301 -36.610458) (xy 237.974571 -36.632399) (xy 237.97387 -36.644834)
			(xy 237.97387 -36.729162) (xy 237.974541 -36.741612) (xy 237.986251 -36.763588) (xy 237.996222 -36.771072)
			(xy 238.01798 -36.786385) (xy 238.057461 -36.822047) (xy 238.091606 -36.862846) (xy 238.119754 -36.907993)
			(xy 238.141358 -36.956612) (xy 238.156001 -37.00776) (xy 238.163397 -37.060447) (xy 238.163862 -37.087048)
			(xy 238.163862 -37.087302) (xy 238.163244 -37.119019) (xy 238.152743 -37.181577) (xy 238.132015 -37.241528)
			(xy 238.11738 -37.269674) (xy 238.112046 -37.27958) (xy 238.110522 -37.301678) (xy 238.142526 -37.384482)
			(xy 238.14702 -37.394568) (xy 238.162807 -37.409971) (xy 238.173006 -37.4142) (xy 238.19754 -37.423263)
			(xy 238.24407 -37.447146) (xy 238.286902 -37.477163) (xy 238.32523 -37.51275) (xy 238.358338 -37.553239)
			(xy 238.385604 -37.597871) (xy 238.406516 -37.64581) (xy 238.420684 -37.696157) (xy 238.42784 -37.747967)
			(xy 238.428276 -37.774118) (xy 238.42779 -37.801369) (xy 238.420034 -37.855317) (xy 238.404679 -37.907612)
			(xy 238.382037 -37.957189) (xy 238.352571 -38.003039) (xy 238.31688 -38.04423) (xy 238.275689 -38.079921)
			(xy 238.229839 -38.109387) (xy 238.180262 -38.132029) (xy 238.127967 -38.147384) (xy 238.074019 -38.15514)
			(xy 238.019517 -38.15514) (xy 237.965569 -38.147384) (xy 237.913274 -38.132029) (xy 237.863697 -38.109387)
			(xy 237.817847 -38.079921) (xy 237.776656 -38.04423) (xy 237.740965 -38.003039) (xy 237.711499 -37.957189)
			(xy 237.688857 -37.907612) (xy 237.673502 -37.855317) (xy 237.665746 -37.801369) (xy 237.66526 -37.774118)
			(xy 237.66526 -37.773864) (xy 237.665862 -37.742146) (xy 237.676369 -37.679588) (xy 237.697104 -37.619637)
			(xy 237.711742 -37.591492) (xy 237.717076 -37.581586) (xy 237.7186 -37.559488) (xy 237.686596 -37.476684)
			(xy 237.682148 -37.466573) (xy 237.666328 -37.451182) (xy 237.656116 -37.446966) (xy 237.631575 -37.43792)
			(xy 237.585043 -37.414035) (xy 237.542211 -37.384018) (xy 237.503881 -37.34843) (xy 237.470773 -37.307938)
			(xy 237.443508 -37.263303) (xy 237.422598 -37.215361) (xy 237.408433 -37.165012) (xy 237.40128 -37.1132)
			(xy 237.400846 -37.087048) (xy 228.662059 -37.087048) (xy 228.671381 -37.118032) (xy 228.679501 -37.173208)
			(xy 228.68001 -37.201094) (xy 228.679501 -37.22898) (xy 228.671381 -37.284156) (xy 228.655313 -37.337563)
			(xy 228.631641 -37.38806) (xy 228.600868 -37.434573) (xy 228.563651 -37.47611) (xy 228.520783 -37.511785)
			(xy 228.473177 -37.540839) (xy 228.421848 -37.562651) (xy 228.367891 -37.576757) (xy 228.312454 -37.582857)
			(xy 228.25672 -37.58082) (xy 228.201877 -37.57069) (xy 228.149093 -37.552683) (xy 228.099493 -37.527182)
			(xy 228.054135 -37.494731) (xy 228.013986 -37.456022) (xy 227.9799 -37.411879) (xy 227.952604 -37.363244)
			(xy 227.932681 -37.311153) (xy 227.920555 -37.256716) (xy 227.916484 -37.201094) (xy 224.607182 -37.201094)
			(xy 224.643548 -37.241681) (xy 224.674321 -37.288194) (xy 224.697993 -37.338691) (xy 224.714061 -37.392098)
			(xy 224.722181 -37.447274) (xy 224.72269 -37.47516) (xy 224.722181 -37.503046) (xy 224.714061 -37.558222)
			(xy 224.697993 -37.611629) (xy 224.674321 -37.662126) (xy 224.674168 -37.662358) (xy 226.14839 -37.662358)
			(xy 226.152461 -37.606736) (xy 226.164587 -37.552299) (xy 226.18451 -37.500208) (xy 226.211806 -37.451573)
			(xy 226.245892 -37.40743) (xy 226.286041 -37.368721) (xy 226.331399 -37.33627) (xy 226.380999 -37.310769)
			(xy 226.433783 -37.292762) (xy 226.488626 -37.282632) (xy 226.54436 -37.280595) (xy 226.599797 -37.286695)
			(xy 226.653754 -37.300801) (xy 226.705083 -37.322613) (xy 226.752689 -37.351667) (xy 226.795557 -37.387342)
			(xy 226.832774 -37.428879) (xy 226.863547 -37.475392) (xy 226.887219 -37.525889) (xy 226.903287 -37.579296)
			(xy 226.911407 -37.634472) (xy 226.911916 -37.662358) (xy 226.911407 -37.690244) (xy 226.903287 -37.74542)
			(xy 226.887219 -37.798827) (xy 226.863547 -37.849324) (xy 226.832774 -37.895837) (xy 226.795557 -37.937374)
			(xy 226.752689 -37.973049) (xy 226.705083 -38.002103) (xy 226.653754 -38.023915) (xy 226.599797 -38.038021)
			(xy 226.54436 -38.044121) (xy 226.488626 -38.042084) (xy 226.433783 -38.031954) (xy 226.380999 -38.013947)
			(xy 226.331399 -37.988446) (xy 226.286041 -37.955995) (xy 226.245892 -37.917286) (xy 226.211806 -37.873143)
			(xy 226.18451 -37.824508) (xy 226.164587 -37.772417) (xy 226.152461 -37.71798) (xy 226.14839 -37.662358)
			(xy 224.674168 -37.662358) (xy 224.643548 -37.708639) (xy 224.606331 -37.750176) (xy 224.563463 -37.785851)
			(xy 224.515857 -37.814905) (xy 224.464528 -37.836717) (xy 224.410571 -37.850823) (xy 224.355134 -37.856923)
			(xy 224.2994 -37.854886) (xy 224.244557 -37.844756) (xy 224.191773 -37.826749) (xy 224.142173 -37.801248)
			(xy 224.096815 -37.768797) (xy 224.056666 -37.730088) (xy 224.02258 -37.685945) (xy 223.995284 -37.63731)
			(xy 223.975361 -37.585219) (xy 223.963235 -37.530782) (xy 223.959164 -37.47516) (xy 208.64644 -37.47516)
			(xy 208.657098 -37.484876) (xy 208.715632 -37.549083) (xy 208.767992 -37.618416) (xy 208.813731 -37.692285)
			(xy 208.852459 -37.77006) (xy 208.883846 -37.851075) (xy 208.907623 -37.934642) (xy 208.923589 -38.020046)
			(xy 208.931605 -38.106558) (xy 208.931605 -38.193442) (xy 208.923589 -38.279954) (xy 208.917011 -38.315138)
			(xy 238.618012 -38.315138) (xy 238.622083 -38.259516) (xy 238.634209 -38.205079) (xy 238.654132 -38.152988)
			(xy 238.681428 -38.104353) (xy 238.715514 -38.06021) (xy 238.755663 -38.021501) (xy 238.801021 -37.98905)
			(xy 238.850621 -37.963549) (xy 238.903405 -37.945542) (xy 238.958248 -37.935412) (xy 239.013982 -37.933375)
			(xy 239.069419 -37.939475) (xy 239.123376 -37.953581) (xy 239.174705 -37.975393) (xy 239.222311 -38.004447)
			(xy 239.265179 -38.040122) (xy 239.302396 -38.081659) (xy 239.333169 -38.128172) (xy 239.356841 -38.178669)
			(xy 239.361283 -38.193435) (xy 243.298286 -38.193435) (xy 243.298286 -38.106565) (xy 243.306301 -38.020065)
			(xy 243.322263 -37.934673) (xy 243.346035 -37.851118) (xy 243.377416 -37.770114) (xy 243.416137 -37.69235)
			(xy 243.461867 -37.61849) (xy 243.514217 -37.549165) (xy 243.572741 -37.484966) (xy 243.636938 -37.42644)
			(xy 243.706261 -37.374088) (xy 243.780118 -37.328354) (xy 243.857881 -37.289631) (xy 243.938884 -37.258247)
			(xy 244.022438 -37.234471) (xy 244.107829 -37.218506) (xy 244.194329 -37.210487) (xy 244.237764 -37.209984)
			(xy 244.315742 -37.209984) (xy 244.325754 -37.209546) (xy 244.34425 -37.20187) (xy 244.358402 -37.187701)
			(xy 244.366057 -37.169197) (xy 244.366542 -37.159184) (xy 244.366542 -37.151564) (xy 244.362224 -37.137594)
			(xy 244.35816 -37.131244) (xy 244.334755 -37.094771) (xy 244.293763 -37.01841) (xy 244.259777 -36.938683)
			(xy 244.233072 -36.856232) (xy 244.213861 -36.77172) (xy 244.2023 -36.685827) (xy 244.198481 -36.599243)
			(xy 244.202436 -36.512666) (xy 244.214131 -36.42679) (xy 244.233474 -36.342309) (xy 244.260309 -36.2599)
			(xy 244.294419 -36.180227) (xy 244.335531 -36.10393) (xy 244.383314 -36.031624) (xy 244.437382 -35.96389)
			(xy 244.497303 -35.901273) (xy 244.562592 -35.844276) (xy 244.632726 -35.793359) (xy 244.70714 -35.74893)
			(xy 244.785235 -35.711348) (xy 244.866384 -35.680913) (xy 244.949933 -35.657872) (xy 245.03521 -35.64241)
			(xy 245.12153 -35.63465) (xy 245.164864 -35.634168) (xy 245.165118 -35.634168) (xy 245.20845 -35.634632)
			(xy 245.294765 -35.642406) (xy 245.380036 -35.657881) (xy 245.463578 -35.680933) (xy 245.544719 -35.711376)
			(xy 245.622807 -35.748966) (xy 245.697213 -35.793399) (xy 245.76734 -35.84432) (xy 245.80447 -35.876738)
			(xy 250.9172 -35.876738) (xy 250.921271 -35.821116) (xy 250.933397 -35.766679) (xy 250.95332 -35.714588)
			(xy 250.980616 -35.665953) (xy 251.014702 -35.62181) (xy 251.054851 -35.583101) (xy 251.100209 -35.55065)
			(xy 251.149809 -35.525149) (xy 251.202593 -35.507142) (xy 251.257436 -35.497012) (xy 251.31317 -35.494975)
			(xy 251.368607 -35.501075) (xy 251.422564 -35.515181) (xy 251.473893 -35.536993) (xy 251.521499 -35.566047)
			(xy 251.564367 -35.601722) (xy 251.601584 -35.643259) (xy 251.632357 -35.689772) (xy 251.656029 -35.740269)
			(xy 251.672097 -35.793676) (xy 251.680217 -35.848852) (xy 251.680726 -35.876738) (xy 254.98882 -35.876738)
			(xy 254.992891 -35.821116) (xy 255.005017 -35.766679) (xy 255.02494 -35.714588) (xy 255.052236 -35.665953)
			(xy 255.086322 -35.62181) (xy 255.126471 -35.583101) (xy 255.171829 -35.55065) (xy 255.221429 -35.525149)
			(xy 255.274213 -35.507142) (xy 255.329056 -35.497012) (xy 255.38479 -35.494975) (xy 255.440227 -35.501075)
			(xy 255.494184 -35.515181) (xy 255.545513 -35.536993) (xy 255.593119 -35.566047) (xy 255.635987 -35.601722)
			(xy 255.673204 -35.643259) (xy 255.703977 -35.689772) (xy 255.727649 -35.740269) (xy 255.743717 -35.793676)
			(xy 255.751837 -35.848852) (xy 255.752346 -35.876738) (xy 255.751837 -35.904624) (xy 255.743717 -35.9598)
			(xy 255.727649 -36.013207) (xy 255.703977 -36.063704) (xy 255.673204 -36.110217) (xy 255.635987 -36.151754)
			(xy 255.593119 -36.187429) (xy 255.545513 -36.216483) (xy 255.494184 -36.238295) (xy 255.440227 -36.252401)
			(xy 255.38479 -36.258501) (xy 255.329056 -36.256464) (xy 255.274213 -36.246334) (xy 255.221429 -36.228327)
			(xy 255.171829 -36.202826) (xy 255.126471 -36.170375) (xy 255.086322 -36.131666) (xy 255.052236 -36.087523)
			(xy 255.02494 -36.038888) (xy 255.005017 -35.986797) (xy 254.992891 -35.93236) (xy 254.98882 -35.876738)
			(xy 251.680726 -35.876738) (xy 251.680217 -35.904624) (xy 251.672097 -35.9598) (xy 251.656029 -36.013207)
			(xy 251.632357 -36.063704) (xy 251.601584 -36.110217) (xy 251.564367 -36.151754) (xy 251.521499 -36.187429)
			(xy 251.473893 -36.216483) (xy 251.422564 -36.238295) (xy 251.368607 -36.252401) (xy 251.31317 -36.258501)
			(xy 251.257436 -36.256464) (xy 251.202593 -36.246334) (xy 251.149809 -36.228327) (xy 251.100209 -36.202826)
			(xy 251.054851 -36.170375) (xy 251.014702 -36.131666) (xy 250.980616 -36.087523) (xy 250.95332 -36.038888)
			(xy 250.933397 -35.986797) (xy 250.921271 -35.93236) (xy 250.9172 -35.876738) (xy 245.80447 -35.876738)
			(xy 245.832623 -35.901318) (xy 245.892537 -35.963935) (xy 245.946602 -36.031667) (xy 245.994381 -36.103971)
			(xy 246.035491 -36.180264) (xy 246.069601 -36.259933) (xy 246.096437 -36.342337) (xy 246.115783 -36.426815)
			(xy 246.127113 -36.50996) (xy 252.813818 -36.50996) (xy 252.817889 -36.454338) (xy 252.830015 -36.399901)
			(xy 252.849938 -36.34781) (xy 252.877234 -36.299175) (xy 252.91132 -36.255032) (xy 252.951469 -36.216323)
			(xy 252.996827 -36.183872) (xy 253.046427 -36.158371) (xy 253.099211 -36.140364) (xy 253.154054 -36.130234)
			(xy 253.209788 -36.128197) (xy 253.265225 -36.134297) (xy 253.319182 -36.148403) (xy 253.370511 -36.170215)
			(xy 253.418117 -36.199269) (xy 253.460985 -36.234944) (xy 253.498202 -36.276481) (xy 253.528975 -36.322994)
			(xy 253.552647 -36.373491) (xy 253.568715 -36.426898) (xy 253.57264 -36.453572) (xy 256.128518 -36.453572)
			(xy 256.132589 -36.39795) (xy 256.144715 -36.343513) (xy 256.164638 -36.291422) (xy 256.191934 -36.242787)
			(xy 256.22602 -36.198644) (xy 256.266169 -36.159935) (xy 256.311527 -36.127484) (xy 256.361127 -36.101983)
			(xy 256.413911 -36.083976) (xy 256.468754 -36.073846) (xy 256.524488 -36.071809) (xy 256.579925 -36.077909)
			(xy 256.633882 -36.092015) (xy 256.685211 -36.113827) (xy 256.732817 -36.142881) (xy 256.775685 -36.178556)
			(xy 256.812902 -36.220093) (xy 256.843675 -36.266606) (xy 256.867347 -36.317103) (xy 256.883415 -36.37051)
			(xy 256.891535 -36.425686) (xy 256.892044 -36.453572) (xy 256.891535 -36.481458) (xy 256.883415 -36.536634)
			(xy 256.867347 -36.590041) (xy 256.843675 -36.640538) (xy 256.812902 -36.687051) (xy 256.775685 -36.728588)
			(xy 256.732817 -36.764263) (xy 256.685211 -36.793317) (xy 256.633882 -36.815129) (xy 256.579925 -36.829235)
			(xy 256.524488 -36.835335) (xy 256.468754 -36.833298) (xy 256.413911 -36.823168) (xy 256.361127 -36.805161)
			(xy 256.311527 -36.77966) (xy 256.266169 -36.747209) (xy 256.22602 -36.7085) (xy 256.191934 -36.664357)
			(xy 256.164638 -36.615722) (xy 256.144715 -36.563631) (xy 256.132589 -36.509194) (xy 256.128518 -36.453572)
			(xy 253.57264 -36.453572) (xy 253.576835 -36.482074) (xy 253.577344 -36.50996) (xy 253.576835 -36.537846)
			(xy 253.568715 -36.593022) (xy 253.552647 -36.646429) (xy 253.528975 -36.696926) (xy 253.498202 -36.743439)
			(xy 253.460985 -36.784976) (xy 253.418117 -36.820651) (xy 253.370511 -36.849705) (xy 253.319182 -36.871517)
			(xy 253.265225 -36.885623) (xy 253.209788 -36.891723) (xy 253.154054 -36.889686) (xy 253.099211 -36.879556)
			(xy 253.046427 -36.861549) (xy 252.996827 -36.836048) (xy 252.951469 -36.803597) (xy 252.91132 -36.764888)
			(xy 252.877234 -36.720745) (xy 252.849938 -36.67211) (xy 252.830015 -36.620019) (xy 252.817889 -36.565582)
			(xy 252.813818 -36.50996) (xy 246.127113 -36.50996) (xy 246.127484 -36.512685) (xy 246.131445 -36.599259)
			(xy 246.127635 -36.685839) (xy 246.116084 -36.77173) (xy 246.096885 -36.85624) (xy 246.070192 -36.938691)
			(xy 246.036221 -37.01842) (xy 245.995244 -37.094784) (xy 245.971822 -37.131244) (xy 245.967758 -37.137594)
			(xy 245.96344 -37.151564) (xy 245.96344 -37.159184) (xy 245.963833 -37.169209) (xy 245.971506 -37.187734)
			(xy 245.985687 -37.201908) (xy 246.004215 -37.209571) (xy 246.01424 -37.209984) (xy 246.091964 -37.209984)
			(xy 246.135406 -37.210393) (xy 246.221919 -37.218406) (xy 246.307323 -37.234368) (xy 246.39089 -37.258142)
			(xy 246.471908 -37.289526) (xy 246.549683 -37.328251) (xy 246.623554 -37.373987) (xy 246.69289 -37.426345)
			(xy 246.74644 -37.47516) (xy 249.959112 -37.47516) (xy 249.963183 -37.419538) (xy 249.975309 -37.365101)
			(xy 249.995232 -37.31301) (xy 250.022528 -37.264375) (xy 250.056614 -37.220232) (xy 250.096763 -37.181523)
			(xy 250.142121 -37.149072) (xy 250.191721 -37.123571) (xy 250.244505 -37.105564) (xy 250.299348 -37.095434)
			(xy 250.355082 -37.093397) (xy 250.410519 -37.099497) (xy 250.464476 -37.113603) (xy 250.515805 -37.135415)
			(xy 250.563411 -37.164469) (xy 250.606279 -37.200144) (xy 250.60713 -37.201094) (xy 253.916432 -37.201094)
			(xy 253.920503 -37.145472) (xy 253.932629 -37.091035) (xy 253.952552 -37.038944) (xy 253.979848 -36.990309)
			(xy 254.013934 -36.946166) (xy 254.054083 -36.907457) (xy 254.099441 -36.875006) (xy 254.149041 -36.849505)
			(xy 254.201825 -36.831498) (xy 254.256668 -36.821368) (xy 254.312402 -36.819331) (xy 254.367839 -36.825431)
			(xy 254.421796 -36.839537) (xy 254.473125 -36.861349) (xy 254.520731 -36.890403) (xy 254.563599 -36.926078)
			(xy 254.600816 -36.967615) (xy 254.631589 -37.014128) (xy 254.655261 -37.064625) (xy 254.662007 -37.087048)
			(xy 263.400794 -37.087048) (xy 263.401282 -37.060445) (xy 263.408657 -37.007754) (xy 263.423285 -36.956599)
			(xy 263.444881 -36.907975) (xy 263.473026 -36.862824) (xy 263.507175 -36.822024) (xy 263.546663 -36.786366)
			(xy 263.568434 -36.771072) (xy 263.578367 -36.763551) (xy 263.590088 -36.7416) (xy 263.590786 -36.729162)
			(xy 263.590786 -36.644834) (xy 263.590135 -36.632381) (xy 263.578413 -36.610403) (xy 263.568434 -36.602924)
			(xy 263.546665 -36.587628) (xy 263.507186 -36.551961) (xy 263.473043 -36.511158) (xy 263.444897 -36.466008)
			(xy 263.423295 -36.417387) (xy 263.408654 -36.366237) (xy 263.401258 -36.31355) (xy 263.400794 -36.286948)
			(xy 263.4013 -36.259696) (xy 263.40905 -36.205747) (xy 263.4244 -36.15345) (xy 263.447038 -36.103869)
			(xy 263.476501 -36.058016) (xy 263.51219 -36.016823) (xy 263.553379 -35.981128) (xy 263.599229 -35.95166)
			(xy 263.648806 -35.929017) (xy 263.701102 -35.91366) (xy 263.75505 -35.905903) (xy 263.782302 -35.90544)
			(xy 263.786874 -35.90544) (xy 263.796085 -35.90519) (xy 263.813404 -35.898934) (xy 263.820656 -35.893248)
			(xy 263.871456 -35.84956) (xy 263.878169 -35.843331) (xy 263.887023 -35.827316) (xy 263.888728 -35.818318)
			(xy 263.888728 -35.818064) (xy 263.893031 -35.791125) (xy 263.908344 -35.738766) (xy 263.930959 -35.689122)
			(xy 263.960414 -35.643205) (xy 263.99611 -35.601952) (xy 264.037318 -35.566204) (xy 264.083197 -35.536691)
			(xy 264.132813 -35.514013) (xy 264.185153 -35.498634) (xy 264.23915 -35.490867) (xy 264.266426 -35.490404)
			(xy 264.293677 -35.490868) (xy 264.347624 -35.498627) (xy 264.399917 -35.513985) (xy 264.449492 -35.536629)
			(xy 264.495341 -35.566096) (xy 264.536529 -35.601789) (xy 264.572219 -35.64298) (xy 264.601684 -35.688831)
			(xy 264.624324 -35.738408) (xy 264.639678 -35.790702) (xy 264.647434 -35.844649) (xy 264.647434 -35.899151)
			(xy 264.639678 -35.953098) (xy 264.624324 -36.005392) (xy 264.601684 -36.054969) (xy 264.572219 -36.10082)
			(xy 264.536529 -36.142011) (xy 264.495341 -36.177704) (xy 264.449492 -36.207171) (xy 264.399917 -36.229815)
			(xy 264.347624 -36.245173) (xy 264.293677 -36.252932) (xy 264.266426 -36.25342) (xy 264.261854 -36.25342)
			(xy 264.252642 -36.25367) (xy 264.235323 -36.259925) (xy 264.228072 -36.265612) (xy 264.177272 -36.3093)
			(xy 264.170542 -36.315513) (xy 264.161697 -36.33154) (xy 264.16 -36.340542) (xy 264.16 -36.340796)
			(xy 264.155782 -36.366996) (xy 264.1411 -36.417989) (xy 264.11949 -36.466454) (xy 264.09137 -36.511455)
			(xy 264.087939 -36.515548) (xy 265.214098 -36.515548) (xy 265.218169 -36.459926) (xy 265.230295 -36.405489)
			(xy 265.250218 -36.353398) (xy 265.277514 -36.304763) (xy 265.3116 -36.26062) (xy 265.351749 -36.221911)
			(xy 265.397107 -36.18946) (xy 265.446707 -36.163959) (xy 265.499491 -36.145952) (xy 265.554334 -36.135822)
			(xy 265.610068 -36.133785) (xy 265.665505 -36.139885) (xy 265.719462 -36.153991) (xy 265.770791 -36.175803)
			(xy 265.818397 -36.204857) (xy 265.861265 -36.240532) (xy 265.898482 -36.282069) (xy 265.929255 -36.328582)
			(xy 265.952927 -36.379079) (xy 265.968995 -36.432486) (xy 265.977115 -36.487662) (xy 265.977624 -36.515548)
			(xy 265.977115 -36.543434) (xy 265.968995 -36.59861) (xy 265.952927 -36.652017) (xy 265.929255 -36.702514)
			(xy 265.898482 -36.749027) (xy 265.861265 -36.790564) (xy 265.818397 -36.826239) (xy 265.770791 -36.855293)
			(xy 265.719462 -36.877105) (xy 265.665505 -36.891211) (xy 265.610068 -36.897311) (xy 265.554334 -36.895274)
			(xy 265.499491 -36.885144) (xy 265.446707 -36.867137) (xy 265.397107 -36.841636) (xy 265.351749 -36.809185)
			(xy 265.3116 -36.770476) (xy 265.277514 -36.726333) (xy 265.250218 -36.677698) (xy 265.230295 -36.625607)
			(xy 265.218169 -36.57117) (xy 265.214098 -36.515548) (xy 264.087939 -36.515548) (xy 264.057282 -36.552123)
			(xy 264.017886 -36.587673) (xy 263.99617 -36.602924) (xy 263.98624 -36.610447) (xy 263.974517 -36.632397)
			(xy 263.973818 -36.644834) (xy 263.973818 -36.729162) (xy 263.97447 -36.741615) (xy 263.986192 -36.763593)
			(xy 263.99617 -36.771072) (xy 264.017938 -36.78637) (xy 264.057417 -36.822036) (xy 264.09156 -36.862839)
			(xy 264.119706 -36.907988) (xy 264.141308 -36.956609) (xy 264.15595 -37.007759) (xy 264.163345 -37.060446)
			(xy 264.16381 -37.087048) (xy 264.16381 -37.087302) (xy 264.163187 -37.119019) (xy 264.152687 -37.181576)
			(xy 264.131961 -37.241528) (xy 264.117328 -37.269674) (xy 264.111994 -37.27958) (xy 264.11047 -37.301678)
			(xy 264.142474 -37.384482) (xy 264.146947 -37.394579) (xy 264.162749 -37.409978) (xy 264.172954 -37.4142)
			(xy 264.197477 -37.423293) (xy 264.244008 -37.44717) (xy 264.286841 -37.477182) (xy 264.325171 -37.512764)
			(xy 264.358281 -37.553249) (xy 264.385548 -37.597879) (xy 264.406462 -37.645815) (xy 264.420631 -37.69616)
			(xy 264.427788 -37.747968) (xy 264.428224 -37.774118) (xy 264.427738 -37.801369) (xy 264.419982 -37.855317)
			(xy 264.404627 -37.907612) (xy 264.381985 -37.957189) (xy 264.352519 -38.003039) (xy 264.316828 -38.04423)
			(xy 264.275637 -38.079921) (xy 264.229787 -38.109387) (xy 264.18021 -38.132029) (xy 264.127915 -38.147384)
			(xy 264.073967 -38.15514) (xy 264.019465 -38.15514) (xy 263.965517 -38.147384) (xy 263.913222 -38.132029)
			(xy 263.863645 -38.109387) (xy 263.817795 -38.079921) (xy 263.776604 -38.04423) (xy 263.740913 -38.003039)
			(xy 263.711447 -37.957189) (xy 263.688805 -37.907612) (xy 263.67345 -37.855317) (xy 263.665694 -37.801369)
			(xy 263.665208 -37.774118) (xy 263.665208 -37.773864) (xy 263.665816 -37.742147) (xy 263.676322 -37.679588)
			(xy 263.697054 -37.619637) (xy 263.71169 -37.591492) (xy 263.717024 -37.581586) (xy 263.718548 -37.559488)
			(xy 263.686544 -37.476684) (xy 263.682075 -37.466585) (xy 263.66627 -37.451188) (xy 263.656064 -37.446966)
			(xy 263.631512 -37.437949) (xy 263.584981 -37.414059) (xy 263.54215 -37.384036) (xy 263.503822 -37.348444)
			(xy 263.470716 -37.307949) (xy 263.443453 -37.26331) (xy 263.422543 -37.215366) (xy 263.40838 -37.165015)
			(xy 263.401228 -37.113201) (xy 263.400794 -37.087048) (xy 254.662007 -37.087048) (xy 254.671329 -37.118032)
			(xy 254.679449 -37.173208) (xy 254.679958 -37.201094) (xy 254.679449 -37.22898) (xy 254.671329 -37.284156)
			(xy 254.655261 -37.337563) (xy 254.631589 -37.38806) (xy 254.600816 -37.434573) (xy 254.563599 -37.47611)
			(xy 254.520731 -37.511785) (xy 254.473125 -37.540839) (xy 254.421796 -37.562651) (xy 254.367839 -37.576757)
			(xy 254.312402 -37.582857) (xy 254.256668 -37.58082) (xy 254.201825 -37.57069) (xy 254.149041 -37.552683)
			(xy 254.099441 -37.527182) (xy 254.054083 -37.494731) (xy 254.013934 -37.456022) (xy 253.979848 -37.411879)
			(xy 253.952552 -37.363244) (xy 253.932629 -37.311153) (xy 253.920503 -37.256716) (xy 253.916432 -37.201094)
			(xy 250.60713 -37.201094) (xy 250.643496 -37.241681) (xy 250.674269 -37.288194) (xy 250.697941 -37.338691)
			(xy 250.714009 -37.392098) (xy 250.722129 -37.447274) (xy 250.722638 -37.47516) (xy 250.722129 -37.503046)
			(xy 250.714009 -37.558222) (xy 250.697941 -37.611629) (xy 250.674269 -37.662126) (xy 250.674116 -37.662358)
			(xy 252.148338 -37.662358) (xy 252.152409 -37.606736) (xy 252.164535 -37.552299) (xy 252.184458 -37.500208)
			(xy 252.211754 -37.451573) (xy 252.24584 -37.40743) (xy 252.285989 -37.368721) (xy 252.331347 -37.33627)
			(xy 252.380947 -37.310769) (xy 252.433731 -37.292762) (xy 252.488574 -37.282632) (xy 252.544308 -37.280595)
			(xy 252.599745 -37.286695) (xy 252.653702 -37.300801) (xy 252.705031 -37.322613) (xy 252.752637 -37.351667)
			(xy 252.795505 -37.387342) (xy 252.832722 -37.428879) (xy 252.863495 -37.475392) (xy 252.887167 -37.525889)
			(xy 252.903235 -37.579296) (xy 252.911355 -37.634472) (xy 252.911864 -37.662358) (xy 252.911355 -37.690244)
			(xy 252.903235 -37.74542) (xy 252.887167 -37.798827) (xy 252.863495 -37.849324) (xy 252.832722 -37.895837)
			(xy 252.795505 -37.937374) (xy 252.752637 -37.973049) (xy 252.705031 -38.002103) (xy 252.653702 -38.023915)
			(xy 252.599745 -38.038021) (xy 252.544308 -38.044121) (xy 252.488574 -38.042084) (xy 252.433731 -38.031954)
			(xy 252.380947 -38.013947) (xy 252.331347 -37.988446) (xy 252.285989 -37.955995) (xy 252.24584 -37.917286)
			(xy 252.211754 -37.873143) (xy 252.184458 -37.824508) (xy 252.164535 -37.772417) (xy 252.152409 -37.71798)
			(xy 252.148338 -37.662358) (xy 250.674116 -37.662358) (xy 250.643496 -37.708639) (xy 250.606279 -37.750176)
			(xy 250.563411 -37.785851) (xy 250.515805 -37.814905) (xy 250.464476 -37.836717) (xy 250.410519 -37.850823)
			(xy 250.355082 -37.856923) (xy 250.299348 -37.854886) (xy 250.244505 -37.844756) (xy 250.191721 -37.826749)
			(xy 250.142121 -37.801248) (xy 250.096763 -37.768797) (xy 250.056614 -37.730088) (xy 250.022528 -37.685945)
			(xy 249.995232 -37.63731) (xy 249.975309 -37.585219) (xy 249.963183 -37.530782) (xy 249.959112 -37.47516)
			(xy 246.74644 -37.47516) (xy 246.757098 -37.484876) (xy 246.815632 -37.549083) (xy 246.867992 -37.618416)
			(xy 246.913731 -37.692285) (xy 246.952459 -37.77006) (xy 246.983846 -37.851075) (xy 247.007623 -37.934642)
			(xy 247.023589 -38.020046) (xy 247.031605 -38.106558) (xy 247.031605 -38.193442) (xy 247.023589 -38.279954)
			(xy 247.007623 -38.365358) (xy 246.983846 -38.448924) (xy 246.967483 -38.49116) (xy 249.959112 -38.49116)
			(xy 249.963183 -38.435538) (xy 249.975309 -38.381101) (xy 249.995232 -38.32901) (xy 250.022528 -38.280375)
			(xy 250.056614 -38.236232) (xy 250.096763 -38.197523) (xy 250.142121 -38.165072) (xy 250.191721 -38.139571)
			(xy 250.244505 -38.121564) (xy 250.299348 -38.111434) (xy 250.355082 -38.109397) (xy 250.410519 -38.115497)
			(xy 250.464476 -38.129603) (xy 250.515805 -38.151415) (xy 250.563411 -38.180469) (xy 250.606279 -38.216144)
			(xy 250.643496 -38.257681) (xy 250.674269 -38.304194) (xy 250.679399 -38.315138) (xy 264.61796 -38.315138)
			(xy 264.622031 -38.259516) (xy 264.634157 -38.205079) (xy 264.65408 -38.152988) (xy 264.681376 -38.104353)
			(xy 264.715462 -38.06021) (xy 264.755611 -38.021501) (xy 264.800969 -37.98905) (xy 264.850569 -37.963549)
			(xy 264.903353 -37.945542) (xy 264.958196 -37.935412) (xy 265.01393 -37.933375) (xy 265.069367 -37.939475)
			(xy 265.123324 -37.953581) (xy 265.174653 -37.975393) (xy 265.222259 -38.004447) (xy 265.265127 -38.040122)
			(xy 265.302344 -38.081659) (xy 265.333117 -38.128172) (xy 265.356789 -38.178669) (xy 265.361232 -38.193437)
			(xy 269.298171 -38.193437) (xy 269.298171 -38.106563) (xy 269.306186 -38.020058) (xy 269.32215 -37.934663)
			(xy 269.345924 -37.851104) (xy 269.377307 -37.770096) (xy 269.416031 -37.692329) (xy 269.461765 -37.618467)
			(xy 269.514119 -37.549139) (xy 269.572647 -37.484938) (xy 269.636849 -37.426412) (xy 269.706177 -37.374058)
			(xy 269.78004 -37.328325) (xy 269.857807 -37.289603) (xy 269.938816 -37.258221) (xy 270.022374 -37.234447)
			(xy 270.10777 -37.218485) (xy 270.194275 -37.21047) (xy 270.237712 -37.209984) (xy 270.31569 -37.209984)
			(xy 270.325713 -37.209572) (xy 270.344232 -37.201902) (xy 270.358406 -37.187727) (xy 270.366073 -37.169207)
			(xy 270.36649 -37.159184) (xy 270.36649 -37.151564) (xy 270.362172 -37.137594) (xy 270.358108 -37.131244)
			(xy 270.334668 -37.094792) (xy 270.293672 -37.018429) (xy 270.259684 -36.938701) (xy 270.232976 -36.856247)
			(xy 270.213763 -36.771733) (xy 270.202201 -36.685836) (xy 270.198381 -36.59925) (xy 270.202335 -36.512669)
			(xy 270.214031 -36.426791) (xy 270.233375 -36.342306) (xy 270.260211 -36.259894) (xy 270.294323 -36.180218)
			(xy 270.335437 -36.103919) (xy 270.383223 -36.031611) (xy 270.437295 -35.963876) (xy 270.497218 -35.901258)
			(xy 270.562512 -35.844261) (xy 270.632649 -35.793344) (xy 270.707067 -35.748916) (xy 270.785166 -35.711334)
			(xy 270.866319 -35.680902) (xy 270.949872 -35.657863) (xy 271.035153 -35.642404) (xy 271.121476 -35.634648)
			(xy 271.164812 -35.634168) (xy 271.165066 -35.634168) (xy 271.208398 -35.634594) (xy 271.294713 -35.642372)
			(xy 271.379984 -35.657851) (xy 271.463526 -35.680906) (xy 271.544666 -35.711353) (xy 271.622753 -35.748945)
			(xy 271.697158 -35.793381) (xy 271.767284 -35.844304) (xy 271.804431 -35.876738) (xy 276.917148 -35.876738)
			(xy 276.921219 -35.821116) (xy 276.933345 -35.766679) (xy 276.953268 -35.714588) (xy 276.980564 -35.665953)
			(xy 277.01465 -35.62181) (xy 277.054799 -35.583101) (xy 277.100157 -35.55065) (xy 277.149757 -35.525149)
			(xy 277.202541 -35.507142) (xy 277.257384 -35.497012) (xy 277.313118 -35.494975) (xy 277.368555 -35.501075)
			(xy 277.422512 -35.515181) (xy 277.473841 -35.536993) (xy 277.521447 -35.566047) (xy 277.564315 -35.601722)
			(xy 277.601532 -35.643259) (xy 277.632305 -35.689772) (xy 277.655977 -35.740269) (xy 277.672045 -35.793676)
			(xy 277.680165 -35.848852) (xy 277.680674 -35.876738) (xy 280.988768 -35.876738) (xy 280.992839 -35.821116)
			(xy 281.004965 -35.766679) (xy 281.024888 -35.714588) (xy 281.052184 -35.665953) (xy 281.08627 -35.62181)
			(xy 281.126419 -35.583101) (xy 281.171777 -35.55065) (xy 281.221377 -35.525149) (xy 281.274161 -35.507142)
			(xy 281.329004 -35.497012) (xy 281.384738 -35.494975) (xy 281.440175 -35.501075) (xy 281.494132 -35.515181)
			(xy 281.545461 -35.536993) (xy 281.593067 -35.566047) (xy 281.635935 -35.601722) (xy 281.673152 -35.643259)
			(xy 281.703925 -35.689772) (xy 281.727597 -35.740269) (xy 281.743665 -35.793676) (xy 281.751785 -35.848852)
			(xy 281.752294 -35.876738) (xy 281.751785 -35.904624) (xy 281.743665 -35.9598) (xy 281.727597 -36.013207)
			(xy 281.703925 -36.063704) (xy 281.673152 -36.110217) (xy 281.635935 -36.151754) (xy 281.593067 -36.187429)
			(xy 281.545461 -36.216483) (xy 281.494132 -36.238295) (xy 281.440175 -36.252401) (xy 281.384738 -36.258501)
			(xy 281.329004 -36.256464) (xy 281.274161 -36.246334) (xy 281.221377 -36.228327) (xy 281.171777 -36.202826)
			(xy 281.126419 -36.170375) (xy 281.08627 -36.131666) (xy 281.052184 -36.087523) (xy 281.024888 -36.038888)
			(xy 281.004965 -35.986797) (xy 280.992839 -35.93236) (xy 280.988768 -35.876738) (xy 277.680674 -35.876738)
			(xy 277.680165 -35.904624) (xy 277.672045 -35.9598) (xy 277.655977 -36.013207) (xy 277.632305 -36.063704)
			(xy 277.601532 -36.110217) (xy 277.564315 -36.151754) (xy 277.521447 -36.187429) (xy 277.473841 -36.216483)
			(xy 277.422512 -36.238295) (xy 277.368555 -36.252401) (xy 277.313118 -36.258501) (xy 277.257384 -36.256464)
			(xy 277.202541 -36.246334) (xy 277.149757 -36.228327) (xy 277.100157 -36.202826) (xy 277.054799 -36.170375)
			(xy 277.01465 -36.131666) (xy 276.980564 -36.087523) (xy 276.953268 -36.038888) (xy 276.933345 -35.986797)
			(xy 276.921219 -35.93236) (xy 276.917148 -35.876738) (xy 271.804431 -35.876738) (xy 271.832566 -35.901304)
			(xy 271.89248 -35.963922) (xy 271.946543 -36.031656) (xy 271.994322 -36.103961) (xy 272.035431 -36.180255)
			(xy 272.069541 -36.259925) (xy 272.096377 -36.34233) (xy 272.115723 -36.426807) (xy 272.127054 -36.50996)
			(xy 278.813766 -36.50996) (xy 278.817837 -36.454338) (xy 278.829963 -36.399901) (xy 278.849886 -36.34781)
			(xy 278.877182 -36.299175) (xy 278.911268 -36.255032) (xy 278.951417 -36.216323) (xy 278.996775 -36.183872)
			(xy 279.046375 -36.158371) (xy 279.099159 -36.140364) (xy 279.154002 -36.130234) (xy 279.209736 -36.128197)
			(xy 279.265173 -36.134297) (xy 279.31913 -36.148403) (xy 279.370459 -36.170215) (xy 279.418065 -36.199269)
			(xy 279.460933 -36.234944) (xy 279.49815 -36.276481) (xy 279.528923 -36.322994) (xy 279.552595 -36.373491)
			(xy 279.568663 -36.426898) (xy 279.572588 -36.453572) (xy 282.128466 -36.453572) (xy 282.132537 -36.39795)
			(xy 282.144663 -36.343513) (xy 282.164586 -36.291422) (xy 282.191882 -36.242787) (xy 282.225968 -36.198644)
			(xy 282.266117 -36.159935) (xy 282.311475 -36.127484) (xy 282.361075 -36.101983) (xy 282.413859 -36.083976)
			(xy 282.468702 -36.073846) (xy 282.524436 -36.071809) (xy 282.579873 -36.077909) (xy 282.63383 -36.092015)
			(xy 282.685159 -36.113827) (xy 282.732765 -36.142881) (xy 282.775633 -36.178556) (xy 282.81285 -36.220093)
			(xy 282.843623 -36.266606) (xy 282.867295 -36.317103) (xy 282.883363 -36.37051) (xy 282.891483 -36.425686)
			(xy 282.891992 -36.453572) (xy 282.891483 -36.481458) (xy 282.883363 -36.536634) (xy 282.867295 -36.590041)
			(xy 282.843623 -36.640538) (xy 282.81285 -36.687051) (xy 282.775633 -36.728588) (xy 282.732765 -36.764263)
			(xy 282.685159 -36.793317) (xy 282.63383 -36.815129) (xy 282.579873 -36.829235) (xy 282.524436 -36.835335)
			(xy 282.468702 -36.833298) (xy 282.413859 -36.823168) (xy 282.361075 -36.805161) (xy 282.311475 -36.77966)
			(xy 282.266117 -36.747209) (xy 282.225968 -36.7085) (xy 282.191882 -36.664357) (xy 282.164586 -36.615722)
			(xy 282.144663 -36.563631) (xy 282.132537 -36.509194) (xy 282.128466 -36.453572) (xy 279.572588 -36.453572)
			(xy 279.576783 -36.482074) (xy 279.577292 -36.50996) (xy 279.576783 -36.537846) (xy 279.568663 -36.593022)
			(xy 279.552595 -36.646429) (xy 279.528923 -36.696926) (xy 279.49815 -36.743439) (xy 279.460933 -36.784976)
			(xy 279.418065 -36.820651) (xy 279.370459 -36.849705) (xy 279.31913 -36.871517) (xy 279.265173 -36.885623)
			(xy 279.209736 -36.891723) (xy 279.154002 -36.889686) (xy 279.099159 -36.879556) (xy 279.046375 -36.861549)
			(xy 278.996775 -36.836048) (xy 278.951417 -36.803597) (xy 278.911268 -36.764888) (xy 278.877182 -36.720745)
			(xy 278.849886 -36.67211) (xy 278.829963 -36.620019) (xy 278.817837 -36.565582) (xy 278.813766 -36.50996)
			(xy 272.127054 -36.50996) (xy 272.127424 -36.512678) (xy 272.131385 -36.599252) (xy 272.127575 -36.685833)
			(xy 272.116025 -36.771724) (xy 272.096827 -36.856236) (xy 272.070136 -36.938688) (xy 272.036166 -37.018417)
			(xy 271.995191 -37.094783) (xy 271.97177 -37.131244) (xy 271.967706 -37.137594) (xy 271.963388 -37.151564)
			(xy 271.963388 -37.159184) (xy 271.963832 -37.169203) (xy 271.971495 -37.187717) (xy 271.985659 -37.20189)
			(xy 272.004169 -37.209562) (xy 272.014188 -37.209984) (xy 272.091912 -37.209984) (xy 272.135352 -37.21041)
			(xy 272.22186 -37.218427) (xy 272.307259 -37.234392) (xy 272.390822 -37.258169) (xy 272.471834 -37.289554)
			(xy 272.549604 -37.32828) (xy 272.62347 -37.374017) (xy 272.692801 -37.426373) (xy 272.746317 -37.47516)
			(xy 275.95906 -37.47516) (xy 275.963131 -37.419538) (xy 275.975257 -37.365101) (xy 275.99518 -37.31301)
			(xy 276.022476 -37.264375) (xy 276.056562 -37.220232) (xy 276.096711 -37.181523) (xy 276.142069 -37.149072)
			(xy 276.191669 -37.123571) (xy 276.244453 -37.105564) (xy 276.299296 -37.095434) (xy 276.35503 -37.093397)
			(xy 276.410467 -37.099497) (xy 276.464424 -37.113603) (xy 276.515753 -37.135415) (xy 276.563359 -37.164469)
			(xy 276.606227 -37.200144) (xy 276.607078 -37.201094) (xy 279.91638 -37.201094) (xy 279.920451 -37.145472)
			(xy 279.932577 -37.091035) (xy 279.9525 -37.038944) (xy 279.979796 -36.990309) (xy 280.013882 -36.946166)
			(xy 280.054031 -36.907457) (xy 280.099389 -36.875006) (xy 280.148989 -36.849505) (xy 280.201773 -36.831498)
			(xy 280.256616 -36.821368) (xy 280.31235 -36.819331) (xy 280.367787 -36.825431) (xy 280.421744 -36.839537)
			(xy 280.473073 -36.861349) (xy 280.520679 -36.890403) (xy 280.563547 -36.926078) (xy 280.600764 -36.967615)
			(xy 280.631537 -37.014128) (xy 280.655209 -37.064625) (xy 280.661955 -37.087048) (xy 289.400742 -37.087048)
			(xy 289.401209 -37.060444) (xy 289.408585 -37.007751) (xy 289.423215 -36.956595) (xy 289.444814 -36.90797)
			(xy 289.472963 -36.862819) (xy 289.507116 -36.82202) (xy 289.546608 -36.786364) (xy 289.568382 -36.771072)
			(xy 289.578305 -36.76354) (xy 289.590034 -36.741598) (xy 289.590734 -36.729162) (xy 289.590734 -36.644834)
			(xy 289.590063 -36.632384) (xy 289.578353 -36.610408) (xy 289.568382 -36.602924) (xy 289.546623 -36.587613)
			(xy 289.507142 -36.551951) (xy 289.472997 -36.511151) (xy 289.444849 -36.466003) (xy 289.423245 -36.417384)
			(xy 289.408602 -36.366236) (xy 289.401206 -36.313549) (xy 289.400742 -36.286948) (xy 289.4012 -36.259694)
			(xy 289.408952 -36.20574) (xy 289.424304 -36.153439) (xy 289.446945 -36.103856) (xy 289.476413 -36.058)
			(xy 289.512107 -36.016806) (xy 289.553302 -35.981111) (xy 289.599158 -35.951644) (xy 289.648741 -35.929004)
			(xy 289.701042 -35.913651) (xy 289.754996 -35.9059) (xy 289.78225 -35.90544) (xy 289.786822 -35.90544)
			(xy 289.796031 -35.905164) (xy 289.81335 -35.898926) (xy 289.820604 -35.893248) (xy 289.871404 -35.84956)
			(xy 289.878109 -35.843323) (xy 289.886969 -35.827314) (xy 289.888676 -35.818318) (xy 289.888676 -35.818064)
			(xy 289.893029 -35.791135) (xy 289.908339 -35.738779) (xy 289.93095 -35.689138) (xy 289.960401 -35.643223)
			(xy 289.996091 -35.601971) (xy 290.037292 -35.566223) (xy 290.083165 -35.536708) (xy 290.132775 -35.514027)
			(xy 290.185109 -35.498644) (xy 290.2391 -35.490871) (xy 290.266374 -35.490404) (xy 290.293629 -35.490841)
			(xy 290.347584 -35.498595) (xy 290.399887 -35.51395) (xy 290.449472 -35.536591) (xy 290.49533 -35.56606)
			(xy 290.536527 -35.601754) (xy 290.572225 -35.642949) (xy 290.601696 -35.688805) (xy 290.624341 -35.738388)
			(xy 290.639699 -35.79069) (xy 290.647457 -35.844645) (xy 290.647457 -35.899155) (xy 290.639699 -35.95311)
			(xy 290.624341 -36.005412) (xy 290.601696 -36.054995) (xy 290.572225 -36.100851) (xy 290.536527 -36.142046)
			(xy 290.49533 -36.17774) (xy 290.449472 -36.207209) (xy 290.399887 -36.22985) (xy 290.347584 -36.245205)
			(xy 290.293629 -36.252959) (xy 290.266374 -36.25342) (xy 290.261802 -36.25342) (xy 290.252588 -36.253645)
			(xy 290.235269 -36.259917) (xy 290.22802 -36.265612) (xy 290.17722 -36.3093) (xy 290.170498 -36.315521)
			(xy 290.161647 -36.331541) (xy 290.159948 -36.340542) (xy 290.159948 -36.340796) (xy 290.155752 -36.367)
			(xy 290.141067 -36.417994) (xy 290.119454 -36.46646) (xy 290.09133 -36.511461) (xy 290.087904 -36.515548)
			(xy 291.214046 -36.515548) (xy 291.218117 -36.459926) (xy 291.230243 -36.405489) (xy 291.250166 -36.353398)
			(xy 291.277462 -36.304763) (xy 291.311548 -36.26062) (xy 291.351697 -36.221911) (xy 291.397055 -36.18946)
			(xy 291.446655 -36.163959) (xy 291.499439 -36.145952) (xy 291.554282 -36.135822) (xy 291.610016 -36.133785)
			(xy 291.665453 -36.139885) (xy 291.71941 -36.153991) (xy 291.770739 -36.175803) (xy 291.818345 -36.204857)
			(xy 291.861213 -36.240532) (xy 291.89843 -36.282069) (xy 291.929203 -36.328582) (xy 291.952875 -36.379079)
			(xy 291.968943 -36.432486) (xy 291.977063 -36.487662) (xy 291.977572 -36.515548) (xy 291.977063 -36.543434)
			(xy 291.968943 -36.59861) (xy 291.952875 -36.652017) (xy 291.929203 -36.702514) (xy 291.89843 -36.749027)
			(xy 291.861213 -36.790564) (xy 291.818345 -36.826239) (xy 291.770739 -36.855293) (xy 291.71941 -36.877105)
			(xy 291.665453 -36.891211) (xy 291.610016 -36.897311) (xy 291.554282 -36.895274) (xy 291.499439 -36.885144)
			(xy 291.446655 -36.867137) (xy 291.397055 -36.841636) (xy 291.351697 -36.809185) (xy 291.311548 -36.770476)
			(xy 291.277462 -36.726333) (xy 291.250166 -36.677698) (xy 291.230243 -36.625607) (xy 291.218117 -36.57117)
			(xy 291.214046 -36.515548) (xy 290.087904 -36.515548) (xy 290.057238 -36.552128) (xy 290.017836 -36.587675)
			(xy 289.996118 -36.602924) (xy 289.986196 -36.610457) (xy 289.974467 -36.632399) (xy 289.973766 -36.644834)
			(xy 289.973766 -36.729162) (xy 289.974439 -36.741612) (xy 289.986148 -36.763588) (xy 289.996118 -36.771072)
			(xy 290.017875 -36.786386) (xy 290.057356 -36.822047) (xy 290.091502 -36.862847) (xy 290.11965 -36.907994)
			(xy 290.141254 -36.956612) (xy 290.155897 -37.007761) (xy 290.163293 -37.060447) (xy 290.163758 -37.087048)
			(xy 290.163758 -37.087302) (xy 290.163141 -37.119019) (xy 290.152639 -37.181577) (xy 290.131911 -37.241528)
			(xy 290.117276 -37.269674) (xy 290.111942 -37.27958) (xy 290.110418 -37.301678) (xy 290.142422 -37.384482)
			(xy 290.146918 -37.394567) (xy 290.162704 -37.409971) (xy 290.172902 -37.4142) (xy 290.197435 -37.423265)
			(xy 290.243966 -37.447148) (xy 290.286797 -37.477164) (xy 290.325126 -37.512751) (xy 290.358234 -37.55324)
			(xy 290.385499 -37.597872) (xy 290.406412 -37.645811) (xy 290.42058 -37.696157) (xy 290.427736 -37.747967)
			(xy 290.428172 -37.774118) (xy 290.427686 -37.801369) (xy 290.41993 -37.855317) (xy 290.404575 -37.907612)
			(xy 290.381933 -37.957189) (xy 290.352467 -38.003039) (xy 290.316776 -38.04423) (xy 290.275585 -38.079921)
			(xy 290.229735 -38.109387) (xy 290.180158 -38.132029) (xy 290.127863 -38.147384) (xy 290.073915 -38.15514)
			(xy 290.019413 -38.15514) (xy 289.965465 -38.147384) (xy 289.91317 -38.132029) (xy 289.863593 -38.109387)
			(xy 289.817743 -38.079921) (xy 289.776552 -38.04423) (xy 289.740861 -38.003039) (xy 289.711395 -37.957189)
			(xy 289.688753 -37.907612) (xy 289.673398 -37.855317) (xy 289.665642 -37.801369) (xy 289.665156 -37.774118)
			(xy 289.665156 -37.773864) (xy 289.665758 -37.742146) (xy 289.676266 -37.679588) (xy 289.697 -37.619637)
			(xy 289.711638 -37.591492) (xy 289.716972 -37.581586) (xy 289.718496 -37.559488) (xy 289.686492 -37.476684)
			(xy 289.682045 -37.466572) (xy 289.666225 -37.451181) (xy 289.656012 -37.446966) (xy 289.63147 -37.437922)
			(xy 289.584938 -37.414037) (xy 289.542106 -37.384019) (xy 289.503777 -37.348431) (xy 289.470669 -37.307939)
			(xy 289.443404 -37.263304) (xy 289.422493 -37.215362) (xy 289.408329 -37.165012) (xy 289.401176 -37.1132)
			(xy 289.400742 -37.087048) (xy 280.661955 -37.087048) (xy 280.671277 -37.118032) (xy 280.679397 -37.173208)
			(xy 280.679906 -37.201094) (xy 280.679397 -37.22898) (xy 280.671277 -37.284156) (xy 280.655209 -37.337563)
			(xy 280.631537 -37.38806) (xy 280.600764 -37.434573) (xy 280.563547 -37.47611) (xy 280.520679 -37.511785)
			(xy 280.473073 -37.540839) (xy 280.421744 -37.562651) (xy 280.367787 -37.576757) (xy 280.31235 -37.582857)
			(xy 280.256616 -37.58082) (xy 280.201773 -37.57069) (xy 280.148989 -37.552683) (xy 280.099389 -37.527182)
			(xy 280.054031 -37.494731) (xy 280.013882 -37.456022) (xy 279.979796 -37.411879) (xy 279.9525 -37.363244)
			(xy 279.932577 -37.311153) (xy 279.920451 -37.256716) (xy 279.91638 -37.201094) (xy 276.607078 -37.201094)
			(xy 276.643444 -37.241681) (xy 276.674217 -37.288194) (xy 276.697889 -37.338691) (xy 276.713957 -37.392098)
			(xy 276.722077 -37.447274) (xy 276.722586 -37.47516) (xy 276.722077 -37.503046) (xy 276.713957 -37.558222)
			(xy 276.697889 -37.611629) (xy 276.674217 -37.662126) (xy 276.674064 -37.662358) (xy 278.148286 -37.662358)
			(xy 278.152357 -37.606736) (xy 278.164483 -37.552299) (xy 278.184406 -37.500208) (xy 278.211702 -37.451573)
			(xy 278.245788 -37.40743) (xy 278.285937 -37.368721) (xy 278.331295 -37.33627) (xy 278.380895 -37.310769)
			(xy 278.433679 -37.292762) (xy 278.488522 -37.282632) (xy 278.544256 -37.280595) (xy 278.599693 -37.286695)
			(xy 278.65365 -37.300801) (xy 278.704979 -37.322613) (xy 278.752585 -37.351667) (xy 278.795453 -37.387342)
			(xy 278.83267 -37.428879) (xy 278.863443 -37.475392) (xy 278.887115 -37.525889) (xy 278.903183 -37.579296)
			(xy 278.911303 -37.634472) (xy 278.911812 -37.662358) (xy 278.911303 -37.690244) (xy 278.903183 -37.74542)
			(xy 278.887115 -37.798827) (xy 278.863443 -37.849324) (xy 278.83267 -37.895837) (xy 278.795453 -37.937374)
			(xy 278.752585 -37.973049) (xy 278.704979 -38.002103) (xy 278.65365 -38.023915) (xy 278.599693 -38.038021)
			(xy 278.544256 -38.044121) (xy 278.488522 -38.042084) (xy 278.433679 -38.031954) (xy 278.380895 -38.013947)
			(xy 278.331295 -37.988446) (xy 278.285937 -37.955995) (xy 278.245788 -37.917286) (xy 278.211702 -37.873143)
			(xy 278.184406 -37.824508) (xy 278.164483 -37.772417) (xy 278.152357 -37.71798) (xy 278.148286 -37.662358)
			(xy 276.674064 -37.662358) (xy 276.643444 -37.708639) (xy 276.606227 -37.750176) (xy 276.563359 -37.785851)
			(xy 276.515753 -37.814905) (xy 276.464424 -37.836717) (xy 276.410467 -37.850823) (xy 276.35503 -37.856923)
			(xy 276.299296 -37.854886) (xy 276.244453 -37.844756) (xy 276.191669 -37.826749) (xy 276.142069 -37.801248)
			(xy 276.096711 -37.768797) (xy 276.056562 -37.730088) (xy 276.022476 -37.685945) (xy 275.99518 -37.63731)
			(xy 275.975257 -37.585219) (xy 275.963131 -37.530782) (xy 275.95906 -37.47516) (xy 272.746317 -37.47516)
			(xy 272.757005 -37.484904) (xy 272.815534 -37.549109) (xy 272.86789 -37.61844) (xy 272.913626 -37.692306)
			(xy 272.952351 -37.770077) (xy 272.983735 -37.85109) (xy 273.00751 -37.934652) (xy 273.023474 -38.020052)
			(xy 273.03149 -38.10656) (xy 273.03149 -38.19344) (xy 273.023474 -38.279948) (xy 273.00751 -38.365348)
			(xy 272.983735 -38.44891) (xy 272.967368 -38.49116) (xy 275.95906 -38.49116) (xy 275.963131 -38.435538)
			(xy 275.975257 -38.381101) (xy 275.99518 -38.32901) (xy 276.022476 -38.280375) (xy 276.056562 -38.236232)
			(xy 276.096711 -38.197523) (xy 276.142069 -38.165072) (xy 276.191669 -38.139571) (xy 276.244453 -38.121564)
			(xy 276.299296 -38.111434) (xy 276.35503 -38.109397) (xy 276.410467 -38.115497) (xy 276.464424 -38.129603)
			(xy 276.515753 -38.151415) (xy 276.563359 -38.180469) (xy 276.606227 -38.216144) (xy 276.643444 -38.257681)
			(xy 276.674217 -38.304194) (xy 276.679347 -38.315138) (xy 290.617908 -38.315138) (xy 290.621979 -38.259516)
			(xy 290.634105 -38.205079) (xy 290.654028 -38.152988) (xy 290.681324 -38.104353) (xy 290.71541 -38.06021)
			(xy 290.755559 -38.021501) (xy 290.800917 -37.98905) (xy 290.850517 -37.963549) (xy 290.903301 -37.945542)
			(xy 290.958144 -37.935412) (xy 291.013878 -37.933375) (xy 291.069315 -37.939475) (xy 291.123272 -37.953581)
			(xy 291.174601 -37.975393) (xy 291.222207 -38.004447) (xy 291.265075 -38.040122) (xy 291.302292 -38.081659)
			(xy 291.333065 -38.128172) (xy 291.356737 -38.178669) (xy 291.361179 -38.193435) (xy 295.298186 -38.193435)
			(xy 295.298186 -38.106565) (xy 295.306201 -38.020065) (xy 295.322163 -37.934674) (xy 295.345935 -37.851119)
			(xy 295.377316 -37.770115) (xy 295.416036 -37.692351) (xy 295.461766 -37.618492) (xy 295.514116 -37.549167)
			(xy 295.572639 -37.484967) (xy 295.636836 -37.426442) (xy 295.706159 -37.374089) (xy 295.780016 -37.328356)
			(xy 295.857778 -37.289632) (xy 295.938781 -37.258248) (xy 296.022335 -37.234472) (xy 296.107725 -37.218506)
			(xy 296.194225 -37.210487) (xy 296.23766 -37.209984) (xy 296.315638 -37.209984) (xy 296.32565 -37.209543)
			(xy 296.344146 -37.201868) (xy 296.358298 -37.1877) (xy 296.365953 -37.169197) (xy 296.366438 -37.159184)
			(xy 296.366438 -37.151564) (xy 296.36212 -37.137594) (xy 296.358056 -37.131244) (xy 296.334654 -37.094769)
			(xy 296.293662 -37.018408) (xy 296.259677 -36.938682) (xy 296.232972 -36.856231) (xy 296.213761 -36.771719)
			(xy 296.2022 -36.685826) (xy 296.198381 -36.599243) (xy 296.202336 -36.512665) (xy 296.214031 -36.42679)
			(xy 296.233374 -36.342309) (xy 296.260209 -36.2599) (xy 296.294319 -36.180227) (xy 296.335431 -36.103931)
			(xy 296.383213 -36.031625) (xy 296.437281 -35.963891) (xy 296.497201 -35.901274) (xy 296.562491 -35.844278)
			(xy 296.632624 -35.79336) (xy 296.707038 -35.748932) (xy 296.785133 -35.711349) (xy 296.866281 -35.680914)
			(xy 296.949829 -35.657873) (xy 297.035107 -35.64241) (xy 297.121426 -35.63465) (xy 297.16476 -35.634168)
			(xy 297.165014 -35.634168) (xy 297.208346 -35.634635) (xy 297.294661 -35.642409) (xy 297.379932 -35.657884)
			(xy 297.463474 -35.680935) (xy 297.544615 -35.711378) (xy 297.622703 -35.748967) (xy 297.697109 -35.793401)
			(xy 297.767236 -35.844321) (xy 297.804365 -35.876738) (xy 302.917096 -35.876738) (xy 302.921167 -35.821116)
			(xy 302.933293 -35.766679) (xy 302.953216 -35.714588) (xy 302.980512 -35.665953) (xy 303.014598 -35.62181)
			(xy 303.054747 -35.583101) (xy 303.100105 -35.55065) (xy 303.149705 -35.525149) (xy 303.202489 -35.507142)
			(xy 303.257332 -35.497012) (xy 303.313066 -35.494975) (xy 303.368503 -35.501075) (xy 303.42246 -35.515181)
			(xy 303.473789 -35.536993) (xy 303.521395 -35.566047) (xy 303.564263 -35.601722) (xy 303.60148 -35.643259)
			(xy 303.632253 -35.689772) (xy 303.655925 -35.740269) (xy 303.671993 -35.793676) (xy 303.680113 -35.848852)
			(xy 303.680622 -35.876738) (xy 306.988716 -35.876738) (xy 306.992787 -35.821116) (xy 307.004913 -35.766679)
			(xy 307.024836 -35.714588) (xy 307.052132 -35.665953) (xy 307.086218 -35.62181) (xy 307.126367 -35.583101)
			(xy 307.171725 -35.55065) (xy 307.221325 -35.525149) (xy 307.274109 -35.507142) (xy 307.328952 -35.497012)
			(xy 307.384686 -35.494975) (xy 307.440123 -35.501075) (xy 307.49408 -35.515181) (xy 307.545409 -35.536993)
			(xy 307.593015 -35.566047) (xy 307.635883 -35.601722) (xy 307.6731 -35.643259) (xy 307.703873 -35.689772)
			(xy 307.727545 -35.740269) (xy 307.743613 -35.793676) (xy 307.751733 -35.848852) (xy 307.752242 -35.876738)
			(xy 307.751733 -35.904624) (xy 307.743613 -35.9598) (xy 307.727545 -36.013207) (xy 307.703873 -36.063704)
			(xy 307.6731 -36.110217) (xy 307.635883 -36.151754) (xy 307.593015 -36.187429) (xy 307.545409 -36.216483)
			(xy 307.49408 -36.238295) (xy 307.440123 -36.252401) (xy 307.384686 -36.258501) (xy 307.328952 -36.256464)
			(xy 307.274109 -36.246334) (xy 307.221325 -36.228327) (xy 307.171725 -36.202826) (xy 307.126367 -36.170375)
			(xy 307.086218 -36.131666) (xy 307.052132 -36.087523) (xy 307.024836 -36.038888) (xy 307.004913 -35.986797)
			(xy 306.992787 -35.93236) (xy 306.988716 -35.876738) (xy 303.680622 -35.876738) (xy 303.680113 -35.904624)
			(xy 303.671993 -35.9598) (xy 303.655925 -36.013207) (xy 303.632253 -36.063704) (xy 303.60148 -36.110217)
			(xy 303.564263 -36.151754) (xy 303.521395 -36.187429) (xy 303.473789 -36.216483) (xy 303.42246 -36.238295)
			(xy 303.368503 -36.252401) (xy 303.313066 -36.258501) (xy 303.257332 -36.256464) (xy 303.202489 -36.246334)
			(xy 303.149705 -36.228327) (xy 303.100105 -36.202826) (xy 303.054747 -36.170375) (xy 303.014598 -36.131666)
			(xy 302.980512 -36.087523) (xy 302.953216 -36.038888) (xy 302.933293 -35.986797) (xy 302.921167 -35.93236)
			(xy 302.917096 -35.876738) (xy 297.804365 -35.876738) (xy 297.832519 -35.901319) (xy 297.892434 -35.963936)
			(xy 297.946498 -36.031668) (xy 297.994278 -36.103972) (xy 298.035388 -36.180265) (xy 298.069498 -36.259934)
			(xy 298.096334 -36.342338) (xy 298.11568 -36.426815) (xy 298.12701 -36.50996) (xy 304.813714 -36.50996)
			(xy 304.817785 -36.454338) (xy 304.829911 -36.399901) (xy 304.849834 -36.34781) (xy 304.87713 -36.299175)
			(xy 304.911216 -36.255032) (xy 304.951365 -36.216323) (xy 304.996723 -36.183872) (xy 305.046323 -36.158371)
			(xy 305.099107 -36.140364) (xy 305.15395 -36.130234) (xy 305.209684 -36.128197) (xy 305.265121 -36.134297)
			(xy 305.319078 -36.148403) (xy 305.370407 -36.170215) (xy 305.418013 -36.199269) (xy 305.460881 -36.234944)
			(xy 305.498098 -36.276481) (xy 305.528871 -36.322994) (xy 305.552543 -36.373491) (xy 305.568611 -36.426898)
			(xy 305.572536 -36.453572) (xy 308.128414 -36.453572) (xy 308.132485 -36.39795) (xy 308.144611 -36.343513)
			(xy 308.164534 -36.291422) (xy 308.19183 -36.242787) (xy 308.225916 -36.198644) (xy 308.266065 -36.159935)
			(xy 308.311423 -36.127484) (xy 308.361023 -36.101983) (xy 308.413807 -36.083976) (xy 308.46865 -36.073846)
			(xy 308.524384 -36.071809) (xy 308.579821 -36.077909) (xy 308.633778 -36.092015) (xy 308.685107 -36.113827)
			(xy 308.732713 -36.142881) (xy 308.775581 -36.178556) (xy 308.812798 -36.220093) (xy 308.843571 -36.266606)
			(xy 308.867243 -36.317103) (xy 308.883311 -36.37051) (xy 308.891431 -36.425686) (xy 308.89194 -36.453572)
			(xy 308.891431 -36.481458) (xy 308.883311 -36.536634) (xy 308.867243 -36.590041) (xy 308.843571 -36.640538)
			(xy 308.812798 -36.687051) (xy 308.775581 -36.728588) (xy 308.732713 -36.764263) (xy 308.685107 -36.793317)
			(xy 308.633778 -36.815129) (xy 308.579821 -36.829235) (xy 308.524384 -36.835335) (xy 308.46865 -36.833298)
			(xy 308.413807 -36.823168) (xy 308.361023 -36.805161) (xy 308.311423 -36.77966) (xy 308.266065 -36.747209)
			(xy 308.225916 -36.7085) (xy 308.19183 -36.664357) (xy 308.164534 -36.615722) (xy 308.144611 -36.563631)
			(xy 308.132485 -36.509194) (xy 308.128414 -36.453572) (xy 305.572536 -36.453572) (xy 305.576731 -36.482074)
			(xy 305.57724 -36.50996) (xy 305.576731 -36.537846) (xy 305.568611 -36.593022) (xy 305.552543 -36.646429)
			(xy 305.528871 -36.696926) (xy 305.498098 -36.743439) (xy 305.460881 -36.784976) (xy 305.418013 -36.820651)
			(xy 305.370407 -36.849705) (xy 305.319078 -36.871517) (xy 305.265121 -36.885623) (xy 305.209684 -36.891723)
			(xy 305.15395 -36.889686) (xy 305.099107 -36.879556) (xy 305.046323 -36.861549) (xy 304.996723 -36.836048)
			(xy 304.951365 -36.803597) (xy 304.911216 -36.764888) (xy 304.87713 -36.720745) (xy 304.849834 -36.67211)
			(xy 304.829911 -36.620019) (xy 304.817785 -36.565582) (xy 304.813714 -36.50996) (xy 298.12701 -36.50996)
			(xy 298.127381 -36.512686) (xy 298.131342 -36.599259) (xy 298.127531 -36.685839) (xy 298.11598 -36.77173)
			(xy 298.096781 -36.856241) (xy 298.070088 -36.938692) (xy 298.036117 -37.01842) (xy 297.99514 -37.094784)
			(xy 297.971718 -37.131244) (xy 297.967654 -37.137594) (xy 297.963336 -37.151564) (xy 297.963336 -37.159184)
			(xy 297.963733 -37.169209) (xy 297.971405 -37.187732) (xy 297.985585 -37.201906) (xy 298.004111 -37.209571)
			(xy 298.014136 -37.209984) (xy 298.09186 -37.209984) (xy 298.135302 -37.210393) (xy 298.221815 -37.218406)
			(xy 298.30722 -37.234368) (xy 298.390787 -37.258141) (xy 298.471805 -37.289525) (xy 298.549581 -37.32825)
			(xy 298.623452 -37.373986) (xy 298.692788 -37.426343) (xy 298.74634 -37.47516) (xy 301.959008 -37.47516)
			(xy 301.963079 -37.419538) (xy 301.975205 -37.365101) (xy 301.995128 -37.31301) (xy 302.022424 -37.264375)
			(xy 302.05651 -37.220232) (xy 302.096659 -37.181523) (xy 302.142017 -37.149072) (xy 302.191617 -37.123571)
			(xy 302.244401 -37.105564) (xy 302.299244 -37.095434) (xy 302.354978 -37.093397) (xy 302.410415 -37.099497)
			(xy 302.464372 -37.113603) (xy 302.515701 -37.135415) (xy 302.563307 -37.164469) (xy 302.606175 -37.200144)
			(xy 302.607026 -37.201094) (xy 305.916328 -37.201094) (xy 305.920399 -37.145472) (xy 305.932525 -37.091035)
			(xy 305.952448 -37.038944) (xy 305.979744 -36.990309) (xy 306.01383 -36.946166) (xy 306.053979 -36.907457)
			(xy 306.099337 -36.875006) (xy 306.148937 -36.849505) (xy 306.201721 -36.831498) (xy 306.256564 -36.821368)
			(xy 306.312298 -36.819331) (xy 306.367735 -36.825431) (xy 306.421692 -36.839537) (xy 306.473021 -36.861349)
			(xy 306.520627 -36.890403) (xy 306.563495 -36.926078) (xy 306.600712 -36.967615) (xy 306.631485 -37.014128)
			(xy 306.655157 -37.064625) (xy 306.661903 -37.087048) (xy 315.40069 -37.087048) (xy 315.40118 -37.060445)
			(xy 315.408555 -37.007754) (xy 315.423182 -36.9566) (xy 315.444778 -36.907975) (xy 315.472923 -36.862824)
			(xy 315.507071 -36.822024) (xy 315.546559 -36.786366) (xy 315.56833 -36.771072) (xy 315.578262 -36.763551)
			(xy 315.589984 -36.7416) (xy 315.590682 -36.729162) (xy 315.590682 -36.644834) (xy 315.590032 -36.632381)
			(xy 315.578309 -36.610403) (xy 315.56833 -36.602924) (xy 315.54656 -36.587629) (xy 315.507081 -36.551962)
			(xy 315.472938 -36.511159) (xy 315.444793 -36.466009) (xy 315.42319 -36.417388) (xy 315.40855 -36.366238)
			(xy 315.401154 -36.31355) (xy 315.40069 -36.286948) (xy 315.4012 -36.259696) (xy 315.40895 -36.205747)
			(xy 315.4243 -36.15345) (xy 315.446937 -36.103871) (xy 315.4764 -36.058017) (xy 315.512089 -36.016824)
			(xy 315.553277 -35.98113) (xy 315.599127 -35.951661) (xy 315.648703 -35.929018) (xy 315.700998 -35.913661)
			(xy 315.754946 -35.905904) (xy 315.782198 -35.90544) (xy 315.78677 -35.90544) (xy 315.795981 -35.905188)
			(xy 315.8133 -35.898934) (xy 315.820552 -35.893248) (xy 315.871352 -35.84956) (xy 315.878064 -35.84333)
			(xy 315.886919 -35.827316) (xy 315.888624 -35.818318) (xy 315.888624 -35.818064) (xy 315.892931 -35.791126)
			(xy 315.908244 -35.738767) (xy 315.930858 -35.689123) (xy 315.960313 -35.643206) (xy 315.996009 -35.601953)
			(xy 316.037216 -35.566206) (xy 316.083095 -35.536692) (xy 316.13271 -35.514014) (xy 316.185049 -35.498635)
			(xy 316.239046 -35.490867) (xy 316.266322 -35.490404) (xy 316.293573 -35.490867) (xy 316.34752 -35.498627)
			(xy 316.399814 -35.513984) (xy 316.44939 -35.536627) (xy 316.495239 -35.566095) (xy 316.536428 -35.601788)
			(xy 316.572118 -35.642979) (xy 316.601583 -35.688829) (xy 316.624224 -35.738407) (xy 316.639578 -35.790701)
			(xy 316.647334 -35.844649) (xy 316.647334 -35.899151) (xy 316.639578 -35.953099) (xy 316.624224 -36.005393)
			(xy 316.601583 -36.054971) (xy 316.572118 -36.100821) (xy 316.536428 -36.142012) (xy 316.495239 -36.177705)
			(xy 316.44939 -36.207173) (xy 316.399814 -36.229816) (xy 316.34752 -36.245173) (xy 316.293573 -36.252933)
			(xy 316.266322 -36.25342) (xy 316.26175 -36.25342) (xy 316.252538 -36.253668) (xy 316.235219 -36.259924)
			(xy 316.227968 -36.265612) (xy 316.177168 -36.3093) (xy 316.170437 -36.315513) (xy 316.161593 -36.33154)
			(xy 316.159896 -36.340542) (xy 316.159896 -36.340796) (xy 316.15568 -36.366996) (xy 316.140998 -36.417989)
			(xy 316.119388 -36.466454) (xy 316.091267 -36.511456) (xy 316.087837 -36.515548) (xy 317.213994 -36.515548)
			(xy 317.218065 -36.459926) (xy 317.230191 -36.405489) (xy 317.250114 -36.353398) (xy 317.27741 -36.304763)
			(xy 317.311496 -36.26062) (xy 317.351645 -36.221911) (xy 317.397003 -36.18946) (xy 317.446603 -36.163959)
			(xy 317.499387 -36.145952) (xy 317.55423 -36.135822) (xy 317.609964 -36.133785) (xy 317.665401 -36.139885)
			(xy 317.719358 -36.153991) (xy 317.770687 -36.175803) (xy 317.818293 -36.204857) (xy 317.861161 -36.240532)
			(xy 317.898378 -36.282069) (xy 317.929151 -36.328582) (xy 317.952823 -36.379079) (xy 317.968891 -36.432486)
			(xy 317.977011 -36.487662) (xy 317.97752 -36.515548) (xy 317.977011 -36.543434) (xy 317.968891 -36.59861)
			(xy 317.952823 -36.652017) (xy 317.929151 -36.702514) (xy 317.898378 -36.749027) (xy 317.861161 -36.790564)
			(xy 317.818293 -36.826239) (xy 317.770687 -36.855293) (xy 317.719358 -36.877105) (xy 317.665401 -36.891211)
			(xy 317.609964 -36.897311) (xy 317.55423 -36.895274) (xy 317.499387 -36.885144) (xy 317.446603 -36.867137)
			(xy 317.397003 -36.841636) (xy 317.351645 -36.809185) (xy 317.311496 -36.770476) (xy 317.27741 -36.726333)
			(xy 317.250114 -36.677698) (xy 317.230191 -36.625607) (xy 317.218065 -36.57117) (xy 317.213994 -36.515548)
			(xy 316.087837 -36.515548) (xy 316.057179 -36.552124) (xy 316.017782 -36.587673) (xy 315.996066 -36.602924)
			(xy 315.986135 -36.610447) (xy 315.974413 -36.632397) (xy 315.973714 -36.644834) (xy 315.973714 -36.729162)
			(xy 315.974368 -36.741615) (xy 315.986088 -36.763592) (xy 315.996066 -36.771072) (xy 316.017833 -36.786371)
			(xy 316.057312 -36.822037) (xy 316.091456 -36.86284) (xy 316.119601 -36.907989) (xy 316.141204 -36.956609)
			(xy 316.155845 -37.007759) (xy 316.163241 -37.060446) (xy 316.163706 -37.087048) (xy 316.163706 -37.087302)
			(xy 316.163083 -37.119019) (xy 316.152583 -37.181576) (xy 316.131857 -37.241528) (xy 316.117224 -37.269674)
			(xy 316.11189 -37.27958) (xy 316.110366 -37.301678) (xy 316.14237 -37.384482) (xy 316.146845 -37.394578)
			(xy 316.162645 -37.409977) (xy 316.17285 -37.4142) (xy 316.197372 -37.423295) (xy 316.243904 -37.447172)
			(xy 316.286736 -37.477183) (xy 316.325067 -37.512765) (xy 316.358176 -37.55325) (xy 316.385444 -37.597879)
			(xy 316.406358 -37.645816) (xy 316.420527 -37.69616) (xy 316.427683 -37.747968) (xy 316.42812 -37.774118)
			(xy 316.427634 -37.801369) (xy 316.419878 -37.855317) (xy 316.404523 -37.907612) (xy 316.381881 -37.957189)
			(xy 316.352415 -38.003039) (xy 316.316724 -38.04423) (xy 316.275533 -38.079921) (xy 316.229683 -38.109387)
			(xy 316.180106 -38.132029) (xy 316.127811 -38.147384) (xy 316.073863 -38.15514) (xy 316.019361 -38.15514)
			(xy 315.965413 -38.147384) (xy 315.913118 -38.132029) (xy 315.863541 -38.109387) (xy 315.817691 -38.079921)
			(xy 315.7765 -38.04423) (xy 315.740809 -38.003039) (xy 315.711343 -37.957189) (xy 315.688701 -37.907612)
			(xy 315.673346 -37.855317) (xy 315.66559 -37.801369) (xy 315.665104 -37.774118) (xy 315.665104 -37.773864)
			(xy 315.665712 -37.742147) (xy 315.676218 -37.679588) (xy 315.69695 -37.619638) (xy 315.711586 -37.591492)
			(xy 315.71692 -37.581586) (xy 315.718444 -37.559488) (xy 315.68644 -37.476684) (xy 315.681973 -37.466584)
			(xy 315.666167 -37.451188) (xy 315.65596 -37.446966) (xy 315.631407 -37.437952) (xy 315.584876 -37.414061)
			(xy 315.542045 -37.384038) (xy 315.503718 -37.348445) (xy 315.470612 -37.307949) (xy 315.443349 -37.263311)
			(xy 315.422439 -37.215366) (xy 315.408276 -37.165015) (xy 315.401124 -37.113201) (xy 315.40069 -37.087048)
			(xy 306.661903 -37.087048) (xy 306.671225 -37.118032) (xy 306.679345 -37.173208) (xy 306.679854 -37.201094)
			(xy 306.679345 -37.22898) (xy 306.671225 -37.284156) (xy 306.655157 -37.337563) (xy 306.631485 -37.38806)
			(xy 306.600712 -37.434573) (xy 306.563495 -37.47611) (xy 306.520627 -37.511785) (xy 306.473021 -37.540839)
			(xy 306.421692 -37.562651) (xy 306.367735 -37.576757) (xy 306.312298 -37.582857) (xy 306.256564 -37.58082)
			(xy 306.201721 -37.57069) (xy 306.148937 -37.552683) (xy 306.099337 -37.527182) (xy 306.053979 -37.494731)
			(xy 306.01383 -37.456022) (xy 305.979744 -37.411879) (xy 305.952448 -37.363244) (xy 305.932525 -37.311153)
			(xy 305.920399 -37.256716) (xy 305.916328 -37.201094) (xy 302.607026 -37.201094) (xy 302.643392 -37.241681)
			(xy 302.674165 -37.288194) (xy 302.697837 -37.338691) (xy 302.713905 -37.392098) (xy 302.722025 -37.447274)
			(xy 302.722534 -37.47516) (xy 302.722025 -37.503046) (xy 302.713905 -37.558222) (xy 302.697837 -37.611629)
			(xy 302.674165 -37.662126) (xy 302.674012 -37.662358) (xy 304.148234 -37.662358) (xy 304.152305 -37.606736)
			(xy 304.164431 -37.552299) (xy 304.184354 -37.500208) (xy 304.21165 -37.451573) (xy 304.245736 -37.40743)
			(xy 304.285885 -37.368721) (xy 304.331243 -37.33627) (xy 304.380843 -37.310769) (xy 304.433627 -37.292762)
			(xy 304.48847 -37.282632) (xy 304.544204 -37.280595) (xy 304.599641 -37.286695) (xy 304.653598 -37.300801)
			(xy 304.704927 -37.322613) (xy 304.752533 -37.351667) (xy 304.795401 -37.387342) (xy 304.832618 -37.428879)
			(xy 304.863391 -37.475392) (xy 304.887063 -37.525889) (xy 304.903131 -37.579296) (xy 304.911251 -37.634472)
			(xy 304.91176 -37.662358) (xy 304.911251 -37.690244) (xy 304.903131 -37.74542) (xy 304.887063 -37.798827)
			(xy 304.863391 -37.849324) (xy 304.832618 -37.895837) (xy 304.795401 -37.937374) (xy 304.752533 -37.973049)
			(xy 304.704927 -38.002103) (xy 304.653598 -38.023915) (xy 304.599641 -38.038021) (xy 304.544204 -38.044121)
			(xy 304.48847 -38.042084) (xy 304.433627 -38.031954) (xy 304.380843 -38.013947) (xy 304.331243 -37.988446)
			(xy 304.285885 -37.955995) (xy 304.245736 -37.917286) (xy 304.21165 -37.873143) (xy 304.184354 -37.824508)
			(xy 304.164431 -37.772417) (xy 304.152305 -37.71798) (xy 304.148234 -37.662358) (xy 302.674012 -37.662358)
			(xy 302.643392 -37.708639) (xy 302.606175 -37.750176) (xy 302.563307 -37.785851) (xy 302.515701 -37.814905)
			(xy 302.464372 -37.836717) (xy 302.410415 -37.850823) (xy 302.354978 -37.856923) (xy 302.299244 -37.854886)
			(xy 302.244401 -37.844756) (xy 302.191617 -37.826749) (xy 302.142017 -37.801248) (xy 302.096659 -37.768797)
			(xy 302.05651 -37.730088) (xy 302.022424 -37.685945) (xy 301.995128 -37.63731) (xy 301.975205 -37.585219)
			(xy 301.963079 -37.530782) (xy 301.959008 -37.47516) (xy 298.74634 -37.47516) (xy 298.756997 -37.484875)
			(xy 298.815531 -37.549081) (xy 298.867891 -37.618415) (xy 298.913631 -37.692284) (xy 298.952359 -37.770059)
			(xy 298.983746 -37.851075) (xy 299.007523 -37.934641) (xy 299.023488 -38.020045) (xy 299.031505 -38.106558)
			(xy 299.031505 -38.193442) (xy 299.023488 -38.279955) (xy 299.007523 -38.365359) (xy 298.983746 -38.448925)
			(xy 298.967383 -38.49116) (xy 301.959008 -38.49116) (xy 301.963079 -38.435538) (xy 301.975205 -38.381101)
			(xy 301.995128 -38.32901) (xy 302.022424 -38.280375) (xy 302.05651 -38.236232) (xy 302.096659 -38.197523)
			(xy 302.142017 -38.165072) (xy 302.191617 -38.139571) (xy 302.244401 -38.121564) (xy 302.299244 -38.111434)
			(xy 302.354978 -38.109397) (xy 302.410415 -38.115497) (xy 302.464372 -38.129603) (xy 302.515701 -38.151415)
			(xy 302.563307 -38.180469) (xy 302.606175 -38.216144) (xy 302.643392 -38.257681) (xy 302.674165 -38.304194)
			(xy 302.679295 -38.315138) (xy 316.617856 -38.315138) (xy 316.621927 -38.259516) (xy 316.634053 -38.205079)
			(xy 316.653976 -38.152988) (xy 316.681272 -38.104353) (xy 316.715358 -38.06021) (xy 316.755507 -38.021501)
			(xy 316.800865 -37.98905) (xy 316.850465 -37.963549) (xy 316.903249 -37.945542) (xy 316.958092 -37.935412)
			(xy 317.013826 -37.933375) (xy 317.069263 -37.939475) (xy 317.12322 -37.953581) (xy 317.174549 -37.975393)
			(xy 317.222155 -38.004447) (xy 317.265023 -38.040122) (xy 317.30224 -38.081659) (xy 317.333013 -38.128172)
			(xy 317.356685 -38.178669) (xy 317.361128 -38.193437) (xy 321.298071 -38.193437) (xy 321.298071 -38.106563)
			(xy 321.306086 -38.020059) (xy 321.32205 -37.934663) (xy 321.345824 -37.851105) (xy 321.377207 -37.770097)
			(xy 321.415931 -37.69233) (xy 321.461664 -37.618468) (xy 321.514018 -37.549141) (xy 321.572546 -37.48494)
			(xy 321.636747 -37.426413) (xy 321.706075 -37.37406) (xy 321.779937 -37.328327) (xy 321.857704 -37.289604)
			(xy 321.938713 -37.258222) (xy 322.022271 -37.234448) (xy 322.107667 -37.218485) (xy 322.194171 -37.21047)
			(xy 322.237608 -37.209984) (xy 322.315586 -37.209984) (xy 322.325608 -37.209569) (xy 322.344128 -37.2019)
			(xy 322.358302 -37.187726) (xy 322.365969 -37.169206) (xy 322.366386 -37.159184) (xy 322.366386 -37.151564)
			(xy 322.362068 -37.137594) (xy 322.358004 -37.131244) (xy 322.334085 -37.094009) (xy 322.292384 -37.015944)
			(xy 322.257999 -36.93439) (xy 322.231221 -36.850033) (xy 322.212272 -36.76358) (xy 322.201312 -36.675755)
			(xy 322.198434 -36.587297) (xy 322.203661 -36.498946) (xy 322.216949 -36.411443) (xy 322.238187 -36.325524)
			(xy 322.267196 -36.241908) (xy 322.303734 -36.161296) (xy 322.347495 -36.084366) (xy 322.398109 -36.011762)
			(xy 322.455155 -35.944093) (xy 322.518152 -35.881927) (xy 322.586572 -35.825786) (xy 322.659842 -35.776139)
			(xy 322.737347 -35.733405) (xy 322.818436 -35.69794) (xy 322.90243 -35.670044) (xy 322.988624 -35.649948)
			(xy 323.076295 -35.637824) (xy 323.164708 -35.633771) (xy 323.253121 -35.637824) (xy 323.340792 -35.649948)
			(xy 323.426986 -35.670044) (xy 323.51098 -35.69794) (xy 323.592069 -35.733405) (xy 323.669574 -35.776139)
			(xy 323.742844 -35.825786) (xy 323.80494 -35.876738) (xy 341.01735 -35.876738) (xy 341.021421 -35.821116)
			(xy 341.033547 -35.766679) (xy 341.05347 -35.714588) (xy 341.080766 -35.665953) (xy 341.114852 -35.62181)
			(xy 341.155001 -35.583101) (xy 341.200359 -35.55065) (xy 341.249959 -35.525149) (xy 341.302743 -35.507142)
			(xy 341.357586 -35.497012) (xy 341.41332 -35.494975) (xy 341.468757 -35.501075) (xy 341.522714 -35.515181)
			(xy 341.574043 -35.536993) (xy 341.621649 -35.566047) (xy 341.664517 -35.601722) (xy 341.701734 -35.643259)
			(xy 341.732507 -35.689772) (xy 341.756179 -35.740269) (xy 341.772247 -35.793676) (xy 341.780367 -35.848852)
			(xy 341.780876 -35.876738) (xy 345.08897 -35.876738) (xy 345.093041 -35.821116) (xy 345.105167 -35.766679)
			(xy 345.12509 -35.714588) (xy 345.152386 -35.665953) (xy 345.186472 -35.62181) (xy 345.226621 -35.583101)
			(xy 345.271979 -35.55065) (xy 345.321579 -35.525149) (xy 345.374363 -35.507142) (xy 345.429206 -35.497012)
			(xy 345.48494 -35.494975) (xy 345.540377 -35.501075) (xy 345.594334 -35.515181) (xy 345.645663 -35.536993)
			(xy 345.693269 -35.566047) (xy 345.736137 -35.601722) (xy 345.773354 -35.643259) (xy 345.804127 -35.689772)
			(xy 345.827799 -35.740269) (xy 345.843867 -35.793676) (xy 345.851987 -35.848852) (xy 345.852496 -35.876738)
			(xy 345.851987 -35.904624) (xy 345.843867 -35.9598) (xy 345.827799 -36.013207) (xy 345.804127 -36.063704)
			(xy 345.773354 -36.110217) (xy 345.736137 -36.151754) (xy 345.693269 -36.187429) (xy 345.645663 -36.216483)
			(xy 345.594334 -36.238295) (xy 345.540377 -36.252401) (xy 345.48494 -36.258501) (xy 345.429206 -36.256464)
			(xy 345.374363 -36.246334) (xy 345.321579 -36.228327) (xy 345.271979 -36.202826) (xy 345.226621 -36.170375)
			(xy 345.186472 -36.131666) (xy 345.152386 -36.087523) (xy 345.12509 -36.038888) (xy 345.105167 -35.986797)
			(xy 345.093041 -35.93236) (xy 345.08897 -35.876738) (xy 341.780876 -35.876738) (xy 341.780367 -35.904624)
			(xy 341.772247 -35.9598) (xy 341.756179 -36.013207) (xy 341.732507 -36.063704) (xy 341.701734 -36.110217)
			(xy 341.664517 -36.151754) (xy 341.621649 -36.187429) (xy 341.574043 -36.216483) (xy 341.522714 -36.238295)
			(xy 341.468757 -36.252401) (xy 341.41332 -36.258501) (xy 341.357586 -36.256464) (xy 341.302743 -36.246334)
			(xy 341.249959 -36.228327) (xy 341.200359 -36.202826) (xy 341.155001 -36.170375) (xy 341.114852 -36.131666)
			(xy 341.080766 -36.087523) (xy 341.05347 -36.038888) (xy 341.033547 -35.986797) (xy 341.021421 -35.93236)
			(xy 341.01735 -35.876738) (xy 323.80494 -35.876738) (xy 323.811264 -35.881927) (xy 323.874261 -35.944093)
			(xy 323.931307 -36.011762) (xy 323.981921 -36.084366) (xy 324.025682 -36.161296) (xy 324.06222 -36.241908)
			(xy 324.091229 -36.325524) (xy 324.112467 -36.411443) (xy 324.125755 -36.498946) (xy 324.126407 -36.50996)
			(xy 342.913968 -36.50996) (xy 342.918039 -36.454338) (xy 342.930165 -36.399901) (xy 342.950088 -36.34781)
			(xy 342.977384 -36.299175) (xy 343.01147 -36.255032) (xy 343.051619 -36.216323) (xy 343.096977 -36.183872)
			(xy 343.146577 -36.158371) (xy 343.199361 -36.140364) (xy 343.254204 -36.130234) (xy 343.309938 -36.128197)
			(xy 343.365375 -36.134297) (xy 343.419332 -36.148403) (xy 343.470661 -36.170215) (xy 343.518267 -36.199269)
			(xy 343.561135 -36.234944) (xy 343.598352 -36.276481) (xy 343.629125 -36.322994) (xy 343.652797 -36.373491)
			(xy 343.668865 -36.426898) (xy 343.67279 -36.453572) (xy 346.228668 -36.453572) (xy 346.232739 -36.39795)
			(xy 346.244865 -36.343513) (xy 346.264788 -36.291422) (xy 346.292084 -36.242787) (xy 346.32617 -36.198644)
			(xy 346.366319 -36.159935) (xy 346.411677 -36.127484) (xy 346.461277 -36.101983) (xy 346.514061 -36.083976)
			(xy 346.568904 -36.073846) (xy 346.624638 -36.071809) (xy 346.680075 -36.077909) (xy 346.734032 -36.092015)
			(xy 346.785361 -36.113827) (xy 346.832967 -36.142881) (xy 346.875835 -36.178556) (xy 346.913052 -36.220093)
			(xy 346.943825 -36.266606) (xy 346.967497 -36.317103) (xy 346.983565 -36.37051) (xy 346.991685 -36.425686)
			(xy 346.992194 -36.453572) (xy 346.991685 -36.481458) (xy 346.983565 -36.536634) (xy 346.967497 -36.590041)
			(xy 346.943825 -36.640538) (xy 346.913052 -36.687051) (xy 346.875835 -36.728588) (xy 346.832967 -36.764263)
			(xy 346.785361 -36.793317) (xy 346.734032 -36.815129) (xy 346.680075 -36.829235) (xy 346.624638 -36.835335)
			(xy 346.568904 -36.833298) (xy 346.514061 -36.823168) (xy 346.461277 -36.805161) (xy 346.411677 -36.77966)
			(xy 346.366319 -36.747209) (xy 346.32617 -36.7085) (xy 346.292084 -36.664357) (xy 346.264788 -36.615722)
			(xy 346.244865 -36.563631) (xy 346.232739 -36.509194) (xy 346.228668 -36.453572) (xy 343.67279 -36.453572)
			(xy 343.676985 -36.482074) (xy 343.677494 -36.50996) (xy 343.676985 -36.537846) (xy 343.668865 -36.593022)
			(xy 343.652797 -36.646429) (xy 343.629125 -36.696926) (xy 343.598352 -36.743439) (xy 343.561135 -36.784976)
			(xy 343.518267 -36.820651) (xy 343.470661 -36.849705) (xy 343.419332 -36.871517) (xy 343.365375 -36.885623)
			(xy 343.309938 -36.891723) (xy 343.254204 -36.889686) (xy 343.199361 -36.879556) (xy 343.146577 -36.861549)
			(xy 343.096977 -36.836048) (xy 343.051619 -36.803597) (xy 343.01147 -36.764888) (xy 342.977384 -36.720745)
			(xy 342.950088 -36.67211) (xy 342.930165 -36.620019) (xy 342.918039 -36.565582) (xy 342.913968 -36.50996)
			(xy 324.126407 -36.50996) (xy 324.130982 -36.587297) (xy 324.128104 -36.675755) (xy 324.117144 -36.76358)
			(xy 324.098195 -36.850033) (xy 324.071417 -36.93439) (xy 324.037032 -37.015944) (xy 323.995331 -37.094009)
			(xy 323.971412 -37.131244) (xy 323.967348 -37.137594) (xy 323.96303 -37.151564) (xy 323.96303 -37.159184)
			(xy 323.963433 -37.169208) (xy 323.971103 -37.18773) (xy 323.985281 -37.201904) (xy 324.003806 -37.20957)
			(xy 324.01383 -37.209984) (xy 324.091808 -37.209984) (xy 324.135248 -37.21041) (xy 324.221756 -37.218427)
			(xy 324.307156 -37.234392) (xy 324.390719 -37.258168) (xy 324.471731 -37.289553) (xy 324.549502 -37.328279)
			(xy 324.623368 -37.374015) (xy 324.692699 -37.426372) (xy 324.746217 -37.47516) (xy 340.059262 -37.47516)
			(xy 340.063333 -37.419538) (xy 340.075459 -37.365101) (xy 340.095382 -37.31301) (xy 340.122678 -37.264375)
			(xy 340.156764 -37.220232) (xy 340.196913 -37.181523) (xy 340.242271 -37.149072) (xy 340.291871 -37.123571)
			(xy 340.344655 -37.105564) (xy 340.399498 -37.095434) (xy 340.455232 -37.093397) (xy 340.510669 -37.099497)
			(xy 340.564626 -37.113603) (xy 340.615955 -37.135415) (xy 340.663561 -37.164469) (xy 340.706429 -37.200144)
			(xy 340.70728 -37.201094) (xy 344.016582 -37.201094) (xy 344.020653 -37.145472) (xy 344.032779 -37.091035)
			(xy 344.052702 -37.038944) (xy 344.079998 -36.990309) (xy 344.114084 -36.946166) (xy 344.154233 -36.907457)
			(xy 344.199591 -36.875006) (xy 344.249191 -36.849505) (xy 344.301975 -36.831498) (xy 344.356818 -36.821368)
			(xy 344.412552 -36.819331) (xy 344.467989 -36.825431) (xy 344.521946 -36.839537) (xy 344.573275 -36.861349)
			(xy 344.620881 -36.890403) (xy 344.663749 -36.926078) (xy 344.700966 -36.967615) (xy 344.731739 -37.014128)
			(xy 344.755411 -37.064625) (xy 344.762157 -37.087048) (xy 353.500944 -37.087048) (xy 353.50141 -37.060444)
			(xy 353.508786 -37.007751) (xy 353.523416 -36.956595) (xy 353.545015 -36.90797) (xy 353.573165 -36.862819)
			(xy 353.607317 -36.82202) (xy 353.64681 -36.786364) (xy 353.668584 -36.771072) (xy 353.678508 -36.763541)
			(xy 353.690236 -36.741598) (xy 353.690936 -36.729162) (xy 353.690936 -36.644834) (xy 353.690265 -36.632384)
			(xy 353.678555 -36.610408) (xy 353.668584 -36.602924) (xy 353.646826 -36.587612) (xy 353.607344 -36.55195)
			(xy 353.573199 -36.51115) (xy 353.545051 -36.466003) (xy 353.523447 -36.417384) (xy 353.508805 -36.366236)
			(xy 353.501408 -36.313549) (xy 353.500944 -36.286948) (xy 353.501523 -36.2597) (xy 353.509271 -36.205758)
			(xy 353.524618 -36.153468) (xy 353.54725 -36.103894) (xy 353.576707 -36.058046) (xy 353.612389 -36.016857)
			(xy 353.653569 -35.981164) (xy 353.69941 -35.951696) (xy 353.748978 -35.929052) (xy 353.801264 -35.913692)
			(xy 353.855204 -35.90593) (xy 353.882452 -35.90544) (xy 353.887024 -35.90544) (xy 353.896233 -35.905165)
			(xy 353.913552 -35.898926) (xy 353.920806 -35.893248) (xy 353.971606 -35.84956) (xy 353.978311 -35.843323)
			(xy 353.987171 -35.827314) (xy 353.988878 -35.818318) (xy 353.988878 -35.818064) (xy 353.99323 -35.791134)
			(xy 354.00854 -35.738779) (xy 354.03115 -35.689137) (xy 354.060601 -35.643223) (xy 354.096291 -35.601971)
			(xy 354.137493 -35.566223) (xy 354.183367 -35.536707) (xy 354.232976 -35.514027) (xy 354.28531 -35.498643)
			(xy 354.339302 -35.490871) (xy 354.366576 -35.490404) (xy 354.393831 -35.490841) (xy 354.447786 -35.498596)
			(xy 354.500089 -35.51395) (xy 354.549673 -35.536592) (xy 354.595531 -35.56606) (xy 354.636728 -35.601755)
			(xy 354.672425 -35.64295) (xy 354.701896 -35.688806) (xy 354.724541 -35.738389) (xy 354.739899 -35.79069)
			(xy 354.747657 -35.844645) (xy 354.747657 -35.899155) (xy 354.739899 -35.95311) (xy 354.724541 -36.005411)
			(xy 354.701896 -36.054994) (xy 354.672425 -36.10085) (xy 354.636728 -36.142045) (xy 354.595531 -36.17774)
			(xy 354.549673 -36.207208) (xy 354.500089 -36.22985) (xy 354.447786 -36.245204) (xy 354.393831 -36.252959)
			(xy 354.366576 -36.25342) (xy 354.362004 -36.25342) (xy 354.35279 -36.253646) (xy 354.335471 -36.259917)
			(xy 354.328222 -36.265612) (xy 354.277422 -36.3093) (xy 354.2707 -36.315521) (xy 354.261849 -36.331541)
			(xy 354.26015 -36.340542) (xy 354.26015 -36.340796) (xy 354.255953 -36.366999) (xy 354.241269 -36.417994)
			(xy 354.219656 -36.46646) (xy 354.191531 -36.511461) (xy 354.188105 -36.515548) (xy 355.314248 -36.515548)
			(xy 355.318319 -36.459926) (xy 355.330445 -36.405489) (xy 355.350368 -36.353398) (xy 355.377664 -36.304763)
			(xy 355.41175 -36.26062) (xy 355.451899 -36.221911) (xy 355.497257 -36.18946) (xy 355.546857 -36.163959)
			(xy 355.599641 -36.145952) (xy 355.654484 -36.135822) (xy 355.710218 -36.133785) (xy 355.765655 -36.139885)
			(xy 355.819612 -36.153991) (xy 355.870941 -36.175803) (xy 355.918547 -36.204857) (xy 355.961415 -36.240532)
			(xy 355.998632 -36.282069) (xy 356.029405 -36.328582) (xy 356.053077 -36.379079) (xy 356.069145 -36.432486)
			(xy 356.077265 -36.487662) (xy 356.077774 -36.515548) (xy 356.077265 -36.543434) (xy 356.069145 -36.59861)
			(xy 356.053077 -36.652017) (xy 356.029405 -36.702514) (xy 355.998632 -36.749027) (xy 355.961415 -36.790564)
			(xy 355.918547 -36.826239) (xy 355.870941 -36.855293) (xy 355.819612 -36.877105) (xy 355.765655 -36.891211)
			(xy 355.710218 -36.897311) (xy 355.654484 -36.895274) (xy 355.599641 -36.885144) (xy 355.546857 -36.867137)
			(xy 355.497257 -36.841636) (xy 355.451899 -36.809185) (xy 355.41175 -36.770476) (xy 355.377664 -36.726333)
			(xy 355.350368 -36.677698) (xy 355.330445 -36.625607) (xy 355.318319 -36.57117) (xy 355.314248 -36.515548)
			(xy 354.188105 -36.515548) (xy 354.157439 -36.552127) (xy 354.118038 -36.587675) (xy 354.09632 -36.602924)
			(xy 354.086399 -36.610458) (xy 354.074669 -36.632399) (xy 354.073968 -36.644834) (xy 354.073968 -36.729162)
			(xy 354.07464 -36.741612) (xy 354.086349 -36.763588) (xy 354.09632 -36.771072) (xy 354.118077 -36.786385)
			(xy 354.157558 -36.822047) (xy 354.191704 -36.862847) (xy 354.219852 -36.907994) (xy 354.241456 -36.956612)
			(xy 354.256099 -37.007761) (xy 354.263495 -37.060447) (xy 354.26396 -37.087048) (xy 354.26396 -37.087302)
			(xy 354.263342 -37.119019) (xy 354.252841 -37.181577) (xy 354.232113 -37.241528) (xy 354.217478 -37.269674)
			(xy 354.212144 -37.27958) (xy 354.21062 -37.301678) (xy 354.242624 -37.384482) (xy 354.247119 -37.394567)
			(xy 354.262905 -37.409971) (xy 354.273104 -37.4142) (xy 354.297638 -37.423264) (xy 354.344168 -37.447147)
			(xy 354.386999 -37.477164) (xy 354.425328 -37.51275) (xy 354.458436 -37.553239) (xy 354.485702 -37.597872)
			(xy 354.506614 -37.645811) (xy 354.520782 -37.696157) (xy 354.527938 -37.747967) (xy 354.528374 -37.774118)
			(xy 354.527888 -37.801369) (xy 354.520132 -37.855317) (xy 354.504777 -37.907612) (xy 354.482135 -37.957189)
			(xy 354.452669 -38.003039) (xy 354.416978 -38.04423) (xy 354.375787 -38.079921) (xy 354.329937 -38.109387)
			(xy 354.28036 -38.132029) (xy 354.228065 -38.147384) (xy 354.174117 -38.15514) (xy 354.119615 -38.15514)
			(xy 354.065667 -38.147384) (xy 354.013372 -38.132029) (xy 353.963795 -38.109387) (xy 353.917945 -38.079921)
			(xy 353.876754 -38.04423) (xy 353.841063 -38.003039) (xy 353.811597 -37.957189) (xy 353.788955 -37.907612)
			(xy 353.7736 -37.855317) (xy 353.765844 -37.801369) (xy 353.765358 -37.774118) (xy 353.765358 -37.773864)
			(xy 353.76596 -37.742146) (xy 353.776467 -37.679588) (xy 353.797202 -37.619637) (xy 353.81184 -37.591492)
			(xy 353.817174 -37.581586) (xy 353.818698 -37.559488) (xy 353.786694 -37.476684) (xy 353.782246 -37.466573)
			(xy 353.766427 -37.451181) (xy 353.756214 -37.446966) (xy 353.731673 -37.437921) (xy 353.685141 -37.414036)
			(xy 353.642308 -37.384019) (xy 353.603979 -37.34843) (xy 353.570871 -37.307939) (xy 353.543606 -37.263303)
			(xy 353.522695 -37.215361) (xy 353.508531 -37.165012) (xy 353.501378 -37.1132) (xy 353.500944 -37.087048)
			(xy 344.762157 -37.087048) (xy 344.771479 -37.118032) (xy 344.779599 -37.173208) (xy 344.780108 -37.201094)
			(xy 344.779599 -37.22898) (xy 344.771479 -37.284156) (xy 344.755411 -37.337563) (xy 344.731739 -37.38806)
			(xy 344.700966 -37.434573) (xy 344.663749 -37.47611) (xy 344.620881 -37.511785) (xy 344.573275 -37.540839)
			(xy 344.521946 -37.562651) (xy 344.467989 -37.576757) (xy 344.412552 -37.582857) (xy 344.356818 -37.58082)
			(xy 344.301975 -37.57069) (xy 344.249191 -37.552683) (xy 344.199591 -37.527182) (xy 344.154233 -37.494731)
			(xy 344.114084 -37.456022) (xy 344.079998 -37.411879) (xy 344.052702 -37.363244) (xy 344.032779 -37.311153)
			(xy 344.020653 -37.256716) (xy 344.016582 -37.201094) (xy 340.70728 -37.201094) (xy 340.743646 -37.241681)
			(xy 340.774419 -37.288194) (xy 340.798091 -37.338691) (xy 340.814159 -37.392098) (xy 340.822279 -37.447274)
			(xy 340.822788 -37.47516) (xy 340.822279 -37.503046) (xy 340.814159 -37.558222) (xy 340.798091 -37.611629)
			(xy 340.774419 -37.662126) (xy 340.774266 -37.662358) (xy 342.248488 -37.662358) (xy 342.252559 -37.606736)
			(xy 342.264685 -37.552299) (xy 342.284608 -37.500208) (xy 342.311904 -37.451573) (xy 342.34599 -37.40743)
			(xy 342.386139 -37.368721) (xy 342.431497 -37.33627) (xy 342.481097 -37.310769) (xy 342.533881 -37.292762)
			(xy 342.588724 -37.282632) (xy 342.644458 -37.280595) (xy 342.699895 -37.286695) (xy 342.753852 -37.300801)
			(xy 342.805181 -37.322613) (xy 342.852787 -37.351667) (xy 342.895655 -37.387342) (xy 342.932872 -37.428879)
			(xy 342.963645 -37.475392) (xy 342.987317 -37.525889) (xy 343.003385 -37.579296) (xy 343.011505 -37.634472)
			(xy 343.012014 -37.662358) (xy 343.011505 -37.690244) (xy 343.003385 -37.74542) (xy 342.987317 -37.798827)
			(xy 342.963645 -37.849324) (xy 342.932872 -37.895837) (xy 342.895655 -37.937374) (xy 342.852787 -37.973049)
			(xy 342.805181 -38.002103) (xy 342.753852 -38.023915) (xy 342.699895 -38.038021) (xy 342.644458 -38.044121)
			(xy 342.588724 -38.042084) (xy 342.533881 -38.031954) (xy 342.481097 -38.013947) (xy 342.431497 -37.988446)
			(xy 342.386139 -37.955995) (xy 342.34599 -37.917286) (xy 342.311904 -37.873143) (xy 342.284608 -37.824508)
			(xy 342.264685 -37.772417) (xy 342.252559 -37.71798) (xy 342.248488 -37.662358) (xy 340.774266 -37.662358)
			(xy 340.743646 -37.708639) (xy 340.706429 -37.750176) (xy 340.663561 -37.785851) (xy 340.615955 -37.814905)
			(xy 340.564626 -37.836717) (xy 340.510669 -37.850823) (xy 340.455232 -37.856923) (xy 340.399498 -37.854886)
			(xy 340.344655 -37.844756) (xy 340.291871 -37.826749) (xy 340.242271 -37.801248) (xy 340.196913 -37.768797)
			(xy 340.156764 -37.730088) (xy 340.122678 -37.685945) (xy 340.095382 -37.63731) (xy 340.075459 -37.585219)
			(xy 340.063333 -37.530782) (xy 340.059262 -37.47516) (xy 324.746217 -37.47516) (xy 324.756903 -37.484902)
			(xy 324.815433 -37.549107) (xy 324.867789 -37.618439) (xy 324.913525 -37.692305) (xy 324.95225 -37.770076)
			(xy 324.983635 -37.851089) (xy 325.00741 -37.934652) (xy 325.023374 -38.020052) (xy 325.03139 -38.10656)
			(xy 325.03139 -38.19344) (xy 325.023374 -38.279948) (xy 325.00741 -38.365348) (xy 324.983635 -38.448911)
			(xy 324.967267 -38.49116) (xy 340.059262 -38.49116) (xy 340.063333 -38.435538) (xy 340.075459 -38.381101)
			(xy 340.095382 -38.32901) (xy 340.122678 -38.280375) (xy 340.156764 -38.236232) (xy 340.196913 -38.197523)
			(xy 340.242271 -38.165072) (xy 340.291871 -38.139571) (xy 340.344655 -38.121564) (xy 340.399498 -38.111434)
			(xy 340.455232 -38.109397) (xy 340.510669 -38.115497) (xy 340.564626 -38.129603) (xy 340.615955 -38.151415)
			(xy 340.663561 -38.180469) (xy 340.706429 -38.216144) (xy 340.743646 -38.257681) (xy 340.774419 -38.304194)
			(xy 340.779549 -38.315138) (xy 354.71811 -38.315138) (xy 354.722181 -38.259516) (xy 354.734307 -38.205079)
			(xy 354.75423 -38.152988) (xy 354.781526 -38.104353) (xy 354.815612 -38.06021) (xy 354.855761 -38.021501)
			(xy 354.901119 -37.98905) (xy 354.950719 -37.963549) (xy 355.003503 -37.945542) (xy 355.058346 -37.935412)
			(xy 355.11408 -37.933375) (xy 355.169517 -37.939475) (xy 355.223474 -37.953581) (xy 355.274803 -37.975393)
			(xy 355.322409 -38.004447) (xy 355.365277 -38.040122) (xy 355.402494 -38.081659) (xy 355.433267 -38.128172)
			(xy 355.456939 -38.178669) (xy 355.461381 -38.193435) (xy 359.398386 -38.193435) (xy 359.398386 -38.106565)
			(xy 359.406401 -38.020065) (xy 359.422363 -37.934673) (xy 359.446135 -37.851119) (xy 359.477516 -37.770114)
			(xy 359.516236 -37.69235) (xy 359.561967 -37.618491) (xy 359.614317 -37.549166) (xy 359.67284 -37.484967)
			(xy 359.737037 -37.426441) (xy 359.80636 -37.374088) (xy 359.880217 -37.328355) (xy 359.957979 -37.289631)
			(xy 360.038983 -37.258247) (xy 360.122536 -37.234471) (xy 360.207927 -37.218506) (xy 360.294427 -37.210487)
			(xy 360.337862 -37.209984) (xy 360.41584 -37.209984) (xy 360.425852 -37.209544) (xy 360.444348 -37.201869)
			(xy 360.4585 -37.187701) (xy 360.466155 -37.169197) (xy 360.46664 -37.159184) (xy 360.46664 -37.151564)
			(xy 360.462322 -37.137594) (xy 360.458258 -37.131244) (xy 360.434339 -37.094009) (xy 360.392638 -37.015944)
			(xy 360.358253 -36.93439) (xy 360.331475 -36.850033) (xy 360.312526 -36.76358) (xy 360.301566 -36.675755)
			(xy 360.298688 -36.587297) (xy 360.303915 -36.498946) (xy 360.317203 -36.411443) (xy 360.338441 -36.325524)
			(xy 360.36745 -36.241908) (xy 360.403988 -36.161296) (xy 360.447749 -36.084366) (xy 360.498363 -36.011762)
			(xy 360.555409 -35.944093) (xy 360.618406 -35.881927) (xy 360.686826 -35.825786) (xy 360.760096 -35.776139)
			(xy 360.837601 -35.733405) (xy 360.91869 -35.69794) (xy 361.002684 -35.670044) (xy 361.088878 -35.649948)
			(xy 361.176549 -35.637824) (xy 361.264962 -35.633771) (xy 361.353375 -35.637824) (xy 361.441046 -35.649948)
			(xy 361.52724 -35.670044) (xy 361.611234 -35.69794) (xy 361.692323 -35.733405) (xy 361.769828 -35.776139)
			(xy 361.843098 -35.825786) (xy 361.905194 -35.876738) (xy 367.017298 -35.876738) (xy 367.021369 -35.821116)
			(xy 367.033495 -35.766679) (xy 367.053418 -35.714588) (xy 367.080714 -35.665953) (xy 367.1148 -35.62181)
			(xy 367.154949 -35.583101) (xy 367.200307 -35.55065) (xy 367.249907 -35.525149) (xy 367.302691 -35.507142)
			(xy 367.357534 -35.497012) (xy 367.413268 -35.494975) (xy 367.468705 -35.501075) (xy 367.522662 -35.515181)
			(xy 367.573991 -35.536993) (xy 367.621597 -35.566047) (xy 367.664465 -35.601722) (xy 367.701682 -35.643259)
			(xy 367.732455 -35.689772) (xy 367.756127 -35.740269) (xy 367.772195 -35.793676) (xy 367.780315 -35.848852)
			(xy 367.780824 -35.876738) (xy 371.088918 -35.876738) (xy 371.092989 -35.821116) (xy 371.105115 -35.766679)
			(xy 371.125038 -35.714588) (xy 371.152334 -35.665953) (xy 371.18642 -35.62181) (xy 371.226569 -35.583101)
			(xy 371.271927 -35.55065) (xy 371.321527 -35.525149) (xy 371.374311 -35.507142) (xy 371.429154 -35.497012)
			(xy 371.484888 -35.494975) (xy 371.540325 -35.501075) (xy 371.594282 -35.515181) (xy 371.645611 -35.536993)
			(xy 371.693217 -35.566047) (xy 371.736085 -35.601722) (xy 371.773302 -35.643259) (xy 371.804075 -35.689772)
			(xy 371.827747 -35.740269) (xy 371.843815 -35.793676) (xy 371.851935 -35.848852) (xy 371.852444 -35.876738)
			(xy 371.851935 -35.904624) (xy 371.843815 -35.9598) (xy 371.827747 -36.013207) (xy 371.804075 -36.063704)
			(xy 371.773302 -36.110217) (xy 371.736085 -36.151754) (xy 371.693217 -36.187429) (xy 371.645611 -36.216483)
			(xy 371.594282 -36.238295) (xy 371.540325 -36.252401) (xy 371.484888 -36.258501) (xy 371.429154 -36.256464)
			(xy 371.374311 -36.246334) (xy 371.321527 -36.228327) (xy 371.271927 -36.202826) (xy 371.226569 -36.170375)
			(xy 371.18642 -36.131666) (xy 371.152334 -36.087523) (xy 371.125038 -36.038888) (xy 371.105115 -35.986797)
			(xy 371.092989 -35.93236) (xy 371.088918 -35.876738) (xy 367.780824 -35.876738) (xy 367.780315 -35.904624)
			(xy 367.772195 -35.9598) (xy 367.756127 -36.013207) (xy 367.732455 -36.063704) (xy 367.701682 -36.110217)
			(xy 367.664465 -36.151754) (xy 367.621597 -36.187429) (xy 367.573991 -36.216483) (xy 367.522662 -36.238295)
			(xy 367.468705 -36.252401) (xy 367.413268 -36.258501) (xy 367.357534 -36.256464) (xy 367.302691 -36.246334)
			(xy 367.249907 -36.228327) (xy 367.200307 -36.202826) (xy 367.154949 -36.170375) (xy 367.1148 -36.131666)
			(xy 367.080714 -36.087523) (xy 367.053418 -36.038888) (xy 367.033495 -35.986797) (xy 367.021369 -35.93236)
			(xy 367.017298 -35.876738) (xy 361.905194 -35.876738) (xy 361.911518 -35.881927) (xy 361.974515 -35.944093)
			(xy 362.031561 -36.011762) (xy 362.082175 -36.084366) (xy 362.125936 -36.161296) (xy 362.162474 -36.241908)
			(xy 362.191483 -36.325524) (xy 362.212721 -36.411443) (xy 362.226009 -36.498946) (xy 362.226661 -36.50996)
			(xy 368.913916 -36.50996) (xy 368.917987 -36.454338) (xy 368.930113 -36.399901) (xy 368.950036 -36.34781)
			(xy 368.977332 -36.299175) (xy 369.011418 -36.255032) (xy 369.051567 -36.216323) (xy 369.096925 -36.183872)
			(xy 369.146525 -36.158371) (xy 369.199309 -36.140364) (xy 369.254152 -36.130234) (xy 369.309886 -36.128197)
			(xy 369.365323 -36.134297) (xy 369.41928 -36.148403) (xy 369.470609 -36.170215) (xy 369.518215 -36.199269)
			(xy 369.561083 -36.234944) (xy 369.5983 -36.276481) (xy 369.629073 -36.322994) (xy 369.652745 -36.373491)
			(xy 369.668813 -36.426898) (xy 369.672738 -36.453572) (xy 372.228616 -36.453572) (xy 372.232687 -36.39795)
			(xy 372.244813 -36.343513) (xy 372.264736 -36.291422) (xy 372.292032 -36.242787) (xy 372.326118 -36.198644)
			(xy 372.366267 -36.159935) (xy 372.411625 -36.127484) (xy 372.461225 -36.101983) (xy 372.514009 -36.083976)
			(xy 372.568852 -36.073846) (xy 372.624586 -36.071809) (xy 372.680023 -36.077909) (xy 372.73398 -36.092015)
			(xy 372.785309 -36.113827) (xy 372.832915 -36.142881) (xy 372.875783 -36.178556) (xy 372.913 -36.220093)
			(xy 372.943773 -36.266606) (xy 372.967445 -36.317103) (xy 372.983513 -36.37051) (xy 372.991633 -36.425686)
			(xy 372.992142 -36.453572) (xy 372.991633 -36.481458) (xy 372.983513 -36.536634) (xy 372.967445 -36.590041)
			(xy 372.943773 -36.640538) (xy 372.913 -36.687051) (xy 372.875783 -36.728588) (xy 372.832915 -36.764263)
			(xy 372.785309 -36.793317) (xy 372.73398 -36.815129) (xy 372.680023 -36.829235) (xy 372.624586 -36.835335)
			(xy 372.568852 -36.833298) (xy 372.514009 -36.823168) (xy 372.461225 -36.805161) (xy 372.411625 -36.77966)
			(xy 372.366267 -36.747209) (xy 372.326118 -36.7085) (xy 372.292032 -36.664357) (xy 372.264736 -36.615722)
			(xy 372.244813 -36.563631) (xy 372.232687 -36.509194) (xy 372.228616 -36.453572) (xy 369.672738 -36.453572)
			(xy 369.676933 -36.482074) (xy 369.677442 -36.50996) (xy 369.676933 -36.537846) (xy 369.668813 -36.593022)
			(xy 369.652745 -36.646429) (xy 369.629073 -36.696926) (xy 369.5983 -36.743439) (xy 369.561083 -36.784976)
			(xy 369.518215 -36.820651) (xy 369.470609 -36.849705) (xy 369.41928 -36.871517) (xy 369.365323 -36.885623)
			(xy 369.309886 -36.891723) (xy 369.254152 -36.889686) (xy 369.199309 -36.879556) (xy 369.146525 -36.861549)
			(xy 369.096925 -36.836048) (xy 369.051567 -36.803597) (xy 369.011418 -36.764888) (xy 368.977332 -36.720745)
			(xy 368.950036 -36.67211) (xy 368.930113 -36.620019) (xy 368.917987 -36.565582) (xy 368.913916 -36.50996)
			(xy 362.226661 -36.50996) (xy 362.231236 -36.587297) (xy 362.228358 -36.675755) (xy 362.217398 -36.76358)
			(xy 362.198449 -36.850033) (xy 362.171671 -36.93439) (xy 362.137286 -37.015944) (xy 362.095585 -37.094009)
			(xy 362.071666 -37.131244) (xy 362.067602 -37.137594) (xy 362.063284 -37.151564) (xy 362.063284 -37.159184)
			(xy 362.063801 -37.169189) (xy 362.071452 -37.187677) (xy 362.085596 -37.20183) (xy 362.10408 -37.209493)
			(xy 362.114084 -37.209984) (xy 362.192062 -37.209984) (xy 362.235504 -37.210393) (xy 362.322017 -37.218406)
			(xy 362.407421 -37.234368) (xy 362.490989 -37.258142) (xy 362.572006 -37.289525) (xy 362.649782 -37.32825)
			(xy 362.723653 -37.373987) (xy 362.792989 -37.426344) (xy 362.84654 -37.47516) (xy 366.05921 -37.47516)
			(xy 366.063281 -37.419538) (xy 366.075407 -37.365101) (xy 366.09533 -37.31301) (xy 366.122626 -37.264375)
			(xy 366.156712 -37.220232) (xy 366.196861 -37.181523) (xy 366.242219 -37.149072) (xy 366.291819 -37.123571)
			(xy 366.344603 -37.105564) (xy 366.399446 -37.095434) (xy 366.45518 -37.093397) (xy 366.510617 -37.099497)
			(xy 366.564574 -37.113603) (xy 366.615903 -37.135415) (xy 366.663509 -37.164469) (xy 366.706377 -37.200144)
			(xy 366.707228 -37.201094) (xy 370.01653 -37.201094) (xy 370.020601 -37.145472) (xy 370.032727 -37.091035)
			(xy 370.05265 -37.038944) (xy 370.079946 -36.990309) (xy 370.114032 -36.946166) (xy 370.154181 -36.907457)
			(xy 370.199539 -36.875006) (xy 370.249139 -36.849505) (xy 370.301923 -36.831498) (xy 370.356766 -36.821368)
			(xy 370.4125 -36.819331) (xy 370.467937 -36.825431) (xy 370.521894 -36.839537) (xy 370.573223 -36.861349)
			(xy 370.620829 -36.890403) (xy 370.663697 -36.926078) (xy 370.700914 -36.967615) (xy 370.731687 -37.014128)
			(xy 370.755359 -37.064625) (xy 370.762105 -37.087048) (xy 379.500892 -37.087048) (xy 379.501381 -37.060445)
			(xy 379.508756 -37.007754) (xy 379.523383 -36.9566) (xy 379.544979 -36.907975) (xy 379.573125 -36.862824)
			(xy 379.607273 -36.822024) (xy 379.646761 -36.786366) (xy 379.668532 -36.771072) (xy 379.678464 -36.763551)
			(xy 379.690186 -36.7416) (xy 379.690884 -36.729162) (xy 379.690884 -36.644834) (xy 379.690233 -36.632381)
			(xy 379.678511 -36.610403) (xy 379.668532 -36.602924) (xy 379.646762 -36.587628) (xy 379.607284 -36.551962)
			(xy 379.573141 -36.511158) (xy 379.544995 -36.466009) (xy 379.523393 -36.417388) (xy 379.508752 -36.366238)
			(xy 379.501356 -36.31355) (xy 379.500892 -36.286948) (xy 379.5014 -36.259696) (xy 379.50915 -36.205747)
			(xy 379.5245 -36.15345) (xy 379.547137 -36.10387) (xy 379.5766 -36.058017) (xy 379.612289 -36.016823)
			(xy 379.653478 -35.981129) (xy 379.699328 -35.95166) (xy 379.748905 -35.929017) (xy 379.8012 -35.913661)
			(xy 379.855148 -35.905903) (xy 379.8824 -35.90544) (xy 379.886972 -35.90544) (xy 379.896183 -35.905189)
			(xy 379.913502 -35.898934) (xy 379.920754 -35.893248) (xy 379.971554 -35.84956) (xy 379.978267 -35.84333)
			(xy 379.987121 -35.827316) (xy 379.988826 -35.818318) (xy 379.988826 -35.818064) (xy 379.993131 -35.791126)
			(xy 380.008444 -35.738767) (xy 380.031059 -35.689122) (xy 380.060514 -35.643206) (xy 380.096209 -35.601953)
			(xy 380.137417 -35.566205) (xy 380.183296 -35.536691) (xy 380.232911 -35.514014) (xy 380.285251 -35.498634)
			(xy 380.339248 -35.490867) (xy 380.366524 -35.490404) (xy 380.393775 -35.490867) (xy 380.447722 -35.498627)
			(xy 380.500015 -35.513985) (xy 380.549591 -35.536628) (xy 380.59544 -35.566096) (xy 380.636629 -35.601788)
			(xy 380.672319 -35.642979) (xy 380.701784 -35.68883) (xy 380.724424 -35.738407) (xy 380.739778 -35.790702)
			(xy 380.747534 -35.844649) (xy 380.747534 -35.899151) (xy 380.739778 -35.953098) (xy 380.724424 -36.005393)
			(xy 380.701784 -36.05497) (xy 380.672319 -36.100821) (xy 380.636629 -36.142012) (xy 380.59544 -36.177704)
			(xy 380.549591 -36.207172) (xy 380.500015 -36.229815) (xy 380.447722 -36.245173) (xy 380.393775 -36.252933)
			(xy 380.366524 -36.25342) (xy 380.361952 -36.25342) (xy 380.35274 -36.253669) (xy 380.335421 -36.259924)
			(xy 380.32817 -36.265612) (xy 380.27737 -36.3093) (xy 380.27064 -36.315513) (xy 380.261795 -36.33154)
			(xy 380.260098 -36.340542) (xy 380.260098 -36.340796) (xy 380.255881 -36.366996) (xy 380.241199 -36.417989)
			(xy 380.219589 -36.466454) (xy 380.191468 -36.511455) (xy 380.188037 -36.515548) (xy 381.314196 -36.515548)
			(xy 381.318267 -36.459926) (xy 381.330393 -36.405489) (xy 381.350316 -36.353398) (xy 381.377612 -36.304763)
			(xy 381.411698 -36.26062) (xy 381.451847 -36.221911) (xy 381.497205 -36.18946) (xy 381.546805 -36.163959)
			(xy 381.599589 -36.145952) (xy 381.654432 -36.135822) (xy 381.710166 -36.133785) (xy 381.765603 -36.139885)
			(xy 381.81956 -36.153991) (xy 381.870889 -36.175803) (xy 381.918495 -36.204857) (xy 381.961363 -36.240532)
			(xy 381.99858 -36.282069) (xy 382.029353 -36.328582) (xy 382.053025 -36.379079) (xy 382.069093 -36.432486)
			(xy 382.077213 -36.487662) (xy 382.077722 -36.515548) (xy 382.077213 -36.543434) (xy 382.069093 -36.59861)
			(xy 382.053025 -36.652017) (xy 382.029353 -36.702514) (xy 381.99858 -36.749027) (xy 381.961363 -36.790564)
			(xy 381.918495 -36.826239) (xy 381.870889 -36.855293) (xy 381.81956 -36.877105) (xy 381.765603 -36.891211)
			(xy 381.710166 -36.897311) (xy 381.654432 -36.895274) (xy 381.599589 -36.885144) (xy 381.546805 -36.867137)
			(xy 381.497205 -36.841636) (xy 381.451847 -36.809185) (xy 381.411698 -36.770476) (xy 381.377612 -36.726333)
			(xy 381.350316 -36.677698) (xy 381.330393 -36.625607) (xy 381.318267 -36.57117) (xy 381.314196 -36.515548)
			(xy 380.188037 -36.515548) (xy 380.157381 -36.552123) (xy 380.117984 -36.587673) (xy 380.096268 -36.602924)
			(xy 380.086337 -36.610447) (xy 380.074615 -36.632397) (xy 380.073916 -36.644834) (xy 380.073916 -36.729162)
			(xy 380.074569 -36.741615) (xy 380.08629 -36.763592) (xy 380.096268 -36.771072) (xy 380.118036 -36.78637)
			(xy 380.157515 -36.822036) (xy 380.191658 -36.862839) (xy 380.219803 -36.907989) (xy 380.241406 -36.956609)
			(xy 380.256048 -37.007759) (xy 380.263443 -37.060446) (xy 380.263908 -37.087048) (xy 380.263908 -37.087302)
			(xy 380.263285 -37.119019) (xy 380.252785 -37.181576) (xy 380.232059 -37.241528) (xy 380.217426 -37.269674)
			(xy 380.212092 -37.27958) (xy 380.210568 -37.301678) (xy 380.242572 -37.384482) (xy 380.247046 -37.394579)
			(xy 380.262847 -37.409978) (xy 380.273052 -37.4142) (xy 380.297575 -37.423294) (xy 380.344106 -37.447171)
			(xy 380.386939 -37.477182) (xy 380.425269 -37.512764) (xy 380.458379 -37.55325) (xy 380.485646 -37.597879)
			(xy 380.50656 -37.645815) (xy 380.520729 -37.69616) (xy 380.527886 -37.747968) (xy 380.528322 -37.774118)
			(xy 380.527836 -37.801369) (xy 380.52008 -37.855317) (xy 380.504725 -37.907612) (xy 380.482083 -37.957189)
			(xy 380.452617 -38.003039) (xy 380.416926 -38.04423) (xy 380.375735 -38.079921) (xy 380.329885 -38.109387)
			(xy 380.280308 -38.132029) (xy 380.228013 -38.147384) (xy 380.174065 -38.15514) (xy 380.119563 -38.15514)
			(xy 380.065615 -38.147384) (xy 380.01332 -38.132029) (xy 379.963743 -38.109387) (xy 379.917893 -38.079921)
			(xy 379.876702 -38.04423) (xy 379.841011 -38.003039) (xy 379.811545 -37.957189) (xy 379.788903 -37.907612)
			(xy 379.773548 -37.855317) (xy 379.765792 -37.801369) (xy 379.765306 -37.774118) (xy 379.765306 -37.773864)
			(xy 379.765914 -37.742147) (xy 379.77642 -37.679588) (xy 379.797152 -37.619638) (xy 379.811788 -37.591492)
			(xy 379.817122 -37.581586) (xy 379.818646 -37.559488) (xy 379.786642 -37.476684) (xy 379.782174 -37.466584)
			(xy 379.766368 -37.451188) (xy 379.756162 -37.446966) (xy 379.731609 -37.437951) (xy 379.685079 -37.41406)
			(xy 379.642248 -37.384037) (xy 379.60392 -37.348444) (xy 379.570814 -37.307949) (xy 379.543551 -37.263311)
			(xy 379.522641 -37.215366) (xy 379.508478 -37.165015) (xy 379.501326 -37.113201) (xy 379.500892 -37.087048)
			(xy 370.762105 -37.087048) (xy 370.771427 -37.118032) (xy 370.779547 -37.173208) (xy 370.780056 -37.201094)
			(xy 370.779547 -37.22898) (xy 370.771427 -37.284156) (xy 370.755359 -37.337563) (xy 370.731687 -37.38806)
			(xy 370.700914 -37.434573) (xy 370.663697 -37.47611) (xy 370.620829 -37.511785) (xy 370.573223 -37.540839)
			(xy 370.521894 -37.562651) (xy 370.467937 -37.576757) (xy 370.4125 -37.582857) (xy 370.356766 -37.58082)
			(xy 370.301923 -37.57069) (xy 370.249139 -37.552683) (xy 370.199539 -37.527182) (xy 370.154181 -37.494731)
			(xy 370.114032 -37.456022) (xy 370.079946 -37.411879) (xy 370.05265 -37.363244) (xy 370.032727 -37.311153)
			(xy 370.020601 -37.256716) (xy 370.01653 -37.201094) (xy 366.707228 -37.201094) (xy 366.743594 -37.241681)
			(xy 366.774367 -37.288194) (xy 366.798039 -37.338691) (xy 366.814107 -37.392098) (xy 366.822227 -37.447274)
			(xy 366.822736 -37.47516) (xy 366.822227 -37.503046) (xy 366.814107 -37.558222) (xy 366.798039 -37.611629)
			(xy 366.774367 -37.662126) (xy 366.774214 -37.662358) (xy 368.248436 -37.662358) (xy 368.252507 -37.606736)
			(xy 368.264633 -37.552299) (xy 368.284556 -37.500208) (xy 368.311852 -37.451573) (xy 368.345938 -37.40743)
			(xy 368.386087 -37.368721) (xy 368.431445 -37.33627) (xy 368.481045 -37.310769) (xy 368.533829 -37.292762)
			(xy 368.588672 -37.282632) (xy 368.644406 -37.280595) (xy 368.699843 -37.286695) (xy 368.7538 -37.300801)
			(xy 368.805129 -37.322613) (xy 368.852735 -37.351667) (xy 368.895603 -37.387342) (xy 368.93282 -37.428879)
			(xy 368.963593 -37.475392) (xy 368.987265 -37.525889) (xy 369.003333 -37.579296) (xy 369.011453 -37.634472)
			(xy 369.011962 -37.662358) (xy 369.011453 -37.690244) (xy 369.003333 -37.74542) (xy 368.987265 -37.798827)
			(xy 368.963593 -37.849324) (xy 368.93282 -37.895837) (xy 368.895603 -37.937374) (xy 368.852735 -37.973049)
			(xy 368.805129 -38.002103) (xy 368.7538 -38.023915) (xy 368.699843 -38.038021) (xy 368.644406 -38.044121)
			(xy 368.588672 -38.042084) (xy 368.533829 -38.031954) (xy 368.481045 -38.013947) (xy 368.431445 -37.988446)
			(xy 368.386087 -37.955995) (xy 368.345938 -37.917286) (xy 368.311852 -37.873143) (xy 368.284556 -37.824508)
			(xy 368.264633 -37.772417) (xy 368.252507 -37.71798) (xy 368.248436 -37.662358) (xy 366.774214 -37.662358)
			(xy 366.743594 -37.708639) (xy 366.706377 -37.750176) (xy 366.663509 -37.785851) (xy 366.615903 -37.814905)
			(xy 366.564574 -37.836717) (xy 366.510617 -37.850823) (xy 366.45518 -37.856923) (xy 366.399446 -37.854886)
			(xy 366.344603 -37.844756) (xy 366.291819 -37.826749) (xy 366.242219 -37.801248) (xy 366.196861 -37.768797)
			(xy 366.156712 -37.730088) (xy 366.122626 -37.685945) (xy 366.09533 -37.63731) (xy 366.075407 -37.585219)
			(xy 366.063281 -37.530782) (xy 366.05921 -37.47516) (xy 362.84654 -37.47516) (xy 362.857198 -37.484876)
			(xy 362.915732 -37.549082) (xy 362.968092 -37.618416) (xy 363.013831 -37.692285) (xy 363.052559 -37.770059)
			(xy 363.083946 -37.851075) (xy 363.107723 -37.934642) (xy 363.123689 -38.020046) (xy 363.131705 -38.106558)
			(xy 363.131705 -38.193442) (xy 363.123689 -38.279954) (xy 363.107723 -38.365358) (xy 363.083946 -38.448925)
			(xy 363.067583 -38.49116) (xy 366.05921 -38.49116) (xy 366.063281 -38.435538) (xy 366.075407 -38.381101)
			(xy 366.09533 -38.32901) (xy 366.122626 -38.280375) (xy 366.156712 -38.236232) (xy 366.196861 -38.197523)
			(xy 366.242219 -38.165072) (xy 366.291819 -38.139571) (xy 366.344603 -38.121564) (xy 366.399446 -38.111434)
			(xy 366.45518 -38.109397) (xy 366.510617 -38.115497) (xy 366.564574 -38.129603) (xy 366.615903 -38.151415)
			(xy 366.663509 -38.180469) (xy 366.706377 -38.216144) (xy 366.743594 -38.257681) (xy 366.774367 -38.304194)
			(xy 366.779497 -38.315138) (xy 380.718058 -38.315138) (xy 380.722129 -38.259516) (xy 380.734255 -38.205079)
			(xy 380.754178 -38.152988) (xy 380.781474 -38.104353) (xy 380.81556 -38.06021) (xy 380.855709 -38.021501)
			(xy 380.901067 -37.98905) (xy 380.950667 -37.963549) (xy 381.003451 -37.945542) (xy 381.058294 -37.935412)
			(xy 381.114028 -37.933375) (xy 381.169465 -37.939475) (xy 381.223422 -37.953581) (xy 381.274751 -37.975393)
			(xy 381.322357 -38.004447) (xy 381.365225 -38.040122) (xy 381.402442 -38.081659) (xy 381.433215 -38.128172)
			(xy 381.456887 -38.178669) (xy 381.46133 -38.193437) (xy 385.398271 -38.193437) (xy 385.398271 -38.106563)
			(xy 385.406286 -38.020059) (xy 385.42225 -37.934663) (xy 385.446024 -37.851105) (xy 385.477407 -37.770097)
			(xy 385.516131 -37.69233) (xy 385.561865 -37.618467) (xy 385.614219 -37.54914) (xy 385.672746 -37.484939)
			(xy 385.736948 -37.426412) (xy 385.806276 -37.374059) (xy 385.880138 -37.328326) (xy 385.957906 -37.289603)
			(xy 386.038914 -37.258221) (xy 386.122473 -37.234447) (xy 386.207868 -37.218485) (xy 386.294373 -37.21047)
			(xy 386.33781 -37.209984) (xy 386.415788 -37.209984) (xy 386.425811 -37.20957) (xy 386.44433 -37.201901)
			(xy 386.458504 -37.187727) (xy 386.466171 -37.169207) (xy 386.466588 -37.159184) (xy 386.466588 -37.151564)
			(xy 386.46227 -37.137594) (xy 386.458206 -37.131244) (xy 386.434287 -37.094009) (xy 386.392586 -37.015944)
			(xy 386.358201 -36.93439) (xy 386.331423 -36.850033) (xy 386.312474 -36.76358) (xy 386.301514 -36.675755)
			(xy 386.298636 -36.587297) (xy 386.303863 -36.498946) (xy 386.317151 -36.411443) (xy 386.338389 -36.325524)
			(xy 386.367398 -36.241908) (xy 386.403936 -36.161296) (xy 386.447697 -36.084366) (xy 386.498311 -36.011762)
			(xy 386.555357 -35.944093) (xy 386.618354 -35.881927) (xy 386.686774 -35.825786) (xy 386.760044 -35.776139)
			(xy 386.837549 -35.733405) (xy 386.918638 -35.69794) (xy 387.002632 -35.670044) (xy 387.088826 -35.649948)
			(xy 387.176497 -35.637824) (xy 387.26491 -35.633771) (xy 387.353323 -35.637824) (xy 387.440994 -35.649948)
			(xy 387.527188 -35.670044) (xy 387.611182 -35.69794) (xy 387.692271 -35.733405) (xy 387.769776 -35.776139)
			(xy 387.843046 -35.825786) (xy 387.905142 -35.876738) (xy 393.017246 -35.876738) (xy 393.021317 -35.821116)
			(xy 393.033443 -35.766679) (xy 393.053366 -35.714588) (xy 393.080662 -35.665953) (xy 393.114748 -35.62181)
			(xy 393.154897 -35.583101) (xy 393.200255 -35.55065) (xy 393.249855 -35.525149) (xy 393.302639 -35.507142)
			(xy 393.357482 -35.497012) (xy 393.413216 -35.494975) (xy 393.468653 -35.501075) (xy 393.52261 -35.515181)
			(xy 393.573939 -35.536993) (xy 393.621545 -35.566047) (xy 393.664413 -35.601722) (xy 393.70163 -35.643259)
			(xy 393.732403 -35.689772) (xy 393.756075 -35.740269) (xy 393.772143 -35.793676) (xy 393.780263 -35.848852)
			(xy 393.780772 -35.876738) (xy 397.088866 -35.876738) (xy 397.092937 -35.821116) (xy 397.105063 -35.766679)
			(xy 397.124986 -35.714588) (xy 397.152282 -35.665953) (xy 397.186368 -35.62181) (xy 397.226517 -35.583101)
			(xy 397.271875 -35.55065) (xy 397.321475 -35.525149) (xy 397.374259 -35.507142) (xy 397.429102 -35.497012)
			(xy 397.484836 -35.494975) (xy 397.540273 -35.501075) (xy 397.59423 -35.515181) (xy 397.645559 -35.536993)
			(xy 397.693165 -35.566047) (xy 397.736033 -35.601722) (xy 397.77325 -35.643259) (xy 397.804023 -35.689772)
			(xy 397.827695 -35.740269) (xy 397.843763 -35.793676) (xy 397.851883 -35.848852) (xy 397.852392 -35.876738)
			(xy 397.851883 -35.904624) (xy 397.843763 -35.9598) (xy 397.827695 -36.013207) (xy 397.804023 -36.063704)
			(xy 397.77325 -36.110217) (xy 397.736033 -36.151754) (xy 397.693165 -36.187429) (xy 397.645559 -36.216483)
			(xy 397.59423 -36.238295) (xy 397.540273 -36.252401) (xy 397.484836 -36.258501) (xy 397.429102 -36.256464)
			(xy 397.374259 -36.246334) (xy 397.321475 -36.228327) (xy 397.271875 -36.202826) (xy 397.226517 -36.170375)
			(xy 397.186368 -36.131666) (xy 397.152282 -36.087523) (xy 397.124986 -36.038888) (xy 397.105063 -35.986797)
			(xy 397.092937 -35.93236) (xy 397.088866 -35.876738) (xy 393.780772 -35.876738) (xy 393.780263 -35.904624)
			(xy 393.772143 -35.9598) (xy 393.756075 -36.013207) (xy 393.732403 -36.063704) (xy 393.70163 -36.110217)
			(xy 393.664413 -36.151754) (xy 393.621545 -36.187429) (xy 393.573939 -36.216483) (xy 393.52261 -36.238295)
			(xy 393.468653 -36.252401) (xy 393.413216 -36.258501) (xy 393.357482 -36.256464) (xy 393.302639 -36.246334)
			(xy 393.249855 -36.228327) (xy 393.200255 -36.202826) (xy 393.154897 -36.170375) (xy 393.114748 -36.131666)
			(xy 393.080662 -36.087523) (xy 393.053366 -36.038888) (xy 393.033443 -35.986797) (xy 393.021317 -35.93236)
			(xy 393.017246 -35.876738) (xy 387.905142 -35.876738) (xy 387.911466 -35.881927) (xy 387.974463 -35.944093)
			(xy 388.031509 -36.011762) (xy 388.082123 -36.084366) (xy 388.125884 -36.161296) (xy 388.162422 -36.241908)
			(xy 388.191431 -36.325524) (xy 388.212669 -36.411443) (xy 388.225957 -36.498946) (xy 388.226609 -36.50996)
			(xy 394.913864 -36.50996) (xy 394.917935 -36.454338) (xy 394.930061 -36.399901) (xy 394.949984 -36.34781)
			(xy 394.97728 -36.299175) (xy 395.011366 -36.255032) (xy 395.051515 -36.216323) (xy 395.096873 -36.183872)
			(xy 395.146473 -36.158371) (xy 395.199257 -36.140364) (xy 395.2541 -36.130234) (xy 395.309834 -36.128197)
			(xy 395.365271 -36.134297) (xy 395.419228 -36.148403) (xy 395.470557 -36.170215) (xy 395.518163 -36.199269)
			(xy 395.561031 -36.234944) (xy 395.598248 -36.276481) (xy 395.629021 -36.322994) (xy 395.652693 -36.373491)
			(xy 395.668761 -36.426898) (xy 395.672686 -36.453572) (xy 398.228564 -36.453572) (xy 398.232635 -36.39795)
			(xy 398.244761 -36.343513) (xy 398.264684 -36.291422) (xy 398.29198 -36.242787) (xy 398.326066 -36.198644)
			(xy 398.366215 -36.159935) (xy 398.411573 -36.127484) (xy 398.461173 -36.101983) (xy 398.513957 -36.083976)
			(xy 398.5688 -36.073846) (xy 398.624534 -36.071809) (xy 398.679971 -36.077909) (xy 398.733928 -36.092015)
			(xy 398.785257 -36.113827) (xy 398.832863 -36.142881) (xy 398.875731 -36.178556) (xy 398.912948 -36.220093)
			(xy 398.943721 -36.266606) (xy 398.967393 -36.317103) (xy 398.983461 -36.37051) (xy 398.991581 -36.425686)
			(xy 398.99209 -36.453572) (xy 398.991581 -36.481458) (xy 398.983461 -36.536634) (xy 398.967393 -36.590041)
			(xy 398.943721 -36.640538) (xy 398.912948 -36.687051) (xy 398.875731 -36.728588) (xy 398.832863 -36.764263)
			(xy 398.785257 -36.793317) (xy 398.733928 -36.815129) (xy 398.679971 -36.829235) (xy 398.624534 -36.835335)
			(xy 398.5688 -36.833298) (xy 398.513957 -36.823168) (xy 398.461173 -36.805161) (xy 398.411573 -36.77966)
			(xy 398.366215 -36.747209) (xy 398.326066 -36.7085) (xy 398.29198 -36.664357) (xy 398.264684 -36.615722)
			(xy 398.244761 -36.563631) (xy 398.232635 -36.509194) (xy 398.228564 -36.453572) (xy 395.672686 -36.453572)
			(xy 395.676881 -36.482074) (xy 395.67739 -36.50996) (xy 395.676881 -36.537846) (xy 395.668761 -36.593022)
			(xy 395.652693 -36.646429) (xy 395.629021 -36.696926) (xy 395.598248 -36.743439) (xy 395.561031 -36.784976)
			(xy 395.518163 -36.820651) (xy 395.470557 -36.849705) (xy 395.419228 -36.871517) (xy 395.365271 -36.885623)
			(xy 395.309834 -36.891723) (xy 395.2541 -36.889686) (xy 395.199257 -36.879556) (xy 395.146473 -36.861549)
			(xy 395.096873 -36.836048) (xy 395.051515 -36.803597) (xy 395.011366 -36.764888) (xy 394.97728 -36.720745)
			(xy 394.949984 -36.67211) (xy 394.930061 -36.620019) (xy 394.917935 -36.565582) (xy 394.913864 -36.50996)
			(xy 388.226609 -36.50996) (xy 388.231184 -36.587297) (xy 388.228306 -36.675755) (xy 388.217346 -36.76358)
			(xy 388.198397 -36.850033) (xy 388.171619 -36.93439) (xy 388.137234 -37.015944) (xy 388.095533 -37.094009)
			(xy 388.071614 -37.131244) (xy 388.06755 -37.137594) (xy 388.063232 -37.151564) (xy 388.063232 -37.159184)
			(xy 388.063633 -37.169208) (xy 388.071304 -37.187731) (xy 388.085482 -37.201905) (xy 388.104008 -37.20957)
			(xy 388.114032 -37.209984) (xy 388.19201 -37.209984) (xy 388.23545 -37.21041) (xy 388.321958 -37.218427)
			(xy 388.407358 -37.234392) (xy 388.49092 -37.258168) (xy 388.571932 -37.289553) (xy 388.649703 -37.328279)
			(xy 388.723569 -37.374016) (xy 388.7929 -37.426373) (xy 388.846416 -37.47516) (xy 392.059158 -37.47516)
			(xy 392.063229 -37.419538) (xy 392.075355 -37.365101) (xy 392.095278 -37.31301) (xy 392.122574 -37.264375)
			(xy 392.15666 -37.220232) (xy 392.196809 -37.181523) (xy 392.242167 -37.149072) (xy 392.291767 -37.123571)
			(xy 392.344551 -37.105564) (xy 392.399394 -37.095434) (xy 392.455128 -37.093397) (xy 392.510565 -37.099497)
			(xy 392.564522 -37.113603) (xy 392.615851 -37.135415) (xy 392.663457 -37.164469) (xy 392.706325 -37.200144)
			(xy 392.707176 -37.201094) (xy 396.016478 -37.201094) (xy 396.020549 -37.145472) (xy 396.032675 -37.091035)
			(xy 396.052598 -37.038944) (xy 396.079894 -36.990309) (xy 396.11398 -36.946166) (xy 396.154129 -36.907457)
			(xy 396.199487 -36.875006) (xy 396.249087 -36.849505) (xy 396.301871 -36.831498) (xy 396.356714 -36.821368)
			(xy 396.412448 -36.819331) (xy 396.467885 -36.825431) (xy 396.521842 -36.839537) (xy 396.573171 -36.861349)
			(xy 396.620777 -36.890403) (xy 396.663645 -36.926078) (xy 396.700862 -36.967615) (xy 396.731635 -37.014128)
			(xy 396.755307 -37.064625) (xy 396.762053 -37.087048) (xy 405.50084 -37.087048) (xy 405.501308 -37.060444)
			(xy 405.508684 -37.007751) (xy 405.523313 -36.956595) (xy 405.544913 -36.90797) (xy 405.573062 -36.862819)
			(xy 405.607214 -36.82202) (xy 405.646706 -36.786365) (xy 405.66848 -36.771072) (xy 405.678403 -36.76354)
			(xy 405.690132 -36.741598) (xy 405.690832 -36.729162) (xy 405.690832 -36.644834) (xy 405.690162 -36.632384)
			(xy 405.678451 -36.610408) (xy 405.66848 -36.602924) (xy 405.646721 -36.587613) (xy 405.60724 -36.551951)
			(xy 405.573094 -36.511151) (xy 405.544947 -36.466004) (xy 405.523343 -36.417384) (xy 405.5087 -36.366236)
			(xy 405.501304 -36.313549) (xy 405.50084 -36.286948) (xy 405.5013 -36.259694) (xy 405.509052 -36.205741)
			(xy 405.524404 -36.15344) (xy 405.547045 -36.103857) (xy 405.576512 -36.058001) (xy 405.612206 -36.016806)
			(xy 405.653401 -35.981112) (xy 405.699257 -35.951645) (xy 405.74884 -35.929004) (xy 405.801141 -35.913652)
			(xy 405.855094 -35.9059) (xy 405.882348 -35.90544) (xy 405.88692 -35.90544) (xy 405.896129 -35.905163)
			(xy 405.913448 -35.898926) (xy 405.920702 -35.893248) (xy 405.971502 -35.84956) (xy 405.978207 -35.843323)
			(xy 405.987067 -35.827314) (xy 405.988774 -35.818318) (xy 405.988774 -35.818064) (xy 405.993129 -35.791135)
			(xy 406.008439 -35.73878) (xy 406.03105 -35.689139) (xy 406.0605 -35.643224) (xy 406.09619 -35.601972)
			(xy 406.137391 -35.566224) (xy 406.183264 -35.536709) (xy 406.232873 -35.514028) (xy 406.285207 -35.498644)
			(xy 406.339198 -35.490871) (xy 406.366472 -35.490404) (xy 406.393727 -35.490841) (xy 406.447683 -35.498595)
			(xy 406.499986 -35.513949) (xy 406.549571 -35.536591) (xy 406.595429 -35.566059) (xy 406.636626 -35.601754)
			(xy 406.672324 -35.642948) (xy 406.701796 -35.688804) (xy 406.724441 -35.738388) (xy 406.739799 -35.79069)
			(xy 406.747557 -35.844645) (xy 406.747557 -35.899155) (xy 406.739799 -35.95311) (xy 406.724441 -36.005412)
			(xy 406.701796 -36.054996) (xy 406.672324 -36.100852) (xy 406.636626 -36.142046) (xy 406.595429 -36.177741)
			(xy 406.549571 -36.207209) (xy 406.499986 -36.229851) (xy 406.447683 -36.245205) (xy 406.393727 -36.252959)
			(xy 406.366472 -36.25342) (xy 406.3619 -36.25342) (xy 406.352686 -36.253644) (xy 406.335367 -36.259917)
			(xy 406.328118 -36.265612) (xy 406.277318 -36.3093) (xy 406.270595 -36.315521) (xy 406.261745 -36.331541)
			(xy 406.260046 -36.340542) (xy 406.260046 -36.340796) (xy 406.255851 -36.367) (xy 406.241166 -36.417994)
			(xy 406.219553 -36.46646) (xy 406.191428 -36.511461) (xy 406.188002 -36.515548) (xy 407.314144 -36.515548)
			(xy 407.318215 -36.459926) (xy 407.330341 -36.405489) (xy 407.350264 -36.353398) (xy 407.37756 -36.304763)
			(xy 407.411646 -36.26062) (xy 407.451795 -36.221911) (xy 407.497153 -36.18946) (xy 407.546753 -36.163959)
			(xy 407.599537 -36.145952) (xy 407.65438 -36.135822) (xy 407.710114 -36.133785) (xy 407.765551 -36.139885)
			(xy 407.819508 -36.153991) (xy 407.870837 -36.175803) (xy 407.918443 -36.204857) (xy 407.961311 -36.240532)
			(xy 407.998528 -36.282069) (xy 408.029301 -36.328582) (xy 408.052973 -36.379079) (xy 408.069041 -36.432486)
			(xy 408.077161 -36.487662) (xy 408.07767 -36.515548) (xy 408.077161 -36.543434) (xy 408.069041 -36.59861)
			(xy 408.052973 -36.652017) (xy 408.029301 -36.702514) (xy 407.998528 -36.749027) (xy 407.961311 -36.790564)
			(xy 407.918443 -36.826239) (xy 407.870837 -36.855293) (xy 407.819508 -36.877105) (xy 407.765551 -36.891211)
			(xy 407.710114 -36.897311) (xy 407.65438 -36.895274) (xy 407.599537 -36.885144) (xy 407.546753 -36.867137)
			(xy 407.497153 -36.841636) (xy 407.451795 -36.809185) (xy 407.411646 -36.770476) (xy 407.37756 -36.726333)
			(xy 407.350264 -36.677698) (xy 407.330341 -36.625607) (xy 407.318215 -36.57117) (xy 407.314144 -36.515548)
			(xy 406.188002 -36.515548) (xy 406.157336 -36.552128) (xy 406.117934 -36.587675) (xy 406.096216 -36.602924)
			(xy 406.086294 -36.610457) (xy 406.074565 -36.632399) (xy 406.073864 -36.644834) (xy 406.073864 -36.729162)
			(xy 406.074538 -36.741612) (xy 406.086246 -36.763588) (xy 406.096216 -36.771072) (xy 406.117972 -36.786386)
			(xy 406.157454 -36.822048) (xy 406.191599 -36.862847) (xy 406.219747 -36.907994) (xy 406.241352 -36.956613)
			(xy 406.255995 -37.007761) (xy 406.263391 -37.060447) (xy 406.263856 -37.087048) (xy 406.263856 -37.087302)
			(xy 406.263239 -37.119019) (xy 406.252737 -37.181577) (xy 406.232009 -37.241528) (xy 406.217374 -37.269674)
			(xy 406.21204 -37.27958) (xy 406.210516 -37.301678) (xy 406.24252 -37.384482) (xy 406.247017 -37.394566)
			(xy 406.262802 -37.40997) (xy 406.273 -37.4142) (xy 406.297533 -37.423266) (xy 406.344063 -37.447149)
			(xy 406.386895 -37.477165) (xy 406.425223 -37.512751) (xy 406.458331 -37.55324) (xy 406.485597 -37.597872)
			(xy 406.50651 -37.645811) (xy 406.520678 -37.696157) (xy 406.527834 -37.747967) (xy 406.52827 -37.774118)
			(xy 406.527784 -37.801369) (xy 406.520028 -37.855317) (xy 406.504673 -37.907612) (xy 406.482031 -37.957189)
			(xy 406.452565 -38.003039) (xy 406.416874 -38.04423) (xy 406.375683 -38.079921) (xy 406.329833 -38.109387)
			(xy 406.280256 -38.132029) (xy 406.227961 -38.147384) (xy 406.174013 -38.15514) (xy 406.119511 -38.15514)
			(xy 406.065563 -38.147384) (xy 406.013268 -38.132029) (xy 405.963691 -38.109387) (xy 405.917841 -38.079921)
			(xy 405.87665 -38.04423) (xy 405.840959 -38.003039) (xy 405.811493 -37.957189) (xy 405.788851 -37.907612)
			(xy 405.773496 -37.855317) (xy 405.76574 -37.801369) (xy 405.765254 -37.774118) (xy 405.765254 -37.773864)
			(xy 405.765856 -37.742146) (xy 405.776364 -37.679588) (xy 405.797098 -37.619637) (xy 405.811736 -37.591492)
			(xy 405.81707 -37.581586) (xy 405.818594 -37.559488) (xy 405.78659 -37.476684) (xy 405.782144 -37.466572)
			(xy 405.766323 -37.451181) (xy 405.75611 -37.446966) (xy 405.731568 -37.437923) (xy 405.685036 -37.414038)
			(xy 405.642204 -37.38402) (xy 405.603874 -37.348431) (xy 405.570767 -37.307939) (xy 405.543502 -37.263304)
			(xy 405.522591 -37.215362) (xy 405.508427 -37.165012) (xy 405.501274 -37.1132) (xy 405.50084 -37.087048)
			(xy 396.762053 -37.087048) (xy 396.771375 -37.118032) (xy 396.779495 -37.173208) (xy 396.780004 -37.201094)
			(xy 396.779495 -37.22898) (xy 396.771375 -37.284156) (xy 396.755307 -37.337563) (xy 396.731635 -37.38806)
			(xy 396.700862 -37.434573) (xy 396.663645 -37.47611) (xy 396.620777 -37.511785) (xy 396.573171 -37.540839)
			(xy 396.521842 -37.562651) (xy 396.467885 -37.576757) (xy 396.412448 -37.582857) (xy 396.356714 -37.58082)
			(xy 396.301871 -37.57069) (xy 396.249087 -37.552683) (xy 396.199487 -37.527182) (xy 396.154129 -37.494731)
			(xy 396.11398 -37.456022) (xy 396.079894 -37.411879) (xy 396.052598 -37.363244) (xy 396.032675 -37.311153)
			(xy 396.020549 -37.256716) (xy 396.016478 -37.201094) (xy 392.707176 -37.201094) (xy 392.743542 -37.241681)
			(xy 392.774315 -37.288194) (xy 392.797987 -37.338691) (xy 392.814055 -37.392098) (xy 392.822175 -37.447274)
			(xy 392.822684 -37.47516) (xy 392.822175 -37.503046) (xy 392.814055 -37.558222) (xy 392.797987 -37.611629)
			(xy 392.774315 -37.662126) (xy 392.774162 -37.662358) (xy 394.248384 -37.662358) (xy 394.252455 -37.606736)
			(xy 394.264581 -37.552299) (xy 394.284504 -37.500208) (xy 394.3118 -37.451573) (xy 394.345886 -37.40743)
			(xy 394.386035 -37.368721) (xy 394.431393 -37.33627) (xy 394.480993 -37.310769) (xy 394.533777 -37.292762)
			(xy 394.58862 -37.282632) (xy 394.644354 -37.280595) (xy 394.699791 -37.286695) (xy 394.753748 -37.300801)
			(xy 394.805077 -37.322613) (xy 394.852683 -37.351667) (xy 394.895551 -37.387342) (xy 394.932768 -37.428879)
			(xy 394.963541 -37.475392) (xy 394.987213 -37.525889) (xy 395.003281 -37.579296) (xy 395.011401 -37.634472)
			(xy 395.01191 -37.662358) (xy 395.011401 -37.690244) (xy 395.003281 -37.74542) (xy 394.987213 -37.798827)
			(xy 394.963541 -37.849324) (xy 394.932768 -37.895837) (xy 394.895551 -37.937374) (xy 394.852683 -37.973049)
			(xy 394.805077 -38.002103) (xy 394.753748 -38.023915) (xy 394.699791 -38.038021) (xy 394.644354 -38.044121)
			(xy 394.58862 -38.042084) (xy 394.533777 -38.031954) (xy 394.480993 -38.013947) (xy 394.431393 -37.988446)
			(xy 394.386035 -37.955995) (xy 394.345886 -37.917286) (xy 394.3118 -37.873143) (xy 394.284504 -37.824508)
			(xy 394.264581 -37.772417) (xy 394.252455 -37.71798) (xy 394.248384 -37.662358) (xy 392.774162 -37.662358)
			(xy 392.743542 -37.708639) (xy 392.706325 -37.750176) (xy 392.663457 -37.785851) (xy 392.615851 -37.814905)
			(xy 392.564522 -37.836717) (xy 392.510565 -37.850823) (xy 392.455128 -37.856923) (xy 392.399394 -37.854886)
			(xy 392.344551 -37.844756) (xy 392.291767 -37.826749) (xy 392.242167 -37.801248) (xy 392.196809 -37.768797)
			(xy 392.15666 -37.730088) (xy 392.122574 -37.685945) (xy 392.095278 -37.63731) (xy 392.075355 -37.585219)
			(xy 392.063229 -37.530782) (xy 392.059158 -37.47516) (xy 388.846416 -37.47516) (xy 388.857104 -37.484903)
			(xy 388.915634 -37.549108) (xy 388.96799 -37.618439) (xy 389.013726 -37.692306) (xy 389.052451 -37.770077)
			(xy 389.083835 -37.851089) (xy 389.10761 -37.934652) (xy 389.123574 -38.020052) (xy 389.13159 -38.10656)
			(xy 389.13159 -38.19344) (xy 389.123574 -38.279948) (xy 389.10761 -38.365348) (xy 389.083835 -38.448911)
			(xy 389.067468 -38.49116) (xy 392.059158 -38.49116) (xy 392.063229 -38.435538) (xy 392.075355 -38.381101)
			(xy 392.095278 -38.32901) (xy 392.122574 -38.280375) (xy 392.15666 -38.236232) (xy 392.196809 -38.197523)
			(xy 392.242167 -38.165072) (xy 392.291767 -38.139571) (xy 392.344551 -38.121564) (xy 392.399394 -38.111434)
			(xy 392.455128 -38.109397) (xy 392.510565 -38.115497) (xy 392.564522 -38.129603) (xy 392.615851 -38.151415)
			(xy 392.663457 -38.180469) (xy 392.706325 -38.216144) (xy 392.743542 -38.257681) (xy 392.774315 -38.304194)
			(xy 392.779445 -38.315138) (xy 406.718006 -38.315138) (xy 406.722077 -38.259516) (xy 406.734203 -38.205079)
			(xy 406.754126 -38.152988) (xy 406.781422 -38.104353) (xy 406.815508 -38.06021) (xy 406.855657 -38.021501)
			(xy 406.901015 -37.98905) (xy 406.950615 -37.963549) (xy 407.003399 -37.945542) (xy 407.058242 -37.935412)
			(xy 407.113976 -37.933375) (xy 407.169413 -37.939475) (xy 407.22337 -37.953581) (xy 407.274699 -37.975393)
			(xy 407.322305 -38.004447) (xy 407.365173 -38.040122) (xy 407.40239 -38.081659) (xy 407.433163 -38.128172)
			(xy 407.456835 -38.178669) (xy 407.461277 -38.193435) (xy 411.398285 -38.193435) (xy 411.398285 -38.106565)
			(xy 411.406301 -38.020065) (xy 411.422263 -37.934674) (xy 411.446035 -37.85112) (xy 411.477415 -37.770115)
			(xy 411.516136 -37.692352) (xy 411.561866 -37.618492) (xy 411.614216 -37.549167) (xy 411.672738 -37.484968)
			(xy 411.736935 -37.426443) (xy 411.806258 -37.37409) (xy 411.880115 -37.328356) (xy 411.957877 -37.289632)
			(xy 412.03888 -37.258248) (xy 412.122433 -37.234472) (xy 412.207824 -37.218506) (xy 412.294323 -37.210487)
			(xy 412.337758 -37.209984) (xy 412.415736 -37.209984) (xy 412.425748 -37.209541) (xy 412.444244 -37.201867)
			(xy 412.458396 -37.1877) (xy 412.466051 -37.169196) (xy 412.466536 -37.159184) (xy 412.466536 -37.151564)
			(xy 412.462218 -37.137594) (xy 412.458154 -37.131244) (xy 412.434754 -37.094768) (xy 412.393762 -37.018407)
			(xy 412.359777 -36.938681) (xy 412.333071 -36.856231) (xy 412.313861 -36.771719) (xy 412.3023 -36.685826)
			(xy 412.298481 -36.599243) (xy 412.302436 -36.512665) (xy 412.314131 -36.42679) (xy 412.333474 -36.342309)
			(xy 412.360309 -36.2599) (xy 412.394419 -36.180228) (xy 412.43553 -36.103931) (xy 412.483312 -36.031626)
			(xy 412.537381 -35.963892) (xy 412.597301 -35.901275) (xy 412.66259 -35.844278) (xy 412.732723 -35.793361)
			(xy 412.807136 -35.748932) (xy 412.885231 -35.711349) (xy 412.966379 -35.680915) (xy 413.049928 -35.657873)
			(xy 413.135205 -35.642411) (xy 413.221524 -35.634651) (xy 413.264858 -35.634168) (xy 413.265112 -35.634168)
			(xy 413.308444 -35.634637) (xy 413.394759 -35.64241) (xy 413.48003 -35.657885) (xy 413.563572 -35.680936)
			(xy 413.644713 -35.711379) (xy 413.722801 -35.748968) (xy 413.797207 -35.793401) (xy 413.867334 -35.844322)
			(xy 413.904462 -35.876738) (xy 419.017194 -35.876738) (xy 419.021265 -35.821116) (xy 419.033391 -35.766679)
			(xy 419.053314 -35.714588) (xy 419.08061 -35.665953) (xy 419.114696 -35.62181) (xy 419.154845 -35.583101)
			(xy 419.200203 -35.55065) (xy 419.249803 -35.525149) (xy 419.302587 -35.507142) (xy 419.35743 -35.497012)
			(xy 419.413164 -35.494975) (xy 419.468601 -35.501075) (xy 419.522558 -35.515181) (xy 419.573887 -35.536993)
			(xy 419.621493 -35.566047) (xy 419.664361 -35.601722) (xy 419.701578 -35.643259) (xy 419.732351 -35.689772)
			(xy 419.756023 -35.740269) (xy 419.772091 -35.793676) (xy 419.780211 -35.848852) (xy 419.78072 -35.876738)
			(xy 423.088814 -35.876738) (xy 423.092885 -35.821116) (xy 423.105011 -35.766679) (xy 423.124934 -35.714588)
			(xy 423.15223 -35.665953) (xy 423.186316 -35.62181) (xy 423.226465 -35.583101) (xy 423.271823 -35.55065)
			(xy 423.321423 -35.525149) (xy 423.374207 -35.507142) (xy 423.42905 -35.497012) (xy 423.484784 -35.494975)
			(xy 423.540221 -35.501075) (xy 423.594178 -35.515181) (xy 423.645507 -35.536993) (xy 423.693113 -35.566047)
			(xy 423.735981 -35.601722) (xy 423.773198 -35.643259) (xy 423.803971 -35.689772) (xy 423.827643 -35.740269)
			(xy 423.843711 -35.793676) (xy 423.851831 -35.848852) (xy 423.85234 -35.876738) (xy 423.851831 -35.904624)
			(xy 423.843711 -35.9598) (xy 423.827643 -36.013207) (xy 423.803971 -36.063704) (xy 423.773198 -36.110217)
			(xy 423.735981 -36.151754) (xy 423.693113 -36.187429) (xy 423.645507 -36.216483) (xy 423.594178 -36.238295)
			(xy 423.540221 -36.252401) (xy 423.484784 -36.258501) (xy 423.42905 -36.256464) (xy 423.374207 -36.246334)
			(xy 423.321423 -36.228327) (xy 423.271823 -36.202826) (xy 423.226465 -36.170375) (xy 423.186316 -36.131666)
			(xy 423.15223 -36.087523) (xy 423.124934 -36.038888) (xy 423.105011 -35.986797) (xy 423.092885 -35.93236)
			(xy 423.088814 -35.876738) (xy 419.78072 -35.876738) (xy 419.780211 -35.904624) (xy 419.772091 -35.9598)
			(xy 419.756023 -36.013207) (xy 419.732351 -36.063704) (xy 419.701578 -36.110217) (xy 419.664361 -36.151754)
			(xy 419.621493 -36.187429) (xy 419.573887 -36.216483) (xy 419.522558 -36.238295) (xy 419.468601 -36.252401)
			(xy 419.413164 -36.258501) (xy 419.35743 -36.256464) (xy 419.302587 -36.246334) (xy 419.249803 -36.228327)
			(xy 419.200203 -36.202826) (xy 419.154845 -36.170375) (xy 419.114696 -36.131666) (xy 419.08061 -36.087523)
			(xy 419.053314 -36.038888) (xy 419.033391 -35.986797) (xy 419.021265 -35.93236) (xy 419.017194 -35.876738)
			(xy 413.904462 -35.876738) (xy 413.932617 -35.90132) (xy 413.992532 -35.963936) (xy 414.046597 -36.031669)
			(xy 414.094376 -36.103972) (xy 414.135486 -36.180265) (xy 414.169596 -36.259934) (xy 414.196432 -36.342338)
			(xy 414.215778 -36.426815) (xy 414.227108 -36.50996) (xy 420.913812 -36.50996) (xy 420.917883 -36.454338)
			(xy 420.930009 -36.399901) (xy 420.949932 -36.34781) (xy 420.977228 -36.299175) (xy 421.011314 -36.255032)
			(xy 421.051463 -36.216323) (xy 421.096821 -36.183872) (xy 421.146421 -36.158371) (xy 421.199205 -36.140364)
			(xy 421.254048 -36.130234) (xy 421.309782 -36.128197) (xy 421.365219 -36.134297) (xy 421.419176 -36.148403)
			(xy 421.470505 -36.170215) (xy 421.518111 -36.199269) (xy 421.560979 -36.234944) (xy 421.598196 -36.276481)
			(xy 421.628969 -36.322994) (xy 421.652641 -36.373491) (xy 421.668709 -36.426898) (xy 421.672634 -36.453572)
			(xy 424.228512 -36.453572) (xy 424.232583 -36.39795) (xy 424.244709 -36.343513) (xy 424.264632 -36.291422)
			(xy 424.291928 -36.242787) (xy 424.326014 -36.198644) (xy 424.366163 -36.159935) (xy 424.411521 -36.127484)
			(xy 424.461121 -36.101983) (xy 424.513905 -36.083976) (xy 424.568748 -36.073846) (xy 424.624482 -36.071809)
			(xy 424.679919 -36.077909) (xy 424.733876 -36.092015) (xy 424.785205 -36.113827) (xy 424.832811 -36.142881)
			(xy 424.875679 -36.178556) (xy 424.912896 -36.220093) (xy 424.943669 -36.266606) (xy 424.967341 -36.317103)
			(xy 424.983409 -36.37051) (xy 424.991529 -36.425686) (xy 424.992038 -36.453572) (xy 424.991529 -36.481458)
			(xy 424.983409 -36.536634) (xy 424.967341 -36.590041) (xy 424.943669 -36.640538) (xy 424.912896 -36.687051)
			(xy 424.875679 -36.728588) (xy 424.832811 -36.764263) (xy 424.785205 -36.793317) (xy 424.733876 -36.815129)
			(xy 424.679919 -36.829235) (xy 424.624482 -36.835335) (xy 424.568748 -36.833298) (xy 424.513905 -36.823168)
			(xy 424.461121 -36.805161) (xy 424.411521 -36.77966) (xy 424.366163 -36.747209) (xy 424.326014 -36.7085)
			(xy 424.291928 -36.664357) (xy 424.264632 -36.615722) (xy 424.244709 -36.563631) (xy 424.232583 -36.509194)
			(xy 424.228512 -36.453572) (xy 421.672634 -36.453572) (xy 421.676829 -36.482074) (xy 421.677338 -36.50996)
			(xy 421.676829 -36.537846) (xy 421.668709 -36.593022) (xy 421.652641 -36.646429) (xy 421.628969 -36.696926)
			(xy 421.598196 -36.743439) (xy 421.560979 -36.784976) (xy 421.518111 -36.820651) (xy 421.470505 -36.849705)
			(xy 421.419176 -36.871517) (xy 421.365219 -36.885623) (xy 421.309782 -36.891723) (xy 421.254048 -36.889686)
			(xy 421.199205 -36.879556) (xy 421.146421 -36.861549) (xy 421.096821 -36.836048) (xy 421.051463 -36.803597)
			(xy 421.011314 -36.764888) (xy 420.977228 -36.720745) (xy 420.949932 -36.67211) (xy 420.930009 -36.620019)
			(xy 420.917883 -36.565582) (xy 420.913812 -36.50996) (xy 414.227108 -36.50996) (xy 414.227479 -36.512686)
			(xy 414.23144 -36.599259) (xy 414.22763 -36.68584) (xy 414.216078 -36.77173) (xy 414.196879 -36.856241)
			(xy 414.170187 -36.938692) (xy 414.136215 -37.01842) (xy 414.095238 -37.094784) (xy 414.071816 -37.131244)
			(xy 414.067752 -37.137594) (xy 414.063434 -37.151564) (xy 414.063434 -37.159184) (xy 414.063833 -37.169209)
			(xy 414.071504 -37.187732) (xy 414.085683 -37.201906) (xy 414.104209 -37.20957) (xy 414.114234 -37.209984)
			(xy 414.191958 -37.209984) (xy 414.2354 -37.210393) (xy 414.321913 -37.218406) (xy 414.407318 -37.234367)
			(xy 414.490886 -37.258141) (xy 414.571903 -37.289524) (xy 414.64968 -37.328249) (xy 414.723551 -37.373985)
			(xy 414.792887 -37.426343) (xy 414.84644 -37.47516) (xy 418.059106 -37.47516) (xy 418.063177 -37.419538)
			(xy 418.075303 -37.365101) (xy 418.095226 -37.31301) (xy 418.122522 -37.264375) (xy 418.156608 -37.220232)
			(xy 418.196757 -37.181523) (xy 418.242115 -37.149072) (xy 418.291715 -37.123571) (xy 418.344499 -37.105564)
			(xy 418.399342 -37.095434) (xy 418.455076 -37.093397) (xy 418.510513 -37.099497) (xy 418.56447 -37.113603)
			(xy 418.615799 -37.135415) (xy 418.663405 -37.164469) (xy 418.706273 -37.200144) (xy 418.707124 -37.201094)
			(xy 422.016426 -37.201094) (xy 422.020497 -37.145472) (xy 422.032623 -37.091035) (xy 422.052546 -37.038944)
			(xy 422.079842 -36.990309) (xy 422.113928 -36.946166) (xy 422.154077 -36.907457) (xy 422.199435 -36.875006)
			(xy 422.249035 -36.849505) (xy 422.301819 -36.831498) (xy 422.356662 -36.821368) (xy 422.412396 -36.819331)
			(xy 422.467833 -36.825431) (xy 422.52179 -36.839537) (xy 422.573119 -36.861349) (xy 422.620725 -36.890403)
			(xy 422.663593 -36.926078) (xy 422.70081 -36.967615) (xy 422.731583 -37.014128) (xy 422.755255 -37.064625)
			(xy 422.762001 -37.087048) (xy 431.500788 -37.087048) (xy 431.501278 -37.060445) (xy 431.508653 -37.007754)
			(xy 431.523281 -36.9566) (xy 431.544877 -36.907975) (xy 431.573022 -36.862824) (xy 431.607169 -36.822024)
			(xy 431.646657 -36.786366) (xy 431.668428 -36.771072) (xy 431.67836 -36.76355) (xy 431.690082 -36.7416)
			(xy 431.69078 -36.729162) (xy 431.69078 -36.644834) (xy 431.690131 -36.63238) (xy 431.678407 -36.610403)
			(xy 431.668428 -36.602924) (xy 431.646657 -36.58763) (xy 431.607179 -36.551963) (xy 431.573036 -36.511159)
			(xy 431.544891 -36.466009) (xy 431.523288 -36.417388) (xy 431.508648 -36.366238) (xy 431.501252 -36.31355)
			(xy 431.500788 -36.286948) (xy 431.5013 -36.259697) (xy 431.50905 -36.205748) (xy 431.5244 -36.153451)
			(xy 431.547037 -36.103871) (xy 431.576499 -36.058018) (xy 431.612188 -36.016825) (xy 431.653376 -35.98113)
			(xy 431.699225 -35.951662) (xy 431.748802 -35.929018) (xy 431.801097 -35.913661) (xy 431.855045 -35.905904)
			(xy 431.882296 -35.90544) (xy 431.886868 -35.90544) (xy 431.896079 -35.905187) (xy 431.913398 -35.898933)
			(xy 431.92065 -35.893248) (xy 431.97145 -35.84956) (xy 431.978162 -35.84333) (xy 431.987017 -35.827316)
			(xy 431.988722 -35.818318) (xy 431.988722 -35.818064) (xy 431.993031 -35.791127) (xy 432.008344 -35.738768)
			(xy 432.030958 -35.689124) (xy 432.060413 -35.643207) (xy 432.096108 -35.601954) (xy 432.137315 -35.566206)
			(xy 432.183194 -35.536693) (xy 432.232808 -35.514015) (xy 432.285148 -35.498635) (xy 432.339144 -35.490868)
			(xy 432.36642 -35.490404) (xy 432.393671 -35.490867) (xy 432.447618 -35.498626) (xy 432.499912 -35.513984)
			(xy 432.549489 -35.536627) (xy 432.595338 -35.566094) (xy 432.636527 -35.601787) (xy 432.672218 -35.642978)
			(xy 432.701683 -35.688829) (xy 432.724323 -35.738406) (xy 432.739678 -35.790701) (xy 432.747434 -35.844649)
			(xy 432.747434 -35.899151) (xy 432.739678 -35.953099) (xy 432.724323 -36.005394) (xy 432.701683 -36.054971)
			(xy 432.672218 -36.100822) (xy 432.636527 -36.142013) (xy 432.595338 -36.177706) (xy 432.549489 -36.207173)
			(xy 432.499912 -36.229816) (xy 432.447618 -36.245174) (xy 432.393671 -36.252933) (xy 432.36642 -36.25342)
			(xy 432.361848 -36.25342) (xy 432.352636 -36.253667) (xy 432.335317 -36.259924) (xy 432.328066 -36.265612)
			(xy 432.277266 -36.3093) (xy 432.270535 -36.315512) (xy 432.261691 -36.331539) (xy 432.259994 -36.340542)
			(xy 432.259994 -36.340796) (xy 432.255779 -36.366996) (xy 432.241096 -36.417989) (xy 432.219486 -36.466455)
			(xy 432.191365 -36.511456) (xy 432.187935 -36.515548) (xy 433.314092 -36.515548) (xy 433.318163 -36.459926)
			(xy 433.330289 -36.405489) (xy 433.350212 -36.353398) (xy 433.377508 -36.304763) (xy 433.411594 -36.26062)
			(xy 433.451743 -36.221911) (xy 433.497101 -36.18946) (xy 433.546701 -36.163959) (xy 433.599485 -36.145952)
			(xy 433.654328 -36.135822) (xy 433.710062 -36.133785) (xy 433.765499 -36.139885) (xy 433.819456 -36.153991)
			(xy 433.870785 -36.175803) (xy 433.918391 -36.204857) (xy 433.961259 -36.240532) (xy 433.998476 -36.282069)
			(xy 434.029249 -36.328582) (xy 434.052921 -36.379079) (xy 434.068989 -36.432486) (xy 434.077109 -36.487662)
			(xy 434.077618 -36.515548) (xy 434.077109 -36.543434) (xy 434.068989 -36.59861) (xy 434.052921 -36.652017)
			(xy 434.029249 -36.702514) (xy 433.998476 -36.749027) (xy 433.961259 -36.790564) (xy 433.918391 -36.826239)
			(xy 433.870785 -36.855293) (xy 433.819456 -36.877105) (xy 433.765499 -36.891211) (xy 433.710062 -36.897311)
			(xy 433.654328 -36.895274) (xy 433.599485 -36.885144) (xy 433.546701 -36.867137) (xy 433.497101 -36.841636)
			(xy 433.451743 -36.809185) (xy 433.411594 -36.770476) (xy 433.377508 -36.726333) (xy 433.350212 -36.677698)
			(xy 433.330289 -36.625607) (xy 433.318163 -36.57117) (xy 433.314092 -36.515548) (xy 432.187935 -36.515548)
			(xy 432.157277 -36.552124) (xy 432.11788 -36.587673) (xy 432.096164 -36.602924) (xy 432.086233 -36.610446)
			(xy 432.074511 -36.632397) (xy 432.073812 -36.644834) (xy 432.073812 -36.729162) (xy 432.074467 -36.741615)
			(xy 432.086187 -36.763592) (xy 432.096164 -36.771072) (xy 432.117931 -36.786371) (xy 432.15741 -36.822037)
			(xy 432.191553 -36.86284) (xy 432.219699 -36.907989) (xy 432.241302 -36.95661) (xy 432.255943 -37.007759)
			(xy 432.263339 -37.060446) (xy 432.263804 -37.087048) (xy 432.263804 -37.087302) (xy 432.263181 -37.119019)
			(xy 432.252681 -37.181576) (xy 432.231955 -37.241528) (xy 432.217322 -37.269674) (xy 432.211988 -37.27958)
			(xy 432.210464 -37.301678) (xy 432.242468 -37.384482) (xy 432.246944 -37.394578) (xy 432.262743 -37.409977)
			(xy 432.272948 -37.4142) (xy 432.29747 -37.423296) (xy 432.344001 -37.447173) (xy 432.386834 -37.477184)
			(xy 432.425165 -37.512765) (xy 432.458274 -37.55325) (xy 432.485542 -37.59788) (xy 432.506456 -37.645816)
			(xy 432.520625 -37.69616) (xy 432.527781 -37.747968) (xy 432.528218 -37.774118) (xy 432.527732 -37.801369)
			(xy 432.519976 -37.855317) (xy 432.504621 -37.907612) (xy 432.481979 -37.957189) (xy 432.452513 -38.003039)
			(xy 432.416822 -38.04423) (xy 432.375631 -38.079921) (xy 432.329781 -38.109387) (xy 432.280204 -38.132029)
			(xy 432.227909 -38.147384) (xy 432.173961 -38.15514) (xy 432.119459 -38.15514) (xy 432.065511 -38.147384)
			(xy 432.013216 -38.132029) (xy 431.963639 -38.109387) (xy 431.917789 -38.079921) (xy 431.876598 -38.04423)
			(xy 431.840907 -38.003039) (xy 431.811441 -37.957189) (xy 431.788799 -37.907612) (xy 431.773444 -37.855317)
			(xy 431.765688 -37.801369) (xy 431.765202 -37.774118) (xy 431.765202 -37.773864) (xy 431.765811 -37.742147)
			(xy 431.776316 -37.679588) (xy 431.797048 -37.619638) (xy 431.811684 -37.591492) (xy 431.817018 -37.581586)
			(xy 431.818542 -37.559488) (xy 431.786538 -37.476684) (xy 431.782072 -37.466583) (xy 431.766265 -37.451187)
			(xy 431.756058 -37.446966) (xy 431.731526 -37.437896) (xy 431.684993 -37.414017) (xy 431.642159 -37.384003)
			(xy 431.603828 -37.348419) (xy 431.570719 -37.30793) (xy 431.543453 -37.263297) (xy 431.522541 -37.215358)
			(xy 431.508375 -37.16501) (xy 431.501222 -37.113199) (xy 431.500788 -37.087048) (xy 422.762001 -37.087048)
			(xy 422.771323 -37.118032) (xy 422.779443 -37.173208) (xy 422.779952 -37.201094) (xy 422.779443 -37.22898)
			(xy 422.771323 -37.284156) (xy 422.755255 -37.337563) (xy 422.731583 -37.38806) (xy 422.70081 -37.434573)
			(xy 422.663593 -37.47611) (xy 422.620725 -37.511785) (xy 422.573119 -37.540839) (xy 422.52179 -37.562651)
			(xy 422.467833 -37.576757) (xy 422.412396 -37.582857) (xy 422.356662 -37.58082) (xy 422.301819 -37.57069)
			(xy 422.249035 -37.552683) (xy 422.199435 -37.527182) (xy 422.154077 -37.494731) (xy 422.113928 -37.456022)
			(xy 422.079842 -37.411879) (xy 422.052546 -37.363244) (xy 422.032623 -37.311153) (xy 422.020497 -37.256716)
			(xy 422.016426 -37.201094) (xy 418.707124 -37.201094) (xy 418.74349 -37.241681) (xy 418.774263 -37.288194)
			(xy 418.797935 -37.338691) (xy 418.814003 -37.392098) (xy 418.822123 -37.447274) (xy 418.822632 -37.47516)
			(xy 418.822123 -37.503046) (xy 418.814003 -37.558222) (xy 418.797935 -37.611629) (xy 418.774263 -37.662126)
			(xy 418.77411 -37.662358) (xy 420.248332 -37.662358) (xy 420.252403 -37.606736) (xy 420.264529 -37.552299)
			(xy 420.284452 -37.500208) (xy 420.311748 -37.451573) (xy 420.345834 -37.40743) (xy 420.385983 -37.368721)
			(xy 420.431341 -37.33627) (xy 420.480941 -37.310769) (xy 420.533725 -37.292762) (xy 420.588568 -37.282632)
			(xy 420.644302 -37.280595) (xy 420.699739 -37.286695) (xy 420.753696 -37.300801) (xy 420.805025 -37.322613)
			(xy 420.852631 -37.351667) (xy 420.895499 -37.387342) (xy 420.932716 -37.428879) (xy 420.963489 -37.475392)
			(xy 420.987161 -37.525889) (xy 421.003229 -37.579296) (xy 421.011349 -37.634472) (xy 421.011858 -37.662358)
			(xy 421.011349 -37.690244) (xy 421.003229 -37.74542) (xy 420.987161 -37.798827) (xy 420.963489 -37.849324)
			(xy 420.932716 -37.895837) (xy 420.895499 -37.937374) (xy 420.852631 -37.973049) (xy 420.805025 -38.002103)
			(xy 420.753696 -38.023915) (xy 420.699739 -38.038021) (xy 420.644302 -38.044121) (xy 420.588568 -38.042084)
			(xy 420.533725 -38.031954) (xy 420.480941 -38.013947) (xy 420.431341 -37.988446) (xy 420.385983 -37.955995)
			(xy 420.345834 -37.917286) (xy 420.311748 -37.873143) (xy 420.284452 -37.824508) (xy 420.264529 -37.772417)
			(xy 420.252403 -37.71798) (xy 420.248332 -37.662358) (xy 418.77411 -37.662358) (xy 418.74349 -37.708639)
			(xy 418.706273 -37.750176) (xy 418.663405 -37.785851) (xy 418.615799 -37.814905) (xy 418.56447 -37.836717)
			(xy 418.510513 -37.850823) (xy 418.455076 -37.856923) (xy 418.399342 -37.854886) (xy 418.344499 -37.844756)
			(xy 418.291715 -37.826749) (xy 418.242115 -37.801248) (xy 418.196757 -37.768797) (xy 418.156608 -37.730088)
			(xy 418.122522 -37.685945) (xy 418.095226 -37.63731) (xy 418.075303 -37.585219) (xy 418.063177 -37.530782)
			(xy 418.059106 -37.47516) (xy 414.84644 -37.47516) (xy 414.857096 -37.484874) (xy 414.915631 -37.549081)
			(xy 414.967991 -37.618414) (xy 415.01373 -37.692284) (xy 415.052459 -37.770058) (xy 415.083846 -37.851074)
			(xy 415.107623 -37.934641) (xy 415.123588 -38.020045) (xy 415.131605 -38.106558) (xy 415.131605 -38.193442)
			(xy 415.123588 -38.279955) (xy 415.107623 -38.365359) (xy 415.083846 -38.448926) (xy 415.067484 -38.49116)
			(xy 418.059106 -38.49116) (xy 418.063177 -38.435538) (xy 418.075303 -38.381101) (xy 418.095226 -38.32901)
			(xy 418.122522 -38.280375) (xy 418.156608 -38.236232) (xy 418.196757 -38.197523) (xy 418.242115 -38.165072)
			(xy 418.291715 -38.139571) (xy 418.344499 -38.121564) (xy 418.399342 -38.111434) (xy 418.455076 -38.109397)
			(xy 418.510513 -38.115497) (xy 418.56447 -38.129603) (xy 418.615799 -38.151415) (xy 418.663405 -38.180469)
			(xy 418.706273 -38.216144) (xy 418.74349 -38.257681) (xy 418.774263 -38.304194) (xy 418.779393 -38.315138)
			(xy 432.717954 -38.315138) (xy 432.722025 -38.259516) (xy 432.734151 -38.205079) (xy 432.754074 -38.152988)
			(xy 432.78137 -38.104353) (xy 432.815456 -38.06021) (xy 432.855605 -38.021501) (xy 432.900963 -37.98905)
			(xy 432.950563 -37.963549) (xy 433.003347 -37.945542) (xy 433.05819 -37.935412) (xy 433.113924 -37.933375)
			(xy 433.169361 -37.939475) (xy 433.223318 -37.953581) (xy 433.274647 -37.975393) (xy 433.322253 -38.004447)
			(xy 433.365121 -38.040122) (xy 433.402338 -38.081659) (xy 433.433111 -38.128172) (xy 433.456783 -38.178669)
			(xy 433.461226 -38.193437) (xy 437.398171 -38.193437) (xy 437.398171 -38.106563) (xy 437.406186 -38.020059)
			(xy 437.42215 -37.934664) (xy 437.445924 -37.851106) (xy 437.477307 -37.770098) (xy 437.51603 -37.692331)
			(xy 437.561764 -37.618469) (xy 437.614118 -37.549141) (xy 437.672645 -37.484941) (xy 437.736846 -37.426414)
			(xy 437.806174 -37.374061) (xy 437.880036 -37.328327) (xy 437.957803 -37.289604) (xy 438.038811 -37.258222)
			(xy 438.122369 -37.234448) (xy 438.207765 -37.218486) (xy 438.294269 -37.21047) (xy 438.337706 -37.209984)
			(xy 438.415684 -37.209984) (xy 438.425706 -37.209567) (xy 438.444226 -37.201899) (xy 438.458399 -37.187726)
			(xy 438.466067 -37.169206) (xy 438.466484 -37.159184) (xy 438.466484 -37.151564) (xy 438.462166 -37.137594)
			(xy 438.458102 -37.131244) (xy 438.434666 -37.094789) (xy 438.393671 -37.018427) (xy 438.359683 -36.938699)
			(xy 438.332975 -36.856246) (xy 438.313763 -36.771731) (xy 438.302201 -36.685835) (xy 438.298381 -36.599249)
			(xy 438.302335 -36.512668) (xy 438.314031 -36.426791) (xy 438.333375 -36.342306) (xy 438.360211 -36.259895)
			(xy 438.394323 -36.180219) (xy 438.435437 -36.103921) (xy 438.483221 -36.031613) (xy 438.537293 -35.963878)
			(xy 438.597216 -35.90126) (xy 438.662509 -35.844263) (xy 438.732646 -35.793346) (xy 438.807064 -35.748918)
			(xy 438.885163 -35.711336) (xy 438.966315 -35.680903) (xy 439.049867 -35.657865) (xy 439.135148 -35.642405)
			(xy 439.221471 -35.634648) (xy 439.264806 -35.634168) (xy 439.26506 -35.634168) (xy 439.308392 -35.634599)
			(xy 439.394707 -35.642376) (xy 439.479978 -35.657855) (xy 439.56352 -35.68091) (xy 439.64466 -35.711355)
			(xy 439.722747 -35.748947) (xy 439.797153 -35.793383) (xy 439.867278 -35.844306) (xy 439.932561 -35.901306)
			(xy 439.992474 -35.963924) (xy 440.046538 -36.031658) (xy 440.094317 -36.103962) (xy 440.135426 -36.180256)
			(xy 440.169536 -36.259926) (xy 440.196372 -36.342331) (xy 440.215718 -36.426808) (xy 440.227419 -36.512679)
			(xy 440.23138 -36.599253) (xy 440.22757 -36.685834) (xy 440.21602 -36.771725) (xy 440.196822 -36.856236)
			(xy 440.170131 -36.938688) (xy 440.136161 -37.018418) (xy 440.095185 -37.094783) (xy 440.071764 -37.131244)
			(xy 440.0677 -37.137594) (xy 440.063382 -37.151564) (xy 440.063382 -37.159184) (xy 440.063901 -37.169188)
			(xy 440.071552 -37.187676) (xy 440.085695 -37.201829) (xy 440.104178 -37.209493) (xy 440.114182 -37.209984)
			(xy 440.191906 -37.209984) (xy 440.235346 -37.21041) (xy 440.321854 -37.218427) (xy 440.407254 -37.234391)
			(xy 440.490817 -37.258167) (xy 440.57183 -37.289552) (xy 440.649601 -37.328278) (xy 440.723467 -37.374014)
			(xy 440.792798 -37.426371) (xy 440.857003 -37.484902) (xy 440.915533 -37.549107) (xy 440.967889 -37.618438)
			(xy 441.013625 -37.692304) (xy 441.05235 -37.770076) (xy 441.083735 -37.851088) (xy 441.10751 -37.934651)
			(xy 441.123474 -38.020051) (xy 441.13149 -38.10656) (xy 441.13149 -38.19344) (xy 441.123474 -38.279949)
			(xy 441.10751 -38.365349) (xy 441.083735 -38.448912) (xy 441.05235 -38.529924) (xy 441.013625 -38.607696)
			(xy 440.967889 -38.681562) (xy 440.915533 -38.750893) (xy 440.857003 -38.815098) (xy 440.792798 -38.873629)
			(xy 440.723467 -38.925986) (xy 440.649601 -38.971722) (xy 440.57183 -39.010448) (xy 440.490817 -39.041833)
			(xy 440.407254 -39.065609) (xy 440.321854 -39.081573) (xy 440.235346 -39.08959) (xy 440.191906 -39.090092)
			(xy 438.337706 -39.090092) (xy 438.294269 -39.08953) (xy 438.207765 -39.081514) (xy 438.122369 -39.065552)
			(xy 438.038811 -39.041778) (xy 437.957803 -39.010396) (xy 437.880036 -38.971673) (xy 437.806174 -38.925939)
			(xy 437.736846 -38.873586) (xy 437.672645 -38.815059) (xy 437.614118 -38.750859) (xy 437.561764 -38.681531)
			(xy 437.51603 -38.607669) (xy 437.477307 -38.529902) (xy 437.445924 -38.448894) (xy 437.42215 -38.365336)
			(xy 437.406186 -38.279941) (xy 437.398171 -38.193437) (xy 433.461226 -38.193437) (xy 433.472851 -38.232076)
			(xy 433.480971 -38.287252) (xy 433.48148 -38.315138) (xy 433.480971 -38.343024) (xy 433.472851 -38.3982)
			(xy 433.456783 -38.451607) (xy 433.433111 -38.502104) (xy 433.402338 -38.548617) (xy 433.365121 -38.590154)
			(xy 433.322253 -38.625829) (xy 433.274647 -38.654883) (xy 433.223318 -38.676695) (xy 433.169361 -38.690801)
			(xy 433.113924 -38.696901) (xy 433.05819 -38.694864) (xy 433.003347 -38.684734) (xy 432.950563 -38.666727)
			(xy 432.900963 -38.641226) (xy 432.855605 -38.608775) (xy 432.815456 -38.570066) (xy 432.78137 -38.525923)
			(xy 432.754074 -38.477288) (xy 432.734151 -38.425197) (xy 432.722025 -38.37076) (xy 432.717954 -38.315138)
			(xy 418.779393 -38.315138) (xy 418.797935 -38.354691) (xy 418.814003 -38.408098) (xy 418.822123 -38.463274)
			(xy 418.822632 -38.49116) (xy 418.822123 -38.519046) (xy 418.814003 -38.574222) (xy 418.797935 -38.627629)
			(xy 418.774263 -38.678126) (xy 418.758985 -38.701218) (xy 421.737534 -38.701218) (xy 421.741605 -38.645596)
			(xy 421.753731 -38.591159) (xy 421.773654 -38.539068) (xy 421.80095 -38.490433) (xy 421.835036 -38.44629)
			(xy 421.875185 -38.407581) (xy 421.920543 -38.37513) (xy 421.970143 -38.349629) (xy 422.022927 -38.331622)
			(xy 422.07777 -38.321492) (xy 422.133504 -38.319455) (xy 422.188941 -38.325555) (xy 422.242898 -38.339661)
			(xy 422.294227 -38.361473) (xy 422.341833 -38.390527) (xy 422.384701 -38.426202) (xy 422.421918 -38.467739)
			(xy 422.452691 -38.514252) (xy 422.476363 -38.564749) (xy 422.492431 -38.618156) (xy 422.500551 -38.673332)
			(xy 422.50106 -38.701218) (xy 422.501032 -38.702742) (xy 423.999912 -38.702742) (xy 424.003983 -38.64712)
			(xy 424.016109 -38.592683) (xy 424.036032 -38.540592) (xy 424.063328 -38.491957) (xy 424.097414 -38.447814)
			(xy 424.137563 -38.409105) (xy 424.182921 -38.376654) (xy 424.232521 -38.351153) (xy 424.285305 -38.333146)
			(xy 424.340148 -38.323016) (xy 424.395882 -38.320979) (xy 424.451319 -38.327079) (xy 424.505276 -38.341185)
			(xy 424.556605 -38.362997) (xy 424.604211 -38.392051) (xy 424.647079 -38.427726) (xy 424.684296 -38.469263)
			(xy 424.715069 -38.515776) (xy 424.738741 -38.566273) (xy 424.754809 -38.61968) (xy 424.762929 -38.674856)
			(xy 424.763438 -38.702742) (xy 424.762929 -38.730628) (xy 424.754809 -38.785804) (xy 424.738741 -38.839211)
			(xy 424.715069 -38.889708) (xy 424.684296 -38.936221) (xy 424.647079 -38.977758) (xy 424.604211 -39.013433)
			(xy 424.556605 -39.042487) (xy 424.505276 -39.064299) (xy 424.451319 -39.078405) (xy 424.395882 -39.084505)
			(xy 424.340148 -39.082468) (xy 424.285305 -39.072338) (xy 424.232521 -39.054331) (xy 424.182921 -39.02883)
			(xy 424.137563 -38.996379) (xy 424.097414 -38.95767) (xy 424.063328 -38.913527) (xy 424.036032 -38.864892)
			(xy 424.016109 -38.812801) (xy 424.003983 -38.758364) (xy 423.999912 -38.702742) (xy 422.501032 -38.702742)
			(xy 422.500551 -38.729104) (xy 422.492431 -38.78428) (xy 422.476363 -38.837687) (xy 422.452691 -38.888184)
			(xy 422.421918 -38.934697) (xy 422.384701 -38.976234) (xy 422.341833 -39.011909) (xy 422.294227 -39.040963)
			(xy 422.242898 -39.062775) (xy 422.188941 -39.076881) (xy 422.133504 -39.082981) (xy 422.07777 -39.080944)
			(xy 422.022927 -39.070814) (xy 421.970143 -39.052807) (xy 421.920543 -39.027306) (xy 421.875185 -38.994855)
			(xy 421.835036 -38.956146) (xy 421.80095 -38.912003) (xy 421.773654 -38.863368) (xy 421.753731 -38.811277)
			(xy 421.741605 -38.75684) (xy 421.737534 -38.701218) (xy 418.758985 -38.701218) (xy 418.74349 -38.724639)
			(xy 418.706273 -38.766176) (xy 418.663405 -38.801851) (xy 418.615799 -38.830905) (xy 418.56447 -38.852717)
			(xy 418.510513 -38.866823) (xy 418.455076 -38.872923) (xy 418.399342 -38.870886) (xy 418.344499 -38.860756)
			(xy 418.291715 -38.842749) (xy 418.242115 -38.817248) (xy 418.196757 -38.784797) (xy 418.156608 -38.746088)
			(xy 418.122522 -38.701945) (xy 418.095226 -38.65331) (xy 418.075303 -38.601219) (xy 418.063177 -38.546782)
			(xy 418.059106 -38.49116) (xy 415.067484 -38.49116) (xy 415.052459 -38.529942) (xy 415.01373 -38.607716)
			(xy 414.967991 -38.681586) (xy 414.915631 -38.750919) (xy 414.857096 -38.815126) (xy 414.792887 -38.873657)
			(xy 414.723551 -38.926015) (xy 414.64968 -38.971751) (xy 414.571903 -39.010476) (xy 414.490886 -39.041859)
			(xy 414.407318 -39.065633) (xy 414.321913 -39.081594) (xy 414.2354 -39.089607) (xy 414.191958 -39.090092)
			(xy 412.337758 -39.090092) (xy 412.294323 -39.089513) (xy 412.207824 -39.081494) (xy 412.122433 -39.065528)
			(xy 412.03888 -39.041752) (xy 411.957877 -39.010368) (xy 411.880115 -38.971644) (xy 411.806258 -38.92591)
			(xy 411.736935 -38.873557) (xy 411.672738 -38.815032) (xy 411.614216 -38.750833) (xy 411.561866 -38.681508)
			(xy 411.516136 -38.607648) (xy 411.477415 -38.529885) (xy 411.446035 -38.44888) (xy 411.422263 -38.365326)
			(xy 411.406301 -38.279935) (xy 411.398285 -38.193435) (xy 407.461277 -38.193435) (xy 407.472903 -38.232076)
			(xy 407.481023 -38.287252) (xy 407.481532 -38.315138) (xy 407.481023 -38.343024) (xy 407.472903 -38.3982)
			(xy 407.456835 -38.451607) (xy 407.433163 -38.502104) (xy 407.40239 -38.548617) (xy 407.365173 -38.590154)
			(xy 407.322305 -38.625829) (xy 407.274699 -38.654883) (xy 407.22337 -38.676695) (xy 407.169413 -38.690801)
			(xy 407.113976 -38.696901) (xy 407.058242 -38.694864) (xy 407.003399 -38.684734) (xy 406.950615 -38.666727)
			(xy 406.901015 -38.641226) (xy 406.855657 -38.608775) (xy 406.815508 -38.570066) (xy 406.781422 -38.525923)
			(xy 406.754126 -38.477288) (xy 406.734203 -38.425197) (xy 406.722077 -38.37076) (xy 406.718006 -38.315138)
			(xy 392.779445 -38.315138) (xy 392.797987 -38.354691) (xy 392.814055 -38.408098) (xy 392.822175 -38.463274)
			(xy 392.822684 -38.49116) (xy 392.822175 -38.519046) (xy 392.814055 -38.574222) (xy 392.797987 -38.627629)
			(xy 392.774315 -38.678126) (xy 392.759037 -38.701218) (xy 395.737586 -38.701218) (xy 395.741657 -38.645596)
			(xy 395.753783 -38.591159) (xy 395.773706 -38.539068) (xy 395.801002 -38.490433) (xy 395.835088 -38.44629)
			(xy 395.875237 -38.407581) (xy 395.920595 -38.37513) (xy 395.970195 -38.349629) (xy 396.022979 -38.331622)
			(xy 396.077822 -38.321492) (xy 396.133556 -38.319455) (xy 396.188993 -38.325555) (xy 396.24295 -38.339661)
			(xy 396.294279 -38.361473) (xy 396.341885 -38.390527) (xy 396.384753 -38.426202) (xy 396.42197 -38.467739)
			(xy 396.452743 -38.514252) (xy 396.476415 -38.564749) (xy 396.492483 -38.618156) (xy 396.500603 -38.673332)
			(xy 396.501112 -38.701218) (xy 396.501084 -38.702742) (xy 397.999964 -38.702742) (xy 398.004035 -38.64712)
			(xy 398.016161 -38.592683) (xy 398.036084 -38.540592) (xy 398.06338 -38.491957) (xy 398.097466 -38.447814)
			(xy 398.137615 -38.409105) (xy 398.182973 -38.376654) (xy 398.232573 -38.351153) (xy 398.285357 -38.333146)
			(xy 398.3402 -38.323016) (xy 398.395934 -38.320979) (xy 398.451371 -38.327079) (xy 398.505328 -38.341185)
			(xy 398.556657 -38.362997) (xy 398.604263 -38.392051) (xy 398.647131 -38.427726) (xy 398.684348 -38.469263)
			(xy 398.715121 -38.515776) (xy 398.738793 -38.566273) (xy 398.754861 -38.61968) (xy 398.762981 -38.674856)
			(xy 398.76349 -38.702742) (xy 398.762981 -38.730628) (xy 398.754861 -38.785804) (xy 398.738793 -38.839211)
			(xy 398.715121 -38.889708) (xy 398.684348 -38.936221) (xy 398.647131 -38.977758) (xy 398.604263 -39.013433)
			(xy 398.556657 -39.042487) (xy 398.505328 -39.064299) (xy 398.451371 -39.078405) (xy 398.395934 -39.084505)
			(xy 398.3402 -39.082468) (xy 398.285357 -39.072338) (xy 398.232573 -39.054331) (xy 398.182973 -39.02883)
			(xy 398.137615 -38.996379) (xy 398.097466 -38.95767) (xy 398.06338 -38.913527) (xy 398.036084 -38.864892)
			(xy 398.016161 -38.812801) (xy 398.004035 -38.758364) (xy 397.999964 -38.702742) (xy 396.501084 -38.702742)
			(xy 396.500603 -38.729104) (xy 396.492483 -38.78428) (xy 396.476415 -38.837687) (xy 396.452743 -38.888184)
			(xy 396.42197 -38.934697) (xy 396.384753 -38.976234) (xy 396.341885 -39.011909) (xy 396.294279 -39.040963)
			(xy 396.24295 -39.062775) (xy 396.188993 -39.076881) (xy 396.133556 -39.082981) (xy 396.077822 -39.080944)
			(xy 396.022979 -39.070814) (xy 395.970195 -39.052807) (xy 395.920595 -39.027306) (xy 395.875237 -38.994855)
			(xy 395.835088 -38.956146) (xy 395.801002 -38.912003) (xy 395.773706 -38.863368) (xy 395.753783 -38.811277)
			(xy 395.741657 -38.75684) (xy 395.737586 -38.701218) (xy 392.759037 -38.701218) (xy 392.743542 -38.724639)
			(xy 392.706325 -38.766176) (xy 392.663457 -38.801851) (xy 392.615851 -38.830905) (xy 392.564522 -38.852717)
			(xy 392.510565 -38.866823) (xy 392.455128 -38.872923) (xy 392.399394 -38.870886) (xy 392.344551 -38.860756)
			(xy 392.291767 -38.842749) (xy 392.242167 -38.817248) (xy 392.196809 -38.784797) (xy 392.15666 -38.746088)
			(xy 392.122574 -38.701945) (xy 392.095278 -38.65331) (xy 392.075355 -38.601219) (xy 392.063229 -38.546782)
			(xy 392.059158 -38.49116) (xy 389.067468 -38.49116) (xy 389.052451 -38.529923) (xy 389.013726 -38.607694)
			(xy 388.96799 -38.681561) (xy 388.915634 -38.750892) (xy 388.857104 -38.815097) (xy 388.7929 -38.873627)
			(xy 388.723569 -38.925984) (xy 388.649703 -38.971721) (xy 388.571932 -39.010447) (xy 388.49092 -39.041832)
			(xy 388.407358 -39.065608) (xy 388.321958 -39.081573) (xy 388.23545 -39.08959) (xy 388.19201 -39.090092)
			(xy 386.33781 -39.090092) (xy 386.294373 -39.08953) (xy 386.207868 -39.081515) (xy 386.122473 -39.065553)
			(xy 386.038914 -39.041779) (xy 385.957906 -39.010397) (xy 385.880138 -38.971674) (xy 385.806276 -38.925941)
			(xy 385.736948 -38.873588) (xy 385.672746 -38.815061) (xy 385.614219 -38.75086) (xy 385.561865 -38.681533)
			(xy 385.516131 -38.60767) (xy 385.477407 -38.529903) (xy 385.446024 -38.448895) (xy 385.42225 -38.365337)
			(xy 385.406286 -38.279941) (xy 385.398271 -38.193437) (xy 381.46133 -38.193437) (xy 381.472955 -38.232076)
			(xy 381.481075 -38.287252) (xy 381.481584 -38.315138) (xy 381.481075 -38.343024) (xy 381.472955 -38.3982)
			(xy 381.456887 -38.451607) (xy 381.433215 -38.502104) (xy 381.402442 -38.548617) (xy 381.365225 -38.590154)
			(xy 381.322357 -38.625829) (xy 381.274751 -38.654883) (xy 381.223422 -38.676695) (xy 381.169465 -38.690801)
			(xy 381.114028 -38.696901) (xy 381.058294 -38.694864) (xy 381.003451 -38.684734) (xy 380.950667 -38.666727)
			(xy 380.901067 -38.641226) (xy 380.855709 -38.608775) (xy 380.81556 -38.570066) (xy 380.781474 -38.525923)
			(xy 380.754178 -38.477288) (xy 380.734255 -38.425197) (xy 380.722129 -38.37076) (xy 380.718058 -38.315138)
			(xy 366.779497 -38.315138) (xy 366.798039 -38.354691) (xy 366.814107 -38.408098) (xy 366.822227 -38.463274)
			(xy 366.822736 -38.49116) (xy 366.822227 -38.519046) (xy 366.814107 -38.574222) (xy 366.798039 -38.627629)
			(xy 366.774367 -38.678126) (xy 366.759089 -38.701218) (xy 369.737638 -38.701218) (xy 369.741709 -38.645596)
			(xy 369.753835 -38.591159) (xy 369.773758 -38.539068) (xy 369.801054 -38.490433) (xy 369.83514 -38.44629)
			(xy 369.875289 -38.407581) (xy 369.920647 -38.37513) (xy 369.970247 -38.349629) (xy 370.023031 -38.331622)
			(xy 370.077874 -38.321492) (xy 370.133608 -38.319455) (xy 370.189045 -38.325555) (xy 370.243002 -38.339661)
			(xy 370.294331 -38.361473) (xy 370.341937 -38.390527) (xy 370.384805 -38.426202) (xy 370.422022 -38.467739)
			(xy 370.452795 -38.514252) (xy 370.476467 -38.564749) (xy 370.492535 -38.618156) (xy 370.500655 -38.673332)
			(xy 370.501164 -38.701218) (xy 370.501136 -38.702742) (xy 372.000016 -38.702742) (xy 372.004087 -38.64712)
			(xy 372.016213 -38.592683) (xy 372.036136 -38.540592) (xy 372.063432 -38.491957) (xy 372.097518 -38.447814)
			(xy 372.137667 -38.409105) (xy 372.183025 -38.376654) (xy 372.232625 -38.351153) (xy 372.285409 -38.333146)
			(xy 372.340252 -38.323016) (xy 372.395986 -38.320979) (xy 372.451423 -38.327079) (xy 372.50538 -38.341185)
			(xy 372.556709 -38.362997) (xy 372.604315 -38.392051) (xy 372.647183 -38.427726) (xy 372.6844 -38.469263)
			(xy 372.715173 -38.515776) (xy 372.738845 -38.566273) (xy 372.754913 -38.61968) (xy 372.763033 -38.674856)
			(xy 372.763542 -38.702742) (xy 372.763033 -38.730628) (xy 372.754913 -38.785804) (xy 372.738845 -38.839211)
			(xy 372.715173 -38.889708) (xy 372.6844 -38.936221) (xy 372.647183 -38.977758) (xy 372.604315 -39.013433)
			(xy 372.556709 -39.042487) (xy 372.50538 -39.064299) (xy 372.451423 -39.078405) (xy 372.395986 -39.084505)
			(xy 372.340252 -39.082468) (xy 372.285409 -39.072338) (xy 372.232625 -39.054331) (xy 372.183025 -39.02883)
			(xy 372.137667 -38.996379) (xy 372.097518 -38.95767) (xy 372.063432 -38.913527) (xy 372.036136 -38.864892)
			(xy 372.016213 -38.812801) (xy 372.004087 -38.758364) (xy 372.000016 -38.702742) (xy 370.501136 -38.702742)
			(xy 370.500655 -38.729104) (xy 370.492535 -38.78428) (xy 370.476467 -38.837687) (xy 370.452795 -38.888184)
			(xy 370.422022 -38.934697) (xy 370.384805 -38.976234) (xy 370.341937 -39.011909) (xy 370.294331 -39.040963)
			(xy 370.243002 -39.062775) (xy 370.189045 -39.076881) (xy 370.133608 -39.082981) (xy 370.077874 -39.080944)
			(xy 370.023031 -39.070814) (xy 369.970247 -39.052807) (xy 369.920647 -39.027306) (xy 369.875289 -38.994855)
			(xy 369.83514 -38.956146) (xy 369.801054 -38.912003) (xy 369.773758 -38.863368) (xy 369.753835 -38.811277)
			(xy 369.741709 -38.75684) (xy 369.737638 -38.701218) (xy 366.759089 -38.701218) (xy 366.743594 -38.724639)
			(xy 366.706377 -38.766176) (xy 366.663509 -38.801851) (xy 366.615903 -38.830905) (xy 366.564574 -38.852717)
			(xy 366.510617 -38.866823) (xy 366.45518 -38.872923) (xy 366.399446 -38.870886) (xy 366.344603 -38.860756)
			(xy 366.291819 -38.842749) (xy 366.242219 -38.817248) (xy 366.196861 -38.784797) (xy 366.156712 -38.746088)
			(xy 366.122626 -38.701945) (xy 366.09533 -38.65331) (xy 366.075407 -38.601219) (xy 366.063281 -38.546782)
			(xy 366.05921 -38.49116) (xy 363.067583 -38.49116) (xy 363.052559 -38.529941) (xy 363.013831 -38.607715)
			(xy 362.968092 -38.681584) (xy 362.915732 -38.750918) (xy 362.857198 -38.815124) (xy 362.792989 -38.873656)
			(xy 362.723653 -38.926013) (xy 362.649782 -38.97175) (xy 362.572006 -39.010475) (xy 362.490989 -39.041858)
			(xy 362.407421 -39.065632) (xy 362.322017 -39.081594) (xy 362.235504 -39.089607) (xy 362.192062 -39.090092)
			(xy 360.337862 -39.090092) (xy 360.294427 -39.089513) (xy 360.207927 -39.081494) (xy 360.122536 -39.065529)
			(xy 360.038983 -39.041753) (xy 359.957979 -39.010369) (xy 359.880217 -38.971645) (xy 359.80636 -38.925912)
			(xy 359.737037 -38.873559) (xy 359.67284 -38.815033) (xy 359.614317 -38.750834) (xy 359.561967 -38.681509)
			(xy 359.516236 -38.60765) (xy 359.477516 -38.529886) (xy 359.446135 -38.448881) (xy 359.422363 -38.365327)
			(xy 359.406401 -38.279935) (xy 359.398386 -38.193435) (xy 355.461381 -38.193435) (xy 355.473007 -38.232076)
			(xy 355.481127 -38.287252) (xy 355.481636 -38.315138) (xy 355.481127 -38.343024) (xy 355.473007 -38.3982)
			(xy 355.456939 -38.451607) (xy 355.433267 -38.502104) (xy 355.402494 -38.548617) (xy 355.365277 -38.590154)
			(xy 355.322409 -38.625829) (xy 355.274803 -38.654883) (xy 355.223474 -38.676695) (xy 355.169517 -38.690801)
			(xy 355.11408 -38.696901) (xy 355.058346 -38.694864) (xy 355.003503 -38.684734) (xy 354.950719 -38.666727)
			(xy 354.901119 -38.641226) (xy 354.855761 -38.608775) (xy 354.815612 -38.570066) (xy 354.781526 -38.525923)
			(xy 354.75423 -38.477288) (xy 354.734307 -38.425197) (xy 354.722181 -38.37076) (xy 354.71811 -38.315138)
			(xy 340.779549 -38.315138) (xy 340.798091 -38.354691) (xy 340.814159 -38.408098) (xy 340.822279 -38.463274)
			(xy 340.822788 -38.49116) (xy 340.822279 -38.519046) (xy 340.814159 -38.574222) (xy 340.798091 -38.627629)
			(xy 340.774419 -38.678126) (xy 340.759141 -38.701218) (xy 343.73769 -38.701218) (xy 343.741761 -38.645596)
			(xy 343.753887 -38.591159) (xy 343.77381 -38.539068) (xy 343.801106 -38.490433) (xy 343.835192 -38.44629)
			(xy 343.875341 -38.407581) (xy 343.920699 -38.37513) (xy 343.970299 -38.349629) (xy 344.023083 -38.331622)
			(xy 344.077926 -38.321492) (xy 344.13366 -38.319455) (xy 344.189097 -38.325555) (xy 344.243054 -38.339661)
			(xy 344.294383 -38.361473) (xy 344.341989 -38.390527) (xy 344.384857 -38.426202) (xy 344.422074 -38.467739)
			(xy 344.452847 -38.514252) (xy 344.476519 -38.564749) (xy 344.492587 -38.618156) (xy 344.500707 -38.673332)
			(xy 344.501216 -38.701218) (xy 344.501188 -38.702742) (xy 346.000068 -38.702742) (xy 346.004139 -38.64712)
			(xy 346.016265 -38.592683) (xy 346.036188 -38.540592) (xy 346.063484 -38.491957) (xy 346.09757 -38.447814)
			(xy 346.137719 -38.409105) (xy 346.183077 -38.376654) (xy 346.232677 -38.351153) (xy 346.285461 -38.333146)
			(xy 346.340304 -38.323016) (xy 346.396038 -38.320979) (xy 346.451475 -38.327079) (xy 346.505432 -38.341185)
			(xy 346.556761 -38.362997) (xy 346.604367 -38.392051) (xy 346.647235 -38.427726) (xy 346.684452 -38.469263)
			(xy 346.715225 -38.515776) (xy 346.738897 -38.566273) (xy 346.754965 -38.61968) (xy 346.763085 -38.674856)
			(xy 346.763594 -38.702742) (xy 346.763085 -38.730628) (xy 346.754965 -38.785804) (xy 346.738897 -38.839211)
			(xy 346.715225 -38.889708) (xy 346.684452 -38.936221) (xy 346.647235 -38.977758) (xy 346.604367 -39.013433)
			(xy 346.556761 -39.042487) (xy 346.505432 -39.064299) (xy 346.451475 -39.078405) (xy 346.396038 -39.084505)
			(xy 346.340304 -39.082468) (xy 346.285461 -39.072338) (xy 346.232677 -39.054331) (xy 346.183077 -39.02883)
			(xy 346.137719 -38.996379) (xy 346.09757 -38.95767) (xy 346.063484 -38.913527) (xy 346.036188 -38.864892)
			(xy 346.016265 -38.812801) (xy 346.004139 -38.758364) (xy 346.000068 -38.702742) (xy 344.501188 -38.702742)
			(xy 344.500707 -38.729104) (xy 344.492587 -38.78428) (xy 344.476519 -38.837687) (xy 344.452847 -38.888184)
			(xy 344.422074 -38.934697) (xy 344.384857 -38.976234) (xy 344.341989 -39.011909) (xy 344.294383 -39.040963)
			(xy 344.243054 -39.062775) (xy 344.189097 -39.076881) (xy 344.13366 -39.082981) (xy 344.077926 -39.080944)
			(xy 344.023083 -39.070814) (xy 343.970299 -39.052807) (xy 343.920699 -39.027306) (xy 343.875341 -38.994855)
			(xy 343.835192 -38.956146) (xy 343.801106 -38.912003) (xy 343.77381 -38.863368) (xy 343.753887 -38.811277)
			(xy 343.741761 -38.75684) (xy 343.73769 -38.701218) (xy 340.759141 -38.701218) (xy 340.743646 -38.724639)
			(xy 340.706429 -38.766176) (xy 340.663561 -38.801851) (xy 340.615955 -38.830905) (xy 340.564626 -38.852717)
			(xy 340.510669 -38.866823) (xy 340.455232 -38.872923) (xy 340.399498 -38.870886) (xy 340.344655 -38.860756)
			(xy 340.291871 -38.842749) (xy 340.242271 -38.817248) (xy 340.196913 -38.784797) (xy 340.156764 -38.746088)
			(xy 340.122678 -38.701945) (xy 340.095382 -38.65331) (xy 340.075459 -38.601219) (xy 340.063333 -38.546782)
			(xy 340.059262 -38.49116) (xy 324.967267 -38.49116) (xy 324.95225 -38.529924) (xy 324.913525 -38.607695)
			(xy 324.867789 -38.681561) (xy 324.815433 -38.750893) (xy 324.756903 -38.815098) (xy 324.692699 -38.873628)
			(xy 324.623368 -38.925985) (xy 324.549502 -38.971721) (xy 324.471731 -39.010447) (xy 324.390719 -39.041832)
			(xy 324.307156 -39.065608) (xy 324.221756 -39.081573) (xy 324.135248 -39.08959) (xy 324.091808 -39.090092)
			(xy 322.237608 -39.090092) (xy 322.194171 -39.08953) (xy 322.107667 -39.081515) (xy 322.022271 -39.065552)
			(xy 321.938713 -39.041778) (xy 321.857704 -39.010396) (xy 321.779937 -38.971673) (xy 321.706075 -38.92594)
			(xy 321.636747 -38.873587) (xy 321.572546 -38.81506) (xy 321.514018 -38.750859) (xy 321.461664 -38.681532)
			(xy 321.415931 -38.60767) (xy 321.377207 -38.529903) (xy 321.345824 -38.448895) (xy 321.32205 -38.365337)
			(xy 321.306086 -38.279941) (xy 321.298071 -38.193437) (xy 317.361128 -38.193437) (xy 317.372753 -38.232076)
			(xy 317.380873 -38.287252) (xy 317.381382 -38.315138) (xy 317.380873 -38.343024) (xy 317.372753 -38.3982)
			(xy 317.356685 -38.451607) (xy 317.333013 -38.502104) (xy 317.30224 -38.548617) (xy 317.265023 -38.590154)
			(xy 317.222155 -38.625829) (xy 317.174549 -38.654883) (xy 317.12322 -38.676695) (xy 317.069263 -38.690801)
			(xy 317.013826 -38.696901) (xy 316.958092 -38.694864) (xy 316.903249 -38.684734) (xy 316.850465 -38.666727)
			(xy 316.800865 -38.641226) (xy 316.755507 -38.608775) (xy 316.715358 -38.570066) (xy 316.681272 -38.525923)
			(xy 316.653976 -38.477288) (xy 316.634053 -38.425197) (xy 316.621927 -38.37076) (xy 316.617856 -38.315138)
			(xy 302.679295 -38.315138) (xy 302.697837 -38.354691) (xy 302.713905 -38.408098) (xy 302.722025 -38.463274)
			(xy 302.722534 -38.49116) (xy 302.722025 -38.519046) (xy 302.713905 -38.574222) (xy 302.697837 -38.627629)
			(xy 302.674165 -38.678126) (xy 302.658887 -38.701218) (xy 305.637436 -38.701218) (xy 305.641507 -38.645596)
			(xy 305.653633 -38.591159) (xy 305.673556 -38.539068) (xy 305.700852 -38.490433) (xy 305.734938 -38.44629)
			(xy 305.775087 -38.407581) (xy 305.820445 -38.37513) (xy 305.870045 -38.349629) (xy 305.922829 -38.331622)
			(xy 305.977672 -38.321492) (xy 306.033406 -38.319455) (xy 306.088843 -38.325555) (xy 306.1428 -38.339661)
			(xy 306.194129 -38.361473) (xy 306.241735 -38.390527) (xy 306.284603 -38.426202) (xy 306.32182 -38.467739)
			(xy 306.352593 -38.514252) (xy 306.376265 -38.564749) (xy 306.392333 -38.618156) (xy 306.400453 -38.673332)
			(xy 306.400962 -38.701218) (xy 306.400934 -38.702742) (xy 307.899814 -38.702742) (xy 307.903885 -38.64712)
			(xy 307.916011 -38.592683) (xy 307.935934 -38.540592) (xy 307.96323 -38.491957) (xy 307.997316 -38.447814)
			(xy 308.037465 -38.409105) (xy 308.082823 -38.376654) (xy 308.132423 -38.351153) (xy 308.185207 -38.333146)
			(xy 308.24005 -38.323016) (xy 308.295784 -38.320979) (xy 308.351221 -38.327079) (xy 308.405178 -38.341185)
			(xy 308.456507 -38.362997) (xy 308.504113 -38.392051) (xy 308.546981 -38.427726) (xy 308.584198 -38.469263)
			(xy 308.614971 -38.515776) (xy 308.638643 -38.566273) (xy 308.654711 -38.61968) (xy 308.662831 -38.674856)
			(xy 308.66334 -38.702742) (xy 308.662831 -38.730628) (xy 308.654711 -38.785804) (xy 308.638643 -38.839211)
			(xy 308.614971 -38.889708) (xy 308.584198 -38.936221) (xy 308.546981 -38.977758) (xy 308.504113 -39.013433)
			(xy 308.456507 -39.042487) (xy 308.405178 -39.064299) (xy 308.351221 -39.078405) (xy 308.295784 -39.084505)
			(xy 308.24005 -39.082468) (xy 308.185207 -39.072338) (xy 308.132423 -39.054331) (xy 308.082823 -39.02883)
			(xy 308.037465 -38.996379) (xy 307.997316 -38.95767) (xy 307.96323 -38.913527) (xy 307.935934 -38.864892)
			(xy 307.916011 -38.812801) (xy 307.903885 -38.758364) (xy 307.899814 -38.702742) (xy 306.400934 -38.702742)
			(xy 306.400453 -38.729104) (xy 306.392333 -38.78428) (xy 306.376265 -38.837687) (xy 306.352593 -38.888184)
			(xy 306.32182 -38.934697) (xy 306.284603 -38.976234) (xy 306.241735 -39.011909) (xy 306.194129 -39.040963)
			(xy 306.1428 -39.062775) (xy 306.088843 -39.076881) (xy 306.033406 -39.082981) (xy 305.977672 -39.080944)
			(xy 305.922829 -39.070814) (xy 305.870045 -39.052807) (xy 305.820445 -39.027306) (xy 305.775087 -38.994855)
			(xy 305.734938 -38.956146) (xy 305.700852 -38.912003) (xy 305.673556 -38.863368) (xy 305.653633 -38.811277)
			(xy 305.641507 -38.75684) (xy 305.637436 -38.701218) (xy 302.658887 -38.701218) (xy 302.643392 -38.724639)
			(xy 302.606175 -38.766176) (xy 302.563307 -38.801851) (xy 302.515701 -38.830905) (xy 302.464372 -38.852717)
			(xy 302.410415 -38.866823) (xy 302.354978 -38.872923) (xy 302.299244 -38.870886) (xy 302.244401 -38.860756)
			(xy 302.191617 -38.842749) (xy 302.142017 -38.817248) (xy 302.096659 -38.784797) (xy 302.05651 -38.746088)
			(xy 302.022424 -38.701945) (xy 301.995128 -38.65331) (xy 301.975205 -38.601219) (xy 301.963079 -38.546782)
			(xy 301.959008 -38.49116) (xy 298.967383 -38.49116) (xy 298.952359 -38.529941) (xy 298.913631 -38.607716)
			(xy 298.867891 -38.681585) (xy 298.815531 -38.750919) (xy 298.756997 -38.815125) (xy 298.692788 -38.873657)
			(xy 298.623452 -38.926014) (xy 298.549581 -38.97175) (xy 298.471805 -39.010475) (xy 298.390787 -39.041859)
			(xy 298.30722 -39.065632) (xy 298.221815 -39.081594) (xy 298.135302 -39.089607) (xy 298.09186 -39.090092)
			(xy 296.23766 -39.090092) (xy 296.194225 -39.089513) (xy 296.107725 -39.081494) (xy 296.022335 -39.065528)
			(xy 295.938781 -39.041752) (xy 295.857778 -39.010368) (xy 295.780016 -38.971644) (xy 295.706159 -38.925911)
			(xy 295.636836 -38.873558) (xy 295.572639 -38.815033) (xy 295.514116 -38.750833) (xy 295.461766 -38.681508)
			(xy 295.416036 -38.607649) (xy 295.377316 -38.529885) (xy 295.345935 -38.448881) (xy 295.322163 -38.365326)
			(xy 295.306201 -38.279935) (xy 295.298186 -38.193435) (xy 291.361179 -38.193435) (xy 291.372805 -38.232076)
			(xy 291.380925 -38.287252) (xy 291.381434 -38.315138) (xy 291.380925 -38.343024) (xy 291.372805 -38.3982)
			(xy 291.356737 -38.451607) (xy 291.333065 -38.502104) (xy 291.302292 -38.548617) (xy 291.265075 -38.590154)
			(xy 291.222207 -38.625829) (xy 291.174601 -38.654883) (xy 291.123272 -38.676695) (xy 291.069315 -38.690801)
			(xy 291.013878 -38.696901) (xy 290.958144 -38.694864) (xy 290.903301 -38.684734) (xy 290.850517 -38.666727)
			(xy 290.800917 -38.641226) (xy 290.755559 -38.608775) (xy 290.71541 -38.570066) (xy 290.681324 -38.525923)
			(xy 290.654028 -38.477288) (xy 290.634105 -38.425197) (xy 290.621979 -38.37076) (xy 290.617908 -38.315138)
			(xy 276.679347 -38.315138) (xy 276.697889 -38.354691) (xy 276.713957 -38.408098) (xy 276.722077 -38.463274)
			(xy 276.722586 -38.49116) (xy 276.722077 -38.519046) (xy 276.713957 -38.574222) (xy 276.697889 -38.627629)
			(xy 276.674217 -38.678126) (xy 276.658939 -38.701218) (xy 279.637488 -38.701218) (xy 279.641559 -38.645596)
			(xy 279.653685 -38.591159) (xy 279.673608 -38.539068) (xy 279.700904 -38.490433) (xy 279.73499 -38.44629)
			(xy 279.775139 -38.407581) (xy 279.820497 -38.37513) (xy 279.870097 -38.349629) (xy 279.922881 -38.331622)
			(xy 279.977724 -38.321492) (xy 280.033458 -38.319455) (xy 280.088895 -38.325555) (xy 280.142852 -38.339661)
			(xy 280.194181 -38.361473) (xy 280.241787 -38.390527) (xy 280.284655 -38.426202) (xy 280.321872 -38.467739)
			(xy 280.352645 -38.514252) (xy 280.376317 -38.564749) (xy 280.392385 -38.618156) (xy 280.400505 -38.673332)
			(xy 280.401014 -38.701218) (xy 280.400986 -38.702742) (xy 281.899866 -38.702742) (xy 281.903937 -38.64712)
			(xy 281.916063 -38.592683) (xy 281.935986 -38.540592) (xy 281.963282 -38.491957) (xy 281.997368 -38.447814)
			(xy 282.037517 -38.409105) (xy 282.082875 -38.376654) (xy 282.132475 -38.351153) (xy 282.185259 -38.333146)
			(xy 282.240102 -38.323016) (xy 282.295836 -38.320979) (xy 282.351273 -38.327079) (xy 282.40523 -38.341185)
			(xy 282.456559 -38.362997) (xy 282.504165 -38.392051) (xy 282.547033 -38.427726) (xy 282.58425 -38.469263)
			(xy 282.615023 -38.515776) (xy 282.638695 -38.566273) (xy 282.654763 -38.61968) (xy 282.662883 -38.674856)
			(xy 282.663392 -38.702742) (xy 282.662883 -38.730628) (xy 282.654763 -38.785804) (xy 282.638695 -38.839211)
			(xy 282.615023 -38.889708) (xy 282.58425 -38.936221) (xy 282.547033 -38.977758) (xy 282.504165 -39.013433)
			(xy 282.456559 -39.042487) (xy 282.40523 -39.064299) (xy 282.351273 -39.078405) (xy 282.295836 -39.084505)
			(xy 282.240102 -39.082468) (xy 282.185259 -39.072338) (xy 282.132475 -39.054331) (xy 282.082875 -39.02883)
			(xy 282.037517 -38.996379) (xy 281.997368 -38.95767) (xy 281.963282 -38.913527) (xy 281.935986 -38.864892)
			(xy 281.916063 -38.812801) (xy 281.903937 -38.758364) (xy 281.899866 -38.702742) (xy 280.400986 -38.702742)
			(xy 280.400505 -38.729104) (xy 280.392385 -38.78428) (xy 280.376317 -38.837687) (xy 280.352645 -38.888184)
			(xy 280.321872 -38.934697) (xy 280.284655 -38.976234) (xy 280.241787 -39.011909) (xy 280.194181 -39.040963)
			(xy 280.142852 -39.062775) (xy 280.088895 -39.076881) (xy 280.033458 -39.082981) (xy 279.977724 -39.080944)
			(xy 279.922881 -39.070814) (xy 279.870097 -39.052807) (xy 279.820497 -39.027306) (xy 279.775139 -38.994855)
			(xy 279.73499 -38.956146) (xy 279.700904 -38.912003) (xy 279.673608 -38.863368) (xy 279.653685 -38.811277)
			(xy 279.641559 -38.75684) (xy 279.637488 -38.701218) (xy 276.658939 -38.701218) (xy 276.643444 -38.724639)
			(xy 276.606227 -38.766176) (xy 276.563359 -38.801851) (xy 276.515753 -38.830905) (xy 276.464424 -38.852717)
			(xy 276.410467 -38.866823) (xy 276.35503 -38.872923) (xy 276.299296 -38.870886) (xy 276.244453 -38.860756)
			(xy 276.191669 -38.842749) (xy 276.142069 -38.817248) (xy 276.096711 -38.784797) (xy 276.056562 -38.746088)
			(xy 276.022476 -38.701945) (xy 275.99518 -38.65331) (xy 275.975257 -38.601219) (xy 275.963131 -38.546782)
			(xy 275.95906 -38.49116) (xy 272.967368 -38.49116) (xy 272.952351 -38.529923) (xy 272.913626 -38.607694)
			(xy 272.86789 -38.68156) (xy 272.815534 -38.750891) (xy 272.757005 -38.815096) (xy 272.692801 -38.873627)
			(xy 272.62347 -38.925983) (xy 272.549604 -38.97172) (xy 272.471834 -39.010446) (xy 272.390822 -39.041831)
			(xy 272.307259 -39.065608) (xy 272.22186 -39.081573) (xy 272.135352 -39.08959) (xy 272.091912 -39.090092)
			(xy 270.237712 -39.090092) (xy 270.194275 -39.08953) (xy 270.10777 -39.081515) (xy 270.022374 -39.065553)
			(xy 269.938816 -39.041779) (xy 269.857807 -39.010397) (xy 269.78004 -38.971675) (xy 269.706177 -38.925942)
			(xy 269.636849 -38.873588) (xy 269.572647 -38.815062) (xy 269.514119 -38.750861) (xy 269.461765 -38.681533)
			(xy 269.416031 -38.607671) (xy 269.377307 -38.529904) (xy 269.345924 -38.448896) (xy 269.32215 -38.365337)
			(xy 269.306186 -38.279942) (xy 269.298171 -38.193437) (xy 265.361232 -38.193437) (xy 265.372857 -38.232076)
			(xy 265.380977 -38.287252) (xy 265.381486 -38.315138) (xy 265.380977 -38.343024) (xy 265.372857 -38.3982)
			(xy 265.356789 -38.451607) (xy 265.333117 -38.502104) (xy 265.302344 -38.548617) (xy 265.265127 -38.590154)
			(xy 265.222259 -38.625829) (xy 265.174653 -38.654883) (xy 265.123324 -38.676695) (xy 265.069367 -38.690801)
			(xy 265.01393 -38.696901) (xy 264.958196 -38.694864) (xy 264.903353 -38.684734) (xy 264.850569 -38.666727)
			(xy 264.800969 -38.641226) (xy 264.755611 -38.608775) (xy 264.715462 -38.570066) (xy 264.681376 -38.525923)
			(xy 264.65408 -38.477288) (xy 264.634157 -38.425197) (xy 264.622031 -38.37076) (xy 264.61796 -38.315138)
			(xy 250.679399 -38.315138) (xy 250.697941 -38.354691) (xy 250.714009 -38.408098) (xy 250.722129 -38.463274)
			(xy 250.722638 -38.49116) (xy 250.722129 -38.519046) (xy 250.714009 -38.574222) (xy 250.697941 -38.627629)
			(xy 250.674269 -38.678126) (xy 250.658991 -38.701218) (xy 253.63754 -38.701218) (xy 253.641611 -38.645596)
			(xy 253.653737 -38.591159) (xy 253.67366 -38.539068) (xy 253.700956 -38.490433) (xy 253.735042 -38.44629)
			(xy 253.775191 -38.407581) (xy 253.820549 -38.37513) (xy 253.870149 -38.349629) (xy 253.922933 -38.331622)
			(xy 253.977776 -38.321492) (xy 254.03351 -38.319455) (xy 254.088947 -38.325555) (xy 254.142904 -38.339661)
			(xy 254.194233 -38.361473) (xy 254.241839 -38.390527) (xy 254.284707 -38.426202) (xy 254.321924 -38.467739)
			(xy 254.352697 -38.514252) (xy 254.376369 -38.564749) (xy 254.392437 -38.618156) (xy 254.400557 -38.673332)
			(xy 254.401066 -38.701218) (xy 254.401038 -38.702742) (xy 255.899918 -38.702742) (xy 255.903989 -38.64712)
			(xy 255.916115 -38.592683) (xy 255.936038 -38.540592) (xy 255.963334 -38.491957) (xy 255.99742 -38.447814)
			(xy 256.037569 -38.409105) (xy 256.082927 -38.376654) (xy 256.132527 -38.351153) (xy 256.185311 -38.333146)
			(xy 256.240154 -38.323016) (xy 256.295888 -38.320979) (xy 256.351325 -38.327079) (xy 256.405282 -38.341185)
			(xy 256.456611 -38.362997) (xy 256.504217 -38.392051) (xy 256.547085 -38.427726) (xy 256.584302 -38.469263)
			(xy 256.615075 -38.515776) (xy 256.638747 -38.566273) (xy 256.654815 -38.61968) (xy 256.662935 -38.674856)
			(xy 256.663444 -38.702742) (xy 256.662935 -38.730628) (xy 256.654815 -38.785804) (xy 256.638747 -38.839211)
			(xy 256.615075 -38.889708) (xy 256.584302 -38.936221) (xy 256.547085 -38.977758) (xy 256.504217 -39.013433)
			(xy 256.456611 -39.042487) (xy 256.405282 -39.064299) (xy 256.351325 -39.078405) (xy 256.295888 -39.084505)
			(xy 256.240154 -39.082468) (xy 256.185311 -39.072338) (xy 256.132527 -39.054331) (xy 256.082927 -39.02883)
			(xy 256.037569 -38.996379) (xy 255.99742 -38.95767) (xy 255.963334 -38.913527) (xy 255.936038 -38.864892)
			(xy 255.916115 -38.812801) (xy 255.903989 -38.758364) (xy 255.899918 -38.702742) (xy 254.401038 -38.702742)
			(xy 254.400557 -38.729104) (xy 254.392437 -38.78428) (xy 254.376369 -38.837687) (xy 254.352697 -38.888184)
			(xy 254.321924 -38.934697) (xy 254.284707 -38.976234) (xy 254.241839 -39.011909) (xy 254.194233 -39.040963)
			(xy 254.142904 -39.062775) (xy 254.088947 -39.076881) (xy 254.03351 -39.082981) (xy 253.977776 -39.080944)
			(xy 253.922933 -39.070814) (xy 253.870149 -39.052807) (xy 253.820549 -39.027306) (xy 253.775191 -38.994855)
			(xy 253.735042 -38.956146) (xy 253.700956 -38.912003) (xy 253.67366 -38.863368) (xy 253.653737 -38.811277)
			(xy 253.641611 -38.75684) (xy 253.63754 -38.701218) (xy 250.658991 -38.701218) (xy 250.643496 -38.724639)
			(xy 250.606279 -38.766176) (xy 250.563411 -38.801851) (xy 250.515805 -38.830905) (xy 250.464476 -38.852717)
			(xy 250.410519 -38.866823) (xy 250.355082 -38.872923) (xy 250.299348 -38.870886) (xy 250.244505 -38.860756)
			(xy 250.191721 -38.842749) (xy 250.142121 -38.817248) (xy 250.096763 -38.784797) (xy 250.056614 -38.746088)
			(xy 250.022528 -38.701945) (xy 249.995232 -38.65331) (xy 249.975309 -38.601219) (xy 249.963183 -38.546782)
			(xy 249.959112 -38.49116) (xy 246.967483 -38.49116) (xy 246.952459 -38.52994) (xy 246.913731 -38.607715)
			(xy 246.867992 -38.681584) (xy 246.815632 -38.750917) (xy 246.757098 -38.815124) (xy 246.69289 -38.873655)
			(xy 246.623554 -38.926013) (xy 246.549683 -38.971749) (xy 246.471908 -39.010474) (xy 246.39089 -39.041858)
			(xy 246.307323 -39.065632) (xy 246.221919 -39.081594) (xy 246.135406 -39.089607) (xy 246.091964 -39.090092)
			(xy 244.237764 -39.090092) (xy 244.194329 -39.089513) (xy 244.107829 -39.081494) (xy 244.022438 -39.065529)
			(xy 243.938884 -39.041753) (xy 243.857881 -39.010369) (xy 243.780118 -38.971646) (xy 243.706261 -38.925912)
			(xy 243.636938 -38.87356) (xy 243.572741 -38.815034) (xy 243.514217 -38.750835) (xy 243.461867 -38.68151)
			(xy 243.416137 -38.60765) (xy 243.377416 -38.529886) (xy 243.346035 -38.448882) (xy 243.322263 -38.365327)
			(xy 243.306301 -38.279935) (xy 243.298286 -38.193435) (xy 239.361283 -38.193435) (xy 239.372909 -38.232076)
			(xy 239.381029 -38.287252) (xy 239.381538 -38.315138) (xy 239.381029 -38.343024) (xy 239.372909 -38.3982)
			(xy 239.356841 -38.451607) (xy 239.333169 -38.502104) (xy 239.302396 -38.548617) (xy 239.265179 -38.590154)
			(xy 239.222311 -38.625829) (xy 239.174705 -38.654883) (xy 239.123376 -38.676695) (xy 239.069419 -38.690801)
			(xy 239.013982 -38.696901) (xy 238.958248 -38.694864) (xy 238.903405 -38.684734) (xy 238.850621 -38.666727)
			(xy 238.801021 -38.641226) (xy 238.755663 -38.608775) (xy 238.715514 -38.570066) (xy 238.681428 -38.525923)
			(xy 238.654132 -38.477288) (xy 238.634209 -38.425197) (xy 238.622083 -38.37076) (xy 238.618012 -38.315138)
			(xy 208.917011 -38.315138) (xy 208.907623 -38.365358) (xy 208.883846 -38.448924) (xy 208.852459 -38.52994)
			(xy 208.813731 -38.607715) (xy 208.767992 -38.681584) (xy 208.753164 -38.701218) (xy 227.637592 -38.701218)
			(xy 227.641663 -38.645596) (xy 227.653789 -38.591159) (xy 227.673712 -38.539068) (xy 227.701008 -38.490433)
			(xy 227.735094 -38.44629) (xy 227.775243 -38.407581) (xy 227.820601 -38.37513) (xy 227.870201 -38.349629)
			(xy 227.922985 -38.331622) (xy 227.977828 -38.321492) (xy 228.033562 -38.319455) (xy 228.088999 -38.325555)
			(xy 228.142956 -38.339661) (xy 228.194285 -38.361473) (xy 228.241891 -38.390527) (xy 228.284759 -38.426202)
			(xy 228.321976 -38.467739) (xy 228.352749 -38.514252) (xy 228.376421 -38.564749) (xy 228.392489 -38.618156)
			(xy 228.400609 -38.673332) (xy 228.401118 -38.701218) (xy 228.40109 -38.702742) (xy 229.89997 -38.702742)
			(xy 229.904041 -38.64712) (xy 229.916167 -38.592683) (xy 229.93609 -38.540592) (xy 229.963386 -38.491957)
			(xy 229.997472 -38.447814) (xy 230.037621 -38.409105) (xy 230.082979 -38.376654) (xy 230.132579 -38.351153)
			(xy 230.185363 -38.333146) (xy 230.240206 -38.323016) (xy 230.29594 -38.320979) (xy 230.351377 -38.327079)
			(xy 230.405334 -38.341185) (xy 230.456663 -38.362997) (xy 230.504269 -38.392051) (xy 230.547137 -38.427726)
			(xy 230.584354 -38.469263) (xy 230.615127 -38.515776) (xy 230.638799 -38.566273) (xy 230.654867 -38.61968)
			(xy 230.662987 -38.674856) (xy 230.663496 -38.702742) (xy 230.662987 -38.730628) (xy 230.654867 -38.785804)
			(xy 230.638799 -38.839211) (xy 230.615127 -38.889708) (xy 230.584354 -38.936221) (xy 230.547137 -38.977758)
			(xy 230.504269 -39.013433) (xy 230.456663 -39.042487) (xy 230.405334 -39.064299) (xy 230.351377 -39.078405)
			(xy 230.29594 -39.084505) (xy 230.240206 -39.082468) (xy 230.185363 -39.072338) (xy 230.132579 -39.054331)
			(xy 230.082979 -39.02883) (xy 230.037621 -38.996379) (xy 229.997472 -38.95767) (xy 229.963386 -38.913527)
			(xy 229.93609 -38.864892) (xy 229.916167 -38.812801) (xy 229.904041 -38.758364) (xy 229.89997 -38.702742)
			(xy 228.40109 -38.702742) (xy 228.400609 -38.729104) (xy 228.392489 -38.78428) (xy 228.376421 -38.837687)
			(xy 228.352749 -38.888184) (xy 228.321976 -38.934697) (xy 228.284759 -38.976234) (xy 228.241891 -39.011909)
			(xy 228.194285 -39.040963) (xy 228.142956 -39.062775) (xy 228.088999 -39.076881) (xy 228.033562 -39.082981)
			(xy 227.977828 -39.080944) (xy 227.922985 -39.070814) (xy 227.870201 -39.052807) (xy 227.820601 -39.027306)
			(xy 227.775243 -38.994855) (xy 227.735094 -38.956146) (xy 227.701008 -38.912003) (xy 227.673712 -38.863368)
			(xy 227.653789 -38.811277) (xy 227.641663 -38.75684) (xy 227.637592 -38.701218) (xy 208.753164 -38.701218)
			(xy 208.715632 -38.750917) (xy 208.657098 -38.815124) (xy 208.59289 -38.873655) (xy 208.523554 -38.926013)
			(xy 208.449683 -38.971749) (xy 208.371908 -39.010474) (xy 208.29089 -39.041858) (xy 208.207323 -39.065632)
			(xy 208.121919 -39.081594) (xy 208.035406 -39.089607) (xy 207.991964 -39.090092) (xy 206.137764 -39.090092)
			(xy 206.094329 -39.089513) (xy 206.007829 -39.081494) (xy 205.922438 -39.065529) (xy 205.838884 -39.041753)
			(xy 205.757881 -39.010369) (xy 205.680118 -38.971646) (xy 205.606261 -38.925912) (xy 205.536938 -38.87356)
			(xy 205.472741 -38.815034) (xy 205.414217 -38.750835) (xy 205.361867 -38.68151) (xy 205.316137 -38.60765)
			(xy 205.277416 -38.529886) (xy 205.246035 -38.448882) (xy 205.222263 -38.365327) (xy 205.206301 -38.279935)
			(xy 205.198286 -38.193435) (xy 201.261283 -38.193435) (xy 201.272909 -38.232076) (xy 201.281029 -38.287252)
			(xy 201.281538 -38.315138) (xy 201.281029 -38.343024) (xy 201.272909 -38.3982) (xy 201.256841 -38.451607)
			(xy 201.233169 -38.502104) (xy 201.202396 -38.548617) (xy 201.165179 -38.590154) (xy 201.122311 -38.625829)
			(xy 201.074705 -38.654883) (xy 201.023376 -38.676695) (xy 200.969419 -38.690801) (xy 200.913982 -38.696901)
			(xy 200.858248 -38.694864) (xy 200.803405 -38.684734) (xy 200.750621 -38.666727) (xy 200.701021 -38.641226)
			(xy 200.655663 -38.608775) (xy 200.615514 -38.570066) (xy 200.581428 -38.525923) (xy 200.554132 -38.477288)
			(xy 200.534209 -38.425197) (xy 200.522083 -38.37076) (xy 200.518012 -38.315138) (xy 186.579451 -38.315138)
			(xy 186.597993 -38.354691) (xy 186.614061 -38.408098) (xy 186.622181 -38.463274) (xy 186.62269 -38.49116)
			(xy 186.622181 -38.519046) (xy 186.614061 -38.574222) (xy 186.597993 -38.627629) (xy 186.574321 -38.678126)
			(xy 186.559043 -38.701218) (xy 189.537592 -38.701218) (xy 189.541663 -38.645596) (xy 189.553789 -38.591159)
			(xy 189.573712 -38.539068) (xy 189.601008 -38.490433) (xy 189.635094 -38.44629) (xy 189.675243 -38.407581)
			(xy 189.720601 -38.37513) (xy 189.770201 -38.349629) (xy 189.822985 -38.331622) (xy 189.877828 -38.321492)
			(xy 189.933562 -38.319455) (xy 189.988999 -38.325555) (xy 190.042956 -38.339661) (xy 190.094285 -38.361473)
			(xy 190.141891 -38.390527) (xy 190.184759 -38.426202) (xy 190.221976 -38.467739) (xy 190.252749 -38.514252)
			(xy 190.276421 -38.564749) (xy 190.292489 -38.618156) (xy 190.300609 -38.673332) (xy 190.301118 -38.701218)
			(xy 190.30109 -38.702742) (xy 191.79997 -38.702742) (xy 191.804041 -38.64712) (xy 191.816167 -38.592683)
			(xy 191.83609 -38.540592) (xy 191.863386 -38.491957) (xy 191.897472 -38.447814) (xy 191.937621 -38.409105)
			(xy 191.982979 -38.376654) (xy 192.032579 -38.351153) (xy 192.085363 -38.333146) (xy 192.140206 -38.323016)
			(xy 192.19594 -38.320979) (xy 192.251377 -38.327079) (xy 192.305334 -38.341185) (xy 192.356663 -38.362997)
			(xy 192.404269 -38.392051) (xy 192.447137 -38.427726) (xy 192.484354 -38.469263) (xy 192.515127 -38.515776)
			(xy 192.538799 -38.566273) (xy 192.554867 -38.61968) (xy 192.562987 -38.674856) (xy 192.563496 -38.702742)
			(xy 192.562987 -38.730628) (xy 192.554867 -38.785804) (xy 192.538799 -38.839211) (xy 192.515127 -38.889708)
			(xy 192.484354 -38.936221) (xy 192.447137 -38.977758) (xy 192.404269 -39.013433) (xy 192.356663 -39.042487)
			(xy 192.305334 -39.064299) (xy 192.251377 -39.078405) (xy 192.19594 -39.084505) (xy 192.140206 -39.082468)
			(xy 192.085363 -39.072338) (xy 192.032579 -39.054331) (xy 191.982979 -39.02883) (xy 191.937621 -38.996379)
			(xy 191.897472 -38.95767) (xy 191.863386 -38.913527) (xy 191.83609 -38.864892) (xy 191.816167 -38.812801)
			(xy 191.804041 -38.758364) (xy 191.79997 -38.702742) (xy 190.30109 -38.702742) (xy 190.300609 -38.729104)
			(xy 190.292489 -38.78428) (xy 190.276421 -38.837687) (xy 190.252749 -38.888184) (xy 190.221976 -38.934697)
			(xy 190.184759 -38.976234) (xy 190.141891 -39.011909) (xy 190.094285 -39.040963) (xy 190.042956 -39.062775)
			(xy 189.988999 -39.076881) (xy 189.933562 -39.082981) (xy 189.877828 -39.080944) (xy 189.822985 -39.070814)
			(xy 189.770201 -39.052807) (xy 189.720601 -39.027306) (xy 189.675243 -38.994855) (xy 189.635094 -38.956146)
			(xy 189.601008 -38.912003) (xy 189.573712 -38.863368) (xy 189.553789 -38.811277) (xy 189.541663 -38.75684)
			(xy 189.537592 -38.701218) (xy 186.559043 -38.701218) (xy 186.543548 -38.724639) (xy 186.506331 -38.766176)
			(xy 186.463463 -38.801851) (xy 186.415857 -38.830905) (xy 186.364528 -38.852717) (xy 186.310571 -38.866823)
			(xy 186.255134 -38.872923) (xy 186.1994 -38.870886) (xy 186.144557 -38.860756) (xy 186.091773 -38.842749)
			(xy 186.042173 -38.817248) (xy 185.996815 -38.784797) (xy 185.956666 -38.746088) (xy 185.92258 -38.701945)
			(xy 185.895284 -38.65331) (xy 185.875361 -38.601219) (xy 185.863235 -38.546782) (xy 185.859164 -38.49116)
			(xy 182.867467 -38.49116) (xy 182.852451 -38.529922) (xy 182.813726 -38.607693) (xy 182.767991 -38.681559)
			(xy 182.715635 -38.75089) (xy 182.657106 -38.815095) (xy 182.592902 -38.873625) (xy 182.523572 -38.925982)
			(xy 182.449707 -38.971719) (xy 182.371936 -39.010445) (xy 182.290925 -39.04183) (xy 182.207363 -39.065607)
			(xy 182.121963 -39.081572) (xy 182.035455 -39.08959) (xy 181.992016 -39.090092) (xy 180.137816 -39.090092)
			(xy 180.094378 -39.08953) (xy 180.007874 -39.081516) (xy 179.922478 -39.065554) (xy 179.838919 -39.04178)
			(xy 179.75791 -39.010399) (xy 179.680142 -38.971676) (xy 179.606279 -38.925943) (xy 179.53695 -38.87359)
			(xy 179.472748 -38.815063) (xy 179.414221 -38.750862) (xy 179.361866 -38.681534) (xy 179.316132 -38.607672)
			(xy 179.277408 -38.529905) (xy 179.246025 -38.448896) (xy 179.22225 -38.365338) (xy 179.206287 -38.279942)
			(xy 179.198271 -38.193438) (xy 175.261336 -38.193438) (xy 175.272961 -38.232076) (xy 175.281081 -38.287252)
			(xy 175.28159 -38.315138) (xy 175.281081 -38.343024) (xy 175.272961 -38.3982) (xy 175.256893 -38.451607)
			(xy 175.233221 -38.502104) (xy 175.202448 -38.548617) (xy 175.165231 -38.590154) (xy 175.122363 -38.625829)
			(xy 175.074757 -38.654883) (xy 175.023428 -38.676695) (xy 174.969471 -38.690801) (xy 174.914034 -38.696901)
			(xy 174.8583 -38.694864) (xy 174.803457 -38.684734) (xy 174.750673 -38.666727) (xy 174.701073 -38.641226)
			(xy 174.655715 -38.608775) (xy 174.615566 -38.570066) (xy 174.58148 -38.525923) (xy 174.554184 -38.477288)
			(xy 174.534261 -38.425197) (xy 174.522135 -38.37076) (xy 174.518064 -38.315138) (xy 160.579503 -38.315138)
			(xy 160.598045 -38.354691) (xy 160.614113 -38.408098) (xy 160.622233 -38.463274) (xy 160.622742 -38.49116)
			(xy 160.622233 -38.519046) (xy 160.614113 -38.574222) (xy 160.598045 -38.627629) (xy 160.574373 -38.678126)
			(xy 160.559095 -38.701218) (xy 163.537644 -38.701218) (xy 163.541715 -38.645596) (xy 163.553841 -38.591159)
			(xy 163.573764 -38.539068) (xy 163.60106 -38.490433) (xy 163.635146 -38.44629) (xy 163.675295 -38.407581)
			(xy 163.720653 -38.37513) (xy 163.770253 -38.349629) (xy 163.823037 -38.331622) (xy 163.87788 -38.321492)
			(xy 163.933614 -38.319455) (xy 163.989051 -38.325555) (xy 164.043008 -38.339661) (xy 164.094337 -38.361473)
			(xy 164.141943 -38.390527) (xy 164.184811 -38.426202) (xy 164.222028 -38.467739) (xy 164.252801 -38.514252)
			(xy 164.276473 -38.564749) (xy 164.292541 -38.618156) (xy 164.300661 -38.673332) (xy 164.30117 -38.701218)
			(xy 164.301142 -38.702742) (xy 165.800022 -38.702742) (xy 165.804093 -38.64712) (xy 165.816219 -38.592683)
			(xy 165.836142 -38.540592) (xy 165.863438 -38.491957) (xy 165.897524 -38.447814) (xy 165.937673 -38.409105)
			(xy 165.983031 -38.376654) (xy 166.032631 -38.351153) (xy 166.085415 -38.333146) (xy 166.140258 -38.323016)
			(xy 166.195992 -38.320979) (xy 166.251429 -38.327079) (xy 166.305386 -38.341185) (xy 166.356715 -38.362997)
			(xy 166.404321 -38.392051) (xy 166.447189 -38.427726) (xy 166.484406 -38.469263) (xy 166.515179 -38.515776)
			(xy 166.538851 -38.566273) (xy 166.554919 -38.61968) (xy 166.563039 -38.674856) (xy 166.563548 -38.702742)
			(xy 166.563039 -38.730628) (xy 166.554919 -38.785804) (xy 166.538851 -38.839211) (xy 166.515179 -38.889708)
			(xy 166.484406 -38.936221) (xy 166.447189 -38.977758) (xy 166.404321 -39.013433) (xy 166.356715 -39.042487)
			(xy 166.305386 -39.064299) (xy 166.251429 -39.078405) (xy 166.195992 -39.084505) (xy 166.140258 -39.082468)
			(xy 166.085415 -39.072338) (xy 166.032631 -39.054331) (xy 165.983031 -39.02883) (xy 165.937673 -38.996379)
			(xy 165.897524 -38.95767) (xy 165.863438 -38.913527) (xy 165.836142 -38.864892) (xy 165.816219 -38.812801)
			(xy 165.804093 -38.758364) (xy 165.800022 -38.702742) (xy 164.301142 -38.702742) (xy 164.300661 -38.729104)
			(xy 164.292541 -38.78428) (xy 164.276473 -38.837687) (xy 164.252801 -38.888184) (xy 164.222028 -38.934697)
			(xy 164.184811 -38.976234) (xy 164.141943 -39.011909) (xy 164.094337 -39.040963) (xy 164.043008 -39.062775)
			(xy 163.989051 -39.076881) (xy 163.933614 -39.082981) (xy 163.87788 -39.080944) (xy 163.823037 -39.070814)
			(xy 163.770253 -39.052807) (xy 163.720653 -39.027306) (xy 163.675295 -38.994855) (xy 163.635146 -38.956146)
			(xy 163.60106 -38.912003) (xy 163.573764 -38.863368) (xy 163.553841 -38.811277) (xy 163.541715 -38.75684)
			(xy 163.537644 -38.701218) (xy 160.559095 -38.701218) (xy 160.5436 -38.724639) (xy 160.506383 -38.766176)
			(xy 160.463515 -38.801851) (xy 160.415909 -38.830905) (xy 160.36458 -38.852717) (xy 160.310623 -38.866823)
			(xy 160.255186 -38.872923) (xy 160.199452 -38.870886) (xy 160.144609 -38.860756) (xy 160.091825 -38.842749)
			(xy 160.042225 -38.817248) (xy 159.996867 -38.784797) (xy 159.956718 -38.746088) (xy 159.922632 -38.701945)
			(xy 159.895336 -38.65331) (xy 159.875413 -38.601219) (xy 159.863287 -38.546782) (xy 159.859216 -38.49116)
			(xy 156.867583 -38.49116) (xy 156.85256 -38.529939) (xy 156.813832 -38.607714) (xy 156.768093 -38.681582)
			(xy 156.715733 -38.750916) (xy 156.6572 -38.815122) (xy 156.592991 -38.873654) (xy 156.523656 -38.926011)
			(xy 156.449786 -38.971748) (xy 156.37201 -39.010473) (xy 156.290993 -39.041857) (xy 156.207426 -39.065631)
			(xy 156.122022 -39.081593) (xy 156.03551 -39.089607) (xy 155.992068 -39.090092) (xy 154.137868 -39.090092)
			(xy 154.094433 -39.089513) (xy 154.007933 -39.081495) (xy 153.922541 -39.06553) (xy 153.838987 -39.041754)
			(xy 153.757983 -39.010371) (xy 153.680221 -38.971647) (xy 153.606363 -38.925914) (xy 153.537039 -38.873561)
			(xy 153.472842 -38.815035) (xy 153.414319 -38.750836) (xy 153.361968 -38.681511) (xy 153.316237 -38.607651)
			(xy 153.277516 -38.529887) (xy 153.246136 -38.448882) (xy 153.222363 -38.365328) (xy 153.206401 -38.279936)
			(xy 153.198386 -38.193435) (xy 149.261387 -38.193435) (xy 149.273013 -38.232076) (xy 149.281133 -38.287252)
			(xy 149.281642 -38.315138) (xy 149.281133 -38.343024) (xy 149.273013 -38.3982) (xy 149.256945 -38.451607)
			(xy 149.233273 -38.502104) (xy 149.2025 -38.548617) (xy 149.165283 -38.590154) (xy 149.122415 -38.625829)
			(xy 149.074809 -38.654883) (xy 149.02348 -38.676695) (xy 148.969523 -38.690801) (xy 148.914086 -38.696901)
			(xy 148.858352 -38.694864) (xy 148.803509 -38.684734) (xy 148.750725 -38.666727) (xy 148.701125 -38.641226)
			(xy 148.655767 -38.608775) (xy 148.615618 -38.570066) (xy 148.581532 -38.525923) (xy 148.554236 -38.477288)
			(xy 148.534313 -38.425197) (xy 148.522187 -38.37076) (xy 148.518116 -38.315138) (xy 134.579555 -38.315138)
			(xy 134.598097 -38.354691) (xy 134.614165 -38.408098) (xy 134.622285 -38.463274) (xy 134.622794 -38.49116)
			(xy 134.622285 -38.519046) (xy 134.614165 -38.574222) (xy 134.598097 -38.627629) (xy 134.574425 -38.678126)
			(xy 134.559147 -38.701218) (xy 137.537696 -38.701218) (xy 137.541767 -38.645596) (xy 137.553893 -38.591159)
			(xy 137.573816 -38.539068) (xy 137.601112 -38.490433) (xy 137.635198 -38.44629) (xy 137.675347 -38.407581)
			(xy 137.720705 -38.37513) (xy 137.770305 -38.349629) (xy 137.823089 -38.331622) (xy 137.877932 -38.321492)
			(xy 137.933666 -38.319455) (xy 137.989103 -38.325555) (xy 138.04306 -38.339661) (xy 138.094389 -38.361473)
			(xy 138.141995 -38.390527) (xy 138.184863 -38.426202) (xy 138.22208 -38.467739) (xy 138.252853 -38.514252)
			(xy 138.276525 -38.564749) (xy 138.292593 -38.618156) (xy 138.300713 -38.673332) (xy 138.301222 -38.701218)
			(xy 138.301194 -38.702742) (xy 139.800074 -38.702742) (xy 139.804145 -38.64712) (xy 139.816271 -38.592683)
			(xy 139.836194 -38.540592) (xy 139.86349 -38.491957) (xy 139.897576 -38.447814) (xy 139.937725 -38.409105)
			(xy 139.983083 -38.376654) (xy 140.032683 -38.351153) (xy 140.085467 -38.333146) (xy 140.14031 -38.323016)
			(xy 140.196044 -38.320979) (xy 140.251481 -38.327079) (xy 140.305438 -38.341185) (xy 140.356767 -38.362997)
			(xy 140.404373 -38.392051) (xy 140.447241 -38.427726) (xy 140.484458 -38.469263) (xy 140.515231 -38.515776)
			(xy 140.538903 -38.566273) (xy 140.554971 -38.61968) (xy 140.563091 -38.674856) (xy 140.5636 -38.702742)
			(xy 140.563091 -38.730628) (xy 140.554971 -38.785804) (xy 140.538903 -38.839211) (xy 140.515231 -38.889708)
			(xy 140.484458 -38.936221) (xy 140.447241 -38.977758) (xy 140.404373 -39.013433) (xy 140.356767 -39.042487)
			(xy 140.305438 -39.064299) (xy 140.251481 -39.078405) (xy 140.196044 -39.084505) (xy 140.14031 -39.082468)
			(xy 140.085467 -39.072338) (xy 140.032683 -39.054331) (xy 139.983083 -39.02883) (xy 139.937725 -38.996379)
			(xy 139.897576 -38.95767) (xy 139.86349 -38.913527) (xy 139.836194 -38.864892) (xy 139.816271 -38.812801)
			(xy 139.804145 -38.758364) (xy 139.800074 -38.702742) (xy 138.301194 -38.702742) (xy 138.300713 -38.729104)
			(xy 138.292593 -38.78428) (xy 138.276525 -38.837687) (xy 138.252853 -38.888184) (xy 138.22208 -38.934697)
			(xy 138.184863 -38.976234) (xy 138.141995 -39.011909) (xy 138.094389 -39.040963) (xy 138.04306 -39.062775)
			(xy 137.989103 -39.076881) (xy 137.933666 -39.082981) (xy 137.877932 -39.080944) (xy 137.823089 -39.070814)
			(xy 137.770305 -39.052807) (xy 137.720705 -39.027306) (xy 137.675347 -38.994855) (xy 137.635198 -38.956146)
			(xy 137.601112 -38.912003) (xy 137.573816 -38.863368) (xy 137.553893 -38.811277) (xy 137.541767 -38.75684)
			(xy 137.537696 -38.701218) (xy 134.559147 -38.701218) (xy 134.543652 -38.724639) (xy 134.506435 -38.766176)
			(xy 134.463567 -38.801851) (xy 134.415961 -38.830905) (xy 134.364632 -38.852717) (xy 134.310675 -38.866823)
			(xy 134.255238 -38.872923) (xy 134.199504 -38.870886) (xy 134.144661 -38.860756) (xy 134.091877 -38.842749)
			(xy 134.042277 -38.817248) (xy 133.996919 -38.784797) (xy 133.95677 -38.746088) (xy 133.922684 -38.701945)
			(xy 133.895388 -38.65331) (xy 133.875465 -38.601219) (xy 133.863339 -38.546782) (xy 133.859268 -38.49116)
			(xy 130.867568 -38.49116) (xy 130.852552 -38.529921) (xy 130.813827 -38.607692) (xy 130.768092 -38.681558)
			(xy 130.715737 -38.750889) (xy 130.657207 -38.815093) (xy 130.593004 -38.873624) (xy 130.523674 -38.925981)
			(xy 130.449809 -38.971717) (xy 130.372039 -39.010444) (xy 130.291028 -39.041829) (xy 130.207466 -39.065606)
			(xy 130.122067 -39.081572) (xy 130.035559 -39.089589) (xy 129.99212 -39.090092) (xy 128.13792 -39.090092)
			(xy 128.094482 -39.08953) (xy 128.007977 -39.081516) (xy 127.922581 -39.065555) (xy 127.839022 -39.041781)
			(xy 127.758012 -39.0104) (xy 127.680244 -38.971677) (xy 127.606381 -38.925944) (xy 127.537052 -38.873591)
			(xy 127.47285 -38.815064) (xy 127.414322 -38.750863) (xy 127.361967 -38.681536) (xy 127.316232 -38.607673)
			(xy 127.277508 -38.529906) (xy 127.246125 -38.448897) (xy 127.22235 -38.365338) (xy 127.206387 -38.279942)
			(xy 127.198371 -38.193438) (xy 123.26144 -38.193438) (xy 123.273065 -38.232076) (xy 123.281185 -38.287252)
			(xy 123.281694 -38.315138) (xy 123.281185 -38.343024) (xy 123.273065 -38.3982) (xy 123.256997 -38.451607)
			(xy 123.233325 -38.502104) (xy 123.202552 -38.548617) (xy 123.165335 -38.590154) (xy 123.122467 -38.625829)
			(xy 123.074861 -38.654883) (xy 123.023532 -38.676695) (xy 122.969575 -38.690801) (xy 122.914138 -38.696901)
			(xy 122.858404 -38.694864) (xy 122.803561 -38.684734) (xy 122.750777 -38.666727) (xy 122.701177 -38.641226)
			(xy 122.655819 -38.608775) (xy 122.61567 -38.570066) (xy 122.581584 -38.525923) (xy 122.554288 -38.477288)
			(xy 122.534365 -38.425197) (xy 122.522239 -38.37076) (xy 122.518168 -38.315138) (xy 108.579607 -38.315138)
			(xy 108.598149 -38.354691) (xy 108.614217 -38.408098) (xy 108.622337 -38.463274) (xy 108.622846 -38.49116)
			(xy 108.622337 -38.519046) (xy 108.614217 -38.574222) (xy 108.598149 -38.627629) (xy 108.574477 -38.678126)
			(xy 108.559199 -38.701218) (xy 111.537748 -38.701218) (xy 111.541819 -38.645596) (xy 111.553945 -38.591159)
			(xy 111.573868 -38.539068) (xy 111.601164 -38.490433) (xy 111.63525 -38.44629) (xy 111.675399 -38.407581)
			(xy 111.720757 -38.37513) (xy 111.770357 -38.349629) (xy 111.823141 -38.331622) (xy 111.877984 -38.321492)
			(xy 111.933718 -38.319455) (xy 111.989155 -38.325555) (xy 112.043112 -38.339661) (xy 112.094441 -38.361473)
			(xy 112.142047 -38.390527) (xy 112.184915 -38.426202) (xy 112.222132 -38.467739) (xy 112.252905 -38.514252)
			(xy 112.276577 -38.564749) (xy 112.292645 -38.618156) (xy 112.300765 -38.673332) (xy 112.301274 -38.701218)
			(xy 112.301246 -38.702742) (xy 113.800126 -38.702742) (xy 113.804197 -38.64712) (xy 113.816323 -38.592683)
			(xy 113.836246 -38.540592) (xy 113.863542 -38.491957) (xy 113.897628 -38.447814) (xy 113.937777 -38.409105)
			(xy 113.983135 -38.376654) (xy 114.032735 -38.351153) (xy 114.085519 -38.333146) (xy 114.140362 -38.323016)
			(xy 114.196096 -38.320979) (xy 114.251533 -38.327079) (xy 114.30549 -38.341185) (xy 114.356819 -38.362997)
			(xy 114.404425 -38.392051) (xy 114.447293 -38.427726) (xy 114.48451 -38.469263) (xy 114.515283 -38.515776)
			(xy 114.538955 -38.566273) (xy 114.555023 -38.61968) (xy 114.563143 -38.674856) (xy 114.563652 -38.702742)
			(xy 114.563143 -38.730628) (xy 114.555023 -38.785804) (xy 114.538955 -38.839211) (xy 114.515283 -38.889708)
			(xy 114.48451 -38.936221) (xy 114.447293 -38.977758) (xy 114.404425 -39.013433) (xy 114.356819 -39.042487)
			(xy 114.30549 -39.064299) (xy 114.251533 -39.078405) (xy 114.196096 -39.084505) (xy 114.140362 -39.082468)
			(xy 114.085519 -39.072338) (xy 114.032735 -39.054331) (xy 113.983135 -39.02883) (xy 113.937777 -38.996379)
			(xy 113.897628 -38.95767) (xy 113.863542 -38.913527) (xy 113.836246 -38.864892) (xy 113.816323 -38.812801)
			(xy 113.804197 -38.758364) (xy 113.800126 -38.702742) (xy 112.301246 -38.702742) (xy 112.300765 -38.729104)
			(xy 112.292645 -38.78428) (xy 112.276577 -38.837687) (xy 112.252905 -38.888184) (xy 112.222132 -38.934697)
			(xy 112.184915 -38.976234) (xy 112.142047 -39.011909) (xy 112.094441 -39.040963) (xy 112.043112 -39.062775)
			(xy 111.989155 -39.076881) (xy 111.933718 -39.082981) (xy 111.877984 -39.080944) (xy 111.823141 -39.070814)
			(xy 111.770357 -39.052807) (xy 111.720757 -39.027306) (xy 111.675399 -38.994855) (xy 111.63525 -38.956146)
			(xy 111.601164 -38.912003) (xy 111.573868 -38.863368) (xy 111.553945 -38.811277) (xy 111.541819 -38.75684)
			(xy 111.537748 -38.701218) (xy 108.559199 -38.701218) (xy 108.543704 -38.724639) (xy 108.506487 -38.766176)
			(xy 108.463619 -38.801851) (xy 108.416013 -38.830905) (xy 108.364684 -38.852717) (xy 108.310727 -38.866823)
			(xy 108.25529 -38.872923) (xy 108.199556 -38.870886) (xy 108.144713 -38.860756) (xy 108.091929 -38.842749)
			(xy 108.042329 -38.817248) (xy 107.996971 -38.784797) (xy 107.956822 -38.746088) (xy 107.922736 -38.701945)
			(xy 107.89544 -38.65331) (xy 107.875517 -38.601219) (xy 107.863391 -38.546782) (xy 107.85932 -38.49116)
			(xy 92.767384 -38.49116) (xy 92.75236 -38.52994) (xy 92.713632 -38.607714) (xy 92.667893 -38.681583)
			(xy 92.615533 -38.750917) (xy 92.556999 -38.815123) (xy 92.49279 -38.873655) (xy 92.423455 -38.926012)
			(xy 92.349584 -38.971748) (xy 92.271809 -39.010473) (xy 92.190792 -39.041857) (xy 92.107225 -39.065631)
			(xy 92.02182 -39.081593) (xy 91.935308 -39.089607) (xy 91.891866 -39.090092) (xy 90.037666 -39.090092)
			(xy 89.994231 -39.089513) (xy 89.907731 -39.081495) (xy 89.82234 -39.065529) (xy 89.738786 -39.041754)
			(xy 89.657782 -39.01037) (xy 89.58002 -38.971646) (xy 89.506162 -38.925913) (xy 89.436838 -38.87356)
			(xy 89.372641 -38.815035) (xy 89.314118 -38.750835) (xy 89.261768 -38.68151) (xy 89.216037 -38.607651)
			(xy 89.177316 -38.529887) (xy 89.145936 -38.448882) (xy 89.122163 -38.365327) (xy 89.106201 -38.279936)
			(xy 89.098186 -38.193435) (xy 85.161185 -38.193435) (xy 85.172811 -38.232076) (xy 85.180931 -38.287252)
			(xy 85.18144 -38.315138) (xy 85.180931 -38.343024) (xy 85.172811 -38.3982) (xy 85.156743 -38.451607)
			(xy 85.133071 -38.502104) (xy 85.102298 -38.548617) (xy 85.065081 -38.590154) (xy 85.022213 -38.625829)
			(xy 84.974607 -38.654883) (xy 84.923278 -38.676695) (xy 84.869321 -38.690801) (xy 84.813884 -38.696901)
			(xy 84.75815 -38.694864) (xy 84.703307 -38.684734) (xy 84.650523 -38.666727) (xy 84.600923 -38.641226)
			(xy 84.555565 -38.608775) (xy 84.515416 -38.570066) (xy 84.48133 -38.525923) (xy 84.454034 -38.477288)
			(xy 84.434111 -38.425197) (xy 84.421985 -38.37076) (xy 84.417914 -38.315138) (xy 70.479353 -38.315138)
			(xy 70.497895 -38.354691) (xy 70.513963 -38.408098) (xy 70.522083 -38.463274) (xy 70.522592 -38.49116)
			(xy 70.522083 -38.519046) (xy 70.513963 -38.574222) (xy 70.497895 -38.627629) (xy 70.474223 -38.678126)
			(xy 70.458945 -38.701218) (xy 73.437494 -38.701218) (xy 73.441565 -38.645596) (xy 73.453691 -38.591159)
			(xy 73.473614 -38.539068) (xy 73.50091 -38.490433) (xy 73.534996 -38.44629) (xy 73.575145 -38.407581)
			(xy 73.620503 -38.37513) (xy 73.670103 -38.349629) (xy 73.722887 -38.331622) (xy 73.77773 -38.321492)
			(xy 73.833464 -38.319455) (xy 73.888901 -38.325555) (xy 73.942858 -38.339661) (xy 73.994187 -38.361473)
			(xy 74.041793 -38.390527) (xy 74.084661 -38.426202) (xy 74.121878 -38.467739) (xy 74.152651 -38.514252)
			(xy 74.176323 -38.564749) (xy 74.192391 -38.618156) (xy 74.200511 -38.673332) (xy 74.20102 -38.701218)
			(xy 74.200992 -38.702742) (xy 75.699872 -38.702742) (xy 75.703943 -38.64712) (xy 75.716069 -38.592683)
			(xy 75.735992 -38.540592) (xy 75.763288 -38.491957) (xy 75.797374 -38.447814) (xy 75.837523 -38.409105)
			(xy 75.882881 -38.376654) (xy 75.932481 -38.351153) (xy 75.985265 -38.333146) (xy 76.040108 -38.323016)
			(xy 76.095842 -38.320979) (xy 76.151279 -38.327079) (xy 76.205236 -38.341185) (xy 76.256565 -38.362997)
			(xy 76.304171 -38.392051) (xy 76.347039 -38.427726) (xy 76.384256 -38.469263) (xy 76.415029 -38.515776)
			(xy 76.438701 -38.566273) (xy 76.454769 -38.61968) (xy 76.462889 -38.674856) (xy 76.463398 -38.702742)
			(xy 76.462889 -38.730628) (xy 76.454769 -38.785804) (xy 76.438701 -38.839211) (xy 76.415029 -38.889708)
			(xy 76.384256 -38.936221) (xy 76.347039 -38.977758) (xy 76.304171 -39.013433) (xy 76.256565 -39.042487)
			(xy 76.205236 -39.064299) (xy 76.151279 -39.078405) (xy 76.095842 -39.084505) (xy 76.040108 -39.082468)
			(xy 75.985265 -39.072338) (xy 75.932481 -39.054331) (xy 75.882881 -39.02883) (xy 75.837523 -38.996379)
			(xy 75.797374 -38.95767) (xy 75.763288 -38.913527) (xy 75.735992 -38.864892) (xy 75.716069 -38.812801)
			(xy 75.703943 -38.758364) (xy 75.699872 -38.702742) (xy 74.200992 -38.702742) (xy 74.200511 -38.729104)
			(xy 74.192391 -38.78428) (xy 74.176323 -38.837687) (xy 74.152651 -38.888184) (xy 74.121878 -38.934697)
			(xy 74.084661 -38.976234) (xy 74.041793 -39.011909) (xy 73.994187 -39.040963) (xy 73.942858 -39.062775)
			(xy 73.888901 -39.076881) (xy 73.833464 -39.082981) (xy 73.77773 -39.080944) (xy 73.722887 -39.070814)
			(xy 73.670103 -39.052807) (xy 73.620503 -39.027306) (xy 73.575145 -38.994855) (xy 73.534996 -38.956146)
			(xy 73.50091 -38.912003) (xy 73.473614 -38.863368) (xy 73.453691 -38.811277) (xy 73.441565 -38.75684)
			(xy 73.437494 -38.701218) (xy 70.458945 -38.701218) (xy 70.44345 -38.724639) (xy 70.406233 -38.766176)
			(xy 70.363365 -38.801851) (xy 70.315759 -38.830905) (xy 70.26443 -38.852717) (xy 70.210473 -38.866823)
			(xy 70.155036 -38.872923) (xy 70.099302 -38.870886) (xy 70.044459 -38.860756) (xy 69.991675 -38.842749)
			(xy 69.942075 -38.817248) (xy 69.896717 -38.784797) (xy 69.856568 -38.746088) (xy 69.822482 -38.701945)
			(xy 69.795186 -38.65331) (xy 69.775263 -38.601219) (xy 69.763137 -38.546782) (xy 69.759066 -38.49116)
			(xy 66.767368 -38.49116) (xy 66.752352 -38.529921) (xy 66.713627 -38.607692) (xy 66.667892 -38.681558)
			(xy 66.615536 -38.750889) (xy 66.557007 -38.815094) (xy 66.492803 -38.873624) (xy 66.423473 -38.925981)
			(xy 66.349608 -38.971718) (xy 66.271838 -39.010444) (xy 66.190826 -39.04183) (xy 66.107264 -39.065606)
			(xy 66.021865 -39.081572) (xy 65.935357 -39.08959) (xy 65.891918 -39.090092) (xy 64.037718 -39.090092)
			(xy 63.99428 -39.08953) (xy 63.907776 -39.081516) (xy 63.822379 -39.065554) (xy 63.73882 -39.041781)
			(xy 63.657811 -39.010399) (xy 63.580043 -38.971677) (xy 63.50618 -38.925944) (xy 63.436851 -38.87359)
			(xy 63.372649 -38.815064) (xy 63.314121 -38.750863) (xy 63.261767 -38.681535) (xy 63.216032 -38.607673)
			(xy 63.177308 -38.529905) (xy 63.145925 -38.448897) (xy 63.12215 -38.365338) (xy 63.106187 -38.279942)
			(xy 63.098171 -38.193438) (xy 59.161238 -38.193438) (xy 59.172863 -38.232076) (xy 59.180983 -38.287252)
			(xy 59.181492 -38.315138) (xy 59.180983 -38.343024) (xy 59.172863 -38.3982) (xy 59.156795 -38.451607)
			(xy 59.133123 -38.502104) (xy 59.10235 -38.548617) (xy 59.065133 -38.590154) (xy 59.022265 -38.625829)
			(xy 58.974659 -38.654883) (xy 58.92333 -38.676695) (xy 58.869373 -38.690801) (xy 58.813936 -38.696901)
			(xy 58.758202 -38.694864) (xy 58.703359 -38.684734) (xy 58.650575 -38.666727) (xy 58.600975 -38.641226)
			(xy 58.555617 -38.608775) (xy 58.515468 -38.570066) (xy 58.481382 -38.525923) (xy 58.454086 -38.477288)
			(xy 58.434163 -38.425197) (xy 58.422037 -38.37076) (xy 58.417966 -38.315138) (xy 44.479405 -38.315138)
			(xy 44.497947 -38.354691) (xy 44.514015 -38.408098) (xy 44.522135 -38.463274) (xy 44.522644 -38.49116)
			(xy 44.522135 -38.519046) (xy 44.514015 -38.574222) (xy 44.497947 -38.627629) (xy 44.474275 -38.678126)
			(xy 44.458997 -38.701218) (xy 47.437546 -38.701218) (xy 47.441617 -38.645596) (xy 47.453743 -38.591159)
			(xy 47.473666 -38.539068) (xy 47.500962 -38.490433) (xy 47.535048 -38.44629) (xy 47.575197 -38.407581)
			(xy 47.620555 -38.37513) (xy 47.670155 -38.349629) (xy 47.722939 -38.331622) (xy 47.777782 -38.321492)
			(xy 47.833516 -38.319455) (xy 47.888953 -38.325555) (xy 47.94291 -38.339661) (xy 47.994239 -38.361473)
			(xy 48.041845 -38.390527) (xy 48.084713 -38.426202) (xy 48.12193 -38.467739) (xy 48.152703 -38.514252)
			(xy 48.176375 -38.564749) (xy 48.192443 -38.618156) (xy 48.200563 -38.673332) (xy 48.201072 -38.701218)
			(xy 48.201044 -38.702742) (xy 49.699924 -38.702742) (xy 49.703995 -38.64712) (xy 49.716121 -38.592683)
			(xy 49.736044 -38.540592) (xy 49.76334 -38.491957) (xy 49.797426 -38.447814) (xy 49.837575 -38.409105)
			(xy 49.882933 -38.376654) (xy 49.932533 -38.351153) (xy 49.985317 -38.333146) (xy 50.04016 -38.323016)
			(xy 50.095894 -38.320979) (xy 50.151331 -38.327079) (xy 50.205288 -38.341185) (xy 50.256617 -38.362997)
			(xy 50.304223 -38.392051) (xy 50.347091 -38.427726) (xy 50.384308 -38.469263) (xy 50.415081 -38.515776)
			(xy 50.438753 -38.566273) (xy 50.454821 -38.61968) (xy 50.462941 -38.674856) (xy 50.46345 -38.702742)
			(xy 50.462941 -38.730628) (xy 50.454821 -38.785804) (xy 50.438753 -38.839211) (xy 50.415081 -38.889708)
			(xy 50.384308 -38.936221) (xy 50.347091 -38.977758) (xy 50.304223 -39.013433) (xy 50.256617 -39.042487)
			(xy 50.205288 -39.064299) (xy 50.151331 -39.078405) (xy 50.095894 -39.084505) (xy 50.04016 -39.082468)
			(xy 49.985317 -39.072338) (xy 49.932533 -39.054331) (xy 49.882933 -39.02883) (xy 49.837575 -38.996379)
			(xy 49.797426 -38.95767) (xy 49.76334 -38.913527) (xy 49.736044 -38.864892) (xy 49.716121 -38.812801)
			(xy 49.703995 -38.758364) (xy 49.699924 -38.702742) (xy 48.201044 -38.702742) (xy 48.200563 -38.729104)
			(xy 48.192443 -38.78428) (xy 48.176375 -38.837687) (xy 48.152703 -38.888184) (xy 48.12193 -38.934697)
			(xy 48.084713 -38.976234) (xy 48.041845 -39.011909) (xy 47.994239 -39.040963) (xy 47.94291 -39.062775)
			(xy 47.888953 -39.076881) (xy 47.833516 -39.082981) (xy 47.777782 -39.080944) (xy 47.722939 -39.070814)
			(xy 47.670155 -39.052807) (xy 47.620555 -39.027306) (xy 47.575197 -38.994855) (xy 47.535048 -38.956146)
			(xy 47.500962 -38.912003) (xy 47.473666 -38.863368) (xy 47.453743 -38.811277) (xy 47.441617 -38.75684)
			(xy 47.437546 -38.701218) (xy 44.458997 -38.701218) (xy 44.443502 -38.724639) (xy 44.406285 -38.766176)
			(xy 44.363417 -38.801851) (xy 44.315811 -38.830905) (xy 44.264482 -38.852717) (xy 44.210525 -38.866823)
			(xy 44.155088 -38.872923) (xy 44.099354 -38.870886) (xy 44.044511 -38.860756) (xy 43.991727 -38.842749)
			(xy 43.942127 -38.817248) (xy 43.896769 -38.784797) (xy 43.85662 -38.746088) (xy 43.822534 -38.701945)
			(xy 43.795238 -38.65331) (xy 43.775315 -38.601219) (xy 43.763189 -38.546782) (xy 43.759118 -38.49116)
			(xy 40.76741 -38.49116) (xy 40.752383 -38.52995) (xy 40.713659 -38.607718) (xy 40.667925 -38.681581)
			(xy 40.61557 -38.75091) (xy 40.557042 -38.815112) (xy 40.49284 -38.87364) (xy 40.423511 -38.925995)
			(xy 40.349648 -38.971729) (xy 40.27188 -39.010453) (xy 40.19087 -39.041836) (xy 40.10731 -39.065611)
			(xy 40.021914 -39.081574) (xy 39.935408 -39.08959) (xy 39.89197 -39.090092) (xy 38.03777 -39.090092)
			(xy 37.994332 -39.089594) (xy 37.907826 -39.081578) (xy 37.822429 -39.065615) (xy 37.738869 -39.04184)
			(xy 37.657859 -39.010457) (xy 37.58009 -38.971733) (xy 37.506226 -38.925998) (xy 37.436898 -38.873643)
			(xy 37.372695 -38.815115) (xy 37.314167 -38.750912) (xy 37.261812 -38.681584) (xy 37.216077 -38.60772)
			(xy 37.177353 -38.529951) (xy 37.14597 -38.448941) (xy 37.122195 -38.365381) (xy 37.106232 -38.279984)
			(xy 37.098216 -38.193478) (xy 33.161302 -38.193478) (xy 33.172915 -38.232076) (xy 33.181035 -38.287252)
			(xy 33.181544 -38.315138) (xy 33.181035 -38.343024) (xy 33.172915 -38.3982) (xy 33.156847 -38.451607)
			(xy 33.133175 -38.502104) (xy 33.102402 -38.548617) (xy 33.065185 -38.590154) (xy 33.022317 -38.625829)
			(xy 32.974711 -38.654883) (xy 32.923382 -38.676695) (xy 32.869425 -38.690801) (xy 32.813988 -38.696901)
			(xy 32.758254 -38.694864) (xy 32.703411 -38.684734) (xy 32.650627 -38.666727) (xy 32.601027 -38.641226)
			(xy 32.555669 -38.608775) (xy 32.51552 -38.570066) (xy 32.481434 -38.525923) (xy 32.454138 -38.477288)
			(xy 32.434215 -38.425197) (xy 32.422089 -38.37076) (xy 32.418018 -38.315138) (xy 18.479457 -38.315138)
			(xy 18.497999 -38.354691) (xy 18.514067 -38.408098) (xy 18.522187 -38.463274) (xy 18.522696 -38.49116)
			(xy 18.522187 -38.519046) (xy 18.514067 -38.574222) (xy 18.497999 -38.627629) (xy 18.474327 -38.678126)
			(xy 18.459049 -38.701218) (xy 21.437598 -38.701218) (xy 21.441669 -38.645596) (xy 21.453795 -38.591159)
			(xy 21.473718 -38.539068) (xy 21.501014 -38.490433) (xy 21.5351 -38.44629) (xy 21.575249 -38.407581)
			(xy 21.620607 -38.37513) (xy 21.670207 -38.349629) (xy 21.722991 -38.331622) (xy 21.777834 -38.321492)
			(xy 21.833568 -38.319455) (xy 21.889005 -38.325555) (xy 21.942962 -38.339661) (xy 21.994291 -38.361473)
			(xy 22.041897 -38.390527) (xy 22.084765 -38.426202) (xy 22.121982 -38.467739) (xy 22.152755 -38.514252)
			(xy 22.176427 -38.564749) (xy 22.192495 -38.618156) (xy 22.200615 -38.673332) (xy 22.201124 -38.701218)
			(xy 22.201096 -38.702742) (xy 23.699976 -38.702742) (xy 23.704047 -38.64712) (xy 23.716173 -38.592683)
			(xy 23.736096 -38.540592) (xy 23.763392 -38.491957) (xy 23.797478 -38.447814) (xy 23.837627 -38.409105)
			(xy 23.882985 -38.376654) (xy 23.932585 -38.351153) (xy 23.985369 -38.333146) (xy 24.040212 -38.323016)
			(xy 24.095946 -38.320979) (xy 24.151383 -38.327079) (xy 24.20534 -38.341185) (xy 24.256669 -38.362997)
			(xy 24.304275 -38.392051) (xy 24.347143 -38.427726) (xy 24.38436 -38.469263) (xy 24.415133 -38.515776)
			(xy 24.438805 -38.566273) (xy 24.454873 -38.61968) (xy 24.462993 -38.674856) (xy 24.463502 -38.702742)
			(xy 24.462993 -38.730628) (xy 24.454873 -38.785804) (xy 24.438805 -38.839211) (xy 24.415133 -38.889708)
			(xy 24.38436 -38.936221) (xy 24.347143 -38.977758) (xy 24.304275 -39.013433) (xy 24.256669 -39.042487)
			(xy 24.20534 -39.064299) (xy 24.151383 -39.078405) (xy 24.095946 -39.084505) (xy 24.040212 -39.082468)
			(xy 23.985369 -39.072338) (xy 23.932585 -39.054331) (xy 23.882985 -39.02883) (xy 23.837627 -38.996379)
			(xy 23.797478 -38.95767) (xy 23.763392 -38.913527) (xy 23.736096 -38.864892) (xy 23.716173 -38.812801)
			(xy 23.704047 -38.758364) (xy 23.699976 -38.702742) (xy 22.201096 -38.702742) (xy 22.200615 -38.729104)
			(xy 22.192495 -38.78428) (xy 22.176427 -38.837687) (xy 22.152755 -38.888184) (xy 22.121982 -38.934697)
			(xy 22.084765 -38.976234) (xy 22.041897 -39.011909) (xy 21.994291 -39.040963) (xy 21.942962 -39.062775)
			(xy 21.889005 -39.076881) (xy 21.833568 -39.082981) (xy 21.777834 -39.080944) (xy 21.722991 -39.070814)
			(xy 21.670207 -39.052807) (xy 21.620607 -39.027306) (xy 21.575249 -38.994855) (xy 21.5351 -38.956146)
			(xy 21.501014 -38.912003) (xy 21.473718 -38.863368) (xy 21.453795 -38.811277) (xy 21.441669 -38.75684)
			(xy 21.437598 -38.701218) (xy 18.459049 -38.701218) (xy 18.443554 -38.724639) (xy 18.406337 -38.766176)
			(xy 18.363469 -38.801851) (xy 18.315863 -38.830905) (xy 18.264534 -38.852717) (xy 18.210577 -38.866823)
			(xy 18.15514 -38.872923) (xy 18.099406 -38.870886) (xy 18.044563 -38.860756) (xy 17.991779 -38.842749)
			(xy 17.942179 -38.817248) (xy 17.896821 -38.784797) (xy 17.856672 -38.746088) (xy 17.822586 -38.701945)
			(xy 17.79529 -38.65331) (xy 17.775367 -38.601219) (xy 17.763241 -38.546782) (xy 17.75917 -38.49116)
			(xy 14.76746 -38.49116) (xy 14.752433 -38.529949) (xy 14.713709 -38.607717) (xy 14.667975 -38.681581)
			(xy 14.615621 -38.750909) (xy 14.557093 -38.815111) (xy 14.492891 -38.873639) (xy 14.423562 -38.925994)
			(xy 14.349699 -38.971728) (xy 14.271931 -39.010452) (xy 14.190921 -39.041836) (xy 14.107362 -39.065611)
			(xy 14.021965 -39.081574) (xy 13.93546 -39.08959) (xy 13.892022 -39.090092) (xy 12.037822 -39.090092)
			(xy 11.994383 -39.089609) (xy 11.907876 -39.081594) (xy 11.822477 -39.06563) (xy 11.738915 -39.041855)
			(xy 11.657904 -39.010471) (xy 11.580134 -38.971746) (xy 11.506269 -38.926011) (xy 11.436939 -38.873655)
			(xy 11.372735 -38.815126) (xy 11.314206 -38.750923) (xy 11.26185 -38.681593) (xy 11.216115 -38.607728)
			(xy 11.17739 -38.529958) (xy 11.146006 -38.448946) (xy 11.122231 -38.365385) (xy 11.106267 -38.279986)
			(xy 11.098251 -38.193479) (xy 7.614753 -38.193479) (xy 7.645976 -38.213545) (xy 7.687166 -38.249237)
			(xy 7.722857 -38.290428) (xy 7.752324 -38.336278) (xy 7.774965 -38.385856) (xy 7.79032 -38.438151)
			(xy 7.798076 -38.492099) (xy 7.798076 -38.546601) (xy 7.79032 -38.600549) (xy 7.774965 -38.652844)
			(xy 7.752324 -38.702422) (xy 7.722857 -38.748272) (xy 7.687166 -38.789463) (xy 7.645976 -38.825155)
			(xy 7.600125 -38.854622) (xy 7.550548 -38.877263) (xy 7.498253 -38.892619) (xy 7.444305 -38.900376)
			(xy 7.417054 -38.900862) (xy 7.388138 -38.900319) (xy 7.330967 -38.891598) (xy 7.275768 -38.874345)
			(xy 7.223806 -38.848958) (xy 7.176272 -38.816018) (xy 7.134254 -38.77628) (xy 7.116064 -38.753796)
			(xy 7.108463 -38.744982) (xy 7.087558 -38.734802) (xy 7.075932 -38.734238) (xy 6.996176 -38.734238)
			(xy 6.984542 -38.734764) (xy 6.963632 -38.744961) (xy 6.956044 -38.753796) (xy 6.937827 -38.776258)
			(xy 6.895813 -38.815994) (xy 6.848283 -38.848936) (xy 6.796327 -38.874328) (xy 6.741134 -38.891589)
			(xy 6.683968 -38.900324) (xy 6.655054 -38.900862) (xy 6.627801 -38.900391) (xy 6.57385 -38.892635)
			(xy 6.521553 -38.877279) (xy 6.471973 -38.854637) (xy 6.426119 -38.825169) (xy 6.384927 -38.789476)
			(xy 6.349233 -38.748284) (xy 6.319765 -38.702431) (xy 6.297122 -38.652851) (xy 6.281766 -38.600553)
			(xy 6.274009 -38.546603) (xy 3.040664 -38.546603) (xy 3.072279 -38.577394) (xy 3.090418 -38.600634)
			(xy 3.090672 -38.600888) (xy 3.097004 -38.608481) (xy 3.113988 -38.618558) (xy 3.123692 -38.620446)
			(xy 3.204464 -38.632384) (xy 3.223768 -38.627558) (xy 3.231642 -38.621716) (xy 3.231896 -38.621716)
			(xy 3.256621 -38.604185) (xy 3.310481 -38.576389) (xy 3.368059 -38.55746) (xy 3.427905 -38.547877)
			(xy 3.45821 -38.547294) (xy 3.486746 -38.547858) (xy 3.543179 -38.55638) (xy 3.597711 -38.573215)
			(xy 3.649126 -38.597989) (xy 3.696275 -38.630148) (xy 3.738106 -38.668974) (xy 3.773683 -38.7136)
			(xy 3.78841 -38.738048) (xy 3.793128 -38.745593) (xy 3.806745 -38.757035) (xy 3.823459 -38.763116)
			(xy 3.832352 -38.763448) (xy 3.920744 -38.763448) (xy 3.929622 -38.763048) (xy 3.9463 -38.756952)
			(xy 3.959905 -38.745539) (xy 3.964686 -38.738048) (xy 3.979347 -38.713554) (xy 4.01492 -38.668907)
			(xy 4.056754 -38.630065) (xy 4.103914 -38.597897) (xy 4.155344 -38.573123) (xy 4.209894 -38.556297)
			(xy 4.266343 -38.547795) (xy 4.294886 -38.547294) (xy 4.322139 -38.547753) (xy 4.376091 -38.55551)
			(xy 4.428389 -38.570865) (xy 4.47797 -38.593508) (xy 4.523824 -38.622976) (xy 4.565018 -38.65867)
			(xy 4.600712 -38.699863) (xy 4.63018 -38.745716) (xy 4.652823 -38.795297) (xy 4.66818 -38.847595)
			(xy 4.675937 -38.901547) (xy 4.675937 -38.928802) (xy 5.182868 -38.928802) (xy 5.186939 -38.87318)
			(xy 5.199065 -38.818743) (xy 5.218988 -38.766652) (xy 5.246284 -38.718017) (xy 5.28037 -38.673874)
			(xy 5.320519 -38.635165) (xy 5.365877 -38.602714) (xy 5.415477 -38.577213) (xy 5.468261 -38.559206)
			(xy 5.523104 -38.549076) (xy 5.578838 -38.547039) (xy 5.634275 -38.553139) (xy 5.688232 -38.567245)
			(xy 5.739561 -38.589057) (xy 5.787167 -38.618111) (xy 5.830035 -38.653786) (xy 5.867252 -38.695323)
			(xy 5.898025 -38.741836) (xy 5.921697 -38.792333) (xy 5.937765 -38.84574) (xy 5.945885 -38.900916)
			(xy 5.946394 -38.928802) (xy 5.945885 -38.956688) (xy 5.937765 -39.011864) (xy 5.921697 -39.065271)
			(xy 5.898025 -39.115768) (xy 5.881067 -39.1414) (xy 224.664776 -39.1414) (xy 224.668847 -39.085778)
			(xy 224.680973 -39.031341) (xy 224.700896 -38.97925) (xy 224.728192 -38.930615) (xy 224.762278 -38.886472)
			(xy 224.802427 -38.847763) (xy 224.847785 -38.815312) (xy 224.897385 -38.789811) (xy 224.950169 -38.771804)
			(xy 225.005012 -38.761674) (xy 225.060746 -38.759637) (xy 225.116183 -38.765737) (xy 225.17014 -38.779843)
			(xy 225.221469 -38.801655) (xy 225.269075 -38.830709) (xy 225.311943 -38.866384) (xy 225.34916 -38.907921)
			(xy 225.379933 -38.954434) (xy 225.403605 -39.004931) (xy 225.419673 -39.058338) (xy 225.427793 -39.113514)
			(xy 225.428302 -39.1414) (xy 225.427793 -39.169286) (xy 225.419673 -39.224462) (xy 225.403605 -39.277869)
			(xy 225.379933 -39.328366) (xy 225.34916 -39.374879) (xy 225.311943 -39.416416) (xy 225.269075 -39.452091)
			(xy 225.221469 -39.481145) (xy 225.17014 -39.502957) (xy 225.116183 -39.517063) (xy 225.060746 -39.523163)
			(xy 225.005012 -39.521126) (xy 224.950169 -39.510996) (xy 224.897385 -39.492989) (xy 224.847785 -39.467488)
			(xy 224.802427 -39.435037) (xy 224.762278 -39.396328) (xy 224.728192 -39.352185) (xy 224.700896 -39.30355)
			(xy 224.680973 -39.251459) (xy 224.668847 -39.197022) (xy 224.664776 -39.1414) (xy 5.881067 -39.1414)
			(xy 5.867252 -39.162281) (xy 5.830035 -39.203818) (xy 5.787167 -39.239493) (xy 5.739561 -39.268547)
			(xy 5.688232 -39.290359) (xy 5.634275 -39.304465) (xy 5.578838 -39.310565) (xy 5.523104 -39.308528)
			(xy 5.468261 -39.298398) (xy 5.415477 -39.280391) (xy 5.365877 -39.25489) (xy 5.320519 -39.222439)
			(xy 5.28037 -39.18373) (xy 5.246284 -39.139587) (xy 5.218988 -39.090952) (xy 5.199065 -39.038861)
			(xy 5.186939 -38.984424) (xy 5.182868 -38.928802) (xy 4.675937 -38.928802) (xy 4.675937 -38.956053)
			(xy 4.66818 -39.010005) (xy 4.652823 -39.062303) (xy 4.63018 -39.111884) (xy 4.600712 -39.157737)
			(xy 4.565018 -39.19893) (xy 4.523824 -39.234624) (xy 4.47797 -39.264092) (xy 4.428389 -39.286735)
			(xy 4.376091 -39.30209) (xy 4.322139 -39.309847) (xy 4.294886 -39.31031) (xy 4.26635 -39.309747)
			(xy 4.209918 -39.301225) (xy 4.155385 -39.284389) (xy 4.10397 -39.259615) (xy 4.056821 -39.227456)
			(xy 4.014991 -39.18863) (xy 3.979413 -39.144004) (xy 3.964686 -39.119556) (xy 3.959969 -39.11201)
			(xy 3.946352 -39.100568) (xy 3.929637 -39.094488) (xy 3.920744 -39.094156) (xy 3.832352 -39.094156)
			(xy 3.823474 -39.094551) (xy 3.806795 -39.100649) (xy 3.793191 -39.112064) (xy 3.78841 -39.119556)
			(xy 3.773715 -39.144029) (xy 3.738148 -39.188676) (xy 3.696319 -39.227519) (xy 3.649165 -39.259689)
			(xy 3.597741 -39.284467) (xy 3.543196 -39.301298) (xy 3.486751 -39.309805) (xy 3.45821 -39.31031)
			(xy 3.431137 -39.309799) (xy 3.377535 -39.302152) (xy 3.325554 -39.286997) (xy 3.276242 -39.264638)
			(xy 3.230589 -39.235526) (xy 3.189515 -39.200247) (xy 3.153848 -39.15951) (xy 3.138678 -39.137082)
			(xy 3.13232 -39.128307) (xy 3.114022 -39.116733) (xy 3.103372 -39.11473) (xy 3.071368 -39.109904)
			(xy 3.060665 -39.108883) (xy 3.040013 -39.114783) (xy 3.03149 -39.121334) (xy 3.019806 -39.130732)
			(xy 3.010995 -39.138336) (xy 3.000813 -39.159239) (xy 3.000248 -39.170864) (xy 3.000248 -39.25062)
			(xy 3.000773 -39.262254) (xy 3.01097 -39.283164) (xy 3.019806 -39.290752) (xy 3.042287 -39.308946)
			(xy 3.082022 -39.350965) (xy 3.114961 -39.3985) (xy 3.14035 -39.45046) (xy 3.157607 -39.505657) (xy 3.166337 -39.562826)
			(xy 3.166872 -39.591742) (xy 3.166423 -39.618987) (xy 3.15866 -39.672922) (xy 3.143299 -39.725202)
			(xy 3.120651 -39.774763) (xy 3.091178 -39.820595) (xy 3.055482 -39.861765) (xy 3.014288 -39.897433)
			(xy 2.991612 -39.912544) (xy 2.984568 -39.917367) (xy 2.974028 -39.930787) (xy 2.968511 -39.946935)
			(xy 2.968244 -39.95547) (xy 2.968244 -39.97198) (xy 25.895806 -39.97198) (xy 25.899877 -39.916358)
			(xy 25.912003 -39.861921) (xy 25.931926 -39.80983) (xy 25.959222 -39.761195) (xy 25.993308 -39.717052)
			(xy 26.033457 -39.678343) (xy 26.078815 -39.645892) (xy 26.128415 -39.620391) (xy 26.181199 -39.602384)
			(xy 26.236042 -39.592254) (xy 26.291776 -39.590217) (xy 26.347213 -39.596317) (xy 26.40117 -39.610423)
			(xy 26.452499 -39.632235) (xy 26.500105 -39.661289) (xy 26.542973 -39.696964) (xy 26.58019 -39.738501)
			(xy 26.610963 -39.785014) (xy 26.634635 -39.835511) (xy 26.650703 -39.888918) (xy 26.658823 -39.944094)
			(xy 26.659332 -39.97198) (xy 51.895754 -39.97198) (xy 51.899825 -39.916358) (xy 51.911951 -39.861921)
			(xy 51.931874 -39.80983) (xy 51.95917 -39.761195) (xy 51.993256 -39.717052) (xy 52.033405 -39.678343)
			(xy 52.078763 -39.645892) (xy 52.128363 -39.620391) (xy 52.181147 -39.602384) (xy 52.23599 -39.592254)
			(xy 52.291724 -39.590217) (xy 52.347161 -39.596317) (xy 52.401118 -39.610423) (xy 52.452447 -39.632235)
			(xy 52.500053 -39.661289) (xy 52.542921 -39.696964) (xy 52.580138 -39.738501) (xy 52.610911 -39.785014)
			(xy 52.634583 -39.835511) (xy 52.650651 -39.888918) (xy 52.658771 -39.944094) (xy 52.65928 -39.97198)
			(xy 77.895702 -39.97198) (xy 77.899773 -39.916358) (xy 77.911899 -39.861921) (xy 77.931822 -39.80983)
			(xy 77.959118 -39.761195) (xy 77.993204 -39.717052) (xy 78.033353 -39.678343) (xy 78.078711 -39.645892)
			(xy 78.128311 -39.620391) (xy 78.181095 -39.602384) (xy 78.235938 -39.592254) (xy 78.291672 -39.590217)
			(xy 78.347109 -39.596317) (xy 78.401066 -39.610423) (xy 78.452395 -39.632235) (xy 78.500001 -39.661289)
			(xy 78.542869 -39.696964) (xy 78.580086 -39.738501) (xy 78.610859 -39.785014) (xy 78.634531 -39.835511)
			(xy 78.650599 -39.888918) (xy 78.658719 -39.944094) (xy 78.659228 -39.97198) (xy 115.995956 -39.97198)
			(xy 116.000027 -39.916358) (xy 116.012153 -39.861921) (xy 116.032076 -39.80983) (xy 116.059372 -39.761195)
			(xy 116.093458 -39.717052) (xy 116.133607 -39.678343) (xy 116.178965 -39.645892) (xy 116.228565 -39.620391)
			(xy 116.281349 -39.602384) (xy 116.336192 -39.592254) (xy 116.391926 -39.590217) (xy 116.447363 -39.596317)
			(xy 116.50132 -39.610423) (xy 116.552649 -39.632235) (xy 116.600255 -39.661289) (xy 116.643123 -39.696964)
			(xy 116.68034 -39.738501) (xy 116.711113 -39.785014) (xy 116.734785 -39.835511) (xy 116.750853 -39.888918)
			(xy 116.758973 -39.944094) (xy 116.759482 -39.97198) (xy 141.995904 -39.97198) (xy 141.999975 -39.916358)
			(xy 142.012101 -39.861921) (xy 142.032024 -39.80983) (xy 142.05932 -39.761195) (xy 142.093406 -39.717052)
			(xy 142.133555 -39.678343) (xy 142.178913 -39.645892) (xy 142.228513 -39.620391) (xy 142.281297 -39.602384)
			(xy 142.33614 -39.592254) (xy 142.391874 -39.590217) (xy 142.447311 -39.596317) (xy 142.501268 -39.610423)
			(xy 142.552597 -39.632235) (xy 142.600203 -39.661289) (xy 142.643071 -39.696964) (xy 142.680288 -39.738501)
			(xy 142.711061 -39.785014) (xy 142.734733 -39.835511) (xy 142.750801 -39.888918) (xy 142.758921 -39.944094)
			(xy 142.75943 -39.97198) (xy 167.995852 -39.97198) (xy 167.999923 -39.916358) (xy 168.012049 -39.861921)
			(xy 168.031972 -39.80983) (xy 168.059268 -39.761195) (xy 168.093354 -39.717052) (xy 168.133503 -39.678343)
			(xy 168.178861 -39.645892) (xy 168.228461 -39.620391) (xy 168.281245 -39.602384) (xy 168.336088 -39.592254)
			(xy 168.391822 -39.590217) (xy 168.447259 -39.596317) (xy 168.501216 -39.610423) (xy 168.552545 -39.632235)
			(xy 168.600151 -39.661289) (xy 168.643019 -39.696964) (xy 168.680236 -39.738501) (xy 168.711009 -39.785014)
			(xy 168.734681 -39.835511) (xy 168.750749 -39.888918) (xy 168.758869 -39.944094) (xy 168.759378 -39.97198)
			(xy 193.9958 -39.97198) (xy 193.999871 -39.916358) (xy 194.011997 -39.861921) (xy 194.03192 -39.80983)
			(xy 194.059216 -39.761195) (xy 194.093302 -39.717052) (xy 194.133451 -39.678343) (xy 194.178809 -39.645892)
			(xy 194.228409 -39.620391) (xy 194.281193 -39.602384) (xy 194.336036 -39.592254) (xy 194.39177 -39.590217)
			(xy 194.447207 -39.596317) (xy 194.501164 -39.610423) (xy 194.552493 -39.632235) (xy 194.600099 -39.661289)
			(xy 194.642967 -39.696964) (xy 194.680184 -39.738501) (xy 194.710957 -39.785014) (xy 194.734629 -39.835511)
			(xy 194.750697 -39.888918) (xy 194.758817 -39.944094) (xy 194.759326 -39.97198) (xy 194.758817 -39.999866)
			(xy 194.750697 -40.055042) (xy 194.734629 -40.108449) (xy 194.710957 -40.158946) (xy 194.696015 -40.18153)
			(xy 228.109524 -40.18153) (xy 228.113595 -40.125908) (xy 228.125721 -40.071471) (xy 228.145644 -40.01938)
			(xy 228.17294 -39.970745) (xy 228.207026 -39.926602) (xy 228.247175 -39.887893) (xy 228.292533 -39.855442)
			(xy 228.342133 -39.829941) (xy 228.394917 -39.811934) (xy 228.44976 -39.801804) (xy 228.505494 -39.799767)
			(xy 228.560931 -39.805867) (xy 228.614888 -39.819973) (xy 228.666217 -39.841785) (xy 228.713823 -39.870839)
			(xy 228.756691 -39.906514) (xy 228.793908 -39.948051) (xy 228.809739 -39.97198) (xy 232.0958 -39.97198)
			(xy 232.099871 -39.916358) (xy 232.111997 -39.861921) (xy 232.13192 -39.80983) (xy 232.159216 -39.761195)
			(xy 232.193302 -39.717052) (xy 232.233451 -39.678343) (xy 232.278809 -39.645892) (xy 232.328409 -39.620391)
			(xy 232.381193 -39.602384) (xy 232.436036 -39.592254) (xy 232.49177 -39.590217) (xy 232.547207 -39.596317)
			(xy 232.601164 -39.610423) (xy 232.652493 -39.632235) (xy 232.700099 -39.661289) (xy 232.742967 -39.696964)
			(xy 232.780184 -39.738501) (xy 232.810957 -39.785014) (xy 232.834629 -39.835511) (xy 232.850697 -39.888918)
			(xy 232.858817 -39.944094) (xy 232.859326 -39.97198) (xy 258.095748 -39.97198) (xy 258.099819 -39.916358)
			(xy 258.111945 -39.861921) (xy 258.131868 -39.80983) (xy 258.159164 -39.761195) (xy 258.19325 -39.717052)
			(xy 258.233399 -39.678343) (xy 258.278757 -39.645892) (xy 258.328357 -39.620391) (xy 258.381141 -39.602384)
			(xy 258.435984 -39.592254) (xy 258.491718 -39.590217) (xy 258.547155 -39.596317) (xy 258.601112 -39.610423)
			(xy 258.652441 -39.632235) (xy 258.700047 -39.661289) (xy 258.742915 -39.696964) (xy 258.780132 -39.738501)
			(xy 258.810905 -39.785014) (xy 258.834577 -39.835511) (xy 258.850645 -39.888918) (xy 258.858765 -39.944094)
			(xy 258.859274 -39.97198) (xy 284.095696 -39.97198) (xy 284.099767 -39.916358) (xy 284.111893 -39.861921)
			(xy 284.131816 -39.80983) (xy 284.159112 -39.761195) (xy 284.193198 -39.717052) (xy 284.233347 -39.678343)
			(xy 284.278705 -39.645892) (xy 284.328305 -39.620391) (xy 284.381089 -39.602384) (xy 284.435932 -39.592254)
			(xy 284.491666 -39.590217) (xy 284.547103 -39.596317) (xy 284.60106 -39.610423) (xy 284.652389 -39.632235)
			(xy 284.699995 -39.661289) (xy 284.742863 -39.696964) (xy 284.78008 -39.738501) (xy 284.810853 -39.785014)
			(xy 284.834525 -39.835511) (xy 284.850593 -39.888918) (xy 284.858713 -39.944094) (xy 284.859222 -39.97198)
			(xy 310.095644 -39.97198) (xy 310.099715 -39.916358) (xy 310.111841 -39.861921) (xy 310.131764 -39.80983)
			(xy 310.15906 -39.761195) (xy 310.193146 -39.717052) (xy 310.233295 -39.678343) (xy 310.278653 -39.645892)
			(xy 310.328253 -39.620391) (xy 310.381037 -39.602384) (xy 310.43588 -39.592254) (xy 310.491614 -39.590217)
			(xy 310.547051 -39.596317) (xy 310.601008 -39.610423) (xy 310.652337 -39.632235) (xy 310.699943 -39.661289)
			(xy 310.742811 -39.696964) (xy 310.780028 -39.738501) (xy 310.810801 -39.785014) (xy 310.834473 -39.835511)
			(xy 310.850541 -39.888918) (xy 310.858661 -39.944094) (xy 310.85917 -39.97198) (xy 348.195898 -39.97198)
			(xy 348.199969 -39.916358) (xy 348.212095 -39.861921) (xy 348.232018 -39.80983) (xy 348.259314 -39.761195)
			(xy 348.2934 -39.717052) (xy 348.333549 -39.678343) (xy 348.378907 -39.645892) (xy 348.428507 -39.620391)
			(xy 348.481291 -39.602384) (xy 348.536134 -39.592254) (xy 348.591868 -39.590217) (xy 348.647305 -39.596317)
			(xy 348.701262 -39.610423) (xy 348.752591 -39.632235) (xy 348.800197 -39.661289) (xy 348.843065 -39.696964)
			(xy 348.880282 -39.738501) (xy 348.911055 -39.785014) (xy 348.934727 -39.835511) (xy 348.950795 -39.888918)
			(xy 348.958915 -39.944094) (xy 348.959424 -39.97198) (xy 374.195846 -39.97198) (xy 374.199917 -39.916358)
			(xy 374.212043 -39.861921) (xy 374.231966 -39.80983) (xy 374.259262 -39.761195) (xy 374.293348 -39.717052)
			(xy 374.333497 -39.678343) (xy 374.378855 -39.645892) (xy 374.428455 -39.620391) (xy 374.481239 -39.602384)
			(xy 374.536082 -39.592254) (xy 374.591816 -39.590217) (xy 374.647253 -39.596317) (xy 374.70121 -39.610423)
			(xy 374.752539 -39.632235) (xy 374.800145 -39.661289) (xy 374.843013 -39.696964) (xy 374.88023 -39.738501)
			(xy 374.911003 -39.785014) (xy 374.934675 -39.835511) (xy 374.950743 -39.888918) (xy 374.958863 -39.944094)
			(xy 374.959372 -39.97198) (xy 400.195794 -39.97198) (xy 400.199865 -39.916358) (xy 400.211991 -39.861921)
			(xy 400.231914 -39.80983) (xy 400.25921 -39.761195) (xy 400.293296 -39.717052) (xy 400.333445 -39.678343)
			(xy 400.378803 -39.645892) (xy 400.428403 -39.620391) (xy 400.481187 -39.602384) (xy 400.53603 -39.592254)
			(xy 400.591764 -39.590217) (xy 400.647201 -39.596317) (xy 400.701158 -39.610423) (xy 400.752487 -39.632235)
			(xy 400.800093 -39.661289) (xy 400.842961 -39.696964) (xy 400.880178 -39.738501) (xy 400.910951 -39.785014)
			(xy 400.934623 -39.835511) (xy 400.950691 -39.888918) (xy 400.958811 -39.944094) (xy 400.95932 -39.97198)
			(xy 426.195742 -39.97198) (xy 426.199813 -39.916358) (xy 426.211939 -39.861921) (xy 426.231862 -39.80983)
			(xy 426.259158 -39.761195) (xy 426.293244 -39.717052) (xy 426.333393 -39.678343) (xy 426.378751 -39.645892)
			(xy 426.428351 -39.620391) (xy 426.481135 -39.602384) (xy 426.535978 -39.592254) (xy 426.591712 -39.590217)
			(xy 426.647149 -39.596317) (xy 426.701106 -39.610423) (xy 426.752435 -39.632235) (xy 426.800041 -39.661289)
			(xy 426.842909 -39.696964) (xy 426.880126 -39.738501) (xy 426.910899 -39.785014) (xy 426.934571 -39.835511)
			(xy 426.950639 -39.888918) (xy 426.958759 -39.944094) (xy 426.959268 -39.97198) (xy 426.958759 -39.999866)
			(xy 426.950639 -40.055042) (xy 426.934571 -40.108449) (xy 426.910899 -40.158946) (xy 426.880126 -40.205459)
			(xy 426.842909 -40.246996) (xy 426.800041 -40.282671) (xy 426.752435 -40.311725) (xy 426.701106 -40.333537)
			(xy 426.647149 -40.347643) (xy 426.591712 -40.353743) (xy 426.535978 -40.351706) (xy 426.481135 -40.341576)
			(xy 426.428351 -40.323569) (xy 426.378751 -40.298068) (xy 426.333393 -40.265617) (xy 426.293244 -40.226908)
			(xy 426.259158 -40.182765) (xy 426.231862 -40.13413) (xy 426.211939 -40.082039) (xy 426.199813 -40.027602)
			(xy 426.195742 -39.97198) (xy 400.95932 -39.97198) (xy 400.958811 -39.999866) (xy 400.950691 -40.055042)
			(xy 400.934623 -40.108449) (xy 400.910951 -40.158946) (xy 400.880178 -40.205459) (xy 400.842961 -40.246996)
			(xy 400.800093 -40.282671) (xy 400.752487 -40.311725) (xy 400.701158 -40.333537) (xy 400.647201 -40.347643)
			(xy 400.591764 -40.353743) (xy 400.53603 -40.351706) (xy 400.481187 -40.341576) (xy 400.428403 -40.323569)
			(xy 400.378803 -40.298068) (xy 400.333445 -40.265617) (xy 400.293296 -40.226908) (xy 400.25921 -40.182765)
			(xy 400.231914 -40.13413) (xy 400.211991 -40.082039) (xy 400.199865 -40.027602) (xy 400.195794 -39.97198)
			(xy 374.959372 -39.97198) (xy 374.958863 -39.999866) (xy 374.950743 -40.055042) (xy 374.934675 -40.108449)
			(xy 374.911003 -40.158946) (xy 374.88023 -40.205459) (xy 374.843013 -40.246996) (xy 374.800145 -40.282671)
			(xy 374.752539 -40.311725) (xy 374.70121 -40.333537) (xy 374.647253 -40.347643) (xy 374.591816 -40.353743)
			(xy 374.536082 -40.351706) (xy 374.481239 -40.341576) (xy 374.428455 -40.323569) (xy 374.378855 -40.298068)
			(xy 374.333497 -40.265617) (xy 374.293348 -40.226908) (xy 374.259262 -40.182765) (xy 374.231966 -40.13413)
			(xy 374.212043 -40.082039) (xy 374.199917 -40.027602) (xy 374.195846 -39.97198) (xy 348.959424 -39.97198)
			(xy 348.958915 -39.999866) (xy 348.950795 -40.055042) (xy 348.934727 -40.108449) (xy 348.911055 -40.158946)
			(xy 348.880282 -40.205459) (xy 348.843065 -40.246996) (xy 348.800197 -40.282671) (xy 348.752591 -40.311725)
			(xy 348.701262 -40.333537) (xy 348.647305 -40.347643) (xy 348.591868 -40.353743) (xy 348.536134 -40.351706)
			(xy 348.481291 -40.341576) (xy 348.428507 -40.323569) (xy 348.378907 -40.298068) (xy 348.333549 -40.265617)
			(xy 348.2934 -40.226908) (xy 348.259314 -40.182765) (xy 348.232018 -40.13413) (xy 348.212095 -40.082039)
			(xy 348.199969 -40.027602) (xy 348.195898 -39.97198) (xy 310.85917 -39.97198) (xy 310.858661 -39.999866)
			(xy 310.850541 -40.055042) (xy 310.834473 -40.108449) (xy 310.810801 -40.158946) (xy 310.780028 -40.205459)
			(xy 310.742811 -40.246996) (xy 310.699943 -40.282671) (xy 310.652337 -40.311725) (xy 310.601008 -40.333537)
			(xy 310.547051 -40.347643) (xy 310.491614 -40.353743) (xy 310.43588 -40.351706) (xy 310.381037 -40.341576)
			(xy 310.328253 -40.323569) (xy 310.278653 -40.298068) (xy 310.233295 -40.265617) (xy 310.193146 -40.226908)
			(xy 310.15906 -40.182765) (xy 310.131764 -40.13413) (xy 310.111841 -40.082039) (xy 310.099715 -40.027602)
			(xy 310.095644 -39.97198) (xy 284.859222 -39.97198) (xy 284.858713 -39.999866) (xy 284.850593 -40.055042)
			(xy 284.834525 -40.108449) (xy 284.810853 -40.158946) (xy 284.78008 -40.205459) (xy 284.742863 -40.246996)
			(xy 284.699995 -40.282671) (xy 284.652389 -40.311725) (xy 284.60106 -40.333537) (xy 284.547103 -40.347643)
			(xy 284.491666 -40.353743) (xy 284.435932 -40.351706) (xy 284.381089 -40.341576) (xy 284.328305 -40.323569)
			(xy 284.278705 -40.298068) (xy 284.233347 -40.265617) (xy 284.193198 -40.226908) (xy 284.159112 -40.182765)
			(xy 284.131816 -40.13413) (xy 284.111893 -40.082039) (xy 284.099767 -40.027602) (xy 284.095696 -39.97198)
			(xy 258.859274 -39.97198) (xy 258.858765 -39.999866) (xy 258.850645 -40.055042) (xy 258.834577 -40.108449)
			(xy 258.810905 -40.158946) (xy 258.780132 -40.205459) (xy 258.742915 -40.246996) (xy 258.700047 -40.282671)
			(xy 258.652441 -40.311725) (xy 258.601112 -40.333537) (xy 258.547155 -40.347643) (xy 258.491718 -40.353743)
			(xy 258.435984 -40.351706) (xy 258.381141 -40.341576) (xy 258.328357 -40.323569) (xy 258.278757 -40.298068)
			(xy 258.233399 -40.265617) (xy 258.19325 -40.226908) (xy 258.159164 -40.182765) (xy 258.131868 -40.13413)
			(xy 258.111945 -40.082039) (xy 258.099819 -40.027602) (xy 258.095748 -39.97198) (xy 232.859326 -39.97198)
			(xy 232.858817 -39.999866) (xy 232.850697 -40.055042) (xy 232.834629 -40.108449) (xy 232.810957 -40.158946)
			(xy 232.780184 -40.205459) (xy 232.742967 -40.246996) (xy 232.700099 -40.282671) (xy 232.652493 -40.311725)
			(xy 232.601164 -40.333537) (xy 232.547207 -40.347643) (xy 232.49177 -40.353743) (xy 232.436036 -40.351706)
			(xy 232.381193 -40.341576) (xy 232.328409 -40.323569) (xy 232.278809 -40.298068) (xy 232.233451 -40.265617)
			(xy 232.193302 -40.226908) (xy 232.159216 -40.182765) (xy 232.13192 -40.13413) (xy 232.111997 -40.082039)
			(xy 232.099871 -40.027602) (xy 232.0958 -39.97198) (xy 228.809739 -39.97198) (xy 228.824681 -39.994564)
			(xy 228.848353 -40.045061) (xy 228.864421 -40.098468) (xy 228.872541 -40.153644) (xy 228.87305 -40.18153)
			(xy 228.872541 -40.209416) (xy 228.864421 -40.264592) (xy 228.848353 -40.317999) (xy 228.824681 -40.368496)
			(xy 228.793908 -40.415009) (xy 228.756691 -40.456546) (xy 228.713823 -40.492221) (xy 228.666217 -40.521275)
			(xy 228.614888 -40.543087) (xy 228.560931 -40.557193) (xy 228.505494 -40.563293) (xy 228.44976 -40.561256)
			(xy 228.394917 -40.551126) (xy 228.342133 -40.533119) (xy 228.292533 -40.507618) (xy 228.247175 -40.475167)
			(xy 228.207026 -40.436458) (xy 228.17294 -40.392315) (xy 228.145644 -40.34368) (xy 228.125721 -40.291589)
			(xy 228.113595 -40.237152) (xy 228.109524 -40.18153) (xy 194.696015 -40.18153) (xy 194.680184 -40.205459)
			(xy 194.642967 -40.246996) (xy 194.600099 -40.282671) (xy 194.552493 -40.311725) (xy 194.501164 -40.333537)
			(xy 194.447207 -40.347643) (xy 194.39177 -40.353743) (xy 194.336036 -40.351706) (xy 194.281193 -40.341576)
			(xy 194.228409 -40.323569) (xy 194.178809 -40.298068) (xy 194.133451 -40.265617) (xy 194.093302 -40.226908)
			(xy 194.059216 -40.182765) (xy 194.03192 -40.13413) (xy 194.011997 -40.082039) (xy 193.999871 -40.027602)
			(xy 193.9958 -39.97198) (xy 168.759378 -39.97198) (xy 168.758869 -39.999866) (xy 168.750749 -40.055042)
			(xy 168.734681 -40.108449) (xy 168.711009 -40.158946) (xy 168.680236 -40.205459) (xy 168.643019 -40.246996)
			(xy 168.600151 -40.282671) (xy 168.552545 -40.311725) (xy 168.501216 -40.333537) (xy 168.447259 -40.347643)
			(xy 168.391822 -40.353743) (xy 168.336088 -40.351706) (xy 168.281245 -40.341576) (xy 168.228461 -40.323569)
			(xy 168.178861 -40.298068) (xy 168.133503 -40.265617) (xy 168.093354 -40.226908) (xy 168.059268 -40.182765)
			(xy 168.031972 -40.13413) (xy 168.012049 -40.082039) (xy 167.999923 -40.027602) (xy 167.995852 -39.97198)
			(xy 142.75943 -39.97198) (xy 142.758921 -39.999866) (xy 142.750801 -40.055042) (xy 142.734733 -40.108449)
			(xy 142.711061 -40.158946) (xy 142.680288 -40.205459) (xy 142.643071 -40.246996) (xy 142.600203 -40.282671)
			(xy 142.552597 -40.311725) (xy 142.501268 -40.333537) (xy 142.447311 -40.347643) (xy 142.391874 -40.353743)
			(xy 142.33614 -40.351706) (xy 142.281297 -40.341576) (xy 142.228513 -40.323569) (xy 142.178913 -40.298068)
			(xy 142.133555 -40.265617) (xy 142.093406 -40.226908) (xy 142.05932 -40.182765) (xy 142.032024 -40.13413)
			(xy 142.012101 -40.082039) (xy 141.999975 -40.027602) (xy 141.995904 -39.97198) (xy 116.759482 -39.97198)
			(xy 116.758973 -39.999866) (xy 116.750853 -40.055042) (xy 116.734785 -40.108449) (xy 116.711113 -40.158946)
			(xy 116.68034 -40.205459) (xy 116.643123 -40.246996) (xy 116.600255 -40.282671) (xy 116.552649 -40.311725)
			(xy 116.50132 -40.333537) (xy 116.447363 -40.347643) (xy 116.391926 -40.353743) (xy 116.336192 -40.351706)
			(xy 116.281349 -40.341576) (xy 116.228565 -40.323569) (xy 116.178965 -40.298068) (xy 116.133607 -40.265617)
			(xy 116.093458 -40.226908) (xy 116.059372 -40.182765) (xy 116.032076 -40.13413) (xy 116.012153 -40.082039)
			(xy 116.000027 -40.027602) (xy 115.995956 -39.97198) (xy 78.659228 -39.97198) (xy 78.658719 -39.999866)
			(xy 78.650599 -40.055042) (xy 78.634531 -40.108449) (xy 78.610859 -40.158946) (xy 78.580086 -40.205459)
			(xy 78.542869 -40.246996) (xy 78.500001 -40.282671) (xy 78.452395 -40.311725) (xy 78.401066 -40.333537)
			(xy 78.347109 -40.347643) (xy 78.291672 -40.353743) (xy 78.235938 -40.351706) (xy 78.181095 -40.341576)
			(xy 78.128311 -40.323569) (xy 78.078711 -40.298068) (xy 78.033353 -40.265617) (xy 77.993204 -40.226908)
			(xy 77.959118 -40.182765) (xy 77.931822 -40.13413) (xy 77.911899 -40.082039) (xy 77.899773 -40.027602)
			(xy 77.895702 -39.97198) (xy 52.65928 -39.97198) (xy 52.658771 -39.999866) (xy 52.650651 -40.055042)
			(xy 52.634583 -40.108449) (xy 52.610911 -40.158946) (xy 52.580138 -40.205459) (xy 52.542921 -40.246996)
			(xy 52.500053 -40.282671) (xy 52.452447 -40.311725) (xy 52.401118 -40.333537) (xy 52.347161 -40.347643)
			(xy 52.291724 -40.353743) (xy 52.23599 -40.351706) (xy 52.181147 -40.341576) (xy 52.128363 -40.323569)
			(xy 52.078763 -40.298068) (xy 52.033405 -40.265617) (xy 51.993256 -40.226908) (xy 51.95917 -40.182765)
			(xy 51.931874 -40.13413) (xy 51.911951 -40.082039) (xy 51.899825 -40.027602) (xy 51.895754 -39.97198)
			(xy 26.659332 -39.97198) (xy 26.658823 -39.999866) (xy 26.650703 -40.055042) (xy 26.634635 -40.108449)
			(xy 26.610963 -40.158946) (xy 26.58019 -40.205459) (xy 26.542973 -40.246996) (xy 26.500105 -40.282671)
			(xy 26.452499 -40.311725) (xy 26.40117 -40.333537) (xy 26.347213 -40.347643) (xy 26.291776 -40.353743)
			(xy 26.236042 -40.351706) (xy 26.181199 -40.341576) (xy 26.128415 -40.323569) (xy 26.078815 -40.298068)
			(xy 26.033457 -40.265617) (xy 25.993308 -40.226908) (xy 25.959222 -40.182765) (xy 25.931926 -40.13413)
			(xy 25.912003 -40.082039) (xy 25.899877 -40.027602) (xy 25.895806 -39.97198) (xy 2.968244 -39.97198)
			(xy 2.968244 -40.040814) (xy 2.968594 -40.049331) (xy 2.974133 -40.065438) (xy 2.984631 -40.078851)
			(xy 2.991612 -40.08374) (xy 3.014288 -40.098849) (xy 3.055483 -40.134517) (xy 3.09118 -40.175686)
			(xy 3.12065 -40.221519) (xy 3.143295 -40.271081) (xy 3.158653 -40.323362) (xy 3.166409 -40.377297)
			(xy 3.166872 -40.404542) (xy 3.166323 -40.433458) (xy 3.157602 -40.490628) (xy 3.140351 -40.545827)
			(xy 3.114965 -40.597789) (xy 3.082026 -40.645324) (xy 3.04229 -40.687341) (xy 3.019806 -40.705532)
			(xy 3.010995 -40.713136) (xy 3.000813 -40.734039) (xy 3.000248 -40.745664) (xy 3.000248 -40.82542)
			(xy 3.000773 -40.837054) (xy 3.01097 -40.857964) (xy 3.019806 -40.865552) (xy 3.042287 -40.883746)
			(xy 3.082022 -40.925765) (xy 3.114961 -40.9733) (xy 3.14035 -41.02526) (xy 3.157607 -41.080457) (xy 3.166337 -41.137626)
			(xy 3.166872 -41.166542) (xy 5.443982 -41.166542) (xy 5.4445 -41.137625) (xy 5.453225 -41.080452)
			(xy 5.470481 -41.025252) (xy 5.495872 -40.97329) (xy 5.528818 -40.925756) (xy 5.568561 -40.883741)
			(xy 5.591048 -40.865552) (xy 5.599875 -40.857964) (xy 5.610046 -40.837048) (xy 5.610606 -40.82542)
			(xy 5.610606 -40.745664) (xy 5.610071 -40.734032) (xy 5.599879 -40.713122) (xy 5.591048 -40.705532)
			(xy 5.568569 -40.687336) (xy 5.528836 -40.645316) (xy 5.495898 -40.597781) (xy 5.470509 -40.545821)
			(xy 5.453251 -40.490625) (xy 5.444519 -40.433457) (xy 5.443982 -40.404542) (xy 5.444468 -40.377291)
			(xy 5.452224 -40.323343) (xy 5.467579 -40.271048) (xy 5.490221 -40.221471) (xy 5.519687 -40.175621)
			(xy 5.555378 -40.13443) (xy 5.596569 -40.098739) (xy 5.642419 -40.069273) (xy 5.691996 -40.046631)
			(xy 5.744291 -40.031276) (xy 5.798239 -40.02352) (xy 5.852741 -40.02352) (xy 5.906689 -40.031276)
			(xy 5.958984 -40.046631) (xy 6.008561 -40.069273) (xy 6.054411 -40.098739) (xy 6.095602 -40.13443)
			(xy 6.131293 -40.175621) (xy 6.160759 -40.221471) (xy 6.183401 -40.271048) (xy 6.198756 -40.323343)
			(xy 6.206512 -40.377291) (xy 6.206998 -40.404542) (xy 6.206439 -40.433457) (xy 6.197718 -40.490627)
			(xy 6.180469 -40.545825) (xy 6.155085 -40.597787) (xy 6.122148 -40.645322) (xy 6.082414 -40.687341)
			(xy 6.059932 -40.705532) (xy 6.051109 -40.713123) (xy 6.040937 -40.734036) (xy 6.040374 -40.745664)
			(xy 6.040374 -40.82542) (xy 6.04089 -40.837056) (xy 6.051092 -40.857967) (xy 6.059932 -40.865552)
			(xy 6.082412 -40.883747) (xy 6.122147 -40.925766) (xy 6.155087 -40.9733) (xy 6.180476 -41.025261)
			(xy 6.197733 -41.080457) (xy 6.206463 -41.137626) (xy 6.206998 -41.166542) (xy 6.206512 -41.193793)
			(xy 6.198756 -41.247741) (xy 6.183401 -41.300036) (xy 6.160759 -41.349613) (xy 6.131293 -41.395463)
			(xy 6.095602 -41.436654) (xy 6.058207 -41.469056) (xy 11.297918 -41.469056) (xy 11.301989 -41.413434)
			(xy 11.314115 -41.358997) (xy 11.334038 -41.306906) (xy 11.361334 -41.258271) (xy 11.39542 -41.214128)
			(xy 11.435569 -41.175419) (xy 11.480927 -41.142968) (xy 11.530527 -41.117467) (xy 11.583311 -41.09946)
			(xy 11.638154 -41.08933) (xy 11.693888 -41.087293) (xy 11.749325 -41.093393) (xy 11.803282 -41.107499)
			(xy 11.854611 -41.129311) (xy 11.902217 -41.158365) (xy 11.945085 -41.19404) (xy 11.982302 -41.235577)
			(xy 12.004253 -41.268755) (xy 15.843927 -41.268755) (xy 15.843927 -41.214245) (xy 15.851685 -41.160289)
			(xy 15.867043 -41.107986) (xy 15.889688 -41.058401) (xy 15.919159 -41.012544) (xy 15.954857 -40.971348)
			(xy 15.996054 -40.935652) (xy 16.041912 -40.906182) (xy 16.091497 -40.883538) (xy 16.1438 -40.868182)
			(xy 16.197757 -40.860426) (xy 16.225012 -40.859964) (xy 16.253751 -40.86049) (xy 16.310578 -40.869114)
			(xy 16.365468 -40.886164) (xy 16.41718 -40.911254) (xy 16.464543 -40.943818) (xy 16.48587 -40.963088)
			(xy 16.492728 -40.969692) (xy 16.510762 -40.976804) (xy 16.599662 -40.976804) (xy 16.617696 -40.969692)
			(xy 16.624554 -40.963088) (xy 16.645883 -40.94382) (xy 16.693244 -40.911251) (xy 16.744955 -40.886157)
			(xy 16.799845 -40.869106) (xy 16.856673 -40.860484) (xy 16.885412 -40.859964) (xy 16.912661 -40.860507)
			(xy 16.966603 -40.868264) (xy 17.018892 -40.883619) (xy 17.068464 -40.90626) (xy 17.11431 -40.935724)
			(xy 17.155496 -40.971413) (xy 17.191183 -41.0126) (xy 17.220646 -41.058446) (xy 17.243285 -41.108019)
			(xy 17.258638 -41.160309) (xy 17.266394 -41.214251) (xy 17.266394 -41.268749) (xy 17.258638 -41.322691)
			(xy 17.243285 -41.374981) (xy 17.220646 -41.424554) (xy 17.191183 -41.4704) (xy 17.155496 -41.511587)
			(xy 17.11431 -41.547276) (xy 17.068464 -41.57674) (xy 17.018892 -41.599381) (xy 16.966603 -41.614736)
			(xy 16.912661 -41.622493) (xy 16.885412 -41.62298) (xy 16.856674 -41.622428) (xy 16.799849 -41.613809)
			(xy 16.74496 -41.596764) (xy 16.693248 -41.57168) (xy 16.645883 -41.539123) (xy 16.624554 -41.519856)
			(xy 16.617696 -41.513252) (xy 16.599662 -41.50614) (xy 16.510762 -41.50614) (xy 16.492728 -41.513252)
			(xy 16.48587 -41.519856) (xy 16.464537 -41.53912) (xy 16.417177 -41.571687) (xy 16.365467 -41.596781)
			(xy 16.310577 -41.613834) (xy 16.253751 -41.622458) (xy 16.225012 -41.62298) (xy 16.197757 -41.622574)
			(xy 16.1438 -41.614818) (xy 16.091497 -41.599462) (xy 16.041912 -41.576818) (xy 15.996054 -41.547348)
			(xy 15.954857 -41.511652) (xy 15.919159 -41.470456) (xy 15.889688 -41.424599) (xy 15.867043 -41.375014)
			(xy 15.851685 -41.322711) (xy 15.843927 -41.268755) (xy 12.004253 -41.268755) (xy 12.013075 -41.28209)
			(xy 12.036747 -41.332587) (xy 12.052815 -41.385994) (xy 12.060935 -41.44117) (xy 12.061444 -41.469056)
			(xy 12.060935 -41.496942) (xy 12.052815 -41.552118) (xy 12.036747 -41.605525) (xy 12.013075 -41.656022)
			(xy 11.982302 -41.702535) (xy 11.945085 -41.744072) (xy 11.902217 -41.779747) (xy 11.854611 -41.808801)
			(xy 11.803282 -41.830613) (xy 11.749325 -41.844719) (xy 11.693888 -41.850819) (xy 11.638154 -41.848782)
			(xy 11.583311 -41.838652) (xy 11.530527 -41.820645) (xy 11.480927 -41.795144) (xy 11.435569 -41.762693)
			(xy 11.39542 -41.723984) (xy 11.361334 -41.679841) (xy 11.334038 -41.631206) (xy 11.314115 -41.579115)
			(xy 11.301989 -41.524678) (xy 11.297918 -41.469056) (xy 6.058207 -41.469056) (xy 6.054411 -41.472345)
			(xy 6.008561 -41.501811) (xy 5.958984 -41.524453) (xy 5.906689 -41.539808) (xy 5.852741 -41.547564)
			(xy 5.798239 -41.547564) (xy 5.744291 -41.539808) (xy 5.691996 -41.524453) (xy 5.642419 -41.501811)
			(xy 5.596569 -41.472345) (xy 5.555378 -41.436654) (xy 5.519687 -41.395463) (xy 5.490221 -41.349613)
			(xy 5.467579 -41.300036) (xy 5.452224 -41.247741) (xy 5.444468 -41.193793) (xy 5.443982 -41.166542)
			(xy 3.166872 -41.166542) (xy 3.166386 -41.193793) (xy 3.15863 -41.247741) (xy 3.143275 -41.300036)
			(xy 3.120633 -41.349613) (xy 3.091167 -41.395463) (xy 3.055476 -41.436654) (xy 3.014285 -41.472345)
			(xy 2.968435 -41.501811) (xy 2.918858 -41.524453) (xy 2.866563 -41.539808) (xy 2.812615 -41.547564)
			(xy 2.758113 -41.547564) (xy 2.704165 -41.539808) (xy 2.65187 -41.524453) (xy 2.602293 -41.501811)
			(xy 2.556443 -41.472345) (xy 2.515252 -41.436654) (xy 2.479561 -41.395463) (xy 2.450095 -41.349613)
			(xy 2.427453 -41.300036) (xy 2.412098 -41.247741) (xy 2.404342 -41.193793) (xy 2.403856 -41.166542)
			(xy 1.987296 -41.166542) (xy 1.987296 -42.250614) (xy 2.72872 -42.250614) (xy 2.732791 -42.194992)
			(xy 2.744917 -42.140555) (xy 2.76484 -42.088464) (xy 2.792136 -42.039829) (xy 2.826222 -41.995686)
			(xy 2.866371 -41.956977) (xy 2.911729 -41.924526) (xy 2.961329 -41.899025) (xy 3.014113 -41.881018)
			(xy 3.068956 -41.870888) (xy 3.12469 -41.868851) (xy 3.180127 -41.874951) (xy 3.234084 -41.889057)
			(xy 3.285413 -41.910869) (xy 3.333019 -41.939923) (xy 3.375887 -41.975598) (xy 3.413104 -42.017135)
			(xy 3.443877 -42.063648) (xy 3.467549 -42.114145) (xy 3.483617 -42.167552) (xy 3.491737 -42.222728)
			(xy 3.492246 -42.250614) (xy 3.491737 -42.2785) (xy 3.483617 -42.333676) (xy 3.467549 -42.387083)
			(xy 3.460557 -42.401998) (xy 4.015484 -42.401998) (xy 4.019555 -42.346376) (xy 4.031681 -42.291939)
			(xy 4.051604 -42.239848) (xy 4.0789 -42.191213) (xy 4.112986 -42.14707) (xy 4.153135 -42.108361)
			(xy 4.198493 -42.07591) (xy 4.248093 -42.050409) (xy 4.300877 -42.032402) (xy 4.35572 -42.022272)
			(xy 4.411454 -42.020235) (xy 4.466891 -42.026335) (xy 4.520848 -42.040441) (xy 4.572177 -42.062253)
			(xy 4.619783 -42.091307) (xy 4.662651 -42.126982) (xy 4.699868 -42.168519) (xy 4.730641 -42.215032)
			(xy 4.754313 -42.265529) (xy 4.770381 -42.318936) (xy 4.774531 -42.347134) (xy 5.291072 -42.347134)
			(xy 5.295143 -42.291512) (xy 5.307269 -42.237075) (xy 5.327192 -42.184984) (xy 5.354488 -42.136349)
			(xy 5.388574 -42.092206) (xy 5.428723 -42.053497) (xy 5.474081 -42.021046) (xy 5.523681 -41.995545)
			(xy 5.576465 -41.977538) (xy 5.631308 -41.967408) (xy 5.687042 -41.965371) (xy 5.742479 -41.971471)
			(xy 5.796436 -41.985577) (xy 5.847765 -42.007389) (xy 5.895371 -42.036443) (xy 5.938239 -42.072118)
			(xy 5.975456 -42.113655) (xy 6.006229 -42.160168) (xy 6.029901 -42.210665) (xy 6.045969 -42.264072)
			(xy 6.054089 -42.319248) (xy 6.054598 -42.347134) (xy 6.054089 -42.37502) (xy 6.045969 -42.430196)
			(xy 6.029901 -42.483603) (xy 6.006229 -42.5341) (xy 5.975456 -42.580613) (xy 5.938239 -42.62215)
			(xy 5.895371 -42.657825) (xy 5.847765 -42.686879) (xy 5.796436 -42.708691) (xy 5.742479 -42.722797)
			(xy 5.687042 -42.728897) (xy 5.631308 -42.72686) (xy 5.576465 -42.71673) (xy 5.523681 -42.698723)
			(xy 5.474081 -42.673222) (xy 5.428723 -42.640771) (xy 5.388574 -42.602062) (xy 5.354488 -42.557919)
			(xy 5.327192 -42.509284) (xy 5.307269 -42.457193) (xy 5.295143 -42.402756) (xy 5.291072 -42.347134)
			(xy 4.774531 -42.347134) (xy 4.778501 -42.374112) (xy 4.77901 -42.401998) (xy 4.778501 -42.429884)
			(xy 4.770381 -42.48506) (xy 4.754313 -42.538467) (xy 4.730641 -42.588964) (xy 4.699868 -42.635477)
			(xy 4.662651 -42.677014) (xy 4.619783 -42.712689) (xy 4.572177 -42.741743) (xy 4.520848 -42.763555)
			(xy 4.466891 -42.777661) (xy 4.411454 -42.783761) (xy 4.35572 -42.781724) (xy 4.300877 -42.771594)
			(xy 4.248093 -42.753587) (xy 4.198493 -42.728086) (xy 4.153135 -42.695635) (xy 4.112986 -42.656926)
			(xy 4.0789 -42.612783) (xy 4.051604 -42.564148) (xy 4.031681 -42.512057) (xy 4.019555 -42.45762)
			(xy 4.015484 -42.401998) (xy 3.460557 -42.401998) (xy 3.443877 -42.43758) (xy 3.413104 -42.484093)
			(xy 3.375887 -42.52563) (xy 3.333019 -42.561305) (xy 3.285413 -42.590359) (xy 3.234084 -42.612171)
			(xy 3.180127 -42.626277) (xy 3.12469 -42.632377) (xy 3.068956 -42.63034) (xy 3.014113 -42.62021)
			(xy 2.961329 -42.602203) (xy 2.911729 -42.576702) (xy 2.866371 -42.544251) (xy 2.826222 -42.505542)
			(xy 2.792136 -42.461399) (xy 2.76484 -42.412764) (xy 2.744917 -42.360673) (xy 2.732791 -42.306236)
			(xy 2.72872 -42.250614) (xy 1.987296 -42.250614) (xy 1.987296 -43.305222) (xy 18.307304 -43.305222)
			(xy 18.307782 -43.277852) (xy 18.315597 -43.223674) (xy 18.331083 -43.171171) (xy 18.353922 -43.121424)
			(xy 18.383644 -43.075456) (xy 18.401284 -43.054524) (xy 18.401538 -43.05427) (xy 18.407106 -43.047171)
			(xy 18.413363 -43.030264) (xy 18.41373 -43.02125) (xy 18.41373 -42.954194) (xy 18.413369 -42.945178)
			(xy 18.407123 -42.928261) (xy 18.401538 -42.921174) (xy 18.401284 -42.921174) (xy 18.401284 -42.92092)
			(xy 18.383638 -42.899993) (xy 18.353928 -42.854019) (xy 18.331094 -42.80427) (xy 18.315604 -42.751768)
			(xy 18.307777 -42.697591) (xy 18.307304 -42.670222) (xy 18.30784 -42.641484) (xy 18.316459 -42.584657)
			(xy 18.333507 -42.529766) (xy 18.358595 -42.478054) (xy 18.391158 -42.430691) (xy 18.410428 -42.409364)
			(xy 18.417032 -42.402506) (xy 18.424144 -42.384472) (xy 18.424144 -42.295572) (xy 18.417032 -42.277538)
			(xy 18.410428 -42.27068) (xy 18.391179 -42.249334) (xy 18.358613 -42.201975) (xy 18.333519 -42.150267)
			(xy 18.316468 -42.095379) (xy 18.307843 -42.038554) (xy 18.30784 -41.981078) (xy 18.31646 -41.924253)
			(xy 18.333508 -41.869363) (xy 18.358596 -41.817653) (xy 18.391159 -41.770291) (xy 18.410428 -41.748964)
			(xy 18.417032 -41.742106) (xy 18.424144 -41.724072) (xy 18.424144 -41.635172) (xy 18.417032 -41.617138)
			(xy 18.410428 -41.61028) (xy 18.391166 -41.588945) (xy 18.358599 -41.541585) (xy 18.333505 -41.489876)
			(xy 18.316452 -41.434987) (xy 18.307827 -41.37816) (xy 18.307304 -41.349422) (xy 18.30779 -41.322171)
			(xy 18.315546 -41.268223) (xy 18.330901 -41.215928) (xy 18.353543 -41.166351) (xy 18.383009 -41.120501)
			(xy 18.4187 -41.07931) (xy 18.459891 -41.043619) (xy 18.505741 -41.014153) (xy 18.555318 -40.991511)
			(xy 18.607613 -40.976156) (xy 18.661561 -40.9684) (xy 18.716063 -40.9684) (xy 18.739184 -40.971724)
			(xy 26.594052 -40.971724) (xy 26.598123 -40.916102) (xy 26.610249 -40.861665) (xy 26.630172 -40.809574)
			(xy 26.657468 -40.760939) (xy 26.691554 -40.716796) (xy 26.731703 -40.678087) (xy 26.777061 -40.645636)
			(xy 26.826661 -40.620135) (xy 26.879445 -40.602128) (xy 26.934288 -40.591998) (xy 26.990022 -40.589961)
			(xy 27.045459 -40.596061) (xy 27.099416 -40.610167) (xy 27.150745 -40.631979) (xy 27.198351 -40.661033)
			(xy 27.241219 -40.696708) (xy 27.278436 -40.738245) (xy 27.309209 -40.784758) (xy 27.332881 -40.835255)
			(xy 27.348949 -40.888662) (xy 27.357069 -40.943838) (xy 27.357578 -40.971724) (xy 27.357069 -40.99961)
			(xy 27.348949 -41.054786) (xy 27.332881 -41.108193) (xy 27.309209 -41.15869) (xy 27.278436 -41.205203)
			(xy 27.241219 -41.24674) (xy 27.21477 -41.268751) (xy 41.84395 -41.268751) (xy 41.84395 -41.214249)
			(xy 41.851706 -41.1603) (xy 41.86706 -41.108005) (xy 41.8897 -41.058427) (xy 41.919165 -41.012575)
			(xy 41.954854 -40.971383) (xy 41.996043 -40.935689) (xy 42.041892 -40.906219) (xy 42.091467 -40.883574)
			(xy 42.143761 -40.868214) (xy 42.197709 -40.860453) (xy 42.22496 -40.859964) (xy 42.2537 -40.860461)
			(xy 42.310528 -40.869091) (xy 42.365419 -40.886148) (xy 42.41713 -40.911246) (xy 42.464492 -40.943815)
			(xy 42.485818 -40.963088) (xy 42.492676 -40.969692) (xy 42.51071 -40.976804) (xy 42.59961 -40.976804)
			(xy 42.617644 -40.969692) (xy 42.624502 -40.963088) (xy 42.645853 -40.943845) (xy 42.693207 -40.911273)
			(xy 42.744913 -40.886174) (xy 42.799799 -40.869117) (xy 42.856622 -40.860488) (xy 42.88536 -40.859964)
			(xy 42.912613 -40.860481) (xy 42.966564 -40.868232) (xy 43.018863 -40.883584) (xy 43.068444 -40.906222)
			(xy 43.114299 -40.935687) (xy 43.155494 -40.971378) (xy 43.191189 -41.012569) (xy 43.220658 -41.05842)
			(xy 43.243302 -41.108) (xy 43.258659 -41.160297) (xy 43.266417 -41.214247) (xy 43.266417 -41.268753)
			(xy 43.258659 -41.322703) (xy 43.243302 -41.375) (xy 43.220658 -41.42458) (xy 43.191189 -41.470431)
			(xy 43.155494 -41.511622) (xy 43.114299 -41.547313) (xy 43.068444 -41.576778) (xy 43.018863 -41.599416)
			(xy 42.966564 -41.614768) (xy 42.912613 -41.622519) (xy 42.88536 -41.62298) (xy 42.856621 -41.622459)
			(xy 42.799795 -41.613833) (xy 42.744905 -41.596781) (xy 42.693193 -41.571689) (xy 42.64583 -41.539126)
			(xy 42.624502 -41.519856) (xy 42.617644 -41.513252) (xy 42.59961 -41.50614) (xy 42.51071 -41.50614)
			(xy 42.492676 -41.513252) (xy 42.485818 -41.519856) (xy 42.464506 -41.539145) (xy 42.41714 -41.571709)
			(xy 42.365425 -41.596798) (xy 42.310531 -41.613844) (xy 42.2537 -41.622462) (xy 42.22496 -41.62298)
			(xy 42.197709 -41.622547) (xy 42.143761 -41.614786) (xy 42.091467 -41.599426) (xy 42.041892 -41.576781)
			(xy 41.996043 -41.547311) (xy 41.954854 -41.511617) (xy 41.919165 -41.470425) (xy 41.8897 -41.424573)
			(xy 41.86706 -41.374995) (xy 41.851706 -41.3227) (xy 41.84395 -41.268751) (xy 27.21477 -41.268751)
			(xy 27.198351 -41.282415) (xy 27.150745 -41.311469) (xy 27.099416 -41.333281) (xy 27.045459 -41.347387)
			(xy 26.990022 -41.353487) (xy 26.934288 -41.35145) (xy 26.879445 -41.34132) (xy 26.826661 -41.323313)
			(xy 26.777061 -41.297812) (xy 26.731703 -41.265361) (xy 26.691554 -41.226652) (xy 26.657468 -41.182509)
			(xy 26.630172 -41.133874) (xy 26.610249 -41.081783) (xy 26.598123 -41.027346) (xy 26.594052 -40.971724)
			(xy 18.739184 -40.971724) (xy 18.770011 -40.976156) (xy 18.822306 -40.991511) (xy 18.871883 -41.014153)
			(xy 18.917733 -41.043619) (xy 18.958924 -41.07931) (xy 18.994615 -41.120501) (xy 19.024081 -41.166351)
			(xy 19.046723 -41.215928) (xy 19.062078 -41.268223) (xy 19.069834 -41.322171) (xy 19.07032 -41.349422)
			(xy 19.069804 -41.378161) (xy 19.061179 -41.434989) (xy 19.044127 -41.489879) (xy 19.019033 -41.541591)
			(xy 18.986467 -41.588953) (xy 18.967196 -41.61028) (xy 18.960592 -41.617138) (xy 18.95348 -41.635172)
			(xy 18.95348 -41.724072) (xy 18.960592 -41.742106) (xy 18.967196 -41.748964) (xy 18.986488 -41.770272)
			(xy 19.019051 -41.817639) (xy 19.04414 -41.869353) (xy 19.061187 -41.924247) (xy 19.069807 -41.981076)
			(xy 19.069805 -42.038556) (xy 19.06118 -42.095385) (xy 19.044128 -42.150276) (xy 19.019034 -42.201989)
			(xy 18.986468 -42.249353) (xy 18.967196 -42.27068) (xy 18.960592 -42.277538) (xy 18.95348 -42.295572)
			(xy 18.95348 -42.384472) (xy 18.960592 -42.402506) (xy 18.967196 -42.409364) (xy 18.986466 -42.430692)
			(xy 19.019035 -42.478053) (xy 19.044128 -42.529764) (xy 19.061179 -42.584655) (xy 19.0698 -42.641483)
			(xy 19.07032 -42.670222) (xy 19.069886 -42.697594) (xy 19.062064 -42.751775) (xy 19.046568 -42.804279)
			(xy 19.02601 -42.849038) (xy 20.892006 -42.849038) (xy 20.896077 -42.793416) (xy 20.908203 -42.738979)
			(xy 20.928126 -42.686888) (xy 20.955422 -42.638253) (xy 20.989508 -42.59411) (xy 21.029657 -42.555401)
			(xy 21.075015 -42.52295) (xy 21.124615 -42.497449) (xy 21.177399 -42.479442) (xy 21.232242 -42.469312)
			(xy 21.287976 -42.467275) (xy 21.343413 -42.473375) (xy 21.39737 -42.487481) (xy 21.448699 -42.509293)
			(xy 21.496305 -42.538347) (xy 21.539173 -42.574022) (xy 21.57639 -42.615559) (xy 21.607163 -42.662072)
			(xy 21.630835 -42.712569) (xy 21.646903 -42.765976) (xy 21.655023 -42.821152) (xy 21.655384 -42.84091)
			(xy 26.933142 -42.84091) (xy 26.937213 -42.785288) (xy 26.949339 -42.730851) (xy 26.969262 -42.67876)
			(xy 26.996558 -42.630125) (xy 27.030644 -42.585982) (xy 27.070793 -42.547273) (xy 27.116151 -42.514822)
			(xy 27.165751 -42.489321) (xy 27.218535 -42.471314) (xy 27.273378 -42.461184) (xy 27.329112 -42.459147)
			(xy 27.384549 -42.465247) (xy 27.438506 -42.479353) (xy 27.489835 -42.501165) (xy 27.537441 -42.530219)
			(xy 27.580309 -42.565894) (xy 27.617526 -42.607431) (xy 27.648299 -42.653944) (xy 27.671971 -42.704441)
			(xy 27.688039 -42.757848) (xy 27.696159 -42.813024) (xy 27.696668 -42.84091) (xy 27.696159 -42.868796)
			(xy 27.688039 -42.923972) (xy 27.671971 -42.977379) (xy 27.648299 -43.027876) (xy 27.617526 -43.074389)
			(xy 27.580309 -43.115926) (xy 27.537441 -43.151601) (xy 27.489835 -43.180655) (xy 27.438506 -43.202467)
			(xy 27.384549 -43.216573) (xy 27.329112 -43.222673) (xy 27.273378 -43.220636) (xy 27.218535 -43.210506)
			(xy 27.165751 -43.192499) (xy 27.116151 -43.166998) (xy 27.070793 -43.134547) (xy 27.030644 -43.095838)
			(xy 26.996558 -43.051695) (xy 26.969262 -43.00306) (xy 26.949339 -42.950969) (xy 26.937213 -42.896532)
			(xy 26.933142 -42.84091) (xy 21.655384 -42.84091) (xy 21.655532 -42.849038) (xy 21.655023 -42.876924)
			(xy 21.646903 -42.9321) (xy 21.630835 -42.985507) (xy 21.607163 -43.036004) (xy 21.57639 -43.082517)
			(xy 21.539173 -43.124054) (xy 21.496305 -43.159729) (xy 21.448699 -43.188783) (xy 21.39737 -43.210595)
			(xy 21.343413 -43.224701) (xy 21.287976 -43.230801) (xy 21.232242 -43.228764) (xy 21.177399 -43.218634)
			(xy 21.124615 -43.200627) (xy 21.075015 -43.175126) (xy 21.029657 -43.142675) (xy 20.989508 -43.103966)
			(xy 20.955422 -43.059823) (xy 20.928126 -43.011188) (xy 20.908203 -42.959097) (xy 20.896077 -42.90466)
			(xy 20.892006 -42.849038) (xy 19.02601 -42.849038) (xy 19.023719 -42.854026) (xy 18.993986 -42.89999)
			(xy 18.97634 -42.92092) (xy 18.976086 -42.921174) (xy 18.970503 -42.928263) (xy 18.964254 -42.945178)
			(xy 18.963894 -42.954194) (xy 18.963894 -43.02125) (xy 18.964277 -43.030264) (xy 18.970507 -43.047181)
			(xy 18.976086 -43.05427) (xy 18.97634 -43.05427) (xy 18.97634 -43.054524) (xy 18.993964 -43.075468)
			(xy 19.023676 -43.121438) (xy 19.046515 -43.171183) (xy 19.06201 -43.223681) (xy 19.069843 -43.277854)
			(xy 19.07032 -43.305222) (xy 44.307252 -43.305222) (xy 44.307718 -43.277852) (xy 44.315534 -43.223672)
			(xy 44.331022 -43.171168) (xy 44.353864 -43.121422) (xy 44.38359 -43.075455) (xy 44.401232 -43.054524)
			(xy 44.401486 -43.05427) (xy 44.407048 -43.047166) (xy 44.41331 -43.030263) (xy 44.413678 -43.02125)
			(xy 44.413678 -42.954194) (xy 44.413329 -42.945176) (xy 44.407076 -42.928259) (xy 44.401486 -42.921174)
			(xy 44.401232 -42.921174) (xy 44.401232 -42.92092) (xy 44.383594 -42.899987) (xy 44.353881 -42.854015)
			(xy 44.331044 -42.804268) (xy 44.315553 -42.751767) (xy 44.307725 -42.697591) (xy 44.307252 -42.670222)
			(xy 44.307802 -42.641484) (xy 44.31642 -42.584659) (xy 44.333465 -42.529769) (xy 44.35855 -42.478057)
			(xy 44.391109 -42.430692) (xy 44.410376 -42.409364) (xy 44.41698 -42.402506) (xy 44.424092 -42.384472)
			(xy 44.424092 -42.295572) (xy 44.41698 -42.277538) (xy 44.410376 -42.27068) (xy 44.391129 -42.249333)
			(xy 44.358567 -42.201973) (xy 44.333478 -42.150264) (xy 44.316428 -42.095377) (xy 44.307805 -42.038553)
			(xy 44.307802 -41.981079) (xy 44.316421 -41.924255) (xy 44.333466 -41.869366) (xy 44.358551 -41.817655)
			(xy 44.391109 -41.770292) (xy 44.410376 -41.748964) (xy 44.41698 -41.742106) (xy 44.424092 -41.724072)
			(xy 44.424092 -41.635172) (xy 44.41698 -41.617138) (xy 44.410376 -41.61028) (xy 44.391122 -41.588938)
			(xy 44.358552 -41.541581) (xy 44.333456 -41.489873) (xy 44.316401 -41.434985) (xy 44.307775 -41.37816)
			(xy 44.307252 -41.349422) (xy 44.307738 -41.322171) (xy 44.315494 -41.268223) (xy 44.330849 -41.215928)
			(xy 44.353491 -41.166351) (xy 44.382957 -41.120501) (xy 44.418648 -41.07931) (xy 44.459839 -41.043619)
			(xy 44.505689 -41.014153) (xy 44.555266 -40.991511) (xy 44.607561 -40.976156) (xy 44.661509 -40.9684)
			(xy 44.716011 -40.9684) (xy 44.739132 -40.971724) (xy 52.594 -40.971724) (xy 52.598071 -40.916102)
			(xy 52.610197 -40.861665) (xy 52.63012 -40.809574) (xy 52.657416 -40.760939) (xy 52.691502 -40.716796)
			(xy 52.731651 -40.678087) (xy 52.777009 -40.645636) (xy 52.826609 -40.620135) (xy 52.879393 -40.602128)
			(xy 52.934236 -40.591998) (xy 52.98997 -40.589961) (xy 53.045407 -40.596061) (xy 53.099364 -40.610167)
			(xy 53.150693 -40.631979) (xy 53.198299 -40.661033) (xy 53.241167 -40.696708) (xy 53.278384 -40.738245)
			(xy 53.309157 -40.784758) (xy 53.332829 -40.835255) (xy 53.348897 -40.888662) (xy 53.357017 -40.943838)
			(xy 53.357526 -40.971724) (xy 53.357017 -40.99961) (xy 53.348897 -41.054786) (xy 53.332829 -41.108193)
			(xy 53.309157 -41.15869) (xy 53.278384 -41.205203) (xy 53.241167 -41.24674) (xy 53.214713 -41.268755)
			(xy 67.843827 -41.268755) (xy 67.843827 -41.214245) (xy 67.851585 -41.160289) (xy 67.866942 -41.107987)
			(xy 67.889587 -41.058402) (xy 67.919058 -41.012545) (xy 67.954755 -40.971349) (xy 67.995952 -40.935653)
			(xy 68.041809 -40.906183) (xy 68.091394 -40.883539) (xy 68.143697 -40.868183) (xy 68.197653 -40.860426)
			(xy 68.224908 -40.859964) (xy 68.253647 -40.860492) (xy 68.310473 -40.869115) (xy 68.365364 -40.886165)
			(xy 68.417075 -40.911255) (xy 68.464439 -40.943818) (xy 68.485766 -40.963088) (xy 68.492624 -40.969692)
			(xy 68.510658 -40.976804) (xy 68.599558 -40.976804) (xy 68.617592 -40.969692) (xy 68.62445 -40.963088)
			(xy 68.645781 -40.943822) (xy 68.693141 -40.911253) (xy 68.744852 -40.886159) (xy 68.799742 -40.869107)
			(xy 68.856569 -40.860484) (xy 68.885308 -40.859964) (xy 68.912557 -40.860507) (xy 68.9665 -40.868264)
			(xy 69.01879 -40.883618) (xy 69.068362 -40.906258) (xy 69.114208 -40.935722) (xy 69.155394 -40.971411)
			(xy 69.191082 -41.012598) (xy 69.220546 -41.058445) (xy 69.243185 -41.108018) (xy 69.258538 -41.160308)
			(xy 69.266294 -41.214251) (xy 69.266294 -41.268749) (xy 69.258538 -41.322692) (xy 69.243185 -41.374982)
			(xy 69.220546 -41.424555) (xy 69.191082 -41.470402) (xy 69.155394 -41.511589) (xy 69.114208 -41.547277)
			(xy 69.068362 -41.576742) (xy 69.01879 -41.599382) (xy 68.9665 -41.614736) (xy 68.912557 -41.622493)
			(xy 68.885308 -41.62298) (xy 68.85657 -41.62243) (xy 68.799745 -41.613811) (xy 68.744855 -41.596765)
			(xy 68.693143 -41.57168) (xy 68.645779 -41.539123) (xy 68.62445 -41.519856) (xy 68.617592 -41.513252)
			(xy 68.599558 -41.50614) (xy 68.510658 -41.50614) (xy 68.492624 -41.513252) (xy 68.485766 -41.519856)
			(xy 68.464435 -41.539122) (xy 68.417074 -41.571689) (xy 68.365363 -41.596783) (xy 68.310474 -41.613834)
			(xy 68.253647 -41.622458) (xy 68.224908 -41.62298) (xy 68.197653 -41.622574) (xy 68.143697 -41.614817)
			(xy 68.091394 -41.599461) (xy 68.041809 -41.576817) (xy 67.995952 -41.547347) (xy 67.954755 -41.511651)
			(xy 67.919058 -41.470455) (xy 67.889587 -41.424598) (xy 67.866942 -41.375013) (xy 67.851585 -41.322711)
			(xy 67.843827 -41.268755) (xy 53.214713 -41.268755) (xy 53.198299 -41.282415) (xy 53.150693 -41.311469)
			(xy 53.099364 -41.333281) (xy 53.045407 -41.347387) (xy 52.98997 -41.353487) (xy 52.934236 -41.35145)
			(xy 52.879393 -41.34132) (xy 52.826609 -41.323313) (xy 52.777009 -41.297812) (xy 52.731651 -41.265361)
			(xy 52.691502 -41.226652) (xy 52.657416 -41.182509) (xy 52.63012 -41.133874) (xy 52.610197 -41.081783)
			(xy 52.598071 -41.027346) (xy 52.594 -40.971724) (xy 44.739132 -40.971724) (xy 44.769959 -40.976156)
			(xy 44.822254 -40.991511) (xy 44.871831 -41.014153) (xy 44.917681 -41.043619) (xy 44.958872 -41.07931)
			(xy 44.994563 -41.120501) (xy 45.024029 -41.166351) (xy 45.046671 -41.215928) (xy 45.062026 -41.268223)
			(xy 45.069782 -41.322171) (xy 45.070268 -41.349422) (xy 45.069739 -41.37816) (xy 45.061115 -41.434987)
			(xy 45.044065 -41.489877) (xy 45.018975 -41.541589) (xy 44.986413 -41.588952) (xy 44.967144 -41.61028)
			(xy 44.96054 -41.617138) (xy 44.953428 -41.635172) (xy 44.953428 -41.724072) (xy 44.96054 -41.742106)
			(xy 44.967144 -41.748964) (xy 44.986438 -41.770271) (xy 45.019005 -41.817636) (xy 45.044098 -41.869351)
			(xy 45.061148 -41.924245) (xy 45.069769 -41.981076) (xy 45.069767 -42.038556) (xy 45.06114 -42.095386)
			(xy 45.044086 -42.150279) (xy 45.018989 -42.201992) (xy 44.986418 -42.249354) (xy 44.967144 -42.27068)
			(xy 44.96054 -42.277538) (xy 44.953428 -42.295572) (xy 44.953428 -42.384472) (xy 44.96054 -42.402506)
			(xy 44.967144 -42.409364) (xy 44.986422 -42.430685) (xy 45.018988 -42.478048) (xy 45.044079 -42.529761)
			(xy 45.061128 -42.584654) (xy 45.069749 -42.641482) (xy 45.070268 -42.670222) (xy 45.069823 -42.697593)
			(xy 45.062001 -42.751773) (xy 45.046508 -42.804277) (xy 45.025951 -42.849038) (xy 46.891954 -42.849038)
			(xy 46.896025 -42.793416) (xy 46.908151 -42.738979) (xy 46.928074 -42.686888) (xy 46.95537 -42.638253)
			(xy 46.989456 -42.59411) (xy 47.029605 -42.555401) (xy 47.074963 -42.52295) (xy 47.124563 -42.497449)
			(xy 47.177347 -42.479442) (xy 47.23219 -42.469312) (xy 47.287924 -42.467275) (xy 47.343361 -42.473375)
			(xy 47.397318 -42.487481) (xy 47.448647 -42.509293) (xy 47.496253 -42.538347) (xy 47.539121 -42.574022)
			(xy 47.576338 -42.615559) (xy 47.607111 -42.662072) (xy 47.630783 -42.712569) (xy 47.646851 -42.765976)
			(xy 47.654971 -42.821152) (xy 47.655332 -42.84091) (xy 52.93309 -42.84091) (xy 52.937161 -42.785288)
			(xy 52.949287 -42.730851) (xy 52.96921 -42.67876) (xy 52.996506 -42.630125) (xy 53.030592 -42.585982)
			(xy 53.070741 -42.547273) (xy 53.116099 -42.514822) (xy 53.165699 -42.489321) (xy 53.218483 -42.471314)
			(xy 53.273326 -42.461184) (xy 53.32906 -42.459147) (xy 53.384497 -42.465247) (xy 53.438454 -42.479353)
			(xy 53.489783 -42.501165) (xy 53.537389 -42.530219) (xy 53.580257 -42.565894) (xy 53.617474 -42.607431)
			(xy 53.648247 -42.653944) (xy 53.671919 -42.704441) (xy 53.687987 -42.757848) (xy 53.696107 -42.813024)
			(xy 53.696616 -42.84091) (xy 53.696107 -42.868796) (xy 53.687987 -42.923972) (xy 53.671919 -42.977379)
			(xy 53.648247 -43.027876) (xy 53.617474 -43.074389) (xy 53.580257 -43.115926) (xy 53.537389 -43.151601)
			(xy 53.489783 -43.180655) (xy 53.438454 -43.202467) (xy 53.384497 -43.216573) (xy 53.32906 -43.222673)
			(xy 53.273326 -43.220636) (xy 53.218483 -43.210506) (xy 53.165699 -43.192499) (xy 53.116099 -43.166998)
			(xy 53.070741 -43.134547) (xy 53.030592 -43.095838) (xy 52.996506 -43.051695) (xy 52.96921 -43.00306)
			(xy 52.949287 -42.950969) (xy 52.937161 -42.896532) (xy 52.93309 -42.84091) (xy 47.655332 -42.84091)
			(xy 47.65548 -42.849038) (xy 47.654971 -42.876924) (xy 47.646851 -42.9321) (xy 47.630783 -42.985507)
			(xy 47.607111 -43.036004) (xy 47.576338 -43.082517) (xy 47.539121 -43.124054) (xy 47.496253 -43.159729)
			(xy 47.448647 -43.188783) (xy 47.397318 -43.210595) (xy 47.343361 -43.224701) (xy 47.287924 -43.230801)
			(xy 47.23219 -43.228764) (xy 47.177347 -43.218634) (xy 47.124563 -43.200627) (xy 47.074963 -43.175126)
			(xy 47.029605 -43.142675) (xy 46.989456 -43.103966) (xy 46.95537 -43.059823) (xy 46.928074 -43.011188)
			(xy 46.908151 -42.959097) (xy 46.896025 -42.90466) (xy 46.891954 -42.849038) (xy 45.025951 -42.849038)
			(xy 45.023661 -42.854024) (xy 44.993932 -42.899989) (xy 44.976288 -42.92092) (xy 44.976034 -42.921174)
			(xy 44.970444 -42.928258) (xy 44.964201 -42.945177) (xy 44.963842 -42.954194) (xy 44.963842 -43.02125)
			(xy 44.964214 -43.030266) (xy 44.97045 -43.047183) (xy 44.976034 -43.05427) (xy 44.976288 -43.05427)
			(xy 44.976288 -43.054524) (xy 44.993903 -43.075475) (xy 45.023619 -43.121443) (xy 45.04646 -43.171185)
			(xy 45.061956 -43.223682) (xy 45.069791 -43.277854) (xy 45.070268 -43.305222) (xy 70.3072 -43.305222)
			(xy 70.307679 -43.277852) (xy 70.315494 -43.223674) (xy 70.33098 -43.171171) (xy 70.353819 -43.121424)
			(xy 70.38354 -43.075456) (xy 70.40118 -43.054524) (xy 70.401434 -43.05427) (xy 70.407001 -43.04717)
			(xy 70.413258 -43.030263) (xy 70.413626 -43.02125) (xy 70.413626 -42.954194) (xy 70.413266 -42.945178)
			(xy 70.40702 -42.928261) (xy 70.401434 -42.921174) (xy 70.40118 -42.921174) (xy 70.40118 -42.92092)
			(xy 70.383534 -42.899994) (xy 70.353824 -42.854019) (xy 70.330989 -42.80427) (xy 70.3155 -42.751768)
			(xy 70.307673 -42.697592) (xy 70.3072 -42.670222) (xy 70.307737 -42.641484) (xy 70.316356 -42.584657)
			(xy 70.333403 -42.529766) (xy 70.358492 -42.478054) (xy 70.391054 -42.430691) (xy 70.410324 -42.409364)
			(xy 70.416928 -42.402506) (xy 70.42404 -42.384472) (xy 70.42404 -42.295572) (xy 70.416928 -42.277538)
			(xy 70.410324 -42.27068) (xy 70.391075 -42.249334) (xy 70.358509 -42.201975) (xy 70.333416 -42.150266)
			(xy 70.316365 -42.095379) (xy 70.30774 -42.038554) (xy 70.307738 -41.981078) (xy 70.316357 -41.924253)
			(xy 70.333404 -41.869364) (xy 70.358493 -41.817653) (xy 70.391055 -41.770291) (xy 70.410324 -41.748964)
			(xy 70.416928 -41.742106) (xy 70.42404 -41.724072) (xy 70.42404 -41.635172) (xy 70.416928 -41.617138)
			(xy 70.410324 -41.61028) (xy 70.391061 -41.588946) (xy 70.358494 -41.541586) (xy 70.333401 -41.489876)
			(xy 70.316348 -41.434987) (xy 70.307723 -41.37816) (xy 70.3072 -41.349422) (xy 70.307686 -41.322171)
			(xy 70.315442 -41.268223) (xy 70.330797 -41.215928) (xy 70.353439 -41.166351) (xy 70.382905 -41.120501)
			(xy 70.418596 -41.07931) (xy 70.459787 -41.043619) (xy 70.505637 -41.014153) (xy 70.555214 -40.991511)
			(xy 70.607509 -40.976156) (xy 70.661457 -40.9684) (xy 70.715959 -40.9684) (xy 70.73908 -40.971724)
			(xy 78.593948 -40.971724) (xy 78.598019 -40.916102) (xy 78.610145 -40.861665) (xy 78.630068 -40.809574)
			(xy 78.657364 -40.760939) (xy 78.69145 -40.716796) (xy 78.731599 -40.678087) (xy 78.776957 -40.645636)
			(xy 78.826557 -40.620135) (xy 78.879341 -40.602128) (xy 78.934184 -40.591998) (xy 78.989918 -40.589961)
			(xy 79.045355 -40.596061) (xy 79.099312 -40.610167) (xy 79.150641 -40.631979) (xy 79.198247 -40.661033)
			(xy 79.241115 -40.696708) (xy 79.278332 -40.738245) (xy 79.309105 -40.784758) (xy 79.332777 -40.835255)
			(xy 79.348845 -40.888662) (xy 79.356965 -40.943838) (xy 79.357474 -40.971724) (xy 79.356965 -40.99961)
			(xy 79.348845 -41.054786) (xy 79.332777 -41.108193) (xy 79.309105 -41.15869) (xy 79.278332 -41.205203)
			(xy 79.241115 -41.24674) (xy 79.214666 -41.268751) (xy 93.84385 -41.268751) (xy 93.84385 -41.214249)
			(xy 93.851606 -41.160301) (xy 93.86696 -41.108006) (xy 93.889599 -41.058428) (xy 93.919064 -41.012576)
			(xy 93.954753 -40.971384) (xy 93.995941 -40.93569) (xy 94.041789 -40.90622) (xy 94.091365 -40.883575)
			(xy 94.143658 -40.868215) (xy 94.197605 -40.860453) (xy 94.224856 -40.859964) (xy 94.253596 -40.860463)
			(xy 94.310424 -40.869093) (xy 94.365314 -40.88615) (xy 94.417026 -40.911246) (xy 94.464387 -40.943816)
			(xy 94.485714 -40.963088) (xy 94.492572 -40.969692) (xy 94.510606 -40.976804) (xy 94.599506 -40.976804)
			(xy 94.61754 -40.969692) (xy 94.624398 -40.963088) (xy 94.645709 -40.943799) (xy 94.693075 -40.911233)
			(xy 94.74479 -40.886143) (xy 94.799685 -40.869097) (xy 94.856516 -40.860481) (xy 94.885256 -40.859964)
			(xy 94.912509 -40.86048) (xy 94.966461 -40.868232) (xy 95.01876 -40.883583) (xy 95.068342 -40.906221)
			(xy 95.114197 -40.935686) (xy 95.155392 -40.971377) (xy 95.191088 -41.012567) (xy 95.220558 -41.058419)
			(xy 95.243202 -41.107999) (xy 95.258559 -41.160296) (xy 95.266317 -41.214247) (xy 95.266317 -41.268753)
			(xy 95.258559 -41.322704) (xy 95.243202 -41.375001) (xy 95.220558 -41.424581) (xy 95.191088 -41.470433)
			(xy 95.155392 -41.511623) (xy 95.114197 -41.547314) (xy 95.068342 -41.576779) (xy 95.01876 -41.599417)
			(xy 94.966461 -41.614768) (xy 94.912509 -41.62252) (xy 94.885256 -41.62298) (xy 94.856517 -41.622462)
			(xy 94.79969 -41.613834) (xy 94.744801 -41.596782) (xy 94.693089 -41.57169) (xy 94.645726 -41.539126)
			(xy 94.624398 -41.519856) (xy 94.61754 -41.513252) (xy 94.599506 -41.50614) (xy 94.510606 -41.50614)
			(xy 94.492572 -41.513252) (xy 94.485714 -41.519856) (xy 94.464404 -41.539147) (xy 94.417038 -41.57171)
			(xy 94.365322 -41.596799) (xy 94.310427 -41.613845) (xy 94.253596 -41.622462) (xy 94.224856 -41.62298)
			(xy 94.197605 -41.622547) (xy 94.143658 -41.614785) (xy 94.091365 -41.599425) (xy 94.041789 -41.57678)
			(xy 93.995941 -41.54731) (xy 93.954753 -41.511616) (xy 93.919064 -41.470424) (xy 93.889599 -41.424572)
			(xy 93.86696 -41.374994) (xy 93.851606 -41.322699) (xy 93.84385 -41.268751) (xy 79.214666 -41.268751)
			(xy 79.198247 -41.282415) (xy 79.150641 -41.311469) (xy 79.099312 -41.333281) (xy 79.045355 -41.347387)
			(xy 78.989918 -41.353487) (xy 78.934184 -41.35145) (xy 78.879341 -41.34132) (xy 78.826557 -41.323313)
			(xy 78.776957 -41.297812) (xy 78.731599 -41.265361) (xy 78.69145 -41.226652) (xy 78.657364 -41.182509)
			(xy 78.630068 -41.133874) (xy 78.610145 -41.081783) (xy 78.598019 -41.027346) (xy 78.593948 -40.971724)
			(xy 70.73908 -40.971724) (xy 70.769907 -40.976156) (xy 70.822202 -40.991511) (xy 70.871779 -41.014153)
			(xy 70.917629 -41.043619) (xy 70.95882 -41.07931) (xy 70.994511 -41.120501) (xy 71.023977 -41.166351)
			(xy 71.046619 -41.215928) (xy 71.061974 -41.268223) (xy 71.06973 -41.322171) (xy 71.070216 -41.349422)
			(xy 71.069701 -41.378161) (xy 71.061076 -41.434989) (xy 71.044023 -41.489879) (xy 71.01893 -41.541591)
			(xy 70.986363 -41.588953) (xy 70.967092 -41.61028) (xy 70.960488 -41.617138) (xy 70.953376 -41.635172)
			(xy 70.953376 -41.724072) (xy 70.960488 -41.742106) (xy 70.967092 -41.748964) (xy 70.986384 -41.770272)
			(xy 71.018947 -41.817638) (xy 71.044036 -41.869353) (xy 71.061084 -41.924247) (xy 71.069704 -41.981076)
			(xy 71.069702 -42.038556) (xy 71.061077 -42.095385) (xy 71.044025 -42.150277) (xy 71.018931 -42.201989)
			(xy 70.986364 -42.249353) (xy 70.967092 -42.27068) (xy 70.960488 -42.277538) (xy 70.953376 -42.295572)
			(xy 70.953376 -42.384472) (xy 70.960488 -42.402506) (xy 70.967092 -42.409364) (xy 70.986378 -42.430678)
			(xy 71.018941 -42.478044) (xy 71.04403 -42.529759) (xy 71.061077 -42.584652) (xy 71.069697 -42.641482)
			(xy 71.070216 -42.670222) (xy 71.069783 -42.697594) (xy 71.061961 -42.751775) (xy 71.046465 -42.804279)
			(xy 71.025906 -42.849038) (xy 72.891902 -42.849038) (xy 72.895973 -42.793416) (xy 72.908099 -42.738979)
			(xy 72.928022 -42.686888) (xy 72.955318 -42.638253) (xy 72.989404 -42.59411) (xy 73.029553 -42.555401)
			(xy 73.074911 -42.52295) (xy 73.124511 -42.497449) (xy 73.177295 -42.479442) (xy 73.232138 -42.469312)
			(xy 73.287872 -42.467275) (xy 73.343309 -42.473375) (xy 73.397266 -42.487481) (xy 73.448595 -42.509293)
			(xy 73.496201 -42.538347) (xy 73.539069 -42.574022) (xy 73.576286 -42.615559) (xy 73.607059 -42.662072)
			(xy 73.630731 -42.712569) (xy 73.646799 -42.765976) (xy 73.654919 -42.821152) (xy 73.65528 -42.84091)
			(xy 78.933038 -42.84091) (xy 78.937109 -42.785288) (xy 78.949235 -42.730851) (xy 78.969158 -42.67876)
			(xy 78.996454 -42.630125) (xy 79.03054 -42.585982) (xy 79.070689 -42.547273) (xy 79.116047 -42.514822)
			(xy 79.165647 -42.489321) (xy 79.218431 -42.471314) (xy 79.273274 -42.461184) (xy 79.329008 -42.459147)
			(xy 79.384445 -42.465247) (xy 79.438402 -42.479353) (xy 79.489731 -42.501165) (xy 79.537337 -42.530219)
			(xy 79.580205 -42.565894) (xy 79.617422 -42.607431) (xy 79.648195 -42.653944) (xy 79.671867 -42.704441)
			(xy 79.687935 -42.757848) (xy 79.696055 -42.813024) (xy 79.696564 -42.84091) (xy 79.696055 -42.868796)
			(xy 79.687935 -42.923972) (xy 79.671867 -42.977379) (xy 79.648195 -43.027876) (xy 79.617422 -43.074389)
			(xy 79.580205 -43.115926) (xy 79.537337 -43.151601) (xy 79.489731 -43.180655) (xy 79.438402 -43.202467)
			(xy 79.384445 -43.216573) (xy 79.329008 -43.222673) (xy 79.273274 -43.220636) (xy 79.218431 -43.210506)
			(xy 79.165647 -43.192499) (xy 79.116047 -43.166998) (xy 79.070689 -43.134547) (xy 79.03054 -43.095838)
			(xy 78.996454 -43.051695) (xy 78.969158 -43.00306) (xy 78.949235 -42.950969) (xy 78.937109 -42.896532)
			(xy 78.933038 -42.84091) (xy 73.65528 -42.84091) (xy 73.655428 -42.849038) (xy 73.654919 -42.876924)
			(xy 73.646799 -42.9321) (xy 73.630731 -42.985507) (xy 73.607059 -43.036004) (xy 73.576286 -43.082517)
			(xy 73.539069 -43.124054) (xy 73.496201 -43.159729) (xy 73.448595 -43.188783) (xy 73.397266 -43.210595)
			(xy 73.343309 -43.224701) (xy 73.287872 -43.230801) (xy 73.232138 -43.228764) (xy 73.177295 -43.218634)
			(xy 73.124511 -43.200627) (xy 73.074911 -43.175126) (xy 73.029553 -43.142675) (xy 72.989404 -43.103966)
			(xy 72.955318 -43.059823) (xy 72.928022 -43.011188) (xy 72.908099 -42.959097) (xy 72.895973 -42.90466)
			(xy 72.891902 -42.849038) (xy 71.025906 -42.849038) (xy 71.023615 -42.854026) (xy 70.993882 -42.89999)
			(xy 70.976236 -42.92092) (xy 70.975982 -42.921174) (xy 70.970398 -42.928262) (xy 70.96415 -42.945178)
			(xy 70.96379 -42.954194) (xy 70.96379 -43.02125) (xy 70.964173 -43.030264) (xy 70.970403 -43.047181)
			(xy 70.975982 -43.05427) (xy 70.976236 -43.05427) (xy 70.976236 -43.054524) (xy 70.993859 -43.075469)
			(xy 71.023572 -43.121439) (xy 71.04641 -43.171183) (xy 71.061905 -43.223681) (xy 71.069739 -43.277854)
			(xy 71.070216 -43.305222) (xy 96.307148 -43.305222) (xy 96.307615 -43.277852) (xy 96.315431 -43.223672)
			(xy 96.330919 -43.171169) (xy 96.353761 -43.121422) (xy 96.383486 -43.075455) (xy 96.401128 -43.054524)
			(xy 96.401382 -43.05427) (xy 96.406943 -43.047166) (xy 96.413205 -43.030263) (xy 96.413574 -43.02125)
			(xy 96.413574 -42.954194) (xy 96.413226 -42.945176) (xy 96.406973 -42.928259) (xy 96.401382 -42.921174)
			(xy 96.401128 -42.921174) (xy 96.401128 -42.92092) (xy 96.383489 -42.899988) (xy 96.353776 -42.854015)
			(xy 96.33094 -42.804268) (xy 96.315449 -42.751767) (xy 96.307621 -42.697591) (xy 96.307148 -42.670222)
			(xy 96.307699 -42.641484) (xy 96.316317 -42.584659) (xy 96.333362 -42.529769) (xy 96.358447 -42.478057)
			(xy 96.391005 -42.430692) (xy 96.410272 -42.409364) (xy 96.416876 -42.402506) (xy 96.423988 -42.384472)
			(xy 96.423988 -42.295572) (xy 96.416876 -42.277538) (xy 96.410272 -42.27068) (xy 96.391025 -42.249333)
			(xy 96.358464 -42.201973) (xy 96.333374 -42.150264) (xy 96.316325 -42.095377) (xy 96.307702 -42.038553)
			(xy 96.307699 -41.981079) (xy 96.316318 -41.924255) (xy 96.333363 -41.869366) (xy 96.358448 -41.817655)
			(xy 96.391005 -41.770292) (xy 96.410272 -41.748964) (xy 96.416876 -41.742106) (xy 96.423988 -41.724072)
			(xy 96.423988 -41.635172) (xy 96.416876 -41.617138) (xy 96.410272 -41.61028) (xy 96.391017 -41.588939)
			(xy 96.358448 -41.541581) (xy 96.333351 -41.489873) (xy 96.316297 -41.434985) (xy 96.307671 -41.37816)
			(xy 96.307148 -41.349422) (xy 96.307634 -41.322171) (xy 96.31539 -41.268223) (xy 96.330745 -41.215928)
			(xy 96.353387 -41.166351) (xy 96.382853 -41.120501) (xy 96.418544 -41.07931) (xy 96.459735 -41.043619)
			(xy 96.505585 -41.014153) (xy 96.555162 -40.991511) (xy 96.607457 -40.976156) (xy 96.661405 -40.9684)
			(xy 96.715907 -40.9684) (xy 96.739028 -40.971724) (xy 116.694202 -40.971724) (xy 116.698273 -40.916102)
			(xy 116.710399 -40.861665) (xy 116.730322 -40.809574) (xy 116.757618 -40.760939) (xy 116.791704 -40.716796)
			(xy 116.831853 -40.678087) (xy 116.877211 -40.645636) (xy 116.926811 -40.620135) (xy 116.979595 -40.602128)
			(xy 117.034438 -40.591998) (xy 117.090172 -40.589961) (xy 117.145609 -40.596061) (xy 117.199566 -40.610167)
			(xy 117.250895 -40.631979) (xy 117.298501 -40.661033) (xy 117.341369 -40.696708) (xy 117.378586 -40.738245)
			(xy 117.409359 -40.784758) (xy 117.433031 -40.835255) (xy 117.449099 -40.888662) (xy 117.457219 -40.943838)
			(xy 117.457728 -40.971724) (xy 117.457219 -40.99961) (xy 117.449099 -41.054786) (xy 117.433031 -41.108193)
			(xy 117.409359 -41.15869) (xy 117.378586 -41.205203) (xy 117.341369 -41.24674) (xy 117.314915 -41.268755)
			(xy 131.944027 -41.268755) (xy 131.944027 -41.214245) (xy 131.951785 -41.160289) (xy 131.967142 -41.107986)
			(xy 131.989787 -41.058402) (xy 132.019258 -41.012545) (xy 132.054956 -40.971349) (xy 132.096153 -40.935652)
			(xy 132.142011 -40.906183) (xy 132.191596 -40.883539) (xy 132.243899 -40.868183) (xy 132.297855 -40.860426)
			(xy 132.32511 -40.859964) (xy 132.353849 -40.860491) (xy 132.410675 -40.869114) (xy 132.465566 -40.886164)
			(xy 132.517278 -40.911255) (xy 132.564641 -40.943818) (xy 132.585968 -40.963088) (xy 132.592826 -40.969692)
			(xy 132.61086 -40.976804) (xy 132.69976 -40.976804) (xy 132.717794 -40.969692) (xy 132.724652 -40.963088)
			(xy 132.745982 -40.943821) (xy 132.793343 -40.911252) (xy 132.845053 -40.886158) (xy 132.899944 -40.869107)
			(xy 132.956771 -40.860484) (xy 132.98551 -40.859964) (xy 133.012759 -40.860507) (xy 133.066701 -40.868264)
			(xy 133.118991 -40.883619) (xy 133.168563 -40.906259) (xy 133.214409 -40.935723) (xy 133.255595 -40.971412)
			(xy 133.291283 -41.012599) (xy 133.320746 -41.058445) (xy 133.343385 -41.108018) (xy 133.358738 -41.160308)
			(xy 133.366494 -41.214251) (xy 133.366494 -41.268749) (xy 133.358738 -41.322692) (xy 133.343385 -41.374982)
			(xy 133.320746 -41.424555) (xy 133.291283 -41.470401) (xy 133.255595 -41.511588) (xy 133.214409 -41.547277)
			(xy 133.168563 -41.576741) (xy 133.118991 -41.599381) (xy 133.066701 -41.614736) (xy 133.012759 -41.622493)
			(xy 132.98551 -41.62298) (xy 132.956772 -41.622429) (xy 132.899947 -41.61381) (xy 132.845058 -41.596765)
			(xy 132.793345 -41.57168) (xy 132.745981 -41.539123) (xy 132.724652 -41.519856) (xy 132.717794 -41.513252)
			(xy 132.69976 -41.50614) (xy 132.61086 -41.50614) (xy 132.592826 -41.513252) (xy 132.585968 -41.519856)
			(xy 132.564636 -41.539121) (xy 132.517275 -41.571688) (xy 132.465565 -41.596782) (xy 132.410675 -41.613834)
			(xy 132.353849 -41.622458) (xy 132.32511 -41.62298) (xy 132.297855 -41.622574) (xy 132.243899 -41.614817)
			(xy 132.191596 -41.599461) (xy 132.142011 -41.576817) (xy 132.096153 -41.547348) (xy 132.054956 -41.511651)
			(xy 132.019258 -41.470455) (xy 131.989787 -41.424598) (xy 131.967142 -41.375014) (xy 131.951785 -41.322711)
			(xy 131.944027 -41.268755) (xy 117.314915 -41.268755) (xy 117.298501 -41.282415) (xy 117.250895 -41.311469)
			(xy 117.199566 -41.333281) (xy 117.145609 -41.347387) (xy 117.090172 -41.353487) (xy 117.034438 -41.35145)
			(xy 116.979595 -41.34132) (xy 116.926811 -41.323313) (xy 116.877211 -41.297812) (xy 116.831853 -41.265361)
			(xy 116.791704 -41.226652) (xy 116.757618 -41.182509) (xy 116.730322 -41.133874) (xy 116.710399 -41.081783)
			(xy 116.698273 -41.027346) (xy 116.694202 -40.971724) (xy 96.739028 -40.971724) (xy 96.769855 -40.976156)
			(xy 96.82215 -40.991511) (xy 96.871727 -41.014153) (xy 96.917577 -41.043619) (xy 96.958768 -41.07931)
			(xy 96.994459 -41.120501) (xy 97.023925 -41.166351) (xy 97.046567 -41.215928) (xy 97.061922 -41.268223)
			(xy 97.069678 -41.322171) (xy 97.070164 -41.349422) (xy 97.069637 -41.378161) (xy 97.061012 -41.434987)
			(xy 97.043962 -41.489877) (xy 97.018872 -41.541589) (xy 96.986309 -41.588952) (xy 96.96704 -41.61028)
			(xy 96.960436 -41.617138) (xy 96.953324 -41.635172) (xy 96.953324 -41.724072) (xy 96.960436 -41.742106)
			(xy 96.96704 -41.748964) (xy 96.986334 -41.770271) (xy 97.018902 -41.817636) (xy 97.043995 -41.869351)
			(xy 97.061045 -41.924245) (xy 97.069666 -41.981076) (xy 97.069664 -42.038557) (xy 97.061037 -42.095387)
			(xy 97.043983 -42.150279) (xy 97.018886 -42.201992) (xy 96.986314 -42.249354) (xy 96.96704 -42.27068)
			(xy 96.960436 -42.277538) (xy 96.953324 -42.295572) (xy 96.953324 -42.384472) (xy 96.960436 -42.402506)
			(xy 96.96704 -42.409364) (xy 96.986318 -42.430685) (xy 97.018884 -42.478048) (xy 97.043975 -42.529761)
			(xy 97.061024 -42.584654) (xy 97.069645 -42.641483) (xy 97.070164 -42.670222) (xy 97.06972 -42.697593)
			(xy 97.061898 -42.751773) (xy 97.046404 -42.804277) (xy 97.025847 -42.849038) (xy 98.89185 -42.849038)
			(xy 98.895921 -42.793416) (xy 98.908047 -42.738979) (xy 98.92797 -42.686888) (xy 98.955266 -42.638253)
			(xy 98.989352 -42.59411) (xy 99.029501 -42.555401) (xy 99.074859 -42.52295) (xy 99.124459 -42.497449)
			(xy 99.177243 -42.479442) (xy 99.232086 -42.469312) (xy 99.28782 -42.467275) (xy 99.343257 -42.473375)
			(xy 99.397214 -42.487481) (xy 99.448543 -42.509293) (xy 99.496149 -42.538347) (xy 99.539017 -42.574022)
			(xy 99.576234 -42.615559) (xy 99.607007 -42.662072) (xy 99.630679 -42.712569) (xy 99.646747 -42.765976)
			(xy 99.654867 -42.821152) (xy 99.655228 -42.84091) (xy 104.932986 -42.84091) (xy 104.937057 -42.785288)
			(xy 104.949183 -42.730851) (xy 104.969106 -42.67876) (xy 104.996402 -42.630125) (xy 105.030488 -42.585982)
			(xy 105.070637 -42.547273) (xy 105.115995 -42.514822) (xy 105.165595 -42.489321) (xy 105.218379 -42.471314)
			(xy 105.273222 -42.461184) (xy 105.328956 -42.459147) (xy 105.384393 -42.465247) (xy 105.43835 -42.479353)
			(xy 105.489679 -42.501165) (xy 105.537285 -42.530219) (xy 105.580153 -42.565894) (xy 105.61737 -42.607431)
			(xy 105.648143 -42.653944) (xy 105.671815 -42.704441) (xy 105.687883 -42.757848) (xy 105.696003 -42.813024)
			(xy 105.696512 -42.84091) (xy 105.696003 -42.868796) (xy 105.687883 -42.923972) (xy 105.671815 -42.977379)
			(xy 105.648143 -43.027876) (xy 105.61737 -43.074389) (xy 105.580153 -43.115926) (xy 105.537285 -43.151601)
			(xy 105.489679 -43.180655) (xy 105.43835 -43.202467) (xy 105.384393 -43.216573) (xy 105.328956 -43.222673)
			(xy 105.273222 -43.220636) (xy 105.218379 -43.210506) (xy 105.165595 -43.192499) (xy 105.115995 -43.166998)
			(xy 105.070637 -43.134547) (xy 105.030488 -43.095838) (xy 104.996402 -43.051695) (xy 104.969106 -43.00306)
			(xy 104.949183 -42.950969) (xy 104.937057 -42.896532) (xy 104.932986 -42.84091) (xy 99.655228 -42.84091)
			(xy 99.655376 -42.849038) (xy 99.654867 -42.876924) (xy 99.646747 -42.9321) (xy 99.630679 -42.985507)
			(xy 99.607007 -43.036004) (xy 99.576234 -43.082517) (xy 99.539017 -43.124054) (xy 99.496149 -43.159729)
			(xy 99.448543 -43.188783) (xy 99.397214 -43.210595) (xy 99.343257 -43.224701) (xy 99.28782 -43.230801)
			(xy 99.232086 -43.228764) (xy 99.177243 -43.218634) (xy 99.124459 -43.200627) (xy 99.074859 -43.175126)
			(xy 99.029501 -43.142675) (xy 98.989352 -43.103966) (xy 98.955266 -43.059823) (xy 98.92797 -43.011188)
			(xy 98.908047 -42.959097) (xy 98.895921 -42.90466) (xy 98.89185 -42.849038) (xy 97.025847 -42.849038)
			(xy 97.023557 -42.854024) (xy 96.993828 -42.899989) (xy 96.976184 -42.92092) (xy 96.97593 -42.921174)
			(xy 96.97034 -42.928258) (xy 96.964097 -42.945177) (xy 96.963738 -42.954194) (xy 96.963738 -43.02125)
			(xy 96.964111 -43.030265) (xy 96.970346 -43.047183) (xy 96.97593 -43.05427) (xy 96.976184 -43.05427)
			(xy 96.976184 -43.054524) (xy 96.993798 -43.075476) (xy 97.023515 -43.121443) (xy 97.046355 -43.171185)
			(xy 97.061852 -43.223682) (xy 97.069687 -43.277854) (xy 97.070164 -43.305222) (xy 134.407402 -43.305222)
			(xy 134.40788 -43.277852) (xy 134.415695 -43.223674) (xy 134.431181 -43.171171) (xy 134.45402 -43.121424)
			(xy 134.483742 -43.075456) (xy 134.501382 -43.054524) (xy 134.501636 -43.05427) (xy 134.507203 -43.047171)
			(xy 134.513461 -43.030263) (xy 134.513828 -43.02125) (xy 134.513828 -42.954194) (xy 134.513468 -42.945178)
			(xy 134.507222 -42.928261) (xy 134.501636 -42.921174) (xy 134.501382 -42.921174) (xy 134.501382 -42.92092)
			(xy 134.483736 -42.899994) (xy 134.454026 -42.854019) (xy 134.431192 -42.80427) (xy 134.415702 -42.751768)
			(xy 134.407875 -42.697592) (xy 134.407402 -42.670222) (xy 134.407939 -42.641484) (xy 134.416558 -42.584657)
			(xy 134.433605 -42.529766) (xy 134.458694 -42.478054) (xy 134.491256 -42.430691) (xy 134.510526 -42.409364)
			(xy 134.51713 -42.402506) (xy 134.524242 -42.384472) (xy 134.524242 -42.295572) (xy 134.51713 -42.277538)
			(xy 134.510526 -42.27068) (xy 134.491277 -42.249334) (xy 134.458711 -42.201975) (xy 134.433618 -42.150267)
			(xy 134.416566 -42.095379) (xy 134.407941 -42.038554) (xy 134.407939 -41.981078) (xy 134.416559 -41.924253)
			(xy 134.433606 -41.869363) (xy 134.458695 -41.817653) (xy 134.491257 -41.770291) (xy 134.510526 -41.748964)
			(xy 134.51713 -41.742106) (xy 134.524242 -41.724072) (xy 134.524242 -41.635172) (xy 134.51713 -41.617138)
			(xy 134.510526 -41.61028) (xy 134.491264 -41.588946) (xy 134.458697 -41.541585) (xy 134.433603 -41.489876)
			(xy 134.41655 -41.434987) (xy 134.407925 -41.37816) (xy 134.407402 -41.349422) (xy 134.407888 -41.322171)
			(xy 134.415644 -41.268223) (xy 134.430999 -41.215928) (xy 134.453641 -41.166351) (xy 134.483107 -41.120501)
			(xy 134.518798 -41.07931) (xy 134.559989 -41.043619) (xy 134.605839 -41.014153) (xy 134.655416 -40.991511)
			(xy 134.707711 -40.976156) (xy 134.761659 -40.9684) (xy 134.816161 -40.9684) (xy 134.839282 -40.971724)
			(xy 142.69415 -40.971724) (xy 142.698221 -40.916102) (xy 142.710347 -40.861665) (xy 142.73027 -40.809574)
			(xy 142.757566 -40.760939) (xy 142.791652 -40.716796) (xy 142.831801 -40.678087) (xy 142.877159 -40.645636)
			(xy 142.926759 -40.620135) (xy 142.979543 -40.602128) (xy 143.034386 -40.591998) (xy 143.09012 -40.589961)
			(xy 143.145557 -40.596061) (xy 143.199514 -40.610167) (xy 143.250843 -40.631979) (xy 143.298449 -40.661033)
			(xy 143.341317 -40.696708) (xy 143.378534 -40.738245) (xy 143.409307 -40.784758) (xy 143.432979 -40.835255)
			(xy 143.449047 -40.888662) (xy 143.457167 -40.943838) (xy 143.457676 -40.971724) (xy 143.457167 -40.99961)
			(xy 143.449047 -41.054786) (xy 143.432979 -41.108193) (xy 143.409307 -41.15869) (xy 143.378534 -41.205203)
			(xy 143.341317 -41.24674) (xy 143.314868 -41.268751) (xy 157.28365 -41.268751) (xy 157.28365 -41.214249)
			(xy 157.291406 -41.160301) (xy 157.30676 -41.108005) (xy 157.3294 -41.058427) (xy 157.358864 -41.012576)
			(xy 157.394554 -40.971383) (xy 157.435742 -40.935689) (xy 157.48159 -40.90622) (xy 157.531166 -40.883575)
			(xy 157.58346 -40.868215) (xy 157.637407 -40.860453) (xy 157.664658 -40.859964) (xy 157.693398 -40.860462)
			(xy 157.750226 -40.869092) (xy 157.805116 -40.886149) (xy 157.856828 -40.911246) (xy 157.90419 -40.943815)
			(xy 157.925516 -40.963088) (xy 157.932374 -40.969692) (xy 157.950408 -40.976804) (xy 158.039308 -40.976804)
			(xy 158.057342 -40.969692) (xy 158.0642 -40.963088) (xy 158.085527 -40.943818) (xy 158.13289 -40.911253)
			(xy 158.184601 -40.886162) (xy 158.239492 -40.869112) (xy 158.296319 -40.86049) (xy 158.353797 -40.86049)
			(xy 158.410624 -40.869112) (xy 158.465515 -40.886162) (xy 158.517226 -40.911253) (xy 158.564589 -40.943818)
			(xy 158.585916 -40.963088) (xy 158.592774 -40.969692) (xy 158.610808 -40.976804) (xy 158.699708 -40.976804)
			(xy 158.717742 -40.969692) (xy 158.7246 -40.963088) (xy 158.745911 -40.943798) (xy 158.793276 -40.911233)
			(xy 158.844992 -40.886143) (xy 158.899887 -40.869097) (xy 158.956718 -40.860481) (xy 158.985458 -40.859964)
			(xy 159.012711 -40.86048) (xy 159.066662 -40.868232) (xy 159.118961 -40.883583) (xy 159.168543 -40.906222)
			(xy 159.214398 -40.935686) (xy 159.255593 -40.971377) (xy 159.291288 -41.012568) (xy 159.320758 -41.05842)
			(xy 159.343402 -41.107999) (xy 159.358759 -41.160297) (xy 159.366517 -41.214247) (xy 159.366517 -41.268753)
			(xy 159.358759 -41.322703) (xy 159.343402 -41.375001) (xy 159.320758 -41.42458) (xy 159.291288 -41.470432)
			(xy 159.255593 -41.511623) (xy 159.214398 -41.547314) (xy 159.168543 -41.576778) (xy 159.118961 -41.599417)
			(xy 159.066662 -41.614768) (xy 159.012711 -41.62252) (xy 158.985458 -41.62298) (xy 158.956719 -41.62246)
			(xy 158.899893 -41.613834) (xy 158.845003 -41.596781) (xy 158.793291 -41.571689) (xy 158.745928 -41.539126)
			(xy 158.7246 -41.519856) (xy 158.717742 -41.513252) (xy 158.699708 -41.50614) (xy 158.610808 -41.50614)
			(xy 158.592774 -41.513252) (xy 158.585916 -41.519856) (xy 158.564589 -41.539126) (xy 158.517226 -41.571691)
			(xy 158.465515 -41.596782) (xy 158.410624 -41.613832) (xy 158.353797 -41.622454) (xy 158.296319 -41.622454)
			(xy 158.239492 -41.613832) (xy 158.184601 -41.596782) (xy 158.13289 -41.571691) (xy 158.085527 -41.539126)
			(xy 158.0642 -41.519856) (xy 158.057342 -41.513252) (xy 158.039308 -41.50614) (xy 157.950408 -41.50614)
			(xy 157.932374 -41.513252) (xy 157.925516 -41.519856) (xy 157.904205 -41.539146) (xy 157.856839 -41.57171)
			(xy 157.805123 -41.596799) (xy 157.750229 -41.613845) (xy 157.693398 -41.622462) (xy 157.664658 -41.62298)
			(xy 157.637407 -41.622547) (xy 157.58346 -41.614785) (xy 157.531166 -41.599425) (xy 157.48159 -41.57678)
			(xy 157.435742 -41.547311) (xy 157.394554 -41.511617) (xy 157.358864 -41.470424) (xy 157.3294 -41.424573)
			(xy 157.30676 -41.374995) (xy 157.291406 -41.322699) (xy 157.28365 -41.268751) (xy 143.314868 -41.268751)
			(xy 143.298449 -41.282415) (xy 143.250843 -41.311469) (xy 143.199514 -41.333281) (xy 143.145557 -41.347387)
			(xy 143.09012 -41.353487) (xy 143.034386 -41.35145) (xy 142.979543 -41.34132) (xy 142.926759 -41.323313)
			(xy 142.877159 -41.297812) (xy 142.831801 -41.265361) (xy 142.791652 -41.226652) (xy 142.757566 -41.182509)
			(xy 142.73027 -41.133874) (xy 142.710347 -41.081783) (xy 142.698221 -41.027346) (xy 142.69415 -40.971724)
			(xy 134.839282 -40.971724) (xy 134.870109 -40.976156) (xy 134.922404 -40.991511) (xy 134.971981 -41.014153)
			(xy 135.017831 -41.043619) (xy 135.059022 -41.07931) (xy 135.094713 -41.120501) (xy 135.124179 -41.166351)
			(xy 135.146821 -41.215928) (xy 135.162176 -41.268223) (xy 135.169932 -41.322171) (xy 135.170418 -41.349422)
			(xy 135.169903 -41.378161) (xy 135.161277 -41.434989) (xy 135.144225 -41.489879) (xy 135.119132 -41.541591)
			(xy 135.086565 -41.588953) (xy 135.067294 -41.61028) (xy 135.06069 -41.617138) (xy 135.053578 -41.635172)
			(xy 135.053578 -41.724072) (xy 135.06069 -41.742106) (xy 135.067294 -41.748964) (xy 135.086586 -41.770272)
			(xy 135.119149 -41.817638) (xy 135.144238 -41.869353) (xy 135.161286 -41.924247) (xy 135.169906 -41.981076)
			(xy 135.169903 -42.038556) (xy 135.161278 -42.095385) (xy 135.144226 -42.150277) (xy 135.119133 -42.201989)
			(xy 135.086566 -42.249353) (xy 135.067294 -42.27068) (xy 135.06069 -42.277538) (xy 135.053578 -42.295572)
			(xy 135.053578 -42.384472) (xy 135.06069 -42.402506) (xy 135.067294 -42.409364) (xy 135.086564 -42.430692)
			(xy 135.119132 -42.478053) (xy 135.144226 -42.529764) (xy 135.161277 -42.584655) (xy 135.169898 -42.641483)
			(xy 135.170418 -42.670222) (xy 135.169985 -42.697594) (xy 135.162162 -42.751775) (xy 135.146666 -42.804279)
			(xy 135.126108 -42.849038) (xy 136.992104 -42.849038) (xy 136.996175 -42.793416) (xy 137.008301 -42.738979)
			(xy 137.028224 -42.686888) (xy 137.05552 -42.638253) (xy 137.089606 -42.59411) (xy 137.129755 -42.555401)
			(xy 137.175113 -42.52295) (xy 137.224713 -42.497449) (xy 137.277497 -42.479442) (xy 137.33234 -42.469312)
			(xy 137.388074 -42.467275) (xy 137.443511 -42.473375) (xy 137.497468 -42.487481) (xy 137.548797 -42.509293)
			(xy 137.596403 -42.538347) (xy 137.639271 -42.574022) (xy 137.676488 -42.615559) (xy 137.707261 -42.662072)
			(xy 137.730933 -42.712569) (xy 137.747001 -42.765976) (xy 137.755121 -42.821152) (xy 137.755482 -42.84091)
			(xy 143.03324 -42.84091) (xy 143.037311 -42.785288) (xy 143.049437 -42.730851) (xy 143.06936 -42.67876)
			(xy 143.096656 -42.630125) (xy 143.130742 -42.585982) (xy 143.170891 -42.547273) (xy 143.216249 -42.514822)
			(xy 143.265849 -42.489321) (xy 143.318633 -42.471314) (xy 143.373476 -42.461184) (xy 143.42921 -42.459147)
			(xy 143.484647 -42.465247) (xy 143.538604 -42.479353) (xy 143.589933 -42.501165) (xy 143.637539 -42.530219)
			(xy 143.680407 -42.565894) (xy 143.717624 -42.607431) (xy 143.748397 -42.653944) (xy 143.772069 -42.704441)
			(xy 143.788137 -42.757848) (xy 143.796257 -42.813024) (xy 143.796766 -42.84091) (xy 143.796257 -42.868796)
			(xy 143.788137 -42.923972) (xy 143.772069 -42.977379) (xy 143.748397 -43.027876) (xy 143.717624 -43.074389)
			(xy 143.680407 -43.115926) (xy 143.637539 -43.151601) (xy 143.589933 -43.180655) (xy 143.538604 -43.202467)
			(xy 143.484647 -43.216573) (xy 143.42921 -43.222673) (xy 143.373476 -43.220636) (xy 143.318633 -43.210506)
			(xy 143.265849 -43.192499) (xy 143.216249 -43.166998) (xy 143.170891 -43.134547) (xy 143.130742 -43.095838)
			(xy 143.096656 -43.051695) (xy 143.06936 -43.00306) (xy 143.049437 -42.950969) (xy 143.037311 -42.896532)
			(xy 143.03324 -42.84091) (xy 137.755482 -42.84091) (xy 137.75563 -42.849038) (xy 137.755121 -42.876924)
			(xy 137.747001 -42.9321) (xy 137.730933 -42.985507) (xy 137.707261 -43.036004) (xy 137.676488 -43.082517)
			(xy 137.639271 -43.124054) (xy 137.596403 -43.159729) (xy 137.548797 -43.188783) (xy 137.497468 -43.210595)
			(xy 137.443511 -43.224701) (xy 137.388074 -43.230801) (xy 137.33234 -43.228764) (xy 137.277497 -43.218634)
			(xy 137.224713 -43.200627) (xy 137.175113 -43.175126) (xy 137.129755 -43.142675) (xy 137.089606 -43.103966)
			(xy 137.05552 -43.059823) (xy 137.028224 -43.011188) (xy 137.008301 -42.959097) (xy 136.996175 -42.90466)
			(xy 136.992104 -42.849038) (xy 135.126108 -42.849038) (xy 135.123817 -42.854026) (xy 135.094084 -42.89999)
			(xy 135.076438 -42.92092) (xy 135.076184 -42.921174) (xy 135.0706 -42.928263) (xy 135.064352 -42.945178)
			(xy 135.063992 -42.954194) (xy 135.063992 -43.02125) (xy 135.064374 -43.030264) (xy 135.070604 -43.047181)
			(xy 135.076184 -43.05427) (xy 135.076438 -43.05427) (xy 135.076438 -43.054524) (xy 135.094061 -43.075469)
			(xy 135.123774 -43.121439) (xy 135.146613 -43.171183) (xy 135.162108 -43.223681) (xy 135.169941 -43.277854)
			(xy 135.170418 -43.305222) (xy 160.40735 -43.305222) (xy 160.407817 -43.277852) (xy 160.415633 -43.223672)
			(xy 160.431121 -43.171169) (xy 160.453963 -43.121422) (xy 160.483688 -43.075455) (xy 160.50133 -43.054524)
			(xy 160.501584 -43.05427) (xy 160.507146 -43.047166) (xy 160.513408 -43.030263) (xy 160.513776 -43.02125)
			(xy 160.513776 -42.954194) (xy 160.513427 -42.945176) (xy 160.507175 -42.928259) (xy 160.501584 -42.921174)
			(xy 160.50133 -42.921174) (xy 160.50133 -42.92092) (xy 160.483691 -42.899987) (xy 160.453979 -42.854015)
			(xy 160.431142 -42.804268) (xy 160.415651 -42.751767) (xy 160.407823 -42.697591) (xy 160.40735 -42.670222)
			(xy 160.4079 -42.641484) (xy 160.416519 -42.584659) (xy 160.433563 -42.529769) (xy 160.458648 -42.478057)
			(xy 160.491207 -42.430692) (xy 160.510474 -42.409364) (xy 160.517078 -42.402506) (xy 160.52419 -42.384472)
			(xy 160.52419 -42.295572) (xy 160.517078 -42.277538) (xy 160.510474 -42.27068) (xy 160.491227 -42.249333)
			(xy 160.458665 -42.201973) (xy 160.433576 -42.150264) (xy 160.416527 -42.095377) (xy 160.407903 -42.038553)
			(xy 160.407901 -41.981079) (xy 160.41652 -41.924255) (xy 160.433564 -41.869366) (xy 160.458649 -41.817655)
			(xy 160.491207 -41.770292) (xy 160.510474 -41.748964) (xy 160.517078 -41.742106) (xy 160.52419 -41.724072)
			(xy 160.52419 -41.635172) (xy 160.517078 -41.617138) (xy 160.510474 -41.61028) (xy 160.49122 -41.588939)
			(xy 160.45865 -41.541581) (xy 160.433554 -41.489873) (xy 160.416499 -41.434985) (xy 160.407873 -41.37816)
			(xy 160.40735 -41.349422) (xy 160.407836 -41.322171) (xy 160.415592 -41.268223) (xy 160.430947 -41.215928)
			(xy 160.453589 -41.166351) (xy 160.483055 -41.120501) (xy 160.518746 -41.07931) (xy 160.559937 -41.043619)
			(xy 160.605787 -41.014153) (xy 160.655364 -40.991511) (xy 160.707659 -40.976156) (xy 160.761607 -40.9684)
			(xy 160.816109 -40.9684) (xy 160.83923 -40.971724) (xy 168.694098 -40.971724) (xy 168.698169 -40.916102)
			(xy 168.710295 -40.861665) (xy 168.730218 -40.809574) (xy 168.757514 -40.760939) (xy 168.7916 -40.716796)
			(xy 168.831749 -40.678087) (xy 168.877107 -40.645636) (xy 168.926707 -40.620135) (xy 168.979491 -40.602128)
			(xy 169.034334 -40.591998) (xy 169.090068 -40.589961) (xy 169.145505 -40.596061) (xy 169.199462 -40.610167)
			(xy 169.250791 -40.631979) (xy 169.298397 -40.661033) (xy 169.341265 -40.696708) (xy 169.378482 -40.738245)
			(xy 169.409255 -40.784758) (xy 169.432927 -40.835255) (xy 169.448995 -40.888662) (xy 169.457115 -40.943838)
			(xy 169.457624 -40.971724) (xy 169.457115 -40.99961) (xy 169.448995 -41.054786) (xy 169.432927 -41.108193)
			(xy 169.409255 -41.15869) (xy 169.378482 -41.205203) (xy 169.341265 -41.24674) (xy 169.314811 -41.268755)
			(xy 183.943927 -41.268755) (xy 183.943927 -41.214245) (xy 183.951685 -41.160289) (xy 183.967042 -41.107987)
			(xy 183.989687 -41.058403) (xy 184.019157 -41.012546) (xy 184.054854 -40.97135) (xy 184.096051 -40.935654)
			(xy 184.141908 -40.906184) (xy 184.191493 -40.88354) (xy 184.243795 -40.868183) (xy 184.297751 -40.860427)
			(xy 184.325006 -40.859964) (xy 184.353745 -40.860494) (xy 184.410571 -40.869116) (xy 184.465462 -40.886166)
			(xy 184.517173 -40.911255) (xy 184.564537 -40.943818) (xy 184.585864 -40.963088) (xy 184.592722 -40.969692)
			(xy 184.610756 -40.976804) (xy 184.699656 -40.976804) (xy 184.71769 -40.969692) (xy 184.724548 -40.963088)
			(xy 184.74588 -40.943823) (xy 184.79324 -40.911254) (xy 184.84495 -40.886159) (xy 184.89984 -40.869108)
			(xy 184.956667 -40.860485) (xy 184.985406 -40.859964) (xy 185.012655 -40.860507) (xy 185.066598 -40.868263)
			(xy 185.118888 -40.883618) (xy 185.168461 -40.906258) (xy 185.214307 -40.935722) (xy 185.255494 -40.971411)
			(xy 185.291182 -41.012598) (xy 185.320645 -41.058444) (xy 185.343284 -41.108017) (xy 185.358638 -41.160308)
			(xy 185.366394 -41.214251) (xy 185.366394 -41.268749) (xy 185.358638 -41.322692) (xy 185.343284 -41.374983)
			(xy 185.320645 -41.424556) (xy 185.291182 -41.470402) (xy 185.255494 -41.511589) (xy 185.214307 -41.547278)
			(xy 185.168461 -41.576742) (xy 185.118888 -41.599382) (xy 185.066598 -41.614737) (xy 185.012655 -41.622493)
			(xy 184.985406 -41.62298) (xy 184.956668 -41.622431) (xy 184.899843 -41.613811) (xy 184.844953 -41.596766)
			(xy 184.793241 -41.571681) (xy 184.745877 -41.539123) (xy 184.724548 -41.519856) (xy 184.71769 -41.513252)
			(xy 184.699656 -41.50614) (xy 184.610756 -41.50614) (xy 184.592722 -41.513252) (xy 184.585864 -41.519856)
			(xy 184.564534 -41.539123) (xy 184.517173 -41.57169) (xy 184.465462 -41.596783) (xy 184.410572 -41.613835)
			(xy 184.353745 -41.622459) (xy 184.325006 -41.62298) (xy 184.297751 -41.622573) (xy 184.243795 -41.614817)
			(xy 184.191493 -41.59946) (xy 184.141908 -41.576816) (xy 184.096051 -41.547346) (xy 184.054854 -41.51165)
			(xy 184.019157 -41.470454) (xy 183.989687 -41.424597) (xy 183.967042 -41.375013) (xy 183.951685 -41.322711)
			(xy 183.943927 -41.268755) (xy 169.314811 -41.268755) (xy 169.298397 -41.282415) (xy 169.250791 -41.311469)
			(xy 169.199462 -41.333281) (xy 169.145505 -41.347387) (xy 169.090068 -41.353487) (xy 169.034334 -41.35145)
			(xy 168.979491 -41.34132) (xy 168.926707 -41.323313) (xy 168.877107 -41.297812) (xy 168.831749 -41.265361)
			(xy 168.7916 -41.226652) (xy 168.757514 -41.182509) (xy 168.730218 -41.133874) (xy 168.710295 -41.081783)
			(xy 168.698169 -41.027346) (xy 168.694098 -40.971724) (xy 160.83923 -40.971724) (xy 160.870057 -40.976156)
			(xy 160.922352 -40.991511) (xy 160.971929 -41.014153) (xy 161.017779 -41.043619) (xy 161.05897 -41.07931)
			(xy 161.094661 -41.120501) (xy 161.124127 -41.166351) (xy 161.146769 -41.215928) (xy 161.162124 -41.268223)
			(xy 161.16988 -41.322171) (xy 161.170366 -41.349422) (xy 161.169838 -41.378161) (xy 161.161214 -41.434987)
			(xy 161.144164 -41.489877) (xy 161.119074 -41.541589) (xy 161.086511 -41.588952) (xy 161.067242 -41.61028)
			(xy 161.060638 -41.617138) (xy 161.053526 -41.635172) (xy 161.053526 -41.724072) (xy 161.060638 -41.742106)
			(xy 161.067242 -41.748964) (xy 161.086536 -41.770271) (xy 161.119103 -41.817636) (xy 161.144196 -41.869351)
			(xy 161.161246 -41.924245) (xy 161.169868 -41.981076) (xy 161.169865 -42.038557) (xy 161.161239 -42.095387)
			(xy 161.144184 -42.150279) (xy 161.119087 -42.201992) (xy 161.086516 -42.249354) (xy 161.067242 -42.27068)
			(xy 161.060638 -42.277538) (xy 161.053526 -42.295572) (xy 161.053526 -42.384472) (xy 161.060638 -42.402506)
			(xy 161.067242 -42.409364) (xy 161.08652 -42.430685) (xy 161.119086 -42.478048) (xy 161.144177 -42.529761)
			(xy 161.161226 -42.584654) (xy 161.169847 -42.641483) (xy 161.170366 -42.670222) (xy 161.169921 -42.697593)
			(xy 161.162099 -42.751773) (xy 161.146606 -42.804277) (xy 161.126049 -42.849038) (xy 162.992052 -42.849038)
			(xy 162.996123 -42.793416) (xy 163.008249 -42.738979) (xy 163.028172 -42.686888) (xy 163.055468 -42.638253)
			(xy 163.089554 -42.59411) (xy 163.129703 -42.555401) (xy 163.175061 -42.52295) (xy 163.224661 -42.497449)
			(xy 163.277445 -42.479442) (xy 163.332288 -42.469312) (xy 163.388022 -42.467275) (xy 163.443459 -42.473375)
			(xy 163.497416 -42.487481) (xy 163.548745 -42.509293) (xy 163.596351 -42.538347) (xy 163.639219 -42.574022)
			(xy 163.676436 -42.615559) (xy 163.707209 -42.662072) (xy 163.730881 -42.712569) (xy 163.746949 -42.765976)
			(xy 163.755069 -42.821152) (xy 163.75543 -42.84091) (xy 169.033188 -42.84091) (xy 169.037259 -42.785288)
			(xy 169.049385 -42.730851) (xy 169.069308 -42.67876) (xy 169.096604 -42.630125) (xy 169.13069 -42.585982)
			(xy 169.170839 -42.547273) (xy 169.216197 -42.514822) (xy 169.265797 -42.489321) (xy 169.318581 -42.471314)
			(xy 169.373424 -42.461184) (xy 169.429158 -42.459147) (xy 169.484595 -42.465247) (xy 169.538552 -42.479353)
			(xy 169.589881 -42.501165) (xy 169.637487 -42.530219) (xy 169.680355 -42.565894) (xy 169.717572 -42.607431)
			(xy 169.748345 -42.653944) (xy 169.772017 -42.704441) (xy 169.788085 -42.757848) (xy 169.796205 -42.813024)
			(xy 169.796714 -42.84091) (xy 169.796205 -42.868796) (xy 169.788085 -42.923972) (xy 169.772017 -42.977379)
			(xy 169.748345 -43.027876) (xy 169.717572 -43.074389) (xy 169.680355 -43.115926) (xy 169.637487 -43.151601)
			(xy 169.589881 -43.180655) (xy 169.538552 -43.202467) (xy 169.484595 -43.216573) (xy 169.429158 -43.222673)
			(xy 169.373424 -43.220636) (xy 169.318581 -43.210506) (xy 169.265797 -43.192499) (xy 169.216197 -43.166998)
			(xy 169.170839 -43.134547) (xy 169.13069 -43.095838) (xy 169.096604 -43.051695) (xy 169.069308 -43.00306)
			(xy 169.049385 -42.950969) (xy 169.037259 -42.896532) (xy 169.033188 -42.84091) (xy 163.75543 -42.84091)
			(xy 163.755578 -42.849038) (xy 163.755069 -42.876924) (xy 163.746949 -42.9321) (xy 163.730881 -42.985507)
			(xy 163.707209 -43.036004) (xy 163.676436 -43.082517) (xy 163.639219 -43.124054) (xy 163.596351 -43.159729)
			(xy 163.548745 -43.188783) (xy 163.497416 -43.210595) (xy 163.443459 -43.224701) (xy 163.388022 -43.230801)
			(xy 163.332288 -43.228764) (xy 163.277445 -43.218634) (xy 163.224661 -43.200627) (xy 163.175061 -43.175126)
			(xy 163.129703 -43.142675) (xy 163.089554 -43.103966) (xy 163.055468 -43.059823) (xy 163.028172 -43.011188)
			(xy 163.008249 -42.959097) (xy 162.996123 -42.90466) (xy 162.992052 -42.849038) (xy 161.126049 -42.849038)
			(xy 161.123759 -42.854024) (xy 161.09403 -42.899989) (xy 161.076386 -42.92092) (xy 161.076132 -42.921174)
			(xy 161.070542 -42.928258) (xy 161.064299 -42.945177) (xy 161.06394 -42.954194) (xy 161.06394 -43.02125)
			(xy 161.064312 -43.030266) (xy 161.070548 -43.047183) (xy 161.076132 -43.05427) (xy 161.076386 -43.05427)
			(xy 161.076386 -43.054524) (xy 161.094001 -43.075476) (xy 161.123717 -43.121443) (xy 161.146558 -43.171185)
			(xy 161.162054 -43.223682) (xy 161.169889 -43.277854) (xy 161.170366 -43.305222) (xy 186.407298 -43.305222)
			(xy 186.407777 -43.277852) (xy 186.415592 -43.223674) (xy 186.431078 -43.171171) (xy 186.453917 -43.121424)
			(xy 186.483638 -43.075456) (xy 186.501278 -43.054524) (xy 186.501532 -43.05427) (xy 186.507099 -43.04717)
			(xy 186.513356 -43.030263) (xy 186.513724 -43.02125) (xy 186.513724 -42.954194) (xy 186.513364 -42.945178)
			(xy 186.507118 -42.928261) (xy 186.501532 -42.921174) (xy 186.501278 -42.921174) (xy 186.501278 -42.92092)
			(xy 186.483631 -42.899994) (xy 186.453921 -42.854019) (xy 186.431087 -42.80427) (xy 186.415598 -42.751768)
			(xy 186.407771 -42.697592) (xy 186.407298 -42.670222) (xy 186.407836 -42.641484) (xy 186.416455 -42.584657)
			(xy 186.433502 -42.529766) (xy 186.45859 -42.478054) (xy 186.491153 -42.430691) (xy 186.510422 -42.409364)
			(xy 186.517026 -42.402506) (xy 186.524138 -42.384472) (xy 186.524138 -42.295572) (xy 186.517026 -42.277538)
			(xy 186.510422 -42.27068) (xy 186.491173 -42.249334) (xy 186.458607 -42.201975) (xy 186.433515 -42.150266)
			(xy 186.416463 -42.095378) (xy 186.407838 -42.038554) (xy 186.407836 -41.981078) (xy 186.416456 -41.924253)
			(xy 186.433503 -41.869364) (xy 186.458591 -41.817653) (xy 186.491153 -41.770291) (xy 186.510422 -41.748964)
			(xy 186.517026 -41.742106) (xy 186.524138 -41.724072) (xy 186.524138 -41.635172) (xy 186.517026 -41.617138)
			(xy 186.510422 -41.61028) (xy 186.491159 -41.588946) (xy 186.458592 -41.541586) (xy 186.433499 -41.489876)
			(xy 186.416446 -41.434987) (xy 186.407821 -41.37816) (xy 186.407298 -41.349422) (xy 186.407784 -41.322171)
			(xy 186.41554 -41.268223) (xy 186.430895 -41.215928) (xy 186.453537 -41.166351) (xy 186.483003 -41.120501)
			(xy 186.518694 -41.07931) (xy 186.559885 -41.043619) (xy 186.605735 -41.014153) (xy 186.655312 -40.991511)
			(xy 186.707607 -40.976156) (xy 186.761555 -40.9684) (xy 186.816057 -40.9684) (xy 186.839178 -40.971724)
			(xy 194.694046 -40.971724) (xy 194.698117 -40.916102) (xy 194.710243 -40.861665) (xy 194.730166 -40.809574)
			(xy 194.757462 -40.760939) (xy 194.791548 -40.716796) (xy 194.831697 -40.678087) (xy 194.877055 -40.645636)
			(xy 194.926655 -40.620135) (xy 194.979439 -40.602128) (xy 195.034282 -40.591998) (xy 195.090016 -40.589961)
			(xy 195.145453 -40.596061) (xy 195.19941 -40.610167) (xy 195.250739 -40.631979) (xy 195.298345 -40.661033)
			(xy 195.341213 -40.696708) (xy 195.37843 -40.738245) (xy 195.409203 -40.784758) (xy 195.432875 -40.835255)
			(xy 195.448943 -40.888662) (xy 195.457063 -40.943838) (xy 195.457572 -40.971724) (xy 195.457063 -40.99961)
			(xy 195.448943 -41.054786) (xy 195.432875 -41.108193) (xy 195.409203 -41.15869) (xy 195.37843 -41.205203)
			(xy 195.341213 -41.24674) (xy 195.314764 -41.268751) (xy 209.94395 -41.268751) (xy 209.94395 -41.214249)
			(xy 209.951706 -41.160301) (xy 209.96706 -41.108006) (xy 209.989699 -41.058428) (xy 210.019163 -41.012577)
			(xy 210.054852 -40.971385) (xy 210.09604 -40.935691) (xy 210.141888 -40.906221) (xy 210.191463 -40.883576)
			(xy 210.243756 -40.868215) (xy 210.297703 -40.860453) (xy 210.324954 -40.859964) (xy 210.353694 -40.860465)
			(xy 210.410522 -40.869094) (xy 210.465412 -40.88615) (xy 210.517124 -40.911247) (xy 210.564485 -40.943816)
			(xy 210.585812 -40.963088) (xy 210.59267 -40.969692) (xy 210.610704 -40.976804) (xy 210.699604 -40.976804)
			(xy 210.717638 -40.969692) (xy 210.724496 -40.963088) (xy 210.745808 -40.9438) (xy 210.793173 -40.911234)
			(xy 210.844889 -40.886144) (xy 210.899783 -40.869098) (xy 210.956614 -40.860481) (xy 210.985354 -40.859964)
			(xy 211.012607 -40.86048) (xy 211.066559 -40.868231) (xy 211.118858 -40.883582) (xy 211.168441 -40.90622)
			(xy 211.214296 -40.935685) (xy 211.255491 -40.971376) (xy 211.291187 -41.012567) (xy 211.320658 -41.058419)
			(xy 211.343302 -41.107998) (xy 211.358659 -41.160296) (xy 211.366417 -41.214247) (xy 211.366417 -41.268753)
			(xy 211.358659 -41.322704) (xy 211.343302 -41.375002) (xy 211.320658 -41.424581) (xy 211.291187 -41.470433)
			(xy 211.255491 -41.511624) (xy 211.214296 -41.547315) (xy 211.168441 -41.57678) (xy 211.118858 -41.599418)
			(xy 211.066559 -41.614769) (xy 211.012607 -41.62252) (xy 210.985354 -41.62298) (xy 210.956615 -41.622463)
			(xy 210.899788 -41.613835) (xy 210.844898 -41.596783) (xy 210.793187 -41.57169) (xy 210.745824 -41.539126)
			(xy 210.724496 -41.519856) (xy 210.717638 -41.513252) (xy 210.699604 -41.50614) (xy 210.610704 -41.50614)
			(xy 210.59267 -41.513252) (xy 210.585812 -41.519856) (xy 210.564503 -41.539148) (xy 210.517136 -41.571711)
			(xy 210.46542 -41.5968) (xy 210.410525 -41.613845) (xy 210.353694 -41.622462) (xy 210.324954 -41.62298)
			(xy 210.297703 -41.622547) (xy 210.243756 -41.614785) (xy 210.191463 -41.599424) (xy 210.141888 -41.576779)
			(xy 210.09604 -41.547309) (xy 210.054852 -41.511615) (xy 210.019163 -41.470423) (xy 209.989699 -41.424572)
			(xy 209.96706 -41.374994) (xy 209.951706 -41.322699) (xy 209.94395 -41.268751) (xy 195.314764 -41.268751)
			(xy 195.298345 -41.282415) (xy 195.250739 -41.311469) (xy 195.19941 -41.333281) (xy 195.145453 -41.347387)
			(xy 195.090016 -41.353487) (xy 195.034282 -41.35145) (xy 194.979439 -41.34132) (xy 194.926655 -41.323313)
			(xy 194.877055 -41.297812) (xy 194.831697 -41.265361) (xy 194.791548 -41.226652) (xy 194.757462 -41.182509)
			(xy 194.730166 -41.133874) (xy 194.710243 -41.081783) (xy 194.698117 -41.027346) (xy 194.694046 -40.971724)
			(xy 186.839178 -40.971724) (xy 186.870005 -40.976156) (xy 186.9223 -40.991511) (xy 186.971877 -41.014153)
			(xy 187.017727 -41.043619) (xy 187.058918 -41.07931) (xy 187.094609 -41.120501) (xy 187.124075 -41.166351)
			(xy 187.146717 -41.215928) (xy 187.162072 -41.268223) (xy 187.169828 -41.322171) (xy 187.170314 -41.349422)
			(xy 187.1698 -41.378161) (xy 187.161174 -41.434989) (xy 187.144122 -41.48988) (xy 187.119028 -41.541591)
			(xy 187.086461 -41.588953) (xy 187.06719 -41.61028) (xy 187.060586 -41.617138) (xy 187.053474 -41.635172)
			(xy 187.053474 -41.724072) (xy 187.060586 -41.742106) (xy 187.06719 -41.748964) (xy 187.086482 -41.770272)
			(xy 187.119045 -41.817638) (xy 187.144135 -41.869353) (xy 187.161183 -41.924247) (xy 187.169803 -41.981076)
			(xy 187.1698 -42.038556) (xy 187.161175 -42.095385) (xy 187.144123 -42.150277) (xy 187.119029 -42.20199)
			(xy 187.086462 -42.249353) (xy 187.06719 -42.27068) (xy 187.060586 -42.277538) (xy 187.053474 -42.295572)
			(xy 187.053474 -42.384472) (xy 187.060586 -42.402506) (xy 187.06719 -42.409364) (xy 187.086476 -42.430678)
			(xy 187.119039 -42.478044) (xy 187.144128 -42.529759) (xy 187.161175 -42.584653) (xy 187.169795 -42.641482)
			(xy 187.170314 -42.670222) (xy 187.169857 -42.697593) (xy 187.162037 -42.751772) (xy 187.146545 -42.804275)
			(xy 187.125991 -42.849038) (xy 188.992 -42.849038) (xy 188.996071 -42.793416) (xy 189.008197 -42.738979)
			(xy 189.02812 -42.686888) (xy 189.055416 -42.638253) (xy 189.089502 -42.59411) (xy 189.129651 -42.555401)
			(xy 189.175009 -42.52295) (xy 189.224609 -42.497449) (xy 189.277393 -42.479442) (xy 189.332236 -42.469312)
			(xy 189.38797 -42.467275) (xy 189.443407 -42.473375) (xy 189.497364 -42.487481) (xy 189.548693 -42.509293)
			(xy 189.596299 -42.538347) (xy 189.639167 -42.574022) (xy 189.676384 -42.615559) (xy 189.707157 -42.662072)
			(xy 189.730829 -42.712569) (xy 189.746897 -42.765976) (xy 189.755017 -42.821152) (xy 189.755378 -42.84091)
			(xy 195.033136 -42.84091) (xy 195.037207 -42.785288) (xy 195.049333 -42.730851) (xy 195.069256 -42.67876)
			(xy 195.096552 -42.630125) (xy 195.130638 -42.585982) (xy 195.170787 -42.547273) (xy 195.216145 -42.514822)
			(xy 195.265745 -42.489321) (xy 195.318529 -42.471314) (xy 195.373372 -42.461184) (xy 195.429106 -42.459147)
			(xy 195.484543 -42.465247) (xy 195.5385 -42.479353) (xy 195.589829 -42.501165) (xy 195.637435 -42.530219)
			(xy 195.680303 -42.565894) (xy 195.71752 -42.607431) (xy 195.748293 -42.653944) (xy 195.771965 -42.704441)
			(xy 195.788033 -42.757848) (xy 195.796153 -42.813024) (xy 195.796662 -42.84091) (xy 195.796153 -42.868796)
			(xy 195.788033 -42.923972) (xy 195.771965 -42.977379) (xy 195.748293 -43.027876) (xy 195.71752 -43.074389)
			(xy 195.680303 -43.115926) (xy 195.637435 -43.151601) (xy 195.589829 -43.180655) (xy 195.5385 -43.202467)
			(xy 195.484543 -43.216573) (xy 195.429106 -43.222673) (xy 195.373372 -43.220636) (xy 195.318529 -43.210506)
			(xy 195.265745 -43.192499) (xy 195.216145 -43.166998) (xy 195.170787 -43.134547) (xy 195.130638 -43.095838)
			(xy 195.096552 -43.051695) (xy 195.069256 -43.00306) (xy 195.049333 -42.950969) (xy 195.037207 -42.896532)
			(xy 195.033136 -42.84091) (xy 189.755378 -42.84091) (xy 189.755526 -42.849038) (xy 189.755017 -42.876924)
			(xy 189.746897 -42.9321) (xy 189.730829 -42.985507) (xy 189.707157 -43.036004) (xy 189.676384 -43.082517)
			(xy 189.639167 -43.124054) (xy 189.596299 -43.159729) (xy 189.548693 -43.188783) (xy 189.497364 -43.210595)
			(xy 189.443407 -43.224701) (xy 189.38797 -43.230801) (xy 189.332236 -43.228764) (xy 189.277393 -43.218634)
			(xy 189.224609 -43.200627) (xy 189.175009 -43.175126) (xy 189.129651 -43.142675) (xy 189.089502 -43.103966)
			(xy 189.055416 -43.059823) (xy 189.02812 -43.011188) (xy 189.008197 -42.959097) (xy 188.996071 -42.90466)
			(xy 188.992 -42.849038) (xy 187.125991 -42.849038) (xy 187.123702 -42.854022) (xy 187.093976 -42.899988)
			(xy 187.076334 -42.92092) (xy 187.07608 -42.921174) (xy 187.070496 -42.928262) (xy 187.064248 -42.945178)
			(xy 187.063888 -42.954194) (xy 187.063888 -43.02125) (xy 187.064271 -43.030264) (xy 187.070501 -43.047181)
			(xy 187.07608 -43.05427) (xy 187.076334 -43.05427) (xy 187.076334 -43.054524) (xy 187.093956 -43.07547)
			(xy 187.123669 -43.121439) (xy 187.146508 -43.171183) (xy 187.162003 -43.223681) (xy 187.169837 -43.277854)
			(xy 187.170314 -43.305222) (xy 212.407246 -43.305222) (xy 212.407714 -43.277852) (xy 212.415529 -43.223672)
			(xy 212.431018 -43.171169) (xy 212.453859 -43.121422) (xy 212.483584 -43.075455) (xy 212.501226 -43.054524)
			(xy 212.50148 -43.05427) (xy 212.507053 -43.047174) (xy 212.513306 -43.030264) (xy 212.513672 -43.02125)
			(xy 212.513672 -42.954194) (xy 212.513324 -42.945176) (xy 212.507071 -42.928259) (xy 212.50148 -42.921174)
			(xy 212.501226 -42.921174) (xy 212.501226 -42.92092) (xy 212.483587 -42.899988) (xy 212.453874 -42.854015)
			(xy 212.431038 -42.804268) (xy 212.415547 -42.751767) (xy 212.407719 -42.697591) (xy 212.407246 -42.670222)
			(xy 212.407798 -42.641484) (xy 212.416416 -42.584659) (xy 212.43346 -42.529769) (xy 212.458545 -42.478057)
			(xy 212.491103 -42.430692) (xy 212.51037 -42.409364) (xy 212.516974 -42.402506) (xy 212.524086 -42.384472)
			(xy 212.524086 -42.295572) (xy 212.516974 -42.277538) (xy 212.51037 -42.27068) (xy 212.491123 -42.249333)
			(xy 212.458562 -42.201973) (xy 212.433473 -42.150264) (xy 212.416424 -42.095377) (xy 212.4078 -42.038553)
			(xy 212.407798 -41.981079) (xy 212.416417 -41.924255) (xy 212.433461 -41.869366) (xy 212.458546 -41.817655)
			(xy 212.491103 -41.770292) (xy 212.51037 -41.748964) (xy 212.516974 -41.742106) (xy 212.524086 -41.724072)
			(xy 212.524086 -41.635172) (xy 212.516974 -41.617138) (xy 212.51037 -41.61028) (xy 212.491115 -41.588939)
			(xy 212.458545 -41.541582) (xy 212.433449 -41.489873) (xy 212.416395 -41.434986) (xy 212.407769 -41.37816)
			(xy 212.407246 -41.349422) (xy 212.407732 -41.322171) (xy 212.415488 -41.268223) (xy 212.430843 -41.215928)
			(xy 212.453485 -41.166351) (xy 212.482951 -41.120501) (xy 212.518642 -41.07931) (xy 212.559833 -41.043619)
			(xy 212.605683 -41.014153) (xy 212.65526 -40.991511) (xy 212.707555 -40.976156) (xy 212.761503 -40.9684)
			(xy 212.816005 -40.9684) (xy 212.839126 -40.971724) (xy 232.794046 -40.971724) (xy 232.798117 -40.916102)
			(xy 232.810243 -40.861665) (xy 232.830166 -40.809574) (xy 232.857462 -40.760939) (xy 232.891548 -40.716796)
			(xy 232.931697 -40.678087) (xy 232.977055 -40.645636) (xy 233.026655 -40.620135) (xy 233.079439 -40.602128)
			(xy 233.134282 -40.591998) (xy 233.190016 -40.589961) (xy 233.245453 -40.596061) (xy 233.29941 -40.610167)
			(xy 233.350739 -40.631979) (xy 233.398345 -40.661033) (xy 233.441213 -40.696708) (xy 233.47843 -40.738245)
			(xy 233.509203 -40.784758) (xy 233.532875 -40.835255) (xy 233.548943 -40.888662) (xy 233.557063 -40.943838)
			(xy 233.557572 -40.971724) (xy 233.557063 -40.99961) (xy 233.548943 -41.054786) (xy 233.532875 -41.108193)
			(xy 233.509203 -41.15869) (xy 233.47843 -41.205203) (xy 233.441213 -41.24674) (xy 233.414764 -41.268751)
			(xy 248.04395 -41.268751) (xy 248.04395 -41.214249) (xy 248.051706 -41.160301) (xy 248.06706 -41.108006)
			(xy 248.089699 -41.058428) (xy 248.119163 -41.012577) (xy 248.154852 -40.971385) (xy 248.19604 -40.935691)
			(xy 248.241888 -40.906221) (xy 248.291463 -40.883576) (xy 248.343756 -40.868215) (xy 248.397703 -40.860453)
			(xy 248.424954 -40.859964) (xy 248.453694 -40.860465) (xy 248.510522 -40.869094) (xy 248.565412 -40.88615)
			(xy 248.617124 -40.911247) (xy 248.664485 -40.943816) (xy 248.685812 -40.963088) (xy 248.69267 -40.969692)
			(xy 248.710704 -40.976804) (xy 248.799604 -40.976804) (xy 248.817638 -40.969692) (xy 248.824496 -40.963088)
			(xy 248.845808 -40.9438) (xy 248.893173 -40.911234) (xy 248.944889 -40.886144) (xy 248.999783 -40.869098)
			(xy 249.056614 -40.860481) (xy 249.085354 -40.859964) (xy 249.112607 -40.86048) (xy 249.166559 -40.868231)
			(xy 249.218858 -40.883582) (xy 249.268441 -40.90622) (xy 249.314296 -40.935685) (xy 249.355491 -40.971376)
			(xy 249.391187 -41.012567) (xy 249.420658 -41.058419) (xy 249.443302 -41.107998) (xy 249.458659 -41.160296)
			(xy 249.466417 -41.214247) (xy 249.466417 -41.268753) (xy 249.458659 -41.322704) (xy 249.443302 -41.375002)
			(xy 249.420658 -41.424581) (xy 249.391187 -41.470433) (xy 249.355491 -41.511624) (xy 249.314296 -41.547315)
			(xy 249.268441 -41.57678) (xy 249.218858 -41.599418) (xy 249.166559 -41.614769) (xy 249.112607 -41.62252)
			(xy 249.085354 -41.62298) (xy 249.056615 -41.622463) (xy 248.999788 -41.613835) (xy 248.944898 -41.596783)
			(xy 248.893187 -41.57169) (xy 248.845824 -41.539126) (xy 248.824496 -41.519856) (xy 248.817638 -41.513252)
			(xy 248.799604 -41.50614) (xy 248.710704 -41.50614) (xy 248.69267 -41.513252) (xy 248.685812 -41.519856)
			(xy 248.664503 -41.539148) (xy 248.617136 -41.571711) (xy 248.56542 -41.5968) (xy 248.510525 -41.613845)
			(xy 248.453694 -41.622462) (xy 248.424954 -41.62298) (xy 248.397703 -41.622547) (xy 248.343756 -41.614785)
			(xy 248.291463 -41.599424) (xy 248.241888 -41.576779) (xy 248.19604 -41.547309) (xy 248.154852 -41.511615)
			(xy 248.119163 -41.470423) (xy 248.089699 -41.424572) (xy 248.06706 -41.374994) (xy 248.051706 -41.322699)
			(xy 248.04395 -41.268751) (xy 233.414764 -41.268751) (xy 233.398345 -41.282415) (xy 233.350739 -41.311469)
			(xy 233.29941 -41.333281) (xy 233.245453 -41.347387) (xy 233.190016 -41.353487) (xy 233.134282 -41.35145)
			(xy 233.079439 -41.34132) (xy 233.026655 -41.323313) (xy 232.977055 -41.297812) (xy 232.931697 -41.265361)
			(xy 232.891548 -41.226652) (xy 232.857462 -41.182509) (xy 232.830166 -41.133874) (xy 232.810243 -41.081783)
			(xy 232.798117 -41.027346) (xy 232.794046 -40.971724) (xy 212.839126 -40.971724) (xy 212.869953 -40.976156)
			(xy 212.922248 -40.991511) (xy 212.971825 -41.014153) (xy 213.017675 -41.043619) (xy 213.058866 -41.07931)
			(xy 213.094557 -41.120501) (xy 213.124023 -41.166351) (xy 213.146665 -41.215928) (xy 213.16202 -41.268223)
			(xy 213.169776 -41.322171) (xy 213.170262 -41.349422) (xy 213.169735 -41.378161) (xy 213.161111 -41.434987)
			(xy 213.14406 -41.489877) (xy 213.11897 -41.541589) (xy 213.086407 -41.588952) (xy 213.067138 -41.61028)
			(xy 213.060534 -41.617138) (xy 213.053422 -41.635172) (xy 213.053422 -41.724072) (xy 213.060534 -41.742106)
			(xy 213.067138 -41.748964) (xy 213.086432 -41.770271) (xy 213.119 -41.817636) (xy 213.144093 -41.869351)
			(xy 213.161143 -41.924245) (xy 213.169765 -41.981075) (xy 213.169762 -42.038557) (xy 213.161136 -42.095387)
			(xy 213.144081 -42.150279) (xy 213.118984 -42.201992) (xy 213.086412 -42.249354) (xy 213.067138 -42.27068)
			(xy 213.060534 -42.277538) (xy 213.053422 -42.295572) (xy 213.053422 -42.384472) (xy 213.060534 -42.402506)
			(xy 213.067138 -42.409364) (xy 213.086415 -42.430686) (xy 213.118981 -42.478049) (xy 213.144073 -42.529762)
			(xy 213.161122 -42.584654) (xy 213.169743 -42.641483) (xy 213.170262 -42.670222) (xy 213.169818 -42.697593)
			(xy 213.161996 -42.751774) (xy 213.146503 -42.804277) (xy 213.125946 -42.849038) (xy 214.991948 -42.849038)
			(xy 214.996019 -42.793416) (xy 215.008145 -42.738979) (xy 215.028068 -42.686888) (xy 215.055364 -42.638253)
			(xy 215.08945 -42.59411) (xy 215.129599 -42.555401) (xy 215.174957 -42.52295) (xy 215.224557 -42.497449)
			(xy 215.277341 -42.479442) (xy 215.332184 -42.469312) (xy 215.387918 -42.467275) (xy 215.443355 -42.473375)
			(xy 215.497312 -42.487481) (xy 215.548641 -42.509293) (xy 215.596247 -42.538347) (xy 215.639115 -42.574022)
			(xy 215.676332 -42.615559) (xy 215.707105 -42.662072) (xy 215.730777 -42.712569) (xy 215.746845 -42.765976)
			(xy 215.754965 -42.821152) (xy 215.755326 -42.84091) (xy 221.033084 -42.84091) (xy 221.037155 -42.785288)
			(xy 221.049281 -42.730851) (xy 221.069204 -42.67876) (xy 221.0965 -42.630125) (xy 221.130586 -42.585982)
			(xy 221.170735 -42.547273) (xy 221.216093 -42.514822) (xy 221.265693 -42.489321) (xy 221.318477 -42.471314)
			(xy 221.37332 -42.461184) (xy 221.429054 -42.459147) (xy 221.484491 -42.465247) (xy 221.538448 -42.479353)
			(xy 221.589777 -42.501165) (xy 221.637383 -42.530219) (xy 221.680251 -42.565894) (xy 221.717468 -42.607431)
			(xy 221.748241 -42.653944) (xy 221.753729 -42.66565) (xy 232.397044 -42.66565) (xy 232.401115 -42.610028)
			(xy 232.413241 -42.555591) (xy 232.433164 -42.5035) (xy 232.46046 -42.454865) (xy 232.494546 -42.410722)
			(xy 232.534695 -42.372013) (xy 232.580053 -42.339562) (xy 232.629653 -42.314061) (xy 232.682437 -42.296054)
			(xy 232.73728 -42.285924) (xy 232.793014 -42.283887) (xy 232.848451 -42.289987) (xy 232.902408 -42.304093)
			(xy 232.953737 -42.325905) (xy 233.001343 -42.354959) (xy 233.044211 -42.390634) (xy 233.081428 -42.432171)
			(xy 233.112201 -42.478684) (xy 233.135873 -42.529181) (xy 233.151941 -42.582588) (xy 233.160061 -42.637764)
			(xy 233.16057 -42.66565) (xy 233.160061 -42.693536) (xy 233.151941 -42.748712) (xy 233.135873 -42.802119)
			(xy 233.112201 -42.852616) (xy 233.081428 -42.899129) (xy 233.044211 -42.940666) (xy 233.001343 -42.976341)
			(xy 232.953737 -43.005395) (xy 232.902408 -43.027207) (xy 232.848451 -43.041313) (xy 232.793014 -43.047413)
			(xy 232.73728 -43.045376) (xy 232.682437 -43.035246) (xy 232.629653 -43.017239) (xy 232.580053 -42.991738)
			(xy 232.534695 -42.959287) (xy 232.494546 -42.920578) (xy 232.46046 -42.876435) (xy 232.433164 -42.8278)
			(xy 232.413241 -42.775709) (xy 232.401115 -42.721272) (xy 232.397044 -42.66565) (xy 221.753729 -42.66565)
			(xy 221.771913 -42.704441) (xy 221.787981 -42.757848) (xy 221.796101 -42.813024) (xy 221.79661 -42.84091)
			(xy 221.796101 -42.868796) (xy 221.787981 -42.923972) (xy 221.771913 -42.977379) (xy 221.748241 -43.027876)
			(xy 221.717468 -43.074389) (xy 221.680251 -43.115926) (xy 221.637383 -43.151601) (xy 221.589777 -43.180655)
			(xy 221.538448 -43.202467) (xy 221.484491 -43.216573) (xy 221.429054 -43.222673) (xy 221.37332 -43.220636)
			(xy 221.318477 -43.210506) (xy 221.265693 -43.192499) (xy 221.216093 -43.166998) (xy 221.170735 -43.134547)
			(xy 221.130586 -43.095838) (xy 221.0965 -43.051695) (xy 221.069204 -43.00306) (xy 221.049281 -42.950969)
			(xy 221.037155 -42.896532) (xy 221.033084 -42.84091) (xy 215.755326 -42.84091) (xy 215.755474 -42.849038)
			(xy 215.754965 -42.876924) (xy 215.746845 -42.9321) (xy 215.730777 -42.985507) (xy 215.707105 -43.036004)
			(xy 215.676332 -43.082517) (xy 215.639115 -43.124054) (xy 215.596247 -43.159729) (xy 215.548641 -43.188783)
			(xy 215.497312 -43.210595) (xy 215.443355 -43.224701) (xy 215.387918 -43.230801) (xy 215.332184 -43.228764)
			(xy 215.277341 -43.218634) (xy 215.224557 -43.200627) (xy 215.174957 -43.175126) (xy 215.129599 -43.142675)
			(xy 215.08945 -43.103966) (xy 215.055364 -43.059823) (xy 215.028068 -43.011188) (xy 215.008145 -42.959097)
			(xy 214.996019 -42.90466) (xy 214.991948 -42.849038) (xy 213.125946 -42.849038) (xy 213.123656 -42.854024)
			(xy 213.093926 -42.899989) (xy 213.076282 -42.92092) (xy 213.076028 -42.921174) (xy 213.070438 -42.928258)
			(xy 213.064195 -42.945177) (xy 213.063836 -42.954194) (xy 213.063836 -43.02125) (xy 213.064209 -43.030265)
			(xy 213.070445 -43.047183) (xy 213.076028 -43.05427) (xy 213.076282 -43.05427) (xy 213.076282 -43.054524)
			(xy 213.093896 -43.075476) (xy 213.123612 -43.121443) (xy 213.146453 -43.171186) (xy 213.16195 -43.223682)
			(xy 213.169785 -43.277854) (xy 213.170262 -43.305222) (xy 250.507246 -43.305222) (xy 250.507714 -43.277852)
			(xy 250.515529 -43.223672) (xy 250.531018 -43.171169) (xy 250.553859 -43.121422) (xy 250.583584 -43.075455)
			(xy 250.601226 -43.054524) (xy 250.60148 -43.05427) (xy 250.607053 -43.047174) (xy 250.613306 -43.030264)
			(xy 250.613672 -43.02125) (xy 250.613672 -42.954194) (xy 250.613324 -42.945176) (xy 250.607071 -42.928259)
			(xy 250.60148 -42.921174) (xy 250.601226 -42.921174) (xy 250.601226 -42.92092) (xy 250.583587 -42.899988)
			(xy 250.553874 -42.854015) (xy 250.531038 -42.804268) (xy 250.515547 -42.751767) (xy 250.507719 -42.697591)
			(xy 250.507246 -42.670222) (xy 250.507798 -42.641484) (xy 250.516416 -42.584659) (xy 250.53346 -42.529769)
			(xy 250.558545 -42.478057) (xy 250.591103 -42.430692) (xy 250.61037 -42.409364) (xy 250.616974 -42.402506)
			(xy 250.624086 -42.384472) (xy 250.624086 -42.295572) (xy 250.616974 -42.277538) (xy 250.61037 -42.27068)
			(xy 250.591123 -42.249333) (xy 250.558562 -42.201973) (xy 250.533473 -42.150264) (xy 250.516424 -42.095377)
			(xy 250.5078 -42.038553) (xy 250.507798 -41.981079) (xy 250.516417 -41.924255) (xy 250.533461 -41.869366)
			(xy 250.558546 -41.817655) (xy 250.591103 -41.770292) (xy 250.61037 -41.748964) (xy 250.616974 -41.742106)
			(xy 250.624086 -41.724072) (xy 250.624086 -41.635172) (xy 250.616974 -41.617138) (xy 250.61037 -41.61028)
			(xy 250.591115 -41.588939) (xy 250.558545 -41.541582) (xy 250.533449 -41.489873) (xy 250.516395 -41.434986)
			(xy 250.507769 -41.37816) (xy 250.507246 -41.349422) (xy 250.507732 -41.322171) (xy 250.515488 -41.268223)
			(xy 250.530843 -41.215928) (xy 250.553485 -41.166351) (xy 250.582951 -41.120501) (xy 250.618642 -41.07931)
			(xy 250.659833 -41.043619) (xy 250.705683 -41.014153) (xy 250.75526 -40.991511) (xy 250.807555 -40.976156)
			(xy 250.861503 -40.9684) (xy 250.916005 -40.9684) (xy 250.939126 -40.971724) (xy 258.793994 -40.971724)
			(xy 258.798065 -40.916102) (xy 258.810191 -40.861665) (xy 258.830114 -40.809574) (xy 258.85741 -40.760939)
			(xy 258.891496 -40.716796) (xy 258.931645 -40.678087) (xy 258.977003 -40.645636) (xy 259.026603 -40.620135)
			(xy 259.079387 -40.602128) (xy 259.13423 -40.591998) (xy 259.189964 -40.589961) (xy 259.245401 -40.596061)
			(xy 259.299358 -40.610167) (xy 259.350687 -40.631979) (xy 259.398293 -40.661033) (xy 259.441161 -40.696708)
			(xy 259.478378 -40.738245) (xy 259.509151 -40.784758) (xy 259.532823 -40.835255) (xy 259.548891 -40.888662)
			(xy 259.557011 -40.943838) (xy 259.55752 -40.971724) (xy 259.557011 -40.99961) (xy 259.548891 -41.054786)
			(xy 259.532823 -41.108193) (xy 259.509151 -41.15869) (xy 259.478378 -41.205203) (xy 259.441161 -41.24674)
			(xy 259.414707 -41.268755) (xy 274.043827 -41.268755) (xy 274.043827 -41.214245) (xy 274.051585 -41.16029)
			(xy 274.066942 -41.107988) (xy 274.089586 -41.058404) (xy 274.119057 -41.012547) (xy 274.154753 -40.971352)
			(xy 274.195949 -40.935655) (xy 274.241806 -40.906185) (xy 274.29139 -40.883541) (xy 274.343692 -40.868184)
			(xy 274.397647 -40.860427) (xy 274.424902 -40.859964) (xy 274.45364 -40.860496) (xy 274.510467 -40.869118)
			(xy 274.565357 -40.886167) (xy 274.617069 -40.911256) (xy 274.664432 -40.943819) (xy 274.68576 -40.963088)
			(xy 274.692618 -40.969692) (xy 274.710652 -40.976804) (xy 274.799552 -40.976804) (xy 274.817586 -40.969692)
			(xy 274.824444 -40.963088) (xy 274.845778 -40.943825) (xy 274.893137 -40.911255) (xy 274.944847 -40.886161)
			(xy 274.999736 -40.869108) (xy 275.056563 -40.860485) (xy 275.085302 -40.859964) (xy 275.112551 -40.860506)
			(xy 275.166495 -40.868263) (xy 275.218785 -40.883617) (xy 275.268358 -40.906256) (xy 275.314205 -40.93572)
			(xy 275.355392 -40.971409) (xy 275.391081 -41.012596) (xy 275.420545 -41.058443) (xy 275.443184 -41.108017)
			(xy 275.458538 -41.160307) (xy 275.466294 -41.214251) (xy 275.466294 -41.268749) (xy 275.458538 -41.322693)
			(xy 275.443184 -41.374983) (xy 275.420545 -41.424557) (xy 275.391081 -41.470404) (xy 275.355392 -41.511591)
			(xy 275.314205 -41.54728) (xy 275.268358 -41.576744) (xy 275.218785 -41.599383) (xy 275.166495 -41.614737)
			(xy 275.112551 -41.622494) (xy 275.085302 -41.62298) (xy 275.056564 -41.622434) (xy 274.999739 -41.613813)
			(xy 274.944849 -41.596767) (xy 274.893137 -41.571681) (xy 274.845773 -41.539123) (xy 274.824444 -41.519856)
			(xy 274.817586 -41.513252) (xy 274.799552 -41.50614) (xy 274.710652 -41.50614) (xy 274.692618 -41.513252)
			(xy 274.68576 -41.519856) (xy 274.664431 -41.539125) (xy 274.61707 -41.571692) (xy 274.565359 -41.596785)
			(xy 274.510468 -41.613836) (xy 274.453641 -41.622459) (xy 274.424902 -41.62298) (xy 274.397647 -41.622573)
			(xy 274.343692 -41.614816) (xy 274.29139 -41.599459) (xy 274.241806 -41.576815) (xy 274.195949 -41.547345)
			(xy 274.154753 -41.511648) (xy 274.119057 -41.470453) (xy 274.089586 -41.424596) (xy 274.066942 -41.375012)
			(xy 274.051585 -41.32271) (xy 274.043827 -41.268755) (xy 259.414707 -41.268755) (xy 259.398293 -41.282415)
			(xy 259.350687 -41.311469) (xy 259.299358 -41.333281) (xy 259.245401 -41.347387) (xy 259.189964 -41.353487)
			(xy 259.13423 -41.35145) (xy 259.079387 -41.34132) (xy 259.026603 -41.323313) (xy 258.977003 -41.297812)
			(xy 258.931645 -41.265361) (xy 258.891496 -41.226652) (xy 258.85741 -41.182509) (xy 258.830114 -41.133874)
			(xy 258.810191 -41.081783) (xy 258.798065 -41.027346) (xy 258.793994 -40.971724) (xy 250.939126 -40.971724)
			(xy 250.969953 -40.976156) (xy 251.022248 -40.991511) (xy 251.071825 -41.014153) (xy 251.117675 -41.043619)
			(xy 251.158866 -41.07931) (xy 251.194557 -41.120501) (xy 251.224023 -41.166351) (xy 251.246665 -41.215928)
			(xy 251.26202 -41.268223) (xy 251.269776 -41.322171) (xy 251.270262 -41.349422) (xy 251.269735 -41.378161)
			(xy 251.261111 -41.434987) (xy 251.24406 -41.489877) (xy 251.21897 -41.541589) (xy 251.186407 -41.588952)
			(xy 251.167138 -41.61028) (xy 251.160534 -41.617138) (xy 251.153422 -41.635172) (xy 251.153422 -41.724072)
			(xy 251.160534 -41.742106) (xy 251.167138 -41.748964) (xy 251.186432 -41.770271) (xy 251.219 -41.817636)
			(xy 251.244093 -41.869351) (xy 251.261143 -41.924245) (xy 251.269765 -41.981075) (xy 251.269762 -42.038557)
			(xy 251.261136 -42.095387) (xy 251.244081 -42.150279) (xy 251.218984 -42.201992) (xy 251.186412 -42.249354)
			(xy 251.167138 -42.27068) (xy 251.160534 -42.277538) (xy 251.153422 -42.295572) (xy 251.153422 -42.384472)
			(xy 251.160534 -42.402506) (xy 251.167138 -42.409364) (xy 251.186415 -42.430686) (xy 251.218981 -42.478049)
			(xy 251.244073 -42.529762) (xy 251.261122 -42.584654) (xy 251.269743 -42.641483) (xy 251.270262 -42.670222)
			(xy 251.269818 -42.697593) (xy 251.261996 -42.751774) (xy 251.246503 -42.804277) (xy 251.225946 -42.849038)
			(xy 253.091948 -42.849038) (xy 253.096019 -42.793416) (xy 253.108145 -42.738979) (xy 253.128068 -42.686888)
			(xy 253.155364 -42.638253) (xy 253.18945 -42.59411) (xy 253.229599 -42.555401) (xy 253.274957 -42.52295)
			(xy 253.324557 -42.497449) (xy 253.377341 -42.479442) (xy 253.432184 -42.469312) (xy 253.487918 -42.467275)
			(xy 253.543355 -42.473375) (xy 253.597312 -42.487481) (xy 253.648641 -42.509293) (xy 253.696247 -42.538347)
			(xy 253.739115 -42.574022) (xy 253.776332 -42.615559) (xy 253.807105 -42.662072) (xy 253.830777 -42.712569)
			(xy 253.846845 -42.765976) (xy 253.854965 -42.821152) (xy 253.855326 -42.84091) (xy 259.133084 -42.84091)
			(xy 259.137155 -42.785288) (xy 259.149281 -42.730851) (xy 259.169204 -42.67876) (xy 259.1965 -42.630125)
			(xy 259.230586 -42.585982) (xy 259.270735 -42.547273) (xy 259.316093 -42.514822) (xy 259.365693 -42.489321)
			(xy 259.418477 -42.471314) (xy 259.47332 -42.461184) (xy 259.529054 -42.459147) (xy 259.584491 -42.465247)
			(xy 259.638448 -42.479353) (xy 259.689777 -42.501165) (xy 259.737383 -42.530219) (xy 259.780251 -42.565894)
			(xy 259.817468 -42.607431) (xy 259.848241 -42.653944) (xy 259.871913 -42.704441) (xy 259.887981 -42.757848)
			(xy 259.896101 -42.813024) (xy 259.89661 -42.84091) (xy 259.896101 -42.868796) (xy 259.887981 -42.923972)
			(xy 259.871913 -42.977379) (xy 259.848241 -43.027876) (xy 259.817468 -43.074389) (xy 259.780251 -43.115926)
			(xy 259.737383 -43.151601) (xy 259.689777 -43.180655) (xy 259.638448 -43.202467) (xy 259.584491 -43.216573)
			(xy 259.529054 -43.222673) (xy 259.47332 -43.220636) (xy 259.418477 -43.210506) (xy 259.365693 -43.192499)
			(xy 259.316093 -43.166998) (xy 259.270735 -43.134547) (xy 259.230586 -43.095838) (xy 259.1965 -43.051695)
			(xy 259.169204 -43.00306) (xy 259.149281 -42.950969) (xy 259.137155 -42.896532) (xy 259.133084 -42.84091)
			(xy 253.855326 -42.84091) (xy 253.855474 -42.849038) (xy 253.854965 -42.876924) (xy 253.846845 -42.9321)
			(xy 253.830777 -42.985507) (xy 253.807105 -43.036004) (xy 253.776332 -43.082517) (xy 253.739115 -43.124054)
			(xy 253.696247 -43.159729) (xy 253.648641 -43.188783) (xy 253.597312 -43.210595) (xy 253.543355 -43.224701)
			(xy 253.487918 -43.230801) (xy 253.432184 -43.228764) (xy 253.377341 -43.218634) (xy 253.324557 -43.200627)
			(xy 253.274957 -43.175126) (xy 253.229599 -43.142675) (xy 253.18945 -43.103966) (xy 253.155364 -43.059823)
			(xy 253.128068 -43.011188) (xy 253.108145 -42.959097) (xy 253.096019 -42.90466) (xy 253.091948 -42.849038)
			(xy 251.225946 -42.849038) (xy 251.223656 -42.854024) (xy 251.193926 -42.899989) (xy 251.176282 -42.92092)
			(xy 251.176028 -42.921174) (xy 251.170438 -42.928258) (xy 251.164195 -42.945177) (xy 251.163836 -42.954194)
			(xy 251.163836 -43.02125) (xy 251.164209 -43.030265) (xy 251.170445 -43.047183) (xy 251.176028 -43.05427)
			(xy 251.176282 -43.05427) (xy 251.176282 -43.054524) (xy 251.193896 -43.075476) (xy 251.223612 -43.121443)
			(xy 251.246453 -43.171186) (xy 251.26195 -43.223682) (xy 251.269785 -43.277854) (xy 251.270262 -43.305222)
			(xy 276.507194 -43.305222) (xy 276.507674 -43.277852) (xy 276.515489 -43.223674) (xy 276.530975 -43.171171)
			(xy 276.553813 -43.121424) (xy 276.583534 -43.075456) (xy 276.601174 -43.054524) (xy 276.601428 -43.05427)
			(xy 276.606995 -43.04717) (xy 276.613252 -43.030263) (xy 276.61362 -43.02125) (xy 276.61362 -42.954194)
			(xy 276.613261 -42.945177) (xy 276.607014 -42.928261) (xy 276.601428 -42.921174) (xy 276.601174 -42.921174)
			(xy 276.601174 -42.92092) (xy 276.583527 -42.899995) (xy 276.553817 -42.85402) (xy 276.530983 -42.80427)
			(xy 276.515494 -42.751768) (xy 276.507667 -42.697592) (xy 276.507194 -42.670222) (xy 276.507733 -42.641484)
			(xy 276.516352 -42.584657) (xy 276.533399 -42.529767) (xy 276.558487 -42.478055) (xy 276.591049 -42.430691)
			(xy 276.610318 -42.409364) (xy 276.616922 -42.402506) (xy 276.624034 -42.384472) (xy 276.624034 -42.295572)
			(xy 276.616922 -42.277538) (xy 276.610318 -42.27068) (xy 276.591069 -42.249334) (xy 276.558504 -42.201975)
			(xy 276.533411 -42.150266) (xy 276.51636 -42.095378) (xy 276.507736 -42.038554) (xy 276.507733 -41.981078)
			(xy 276.516353 -41.924253) (xy 276.5334 -41.869364) (xy 276.558488 -41.817653) (xy 276.591049 -41.770291)
			(xy 276.610318 -41.748964) (xy 276.616922 -41.742106) (xy 276.624034 -41.724072) (xy 276.624034 -41.635172)
			(xy 276.616922 -41.617138) (xy 276.610318 -41.61028) (xy 276.591054 -41.588947) (xy 276.558488 -41.541586)
			(xy 276.533394 -41.489876) (xy 276.516342 -41.434987) (xy 276.507717 -41.378161) (xy 276.507194 -41.349422)
			(xy 276.50768 -41.322171) (xy 276.515436 -41.268223) (xy 276.530791 -41.215928) (xy 276.553433 -41.166351)
			(xy 276.582899 -41.120501) (xy 276.61859 -41.07931) (xy 276.659781 -41.043619) (xy 276.705631 -41.014153)
			(xy 276.755208 -40.991511) (xy 276.807503 -40.976156) (xy 276.861451 -40.9684) (xy 276.915953 -40.9684)
			(xy 276.939074 -40.971724) (xy 284.793942 -40.971724) (xy 284.798013 -40.916102) (xy 284.810139 -40.861665)
			(xy 284.830062 -40.809574) (xy 284.857358 -40.760939) (xy 284.891444 -40.716796) (xy 284.931593 -40.678087)
			(xy 284.976951 -40.645636) (xy 285.026551 -40.620135) (xy 285.079335 -40.602128) (xy 285.134178 -40.591998)
			(xy 285.189912 -40.589961) (xy 285.245349 -40.596061) (xy 285.299306 -40.610167) (xy 285.350635 -40.631979)
			(xy 285.398241 -40.661033) (xy 285.441109 -40.696708) (xy 285.478326 -40.738245) (xy 285.509099 -40.784758)
			(xy 285.532771 -40.835255) (xy 285.548839 -40.888662) (xy 285.556959 -40.943838) (xy 285.557468 -40.971724)
			(xy 285.556959 -40.99961) (xy 285.548839 -41.054786) (xy 285.532771 -41.108193) (xy 285.509099 -41.15869)
			(xy 285.478326 -41.205203) (xy 285.441109 -41.24674) (xy 285.41466 -41.268751) (xy 300.04385 -41.268751)
			(xy 300.04385 -41.214249) (xy 300.051605 -41.160302) (xy 300.066959 -41.108007) (xy 300.089598 -41.05843)
			(xy 300.119062 -41.012578) (xy 300.154751 -40.971386) (xy 300.195938 -40.935692) (xy 300.241786 -40.906222)
			(xy 300.29136 -40.883577) (xy 300.343653 -40.868216) (xy 300.397599 -40.860453) (xy 300.42485 -40.859964)
			(xy 300.45359 -40.860467) (xy 300.510417 -40.869096) (xy 300.565308 -40.886152) (xy 300.617019 -40.911247)
			(xy 300.664381 -40.943816) (xy 300.685708 -40.963088) (xy 300.692566 -40.969692) (xy 300.7106 -40.976804)
			(xy 300.7995 -40.976804) (xy 300.817534 -40.969692) (xy 300.824392 -40.963088) (xy 300.845706 -40.943802)
			(xy 300.893071 -40.911236) (xy 300.944785 -40.886145) (xy 300.999679 -40.869099) (xy 301.05651 -40.860481)
			(xy 301.08525 -40.859964) (xy 301.112503 -40.86048) (xy 301.166456 -40.86823) (xy 301.218756 -40.883581)
			(xy 301.268338 -40.906219) (xy 301.314194 -40.935684) (xy 301.35539 -40.971375) (xy 301.391086 -41.012566)
			(xy 301.420557 -41.058418) (xy 301.443201 -41.107998) (xy 301.458559 -41.160296) (xy 301.466317 -41.214247)
			(xy 301.466317 -41.268753) (xy 301.458559 -41.322704) (xy 301.443201 -41.375002) (xy 301.420557 -41.424582)
			(xy 301.391086 -41.470434) (xy 301.35539 -41.511625) (xy 301.314194 -41.547316) (xy 301.268338 -41.576781)
			(xy 301.218756 -41.599419) (xy 301.166456 -41.61477) (xy 301.112503 -41.62252) (xy 301.08525 -41.62298)
			(xy 301.056511 -41.622465) (xy 300.999684 -41.613837) (xy 300.944794 -41.596784) (xy 300.893083 -41.571691)
			(xy 300.84572 -41.539126) (xy 300.824392 -41.519856) (xy 300.817534 -41.513252) (xy 300.7995 -41.50614)
			(xy 300.7106 -41.50614) (xy 300.692566 -41.513252) (xy 300.685708 -41.519856) (xy 300.664401 -41.539149)
			(xy 300.617033 -41.571713) (xy 300.565317 -41.596801) (xy 300.510422 -41.613846) (xy 300.45359 -41.622463)
			(xy 300.42485 -41.62298) (xy 300.397599 -41.622547) (xy 300.343653 -41.614784) (xy 300.29136 -41.599423)
			(xy 300.241786 -41.576778) (xy 300.195938 -41.547308) (xy 300.154751 -41.511614) (xy 300.119062 -41.470422)
			(xy 300.089598 -41.42457) (xy 300.066959 -41.374993) (xy 300.051605 -41.322698) (xy 300.04385 -41.268751)
			(xy 285.41466 -41.268751) (xy 285.398241 -41.282415) (xy 285.350635 -41.311469) (xy 285.299306 -41.333281)
			(xy 285.245349 -41.347387) (xy 285.189912 -41.353487) (xy 285.134178 -41.35145) (xy 285.079335 -41.34132)
			(xy 285.026551 -41.323313) (xy 284.976951 -41.297812) (xy 284.931593 -41.265361) (xy 284.891444 -41.226652)
			(xy 284.857358 -41.182509) (xy 284.830062 -41.133874) (xy 284.810139 -41.081783) (xy 284.798013 -41.027346)
			(xy 284.793942 -40.971724) (xy 276.939074 -40.971724) (xy 276.969901 -40.976156) (xy 277.022196 -40.991511)
			(xy 277.071773 -41.014153) (xy 277.117623 -41.043619) (xy 277.158814 -41.07931) (xy 277.194505 -41.120501)
			(xy 277.223971 -41.166351) (xy 277.246613 -41.215928) (xy 277.261968 -41.268223) (xy 277.269724 -41.322171)
			(xy 277.27021 -41.349422) (xy 277.269697 -41.378161) (xy 277.261071 -41.434989) (xy 277.244019 -41.48988)
			(xy 277.218925 -41.541591) (xy 277.186358 -41.588953) (xy 277.167086 -41.61028) (xy 277.160482 -41.617138)
			(xy 277.15337 -41.635172) (xy 277.15337 -41.724072) (xy 277.160482 -41.742106) (xy 277.167086 -41.748964)
			(xy 277.186378 -41.770272) (xy 277.218942 -41.817638) (xy 277.244032 -41.869353) (xy 277.261079 -41.924246)
			(xy 277.2697 -41.981076) (xy 277.269697 -42.038556) (xy 277.261072 -42.095385) (xy 277.24402 -42.150277)
			(xy 277.218926 -42.20199) (xy 277.186358 -42.249353) (xy 277.167086 -42.27068) (xy 277.160482 -42.277538)
			(xy 277.15337 -42.295572) (xy 277.15337 -42.384472) (xy 277.160482 -42.402506) (xy 277.167086 -42.409364)
			(xy 277.186371 -42.430679) (xy 277.218935 -42.478044) (xy 277.244024 -42.529759) (xy 277.261071 -42.584653)
			(xy 277.269691 -42.641482) (xy 277.27021 -42.670222) (xy 277.269754 -42.697593) (xy 277.261934 -42.751772)
			(xy 277.246442 -42.804275) (xy 277.225887 -42.849038) (xy 279.091896 -42.849038) (xy 279.095967 -42.793416)
			(xy 279.108093 -42.738979) (xy 279.128016 -42.686888) (xy 279.155312 -42.638253) (xy 279.189398 -42.59411)
			(xy 279.229547 -42.555401) (xy 279.274905 -42.52295) (xy 279.324505 -42.497449) (xy 279.377289 -42.479442)
			(xy 279.432132 -42.469312) (xy 279.487866 -42.467275) (xy 279.543303 -42.473375) (xy 279.59726 -42.487481)
			(xy 279.648589 -42.509293) (xy 279.696195 -42.538347) (xy 279.739063 -42.574022) (xy 279.77628 -42.615559)
			(xy 279.807053 -42.662072) (xy 279.830725 -42.712569) (xy 279.846793 -42.765976) (xy 279.854913 -42.821152)
			(xy 279.855274 -42.84091) (xy 285.133032 -42.84091) (xy 285.137103 -42.785288) (xy 285.149229 -42.730851)
			(xy 285.169152 -42.67876) (xy 285.196448 -42.630125) (xy 285.230534 -42.585982) (xy 285.270683 -42.547273)
			(xy 285.316041 -42.514822) (xy 285.365641 -42.489321) (xy 285.418425 -42.471314) (xy 285.473268 -42.461184)
			(xy 285.529002 -42.459147) (xy 285.584439 -42.465247) (xy 285.638396 -42.479353) (xy 285.689725 -42.501165)
			(xy 285.737331 -42.530219) (xy 285.780199 -42.565894) (xy 285.817416 -42.607431) (xy 285.848189 -42.653944)
			(xy 285.871861 -42.704441) (xy 285.887929 -42.757848) (xy 285.896049 -42.813024) (xy 285.896558 -42.84091)
			(xy 285.896049 -42.868796) (xy 285.887929 -42.923972) (xy 285.871861 -42.977379) (xy 285.848189 -43.027876)
			(xy 285.817416 -43.074389) (xy 285.780199 -43.115926) (xy 285.737331 -43.151601) (xy 285.689725 -43.180655)
			(xy 285.638396 -43.202467) (xy 285.584439 -43.216573) (xy 285.529002 -43.222673) (xy 285.473268 -43.220636)
			(xy 285.418425 -43.210506) (xy 285.365641 -43.192499) (xy 285.316041 -43.166998) (xy 285.270683 -43.134547)
			(xy 285.230534 -43.095838) (xy 285.196448 -43.051695) (xy 285.169152 -43.00306) (xy 285.149229 -42.950969)
			(xy 285.137103 -42.896532) (xy 285.133032 -42.84091) (xy 279.855274 -42.84091) (xy 279.855422 -42.849038)
			(xy 279.854913 -42.876924) (xy 279.846793 -42.9321) (xy 279.830725 -42.985507) (xy 279.807053 -43.036004)
			(xy 279.77628 -43.082517) (xy 279.739063 -43.124054) (xy 279.696195 -43.159729) (xy 279.648589 -43.188783)
			(xy 279.59726 -43.210595) (xy 279.543303 -43.224701) (xy 279.487866 -43.230801) (xy 279.432132 -43.228764)
			(xy 279.377289 -43.218634) (xy 279.324505 -43.200627) (xy 279.274905 -43.175126) (xy 279.229547 -43.142675)
			(xy 279.189398 -43.103966) (xy 279.155312 -43.059823) (xy 279.128016 -43.011188) (xy 279.108093 -42.959097)
			(xy 279.095967 -42.90466) (xy 279.091896 -42.849038) (xy 277.225887 -42.849038) (xy 277.223598 -42.854022)
			(xy 277.193872 -42.899988) (xy 277.17623 -42.92092) (xy 277.175976 -42.921174) (xy 277.170392 -42.928262)
			(xy 277.164144 -42.945178) (xy 277.163784 -42.954194) (xy 277.163784 -43.02125) (xy 277.164168 -43.030264)
			(xy 277.170397 -43.047181) (xy 277.175976 -43.05427) (xy 277.17623 -43.05427) (xy 277.17623 -43.054524)
			(xy 277.193852 -43.07547) (xy 277.223565 -43.121439) (xy 277.246404 -43.171184) (xy 277.261899 -43.223681)
			(xy 277.269733 -43.277854) (xy 277.27021 -43.305222) (xy 277.269724 -43.332473) (xy 277.261968 -43.386421)
			(xy 277.246613 -43.438716) (xy 277.223971 -43.488293) (xy 277.194505 -43.534143) (xy 277.158814 -43.575334)
			(xy 277.117623 -43.611025) (xy 277.071773 -43.640491) (xy 277.022196 -43.663133) (xy 276.969901 -43.678488)
			(xy 276.915953 -43.686244) (xy 276.861451 -43.686244) (xy 276.807503 -43.678488) (xy 276.755208 -43.663133)
			(xy 276.705631 -43.640491) (xy 276.659781 -43.611025) (xy 276.61859 -43.575334) (xy 276.582899 -43.534143)
			(xy 276.553433 -43.488293) (xy 276.530791 -43.438716) (xy 276.515436 -43.386421) (xy 276.50768 -43.332473)
			(xy 276.507194 -43.305222) (xy 251.270262 -43.305222) (xy 251.269776 -43.332473) (xy 251.26202 -43.386421)
			(xy 251.246665 -43.438716) (xy 251.224023 -43.488293) (xy 251.194557 -43.534143) (xy 251.158866 -43.575334)
			(xy 251.117675 -43.611025) (xy 251.071825 -43.640491) (xy 251.022248 -43.663133) (xy 250.969953 -43.678488)
			(xy 250.916005 -43.686244) (xy 250.861503 -43.686244) (xy 250.807555 -43.678488) (xy 250.75526 -43.663133)
			(xy 250.705683 -43.640491) (xy 250.659833 -43.611025) (xy 250.618642 -43.575334) (xy 250.582951 -43.534143)
			(xy 250.553485 -43.488293) (xy 250.530843 -43.438716) (xy 250.515488 -43.386421) (xy 250.507732 -43.332473)
			(xy 250.507246 -43.305222) (xy 213.170262 -43.305222) (xy 213.169776 -43.332473) (xy 213.16202 -43.386421)
			(xy 213.146665 -43.438716) (xy 213.124023 -43.488293) (xy 213.094557 -43.534143) (xy 213.058866 -43.575334)
			(xy 213.017675 -43.611025) (xy 212.971825 -43.640491) (xy 212.922248 -43.663133) (xy 212.869953 -43.678488)
			(xy 212.816005 -43.686244) (xy 212.761503 -43.686244) (xy 212.707555 -43.678488) (xy 212.65526 -43.663133)
			(xy 212.605683 -43.640491) (xy 212.559833 -43.611025) (xy 212.518642 -43.575334) (xy 212.482951 -43.534143)
			(xy 212.453485 -43.488293) (xy 212.430843 -43.438716) (xy 212.415488 -43.386421) (xy 212.407732 -43.332473)
			(xy 212.407246 -43.305222) (xy 187.170314 -43.305222) (xy 187.169828 -43.332473) (xy 187.162072 -43.386421)
			(xy 187.146717 -43.438716) (xy 187.124075 -43.488293) (xy 187.094609 -43.534143) (xy 187.058918 -43.575334)
			(xy 187.017727 -43.611025) (xy 186.971877 -43.640491) (xy 186.9223 -43.663133) (xy 186.870005 -43.678488)
			(xy 186.816057 -43.686244) (xy 186.761555 -43.686244) (xy 186.707607 -43.678488) (xy 186.655312 -43.663133)
			(xy 186.605735 -43.640491) (xy 186.559885 -43.611025) (xy 186.518694 -43.575334) (xy 186.483003 -43.534143)
			(xy 186.453537 -43.488293) (xy 186.430895 -43.438716) (xy 186.41554 -43.386421) (xy 186.407784 -43.332473)
			(xy 186.407298 -43.305222) (xy 161.170366 -43.305222) (xy 161.16988 -43.332473) (xy 161.162124 -43.386421)
			(xy 161.146769 -43.438716) (xy 161.124127 -43.488293) (xy 161.094661 -43.534143) (xy 161.05897 -43.575334)
			(xy 161.017779 -43.611025) (xy 160.971929 -43.640491) (xy 160.922352 -43.663133) (xy 160.870057 -43.678488)
			(xy 160.816109 -43.686244) (xy 160.761607 -43.686244) (xy 160.707659 -43.678488) (xy 160.655364 -43.663133)
			(xy 160.605787 -43.640491) (xy 160.559937 -43.611025) (xy 160.518746 -43.575334) (xy 160.483055 -43.534143)
			(xy 160.453589 -43.488293) (xy 160.430947 -43.438716) (xy 160.415592 -43.386421) (xy 160.407836 -43.332473)
			(xy 160.40735 -43.305222) (xy 135.170418 -43.305222) (xy 135.169932 -43.332473) (xy 135.162176 -43.386421)
			(xy 135.146821 -43.438716) (xy 135.124179 -43.488293) (xy 135.094713 -43.534143) (xy 135.059022 -43.575334)
			(xy 135.017831 -43.611025) (xy 134.971981 -43.640491) (xy 134.922404 -43.663133) (xy 134.870109 -43.678488)
			(xy 134.816161 -43.686244) (xy 134.761659 -43.686244) (xy 134.707711 -43.678488) (xy 134.655416 -43.663133)
			(xy 134.605839 -43.640491) (xy 134.559989 -43.611025) (xy 134.518798 -43.575334) (xy 134.483107 -43.534143)
			(xy 134.453641 -43.488293) (xy 134.430999 -43.438716) (xy 134.415644 -43.386421) (xy 134.407888 -43.332473)
			(xy 134.407402 -43.305222) (xy 97.070164 -43.305222) (xy 97.069678 -43.332473) (xy 97.061922 -43.386421)
			(xy 97.046567 -43.438716) (xy 97.023925 -43.488293) (xy 96.994459 -43.534143) (xy 96.958768 -43.575334)
			(xy 96.917577 -43.611025) (xy 96.871727 -43.640491) (xy 96.82215 -43.663133) (xy 96.769855 -43.678488)
			(xy 96.715907 -43.686244) (xy 96.661405 -43.686244) (xy 96.607457 -43.678488) (xy 96.555162 -43.663133)
			(xy 96.505585 -43.640491) (xy 96.459735 -43.611025) (xy 96.418544 -43.575334) (xy 96.382853 -43.534143)
			(xy 96.353387 -43.488293) (xy 96.330745 -43.438716) (xy 96.31539 -43.386421) (xy 96.307634 -43.332473)
			(xy 96.307148 -43.305222) (xy 71.070216 -43.305222) (xy 71.06973 -43.332473) (xy 71.061974 -43.386421)
			(xy 71.046619 -43.438716) (xy 71.023977 -43.488293) (xy 70.994511 -43.534143) (xy 70.95882 -43.575334)
			(xy 70.917629 -43.611025) (xy 70.871779 -43.640491) (xy 70.822202 -43.663133) (xy 70.769907 -43.678488)
			(xy 70.715959 -43.686244) (xy 70.661457 -43.686244) (xy 70.607509 -43.678488) (xy 70.555214 -43.663133)
			(xy 70.505637 -43.640491) (xy 70.459787 -43.611025) (xy 70.418596 -43.575334) (xy 70.382905 -43.534143)
			(xy 70.353439 -43.488293) (xy 70.330797 -43.438716) (xy 70.315442 -43.386421) (xy 70.307686 -43.332473)
			(xy 70.3072 -43.305222) (xy 45.070268 -43.305222) (xy 45.069782 -43.332473) (xy 45.062026 -43.386421)
			(xy 45.046671 -43.438716) (xy 45.024029 -43.488293) (xy 44.994563 -43.534143) (xy 44.958872 -43.575334)
			(xy 44.917681 -43.611025) (xy 44.871831 -43.640491) (xy 44.822254 -43.663133) (xy 44.769959 -43.678488)
			(xy 44.716011 -43.686244) (xy 44.661509 -43.686244) (xy 44.607561 -43.678488) (xy 44.555266 -43.663133)
			(xy 44.505689 -43.640491) (xy 44.459839 -43.611025) (xy 44.418648 -43.575334) (xy 44.382957 -43.534143)
			(xy 44.353491 -43.488293) (xy 44.330849 -43.438716) (xy 44.315494 -43.386421) (xy 44.307738 -43.332473)
			(xy 44.307252 -43.305222) (xy 19.07032 -43.305222) (xy 19.069834 -43.332473) (xy 19.062078 -43.386421)
			(xy 19.046723 -43.438716) (xy 19.024081 -43.488293) (xy 18.994615 -43.534143) (xy 18.958924 -43.575334)
			(xy 18.917733 -43.611025) (xy 18.871883 -43.640491) (xy 18.822306 -43.663133) (xy 18.770011 -43.678488)
			(xy 18.716063 -43.686244) (xy 18.661561 -43.686244) (xy 18.607613 -43.678488) (xy 18.555318 -43.663133)
			(xy 18.505741 -43.640491) (xy 18.459891 -43.611025) (xy 18.4187 -43.575334) (xy 18.383009 -43.534143)
			(xy 18.353543 -43.488293) (xy 18.330901 -43.438716) (xy 18.315546 -43.386421) (xy 18.30779 -43.332473)
			(xy 18.307304 -43.305222) (xy 1.987296 -43.305222) (xy 1.987296 -43.73626) (xy 20.213064 -43.73626)
			(xy 20.217135 -43.680638) (xy 20.229261 -43.626201) (xy 20.249184 -43.57411) (xy 20.27648 -43.525475)
			(xy 20.310566 -43.481332) (xy 20.350715 -43.442623) (xy 20.396073 -43.410172) (xy 20.445673 -43.384671)
			(xy 20.498457 -43.366664) (xy 20.5533 -43.356534) (xy 20.609034 -43.354497) (xy 20.664471 -43.360597)
			(xy 20.718428 -43.374703) (xy 20.769757 -43.396515) (xy 20.817363 -43.425569) (xy 20.860231 -43.461244)
			(xy 20.897448 -43.502781) (xy 20.928221 -43.549294) (xy 20.951893 -43.599791) (xy 20.967961 -43.653198)
			(xy 20.976081 -43.708374) (xy 20.97659 -43.73626) (xy 20.976081 -43.764146) (xy 20.967961 -43.819322)
			(xy 20.951893 -43.872729) (xy 20.928221 -43.923226) (xy 20.897448 -43.969739) (xy 20.860231 -44.011276)
			(xy 20.817363 -44.046951) (xy 20.769757 -44.076005) (xy 20.718428 -44.097817) (xy 20.664471 -44.111923)
			(xy 20.609034 -44.118023) (xy 20.5533 -44.115986) (xy 20.498457 -44.105856) (xy 20.445673 -44.087849)
			(xy 20.396073 -44.062348) (xy 20.350715 -44.029897) (xy 20.310566 -43.991188) (xy 20.27648 -43.947045)
			(xy 20.249184 -43.89841) (xy 20.229261 -43.846319) (xy 20.217135 -43.791882) (xy 20.213064 -43.73626)
			(xy 1.987296 -43.73626) (xy 1.987296 -44.647358) (xy 2.846068 -44.647358) (xy 2.850139 -44.591736)
			(xy 2.862265 -44.537299) (xy 2.882188 -44.485208) (xy 2.909484 -44.436573) (xy 2.94357 -44.39243)
			(xy 2.983719 -44.353721) (xy 3.029077 -44.32127) (xy 3.078677 -44.295769) (xy 3.131461 -44.277762)
			(xy 3.186304 -44.267632) (xy 3.242038 -44.265595) (xy 3.297475 -44.271695) (xy 3.351432 -44.285801)
			(xy 3.402761 -44.307613) (xy 3.450367 -44.336667) (xy 3.493235 -44.372342) (xy 3.530452 -44.413879)
			(xy 3.561225 -44.460392) (xy 3.584897 -44.510889) (xy 3.600965 -44.564296) (xy 3.609085 -44.619472)
			(xy 3.609594 -44.647358) (xy 3.609085 -44.675244) (xy 3.606984 -44.689522) (xy 3.862068 -44.689522)
			(xy 3.866139 -44.6339) (xy 3.878265 -44.579463) (xy 3.898188 -44.527372) (xy 3.925484 -44.478737)
			(xy 3.95957 -44.434594) (xy 3.999719 -44.395885) (xy 4.045077 -44.363434) (xy 4.094677 -44.337933)
			(xy 4.147461 -44.319926) (xy 4.202304 -44.309796) (xy 4.258038 -44.307759) (xy 4.313475 -44.313859)
			(xy 4.367432 -44.327965) (xy 4.418761 -44.349777) (xy 4.466367 -44.378831) (xy 4.509235 -44.414506)
			(xy 4.546452 -44.456043) (xy 4.577225 -44.502556) (xy 4.600897 -44.553053) (xy 4.616965 -44.60646)
			(xy 4.622984 -44.647358) (xy 4.878068 -44.647358) (xy 4.882139 -44.591736) (xy 4.894265 -44.537299)
			(xy 4.914188 -44.485208) (xy 4.941484 -44.436573) (xy 4.97557 -44.39243) (xy 5.015719 -44.353721)
			(xy 5.061077 -44.32127) (xy 5.110677 -44.295769) (xy 5.163461 -44.277762) (xy 5.218304 -44.267632)
			(xy 5.274038 -44.265595) (xy 5.329475 -44.271695) (xy 5.383432 -44.285801) (xy 5.434761 -44.307613)
			(xy 5.482367 -44.336667) (xy 5.525235 -44.372342) (xy 5.562452 -44.413879) (xy 5.593225 -44.460392)
			(xy 5.616897 -44.510889) (xy 5.632965 -44.564296) (xy 5.641085 -44.619472) (xy 5.641594 -44.647358)
			(xy 5.641085 -44.675244) (xy 5.632965 -44.73042) (xy 5.616897 -44.783827) (xy 5.593225 -44.834324)
			(xy 5.562452 -44.880837) (xy 5.525235 -44.922374) (xy 5.482367 -44.958049) (xy 5.434761 -44.987103)
			(xy 5.383432 -45.008915) (xy 5.329475 -45.023021) (xy 5.274038 -45.029121) (xy 5.218304 -45.027084)
			(xy 5.163461 -45.016954) (xy 5.110677 -44.998947) (xy 5.061077 -44.973446) (xy 5.015719 -44.940995)
			(xy 4.97557 -44.902286) (xy 4.941484 -44.858143) (xy 4.914188 -44.809508) (xy 4.894265 -44.757417)
			(xy 4.882139 -44.70298) (xy 4.878068 -44.647358) (xy 4.622984 -44.647358) (xy 4.625085 -44.661636)
			(xy 4.625594 -44.689522) (xy 4.625085 -44.717408) (xy 4.616965 -44.772584) (xy 4.600897 -44.825991)
			(xy 4.577225 -44.876488) (xy 4.546452 -44.923001) (xy 4.509235 -44.964538) (xy 4.466367 -45.000213)
			(xy 4.418761 -45.029267) (xy 4.367432 -45.051079) (xy 4.313475 -45.065185) (xy 4.258038 -45.071285)
			(xy 4.202304 -45.069248) (xy 4.147461 -45.059118) (xy 4.094677 -45.041111) (xy 4.045077 -45.01561)
			(xy 3.999719 -44.983159) (xy 3.95957 -44.94445) (xy 3.925484 -44.900307) (xy 3.898188 -44.851672)
			(xy 3.878265 -44.799581) (xy 3.866139 -44.745144) (xy 3.862068 -44.689522) (xy 3.606984 -44.689522)
			(xy 3.600965 -44.73042) (xy 3.584897 -44.783827) (xy 3.561225 -44.834324) (xy 3.530452 -44.880837)
			(xy 3.493235 -44.922374) (xy 3.450367 -44.958049) (xy 3.402761 -44.987103) (xy 3.351432 -45.008915)
			(xy 3.297475 -45.023021) (xy 3.242038 -45.029121) (xy 3.186304 -45.027084) (xy 3.131461 -45.016954)
			(xy 3.078677 -44.998947) (xy 3.029077 -44.973446) (xy 2.983719 -44.940995) (xy 2.94357 -44.902286)
			(xy 2.909484 -44.858143) (xy 2.882188 -44.809508) (xy 2.862265 -44.757417) (xy 2.850139 -44.70298)
			(xy 2.846068 -44.647358) (xy 1.987296 -44.647358) (xy 1.987296 -45.071792) (xy 6.365492 -45.071792)
			(xy 6.369563 -45.01617) (xy 6.381689 -44.961733) (xy 6.401612 -44.909642) (xy 6.428908 -44.861007)
			(xy 6.462994 -44.816864) (xy 6.503143 -44.778155) (xy 6.548501 -44.745704) (xy 6.598101 -44.720203)
			(xy 6.650885 -44.702196) (xy 6.705728 -44.692066) (xy 6.761462 -44.690029) (xy 6.816899 -44.696129)
			(xy 6.870856 -44.710235) (xy 6.922185 -44.732047) (xy 6.969791 -44.761101) (xy 7.012659 -44.796776)
			(xy 7.049876 -44.838313) (xy 7.080649 -44.884826) (xy 7.104321 -44.935323) (xy 7.120389 -44.98873)
			(xy 7.128509 -45.043906) (xy 7.129018 -45.071792) (xy 7.128509 -45.099678) (xy 7.126333 -45.114464)
			(xy 20.06549 -45.114464) (xy 20.069561 -45.058842) (xy 20.081687 -45.004405) (xy 20.10161 -44.952314)
			(xy 20.128906 -44.903679) (xy 20.162992 -44.859536) (xy 20.203141 -44.820827) (xy 20.248499 -44.788376)
			(xy 20.298099 -44.762875) (xy 20.350883 -44.744868) (xy 20.405726 -44.734738) (xy 20.46146 -44.732701)
			(xy 20.516897 -44.738801) (xy 20.570854 -44.752907) (xy 20.622183 -44.774719) (xy 20.669789 -44.803773)
			(xy 20.712657 -44.839448) (xy 20.749874 -44.880985) (xy 20.780647 -44.927498) (xy 20.804319 -44.977995)
			(xy 20.820387 -45.031402) (xy 20.828507 -45.086578) (xy 20.829016 -45.114464) (xy 20.828507 -45.14235)
			(xy 20.820387 -45.197526) (xy 20.804319 -45.250933) (xy 20.780647 -45.30143) (xy 20.749874 -45.347943)
			(xy 20.712657 -45.38948) (xy 20.669789 -45.425155) (xy 20.622183 -45.454209) (xy 20.570854 -45.476021)
			(xy 20.516897 -45.490127) (xy 20.46146 -45.496227) (xy 20.405726 -45.49419) (xy 20.350883 -45.48406)
			(xy 20.298099 -45.466053) (xy 20.248499 -45.440552) (xy 20.203141 -45.408101) (xy 20.162992 -45.369392)
			(xy 20.128906 -45.325249) (xy 20.10161 -45.276614) (xy 20.081687 -45.224523) (xy 20.069561 -45.170086)
			(xy 20.06549 -45.114464) (xy 7.126333 -45.114464) (xy 7.120389 -45.154854) (xy 7.104321 -45.208261)
			(xy 7.080649 -45.258758) (xy 7.049876 -45.305271) (xy 7.012659 -45.346808) (xy 6.969791 -45.382483)
			(xy 6.922185 -45.411537) (xy 6.870856 -45.433349) (xy 6.816899 -45.447455) (xy 6.761462 -45.453555)
			(xy 6.705728 -45.451518) (xy 6.650885 -45.441388) (xy 6.598101 -45.423381) (xy 6.548501 -45.39788)
			(xy 6.503143 -45.365429) (xy 6.462994 -45.32672) (xy 6.428908 -45.282577) (xy 6.401612 -45.233942)
			(xy 6.381689 -45.181851) (xy 6.369563 -45.127414) (xy 6.365492 -45.071792) (xy 1.987296 -45.071792)
			(xy 1.987296 -45.851318) (xy 7.87476 -45.851318) (xy 7.878831 -45.795696) (xy 7.890957 -45.741259)
			(xy 7.91088 -45.689168) (xy 7.938176 -45.640533) (xy 7.972262 -45.59639) (xy 8.012411 -45.557681)
			(xy 8.057769 -45.52523) (xy 8.107369 -45.499729) (xy 8.160153 -45.481722) (xy 8.214996 -45.471592)
			(xy 8.27073 -45.469555) (xy 8.326167 -45.475655) (xy 8.380124 -45.489761) (xy 8.431453 -45.511573)
			(xy 8.479059 -45.540627) (xy 8.521927 -45.576302) (xy 8.559144 -45.617839) (xy 8.589917 -45.664352)
			(xy 8.613589 -45.714849) (xy 8.629657 -45.768256) (xy 8.637777 -45.823432) (xy 8.638286 -45.851318)
			(xy 8.637777 -45.879204) (xy 8.630854 -45.926248) (xy 11.930886 -45.926248) (xy 11.934957 -45.870626)
			(xy 11.947083 -45.816189) (xy 11.967006 -45.764098) (xy 11.994302 -45.715463) (xy 12.028388 -45.67132)
			(xy 12.068537 -45.632611) (xy 12.113895 -45.60016) (xy 12.163495 -45.574659) (xy 12.216279 -45.556652)
			(xy 12.271122 -45.546522) (xy 12.326856 -45.544485) (xy 12.382293 -45.550585) (xy 12.43625 -45.564691)
			(xy 12.487579 -45.586503) (xy 12.535185 -45.615557) (xy 12.578053 -45.651232) (xy 12.61527 -45.692769)
			(xy 12.646043 -45.739282) (xy 12.669715 -45.789779) (xy 12.685783 -45.843186) (xy 12.693903 -45.898362)
			(xy 12.694412 -45.926248) (xy 12.693903 -45.954134) (xy 12.685783 -46.00931) (xy 12.669715 -46.062717)
			(xy 12.66058 -46.082204) (xy 18.052542 -46.082204) (xy 18.052959 -46.054949) (xy 18.060717 -46.000994)
			(xy 18.076075 -45.948692) (xy 18.098721 -45.899109) (xy 18.128193 -45.853253) (xy 18.163892 -45.812059)
			(xy 18.20509 -45.776365) (xy 18.250949 -45.746899) (xy 18.300535 -45.724259) (xy 18.352839 -45.708907)
			(xy 18.406795 -45.701156) (xy 18.43405 -45.700696) (xy 18.460954 -45.70112) (xy 18.514226 -45.708699)
			(xy 18.565905 -45.723685) (xy 18.614967 -45.745781) (xy 18.660438 -45.774549) (xy 18.701419 -45.80942)
			(xy 18.737095 -45.8497) (xy 18.752312 -45.871892) (xy 18.759424 -45.882814) (xy 18.782284 -45.894752)
			(xy 18.894552 -45.89272) (xy 18.916904 -45.879766) (xy 18.923762 -45.86859) (xy 18.938655 -45.844969)
			(xy 18.974339 -45.802018) (xy 19.015902 -45.764726) (xy 19.062457 -45.733891) (xy 19.113009 -45.710171)
			(xy 19.166479 -45.694072) (xy 19.221724 -45.685939) (xy 19.249644 -45.685456) (xy 19.276638 -45.685892)
			(xy 19.330087 -45.693504) (xy 19.381931 -45.70857) (xy 19.431135 -45.730789) (xy 19.476718 -45.759719)
			(xy 19.497548 -45.776896) (xy 19.505676 -45.784008) (xy 19.52625 -45.790104) (xy 19.611594 -45.779182)
			(xy 19.62214 -45.777415) (xy 19.640422 -45.766355) (xy 19.6469 -45.757846) (xy 19.66226 -45.73662)
			(xy 19.697846 -45.698167) (xy 19.738362 -45.664948) (xy 19.783044 -45.637589) (xy 19.831051 -45.616605)
			(xy 19.881479 -45.602391) (xy 19.933378 -45.595214) (xy 19.959574 -45.594778) (xy 19.986827 -45.595268)
			(xy 20.040779 -45.603021) (xy 20.093078 -45.618374) (xy 20.142659 -45.641015) (xy 20.188514 -45.670481)
			(xy 20.229708 -45.706173) (xy 20.265404 -45.747365) (xy 20.294873 -45.793218) (xy 20.317516 -45.842798)
			(xy 20.332873 -45.895096) (xy 20.340631 -45.949047) (xy 20.340631 -46.003553) (xy 20.332873 -46.057504)
			(xy 20.317516 -46.109802) (xy 20.294873 -46.159382) (xy 20.265404 -46.205235) (xy 20.229708 -46.246427)
			(xy 20.188514 -46.282119) (xy 20.142659 -46.311585) (xy 20.093078 -46.334226) (xy 20.040779 -46.349579)
			(xy 19.986827 -46.357332) (xy 19.959574 -46.357794) (xy 19.932581 -46.357336) (xy 19.879133 -46.349728)
			(xy 19.82729 -46.334666) (xy 19.778085 -46.312452) (xy 19.732501 -46.283528) (xy 19.71167 -46.266354)
			(xy 19.703542 -46.259242) (xy 19.682968 -46.253146) (xy 19.597624 -46.264068) (xy 19.587085 -46.265862)
			(xy 19.568801 -46.276903) (xy 19.562318 -46.285404) (xy 19.544699 -46.3097) (xy 19.503108 -46.352962)
			(xy 19.479514 -46.37151) (xy 19.47164 -46.377352) (xy 19.461226 -46.394878) (xy 19.448018 -46.485302)
			(xy 19.452844 -46.504606) (xy 19.458686 -46.51248) (xy 19.458686 -46.512734) (xy 19.47619 -46.537477)
			(xy 19.503992 -46.59133) (xy 19.522928 -46.648903) (xy 19.532521 -46.708745) (xy 19.533108 -46.739048)
			(xy 19.532667 -46.7663) (xy 19.524904 -46.82025) (xy 19.509543 -46.872545) (xy 19.500096 -46.893226)
			(xy 20.33727 -46.893226) (xy 20.341341 -46.837604) (xy 20.353467 -46.783167) (xy 20.37339 -46.731076)
			(xy 20.400686 -46.682441) (xy 20.434772 -46.638298) (xy 20.474921 -46.599589) (xy 20.520279 -46.567138)
			(xy 20.569879 -46.541637) (xy 20.622663 -46.52363) (xy 20.677506 -46.5135) (xy 20.73324 -46.511463)
			(xy 20.788677 -46.517563) (xy 20.842634 -46.531669) (xy 20.893963 -46.553481) (xy 20.941569 -46.582535)
			(xy 20.984437 -46.61821) (xy 21.021654 -46.659747) (xy 21.052427 -46.70626) (xy 21.076099 -46.756757)
			(xy 21.092167 -46.810164) (xy 21.100287 -46.86534) (xy 21.100796 -46.893226) (xy 21.100287 -46.921112)
			(xy 21.092167 -46.976288) (xy 21.076099 -47.029695) (xy 21.052427 -47.080192) (xy 21.021654 -47.126705)
			(xy 20.984437 -47.168242) (xy 20.941569 -47.203917) (xy 20.893963 -47.232971) (xy 20.842634 -47.254783)
			(xy 20.788677 -47.268889) (xy 20.73324 -47.274989) (xy 20.677506 -47.272952) (xy 20.622663 -47.262822)
			(xy 20.569879 -47.244815) (xy 20.520279 -47.219314) (xy 20.474921 -47.186863) (xy 20.434772 -47.148154)
			(xy 20.400686 -47.104011) (xy 20.37339 -47.055376) (xy 20.353467 -47.003285) (xy 20.341341 -46.948848)
			(xy 20.33727 -46.893226) (xy 19.500096 -46.893226) (xy 19.486896 -46.922123) (xy 19.457425 -46.967973)
			(xy 19.421729 -47.009163) (xy 19.380534 -47.044853) (xy 19.334681 -47.074319) (xy 19.2851 -47.096959)
			(xy 19.232803 -47.112314) (xy 19.178852 -47.12007) (xy 19.1516 -47.120556) (xy 19.125567 -47.120101)
			(xy 19.073984 -47.113015) (xy 19.023843 -47.098987) (xy 18.976072 -47.078278) (xy 18.931557 -47.051271)
			(xy 18.911062 -47.035212) (xy 18.903294 -47.029488) (xy 18.884892 -47.023736) (xy 18.875248 -47.024036)
			(xy 18.795492 -47.030386) (xy 18.777712 -47.039022) (xy 18.771362 -47.046388) (xy 18.753173 -47.066026)
			(xy 18.712267 -47.100549) (xy 18.66694 -47.129019) (xy 18.61808 -47.150878) (xy 18.566645 -47.165697)
			(xy 18.513645 -47.173186) (xy 18.486882 -47.173642) (xy 18.459632 -47.173139) (xy 18.405687 -47.165381)
			(xy 18.353394 -47.150025) (xy 18.303819 -47.127385) (xy 18.25797 -47.09792) (xy 18.216781 -47.06223)
			(xy 18.18109 -47.021042) (xy 18.151623 -46.975195) (xy 18.12898 -46.925621) (xy 18.113622 -46.873329)
			(xy 18.105862 -46.819384) (xy 18.105374 -46.792134) (xy 18.105905 -46.76336) (xy 18.114556 -46.706467)
			(xy 18.131651 -46.651517) (xy 18.156803 -46.599756) (xy 18.189441 -46.55236) (xy 18.208752 -46.531022)
			(xy 18.216118 -46.523148) (xy 18.22323 -46.503336) (xy 18.215864 -46.40707) (xy 18.205958 -46.388274)
			(xy 18.197576 -46.38167) (xy 18.175382 -46.363456) (xy 18.136175 -46.321517) (xy 18.103692 -46.274179)
			(xy 18.078665 -46.222509) (xy 18.06166 -46.167674) (xy 18.05306 -46.11091) (xy 18.052542 -46.082204)
			(xy 12.66058 -46.082204) (xy 12.646043 -46.113214) (xy 12.61527 -46.159727) (xy 12.578053 -46.201264)
			(xy 12.535185 -46.236939) (xy 12.487579 -46.265993) (xy 12.43625 -46.287805) (xy 12.382293 -46.301911)
			(xy 12.326856 -46.308011) (xy 12.271122 -46.305974) (xy 12.216279 -46.295844) (xy 12.163495 -46.277837)
			(xy 12.113895 -46.252336) (xy 12.068537 -46.219885) (xy 12.028388 -46.181176) (xy 11.994302 -46.137033)
			(xy 11.967006 -46.088398) (xy 11.947083 -46.036307) (xy 11.934957 -45.98187) (xy 11.930886 -45.926248)
			(xy 8.630854 -45.926248) (xy 8.629657 -45.93438) (xy 8.613589 -45.987787) (xy 8.589917 -46.038284)
			(xy 8.559144 -46.084797) (xy 8.521927 -46.126334) (xy 8.479059 -46.162009) (xy 8.431453 -46.191063)
			(xy 8.380124 -46.212875) (xy 8.326167 -46.226981) (xy 8.27073 -46.233081) (xy 8.214996 -46.231044)
			(xy 8.160153 -46.220914) (xy 8.107369 -46.202907) (xy 8.057769 -46.177406) (xy 8.012411 -46.144955)
			(xy 7.972262 -46.106246) (xy 7.938176 -46.062103) (xy 7.91088 -46.013468) (xy 7.890957 -45.961377)
			(xy 7.878831 -45.90694) (xy 7.87476 -45.851318) (xy 1.987296 -45.851318) (xy 1.987296 -47.936658)
			(xy 18.652998 -47.936658) (xy 18.653484 -47.909407) (xy 18.66124 -47.855459) (xy 18.676595 -47.803164)
			(xy 18.699237 -47.753587) (xy 18.728703 -47.707737) (xy 18.764394 -47.666546) (xy 18.805585 -47.630855)
			(xy 18.851435 -47.601389) (xy 18.901012 -47.578747) (xy 18.953307 -47.563392) (xy 19.007255 -47.555636)
			(xy 19.061757 -47.555636) (xy 19.115705 -47.563392) (xy 19.168 -47.578747) (xy 19.217577 -47.601389)
			(xy 19.263427 -47.630855) (xy 19.304618 -47.666546) (xy 19.340309 -47.707737) (xy 19.369775 -47.753587)
			(xy 19.392417 -47.803164) (xy 19.407772 -47.855459) (xy 19.415528 -47.909407) (xy 19.416014 -47.936658)
			(xy 19.415568 -47.962999) (xy 19.408317 -48.015181) (xy 19.393961 -48.065871) (xy 19.372772 -48.114105)
			(xy 19.345152 -48.158968) (xy 19.311627 -48.199607) (xy 19.272833 -48.235252) (xy 19.251422 -48.250602)
			(xy 19.239601 -48.2593) (xy 19.221168 -48.282126) (xy 19.209986 -48.30925) (xy 19.206979 -48.338435)
			(xy 19.212394 -48.367269) (xy 19.225785 -48.393374) (xy 19.246046 -48.414593) (xy 19.258534 -48.422306)
			(xy 19.283084 -48.436979) (xy 19.327839 -48.472586) (xy 19.36678 -48.514474) (xy 19.399033 -48.561705)
			(xy 19.423877 -48.61322) (xy 19.440754 -48.667865) (xy 19.449287 -48.724418) (xy 19.449796 -48.753014)
			(xy 19.44931 -48.780265) (xy 19.441554 -48.834213) (xy 19.426199 -48.886508) (xy 19.403557 -48.936085)
			(xy 19.374091 -48.981935) (xy 19.3384 -49.023126) (xy 19.297209 -49.058817) (xy 19.251359 -49.088283)
			(xy 19.201782 -49.110925) (xy 19.149487 -49.12628) (xy 19.095539 -49.134036) (xy 19.041037 -49.134036)
			(xy 18.987089 -49.12628) (xy 18.934794 -49.110925) (xy 18.885217 -49.088283) (xy 18.839367 -49.058817)
			(xy 18.798176 -49.023126) (xy 18.762485 -48.981935) (xy 18.733019 -48.936085) (xy 18.710377 -48.886508)
			(xy 18.695022 -48.834213) (xy 18.687266 -48.780265) (xy 18.68678 -48.753014) (xy 18.687207 -48.726672)
			(xy 18.694462 -48.674489) (xy 18.708822 -48.6238) (xy 18.730014 -48.575566) (xy 18.757636 -48.530703)
			(xy 18.791164 -48.490064) (xy 18.82996 -48.45442) (xy 18.851372 -48.43907) (xy 18.863222 -48.430408)
			(xy 18.881657 -48.407574) (xy 18.892838 -48.380442) (xy 18.895842 -48.351249) (xy 18.890421 -48.322408)
			(xy 18.877022 -48.296299) (xy 18.856752 -48.275078) (xy 18.84426 -48.267366) (xy 18.819741 -48.252645)
			(xy 18.774986 -48.217045) (xy 18.736044 -48.175165) (xy 18.703787 -48.127943) (xy 18.678939 -48.076436)
			(xy 18.662054 -48.021798) (xy 18.653512 -47.965252) (xy 18.652998 -47.936658) (xy 1.987296 -47.936658)
			(xy 1.987296 -49.601951) (xy 2.291062 -49.601951) (xy 2.291062 -49.547449) (xy 2.298818 -49.493502)
			(xy 2.314173 -49.441208) (xy 2.336814 -49.391631) (xy 2.36628 -49.345781) (xy 2.401971 -49.304591)
			(xy 2.443161 -49.2689) (xy 2.489011 -49.239434) (xy 2.538588 -49.216793) (xy 2.590882 -49.201438)
			(xy 2.644829 -49.193682) (xy 2.67208 -49.193196) (xy 2.69945 -49.193675) (xy 2.753628 -49.20149)
			(xy 2.806131 -49.216976) (xy 2.855878 -49.239815) (xy 2.901846 -49.269536) (xy 2.922778 -49.287176)
			(xy 2.923032 -49.28743) (xy 2.930131 -49.292998) (xy 2.947038 -49.299255) (xy 2.956052 -49.299622)
			(xy 3.023108 -49.299622) (xy 3.032125 -49.299264) (xy 3.049041 -49.293016) (xy 3.056128 -49.28743)
			(xy 3.056128 -49.287176) (xy 3.056382 -49.287176) (xy 3.077315 -49.269535) (xy 3.123283 -49.239811)
			(xy 3.173029 -49.216965) (xy 3.225531 -49.201469) (xy 3.279709 -49.19364) (xy 3.334451 -49.19364)
			(xy 3.388629 -49.201469) (xy 3.441131 -49.216965) (xy 3.490877 -49.239811) (xy 3.536845 -49.269535)
			(xy 3.557778 -49.287176) (xy 3.558032 -49.28743) (xy 3.565131 -49.292998) (xy 3.582038 -49.299255)
			(xy 3.591052 -49.299622) (xy 3.658108 -49.299622) (xy 3.667125 -49.299264) (xy 3.684041 -49.293016)
			(xy 3.691128 -49.28743) (xy 3.691128 -49.287176) (xy 3.691382 -49.287176) (xy 3.712307 -49.269528)
			(xy 3.758282 -49.239818) (xy 3.808031 -49.216985) (xy 3.860534 -49.201495) (xy 3.91471 -49.193669)
			(xy 3.94208 -49.193196) (xy 3.968393 -49.193678) (xy 4.020521 -49.20091) (xy 4.071164 -49.215226)
			(xy 4.119363 -49.236356) (xy 4.164207 -49.2639) (xy 4.204847 -49.297336) (xy 4.223004 -49.316386)
			(xy 4.230524 -49.323789) (xy 4.249805 -49.332313) (xy 4.260342 -49.332896) (xy 4.335018 -49.332896)
			(xy 4.345564 -49.332337) (xy 4.36486 -49.323823) (xy 4.372356 -49.316386) (xy 4.390489 -49.297308)
			(xy 4.431124 -49.263853) (xy 4.475969 -49.236297) (xy 4.524174 -49.215163) (xy 4.574825 -49.200851)
			(xy 4.626963 -49.193631) (xy 4.65328 -49.193196) (xy 4.680532 -49.193674) (xy 4.73448 -49.20143)
			(xy 4.786775 -49.216786) (xy 4.836353 -49.239427) (xy 4.882204 -49.268894) (xy 4.923394 -49.304586)
			(xy 4.959086 -49.345776) (xy 4.988553 -49.391627) (xy 5.011194 -49.441205) (xy 5.02655 -49.4935)
			(xy 5.034306 -49.547448) (xy 5.034306 -49.601951) (xy 6.113002 -49.601951) (xy 6.113002 -49.547449)
			(xy 6.120758 -49.493502) (xy 6.136113 -49.441208) (xy 6.158754 -49.391632) (xy 6.18822 -49.345782)
			(xy 6.223911 -49.304592) (xy 6.2651 -49.268901) (xy 6.31095 -49.239435) (xy 6.360526 -49.216794)
			(xy 6.41282 -49.201439) (xy 6.466767 -49.193682) (xy 6.494018 -49.193196) (xy 6.521389 -49.193652)
			(xy 6.575568 -49.201473) (xy 6.628071 -49.216964) (xy 6.677818 -49.239808) (xy 6.723784 -49.269534)
			(xy 6.744716 -49.287176) (xy 6.74497 -49.28743) (xy 6.752059 -49.293013) (xy 6.768974 -49.299261)
			(xy 6.77799 -49.299622) (xy 6.845046 -49.299622) (xy 6.85406 -49.299235) (xy 6.870977 -49.293008)
			(xy 6.878066 -49.28743) (xy 6.878066 -49.287176) (xy 6.87832 -49.287176) (xy 6.899253 -49.269535)
			(xy 6.945221 -49.239811) (xy 6.994967 -49.216965) (xy 7.047469 -49.201469) (xy 7.101647 -49.19364)
			(xy 7.156389 -49.19364) (xy 7.210567 -49.201469) (xy 7.263069 -49.216965) (xy 7.312815 -49.239811)
			(xy 7.358783 -49.269535) (xy 7.379716 -49.287176) (xy 7.37997 -49.28743) (xy 7.387059 -49.293013)
			(xy 7.403974 -49.299261) (xy 7.41299 -49.299622) (xy 7.480046 -49.299622) (xy 7.48906 -49.299235)
			(xy 7.505977 -49.293008) (xy 7.513066 -49.28743) (xy 7.513066 -49.287176) (xy 7.51332 -49.287176)
			(xy 7.534253 -49.269535) (xy 7.580221 -49.239811) (xy 7.629967 -49.216965) (xy 7.682469 -49.201469)
			(xy 7.736647 -49.19364) (xy 7.791389 -49.19364) (xy 7.845567 -49.201469) (xy 7.898069 -49.216965)
			(xy 7.947815 -49.239811) (xy 7.993783 -49.269535) (xy 8.014716 -49.287176) (xy 8.01497 -49.28743)
			(xy 8.022059 -49.293013) (xy 8.038974 -49.299261) (xy 8.04799 -49.299622) (xy 8.115046 -49.299622)
			(xy 8.12406 -49.299235) (xy 8.140977 -49.293008) (xy 8.148066 -49.28743) (xy 8.148066 -49.287176)
			(xy 8.14832 -49.287176) (xy 8.169268 -49.269557) (xy 8.215237 -49.239843) (xy 8.26498 -49.217004)
			(xy 8.317477 -49.201508) (xy 8.37165 -49.193673) (xy 8.399018 -49.193196) (xy 8.426271 -49.193651)
			(xy 8.480223 -49.201408) (xy 8.532522 -49.216764) (xy 8.582102 -49.239407) (xy 8.627956 -49.268875)
			(xy 8.66915 -49.304569) (xy 8.704844 -49.345762) (xy 8.734312 -49.391616) (xy 8.756955 -49.441197)
			(xy 8.772312 -49.493495) (xy 8.780069 -49.547447) (xy 8.780069 -49.601953) (xy 8.772312 -49.655905)
			(xy 8.756955 -49.708203) (xy 8.734312 -49.757784) (xy 8.704844 -49.803638) (xy 8.66915 -49.844831)
			(xy 8.627956 -49.880525) (xy 8.582102 -49.909993) (xy 8.532522 -49.932636) (xy 8.480223 -49.947992)
			(xy 8.426271 -49.955749) (xy 8.399018 -49.956212) (xy 8.371648 -49.955732) (xy 8.31747 -49.947917)
			(xy 8.264967 -49.932431) (xy 8.21522 -49.909593) (xy 8.169252 -49.879872) (xy 8.14832 -49.862232)
			(xy 8.148066 -49.861978) (xy 8.140966 -49.85641) (xy 8.12406 -49.850153) (xy 8.115046 -49.849786)
			(xy 8.04799 -49.849786) (xy 8.038973 -49.850141) (xy 8.022056 -49.856391) (xy 8.01497 -49.861978)
			(xy 8.014716 -49.862232) (xy 7.993783 -49.879873) (xy 7.947815 -49.909597) (xy 7.898069 -49.932443)
			(xy 7.845567 -49.947939) (xy 7.791389 -49.955768) (xy 7.736647 -49.955768) (xy 7.682469 -49.947939)
			(xy 7.629967 -49.932443) (xy 7.580221 -49.909597) (xy 7.534253 -49.879873) (xy 7.51332 -49.862232)
			(xy 7.513066 -49.861978) (xy 7.505966 -49.85641) (xy 7.48906 -49.850153) (xy 7.480046 -49.849786)
			(xy 7.41299 -49.849786) (xy 7.403973 -49.850141) (xy 7.387056 -49.856391) (xy 7.37997 -49.861978)
			(xy 7.37997 -49.862232) (xy 7.379716 -49.862232) (xy 7.358783 -49.879873) (xy 7.312815 -49.909597)
			(xy 7.263069 -49.932443) (xy 7.210567 -49.947939) (xy 7.156389 -49.955768) (xy 7.101647 -49.955768)
			(xy 7.047469 -49.947939) (xy 6.994967 -49.932443) (xy 6.945221 -49.909597) (xy 6.899253 -49.879873)
			(xy 6.87832 -49.862232) (xy 6.878066 -49.861978) (xy 6.870966 -49.85641) (xy 6.85406 -49.850153)
			(xy 6.845046 -49.849786) (xy 6.77799 -49.849786) (xy 6.768973 -49.850141) (xy 6.752056 -49.856391)
			(xy 6.74497 -49.861978) (xy 6.74497 -49.862232) (xy 6.744716 -49.862232) (xy 6.723793 -49.879882)
			(xy 6.677817 -49.909591) (xy 6.628067 -49.932424) (xy 6.575565 -49.947913) (xy 6.521388 -49.955739)
			(xy 6.494018 -49.956212) (xy 6.466767 -49.955718) (xy 6.41282 -49.947961) (xy 6.360526 -49.932606)
			(xy 6.31095 -49.909965) (xy 6.2651 -49.880499) (xy 6.223911 -49.844808) (xy 6.18822 -49.803618) (xy 6.158754 -49.757768)
			(xy 6.136113 -49.708192) (xy 6.120758 -49.655898) (xy 6.113002 -49.601951) (xy 5.034306 -49.601951)
			(xy 5.034306 -49.601952) (xy 5.02655 -49.6559) (xy 5.011194 -49.708195) (xy 4.988553 -49.757773)
			(xy 4.959086 -49.803624) (xy 4.923394 -49.844814) (xy 4.882204 -49.880506) (xy 4.836353 -49.909973)
			(xy 4.786775 -49.932614) (xy 4.73448 -49.94797) (xy 4.680532 -49.955726) (xy 4.65328 -49.956212)
			(xy 4.626966 -49.955754) (xy 4.574837 -49.948517) (xy 4.524194 -49.934196) (xy 4.475995 -49.913061)
			(xy 4.431152 -49.885514) (xy 4.390513 -49.852074) (xy 4.372356 -49.833022) (xy 4.36485 -49.825602)
			(xy 4.345558 -49.817087) (xy 4.335018 -49.816512) (xy 4.260342 -49.816512) (xy 4.249793 -49.817047)
			(xy 4.230497 -49.825577) (xy 4.223004 -49.833022) (xy 4.204844 -49.852073) (xy 4.164215 -49.88553)
			(xy 4.119375 -49.913089) (xy 4.071175 -49.934228) (xy 4.020529 -49.948546) (xy 3.968396 -49.955773)
			(xy 3.94208 -49.956212) (xy 3.914709 -49.955755) (xy 3.86053 -49.947934) (xy 3.808027 -49.932443)
			(xy 3.75828 -49.909599) (xy 3.712314 -49.879874) (xy 3.691382 -49.862232) (xy 3.691128 -49.861978)
			(xy 3.684039 -49.856395) (xy 3.667124 -49.850147) (xy 3.658108 -49.849786) (xy 3.591052 -49.849786)
			(xy 3.582038 -49.850171) (xy 3.565121 -49.856399) (xy 3.558032 -49.861978) (xy 3.558032 -49.862232)
			(xy 3.557778 -49.862232) (xy 3.536845 -49.879873) (xy 3.490877 -49.909597) (xy 3.441131 -49.932443)
			(xy 3.388629 -49.947939) (xy 3.334451 -49.955768) (xy 3.279709 -49.955768) (xy 3.225531 -49.947939)
			(xy 3.173029 -49.932443) (xy 3.123283 -49.909597) (xy 3.077315 -49.879873) (xy 3.056382 -49.862232)
			(xy 3.056128 -49.861978) (xy 3.049039 -49.856395) (xy 3.032124 -49.850147) (xy 3.023108 -49.849786)
			(xy 2.956052 -49.849786) (xy 2.947038 -49.850171) (xy 2.930121 -49.856399) (xy 2.923032 -49.861978)
			(xy 2.923032 -49.862232) (xy 2.922778 -49.862232) (xy 2.901831 -49.879853) (xy 2.855862 -49.909566)
			(xy 2.806118 -49.932405) (xy 2.753621 -49.947901) (xy 2.699448 -49.955735) (xy 2.67208 -49.956212)
			(xy 2.644829 -49.955718) (xy 2.590882 -49.947962) (xy 2.538588 -49.932607) (xy 2.489011 -49.909966)
			(xy 2.443161 -49.8805) (xy 2.401971 -49.844809) (xy 2.36628 -49.803619) (xy 2.336814 -49.757769)
			(xy 2.314173 -49.708192) (xy 2.298818 -49.655898) (xy 2.291062 -49.601951) (xy 1.987296 -49.601951)
			(xy 1.987296 -51.689071) (xy 2.2555 -51.689071) (xy 2.2555 -51.634569) (xy 2.263256 -51.580621) (xy 2.278611 -51.528327)
			(xy 2.301252 -51.47875) (xy 2.330718 -51.4329) (xy 2.36641 -51.39171) (xy 2.4076 -51.356018) (xy 2.45345 -51.326552)
			(xy 2.503027 -51.303911) (xy 2.555321 -51.288556) (xy 2.609269 -51.2808) (xy 2.63652 -51.280314)
			(xy 2.663891 -51.280765) (xy 2.718071 -51.288586) (xy 2.770574 -51.304078) (xy 2.820321 -51.326923)
			(xy 2.866287 -51.356651) (xy 2.887218 -51.374294) (xy 2.887472 -51.374548) (xy 2.894558 -51.380135)
			(xy 2.911475 -51.38638) (xy 2.920492 -51.38674) (xy 2.987548 -51.38674) (xy 2.996564 -51.386371)
			(xy 3.013482 -51.380133) (xy 3.020568 -51.374548) (xy 3.020568 -51.374294) (xy 3.020822 -51.374294)
			(xy 3.041772 -51.356677) (xy 3.08774 -51.326962) (xy 3.137483 -51.304122) (xy 3.18998 -51.288626)
			(xy 3.244152 -51.280791) (xy 3.27152 -51.280314) (xy 3.289863 -51.280554) (xy 3.326376 -51.284112)
			(xy 3.344418 -51.287426) (xy 3.35505 -51.289008) (xy 3.375968 -51.284149) (xy 3.384804 -51.278028)
			(xy 3.453892 -51.225704) (xy 3.464306 -51.206908) (xy 3.465068 -51.195986) (xy 3.467952 -51.167701)
			(xy 3.480991 -51.112363) (xy 3.502089 -51.059569) (xy 3.53078 -51.010486) (xy 3.566431 -50.966199)
			(xy 3.586988 -50.946558) (xy 3.594408 -50.939052) (xy 3.602922 -50.91976) (xy 3.603498 -50.90922)
			(xy 3.603498 -50.834544) (xy 3.602959 -50.823995) (xy 3.594431 -50.8047) (xy 3.586988 -50.797206)
			(xy 3.567926 -50.779057) (xy 3.534469 -50.738426) (xy 3.506912 -50.693584) (xy 3.485774 -50.645382)
			(xy 3.471459 -50.594733) (xy 3.464236 -50.542599) (xy 3.463798 -50.516282) (xy 3.464284 -50.489031)
			(xy 3.47204 -50.435083) (xy 3.487395 -50.382788) (xy 3.510037 -50.333211) (xy 3.539503 -50.287361)
			(xy 3.575194 -50.24617) (xy 3.616385 -50.210479) (xy 3.662235 -50.181013) (xy 3.711812 -50.158371)
			(xy 3.764107 -50.143016) (xy 3.818055 -50.13526) (xy 3.872557 -50.13526) (xy 3.926505 -50.143016)
			(xy 3.9788 -50.158371) (xy 4.028377 -50.181013) (xy 4.074227 -50.210479) (xy 4.115418 -50.24617)
			(xy 4.151109 -50.287361) (xy 4.180575 -50.333211) (xy 4.203217 -50.382788) (xy 4.218572 -50.435083)
			(xy 4.226328 -50.489031) (xy 4.226814 -50.516282) (xy 4.22633 -50.542595) (xy 4.219098 -50.594723)
			(xy 4.204782 -50.645365) (xy 4.183652 -50.693564) (xy 4.156109 -50.738408) (xy 4.122674 -50.779049)
			(xy 4.103624 -50.797206) (xy 4.096221 -50.804727) (xy 4.087697 -50.824007) (xy 4.087114 -50.834544)
			(xy 4.087114 -50.90922) (xy 4.087669 -50.919767) (xy 4.096185 -50.939063) (xy 4.103624 -50.946558)
			(xy 4.122684 -50.964709) (xy 4.15614 -51.00534) (xy 4.183698 -51.050181) (xy 4.204836 -51.098383)
			(xy 4.219152 -51.149031) (xy 4.226376 -51.201166) (xy 4.226814 -51.227482) (xy 4.22652 -51.243992)
			(xy 7.133082 -51.243992) (xy 7.133523 -51.216621) (xy 7.141344 -51.16244) (xy 7.156838 -51.109936)
			(xy 7.179686 -51.060189) (xy 7.209417 -51.014224) (xy 7.227062 -50.993294) (xy 7.227316 -50.99304)
			(xy 7.232894 -50.985947) (xy 7.239145 -50.969035) (xy 7.239508 -50.96002) (xy 7.239508 -50.892964)
			(xy 7.239167 -50.883946) (xy 7.232908 -50.867029) (xy 7.227316 -50.859944) (xy 7.227062 -50.859944)
			(xy 7.227062 -50.85969) (xy 7.209398 -50.838778) (xy 7.179691 -50.792799) (xy 7.156861 -50.743046)
			(xy 7.141375 -50.690541) (xy 7.133553 -50.636362) (xy 7.133082 -50.608992) (xy 7.13357 -50.581741)
			(xy 7.141328 -50.527794) (xy 7.156683 -50.4755) (xy 7.179325 -50.425923) (xy 7.208791 -50.380073)
			(xy 7.244482 -50.338883) (xy 7.285672 -50.303192) (xy 7.331521 -50.273726) (xy 7.381098 -50.251084)
			(xy 7.433392 -50.235728) (xy 7.487339 -50.22797) (xy 7.51459 -50.227484) (xy 7.543508 -50.227978)
			(xy 7.600682 -50.236707) (xy 7.655883 -50.253968) (xy 7.707845 -50.279364) (xy 7.755378 -50.312314)
			(xy 7.797392 -50.352061) (xy 7.81558 -50.37455) (xy 7.823197 -50.383347) (xy 7.844091 -50.393534)
			(xy 7.855712 -50.394108) (xy 7.935468 -50.394108) (xy 7.947095 -50.393533) (xy 7.968005 -50.383369)
			(xy 7.9756 -50.37455) (xy 7.993778 -50.352056) (xy 8.035802 -50.312324) (xy 8.08334 -50.279388) (xy 8.135304 -50.254001)
			(xy 8.190503 -50.236747) (xy 8.247673 -50.228019) (xy 8.27659 -50.227484) (xy 8.303842 -50.227965)
			(xy 8.357792 -50.23572) (xy 8.410089 -50.251074) (xy 8.459669 -50.273715) (xy 8.505522 -50.303181)
			(xy 8.546714 -50.338873) (xy 8.582408 -50.380064) (xy 8.611876 -50.425915) (xy 8.634519 -50.475494)
			(xy 8.649876 -50.52779) (xy 8.657634 -50.58174) (xy 8.658098 -50.608992) (xy 8.657626 -50.635306)
			(xy 8.650392 -50.687434) (xy 8.636074 -50.738077) (xy 8.614942 -50.786276) (xy 8.587397 -50.831119)
			(xy 8.553959 -50.871759) (xy 8.534908 -50.889916) (xy 8.527499 -50.897431) (xy 8.518978 -50.916716)
			(xy 8.518398 -50.927254) (xy 8.518398 -51.00193) (xy 8.518952 -51.012477) (xy 8.52747 -51.031772)
			(xy 8.534908 -51.039268) (xy 8.553991 -51.057396) (xy 8.587445 -51.098032) (xy 8.615001 -51.142878)
			(xy 8.636134 -51.191084) (xy 8.650446 -51.241736) (xy 8.657663 -51.293874) (xy 8.658098 -51.320192)
			(xy 8.657637 -51.347445) (xy 8.649881 -51.401397) (xy 8.634526 -51.453695) (xy 8.611883 -51.503276)
			(xy 8.582415 -51.54913) (xy 8.546721 -51.590323) (xy 8.505528 -51.626016) (xy 8.459674 -51.655484)
			(xy 8.410093 -51.678126) (xy 8.357795 -51.693481) (xy 8.303843 -51.701237) (xy 8.27659 -51.7017)
			(xy 8.248925 -51.701196) (xy 8.194175 -51.693195) (xy 8.141153 -51.677377) (xy 8.090969 -51.654073)
			(xy 8.044674 -51.62377) (xy 8.003236 -51.587104) (xy 7.967523 -51.544841) (xy 7.952486 -51.521614)
			(xy 7.945866 -51.511924) (xy 7.925992 -51.499488) (xy 7.914386 -51.497738) (xy 7.834376 -51.489864)
			(xy 7.822737 -51.489221) (xy 7.800899 -51.497308) (xy 7.792466 -51.505358) (xy 7.792212 -51.505612)
			(xy 7.77411 -51.524172) (xy 7.733782 -51.556752) (xy 7.689412 -51.583567) (xy 7.641818 -51.604124)
			(xy 7.591878 -51.618042) (xy 7.540512 -51.625065) (xy 7.51459 -51.6255) (xy 7.487338 -51.625031)
			(xy 7.433389 -51.617273) (xy 7.381094 -51.601917) (xy 7.331516 -51.579274) (xy 7.285665 -51.549806)
			(xy 7.244475 -51.514112) (xy 7.208784 -51.47292) (xy 7.179318 -51.427068) (xy 7.156677 -51.377489)
			(xy 7.141323 -51.325193) (xy 7.133567 -51.271244) (xy 7.133082 -51.243992) (xy 4.22652 -51.243992)
			(xy 4.226328 -51.254734) (xy 4.218574 -51.308684) (xy 4.20322 -51.360981) (xy 4.18058 -51.410561)
			(xy 4.151115 -51.456414) (xy 4.115423 -51.497606) (xy 4.074233 -51.5333) (xy 4.028382 -51.562769)
			(xy 3.978804 -51.585412) (xy 3.926507 -51.600768) (xy 3.872558 -51.608526) (xy 3.845306 -51.60899)
			(xy 3.826963 -51.60876) (xy 3.79045 -51.605195) (xy 3.772408 -51.601878) (xy 3.761778 -51.60027)
			(xy 3.740858 -51.60515) (xy 3.732022 -51.611276) (xy 3.662934 -51.6636) (xy 3.65252 -51.682396) (xy 3.651758 -51.693318)
			(xy 3.64886 -51.721576) (xy 3.635828 -51.776861) (xy 3.614743 -51.829603) (xy 3.586072 -51.878637)
			(xy 3.550448 -51.922878) (xy 3.508659 -51.961348) (xy 3.461629 -51.993198) (xy 3.410396 -52.017724)
			(xy 3.356093 -52.034383) (xy 3.29992 -52.042806) (xy 3.27152 -52.04333) (xy 3.244149 -52.042869)
			(xy 3.189969 -52.035053) (xy 3.137466 -52.019563) (xy 3.087719 -51.99672) (xy 3.041753 -51.966993)
			(xy 3.020822 -51.94935) (xy 3.020568 -51.949096) (xy 3.013466 -51.943531) (xy 2.996561 -51.937272)
			(xy 2.987548 -51.936904) (xy 2.920492 -51.936904) (xy 2.911475 -51.937256) (xy 2.894558 -51.943507)
			(xy 2.887472 -51.949096) (xy 2.887472 -51.94935) (xy 2.887218 -51.94935) (xy 2.866284 -51.966986)
			(xy 2.820312 -51.9967) (xy 2.770565 -52.019538) (xy 2.718065 -52.035029) (xy 2.663889 -52.042857)
			(xy 2.63652 -52.04333) (xy 2.609269 -52.04284) (xy 2.555321 -52.035084) (xy 2.503027 -52.019729)
			(xy 2.45345 -51.997088) (xy 2.4076 -51.967622) (xy 2.36641 -51.93193) (xy 2.330718 -51.89074) (xy 2.301252 -51.84489)
			(xy 2.278611 -51.795313) (xy 2.263256 -51.743019) (xy 2.2555 -51.689071) (xy 1.987296 -51.689071)
			(xy 1.987296 -52.564103) (xy 3.827227 -52.564103) (xy 3.827227 -52.509597) (xy 3.834984 -52.455646)
			(xy 3.85034 -52.403349) (xy 3.872983 -52.353769) (xy 3.902451 -52.307916) (xy 3.938145 -52.266723)
			(xy 3.979337 -52.23103) (xy 4.02519 -52.201562) (xy 4.074771 -52.17892) (xy 4.127068 -52.163564)
			(xy 4.181019 -52.155807) (xy 4.208272 -52.155344) (xy 4.235642 -52.155816) (xy 4.289821 -52.163631)
			(xy 4.342325 -52.179118) (xy 4.392072 -52.201958) (xy 4.438039 -52.231683) (xy 4.45897 -52.249324)
			(xy 4.459224 -52.249578) (xy 4.466293 -52.25519) (xy 4.483224 -52.261419) (xy 4.492244 -52.26177)
			(xy 4.5593 -52.26177) (xy 4.568318 -52.26142) (xy 4.585235 -52.255168) (xy 4.59232 -52.249578) (xy 4.59232 -52.249324)
			(xy 4.592574 -52.249324) (xy 4.613508 -52.231687) (xy 4.65948 -52.201974) (xy 4.709227 -52.179138)
			(xy 4.761727 -52.163646) (xy 4.815903 -52.155818) (xy 4.843272 -52.155344) (xy 4.870523 -52.155826)
			(xy 4.924471 -52.163583) (xy 4.976766 -52.178938) (xy 5.026343 -52.201579) (xy 5.072194 -52.231046)
			(xy 5.113384 -52.266738) (xy 5.149075 -52.307928) (xy 5.178541 -52.353779) (xy 5.201183 -52.403356)
			(xy 5.216538 -52.455651) (xy 5.224294 -52.509599) (xy 5.224294 -52.555973) (xy 6.583889 -52.555973)
			(xy 6.583889 -52.501467) (xy 6.591646 -52.447517) (xy 6.607002 -52.395219) (xy 6.629645 -52.345639)
			(xy 6.659113 -52.299786) (xy 6.694807 -52.258594) (xy 6.735999 -52.222901) (xy 6.781853 -52.193433)
			(xy 6.831433 -52.170791) (xy 6.88373 -52.155435) (xy 6.937681 -52.147679) (xy 6.964934 -52.147216)
			(xy 6.992305 -52.147658) (xy 7.046485 -52.155481) (xy 7.098989 -52.170976) (xy 7.148735 -52.193823)
			(xy 7.194701 -52.223552) (xy 7.215632 -52.241196) (xy 7.215886 -52.24145) (xy 7.222968 -52.247043)
			(xy 7.239888 -52.253285) (xy 7.248906 -52.253642) (xy 7.315962 -52.253642) (xy 7.324979 -52.253279)
			(xy 7.341896 -52.247037) (xy 7.348982 -52.24145) (xy 7.348982 -52.241196) (xy 7.349236 -52.241196)
			(xy 7.370181 -52.223573) (xy 7.41615 -52.193859) (xy 7.465894 -52.17102) (xy 7.518392 -52.155525)
			(xy 7.572566 -52.147692) (xy 7.599934 -52.147216) (xy 7.627185 -52.147694) (xy 7.681133 -52.155451)
			(xy 7.733428 -52.170807) (xy 7.783005 -52.193448) (xy 7.828856 -52.222915) (xy 7.870046 -52.258607)
			(xy 7.905737 -52.299798) (xy 7.935204 -52.345648) (xy 7.957845 -52.395226) (xy 7.9732 -52.447521)
			(xy 7.980956 -52.501469) (xy 7.980956 -52.555971) (xy 7.9732 -52.609919) (xy 7.957845 -52.662214)
			(xy 7.935204 -52.711792) (xy 7.905737 -52.757642) (xy 7.870046 -52.798833) (xy 7.828856 -52.834525)
			(xy 7.783005 -52.863992) (xy 7.733428 -52.886633) (xy 7.681133 -52.901989) (xy 7.627185 -52.909746)
			(xy 7.599934 -52.910232) (xy 7.572564 -52.909763) (xy 7.518384 -52.901948) (xy 7.46588 -52.886461)
			(xy 7.416133 -52.863619) (xy 7.370167 -52.833894) (xy 7.349236 -52.816252) (xy 7.348982 -52.815998)
			(xy 7.341905 -52.810398) (xy 7.324981 -52.804159) (xy 7.315962 -52.803806) (xy 7.248906 -52.803806)
			(xy 7.239889 -52.804165) (xy 7.222972 -52.810411) (xy 7.215886 -52.815998) (xy 7.215886 -52.816252)
			(xy 7.215632 -52.816252) (xy 7.194693 -52.833882) (xy 7.148723 -52.863597) (xy 7.098977 -52.886435)
			(xy 7.046478 -52.901928) (xy 6.992303 -52.909758) (xy 6.964934 -52.910232) (xy 6.937681 -52.909761)
			(xy 6.88373 -52.902005) (xy 6.831433 -52.886649) (xy 6.781853 -52.864007) (xy 6.735999 -52.834539)
			(xy 6.694807 -52.798846) (xy 6.659113 -52.757654) (xy 6.629645 -52.711801) (xy 6.607002 -52.662221)
			(xy 6.591646 -52.609923) (xy 6.583889 -52.555973) (xy 5.224294 -52.555973) (xy 5.224294 -52.564101)
			(xy 5.216538 -52.618049) (xy 5.201183 -52.670344) (xy 5.178541 -52.719921) (xy 5.149075 -52.765772)
			(xy 5.113384 -52.806962) (xy 5.072194 -52.842654) (xy 5.026343 -52.872121) (xy 4.976766 -52.894762)
			(xy 4.924471 -52.910117) (xy 4.870523 -52.917874) (xy 4.843272 -52.91836) (xy 4.815901 -52.91792)
			(xy 4.76172 -52.910097) (xy 4.709216 -52.894603) (xy 4.65947 -52.871755) (xy 4.613505 -52.842024)
			(xy 4.592574 -52.82438) (xy 4.59232 -52.824126) (xy 4.585238 -52.818533) (xy 4.568317 -52.812292)
			(xy 4.5593 -52.811934) (xy 4.492244 -52.811934) (xy 4.483228 -52.812305) (xy 4.466311 -52.818542)
			(xy 4.459224 -52.824126) (xy 4.459224 -52.82438) (xy 4.45897 -52.82438) (xy 4.43802 -52.841997) (xy 4.392052 -52.871713)
			(xy 4.342309 -52.894553) (xy 4.289813 -52.910049) (xy 4.23564 -52.917883) (xy 4.208272 -52.91836)
			(xy 4.181019 -52.917893) (xy 4.127068 -52.910136) (xy 4.074771 -52.89478) (xy 4.02519 -52.872138)
			(xy 3.979337 -52.84267) (xy 3.938145 -52.806977) (xy 3.902451 -52.765784) (xy 3.872983 -52.719931)
			(xy 3.85034 -52.670351) (xy 3.834984 -52.618054) (xy 3.827227 -52.564103) (xy 1.987296 -52.564103)
			(xy 1.987296 -53.496543) (xy 6.133541 -53.496543) (xy 6.133541 -53.442037) (xy 6.141298 -53.388085)
			(xy 6.156655 -53.335787) (xy 6.179298 -53.286206) (xy 6.208766 -53.240352) (xy 6.24446 -53.199159)
			(xy 6.285654 -53.163465) (xy 6.331508 -53.133997) (xy 6.381088 -53.111354) (xy 6.433387 -53.095998)
			(xy 6.487339 -53.088241) (xy 6.514592 -53.087778) (xy 6.541963 -53.08823) (xy 6.596143 -53.096048)
			(xy 6.648647 -53.111539) (xy 6.698394 -53.134385) (xy 6.74436 -53.164114) (xy 6.76529 -53.181758)
			(xy 6.765544 -53.182012) (xy 6.772641 -53.187583) (xy 6.78955 -53.193839) (xy 6.798564 -53.194204)
			(xy 6.86562 -53.194204) (xy 6.874638 -53.193856) (xy 6.891555 -53.187602) (xy 6.89864 -53.182012)
			(xy 6.89864 -53.181758) (xy 6.898894 -53.181758) (xy 6.919812 -53.164101) (xy 6.965789 -53.134393)
			(xy 7.01554 -53.111561) (xy 7.068044 -53.096074) (xy 7.122222 -53.08825) (xy 7.149592 -53.087778)
			(xy 7.176843 -53.088272) (xy 7.23079 -53.096029) (xy 7.283084 -53.111384) (xy 7.33266 -53.134025)
			(xy 7.37851 -53.163491) (xy 7.419699 -53.199182) (xy 7.45539 -53.240372) (xy 7.484856 -53.286222)
			(xy 7.507497 -53.335798) (xy 7.522852 -53.388092) (xy 7.530608 -53.442039) (xy 7.530608 -53.496541)
			(xy 7.522852 -53.550488) (xy 7.507497 -53.602782) (xy 7.484856 -53.652358) (xy 7.45539 -53.698208)
			(xy 7.419699 -53.739398) (xy 7.37851 -53.775089) (xy 7.33266 -53.804555) (xy 7.283084 -53.827196)
			(xy 7.23079 -53.842551) (xy 7.176843 -53.850308) (xy 7.149592 -53.850794) (xy 7.122222 -53.850334)
			(xy 7.068042 -53.842515) (xy 7.015539 -53.827025) (xy 6.965792 -53.804181) (xy 6.919826 -53.774456)
			(xy 6.898894 -53.756814) (xy 6.89864 -53.75656) (xy 6.89155 -53.750979) (xy 6.874636 -53.74473) (xy 6.86562 -53.744368)
			(xy 6.798564 -53.744368) (xy 6.789546 -53.744715) (xy 6.77263 -53.75097) (xy 6.765544 -53.75656)
			(xy 6.765544 -53.756814) (xy 6.76529 -53.756814) (xy 6.744374 -53.774473) (xy 6.698397 -53.804182)
			(xy 6.648645 -53.827014) (xy 6.596141 -53.8425) (xy 6.541962 -53.850323) (xy 6.514592 -53.850794)
			(xy 6.487339 -53.850339) (xy 6.433387 -53.842582) (xy 6.381088 -53.827226) (xy 6.331508 -53.804583)
			(xy 6.285654 -53.775115) (xy 6.24446 -53.739421) (xy 6.208766 -53.698228) (xy 6.179298 -53.652374)
			(xy 6.156655 -53.602793) (xy 6.141298 -53.550495) (xy 6.133541 -53.496543) (xy 1.987296 -53.496543)
			(xy 1.987296 -54.238906) (xy 8.386062 -54.238906) (xy 8.390133 -54.183284) (xy 8.402259 -54.128847)
			(xy 8.422182 -54.076756) (xy 8.449478 -54.028121) (xy 8.483564 -53.983978) (xy 8.523713 -53.945269)
			(xy 8.569071 -53.912818) (xy 8.618671 -53.887317) (xy 8.671455 -53.86931) (xy 8.726298 -53.85918)
			(xy 8.782032 -53.857143) (xy 8.837469 -53.863243) (xy 8.891426 -53.877349) (xy 8.942755 -53.899161)
			(xy 8.990361 -53.928215) (xy 9.033229 -53.96389) (xy 9.070446 -54.005427) (xy 9.101219 -54.05194)
			(xy 9.124891 -54.102437) (xy 9.140959 -54.155844) (xy 9.149079 -54.21102) (xy 9.149588 -54.238906)
			(xy 9.149079 -54.266792) (xy 9.140959 -54.321968) (xy 9.124891 -54.375375) (xy 9.101219 -54.425872)
			(xy 9.070446 -54.472385) (xy 9.033229 -54.513922) (xy 8.990361 -54.549597) (xy 8.942755 -54.578651)
			(xy 8.891426 -54.600463) (xy 8.837469 -54.614569) (xy 8.782032 -54.620669) (xy 8.726298 -54.618632)
			(xy 8.671455 -54.608502) (xy 8.618671 -54.590495) (xy 8.569071 -54.564994) (xy 8.523713 -54.532543)
			(xy 8.483564 -54.493834) (xy 8.449478 -54.449691) (xy 8.422182 -54.401056) (xy 8.402259 -54.348965)
			(xy 8.390133 -54.294528) (xy 8.386062 -54.238906) (xy 1.987296 -54.238906) (xy 1.987296 -54.989041)
			(xy 3.901168 -54.989041) (xy 3.901168 -54.934539) (xy 3.908924 -54.880592) (xy 3.924279 -54.828297)
			(xy 3.94692 -54.77872) (xy 3.976386 -54.73287) (xy 4.012077 -54.69168) (xy 4.053267 -54.655988) (xy 4.099117 -54.626522)
			(xy 4.148693 -54.603881) (xy 4.200988 -54.588525) (xy 4.254935 -54.580768) (xy 4.282186 -54.580282)
			(xy 4.310277 -54.580788) (xy 4.365854 -54.589013) (xy 4.419622 -54.605302) (xy 4.47042 -54.629303)
			(xy 4.517147 -54.660496) (xy 4.558792 -54.698207) (xy 4.594455 -54.741618) (xy 4.609338 -54.765448)
			(xy 4.614672 -54.774338) (xy 4.63169 -54.78653) (xy 4.724908 -54.80685) (xy 4.745482 -54.802532)
			(xy 4.754118 -54.79669) (xy 4.778175 -54.780679) (xy 4.830109 -54.755339) (xy 4.885269 -54.738117)
			(xy 4.942395 -54.729405) (xy 4.971288 -54.728872) (xy 4.998541 -54.729337) (xy 5.012973 -54.731412)
			(xy 13.520674 -54.731412) (xy 13.521129 -54.704041) (xy 13.528947 -54.649861) (xy 13.544437 -54.597357)
			(xy 13.567282 -54.54761) (xy 13.597011 -54.501645) (xy 13.614654 -54.480714) (xy 13.614908 -54.48046)
			(xy 13.620476 -54.473361) (xy 13.626734 -54.456454) (xy 13.6271 -54.44744) (xy 13.6271 -54.380384)
			(xy 13.626751 -54.371366) (xy 13.620498 -54.35445) (xy 13.614908 -54.347364) (xy 13.614654 -54.347364)
			(xy 13.614654 -54.34711) (xy 13.597024 -54.326168) (xy 13.567297 -54.280203) (xy 13.544449 -54.230458)
			(xy 13.528951 -54.177957) (xy 13.52112 -54.123779) (xy 13.521119 -54.069039) (xy 13.528947 -54.014861)
			(xy 13.544443 -53.962359) (xy 13.567288 -53.912613) (xy 13.597013 -53.866646) (xy 13.614654 -53.845714)
			(xy 13.614908 -53.84546) (xy 13.620476 -53.838361) (xy 13.626734 -53.821454) (xy 13.6271 -53.81244)
			(xy 13.6271 -53.745384) (xy 13.626751 -53.736366) (xy 13.620498 -53.71945) (xy 13.614908 -53.712364)
			(xy 13.614654 -53.712364) (xy 13.614654 -53.71211) (xy 13.597024 -53.691168) (xy 13.567297 -53.645203)
			(xy 13.544449 -53.595458) (xy 13.528951 -53.542957) (xy 13.52112 -53.488779) (xy 13.521119 -53.434039)
			(xy 13.528947 -53.379861) (xy 13.544443 -53.327359) (xy 13.567288 -53.277613) (xy 13.597013 -53.231646)
			(xy 13.614654 -53.210714) (xy 13.614908 -53.21046) (xy 13.620476 -53.203361) (xy 13.626734 -53.186454)
			(xy 13.6271 -53.17744) (xy 13.6271 -53.110384) (xy 13.626751 -53.101366) (xy 13.620498 -53.08445)
			(xy 13.614908 -53.077364) (xy 13.614654 -53.077364) (xy 13.614654 -53.07711) (xy 13.597015 -53.056178)
			(xy 13.567301 -53.010206) (xy 13.544464 -52.960459) (xy 13.528973 -52.907958) (xy 13.521147 -52.853781)
			(xy 13.520674 -52.826412) (xy 13.52116 -52.799161) (xy 13.528916 -52.745213) (xy 13.544271 -52.692918)
			(xy 13.566913 -52.643341) (xy 13.596379 -52.597491) (xy 13.63207 -52.5563) (xy 13.673261 -52.520609)
			(xy 13.719111 -52.491143) (xy 13.768688 -52.468501) (xy 13.820983 -52.453146) (xy 13.874931 -52.44539)
			(xy 13.929433 -52.44539) (xy 13.983381 -52.453146) (xy 14.035676 -52.468501) (xy 14.085253 -52.491143)
			(xy 14.131103 -52.520609) (xy 14.172294 -52.5563) (xy 14.207985 -52.597491) (xy 14.237451 -52.643341)
			(xy 14.260093 -52.692918) (xy 14.275448 -52.745213) (xy 14.283204 -52.799161) (xy 14.28369 -52.826412)
			(xy 14.283233 -52.853783) (xy 14.275414 -52.907962) (xy 14.259922 -52.960466) (xy 14.237079 -53.010212)
			(xy 14.207352 -53.056179) (xy 14.18971 -53.07711) (xy 14.189456 -53.077364) (xy 14.183873 -53.084453)
			(xy 14.177625 -53.101368) (xy 14.177264 -53.110384) (xy 14.177264 -53.17744) (xy 14.17761 -53.186458)
			(xy 14.183866 -53.203374) (xy 14.189456 -53.21046) (xy 14.18971 -53.21046) (xy 14.18971 -53.210714)
			(xy 14.207361 -53.231638) (xy 14.237082 -53.277608) (xy 14.259925 -53.327356) (xy 14.275419 -53.379859)
			(xy 14.283245 -53.434038) (xy 14.283244 -53.48878) (xy 14.275415 -53.542958) (xy 14.259918 -53.595461)
			(xy 14.237074 -53.645208) (xy 14.20735 -53.691177) (xy 14.18971 -53.71211) (xy 14.189456 -53.712364)
			(xy 14.183873 -53.719453) (xy 14.177625 -53.736368) (xy 14.177264 -53.745384) (xy 14.177264 -53.81244)
			(xy 14.17761 -53.821458) (xy 14.183866 -53.838374) (xy 14.189456 -53.84546) (xy 14.18971 -53.84546)
			(xy 14.18971 -53.845714) (xy 14.207361 -53.866638) (xy 14.237082 -53.912608) (xy 14.259925 -53.962356)
			(xy 14.275419 -54.014859) (xy 14.283245 -54.069038) (xy 14.283244 -54.12378) (xy 14.275415 -54.177958)
			(xy 14.259918 -54.230461) (xy 14.237074 -54.280208) (xy 14.20735 -54.326177) (xy 14.18971 -54.34711)
			(xy 14.189456 -54.347364) (xy 14.183873 -54.354453) (xy 14.177625 -54.371368) (xy 14.177264 -54.380384)
			(xy 14.177264 -54.44744) (xy 14.17761 -54.456458) (xy 14.183866 -54.473374) (xy 14.189456 -54.48046)
			(xy 14.18971 -54.48046) (xy 14.18971 -54.480714) (xy 14.207324 -54.501666) (xy 14.237039 -54.547634)
			(xy 14.25988 -54.597376) (xy 14.275377 -54.649872) (xy 14.283212 -54.704044) (xy 14.28369 -54.731412)
			(xy 14.283204 -54.758663) (xy 14.27854 -54.791102) (xy 16.176498 -54.791102) (xy 16.176966 -54.763732)
			(xy 16.184783 -54.709553) (xy 16.200272 -54.65705) (xy 16.223113 -54.607303) (xy 16.252837 -54.561336)
			(xy 16.270478 -54.540404) (xy 16.270732 -54.54015) (xy 16.276307 -54.533056) (xy 16.28256 -54.516145)
			(xy 16.282924 -54.50713) (xy 16.282924 -54.440074) (xy 16.282574 -54.431056) (xy 16.276321 -54.41414)
			(xy 16.270732 -54.407054) (xy 16.270478 -54.407054) (xy 16.270478 -54.4068) (xy 16.252841 -54.385865)
			(xy 16.22312 -54.339896) (xy 16.200278 -54.29015) (xy 16.184783 -54.237649) (xy 16.176956 -54.183471)
			(xy 16.176955 -54.128732) (xy 16.184783 -54.074554) (xy 16.200277 -54.022053) (xy 16.223119 -53.972307)
			(xy 16.252839 -53.926338) (xy 16.270478 -53.905404) (xy 16.270732 -53.90515) (xy 16.276307 -53.898056)
			(xy 16.28256 -53.881145) (xy 16.282924 -53.87213) (xy 16.282924 -53.805074) (xy 16.282574 -53.796056)
			(xy 16.276321 -53.77914) (xy 16.270732 -53.772054) (xy 16.270478 -53.772054) (xy 16.270478 -53.7718)
			(xy 16.252841 -53.750865) (xy 16.22312 -53.704896) (xy 16.200278 -53.65515) (xy 16.184783 -53.602649)
			(xy 16.176956 -53.548471) (xy 16.176955 -53.493732) (xy 16.184783 -53.439554) (xy 16.200277 -53.387053)
			(xy 16.223119 -53.337307) (xy 16.252839 -53.291338) (xy 16.270478 -53.270404) (xy 16.270732 -53.27015)
			(xy 16.276307 -53.263056) (xy 16.28256 -53.246145) (xy 16.282924 -53.23713) (xy 16.282924 -53.170074)
			(xy 16.282574 -53.161056) (xy 16.276321 -53.14414) (xy 16.270732 -53.137054) (xy 16.270478 -53.137054)
			(xy 16.270478 -53.1368) (xy 16.252822 -53.115882) (xy 16.223113 -53.069905) (xy 16.200281 -53.020154)
			(xy 16.184794 -52.96765) (xy 16.17697 -52.913472) (xy 16.176498 -52.886102) (xy 16.176984 -52.858851)
			(xy 16.18474 -52.804903) (xy 16.200095 -52.752608) (xy 16.222737 -52.703031) (xy 16.252203 -52.657181)
			(xy 16.287894 -52.61599) (xy 16.329085 -52.580299) (xy 16.374935 -52.550833) (xy 16.424512 -52.528191)
			(xy 16.476807 -52.512836) (xy 16.530755 -52.50508) (xy 16.585257 -52.50508) (xy 16.639205 -52.512836)
			(xy 16.6915 -52.528191) (xy 16.741077 -52.550833) (xy 16.786927 -52.580299) (xy 16.828118 -52.61599)
			(xy 16.863809 -52.657181) (xy 16.893275 -52.703031) (xy 16.915917 -52.752608) (xy 16.931272 -52.804903)
			(xy 16.939028 -52.858851) (xy 16.939514 -52.886102) (xy 16.939046 -52.913472) (xy 16.931228 -52.967651)
			(xy 16.915739 -53.020154) (xy 16.892898 -53.069901) (xy 16.863175 -53.115868) (xy 16.845534 -53.1368)
			(xy 16.84528 -53.137054) (xy 16.839704 -53.144148) (xy 16.833452 -53.161059) (xy 16.833088 -53.170074)
			(xy 16.833088 -53.23713) (xy 16.833434 -53.246148) (xy 16.839689 -53.263065) (xy 16.84528 -53.27015)
			(xy 16.845534 -53.27015) (xy 16.845534 -53.270404) (xy 16.863178 -53.291334) (xy 16.892906 -53.337302)
			(xy 16.915754 -53.387048) (xy 16.931251 -53.439551) (xy 16.939081 -53.49373) (xy 16.93908 -53.548473)
			(xy 16.931251 -53.602652) (xy 16.915753 -53.655155) (xy 16.892905 -53.704901) (xy 16.863176 -53.750868)
			(xy 16.846604 -53.77053) (xy 17.210786 -53.77053) (xy 17.211293 -53.741612) (xy 17.22002 -53.684439)
			(xy 17.237278 -53.629239) (xy 17.262671 -53.577276) (xy 17.295619 -53.529743) (xy 17.335364 -53.487728)
			(xy 17.357852 -53.46954) (xy 17.36664 -53.461915) (xy 17.376832 -53.441027) (xy 17.37741 -53.429408)
			(xy 17.37741 -53.349652) (xy 17.376881 -53.338019) (xy 17.366685 -53.31711) (xy 17.357852 -53.30952)
			(xy 17.335368 -53.29133) (xy 17.295635 -53.249308) (xy 17.262698 -53.201773) (xy 17.23731 -53.149812)
			(xy 17.220053 -53.094615) (xy 17.211322 -53.037446) (xy 17.210786 -53.00853) (xy 17.211283 -52.981278)
			(xy 17.219036 -52.927329) (xy 17.234388 -52.875032) (xy 17.257026 -52.825452) (xy 17.286491 -52.779599)
			(xy 17.322181 -52.738406) (xy 17.36337 -52.702712) (xy 17.409221 -52.673244) (xy 17.458798 -52.6506)
			(xy 17.511094 -52.635244) (xy 17.565042 -52.627486) (xy 17.592294 -52.627022) (xy 17.618608 -52.627486)
			(xy 17.670737 -52.634721) (xy 17.72138 -52.64904) (xy 17.769579 -52.670173) (xy 17.814423 -52.69772)
			(xy 17.855062 -52.73116) (xy 17.873218 -52.750212) (xy 17.880729 -52.757625) (xy 17.900017 -52.766143)
			(xy 17.910556 -52.766722) (xy 17.985232 -52.766722) (xy 17.995778 -52.766163) (xy 18.015073 -52.757648)
			(xy 18.02257 -52.750212) (xy 18.04075 -52.73118) (xy 18.081374 -52.697721) (xy 18.126209 -52.670158)
			(xy 18.174405 -52.649015) (xy 18.225049 -52.634693) (xy 18.277179 -52.627463) (xy 18.303494 -52.627022)
			(xy 18.330748 -52.627461) (xy 18.384701 -52.635218) (xy 18.437002 -52.650575) (xy 18.486584 -52.673219)
			(xy 18.532438 -52.702689) (xy 18.573632 -52.738385) (xy 18.609326 -52.779581) (xy 18.638793 -52.825437)
			(xy 18.661434 -52.875021) (xy 18.676787 -52.927322) (xy 18.684541 -52.981276) (xy 18.685002 -53.00853)
			(xy 18.684512 -53.036196) (xy 18.676509 -53.090946) (xy 18.660688 -53.143968) (xy 18.637381 -53.194152)
			(xy 18.607077 -53.240448) (xy 18.570409 -53.281885) (xy 18.528144 -53.317597) (xy 18.504916 -53.332634)
			(xy 18.495219 -53.339246) (xy 18.482787 -53.359126) (xy 18.48104 -53.370734) (xy 18.473166 -53.450744)
			(xy 18.47251 -53.462383) (xy 18.480606 -53.484222) (xy 18.48866 -53.492654) (xy 18.488914 -53.492908)
			(xy 18.507484 -53.511) (xy 18.540063 -53.55133) (xy 18.566877 -53.595702) (xy 18.587432 -53.643298)
			(xy 18.601348 -53.69324) (xy 18.608368 -53.744608) (xy 18.608802 -53.77053) (xy 18.60835 -53.797782)
			(xy 18.600589 -53.851732) (xy 18.58523 -53.904027) (xy 18.562585 -53.953605) (xy 18.533115 -53.999456)
			(xy 18.49742 -54.040646) (xy 18.456227 -54.076337) (xy 18.410373 -54.105802) (xy 18.360793 -54.128443)
			(xy 18.308496 -54.143797) (xy 18.254546 -54.151553) (xy 18.227294 -54.152038) (xy 18.199923 -54.151591)
			(xy 18.145742 -54.143771) (xy 18.093239 -54.128278) (xy 18.043492 -54.105432) (xy 17.997526 -54.075702)
			(xy 17.976596 -54.058058) (xy 17.976342 -54.057804) (xy 17.969247 -54.052229) (xy 17.952337 -54.045975)
			(xy 17.943322 -54.045612) (xy 17.876266 -54.045612) (xy 17.867247 -54.04595) (xy 17.85033 -54.052211)
			(xy 17.843246 -54.057804) (xy 17.843246 -54.058058) (xy 17.842992 -54.058058) (xy 17.822068 -54.075708)
			(xy 17.776094 -54.105419) (xy 17.726344 -54.128254) (xy 17.673842 -54.143742) (xy 17.619664 -54.151567)
			(xy 17.592294 -54.152038) (xy 17.565044 -54.151528) (xy 17.511099 -54.143771) (xy 17.458806 -54.128417)
			(xy 17.409231 -54.105777) (xy 17.363382 -54.076313) (xy 17.322193 -54.040624) (xy 17.286501 -53.999437)
			(xy 17.257034 -53.95359) (xy 17.234391 -53.904016) (xy 17.219034 -53.851725) (xy 17.211274 -53.79778)
			(xy 17.210786 -53.77053) (xy 16.846604 -53.77053) (xy 16.845534 -53.7718) (xy 16.84528 -53.772054)
			(xy 16.839704 -53.779148) (xy 16.833452 -53.796059) (xy 16.833088 -53.805074) (xy 16.833088 -53.87213)
			(xy 16.833434 -53.881148) (xy 16.839689 -53.898065) (xy 16.84528 -53.90515) (xy 16.845534 -53.90515)
			(xy 16.845534 -53.905404) (xy 16.863178 -53.926334) (xy 16.892906 -53.972302) (xy 16.915754 -54.022048)
			(xy 16.931251 -54.074551) (xy 16.939081 -54.12873) (xy 16.93908 -54.183473) (xy 16.931251 -54.237652)
			(xy 16.915753 -54.290155) (xy 16.892905 -54.339901) (xy 16.863176 -54.385868) (xy 16.845534 -54.4068)
			(xy 16.84528 -54.407054) (xy 16.839704 -54.414148) (xy 16.833452 -54.431059) (xy 16.833088 -54.440074)
			(xy 16.833088 -54.50713) (xy 16.833434 -54.516148) (xy 16.839689 -54.533065) (xy 16.84528 -54.54015)
			(xy 16.845534 -54.54015) (xy 16.845534 -54.540404) (xy 16.863194 -54.561319) (xy 16.892901 -54.607297)
			(xy 16.915733 -54.657049) (xy 16.931219 -54.709553) (xy 16.939042 -54.763732) (xy 16.939514 -54.791102)
			(xy 16.939028 -54.818353) (xy 16.931272 -54.872301) (xy 16.915917 -54.924596) (xy 16.893275 -54.974173)
			(xy 16.863809 -55.020023) (xy 16.828118 -55.061214) (xy 16.786927 -55.096905) (xy 16.741077 -55.126371)
			(xy 16.6915 -55.149013) (xy 16.639205 -55.164368) (xy 16.585257 -55.172124) (xy 16.530755 -55.172124)
			(xy 16.476807 -55.164368) (xy 16.424512 -55.149013) (xy 16.374935 -55.126371) (xy 16.329085 -55.096905)
			(xy 16.287894 -55.061214) (xy 16.252203 -55.020023) (xy 16.222737 -54.974173) (xy 16.200095 -54.924596)
			(xy 16.18474 -54.872301) (xy 16.176984 -54.818353) (xy 16.176498 -54.791102) (xy 14.27854 -54.791102)
			(xy 14.275448 -54.812611) (xy 14.260093 -54.864906) (xy 14.237451 -54.914483) (xy 14.207985 -54.960333)
			(xy 14.172294 -55.001524) (xy 14.131103 -55.037215) (xy 14.085253 -55.066681) (xy 14.035676 -55.089323)
			(xy 13.983381 -55.104678) (xy 13.929433 -55.112434) (xy 13.874931 -55.112434) (xy 13.820983 -55.104678)
			(xy 13.768688 -55.089323) (xy 13.719111 -55.066681) (xy 13.673261 -55.037215) (xy 13.63207 -55.001524)
			(xy 13.596379 -54.960333) (xy 13.566913 -54.914483) (xy 13.544271 -54.864906) (xy 13.528916 -54.812611)
			(xy 13.52116 -54.758663) (xy 13.520674 -54.731412) (xy 5.012973 -54.731412) (xy 5.052492 -54.737094)
			(xy 5.104789 -54.75245) (xy 5.15437 -54.775092) (xy 5.200223 -54.80456) (xy 5.241415 -54.840253)
			(xy 5.277109 -54.881446) (xy 5.306577 -54.927299) (xy 5.32922 -54.976879) (xy 5.344576 -55.029176)
			(xy 5.352333 -55.083127) (xy 5.352796 -55.11038) (xy 5.352319 -55.13775) (xy 5.344504 -55.191929)
			(xy 5.329018 -55.244432) (xy 5.306178 -55.294179) (xy 5.276456 -55.340146) (xy 5.258816 -55.361078)
			(xy 5.258562 -55.361332) (xy 5.252994 -55.368431) (xy 5.246737 -55.385338) (xy 5.24637 -55.394352)
			(xy 5.24637 -55.461408) (xy 5.24673 -55.470424) (xy 5.252976 -55.487341) (xy 5.258562 -55.494428)
			(xy 5.258816 -55.494428) (xy 5.258816 -55.494682) (xy 5.276457 -55.515615) (xy 5.306181 -55.561583)
			(xy 5.329026 -55.611329) (xy 5.344522 -55.663831) (xy 5.352351 -55.718009) (xy 5.352351 -55.772751)
			(xy 5.344522 -55.826929) (xy 5.329026 -55.879431) (xy 5.306181 -55.929177) (xy 5.276457 -55.975145)
			(xy 5.258816 -55.996078) (xy 5.258562 -55.996332) (xy 5.252994 -56.003431) (xy 5.246737 -56.020338)
			(xy 5.24637 -56.029352) (xy 5.24637 -56.096408) (xy 5.24673 -56.105424) (xy 5.252976 -56.122341)
			(xy 5.258562 -56.129428) (xy 5.258816 -56.129428) (xy 5.258816 -56.129682) (xy 5.276463 -56.150608)
			(xy 5.306173 -56.196583) (xy 5.329007 -56.246332) (xy 5.344496 -56.298834) (xy 5.352323 -56.35301)
			(xy 5.352796 -56.38038) (xy 5.35231 -56.407631) (xy 5.344554 -56.461579) (xy 5.329199 -56.513874)
			(xy 5.306557 -56.563451) (xy 5.277091 -56.609301) (xy 5.2414 -56.650492) (xy 5.200209 -56.686183)
			(xy 5.154359 -56.715649) (xy 5.104782 -56.738291) (xy 5.052487 -56.753646) (xy 4.998539 -56.761402)
			(xy 4.944037 -56.761402) (xy 4.890089 -56.753646) (xy 4.837794 -56.738291) (xy 4.788217 -56.715649)
			(xy 4.742367 -56.686183) (xy 4.701176 -56.650492) (xy 4.665485 -56.609301) (xy 4.636019 -56.563451)
			(xy 4.613377 -56.513874) (xy 4.598022 -56.461579) (xy 4.590266 -56.407631) (xy 4.58978 -56.38038)
			(xy 4.590215 -56.353008) (xy 4.598037 -56.298827) (xy 4.613533 -56.246323) (xy 4.636382 -56.196577)
			(xy 4.666114 -56.150612) (xy 4.68376 -56.129682) (xy 4.684014 -56.129428) (xy 4.689597 -56.122339)
			(xy 4.695845 -56.105424) (xy 4.696206 -56.096408) (xy 4.696206 -56.029352) (xy 4.695823 -56.020338)
			(xy 4.689593 -56.003421) (xy 4.684014 -55.996332) (xy 4.68376 -55.996332) (xy 4.68376 -55.996078)
			(xy 4.666119 -55.975145) (xy 4.636394 -55.929178) (xy 4.613549 -55.879431) (xy 4.598052 -55.826929)
			(xy 4.590224 -55.772751) (xy 4.590224 -55.718009) (xy 4.598052 -55.663831) (xy 4.613549 -55.611329)
			(xy 4.636394 -55.561582) (xy 4.666119 -55.515615) (xy 4.68376 -55.494682) (xy 4.684014 -55.494428)
			(xy 4.689597 -55.487339) (xy 4.695845 -55.470424) (xy 4.696206 -55.461408) (xy 4.696206 -55.394352)
			(xy 4.695823 -55.385338) (xy 4.689593 -55.368421) (xy 4.684014 -55.361332) (xy 4.68376 -55.360824)
			(xy 4.672814 -55.348091) (xy 4.652974 -55.320999) (xy 4.644136 -55.306722) (xy 4.638802 -55.297832)
			(xy 4.621784 -55.28564) (xy 4.528566 -55.26532) (xy 4.507992 -55.269638) (xy 4.499356 -55.27548)
			(xy 4.475304 -55.291499) (xy 4.423368 -55.316838) (xy 4.368207 -55.334058) (xy 4.31108 -55.342767)
			(xy 4.282186 -55.343298) (xy 4.254935 -55.342812) (xy 4.200988 -55.335055) (xy 4.148693 -55.319699)
			(xy 4.099117 -55.297058) (xy 4.053267 -55.267592) (xy 4.012077 -55.2319) (xy 3.976386 -55.19071)
			(xy 3.94692 -55.14486) (xy 3.924279 -55.095283) (xy 3.908924 -55.042988) (xy 3.901168 -54.989041)
			(xy 1.987296 -54.989041) (xy 1.987296 -55.420841) (xy 2.224768 -55.420841) (xy 2.224768 -55.366339)
			(xy 2.232524 -55.312392) (xy 2.247879 -55.260097) (xy 2.27052 -55.21052) (xy 2.299986 -55.16467)
			(xy 2.335677 -55.12348) (xy 2.376867 -55.087788) (xy 2.422717 -55.058322) (xy 2.472293 -55.035681)
			(xy 2.524588 -55.020325) (xy 2.578535 -55.012568) (xy 2.605786 -55.012082) (xy 2.632099 -55.012565)
			(xy 2.684227 -55.019797) (xy 2.734869 -55.034114) (xy 2.783068 -55.055243) (xy 2.827912 -55.082786)
			(xy 2.868553 -55.116222) (xy 2.88671 -55.135272) (xy 2.89423 -55.142676) (xy 2.913511 -55.1512) (xy 2.924048 -55.151782)
			(xy 2.998724 -55.151782) (xy 3.009271 -55.151231) (xy 3.028567 -55.142712) (xy 3.036062 -55.135272)
			(xy 3.054189 -55.116188) (xy 3.094825 -55.082735) (xy 3.139672 -55.05518) (xy 3.187878 -55.034047)
			(xy 3.23853 -55.019735) (xy 3.290668 -55.012517) (xy 3.316986 -55.012082) (xy 3.344239 -55.012545)
			(xy 3.39819 -55.020302) (xy 3.450489 -55.035657) (xy 3.500069 -55.0583) (xy 3.545923 -55.087767)
			(xy 3.587116 -55.123461) (xy 3.62281 -55.164654) (xy 3.652279 -55.210507) (xy 3.674921 -55.260088)
			(xy 3.690278 -55.312386) (xy 3.698035 -55.366337) (xy 3.698035 -55.420843) (xy 3.690278 -55.474794)
			(xy 3.674921 -55.527092) (xy 3.652279 -55.576673) (xy 3.62281 -55.622526) (xy 3.587116 -55.663719)
			(xy 3.545923 -55.699413) (xy 3.500069 -55.72888) (xy 3.450489 -55.751523) (xy 3.39819 -55.766878)
			(xy 3.344239 -55.774635) (xy 3.316986 -55.775098) (xy 3.290672 -55.774641) (xy 3.238543 -55.767404)
			(xy 3.1879 -55.753083) (xy 3.139701 -55.731948) (xy 3.094858 -55.704401) (xy 3.054218 -55.67096)
			(xy 3.036062 -55.651908) (xy 3.028555 -55.644489) (xy 3.009264 -55.635974) (xy 2.998724 -55.635398)
			(xy 2.924048 -55.635398) (xy 2.9135 -55.63594) (xy 2.894204 -55.644466) (xy 2.88671 -55.651908) (xy 2.868544 -55.670953)
			(xy 2.827916 -55.704411) (xy 2.783078 -55.731971) (xy 2.73488 -55.753111) (xy 2.684234 -55.767431)
			(xy 2.632102 -55.774658) (xy 2.605786 -55.775098) (xy 2.578535 -55.774612) (xy 2.524588 -55.766855)
			(xy 2.472293 -55.751499) (xy 2.422717 -55.728858) (xy 2.376867 -55.699392) (xy 2.335677 -55.6637)
			(xy 2.299986 -55.62251) (xy 2.27052 -55.57666) (xy 2.247879 -55.527083) (xy 2.232524 -55.474788)
			(xy 2.224768 -55.420841) (xy 1.987296 -55.420841) (xy 1.987296 -57.48528) (xy 4.606034 -57.48528)
			(xy 4.610105 -57.429658) (xy 4.622231 -57.375221) (xy 4.642154 -57.32313) (xy 4.66945 -57.274495)
			(xy 4.703536 -57.230352) (xy 4.743685 -57.191643) (xy 4.789043 -57.159192) (xy 4.838643 -57.133691)
			(xy 4.891427 -57.115684) (xy 4.94627 -57.105554) (xy 5.002004 -57.103517) (xy 5.057441 -57.109617)
			(xy 5.111398 -57.123723) (xy 5.162727 -57.145535) (xy 5.210333 -57.174589) (xy 5.253201 -57.210264)
			(xy 5.290418 -57.251801) (xy 5.321191 -57.298314) (xy 5.344863 -57.348811) (xy 5.360931 -57.402218)
			(xy 5.369051 -57.457394) (xy 5.36956 -57.48528) (xy 5.369051 -57.513166) (xy 5.360931 -57.568342)
			(xy 5.344863 -57.621749) (xy 5.321191 -57.672246) (xy 5.290418 -57.718759) (xy 5.253201 -57.760296)
			(xy 5.210333 -57.795971) (xy 5.162727 -57.825025) (xy 5.111398 -57.846837) (xy 5.057441 -57.860943)
			(xy 5.002004 -57.867043) (xy 4.94627 -57.865006) (xy 4.891427 -57.854876) (xy 4.838643 -57.836869)
			(xy 4.789043 -57.811368) (xy 4.743685 -57.778917) (xy 4.703536 -57.740208) (xy 4.66945 -57.696065)
			(xy 4.642154 -57.64743) (xy 4.622231 -57.595339) (xy 4.610105 -57.540902) (xy 4.606034 -57.48528)
			(xy 1.987296 -57.48528) (xy 1.987296 -58.076084) (xy 5.358128 -58.076084) (xy 5.362199 -58.020462)
			(xy 5.374325 -57.966025) (xy 5.394248 -57.913934) (xy 5.421544 -57.865299) (xy 5.45563 -57.821156)
			(xy 5.495779 -57.782447) (xy 5.541137 -57.749996) (xy 5.590737 -57.724495) (xy 5.643521 -57.706488)
			(xy 5.698364 -57.696358) (xy 5.754098 -57.694321) (xy 5.809535 -57.700421) (xy 5.863492 -57.714527)
			(xy 5.914821 -57.736339) (xy 5.962427 -57.765393) (xy 6.005295 -57.801068) (xy 6.042512 -57.842605)
			(xy 6.058848 -57.867296) (xy 7.643112 -57.867296) (xy 7.647183 -57.811674) (xy 7.659309 -57.757237)
			(xy 7.679232 -57.705146) (xy 7.706528 -57.656511) (xy 7.740614 -57.612368) (xy 7.780763 -57.573659)
			(xy 7.826121 -57.541208) (xy 7.875721 -57.515707) (xy 7.928505 -57.4977) (xy 7.983348 -57.48757)
			(xy 8.039082 -57.485533) (xy 8.094519 -57.491633) (xy 8.148476 -57.505739) (xy 8.199805 -57.527551)
			(xy 8.247411 -57.556605) (xy 8.290279 -57.59228) (xy 8.327496 -57.633817) (xy 8.358269 -57.68033)
			(xy 8.381941 -57.730827) (xy 8.398009 -57.784234) (xy 8.406129 -57.83941) (xy 8.406638 -57.867296)
			(xy 8.406129 -57.895182) (xy 8.398009 -57.950358) (xy 8.381941 -58.003765) (xy 8.358269 -58.054262)
			(xy 8.327496 -58.100775) (xy 8.290279 -58.142312) (xy 8.247411 -58.177987) (xy 8.199805 -58.207041)
			(xy 8.148476 -58.228853) (xy 8.094519 -58.242959) (xy 8.039082 -58.249059) (xy 7.983348 -58.247022)
			(xy 7.928505 -58.236892) (xy 7.875721 -58.218885) (xy 7.826121 -58.193384) (xy 7.780763 -58.160933)
			(xy 7.740614 -58.122224) (xy 7.706528 -58.078081) (xy 7.679232 -58.029446) (xy 7.659309 -57.977355)
			(xy 7.647183 -57.922918) (xy 7.643112 -57.867296) (xy 6.058848 -57.867296) (xy 6.073285 -57.889118)
			(xy 6.096957 -57.939615) (xy 6.113025 -57.993022) (xy 6.121145 -58.048198) (xy 6.121654 -58.076084)
			(xy 6.121145 -58.10397) (xy 6.113025 -58.159146) (xy 6.096957 -58.212553) (xy 6.073285 -58.26305)
			(xy 6.042512 -58.309563) (xy 6.005295 -58.3511) (xy 5.962427 -58.386775) (xy 5.914821 -58.415829)
			(xy 5.863492 -58.437641) (xy 5.809535 -58.451747) (xy 5.754098 -58.457847) (xy 5.698364 -58.45581)
			(xy 5.643521 -58.44568) (xy 5.590737 -58.427673) (xy 5.541137 -58.402172) (xy 5.495779 -58.369721)
			(xy 5.45563 -58.331012) (xy 5.421544 -58.286869) (xy 5.394248 -58.238234) (xy 5.374325 -58.186143)
			(xy 5.362199 -58.131706) (xy 5.358128 -58.076084) (xy 1.987296 -58.076084) (xy 1.987296 -58.561224)
			(xy 6.562342 -58.561224) (xy 6.566413 -58.505602) (xy 6.578539 -58.451165) (xy 6.598462 -58.399074)
			(xy 6.625758 -58.350439) (xy 6.659844 -58.306296) (xy 6.699993 -58.267587) (xy 6.745351 -58.235136)
			(xy 6.794951 -58.209635) (xy 6.847735 -58.191628) (xy 6.902578 -58.181498) (xy 6.958312 -58.179461)
			(xy 7.013749 -58.185561) (xy 7.067706 -58.199667) (xy 7.119035 -58.221479) (xy 7.166641 -58.250533)
			(xy 7.209509 -58.286208) (xy 7.246726 -58.327745) (xy 7.277499 -58.374258) (xy 7.301171 -58.424755)
			(xy 7.308681 -58.449718) (xy 8.808972 -58.449718) (xy 8.813043 -58.394096) (xy 8.825169 -58.339659)
			(xy 8.845092 -58.287568) (xy 8.872388 -58.238933) (xy 8.906474 -58.19479) (xy 8.946623 -58.156081)
			(xy 8.991981 -58.12363) (xy 9.041581 -58.098129) (xy 9.094365 -58.080122) (xy 9.149208 -58.069992)
			(xy 9.204942 -58.067955) (xy 9.260379 -58.074055) (xy 9.314336 -58.088161) (xy 9.365665 -58.109973)
			(xy 9.413271 -58.139027) (xy 9.456139 -58.174702) (xy 9.493356 -58.216239) (xy 9.524129 -58.262752)
			(xy 9.547801 -58.313249) (xy 9.563869 -58.366656) (xy 9.571989 -58.421832) (xy 9.572498 -58.449718)
			(xy 9.571989 -58.477604) (xy 9.563869 -58.53278) (xy 9.547801 -58.586187) (xy 9.524129 -58.636684)
			(xy 9.493356 -58.683197) (xy 9.456139 -58.724734) (xy 9.448124 -58.731404) (xy 13.520674 -58.731404)
			(xy 13.521124 -58.704033) (xy 13.528943 -58.649853) (xy 13.544435 -58.597349) (xy 13.567281 -58.547602)
			(xy 13.59701 -58.501636) (xy 13.614654 -58.480706) (xy 13.614908 -58.480452) (xy 13.62048 -58.473355)
			(xy 13.626735 -58.456446) (xy 13.6271 -58.447432) (xy 13.6271 -58.380376) (xy 13.626754 -58.371358)
			(xy 13.620499 -58.354441) (xy 13.614908 -58.347356) (xy 13.614654 -58.347356) (xy 13.614654 -58.347102)
			(xy 13.597016 -58.326167) (xy 13.567289 -58.2802) (xy 13.544442 -58.230454) (xy 13.528944 -58.177952)
			(xy 13.521115 -58.123774) (xy 13.521114 -58.069032) (xy 13.528943 -58.014853) (xy 13.54444 -57.962351)
			(xy 13.567286 -57.912605) (xy 13.597012 -57.866638) (xy 13.614654 -57.845706) (xy 13.614908 -57.845452)
			(xy 13.62048 -57.838355) (xy 13.626735 -57.821446) (xy 13.6271 -57.812432) (xy 13.6271 -57.745376)
			(xy 13.626754 -57.736358) (xy 13.620499 -57.719441) (xy 13.614908 -57.712356) (xy 13.614654 -57.712356)
			(xy 13.614654 -57.712102) (xy 13.597016 -57.691167) (xy 13.567289 -57.6452) (xy 13.544442 -57.595454)
			(xy 13.528944 -57.542952) (xy 13.521115 -57.488774) (xy 13.521114 -57.434032) (xy 13.528943 -57.379853)
			(xy 13.54444 -57.327351) (xy 13.567286 -57.277605) (xy 13.597012 -57.231638) (xy 13.614654 -57.210706)
			(xy 13.614908 -57.210452) (xy 13.62048 -57.203355) (xy 13.626735 -57.186446) (xy 13.6271 -57.177432)
			(xy 13.6271 -57.110376) (xy 13.626754 -57.101358) (xy 13.620499 -57.084441) (xy 13.614908 -57.077356)
			(xy 13.614654 -57.077356) (xy 13.614654 -57.077102) (xy 13.597011 -57.056173) (xy 13.567298 -57.0102)
			(xy 13.544462 -56.960452) (xy 13.528972 -56.90795) (xy 13.521146 -56.853774) (xy 13.520674 -56.826404)
			(xy 13.52116 -56.799153) (xy 13.528916 -56.745205) (xy 13.544271 -56.69291) (xy 13.566913 -56.643333)
			(xy 13.596379 -56.597483) (xy 13.63207 -56.556292) (xy 13.673261 -56.520601) (xy 13.719111 -56.491135)
			(xy 13.768688 -56.468493) (xy 13.820983 -56.453138) (xy 13.874931 -56.445382) (xy 13.929433 -56.445382)
			(xy 13.983381 -56.453138) (xy 14.035676 -56.468493) (xy 14.085253 -56.491135) (xy 14.131103 -56.520601)
			(xy 14.172294 -56.556292) (xy 14.207985 -56.597483) (xy 14.237451 -56.643333) (xy 14.260093 -56.69291)
			(xy 14.275448 -56.745205) (xy 14.283204 -56.799153) (xy 14.28369 -56.826404) (xy 14.283229 -56.853774)
			(xy 14.27541 -56.907954) (xy 14.25992 -56.960457) (xy 14.237077 -57.010204) (xy 14.207352 -57.05617)
			(xy 14.18971 -57.077102) (xy 14.189456 -57.077356) (xy 14.183876 -57.084447) (xy 14.177627 -57.101361)
			(xy 14.177264 -57.110376) (xy 14.177264 -57.177432) (xy 14.177613 -57.186449) (xy 14.183867 -57.203366)
			(xy 14.189456 -57.210452) (xy 14.18971 -57.210452) (xy 14.18971 -57.210706) (xy 14.207353 -57.231636)
			(xy 14.237075 -57.277605) (xy 14.259918 -57.327352) (xy 14.275412 -57.379854) (xy 14.28324 -57.434033)
			(xy 14.283239 -57.488773) (xy 14.275411 -57.542951) (xy 14.259916 -57.595453) (xy 14.237072 -57.6452)
			(xy 14.207349 -57.691169) (xy 14.18971 -57.712102) (xy 14.189456 -57.712356) (xy 14.183876 -57.719447)
			(xy 14.177627 -57.736361) (xy 14.177264 -57.745376) (xy 14.177264 -57.812432) (xy 14.177613 -57.821449)
			(xy 14.183867 -57.838366) (xy 14.189456 -57.845452) (xy 14.18971 -57.845452) (xy 14.18971 -57.845706)
			(xy 14.207353 -57.866636) (xy 14.237075 -57.912605) (xy 14.259918 -57.962352) (xy 14.275412 -58.014854)
			(xy 14.28324 -58.069033) (xy 14.283239 -58.123773) (xy 14.275411 -58.177951) (xy 14.259916 -58.230453)
			(xy 14.237072 -58.2802) (xy 14.207349 -58.326169) (xy 14.18971 -58.347102) (xy 14.189456 -58.347356)
			(xy 14.183876 -58.354447) (xy 14.177627 -58.371361) (xy 14.177264 -58.380376) (xy 14.177264 -58.447432)
			(xy 14.177613 -58.456449) (xy 14.183867 -58.473366) (xy 14.189456 -58.480452) (xy 14.18971 -58.480452)
			(xy 14.18971 -58.480706) (xy 14.207367 -58.501624) (xy 14.237076 -58.547601) (xy 14.259908 -58.597352)
			(xy 14.275395 -58.649856) (xy 14.283218 -58.704034) (xy 14.28369 -58.731404) (xy 14.283204 -58.758655)
			(xy 14.27854 -58.791094) (xy 16.176498 -58.791094) (xy 16.176961 -58.763724) (xy 16.18478 -58.709544)
			(xy 16.200269 -58.657041) (xy 16.223112 -58.607295) (xy 16.252837 -58.561328) (xy 16.270478 -58.540396)
			(xy 16.270732 -58.540142) (xy 16.276311 -58.53305) (xy 16.282561 -58.516137) (xy 16.282924 -58.507122)
			(xy 16.282924 -58.440066) (xy 16.282578 -58.431048) (xy 16.276322 -58.414131) (xy 16.270732 -58.407046)
			(xy 16.270478 -58.407046) (xy 16.270478 -58.406792) (xy 16.252833 -58.385863) (xy 16.223113 -58.339893)
			(xy 16.200271 -58.290146) (xy 16.184777 -58.237644) (xy 16.17695 -58.183466) (xy 16.176951 -58.128725)
			(xy 16.184779 -58.074547) (xy 16.200274 -58.022045) (xy 16.223117 -57.972299) (xy 16.252839 -57.92633)
			(xy 16.270478 -57.905396) (xy 16.270732 -57.905142) (xy 16.276311 -57.89805) (xy 16.282561 -57.881137)
			(xy 16.282924 -57.872122) (xy 16.282924 -57.805066) (xy 16.282578 -57.796048) (xy 16.276322 -57.779131)
			(xy 16.270732 -57.772046) (xy 16.270478 -57.772046) (xy 16.270478 -57.771792) (xy 16.252818 -57.750877)
			(xy 16.22311 -57.704899) (xy 16.200279 -57.655147) (xy 16.184792 -57.602643) (xy 16.176969 -57.548464)
			(xy 16.176498 -57.521094) (xy 16.176962 -57.49478) (xy 16.184198 -57.442651) (xy 16.198517 -57.392009)
			(xy 16.219651 -57.34381) (xy 16.247197 -57.298966) (xy 16.280636 -57.258327) (xy 16.299688 -57.24017)
			(xy 16.307103 -57.23266) (xy 16.31562 -57.213371) (xy 16.316198 -57.202832) (xy 16.316198 -57.128156)
			(xy 16.315653 -57.117608) (xy 16.307129 -57.098312) (xy 16.299688 -57.090818) (xy 16.280646 -57.072649)
			(xy 16.247188 -57.032022) (xy 16.219627 -56.987184) (xy 16.198487 -56.938986) (xy 16.184167 -56.888341)
			(xy 16.176938 -56.836209) (xy 16.176498 -56.809894) (xy 16.176984 -56.782643) (xy 16.18474 -56.728695)
			(xy 16.200095 -56.6764) (xy 16.222737 -56.626823) (xy 16.252203 -56.580973) (xy 16.287894 -56.539782)
			(xy 16.329085 -56.504091) (xy 16.374935 -56.474625) (xy 16.424512 -56.451983) (xy 16.476807 -56.436628)
			(xy 16.530755 -56.428872) (xy 16.585257 -56.428872) (xy 16.639205 -56.436628) (xy 16.6915 -56.451983)
			(xy 16.741077 -56.474625) (xy 16.786927 -56.504091) (xy 16.828118 -56.539782) (xy 16.863809 -56.580973)
			(xy 16.893275 -56.626823) (xy 16.915917 -56.6764) (xy 16.931272 -56.728695) (xy 16.939028 -56.782643)
			(xy 16.939514 -56.809894) (xy 16.939038 -56.836208) (xy 16.931804 -56.888336) (xy 16.917487 -56.938978)
			(xy 16.896356 -56.987177) (xy 16.868811 -57.032021) (xy 16.835375 -57.072661) (xy 16.816324 -57.090818)
			(xy 16.808916 -57.098334) (xy 16.800394 -57.117618) (xy 16.799814 -57.128156) (xy 16.799814 -57.202832)
			(xy 16.800362 -57.21338) (xy 16.808884 -57.232675) (xy 16.816324 -57.24017) (xy 16.835363 -57.258343)
			(xy 16.86882 -57.298969) (xy 16.896381 -57.343806) (xy 16.917522 -57.392003) (xy 16.931843 -57.442648)
			(xy 16.935227 -57.467049) (xy 17.118592 -57.467049) (xy 17.118592 -57.412551) (xy 17.126348 -57.358606)
			(xy 17.141702 -57.306315) (xy 17.164341 -57.25674) (xy 17.193805 -57.210893) (xy 17.229493 -57.169704)
			(xy 17.27068 -57.134014) (xy 17.316526 -57.104549) (xy 17.3661 -57.081907) (xy 17.418391 -57.066551)
			(xy 17.472335 -57.058793) (xy 17.499584 -57.058306) (xy 17.525898 -57.058782) (xy 17.578026 -57.066015)
			(xy 17.628669 -57.080332) (xy 17.676868 -57.101463) (xy 17.721711 -57.129008) (xy 17.762351 -57.162445)
			(xy 17.780508 -57.181496) (xy 17.788025 -57.188902) (xy 17.807309 -57.197424) (xy 17.817846 -57.198006)
			(xy 17.892522 -57.198006) (xy 17.903068 -57.197446) (xy 17.922364 -57.188932) (xy 17.92986 -57.181496)
			(xy 17.947993 -57.162418) (xy 17.988627 -57.128963) (xy 18.033472 -57.101407) (xy 18.081678 -57.080272)
			(xy 18.132329 -57.06596) (xy 18.184467 -57.058741) (xy 18.210784 -57.058306) (xy 18.238039 -57.05874)
			(xy 18.291993 -57.066495) (xy 18.344295 -57.08185) (xy 18.393879 -57.104493) (xy 18.439736 -57.133962)
			(xy 18.480932 -57.169657) (xy 18.516629 -57.210851) (xy 18.546099 -57.256707) (xy 18.568744 -57.30629)
			(xy 18.584101 -57.358591) (xy 18.591859 -57.412545) (xy 18.591859 -57.467055) (xy 18.584101 -57.521009)
			(xy 18.568744 -57.57331) (xy 18.546099 -57.622893) (xy 18.516629 -57.668749) (xy 18.480932 -57.709943)
			(xy 18.439736 -57.745638) (xy 18.393879 -57.775107) (xy 18.344295 -57.79775) (xy 18.291993 -57.813105)
			(xy 18.238039 -57.82086) (xy 18.210784 -57.821322) (xy 18.18447 -57.820858) (xy 18.132342 -57.813622)
			(xy 18.081699 -57.799301) (xy 18.0335 -57.778168) (xy 17.988657 -57.750622) (xy 17.948017 -57.717183)
			(xy 17.92986 -57.698132) (xy 17.922351 -57.690715) (xy 17.903062 -57.682198) (xy 17.892522 -57.681622)
			(xy 17.817846 -57.681622) (xy 17.807297 -57.682156) (xy 17.788001 -57.690687) (xy 17.780508 -57.698132)
			(xy 17.762348 -57.717183) (xy 17.721718 -57.750639) (xy 17.676879 -57.778198) (xy 17.628679 -57.799337)
			(xy 17.578033 -57.813656) (xy 17.5259 -57.820882) (xy 17.499584 -57.821322) (xy 17.472335 -57.820807)
			(xy 17.418391 -57.813049) (xy 17.3661 -57.797693) (xy 17.316526 -57.775051) (xy 17.27068 -57.745586)
			(xy 17.229493 -57.709896) (xy 17.193805 -57.668707) (xy 17.164341 -57.62286) (xy 17.141702 -57.573285)
			(xy 17.126348 -57.520994) (xy 17.118592 -57.467049) (xy 16.935227 -57.467049) (xy 16.939073 -57.494779)
			(xy 16.939514 -57.521094) (xy 16.939041 -57.548464) (xy 16.931224 -57.602643) (xy 16.915737 -57.655146)
			(xy 16.892897 -57.704892) (xy 16.863174 -57.75086) (xy 16.845534 -57.771792) (xy 16.84528 -57.772046)
			(xy 16.839708 -57.779142) (xy 16.833453 -57.796052) (xy 16.833088 -57.805066) (xy 16.833088 -57.872122)
			(xy 16.833437 -57.88114) (xy 16.839691 -57.898056) (xy 16.84528 -57.905142) (xy 16.845534 -57.905142)
			(xy 16.845534 -57.905396) (xy 16.86317 -57.926333) (xy 16.892898 -57.972299) (xy 16.915747 -58.022044)
			(xy 16.931245 -58.074546) (xy 16.939075 -58.128725) (xy 16.939076 -58.183466) (xy 16.931247 -58.237645)
			(xy 16.91575 -58.290147) (xy 16.892903 -58.339893) (xy 16.863176 -58.38586) (xy 16.845534 -58.406792)
			(xy 16.84528 -58.407046) (xy 16.839708 -58.414142) (xy 16.833453 -58.431052) (xy 16.833088 -58.440066)
			(xy 16.833088 -58.507122) (xy 16.833437 -58.51614) (xy 16.839691 -58.533056) (xy 16.84528 -58.540142)
			(xy 16.845534 -58.540142) (xy 16.845534 -58.540396) (xy 16.86319 -58.561314) (xy 16.892898 -58.607291)
			(xy 16.91573 -58.657043) (xy 16.931217 -58.709546) (xy 16.939042 -58.763724) (xy 16.939514 -58.791094)
			(xy 16.939028 -58.818345) (xy 16.931272 -58.872293) (xy 16.930875 -58.873644) (xy 18.200624 -58.873644)
			(xy 18.20111 -58.846274) (xy 18.208922 -58.792096) (xy 18.224406 -58.739593) (xy 18.247244 -58.689846)
			(xy 18.276964 -58.643878) (xy 18.294604 -58.622946) (xy 18.294858 -58.622692) (xy 18.300461 -58.615617)
			(xy 18.306696 -58.598691) (xy 18.30705 -58.589672) (xy 18.30705 -58.522616) (xy 18.306696 -58.513599)
			(xy 18.300448 -58.496681) (xy 18.294858 -58.489596) (xy 18.294604 -58.489596) (xy 18.294604 -58.489342)
			(xy 18.276972 -58.468404) (xy 18.247259 -58.422433) (xy 18.224421 -58.372687) (xy 18.208929 -58.320188)
			(xy 18.201099 -58.266013) (xy 18.200624 -58.238644) (xy 18.20111 -58.211393) (xy 18.208866 -58.157445)
			(xy 18.224221 -58.10515) (xy 18.246863 -58.055573) (xy 18.276329 -58.009723) (xy 18.31202 -57.968532)
			(xy 18.353211 -57.932841) (xy 18.399061 -57.903375) (xy 18.448638 -57.880733) (xy 18.500933 -57.865378)
			(xy 18.554881 -57.857622) (xy 18.609383 -57.857622) (xy 18.663331 -57.865378) (xy 18.715626 -57.880733)
			(xy 18.765203 -57.903375) (xy 18.811053 -57.932841) (xy 18.852244 -57.968532) (xy 18.887935 -58.009723)
			(xy 18.917401 -58.055573) (xy 18.940043 -58.10515) (xy 18.955398 -58.157445) (xy 18.963154 -58.211393)
			(xy 18.96364 -58.238644) (xy 18.963156 -58.266014) (xy 18.955345 -58.320193) (xy 18.939861 -58.372696)
			(xy 18.917022 -58.422443) (xy 18.8873 -58.46841) (xy 18.86966 -58.489342) (xy 18.869406 -58.489596)
			(xy 18.863816 -58.49668) (xy 18.857571 -58.513599) (xy 18.857214 -58.522616) (xy 18.857214 -58.589672)
			(xy 18.857582 -58.598688) (xy 18.863822 -58.615605) (xy 18.869406 -58.622692) (xy 18.86966 -58.622692)
			(xy 18.86966 -58.622946) (xy 18.887281 -58.643893) (xy 18.916997 -58.689861) (xy 18.939837 -58.739605)
			(xy 18.955332 -58.792102) (xy 18.963164 -58.846276) (xy 18.96364 -58.873644) (xy 18.963154 -58.900895)
			(xy 18.955398 -58.954843) (xy 18.940043 -59.007138) (xy 18.917401 -59.056715) (xy 18.887935 -59.102565)
			(xy 18.852244 -59.143756) (xy 18.811053 -59.179447) (xy 18.765203 -59.208913) (xy 18.715626 -59.231555)
			(xy 18.663331 -59.24691) (xy 18.609383 -59.254666) (xy 18.554881 -59.254666) (xy 18.500933 -59.24691)
			(xy 18.448638 -59.231555) (xy 18.399061 -59.208913) (xy 18.353211 -59.179447) (xy 18.31202 -59.143756)
			(xy 18.276329 -59.102565) (xy 18.246863 -59.056715) (xy 18.224221 -59.007138) (xy 18.208866 -58.954843)
			(xy 18.20111 -58.900895) (xy 18.200624 -58.873644) (xy 16.930875 -58.873644) (xy 16.915917 -58.924588)
			(xy 16.893275 -58.974165) (xy 16.863809 -59.020015) (xy 16.828118 -59.061206) (xy 16.786927 -59.096897)
			(xy 16.741077 -59.126363) (xy 16.6915 -59.149005) (xy 16.639205 -59.16436) (xy 16.585257 -59.172116)
			(xy 16.530755 -59.172116) (xy 16.476807 -59.16436) (xy 16.424512 -59.149005) (xy 16.374935 -59.126363)
			(xy 16.329085 -59.096897) (xy 16.287894 -59.061206) (xy 16.252203 -59.020015) (xy 16.222737 -58.974165)
			(xy 16.200095 -58.924588) (xy 16.18474 -58.872293) (xy 16.176984 -58.818345) (xy 16.176498 -58.791094)
			(xy 14.27854 -58.791094) (xy 14.275448 -58.812603) (xy 14.260093 -58.864898) (xy 14.237451 -58.914475)
			(xy 14.207985 -58.960325) (xy 14.172294 -59.001516) (xy 14.131103 -59.037207) (xy 14.085253 -59.066673)
			(xy 14.035676 -59.089315) (xy 13.983381 -59.10467) (xy 13.929433 -59.112426) (xy 13.874931 -59.112426)
			(xy 13.820983 -59.10467) (xy 13.768688 -59.089315) (xy 13.719111 -59.066673) (xy 13.673261 -59.037207)
			(xy 13.63207 -59.001516) (xy 13.596379 -58.960325) (xy 13.566913 -58.914475) (xy 13.544271 -58.864898)
			(xy 13.528916 -58.812603) (xy 13.52116 -58.758655) (xy 13.520674 -58.731404) (xy 9.448124 -58.731404)
			(xy 9.413271 -58.760409) (xy 9.365665 -58.789463) (xy 9.314336 -58.811275) (xy 9.260379 -58.825381)
			(xy 9.204942 -58.831481) (xy 9.149208 -58.829444) (xy 9.094365 -58.819314) (xy 9.041581 -58.801307)
			(xy 8.991981 -58.775806) (xy 8.946623 -58.743355) (xy 8.906474 -58.704646) (xy 8.872388 -58.660503)
			(xy 8.845092 -58.611868) (xy 8.825169 -58.559777) (xy 8.813043 -58.50534) (xy 8.808972 -58.449718)
			(xy 7.308681 -58.449718) (xy 7.317239 -58.478162) (xy 7.325359 -58.533338) (xy 7.325868 -58.561224)
			(xy 7.325359 -58.58911) (xy 7.317239 -58.644286) (xy 7.301171 -58.697693) (xy 7.277499 -58.74819)
			(xy 7.246726 -58.794703) (xy 7.209509 -58.83624) (xy 7.166641 -58.871915) (xy 7.119035 -58.900969)
			(xy 7.067706 -58.922781) (xy 7.013749 -58.936887) (xy 6.958312 -58.942987) (xy 6.902578 -58.94095)
			(xy 6.847735 -58.93082) (xy 6.794951 -58.912813) (xy 6.745351 -58.887312) (xy 6.699993 -58.854861)
			(xy 6.659844 -58.816152) (xy 6.625758 -58.772009) (xy 6.598462 -58.723374) (xy 6.578539 -58.671283)
			(xy 6.566413 -58.616846) (xy 6.562342 -58.561224) (xy 1.987296 -58.561224) (xy 1.987296 -59.974734)
			(xy 5.086602 -59.974734) (xy 5.090673 -59.919112) (xy 5.102799 -59.864675) (xy 5.122722 -59.812584)
			(xy 5.150018 -59.763949) (xy 5.184104 -59.719806) (xy 5.224253 -59.681097) (xy 5.269611 -59.648646)
			(xy 5.319211 -59.623145) (xy 5.371995 -59.605138) (xy 5.426838 -59.595008) (xy 5.482572 -59.592971)
			(xy 5.538009 -59.599071) (xy 5.591966 -59.613177) (xy 5.643295 -59.634989) (xy 5.690901 -59.664043)
			(xy 5.733769 -59.699718) (xy 5.770986 -59.741255) (xy 5.801759 -59.787768) (xy 5.825431 -59.838265)
			(xy 5.841499 -59.891672) (xy 5.849619 -59.946848) (xy 5.850128 -59.974734) (xy 5.849619 -60.00262)
			(xy 5.841499 -60.057796) (xy 5.825431 -60.111203) (xy 5.818282 -60.126454) (xy 17.180249 -60.126454)
			(xy 17.180249 -60.071946) (xy 17.188007 -60.017994) (xy 17.203363 -59.965695) (xy 17.226006 -59.916114)
			(xy 17.255476 -59.87026) (xy 17.29117 -59.829066) (xy 17.332364 -59.793372) (xy 17.378219 -59.763904)
			(xy 17.427801 -59.741261) (xy 17.4801 -59.725905) (xy 17.534052 -59.718149) (xy 17.561306 -59.717686)
			(xy 17.588676 -59.718152) (xy 17.642855 -59.72597) (xy 17.695358 -59.74146) (xy 17.745105 -59.764301)
			(xy 17.791072 -59.794025) (xy 17.812004 -59.811666) (xy 17.812258 -59.81192) (xy 17.819351 -59.817497)
			(xy 17.836263 -59.823749) (xy 17.845278 -59.824112) (xy 17.912334 -59.824112) (xy 17.921352 -59.823769)
			(xy 17.938269 -59.817512) (xy 17.945354 -59.81192) (xy 17.945354 -59.811666) (xy 17.945608 -59.811666)
			(xy 17.966541 -59.794025) (xy 18.012509 -59.764301) (xy 18.062255 -59.741455) (xy 18.114757 -59.725959)
			(xy 18.168935 -59.71813) (xy 18.223677 -59.71813) (xy 18.277855 -59.725959) (xy 18.330357 -59.741455)
			(xy 18.380103 -59.764301) (xy 18.426071 -59.794025) (xy 18.447004 -59.811666) (xy 18.447258 -59.81192)
			(xy 18.454351 -59.817497) (xy 18.471263 -59.823749) (xy 18.480278 -59.824112) (xy 18.547334 -59.824112)
			(xy 18.556352 -59.823769) (xy 18.573269 -59.817512) (xy 18.580354 -59.81192) (xy 18.580354 -59.811666)
			(xy 18.580608 -59.811666) (xy 18.601522 -59.794004) (xy 18.6475 -59.764297) (xy 18.697252 -59.741466)
			(xy 18.749757 -59.72598) (xy 18.803936 -59.718157) (xy 18.831306 -59.717686) (xy 18.858557 -59.718184)
			(xy 18.912503 -59.725941) (xy 18.964796 -59.741297) (xy 19.014372 -59.763938) (xy 19.060221 -59.793404)
			(xy 19.101409 -59.829095) (xy 19.1371 -59.870284) (xy 19.166565 -59.916134) (xy 19.189205 -59.96571)
			(xy 19.20456 -60.018003) (xy 19.212316 -60.071949) (xy 19.212316 -60.126451) (xy 19.20456 -60.180397)
			(xy 19.189205 -60.23269) (xy 19.166565 -60.282266) (xy 19.1371 -60.328116) (xy 19.101409 -60.369305)
			(xy 19.060221 -60.404996) (xy 19.014372 -60.434462) (xy 18.964796 -60.457103) (xy 18.912503 -60.472459)
			(xy 18.858557 -60.480216) (xy 18.831306 -60.480702) (xy 18.803936 -60.480232) (xy 18.749757 -60.472415)
			(xy 18.697254 -60.456927) (xy 18.647507 -60.434086) (xy 18.60154 -60.404363) (xy 18.580608 -60.386722)
			(xy 18.580354 -60.386468) (xy 18.573259 -60.380894) (xy 18.556349 -60.374641) (xy 18.547334 -60.374276)
			(xy 18.480278 -60.374276) (xy 18.471261 -60.374627) (xy 18.454344 -60.380879) (xy 18.447258 -60.386468)
			(xy 18.447004 -60.386722) (xy 18.426071 -60.404363) (xy 18.380103 -60.434087) (xy 18.330357 -60.456933)
			(xy 18.277855 -60.472429) (xy 18.223677 -60.480258) (xy 18.168935 -60.480258) (xy 18.114757 -60.472429)
			(xy 18.062255 -60.456933) (xy 18.012509 -60.434087) (xy 17.966541 -60.404363) (xy 17.945608 -60.386722)
			(xy 17.945354 -60.386468) (xy 17.938259 -60.380894) (xy 17.921349 -60.374641) (xy 17.912334 -60.374276)
			(xy 17.845278 -60.374276) (xy 17.836261 -60.374627) (xy 17.819344 -60.380879) (xy 17.812258 -60.386468)
			(xy 17.812258 -60.386722) (xy 17.812004 -60.386722) (xy 17.791084 -60.404376) (xy 17.745108 -60.434085)
			(xy 17.695357 -60.456918) (xy 17.642854 -60.472405) (xy 17.588676 -60.48023) (xy 17.561306 -60.480702)
			(xy 17.534052 -60.480251) (xy 17.4801 -60.472495) (xy 17.427801 -60.457139) (xy 17.378219 -60.434496)
			(xy 17.332364 -60.405028) (xy 17.29117 -60.369334) (xy 17.255476 -60.32814) (xy 17.226006 -60.282286)
			(xy 17.203363 -60.232705) (xy 17.188007 -60.180406) (xy 17.180249 -60.126454) (xy 5.818282 -60.126454)
			(xy 5.801759 -60.1617) (xy 5.770986 -60.208213) (xy 5.733769 -60.24975) (xy 5.690901 -60.285425)
			(xy 5.643295 -60.314479) (xy 5.591966 -60.336291) (xy 5.538009 -60.350397) (xy 5.482572 -60.356497)
			(xy 5.426838 -60.35446) (xy 5.371995 -60.34433) (xy 5.319211 -60.326323) (xy 5.269611 -60.300822)
			(xy 5.224253 -60.268371) (xy 5.184104 -60.229662) (xy 5.150018 -60.185519) (xy 5.122722 -60.136884)
			(xy 5.102799 -60.084793) (xy 5.090673 -60.030356) (xy 5.086602 -59.974734) (xy 1.987296 -59.974734)
			(xy 1.987296 -60.601606) (xy 4.333238 -60.601606) (xy 4.337309 -60.545984) (xy 4.349435 -60.491547)
			(xy 4.369358 -60.439456) (xy 4.396654 -60.390821) (xy 4.43074 -60.346678) (xy 4.470889 -60.307969)
			(xy 4.516247 -60.275518) (xy 4.565847 -60.250017) (xy 4.618631 -60.23201) (xy 4.673474 -60.22188)
			(xy 4.729208 -60.219843) (xy 4.784645 -60.225943) (xy 4.838602 -60.240049) (xy 4.889931 -60.261861)
			(xy 4.937537 -60.290915) (xy 4.980405 -60.32659) (xy 5.017622 -60.368127) (xy 5.048395 -60.41464)
			(xy 5.072067 -60.465137) (xy 5.088135 -60.518544) (xy 5.096255 -60.57372) (xy 5.096764 -60.601606)
			(xy 5.096255 -60.629492) (xy 5.088135 -60.684668) (xy 5.072067 -60.738075) (xy 5.051501 -60.781946)
			(xy 5.674358 -60.781946) (xy 5.678429 -60.726324) (xy 5.690555 -60.671887) (xy 5.710478 -60.619796)
			(xy 5.737774 -60.571161) (xy 5.77186 -60.527018) (xy 5.812009 -60.488309) (xy 5.857367 -60.455858)
			(xy 5.906967 -60.430357) (xy 5.959751 -60.41235) (xy 6.014594 -60.40222) (xy 6.070328 -60.400183)
			(xy 6.125765 -60.406283) (xy 6.179722 -60.420389) (xy 6.231051 -60.442201) (xy 6.278657 -60.471255)
			(xy 6.321525 -60.50693) (xy 6.358742 -60.548467) (xy 6.389515 -60.59498) (xy 6.404528 -60.627006)
			(xy 6.721346 -60.627006) (xy 6.725417 -60.571384) (xy 6.737543 -60.516947) (xy 6.757466 -60.464856)
			(xy 6.784762 -60.416221) (xy 6.818848 -60.372078) (xy 6.858997 -60.333369) (xy 6.904355 -60.300918)
			(xy 6.953955 -60.275417) (xy 7.006739 -60.25741) (xy 7.061582 -60.24728) (xy 7.117316 -60.245243)
			(xy 7.172753 -60.251343) (xy 7.22671 -60.265449) (xy 7.278039 -60.287261) (xy 7.325645 -60.316315)
			(xy 7.368513 -60.35199) (xy 7.40573 -60.393527) (xy 7.436503 -60.44004) (xy 7.460175 -60.490537)
			(xy 7.476243 -60.543944) (xy 7.484363 -60.59912) (xy 7.484872 -60.627006) (xy 7.484756 -60.633356)
			(xy 7.797036 -60.633356) (xy 7.801107 -60.577734) (xy 7.813233 -60.523297) (xy 7.833156 -60.471206)
			(xy 7.860452 -60.422571) (xy 7.894538 -60.378428) (xy 7.934687 -60.339719) (xy 7.980045 -60.307268)
			(xy 8.029645 -60.281767) (xy 8.082429 -60.26376) (xy 8.137272 -60.25363) (xy 8.193006 -60.251593)
			(xy 8.248443 -60.257693) (xy 8.3024 -60.271799) (xy 8.353729 -60.293611) (xy 8.401335 -60.322665)
			(xy 8.444203 -60.35834) (xy 8.48142 -60.399877) (xy 8.512193 -60.44639) (xy 8.535865 -60.496887)
			(xy 8.551933 -60.550294) (xy 8.560053 -60.60547) (xy 8.560562 -60.633356) (xy 8.813036 -60.633356)
			(xy 8.817107 -60.577734) (xy 8.829233 -60.523297) (xy 8.849156 -60.471206) (xy 8.876452 -60.422571)
			(xy 8.910538 -60.378428) (xy 8.950687 -60.339719) (xy 8.996045 -60.307268) (xy 9.045645 -60.281767)
			(xy 9.098429 -60.26376) (xy 9.153272 -60.25363) (xy 9.209006 -60.251593) (xy 9.264443 -60.257693)
			(xy 9.3184 -60.271799) (xy 9.369729 -60.293611) (xy 9.417335 -60.322665) (xy 9.460203 -60.35834)
			(xy 9.49742 -60.399877) (xy 9.528193 -60.44639) (xy 9.551865 -60.496887) (xy 9.567933 -60.550294)
			(xy 9.576053 -60.60547) (xy 9.576562 -60.633356) (xy 9.576053 -60.661242) (xy 9.567933 -60.716418)
			(xy 9.551865 -60.769825) (xy 9.528193 -60.820322) (xy 9.49742 -60.866835) (xy 9.460203 -60.908372)
			(xy 9.417335 -60.944047) (xy 9.369729 -60.973101) (xy 9.3184 -60.994913) (xy 9.264443 -61.009019)
			(xy 9.209006 -61.015119) (xy 9.153272 -61.013082) (xy 9.098429 -61.002952) (xy 9.045645 -60.984945)
			(xy 8.996045 -60.959444) (xy 8.950687 -60.926993) (xy 8.910538 -60.888284) (xy 8.876452 -60.844141)
			(xy 8.849156 -60.795506) (xy 8.829233 -60.743415) (xy 8.817107 -60.688978) (xy 8.813036 -60.633356)
			(xy 8.560562 -60.633356) (xy 8.560053 -60.661242) (xy 8.551933 -60.716418) (xy 8.535865 -60.769825)
			(xy 8.512193 -60.820322) (xy 8.48142 -60.866835) (xy 8.444203 -60.908372) (xy 8.401335 -60.944047)
			(xy 8.353729 -60.973101) (xy 8.3024 -60.994913) (xy 8.248443 -61.009019) (xy 8.193006 -61.015119)
			(xy 8.137272 -61.013082) (xy 8.082429 -61.002952) (xy 8.029645 -60.984945) (xy 7.980045 -60.959444)
			(xy 7.934687 -60.926993) (xy 7.894538 -60.888284) (xy 7.860452 -60.844141) (xy 7.833156 -60.795506)
			(xy 7.813233 -60.743415) (xy 7.801107 -60.688978) (xy 7.797036 -60.633356) (xy 7.484756 -60.633356)
			(xy 7.484363 -60.654892) (xy 7.476243 -60.710068) (xy 7.460175 -60.763475) (xy 7.436503 -60.813972)
			(xy 7.40573 -60.860485) (xy 7.368513 -60.902022) (xy 7.325645 -60.937697) (xy 7.278039 -60.966751)
			(xy 7.22671 -60.988563) (xy 7.172753 -61.002669) (xy 7.117316 -61.008769) (xy 7.061582 -61.006732)
			(xy 7.006739 -60.996602) (xy 6.953955 -60.978595) (xy 6.904355 -60.953094) (xy 6.858997 -60.920643)
			(xy 6.818848 -60.881934) (xy 6.784762 -60.837791) (xy 6.757466 -60.789156) (xy 6.737543 -60.737065)
			(xy 6.725417 -60.682628) (xy 6.721346 -60.627006) (xy 6.404528 -60.627006) (xy 6.413187 -60.645477)
			(xy 6.429255 -60.698884) (xy 6.437375 -60.75406) (xy 6.437884 -60.781946) (xy 6.437375 -60.809832)
			(xy 6.429255 -60.865008) (xy 6.413187 -60.918415) (xy 6.389515 -60.968912) (xy 6.358742 -61.015425)
			(xy 6.321525 -61.056962) (xy 6.278657 -61.092637) (xy 6.231051 -61.121691) (xy 6.179722 -61.143503)
			(xy 6.125765 -61.157609) (xy 6.070328 -61.163709) (xy 6.014594 -61.161672) (xy 5.959751 -61.151542)
			(xy 5.906967 -61.133535) (xy 5.857367 -61.108034) (xy 5.812009 -61.075583) (xy 5.77186 -61.036874)
			(xy 5.737774 -60.992731) (xy 5.710478 -60.944096) (xy 5.690555 -60.892005) (xy 5.678429 -60.837568)
			(xy 5.674358 -60.781946) (xy 5.051501 -60.781946) (xy 5.048395 -60.788572) (xy 5.017622 -60.835085)
			(xy 4.980405 -60.876622) (xy 4.937537 -60.912297) (xy 4.889931 -60.941351) (xy 4.838602 -60.963163)
			(xy 4.784645 -60.977269) (xy 4.729208 -60.983369) (xy 4.673474 -60.981332) (xy 4.618631 -60.971202)
			(xy 4.565847 -60.953195) (xy 4.516247 -60.927694) (xy 4.470889 -60.895243) (xy 4.43074 -60.856534)
			(xy 4.396654 -60.812391) (xy 4.369358 -60.763756) (xy 4.349435 -60.711665) (xy 4.337309 -60.657228)
			(xy 4.333238 -60.601606) (xy 1.987296 -60.601606) (xy 1.987296 -62.429136) (xy 2.093212 -62.429136)
			(xy 2.097283 -62.373514) (xy 2.109409 -62.319077) (xy 2.129332 -62.266986) (xy 2.156628 -62.218351)
			(xy 2.190714 -62.174208) (xy 2.230863 -62.135499) (xy 2.276221 -62.103048) (xy 2.325821 -62.077547)
			(xy 2.378605 -62.05954) (xy 2.433448 -62.04941) (xy 2.489182 -62.047373) (xy 2.544619 -62.053473)
			(xy 2.598576 -62.067579) (xy 2.649905 -62.089391) (xy 2.697511 -62.118445) (xy 2.700622 -62.121034)
			(xy 4.242306 -62.121034) (xy 4.246377 -62.065412) (xy 4.258503 -62.010975) (xy 4.278426 -61.958884)
			(xy 4.305722 -61.910249) (xy 4.339808 -61.866106) (xy 4.379957 -61.827397) (xy 4.425315 -61.794946)
			(xy 4.474915 -61.769445) (xy 4.527699 -61.751438) (xy 4.582542 -61.741308) (xy 4.638276 -61.739271)
			(xy 4.693713 -61.745371) (xy 4.74767 -61.759477) (xy 4.798999 -61.781289) (xy 4.846605 -61.810343)
			(xy 4.889473 -61.846018) (xy 4.92669 -61.887555) (xy 4.957463 -61.934068) (xy 4.981135 -61.984565)
			(xy 4.997203 -62.037972) (xy 4.999185 -62.051438) (xy 8.22909 -62.051438) (xy 8.233161 -61.995816)
			(xy 8.245287 -61.941379) (xy 8.26521 -61.889288) (xy 8.292506 -61.840653) (xy 8.326592 -61.79651)
			(xy 8.366741 -61.757801) (xy 8.412099 -61.72535) (xy 8.461699 -61.699849) (xy 8.514483 -61.681842)
			(xy 8.569326 -61.671712) (xy 8.62506 -61.669675) (xy 8.680497 -61.675775) (xy 8.734454 -61.689881)
			(xy 8.785783 -61.711693) (xy 8.833389 -61.740747) (xy 8.876257 -61.776422) (xy 8.913474 -61.817959)
			(xy 8.944247 -61.864472) (xy 8.967919 -61.914969) (xy 8.983987 -61.968376) (xy 8.992107 -62.023552)
			(xy 8.992616 -62.051438) (xy 8.992107 -62.079324) (xy 8.983987 -62.1345) (xy 8.967919 -62.187907)
			(xy 8.944247 -62.238404) (xy 8.913474 -62.284917) (xy 8.876257 -62.326454) (xy 8.833389 -62.362129)
			(xy 8.785783 -62.391183) (xy 8.734454 -62.412995) (xy 8.680497 -62.427101) (xy 8.62506 -62.433201)
			(xy 8.569326 -62.431164) (xy 8.514483 -62.421034) (xy 8.461699 -62.403027) (xy 8.412099 -62.377526)
			(xy 8.366741 -62.345075) (xy 8.326592 -62.306366) (xy 8.292506 -62.262223) (xy 8.26521 -62.213588)
			(xy 8.245287 -62.161497) (xy 8.233161 -62.10706) (xy 8.22909 -62.051438) (xy 4.999185 -62.051438)
			(xy 5.005323 -62.093148) (xy 5.005832 -62.121034) (xy 5.005323 -62.14892) (xy 4.997203 -62.204096)
			(xy 4.981135 -62.257503) (xy 4.957463 -62.308) (xy 4.92669 -62.354513) (xy 4.889473 -62.39605) (xy 4.846605 -62.431725)
			(xy 4.798999 -62.460779) (xy 4.74767 -62.482591) (xy 4.693713 -62.496697) (xy 4.638276 -62.502797)
			(xy 4.582542 -62.50076) (xy 4.527699 -62.49063) (xy 4.474915 -62.472623) (xy 4.425315 -62.447122)
			(xy 4.379957 -62.414671) (xy 4.339808 -62.375962) (xy 4.305722 -62.331819) (xy 4.278426 -62.283184)
			(xy 4.258503 -62.231093) (xy 4.246377 -62.176656) (xy 4.242306 -62.121034) (xy 2.700622 -62.121034)
			(xy 2.740379 -62.15412) (xy 2.777596 -62.195657) (xy 2.808369 -62.24217) (xy 2.832041 -62.292667)
			(xy 2.848109 -62.346074) (xy 2.856229 -62.40125) (xy 2.856738 -62.429136) (xy 2.856229 -62.457022)
			(xy 2.848109 -62.512198) (xy 2.832041 -62.565605) (xy 2.808369 -62.616102) (xy 2.777596 -62.662615)
			(xy 2.740379 -62.704152) (xy 2.697511 -62.739827) (xy 2.649905 -62.768881) (xy 2.598576 -62.790693)
			(xy 2.544619 -62.804799) (xy 2.489182 -62.810899) (xy 2.433448 -62.808862) (xy 2.378605 -62.798732)
			(xy 2.325821 -62.780725) (xy 2.276221 -62.755224) (xy 2.230863 -62.722773) (xy 2.190714 -62.684064)
			(xy 2.156628 -62.639921) (xy 2.129332 -62.591286) (xy 2.109409 -62.539195) (xy 2.097283 -62.484758)
			(xy 2.093212 -62.429136) (xy 1.987296 -62.429136) (xy 1.987296 -62.812168) (xy 6.917942 -62.812168)
			(xy 6.922013 -62.756546) (xy 6.934139 -62.702109) (xy 6.954062 -62.650018) (xy 6.981358 -62.601383)
			(xy 7.015444 -62.55724) (xy 7.055593 -62.518531) (xy 7.100951 -62.48608) (xy 7.150551 -62.460579)
			(xy 7.203335 -62.442572) (xy 7.258178 -62.432442) (xy 7.313912 -62.430405) (xy 7.369349 -62.436505)
			(xy 7.423306 -62.450611) (xy 7.474635 -62.472423) (xy 7.522241 -62.501477) (xy 7.565109 -62.537152)
			(xy 7.602326 -62.578689) (xy 7.633099 -62.625202) (xy 7.656771 -62.675699) (xy 7.672839 -62.729106)
			(xy 7.680959 -62.784282) (xy 7.681468 -62.812168) (xy 7.680959 -62.840054) (xy 7.672839 -62.89523)
			(xy 7.656771 -62.948637) (xy 7.633099 -62.999134) (xy 7.602326 -63.045647) (xy 7.565109 -63.087184)
			(xy 7.522241 -63.122859) (xy 7.474635 -63.151913) (xy 7.423306 -63.173725) (xy 7.369349 -63.187831)
			(xy 7.313912 -63.193931) (xy 7.258178 -63.191894) (xy 7.203335 -63.181764) (xy 7.150551 -63.163757)
			(xy 7.100951 -63.138256) (xy 7.055593 -63.105805) (xy 7.015444 -63.067096) (xy 6.981358 -63.022953)
			(xy 6.954062 -62.974318) (xy 6.934139 -62.922227) (xy 6.922013 -62.86779) (xy 6.917942 -62.812168)
			(xy 1.987296 -62.812168) (xy 1.987296 -63.273432) (xy 3.576826 -63.273432) (xy 3.580897 -63.21781)
			(xy 3.593023 -63.163373) (xy 3.612946 -63.111282) (xy 3.640242 -63.062647) (xy 3.674328 -63.018504)
			(xy 3.714477 -62.979795) (xy 3.759835 -62.947344) (xy 3.809435 -62.921843) (xy 3.862219 -62.903836)
			(xy 3.917062 -62.893706) (xy 3.972796 -62.891669) (xy 4.028233 -62.897769) (xy 4.08219 -62.911875)
			(xy 4.133519 -62.933687) (xy 4.181125 -62.962741) (xy 4.223993 -62.998416) (xy 4.26121 -63.039953)
			(xy 4.291983 -63.086466) (xy 4.315655 -63.136963) (xy 4.331723 -63.19037) (xy 4.339843 -63.245546)
			(xy 4.339843 -63.245552) (xy 17.104569 -63.245552) (xy 17.104569 -63.191048) (xy 17.112326 -63.137097)
			(xy 17.127683 -63.0848) (xy 17.150325 -63.035221) (xy 17.179793 -62.989369) (xy 17.215487 -62.948177)
			(xy 17.25668 -62.912485) (xy 17.302533 -62.883019) (xy 17.352113 -62.860378) (xy 17.404411 -62.845023)
			(xy 17.458361 -62.837268) (xy 17.485614 -62.836806) (xy 17.512985 -62.837262) (xy 17.567164 -62.845082)
			(xy 17.619667 -62.860574) (xy 17.669414 -62.883417) (xy 17.715381 -62.913144) (xy 17.736312 -62.930786)
			(xy 17.736566 -62.93104) (xy 17.743655 -62.936623) (xy 17.76057 -62.942871) (xy 17.769586 -62.943232)
			(xy 17.836642 -62.943232) (xy 17.845655 -62.94284) (xy 17.862572 -62.936616) (xy 17.869662 -62.93104)
			(xy 17.869662 -62.930786) (xy 17.869916 -62.930786) (xy 17.890849 -62.913145) (xy 17.936817 -62.883421)
			(xy 17.986563 -62.860575) (xy 18.039065 -62.845079) (xy 18.093243 -62.83725) (xy 18.147985 -62.83725)
			(xy 18.202163 -62.845079) (xy 18.254665 -62.860575) (xy 18.304411 -62.883421) (xy 18.350379 -62.913145)
			(xy 18.371312 -62.930786) (xy 18.371566 -62.93104) (xy 18.378655 -62.936623) (xy 18.39557 -62.942871)
			(xy 18.404586 -62.943232) (xy 18.471642 -62.943232) (xy 18.480655 -62.94284) (xy 18.497572 -62.936616)
			(xy 18.504662 -62.93104) (xy 18.504662 -62.930786) (xy 18.504916 -62.930786) (xy 18.525867 -62.913171)
			(xy 18.571835 -62.883456) (xy 18.621578 -62.860615) (xy 18.674074 -62.845119) (xy 18.728246 -62.837284)
			(xy 18.755614 -62.836806) (xy 18.782866 -62.837265) (xy 18.836814 -62.845023) (xy 18.889109 -62.86038)
			(xy 18.938686 -62.883023) (xy 18.984536 -62.912491) (xy 19.025726 -62.948183) (xy 19.061418 -62.989375)
			(xy 19.090884 -63.035226) (xy 19.113525 -63.084804) (xy 19.12888 -63.1371) (xy 19.136636 -63.191048)
			(xy 19.136636 -63.245552) (xy 19.12888 -63.2995) (xy 19.113525 -63.351796) (xy 19.090884 -63.401374)
			(xy 19.061418 -63.447225) (xy 19.025726 -63.488417) (xy 18.984536 -63.524109) (xy 18.938686 -63.553577)
			(xy 18.889109 -63.57622) (xy 18.836814 -63.591577) (xy 18.782866 -63.599335) (xy 18.755614 -63.599822)
			(xy 18.728243 -63.599367) (xy 18.674063 -63.591549) (xy 18.621559 -63.576059) (xy 18.571812 -63.553214)
			(xy 18.525847 -63.523486) (xy 18.504916 -63.505842) (xy 18.504662 -63.505588) (xy 18.497563 -63.50002)
			(xy 18.480656 -63.493762) (xy 18.471642 -63.493396) (xy 18.404586 -63.493396) (xy 18.395569 -63.493747)
			(xy 18.378652 -63.499999) (xy 18.371566 -63.505588) (xy 18.371312 -63.505842) (xy 18.350379 -63.523483)
			(xy 18.304411 -63.553207) (xy 18.254665 -63.576053) (xy 18.202163 -63.591549) (xy 18.147985 -63.599378)
			(xy 18.093243 -63.599378) (xy 18.039065 -63.591549) (xy 17.986563 -63.576053) (xy 17.936817 -63.553207)
			(xy 17.890849 -63.523483) (xy 17.869916 -63.505842) (xy 17.869662 -63.505588) (xy 17.862563 -63.50002)
			(xy 17.845656 -63.493762) (xy 17.836642 -63.493396) (xy 17.769586 -63.493396) (xy 17.760569 -63.493747)
			(xy 17.743652 -63.499999) (xy 17.736566 -63.505588) (xy 17.736566 -63.505842) (xy 17.736312 -63.505842)
			(xy 17.715392 -63.523496) (xy 17.669415 -63.553204) (xy 17.619665 -63.576037) (xy 17.567161 -63.591525)
			(xy 17.512984 -63.59935) (xy 17.485614 -63.599822) (xy 17.458361 -63.599332) (xy 17.404411 -63.591577)
			(xy 17.352113 -63.576222) (xy 17.302533 -63.553581) (xy 17.25668 -63.524115) (xy 17.215487 -63.488423)
			(xy 17.179793 -63.447231) (xy 17.150325 -63.401379) (xy 17.127683 -63.3518) (xy 17.112326 -63.299503)
			(xy 17.104569 -63.245552) (xy 4.339843 -63.245552) (xy 4.340352 -63.273432) (xy 4.339843 -63.301318)
			(xy 4.331723 -63.356494) (xy 4.315655 -63.409901) (xy 4.291983 -63.460398) (xy 4.26121 -63.506911)
			(xy 4.223993 -63.548448) (xy 4.181125 -63.584123) (xy 4.133519 -63.613177) (xy 4.08219 -63.634989)
			(xy 4.028233 -63.649095) (xy 3.972796 -63.655195) (xy 3.917062 -63.653158) (xy 3.862219 -63.643028)
			(xy 3.809435 -63.625021) (xy 3.759835 -63.59952) (xy 3.714477 -63.567069) (xy 3.674328 -63.52836)
			(xy 3.640242 -63.484217) (xy 3.612946 -63.435582) (xy 3.593023 -63.383491) (xy 3.580897 -63.329054)
			(xy 3.576826 -63.273432) (xy 1.987296 -63.273432) (xy 1.987296 -64.292734) (xy 1.987936 -64.304671)
			(xy 1.99177 -64.312292) (xy 5.066028 -64.312292) (xy 5.070099 -64.25667) (xy 5.082225 -64.202233)
			(xy 5.102148 -64.150142) (xy 5.129444 -64.101507) (xy 5.16353 -64.057364) (xy 5.203679 -64.018655)
			(xy 5.249037 -63.986204) (xy 5.298637 -63.960703) (xy 5.351421 -63.942696) (xy 5.406264 -63.932566)
			(xy 5.461998 -63.930529) (xy 5.517435 -63.936629) (xy 5.571392 -63.950735) (xy 5.622721 -63.972547)
			(xy 5.670327 -64.001601) (xy 5.713195 -64.037276) (xy 5.750412 -64.078813) (xy 5.781185 -64.125326)
			(xy 5.804857 -64.175823) (xy 5.820925 -64.22923) (xy 5.829045 -64.284406) (xy 5.829554 -64.312292)
			(xy 5.829045 -64.340178) (xy 5.820925 -64.395354) (xy 5.804857 -64.448761) (xy 5.781185 -64.499258)
			(xy 5.750412 -64.545771) (xy 5.713195 -64.587308) (xy 5.670327 -64.622983) (xy 5.622721 -64.652037)
			(xy 5.571392 -64.673849) (xy 5.517435 -64.687955) (xy 5.461998 -64.694055) (xy 5.406264 -64.692018)
			(xy 5.351421 -64.681888) (xy 5.298637 -64.663881) (xy 5.249037 -64.63838) (xy 5.203679 -64.605929)
			(xy 5.16353 -64.56722) (xy 5.129444 -64.523077) (xy 5.102148 -64.474442) (xy 5.082225 -64.422351)
			(xy 5.070099 -64.367914) (xy 5.066028 -64.312292) (xy 1.99177 -64.312292) (xy 1.998665 -64.326) (xy 2.00787 -64.333628)
			(xy 2.080768 -64.381888) (xy 2.086068 -64.385269) (xy 2.097895 -64.38952) (xy 2.104136 -64.39027)
			(xy 2.116836 -64.391286) (xy 2.117852 -64.390778) (xy 2.12852 -64.386206) (xy 2.129028 -64.386206)
			(xy 2.152701 -64.376601) (xy 2.201959 -64.363049) (xy 2.252583 -64.35618) (xy 2.278126 -64.355726)
			(xy 2.282952 -64.355726) (xy 2.30999 -64.35652) (xy 2.363444 -64.364799) (xy 2.415193 -64.380545)
			(xy 2.464199 -64.403442) (xy 2.509479 -64.433032) (xy 2.550125 -64.468722) (xy 2.585323 -64.509794)
			(xy 2.614367 -64.555427) (xy 2.636674 -64.604704) (xy 2.651797 -64.656639) (xy 2.659432 -64.710188)
			(xy 2.659888 -64.737234) (xy 2.659402 -64.764485) (xy 2.651645 -64.818432) (xy 2.636289 -64.870727)
			(xy 2.613648 -64.920303) (xy 2.584182 -64.966153) (xy 2.54849 -65.007343) (xy 2.5073 -65.043034)
			(xy 2.46145 -65.0725) (xy 2.411873 -65.095141) (xy 2.359578 -65.110496) (xy 2.305631 -65.118252)
			(xy 2.27838 -65.118742) (xy 2.278126 -65.118742) (xy 2.25258 -65.118318) (xy 2.20195 -65.111462)
			(xy 2.152691 -65.097897) (xy 2.129028 -65.088262) (xy 2.12852 -65.088262) (xy 2.117852 -65.08369)
			(xy 2.116836 -65.083182) (xy 2.104136 -65.084198) (xy 2.097915 -65.085034) (xy 2.086108 -65.08928)
			(xy 2.080768 -65.09258) (xy 2.033192 -65.124076) (xy 6.107428 -65.124076) (xy 6.111499 -65.068454)
			(xy 6.123625 -65.014017) (xy 6.143548 -64.961926) (xy 6.170844 -64.913291) (xy 6.20493 -64.869148)
			(xy 6.245079 -64.830439) (xy 6.290437 -64.797988) (xy 6.340037 -64.772487) (xy 6.392821 -64.75448)
			(xy 6.447664 -64.74435) (xy 6.503398 -64.742313) (xy 6.558835 -64.748413) (xy 6.612792 -64.762519)
			(xy 6.664121 -64.784331) (xy 6.711727 -64.813385) (xy 6.754595 -64.84906) (xy 6.791812 -64.890597)
			(xy 6.822585 -64.93711) (xy 6.846257 -64.987607) (xy 6.862325 -65.041014) (xy 6.870445 -65.09619)
			(xy 6.870954 -65.124076) (xy 6.870445 -65.151962) (xy 6.865268 -65.187143) (xy 19.117515 -65.187143)
			(xy 19.117515 -65.132637) (xy 19.125272 -65.078686) (xy 19.140629 -65.026388) (xy 19.163271 -64.976807)
			(xy 19.19274 -64.930954) (xy 19.228434 -64.889761) (xy 19.269627 -64.854067) (xy 19.315481 -64.8246)
			(xy 19.365061 -64.801957) (xy 19.41736 -64.786602) (xy 19.471311 -64.778845) (xy 19.498564 -64.778382)
			(xy 19.499326 -64.778382) (xy 19.529102 -64.778963) (xy 19.587919 -64.788285) (xy 19.61642 -64.796924)
			(xy 19.628612 -64.800988) (xy 19.654012 -64.796162) (xy 19.740372 -64.726312) (xy 19.750024 -64.70269)
			(xy 19.748754 -64.68999) (xy 19.746997 -64.672326) (xy 19.745089 -64.636875) (xy 19.744944 -64.619124)
			(xy 19.744944 -57.543954) (xy 19.744349 -57.532299) (xy 19.734009 -57.5114) (xy 19.725132 -57.503822)
			(xy 19.661632 -57.454546) (xy 19.652016 -57.447893) (xy 19.62913 -57.443247) (xy 19.61769 -57.445656)
			(xy 19.617436 -57.445656) (xy 19.593555 -57.451592) (xy 19.544759 -57.457958) (xy 19.520154 -57.458356)
			(xy 19.492904 -57.457865) (xy 19.438959 -57.450104) (xy 19.386667 -57.434745) (xy 19.337093 -57.412102)
			(xy 19.291245 -57.382635) (xy 19.250057 -57.346945) (xy 19.214366 -57.305757) (xy 19.184899 -57.259909)
			(xy 19.162256 -57.210335) (xy 19.146897 -57.158043) (xy 19.139135 -57.104098) (xy 19.138646 -57.076848)
			(xy 19.139129 -57.049478) (xy 19.146941 -56.995299) (xy 19.162426 -56.942796) (xy 19.185264 -56.893049)
			(xy 19.214986 -56.847082) (xy 19.232626 -56.82615) (xy 19.23288 -56.825896) (xy 19.238484 -56.818822)
			(xy 19.244718 -56.801895) (xy 19.245072 -56.792876) (xy 19.245072 -56.72582) (xy 19.244711 -56.716803)
			(xy 19.238467 -56.699886) (xy 19.23288 -56.6928) (xy 19.232626 -56.6928) (xy 19.232626 -56.692546)
			(xy 19.214999 -56.671604) (xy 19.185284 -56.625634) (xy 19.162446 -56.575889) (xy 19.146952 -56.523391)
			(xy 19.139121 -56.469217) (xy 19.138646 -56.441848) (xy 19.1392 -56.414598) (xy 19.146949 -56.360653)
			(xy 19.162297 -56.30836) (xy 19.18493 -56.258783) (xy 19.214389 -56.212932) (xy 19.250073 -56.17174)
			(xy 19.291256 -56.136045) (xy 19.3371 -56.106575) (xy 19.386672 -56.08393) (xy 19.438961 -56.068569)
			(xy 19.492905 -56.060807) (xy 19.520154 -56.06034) (xy 19.544757 -56.060761) (xy 19.593551 -56.067125)
			(xy 19.617436 -56.07304) (xy 19.61769 -56.07304) (xy 19.629129 -56.075483) (xy 19.65203 -56.070834)
			(xy 19.661632 -56.06415) (xy 19.725132 -56.014874) (xy 19.734025 -56.007306) (xy 19.744363 -55.986403)
			(xy 19.744944 -55.974742) (xy 19.744944 -55.131716) (xy 19.745044 -55.126963) (xy 19.746833 -55.117626)
			(xy 19.7485 -55.113174) (xy 19.838924 -54.883812) (xy 19.840866 -54.879258) (xy 19.84624 -54.870945)
			(xy 19.849592 -54.867302) (xy 19.934428 -54.779164) (xy 19.934936 -54.778656) (xy 19.977862 -54.73319)
			(xy 19.97837 -54.732682) (xy 20.08505 -54.617874) (xy 20.092309 -54.6093) (xy 20.09915 -54.587927)
			(xy 20.098258 -54.576726) (xy 20.098258 -54.576472) (xy 20.095538 -54.554347) (xy 20.092615 -54.509862)
			(xy 20.092416 -54.487572) (xy 20.092416 -54.418992) (xy 20.092633 -54.394778) (xy 20.096065 -54.346473)
			(xy 20.099274 -54.322472) (xy 20.103338 -54.293262) (xy 20.098766 -54.282848) (xy 20.073874 -54.27091)
			(xy 20.069629 -54.268761) (xy 20.061956 -54.26314) (xy 20.058634 -54.259734) (xy 19.97837 -54.173374)
			(xy 19.977862 -54.172866) (xy 19.961098 -54.155086) (xy 19.953909 -54.148151) (xy 19.935677 -54.14003)
			(xy 19.915726 -54.139475) (xy 19.89707 -54.146569) (xy 19.88947 -54.153054) (xy 19.889216 -54.153308)
			(xy 19.882688 -54.160117) (xy 19.874696 -54.177188) (xy 19.873388 -54.195991) (xy 19.875754 -54.205124)
			(xy 19.875754 -54.205632) (xy 19.884027 -54.233546) (xy 19.89295 -54.291077) (xy 19.893534 -54.320186)
			(xy 19.893048 -54.347437) (xy 19.885292 -54.401385) (xy 19.869937 -54.45368) (xy 19.847295 -54.503257)
			(xy 19.817829 -54.549107) (xy 19.782138 -54.590298) (xy 19.740947 -54.625989) (xy 19.695097 -54.655455)
			(xy 19.64552 -54.678097) (xy 19.593225 -54.693452) (xy 19.539277 -54.701208) (xy 19.484775 -54.701208)
			(xy 19.430827 -54.693452) (xy 19.378532 -54.678097) (xy 19.328955 -54.655455) (xy 19.283105 -54.625989)
			(xy 19.241914 -54.590298) (xy 19.206223 -54.549107) (xy 19.176757 -54.503257) (xy 19.154115 -54.45368)
			(xy 19.13876 -54.401385) (xy 19.131004 -54.347437) (xy 19.130518 -54.320186) (xy 19.130971 -54.292815)
			(xy 19.138792 -54.238635) (xy 19.154283 -54.186132) (xy 19.177128 -54.136385) (xy 19.206855 -54.090419)
			(xy 19.224498 -54.069488) (xy 19.224752 -54.069234) (xy 19.230337 -54.062146) (xy 19.236583 -54.04523)
			(xy 19.236944 -54.036214) (xy 19.236944 -53.969158) (xy 19.236572 -53.960142) (xy 19.230336 -53.943225)
			(xy 19.224752 -53.936138) (xy 19.224498 -53.936138) (xy 19.224498 -53.935884) (xy 19.206885 -53.914931)
			(xy 19.177169 -53.868964) (xy 19.154328 -53.819222) (xy 19.138831 -53.766726) (xy 19.130996 -53.712554)
			(xy 19.130518 -53.685186) (xy 19.130942 -53.657932) (xy 19.138701 -53.603978) (xy 19.154061 -53.551678)
			(xy 19.176707 -53.502096) (xy 19.206179 -53.456241) (xy 19.241876 -53.415048) (xy 19.283073 -53.379355)
			(xy 19.328931 -53.349887) (xy 19.378515 -53.327247) (xy 19.430817 -53.311893) (xy 19.484772 -53.304139)
			(xy 19.512026 -53.303678) (xy 19.538343 -53.304137) (xy 19.590473 -53.311399) (xy 19.615912 -53.318156)
			(xy 19.627342 -53.321458) (xy 19.650456 -53.31714) (xy 19.724878 -53.260752) (xy 19.733875 -53.253164)
			(xy 19.744344 -53.232119) (xy 19.744944 -53.220366) (xy 19.744944 -48.947324) (xy 19.745072 -48.942433)
			(xy 19.746996 -48.93284) (xy 19.748754 -48.928274) (xy 19.845782 -48.689006) (xy 19.847941 -48.684171)
			(xy 19.853964 -48.675466) (xy 19.85772 -48.671734) (xy 19.949922 -48.58258) (xy 19.95043 -48.582072)
			(xy 21.58492 -46.947582) (xy 21.585428 -46.947074) (xy 21.611295 -46.921224) (xy 21.667676 -46.874644)
			(xy 21.728693 -46.834328) (xy 21.793654 -46.800733) (xy 21.861821 -46.774241) (xy 21.932419 -46.755153)
			(xy 21.96846 -46.748954) (xy 21.972524 -46.727618) (xy 21.979295 -46.694189) (xy 21.998653 -46.628784)
			(xy 22.024406 -46.565622) (xy 22.0563 -46.505327) (xy 22.094018 -46.448495) (xy 22.13719 -46.395686)
			(xy 22.160992 -46.371256) (xy 22.206458 -46.32579) (xy 22.213167 -46.318398) (xy 22.220762 -46.299956)
			(xy 22.220755 -46.280011) (xy 22.213148 -46.261573) (xy 22.206458 -46.254162) (xy 22.200616 -46.24832)
			(xy 22.187916 -46.241462) (xy 22.180296 -46.239938) (xy 22.179788 -46.239938) (xy 22.153972 -46.234546)
			(xy 22.104025 -46.217614) (xy 22.056887 -46.193962) (xy 22.013458 -46.164041) (xy 21.974565 -46.128421)
			(xy 21.940951 -46.087783) (xy 21.913257 -46.042901) (xy 21.892011 -45.994631) (xy 21.877618 -45.943894)
			(xy 21.870353 -45.891657) (xy 21.869908 -45.865288) (xy 21.870344 -45.838034) (xy 21.878103 -45.784081)
			(xy 21.893461 -45.731782) (xy 21.916106 -45.682201) (xy 21.945577 -45.636347) (xy 21.981274 -45.595154)
			(xy 22.022469 -45.55946) (xy 22.068325 -45.529993) (xy 22.117908 -45.507351) (xy 22.170209 -45.491997)
			(xy 22.224162 -45.484242) (xy 22.251416 -45.48378) (xy 22.277801 -45.4842) (xy 22.330069 -45.491455)
			(xy 22.380836 -45.50585) (xy 22.429132 -45.527111) (xy 22.474033 -45.554832) (xy 22.514681 -45.588482)
			(xy 22.550298 -45.627417) (xy 22.580204 -45.670894) (xy 22.603826 -45.718081) (xy 22.620712 -45.768075)
			(xy 22.626066 -45.793914) (xy 22.626066 -45.794168) (xy 22.627802 -45.80145) (xy 22.63491 -45.814619)
			(xy 22.640036 -45.820076) (xy 22.64029 -45.82033) (xy 22.647702 -45.827014) (xy 22.666135 -45.834611)
			(xy 22.686073 -45.834611) (xy 22.704506 -45.827014) (xy 22.711918 -45.82033) (xy 22.772116 -45.760386)
			(xy 22.80091 -45.732414) (xy 22.863914 -45.682661) (xy 22.932294 -45.640601) (xy 23.005115 -45.606808)
			(xy 23.081382 -45.581744) (xy 23.120604 -45.573188) (xy 23.130242 -45.570764) (xy 23.146728 -45.559695)
			(xy 23.157782 -45.543198) (xy 23.160228 -45.533564) (xy 23.168766 -45.494338) (xy 23.193829 -45.418068)
			(xy 23.227624 -45.345246) (xy 23.269687 -45.276865) (xy 23.319444 -45.213862) (xy 23.347426 -45.185076)
			(xy 24.050498 -44.48175) (xy 24.078087 -44.454845) (xy 24.138298 -44.406742) (xy 24.203519 -44.365689)
			(xy 24.27293 -44.332203) (xy 24.345656 -44.306707) (xy 24.420781 -44.289521) (xy 24.497359 -44.280861)
			(xy 24.535892 -44.280328) (xy 24.7396 -44.280328) (xy 24.741378 -44.280582) (xy 24.741632 -44.280582)
			(xy 24.751367 -44.280115) (xy 24.769416 -44.2728) (xy 24.783456 -44.259305) (xy 24.78786 -44.25061)
			(xy 24.82596 -44.166028) (xy 24.829518 -44.156862) (xy 24.830237 -44.137236) (xy 24.82355 -44.11877)
			(xy 24.817324 -44.111164) (xy 24.799134 -44.090083) (xy 24.768466 -44.04361) (xy 24.74488 -43.993172)
			(xy 24.728876 -43.939841) (xy 24.720795 -43.88475) (xy 24.720296 -43.85691) (xy 24.720782 -43.829659)
			(xy 24.728538 -43.775711) (xy 24.743893 -43.723416) (xy 24.766535 -43.673839) (xy 24.796001 -43.627989)
			(xy 24.831692 -43.586798) (xy 24.872883 -43.551107) (xy 24.918733 -43.521641) (xy 24.96831 -43.498999)
			(xy 25.020605 -43.483644) (xy 25.074553 -43.475888) (xy 25.129055 -43.475888) (xy 25.183003 -43.483644)
			(xy 25.235298 -43.498999) (xy 25.284875 -43.521641) (xy 25.330725 -43.551107) (xy 25.371916 -43.586798)
			(xy 25.407607 -43.627989) (xy 25.437073 -43.673839) (xy 25.459715 -43.723416) (xy 25.47507 -43.775711)
			(xy 25.482826 -43.829659) (xy 25.483312 -43.85691) (xy 26.933142 -43.85691) (xy 26.937213 -43.801288)
			(xy 26.949339 -43.746851) (xy 26.969262 -43.69476) (xy 26.996558 -43.646125) (xy 27.030644 -43.601982)
			(xy 27.070793 -43.563273) (xy 27.116151 -43.530822) (xy 27.165751 -43.505321) (xy 27.218535 -43.487314)
			(xy 27.273378 -43.477184) (xy 27.329112 -43.475147) (xy 27.384549 -43.481247) (xy 27.438506 -43.495353)
			(xy 27.489835 -43.517165) (xy 27.537441 -43.546219) (xy 27.580309 -43.581894) (xy 27.617526 -43.623431)
			(xy 27.648299 -43.669944) (xy 27.671971 -43.720441) (xy 27.67673 -43.73626) (xy 46.213012 -43.73626)
			(xy 46.217083 -43.680638) (xy 46.229209 -43.626201) (xy 46.249132 -43.57411) (xy 46.276428 -43.525475)
			(xy 46.310514 -43.481332) (xy 46.350663 -43.442623) (xy 46.396021 -43.410172) (xy 46.445621 -43.384671)
			(xy 46.498405 -43.366664) (xy 46.553248 -43.356534) (xy 46.608982 -43.354497) (xy 46.664419 -43.360597)
			(xy 46.718376 -43.374703) (xy 46.769705 -43.396515) (xy 46.817311 -43.425569) (xy 46.860179 -43.461244)
			(xy 46.897396 -43.502781) (xy 46.928169 -43.549294) (xy 46.951841 -43.599791) (xy 46.967909 -43.653198)
			(xy 46.976029 -43.708374) (xy 46.976538 -43.73626) (xy 46.976029 -43.764146) (xy 46.967909 -43.819322)
			(xy 46.951841 -43.872729) (xy 46.928169 -43.923226) (xy 46.897396 -43.969739) (xy 46.860179 -44.011276)
			(xy 46.817311 -44.046951) (xy 46.769705 -44.076005) (xy 46.718376 -44.097817) (xy 46.664419 -44.111923)
			(xy 46.608982 -44.118023) (xy 46.553248 -44.115986) (xy 46.498405 -44.105856) (xy 46.445621 -44.087849)
			(xy 46.396021 -44.062348) (xy 46.350663 -44.029897) (xy 46.310514 -43.991188) (xy 46.276428 -43.947045)
			(xy 46.249132 -43.89841) (xy 46.229209 -43.846319) (xy 46.217083 -43.791882) (xy 46.213012 -43.73626)
			(xy 27.67673 -43.73626) (xy 27.688039 -43.773848) (xy 27.696159 -43.829024) (xy 27.696668 -43.85691)
			(xy 27.696159 -43.884796) (xy 27.688039 -43.939972) (xy 27.671971 -43.993379) (xy 27.648299 -44.043876)
			(xy 27.617526 -44.090389) (xy 27.580309 -44.131926) (xy 27.537441 -44.167601) (xy 27.489835 -44.196655)
			(xy 27.438506 -44.218467) (xy 27.384549 -44.232573) (xy 27.329112 -44.238673) (xy 27.273378 -44.236636)
			(xy 27.218535 -44.226506) (xy 27.165751 -44.208499) (xy 27.116151 -44.182998) (xy 27.070793 -44.150547)
			(xy 27.030644 -44.111838) (xy 26.996558 -44.067695) (xy 26.969262 -44.01906) (xy 26.949339 -43.966969)
			(xy 26.937213 -43.912532) (xy 26.933142 -43.85691) (xy 25.483312 -43.85691) (xy 25.482864 -43.883097)
			(xy 25.475687 -43.934978) (xy 25.461481 -43.98539) (xy 25.440515 -44.033385) (xy 25.413181 -44.078062)
			(xy 25.379995 -44.118582) (xy 25.341579 -44.154182) (xy 25.298655 -44.184193) (xy 25.27554 -44.196508)
			(xy 25.266453 -44.201655) (xy 25.253068 -44.217653) (xy 25.247154 -44.237656) (xy 25.24969 -44.258361)
			(xy 25.260256 -44.276346) (xy 25.277106 -44.288641) (xy 25.297458 -44.293215) (xy 25.307798 -44.291758)
			(xy 25.338573 -44.286429) (xy 25.400773 -44.280706) (xy 25.432004 -44.280328) (xy 26.893266 -44.280328)
			(xy 26.928135 -44.28073) (xy 26.997514 -44.287779) (xy 27.065821 -44.301827) (xy 27.132351 -44.322731)
			(xy 27.196419 -44.350274) (xy 27.257362 -44.384173) (xy 27.286204 -44.403772) (xy 27.294943 -44.409287)
			(xy 27.31516 -44.413458) (xy 27.335377 -44.409287) (xy 27.344116 -44.403772) (xy 27.372961 -44.384178)
			(xy 27.433904 -44.350281) (xy 27.497971 -44.32274) (xy 27.564501 -44.301839) (xy 27.632807 -44.287792)
			(xy 27.702186 -44.280745) (xy 27.737054 -44.280328) (xy 42.943526 -44.280328) (xy 42.967148 -44.266358)
			(xy 42.971974 -44.257722) (xy 42.980102 -44.265596) (xy 42.987478 -44.272216) (xy 43.005766 -44.279803)
			(xy 43.015662 -44.280328) (xy 45.974508 -44.280328) (xy 46.014376 -44.280974) (xy 46.093569 -44.290266)
			(xy 46.171154 -44.308666) (xy 46.246085 -44.335926) (xy 46.317356 -44.371681) (xy 46.384008 -44.415448)
			(xy 46.414944 -44.440602) (xy 46.421975 -44.445987) (xy 46.438608 -44.452026) (xy 46.456304 -44.452026)
			(xy 46.472937 -44.445987) (xy 46.479968 -44.440602) (xy 46.510877 -44.415407) (xy 46.577517 -44.371605)
			(xy 46.648788 -44.335829) (xy 46.723727 -44.308563) (xy 46.801325 -44.290174) (xy 46.880531 -44.280912)
			(xy 46.920404 -44.280328) (xy 50.739548 -44.280328) (xy 50.741326 -44.280582) (xy 50.74158 -44.280582)
			(xy 50.751319 -44.28015) (xy 50.769368 -44.272819) (xy 50.783407 -44.259311) (xy 50.787808 -44.25061)
			(xy 50.825908 -44.166028) (xy 50.829455 -44.15686) (xy 50.830173 -44.137237) (xy 50.823494 -44.118772)
			(xy 50.817272 -44.111164) (xy 50.799073 -44.09009) (xy 50.768408 -44.043614) (xy 50.744825 -43.993174)
			(xy 50.728823 -43.939842) (xy 50.720743 -43.884751) (xy 50.720244 -43.85691) (xy 50.72073 -43.829659)
			(xy 50.728486 -43.775711) (xy 50.743841 -43.723416) (xy 50.766483 -43.673839) (xy 50.795949 -43.627989)
			(xy 50.83164 -43.586798) (xy 50.872831 -43.551107) (xy 50.918681 -43.521641) (xy 50.968258 -43.498999)
			(xy 51.020553 -43.483644) (xy 51.074501 -43.475888) (xy 51.129003 -43.475888) (xy 51.182951 -43.483644)
			(xy 51.235246 -43.498999) (xy 51.284823 -43.521641) (xy 51.330673 -43.551107) (xy 51.371864 -43.586798)
			(xy 51.407555 -43.627989) (xy 51.437021 -43.673839) (xy 51.459663 -43.723416) (xy 51.475018 -43.775711)
			(xy 51.482774 -43.829659) (xy 51.48326 -43.85691) (xy 52.93309 -43.85691) (xy 52.937161 -43.801288)
			(xy 52.949287 -43.746851) (xy 52.96921 -43.69476) (xy 52.996506 -43.646125) (xy 53.030592 -43.601982)
			(xy 53.070741 -43.563273) (xy 53.116099 -43.530822) (xy 53.165699 -43.505321) (xy 53.218483 -43.487314)
			(xy 53.273326 -43.477184) (xy 53.32906 -43.475147) (xy 53.384497 -43.481247) (xy 53.438454 -43.495353)
			(xy 53.489783 -43.517165) (xy 53.537389 -43.546219) (xy 53.580257 -43.581894) (xy 53.617474 -43.623431)
			(xy 53.648247 -43.669944) (xy 53.671919 -43.720441) (xy 53.676678 -43.73626) (xy 72.21296 -43.73626)
			(xy 72.217031 -43.680638) (xy 72.229157 -43.626201) (xy 72.24908 -43.57411) (xy 72.276376 -43.525475)
			(xy 72.310462 -43.481332) (xy 72.350611 -43.442623) (xy 72.395969 -43.410172) (xy 72.445569 -43.384671)
			(xy 72.498353 -43.366664) (xy 72.553196 -43.356534) (xy 72.60893 -43.354497) (xy 72.664367 -43.360597)
			(xy 72.718324 -43.374703) (xy 72.769653 -43.396515) (xy 72.817259 -43.425569) (xy 72.860127 -43.461244)
			(xy 72.897344 -43.502781) (xy 72.928117 -43.549294) (xy 72.951789 -43.599791) (xy 72.967857 -43.653198)
			(xy 72.975977 -43.708374) (xy 72.976486 -43.73626) (xy 72.975977 -43.764146) (xy 72.967857 -43.819322)
			(xy 72.951789 -43.872729) (xy 72.928117 -43.923226) (xy 72.897344 -43.969739) (xy 72.860127 -44.011276)
			(xy 72.817259 -44.046951) (xy 72.769653 -44.076005) (xy 72.718324 -44.097817) (xy 72.664367 -44.111923)
			(xy 72.60893 -44.118023) (xy 72.553196 -44.115986) (xy 72.498353 -44.105856) (xy 72.445569 -44.087849)
			(xy 72.395969 -44.062348) (xy 72.350611 -44.029897) (xy 72.310462 -43.991188) (xy 72.276376 -43.947045)
			(xy 72.24908 -43.89841) (xy 72.229157 -43.846319) (xy 72.217031 -43.791882) (xy 72.21296 -43.73626)
			(xy 53.676678 -43.73626) (xy 53.687987 -43.773848) (xy 53.696107 -43.829024) (xy 53.696616 -43.85691)
			(xy 53.696107 -43.884796) (xy 53.687987 -43.939972) (xy 53.671919 -43.993379) (xy 53.648247 -44.043876)
			(xy 53.617474 -44.090389) (xy 53.580257 -44.131926) (xy 53.537389 -44.167601) (xy 53.489783 -44.196655)
			(xy 53.438454 -44.218467) (xy 53.384497 -44.232573) (xy 53.32906 -44.238673) (xy 53.273326 -44.236636)
			(xy 53.218483 -44.226506) (xy 53.165699 -44.208499) (xy 53.116099 -44.182998) (xy 53.070741 -44.150547)
			(xy 53.030592 -44.111838) (xy 52.996506 -44.067695) (xy 52.96921 -44.01906) (xy 52.949287 -43.966969)
			(xy 52.937161 -43.912532) (xy 52.93309 -43.85691) (xy 51.48326 -43.85691) (xy 51.482786 -43.883096)
			(xy 51.47561 -43.934975) (xy 51.461406 -43.985385) (xy 51.440443 -44.033379) (xy 51.413113 -44.078055)
			(xy 51.379931 -44.118575) (xy 51.34152 -44.154177) (xy 51.298601 -44.184191) (xy 51.275488 -44.196508)
			(xy 51.266428 -44.201687) (xy 51.253064 -44.21768) (xy 51.247163 -44.237669) (xy 51.249698 -44.258356)
			(xy 51.260252 -44.276328) (xy 51.277083 -44.28862) (xy 51.297414 -44.293204) (xy 51.307746 -44.291758)
			(xy 51.33852 -44.286423) (xy 51.400721 -44.280703) (xy 51.431952 -44.280328) (xy 52.893214 -44.280328)
			(xy 52.928082 -44.280757) (xy 52.997461 -44.287801) (xy 53.065767 -44.301844) (xy 53.132297 -44.322743)
			(xy 53.196365 -44.350281) (xy 53.257309 -44.384175) (xy 53.286152 -44.403772) (xy 53.294891 -44.409287)
			(xy 53.315108 -44.413458) (xy 53.335325 -44.409287) (xy 53.344064 -44.403772) (xy 53.372895 -44.384156)
			(xy 53.433841 -44.350263) (xy 53.497911 -44.322725) (xy 53.564444 -44.301827) (xy 53.632753 -44.287785)
			(xy 53.702133 -44.280743) (xy 53.737002 -44.280328) (xy 68.943474 -44.280328) (xy 68.967096 -44.266358)
			(xy 68.971922 -44.257722) (xy 68.98005 -44.265596) (xy 68.98741 -44.272236) (xy 69.00571 -44.279811)
			(xy 69.01561 -44.280328) (xy 71.974456 -44.280328) (xy 72.014325 -44.280946) (xy 72.093519 -44.290243)
			(xy 72.171104 -44.308649) (xy 72.246036 -44.335914) (xy 72.317306 -44.371674) (xy 72.383956 -44.415445)
			(xy 72.414892 -44.440602) (xy 72.421923 -44.445987) (xy 72.438556 -44.452026) (xy 72.456252 -44.452026)
			(xy 72.472885 -44.445987) (xy 72.479916 -44.440602) (xy 72.510845 -44.415432) (xy 72.57748 -44.371626)
			(xy 72.648746 -44.335847) (xy 72.723682 -44.308576) (xy 72.801276 -44.290183) (xy 72.88048 -44.280915)
			(xy 72.920352 -44.280328) (xy 76.739496 -44.280328) (xy 76.741274 -44.280582) (xy 76.741528 -44.280582)
			(xy 76.751263 -44.280112) (xy 76.769311 -44.272799) (xy 76.783352 -44.259305) (xy 76.787756 -44.25061)
			(xy 76.825856 -44.166028) (xy 76.829415 -44.156862) (xy 76.830134 -44.137236) (xy 76.823447 -44.11877)
			(xy 76.81722 -44.111164) (xy 76.799029 -44.090084) (xy 76.768362 -44.04361) (xy 76.744776 -43.993172)
			(xy 76.728772 -43.939841) (xy 76.720691 -43.88475) (xy 76.720192 -43.85691) (xy 76.720678 -43.829659)
			(xy 76.728434 -43.775711) (xy 76.743789 -43.723416) (xy 76.766431 -43.673839) (xy 76.795897 -43.627989)
			(xy 76.831588 -43.586798) (xy 76.872779 -43.551107) (xy 76.918629 -43.521641) (xy 76.968206 -43.498999)
			(xy 77.020501 -43.483644) (xy 77.074449 -43.475888) (xy 77.128951 -43.475888) (xy 77.182899 -43.483644)
			(xy 77.235194 -43.498999) (xy 77.284771 -43.521641) (xy 77.330621 -43.551107) (xy 77.371812 -43.586798)
			(xy 77.407503 -43.627989) (xy 77.436969 -43.673839) (xy 77.459611 -43.723416) (xy 77.474966 -43.775711)
			(xy 77.482722 -43.829659) (xy 77.483208 -43.85691) (xy 78.933038 -43.85691) (xy 78.937109 -43.801288)
			(xy 78.949235 -43.746851) (xy 78.969158 -43.69476) (xy 78.996454 -43.646125) (xy 79.03054 -43.601982)
			(xy 79.070689 -43.563273) (xy 79.116047 -43.530822) (xy 79.165647 -43.505321) (xy 79.218431 -43.487314)
			(xy 79.273274 -43.477184) (xy 79.329008 -43.475147) (xy 79.384445 -43.481247) (xy 79.438402 -43.495353)
			(xy 79.489731 -43.517165) (xy 79.537337 -43.546219) (xy 79.580205 -43.581894) (xy 79.617422 -43.623431)
			(xy 79.648195 -43.669944) (xy 79.671867 -43.720441) (xy 79.676626 -43.73626) (xy 98.212908 -43.73626)
			(xy 98.216979 -43.680638) (xy 98.229105 -43.626201) (xy 98.249028 -43.57411) (xy 98.276324 -43.525475)
			(xy 98.31041 -43.481332) (xy 98.350559 -43.442623) (xy 98.395917 -43.410172) (xy 98.445517 -43.384671)
			(xy 98.498301 -43.366664) (xy 98.553144 -43.356534) (xy 98.608878 -43.354497) (xy 98.664315 -43.360597)
			(xy 98.718272 -43.374703) (xy 98.769601 -43.396515) (xy 98.817207 -43.425569) (xy 98.860075 -43.461244)
			(xy 98.897292 -43.502781) (xy 98.928065 -43.549294) (xy 98.951737 -43.599791) (xy 98.967805 -43.653198)
			(xy 98.975925 -43.708374) (xy 98.976434 -43.73626) (xy 98.975925 -43.764146) (xy 98.967805 -43.819322)
			(xy 98.951737 -43.872729) (xy 98.928065 -43.923226) (xy 98.897292 -43.969739) (xy 98.860075 -44.011276)
			(xy 98.817207 -44.046951) (xy 98.769601 -44.076005) (xy 98.718272 -44.097817) (xy 98.664315 -44.111923)
			(xy 98.608878 -44.118023) (xy 98.553144 -44.115986) (xy 98.498301 -44.105856) (xy 98.445517 -44.087849)
			(xy 98.395917 -44.062348) (xy 98.350559 -44.029897) (xy 98.31041 -43.991188) (xy 98.276324 -43.947045)
			(xy 98.249028 -43.89841) (xy 98.229105 -43.846319) (xy 98.216979 -43.791882) (xy 98.212908 -43.73626)
			(xy 79.676626 -43.73626) (xy 79.687935 -43.773848) (xy 79.696055 -43.829024) (xy 79.696564 -43.85691)
			(xy 79.696055 -43.884796) (xy 79.687935 -43.939972) (xy 79.671867 -43.993379) (xy 79.648195 -44.043876)
			(xy 79.617422 -44.090389) (xy 79.580205 -44.131926) (xy 79.537337 -44.167601) (xy 79.489731 -44.196655)
			(xy 79.438402 -44.218467) (xy 79.384445 -44.232573) (xy 79.329008 -44.238673) (xy 79.273274 -44.236636)
			(xy 79.218431 -44.226506) (xy 79.165647 -44.208499) (xy 79.116047 -44.182998) (xy 79.070689 -44.150547)
			(xy 79.03054 -44.111838) (xy 78.996454 -44.067695) (xy 78.969158 -44.01906) (xy 78.949235 -43.966969)
			(xy 78.937109 -43.912532) (xy 78.933038 -43.85691) (xy 77.483208 -43.85691) (xy 77.482762 -43.883097)
			(xy 77.475585 -43.934979) (xy 77.461379 -43.98539) (xy 77.440412 -44.033386) (xy 77.413079 -44.078063)
			(xy 77.379892 -44.118582) (xy 77.341476 -44.154182) (xy 77.298552 -44.184193) (xy 77.275436 -44.196508)
			(xy 77.266351 -44.201657) (xy 77.252967 -44.217655) (xy 77.247055 -44.237657) (xy 77.24959 -44.25836)
			(xy 77.260155 -44.276345) (xy 77.277005 -44.28864) (xy 77.297355 -44.293214) (xy 77.307694 -44.291758)
			(xy 77.338469 -44.28643) (xy 77.400669 -44.280706) (xy 77.4319 -44.280328) (xy 78.893162 -44.280328)
			(xy 78.92803 -44.280732) (xy 78.99741 -44.28778) (xy 79.065717 -44.301829) (xy 79.132247 -44.322732)
			(xy 79.196314 -44.350275) (xy 79.257258 -44.384173) (xy 79.2861 -44.403772) (xy 79.294839 -44.409287)
			(xy 79.315056 -44.413458) (xy 79.335273 -44.409287) (xy 79.344012 -44.403772) (xy 79.372858 -44.384179)
			(xy 79.433801 -44.350283) (xy 79.497868 -44.322741) (xy 79.564397 -44.30184) (xy 79.632703 -44.287793)
			(xy 79.702082 -44.280746) (xy 79.73695 -44.280328) (xy 94.943422 -44.280328) (xy 94.967044 -44.266358)
			(xy 94.97187 -44.257722) (xy 94.979998 -44.265596) (xy 94.987376 -44.272214) (xy 95.005662 -44.279802)
			(xy 95.015558 -44.280328) (xy 97.974404 -44.280328) (xy 98.014273 -44.280918) (xy 98.093469 -44.290221)
			(xy 98.171054 -44.308632) (xy 98.245986 -44.335903) (xy 98.317256 -44.371667) (xy 98.383905 -44.415443)
			(xy 98.41484 -44.440602) (xy 98.421871 -44.445987) (xy 98.438504 -44.452026) (xy 98.4562 -44.452026)
			(xy 98.472833 -44.445987) (xy 98.479864 -44.440602) (xy 98.510775 -44.415409) (xy 98.577414 -44.371606)
			(xy 98.648684 -44.33583) (xy 98.723624 -44.308564) (xy 98.801221 -44.290175) (xy 98.880427 -44.280912)
			(xy 98.9203 -44.280328) (xy 102.739444 -44.280328) (xy 102.741222 -44.280582) (xy 102.741476 -44.280582)
			(xy 102.751214 -44.280147) (xy 102.769264 -44.272817) (xy 102.783303 -44.25931) (xy 102.787704 -44.25061)
			(xy 102.825804 -44.166028) (xy 102.829352 -44.15686) (xy 102.83007 -44.137237) (xy 102.82339 -44.118772)
			(xy 102.817168 -44.111164) (xy 102.798968 -44.090091) (xy 102.768304 -44.043614) (xy 102.74472 -43.993174)
			(xy 102.728719 -43.939842) (xy 102.720639 -43.884751) (xy 102.72014 -43.85691) (xy 102.720626 -43.829659)
			(xy 102.728382 -43.775711) (xy 102.743737 -43.723416) (xy 102.766379 -43.673839) (xy 102.795845 -43.627989)
			(xy 102.831536 -43.586798) (xy 102.872727 -43.551107) (xy 102.918577 -43.521641) (xy 102.968154 -43.498999)
			(xy 103.020449 -43.483644) (xy 103.074397 -43.475888) (xy 103.128899 -43.475888) (xy 103.182847 -43.483644)
			(xy 103.235142 -43.498999) (xy 103.284719 -43.521641) (xy 103.330569 -43.551107) (xy 103.37176 -43.586798)
			(xy 103.407451 -43.627989) (xy 103.436917 -43.673839) (xy 103.459559 -43.723416) (xy 103.474914 -43.775711)
			(xy 103.48267 -43.829659) (xy 103.483156 -43.85691) (xy 104.932986 -43.85691) (xy 104.937057 -43.801288)
			(xy 104.949183 -43.746851) (xy 104.969106 -43.69476) (xy 104.996402 -43.646125) (xy 105.030488 -43.601982)
			(xy 105.070637 -43.563273) (xy 105.115995 -43.530822) (xy 105.165595 -43.505321) (xy 105.218379 -43.487314)
			(xy 105.273222 -43.477184) (xy 105.328956 -43.475147) (xy 105.384393 -43.481247) (xy 105.43835 -43.495353)
			(xy 105.489679 -43.517165) (xy 105.537285 -43.546219) (xy 105.580153 -43.581894) (xy 105.61737 -43.623431)
			(xy 105.648143 -43.669944) (xy 105.671815 -43.720441) (xy 105.676574 -43.73626) (xy 136.313162 -43.73626)
			(xy 136.317233 -43.680638) (xy 136.329359 -43.626201) (xy 136.349282 -43.57411) (xy 136.376578 -43.525475)
			(xy 136.410664 -43.481332) (xy 136.450813 -43.442623) (xy 136.496171 -43.410172) (xy 136.545771 -43.384671)
			(xy 136.598555 -43.366664) (xy 136.653398 -43.356534) (xy 136.709132 -43.354497) (xy 136.764569 -43.360597)
			(xy 136.818526 -43.374703) (xy 136.869855 -43.396515) (xy 136.917461 -43.425569) (xy 136.960329 -43.461244)
			(xy 136.997546 -43.502781) (xy 137.028319 -43.549294) (xy 137.051991 -43.599791) (xy 137.068059 -43.653198)
			(xy 137.076179 -43.708374) (xy 137.076688 -43.73626) (xy 137.076179 -43.764146) (xy 137.068059 -43.819322)
			(xy 137.051991 -43.872729) (xy 137.028319 -43.923226) (xy 136.997546 -43.969739) (xy 136.960329 -44.011276)
			(xy 136.917461 -44.046951) (xy 136.869855 -44.076005) (xy 136.818526 -44.097817) (xy 136.764569 -44.111923)
			(xy 136.709132 -44.118023) (xy 136.653398 -44.115986) (xy 136.598555 -44.105856) (xy 136.545771 -44.087849)
			(xy 136.496171 -44.062348) (xy 136.450813 -44.029897) (xy 136.410664 -43.991188) (xy 136.376578 -43.947045)
			(xy 136.349282 -43.89841) (xy 136.329359 -43.846319) (xy 136.317233 -43.791882) (xy 136.313162 -43.73626)
			(xy 105.676574 -43.73626) (xy 105.687883 -43.773848) (xy 105.696003 -43.829024) (xy 105.696512 -43.85691)
			(xy 105.696003 -43.884796) (xy 105.687883 -43.939972) (xy 105.671815 -43.993379) (xy 105.648143 -44.043876)
			(xy 105.61737 -44.090389) (xy 105.580153 -44.131926) (xy 105.537285 -44.167601) (xy 105.489679 -44.196655)
			(xy 105.43835 -44.218467) (xy 105.384393 -44.232573) (xy 105.328956 -44.238673) (xy 105.273222 -44.236636)
			(xy 105.218379 -44.226506) (xy 105.165595 -44.208499) (xy 105.115995 -44.182998) (xy 105.070637 -44.150547)
			(xy 105.030488 -44.111838) (xy 104.996402 -44.067695) (xy 104.969106 -44.01906) (xy 104.949183 -43.966969)
			(xy 104.937057 -43.912532) (xy 104.932986 -43.85691) (xy 103.483156 -43.85691) (xy 103.482684 -43.883096)
			(xy 103.475508 -43.934975) (xy 103.461304 -43.985385) (xy 103.44034 -44.033379) (xy 103.413011 -44.078056)
			(xy 103.379828 -44.118576) (xy 103.341416 -44.154177) (xy 103.298497 -44.184191) (xy 103.275384 -44.196508)
			(xy 103.266275 -44.201627) (xy 103.252871 -44.217629) (xy 103.246947 -44.237646) (xy 103.249483 -44.258365)
			(xy 103.260059 -44.276362) (xy 103.276927 -44.288659) (xy 103.297296 -44.293224) (xy 103.307642 -44.291758)
			(xy 103.338416 -44.286423) (xy 103.400617 -44.280704) (xy 103.431848 -44.280328) (xy 104.89311 -44.280328)
			(xy 104.927978 -44.280759) (xy 104.997356 -44.287802) (xy 105.065663 -44.301845) (xy 105.132193 -44.322744)
			(xy 105.196261 -44.350282) (xy 105.257205 -44.384175) (xy 105.286048 -44.403772) (xy 105.294787 -44.409287)
			(xy 105.315004 -44.413458) (xy 105.335221 -44.409287) (xy 105.34396 -44.403772) (xy 105.372792 -44.384158)
			(xy 105.433738 -44.350264) (xy 105.497808 -44.322726) (xy 105.56434 -44.301828) (xy 105.632649 -44.287786)
			(xy 105.702029 -44.280743) (xy 105.736898 -44.280328) (xy 133.043676 -44.280328) (xy 133.067298 -44.266358)
			(xy 133.072124 -44.257722) (xy 133.080252 -44.265596) (xy 133.087611 -44.272237) (xy 133.105912 -44.279812)
			(xy 133.115812 -44.280328) (xy 136.074658 -44.280328) (xy 136.114527 -44.280944) (xy 136.193721 -44.290242)
			(xy 136.271306 -44.308648) (xy 136.346238 -44.335914) (xy 136.417508 -44.371673) (xy 136.484158 -44.415445)
			(xy 136.515094 -44.440602) (xy 136.522125 -44.445987) (xy 136.538758 -44.452026) (xy 136.556454 -44.452026)
			(xy 136.573087 -44.445987) (xy 136.580118 -44.440602) (xy 136.611046 -44.415431) (xy 136.677681 -44.371625)
			(xy 136.748948 -44.335846) (xy 136.823884 -44.308576) (xy 136.901478 -44.290182) (xy 136.980682 -44.280915)
			(xy 137.020554 -44.280328) (xy 140.839698 -44.280328) (xy 140.841476 -44.280582) (xy 140.84173 -44.280582)
			(xy 140.851465 -44.280114) (xy 140.869514 -44.272799) (xy 140.883554 -44.259305) (xy 140.887958 -44.25061)
			(xy 140.926058 -44.166028) (xy 140.929616 -44.156862) (xy 140.930335 -44.137236) (xy 140.923649 -44.11877)
			(xy 140.917422 -44.111164) (xy 140.899231 -44.090083) (xy 140.868564 -44.04361) (xy 140.844978 -43.993172)
			(xy 140.828974 -43.939841) (xy 140.820893 -43.88475) (xy 140.820394 -43.85691) (xy 140.82088 -43.829659)
			(xy 140.828636 -43.775711) (xy 140.843991 -43.723416) (xy 140.866633 -43.673839) (xy 140.896099 -43.627989)
			(xy 140.93179 -43.586798) (xy 140.972981 -43.551107) (xy 141.018831 -43.521641) (xy 141.068408 -43.498999)
			(xy 141.120703 -43.483644) (xy 141.174651 -43.475888) (xy 141.229153 -43.475888) (xy 141.283101 -43.483644)
			(xy 141.335396 -43.498999) (xy 141.384973 -43.521641) (xy 141.430823 -43.551107) (xy 141.472014 -43.586798)
			(xy 141.507705 -43.627989) (xy 141.537171 -43.673839) (xy 141.559813 -43.723416) (xy 141.575168 -43.775711)
			(xy 141.582924 -43.829659) (xy 141.58341 -43.85691) (xy 143.03324 -43.85691) (xy 143.037311 -43.801288)
			(xy 143.049437 -43.746851) (xy 143.06936 -43.69476) (xy 143.096656 -43.646125) (xy 143.130742 -43.601982)
			(xy 143.170891 -43.563273) (xy 143.216249 -43.530822) (xy 143.265849 -43.505321) (xy 143.318633 -43.487314)
			(xy 143.373476 -43.477184) (xy 143.42921 -43.475147) (xy 143.484647 -43.481247) (xy 143.538604 -43.495353)
			(xy 143.589933 -43.517165) (xy 143.637539 -43.546219) (xy 143.680407 -43.581894) (xy 143.717624 -43.623431)
			(xy 143.748397 -43.669944) (xy 143.772069 -43.720441) (xy 143.776828 -43.73626) (xy 162.31311 -43.73626)
			(xy 162.317181 -43.680638) (xy 162.329307 -43.626201) (xy 162.34923 -43.57411) (xy 162.376526 -43.525475)
			(xy 162.410612 -43.481332) (xy 162.450761 -43.442623) (xy 162.496119 -43.410172) (xy 162.545719 -43.384671)
			(xy 162.598503 -43.366664) (xy 162.653346 -43.356534) (xy 162.70908 -43.354497) (xy 162.764517 -43.360597)
			(xy 162.818474 -43.374703) (xy 162.869803 -43.396515) (xy 162.917409 -43.425569) (xy 162.960277 -43.461244)
			(xy 162.997494 -43.502781) (xy 163.028267 -43.549294) (xy 163.051939 -43.599791) (xy 163.068007 -43.653198)
			(xy 163.076127 -43.708374) (xy 163.076636 -43.73626) (xy 163.076127 -43.764146) (xy 163.068007 -43.819322)
			(xy 163.051939 -43.872729) (xy 163.028267 -43.923226) (xy 162.997494 -43.969739) (xy 162.960277 -44.011276)
			(xy 162.917409 -44.046951) (xy 162.869803 -44.076005) (xy 162.818474 -44.097817) (xy 162.764517 -44.111923)
			(xy 162.70908 -44.118023) (xy 162.653346 -44.115986) (xy 162.598503 -44.105856) (xy 162.545719 -44.087849)
			(xy 162.496119 -44.062348) (xy 162.450761 -44.029897) (xy 162.410612 -43.991188) (xy 162.376526 -43.947045)
			(xy 162.34923 -43.89841) (xy 162.329307 -43.846319) (xy 162.317181 -43.791882) (xy 162.31311 -43.73626)
			(xy 143.776828 -43.73626) (xy 143.788137 -43.773848) (xy 143.796257 -43.829024) (xy 143.796766 -43.85691)
			(xy 143.796257 -43.884796) (xy 143.788137 -43.939972) (xy 143.772069 -43.993379) (xy 143.748397 -44.043876)
			(xy 143.717624 -44.090389) (xy 143.680407 -44.131926) (xy 143.637539 -44.167601) (xy 143.589933 -44.196655)
			(xy 143.538604 -44.218467) (xy 143.484647 -44.232573) (xy 143.42921 -44.238673) (xy 143.373476 -44.236636)
			(xy 143.318633 -44.226506) (xy 143.265849 -44.208499) (xy 143.216249 -44.182998) (xy 143.170891 -44.150547)
			(xy 143.130742 -44.111838) (xy 143.096656 -44.067695) (xy 143.06936 -44.01906) (xy 143.049437 -43.966969)
			(xy 143.037311 -43.912532) (xy 143.03324 -43.85691) (xy 141.58341 -43.85691) (xy 141.582963 -43.883097)
			(xy 141.575786 -43.934978) (xy 141.56158 -43.98539) (xy 141.540613 -44.033386) (xy 141.51328 -44.078063)
			(xy 141.480094 -44.118582) (xy 141.441677 -44.154182) (xy 141.398753 -44.184193) (xy 141.375638 -44.196508)
			(xy 141.366552 -44.201656) (xy 141.353167 -44.217654) (xy 141.347254 -44.237657) (xy 141.34979 -44.258361)
			(xy 141.360356 -44.276346) (xy 141.377206 -44.28864) (xy 141.397557 -44.293214) (xy 141.407896 -44.291758)
			(xy 141.438671 -44.28643) (xy 141.500871 -44.280706) (xy 141.532102 -44.280328) (xy 142.993364 -44.280328)
			(xy 143.028233 -44.280731) (xy 143.097612 -44.28778) (xy 143.165919 -44.301828) (xy 143.232449 -44.322732)
			(xy 143.296517 -44.350274) (xy 143.35746 -44.384173) (xy 143.386302 -44.403772) (xy 143.395041 -44.409287)
			(xy 143.415258 -44.413458) (xy 143.435475 -44.409287) (xy 143.444214 -44.403772) (xy 143.473059 -44.384179)
			(xy 143.534003 -44.350282) (xy 143.598069 -44.322741) (xy 143.664599 -44.301839) (xy 143.732905 -44.287792)
			(xy 143.802284 -44.280745) (xy 143.837152 -44.280328) (xy 159.043624 -44.280328) (xy 159.067246 -44.266358)
			(xy 159.072072 -44.257722) (xy 159.0802 -44.265596) (xy 159.087577 -44.272215) (xy 159.105864 -44.279802)
			(xy 159.11576 -44.280328) (xy 162.074606 -44.280328) (xy 162.114476 -44.280916) (xy 162.193671 -44.29022)
			(xy 162.271256 -44.308631) (xy 162.346188 -44.335902) (xy 162.417458 -44.371667) (xy 162.484107 -44.415443)
			(xy 162.515042 -44.440602) (xy 162.522073 -44.445987) (xy 162.538706 -44.452026) (xy 162.556402 -44.452026)
			(xy 162.573035 -44.445987) (xy 162.580066 -44.440602) (xy 162.610976 -44.415408) (xy 162.677615 -44.371606)
			(xy 162.748886 -44.33583) (xy 162.823826 -44.308563) (xy 162.901423 -44.290175) (xy 162.980629 -44.280912)
			(xy 163.020502 -44.280328) (xy 166.839646 -44.280328) (xy 166.841424 -44.280582) (xy 166.841678 -44.280582)
			(xy 166.851417 -44.280149) (xy 166.869466 -44.272818) (xy 166.883505 -44.25931) (xy 166.887906 -44.25061)
			(xy 166.926006 -44.166028) (xy 166.929554 -44.15686) (xy 166.930272 -44.137237) (xy 166.923592 -44.118772)
			(xy 166.91737 -44.111164) (xy 166.899171 -44.090091) (xy 166.868506 -44.043614) (xy 166.844923 -43.993174)
			(xy 166.828921 -43.939842) (xy 166.820841 -43.884751) (xy 166.820342 -43.85691) (xy 166.820828 -43.829659)
			(xy 166.828584 -43.775711) (xy 166.843939 -43.723416) (xy 166.866581 -43.673839) (xy 166.896047 -43.627989)
			(xy 166.931738 -43.586798) (xy 166.972929 -43.551107) (xy 167.018779 -43.521641) (xy 167.068356 -43.498999)
			(xy 167.120651 -43.483644) (xy 167.174599 -43.475888) (xy 167.229101 -43.475888) (xy 167.283049 -43.483644)
			(xy 167.335344 -43.498999) (xy 167.384921 -43.521641) (xy 167.430771 -43.551107) (xy 167.471962 -43.586798)
			(xy 167.507653 -43.627989) (xy 167.537119 -43.673839) (xy 167.559761 -43.723416) (xy 167.575116 -43.775711)
			(xy 167.582872 -43.829659) (xy 167.583358 -43.85691) (xy 169.033188 -43.85691) (xy 169.037259 -43.801288)
			(xy 169.049385 -43.746851) (xy 169.069308 -43.69476) (xy 169.096604 -43.646125) (xy 169.13069 -43.601982)
			(xy 169.170839 -43.563273) (xy 169.216197 -43.530822) (xy 169.265797 -43.505321) (xy 169.318581 -43.487314)
			(xy 169.373424 -43.477184) (xy 169.429158 -43.475147) (xy 169.484595 -43.481247) (xy 169.538552 -43.495353)
			(xy 169.589881 -43.517165) (xy 169.637487 -43.546219) (xy 169.680355 -43.581894) (xy 169.717572 -43.623431)
			(xy 169.748345 -43.669944) (xy 169.772017 -43.720441) (xy 169.776776 -43.73626) (xy 188.313058 -43.73626)
			(xy 188.317129 -43.680638) (xy 188.329255 -43.626201) (xy 188.349178 -43.57411) (xy 188.376474 -43.525475)
			(xy 188.41056 -43.481332) (xy 188.450709 -43.442623) (xy 188.496067 -43.410172) (xy 188.545667 -43.384671)
			(xy 188.598451 -43.366664) (xy 188.653294 -43.356534) (xy 188.709028 -43.354497) (xy 188.764465 -43.360597)
			(xy 188.818422 -43.374703) (xy 188.869751 -43.396515) (xy 188.917357 -43.425569) (xy 188.960225 -43.461244)
			(xy 188.997442 -43.502781) (xy 189.028215 -43.549294) (xy 189.051887 -43.599791) (xy 189.067955 -43.653198)
			(xy 189.076075 -43.708374) (xy 189.076584 -43.73626) (xy 189.076075 -43.764146) (xy 189.067955 -43.819322)
			(xy 189.051887 -43.872729) (xy 189.028215 -43.923226) (xy 188.997442 -43.969739) (xy 188.960225 -44.011276)
			(xy 188.917357 -44.046951) (xy 188.869751 -44.076005) (xy 188.818422 -44.097817) (xy 188.764465 -44.111923)
			(xy 188.709028 -44.118023) (xy 188.653294 -44.115986) (xy 188.598451 -44.105856) (xy 188.545667 -44.087849)
			(xy 188.496067 -44.062348) (xy 188.450709 -44.029897) (xy 188.41056 -43.991188) (xy 188.376474 -43.947045)
			(xy 188.349178 -43.89841) (xy 188.329255 -43.846319) (xy 188.317129 -43.791882) (xy 188.313058 -43.73626)
			(xy 169.776776 -43.73626) (xy 169.788085 -43.773848) (xy 169.796205 -43.829024) (xy 169.796714 -43.85691)
			(xy 169.796205 -43.884796) (xy 169.788085 -43.939972) (xy 169.772017 -43.993379) (xy 169.748345 -44.043876)
			(xy 169.717572 -44.090389) (xy 169.680355 -44.131926) (xy 169.637487 -44.167601) (xy 169.589881 -44.196655)
			(xy 169.538552 -44.218467) (xy 169.484595 -44.232573) (xy 169.429158 -44.238673) (xy 169.373424 -44.236636)
			(xy 169.318581 -44.226506) (xy 169.265797 -44.208499) (xy 169.216197 -44.182998) (xy 169.170839 -44.150547)
			(xy 169.13069 -44.111838) (xy 169.096604 -44.067695) (xy 169.069308 -44.01906) (xy 169.049385 -43.966969)
			(xy 169.037259 -43.912532) (xy 169.033188 -43.85691) (xy 167.583358 -43.85691) (xy 167.582885 -43.883096)
			(xy 167.575709 -43.934975) (xy 167.561505 -43.985385) (xy 167.540542 -44.033379) (xy 167.513212 -44.078056)
			(xy 167.48003 -44.118575) (xy 167.441618 -44.154177) (xy 167.398699 -44.184191) (xy 167.375586 -44.196508)
			(xy 167.366476 -44.201626) (xy 167.353071 -44.217628) (xy 167.347146 -44.237645) (xy 167.349682 -44.258366)
			(xy 167.360259 -44.276363) (xy 167.377127 -44.28866) (xy 167.397498 -44.293224) (xy 167.407844 -44.291758)
			(xy 167.438618 -44.286423) (xy 167.500819 -44.280703) (xy 167.53205 -44.280328) (xy 168.993312 -44.280328)
			(xy 169.02818 -44.280758) (xy 169.097559 -44.287802) (xy 169.165865 -44.301845) (xy 169.232395 -44.322743)
			(xy 169.296463 -44.350281) (xy 169.357407 -44.384175) (xy 169.38625 -44.403772) (xy 169.394989 -44.409287)
			(xy 169.415206 -44.413458) (xy 169.435423 -44.409287) (xy 169.444162 -44.403772) (xy 169.472993 -44.384157)
			(xy 169.53394 -44.350264) (xy 169.59801 -44.322726) (xy 169.664542 -44.301828) (xy 169.732851 -44.287785)
			(xy 169.802231 -44.280743) (xy 169.8371 -44.280328) (xy 185.043572 -44.280328) (xy 185.067194 -44.266358)
			(xy 185.07202 -44.257722) (xy 185.080148 -44.265596) (xy 185.087509 -44.272236) (xy 185.105808 -44.279811)
			(xy 185.115708 -44.280328) (xy 188.074554 -44.280328) (xy 188.114423 -44.280947) (xy 188.193617 -44.290244)
			(xy 188.271202 -44.308649) (xy 188.346134 -44.335915) (xy 188.417404 -44.371674) (xy 188.484054 -44.415445)
			(xy 188.51499 -44.440602) (xy 188.522021 -44.445987) (xy 188.538654 -44.452026) (xy 188.55635 -44.452026)
			(xy 188.572983 -44.445987) (xy 188.580014 -44.440602) (xy 188.610943 -44.415433) (xy 188.677578 -44.371627)
			(xy 188.748845 -44.335847) (xy 188.823781 -44.308577) (xy 188.901374 -44.290183) (xy 188.980578 -44.280915)
			(xy 189.02045 -44.280328) (xy 192.839594 -44.280328) (xy 192.841372 -44.280582) (xy 192.841626 -44.280582)
			(xy 192.851361 -44.280111) (xy 192.869409 -44.272798) (xy 192.88345 -44.259305) (xy 192.887854 -44.25061)
			(xy 192.925954 -44.166028) (xy 192.929513 -44.156863) (xy 192.930232 -44.137236) (xy 192.923545 -44.11877)
			(xy 192.917318 -44.111164) (xy 192.899127 -44.090084) (xy 192.868459 -44.04361) (xy 192.844874 -43.993172)
			(xy 192.82887 -43.939841) (xy 192.820789 -43.88475) (xy 192.82029 -43.85691) (xy 192.820776 -43.829659)
			(xy 192.828532 -43.775711) (xy 192.843887 -43.723416) (xy 192.866529 -43.673839) (xy 192.895995 -43.627989)
			(xy 192.931686 -43.586798) (xy 192.972877 -43.551107) (xy 193.018727 -43.521641) (xy 193.068304 -43.498999)
			(xy 193.120599 -43.483644) (xy 193.174547 -43.475888) (xy 193.229049 -43.475888) (xy 193.282997 -43.483644)
			(xy 193.335292 -43.498999) (xy 193.384869 -43.521641) (xy 193.430719 -43.551107) (xy 193.47191 -43.586798)
			(xy 193.507601 -43.627989) (xy 193.537067 -43.673839) (xy 193.559709 -43.723416) (xy 193.575064 -43.775711)
			(xy 193.58282 -43.829659) (xy 193.583306 -43.85691) (xy 195.033136 -43.85691) (xy 195.037207 -43.801288)
			(xy 195.049333 -43.746851) (xy 195.069256 -43.69476) (xy 195.096552 -43.646125) (xy 195.130638 -43.601982)
			(xy 195.170787 -43.563273) (xy 195.216145 -43.530822) (xy 195.265745 -43.505321) (xy 195.318529 -43.487314)
			(xy 195.373372 -43.477184) (xy 195.429106 -43.475147) (xy 195.484543 -43.481247) (xy 195.5385 -43.495353)
			(xy 195.589829 -43.517165) (xy 195.637435 -43.546219) (xy 195.680303 -43.581894) (xy 195.71752 -43.623431)
			(xy 195.748293 -43.669944) (xy 195.771965 -43.720441) (xy 195.776724 -43.73626) (xy 214.313006 -43.73626)
			(xy 214.317077 -43.680638) (xy 214.329203 -43.626201) (xy 214.349126 -43.57411) (xy 214.376422 -43.525475)
			(xy 214.410508 -43.481332) (xy 214.450657 -43.442623) (xy 214.496015 -43.410172) (xy 214.545615 -43.384671)
			(xy 214.598399 -43.366664) (xy 214.653242 -43.356534) (xy 214.708976 -43.354497) (xy 214.764413 -43.360597)
			(xy 214.81837 -43.374703) (xy 214.869699 -43.396515) (xy 214.917305 -43.425569) (xy 214.960173 -43.461244)
			(xy 214.99739 -43.502781) (xy 215.028163 -43.549294) (xy 215.051835 -43.599791) (xy 215.067903 -43.653198)
			(xy 215.076023 -43.708374) (xy 215.076532 -43.73626) (xy 215.076023 -43.764146) (xy 215.067903 -43.819322)
			(xy 215.051835 -43.872729) (xy 215.028163 -43.923226) (xy 214.99739 -43.969739) (xy 214.960173 -44.011276)
			(xy 214.917305 -44.046951) (xy 214.869699 -44.076005) (xy 214.81837 -44.097817) (xy 214.764413 -44.111923)
			(xy 214.708976 -44.118023) (xy 214.653242 -44.115986) (xy 214.598399 -44.105856) (xy 214.545615 -44.087849)
			(xy 214.496015 -44.062348) (xy 214.450657 -44.029897) (xy 214.410508 -43.991188) (xy 214.376422 -43.947045)
			(xy 214.349126 -43.89841) (xy 214.329203 -43.846319) (xy 214.317077 -43.791882) (xy 214.313006 -43.73626)
			(xy 195.776724 -43.73626) (xy 195.788033 -43.773848) (xy 195.796153 -43.829024) (xy 195.796662 -43.85691)
			(xy 195.796153 -43.884796) (xy 195.788033 -43.939972) (xy 195.771965 -43.993379) (xy 195.748293 -44.043876)
			(xy 195.71752 -44.090389) (xy 195.680303 -44.131926) (xy 195.637435 -44.167601) (xy 195.589829 -44.196655)
			(xy 195.5385 -44.218467) (xy 195.484543 -44.232573) (xy 195.429106 -44.238673) (xy 195.373372 -44.236636)
			(xy 195.318529 -44.226506) (xy 195.265745 -44.208499) (xy 195.216145 -44.182998) (xy 195.170787 -44.150547)
			(xy 195.130638 -44.111838) (xy 195.096552 -44.067695) (xy 195.069256 -44.01906) (xy 195.049333 -43.966969)
			(xy 195.037207 -43.912532) (xy 195.033136 -43.85691) (xy 193.583306 -43.85691) (xy 193.582862 -43.883098)
			(xy 193.575684 -43.934979) (xy 193.561478 -43.985391) (xy 193.540511 -44.033386) (xy 193.513177 -44.078063)
			(xy 193.479991 -44.118582) (xy 193.441574 -44.154182) (xy 193.39865 -44.184193) (xy 193.375534 -44.196508)
			(xy 193.36645 -44.201658) (xy 193.353067 -44.217656) (xy 193.347155 -44.237658) (xy 193.349691 -44.25836)
			(xy 193.360255 -44.276344) (xy 193.377104 -44.288639) (xy 193.397453 -44.293214) (xy 193.407792 -44.291758)
			(xy 193.438567 -44.28643) (xy 193.500767 -44.280706) (xy 193.531998 -44.280328) (xy 194.99326 -44.280328)
			(xy 195.028128 -44.280733) (xy 195.097508 -44.287781) (xy 195.165815 -44.301829) (xy 195.232345 -44.322732)
			(xy 195.296412 -44.350275) (xy 195.357356 -44.384173) (xy 195.386198 -44.403772) (xy 195.394937 -44.409287)
			(xy 195.415154 -44.413458) (xy 195.435371 -44.409287) (xy 195.44411 -44.403772) (xy 195.472957 -44.38418)
			(xy 195.5339 -44.350283) (xy 195.597966 -44.322742) (xy 195.664495 -44.30184) (xy 195.732802 -44.287793)
			(xy 195.80218 -44.280746) (xy 195.837048 -44.280328) (xy 211.04352 -44.280328) (xy 211.067142 -44.266358)
			(xy 211.071968 -44.257722) (xy 211.080096 -44.265596) (xy 211.087441 -44.272256) (xy 211.105752 -44.279819)
			(xy 211.115656 -44.280328) (xy 214.074502 -44.280328) (xy 214.114371 -44.280919) (xy 214.193567 -44.290222)
			(xy 214.271152 -44.308632) (xy 214.346084 -44.335903) (xy 214.417354 -44.371667) (xy 214.484003 -44.415443)
			(xy 214.514938 -44.440602) (xy 214.521969 -44.445987) (xy 214.538602 -44.452026) (xy 214.556298 -44.452026)
			(xy 214.572931 -44.445987) (xy 214.579962 -44.440602) (xy 214.610874 -44.41541) (xy 214.677512 -44.371607)
			(xy 214.748783 -44.335831) (xy 214.823722 -44.308564) (xy 214.901319 -44.290175) (xy 214.980525 -44.280912)
			(xy 215.020398 -44.280328) (xy 218.839542 -44.280328) (xy 218.84132 -44.280582) (xy 218.841574 -44.280582)
			(xy 218.851312 -44.280146) (xy 218.869362 -44.272816) (xy 218.883401 -44.25931) (xy 218.887802 -44.25061)
			(xy 218.925902 -44.166028) (xy 218.929451 -44.15686) (xy 218.930169 -44.137237) (xy 218.923488 -44.118772)
			(xy 218.917266 -44.111164) (xy 218.899066 -44.090091) (xy 218.868402 -44.043614) (xy 218.844818 -43.993174)
			(xy 218.828817 -43.939842) (xy 218.820737 -43.884751) (xy 218.820238 -43.85691) (xy 218.820724 -43.829659)
			(xy 218.82848 -43.775711) (xy 218.843835 -43.723416) (xy 218.866477 -43.673839) (xy 218.895943 -43.627989)
			(xy 218.931634 -43.586798) (xy 218.972825 -43.551107) (xy 219.018675 -43.521641) (xy 219.068252 -43.498999)
			(xy 219.120547 -43.483644) (xy 219.174495 -43.475888) (xy 219.228997 -43.475888) (xy 219.282945 -43.483644)
			(xy 219.33524 -43.498999) (xy 219.384817 -43.521641) (xy 219.430667 -43.551107) (xy 219.471858 -43.586798)
			(xy 219.507549 -43.627989) (xy 219.537015 -43.673839) (xy 219.559657 -43.723416) (xy 219.575012 -43.775711)
			(xy 219.582768 -43.829659) (xy 219.583254 -43.85691) (xy 219.582784 -43.883096) (xy 219.575607 -43.934975)
			(xy 219.561403 -43.985385) (xy 219.540439 -44.03338) (xy 219.513109 -44.078056) (xy 219.479927 -44.118576)
			(xy 219.441515 -44.154177) (xy 219.398595 -44.184192) (xy 219.375482 -44.196508) (xy 219.366374 -44.201628)
			(xy 219.35297 -44.21763) (xy 219.347047 -44.237646) (xy 219.349583 -44.258365) (xy 219.360159 -44.276361)
			(xy 219.377026 -44.288659) (xy 219.397394 -44.293223) (xy 219.40774 -44.291758) (xy 219.438514 -44.286424)
			(xy 219.500715 -44.280704) (xy 219.531946 -44.280328) (xy 221.05493 -44.280328) (xy 221.06471 -44.279914)
			(xy 221.082858 -44.272617) (xy 221.096981 -44.259086) (xy 221.101412 -44.250356) (xy 221.139258 -44.166028)
			(xy 221.142816 -44.156862) (xy 221.143535 -44.137236) (xy 221.136849 -44.11877) (xy 221.130622 -44.111164)
			(xy 221.112431 -44.090083) (xy 221.081764 -44.04361) (xy 221.058178 -43.993172) (xy 221.042174 -43.939841)
			(xy 221.034093 -43.88475) (xy 221.033594 -43.85691) (xy 221.03408 -43.829659) (xy 221.041836 -43.775711)
			(xy 221.057191 -43.723416) (xy 221.079833 -43.673839) (xy 221.109299 -43.627989) (xy 221.14499 -43.586798)
			(xy 221.186181 -43.551107) (xy 221.232031 -43.521641) (xy 221.281608 -43.498999) (xy 221.333903 -43.483644)
			(xy 221.387851 -43.475888) (xy 221.442353 -43.475888) (xy 221.496301 -43.483644) (xy 221.548596 -43.498999)
			(xy 221.598173 -43.521641) (xy 221.644023 -43.551107) (xy 221.685214 -43.586798) (xy 221.720905 -43.627989)
			(xy 221.750371 -43.673839) (xy 221.773013 -43.723416) (xy 221.776784 -43.73626) (xy 252.413006 -43.73626)
			(xy 252.417077 -43.680638) (xy 252.429203 -43.626201) (xy 252.449126 -43.57411) (xy 252.476422 -43.525475)
			(xy 252.510508 -43.481332) (xy 252.550657 -43.442623) (xy 252.596015 -43.410172) (xy 252.645615 -43.384671)
			(xy 252.698399 -43.366664) (xy 252.753242 -43.356534) (xy 252.808976 -43.354497) (xy 252.864413 -43.360597)
			(xy 252.91837 -43.374703) (xy 252.969699 -43.396515) (xy 253.017305 -43.425569) (xy 253.060173 -43.461244)
			(xy 253.09739 -43.502781) (xy 253.128163 -43.549294) (xy 253.151835 -43.599791) (xy 253.167903 -43.653198)
			(xy 253.176023 -43.708374) (xy 253.176532 -43.73626) (xy 253.176023 -43.764146) (xy 253.167903 -43.819322)
			(xy 253.151835 -43.872729) (xy 253.128163 -43.923226) (xy 253.09739 -43.969739) (xy 253.060173 -44.011276)
			(xy 253.017305 -44.046951) (xy 252.969699 -44.076005) (xy 252.91837 -44.097817) (xy 252.864413 -44.111923)
			(xy 252.808976 -44.118023) (xy 252.753242 -44.115986) (xy 252.698399 -44.105856) (xy 252.645615 -44.087849)
			(xy 252.596015 -44.062348) (xy 252.550657 -44.029897) (xy 252.510508 -43.991188) (xy 252.476422 -43.947045)
			(xy 252.449126 -43.89841) (xy 252.429203 -43.846319) (xy 252.417077 -43.791882) (xy 252.413006 -43.73626)
			(xy 221.776784 -43.73626) (xy 221.788368 -43.775711) (xy 221.796124 -43.829659) (xy 221.79661 -43.85691)
			(xy 221.796078 -43.884747) (xy 221.78798 -43.939828) (xy 221.771972 -43.993151) (xy 221.748393 -44.043585)
			(xy 221.717743 -44.090061) (xy 221.699582 -44.111164) (xy 221.693322 -44.118755) (xy 221.686606 -44.137231)
			(xy 221.68733 -44.156877) (xy 221.690946 -44.166028) (xy 221.728792 -44.250356) (xy 221.733152 -44.259135)
			(xy 221.747279 -44.272702) (xy 221.765477 -44.279947) (xy 221.775274 -44.280328) (xy 249.14352 -44.280328)
			(xy 249.167142 -44.266358) (xy 249.171968 -44.257722) (xy 249.180096 -44.265596) (xy 249.187441 -44.272256)
			(xy 249.205752 -44.279819) (xy 249.215656 -44.280328) (xy 252.174502 -44.280328) (xy 252.214371 -44.280919)
			(xy 252.293567 -44.290222) (xy 252.371152 -44.308632) (xy 252.446084 -44.335903) (xy 252.517354 -44.371667)
			(xy 252.584003 -44.415443) (xy 252.614938 -44.440602) (xy 252.621969 -44.445987) (xy 252.638602 -44.452026)
			(xy 252.656298 -44.452026) (xy 252.672931 -44.445987) (xy 252.679962 -44.440602) (xy 252.710874 -44.41541)
			(xy 252.777512 -44.371607) (xy 252.848783 -44.335831) (xy 252.923722 -44.308564) (xy 253.001319 -44.290175)
			(xy 253.080525 -44.280912) (xy 253.120398 -44.280328) (xy 256.939542 -44.280328) (xy 256.94132 -44.280582)
			(xy 256.941574 -44.280582) (xy 256.951312 -44.280146) (xy 256.969362 -44.272816) (xy 256.983401 -44.25931)
			(xy 256.987802 -44.25061) (xy 257.025902 -44.166028) (xy 257.029451 -44.15686) (xy 257.030169 -44.137237)
			(xy 257.023488 -44.118772) (xy 257.017266 -44.111164) (xy 256.999066 -44.090091) (xy 256.968402 -44.043614)
			(xy 256.944818 -43.993174) (xy 256.928817 -43.939842) (xy 256.920737 -43.884751) (xy 256.920238 -43.85691)
			(xy 256.920724 -43.829659) (xy 256.92848 -43.775711) (xy 256.943835 -43.723416) (xy 256.966477 -43.673839)
			(xy 256.995943 -43.627989) (xy 257.031634 -43.586798) (xy 257.072825 -43.551107) (xy 257.118675 -43.521641)
			(xy 257.168252 -43.498999) (xy 257.220547 -43.483644) (xy 257.274495 -43.475888) (xy 257.328997 -43.475888)
			(xy 257.382945 -43.483644) (xy 257.43524 -43.498999) (xy 257.484817 -43.521641) (xy 257.530667 -43.551107)
			(xy 257.571858 -43.586798) (xy 257.607549 -43.627989) (xy 257.637015 -43.673839) (xy 257.659657 -43.723416)
			(xy 257.675012 -43.775711) (xy 257.682768 -43.829659) (xy 257.683254 -43.85691) (xy 257.682784 -43.883096)
			(xy 257.675607 -43.934975) (xy 257.661403 -43.985385) (xy 257.640439 -44.03338) (xy 257.613109 -44.078056)
			(xy 257.579927 -44.118576) (xy 257.541515 -44.154177) (xy 257.498595 -44.184192) (xy 257.475482 -44.196508)
			(xy 257.466374 -44.201628) (xy 257.45297 -44.21763) (xy 257.447047 -44.237646) (xy 257.449583 -44.258365)
			(xy 257.460159 -44.276361) (xy 257.477026 -44.288659) (xy 257.497394 -44.293223) (xy 257.50774 -44.291758)
			(xy 257.538514 -44.286424) (xy 257.600715 -44.280704) (xy 257.631946 -44.280328) (xy 259.15493 -44.280328)
			(xy 259.16471 -44.279914) (xy 259.182858 -44.272617) (xy 259.196981 -44.259086) (xy 259.201412 -44.250356)
			(xy 259.239258 -44.166028) (xy 259.242816 -44.156862) (xy 259.243535 -44.137236) (xy 259.236849 -44.11877)
			(xy 259.230622 -44.111164) (xy 259.212431 -44.090083) (xy 259.181764 -44.04361) (xy 259.158178 -43.993172)
			(xy 259.142174 -43.939841) (xy 259.134093 -43.88475) (xy 259.133594 -43.85691) (xy 259.13408 -43.829659)
			(xy 259.141836 -43.775711) (xy 259.157191 -43.723416) (xy 259.179833 -43.673839) (xy 259.209299 -43.627989)
			(xy 259.24499 -43.586798) (xy 259.286181 -43.551107) (xy 259.332031 -43.521641) (xy 259.381608 -43.498999)
			(xy 259.433903 -43.483644) (xy 259.487851 -43.475888) (xy 259.542353 -43.475888) (xy 259.596301 -43.483644)
			(xy 259.648596 -43.498999) (xy 259.698173 -43.521641) (xy 259.744023 -43.551107) (xy 259.785214 -43.586798)
			(xy 259.820905 -43.627989) (xy 259.850371 -43.673839) (xy 259.873013 -43.723416) (xy 259.876784 -43.73626)
			(xy 278.412954 -43.73626) (xy 278.417025 -43.680638) (xy 278.429151 -43.626201) (xy 278.449074 -43.57411)
			(xy 278.47637 -43.525475) (xy 278.510456 -43.481332) (xy 278.550605 -43.442623) (xy 278.595963 -43.410172)
			(xy 278.645563 -43.384671) (xy 278.698347 -43.366664) (xy 278.75319 -43.356534) (xy 278.808924 -43.354497)
			(xy 278.864361 -43.360597) (xy 278.918318 -43.374703) (xy 278.969647 -43.396515) (xy 279.017253 -43.425569)
			(xy 279.060121 -43.461244) (xy 279.097338 -43.502781) (xy 279.128111 -43.549294) (xy 279.136337 -43.566842)
			(xy 281.533344 -43.566842) (xy 281.537415 -43.51122) (xy 281.549541 -43.456783) (xy 281.569464 -43.404692)
			(xy 281.59676 -43.356057) (xy 281.630846 -43.311914) (xy 281.670995 -43.273205) (xy 281.716353 -43.240754)
			(xy 281.765953 -43.215253) (xy 281.818737 -43.197246) (xy 281.87358 -43.187116) (xy 281.929314 -43.185079)
			(xy 281.984751 -43.191179) (xy 282.038708 -43.205285) (xy 282.090037 -43.227097) (xy 282.137643 -43.256151)
			(xy 282.180511 -43.291826) (xy 282.192514 -43.305222) (xy 302.507142 -43.305222) (xy 302.507611 -43.277852)
			(xy 302.515426 -43.223672) (xy 302.530914 -43.171169) (xy 302.553756 -43.121422) (xy 302.58348 -43.075455)
			(xy 302.601122 -43.054524) (xy 302.601376 -43.05427) (xy 302.606948 -43.047174) (xy 302.613202 -43.030264)
			(xy 302.613568 -43.02125) (xy 302.613568 -42.954194) (xy 302.613221 -42.945176) (xy 302.606967 -42.928259)
			(xy 302.601376 -42.921174) (xy 302.601122 -42.921174) (xy 302.601122 -42.92092) (xy 302.583482 -42.899988)
			(xy 302.55377 -42.854016) (xy 302.530934 -42.804268) (xy 302.515443 -42.751767) (xy 302.507615 -42.697591)
			(xy 302.507142 -42.670222) (xy 302.507695 -42.641484) (xy 302.516313 -42.584659) (xy 302.533357 -42.529769)
			(xy 302.558441 -42.478057) (xy 302.590999 -42.430693) (xy 302.610266 -42.409364) (xy 302.61687 -42.402506)
			(xy 302.623982 -42.384472) (xy 302.623982 -42.295572) (xy 302.61687 -42.277538) (xy 302.610266 -42.27068)
			(xy 302.59102 -42.249333) (xy 302.558458 -42.201972) (xy 302.53337 -42.150263) (xy 302.516321 -42.095376)
			(xy 302.507697 -42.038553) (xy 302.507695 -41.981079) (xy 302.516313 -41.924255) (xy 302.533358 -41.869366)
			(xy 302.558442 -41.817655) (xy 302.590999 -41.770292) (xy 302.610266 -41.748964) (xy 302.61687 -41.742106)
			(xy 302.623982 -41.724072) (xy 302.623982 -41.635172) (xy 302.61687 -41.617138) (xy 302.610266 -41.61028)
			(xy 302.59101 -41.58894) (xy 302.558441 -41.541582) (xy 302.533345 -41.489874) (xy 302.516291 -41.434986)
			(xy 302.507665 -41.37816) (xy 302.507142 -41.349422) (xy 302.507628 -41.322171) (xy 302.515384 -41.268223)
			(xy 302.530739 -41.215928) (xy 302.553381 -41.166351) (xy 302.582847 -41.120501) (xy 302.618538 -41.07931)
			(xy 302.659729 -41.043619) (xy 302.705579 -41.014153) (xy 302.755156 -40.991511) (xy 302.807451 -40.976156)
			(xy 302.861399 -40.9684) (xy 302.915901 -40.9684) (xy 302.939022 -40.971724) (xy 310.79389 -40.971724)
			(xy 310.797961 -40.916102) (xy 310.810087 -40.861665) (xy 310.83001 -40.809574) (xy 310.857306 -40.760939)
			(xy 310.891392 -40.716796) (xy 310.931541 -40.678087) (xy 310.976899 -40.645636) (xy 311.026499 -40.620135)
			(xy 311.079283 -40.602128) (xy 311.134126 -40.591998) (xy 311.18986 -40.589961) (xy 311.245297 -40.596061)
			(xy 311.299254 -40.610167) (xy 311.350583 -40.631979) (xy 311.398189 -40.661033) (xy 311.441057 -40.696708)
			(xy 311.478274 -40.738245) (xy 311.509047 -40.784758) (xy 311.532719 -40.835255) (xy 311.548787 -40.888662)
			(xy 311.556907 -40.943838) (xy 311.557416 -40.971724) (xy 311.556907 -40.99961) (xy 311.548787 -41.054786)
			(xy 311.532719 -41.108193) (xy 311.509047 -41.15869) (xy 311.478274 -41.205203) (xy 311.441057 -41.24674)
			(xy 311.414606 -41.268753) (xy 326.04375 -41.268753) (xy 326.04375 -41.214247) (xy 326.051507 -41.160295)
			(xy 326.066863 -41.107997) (xy 326.089506 -41.058416) (xy 326.118974 -41.012563) (xy 326.154668 -40.971369)
			(xy 326.195861 -40.935675) (xy 326.241714 -40.906207) (xy 326.291295 -40.883564) (xy 326.343593 -40.868207)
			(xy 326.397545 -40.86045) (xy 326.424798 -40.859964) (xy 326.453536 -40.860499) (xy 326.510363 -40.86912)
			(xy 326.565253 -40.886168) (xy 326.616965 -40.911257) (xy 326.664328 -40.943819) (xy 326.685656 -40.963088)
			(xy 326.692514 -40.969692) (xy 326.710548 -40.976804) (xy 326.799448 -40.976804) (xy 326.817482 -40.969692)
			(xy 326.82434 -40.963088) (xy 326.845675 -40.943827) (xy 326.893034 -40.911257) (xy 326.944744 -40.886162)
			(xy 326.999633 -40.869109) (xy 327.056459 -40.860485) (xy 327.085198 -40.859964) (xy 327.112449 -40.860483)
			(xy 327.166396 -40.868239) (xy 327.21869 -40.883594) (xy 327.268267 -40.906235) (xy 327.314117 -40.935701)
			(xy 327.355307 -40.971392) (xy 327.390998 -41.012581) (xy 327.420464 -41.058431) (xy 327.443105 -41.108008)
			(xy 327.45846 -41.160302) (xy 327.466217 -41.214249) (xy 327.466217 -41.268751) (xy 327.45846 -41.322698)
			(xy 327.443105 -41.374992) (xy 327.420464 -41.424569) (xy 327.390998 -41.470419) (xy 327.355307 -41.511608)
			(xy 327.314117 -41.547299) (xy 327.268267 -41.576765) (xy 327.21869 -41.599406) (xy 327.166396 -41.614761)
			(xy 327.112449 -41.622517) (xy 327.085198 -41.62298) (xy 327.05646 -41.622436) (xy 326.999635 -41.613815)
			(xy 326.944745 -41.596769) (xy 326.893033 -41.571682) (xy 326.845669 -41.539123) (xy 326.82434 -41.519856)
			(xy 326.817482 -41.513252) (xy 326.799448 -41.50614) (xy 326.710548 -41.50614) (xy 326.692514 -41.513252)
			(xy 326.685656 -41.519856) (xy 326.664329 -41.539127) (xy 326.616967 -41.571693) (xy 326.565255 -41.596786)
			(xy 326.510365 -41.613836) (xy 326.453537 -41.622459) (xy 326.424798 -41.62298) (xy 326.397545 -41.62255)
			(xy 326.343593 -41.614793) (xy 326.291295 -41.599436) (xy 326.241714 -41.576793) (xy 326.195861 -41.547325)
			(xy 326.154668 -41.511631) (xy 326.118974 -41.470437) (xy 326.089506 -41.424584) (xy 326.066863 -41.375003)
			(xy 326.051507 -41.322705) (xy 326.04375 -41.268753) (xy 311.414606 -41.268753) (xy 311.398189 -41.282415)
			(xy 311.350583 -41.311469) (xy 311.299254 -41.333281) (xy 311.245297 -41.347387) (xy 311.18986 -41.353487)
			(xy 311.134126 -41.35145) (xy 311.079283 -41.34132) (xy 311.026499 -41.323313) (xy 310.976899 -41.297812)
			(xy 310.931541 -41.265361) (xy 310.891392 -41.226652) (xy 310.857306 -41.182509) (xy 310.83001 -41.133874)
			(xy 310.810087 -41.081783) (xy 310.797961 -41.027346) (xy 310.79389 -40.971724) (xy 302.939022 -40.971724)
			(xy 302.969849 -40.976156) (xy 303.022144 -40.991511) (xy 303.071721 -41.014153) (xy 303.117571 -41.043619)
			(xy 303.158762 -41.07931) (xy 303.194453 -41.120501) (xy 303.223919 -41.166351) (xy 303.246561 -41.215928)
			(xy 303.261916 -41.268223) (xy 303.269672 -41.322171) (xy 303.270158 -41.349422) (xy 303.269632 -41.378161)
			(xy 303.261008 -41.434987) (xy 303.243957 -41.489877) (xy 303.218867 -41.541589) (xy 303.186303 -41.588952)
			(xy 303.167034 -41.61028) (xy 303.16043 -41.617138) (xy 303.153318 -41.635172) (xy 303.153318 -41.724072)
			(xy 303.16043 -41.742106) (xy 303.167034 -41.748964) (xy 303.186324 -41.770273) (xy 303.218884 -41.81764)
			(xy 303.24397 -41.869355) (xy 303.261016 -41.924248) (xy 303.269635 -41.981077) (xy 303.269633 -42.038555)
			(xy 303.261009 -42.095383) (xy 303.243958 -42.150275) (xy 303.218868 -42.201987) (xy 303.186304 -42.249352)
			(xy 303.167034 -42.27068) (xy 303.16043 -42.277538) (xy 303.153318 -42.295572) (xy 303.153318 -42.384472)
			(xy 303.16043 -42.402506) (xy 303.167034 -42.409364) (xy 303.186311 -42.430686) (xy 303.218877 -42.478049)
			(xy 303.243969 -42.529762) (xy 303.261018 -42.584654) (xy 303.269639 -42.641483) (xy 303.270158 -42.670222)
			(xy 303.269715 -42.697593) (xy 303.261893 -42.751774) (xy 303.246399 -42.804277) (xy 303.225842 -42.849038)
			(xy 305.091844 -42.849038) (xy 305.095915 -42.793416) (xy 305.108041 -42.738979) (xy 305.127964 -42.686888)
			(xy 305.15526 -42.638253) (xy 305.189346 -42.59411) (xy 305.229495 -42.555401) (xy 305.274853 -42.52295)
			(xy 305.324453 -42.497449) (xy 305.377237 -42.479442) (xy 305.43208 -42.469312) (xy 305.487814 -42.467275)
			(xy 305.543251 -42.473375) (xy 305.597208 -42.487481) (xy 305.648537 -42.509293) (xy 305.696143 -42.538347)
			(xy 305.739011 -42.574022) (xy 305.776228 -42.615559) (xy 305.807001 -42.662072) (xy 305.830673 -42.712569)
			(xy 305.846741 -42.765976) (xy 305.854861 -42.821152) (xy 305.855222 -42.84091) (xy 311.13298 -42.84091)
			(xy 311.137051 -42.785288) (xy 311.149177 -42.730851) (xy 311.1691 -42.67876) (xy 311.196396 -42.630125)
			(xy 311.230482 -42.585982) (xy 311.270631 -42.547273) (xy 311.315989 -42.514822) (xy 311.365589 -42.489321)
			(xy 311.418373 -42.471314) (xy 311.473216 -42.461184) (xy 311.52895 -42.459147) (xy 311.584387 -42.465247)
			(xy 311.638344 -42.479353) (xy 311.689673 -42.501165) (xy 311.737279 -42.530219) (xy 311.780147 -42.565894)
			(xy 311.817364 -42.607431) (xy 311.848137 -42.653944) (xy 311.871809 -42.704441) (xy 311.887877 -42.757848)
			(xy 311.895997 -42.813024) (xy 311.896506 -42.84091) (xy 311.895997 -42.868796) (xy 311.887877 -42.923972)
			(xy 311.871809 -42.977379) (xy 311.848137 -43.027876) (xy 311.817364 -43.074389) (xy 311.780147 -43.115926)
			(xy 311.737279 -43.151601) (xy 311.689673 -43.180655) (xy 311.638344 -43.202467) (xy 311.584387 -43.216573)
			(xy 311.52895 -43.222673) (xy 311.473216 -43.220636) (xy 311.418373 -43.210506) (xy 311.365589 -43.192499)
			(xy 311.315989 -43.166998) (xy 311.270631 -43.134547) (xy 311.230482 -43.095838) (xy 311.196396 -43.051695)
			(xy 311.1691 -43.00306) (xy 311.149177 -42.950969) (xy 311.137051 -42.896532) (xy 311.13298 -42.84091)
			(xy 305.855222 -42.84091) (xy 305.85537 -42.849038) (xy 305.854861 -42.876924) (xy 305.846741 -42.9321)
			(xy 305.830673 -42.985507) (xy 305.807001 -43.036004) (xy 305.776228 -43.082517) (xy 305.739011 -43.124054)
			(xy 305.696143 -43.159729) (xy 305.648537 -43.188783) (xy 305.597208 -43.210595) (xy 305.543251 -43.224701)
			(xy 305.487814 -43.230801) (xy 305.43208 -43.228764) (xy 305.377237 -43.218634) (xy 305.324453 -43.200627)
			(xy 305.274853 -43.175126) (xy 305.229495 -43.142675) (xy 305.189346 -43.103966) (xy 305.15526 -43.059823)
			(xy 305.127964 -43.011188) (xy 305.108041 -42.959097) (xy 305.095915 -42.90466) (xy 305.091844 -42.849038)
			(xy 303.225842 -42.849038) (xy 303.223552 -42.854024) (xy 303.193822 -42.899989) (xy 303.176178 -42.92092)
			(xy 303.175924 -42.921174) (xy 303.170333 -42.928257) (xy 303.164091 -42.945177) (xy 303.163732 -42.954194)
			(xy 303.163732 -43.02125) (xy 303.164106 -43.030265) (xy 303.170341 -43.047183) (xy 303.175924 -43.05427)
			(xy 303.176178 -43.05427) (xy 303.176178 -43.054524) (xy 303.193792 -43.075477) (xy 303.223508 -43.121444)
			(xy 303.246349 -43.171186) (xy 303.261846 -43.223682) (xy 303.269681 -43.277854) (xy 303.270158 -43.305222)
			(xy 303.269672 -43.332473) (xy 303.261916 -43.386421) (xy 303.246561 -43.438716) (xy 303.223919 -43.488293)
			(xy 303.194453 -43.534143) (xy 303.158762 -43.575334) (xy 303.117571 -43.611025) (xy 303.071721 -43.640491)
			(xy 303.022144 -43.663133) (xy 302.969849 -43.678488) (xy 302.915901 -43.686244) (xy 302.861399 -43.686244)
			(xy 302.807451 -43.678488) (xy 302.755156 -43.663133) (xy 302.705579 -43.640491) (xy 302.659729 -43.611025)
			(xy 302.618538 -43.575334) (xy 302.582847 -43.534143) (xy 302.553381 -43.488293) (xy 302.530739 -43.438716)
			(xy 302.515384 -43.386421) (xy 302.507628 -43.332473) (xy 302.507142 -43.305222) (xy 282.192514 -43.305222)
			(xy 282.217728 -43.333363) (xy 282.248501 -43.379876) (xy 282.272173 -43.430373) (xy 282.288241 -43.48378)
			(xy 282.296361 -43.538956) (xy 282.29687 -43.566842) (xy 282.296361 -43.594728) (xy 282.288241 -43.649904)
			(xy 282.272173 -43.703311) (xy 282.248501 -43.753808) (xy 282.217728 -43.800321) (xy 282.180511 -43.841858)
			(xy 282.137643 -43.877533) (xy 282.090037 -43.906587) (xy 282.038708 -43.928399) (xy 281.984751 -43.942505)
			(xy 281.929314 -43.948605) (xy 281.87358 -43.946568) (xy 281.818737 -43.936438) (xy 281.765953 -43.918431)
			(xy 281.716353 -43.89293) (xy 281.670995 -43.860479) (xy 281.630846 -43.82177) (xy 281.59676 -43.777627)
			(xy 281.569464 -43.728992) (xy 281.549541 -43.676901) (xy 281.537415 -43.622464) (xy 281.533344 -43.566842)
			(xy 279.136337 -43.566842) (xy 279.151783 -43.599791) (xy 279.167851 -43.653198) (xy 279.175971 -43.708374)
			(xy 279.17648 -43.73626) (xy 279.175971 -43.764146) (xy 279.167851 -43.819322) (xy 279.151783 -43.872729)
			(xy 279.128111 -43.923226) (xy 279.097338 -43.969739) (xy 279.060121 -44.011276) (xy 279.017253 -44.046951)
			(xy 278.969647 -44.076005) (xy 278.918318 -44.097817) (xy 278.864361 -44.111923) (xy 278.808924 -44.118023)
			(xy 278.75319 -44.115986) (xy 278.698347 -44.105856) (xy 278.645563 -44.087849) (xy 278.595963 -44.062348)
			(xy 278.550605 -44.029897) (xy 278.510456 -43.991188) (xy 278.47637 -43.947045) (xy 278.449074 -43.89841)
			(xy 278.429151 -43.846319) (xy 278.417025 -43.791882) (xy 278.412954 -43.73626) (xy 259.876784 -43.73626)
			(xy 259.888368 -43.775711) (xy 259.896124 -43.829659) (xy 259.89661 -43.85691) (xy 259.896078 -43.884747)
			(xy 259.88798 -43.939828) (xy 259.871972 -43.993151) (xy 259.848393 -44.043585) (xy 259.817743 -44.090061)
			(xy 259.799582 -44.111164) (xy 259.793322 -44.118755) (xy 259.786606 -44.137231) (xy 259.78733 -44.156877)
			(xy 259.790946 -44.166028) (xy 259.828792 -44.250356) (xy 259.833152 -44.259135) (xy 259.847279 -44.272702)
			(xy 259.865477 -44.279947) (xy 259.875274 -44.280328) (xy 275.143468 -44.280328) (xy 275.16709 -44.266358)
			(xy 275.171916 -44.257722) (xy 275.180044 -44.265596) (xy 275.187406 -44.272234) (xy 275.205704 -44.27981)
			(xy 275.215604 -44.280328) (xy 278.17445 -44.280328) (xy 278.214319 -44.280949) (xy 278.293513 -44.290246)
			(xy 278.371098 -44.308651) (xy 278.446029 -44.335916) (xy 278.5173 -44.371675) (xy 278.58395 -44.415446)
			(xy 278.614886 -44.440602) (xy 278.621917 -44.445987) (xy 278.63855 -44.452026) (xy 278.656246 -44.452026)
			(xy 278.672879 -44.445987) (xy 278.67991 -44.440602) (xy 278.710841 -44.415434) (xy 278.777475 -44.371629)
			(xy 278.848741 -44.335849) (xy 278.923677 -44.308578) (xy 279.001271 -44.290184) (xy 279.080474 -44.280915)
			(xy 279.120346 -44.280328) (xy 282.93949 -44.280328) (xy 282.941268 -44.280582) (xy 282.941522 -44.280582)
			(xy 282.951257 -44.280108) (xy 282.969305 -44.272796) (xy 282.983346 -44.259304) (xy 282.98775 -44.25061)
			(xy 283.02585 -44.166028) (xy 283.02941 -44.156863) (xy 283.030129 -44.137236) (xy 283.023441 -44.11877)
			(xy 283.017214 -44.111164) (xy 282.999022 -44.090084) (xy 282.968355 -44.04361) (xy 282.944769 -43.993172)
			(xy 282.928766 -43.939841) (xy 282.920685 -43.88475) (xy 282.920186 -43.85691) (xy 282.920672 -43.829659)
			(xy 282.928428 -43.775711) (xy 282.943783 -43.723416) (xy 282.966425 -43.673839) (xy 282.995891 -43.627989)
			(xy 283.031582 -43.586798) (xy 283.072773 -43.551107) (xy 283.118623 -43.521641) (xy 283.1682 -43.498999)
			(xy 283.220495 -43.483644) (xy 283.274443 -43.475888) (xy 283.328945 -43.475888) (xy 283.382893 -43.483644)
			(xy 283.435188 -43.498999) (xy 283.484765 -43.521641) (xy 283.530615 -43.551107) (xy 283.571806 -43.586798)
			(xy 283.607497 -43.627989) (xy 283.636963 -43.673839) (xy 283.659605 -43.723416) (xy 283.67496 -43.775711)
			(xy 283.682716 -43.829659) (xy 283.683202 -43.85691) (xy 283.68276 -43.883098) (xy 283.675582 -43.934979)
			(xy 283.661376 -43.985391) (xy 283.640409 -44.033387) (xy 283.613075 -44.078064) (xy 283.579888 -44.118583)
			(xy 283.541471 -44.154183) (xy 283.498546 -44.184194) (xy 283.47543 -44.196508) (xy 283.466348 -44.201661)
			(xy 283.452967 -44.217658) (xy 283.447056 -44.237659) (xy 283.449591 -44.25836) (xy 283.460155 -44.276343)
			(xy 283.477002 -44.288637) (xy 283.49735 -44.293213) (xy 283.507688 -44.291758) (xy 283.538464 -44.286431)
			(xy 283.600663 -44.280706) (xy 283.631894 -44.280328) (xy 285.154878 -44.280328) (xy 285.164654 -44.279876)
			(xy 285.1828 -44.272597) (xy 285.196927 -44.25908) (xy 285.20136 -44.250356) (xy 285.239206 -44.166028)
			(xy 285.242754 -44.15686) (xy 285.243472 -44.137237) (xy 285.236792 -44.118772) (xy 285.23057 -44.111164)
			(xy 285.212371 -44.090091) (xy 285.181706 -44.043614) (xy 285.158123 -43.993174) (xy 285.142121 -43.939842)
			(xy 285.134041 -43.884751) (xy 285.133542 -43.85691) (xy 285.134028 -43.829659) (xy 285.141784 -43.775711)
			(xy 285.157139 -43.723416) (xy 285.179781 -43.673839) (xy 285.209247 -43.627989) (xy 285.244938 -43.586798)
			(xy 285.286129 -43.551107) (xy 285.331979 -43.521641) (xy 285.381556 -43.498999) (xy 285.433851 -43.483644)
			(xy 285.487799 -43.475888) (xy 285.542301 -43.475888) (xy 285.596249 -43.483644) (xy 285.648544 -43.498999)
			(xy 285.698121 -43.521641) (xy 285.743971 -43.551107) (xy 285.785162 -43.586798) (xy 285.820853 -43.627989)
			(xy 285.850319 -43.673839) (xy 285.872961 -43.723416) (xy 285.876732 -43.73626) (xy 304.412902 -43.73626)
			(xy 304.416973 -43.680638) (xy 304.429099 -43.626201) (xy 304.449022 -43.57411) (xy 304.476318 -43.525475)
			(xy 304.510404 -43.481332) (xy 304.550553 -43.442623) (xy 304.595911 -43.410172) (xy 304.645511 -43.384671)
			(xy 304.698295 -43.366664) (xy 304.753138 -43.356534) (xy 304.808872 -43.354497) (xy 304.864309 -43.360597)
			(xy 304.918266 -43.374703) (xy 304.969595 -43.396515) (xy 305.017201 -43.425569) (xy 305.060069 -43.461244)
			(xy 305.097286 -43.502781) (xy 305.128059 -43.549294) (xy 305.136285 -43.566842) (xy 307.533292 -43.566842)
			(xy 307.537363 -43.51122) (xy 307.549489 -43.456783) (xy 307.569412 -43.404692) (xy 307.596708 -43.356057)
			(xy 307.630794 -43.311914) (xy 307.670943 -43.273205) (xy 307.716301 -43.240754) (xy 307.765901 -43.215253)
			(xy 307.818685 -43.197246) (xy 307.873528 -43.187116) (xy 307.929262 -43.185079) (xy 307.984699 -43.191179)
			(xy 308.038656 -43.205285) (xy 308.089985 -43.227097) (xy 308.137591 -43.256151) (xy 308.180459 -43.291826)
			(xy 308.192462 -43.305222) (xy 328.50709 -43.305222) (xy 328.507571 -43.277852) (xy 328.515386 -43.223674)
			(xy 328.530872 -43.171171) (xy 328.55371 -43.121424) (xy 328.583431 -43.075456) (xy 328.60107 -43.054524)
			(xy 328.601324 -43.05427) (xy 328.60689 -43.04717) (xy 328.613148 -43.030263) (xy 328.613516 -43.02125)
			(xy 328.613516 -42.954194) (xy 328.613158 -42.945177) (xy 328.606911 -42.928261) (xy 328.601324 -42.921174)
			(xy 328.60107 -42.921174) (xy 328.60107 -42.92092) (xy 328.583422 -42.899995) (xy 328.553713 -42.85402)
			(xy 328.530879 -42.80427) (xy 328.51539 -42.751768) (xy 328.507563 -42.697592) (xy 328.50709 -42.670222)
			(xy 328.50763 -42.641484) (xy 328.516249 -42.584657) (xy 328.533295 -42.529767) (xy 328.558383 -42.478055)
			(xy 328.590945 -42.430691) (xy 328.610214 -42.409364) (xy 328.616818 -42.402506) (xy 328.62393 -42.384472)
			(xy 328.62393 -42.295572) (xy 328.616818 -42.277538) (xy 328.610214 -42.27068) (xy 328.590965 -42.249334)
			(xy 328.5584 -42.201975) (xy 328.533308 -42.150266) (xy 328.516257 -42.095378) (xy 328.507633 -42.038554)
			(xy 328.50763 -41.981078) (xy 328.51625 -41.924253) (xy 328.533296 -41.869364) (xy 328.558384 -41.817653)
			(xy 328.590945 -41.770291) (xy 328.610214 -41.748964) (xy 328.616818 -41.742106) (xy 328.62393 -41.724072)
			(xy 328.62393 -41.635172) (xy 328.616818 -41.617138) (xy 328.610214 -41.61028) (xy 328.59095 -41.588947)
			(xy 328.558383 -41.541587) (xy 328.53329 -41.489876) (xy 328.516238 -41.434987) (xy 328.507613 -41.378161)
			(xy 328.50709 -41.349422) (xy 328.507576 -41.322171) (xy 328.515332 -41.268223) (xy 328.530687 -41.215928)
			(xy 328.553329 -41.166351) (xy 328.582795 -41.120501) (xy 328.618486 -41.07931) (xy 328.659677 -41.043619)
			(xy 328.705527 -41.014153) (xy 328.755104 -40.991511) (xy 328.807399 -40.976156) (xy 328.861347 -40.9684)
			(xy 328.915849 -40.9684) (xy 328.93897 -40.971724) (xy 348.894144 -40.971724) (xy 348.898215 -40.916102)
			(xy 348.910341 -40.861665) (xy 348.930264 -40.809574) (xy 348.95756 -40.760939) (xy 348.991646 -40.716796)
			(xy 349.031795 -40.678087) (xy 349.077153 -40.645636) (xy 349.126753 -40.620135) (xy 349.179537 -40.602128)
			(xy 349.23438 -40.591998) (xy 349.290114 -40.589961) (xy 349.345551 -40.596061) (xy 349.399508 -40.610167)
			(xy 349.450837 -40.631979) (xy 349.498443 -40.661033) (xy 349.541311 -40.696708) (xy 349.578528 -40.738245)
			(xy 349.609301 -40.784758) (xy 349.632973 -40.835255) (xy 349.649041 -40.888662) (xy 349.657161 -40.943838)
			(xy 349.65767 -40.971724) (xy 349.657161 -40.99961) (xy 349.649041 -41.054786) (xy 349.632973 -41.108193)
			(xy 349.609301 -41.15869) (xy 349.578528 -41.205203) (xy 349.541311 -41.24674) (xy 349.514862 -41.268751)
			(xy 364.14405 -41.268751) (xy 364.14405 -41.214249) (xy 364.151806 -41.160301) (xy 364.167159 -41.108007)
			(xy 364.189799 -41.058429) (xy 364.219263 -41.012578) (xy 364.254952 -40.971386) (xy 364.296139 -40.935691)
			(xy 364.341987 -40.906222) (xy 364.391562 -40.883576) (xy 364.443855 -40.868216) (xy 364.497801 -40.860453)
			(xy 364.525052 -40.859964) (xy 364.553792 -40.860466) (xy 364.61062 -40.869095) (xy 364.66551 -40.886151)
			(xy 364.717221 -40.911247) (xy 364.764583 -40.943816) (xy 364.78591 -40.963088) (xy 364.792768 -40.969692)
			(xy 364.810802 -40.976804) (xy 364.899702 -40.976804) (xy 364.917736 -40.969692) (xy 364.924594 -40.963088)
			(xy 364.945907 -40.943801) (xy 364.993272 -40.911235) (xy 365.044987 -40.886145) (xy 365.099881 -40.869098)
			(xy 365.156712 -40.860481) (xy 365.185452 -40.859964) (xy 365.212705 -40.86048) (xy 365.266657 -40.868231)
			(xy 365.318957 -40.883582) (xy 365.36854 -40.90622) (xy 365.414395 -40.935684) (xy 365.455591 -40.971375)
			(xy 365.491287 -41.012566) (xy 365.520757 -41.058418) (xy 365.543402 -41.107998) (xy 365.558759 -41.160296)
			(xy 365.566517 -41.214247) (xy 365.566517 -41.268753) (xy 365.558759 -41.322704) (xy 365.543402 -41.375002)
			(xy 365.520757 -41.424582) (xy 365.491287 -41.470434) (xy 365.455591 -41.511625) (xy 365.414395 -41.547316)
			(xy 365.36854 -41.57678) (xy 365.318957 -41.599418) (xy 365.266657 -41.614769) (xy 365.212705 -41.62252)
			(xy 365.185452 -41.62298) (xy 365.156713 -41.622464) (xy 365.099886 -41.613836) (xy 365.044996 -41.596783)
			(xy 364.993285 -41.571691) (xy 364.945922 -41.539126) (xy 364.924594 -41.519856) (xy 364.917736 -41.513252)
			(xy 364.899702 -41.50614) (xy 364.810802 -41.50614) (xy 364.792768 -41.513252) (xy 364.78591 -41.519856)
			(xy 364.764602 -41.539149) (xy 364.717235 -41.571712) (xy 364.665518 -41.5968) (xy 364.610623 -41.613846)
			(xy 364.553792 -41.622463) (xy 364.525052 -41.62298) (xy 364.497801 -41.622547) (xy 364.443854 -41.614784)
			(xy 364.391562 -41.599424) (xy 364.341987 -41.576778) (xy 364.296139 -41.547309) (xy 364.254952 -41.511614)
			(xy 364.219263 -41.470422) (xy 364.189799 -41.424571) (xy 364.167159 -41.374993) (xy 364.151806 -41.322699)
			(xy 364.14405 -41.268751) (xy 349.514862 -41.268751) (xy 349.498443 -41.282415) (xy 349.450837 -41.311469)
			(xy 349.399508 -41.333281) (xy 349.345551 -41.347387) (xy 349.290114 -41.353487) (xy 349.23438 -41.35145)
			(xy 349.179537 -41.34132) (xy 349.126753 -41.323313) (xy 349.077153 -41.297812) (xy 349.031795 -41.265361)
			(xy 348.991646 -41.226652) (xy 348.95756 -41.182509) (xy 348.930264 -41.133874) (xy 348.910341 -41.081783)
			(xy 348.898215 -41.027346) (xy 348.894144 -40.971724) (xy 328.93897 -40.971724) (xy 328.969797 -40.976156)
			(xy 329.022092 -40.991511) (xy 329.071669 -41.014153) (xy 329.117519 -41.043619) (xy 329.15871 -41.07931)
			(xy 329.194401 -41.120501) (xy 329.223867 -41.166351) (xy 329.246509 -41.215928) (xy 329.261864 -41.268223)
			(xy 329.26962 -41.322171) (xy 329.270106 -41.349422) (xy 329.269594 -41.378161) (xy 329.260968 -41.434989)
			(xy 329.243915 -41.48988) (xy 329.218821 -41.541591) (xy 329.186254 -41.588954) (xy 329.166982 -41.61028)
			(xy 329.160378 -41.617138) (xy 329.153266 -41.635172) (xy 329.153266 -41.724072) (xy 329.160378 -41.742106)
			(xy 329.166982 -41.748964) (xy 329.186274 -41.770272) (xy 329.218838 -41.817638) (xy 329.243928 -41.869353)
			(xy 329.260976 -41.924246) (xy 329.269597 -41.981076) (xy 329.269594 -42.038556) (xy 329.260969 -42.095385)
			(xy 329.243917 -42.150277) (xy 329.218822 -42.20199) (xy 329.186254 -42.249353) (xy 329.166982 -42.27068)
			(xy 329.160378 -42.277538) (xy 329.153266 -42.295572) (xy 329.153266 -42.384472) (xy 329.160378 -42.402506)
			(xy 329.166982 -42.409364) (xy 329.186266 -42.430679) (xy 329.21883 -42.478045) (xy 329.24392 -42.529759)
			(xy 329.260967 -42.584653) (xy 329.269587 -42.641482) (xy 329.270106 -42.670222) (xy 329.269651 -42.697593)
			(xy 329.261831 -42.751772) (xy 329.246339 -42.804275) (xy 329.225784 -42.849038) (xy 331.091792 -42.849038)
			(xy 331.095863 -42.793416) (xy 331.107989 -42.738979) (xy 331.127912 -42.686888) (xy 331.155208 -42.638253)
			(xy 331.189294 -42.59411) (xy 331.229443 -42.555401) (xy 331.274801 -42.52295) (xy 331.324401 -42.497449)
			(xy 331.377185 -42.479442) (xy 331.432028 -42.469312) (xy 331.487762 -42.467275) (xy 331.543199 -42.473375)
			(xy 331.597156 -42.487481) (xy 331.648485 -42.509293) (xy 331.696091 -42.538347) (xy 331.738959 -42.574022)
			(xy 331.776176 -42.615559) (xy 331.806949 -42.662072) (xy 331.830621 -42.712569) (xy 331.846689 -42.765976)
			(xy 331.854809 -42.821152) (xy 331.85517 -42.84091) (xy 337.132928 -42.84091) (xy 337.136999 -42.785288)
			(xy 337.149125 -42.730851) (xy 337.169048 -42.67876) (xy 337.196344 -42.630125) (xy 337.23043 -42.585982)
			(xy 337.270579 -42.547273) (xy 337.315937 -42.514822) (xy 337.365537 -42.489321) (xy 337.418321 -42.471314)
			(xy 337.473164 -42.461184) (xy 337.528898 -42.459147) (xy 337.584335 -42.465247) (xy 337.638292 -42.479353)
			(xy 337.689621 -42.501165) (xy 337.737227 -42.530219) (xy 337.780095 -42.565894) (xy 337.817312 -42.607431)
			(xy 337.848085 -42.653944) (xy 337.871757 -42.704441) (xy 337.887825 -42.757848) (xy 337.895945 -42.813024)
			(xy 337.896454 -42.84091) (xy 337.895945 -42.868796) (xy 337.887825 -42.923972) (xy 337.871757 -42.977379)
			(xy 337.848085 -43.027876) (xy 337.817312 -43.074389) (xy 337.780095 -43.115926) (xy 337.737227 -43.151601)
			(xy 337.689621 -43.180655) (xy 337.638292 -43.202467) (xy 337.584335 -43.216573) (xy 337.528898 -43.222673)
			(xy 337.473164 -43.220636) (xy 337.418321 -43.210506) (xy 337.365537 -43.192499) (xy 337.315937 -43.166998)
			(xy 337.270579 -43.134547) (xy 337.23043 -43.095838) (xy 337.196344 -43.051695) (xy 337.169048 -43.00306)
			(xy 337.149125 -42.950969) (xy 337.136999 -42.896532) (xy 337.132928 -42.84091) (xy 331.85517 -42.84091)
			(xy 331.855318 -42.849038) (xy 331.854809 -42.876924) (xy 331.846689 -42.9321) (xy 331.830621 -42.985507)
			(xy 331.806949 -43.036004) (xy 331.776176 -43.082517) (xy 331.738959 -43.124054) (xy 331.696091 -43.159729)
			(xy 331.648485 -43.188783) (xy 331.597156 -43.210595) (xy 331.543199 -43.224701) (xy 331.487762 -43.230801)
			(xy 331.432028 -43.228764) (xy 331.377185 -43.218634) (xy 331.324401 -43.200627) (xy 331.274801 -43.175126)
			(xy 331.229443 -43.142675) (xy 331.189294 -43.103966) (xy 331.155208 -43.059823) (xy 331.127912 -43.011188)
			(xy 331.107989 -42.959097) (xy 331.095863 -42.90466) (xy 331.091792 -42.849038) (xy 329.225784 -42.849038)
			(xy 329.223495 -42.854022) (xy 329.193768 -42.899988) (xy 329.176126 -42.92092) (xy 329.175872 -42.921174)
			(xy 329.170287 -42.928262) (xy 329.16404 -42.945178) (xy 329.16368 -42.954194) (xy 329.16368 -43.02125)
			(xy 329.164065 -43.030264) (xy 329.170294 -43.047181) (xy 329.175872 -43.05427) (xy 329.176126 -43.05427)
			(xy 329.176126 -43.054524) (xy 329.193747 -43.075471) (xy 329.223461 -43.12144) (xy 329.2463 -43.171184)
			(xy 329.261795 -43.223681) (xy 329.269629 -43.277854) (xy 329.270106 -43.305222) (xy 329.26962 -43.332473)
			(xy 329.261864 -43.386421) (xy 329.246509 -43.438716) (xy 329.223867 -43.488293) (xy 329.194401 -43.534143)
			(xy 329.15871 -43.575334) (xy 329.117519 -43.611025) (xy 329.071669 -43.640491) (xy 329.022092 -43.663133)
			(xy 328.969797 -43.678488) (xy 328.915849 -43.686244) (xy 328.861347 -43.686244) (xy 328.807399 -43.678488)
			(xy 328.755104 -43.663133) (xy 328.705527 -43.640491) (xy 328.659677 -43.611025) (xy 328.618486 -43.575334)
			(xy 328.582795 -43.534143) (xy 328.553329 -43.488293) (xy 328.530687 -43.438716) (xy 328.515332 -43.386421)
			(xy 328.507576 -43.332473) (xy 328.50709 -43.305222) (xy 308.192462 -43.305222) (xy 308.217676 -43.333363)
			(xy 308.248449 -43.379876) (xy 308.272121 -43.430373) (xy 308.288189 -43.48378) (xy 308.296309 -43.538956)
			(xy 308.296818 -43.566842) (xy 308.296309 -43.594728) (xy 308.288189 -43.649904) (xy 308.272121 -43.703311)
			(xy 308.248449 -43.753808) (xy 308.217676 -43.800321) (xy 308.180459 -43.841858) (xy 308.137591 -43.877533)
			(xy 308.089985 -43.906587) (xy 308.038656 -43.928399) (xy 307.984699 -43.942505) (xy 307.929262 -43.948605)
			(xy 307.873528 -43.946568) (xy 307.818685 -43.936438) (xy 307.765901 -43.918431) (xy 307.716301 -43.89293)
			(xy 307.670943 -43.860479) (xy 307.630794 -43.82177) (xy 307.596708 -43.777627) (xy 307.569412 -43.728992)
			(xy 307.549489 -43.676901) (xy 307.537363 -43.622464) (xy 307.533292 -43.566842) (xy 305.136285 -43.566842)
			(xy 305.151731 -43.599791) (xy 305.167799 -43.653198) (xy 305.175919 -43.708374) (xy 305.176428 -43.73626)
			(xy 305.175919 -43.764146) (xy 305.167799 -43.819322) (xy 305.151731 -43.872729) (xy 305.128059 -43.923226)
			(xy 305.097286 -43.969739) (xy 305.060069 -44.011276) (xy 305.017201 -44.046951) (xy 304.969595 -44.076005)
			(xy 304.918266 -44.097817) (xy 304.864309 -44.111923) (xy 304.808872 -44.118023) (xy 304.753138 -44.115986)
			(xy 304.698295 -44.105856) (xy 304.645511 -44.087849) (xy 304.595911 -44.062348) (xy 304.550553 -44.029897)
			(xy 304.510404 -43.991188) (xy 304.476318 -43.947045) (xy 304.449022 -43.89841) (xy 304.429099 -43.846319)
			(xy 304.416973 -43.791882) (xy 304.412902 -43.73626) (xy 285.876732 -43.73626) (xy 285.888316 -43.775711)
			(xy 285.896072 -43.829659) (xy 285.896558 -43.85691) (xy 285.896039 -43.884747) (xy 285.88794 -43.93983)
			(xy 285.87193 -43.993153) (xy 285.848348 -44.043587) (xy 285.817693 -44.090062) (xy 285.79953 -44.111164)
			(xy 285.793268 -44.118753) (xy 285.786558 -44.137231) (xy 285.78728 -44.156876) (xy 285.790894 -44.166028)
			(xy 285.82874 -44.250356) (xy 285.833137 -44.259113) (xy 285.847248 -44.272682) (xy 285.865431 -44.279938)
			(xy 285.875222 -44.280328) (xy 301.143416 -44.280328) (xy 301.167038 -44.266358) (xy 301.171864 -44.257722)
			(xy 301.179992 -44.265596) (xy 301.187338 -44.272255) (xy 301.205649 -44.279819) (xy 301.215552 -44.280328)
			(xy 304.174398 -44.280328) (xy 304.214267 -44.280921) (xy 304.293463 -44.290224) (xy 304.371048 -44.308634)
			(xy 304.44598 -44.335904) (xy 304.51725 -44.371668) (xy 304.583899 -44.415443) (xy 304.614834 -44.440602)
			(xy 304.621865 -44.445987) (xy 304.638498 -44.452026) (xy 304.656194 -44.452026) (xy 304.672827 -44.445987)
			(xy 304.679858 -44.440602) (xy 304.710771 -44.415412) (xy 304.77741 -44.371609) (xy 304.84868 -44.335832)
			(xy 304.923619 -44.308565) (xy 305.001215 -44.290176) (xy 305.080421 -44.280912) (xy 305.120294 -44.280328)
			(xy 308.939438 -44.280328) (xy 308.941216 -44.280582) (xy 308.94147 -44.280582) (xy 308.951208 -44.280143)
			(xy 308.969258 -44.272815) (xy 308.983296 -44.259309) (xy 308.987698 -44.25061) (xy 309.025798 -44.166028)
			(xy 309.029348 -44.15686) (xy 309.030066 -44.137237) (xy 309.023385 -44.118772) (xy 309.017162 -44.111164)
			(xy 308.998961 -44.090092) (xy 308.968297 -44.043615) (xy 308.944714 -43.993175) (xy 308.928713 -43.939842)
			(xy 308.920633 -43.884751) (xy 308.920134 -43.85691) (xy 308.92062 -43.829659) (xy 308.928376 -43.775711)
			(xy 308.943731 -43.723416) (xy 308.966373 -43.673839) (xy 308.995839 -43.627989) (xy 309.03153 -43.586798)
			(xy 309.072721 -43.551107) (xy 309.118571 -43.521641) (xy 309.168148 -43.498999) (xy 309.220443 -43.483644)
			(xy 309.274391 -43.475888) (xy 309.328893 -43.475888) (xy 309.382841 -43.483644) (xy 309.435136 -43.498999)
			(xy 309.484713 -43.521641) (xy 309.530563 -43.551107) (xy 309.571754 -43.586798) (xy 309.607445 -43.627989)
			(xy 309.636911 -43.673839) (xy 309.659553 -43.723416) (xy 309.674908 -43.775711) (xy 309.682664 -43.829659)
			(xy 309.68315 -43.85691) (xy 309.682682 -43.883096) (xy 309.675505 -43.934976) (xy 309.661301 -43.985386)
			(xy 309.640337 -44.03338) (xy 309.613007 -44.078057) (xy 309.579824 -44.118577) (xy 309.541411 -44.154178)
			(xy 309.498491 -44.184192) (xy 309.475378 -44.196508) (xy 309.466272 -44.201631) (xy 309.45287 -44.217633)
			(xy 309.446948 -44.237647) (xy 309.449484 -44.258365) (xy 309.460059 -44.27636) (xy 309.476924 -44.288657)
			(xy 309.497291 -44.293222) (xy 309.507636 -44.291758) (xy 309.538411 -44.286424) (xy 309.600611 -44.280704)
			(xy 309.631842 -44.280328) (xy 311.154826 -44.280328) (xy 311.164605 -44.279911) (xy 311.182753 -44.272616)
			(xy 311.196877 -44.259085) (xy 311.201308 -44.250356) (xy 311.239154 -44.166028) (xy 311.242713 -44.156863)
			(xy 311.243432 -44.137236) (xy 311.236745 -44.11877) (xy 311.230518 -44.111164) (xy 311.212327 -44.090084)
			(xy 311.181659 -44.04361) (xy 311.158074 -43.993172) (xy 311.14207 -43.939841) (xy 311.133989 -43.88475)
			(xy 311.13349 -43.85691) (xy 311.133976 -43.829659) (xy 311.141732 -43.775711) (xy 311.157087 -43.723416)
			(xy 311.179729 -43.673839) (xy 311.209195 -43.627989) (xy 311.244886 -43.586798) (xy 311.286077 -43.551107)
			(xy 311.331927 -43.521641) (xy 311.381504 -43.498999) (xy 311.433799 -43.483644) (xy 311.487747 -43.475888)
			(xy 311.542249 -43.475888) (xy 311.596197 -43.483644) (xy 311.648492 -43.498999) (xy 311.698069 -43.521641)
			(xy 311.743919 -43.551107) (xy 311.78511 -43.586798) (xy 311.820801 -43.627989) (xy 311.850267 -43.673839)
			(xy 311.872909 -43.723416) (xy 311.87668 -43.73626) (xy 330.41285 -43.73626) (xy 330.416921 -43.680638)
			(xy 330.429047 -43.626201) (xy 330.44897 -43.57411) (xy 330.476266 -43.525475) (xy 330.510352 -43.481332)
			(xy 330.550501 -43.442623) (xy 330.595859 -43.410172) (xy 330.645459 -43.384671) (xy 330.698243 -43.366664)
			(xy 330.753086 -43.356534) (xy 330.80882 -43.354497) (xy 330.864257 -43.360597) (xy 330.918214 -43.374703)
			(xy 330.969543 -43.396515) (xy 331.017149 -43.425569) (xy 331.060017 -43.461244) (xy 331.097234 -43.502781)
			(xy 331.128007 -43.549294) (xy 331.136233 -43.566842) (xy 333.53324 -43.566842) (xy 333.537311 -43.51122)
			(xy 333.549437 -43.456783) (xy 333.56936 -43.404692) (xy 333.596656 -43.356057) (xy 333.630742 -43.311914)
			(xy 333.670891 -43.273205) (xy 333.716249 -43.240754) (xy 333.765849 -43.215253) (xy 333.818633 -43.197246)
			(xy 333.873476 -43.187116) (xy 333.92921 -43.185079) (xy 333.984647 -43.191179) (xy 334.038604 -43.205285)
			(xy 334.089933 -43.227097) (xy 334.137539 -43.256151) (xy 334.180407 -43.291826) (xy 334.19241 -43.305222)
			(xy 366.607344 -43.305222) (xy 366.607812 -43.277852) (xy 366.615628 -43.223672) (xy 366.631116 -43.171169)
			(xy 366.653957 -43.121422) (xy 366.683682 -43.075455) (xy 366.701324 -43.054524) (xy 366.701578 -43.05427)
			(xy 366.707151 -43.047174) (xy 366.713404 -43.030264) (xy 366.71377 -43.02125) (xy 366.71377 -42.954194)
			(xy 366.713423 -42.945176) (xy 366.707169 -42.928259) (xy 366.701578 -42.921174) (xy 366.701324 -42.921174)
			(xy 366.701324 -42.92092) (xy 366.683685 -42.899988) (xy 366.653972 -42.854016) (xy 366.631136 -42.804268)
			(xy 366.615645 -42.751767) (xy 366.607817 -42.697591) (xy 366.607344 -42.670222) (xy 366.607896 -42.641484)
			(xy 366.616514 -42.584659) (xy 366.633558 -42.529769) (xy 366.658643 -42.478057) (xy 366.691201 -42.430692)
			(xy 366.710468 -42.409364) (xy 366.717072 -42.402506) (xy 366.724184 -42.384472) (xy 366.724184 -42.295572)
			(xy 366.717072 -42.277538) (xy 366.710468 -42.27068) (xy 366.691222 -42.249333) (xy 366.65866 -42.201972)
			(xy 366.633571 -42.150264) (xy 366.616522 -42.095376) (xy 366.607899 -42.038553) (xy 366.607896 -41.981079)
			(xy 366.616515 -41.924255) (xy 366.633559 -41.869366) (xy 366.658644 -41.817655) (xy 366.691201 -41.770292)
			(xy 366.710468 -41.748964) (xy 366.717072 -41.742106) (xy 366.724184 -41.724072) (xy 366.724184 -41.635172)
			(xy 366.717072 -41.617138) (xy 366.710468 -41.61028) (xy 366.691213 -41.58894) (xy 366.658643 -41.541582)
			(xy 366.633547 -41.489874) (xy 366.616493 -41.434986) (xy 366.607867 -41.37816) (xy 366.607344 -41.349422)
			(xy 366.60783 -41.322171) (xy 366.615586 -41.268223) (xy 366.630941 -41.215928) (xy 366.653583 -41.166351)
			(xy 366.683049 -41.120501) (xy 366.71874 -41.07931) (xy 366.759931 -41.043619) (xy 366.805781 -41.014153)
			(xy 366.855358 -40.991511) (xy 366.907653 -40.976156) (xy 366.961601 -40.9684) (xy 367.016103 -40.9684)
			(xy 367.039224 -40.971724) (xy 374.894092 -40.971724) (xy 374.898163 -40.916102) (xy 374.910289 -40.861665)
			(xy 374.930212 -40.809574) (xy 374.957508 -40.760939) (xy 374.991594 -40.716796) (xy 375.031743 -40.678087)
			(xy 375.077101 -40.645636) (xy 375.126701 -40.620135) (xy 375.179485 -40.602128) (xy 375.234328 -40.591998)
			(xy 375.290062 -40.589961) (xy 375.345499 -40.596061) (xy 375.399456 -40.610167) (xy 375.450785 -40.631979)
			(xy 375.498391 -40.661033) (xy 375.541259 -40.696708) (xy 375.578476 -40.738245) (xy 375.609249 -40.784758)
			(xy 375.632921 -40.835255) (xy 375.648989 -40.888662) (xy 375.657109 -40.943838) (xy 375.657618 -40.971724)
			(xy 375.657109 -40.99961) (xy 375.648989 -41.054786) (xy 375.632921 -41.108193) (xy 375.609249 -41.15869)
			(xy 375.578476 -41.205203) (xy 375.541259 -41.24674) (xy 375.514808 -41.268753) (xy 390.14395 -41.268753)
			(xy 390.14395 -41.214247) (xy 390.151707 -41.160295) (xy 390.167063 -41.107996) (xy 390.189706 -41.058416)
			(xy 390.219174 -41.012562) (xy 390.254869 -40.971369) (xy 390.296062 -40.935674) (xy 390.341916 -40.906206)
			(xy 390.391496 -40.883563) (xy 390.443795 -40.868207) (xy 390.497747 -40.86045) (xy 390.525 -40.859964)
			(xy 390.553738 -40.860497) (xy 390.610565 -40.869119) (xy 390.665455 -40.886167) (xy 390.717167 -40.911257)
			(xy 390.76453 -40.943819) (xy 390.785858 -40.963088) (xy 390.792716 -40.969692) (xy 390.81075 -40.976804)
			(xy 390.89965 -40.976804) (xy 390.917684 -40.969692) (xy 390.924542 -40.963088) (xy 390.945876 -40.943826)
			(xy 390.993235 -40.911256) (xy 391.044945 -40.886161) (xy 391.099835 -40.869109) (xy 391.156661 -40.860485)
			(xy 391.1854 -40.859964) (xy 391.212649 -40.860506) (xy 391.266593 -40.868262) (xy 391.318884 -40.883616)
			(xy 391.368457 -40.906256) (xy 391.414304 -40.93572) (xy 391.455491 -40.971409) (xy 391.49118 -41.012596)
			(xy 391.520644 -41.058443) (xy 391.543284 -41.108016) (xy 391.558638 -41.160307) (xy 391.566394 -41.214251)
			(xy 391.566394 -41.268749) (xy 391.558638 -41.322693) (xy 391.543284 -41.374984) (xy 391.520644 -41.424557)
			(xy 391.49118 -41.470404) (xy 391.455491 -41.511591) (xy 391.414304 -41.54728) (xy 391.368457 -41.576744)
			(xy 391.318884 -41.599384) (xy 391.266593 -41.614738) (xy 391.212649 -41.622494) (xy 391.1854 -41.62298)
			(xy 391.156662 -41.622435) (xy 391.099837 -41.613814) (xy 391.044947 -41.596768) (xy 390.993235 -41.571682)
			(xy 390.945871 -41.539123) (xy 390.924542 -41.519856) (xy 390.917684 -41.513252) (xy 390.89965 -41.50614)
			(xy 390.81075 -41.50614) (xy 390.792716 -41.513252) (xy 390.785858 -41.519856) (xy 390.76453 -41.539126)
			(xy 390.717168 -41.571692) (xy 390.665457 -41.596785) (xy 390.610566 -41.613836) (xy 390.553739 -41.622459)
			(xy 390.525 -41.62298) (xy 390.497747 -41.62255) (xy 390.443795 -41.614793) (xy 390.391496 -41.599437)
			(xy 390.341916 -41.576794) (xy 390.296062 -41.547326) (xy 390.254869 -41.511631) (xy 390.219174 -41.470438)
			(xy 390.189706 -41.424584) (xy 390.167063 -41.375004) (xy 390.151707 -41.322705) (xy 390.14395 -41.268753)
			(xy 375.514808 -41.268753) (xy 375.498391 -41.282415) (xy 375.450785 -41.311469) (xy 375.399456 -41.333281)
			(xy 375.345499 -41.347387) (xy 375.290062 -41.353487) (xy 375.234328 -41.35145) (xy 375.179485 -41.34132)
			(xy 375.126701 -41.323313) (xy 375.077101 -41.297812) (xy 375.031743 -41.265361) (xy 374.991594 -41.226652)
			(xy 374.957508 -41.182509) (xy 374.930212 -41.133874) (xy 374.910289 -41.081783) (xy 374.898163 -41.027346)
			(xy 374.894092 -40.971724) (xy 367.039224 -40.971724) (xy 367.070051 -40.976156) (xy 367.122346 -40.991511)
			(xy 367.171923 -41.014153) (xy 367.217773 -41.043619) (xy 367.258964 -41.07931) (xy 367.294655 -41.120501)
			(xy 367.324121 -41.166351) (xy 367.346763 -41.215928) (xy 367.362118 -41.268223) (xy 367.369874 -41.322171)
			(xy 367.37036 -41.349422) (xy 367.369834 -41.378161) (xy 367.361209 -41.434987) (xy 367.344159 -41.489877)
			(xy 367.319068 -41.541589) (xy 367.286505 -41.588952) (xy 367.267236 -41.61028) (xy 367.260632 -41.617138)
			(xy 367.25352 -41.635172) (xy 367.25352 -41.724072) (xy 367.260632 -41.742106) (xy 367.267236 -41.748964)
			(xy 367.28653 -41.770271) (xy 367.319098 -41.817636) (xy 367.344191 -41.86935) (xy 367.361242 -41.924245)
			(xy 367.369863 -41.981075) (xy 367.369861 -42.038557) (xy 367.361234 -42.095387) (xy 367.34418 -42.150279)
			(xy 367.319082 -42.201992) (xy 367.28651 -42.249354) (xy 367.267236 -42.27068) (xy 367.260632 -42.277538)
			(xy 367.25352 -42.295572) (xy 367.25352 -42.384472) (xy 367.260632 -42.402506) (xy 367.267236 -42.409364)
			(xy 367.286513 -42.430686) (xy 367.319079 -42.478049) (xy 367.344171 -42.529762) (xy 367.36122 -42.584654)
			(xy 367.369841 -42.641483) (xy 367.37036 -42.670222) (xy 367.369917 -42.697593) (xy 367.362095 -42.751774)
			(xy 367.346601 -42.804277) (xy 367.326044 -42.849038) (xy 369.192046 -42.849038) (xy 369.196117 -42.793416)
			(xy 369.208243 -42.738979) (xy 369.228166 -42.686888) (xy 369.255462 -42.638253) (xy 369.289548 -42.59411)
			(xy 369.329697 -42.555401) (xy 369.375055 -42.52295) (xy 369.424655 -42.497449) (xy 369.477439 -42.479442)
			(xy 369.532282 -42.469312) (xy 369.588016 -42.467275) (xy 369.643453 -42.473375) (xy 369.69741 -42.487481)
			(xy 369.748739 -42.509293) (xy 369.796345 -42.538347) (xy 369.839213 -42.574022) (xy 369.87643 -42.615559)
			(xy 369.907203 -42.662072) (xy 369.930875 -42.712569) (xy 369.946943 -42.765976) (xy 369.955063 -42.821152)
			(xy 369.955424 -42.84091) (xy 375.233182 -42.84091) (xy 375.237253 -42.785288) (xy 375.249379 -42.730851)
			(xy 375.269302 -42.67876) (xy 375.296598 -42.630125) (xy 375.330684 -42.585982) (xy 375.370833 -42.547273)
			(xy 375.416191 -42.514822) (xy 375.465791 -42.489321) (xy 375.518575 -42.471314) (xy 375.573418 -42.461184)
			(xy 375.629152 -42.459147) (xy 375.684589 -42.465247) (xy 375.738546 -42.479353) (xy 375.789875 -42.501165)
			(xy 375.837481 -42.530219) (xy 375.880349 -42.565894) (xy 375.917566 -42.607431) (xy 375.948339 -42.653944)
			(xy 375.972011 -42.704441) (xy 375.988079 -42.757848) (xy 375.996199 -42.813024) (xy 375.996708 -42.84091)
			(xy 375.996199 -42.868796) (xy 375.988079 -42.923972) (xy 375.972011 -42.977379) (xy 375.948339 -43.027876)
			(xy 375.917566 -43.074389) (xy 375.880349 -43.115926) (xy 375.837481 -43.151601) (xy 375.789875 -43.180655)
			(xy 375.738546 -43.202467) (xy 375.684589 -43.216573) (xy 375.629152 -43.222673) (xy 375.573418 -43.220636)
			(xy 375.518575 -43.210506) (xy 375.465791 -43.192499) (xy 375.416191 -43.166998) (xy 375.370833 -43.134547)
			(xy 375.330684 -43.095838) (xy 375.296598 -43.051695) (xy 375.269302 -43.00306) (xy 375.249379 -42.950969)
			(xy 375.237253 -42.896532) (xy 375.233182 -42.84091) (xy 369.955424 -42.84091) (xy 369.955572 -42.849038)
			(xy 369.955063 -42.876924) (xy 369.946943 -42.9321) (xy 369.930875 -42.985507) (xy 369.907203 -43.036004)
			(xy 369.87643 -43.082517) (xy 369.839213 -43.124054) (xy 369.796345 -43.159729) (xy 369.748739 -43.188783)
			(xy 369.69741 -43.210595) (xy 369.643453 -43.224701) (xy 369.588016 -43.230801) (xy 369.532282 -43.228764)
			(xy 369.477439 -43.218634) (xy 369.424655 -43.200627) (xy 369.375055 -43.175126) (xy 369.329697 -43.142675)
			(xy 369.289548 -43.103966) (xy 369.255462 -43.059823) (xy 369.228166 -43.011188) (xy 369.208243 -42.959097)
			(xy 369.196117 -42.90466) (xy 369.192046 -42.849038) (xy 367.326044 -42.849038) (xy 367.323754 -42.854024)
			(xy 367.294024 -42.899989) (xy 367.27638 -42.92092) (xy 367.276126 -42.921174) (xy 367.270536 -42.928258)
			(xy 367.264293 -42.945177) (xy 367.263934 -42.954194) (xy 367.263934 -43.02125) (xy 367.264308 -43.030265)
			(xy 367.270543 -43.047183) (xy 367.276126 -43.05427) (xy 367.27638 -43.05427) (xy 367.27638 -43.054524)
			(xy 367.293994 -43.075476) (xy 367.32371 -43.121443) (xy 367.346551 -43.171186) (xy 367.362048 -43.223682)
			(xy 367.369883 -43.277854) (xy 367.37036 -43.305222) (xy 367.369874 -43.332473) (xy 367.362118 -43.386421)
			(xy 367.346763 -43.438716) (xy 367.324121 -43.488293) (xy 367.294655 -43.534143) (xy 367.258964 -43.575334)
			(xy 367.217773 -43.611025) (xy 367.171923 -43.640491) (xy 367.122346 -43.663133) (xy 367.070051 -43.678488)
			(xy 367.016103 -43.686244) (xy 366.961601 -43.686244) (xy 366.907653 -43.678488) (xy 366.855358 -43.663133)
			(xy 366.805781 -43.640491) (xy 366.759931 -43.611025) (xy 366.71874 -43.575334) (xy 366.683049 -43.534143)
			(xy 366.653583 -43.488293) (xy 366.630941 -43.438716) (xy 366.615586 -43.386421) (xy 366.60783 -43.332473)
			(xy 366.607344 -43.305222) (xy 334.19241 -43.305222) (xy 334.217624 -43.333363) (xy 334.248397 -43.379876)
			(xy 334.272069 -43.430373) (xy 334.288137 -43.48378) (xy 334.296257 -43.538956) (xy 334.296766 -43.566842)
			(xy 334.296257 -43.594728) (xy 334.288137 -43.649904) (xy 334.272069 -43.703311) (xy 334.248397 -43.753808)
			(xy 334.217624 -43.800321) (xy 334.180407 -43.841858) (xy 334.137539 -43.877533) (xy 334.089933 -43.906587)
			(xy 334.038604 -43.928399) (xy 333.984647 -43.942505) (xy 333.92921 -43.948605) (xy 333.873476 -43.946568)
			(xy 333.818633 -43.936438) (xy 333.765849 -43.918431) (xy 333.716249 -43.89293) (xy 333.670891 -43.860479)
			(xy 333.630742 -43.82177) (xy 333.596656 -43.777627) (xy 333.56936 -43.728992) (xy 333.549437 -43.676901)
			(xy 333.537311 -43.622464) (xy 333.53324 -43.566842) (xy 331.136233 -43.566842) (xy 331.151679 -43.599791)
			(xy 331.167747 -43.653198) (xy 331.175867 -43.708374) (xy 331.176376 -43.73626) (xy 331.175867 -43.764146)
			(xy 331.167747 -43.819322) (xy 331.151679 -43.872729) (xy 331.128007 -43.923226) (xy 331.097234 -43.969739)
			(xy 331.060017 -44.011276) (xy 331.017149 -44.046951) (xy 330.969543 -44.076005) (xy 330.918214 -44.097817)
			(xy 330.864257 -44.111923) (xy 330.80882 -44.118023) (xy 330.753086 -44.115986) (xy 330.698243 -44.105856)
			(xy 330.645459 -44.087849) (xy 330.595859 -44.062348) (xy 330.550501 -44.029897) (xy 330.510352 -43.991188)
			(xy 330.476266 -43.947045) (xy 330.44897 -43.89841) (xy 330.429047 -43.846319) (xy 330.416921 -43.791882)
			(xy 330.41285 -43.73626) (xy 311.87668 -43.73626) (xy 311.888264 -43.775711) (xy 311.89602 -43.829659)
			(xy 311.896506 -43.85691) (xy 311.895975 -43.884747) (xy 311.887877 -43.939828) (xy 311.871869 -43.993151)
			(xy 311.84829 -44.043585) (xy 311.817639 -44.090061) (xy 311.799478 -44.111164) (xy 311.793218 -44.118755)
			(xy 311.786503 -44.137231) (xy 311.787226 -44.156877) (xy 311.790842 -44.166028) (xy 311.828688 -44.250356)
			(xy 311.83305 -44.259133) (xy 311.847177 -44.2727) (xy 311.865374 -44.279946) (xy 311.87517 -44.280328)
			(xy 327.143364 -44.280328) (xy 327.166986 -44.266358) (xy 327.171812 -44.257722) (xy 327.17994 -44.265596)
			(xy 327.187303 -44.272232) (xy 327.205601 -44.279809) (xy 327.2155 -44.280328) (xy 330.174346 -44.280328)
			(xy 330.214214 -44.280951) (xy 330.293409 -44.290248) (xy 330.370993 -44.308652) (xy 330.445925 -44.335917)
			(xy 330.517196 -44.371675) (xy 330.583846 -44.415446) (xy 330.614782 -44.440602) (xy 330.621813 -44.445987)
			(xy 330.638446 -44.452026) (xy 330.656142 -44.452026) (xy 330.672775 -44.445987) (xy 330.679806 -44.440602)
			(xy 330.710738 -44.415436) (xy 330.777372 -44.37163) (xy 330.848638 -44.33585) (xy 330.923574 -44.308579)
			(xy 331.001167 -44.290184) (xy 331.08037 -44.280915) (xy 331.120242 -44.280328) (xy 334.939386 -44.280328)
			(xy 334.941164 -44.280582) (xy 334.941418 -44.280582) (xy 334.951152 -44.280105) (xy 334.9692 -44.272795)
			(xy 334.983242 -44.259304) (xy 334.987646 -44.25061) (xy 335.025746 -44.166028) (xy 335.029307 -44.156863)
			(xy 335.030026 -44.137236) (xy 335.023338 -44.11877) (xy 335.01711 -44.111164) (xy 334.998917 -44.090085)
			(xy 334.96825 -44.043611) (xy 334.944665 -43.993172) (xy 334.928662 -43.939841) (xy 334.920581 -43.88475)
			(xy 334.920082 -43.85691) (xy 334.920568 -43.829659) (xy 334.928324 -43.775711) (xy 334.943679 -43.723416)
			(xy 334.966321 -43.673839) (xy 334.995787 -43.627989) (xy 335.031478 -43.586798) (xy 335.072669 -43.551107)
			(xy 335.118519 -43.521641) (xy 335.168096 -43.498999) (xy 335.220391 -43.483644) (xy 335.274339 -43.475888)
			(xy 335.328841 -43.475888) (xy 335.382789 -43.483644) (xy 335.435084 -43.498999) (xy 335.484661 -43.521641)
			(xy 335.530511 -43.551107) (xy 335.571702 -43.586798) (xy 335.607393 -43.627989) (xy 335.636859 -43.673839)
			(xy 335.659501 -43.723416) (xy 335.674856 -43.775711) (xy 335.682612 -43.829659) (xy 335.683098 -43.85691)
			(xy 335.682658 -43.883098) (xy 335.67548 -43.934979) (xy 335.661274 -43.985392) (xy 335.640306 -44.033387)
			(xy 335.612972 -44.078064) (xy 335.579784 -44.118584) (xy 335.541367 -44.154183) (xy 335.498442 -44.184194)
			(xy 335.475326 -44.196508) (xy 335.466246 -44.201663) (xy 335.452867 -44.21766) (xy 335.446956 -44.23766)
			(xy 335.449492 -44.258359) (xy 335.460055 -44.276341) (xy 335.4769 -44.288635) (xy 335.497246 -44.293212)
			(xy 335.507584 -44.291758) (xy 335.53836 -44.286431) (xy 335.600559 -44.280706) (xy 335.63179 -44.280328)
			(xy 337.154774 -44.280328) (xy 337.16455 -44.279873) (xy 337.182696 -44.272596) (xy 337.196823 -44.259079)
			(xy 337.201256 -44.250356) (xy 337.239102 -44.166028) (xy 337.242651 -44.15686) (xy 337.243369 -44.137237)
			(xy 337.236688 -44.118772) (xy 337.230466 -44.111164) (xy 337.212266 -44.090091) (xy 337.181602 -44.043614)
			(xy 337.158018 -43.993174) (xy 337.142017 -43.939842) (xy 337.133937 -43.884751) (xy 337.133438 -43.85691)
			(xy 337.133924 -43.829659) (xy 337.14168 -43.775711) (xy 337.157035 -43.723416) (xy 337.179677 -43.673839)
			(xy 337.209143 -43.627989) (xy 337.244834 -43.586798) (xy 337.286025 -43.551107) (xy 337.331875 -43.521641)
			(xy 337.381452 -43.498999) (xy 337.433747 -43.483644) (xy 337.487695 -43.475888) (xy 337.542197 -43.475888)
			(xy 337.596145 -43.483644) (xy 337.64844 -43.498999) (xy 337.698017 -43.521641) (xy 337.743867 -43.551107)
			(xy 337.785058 -43.586798) (xy 337.820749 -43.627989) (xy 337.850215 -43.673839) (xy 337.872857 -43.723416)
			(xy 337.876628 -43.73626) (xy 368.513104 -43.73626) (xy 368.517175 -43.680638) (xy 368.529301 -43.626201)
			(xy 368.549224 -43.57411) (xy 368.57652 -43.525475) (xy 368.610606 -43.481332) (xy 368.650755 -43.442623)
			(xy 368.696113 -43.410172) (xy 368.745713 -43.384671) (xy 368.798497 -43.366664) (xy 368.85334 -43.356534)
			(xy 368.909074 -43.354497) (xy 368.964511 -43.360597) (xy 369.018468 -43.374703) (xy 369.069797 -43.396515)
			(xy 369.117403 -43.425569) (xy 369.160271 -43.461244) (xy 369.197488 -43.502781) (xy 369.228261 -43.549294)
			(xy 369.236487 -43.566842) (xy 371.633494 -43.566842) (xy 371.637565 -43.51122) (xy 371.649691 -43.456783)
			(xy 371.669614 -43.404692) (xy 371.69691 -43.356057) (xy 371.730996 -43.311914) (xy 371.771145 -43.273205)
			(xy 371.816503 -43.240754) (xy 371.866103 -43.215253) (xy 371.918887 -43.197246) (xy 371.97373 -43.187116)
			(xy 372.029464 -43.185079) (xy 372.084901 -43.191179) (xy 372.138858 -43.205285) (xy 372.190187 -43.227097)
			(xy 372.237793 -43.256151) (xy 372.280661 -43.291826) (xy 372.292664 -43.305222) (xy 392.607292 -43.305222)
			(xy 392.607773 -43.277852) (xy 392.615587 -43.223674) (xy 392.631073 -43.171171) (xy 392.653912 -43.121424)
			(xy 392.683633 -43.075456) (xy 392.701272 -43.054524) (xy 392.701526 -43.05427) (xy 392.707092 -43.04717)
			(xy 392.71335 -43.030263) (xy 392.713718 -43.02125) (xy 392.713718 -42.954194) (xy 392.71336 -42.945177)
			(xy 392.707113 -42.928261) (xy 392.701526 -42.921174) (xy 392.701272 -42.921174) (xy 392.701272 -42.92092)
			(xy 392.683624 -42.899995) (xy 392.653915 -42.85402) (xy 392.631081 -42.80427) (xy 392.615592 -42.751768)
			(xy 392.607765 -42.697592) (xy 392.607292 -42.670222) (xy 392.607831 -42.641484) (xy 392.61645 -42.584657)
			(xy 392.633497 -42.529767) (xy 392.658585 -42.478055) (xy 392.691147 -42.430691) (xy 392.710416 -42.409364)
			(xy 392.71702 -42.402506) (xy 392.724132 -42.384472) (xy 392.724132 -42.295572) (xy 392.71702 -42.277538)
			(xy 392.710416 -42.27068) (xy 392.691167 -42.249334) (xy 392.658602 -42.201975) (xy 392.63351 -42.150266)
			(xy 392.616459 -42.095378) (xy 392.607834 -42.038554) (xy 392.607832 -41.981078) (xy 392.616451 -41.924253)
			(xy 392.633498 -41.869364) (xy 392.658586 -41.817653) (xy 392.691147 -41.770291) (xy 392.710416 -41.748964)
			(xy 392.71702 -41.742106) (xy 392.724132 -41.724072) (xy 392.724132 -41.635172) (xy 392.71702 -41.617138)
			(xy 392.710416 -41.61028) (xy 392.691152 -41.588947) (xy 392.658586 -41.541586) (xy 392.633492 -41.489876)
			(xy 392.61644 -41.434987) (xy 392.607815 -41.378161) (xy 392.607292 -41.349422) (xy 392.607778 -41.322171)
			(xy 392.615534 -41.268223) (xy 392.630889 -41.215928) (xy 392.653531 -41.166351) (xy 392.682997 -41.120501)
			(xy 392.718688 -41.07931) (xy 392.759879 -41.043619) (xy 392.805729 -41.014153) (xy 392.855306 -40.991511)
			(xy 392.907601 -40.976156) (xy 392.961549 -40.9684) (xy 393.016051 -40.9684) (xy 393.039172 -40.971724)
			(xy 400.89404 -40.971724) (xy 400.898111 -40.916102) (xy 400.910237 -40.861665) (xy 400.93016 -40.809574)
			(xy 400.957456 -40.760939) (xy 400.991542 -40.716796) (xy 401.031691 -40.678087) (xy 401.077049 -40.645636)
			(xy 401.126649 -40.620135) (xy 401.179433 -40.602128) (xy 401.234276 -40.591998) (xy 401.29001 -40.589961)
			(xy 401.345447 -40.596061) (xy 401.399404 -40.610167) (xy 401.450733 -40.631979) (xy 401.498339 -40.661033)
			(xy 401.541207 -40.696708) (xy 401.578424 -40.738245) (xy 401.609197 -40.784758) (xy 401.632869 -40.835255)
			(xy 401.648937 -40.888662) (xy 401.657057 -40.943838) (xy 401.657566 -40.971724) (xy 401.657057 -40.99961)
			(xy 401.648937 -41.054786) (xy 401.632869 -41.108193) (xy 401.609197 -41.15869) (xy 401.578424 -41.205203)
			(xy 401.541207 -41.24674) (xy 401.514751 -41.268757) (xy 416.143827 -41.268757) (xy 416.143827 -41.214243)
			(xy 416.151586 -41.160284) (xy 416.166945 -41.107978) (xy 416.189593 -41.058391) (xy 416.219068 -41.012532)
			(xy 416.254769 -40.971335) (xy 416.295971 -40.935639) (xy 416.341833 -40.90617) (xy 416.391423 -40.883529)
			(xy 416.443731 -40.868176) (xy 416.497691 -40.860424) (xy 416.524948 -40.859964) (xy 416.553688 -40.860468)
			(xy 416.610515 -40.869097) (xy 416.665406 -40.886152) (xy 416.717117 -40.911248) (xy 416.764479 -40.943816)
			(xy 416.785806 -40.963088) (xy 416.792664 -40.969692) (xy 416.810698 -40.976804) (xy 416.899598 -40.976804)
			(xy 416.917632 -40.969692) (xy 416.92449 -40.963088) (xy 416.945805 -40.943803) (xy 416.993169 -40.911237)
			(xy 417.044884 -40.886146) (xy 417.099778 -40.869099) (xy 417.156608 -40.860482) (xy 417.185348 -40.859964)
			(xy 417.212595 -40.860509) (xy 417.266533 -40.868271) (xy 417.318819 -40.883629) (xy 417.368386 -40.906271)
			(xy 417.414227 -40.935737) (xy 417.455408 -40.971426) (xy 417.491092 -41.012611) (xy 417.520552 -41.058456)
			(xy 417.543188 -41.108026) (xy 417.558539 -41.160313) (xy 417.566294 -41.214253) (xy 417.566294 -41.268747)
			(xy 417.558539 -41.322687) (xy 417.543188 -41.374974) (xy 417.520552 -41.424544) (xy 417.491092 -41.470389)
			(xy 417.455408 -41.511574) (xy 417.414227 -41.547263) (xy 417.368386 -41.576729) (xy 417.318819 -41.599371)
			(xy 417.266533 -41.614729) (xy 417.212595 -41.622491) (xy 417.185348 -41.62298) (xy 417.156609 -41.622467)
			(xy 417.099782 -41.613838) (xy 417.044892 -41.596784) (xy 416.993181 -41.571691) (xy 416.945818 -41.539126)
			(xy 416.92449 -41.519856) (xy 416.917632 -41.513252) (xy 416.899598 -41.50614) (xy 416.810698 -41.50614)
			(xy 416.792664 -41.513252) (xy 416.785806 -41.519856) (xy 416.764499 -41.53915) (xy 416.717132 -41.571714)
			(xy 416.665415 -41.596802) (xy 416.61052 -41.613847) (xy 416.553688 -41.622463) (xy 416.524948 -41.62298)
			(xy 416.497691 -41.622576) (xy 416.443731 -41.614824) (xy 416.391423 -41.599471) (xy 416.341833 -41.57683)
			(xy 416.295971 -41.547361) (xy 416.254769 -41.511665) (xy 416.219068 -41.470468) (xy 416.189593 -41.424609)
			(xy 416.166945 -41.375022) (xy 416.151586 -41.322716) (xy 416.143827 -41.268757) (xy 401.514751 -41.268757)
			(xy 401.498339 -41.282415) (xy 401.450733 -41.311469) (xy 401.399404 -41.333281) (xy 401.345447 -41.347387)
			(xy 401.29001 -41.353487) (xy 401.234276 -41.35145) (xy 401.179433 -41.34132) (xy 401.126649 -41.323313)
			(xy 401.077049 -41.297812) (xy 401.031691 -41.265361) (xy 400.991542 -41.226652) (xy 400.957456 -41.182509)
			(xy 400.93016 -41.133874) (xy 400.910237 -41.081783) (xy 400.898111 -41.027346) (xy 400.89404 -40.971724)
			(xy 393.039172 -40.971724) (xy 393.069999 -40.976156) (xy 393.122294 -40.991511) (xy 393.171871 -41.014153)
			(xy 393.217721 -41.043619) (xy 393.258912 -41.07931) (xy 393.294603 -41.120501) (xy 393.324069 -41.166351)
			(xy 393.346711 -41.215928) (xy 393.362066 -41.268223) (xy 393.369822 -41.322171) (xy 393.370308 -41.349422)
			(xy 393.369796 -41.378161) (xy 393.36117 -41.434989) (xy 393.344117 -41.48988) (xy 393.319023 -41.541591)
			(xy 393.286456 -41.588953) (xy 393.267184 -41.61028) (xy 393.26058 -41.617138) (xy 393.253468 -41.635172)
			(xy 393.253468 -41.724072) (xy 393.26058 -41.742106) (xy 393.267184 -41.748964) (xy 393.286476 -41.770272)
			(xy 393.31904 -41.817638) (xy 393.34413 -41.869353) (xy 393.361178 -41.924246) (xy 393.369798 -41.981076)
			(xy 393.369796 -42.038556) (xy 393.361171 -42.095385) (xy 393.344118 -42.150277) (xy 393.319024 -42.20199)
			(xy 393.286456 -42.249353) (xy 393.267184 -42.27068) (xy 393.26058 -42.277538) (xy 393.253468 -42.295572)
			(xy 393.253468 -42.384472) (xy 393.26058 -42.402506) (xy 393.267184 -42.409364) (xy 393.286469 -42.430679)
			(xy 393.319032 -42.478045) (xy 393.344122 -42.529759) (xy 393.361169 -42.584653) (xy 393.369789 -42.641482)
			(xy 393.370308 -42.670222) (xy 393.369853 -42.697593) (xy 393.362032 -42.751772) (xy 393.34654 -42.804275)
			(xy 393.325985 -42.849038) (xy 395.191994 -42.849038) (xy 395.196065 -42.793416) (xy 395.208191 -42.738979)
			(xy 395.228114 -42.686888) (xy 395.25541 -42.638253) (xy 395.289496 -42.59411) (xy 395.329645 -42.555401)
			(xy 395.375003 -42.52295) (xy 395.424603 -42.497449) (xy 395.477387 -42.479442) (xy 395.53223 -42.469312)
			(xy 395.587964 -42.467275) (xy 395.643401 -42.473375) (xy 395.697358 -42.487481) (xy 395.748687 -42.509293)
			(xy 395.796293 -42.538347) (xy 395.839161 -42.574022) (xy 395.876378 -42.615559) (xy 395.907151 -42.662072)
			(xy 395.930823 -42.712569) (xy 395.946891 -42.765976) (xy 395.955011 -42.821152) (xy 395.955372 -42.84091)
			(xy 401.23313 -42.84091) (xy 401.237201 -42.785288) (xy 401.249327 -42.730851) (xy 401.26925 -42.67876)
			(xy 401.296546 -42.630125) (xy 401.330632 -42.585982) (xy 401.370781 -42.547273) (xy 401.416139 -42.514822)
			(xy 401.465739 -42.489321) (xy 401.518523 -42.471314) (xy 401.573366 -42.461184) (xy 401.6291 -42.459147)
			(xy 401.684537 -42.465247) (xy 401.738494 -42.479353) (xy 401.789823 -42.501165) (xy 401.837429 -42.530219)
			(xy 401.880297 -42.565894) (xy 401.917514 -42.607431) (xy 401.948287 -42.653944) (xy 401.971959 -42.704441)
			(xy 401.988027 -42.757848) (xy 401.996147 -42.813024) (xy 401.996656 -42.84091) (xy 401.996147 -42.868796)
			(xy 401.988027 -42.923972) (xy 401.971959 -42.977379) (xy 401.948287 -43.027876) (xy 401.917514 -43.074389)
			(xy 401.880297 -43.115926) (xy 401.837429 -43.151601) (xy 401.789823 -43.180655) (xy 401.738494 -43.202467)
			(xy 401.684537 -43.216573) (xy 401.6291 -43.222673) (xy 401.573366 -43.220636) (xy 401.518523 -43.210506)
			(xy 401.465739 -43.192499) (xy 401.416139 -43.166998) (xy 401.370781 -43.134547) (xy 401.330632 -43.095838)
			(xy 401.296546 -43.051695) (xy 401.26925 -43.00306) (xy 401.249327 -42.950969) (xy 401.237201 -42.896532)
			(xy 401.23313 -42.84091) (xy 395.955372 -42.84091) (xy 395.95552 -42.849038) (xy 395.955011 -42.876924)
			(xy 395.946891 -42.9321) (xy 395.930823 -42.985507) (xy 395.907151 -43.036004) (xy 395.876378 -43.082517)
			(xy 395.839161 -43.124054) (xy 395.796293 -43.159729) (xy 395.748687 -43.188783) (xy 395.697358 -43.210595)
			(xy 395.643401 -43.224701) (xy 395.587964 -43.230801) (xy 395.53223 -43.228764) (xy 395.477387 -43.218634)
			(xy 395.424603 -43.200627) (xy 395.375003 -43.175126) (xy 395.329645 -43.142675) (xy 395.289496 -43.103966)
			(xy 395.25541 -43.059823) (xy 395.228114 -43.011188) (xy 395.208191 -42.959097) (xy 395.196065 -42.90466)
			(xy 395.191994 -42.849038) (xy 393.325985 -42.849038) (xy 393.323696 -42.854022) (xy 393.29397 -42.899988)
			(xy 393.276328 -42.92092) (xy 393.276074 -42.921174) (xy 393.270489 -42.928262) (xy 393.264242 -42.945178)
			(xy 393.263882 -42.954194) (xy 393.263882 -43.02125) (xy 393.264267 -43.030264) (xy 393.270495 -43.047181)
			(xy 393.276074 -43.05427) (xy 393.276328 -43.05427) (xy 393.276328 -43.054524) (xy 393.293949 -43.07547)
			(xy 393.323663 -43.12144) (xy 393.346502 -43.171184) (xy 393.361997 -43.223681) (xy 393.369831 -43.277854)
			(xy 393.370308 -43.305222) (xy 393.369822 -43.332473) (xy 393.362066 -43.386421) (xy 393.346711 -43.438716)
			(xy 393.324069 -43.488293) (xy 393.294603 -43.534143) (xy 393.258912 -43.575334) (xy 393.217721 -43.611025)
			(xy 393.171871 -43.640491) (xy 393.122294 -43.663133) (xy 393.069999 -43.678488) (xy 393.016051 -43.686244)
			(xy 392.961549 -43.686244) (xy 392.907601 -43.678488) (xy 392.855306 -43.663133) (xy 392.805729 -43.640491)
			(xy 392.759879 -43.611025) (xy 392.718688 -43.575334) (xy 392.682997 -43.534143) (xy 392.653531 -43.488293)
			(xy 392.630889 -43.438716) (xy 392.615534 -43.386421) (xy 392.607778 -43.332473) (xy 392.607292 -43.305222)
			(xy 372.292664 -43.305222) (xy 372.317878 -43.333363) (xy 372.348651 -43.379876) (xy 372.372323 -43.430373)
			(xy 372.388391 -43.48378) (xy 372.396511 -43.538956) (xy 372.39702 -43.566842) (xy 372.396511 -43.594728)
			(xy 372.388391 -43.649904) (xy 372.372323 -43.703311) (xy 372.348651 -43.753808) (xy 372.317878 -43.800321)
			(xy 372.280661 -43.841858) (xy 372.237793 -43.877533) (xy 372.190187 -43.906587) (xy 372.138858 -43.928399)
			(xy 372.084901 -43.942505) (xy 372.029464 -43.948605) (xy 371.97373 -43.946568) (xy 371.918887 -43.936438)
			(xy 371.866103 -43.918431) (xy 371.816503 -43.89293) (xy 371.771145 -43.860479) (xy 371.730996 -43.82177)
			(xy 371.69691 -43.777627) (xy 371.669614 -43.728992) (xy 371.649691 -43.676901) (xy 371.637565 -43.622464)
			(xy 371.633494 -43.566842) (xy 369.236487 -43.566842) (xy 369.251933 -43.599791) (xy 369.268001 -43.653198)
			(xy 369.276121 -43.708374) (xy 369.27663 -43.73626) (xy 369.276121 -43.764146) (xy 369.268001 -43.819322)
			(xy 369.251933 -43.872729) (xy 369.228261 -43.923226) (xy 369.197488 -43.969739) (xy 369.160271 -44.011276)
			(xy 369.117403 -44.046951) (xy 369.069797 -44.076005) (xy 369.018468 -44.097817) (xy 368.964511 -44.111923)
			(xy 368.909074 -44.118023) (xy 368.85334 -44.115986) (xy 368.798497 -44.105856) (xy 368.745713 -44.087849)
			(xy 368.696113 -44.062348) (xy 368.650755 -44.029897) (xy 368.610606 -43.991188) (xy 368.57652 -43.947045)
			(xy 368.549224 -43.89841) (xy 368.529301 -43.846319) (xy 368.517175 -43.791882) (xy 368.513104 -43.73626)
			(xy 337.876628 -43.73626) (xy 337.888212 -43.775711) (xy 337.895968 -43.829659) (xy 337.896454 -43.85691)
			(xy 337.895936 -43.884747) (xy 337.887837 -43.93983) (xy 337.871827 -43.993153) (xy 337.848244 -44.043587)
			(xy 337.817589 -44.090062) (xy 337.799426 -44.111164) (xy 337.793164 -44.118752) (xy 337.786454 -44.13723)
			(xy 337.787177 -44.156876) (xy 337.79079 -44.166028) (xy 337.828636 -44.250356) (xy 337.833035 -44.259112)
			(xy 337.847146 -44.27268) (xy 337.865327 -44.279937) (xy 337.875118 -44.280328) (xy 365.243618 -44.280328)
			(xy 365.26724 -44.266358) (xy 365.272066 -44.257722) (xy 365.280194 -44.265596) (xy 365.287539 -44.272256)
			(xy 365.30585 -44.279819) (xy 365.315754 -44.280328) (xy 368.2746 -44.280328) (xy 368.314469 -44.28092)
			(xy 368.393665 -44.290223) (xy 368.47125 -44.308633) (xy 368.546182 -44.335904) (xy 368.617452 -44.371667)
			(xy 368.684101 -44.415443) (xy 368.715036 -44.440602) (xy 368.722067 -44.445987) (xy 368.7387 -44.452026)
			(xy 368.756396 -44.452026) (xy 368.773029 -44.445987) (xy 368.78006 -44.440602) (xy 368.810972 -44.415411)
			(xy 368.877611 -44.371608) (xy 368.948881 -44.335832) (xy 369.023821 -44.308565) (xy 369.101417 -44.290176)
			(xy 369.180623 -44.280912) (xy 369.220496 -44.280328) (xy 373.03964 -44.280328) (xy 373.041418 -44.280582)
			(xy 373.041672 -44.280582) (xy 373.05141 -44.280144) (xy 373.06946 -44.272816) (xy 373.083498 -44.25931)
			(xy 373.0879 -44.25061) (xy 373.126 -44.166028) (xy 373.129549 -44.15686) (xy 373.130267 -44.137237)
			(xy 373.123586 -44.118772) (xy 373.117364 -44.111164) (xy 373.099164 -44.090091) (xy 373.068499 -44.043615)
			(xy 373.044916 -43.993175) (xy 373.028915 -43.939842) (xy 373.020835 -43.884751) (xy 373.020336 -43.85691)
			(xy 373.020822 -43.829659) (xy 373.028578 -43.775711) (xy 373.043933 -43.723416) (xy 373.066575 -43.673839)
			(xy 373.096041 -43.627989) (xy 373.131732 -43.586798) (xy 373.172923 -43.551107) (xy 373.218773 -43.521641)
			(xy 373.26835 -43.498999) (xy 373.320645 -43.483644) (xy 373.374593 -43.475888) (xy 373.429095 -43.475888)
			(xy 373.483043 -43.483644) (xy 373.535338 -43.498999) (xy 373.584915 -43.521641) (xy 373.630765 -43.551107)
			(xy 373.671956 -43.586798) (xy 373.707647 -43.627989) (xy 373.737113 -43.673839) (xy 373.759755 -43.723416)
			(xy 373.77511 -43.775711) (xy 373.782866 -43.829659) (xy 373.783352 -43.85691) (xy 373.782883 -43.883096)
			(xy 373.775706 -43.934975) (xy 373.761502 -43.985386) (xy 373.740538 -44.03338) (xy 373.713208 -44.078057)
			(xy 373.680025 -44.118576) (xy 373.641613 -44.154178) (xy 373.598693 -44.184192) (xy 373.57558 -44.196508)
			(xy 373.566473 -44.20163) (xy 373.55307 -44.217632) (xy 373.547147 -44.237647) (xy 373.549683 -44.258365)
			(xy 373.560259 -44.276361) (xy 373.577125 -44.288658) (xy 373.597492 -44.293223) (xy 373.607838 -44.291758)
			(xy 373.638612 -44.286424) (xy 373.700813 -44.280704) (xy 373.732044 -44.280328) (xy 375.255028 -44.280328)
			(xy 375.264808 -44.279913) (xy 375.282955 -44.272617) (xy 375.297079 -44.259085) (xy 375.30151 -44.250356)
			(xy 375.339356 -44.166028) (xy 375.342915 -44.156862) (xy 375.343634 -44.137236) (xy 375.336947 -44.11877)
			(xy 375.33072 -44.111164) (xy 375.312529 -44.090084) (xy 375.281862 -44.04361) (xy 375.258276 -43.993172)
			(xy 375.242272 -43.939841) (xy 375.234191 -43.88475) (xy 375.233692 -43.85691) (xy 375.234178 -43.829659)
			(xy 375.241934 -43.775711) (xy 375.257289 -43.723416) (xy 375.279931 -43.673839) (xy 375.309397 -43.627989)
			(xy 375.345088 -43.586798) (xy 375.386279 -43.551107) (xy 375.432129 -43.521641) (xy 375.481706 -43.498999)
			(xy 375.534001 -43.483644) (xy 375.587949 -43.475888) (xy 375.642451 -43.475888) (xy 375.696399 -43.483644)
			(xy 375.748694 -43.498999) (xy 375.798271 -43.521641) (xy 375.844121 -43.551107) (xy 375.885312 -43.586798)
			(xy 375.921003 -43.627989) (xy 375.950469 -43.673839) (xy 375.973111 -43.723416) (xy 375.976882 -43.73626)
			(xy 394.513052 -43.73626) (xy 394.517123 -43.680638) (xy 394.529249 -43.626201) (xy 394.549172 -43.57411)
			(xy 394.576468 -43.525475) (xy 394.610554 -43.481332) (xy 394.650703 -43.442623) (xy 394.696061 -43.410172)
			(xy 394.745661 -43.384671) (xy 394.798445 -43.366664) (xy 394.853288 -43.356534) (xy 394.909022 -43.354497)
			(xy 394.964459 -43.360597) (xy 395.018416 -43.374703) (xy 395.069745 -43.396515) (xy 395.117351 -43.425569)
			(xy 395.160219 -43.461244) (xy 395.197436 -43.502781) (xy 395.228209 -43.549294) (xy 395.236435 -43.566842)
			(xy 397.633442 -43.566842) (xy 397.637513 -43.51122) (xy 397.649639 -43.456783) (xy 397.669562 -43.404692)
			(xy 397.696858 -43.356057) (xy 397.730944 -43.311914) (xy 397.771093 -43.273205) (xy 397.816451 -43.240754)
			(xy 397.866051 -43.215253) (xy 397.918835 -43.197246) (xy 397.973678 -43.187116) (xy 398.029412 -43.185079)
			(xy 398.084849 -43.191179) (xy 398.138806 -43.205285) (xy 398.190135 -43.227097) (xy 398.237741 -43.256151)
			(xy 398.280609 -43.291826) (xy 398.292612 -43.305222) (xy 418.60724 -43.305222) (xy 418.607709 -43.277852)
			(xy 418.615525 -43.223672) (xy 418.631013 -43.171169) (xy 418.653854 -43.121422) (xy 418.683579 -43.075455)
			(xy 418.70122 -43.054524) (xy 418.701474 -43.05427) (xy 418.707046 -43.047174) (xy 418.7133 -43.030264)
			(xy 418.713666 -43.02125) (xy 418.713666 -42.954194) (xy 418.713319 -42.945176) (xy 418.707066 -42.928259)
			(xy 418.701474 -42.921174) (xy 418.70122 -42.921174) (xy 418.70122 -42.92092) (xy 418.68358 -42.899989)
			(xy 418.653868 -42.854016) (xy 418.631031 -42.804268) (xy 418.615541 -42.751767) (xy 418.607713 -42.697591)
			(xy 418.60724 -42.670222) (xy 418.607793 -42.641484) (xy 418.616411 -42.584659) (xy 418.633455 -42.529769)
			(xy 418.65854 -42.478057) (xy 418.691097 -42.430693) (xy 418.710364 -42.409364) (xy 418.716968 -42.402506)
			(xy 418.72408 -42.384472) (xy 418.72408 -42.295572) (xy 418.716968 -42.277538) (xy 418.710364 -42.27068)
			(xy 418.691113 -42.249335) (xy 418.658544 -42.201977) (xy 418.633448 -42.150268) (xy 418.616395 -42.09538)
			(xy 418.607769 -42.038554) (xy 418.607767 -41.981078) (xy 418.616388 -41.924251) (xy 418.633437 -41.869361)
			(xy 418.658528 -41.817651) (xy 418.691093 -41.77029) (xy 418.710364 -41.748964) (xy 418.716968 -41.742106)
			(xy 418.72408 -41.724072) (xy 418.72408 -41.635172) (xy 418.716968 -41.617138) (xy 418.710364 -41.61028)
			(xy 418.691108 -41.58894) (xy 418.658539 -41.541582) (xy 418.633443 -41.489874) (xy 418.616389 -41.434986)
			(xy 418.607763 -41.37816) (xy 418.60724 -41.349422) (xy 418.607726 -41.322171) (xy 418.615482 -41.268223)
			(xy 418.630837 -41.215928) (xy 418.653479 -41.166351) (xy 418.682945 -41.120501) (xy 418.718636 -41.07931)
			(xy 418.759827 -41.043619) (xy 418.805677 -41.014153) (xy 418.855254 -40.991511) (xy 418.907549 -40.976156)
			(xy 418.961497 -40.9684) (xy 419.015999 -40.9684) (xy 419.03912 -40.971724) (xy 426.893988 -40.971724)
			(xy 426.898059 -40.916102) (xy 426.910185 -40.861665) (xy 426.930108 -40.809574) (xy 426.957404 -40.760939)
			(xy 426.99149 -40.716796) (xy 427.031639 -40.678087) (xy 427.076997 -40.645636) (xy 427.126597 -40.620135)
			(xy 427.179381 -40.602128) (xy 427.234224 -40.591998) (xy 427.289958 -40.589961) (xy 427.345395 -40.596061)
			(xy 427.399352 -40.610167) (xy 427.450681 -40.631979) (xy 427.498287 -40.661033) (xy 427.541155 -40.696708)
			(xy 427.578372 -40.738245) (xy 427.609145 -40.784758) (xy 427.632817 -40.835255) (xy 427.648885 -40.888662)
			(xy 427.657005 -40.943838) (xy 427.657514 -40.971724) (xy 427.657005 -40.99961) (xy 427.648885 -41.054786)
			(xy 427.632817 -41.108193) (xy 427.609145 -41.15869) (xy 427.578372 -41.205203) (xy 427.541155 -41.24674)
			(xy 427.514704 -41.268753) (xy 442.14385 -41.268753) (xy 442.14385 -41.214247) (xy 442.151607 -41.160296)
			(xy 442.166963 -41.107997) (xy 442.189605 -41.058417) (xy 442.219073 -41.012563) (xy 442.254767 -40.97137)
			(xy 442.29596 -40.935676) (xy 442.341813 -40.906207) (xy 442.391394 -40.883564) (xy 442.443692 -40.868208)
			(xy 442.497643 -40.86045) (xy 442.524896 -40.859964) (xy 442.553634 -40.8605) (xy 442.610461 -40.869121)
			(xy 442.665351 -40.886169) (xy 442.717063 -40.911257) (xy 442.764426 -40.943819) (xy 442.785754 -40.963088)
			(xy 442.792612 -40.969692) (xy 442.810646 -40.976804) (xy 442.899546 -40.976804) (xy 442.91758 -40.969692)
			(xy 442.924438 -40.963088) (xy 442.945774 -40.943827) (xy 442.993133 -40.911258) (xy 443.044842 -40.886163)
			(xy 443.099731 -40.86911) (xy 443.156557 -40.860485) (xy 443.185296 -40.859964) (xy 443.212547 -40.860483)
			(xy 443.266494 -40.868239) (xy 443.318789 -40.883593) (xy 443.368366 -40.906234) (xy 443.414216 -40.9357)
			(xy 443.455406 -40.971391) (xy 443.491098 -41.012581) (xy 443.520564 -41.058431) (xy 443.543205 -41.108007)
			(xy 443.55856 -41.160302) (xy 443.566317 -41.214249) (xy 443.566317 -41.268751) (xy 443.55856 -41.322698)
			(xy 443.543205 -41.374993) (xy 443.520564 -41.424569) (xy 443.491098 -41.470419) (xy 443.455406 -41.511609)
			(xy 443.414216 -41.5473) (xy 443.368366 -41.576766) (xy 443.318789 -41.599407) (xy 443.266494 -41.614761)
			(xy 443.212547 -41.622517) (xy 443.185296 -41.62298) (xy 443.156558 -41.622437) (xy 443.099732 -41.613816)
			(xy 443.044843 -41.596769) (xy 442.993131 -41.571683) (xy 442.945767 -41.539123) (xy 442.924438 -41.519856)
			(xy 442.91758 -41.513252) (xy 442.899546 -41.50614) (xy 442.810646 -41.50614) (xy 442.792612 -41.513252)
			(xy 442.785754 -41.519856) (xy 442.764428 -41.539128) (xy 442.717066 -41.571694) (xy 442.665354 -41.596786)
			(xy 442.610463 -41.613837) (xy 442.553635 -41.622459) (xy 442.524896 -41.62298) (xy 442.497643 -41.62255)
			(xy 442.443692 -41.614792) (xy 442.391394 -41.599436) (xy 442.341813 -41.576793) (xy 442.29596 -41.547324)
			(xy 442.254767 -41.51163) (xy 442.219073 -41.470437) (xy 442.189605 -41.424583) (xy 442.166963 -41.375003)
			(xy 442.151607 -41.322704) (xy 442.14385 -41.268753) (xy 427.514704 -41.268753) (xy 427.498287 -41.282415)
			(xy 427.450681 -41.311469) (xy 427.399352 -41.333281) (xy 427.345395 -41.347387) (xy 427.289958 -41.353487)
			(xy 427.234224 -41.35145) (xy 427.179381 -41.34132) (xy 427.126597 -41.323313) (xy 427.076997 -41.297812)
			(xy 427.031639 -41.265361) (xy 426.99149 -41.226652) (xy 426.957404 -41.182509) (xy 426.930108 -41.133874)
			(xy 426.910185 -41.081783) (xy 426.898059 -41.027346) (xy 426.893988 -40.971724) (xy 419.03912 -40.971724)
			(xy 419.069947 -40.976156) (xy 419.122242 -40.991511) (xy 419.171819 -41.014153) (xy 419.217669 -41.043619)
			(xy 419.25886 -41.07931) (xy 419.294551 -41.120501) (xy 419.324017 -41.166351) (xy 419.346659 -41.215928)
			(xy 419.362014 -41.268223) (xy 419.36977 -41.322171) (xy 419.370256 -41.349422) (xy 419.369731 -41.378161)
			(xy 419.361106 -41.434987) (xy 419.344056 -41.489877) (xy 419.318965 -41.541589) (xy 419.286402 -41.588952)
			(xy 419.267132 -41.61028) (xy 419.260528 -41.617138) (xy 419.253416 -41.635172) (xy 419.253416 -41.724072)
			(xy 419.260528 -41.742106) (xy 419.267132 -41.748964) (xy 419.286422 -41.770273) (xy 419.318982 -41.81764)
			(xy 419.344069 -41.869355) (xy 419.361114 -41.924248) (xy 419.369733 -41.981077) (xy 419.369731 -42.038555)
			(xy 419.361107 -42.095383) (xy 419.344057 -42.150275) (xy 419.318966 -42.201988) (xy 419.286402 -42.249352)
			(xy 419.267132 -42.27068) (xy 419.260528 -42.277538) (xy 419.253416 -42.295572) (xy 419.253416 -42.384472)
			(xy 419.260528 -42.402506) (xy 419.267132 -42.409364) (xy 419.286408 -42.430686) (xy 419.318975 -42.478049)
			(xy 419.344067 -42.529762) (xy 419.361116 -42.584654) (xy 419.369737 -42.641483) (xy 419.370256 -42.670222)
			(xy 419.369814 -42.697593) (xy 419.361992 -42.751774) (xy 419.346498 -42.804278) (xy 419.32594 -42.849038)
			(xy 421.191942 -42.849038) (xy 421.196013 -42.793416) (xy 421.208139 -42.738979) (xy 421.228062 -42.686888)
			(xy 421.255358 -42.638253) (xy 421.289444 -42.59411) (xy 421.329593 -42.555401) (xy 421.374951 -42.52295)
			(xy 421.424551 -42.497449) (xy 421.477335 -42.479442) (xy 421.532178 -42.469312) (xy 421.587912 -42.467275)
			(xy 421.643349 -42.473375) (xy 421.697306 -42.487481) (xy 421.748635 -42.509293) (xy 421.796241 -42.538347)
			(xy 421.839109 -42.574022) (xy 421.876326 -42.615559) (xy 421.907099 -42.662072) (xy 421.930771 -42.712569)
			(xy 421.946839 -42.765976) (xy 421.954959 -42.821152) (xy 421.95532 -42.84091) (xy 427.233078 -42.84091)
			(xy 427.237149 -42.785288) (xy 427.249275 -42.730851) (xy 427.269198 -42.67876) (xy 427.296494 -42.630125)
			(xy 427.33058 -42.585982) (xy 427.370729 -42.547273) (xy 427.416087 -42.514822) (xy 427.465687 -42.489321)
			(xy 427.518471 -42.471314) (xy 427.573314 -42.461184) (xy 427.629048 -42.459147) (xy 427.684485 -42.465247)
			(xy 427.738442 -42.479353) (xy 427.789771 -42.501165) (xy 427.837377 -42.530219) (xy 427.880245 -42.565894)
			(xy 427.917462 -42.607431) (xy 427.948235 -42.653944) (xy 427.971907 -42.704441) (xy 427.987975 -42.757848)
			(xy 427.996095 -42.813024) (xy 427.996604 -42.84091) (xy 427.996095 -42.868796) (xy 427.987975 -42.923972)
			(xy 427.971907 -42.977379) (xy 427.948235 -43.027876) (xy 427.917462 -43.074389) (xy 427.880245 -43.115926)
			(xy 427.837377 -43.151601) (xy 427.789771 -43.180655) (xy 427.738442 -43.202467) (xy 427.684485 -43.216573)
			(xy 427.629048 -43.222673) (xy 427.573314 -43.220636) (xy 427.518471 -43.210506) (xy 427.465687 -43.192499)
			(xy 427.416087 -43.166998) (xy 427.370729 -43.134547) (xy 427.33058 -43.095838) (xy 427.296494 -43.051695)
			(xy 427.269198 -43.00306) (xy 427.249275 -42.950969) (xy 427.237149 -42.896532) (xy 427.233078 -42.84091)
			(xy 421.95532 -42.84091) (xy 421.955468 -42.849038) (xy 421.954959 -42.876924) (xy 421.946839 -42.9321)
			(xy 421.930771 -42.985507) (xy 421.907099 -43.036004) (xy 421.876326 -43.082517) (xy 421.839109 -43.124054)
			(xy 421.796241 -43.159729) (xy 421.748635 -43.188783) (xy 421.697306 -43.210595) (xy 421.643349 -43.224701)
			(xy 421.587912 -43.230801) (xy 421.532178 -43.228764) (xy 421.477335 -43.218634) (xy 421.424551 -43.200627)
			(xy 421.374951 -43.175126) (xy 421.329593 -43.142675) (xy 421.289444 -43.103966) (xy 421.255358 -43.059823)
			(xy 421.228062 -43.011188) (xy 421.208139 -42.959097) (xy 421.196013 -42.90466) (xy 421.191942 -42.849038)
			(xy 419.32594 -42.849038) (xy 419.32365 -42.854024) (xy 419.29392 -42.899989) (xy 419.276276 -42.92092)
			(xy 419.276022 -42.921174) (xy 419.270431 -42.928257) (xy 419.264189 -42.945177) (xy 419.26383 -42.954194)
			(xy 419.26383 -43.02125) (xy 419.264204 -43.030265) (xy 419.270439 -43.047183) (xy 419.276022 -43.05427)
			(xy 419.276276 -43.05427) (xy 419.276276 -43.054524) (xy 419.293889 -43.075477) (xy 419.323606 -43.121444)
			(xy 419.346447 -43.171186) (xy 419.361944 -43.223682) (xy 419.369779 -43.277854) (xy 419.370256 -43.305222)
			(xy 419.36977 -43.332473) (xy 419.362014 -43.386421) (xy 419.346659 -43.438716) (xy 419.324017 -43.488293)
			(xy 419.294551 -43.534143) (xy 419.25886 -43.575334) (xy 419.217669 -43.611025) (xy 419.171819 -43.640491)
			(xy 419.122242 -43.663133) (xy 419.069947 -43.678488) (xy 419.015999 -43.686244) (xy 418.961497 -43.686244)
			(xy 418.907549 -43.678488) (xy 418.855254 -43.663133) (xy 418.805677 -43.640491) (xy 418.759827 -43.611025)
			(xy 418.718636 -43.575334) (xy 418.682945 -43.534143) (xy 418.653479 -43.488293) (xy 418.630837 -43.438716)
			(xy 418.615482 -43.386421) (xy 418.607726 -43.332473) (xy 418.60724 -43.305222) (xy 398.292612 -43.305222)
			(xy 398.317826 -43.333363) (xy 398.348599 -43.379876) (xy 398.372271 -43.430373) (xy 398.388339 -43.48378)
			(xy 398.396459 -43.538956) (xy 398.396968 -43.566842) (xy 398.396459 -43.594728) (xy 398.388339 -43.649904)
			(xy 398.372271 -43.703311) (xy 398.348599 -43.753808) (xy 398.317826 -43.800321) (xy 398.280609 -43.841858)
			(xy 398.237741 -43.877533) (xy 398.190135 -43.906587) (xy 398.138806 -43.928399) (xy 398.084849 -43.942505)
			(xy 398.029412 -43.948605) (xy 397.973678 -43.946568) (xy 397.918835 -43.936438) (xy 397.866051 -43.918431)
			(xy 397.816451 -43.89293) (xy 397.771093 -43.860479) (xy 397.730944 -43.82177) (xy 397.696858 -43.777627)
			(xy 397.669562 -43.728992) (xy 397.649639 -43.676901) (xy 397.637513 -43.622464) (xy 397.633442 -43.566842)
			(xy 395.236435 -43.566842) (xy 395.251881 -43.599791) (xy 395.267949 -43.653198) (xy 395.276069 -43.708374)
			(xy 395.276578 -43.73626) (xy 395.276069 -43.764146) (xy 395.267949 -43.819322) (xy 395.251881 -43.872729)
			(xy 395.228209 -43.923226) (xy 395.197436 -43.969739) (xy 395.160219 -44.011276) (xy 395.117351 -44.046951)
			(xy 395.069745 -44.076005) (xy 395.018416 -44.097817) (xy 394.964459 -44.111923) (xy 394.909022 -44.118023)
			(xy 394.853288 -44.115986) (xy 394.798445 -44.105856) (xy 394.745661 -44.087849) (xy 394.696061 -44.062348)
			(xy 394.650703 -44.029897) (xy 394.610554 -43.991188) (xy 394.576468 -43.947045) (xy 394.549172 -43.89841)
			(xy 394.529249 -43.846319) (xy 394.517123 -43.791882) (xy 394.513052 -43.73626) (xy 375.976882 -43.73626)
			(xy 375.988466 -43.775711) (xy 375.996222 -43.829659) (xy 375.996708 -43.85691) (xy 375.996176 -43.884747)
			(xy 375.988079 -43.939828) (xy 375.972071 -43.993151) (xy 375.948492 -44.043585) (xy 375.917841 -44.090061)
			(xy 375.89968 -44.111164) (xy 375.89342 -44.118755) (xy 375.886704 -44.137231) (xy 375.887428 -44.156877)
			(xy 375.891044 -44.166028) (xy 375.92889 -44.250356) (xy 375.933251 -44.259134) (xy 375.947378 -44.272701)
			(xy 375.965576 -44.279946) (xy 375.975372 -44.280328) (xy 391.243566 -44.280328) (xy 391.267188 -44.266358)
			(xy 391.272014 -44.257722) (xy 391.280142 -44.265596) (xy 391.287505 -44.272233) (xy 391.305803 -44.27981)
			(xy 391.315702 -44.280328) (xy 394.274548 -44.280328) (xy 394.314417 -44.28095) (xy 394.393611 -44.290247)
			(xy 394.471196 -44.308652) (xy 394.546127 -44.335916) (xy 394.617398 -44.371675) (xy 394.684048 -44.415446)
			(xy 394.714984 -44.440602) (xy 394.722015 -44.445987) (xy 394.738648 -44.452026) (xy 394.756344 -44.452026)
			(xy 394.772977 -44.445987) (xy 394.780008 -44.440602) (xy 394.810939 -44.415435) (xy 394.877574 -44.37163)
			(xy 394.94884 -44.335849) (xy 395.023776 -44.308578) (xy 395.101369 -44.290184) (xy 395.180572 -44.280915)
			(xy 395.220444 -44.280328) (xy 399.039842 -44.280328) (xy 399.041366 -44.280582) (xy 399.04162 -44.280582)
			(xy 399.051354 -44.280107) (xy 399.069403 -44.272796) (xy 399.083444 -44.259304) (xy 399.087848 -44.25061)
			(xy 399.125948 -44.166028) (xy 399.129508 -44.156863) (xy 399.130228 -44.137236) (xy 399.12354 -44.11877)
			(xy 399.117312 -44.111164) (xy 399.09912 -44.090085) (xy 399.068453 -44.04361) (xy 399.044867 -43.993172)
			(xy 399.028864 -43.939841) (xy 399.020783 -43.88475) (xy 399.020284 -43.85691) (xy 399.02077 -43.829659)
			(xy 399.028526 -43.775711) (xy 399.043881 -43.723416) (xy 399.066523 -43.673839) (xy 399.095989 -43.627989)
			(xy 399.13168 -43.586798) (xy 399.172871 -43.551107) (xy 399.218721 -43.521641) (xy 399.268298 -43.498999)
			(xy 399.320593 -43.483644) (xy 399.374541 -43.475888) (xy 399.429043 -43.475888) (xy 399.482991 -43.483644)
			(xy 399.535286 -43.498999) (xy 399.584863 -43.521641) (xy 399.630713 -43.551107) (xy 399.671904 -43.586798)
			(xy 399.707595 -43.627989) (xy 399.737061 -43.673839) (xy 399.759703 -43.723416) (xy 399.775058 -43.775711)
			(xy 399.782814 -43.829659) (xy 399.7833 -43.85691) (xy 399.782859 -43.883098) (xy 399.775681 -43.934979)
			(xy 399.761475 -43.985391) (xy 399.740508 -44.033387) (xy 399.713173 -44.078064) (xy 399.679986 -44.118583)
			(xy 399.641569 -44.154183) (xy 399.598644 -44.184194) (xy 399.575528 -44.196508) (xy 399.566447 -44.201662)
			(xy 399.553067 -44.217659) (xy 399.547156 -44.237659) (xy 399.549692 -44.25836) (xy 399.560255 -44.276342)
			(xy 399.577101 -44.288636) (xy 399.597448 -44.293212) (xy 399.607786 -44.291758) (xy 399.638562 -44.286431)
			(xy 399.700761 -44.280706) (xy 399.731992 -44.280328) (xy 401.254976 -44.280328) (xy 401.264752 -44.279875)
			(xy 401.282898 -44.272597) (xy 401.297025 -44.25908) (xy 401.301458 -44.250356) (xy 401.339304 -44.166028)
			(xy 401.342852 -44.15686) (xy 401.34357 -44.137237) (xy 401.33689 -44.118772) (xy 401.330668 -44.111164)
			(xy 401.312468 -44.090091) (xy 401.281804 -44.043614) (xy 401.25822 -43.993174) (xy 401.242219 -43.939842)
			(xy 401.234139 -43.884751) (xy 401.23364 -43.85691) (xy 401.234126 -43.829659) (xy 401.241882 -43.775711)
			(xy 401.257237 -43.723416) (xy 401.279879 -43.673839) (xy 401.309345 -43.627989) (xy 401.345036 -43.586798)
			(xy 401.386227 -43.551107) (xy 401.432077 -43.521641) (xy 401.481654 -43.498999) (xy 401.533949 -43.483644)
			(xy 401.587897 -43.475888) (xy 401.642399 -43.475888) (xy 401.696347 -43.483644) (xy 401.748642 -43.498999)
			(xy 401.798219 -43.521641) (xy 401.844069 -43.551107) (xy 401.88526 -43.586798) (xy 401.920951 -43.627989)
			(xy 401.950417 -43.673839) (xy 401.973059 -43.723416) (xy 401.97683 -43.73626) (xy 420.513 -43.73626)
			(xy 420.517071 -43.680638) (xy 420.529197 -43.626201) (xy 420.54912 -43.57411) (xy 420.576416 -43.525475)
			(xy 420.610502 -43.481332) (xy 420.650651 -43.442623) (xy 420.696009 -43.410172) (xy 420.745609 -43.384671)
			(xy 420.798393 -43.366664) (xy 420.853236 -43.356534) (xy 420.90897 -43.354497) (xy 420.964407 -43.360597)
			(xy 421.018364 -43.374703) (xy 421.069693 -43.396515) (xy 421.117299 -43.425569) (xy 421.160167 -43.461244)
			(xy 421.197384 -43.502781) (xy 421.228157 -43.549294) (xy 421.236383 -43.566842) (xy 423.63339 -43.566842)
			(xy 423.637461 -43.51122) (xy 423.649587 -43.456783) (xy 423.66951 -43.404692) (xy 423.696806 -43.356057)
			(xy 423.730892 -43.311914) (xy 423.771041 -43.273205) (xy 423.816399 -43.240754) (xy 423.865999 -43.215253)
			(xy 423.918783 -43.197246) (xy 423.973626 -43.187116) (xy 424.02936 -43.185079) (xy 424.084797 -43.191179)
			(xy 424.138754 -43.205285) (xy 424.190083 -43.227097) (xy 424.237689 -43.256151) (xy 424.280557 -43.291826)
			(xy 424.29256 -43.305222) (xy 444.607188 -43.305222) (xy 444.60767 -43.277852) (xy 444.615484 -43.223674)
			(xy 444.63097 -43.171171) (xy 444.653808 -43.121424) (xy 444.683529 -43.075456) (xy 444.701168 -43.054524)
			(xy 444.701422 -43.05427) (xy 444.706988 -43.047169) (xy 444.713246 -43.030263) (xy 444.713614 -43.02125)
			(xy 444.713614 -42.954194) (xy 444.713257 -42.945177) (xy 444.707009 -42.92826) (xy 444.701422 -42.921174)
			(xy 444.701168 -42.921174) (xy 444.701168 -42.92092) (xy 444.68352 -42.899995) (xy 444.65381 -42.85402)
			(xy 444.630977 -42.804271) (xy 444.615488 -42.751768) (xy 444.607661 -42.697592) (xy 444.607188 -42.670222)
			(xy 444.607728 -42.641484) (xy 444.616347 -42.584657) (xy 444.633394 -42.529767) (xy 444.658482 -42.478055)
			(xy 444.691043 -42.430691) (xy 444.710312 -42.409364) (xy 444.716916 -42.402506) (xy 444.724028 -42.384472)
			(xy 444.724028 -42.295572) (xy 444.716916 -42.277538) (xy 444.710312 -42.27068) (xy 444.691064 -42.249334)
			(xy 444.658499 -42.201975) (xy 444.633407 -42.150266) (xy 444.616356 -42.095378) (xy 444.607731 -42.038554)
			(xy 444.607729 -41.981078) (xy 444.616348 -41.924253) (xy 444.633395 -41.869364) (xy 444.658482 -41.817653)
			(xy 444.691043 -41.770291) (xy 444.710312 -41.748964) (xy 444.716916 -41.742106) (xy 444.724028 -41.724072)
			(xy 444.724028 -41.635172) (xy 444.716916 -41.617138) (xy 444.710312 -41.61028) (xy 444.691047 -41.588948)
			(xy 444.658481 -41.541587) (xy 444.633388 -41.489876) (xy 444.616336 -41.434987) (xy 444.607711 -41.378161)
			(xy 444.607188 -41.349422) (xy 444.607674 -41.322171) (xy 444.61543 -41.268223) (xy 444.630785 -41.215928)
			(xy 444.653427 -41.166351) (xy 444.682893 -41.120501) (xy 444.718584 -41.07931) (xy 444.759775 -41.043619)
			(xy 444.805625 -41.014153) (xy 444.855202 -40.991511) (xy 444.907497 -40.976156) (xy 444.961445 -40.9684)
			(xy 445.015947 -40.9684) (xy 445.069895 -40.976156) (xy 445.12219 -40.991511) (xy 445.171767 -41.014153)
			(xy 445.217617 -41.043619) (xy 445.258808 -41.07931) (xy 445.294499 -41.120501) (xy 445.323965 -41.166351)
			(xy 445.346607 -41.215928) (xy 445.361962 -41.268223) (xy 445.369718 -41.322171) (xy 445.370204 -41.349422)
			(xy 445.369693 -41.378161) (xy 445.361067 -41.434989) (xy 445.344014 -41.48988) (xy 445.31892 -41.541592)
			(xy 445.286352 -41.588954) (xy 445.26708 -41.61028) (xy 445.260476 -41.617138) (xy 445.253364 -41.635172)
			(xy 445.253364 -41.724072) (xy 445.260476 -41.742106) (xy 445.26708 -41.748964) (xy 445.286372 -41.770272)
			(xy 445.318937 -41.817638) (xy 445.344027 -41.869353) (xy 445.361075 -41.924246) (xy 445.369695 -41.981076)
			(xy 445.369693 -42.038556) (xy 445.361068 -42.095385) (xy 445.344015 -42.150277) (xy 445.31892 -42.20199)
			(xy 445.286352 -42.249353) (xy 445.26708 -42.27068) (xy 445.260476 -42.277538) (xy 445.253364 -42.295572)
			(xy 445.253364 -42.384472) (xy 445.260476 -42.402506) (xy 445.26708 -42.409364) (xy 445.286364 -42.430679)
			(xy 445.318928 -42.478045) (xy 445.344017 -42.52976) (xy 445.361065 -42.584653) (xy 445.369685 -42.641482)
			(xy 445.370204 -42.670222) (xy 445.36975 -42.697593) (xy 445.361929 -42.751772) (xy 445.346437 -42.804275)
			(xy 445.325882 -42.849038) (xy 447.19189 -42.849038) (xy 447.195961 -42.793416) (xy 447.208087 -42.738979)
			(xy 447.22801 -42.686888) (xy 447.255306 -42.638253) (xy 447.289392 -42.59411) (xy 447.329541 -42.555401)
			(xy 447.374899 -42.52295) (xy 447.424499 -42.497449) (xy 447.477283 -42.479442) (xy 447.532126 -42.469312)
			(xy 447.58786 -42.467275) (xy 447.643297 -42.473375) (xy 447.697254 -42.487481) (xy 447.748583 -42.509293)
			(xy 447.796189 -42.538347) (xy 447.839057 -42.574022) (xy 447.876274 -42.615559) (xy 447.907047 -42.662072)
			(xy 447.930719 -42.712569) (xy 447.946787 -42.765976) (xy 447.954907 -42.821152) (xy 447.955268 -42.84091)
			(xy 453.233026 -42.84091) (xy 453.237097 -42.785288) (xy 453.249223 -42.730851) (xy 453.269146 -42.67876)
			(xy 453.296442 -42.630125) (xy 453.330528 -42.585982) (xy 453.370677 -42.547273) (xy 453.416035 -42.514822)
			(xy 453.465635 -42.489321) (xy 453.518419 -42.471314) (xy 453.573262 -42.461184) (xy 453.628996 -42.459147)
			(xy 453.684433 -42.465247) (xy 453.73839 -42.479353) (xy 453.789719 -42.501165) (xy 453.837325 -42.530219)
			(xy 453.880193 -42.565894) (xy 453.91741 -42.607431) (xy 453.948183 -42.653944) (xy 453.971855 -42.704441)
			(xy 453.987923 -42.757848) (xy 453.996043 -42.813024) (xy 453.996552 -42.84091) (xy 453.996043 -42.868796)
			(xy 453.987923 -42.923972) (xy 453.971855 -42.977379) (xy 453.948183 -43.027876) (xy 453.91741 -43.074389)
			(xy 453.880193 -43.115926) (xy 453.837325 -43.151601) (xy 453.789719 -43.180655) (xy 453.73839 -43.202467)
			(xy 453.684433 -43.216573) (xy 453.628996 -43.222673) (xy 453.573262 -43.220636) (xy 453.518419 -43.210506)
			(xy 453.465635 -43.192499) (xy 453.416035 -43.166998) (xy 453.370677 -43.134547) (xy 453.330528 -43.095838)
			(xy 453.296442 -43.051695) (xy 453.269146 -43.00306) (xy 453.249223 -42.950969) (xy 453.237097 -42.896532)
			(xy 453.233026 -42.84091) (xy 447.955268 -42.84091) (xy 447.955416 -42.849038) (xy 447.954907 -42.876924)
			(xy 447.946787 -42.9321) (xy 447.930719 -42.985507) (xy 447.907047 -43.036004) (xy 447.876274 -43.082517)
			(xy 447.839057 -43.124054) (xy 447.796189 -43.159729) (xy 447.748583 -43.188783) (xy 447.697254 -43.210595)
			(xy 447.643297 -43.224701) (xy 447.58786 -43.230801) (xy 447.532126 -43.228764) (xy 447.477283 -43.218634)
			(xy 447.424499 -43.200627) (xy 447.374899 -43.175126) (xy 447.329541 -43.142675) (xy 447.289392 -43.103966)
			(xy 447.255306 -43.059823) (xy 447.22801 -43.011188) (xy 447.208087 -42.959097) (xy 447.195961 -42.90466)
			(xy 447.19189 -42.849038) (xy 445.325882 -42.849038) (xy 445.323593 -42.854022) (xy 445.293866 -42.899989)
			(xy 445.276224 -42.92092) (xy 445.27597 -42.921174) (xy 445.270385 -42.928261) (xy 445.264138 -42.945178)
			(xy 445.263778 -42.954194) (xy 445.263778 -43.02125) (xy 445.264164 -43.030264) (xy 445.270392 -43.047181)
			(xy 445.27597 -43.05427) (xy 445.276224 -43.05427) (xy 445.276224 -43.054524) (xy 445.293845 -43.075471)
			(xy 445.323558 -43.12144) (xy 445.346398 -43.171184) (xy 445.361893 -43.223681) (xy 445.369727 -43.277854)
			(xy 445.370204 -43.305222) (xy 445.369718 -43.332473) (xy 445.361962 -43.386421) (xy 445.346607 -43.438716)
			(xy 445.323965 -43.488293) (xy 445.294499 -43.534143) (xy 445.258808 -43.575334) (xy 445.217617 -43.611025)
			(xy 445.171767 -43.640491) (xy 445.12219 -43.663133) (xy 445.069895 -43.678488) (xy 445.015947 -43.686244)
			(xy 444.961445 -43.686244) (xy 444.907497 -43.678488) (xy 444.855202 -43.663133) (xy 444.805625 -43.640491)
			(xy 444.759775 -43.611025) (xy 444.718584 -43.575334) (xy 444.682893 -43.534143) (xy 444.653427 -43.488293)
			(xy 444.630785 -43.438716) (xy 444.61543 -43.386421) (xy 444.607674 -43.332473) (xy 444.607188 -43.305222)
			(xy 424.29256 -43.305222) (xy 424.317774 -43.333363) (xy 424.348547 -43.379876) (xy 424.372219 -43.430373)
			(xy 424.388287 -43.48378) (xy 424.396407 -43.538956) (xy 424.396916 -43.566842) (xy 424.396407 -43.594728)
			(xy 424.388287 -43.649904) (xy 424.372219 -43.703311) (xy 424.348547 -43.753808) (xy 424.317774 -43.800321)
			(xy 424.280557 -43.841858) (xy 424.237689 -43.877533) (xy 424.190083 -43.906587) (xy 424.138754 -43.928399)
			(xy 424.084797 -43.942505) (xy 424.02936 -43.948605) (xy 423.973626 -43.946568) (xy 423.918783 -43.936438)
			(xy 423.865999 -43.918431) (xy 423.816399 -43.89293) (xy 423.771041 -43.860479) (xy 423.730892 -43.82177)
			(xy 423.696806 -43.777627) (xy 423.66951 -43.728992) (xy 423.649587 -43.676901) (xy 423.637461 -43.622464)
			(xy 423.63339 -43.566842) (xy 421.236383 -43.566842) (xy 421.251829 -43.599791) (xy 421.267897 -43.653198)
			(xy 421.276017 -43.708374) (xy 421.276526 -43.73626) (xy 421.276017 -43.764146) (xy 421.267897 -43.819322)
			(xy 421.251829 -43.872729) (xy 421.228157 -43.923226) (xy 421.197384 -43.969739) (xy 421.160167 -44.011276)
			(xy 421.117299 -44.046951) (xy 421.069693 -44.076005) (xy 421.018364 -44.097817) (xy 420.964407 -44.111923)
			(xy 420.90897 -44.118023) (xy 420.853236 -44.115986) (xy 420.798393 -44.105856) (xy 420.745609 -44.087849)
			(xy 420.696009 -44.062348) (xy 420.650651 -44.029897) (xy 420.610502 -43.991188) (xy 420.576416 -43.947045)
			(xy 420.54912 -43.89841) (xy 420.529197 -43.846319) (xy 420.517071 -43.791882) (xy 420.513 -43.73626)
			(xy 401.97683 -43.73626) (xy 401.988414 -43.775711) (xy 401.99617 -43.829659) (xy 401.996656 -43.85691)
			(xy 401.996138 -43.884747) (xy 401.988039 -43.93983) (xy 401.972028 -43.993153) (xy 401.948446 -44.043587)
			(xy 401.917791 -44.090062) (xy 401.899628 -44.111164) (xy 401.893366 -44.118752) (xy 401.886656 -44.137231)
			(xy 401.887379 -44.156876) (xy 401.890992 -44.166028) (xy 401.928838 -44.250356) (xy 401.933236 -44.259112)
			(xy 401.947347 -44.272681) (xy 401.965529 -44.279937) (xy 401.97532 -44.280328) (xy 417.243514 -44.280328)
			(xy 417.267136 -44.266358) (xy 417.271962 -44.257722) (xy 417.28009 -44.265596) (xy 417.287437 -44.272254)
			(xy 417.305747 -44.279818) (xy 417.31565 -44.280328) (xy 420.274496 -44.280328) (xy 420.314365 -44.280922)
			(xy 420.393561 -44.290224) (xy 420.471146 -44.308634) (xy 420.546078 -44.335905) (xy 420.617348 -44.371668)
			(xy 420.683997 -44.415444) (xy 420.714932 -44.440602) (xy 420.721963 -44.445987) (xy 420.738596 -44.452026)
			(xy 420.756292 -44.452026) (xy 420.772925 -44.445987) (xy 420.779956 -44.440602) (xy 420.81087 -44.415413)
			(xy 420.877508 -44.37161) (xy 420.948778 -44.335833) (xy 421.023717 -44.308566) (xy 421.101313 -44.290176)
			(xy 421.180519 -44.280913) (xy 421.220392 -44.280328) (xy 425.03979 -44.280328) (xy 425.041314 -44.280582)
			(xy 425.041568 -44.280582) (xy 425.051306 -44.280142) (xy 425.069355 -44.272814) (xy 425.083394 -44.259309)
			(xy 425.087796 -44.25061) (xy 425.125896 -44.166028) (xy 425.129446 -44.15686) (xy 425.130164 -44.137237)
			(xy 425.123483 -44.118772) (xy 425.11726 -44.111164) (xy 425.099059 -44.090092) (xy 425.068395 -44.043615)
			(xy 425.044812 -43.993175) (xy 425.028811 -43.939842) (xy 425.020731 -43.884751) (xy 425.020232 -43.85691)
			(xy 425.020718 -43.829659) (xy 425.028474 -43.775711) (xy 425.043829 -43.723416) (xy 425.066471 -43.673839)
			(xy 425.095937 -43.627989) (xy 425.131628 -43.586798) (xy 425.172819 -43.551107) (xy 425.218669 -43.521641)
			(xy 425.268246 -43.498999) (xy 425.320541 -43.483644) (xy 425.374489 -43.475888) (xy 425.428991 -43.475888)
			(xy 425.482939 -43.483644) (xy 425.535234 -43.498999) (xy 425.584811 -43.521641) (xy 425.630661 -43.551107)
			(xy 425.671852 -43.586798) (xy 425.707543 -43.627989) (xy 425.737009 -43.673839) (xy 425.759651 -43.723416)
			(xy 425.775006 -43.775711) (xy 425.782762 -43.829659) (xy 425.783248 -43.85691) (xy 425.782781 -43.883097)
			(xy 425.775604 -43.934976) (xy 425.7614 -43.985386) (xy 425.740436 -44.03338) (xy 425.713105 -44.078057)
			(xy 425.679922 -44.118577) (xy 425.64151 -44.154178) (xy 425.59859 -44.184192) (xy 425.575476 -44.196508)
			(xy 425.566371 -44.201632) (xy 425.55297 -44.217634) (xy 425.547048 -44.237648) (xy 425.549584 -44.258365)
			(xy 425.560158 -44.276359) (xy 425.577023 -44.288656) (xy 425.597389 -44.293222) (xy 425.607734 -44.291758)
			(xy 425.638509 -44.286424) (xy 425.700709 -44.280704) (xy 425.73194 -44.280328) (xy 427.254924 -44.280328)
			(xy 427.264703 -44.27991) (xy 427.282851 -44.272615) (xy 427.296975 -44.259085) (xy 427.301406 -44.250356)
			(xy 427.339252 -44.166028) (xy 427.342811 -44.156863) (xy 427.343531 -44.137236) (xy 427.336843 -44.11877)
			(xy 427.330616 -44.111164) (xy 427.312424 -44.090084) (xy 427.281757 -44.04361) (xy 427.258171 -43.993172)
			(xy 427.242168 -43.939841) (xy 427.234087 -43.88475) (xy 427.233588 -43.85691) (xy 427.234074 -43.829659)
			(xy 427.24183 -43.775711) (xy 427.257185 -43.723416) (xy 427.279827 -43.673839) (xy 427.309293 -43.627989)
			(xy 427.344984 -43.586798) (xy 427.386175 -43.551107) (xy 427.432025 -43.521641) (xy 427.481602 -43.498999)
			(xy 427.533897 -43.483644) (xy 427.587845 -43.475888) (xy 427.642347 -43.475888) (xy 427.696295 -43.483644)
			(xy 427.74859 -43.498999) (xy 427.798167 -43.521641) (xy 427.844017 -43.551107) (xy 427.885208 -43.586798)
			(xy 427.920899 -43.627989) (xy 427.950365 -43.673839) (xy 427.973007 -43.723416) (xy 427.976778 -43.73626)
			(xy 446.512948 -43.73626) (xy 446.517019 -43.680638) (xy 446.529145 -43.626201) (xy 446.549068 -43.57411)
			(xy 446.576364 -43.525475) (xy 446.61045 -43.481332) (xy 446.650599 -43.442623) (xy 446.695957 -43.410172)
			(xy 446.745557 -43.384671) (xy 446.798341 -43.366664) (xy 446.853184 -43.356534) (xy 446.908918 -43.354497)
			(xy 446.964355 -43.360597) (xy 447.018312 -43.374703) (xy 447.069641 -43.396515) (xy 447.117247 -43.425569)
			(xy 447.160115 -43.461244) (xy 447.197332 -43.502781) (xy 447.228105 -43.549294) (xy 447.236331 -43.566842)
			(xy 449.633338 -43.566842) (xy 449.637409 -43.51122) (xy 449.649535 -43.456783) (xy 449.669458 -43.404692)
			(xy 449.696754 -43.356057) (xy 449.73084 -43.311914) (xy 449.770989 -43.273205) (xy 449.816347 -43.240754)
			(xy 449.865947 -43.215253) (xy 449.918731 -43.197246) (xy 449.973574 -43.187116) (xy 450.029308 -43.185079)
			(xy 450.084745 -43.191179) (xy 450.138702 -43.205285) (xy 450.190031 -43.227097) (xy 450.237637 -43.256151)
			(xy 450.280505 -43.291826) (xy 450.317722 -43.333363) (xy 450.348495 -43.379876) (xy 450.372167 -43.430373)
			(xy 450.388235 -43.48378) (xy 450.396355 -43.538956) (xy 450.396864 -43.566842) (xy 450.396355 -43.594728)
			(xy 450.388235 -43.649904) (xy 450.372167 -43.703311) (xy 450.348495 -43.753808) (xy 450.317722 -43.800321)
			(xy 450.280505 -43.841858) (xy 450.237637 -43.877533) (xy 450.190031 -43.906587) (xy 450.138702 -43.928399)
			(xy 450.084745 -43.942505) (xy 450.029308 -43.948605) (xy 449.973574 -43.946568) (xy 449.918731 -43.936438)
			(xy 449.865947 -43.918431) (xy 449.816347 -43.89293) (xy 449.770989 -43.860479) (xy 449.73084 -43.82177)
			(xy 449.696754 -43.777627) (xy 449.669458 -43.728992) (xy 449.649535 -43.676901) (xy 449.637409 -43.622464)
			(xy 449.633338 -43.566842) (xy 447.236331 -43.566842) (xy 447.251777 -43.599791) (xy 447.267845 -43.653198)
			(xy 447.275965 -43.708374) (xy 447.276474 -43.73626) (xy 447.275965 -43.764146) (xy 447.267845 -43.819322)
			(xy 447.251777 -43.872729) (xy 447.228105 -43.923226) (xy 447.197332 -43.969739) (xy 447.160115 -44.011276)
			(xy 447.117247 -44.046951) (xy 447.069641 -44.076005) (xy 447.018312 -44.097817) (xy 446.964355 -44.111923)
			(xy 446.908918 -44.118023) (xy 446.853184 -44.115986) (xy 446.798341 -44.105856) (xy 446.745557 -44.087849)
			(xy 446.695957 -44.062348) (xy 446.650599 -44.029897) (xy 446.61045 -43.991188) (xy 446.576364 -43.947045)
			(xy 446.549068 -43.89841) (xy 446.529145 -43.846319) (xy 446.517019 -43.791882) (xy 446.512948 -43.73626)
			(xy 427.976778 -43.73626) (xy 427.988362 -43.775711) (xy 427.996118 -43.829659) (xy 427.996604 -43.85691)
			(xy 427.996073 -43.884747) (xy 427.987976 -43.939828) (xy 427.971967 -43.993151) (xy 427.948388 -44.043585)
			(xy 427.917737 -44.090061) (xy 427.899576 -44.111164) (xy 427.893316 -44.118755) (xy 427.886601 -44.137231)
			(xy 427.887324 -44.156877) (xy 427.89094 -44.166028) (xy 427.928786 -44.250356) (xy 427.93315 -44.259133)
			(xy 427.947276 -44.2727) (xy 427.965472 -44.279946) (xy 427.975268 -44.280328) (xy 443.243462 -44.280328)
			(xy 443.267084 -44.266358) (xy 443.27191 -44.257722) (xy 443.280038 -44.265596) (xy 443.287402 -44.272231)
			(xy 443.305699 -44.279809) (xy 443.315598 -44.280328) (xy 446.274444 -44.280328) (xy 446.314312 -44.280953)
			(xy 446.393507 -44.290249) (xy 446.471091 -44.308653) (xy 446.546023 -44.335917) (xy 446.617294 -44.371675)
			(xy 446.683944 -44.415446) (xy 446.71488 -44.440602) (xy 446.721911 -44.445987) (xy 446.738544 -44.452026)
			(xy 446.75624 -44.452026) (xy 446.772873 -44.445987) (xy 446.779904 -44.440602) (xy 446.810837 -44.415437)
			(xy 446.877471 -44.371631) (xy 446.948737 -44.335851) (xy 447.023672 -44.308579) (xy 447.101265 -44.290185)
			(xy 447.180468 -44.280916) (xy 447.22034 -44.280328) (xy 451.039738 -44.280328) (xy 451.041262 -44.280582)
			(xy 451.041516 -44.280582) (xy 451.05125 -44.280104) (xy 451.069298 -44.272794) (xy 451.08334 -44.259304)
			(xy 451.087744 -44.25061) (xy 451.125844 -44.166028) (xy 451.129405 -44.156863) (xy 451.130125 -44.137236)
			(xy 451.123436 -44.11877) (xy 451.117208 -44.111164) (xy 451.099015 -44.090085) (xy 451.068348 -44.043611)
			(xy 451.044763 -43.993173) (xy 451.028759 -43.939841) (xy 451.020679 -43.88475) (xy 451.02018 -43.85691)
			(xy 451.020666 -43.829659) (xy 451.028422 -43.775711) (xy 451.043777 -43.723416) (xy 451.066419 -43.673839)
			(xy 451.095885 -43.627989) (xy 451.131576 -43.586798) (xy 451.172767 -43.551107) (xy 451.218617 -43.521641)
			(xy 451.268194 -43.498999) (xy 451.320489 -43.483644) (xy 451.374437 -43.475888) (xy 451.428939 -43.475888)
			(xy 451.482887 -43.483644) (xy 451.535182 -43.498999) (xy 451.584759 -43.521641) (xy 451.630609 -43.551107)
			(xy 451.6718 -43.586798) (xy 451.707491 -43.627989) (xy 451.736957 -43.673839) (xy 451.759599 -43.723416)
			(xy 451.774954 -43.775711) (xy 451.78271 -43.829659) (xy 451.783196 -43.85691) (xy 451.782757 -43.883098)
			(xy 451.775579 -43.934979) (xy 451.761373 -43.985392) (xy 451.740405 -44.033388) (xy 451.713071 -44.078065)
			(xy 451.679883 -44.118584) (xy 451.641465 -44.154183) (xy 451.59854 -44.184194) (xy 451.575424 -44.196508)
			(xy 451.566345 -44.201665) (xy 451.552966 -44.217661) (xy 451.547057 -44.23766) (xy 451.549592 -44.258359)
			(xy 451.560155 -44.276341) (xy 451.576999 -44.288635) (xy 451.597345 -44.293212) (xy 451.607682 -44.291758)
			(xy 451.638458 -44.286431) (xy 451.700657 -44.280706) (xy 451.731888 -44.280328) (xy 453.254872 -44.280328)
			(xy 453.264648 -44.279872) (xy 453.282794 -44.272595) (xy 453.296921 -44.259079) (xy 453.301354 -44.250356)
			(xy 453.3392 -44.166028) (xy 453.342749 -44.15686) (xy 453.343467 -44.137237) (xy 453.336786 -44.118772)
			(xy 453.330564 -44.111164) (xy 453.312364 -44.090091) (xy 453.281699 -44.043615) (xy 453.258116 -43.993175)
			(xy 453.242115 -43.939842) (xy 453.234035 -43.884751) (xy 453.233536 -43.85691) (xy 453.234022 -43.829659)
			(xy 453.241778 -43.775711) (xy 453.257133 -43.723416) (xy 453.279775 -43.673839) (xy 453.309241 -43.627989)
			(xy 453.344932 -43.586798) (xy 453.386123 -43.551107) (xy 453.431973 -43.521641) (xy 453.48155 -43.498999)
			(xy 453.533845 -43.483644) (xy 453.587793 -43.475888) (xy 453.642295 -43.475888) (xy 453.696243 -43.483644)
			(xy 453.748538 -43.498999) (xy 453.798115 -43.521641) (xy 453.843965 -43.551107) (xy 453.885156 -43.586798)
			(xy 453.920847 -43.627989) (xy 453.950313 -43.673839) (xy 453.972955 -43.723416) (xy 453.98831 -43.775711)
			(xy 453.996066 -43.829659) (xy 453.996552 -43.85691) (xy 453.996035 -43.884747) (xy 453.987935 -43.93983)
			(xy 453.971925 -43.993153) (xy 453.948342 -44.043587) (xy 453.917687 -44.090063) (xy 453.899524 -44.111164)
			(xy 453.893262 -44.118752) (xy 453.886552 -44.13723) (xy 453.887275 -44.156876) (xy 453.890888 -44.166028)
			(xy 453.928734 -44.250356) (xy 453.933135 -44.259111) (xy 453.947245 -44.272679) (xy 453.965426 -44.279937)
			(xy 453.975216 -44.280328) (xy 457.256134 -44.280328) (xy 457.261024 -44.280469) (xy 457.270617 -44.282384)
			(xy 457.275184 -44.284138) (xy 457.514452 -44.381166) (xy 457.519281 -44.383337) (xy 457.527989 -44.389352)
			(xy 457.531724 -44.393104) (xy 457.620878 -44.485306) (xy 457.621386 -44.485814) (xy 459.49108 -46.355254)
			(xy 459.517969 -46.382848) (xy 459.566024 -46.443076) (xy 459.607031 -46.508307) (xy 459.640475 -46.577721)
			(xy 459.665934 -46.650443) (xy 459.68309 -46.725558) (xy 459.691724 -46.802123) (xy 459.692248 -46.840648)
			(xy 459.692248 -65.568068) (xy 459.691713 -65.606055) (xy 459.68335 -65.681568) (xy 459.66669 -65.755694)
			(xy 459.641937 -65.827523) (xy 459.609395 -65.896175) (xy 459.569462 -65.960808) (xy 459.522628 -66.020631)
			(xy 459.496414 -66.048128) (xy 459.495398 -66.049144) (xy 459.490572 -66.053716) (xy 459.490572 -66.05397)
			(xy 455.48423 -70.060312) (xy 455.477397 -70.067717) (xy 455.469672 -70.086312) (xy 455.469244 -70.09638)
			(xy 455.469244 -74.736452) (xy 455.46966 -74.746476) (xy 455.477322 -74.765) (xy 455.491497 -74.779176)
			(xy 455.51002 -74.786839) (xy 455.520044 -74.787252) (xy 457.556616 -74.787252) (xy 457.566688 -74.786848)
			(xy 457.585286 -74.779114) (xy 457.592684 -74.772266) (xy 457.994258 -74.370692) (xy 458.017834 -74.347772)
			(xy 458.069246 -74.306779) (xy 458.124921 -74.271794) (xy 458.184159 -74.243255) (xy 458.246218 -74.22152)
			(xy 458.310318 -74.206864) (xy 458.375655 -74.199468) (xy 458.408532 -74.198988) (xy 458.443942 -74.19946)
			(xy 458.514244 -74.208002) (xy 458.583003 -74.224958) (xy 458.649217 -74.250081) (xy 458.711918 -74.283003)
			(xy 458.770193 -74.323245) (xy 458.823191 -74.37022) (xy 458.870139 -74.423242) (xy 458.910351 -74.481537)
			(xy 458.943242 -74.544255) (xy 458.968331 -74.610481) (xy 458.985252 -74.67925) (xy 458.993758 -74.749556)
			(xy 458.994256 -74.784966) (xy 458.993817 -74.817838) (xy 458.986472 -74.883171) (xy 458.971859 -74.94727)
			(xy 458.950162 -75.009331) (xy 458.921653 -75.068572) (xy 458.886692 -75.124249) (xy 458.845717 -75.175663)
			(xy 458.822806 -75.19924) (xy 458.74178 -75.280266) (xy 458.74051 -75.320144) (xy 458.753972 -75.335384)
			(xy 458.771901 -75.356425) (xy 458.802179 -75.402672) (xy 458.825461 -75.452806) (xy 458.841258 -75.505778)
			(xy 458.849239 -75.560476) (xy 458.84973 -75.588114) (xy 458.84973 -75.588368) (xy 458.84914 -75.618123)
			(xy 458.839904 -75.676911) (xy 458.821635 -75.733546) (xy 458.794778 -75.786651) (xy 458.777848 -75.811126)
			(xy 458.772867 -75.818595) (xy 458.76809 -75.835891) (xy 458.769557 -75.853775) (xy 458.77709 -75.870062)
			(xy 458.783182 -75.876658) (xy 458.934058 -76.027534) (xy 458.956966 -76.051089) (xy 458.99793 -76.102467)
			(xy 459.032884 -76.158109) (xy 459.061388 -76.217314) (xy 459.083084 -76.279339) (xy 459.0977 -76.343402)
			(xy 459.105051 -76.408699) (xy 459.105508 -76.441554) (xy 459.105508 -76.441808) (xy 459.105018 -76.477208)
			(xy 459.096483 -76.54749) (xy 459.079539 -76.616232) (xy 459.054432 -76.68243) (xy 459.021529 -76.745118)
			(xy 458.98131 -76.803384) (xy 458.93436 -76.856377) (xy 458.881365 -76.903324) (xy 458.823098 -76.943542)
			(xy 458.760408 -76.976442) (xy 458.694209 -77.001546) (xy 458.625467 -77.018488) (xy 458.555184 -77.02702)
			(xy 458.519784 -77.027532) (xy 458.51953 -77.027532) (xy 458.486678 -77.027025) (xy 458.421387 -77.019667)
			(xy 458.357329 -77.005049) (xy 458.295309 -76.983357) (xy 458.236105 -76.954862) (xy 458.180461 -76.919922)
			(xy 458.129076 -76.878976) (xy 458.10551 -76.856082) (xy 457.72959 -76.480162) (xy 457.722192 -76.47332)
			(xy 457.703591 -76.465602) (xy 457.693522 -76.465176) (xy 455.906378 -76.465176) (xy 455.880978 -76.482194)
			(xy 455.875136 -76.496418) (xy 455.871723 -76.50586) (xy 455.871758 -76.525918) (xy 455.87949 -76.544426)
			(xy 455.886312 -76.55179) (xy 455.96937 -76.634848) (xy 455.992287 -76.658395) (xy 456.03325 -76.709775)
			(xy 456.068202 -76.765418) (xy 456.096705 -76.824625) (xy 456.1184 -76.88665) (xy 456.133014 -76.950715)
			(xy 456.140364 -77.016013) (xy 456.14082 -77.048868) (xy 456.14082 -77.049122) (xy 456.140298 -77.084003)
			(xy 456.132001 -77.15327) (xy 456.115538 -77.221062) (xy 456.091143 -77.28642) (xy 456.059161 -77.34842)
			(xy 456.020045 -77.406184) (xy 455.974346 -77.458895) (xy 455.922713 -77.505807) (xy 455.865875 -77.546258)
			(xy 455.804637 -77.579674) (xy 455.739864 -77.605583) (xy 455.672473 -77.623618) (xy 455.603418 -77.633525)
			(xy 455.568558 -77.634846) (xy 455.568304 -77.634846) (xy 455.558489 -77.635554) (xy 455.540456 -77.643383)
			(xy 455.533252 -77.650086) (xy 455.483722 -77.700886) (xy 455.477156 -77.708276) (xy 455.469709 -77.726571)
			(xy 455.469244 -77.736446) (xy 455.469244 -86.3981) (xy 455.468833 -86.408171) (xy 455.461104 -86.42677)
			(xy 455.454258 -86.434168) (xy 451.130416 -90.75801) (xy 451.123006 -90.764837) (xy 451.104414 -90.772564)
			(xy 451.094348 -90.772996) (xy 444.18123 -90.772996) (xy 444.171159 -90.773412) (xy 444.15256 -90.781137)
			(xy 444.145162 -90.787982) (xy 443.895734 -91.03741) (xy 443.888902 -91.044817) (xy 443.881177 -91.063411)
			(xy 443.880748 -91.073478) (xy 443.880748 -91.407996) (xy 443.880334 -91.418067) (xy 443.872607 -91.436665)
			(xy 443.865762 -91.444064) (xy 443.728856 -91.58097) (xy 443.722186 -91.588393) (xy 443.714582 -91.606821)
			(xy 443.714578 -91.626756) (xy 443.722173 -91.645187) (xy 443.728856 -91.652598) (xy 444.762128 -92.685616)
			(xy 444.780141 -92.704404) (xy 444.810723 -92.746517) (xy 444.834353 -92.792889) (xy 444.850452 -92.842382)
			(xy 444.858625 -92.893782) (xy 444.859156 -92.919804) (xy 444.859156 -93.488002) (xy 444.859565 -93.498073)
			(xy 444.867296 -93.516672) (xy 444.874142 -93.52407) (xy 445.226948 -93.876622) (xy 445.231336 -93.880744)
			(xy 445.241604 -93.887025) (xy 445.247268 -93.889068) (xy 445.247776 -93.889068) (xy 445.273326 -93.8975)
			(xy 445.32193 -93.920573) (xy 445.36681 -93.950245) (xy 445.407077 -93.985928) (xy 445.441932 -94.026914)
			(xy 445.470684 -94.07239) (xy 445.492762 -94.121454) (xy 445.507728 -94.173134) (xy 445.515285 -94.226403)
			(xy 445.515311 -94.227904) (xy 445.76822 -94.227904) (xy 445.772291 -94.172282) (xy 445.784417 -94.117845)
			(xy 445.80434 -94.065754) (xy 445.831636 -94.017119) (xy 445.865722 -93.972976) (xy 445.905871 -93.934267)
			(xy 445.951229 -93.901816) (xy 446.000829 -93.876315) (xy 446.053613 -93.858308) (xy 446.108456 -93.848178)
			(xy 446.16419 -93.846141) (xy 446.219627 -93.852241) (xy 446.273584 -93.866347) (xy 446.324913 -93.888159)
			(xy 446.372519 -93.917213) (xy 446.415387 -93.952888) (xy 446.452604 -93.994425) (xy 446.483377 -94.040938)
			(xy 446.507049 -94.091435) (xy 446.523117 -94.144842) (xy 446.531237 -94.200018) (xy 446.531746 -94.227904)
			(xy 446.53131 -94.25178) (xy 446.78422 -94.25178) (xy 446.788291 -94.196158) (xy 446.800417 -94.141721)
			(xy 446.82034 -94.08963) (xy 446.847636 -94.040995) (xy 446.881722 -93.996852) (xy 446.921871 -93.958143)
			(xy 446.967229 -93.925692) (xy 447.016829 -93.900191) (xy 447.069613 -93.882184) (xy 447.124456 -93.872054)
			(xy 447.18019 -93.870017) (xy 447.235627 -93.876117) (xy 447.289584 -93.890223) (xy 447.340913 -93.912035)
			(xy 447.388519 -93.941089) (xy 447.431387 -93.976764) (xy 447.468604 -94.018301) (xy 447.499377 -94.064814)
			(xy 447.523049 -94.115311) (xy 447.539117 -94.168718) (xy 447.544949 -94.208346) (xy 448.05422 -94.208346)
			(xy 448.058291 -94.152724) (xy 448.070417 -94.098287) (xy 448.09034 -94.046196) (xy 448.117636 -93.997561)
			(xy 448.151722 -93.953418) (xy 448.191871 -93.914709) (xy 448.237229 -93.882258) (xy 448.286829 -93.856757)
			(xy 448.339613 -93.83875) (xy 448.394456 -93.82862) (xy 448.45019 -93.826583) (xy 448.505627 -93.832683)
			(xy 448.559584 -93.846789) (xy 448.610913 -93.868601) (xy 448.658519 -93.897655) (xy 448.701387 -93.93333)
			(xy 448.738604 -93.974867) (xy 448.769377 -94.02138) (xy 448.793049 -94.071877) (xy 448.809117 -94.125284)
			(xy 448.817237 -94.18046) (xy 448.817746 -94.208346) (xy 448.817237 -94.236232) (xy 448.809117 -94.291408)
			(xy 448.793049 -94.344815) (xy 448.769377 -94.395312) (xy 448.738604 -94.441825) (xy 448.701387 -94.483362)
			(xy 448.658519 -94.519037) (xy 448.610913 -94.548091) (xy 448.559584 -94.569903) (xy 448.505627 -94.584009)
			(xy 448.45019 -94.590109) (xy 448.394456 -94.588072) (xy 448.339613 -94.577942) (xy 448.286829 -94.559935)
			(xy 448.237229 -94.534434) (xy 448.191871 -94.501983) (xy 448.151722 -94.463274) (xy 448.117636 -94.419131)
			(xy 448.09034 -94.370496) (xy 448.070417 -94.318405) (xy 448.058291 -94.263968) (xy 448.05422 -94.208346)
			(xy 447.544949 -94.208346) (xy 447.547237 -94.223894) (xy 447.547746 -94.25178) (xy 447.547237 -94.279666)
			(xy 447.539117 -94.334842) (xy 447.523049 -94.388249) (xy 447.499377 -94.438746) (xy 447.468604 -94.485259)
			(xy 447.431387 -94.526796) (xy 447.388519 -94.562471) (xy 447.340913 -94.591525) (xy 447.289584 -94.613337)
			(xy 447.235627 -94.627443) (xy 447.18019 -94.633543) (xy 447.124456 -94.631506) (xy 447.069613 -94.621376)
			(xy 447.016829 -94.603369) (xy 446.967229 -94.577868) (xy 446.921871 -94.545417) (xy 446.881722 -94.506708)
			(xy 446.847636 -94.462565) (xy 446.82034 -94.41393) (xy 446.800417 -94.361839) (xy 446.788291 -94.307402)
			(xy 446.78422 -94.25178) (xy 446.53131 -94.25178) (xy 446.531237 -94.25579) (xy 446.523117 -94.310966)
			(xy 446.507049 -94.364373) (xy 446.483377 -94.41487) (xy 446.452604 -94.461383) (xy 446.415387 -94.50292)
			(xy 446.372519 -94.538595) (xy 446.324913 -94.567649) (xy 446.273584 -94.589461) (xy 446.219627 -94.603567)
			(xy 446.16419 -94.609667) (xy 446.108456 -94.60763) (xy 446.053613 -94.5975) (xy 446.000829 -94.579493)
			(xy 445.951229 -94.553992) (xy 445.905871 -94.521541) (xy 445.865722 -94.482832) (xy 445.831636 -94.438689)
			(xy 445.80434 -94.390054) (xy 445.784417 -94.337963) (xy 445.772291 -94.283526) (xy 445.76822 -94.227904)
			(xy 445.515311 -94.227904) (xy 445.515746 -94.253304) (xy 445.515226 -94.280554) (xy 445.50747 -94.334498)
			(xy 445.492116 -94.38679) (xy 445.469477 -94.436365) (xy 445.440014 -94.482213) (xy 445.404326 -94.523402)
			(xy 445.36314 -94.559094) (xy 445.317295 -94.588561) (xy 445.267722 -94.611204) (xy 445.215431 -94.626563)
			(xy 445.161488 -94.634324) (xy 445.134238 -94.634812) (xy 445.107327 -94.634359) (xy 445.054043 -94.626774)
			(xy 445.002353 -94.611778) (xy 444.953282 -94.589669) (xy 444.907804 -94.560884) (xy 444.866822 -94.525995)
			(xy 444.831149 -94.485694) (xy 444.801491 -94.440781) (xy 444.778438 -94.392147) (xy 444.770002 -94.366588)
			(xy 444.770002 -94.366334) (xy 444.768019 -94.360642) (xy 444.761725 -94.350367) (xy 444.757556 -94.346014)
			(xy 444.666878 -94.255336) (xy 444.660045 -94.249024) (xy 444.643112 -94.24136) (xy 444.624559 -94.240241)
			(xy 444.61557 -94.242636) (xy 444.52921 -94.270576) (xy 444.520514 -94.273832) (xy 444.506011 -94.285392)
			(xy 444.496605 -94.301376) (xy 444.494666 -94.310454) (xy 444.494666 -94.310708) (xy 444.489909 -94.337175)
			(xy 444.473893 -94.388509) (xy 444.450825 -94.437084) (xy 444.421161 -94.481936) (xy 444.385491 -94.522177)
			(xy 444.344521 -94.557007) (xy 444.299064 -94.585737) (xy 444.250022 -94.607795) (xy 444.198368 -94.622746)
			(xy 444.145125 -94.630292) (xy 444.118238 -94.630748) (xy 444.09099 -94.630187) (xy 444.037047 -94.622436)
			(xy 443.984756 -94.607088) (xy 443.935181 -94.584454) (xy 443.889333 -94.554996) (xy 443.848143 -94.519312)
			(xy 443.812451 -94.47813) (xy 443.782983 -94.432287) (xy 443.760339 -94.382717) (xy 443.74498 -94.33043)
			(xy 443.737219 -94.276488) (xy 443.73673 -94.24924) (xy 443.737152 -94.22225) (xy 443.744755 -94.168809)
			(xy 443.759815 -94.116972) (xy 443.782032 -94.067776) (xy 443.810961 -94.022203) (xy 443.846025 -93.981162)
			(xy 443.886523 -93.945474) (xy 443.931648 -93.91585) (xy 443.980498 -93.892883) (xy 444.032098 -93.877031)
			(xy 444.085416 -93.86861) (xy 444.112396 -93.867732) (xy 444.124334 -93.867732) (xy 444.145416 -93.85681)
			(xy 444.207646 -93.77299) (xy 444.21171 -93.749622) (xy 444.208408 -93.738192) (xy 444.202427 -93.715743)
			(xy 444.196047 -93.669727) (xy 444.195708 -93.646498) (xy 444.195708 -93.078808) (xy 444.195303 -93.068736)
			(xy 444.187571 -93.050137) (xy 444.180722 -93.04274) (xy 440.92114 -89.783412) (xy 440.913719 -89.776599)
			(xy 440.895136 -89.768863) (xy 440.885072 -89.768426) (xy 433.310538 -89.768426) (xy 433.254912 -89.768172)
			(xy 431.052732 -89.768172) (xy 431.042662 -89.768595) (xy 431.024063 -89.776315) (xy 431.016664 -89.783158)
			(xy 429.945038 -90.854784) (xy 429.930306 -90.854784) (xy 429.921547 -90.855175) (xy 429.905042 -90.861048)
			(xy 429.891463 -90.872116) (xy 429.886618 -90.879422) (xy 429.871717 -90.903129) (xy 429.836065 -90.946304)
			(xy 429.794483 -90.983803) (xy 429.747865 -91.014818) (xy 429.697212 -91.038683) (xy 429.643615 -91.054886)
			(xy 429.588224 -91.063077) (xy 429.560228 -91.063572) (xy 429.529424 -91.062987) (xy 429.468622 -91.053052)
			(xy 429.410209 -91.033468) (xy 429.382682 -91.01963) (xy 429.377159 -91.016912) (xy 429.365213 -91.013957)
			(xy 429.35906 -91.013788) (xy 427.320964 -91.013788) (xy 427.29494 -91.013266) (xy 427.243536 -91.0051)
			(xy 427.194038 -90.989005) (xy 427.147662 -90.965376) (xy 427.105546 -90.934793) (xy 427.086776 -90.91676)
			(xy 425.953174 -89.783158) (xy 425.945782 -89.776308) (xy 425.927176 -89.768595) (xy 425.917106 -89.768172)
			(xy 425.812966 -89.768172) (xy 425.802803 -89.768575) (xy 425.784066 -89.776455) (xy 425.776644 -89.783412)
			(xy 425.718478 -89.842848) (xy 425.711112 -89.861644) (xy 425.711366 -89.872058) (xy 425.71162 -89.88552)
			(xy 425.71162 -89.886028) (xy 425.711144 -89.91889) (xy 425.70376 -89.984198) (xy 425.68911 -90.048269)
			(xy 425.667378 -90.110297) (xy 425.638837 -90.169501) (xy 425.603848 -90.225137) (xy 425.562849 -90.276506)
			(xy 425.539916 -90.300048) (xy 424.08729 -91.752674) (xy 424.063727 -91.775574) (xy 424.01235 -91.816538)
			(xy 423.956709 -91.851492) (xy 423.897506 -91.879997) (xy 423.835483 -91.901695) (xy 423.77142 -91.916312)
			(xy 423.706124 -91.923665) (xy 423.67327 -91.924124) (xy 409.381452 -91.924124) (xy 409.371385 -91.92457)
			(xy 409.352787 -91.932276) (xy 409.345384 -91.93911) (xy 408.363674 -92.921074) (xy 408.340118 -92.943981)
			(xy 408.28874 -92.984945) (xy 408.233098 -93.019898) (xy 408.173893 -93.048402) (xy 408.111869 -93.070099)
			(xy 408.047806 -93.084715) (xy 407.982509 -93.092066) (xy 407.949654 -93.092524) (xy 403.944582 -93.092524)
			(xy 403.934511 -93.092934) (xy 403.915913 -93.100665) (xy 403.908514 -93.10751) (xy 403.307621 -93.708447)
			(xy 417.390634 -93.708447) (xy 417.390634 -93.621553) (xy 417.398651 -93.535028) (xy 417.414618 -93.449613)
			(xy 417.438398 -93.366035) (xy 417.469787 -93.285008) (xy 417.508519 -93.207223) (xy 417.554263 -93.133343)
			(xy 417.606628 -93.063999) (xy 417.665168 -92.999782) (xy 417.729383 -92.941241) (xy 417.798726 -92.888874)
			(xy 417.872605 -92.843129) (xy 417.95039 -92.804395) (xy 418.031416 -92.773004) (xy 418.114994 -92.749223)
			(xy 418.200409 -92.733254) (xy 418.286933 -92.725235) (xy 418.33038 -92.724732) (xy 420.18458 -92.724732)
			(xy 420.228031 -92.725198) (xy 420.314564 -92.733214) (xy 420.399987 -92.749182) (xy 420.483573 -92.772963)
			(xy 420.564607 -92.804355) (xy 420.6424 -92.843091) (xy 420.716286 -92.88884) (xy 420.785636 -92.941211)
			(xy 420.849857 -92.999757) (xy 420.908402 -93.06398) (xy 420.960772 -93.133331) (xy 421.006519 -93.207218)
			(xy 421.045253 -93.285011) (xy 421.076644 -93.366046) (xy 421.100423 -93.449632) (xy 421.116388 -93.535056)
			(xy 421.124403 -93.621589) (xy 421.124888 -93.66504) (xy 421.124328 -93.710119) (xy 421.115685 -93.799862)
			(xy 421.098499 -93.888368) (xy 421.07293 -93.974824) (xy 421.056562 -94.01683) (xy 421.052244 -94.027752)
			(xy 421.053768 -94.051374) (xy 421.106854 -94.14129) (xy 421.126666 -94.154244) (xy 421.13835 -94.155768)
			(xy 421.184322 -94.161949) (xy 421.275057 -94.181259) (xy 421.363774 -94.208369) (xy 421.386382 -94.21749)
			(xy 437.504838 -94.21749) (xy 437.508909 -94.161868) (xy 437.521035 -94.107431) (xy 437.540958 -94.05534)
			(xy 437.568254 -94.006705) (xy 437.60234 -93.962562) (xy 437.642489 -93.923853) (xy 437.687847 -93.891402)
			(xy 437.737447 -93.865901) (xy 437.790231 -93.847894) (xy 437.845074 -93.837764) (xy 437.900808 -93.835727)
			(xy 437.956245 -93.841827) (xy 438.010202 -93.855933) (xy 438.061531 -93.877745) (xy 438.109137 -93.906799)
			(xy 438.152005 -93.942474) (xy 438.187904 -93.98254) (xy 442.727078 -93.98254) (xy 442.731149 -93.926918)
			(xy 442.743275 -93.872481) (xy 442.763198 -93.82039) (xy 442.790494 -93.771755) (xy 442.82458 -93.727612)
			(xy 442.864729 -93.688903) (xy 442.910087 -93.656452) (xy 442.959687 -93.630951) (xy 443.012471 -93.612944)
			(xy 443.067314 -93.602814) (xy 443.123048 -93.600777) (xy 443.178485 -93.606877) (xy 443.232442 -93.620983)
			(xy 443.283771 -93.642795) (xy 443.331377 -93.671849) (xy 443.374245 -93.707524) (xy 443.411462 -93.749061)
			(xy 443.442235 -93.795574) (xy 443.465907 -93.846071) (xy 443.481975 -93.899478) (xy 443.490095 -93.954654)
			(xy 443.490604 -93.98254) (xy 443.490095 -94.010426) (xy 443.481975 -94.065602) (xy 443.465907 -94.119009)
			(xy 443.442235 -94.169506) (xy 443.411462 -94.216019) (xy 443.374245 -94.257556) (xy 443.331377 -94.293231)
			(xy 443.283771 -94.322285) (xy 443.232442 -94.344097) (xy 443.178485 -94.358203) (xy 443.123048 -94.364303)
			(xy 443.067314 -94.362266) (xy 443.012471 -94.352136) (xy 442.959687 -94.334129) (xy 442.910087 -94.308628)
			(xy 442.864729 -94.276177) (xy 442.82458 -94.237468) (xy 442.790494 -94.193325) (xy 442.763198 -94.14469)
			(xy 442.743275 -94.092599) (xy 442.731149 -94.038162) (xy 442.727078 -93.98254) (xy 438.187904 -93.98254)
			(xy 438.189222 -93.984011) (xy 438.219995 -94.030524) (xy 438.243667 -94.081021) (xy 438.259735 -94.134428)
			(xy 438.267855 -94.189604) (xy 438.268364 -94.21749) (xy 438.267855 -94.245376) (xy 438.259735 -94.300552)
			(xy 438.243667 -94.353959) (xy 438.219995 -94.404456) (xy 438.189222 -94.450969) (xy 438.152005 -94.492506)
			(xy 438.109137 -94.528181) (xy 438.061531 -94.557235) (xy 438.010202 -94.579047) (xy 437.956245 -94.593153)
			(xy 437.900808 -94.599253) (xy 437.845074 -94.597216) (xy 437.790231 -94.587086) (xy 437.737447 -94.569079)
			(xy 437.687847 -94.543578) (xy 437.642489 -94.511127) (xy 437.60234 -94.472418) (xy 437.568254 -94.428275)
			(xy 437.540958 -94.37964) (xy 437.521035 -94.327549) (xy 437.508909 -94.273112) (xy 437.504838 -94.21749)
			(xy 421.386382 -94.21749) (xy 421.449803 -94.243077) (xy 421.532496 -94.285118) (xy 421.611228 -94.334178)
			(xy 421.685407 -94.389885) (xy 421.754471 -94.451818) (xy 421.8179 -94.519512) (xy 421.875215 -94.592454)
			(xy 421.925984 -94.670095) (xy 421.969823 -94.751849) (xy 422.006403 -94.837099) (xy 422.035447 -94.925202)
			(xy 422.056735 -95.015493) (xy 422.070108 -95.107291) (xy 422.075464 -95.199902) (xy 422.072763 -95.29263)
			(xy 422.062025 -95.384773) (xy 422.043332 -95.475636) (xy 422.016824 -95.564535) (xy 421.982701 -95.650798)
			(xy 421.941221 -95.733774) (xy 421.892697 -95.812837) (xy 421.837495 -95.887392) (xy 421.776031 -95.956874)
			(xy 421.741526 -95.989648) (xy 423.864022 -95.989648) (xy 423.868093 -95.934026) (xy 423.880219 -95.879589)
			(xy 423.900142 -95.827498) (xy 423.927438 -95.778863) (xy 423.961524 -95.73472) (xy 424.001673 -95.696011)
			(xy 424.047031 -95.66356) (xy 424.096631 -95.638059) (xy 424.149415 -95.620052) (xy 424.204258 -95.609922)
			(xy 424.259992 -95.607885) (xy 424.315429 -95.613985) (xy 424.369386 -95.628091) (xy 424.420715 -95.649903)
			(xy 424.468321 -95.678957) (xy 424.511189 -95.714632) (xy 424.548406 -95.756169) (xy 424.579179 -95.802682)
			(xy 424.602851 -95.853179) (xy 424.618919 -95.906586) (xy 424.627039 -95.961762) (xy 424.627548 -95.989648)
			(xy 426.469554 -95.989648) (xy 426.473625 -95.934026) (xy 426.485751 -95.879589) (xy 426.505674 -95.827498)
			(xy 426.53297 -95.778863) (xy 426.567056 -95.73472) (xy 426.607205 -95.696011) (xy 426.652563 -95.66356)
			(xy 426.702163 -95.638059) (xy 426.754947 -95.620052) (xy 426.80979 -95.609922) (xy 426.865524 -95.607885)
			(xy 426.920961 -95.613985) (xy 426.974918 -95.628091) (xy 427.026247 -95.649903) (xy 427.073853 -95.678957)
			(xy 427.116721 -95.714632) (xy 427.153938 -95.756169) (xy 427.184221 -95.801942) (xy 436.941466 -95.801942)
			(xy 436.945537 -95.74632) (xy 436.957663 -95.691883) (xy 436.977586 -95.639792) (xy 437.004882 -95.591157)
			(xy 437.038968 -95.547014) (xy 437.079117 -95.508305) (xy 437.124475 -95.475854) (xy 437.174075 -95.450353)
			(xy 437.226859 -95.432346) (xy 437.281702 -95.422216) (xy 437.337436 -95.420179) (xy 437.392873 -95.426279)
			(xy 437.44683 -95.440385) (xy 437.498159 -95.462197) (xy 437.545765 -95.491251) (xy 437.588633 -95.526926)
			(xy 437.62585 -95.568463) (xy 437.656623 -95.614976) (xy 437.680295 -95.665473) (xy 437.696363 -95.71888)
			(xy 437.704483 -95.774056) (xy 437.704992 -95.801942) (xy 437.957466 -95.801942) (xy 437.961537 -95.74632)
			(xy 437.973663 -95.691883) (xy 437.993586 -95.639792) (xy 438.020882 -95.591157) (xy 438.054968 -95.547014)
			(xy 438.095117 -95.508305) (xy 438.140475 -95.475854) (xy 438.190075 -95.450353) (xy 438.242859 -95.432346)
			(xy 438.297702 -95.422216) (xy 438.353436 -95.420179) (xy 438.408873 -95.426279) (xy 438.46283 -95.440385)
			(xy 438.514159 -95.462197) (xy 438.561765 -95.491251) (xy 438.604633 -95.526926) (xy 438.64185 -95.568463)
			(xy 438.672623 -95.614976) (xy 438.696295 -95.665473) (xy 438.712363 -95.71888) (xy 438.720483 -95.774056)
			(xy 438.720992 -95.801942) (xy 438.974736 -95.801942) (xy 438.978807 -95.74632) (xy 438.990933 -95.691883)
			(xy 439.010856 -95.639792) (xy 439.038152 -95.591157) (xy 439.072238 -95.547014) (xy 439.112387 -95.508305)
			(xy 439.157745 -95.475854) (xy 439.207345 -95.450353) (xy 439.260129 -95.432346) (xy 439.314972 -95.422216)
			(xy 439.370706 -95.420179) (xy 439.426143 -95.426279) (xy 439.4801 -95.440385) (xy 439.531429 -95.462197)
			(xy 439.579035 -95.491251) (xy 439.621903 -95.526926) (xy 439.65912 -95.568463) (xy 439.689893 -95.614976)
			(xy 439.710038 -95.65795) (xy 440.264801 -95.65795) (xy 440.264801 -95.60345) (xy 440.272557 -95.549505)
			(xy 440.287912 -95.497214) (xy 440.310552 -95.447639) (xy 440.340017 -95.401791) (xy 440.375706 -95.360604)
			(xy 440.416895 -95.324914) (xy 440.462743 -95.29545) (xy 440.512317 -95.27281) (xy 440.564609 -95.257457)
			(xy 440.618554 -95.249701) (xy 440.645804 -95.249238) (xy 440.673197 -95.249735) (xy 440.727421 -95.25756)
			(xy 440.779968 -95.273062) (xy 440.829756 -95.295922) (xy 440.875761 -95.32567) (xy 440.917037 -95.361695)
			(xy 440.952735 -95.403254) (xy 440.982119 -95.449493) (xy 440.993784 -95.474282) (xy 440.999692 -95.486342)
			(xy 441.016727 -95.50709) (xy 441.038587 -95.522671) (xy 441.063758 -95.532004) (xy 441.090492 -95.534441)
			(xy 441.116935 -95.529815) (xy 441.141254 -95.518445) (xy 441.151772 -95.510096) (xy 441.172472 -95.493223)
			(xy 441.217717 -95.464852) (xy 441.266479 -95.443075) (xy 441.317805 -95.428321) (xy 441.370688 -95.420877)
			(xy 441.39739 -95.420434) (xy 441.397644 -95.420434) (xy 441.424896 -95.420839) (xy 441.478845 -95.428601)
			(xy 441.53114 -95.443962) (xy 441.580717 -95.466608) (xy 441.626567 -95.496079) (xy 441.667757 -95.531774)
			(xy 441.703448 -95.572968) (xy 441.732913 -95.618821) (xy 441.755553 -95.668401) (xy 441.770908 -95.720698)
			(xy 441.778664 -95.774648) (xy 441.778664 -95.801942) (xy 442.021466 -95.801942) (xy 442.025537 -95.74632)
			(xy 442.037663 -95.691883) (xy 442.057586 -95.639792) (xy 442.084882 -95.591157) (xy 442.118968 -95.547014)
			(xy 442.159117 -95.508305) (xy 442.204475 -95.475854) (xy 442.254075 -95.450353) (xy 442.306859 -95.432346)
			(xy 442.361702 -95.422216) (xy 442.417436 -95.420179) (xy 442.472873 -95.426279) (xy 442.52683 -95.440385)
			(xy 442.578159 -95.462197) (xy 442.625765 -95.491251) (xy 442.668633 -95.526926) (xy 442.70585 -95.568463)
			(xy 442.736623 -95.614976) (xy 442.760295 -95.665473) (xy 442.776363 -95.71888) (xy 442.784483 -95.774056)
			(xy 442.784992 -95.801942) (xy 442.784483 -95.829828) (xy 442.776363 -95.885004) (xy 442.760295 -95.938411)
			(xy 442.736623 -95.988908) (xy 442.70585 -96.035421) (xy 442.668633 -96.076958) (xy 442.625765 -96.112633)
			(xy 442.578159 -96.141687) (xy 442.52683 -96.163499) (xy 442.472873 -96.177605) (xy 442.417436 -96.183705)
			(xy 442.361702 -96.181668) (xy 442.306859 -96.171538) (xy 442.254075 -96.153531) (xy 442.204475 -96.12803)
			(xy 442.159117 -96.095579) (xy 442.118968 -96.05687) (xy 442.084882 -96.012727) (xy 442.057586 -95.964092)
			(xy 442.037663 -95.912001) (xy 442.025537 -95.857564) (xy 442.021466 -95.801942) (xy 441.778664 -95.801942)
			(xy 441.778664 -95.829152) (xy 441.770908 -95.883102) (xy 441.755553 -95.935399) (xy 441.732913 -95.984979)
			(xy 441.703448 -96.030832) (xy 441.667757 -96.072026) (xy 441.626567 -96.107721) (xy 441.580717 -96.137192)
			(xy 441.53114 -96.159838) (xy 441.478845 -96.175199) (xy 441.424896 -96.182961) (xy 441.397644 -96.18345)
			(xy 441.370249 -96.183003) (xy 441.316023 -96.175171) (xy 441.263475 -96.159662) (xy 441.213686 -96.136794)
			(xy 441.167681 -96.107039) (xy 441.126406 -96.071008) (xy 441.09071 -96.029443) (xy 441.061328 -95.983198)
			(xy 441.049664 -95.958406) (xy 441.043827 -95.946308) (xy 441.026779 -95.925557) (xy 441.004904 -95.909976)
			(xy 440.97972 -95.900648) (xy 440.952974 -95.898217) (xy 440.926521 -95.902854) (xy 440.902196 -95.914237)
			(xy 440.891676 -95.922592) (xy 440.870957 -95.939441) (xy 440.825718 -95.967816) (xy 440.77696 -95.989598)
			(xy 440.725639 -96.004358) (xy 440.672759 -96.011808) (xy 440.646058 -96.012254) (xy 440.645804 -96.012254)
			(xy 440.618554 -96.011699) (xy 440.564609 -96.003943) (xy 440.512317 -95.98859) (xy 440.462743 -95.96595)
			(xy 440.416895 -95.936486) (xy 440.375706 -95.900796) (xy 440.340017 -95.859609) (xy 440.310552 -95.813761)
			(xy 440.287912 -95.764186) (xy 440.272557 -95.711895) (xy 440.264801 -95.65795) (xy 439.710038 -95.65795)
			(xy 439.713565 -95.665473) (xy 439.729633 -95.71888) (xy 439.737753 -95.774056) (xy 439.738262 -95.801942)
			(xy 439.737753 -95.829828) (xy 439.729633 -95.885004) (xy 439.713565 -95.938411) (xy 439.689893 -95.988908)
			(xy 439.65912 -96.035421) (xy 439.621903 -96.076958) (xy 439.579035 -96.112633) (xy 439.531429 -96.141687)
			(xy 439.4801 -96.163499) (xy 439.426143 -96.177605) (xy 439.370706 -96.183705) (xy 439.314972 -96.181668)
			(xy 439.260129 -96.171538) (xy 439.207345 -96.153531) (xy 439.157745 -96.12803) (xy 439.112387 -96.095579)
			(xy 439.072238 -96.05687) (xy 439.038152 -96.012727) (xy 439.010856 -95.964092) (xy 438.990933 -95.912001)
			(xy 438.978807 -95.857564) (xy 438.974736 -95.801942) (xy 438.720992 -95.801942) (xy 438.720483 -95.829828)
			(xy 438.712363 -95.885004) (xy 438.696295 -95.938411) (xy 438.672623 -95.988908) (xy 438.64185 -96.035421)
			(xy 438.604633 -96.076958) (xy 438.561765 -96.112633) (xy 438.514159 -96.141687) (xy 438.46283 -96.163499)
			(xy 438.408873 -96.177605) (xy 438.353436 -96.183705) (xy 438.297702 -96.181668) (xy 438.242859 -96.171538)
			(xy 438.190075 -96.153531) (xy 438.140475 -96.12803) (xy 438.095117 -96.095579) (xy 438.054968 -96.05687)
			(xy 438.020882 -96.012727) (xy 437.993586 -95.964092) (xy 437.973663 -95.912001) (xy 437.961537 -95.857564)
			(xy 437.957466 -95.801942) (xy 437.704992 -95.801942) (xy 437.704483 -95.829828) (xy 437.696363 -95.885004)
			(xy 437.680295 -95.938411) (xy 437.656623 -95.988908) (xy 437.62585 -96.035421) (xy 437.588633 -96.076958)
			(xy 437.545765 -96.112633) (xy 437.498159 -96.141687) (xy 437.44683 -96.163499) (xy 437.392873 -96.177605)
			(xy 437.337436 -96.183705) (xy 437.281702 -96.181668) (xy 437.226859 -96.171538) (xy 437.174075 -96.153531)
			(xy 437.124475 -96.12803) (xy 437.079117 -96.095579) (xy 437.038968 -96.05687) (xy 437.004882 -96.012727)
			(xy 436.977586 -95.964092) (xy 436.957663 -95.912001) (xy 436.945537 -95.857564) (xy 436.941466 -95.801942)
			(xy 427.184221 -95.801942) (xy 427.184711 -95.802682) (xy 427.208383 -95.853179) (xy 427.224451 -95.906586)
			(xy 427.232571 -95.961762) (xy 427.23308 -95.989648) (xy 427.232571 -96.017534) (xy 427.224451 -96.07271)
			(xy 427.208383 -96.126117) (xy 427.184711 -96.176614) (xy 427.153938 -96.223127) (xy 427.116721 -96.264664)
			(xy 427.073853 -96.300339) (xy 427.026247 -96.329393) (xy 426.974918 -96.351205) (xy 426.920961 -96.365311)
			(xy 426.865524 -96.371411) (xy 426.80979 -96.369374) (xy 426.754947 -96.359244) (xy 426.702163 -96.341237)
			(xy 426.652563 -96.315736) (xy 426.607205 -96.283285) (xy 426.567056 -96.244576) (xy 426.53297 -96.200433)
			(xy 426.505674 -96.151798) (xy 426.485751 -96.099707) (xy 426.473625 -96.04527) (xy 426.469554 -95.989648)
			(xy 424.627548 -95.989648) (xy 424.627039 -96.017534) (xy 424.618919 -96.07271) (xy 424.602851 -96.126117)
			(xy 424.579179 -96.176614) (xy 424.548406 -96.223127) (xy 424.511189 -96.264664) (xy 424.468321 -96.300339)
			(xy 424.420715 -96.329393) (xy 424.369386 -96.351205) (xy 424.315429 -96.365311) (xy 424.259992 -96.371411)
			(xy 424.204258 -96.369374) (xy 424.149415 -96.359244) (xy 424.096631 -96.341237) (xy 424.047031 -96.315736)
			(xy 424.001673 -96.283285) (xy 423.961524 -96.244576) (xy 423.927438 -96.200433) (xy 423.900142 -96.151798)
			(xy 423.880219 -96.099707) (xy 423.868093 -96.04527) (xy 423.864022 -95.989648) (xy 421.741526 -95.989648)
			(xy 421.70877 -96.020761) (xy 421.636218 -96.07857) (xy 421.558923 -96.129864) (xy 421.477468 -96.174258)
			(xy 421.392468 -96.211415) (xy 421.304564 -96.241056) (xy 421.21442 -96.262956) (xy 421.122715 -96.276951)
			(xy 421.030142 -96.282936) (xy 420.937398 -96.280864) (xy 420.845185 -96.270751) (xy 420.754196 -96.252675)
			(xy 420.66512 -96.226771) (xy 420.578628 -96.193234) (xy 420.495372 -96.152318) (xy 420.415981 -96.104331)
			(xy 420.341054 -96.049636) (xy 420.271156 -95.988645) (xy 420.206814 -95.921819) (xy 420.148515 -95.84966)
			(xy 420.096697 -95.772715) (xy 420.051752 -95.691564) (xy 420.014019 -95.606818) (xy 419.983783 -95.519117)
			(xy 419.961271 -95.429124) (xy 419.946654 -95.337516) (xy 419.940042 -95.244985) (xy 419.941485 -95.15223)
			(xy 419.950971 -95.05995) (xy 419.96843 -94.968841) (xy 419.993729 -94.879591) (xy 420.026678 -94.792873)
			(xy 420.046404 -94.75089) (xy 420.051992 -94.739206) (xy 420.050722 -94.713044) (xy 419.99789 -94.629224)
			(xy 419.993012 -94.622126) (xy 419.979555 -94.611397) (xy 419.963315 -94.605695) (xy 419.95471 -94.605348)
			(xy 418.33038 -94.605348) (xy 418.286933 -94.604765) (xy 418.200409 -94.596746) (xy 418.114994 -94.580777)
			(xy 418.031416 -94.556996) (xy 417.95039 -94.525605) (xy 417.872605 -94.486871) (xy 417.798726 -94.441126)
			(xy 417.729383 -94.388759) (xy 417.665168 -94.330218) (xy 417.606628 -94.266001) (xy 417.554263 -94.196657)
			(xy 417.508519 -94.122777) (xy 417.469787 -94.044992) (xy 417.438398 -93.963965) (xy 417.414618 -93.880387)
			(xy 417.398651 -93.794972) (xy 417.390634 -93.708447) (xy 403.307621 -93.708447) (xy 401.578144 -95.438051)
			(xy 405.06726 -95.438051) (xy 405.06726 -95.383549) (xy 405.075016 -95.329602) (xy 405.09037 -95.277308)
			(xy 405.113009 -95.227731) (xy 405.142473 -95.18188) (xy 405.178162 -95.140689) (xy 405.21935 -95.104996)
			(xy 405.265198 -95.075527) (xy 405.314772 -95.052883) (xy 405.367065 -95.037524) (xy 405.421011 -95.029762)
			(xy 405.448262 -95.029274) (xy 405.474997 -95.029709) (xy 405.527944 -95.037171) (xy 405.57933 -95.051955)
			(xy 405.628148 -95.07377) (xy 405.67344 -95.102189) (xy 405.71432 -95.136655) (xy 405.732488 -95.156274)
			(xy 405.740171 -95.164039) (xy 405.760178 -95.172739) (xy 405.771096 -95.173038) (xy 405.85898 -95.171768)
			(xy 405.879046 -95.162116) (xy 405.885904 -95.153734) (xy 405.904148 -95.132833) (xy 405.945595 -95.095957)
			(xy 405.991948 -95.065477) (xy 406.042228 -95.042035) (xy 406.095375 -95.026127) (xy 406.150266 -95.018089)
			(xy 406.178004 -95.01759) (xy 406.178258 -95.01759) (xy 406.205513 -95.018054) (xy 406.259468 -95.025807)
			(xy 406.31177 -95.041159) (xy 406.361356 -95.063799) (xy 406.407214 -95.093266) (xy 406.448411 -95.128959)
			(xy 406.484109 -95.170153) (xy 406.484821 -95.17126) (xy 416.22802 -95.17126) (xy 416.232091 -95.115638)
			(xy 416.244217 -95.061201) (xy 416.26414 -95.00911) (xy 416.291436 -94.960475) (xy 416.325522 -94.916332)
			(xy 416.365671 -94.877623) (xy 416.411029 -94.845172) (xy 416.460629 -94.819671) (xy 416.513413 -94.801664)
			(xy 416.568256 -94.791534) (xy 416.62399 -94.789497) (xy 416.679427 -94.795597) (xy 416.733384 -94.809703)
			(xy 416.784713 -94.831515) (xy 416.832319 -94.860569) (xy 416.875187 -94.896244) (xy 416.912404 -94.937781)
			(xy 416.943177 -94.984294) (xy 416.966849 -95.034791) (xy 416.982917 -95.088198) (xy 416.991037 -95.143374)
			(xy 416.991546 -95.17126) (xy 416.991037 -95.199146) (xy 416.982917 -95.254322) (xy 416.966849 -95.307729)
			(xy 416.943177 -95.358226) (xy 416.912404 -95.404739) (xy 416.875187 -95.446276) (xy 416.832319 -95.481951)
			(xy 416.784713 -95.511005) (xy 416.733384 -95.532817) (xy 416.679427 -95.546923) (xy 416.62399 -95.553023)
			(xy 416.568256 -95.550986) (xy 416.513413 -95.540856) (xy 416.460629 -95.522849) (xy 416.411029 -95.497348)
			(xy 416.365671 -95.464897) (xy 416.325522 -95.426188) (xy 416.291436 -95.382045) (xy 416.26414 -95.33341)
			(xy 416.244217 -95.281319) (xy 416.232091 -95.226882) (xy 416.22802 -95.17126) (xy 406.484821 -95.17126)
			(xy 406.513581 -95.216007) (xy 406.536226 -95.26559) (xy 406.551585 -95.317891) (xy 406.559343 -95.371845)
			(xy 406.559343 -95.426355) (xy 406.551585 -95.480309) (xy 406.536226 -95.53261) (xy 406.513581 -95.582193)
			(xy 406.484109 -95.628047) (xy 406.448411 -95.669241) (xy 406.407214 -95.704934) (xy 406.361356 -95.734401)
			(xy 406.31177 -95.757041) (xy 406.259468 -95.772393) (xy 406.205513 -95.780146) (xy 406.178258 -95.780606)
			(xy 406.151523 -95.780164) (xy 406.098576 -95.772705) (xy 406.04719 -95.757923) (xy 405.998372 -95.736109)
			(xy 405.953079 -95.70769) (xy 405.9122 -95.673225) (xy 405.894032 -95.653606) (xy 405.886344 -95.645847)
			(xy 405.86634 -95.637144) (xy 405.855424 -95.636842) (xy 405.76754 -95.638112) (xy 405.747474 -95.647764)
			(xy 405.740616 -95.656146) (xy 405.722379 -95.677053) (xy 405.680929 -95.713925) (xy 405.634574 -95.744403)
			(xy 405.584292 -95.767843) (xy 405.531145 -95.78375) (xy 405.476254 -95.79179) (xy 405.448516 -95.79229)
			(xy 405.448262 -95.79229) (xy 405.421011 -95.791838) (xy 405.367065 -95.784076) (xy 405.314772 -95.768717)
			(xy 405.265198 -95.746073) (xy 405.21935 -95.716604) (xy 405.178162 -95.680911) (xy 405.142473 -95.63972)
			(xy 405.113009 -95.593869) (xy 405.09037 -95.544292) (xy 405.075016 -95.491998) (xy 405.06726 -95.438051)
			(xy 401.578144 -95.438051) (xy 400.55723 -96.45904) (xy 405.138128 -96.45904) (xy 405.138614 -96.431789)
			(xy 405.14637 -96.377841) (xy 405.161725 -96.325546) (xy 405.184367 -96.275969) (xy 405.213833 -96.230119)
			(xy 405.249524 -96.188928) (xy 405.290715 -96.153237) (xy 405.336565 -96.123771) (xy 405.386142 -96.101129)
			(xy 405.438437 -96.085774) (xy 405.492385 -96.078018) (xy 405.546887 -96.078018) (xy 405.600835 -96.085774)
			(xy 405.65313 -96.101129) (xy 405.702707 -96.123771) (xy 405.748557 -96.153237) (xy 405.789748 -96.188928)
			(xy 405.825439 -96.230119) (xy 405.854905 -96.275969) (xy 405.877547 -96.325546) (xy 405.892902 -96.377841)
			(xy 405.900307 -96.429346) (xy 415.757422 -96.429346) (xy 415.757422 -96.374854) (xy 415.765177 -96.320916)
			(xy 415.780528 -96.26863) (xy 415.803164 -96.219062) (xy 415.832623 -96.173218) (xy 415.868306 -96.132034)
			(xy 415.909486 -96.096347) (xy 415.955326 -96.066883) (xy 416.004893 -96.044242) (xy 416.057177 -96.028885)
			(xy 416.111114 -96.021125) (xy 416.13836 -96.020636) (xy 416.167179 -96.021157) (xy 416.224159 -96.029847)
			(xy 416.279184 -96.047006) (xy 416.331003 -96.072244) (xy 416.378439 -96.104986) (xy 416.420412 -96.144489)
			(xy 416.455968 -96.189853) (xy 416.470592 -96.214692) (xy 416.47853 -96.227544) (xy 416.500395 -96.248359)
			(xy 416.527391 -96.261871) (xy 416.557157 -96.266901) (xy 416.587093 -96.263007) (xy 416.614583 -96.250532)
			(xy 416.637224 -96.230564) (xy 416.645598 -96.217994) (xy 416.660612 -96.194657) (xy 416.696287 -96.152155)
			(xy 416.737744 -96.115272) (xy 416.784109 -96.084786) (xy 416.834402 -96.06134) (xy 416.887561 -96.04543)
			(xy 416.942465 -96.03739) (xy 416.97021 -96.036892) (xy 416.997461 -96.037378) (xy 417.051407 -96.045136)
			(xy 417.103701 -96.060492) (xy 417.153277 -96.083134) (xy 417.199126 -96.1126) (xy 417.240315 -96.148292)
			(xy 417.276006 -96.189482) (xy 417.305471 -96.235332) (xy 417.328111 -96.284908) (xy 417.343466 -96.337202)
			(xy 417.348895 -96.374966) (xy 442.727078 -96.374966) (xy 442.731149 -96.319344) (xy 442.743275 -96.264907)
			(xy 442.763198 -96.212816) (xy 442.790494 -96.164181) (xy 442.82458 -96.120038) (xy 442.864729 -96.081329)
			(xy 442.910087 -96.048878) (xy 442.959687 -96.023377) (xy 443.012471 -96.00537) (xy 443.067314 -95.99524)
			(xy 443.123048 -95.993203) (xy 443.178485 -95.999303) (xy 443.232442 -96.013409) (xy 443.283771 -96.035221)
			(xy 443.331377 -96.064275) (xy 443.374245 -96.09995) (xy 443.411462 -96.141487) (xy 443.442235 -96.188)
			(xy 443.465907 -96.238497) (xy 443.480906 -96.288352) (xy 444.152272 -96.288352) (xy 444.156343 -96.23273)
			(xy 444.168469 -96.178293) (xy 444.188392 -96.126202) (xy 444.215688 -96.077567) (xy 444.249774 -96.033424)
			(xy 444.289923 -95.994715) (xy 444.335281 -95.962264) (xy 444.384881 -95.936763) (xy 444.437665 -95.918756)
			(xy 444.492508 -95.908626) (xy 444.548242 -95.906589) (xy 444.603679 -95.912689) (xy 444.657636 -95.926795)
			(xy 444.708965 -95.948607) (xy 444.756571 -95.977661) (xy 444.799439 -96.013336) (xy 444.836656 -96.054873)
			(xy 444.867429 -96.101386) (xy 444.891101 -96.151883) (xy 444.907169 -96.20529) (xy 444.915289 -96.260466)
			(xy 444.91552 -96.273112) (xy 445.497964 -96.273112) (xy 445.502035 -96.21749) (xy 445.514161 -96.163053)
			(xy 445.534084 -96.110962) (xy 445.56138 -96.062327) (xy 445.595466 -96.018184) (xy 445.635615 -95.979475)
			(xy 445.680973 -95.947024) (xy 445.730573 -95.921523) (xy 445.783357 -95.903516) (xy 445.8382 -95.893386)
			(xy 445.893934 -95.891349) (xy 445.949371 -95.897449) (xy 446.003328 -95.911555) (xy 446.054657 -95.933367)
			(xy 446.102263 -95.962421) (xy 446.145131 -95.998096) (xy 446.182348 -96.039633) (xy 446.213121 -96.086146)
			(xy 446.236793 -96.136643) (xy 446.252861 -96.19005) (xy 446.260981 -96.245226) (xy 446.26149 -96.273112)
			(xy 446.260981 -96.300998) (xy 446.252861 -96.356174) (xy 446.236793 -96.409581) (xy 446.23373 -96.416114)
			(xy 448.05422 -96.416114) (xy 448.058291 -96.360492) (xy 448.070417 -96.306055) (xy 448.09034 -96.253964)
			(xy 448.117636 -96.205329) (xy 448.151722 -96.161186) (xy 448.191871 -96.122477) (xy 448.237229 -96.090026)
			(xy 448.286829 -96.064525) (xy 448.339613 -96.046518) (xy 448.394456 -96.036388) (xy 448.45019 -96.034351)
			(xy 448.505627 -96.040451) (xy 448.559584 -96.054557) (xy 448.610913 -96.076369) (xy 448.658519 -96.105423)
			(xy 448.701387 -96.141098) (xy 448.738604 -96.182635) (xy 448.769377 -96.229148) (xy 448.793049 -96.279645)
			(xy 448.809117 -96.333052) (xy 448.817237 -96.388228) (xy 448.817746 -96.416114) (xy 448.817237 -96.444)
			(xy 448.809117 -96.499176) (xy 448.793049 -96.552583) (xy 448.769377 -96.60308) (xy 448.738604 -96.649593)
			(xy 448.701387 -96.69113) (xy 448.658519 -96.726805) (xy 448.610913 -96.755859) (xy 448.559584 -96.777671)
			(xy 448.505627 -96.791777) (xy 448.45019 -96.797877) (xy 448.394456 -96.79584) (xy 448.339613 -96.78571)
			(xy 448.286829 -96.767703) (xy 448.237229 -96.742202) (xy 448.191871 -96.709751) (xy 448.151722 -96.671042)
			(xy 448.117636 -96.626899) (xy 448.09034 -96.578264) (xy 448.070417 -96.526173) (xy 448.058291 -96.471736)
			(xy 448.05422 -96.416114) (xy 446.23373 -96.416114) (xy 446.213121 -96.460078) (xy 446.182348 -96.506591)
			(xy 446.145131 -96.548128) (xy 446.102263 -96.583803) (xy 446.054657 -96.612857) (xy 446.003328 -96.634669)
			(xy 445.949371 -96.648775) (xy 445.893934 -96.654875) (xy 445.8382 -96.652838) (xy 445.783357 -96.642708)
			(xy 445.730573 -96.624701) (xy 445.680973 -96.5992) (xy 445.635615 -96.566749) (xy 445.595466 -96.52804)
			(xy 445.56138 -96.483897) (xy 445.534084 -96.435262) (xy 445.514161 -96.383171) (xy 445.502035 -96.328734)
			(xy 445.497964 -96.273112) (xy 444.91552 -96.273112) (xy 444.915798 -96.288352) (xy 444.915289 -96.316238)
			(xy 444.907169 -96.371414) (xy 444.891101 -96.424821) (xy 444.867429 -96.475318) (xy 444.836656 -96.521831)
			(xy 444.799439 -96.563368) (xy 444.756571 -96.599043) (xy 444.708965 -96.628097) (xy 444.657636 -96.649909)
			(xy 444.603679 -96.664015) (xy 444.548242 -96.670115) (xy 444.492508 -96.668078) (xy 444.437665 -96.657948)
			(xy 444.384881 -96.639941) (xy 444.335281 -96.61444) (xy 444.289923 -96.581989) (xy 444.249774 -96.54328)
			(xy 444.215688 -96.499137) (xy 444.188392 -96.450502) (xy 444.168469 -96.398411) (xy 444.156343 -96.343974)
			(xy 444.152272 -96.288352) (xy 443.480906 -96.288352) (xy 443.481975 -96.291904) (xy 443.490095 -96.34708)
			(xy 443.490604 -96.374966) (xy 443.490095 -96.402852) (xy 443.481975 -96.458028) (xy 443.465907 -96.511435)
			(xy 443.442235 -96.561932) (xy 443.411462 -96.608445) (xy 443.374245 -96.649982) (xy 443.331377 -96.685657)
			(xy 443.283771 -96.714711) (xy 443.232442 -96.736523) (xy 443.178485 -96.750629) (xy 443.123048 -96.756729)
			(xy 443.067314 -96.754692) (xy 443.012471 -96.744562) (xy 442.959687 -96.726555) (xy 442.910087 -96.701054)
			(xy 442.864729 -96.668603) (xy 442.82458 -96.629894) (xy 442.790494 -96.585751) (xy 442.763198 -96.537116)
			(xy 442.743275 -96.485025) (xy 442.731149 -96.430588) (xy 442.727078 -96.374966) (xy 417.348895 -96.374966)
			(xy 417.351222 -96.391149) (xy 417.351222 -96.445651) (xy 417.343466 -96.499598) (xy 417.328111 -96.551892)
			(xy 417.305471 -96.601468) (xy 417.276006 -96.647318) (xy 417.240315 -96.688508) (xy 417.199126 -96.7242)
			(xy 417.153277 -96.753666) (xy 417.103701 -96.776308) (xy 417.051407 -96.791664) (xy 416.997461 -96.799422)
			(xy 416.97021 -96.799908) (xy 416.941392 -96.79936) (xy 416.884412 -96.790679) (xy 416.829386 -96.773526)
			(xy 416.777566 -96.748294) (xy 416.730129 -96.715555) (xy 416.688156 -96.676054) (xy 416.652601 -96.630691)
			(xy 416.637978 -96.605852) (xy 416.630083 -96.592969) (xy 416.608212 -96.572143) (xy 416.581206 -96.558625)
			(xy 416.551428 -96.553597) (xy 416.521481 -96.557497) (xy 416.493985 -96.569986) (xy 416.471343 -96.589971)
			(xy 416.462972 -96.60255) (xy 416.447994 -96.625911) (xy 416.412311 -96.66841) (xy 416.370847 -96.70529)
			(xy 416.324476 -96.735773) (xy 416.274178 -96.759214) (xy 416.221014 -96.775121) (xy 416.166106 -96.783156)
			(xy 416.13836 -96.783652) (xy 416.111114 -96.783075) (xy 416.057177 -96.775315) (xy 416.004893 -96.759958)
			(xy 415.955326 -96.737317) (xy 415.909486 -96.707853) (xy 415.868306 -96.672166) (xy 415.832623 -96.630982)
			(xy 415.803164 -96.585138) (xy 415.780528 -96.53557) (xy 415.765177 -96.483284) (xy 415.757422 -96.429346)
			(xy 405.900307 -96.429346) (xy 405.900658 -96.431789) (xy 405.901144 -96.45904) (xy 405.900686 -96.48542)
			(xy 405.893422 -96.537679) (xy 405.879025 -96.588437) (xy 405.85777 -96.636727) (xy 405.830062 -96.681626)
			(xy 405.796431 -96.722278) (xy 405.757517 -96.757907) (xy 405.736044 -96.773238) (xy 405.724042 -96.782069)
			(xy 405.7054 -96.805302) (xy 405.694256 -96.832926) (xy 405.69156 -96.86259) (xy 405.697541 -96.89177)
			(xy 405.702523 -96.901) (xy 417.621972 -96.901) (xy 417.626043 -96.845378) (xy 417.638169 -96.790941)
			(xy 417.658092 -96.73885) (xy 417.685388 -96.690215) (xy 417.719474 -96.646072) (xy 417.759623 -96.607363)
			(xy 417.804981 -96.574912) (xy 417.854581 -96.549411) (xy 417.907365 -96.531404) (xy 417.962208 -96.521274)
			(xy 418.017942 -96.519237) (xy 418.073379 -96.525337) (xy 418.127336 -96.539443) (xy 418.178665 -96.561255)
			(xy 418.226271 -96.590309) (xy 418.269139 -96.625984) (xy 418.306356 -96.667521) (xy 418.337129 -96.714034)
			(xy 418.360801 -96.764531) (xy 418.376869 -96.817938) (xy 418.384989 -96.873114) (xy 418.385498 -96.901)
			(xy 420.073072 -96.901) (xy 420.077143 -96.845378) (xy 420.089269 -96.790941) (xy 420.109192 -96.73885)
			(xy 420.136488 -96.690215) (xy 420.170574 -96.646072) (xy 420.210723 -96.607363) (xy 420.256081 -96.574912)
			(xy 420.305681 -96.549411) (xy 420.358465 -96.531404) (xy 420.413308 -96.521274) (xy 420.469042 -96.519237)
			(xy 420.524479 -96.525337) (xy 420.578436 -96.539443) (xy 420.629765 -96.561255) (xy 420.677371 -96.590309)
			(xy 420.720239 -96.625984) (xy 420.757456 -96.667521) (xy 420.788229 -96.714034) (xy 420.811901 -96.764531)
			(xy 420.827969 -96.817938) (xy 420.836089 -96.873114) (xy 420.836598 -96.901) (xy 420.836089 -96.928886)
			(xy 420.827969 -96.984062) (xy 420.811901 -97.037469) (xy 420.810744 -97.039938) (xy 423.025568 -97.039938)
			(xy 423.029639 -96.984316) (xy 423.041765 -96.929879) (xy 423.061688 -96.877788) (xy 423.088984 -96.829153)
			(xy 423.12307 -96.78501) (xy 423.163219 -96.746301) (xy 423.208577 -96.71385) (xy 423.258177 -96.688349)
			(xy 423.310961 -96.670342) (xy 423.365804 -96.660212) (xy 423.421538 -96.658175) (xy 423.476975 -96.664275)
			(xy 423.530932 -96.678381) (xy 423.582261 -96.700193) (xy 423.629867 -96.729247) (xy 423.672735 -96.764922)
			(xy 423.709952 -96.806459) (xy 423.740725 -96.852972) (xy 423.764397 -96.903469) (xy 423.780465 -96.956876)
			(xy 423.787643 -97.005648) (xy 426.469554 -97.005648) (xy 426.473625 -96.950026) (xy 426.485751 -96.895589)
			(xy 426.505674 -96.843498) (xy 426.53297 -96.794863) (xy 426.567056 -96.75072) (xy 426.607205 -96.712011)
			(xy 426.652563 -96.67956) (xy 426.702163 -96.654059) (xy 426.754947 -96.636052) (xy 426.80979 -96.625922)
			(xy 426.865524 -96.623885) (xy 426.920961 -96.629985) (xy 426.974918 -96.644091) (xy 427.026247 -96.665903)
			(xy 427.073853 -96.694957) (xy 427.116721 -96.730632) (xy 427.153938 -96.772169) (xy 427.184711 -96.818682)
			(xy 427.208383 -96.869179) (xy 427.224451 -96.922586) (xy 427.232571 -96.977762) (xy 427.23308 -97.005648)
			(xy 427.232571 -97.033534) (xy 427.224451 -97.08871) (xy 427.208383 -97.142117) (xy 427.184711 -97.192614)
			(xy 427.153938 -97.239127) (xy 427.116721 -97.280664) (xy 427.073853 -97.316339) (xy 427.026247 -97.345393)
			(xy 426.974918 -97.367205) (xy 426.920961 -97.381311) (xy 426.865524 -97.387411) (xy 426.80979 -97.385374)
			(xy 426.754947 -97.375244) (xy 426.702163 -97.357237) (xy 426.652563 -97.331736) (xy 426.607205 -97.299285)
			(xy 426.567056 -97.260576) (xy 426.53297 -97.216433) (xy 426.505674 -97.167798) (xy 426.485751 -97.115707)
			(xy 426.473625 -97.06127) (xy 426.469554 -97.005648) (xy 423.787643 -97.005648) (xy 423.788585 -97.012052)
			(xy 423.789094 -97.039938) (xy 423.788585 -97.067824) (xy 423.780465 -97.123) (xy 423.764397 -97.176407)
			(xy 423.740725 -97.226904) (xy 423.709952 -97.273417) (xy 423.672735 -97.314954) (xy 423.629867 -97.350629)
			(xy 423.582261 -97.379683) (xy 423.530932 -97.401495) (xy 423.476975 -97.415601) (xy 423.421538 -97.421701)
			(xy 423.365804 -97.419664) (xy 423.310961 -97.409534) (xy 423.258177 -97.391527) (xy 423.208577 -97.366026)
			(xy 423.163219 -97.333575) (xy 423.12307 -97.294866) (xy 423.088984 -97.250723) (xy 423.061688 -97.202088)
			(xy 423.041765 -97.149997) (xy 423.029639 -97.09556) (xy 423.025568 -97.039938) (xy 420.810744 -97.039938)
			(xy 420.788229 -97.087966) (xy 420.757456 -97.134479) (xy 420.720239 -97.176016) (xy 420.677371 -97.211691)
			(xy 420.629765 -97.240745) (xy 420.578436 -97.262557) (xy 420.524479 -97.276663) (xy 420.469042 -97.282763)
			(xy 420.413308 -97.280726) (xy 420.358465 -97.270596) (xy 420.305681 -97.252589) (xy 420.256081 -97.227088)
			(xy 420.210723 -97.194637) (xy 420.170574 -97.155928) (xy 420.136488 -97.111785) (xy 420.109192 -97.06315)
			(xy 420.089269 -97.011059) (xy 420.077143 -96.956622) (xy 420.073072 -96.901) (xy 418.385498 -96.901)
			(xy 418.384989 -96.928886) (xy 418.376869 -96.984062) (xy 418.360801 -97.037469) (xy 418.337129 -97.087966)
			(xy 418.306356 -97.134479) (xy 418.269139 -97.176016) (xy 418.226271 -97.211691) (xy 418.178665 -97.240745)
			(xy 418.127336 -97.262557) (xy 418.073379 -97.276663) (xy 418.017942 -97.282763) (xy 417.962208 -97.280726)
			(xy 417.907365 -97.270596) (xy 417.854581 -97.252589) (xy 417.804981 -97.227088) (xy 417.759623 -97.194637)
			(xy 417.719474 -97.155928) (xy 417.685388 -97.111785) (xy 417.658092 -97.06315) (xy 417.638169 -97.011059)
			(xy 417.626043 -96.956622) (xy 417.621972 -96.901) (xy 405.702523 -96.901) (xy 405.711689 -96.917983)
			(xy 405.732801 -96.938996) (xy 405.745696 -96.946466) (xy 405.771353 -96.960855) (xy 405.818304 -96.99629)
			(xy 405.859261 -97.03851) (xy 405.893254 -97.086516) (xy 405.919476 -97.13917) (xy 405.937308 -97.195224)
			(xy 405.946325 -97.253351) (xy 405.946864 -97.282762) (xy 405.946378 -97.310013) (xy 405.938622 -97.363961)
			(xy 405.923267 -97.416256) (xy 405.900625 -97.465833) (xy 405.871159 -97.511683) (xy 405.835468 -97.552874)
			(xy 405.794277 -97.588565) (xy 405.748427 -97.618031) (xy 405.700017 -97.64014) (xy 422.218102 -97.64014)
			(xy 422.222173 -97.584518) (xy 422.234299 -97.530081) (xy 422.254222 -97.47799) (xy 422.281518 -97.429355)
			(xy 422.315604 -97.385212) (xy 422.355753 -97.346503) (xy 422.401111 -97.314052) (xy 422.450711 -97.288551)
			(xy 422.503495 -97.270544) (xy 422.558338 -97.260414) (xy 422.614072 -97.258377) (xy 422.669509 -97.264477)
			(xy 422.723466 -97.278583) (xy 422.774795 -97.300395) (xy 422.822401 -97.329449) (xy 422.865269 -97.365124)
			(xy 422.902486 -97.406661) (xy 422.933259 -97.453174) (xy 422.956931 -97.503671) (xy 422.972999 -97.557078)
			(xy 422.981119 -97.612254) (xy 422.981628 -97.64014) (xy 422.981119 -97.668026) (xy 422.972999 -97.723202)
			(xy 422.956931 -97.776609) (xy 422.933259 -97.827106) (xy 422.902486 -97.873619) (xy 422.865269 -97.915156)
			(xy 422.822401 -97.950831) (xy 422.774795 -97.979885) (xy 422.723466 -98.001697) (xy 422.669509 -98.015803)
			(xy 422.614072 -98.021903) (xy 422.558338 -98.019866) (xy 422.503495 -98.009736) (xy 422.450711 -97.991729)
			(xy 422.401111 -97.966228) (xy 422.355753 -97.933777) (xy 422.315604 -97.895068) (xy 422.281518 -97.850925)
			(xy 422.254222 -97.80229) (xy 422.234299 -97.750199) (xy 422.222173 -97.695762) (xy 422.218102 -97.64014)
			(xy 405.700017 -97.64014) (xy 405.69885 -97.640673) (xy 405.646555 -97.656028) (xy 405.592607 -97.663784)
			(xy 405.538105 -97.663784) (xy 405.484157 -97.656028) (xy 405.431862 -97.640673) (xy 405.382285 -97.618031)
			(xy 405.336435 -97.588565) (xy 405.295244 -97.552874) (xy 405.259553 -97.511683) (xy 405.230087 -97.465833)
			(xy 405.207445 -97.416256) (xy 405.19209 -97.363961) (xy 405.184334 -97.310013) (xy 405.183848 -97.282762)
			(xy 405.184311 -97.256382) (xy 405.191575 -97.204124) (xy 405.205971 -97.153366) (xy 405.227225 -97.105076)
			(xy 405.254932 -97.060177) (xy 405.288563 -97.019524) (xy 405.327475 -96.983895) (xy 405.348948 -96.968564)
			(xy 405.36095 -96.959731) (xy 405.379593 -96.9365) (xy 405.390738 -96.908876) (xy 405.393434 -96.879211)
			(xy 405.387453 -96.85003) (xy 405.373304 -96.823818) (xy 405.352191 -96.802806) (xy 405.339296 -96.795336)
			(xy 405.313638 -96.780948) (xy 405.266688 -96.745513) (xy 405.225731 -96.703292) (xy 405.191739 -96.655286)
			(xy 405.165516 -96.602632) (xy 405.147685 -96.546578) (xy 405.138667 -96.488451) (xy 405.138128 -96.45904)
			(xy 400.55723 -96.45904) (xy 400.453098 -96.56318) (xy 400.445236 -96.571913) (xy 400.43769 -96.594139)
			(xy 400.43862 -96.605852) (xy 400.45132 -96.6978) (xy 400.464528 -96.717612) (xy 400.474942 -96.723454)
			(xy 400.499818 -96.738021) (xy 400.545194 -96.773575) (xy 400.584703 -96.815553) (xy 400.617445 -96.862999)
			(xy 400.642673 -96.914832) (xy 400.659814 -96.969871) (xy 400.668476 -97.026863) (xy 400.668998 -97.055686)
			(xy 400.668532 -97.082939) (xy 400.660776 -97.13689) (xy 400.645422 -97.189189) (xy 400.62278 -97.238769)
			(xy 400.593312 -97.284623) (xy 400.557619 -97.325816) (xy 400.516426 -97.36151) (xy 400.470573 -97.390978)
			(xy 400.420992 -97.41362) (xy 400.368694 -97.428975) (xy 400.314743 -97.436731) (xy 400.28749 -97.437194)
			(xy 400.258671 -97.436669) (xy 400.20169 -97.427984) (xy 400.146663 -97.410829) (xy 400.094842 -97.385592)
			(xy 400.047406 -97.35285) (xy 400.005434 -97.313346) (xy 399.96988 -97.267978) (xy 399.955258 -97.243138)
			(xy 399.948903 -97.233269) (xy 399.929455 -97.220168) (xy 399.91792 -97.217992) (xy 399.837656 -97.206816)
			(xy 399.825933 -97.205816) (xy 399.803682 -97.213371) (xy 399.794984 -97.221294) (xy 398.845278 -98.171)
			(xy 423.864022 -98.171) (xy 423.868093 -98.115378) (xy 423.880219 -98.060941) (xy 423.900142 -98.00885)
			(xy 423.927438 -97.960215) (xy 423.961524 -97.916072) (xy 424.001673 -97.877363) (xy 424.047031 -97.844912)
			(xy 424.096631 -97.819411) (xy 424.149415 -97.801404) (xy 424.204258 -97.791274) (xy 424.259992 -97.789237)
			(xy 424.315429 -97.795337) (xy 424.369386 -97.809443) (xy 424.420715 -97.831255) (xy 424.468321 -97.860309)
			(xy 424.511189 -97.895984) (xy 424.548406 -97.937521) (xy 424.579179 -97.984034) (xy 424.596812 -98.021648)
			(xy 426.469554 -98.021648) (xy 426.473625 -97.966026) (xy 426.485751 -97.911589) (xy 426.505674 -97.859498)
			(xy 426.53297 -97.810863) (xy 426.567056 -97.76672) (xy 426.607205 -97.728011) (xy 426.652563 -97.69556)
			(xy 426.702163 -97.670059) (xy 426.754947 -97.652052) (xy 426.80979 -97.641922) (xy 426.865524 -97.639885)
			(xy 426.920961 -97.645985) (xy 426.974918 -97.660091) (xy 427.026247 -97.681903) (xy 427.073853 -97.710957)
			(xy 427.116721 -97.746632) (xy 427.153938 -97.788169) (xy 427.184711 -97.834682) (xy 427.208383 -97.885179)
			(xy 427.224451 -97.938586) (xy 427.226657 -97.953576) (xy 436.643016 -97.953576) (xy 436.647087 -97.897954)
			(xy 436.659213 -97.843517) (xy 436.679136 -97.791426) (xy 436.706432 -97.742791) (xy 436.740518 -97.698648)
			(xy 436.780667 -97.659939) (xy 436.826025 -97.627488) (xy 436.875625 -97.601987) (xy 436.928409 -97.58398)
			(xy 436.983252 -97.57385) (xy 437.038986 -97.571813) (xy 437.094423 -97.577913) (xy 437.14838 -97.592019)
			(xy 437.199709 -97.613831) (xy 437.247315 -97.642885) (xy 437.290183 -97.67856) (xy 437.3274 -97.720097)
			(xy 437.358173 -97.76661) (xy 437.381845 -97.817107) (xy 437.383089 -97.821242) (xy 437.957466 -97.821242)
			(xy 437.961537 -97.76562) (xy 437.973663 -97.711183) (xy 437.993586 -97.659092) (xy 438.020882 -97.610457)
			(xy 438.054968 -97.566314) (xy 438.095117 -97.527605) (xy 438.140475 -97.495154) (xy 438.190075 -97.469653)
			(xy 438.242859 -97.451646) (xy 438.297702 -97.441516) (xy 438.353436 -97.439479) (xy 438.408873 -97.445579)
			(xy 438.46283 -97.459685) (xy 438.514159 -97.481497) (xy 438.561765 -97.510551) (xy 438.604633 -97.546226)
			(xy 438.64185 -97.587763) (xy 438.672623 -97.634276) (xy 438.696295 -97.684773) (xy 438.712363 -97.73818)
			(xy 438.720483 -97.793356) (xy 438.720992 -97.821242) (xy 438.720495 -97.848447) (xy 439.22852 -97.848447)
			(xy 439.22852 -97.793953) (xy 439.236275 -97.740012) (xy 439.251628 -97.687725) (xy 439.274265 -97.638154)
			(xy 439.303727 -97.592309) (xy 439.339413 -97.551124) (xy 439.380597 -97.515437) (xy 439.42644 -97.485973)
			(xy 439.47601 -97.463334) (xy 439.528297 -97.447979) (xy 439.582237 -97.440221) (xy 439.609484 -97.439734)
			(xy 439.638401 -97.440251) (xy 439.695573 -97.448978) (xy 439.750772 -97.466236) (xy 439.802734 -97.491628)
			(xy 439.850268 -97.524572) (xy 439.892284 -97.564314) (xy 439.910474 -97.5868) (xy 439.918102 -97.595585)
			(xy 439.938987 -97.605781) (xy 439.950606 -97.606358) (xy 440.030362 -97.606358) (xy 440.041999 -97.605855)
			(xy 440.062909 -97.595642) (xy 440.070494 -97.5868) (xy 440.088688 -97.564319) (xy 440.130707 -97.524584)
			(xy 440.178242 -97.491645) (xy 440.230202 -97.466256) (xy 440.285399 -97.448999) (xy 440.342568 -97.440269)
			(xy 440.371484 -97.439734) (xy 440.398741 -97.440112) (xy 440.452699 -97.447868) (xy 440.505005 -97.463224)
			(xy 440.554593 -97.485868) (xy 440.600453 -97.515339) (xy 440.641652 -97.551037) (xy 440.677351 -97.592234)
			(xy 440.706824 -97.638093) (xy 440.72947 -97.68768) (xy 440.744829 -97.739985) (xy 440.752587 -97.793943)
			(xy 440.752587 -97.821242) (xy 441.005466 -97.821242) (xy 441.009537 -97.76562) (xy 441.021663 -97.711183)
			(xy 441.041586 -97.659092) (xy 441.068882 -97.610457) (xy 441.102968 -97.566314) (xy 441.143117 -97.527605)
			(xy 441.188475 -97.495154) (xy 441.238075 -97.469653) (xy 441.290859 -97.451646) (xy 441.345702 -97.441516)
			(xy 441.401436 -97.439479) (xy 441.456873 -97.445579) (xy 441.51083 -97.459685) (xy 441.562159 -97.481497)
			(xy 441.609765 -97.510551) (xy 441.629968 -97.527364) (xy 442.639702 -97.527364) (xy 442.643773 -97.471742)
			(xy 442.655899 -97.417305) (xy 442.675822 -97.365214) (xy 442.703118 -97.316579) (xy 442.737204 -97.272436)
			(xy 442.777353 -97.233727) (xy 442.822711 -97.201276) (xy 442.872311 -97.175775) (xy 442.925095 -97.157768)
			(xy 442.979938 -97.147638) (xy 443.035672 -97.145601) (xy 443.091109 -97.151701) (xy 443.145066 -97.165807)
			(xy 443.196395 -97.187619) (xy 443.244001 -97.216673) (xy 443.286869 -97.252348) (xy 443.324086 -97.293885)
			(xy 443.354859 -97.340398) (xy 443.378531 -97.390895) (xy 443.394599 -97.444302) (xy 443.402719 -97.499478)
			(xy 443.403228 -97.527364) (xy 443.402719 -97.55525) (xy 443.394599 -97.610426) (xy 443.378531 -97.663833)
			(xy 443.354859 -97.71433) (xy 443.324086 -97.760843) (xy 443.286869 -97.80238) (xy 443.252606 -97.830894)
			(xy 443.498476 -97.830894) (xy 443.502547 -97.775272) (xy 443.514673 -97.720835) (xy 443.534596 -97.668744)
			(xy 443.561892 -97.620109) (xy 443.595978 -97.575966) (xy 443.636127 -97.537257) (xy 443.681485 -97.504806)
			(xy 443.731085 -97.479305) (xy 443.783869 -97.461298) (xy 443.838712 -97.451168) (xy 443.894446 -97.449131)
			(xy 443.949883 -97.455231) (xy 444.00384 -97.469337) (xy 444.055169 -97.491149) (xy 444.102775 -97.520203)
			(xy 444.145643 -97.555878) (xy 444.18286 -97.597415) (xy 444.213633 -97.643928) (xy 444.237305 -97.694425)
			(xy 444.253373 -97.747832) (xy 444.261493 -97.803008) (xy 444.262002 -97.830894) (xy 444.261493 -97.85878)
			(xy 444.253373 -97.913956) (xy 444.237305 -97.967363) (xy 444.213633 -98.01786) (xy 444.18286 -98.064373)
			(xy 444.145643 -98.10591) (xy 444.102775 -98.141585) (xy 444.055169 -98.170639) (xy 444.00384 -98.192451)
			(xy 443.949883 -98.206557) (xy 443.894446 -98.212657) (xy 443.838712 -98.21062) (xy 443.783869 -98.20049)
			(xy 443.731085 -98.182483) (xy 443.681485 -98.156982) (xy 443.636127 -98.124531) (xy 443.595978 -98.085822)
			(xy 443.561892 -98.041679) (xy 443.534596 -97.993044) (xy 443.514673 -97.940953) (xy 443.502547 -97.886516)
			(xy 443.498476 -97.830894) (xy 443.252606 -97.830894) (xy 443.244001 -97.838055) (xy 443.196395 -97.867109)
			(xy 443.145066 -97.888921) (xy 443.091109 -97.903027) (xy 443.035672 -97.909127) (xy 442.979938 -97.90709)
			(xy 442.925095 -97.89696) (xy 442.872311 -97.878953) (xy 442.822711 -97.853452) (xy 442.777353 -97.821001)
			(xy 442.737204 -97.782292) (xy 442.703118 -97.738149) (xy 442.675822 -97.689514) (xy 442.655899 -97.637423)
			(xy 442.643773 -97.582986) (xy 442.639702 -97.527364) (xy 441.629968 -97.527364) (xy 441.652633 -97.546226)
			(xy 441.68985 -97.587763) (xy 441.720623 -97.634276) (xy 441.744295 -97.684773) (xy 441.760363 -97.73818)
			(xy 441.768483 -97.793356) (xy 441.768992 -97.821242) (xy 441.768483 -97.849128) (xy 441.760363 -97.904304)
			(xy 441.744295 -97.957711) (xy 441.720623 -98.008208) (xy 441.68985 -98.054721) (xy 441.652633 -98.096258)
			(xy 441.609765 -98.131933) (xy 441.562159 -98.160987) (xy 441.51083 -98.182799) (xy 441.456873 -98.196905)
			(xy 441.401436 -98.203005) (xy 441.345702 -98.200968) (xy 441.290859 -98.190838) (xy 441.238075 -98.172831)
			(xy 441.188475 -98.14733) (xy 441.143117 -98.114879) (xy 441.102968 -98.07617) (xy 441.068882 -98.032027)
			(xy 441.041586 -97.983392) (xy 441.021663 -97.931301) (xy 441.009537 -97.876864) (xy 441.005466 -97.821242)
			(xy 440.752587 -97.821242) (xy 440.752587 -97.848457) (xy 440.744829 -97.902415) (xy 440.72947 -97.95472)
			(xy 440.706824 -98.004307) (xy 440.677351 -98.050166) (xy 440.641652 -98.091363) (xy 440.600453 -98.127061)
			(xy 440.554593 -98.156532) (xy 440.505005 -98.179176) (xy 440.452699 -98.194532) (xy 440.398741 -98.202288)
			(xy 440.371484 -98.20275) (xy 440.342568 -98.20219) (xy 440.285398 -98.193472) (xy 440.2302 -98.176224)
			(xy 440.178237 -98.15084) (xy 440.130702 -98.117903) (xy 440.088685 -98.078167) (xy 440.070494 -98.055684)
			(xy 440.062883 -98.046881) (xy 440.041985 -98.036696) (xy 440.030362 -98.036126) (xy 439.950606 -98.036126)
			(xy 439.938975 -98.036674) (xy 439.918065 -98.046856) (xy 439.910474 -98.055684) (xy 439.892294 -98.078177)
			(xy 439.850272 -98.117912) (xy 439.802735 -98.15085) (xy 439.750772 -98.176237) (xy 439.695572 -98.193491)
			(xy 439.638401 -98.202217) (xy 439.609484 -98.20275) (xy 439.582237 -98.202179) (xy 439.528297 -98.194421)
			(xy 439.47601 -98.179066) (xy 439.42644 -98.156427) (xy 439.380597 -98.126963) (xy 439.339413 -98.091276)
			(xy 439.303727 -98.050091) (xy 439.274265 -98.004246) (xy 439.251628 -97.954675) (xy 439.236275 -97.902388)
			(xy 439.22852 -97.848447) (xy 438.720495 -97.848447) (xy 438.720483 -97.849128) (xy 438.712363 -97.904304)
			(xy 438.696295 -97.957711) (xy 438.672623 -98.008208) (xy 438.64185 -98.054721) (xy 438.604633 -98.096258)
			(xy 438.561765 -98.131933) (xy 438.514159 -98.160987) (xy 438.46283 -98.182799) (xy 438.408873 -98.196905)
			(xy 438.353436 -98.203005) (xy 438.297702 -98.200968) (xy 438.242859 -98.190838) (xy 438.190075 -98.172831)
			(xy 438.140475 -98.14733) (xy 438.095117 -98.114879) (xy 438.054968 -98.07617) (xy 438.020882 -98.032027)
			(xy 437.993586 -97.983392) (xy 437.973663 -97.931301) (xy 437.961537 -97.876864) (xy 437.957466 -97.821242)
			(xy 437.383089 -97.821242) (xy 437.397913 -97.870514) (xy 437.406033 -97.92569) (xy 437.406542 -97.953576)
			(xy 437.406033 -97.981462) (xy 437.397913 -98.036638) (xy 437.381845 -98.090045) (xy 437.358173 -98.140542)
			(xy 437.3274 -98.187055) (xy 437.290183 -98.228592) (xy 437.247315 -98.264267) (xy 437.199709 -98.293321)
			(xy 437.14838 -98.315133) (xy 437.094423 -98.329239) (xy 437.038986 -98.335339) (xy 436.983252 -98.333302)
			(xy 436.928409 -98.323172) (xy 436.875625 -98.305165) (xy 436.826025 -98.279664) (xy 436.780667 -98.247213)
			(xy 436.740518 -98.208504) (xy 436.706432 -98.164361) (xy 436.679136 -98.115726) (xy 436.659213 -98.063635)
			(xy 436.647087 -98.009198) (xy 436.643016 -97.953576) (xy 427.226657 -97.953576) (xy 427.232571 -97.993762)
			(xy 427.23308 -98.021648) (xy 427.232571 -98.049534) (xy 427.224451 -98.10471) (xy 427.208383 -98.158117)
			(xy 427.184711 -98.208614) (xy 427.153938 -98.255127) (xy 427.116721 -98.296664) (xy 427.073853 -98.332339)
			(xy 427.026247 -98.361393) (xy 426.974918 -98.383205) (xy 426.920961 -98.397311) (xy 426.865524 -98.403411)
			(xy 426.80979 -98.401374) (xy 426.754947 -98.391244) (xy 426.702163 -98.373237) (xy 426.652563 -98.347736)
			(xy 426.607205 -98.315285) (xy 426.567056 -98.276576) (xy 426.53297 -98.232433) (xy 426.505674 -98.183798)
			(xy 426.485751 -98.131707) (xy 426.473625 -98.07727) (xy 426.469554 -98.021648) (xy 424.596812 -98.021648)
			(xy 424.602851 -98.034531) (xy 424.618919 -98.087938) (xy 424.627039 -98.143114) (xy 424.627548 -98.171)
			(xy 424.627039 -98.198886) (xy 424.618919 -98.254062) (xy 424.602851 -98.307469) (xy 424.579179 -98.357966)
			(xy 424.548406 -98.404479) (xy 424.511189 -98.446016) (xy 424.468321 -98.481691) (xy 424.420715 -98.510745)
			(xy 424.369386 -98.532557) (xy 424.328048 -98.543364) (xy 435.285894 -98.543364) (xy 435.289965 -98.487742)
			(xy 435.302091 -98.433305) (xy 435.322014 -98.381214) (xy 435.34931 -98.332579) (xy 435.383396 -98.288436)
			(xy 435.423545 -98.249727) (xy 435.468903 -98.217276) (xy 435.518503 -98.191775) (xy 435.571287 -98.173768)
			(xy 435.62613 -98.163638) (xy 435.681864 -98.161601) (xy 435.737301 -98.167701) (xy 435.791258 -98.181807)
			(xy 435.842587 -98.203619) (xy 435.890193 -98.232673) (xy 435.933061 -98.268348) (xy 435.970278 -98.309885)
			(xy 436.001051 -98.356398) (xy 436.024723 -98.406895) (xy 436.040791 -98.460302) (xy 436.048911 -98.515478)
			(xy 436.04942 -98.543364) (xy 436.048911 -98.57125) (xy 436.040791 -98.626426) (xy 436.024723 -98.679833)
			(xy 436.001051 -98.73033) (xy 435.98174 -98.759518) (xy 447.471292 -98.759518) (xy 447.471771 -98.732148)
			(xy 447.479586 -98.67797) (xy 447.495072 -98.625467) (xy 447.517911 -98.57572) (xy 447.547632 -98.529752)
			(xy 447.565272 -98.50882) (xy 447.565526 -98.508566) (xy 447.571094 -98.501467) (xy 447.577351 -98.48456)
			(xy 447.577718 -98.475546) (xy 447.577718 -98.40849) (xy 447.577362 -98.399473) (xy 447.571113 -98.382556)
			(xy 447.565526 -98.37547) (xy 447.565272 -98.37547) (xy 447.565272 -98.375216) (xy 447.547647 -98.35427)
			(xy 447.517918 -98.308306) (xy 447.495069 -98.258562) (xy 447.479569 -98.206061) (xy 447.471738 -98.151884)
			(xy 447.471736 -98.097143) (xy 447.479564 -98.042965) (xy 447.495059 -97.990464) (xy 447.517905 -97.940718)
			(xy 447.547631 -97.894752) (xy 447.565272 -97.87382) (xy 447.565526 -97.873566) (xy 447.571094 -97.866467)
			(xy 447.577351 -97.84956) (xy 447.577718 -97.840546) (xy 447.577718 -97.77349) (xy 447.577362 -97.764473)
			(xy 447.571113 -97.747556) (xy 447.565526 -97.74047) (xy 447.565272 -97.74047) (xy 447.565272 -97.740216)
			(xy 447.547623 -97.719292) (xy 447.517913 -97.673317) (xy 447.49508 -97.623567) (xy 447.479591 -97.571065)
			(xy 447.471765 -97.516888) (xy 447.471292 -97.489518) (xy 447.471778 -97.462267) (xy 447.479534 -97.408319)
			(xy 447.494889 -97.356024) (xy 447.517531 -97.306447) (xy 447.546997 -97.260597) (xy 447.582688 -97.219406)
			(xy 447.623879 -97.183715) (xy 447.669729 -97.154249) (xy 447.719306 -97.131607) (xy 447.771601 -97.116252)
			(xy 447.825549 -97.108496) (xy 447.880051 -97.108496) (xy 447.933999 -97.116252) (xy 447.986294 -97.131607)
			(xy 448.035871 -97.154249) (xy 448.081721 -97.183715) (xy 448.122912 -97.219406) (xy 448.158603 -97.260597)
			(xy 448.188069 -97.306447) (xy 448.210711 -97.356024) (xy 448.226066 -97.408319) (xy 448.233822 -97.462267)
			(xy 448.234308 -97.489518) (xy 448.233851 -97.516889) (xy 448.22603 -97.571068) (xy 448.210539 -97.623571)
			(xy 448.187696 -97.673318) (xy 448.15797 -97.719284) (xy 448.140328 -97.740216) (xy 448.140074 -97.74047)
			(xy 448.134491 -97.747559) (xy 448.128243 -97.764474) (xy 448.127882 -97.77349) (xy 448.127882 -97.840546)
			(xy 448.128269 -97.84956) (xy 448.134496 -97.866477) (xy 448.140074 -97.873566) (xy 448.140328 -97.873566)
			(xy 448.140328 -97.87382) (xy 448.157988 -97.894738) (xy 448.187716 -97.940707) (xy 448.210563 -97.990455)
			(xy 448.22606 -98.04296) (xy 448.233887 -98.097142) (xy 448.233886 -98.151886) (xy 448.226054 -98.206066)
			(xy 448.210553 -98.25857) (xy 448.187703 -98.308317) (xy 448.157972 -98.354284) (xy 448.140328 -98.375216)
			(xy 448.140074 -98.37547) (xy 448.134491 -98.382559) (xy 448.128243 -98.399474) (xy 448.127882 -98.40849)
			(xy 448.127882 -98.475546) (xy 448.128269 -98.48456) (xy 448.134496 -98.501477) (xy 448.136129 -98.503552)
			(xy 449.126063 -98.503552) (xy 449.126063 -98.449048) (xy 449.13382 -98.395098) (xy 449.149176 -98.342801)
			(xy 449.171818 -98.293222) (xy 449.201286 -98.247369) (xy 449.236979 -98.206177) (xy 449.278171 -98.170485)
			(xy 449.324023 -98.141017) (xy 449.373603 -98.118375) (xy 449.4259 -98.10302) (xy 449.47985 -98.095263)
			(xy 449.507102 -98.0948) (xy 449.533416 -98.095266) (xy 449.585545 -98.102501) (xy 449.636187 -98.116821)
			(xy 449.684386 -98.137953) (xy 449.72923 -98.1655) (xy 449.769869 -98.198938) (xy 449.788026 -98.21799)
			(xy 449.795537 -98.225404) (xy 449.814825 -98.233921) (xy 449.825364 -98.2345) (xy 449.90004 -98.2345)
			(xy 449.910588 -98.233952) (xy 449.929883 -98.22543) (xy 449.937378 -98.21799) (xy 449.955549 -98.19895)
			(xy 449.996176 -98.165492) (xy 450.041013 -98.137931) (xy 450.089211 -98.11679) (xy 450.139855 -98.102469)
			(xy 450.191987 -98.095241) (xy 450.218302 -98.0948) (xy 450.245554 -98.09527) (xy 450.299502 -98.103027)
			(xy 450.351798 -98.118382) (xy 450.401376 -98.141024) (xy 450.447227 -98.170491) (xy 450.488418 -98.206183)
			(xy 450.52411 -98.247374) (xy 450.553577 -98.293226) (xy 450.573272 -98.336354) (xy 451.149466 -98.336354)
			(xy 451.149948 -98.308984) (xy 451.157759 -98.254805) (xy 451.173244 -98.202302) (xy 451.196082 -98.152554)
			(xy 451.225805 -98.106587) (xy 451.243446 -98.085656) (xy 451.2437 -98.085402) (xy 451.249292 -98.078319)
			(xy 451.255535 -98.0614) (xy 451.255892 -98.052382) (xy 451.255892 -97.985326) (xy 451.255524 -97.97631)
			(xy 451.249284 -97.959393) (xy 451.2437 -97.952306) (xy 451.243446 -97.952306) (xy 451.243446 -97.952052)
			(xy 451.225759 -97.931156) (xy 451.196035 -97.885182) (xy 451.173191 -97.83543) (xy 451.157698 -97.782922)
			(xy 451.149873 -97.728738) (xy 451.149878 -97.673992) (xy 451.157713 -97.61981) (xy 451.173216 -97.567305)
			(xy 451.196068 -97.517557) (xy 451.225801 -97.471588) (xy 451.243446 -97.450656) (xy 451.2437 -97.450402)
			(xy 451.249292 -97.443319) (xy 451.255535 -97.4264) (xy 451.255892 -97.417382) (xy 451.255892 -97.350326)
			(xy 451.255524 -97.34131) (xy 451.249284 -97.324393) (xy 451.2437 -97.317306) (xy 451.243446 -97.317306)
			(xy 451.243446 -97.317052) (xy 451.225825 -97.296105) (xy 451.196109 -97.250137) (xy 451.173269 -97.200394)
			(xy 451.157774 -97.147896) (xy 451.149942 -97.093722) (xy 451.149466 -97.066354) (xy 451.149952 -97.039103)
			(xy 451.157708 -96.985155) (xy 451.173063 -96.93286) (xy 451.195705 -96.883283) (xy 451.225171 -96.837433)
			(xy 451.260862 -96.796242) (xy 451.302053 -96.760551) (xy 451.347903 -96.731085) (xy 451.39748 -96.708443)
			(xy 451.449775 -96.693088) (xy 451.503723 -96.685332) (xy 451.558225 -96.685332) (xy 451.612173 -96.693088)
			(xy 451.664468 -96.708443) (xy 451.714045 -96.731085) (xy 451.759895 -96.760551) (xy 451.801086 -96.796242)
			(xy 451.836777 -96.837433) (xy 451.866243 -96.883283) (xy 451.888885 -96.93286) (xy 451.90424 -96.985155)
			(xy 451.911996 -97.039103) (xy 451.912482 -97.066354) (xy 451.911993 -97.093723) (xy 451.904182 -97.147902)
			(xy 451.888698 -97.200405) (xy 451.865861 -97.250152) (xy 451.836141 -97.29612) (xy 451.818502 -97.317052)
			(xy 451.818248 -97.317306) (xy 451.812647 -97.324382) (xy 451.80641 -97.341307) (xy 451.806056 -97.350326)
			(xy 451.806056 -97.417382) (xy 451.80641 -97.426399) (xy 451.812658 -97.443317) (xy 451.818248 -97.450402)
			(xy 451.818502 -97.450402) (xy 451.818502 -97.450656) (xy 451.836096 -97.471626) (xy 451.865821 -97.517588)
			(xy 451.888667 -97.567328) (xy 451.904166 -97.619824) (xy 451.911998 -97.673997) (xy 451.912003 -97.728733)
			(xy 451.904181 -97.782908) (xy 451.888692 -97.835407) (xy 451.865854 -97.885151) (xy 451.836138 -97.931119)
			(xy 451.818502 -97.952052) (xy 451.818248 -97.952306) (xy 451.812647 -97.959382) (xy 451.80641 -97.976307)
			(xy 451.806056 -97.985326) (xy 451.806056 -98.052382) (xy 451.80641 -98.061399) (xy 451.812658 -98.078317)
			(xy 451.818248 -98.085402) (xy 451.818502 -98.085402) (xy 451.818502 -98.085656) (xy 451.836134 -98.106594)
			(xy 451.865847 -98.152565) (xy 451.888684 -98.202311) (xy 451.904177 -98.25481) (xy 451.912007 -98.308985)
			(xy 451.912482 -98.336354) (xy 451.911996 -98.363605) (xy 451.90424 -98.417553) (xy 451.888885 -98.469848)
			(xy 451.866243 -98.519425) (xy 451.836777 -98.565275) (xy 451.801086 -98.606466) (xy 451.759895 -98.642157)
			(xy 451.714045 -98.671623) (xy 451.664468 -98.694265) (xy 451.612173 -98.70962) (xy 451.558225 -98.717376)
			(xy 451.503723 -98.717376) (xy 451.449775 -98.70962) (xy 451.39748 -98.694265) (xy 451.347903 -98.671623)
			(xy 451.302053 -98.642157) (xy 451.260862 -98.606466) (xy 451.225171 -98.565275) (xy 451.195705 -98.519425)
			(xy 451.173063 -98.469848) (xy 451.157708 -98.417553) (xy 451.149952 -98.363605) (xy 451.149466 -98.336354)
			(xy 450.573272 -98.336354) (xy 450.576218 -98.342804) (xy 450.591574 -98.3951) (xy 450.59933 -98.449048)
			(xy 450.59933 -98.503552) (xy 450.591574 -98.5575) (xy 450.576218 -98.609796) (xy 450.553577 -98.659374)
			(xy 450.52411 -98.705226) (xy 450.488418 -98.746417) (xy 450.447227 -98.782109) (xy 450.401376 -98.811576)
			(xy 450.351798 -98.834218) (xy 450.299502 -98.849573) (xy 450.245554 -98.85733) (xy 450.218302 -98.857816)
			(xy 450.191988 -98.857342) (xy 450.13986 -98.850108) (xy 450.089218 -98.83579) (xy 450.041019 -98.814658)
			(xy 449.996175 -98.787114) (xy 449.955535 -98.753677) (xy 449.937378 -98.734626) (xy 449.929863 -98.727216)
			(xy 449.910578 -98.718696) (xy 449.90004 -98.718116) (xy 449.825364 -98.718116) (xy 449.814816 -98.718662)
			(xy 449.79552 -98.727185) (xy 449.788026 -98.734626) (xy 449.769856 -98.753667) (xy 449.729229 -98.787124)
			(xy 449.684391 -98.814685) (xy 449.636194 -98.835826) (xy 449.585549 -98.850146) (xy 449.533417 -98.857375)
			(xy 449.507102 -98.857816) (xy 449.47985 -98.857337) (xy 449.4259 -98.84958) (xy 449.373603 -98.834225)
			(xy 449.324023 -98.811583) (xy 449.278171 -98.782115) (xy 449.236979 -98.746423) (xy 449.201286 -98.705231)
			(xy 449.171818 -98.659378) (xy 449.149176 -98.609799) (xy 449.13382 -98.557502) (xy 449.126063 -98.503552)
			(xy 448.136129 -98.503552) (xy 448.140074 -98.508566) (xy 448.140328 -98.509074) (xy 448.151273 -98.521808)
			(xy 448.171114 -98.548899) (xy 448.179952 -98.563176) (xy 448.185286 -98.572066) (xy 448.202304 -98.584258)
			(xy 448.295522 -98.604578) (xy 448.316096 -98.60026) (xy 448.324732 -98.594418) (xy 448.348787 -98.578404)
			(xy 448.400722 -98.553064) (xy 448.455882 -98.535842) (xy 448.513009 -98.527132) (xy 448.541902 -98.5266)
			(xy 448.569154 -98.52707) (xy 448.623102 -98.534827) (xy 448.675398 -98.550182) (xy 448.724976 -98.572824)
			(xy 448.770827 -98.602291) (xy 448.812018 -98.637983) (xy 448.84771 -98.679174) (xy 448.877177 -98.725026)
			(xy 448.899818 -98.774604) (xy 448.915174 -98.8269) (xy 448.92293 -98.880848) (xy 448.92293 -98.935352)
			(xy 448.915174 -98.9893) (xy 448.899818 -99.041596) (xy 448.877177 -99.091174) (xy 448.84771 -99.137026)
			(xy 448.812018 -99.178217) (xy 448.770827 -99.213909) (xy 448.724976 -99.243376) (xy 448.675398 -99.266018)
			(xy 448.623102 -99.281373) (xy 448.569154 -99.28913) (xy 448.541902 -99.289616) (xy 448.51381 -99.28912)
			(xy 448.458233 -99.280893) (xy 448.404464 -99.264602) (xy 448.353667 -99.2406) (xy 448.30694 -99.209405)
			(xy 448.265295 -99.171693) (xy 448.229633 -99.12828) (xy 448.21475 -99.10445) (xy 448.209416 -99.09556)
			(xy 448.192398 -99.083368) (xy 448.09918 -99.063048) (xy 448.078606 -99.067366) (xy 448.06997 -99.073208)
			(xy 448.045916 -99.089224) (xy 447.993981 -99.114563) (xy 447.93882 -99.131784) (xy 447.881693 -99.140494)
			(xy 447.8528 -99.141026) (xy 447.82555 -99.140522) (xy 447.771603 -99.132766) (xy 447.71931 -99.117412)
			(xy 447.669734 -99.094772) (xy 447.623885 -99.065308) (xy 447.582695 -99.029618) (xy 447.547003 -98.98843)
			(xy 447.517536 -98.942582) (xy 447.494894 -98.893007) (xy 447.479538 -98.840714) (xy 447.471779 -98.786768)
			(xy 447.471292 -98.759518) (xy 435.98174 -98.759518) (xy 435.970278 -98.776843) (xy 435.933061 -98.81838)
			(xy 435.890193 -98.854055) (xy 435.842587 -98.883109) (xy 435.791258 -98.904921) (xy 435.737301 -98.919027)
			(xy 435.681864 -98.925127) (xy 435.62613 -98.92309) (xy 435.571287 -98.91296) (xy 435.518503 -98.894953)
			(xy 435.468903 -98.869452) (xy 435.423545 -98.837001) (xy 435.383396 -98.798292) (xy 435.34931 -98.754149)
			(xy 435.322014 -98.705514) (xy 435.302091 -98.653423) (xy 435.289965 -98.598986) (xy 435.285894 -98.543364)
			(xy 424.328048 -98.543364) (xy 424.315429 -98.546663) (xy 424.259992 -98.552763) (xy 424.204258 -98.550726)
			(xy 424.149415 -98.540596) (xy 424.096631 -98.522589) (xy 424.047031 -98.497088) (xy 424.001673 -98.464637)
			(xy 423.961524 -98.425928) (xy 423.927438 -98.381785) (xy 423.900142 -98.33315) (xy 423.880219 -98.281059)
			(xy 423.868093 -98.226622) (xy 423.864022 -98.171) (xy 398.845278 -98.171) (xy 398.456404 -98.559874)
			(xy 398.432834 -98.582767) (xy 398.381458 -98.623731) (xy 398.325819 -98.658686) (xy 398.266617 -98.687193)
			(xy 398.204595 -98.708891) (xy 398.140533 -98.72351) (xy 398.075238 -98.730865) (xy 398.042384 -98.731324)
			(xy 397.547846 -98.731324) (xy 397.537689 -98.731783) (xy 397.518953 -98.739625) (xy 397.511524 -98.746564)
			(xy 397.453612 -98.806254) (xy 397.446246 -98.825304) (xy 397.4465 -98.835464) (xy 397.4465 -98.845116)
			(xy 399.551142 -98.845116) (xy 399.555213 -98.789494) (xy 399.567339 -98.735057) (xy 399.587262 -98.682966)
			(xy 399.614558 -98.634331) (xy 399.648644 -98.590188) (xy 399.688793 -98.551479) (xy 399.734151 -98.519028)
			(xy 399.783751 -98.493527) (xy 399.836535 -98.47552) (xy 399.891378 -98.46539) (xy 399.947112 -98.463353)
			(xy 400.002549 -98.469453) (xy 400.056506 -98.483559) (xy 400.107835 -98.505371) (xy 400.155441 -98.534425)
			(xy 400.198309 -98.5701) (xy 400.235526 -98.611637) (xy 400.266299 -98.65815) (xy 400.289971 -98.708647)
			(xy 400.306039 -98.762054) (xy 400.314159 -98.81723) (xy 400.314668 -98.845116) (xy 400.314159 -98.873002)
			(xy 400.306039 -98.928178) (xy 400.289971 -98.981585) (xy 400.266299 -99.032082) (xy 400.235526 -99.078595)
			(xy 400.198309 -99.120132) (xy 400.155441 -99.155807) (xy 400.107835 -99.184861) (xy 400.056506 -99.206673)
			(xy 400.002549 -99.220779) (xy 399.947112 -99.226879) (xy 399.891378 -99.224842) (xy 399.836535 -99.214712)
			(xy 399.783751 -99.196705) (xy 399.734151 -99.171204) (xy 399.688793 -99.138753) (xy 399.648644 -99.100044)
			(xy 399.614558 -99.055901) (xy 399.587262 -99.007266) (xy 399.567339 -98.955175) (xy 399.555213 -98.900738)
			(xy 399.551142 -98.845116) (xy 397.4465 -98.845116) (xy 397.446014 -98.872367) (xy 397.438258 -98.926315)
			(xy 397.422903 -98.97861) (xy 397.400261 -99.028187) (xy 397.370795 -99.074037) (xy 397.335104 -99.115228)
			(xy 397.293913 -99.150919) (xy 397.248063 -99.180385) (xy 397.198486 -99.203027) (xy 397.146191 -99.218382)
			(xy 397.092243 -99.226138) (xy 397.037741 -99.226138) (xy 396.983793 -99.218382) (xy 396.931498 -99.203027)
			(xy 396.881921 -99.180385) (xy 396.836071 -99.150919) (xy 396.79488 -99.115228) (xy 396.759189 -99.074037)
			(xy 396.729723 -99.028187) (xy 396.707081 -98.97861) (xy 396.691726 -98.926315) (xy 396.68397 -98.872367)
			(xy 396.683484 -98.845116) (xy 396.683484 -98.835464) (xy 396.683738 -98.825304) (xy 396.676372 -98.806254)
			(xy 396.61846 -98.746564) (xy 396.611023 -98.739634) (xy 396.592294 -98.731772) (xy 396.582138 -98.731324)
			(xy 395.81582 -98.731324) (xy 395.805662 -98.731769) (xy 395.786926 -98.739621) (xy 395.779498 -98.746564)
			(xy 395.721586 -98.806254) (xy 395.71422 -98.825304) (xy 395.714474 -98.835464) (xy 395.714474 -98.845116)
			(xy 395.713988 -98.872367) (xy 395.706232 -98.926315) (xy 395.690877 -98.97861) (xy 395.668235 -99.028187)
			(xy 395.638769 -99.074037) (xy 395.603078 -99.115228) (xy 395.561887 -99.150919) (xy 395.516037 -99.180385)
			(xy 395.46646 -99.203027) (xy 395.414165 -99.218382) (xy 395.360217 -99.226138) (xy 395.305715 -99.226138)
			(xy 395.251767 -99.218382) (xy 395.199472 -99.203027) (xy 395.149895 -99.180385) (xy 395.104045 -99.150919)
			(xy 395.062854 -99.115228) (xy 395.027163 -99.074037) (xy 394.997697 -99.028187) (xy 394.975055 -98.97861)
			(xy 394.9597 -98.926315) (xy 394.951944 -98.872367) (xy 394.951458 -98.845116) (xy 394.951458 -98.835464)
			(xy 394.951712 -98.825304) (xy 394.944346 -98.806254) (xy 394.886434 -98.746564) (xy 394.879006 -98.739622)
			(xy 394.86027 -98.731768) (xy 394.850112 -98.731324) (xy 393.83462 -98.731324) (xy 393.824462 -98.731769)
			(xy 393.805726 -98.739621) (xy 393.798298 -98.746564) (xy 393.740386 -98.806254) (xy 393.73302 -98.825304)
			(xy 393.733274 -98.835464) (xy 393.733274 -98.845116) (xy 393.73286 -98.872371) (xy 393.7251 -98.926325)
			(xy 393.70974 -98.978626) (xy 393.687093 -99.028209) (xy 393.65762 -99.074063) (xy 393.621921 -99.115257)
			(xy 393.580723 -99.15095) (xy 393.534865 -99.180417) (xy 393.485279 -99.203058) (xy 393.432976 -99.218411)
			(xy 393.379021 -99.226163) (xy 393.351766 -99.226624) (xy 393.323769 -99.226132) (xy 393.268378 -99.217943)
			(xy 393.214778 -99.201746) (xy 393.164121 -99.177888) (xy 393.117495 -99.146883) (xy 393.075902 -99.109395)
			(xy 393.040235 -99.066231) (xy 393.01126 -99.018317) (xy 392.999976 -98.99269) (xy 392.996372 -98.984935)
			(xy 392.984942 -98.972224) (xy 392.977624 -98.967798) (xy 392.951716 -98.95332) (xy 392.94386 -98.949467)
			(xy 392.926592 -98.94673) (xy 392.917934 -98.947986) (xy 392.892122 -98.952368) (xy 392.839974 -98.957072)
			(xy 392.813794 -98.957384) (xy 387.181344 -98.957384) (xy 387.170541 -98.957876) (xy 387.150812 -98.966679)
			(xy 387.143244 -98.974402) (xy 387.085586 -99.039426) (xy 387.079236 -99.060254) (xy 387.080506 -99.070922)
			(xy 387.081809 -99.082307) (xy 387.083209 -99.105183) (xy 387.0833 -99.116642) (xy 387.082861 -99.143895)
			(xy 387.075099 -99.197844) (xy 387.059738 -99.250141) (xy 387.037091 -99.299718) (xy 387.00762 -99.345569)
			(xy 386.971924 -99.386759) (xy 386.930729 -99.42245) (xy 386.884875 -99.451915) (xy 386.835294 -99.474555)
			(xy 386.782996 -99.489909) (xy 386.729045 -99.497665) (xy 386.701792 -99.49815) (xy 386.686999 -99.498018)
			(xy 386.657501 -99.495727) (xy 386.642864 -99.493578) (xy 386.63189 -99.492444) (xy 386.610698 -99.498511)
			(xy 386.60197 -99.505262) (xy 386.543296 -99.5553) (xy 386.535274 -99.562873) (xy 386.526055 -99.582889)
			(xy 386.525516 -99.593908) (xy 386.525516 -99.8982) (xy 386.526049 -99.90922) (xy 386.535271 -99.929236)
			(xy 386.543296 -99.936808) (xy 386.60197 -99.986846) (xy 386.610686 -99.993626) (xy 386.631886 -99.9997)
			(xy 386.642864 -99.99853) (xy 386.657502 -99.996387) (xy 386.686999 -99.9941) (xy 386.701792 -99.993958)
			(xy 386.729043 -99.994489) (xy 386.78299 -100.002244) (xy 386.835284 -100.017598) (xy 386.884861 -100.040238)
			(xy 386.930711 -100.069703) (xy 386.971901 -100.105394) (xy 387.007592 -100.146583) (xy 387.037058 -100.192432)
			(xy 387.059699 -100.242009) (xy 387.075054 -100.294302) (xy 387.082811 -100.348249) (xy 387.082811 -100.402751)
			(xy 387.075054 -100.456698) (xy 387.059699 -100.508991) (xy 387.037058 -100.558568) (xy 387.007592 -100.604417)
			(xy 386.972461 -100.64496) (xy 392.969748 -100.64496) (xy 392.973819 -100.589338) (xy 392.985945 -100.534901)
			(xy 393.005868 -100.48281) (xy 393.033164 -100.434175) (xy 393.06725 -100.390032) (xy 393.107399 -100.351323)
			(xy 393.152757 -100.318872) (xy 393.202357 -100.293371) (xy 393.255141 -100.275364) (xy 393.309984 -100.265234)
			(xy 393.365718 -100.263197) (xy 393.421155 -100.269297) (xy 393.475112 -100.283403) (xy 393.526441 -100.305215)
			(xy 393.574047 -100.334269) (xy 393.616915 -100.369944) (xy 393.654132 -100.411481) (xy 393.684905 -100.457994)
			(xy 393.708577 -100.508491) (xy 393.724645 -100.561898) (xy 393.732765 -100.617074) (xy 393.733274 -100.64496)
			(xy 394.950948 -100.64496) (xy 394.955019 -100.589338) (xy 394.967145 -100.534901) (xy 394.987068 -100.48281)
			(xy 395.014364 -100.434175) (xy 395.04845 -100.390032) (xy 395.088599 -100.351323) (xy 395.133957 -100.318872)
			(xy 395.183557 -100.293371) (xy 395.236341 -100.275364) (xy 395.291184 -100.265234) (xy 395.346918 -100.263197)
			(xy 395.402355 -100.269297) (xy 395.456312 -100.283403) (xy 395.507641 -100.305215) (xy 395.555247 -100.334269)
			(xy 395.598115 -100.369944) (xy 395.635332 -100.411481) (xy 395.666105 -100.457994) (xy 395.689777 -100.508491)
			(xy 395.705845 -100.561898) (xy 395.713965 -100.617074) (xy 395.714474 -100.64496) (xy 396.309594 -100.64496)
			(xy 396.313665 -100.589338) (xy 396.325791 -100.534901) (xy 396.345714 -100.48281) (xy 396.37301 -100.434175)
			(xy 396.407096 -100.390032) (xy 396.447245 -100.351323) (xy 396.492603 -100.318872) (xy 396.542203 -100.293371)
			(xy 396.594987 -100.275364) (xy 396.64983 -100.265234) (xy 396.705564 -100.263197) (xy 396.761001 -100.269297)
			(xy 396.814958 -100.283403) (xy 396.866287 -100.305215) (xy 396.913893 -100.334269) (xy 396.956761 -100.369944)
			(xy 396.993978 -100.411481) (xy 397.024751 -100.457994) (xy 397.048423 -100.508491) (xy 397.064491 -100.561898)
			(xy 397.072611 -100.617074) (xy 397.07312 -100.64496) (xy 397.072611 -100.672846) (xy 397.064491 -100.728022)
			(xy 397.048423 -100.781429) (xy 397.024751 -100.831926) (xy 396.993978 -100.878439) (xy 396.956761 -100.919976)
			(xy 396.913893 -100.955651) (xy 396.866287 -100.984705) (xy 396.814958 -101.006517) (xy 396.761001 -101.020623)
			(xy 396.705564 -101.026723) (xy 396.64983 -101.024686) (xy 396.594987 -101.014556) (xy 396.542203 -100.996549)
			(xy 396.492603 -100.971048) (xy 396.447245 -100.938597) (xy 396.407096 -100.899888) (xy 396.37301 -100.855745)
			(xy 396.345714 -100.80711) (xy 396.325791 -100.755019) (xy 396.313665 -100.700582) (xy 396.309594 -100.64496)
			(xy 395.714474 -100.64496) (xy 395.713965 -100.672846) (xy 395.705845 -100.728022) (xy 395.689777 -100.781429)
			(xy 395.666105 -100.831926) (xy 395.635332 -100.878439) (xy 395.598115 -100.919976) (xy 395.555247 -100.955651)
			(xy 395.507641 -100.984705) (xy 395.456312 -101.006517) (xy 395.402355 -101.020623) (xy 395.346918 -101.026723)
			(xy 395.291184 -101.024686) (xy 395.236341 -101.014556) (xy 395.183557 -100.996549) (xy 395.133957 -100.971048)
			(xy 395.088599 -100.938597) (xy 395.04845 -100.899888) (xy 395.014364 -100.855745) (xy 394.987068 -100.80711)
			(xy 394.967145 -100.755019) (xy 394.955019 -100.700582) (xy 394.950948 -100.64496) (xy 393.733274 -100.64496)
			(xy 393.732765 -100.672846) (xy 393.724645 -100.728022) (xy 393.708577 -100.781429) (xy 393.684905 -100.831926)
			(xy 393.654132 -100.878439) (xy 393.616915 -100.919976) (xy 393.574047 -100.955651) (xy 393.526441 -100.984705)
			(xy 393.475112 -101.006517) (xy 393.421155 -101.020623) (xy 393.365718 -101.026723) (xy 393.309984 -101.024686)
			(xy 393.255141 -101.014556) (xy 393.202357 -100.996549) (xy 393.152757 -100.971048) (xy 393.107399 -100.938597)
			(xy 393.06725 -100.899888) (xy 393.033164 -100.855745) (xy 393.005868 -100.80711) (xy 392.985945 -100.755019)
			(xy 392.973819 -100.700582) (xy 392.969748 -100.64496) (xy 386.972461 -100.64496) (xy 386.971901 -100.645606)
			(xy 386.930711 -100.681297) (xy 386.884861 -100.710762) (xy 386.835284 -100.733402) (xy 386.78299 -100.748756)
			(xy 386.729043 -100.756511) (xy 386.701792 -100.756974) (xy 386.675885 -100.756502) (xy 386.624548 -100.749477)
			(xy 386.574634 -100.735571) (xy 386.527061 -100.715039) (xy 386.482702 -100.68826) (xy 386.442375 -100.655725)
			(xy 386.406821 -100.618034) (xy 386.391404 -100.597208) (xy 386.385673 -100.589869) (xy 386.370163 -100.579589)
			(xy 386.361178 -100.577142) (xy 386.330698 -100.570284) (xy 386.321419 -100.568559) (xy 386.302759 -100.571284)
			(xy 386.294376 -100.575618) (xy 386.268404 -100.589921) (xy 386.213551 -100.61243) (xy 386.156246 -100.627654)
			(xy 386.097454 -100.635337) (xy 386.067808 -100.635816) (xy 386.038165 -100.635327) (xy 385.979383 -100.627603)
			(xy 385.922084 -100.612374) (xy 385.867224 -100.589893) (xy 385.84124 -100.575618) (xy 385.832823 -100.571381)
			(xy 385.814197 -100.568642) (xy 385.804918 -100.570284) (xy 385.774438 -100.577142) (xy 385.76544 -100.579554)
			(xy 385.749937 -100.589858) (xy 385.744212 -100.597208) (xy 385.728815 -100.618053) (xy 385.693271 -100.655765)
			(xy 385.652947 -100.688315) (xy 385.608586 -100.715103) (xy 385.561005 -100.735636) (xy 385.511081 -100.749535)
			(xy 385.459735 -100.756544) (xy 385.433824 -100.756974) (xy 385.406568 -100.756581) (xy 385.352609 -100.748826)
			(xy 385.300304 -100.73347) (xy 385.250716 -100.710827) (xy 385.204856 -100.681357) (xy 385.163657 -100.64566)
			(xy 385.127957 -100.604463) (xy 385.098484 -100.558605) (xy 385.075838 -100.509019) (xy 385.060479 -100.456714)
			(xy 385.052721 -100.402756) (xy 385.052721 -100.348244) (xy 385.060479 -100.294286) (xy 385.075838 -100.241981)
			(xy 385.098484 -100.192395) (xy 385.127957 -100.146537) (xy 385.163657 -100.10534) (xy 385.204856 -100.069643)
			(xy 385.250716 -100.040173) (xy 385.300304 -100.01753) (xy 385.352609 -100.002174) (xy 385.406568 -99.994419)
			(xy 385.433824 -99.993958) (xy 385.448617 -99.994088) (xy 385.478115 -99.996381) (xy 385.492752 -99.99853)
			(xy 385.503728 -99.999613) (xy 385.524915 -99.99358) (xy 385.533646 -99.986846) (xy 385.59232 -99.936808)
			(xy 385.60034 -99.929234) (xy 385.609559 -99.909218) (xy 385.6101 -99.8982) (xy 385.6101 -99.593908)
			(xy 385.609558 -99.58289) (xy 385.600341 -99.562873) (xy 385.59232 -99.5553) (xy 385.533646 -99.505262)
			(xy 385.524959 -99.498438) (xy 385.503736 -99.49239) (xy 385.492752 -99.493578) (xy 385.478114 -99.495719)
			(xy 385.448617 -99.498007) (xy 385.433824 -99.49815) (xy 385.408273 -99.497741) (xy 385.357627 -99.490933)
			(xy 385.308344 -99.477423) (xy 385.261307 -99.457451) (xy 385.217358 -99.431377) (xy 385.177285 -99.399668)
			(xy 385.15925 -99.381564) (xy 385.152138 -99.374198) (xy 385.133596 -99.366324) (xy 385.050792 -99.365562)
			(xy 385.040679 -99.365872) (xy 385.021947 -99.373477) (xy 385.01447 -99.380294) (xy 383.90195 -100.492814)
			(xy 383.89491 -100.50059) (xy 383.887267 -100.520103) (xy 383.888002 -100.541046) (xy 383.892044 -100.550726)
			(xy 383.940558 -100.651818) (xy 383.969006 -100.667312) (xy 383.985008 -100.665534) (xy 383.99754 -100.664232)
			(xy 384.022701 -100.662834) (xy 384.0353 -100.66274) (xy 384.064943 -100.663231) (xy 384.123725 -100.670955)
			(xy 384.181023 -100.686184) (xy 384.235883 -100.708663) (xy 384.261868 -100.722938) (xy 384.270284 -100.727178)
			(xy 384.288911 -100.729916) (xy 384.29819 -100.728272) (xy 384.32867 -100.721414) (xy 384.337663 -100.718987)
			(xy 384.353167 -100.708693) (xy 384.358896 -100.701348) (xy 384.374275 -100.68049) (xy 384.409823 -100.64278)
			(xy 384.450151 -100.610233) (xy 384.494515 -100.583446) (xy 384.542099 -100.562916) (xy 384.592024 -100.549019)
			(xy 384.643372 -100.542011) (xy 384.669284 -100.541582) (xy 384.696537 -100.542064) (xy 384.750488 -100.549819)
			(xy 384.802787 -100.565173) (xy 384.852367 -100.587814) (xy 384.898221 -100.617281) (xy 384.939415 -100.652974)
			(xy 384.975109 -100.694166) (xy 385.004578 -100.740019) (xy 385.027221 -100.789598) (xy 385.042577 -100.841896)
			(xy 385.050335 -100.895847) (xy 385.050335 -100.950353) (xy 385.042577 -101.004304) (xy 385.027221 -101.056602)
			(xy 385.004578 -101.106181) (xy 384.975109 -101.152034) (xy 384.939415 -101.193226) (xy 384.898221 -101.228919)
			(xy 384.852367 -101.258386) (xy 384.802787 -101.281027) (xy 384.750488 -101.296381) (xy 384.696537 -101.304136)
			(xy 384.669284 -101.304598) (xy 384.654491 -101.304466) (xy 384.624993 -101.302175) (xy 384.610356 -101.300026)
			(xy 384.599382 -101.298876) (xy 384.578188 -101.304953) (xy 384.569462 -101.31171) (xy 384.510788 -101.361748)
			(xy 384.502789 -101.369341) (xy 384.493557 -101.389342) (xy 384.493008 -101.400356) (xy 384.493008 -101.704648)
			(xy 384.493572 -101.715664) (xy 384.502773 -101.735681) (xy 384.510788 -101.743256) (xy 384.569462 -101.793294)
			(xy 384.578142 -101.800127) (xy 384.599371 -101.806168) (xy 384.610356 -101.804978) (xy 384.624994 -101.802836)
			(xy 384.654491 -101.800549) (xy 384.669284 -101.800406) (xy 384.696539 -101.80084) (xy 384.750493 -101.808595)
			(xy 384.802795 -101.82395) (xy 384.852379 -101.846593) (xy 384.898236 -101.876062) (xy 384.939432 -101.911757)
			(xy 384.975129 -101.952951) (xy 385.004599 -101.998807) (xy 385.027244 -102.04839) (xy 385.042601 -102.100691)
			(xy 385.050359 -102.154645) (xy 385.050359 -102.209155) (xy 385.042601 -102.263109) (xy 385.027244 -102.31541)
			(xy 385.004599 -102.364993) (xy 384.975129 -102.410849) (xy 384.939432 -102.452043) (xy 384.898236 -102.487738)
			(xy 384.852379 -102.517207) (xy 384.802795 -102.53985) (xy 384.750493 -102.555205) (xy 384.696539 -102.56296)
			(xy 384.669284 -102.563422) (xy 384.643377 -102.562936) (xy 384.592042 -102.555911) (xy 384.542129 -102.542006)
			(xy 384.494557 -102.521476) (xy 384.450198 -102.494699) (xy 384.40987 -102.462168) (xy 384.374314 -102.42448)
			(xy 384.358896 -102.403656) (xy 384.353159 -102.396322) (xy 384.337654 -102.386037) (xy 384.32867 -102.38359)
			(xy 384.29819 -102.376732) (xy 384.288912 -102.374997) (xy 384.27025 -102.377727) (xy 384.261868 -102.382066)
			(xy 384.235895 -102.396367) (xy 384.181042 -102.418877) (xy 384.123738 -102.434102) (xy 384.064946 -102.441786)
			(xy 384.0353 -102.442264) (xy 384.005657 -102.441772) (xy 383.946875 -102.434048) (xy 383.889577 -102.41882)
			(xy 383.834717 -102.39634) (xy 383.808732 -102.382066) (xy 383.800316 -102.377827) (xy 383.781689 -102.375088)
			(xy 383.77241 -102.376732) (xy 383.74193 -102.38359) (xy 383.732937 -102.386015) (xy 383.717432 -102.396311)
			(xy 383.711704 -102.403656) (xy 383.696326 -102.424515) (xy 383.660778 -102.462224) (xy 383.620449 -102.494772)
			(xy 383.576085 -102.521558) (xy 383.528501 -102.542088) (xy 383.478576 -102.555985) (xy 383.427228 -102.562993)
			(xy 383.401316 -102.563422) (xy 383.374063 -102.562932) (xy 383.320113 -102.555177) (xy 383.267815 -102.539823)
			(xy 383.218235 -102.517182) (xy 383.172381 -102.487716) (xy 383.131188 -102.452023) (xy 383.095494 -102.410832)
			(xy 383.066026 -102.36498) (xy 383.043383 -102.3154) (xy 383.028026 -102.263103) (xy 383.020269 -102.209153)
			(xy 383.020269 -102.154647) (xy 383.028026 -102.100697) (xy 383.043383 -102.0484) (xy 383.066026 -101.99882)
			(xy 383.095494 -101.952968) (xy 383.131188 -101.911777) (xy 383.172381 -101.876084) (xy 383.218235 -101.846618)
			(xy 383.267815 -101.823977) (xy 383.320113 -101.808623) (xy 383.374063 -101.800868) (xy 383.401316 -101.800406)
			(xy 383.416109 -101.800538) (xy 383.445607 -101.802829) (xy 383.460244 -101.804978) (xy 383.471218 -101.806127)
			(xy 383.492412 -101.800051) (xy 383.501138 -101.793294) (xy 383.559812 -101.743256) (xy 383.56781 -101.735661)
			(xy 383.577042 -101.715661) (xy 383.577592 -101.704648) (xy 383.577592 -101.400356) (xy 383.577025 -101.389341)
			(xy 383.567826 -101.369324) (xy 383.559812 -101.361748) (xy 383.501138 -101.31171) (xy 383.492457 -101.304877)
			(xy 383.471229 -101.298836) (xy 383.460244 -101.300026) (xy 383.445606 -101.302168) (xy 383.416109 -101.304455)
			(xy 383.401316 -101.304598) (xy 383.375042 -101.304153) (xy 383.322991 -101.296953) (xy 383.272421 -101.282673)
			(xy 383.224291 -101.261584) (xy 383.201672 -101.24821) (xy 383.186686 -101.238812) (xy 383.151888 -101.242876)
			(xy 382.02489 -102.369874) (xy 382.001327 -102.392774) (xy 381.94995 -102.433738) (xy 381.894309 -102.468692)
			(xy 381.835106 -102.497197) (xy 381.773083 -102.518895) (xy 381.70902 -102.533512) (xy 381.643724 -102.540865)
			(xy 381.61087 -102.541324) (xy 370.796566 -102.541324) (xy 370.785909 -102.541937) (xy 370.766433 -102.550599)
			(xy 370.752147 -102.566419) (xy 370.748306 -102.576376) (xy 370.739947 -102.600284) (xy 370.717834 -102.645848)
			(xy 370.689879 -102.688081) (xy 370.656575 -102.726238) (xy 370.637816 -102.743254) (xy 370.637195 -102.743855)
			(xy 385.052739 -102.743855) (xy 385.052739 -102.689345) (xy 385.060497 -102.63539) (xy 385.075855 -102.583088)
			(xy 385.0985 -102.533504) (xy 385.127972 -102.487647) (xy 385.163669 -102.446452) (xy 385.204867 -102.410757)
			(xy 385.250725 -102.381288) (xy 385.30031 -102.358646) (xy 385.352613 -102.343292) (xy 385.406569 -102.335537)
			(xy 385.433824 -102.335076) (xy 385.459731 -102.335557) (xy 385.511066 -102.342583) (xy 385.560979 -102.356489)
			(xy 385.608552 -102.37702) (xy 385.65291 -102.403797) (xy 385.693238 -102.436329) (xy 385.728794 -102.474018)
			(xy 385.744212 -102.494842) (xy 385.749947 -102.502178) (xy 385.765453 -102.512462) (xy 385.774438 -102.514908)
			(xy 385.804918 -102.521766) (xy 385.814197 -102.523493) (xy 385.832857 -102.520765) (xy 385.84124 -102.516432)
			(xy 385.867227 -102.502177) (xy 385.922092 -102.479745) (xy 385.979393 -102.464578) (xy 386.038171 -102.456931)
			(xy 386.097445 -102.456931) (xy 386.156223 -102.464578) (xy 386.213524 -102.479745) (xy 386.268389 -102.502177)
			(xy 386.294376 -102.516432) (xy 386.30279 -102.520675) (xy 386.321419 -102.523412) (xy 386.330698 -102.521766)
			(xy 386.361178 -102.514908) (xy 386.370173 -102.512487) (xy 386.385676 -102.502188) (xy 386.391404 -102.494842)
			(xy 386.406776 -102.473979) (xy 386.442326 -102.43627) (xy 386.482655 -102.403722) (xy 386.527021 -102.376937)
			(xy 386.574605 -102.356407) (xy 386.624531 -102.342511) (xy 386.67588 -102.335505) (xy 386.701792 -102.335076)
			(xy 386.729044 -102.335571) (xy 386.782994 -102.343326) (xy 386.83529 -102.358681) (xy 386.884869 -102.381322)
			(xy 386.930721 -102.410789) (xy 386.970271 -102.445058) (xy 392.969748 -102.445058) (xy 392.973819 -102.389436)
			(xy 392.985945 -102.334999) (xy 393.005868 -102.282908) (xy 393.033164 -102.234273) (xy 393.06725 -102.19013)
			(xy 393.107399 -102.151421) (xy 393.152757 -102.11897) (xy 393.202357 -102.093469) (xy 393.255141 -102.075462)
			(xy 393.309984 -102.065332) (xy 393.365718 -102.063295) (xy 393.421155 -102.069395) (xy 393.475112 -102.083501)
			(xy 393.526441 -102.105313) (xy 393.574047 -102.134367) (xy 393.616915 -102.170042) (xy 393.654132 -102.211579)
			(xy 393.684905 -102.258092) (xy 393.708577 -102.308589) (xy 393.724645 -102.361996) (xy 393.732765 -102.417172)
			(xy 393.733274 -102.445058) (xy 393.732765 -102.472944) (xy 393.724645 -102.52812) (xy 393.708577 -102.581527)
			(xy 393.684905 -102.632024) (xy 393.654132 -102.678537) (xy 393.616915 -102.720074) (xy 393.574047 -102.755749)
			(xy 393.526441 -102.784803) (xy 393.475112 -102.806615) (xy 393.421155 -102.820721) (xy 393.365718 -102.826821)
			(xy 393.309984 -102.824784) (xy 393.255141 -102.814654) (xy 393.202357 -102.796647) (xy 393.152757 -102.771146)
			(xy 393.107399 -102.738695) (xy 393.06725 -102.699986) (xy 393.033164 -102.655843) (xy 393.005868 -102.607208)
			(xy 392.985945 -102.555117) (xy 392.973819 -102.50068) (xy 392.969748 -102.445058) (xy 386.970271 -102.445058)
			(xy 386.971913 -102.446481) (xy 387.007606 -102.487672) (xy 387.037074 -102.533524) (xy 387.059716 -102.583102)
			(xy 387.075072 -102.635399) (xy 387.082829 -102.689348) (xy 387.082829 -102.743852) (xy 387.075072 -102.797801)
			(xy 387.06051 -102.847394) (xy 395.275814 -102.847394) (xy 395.279885 -102.791772) (xy 395.292011 -102.737335)
			(xy 395.311934 -102.685244) (xy 395.33923 -102.636609) (xy 395.373316 -102.592466) (xy 395.413465 -102.553757)
			(xy 395.458823 -102.521306) (xy 395.508423 -102.495805) (xy 395.561207 -102.477798) (xy 395.61605 -102.467668)
			(xy 395.671784 -102.465631) (xy 395.727221 -102.471731) (xy 395.729596 -102.472352) (xy 399.552136 -102.472352)
			(xy 399.552136 -102.417848) (xy 399.559892 -102.363897) (xy 399.575247 -102.3116) (xy 399.597888 -102.26202)
			(xy 399.627353 -102.216167) (xy 399.663045 -102.174973) (xy 399.704235 -102.139277) (xy 399.750085 -102.109807)
			(xy 399.799663 -102.087161) (xy 399.851958 -102.071801) (xy 399.905908 -102.064039) (xy 399.93316 -102.06355)
			(xy 399.950208 -102.063747) (xy 399.984168 -102.066802) (xy 400.000978 -102.069646) (xy 400.012305 -102.071082)
			(xy 400.034322 -102.065146) (xy 400.043396 -102.058216) (xy 400.068034 -102.03688) (xy 400.076373 -102.028998)
			(xy 400.085496 -102.007968) (xy 400.08556 -101.996494) (xy 400.085052 -101.976428) (xy 400.085052 -101.112574)
			(xy 400.08556 -101.093778) (xy 400.085474 -101.082217) (xy 400.076203 -101.06106) (xy 400.06778 -101.053138)
			(xy 400.043396 -101.032056) (xy 400.034415 -101.025072) (xy 400.012525 -101.018995) (xy 400.001232 -101.020372)
			(xy 399.984361 -101.02324) (xy 399.950272 -101.026294) (xy 399.93316 -101.026468) (xy 399.905908 -101.026059)
			(xy 399.851959 -101.018297) (xy 399.799663 -101.002937) (xy 399.750086 -100.980291) (xy 399.704236 -100.950821)
			(xy 399.663046 -100.915126) (xy 399.627355 -100.873932) (xy 399.597889 -100.828079) (xy 399.575249 -100.778499)
			(xy 399.559894 -100.726202) (xy 399.552138 -100.672252) (xy 399.552138 -100.617748) (xy 399.559894 -100.563798)
			(xy 399.575249 -100.511501) (xy 399.597889 -100.461921) (xy 399.627355 -100.416068) (xy 399.663046 -100.374874)
			(xy 399.704236 -100.339179) (xy 399.750086 -100.309709) (xy 399.799663 -100.287063) (xy 399.851959 -100.271703)
			(xy 399.905908 -100.263941) (xy 399.93316 -100.263452) (xy 399.960139 -100.26387) (xy 400.01356 -100.27146)
			(xy 400.065377 -100.286506) (xy 400.114554 -100.30871) (xy 400.160109 -100.337626) (xy 400.201131 -100.372677)
			(xy 400.2368 -100.413163) (xy 400.266404 -100.458275) (xy 400.28935 -100.50711) (xy 400.305181 -100.558693)
			(xy 400.309842 -100.58527) (xy 400.312036 -100.595491) (xy 400.323296 -100.613073) (xy 400.331686 -100.619306)
			(xy 400.40306 -100.666804) (xy 400.424142 -100.670614) (xy 400.434302 -100.668074) (xy 400.461004 -100.662003)
			(xy 400.515379 -100.655507) (xy 400.54276 -100.65512) (xy 400.570142 -100.655488) (xy 400.624518 -100.661987)
			(xy 400.651218 -100.668074) (xy 400.661378 -100.670614) (xy 400.68246 -100.666804) (xy 400.762724 -100.613464)
			(xy 400.7739 -100.595938) (xy 400.775678 -100.58527) (xy 400.780321 -100.558694) (xy 400.796179 -100.507128)
			(xy 400.819145 -100.458311) (xy 400.84876 -100.413217) (xy 400.884433 -100.372745) (xy 400.925453 -100.337704)
			(xy 400.971002 -100.308791) (xy 401.020169 -100.286585) (xy 401.071975 -100.271529) (xy 401.125385 -100.263922)
			(xy 401.15236 -100.263452) (xy 401.17973 -100.263929) (xy 401.233909 -100.271742) (xy 401.286413 -100.287228)
			(xy 401.33616 -100.310068) (xy 401.382127 -100.339791) (xy 401.403058 -100.357432) (xy 401.403312 -100.357686)
			(xy 401.410392 -100.363282) (xy 401.427314 -100.369524) (xy 401.436332 -100.369878) (xy 401.503388 -100.369878)
			(xy 401.512405 -100.36952) (xy 401.529322 -100.363274) (xy 401.536408 -100.357686) (xy 401.536408 -100.357432)
			(xy 401.536662 -100.357432) (xy 401.557602 -100.339802) (xy 401.603572 -100.310088) (xy 401.653317 -100.28725)
			(xy 401.705817 -100.271757) (xy 401.759991 -100.263927) (xy 401.78736 -100.263452) (xy 401.804408 -100.263649)
			(xy 401.838368 -100.266703) (xy 401.855178 -100.269548) (xy 401.866505 -100.270983) (xy 401.888522 -100.265048)
			(xy 401.897596 -100.258118) (xy 401.922234 -100.236782) (xy 401.930572 -100.2289) (xy 401.939696 -100.20787)
			(xy 401.93976 -100.196396) (xy 401.939252 -100.17633) (xy 401.939252 -99.312476) (xy 401.93976 -99.29368)
			(xy 401.939673 -99.282119) (xy 401.930402 -99.260962) (xy 401.92198 -99.25304) (xy 401.897596 -99.231958)
			(xy 401.888615 -99.224974) (xy 401.866724 -99.218897) (xy 401.855432 -99.220274) (xy 401.838561 -99.223142)
			(xy 401.804472 -99.226196) (xy 401.78736 -99.22637) (xy 401.760108 -99.225957) (xy 401.706159 -99.218195)
			(xy 401.653864 -99.202835) (xy 401.604287 -99.18019) (xy 401.558437 -99.150719) (xy 401.517247 -99.115024)
			(xy 401.481557 -99.073831) (xy 401.452091 -99.027978) (xy 401.429451 -98.978398) (xy 401.414096 -98.926102)
			(xy 401.40634 -98.872152) (xy 401.40634 -98.817648) (xy 401.414096 -98.763698) (xy 401.429451 -98.711402)
			(xy 401.452091 -98.661822) (xy 401.481557 -98.615969) (xy 401.517247 -98.574776) (xy 401.558437 -98.539081)
			(xy 401.604287 -98.50961) (xy 401.653864 -98.486965) (xy 401.706159 -98.471605) (xy 401.760108 -98.463843)
			(xy 401.78736 -98.463354) (xy 401.814339 -98.463771) (xy 401.86776 -98.47136) (xy 401.919577 -98.486407)
			(xy 401.968755 -98.50861) (xy 402.01431 -98.537527) (xy 402.055332 -98.572578) (xy 402.091001 -98.613065)
			(xy 402.120605 -98.658176) (xy 402.143551 -98.707012) (xy 402.159381 -98.758595) (xy 402.164042 -98.785172)
			(xy 402.166235 -98.795393) (xy 402.177496 -98.812975) (xy 402.185886 -98.819208) (xy 402.25726 -98.866706)
			(xy 402.278342 -98.870516) (xy 402.288502 -98.867976) (xy 402.315195 -98.861827) (xy 402.369572 -98.855211)
			(xy 402.39696 -98.854768) (xy 402.424348 -98.855215) (xy 402.478724 -98.861834) (xy 402.505418 -98.867976)
			(xy 402.515578 -98.870516) (xy 402.53666 -98.866706) (xy 402.616924 -98.813366) (xy 402.6281 -98.79584)
			(xy 402.629878 -98.785172) (xy 402.634522 -98.758597) (xy 402.65038 -98.707031) (xy 402.673346 -98.658213)
			(xy 402.702961 -98.613119) (xy 402.738634 -98.572647) (xy 402.779654 -98.537606) (xy 402.825202 -98.508694)
			(xy 402.874369 -98.486487) (xy 402.926175 -98.471431) (xy 402.979585 -98.463824) (xy 403.00656 -98.463354)
			(xy 403.033812 -98.463891) (xy 403.087762 -98.471642) (xy 403.140059 -98.486993) (xy 403.18964 -98.509631)
			(xy 403.235493 -98.539095) (xy 403.276686 -98.574785) (xy 403.312381 -98.615975) (xy 403.34185 -98.661825)
			(xy 403.364493 -98.711403) (xy 403.379849 -98.763699) (xy 403.387607 -98.817648) (xy 403.387607 -98.872152)
			(xy 403.379849 -98.926101) (xy 403.364493 -98.978397) (xy 403.34185 -99.027975) (xy 403.312381 -99.073825)
			(xy 403.276686 -99.115015) (xy 403.235493 -99.150705) (xy 403.18964 -99.180169) (xy 403.140059 -99.202807)
			(xy 403.101072 -99.214251) (xy 417.622978 -99.214251) (xy 417.622978 -99.159749) (xy 417.630734 -99.105802)
			(xy 417.646089 -99.053508) (xy 417.668729 -99.003932) (xy 417.698194 -98.958082) (xy 417.733885 -98.916892)
			(xy 417.775074 -98.8812) (xy 417.820923 -98.851734) (xy 417.870499 -98.829092) (xy 417.922793 -98.813736)
			(xy 417.976739 -98.805978) (xy 418.00399 -98.805492) (xy 418.030594 -98.805952) (xy 418.083286 -98.813332)
			(xy 418.134441 -98.827965) (xy 418.183066 -98.849566) (xy 418.228216 -98.877715) (xy 418.269016 -98.911867)
			(xy 418.304672 -98.951359) (xy 418.319966 -98.973132) (xy 418.3283 -98.984612) (xy 418.350044 -99.002816)
			(xy 418.375957 -99.014334) (xy 418.40404 -99.018274) (xy 418.432123 -99.014334) (xy 418.458036 -99.002816)
			(xy 418.47978 -98.984612) (xy 418.488114 -98.973132) (xy 418.503386 -98.951345) (xy 418.539056 -98.911866)
			(xy 418.579864 -98.877725) (xy 418.625018 -98.849581) (xy 418.673643 -98.827982) (xy 418.724796 -98.813345)
			(xy 418.777487 -98.805954) (xy 418.80409 -98.805492) (xy 418.831343 -98.805955) (xy 418.885295 -98.81371)
			(xy 418.937594 -98.829066) (xy 418.987176 -98.851708) (xy 419.03303 -98.881175) (xy 419.074224 -98.916869)
			(xy 419.109919 -98.958062) (xy 419.139388 -99.003915) (xy 419.154793 -99.037648) (xy 426.469554 -99.037648)
			(xy 426.473625 -98.982026) (xy 426.485751 -98.927589) (xy 426.505674 -98.875498) (xy 426.53297 -98.826863)
			(xy 426.567056 -98.78272) (xy 426.607205 -98.744011) (xy 426.652563 -98.71156) (xy 426.702163 -98.686059)
			(xy 426.754947 -98.668052) (xy 426.80979 -98.657922) (xy 426.865524 -98.655885) (xy 426.920961 -98.661985)
			(xy 426.974918 -98.676091) (xy 427.026247 -98.697903) (xy 427.073853 -98.726957) (xy 427.116721 -98.762632)
			(xy 427.153938 -98.804169) (xy 427.184711 -98.850682) (xy 427.208383 -98.901179) (xy 427.224451 -98.954586)
			(xy 427.232571 -99.009762) (xy 427.23308 -99.037648) (xy 427.232571 -99.065534) (xy 427.224451 -99.12071)
			(xy 427.208383 -99.174117) (xy 427.184711 -99.224614) (xy 427.153938 -99.271127) (xy 427.116721 -99.312664)
			(xy 427.073853 -99.348339) (xy 427.026247 -99.377393) (xy 426.974918 -99.399205) (xy 426.920961 -99.413311)
			(xy 426.865524 -99.419411) (xy 426.80979 -99.417374) (xy 426.754947 -99.407244) (xy 426.702163 -99.389237)
			(xy 426.652563 -99.363736) (xy 426.607205 -99.331285) (xy 426.567056 -99.292576) (xy 426.53297 -99.248433)
			(xy 426.505674 -99.199798) (xy 426.485751 -99.147707) (xy 426.473625 -99.09327) (xy 426.469554 -99.037648)
			(xy 419.154793 -99.037648) (xy 419.162031 -99.053496) (xy 419.177387 -99.105795) (xy 419.185145 -99.159747)
			(xy 419.185145 -99.214253) (xy 419.177387 -99.268205) (xy 419.162031 -99.320504) (xy 419.139388 -99.370085)
			(xy 419.109919 -99.415938) (xy 419.089082 -99.439984) (xy 423.610022 -99.439984) (xy 423.614093 -99.384362)
			(xy 423.626219 -99.329925) (xy 423.646142 -99.277834) (xy 423.673438 -99.229199) (xy 423.707524 -99.185056)
			(xy 423.747673 -99.146347) (xy 423.793031 -99.113896) (xy 423.842631 -99.088395) (xy 423.895415 -99.070388)
			(xy 423.950258 -99.060258) (xy 424.005992 -99.058221) (xy 424.061429 -99.064321) (xy 424.115386 -99.078427)
			(xy 424.166715 -99.100239) (xy 424.214321 -99.129293) (xy 424.257189 -99.164968) (xy 424.294406 -99.206505)
			(xy 424.325179 -99.253018) (xy 424.348851 -99.303515) (xy 424.364919 -99.356922) (xy 424.373039 -99.412098)
			(xy 424.373548 -99.439984) (xy 424.373376 -99.449382) (xy 436.206136 -99.449382) (xy 436.210207 -99.39376)
			(xy 436.222333 -99.339323) (xy 436.242256 -99.287232) (xy 436.269552 -99.238597) (xy 436.303638 -99.194454)
			(xy 436.343787 -99.155745) (xy 436.389145 -99.123294) (xy 436.438745 -99.097793) (xy 436.491529 -99.079786)
			(xy 436.546372 -99.069656) (xy 436.602106 -99.067619) (xy 436.657543 -99.073719) (xy 436.7115 -99.087825)
			(xy 436.762829 -99.109637) (xy 436.810435 -99.138691) (xy 436.853303 -99.174366) (xy 436.89052 -99.215903)
			(xy 436.921293 -99.262416) (xy 436.944965 -99.312913) (xy 436.961033 -99.36632) (xy 436.969153 -99.421496)
			(xy 436.969662 -99.449382) (xy 436.969153 -99.477268) (xy 436.961033 -99.532444) (xy 436.944965 -99.585851)
			(xy 436.931543 -99.614482) (xy 438.639964 -99.614482) (xy 438.644035 -99.55886) (xy 438.656161 -99.504423)
			(xy 438.676084 -99.452332) (xy 438.70338 -99.403697) (xy 438.737466 -99.359554) (xy 438.777615 -99.320845)
			(xy 438.822973 -99.288394) (xy 438.872573 -99.262893) (xy 438.925357 -99.244886) (xy 438.9802 -99.234756)
			(xy 439.035934 -99.232719) (xy 439.091371 -99.238819) (xy 439.145328 -99.252925) (xy 439.196657 -99.274737)
			(xy 439.244263 -99.303791) (xy 439.287131 -99.339466) (xy 439.324348 -99.381003) (xy 439.355121 -99.427516)
			(xy 439.378793 -99.478013) (xy 439.394861 -99.53142) (xy 439.402981 -99.586596) (xy 439.40349 -99.614482)
			(xy 439.403281 -99.625912) (xy 439.80684 -99.625912) (xy 439.810911 -99.57029) (xy 439.823037 -99.515853)
			(xy 439.84296 -99.463762) (xy 439.870256 -99.415127) (xy 439.904342 -99.370984) (xy 439.944491 -99.332275)
			(xy 439.989849 -99.299824) (xy 440.039449 -99.274323) (xy 440.092233 -99.256316) (xy 440.147076 -99.246186)
			(xy 440.20281 -99.244149) (xy 440.258247 -99.250249) (xy 440.312204 -99.264355) (xy 440.363533 -99.286167)
			(xy 440.411139 -99.315221) (xy 440.454007 -99.350896) (xy 440.491224 -99.392433) (xy 440.521997 -99.438946)
			(xy 440.531176 -99.458526) (xy 441.938662 -99.458526) (xy 441.942733 -99.402904) (xy 441.954859 -99.348467)
			(xy 441.974782 -99.296376) (xy 442.002078 -99.247741) (xy 442.036164 -99.203598) (xy 442.076313 -99.164889)
			(xy 442.121671 -99.132438) (xy 442.171271 -99.106937) (xy 442.224055 -99.08893) (xy 442.278898 -99.0788)
			(xy 442.334632 -99.076763) (xy 442.390069 -99.082863) (xy 442.444026 -99.096969) (xy 442.495355 -99.118781)
			(xy 442.542961 -99.147835) (xy 442.585829 -99.18351) (xy 442.623046 -99.225047) (xy 442.653819 -99.27156)
			(xy 442.677491 -99.322057) (xy 442.693559 -99.375464) (xy 442.701679 -99.43064) (xy 442.702188 -99.458526)
			(xy 442.701679 -99.486412) (xy 442.693559 -99.541588) (xy 442.677491 -99.594995) (xy 442.653819 -99.645492)
			(xy 442.623046 -99.692005) (xy 442.585829 -99.733542) (xy 442.542961 -99.769217) (xy 442.495355 -99.798271)
			(xy 442.444026 -99.820083) (xy 442.390069 -99.834189) (xy 442.334632 -99.840289) (xy 442.278898 -99.838252)
			(xy 442.224055 -99.828122) (xy 442.171271 -99.810115) (xy 442.121671 -99.784614) (xy 442.076313 -99.752163)
			(xy 442.036164 -99.713454) (xy 442.002078 -99.669311) (xy 441.974782 -99.620676) (xy 441.954859 -99.568585)
			(xy 441.942733 -99.514148) (xy 441.938662 -99.458526) (xy 440.531176 -99.458526) (xy 440.545669 -99.489443)
			(xy 440.561737 -99.54285) (xy 440.569857 -99.598026) (xy 440.570366 -99.625912) (xy 440.569857 -99.653798)
			(xy 440.561737 -99.708974) (xy 440.545669 -99.762381) (xy 440.521997 -99.812878) (xy 440.491224 -99.859391)
			(xy 440.454007 -99.900928) (xy 440.411139 -99.936603) (xy 440.363533 -99.965657) (xy 440.312204 -99.987469)
			(xy 440.258247 -100.001575) (xy 440.20281 -100.007675) (xy 440.147076 -100.005638) (xy 440.092233 -99.995508)
			(xy 440.039449 -99.977501) (xy 439.989849 -99.952) (xy 439.944491 -99.919549) (xy 439.904342 -99.88084)
			(xy 439.870256 -99.836697) (xy 439.84296 -99.788062) (xy 439.823037 -99.735971) (xy 439.810911 -99.681534)
			(xy 439.80684 -99.625912) (xy 439.403281 -99.625912) (xy 439.402981 -99.642368) (xy 439.394861 -99.697544)
			(xy 439.378793 -99.750951) (xy 439.355121 -99.801448) (xy 439.324348 -99.847961) (xy 439.287131 -99.889498)
			(xy 439.244263 -99.925173) (xy 439.196657 -99.954227) (xy 439.145328 -99.976039) (xy 439.091371 -99.990145)
			(xy 439.035934 -99.996245) (xy 438.9802 -99.994208) (xy 438.925357 -99.984078) (xy 438.872573 -99.966071)
			(xy 438.822973 -99.94057) (xy 438.777615 -99.908119) (xy 438.737466 -99.86941) (xy 438.70338 -99.825267)
			(xy 438.676084 -99.776632) (xy 438.656161 -99.724541) (xy 438.644035 -99.670104) (xy 438.639964 -99.614482)
			(xy 436.931543 -99.614482) (xy 436.921293 -99.636348) (xy 436.89052 -99.682861) (xy 436.853303 -99.724398)
			(xy 436.810435 -99.760073) (xy 436.762829 -99.789127) (xy 436.7115 -99.810939) (xy 436.657543 -99.825045)
			(xy 436.602106 -99.831145) (xy 436.546372 -99.829108) (xy 436.491529 -99.818978) (xy 436.438745 -99.800971)
			(xy 436.389145 -99.77547) (xy 436.343787 -99.743019) (xy 436.303638 -99.70431) (xy 436.269552 -99.660167)
			(xy 436.242256 -99.611532) (xy 436.222333 -99.559441) (xy 436.210207 -99.505004) (xy 436.206136 -99.449382)
			(xy 424.373376 -99.449382) (xy 424.373039 -99.46787) (xy 424.364919 -99.523046) (xy 424.348851 -99.576453)
			(xy 424.325179 -99.62695) (xy 424.294406 -99.673463) (xy 424.257189 -99.715) (xy 424.214321 -99.750675)
			(xy 424.166715 -99.779729) (xy 424.115386 -99.801541) (xy 424.061429 -99.815647) (xy 424.005992 -99.821747)
			(xy 423.950258 -99.81971) (xy 423.895415 -99.80958) (xy 423.842631 -99.791573) (xy 423.793031 -99.766072)
			(xy 423.747673 -99.733621) (xy 423.707524 -99.694912) (xy 423.673438 -99.650769) (xy 423.646142 -99.602134)
			(xy 423.626219 -99.550043) (xy 423.614093 -99.495606) (xy 423.610022 -99.439984) (xy 419.089082 -99.439984)
			(xy 419.074224 -99.457131) (xy 419.03303 -99.492825) (xy 418.987176 -99.522292) (xy 418.937594 -99.544934)
			(xy 418.885295 -99.56029) (xy 418.831343 -99.568045) (xy 418.80409 -99.568508) (xy 418.777486 -99.568063)
			(xy 418.724793 -99.56068) (xy 418.673637 -99.546045) (xy 418.625012 -99.524442) (xy 418.579862 -99.49629)
			(xy 418.539063 -99.462135) (xy 418.503407 -99.422642) (xy 418.488114 -99.400868) (xy 418.47978 -99.389388)
			(xy 418.458036 -99.371184) (xy 418.432123 -99.359666) (xy 418.40404 -99.355726) (xy 418.375957 -99.359666)
			(xy 418.350044 -99.371184) (xy 418.3283 -99.389388) (xy 418.319966 -99.400868) (xy 418.304644 -99.422618)
			(xy 418.268982 -99.462097) (xy 418.228183 -99.496242) (xy 418.183038 -99.52439) (xy 418.134421 -99.545995)
			(xy 418.083275 -99.56064) (xy 418.030591 -99.568041) (xy 418.00399 -99.568508) (xy 417.976739 -99.568022)
			(xy 417.922793 -99.560264) (xy 417.870499 -99.544908) (xy 417.820923 -99.522266) (xy 417.775074 -99.4928)
			(xy 417.733885 -99.457108) (xy 417.698194 -99.415918) (xy 417.668729 -99.370068) (xy 417.646089 -99.320492)
			(xy 417.630734 -99.268198) (xy 417.622978 -99.214251) (xy 403.101072 -99.214251) (xy 403.087762 -99.218158)
			(xy 403.033812 -99.225909) (xy 403.00656 -99.22637) (xy 402.989448 -99.226175) (xy 402.955361 -99.223125)
			(xy 402.938488 -99.220274) (xy 402.927196 -99.218921) (xy 402.905307 -99.224984) (xy 402.896324 -99.231958)
			(xy 402.87194 -99.25304) (xy 402.863494 -99.260941) (xy 402.854241 -99.282114) (xy 402.85416 -99.29368)
			(xy 402.854668 -99.312476) (xy 402.854668 -99.750372) (xy 405.89784 -99.750372) (xy 405.901911 -99.69475)
			(xy 405.914037 -99.640313) (xy 405.93396 -99.588222) (xy 405.961256 -99.539587) (xy 405.995342 -99.495444)
			(xy 406.035491 -99.456735) (xy 406.080849 -99.424284) (xy 406.130449 -99.398783) (xy 406.183233 -99.380776)
			(xy 406.238076 -99.370646) (xy 406.29381 -99.368609) (xy 406.349247 -99.374709) (xy 406.403204 -99.388815)
			(xy 406.454533 -99.410627) (xy 406.502139 -99.439681) (xy 406.545007 -99.475356) (xy 406.582224 -99.516893)
			(xy 406.612997 -99.563406) (xy 406.636669 -99.613903) (xy 406.652737 -99.66731) (xy 406.660857 -99.722486)
			(xy 406.661366 -99.750372) (xy 406.660857 -99.778258) (xy 406.652737 -99.833434) (xy 406.636669 -99.886841)
			(xy 406.612997 -99.937338) (xy 406.582224 -99.983851) (xy 406.545007 -100.025388) (xy 406.527531 -100.039932)
			(xy 422.176954 -100.039932) (xy 422.181025 -99.98431) (xy 422.193151 -99.929873) (xy 422.213074 -99.877782)
			(xy 422.24037 -99.829147) (xy 422.274456 -99.785004) (xy 422.314605 -99.746295) (xy 422.359963 -99.713844)
			(xy 422.409563 -99.688343) (xy 422.462347 -99.670336) (xy 422.51719 -99.660206) (xy 422.572924 -99.658169)
			(xy 422.628361 -99.664269) (xy 422.682318 -99.678375) (xy 422.733647 -99.700187) (xy 422.781253 -99.729241)
			(xy 422.824121 -99.764916) (xy 422.861338 -99.806453) (xy 422.892111 -99.852966) (xy 422.915783 -99.903463)
			(xy 422.931851 -99.95687) (xy 422.939971 -100.012046) (xy 422.94048 -100.039932) (xy 422.940174 -100.056696)
			(xy 426.469554 -100.056696) (xy 426.473625 -100.001074) (xy 426.485751 -99.946637) (xy 426.505674 -99.894546)
			(xy 426.53297 -99.845911) (xy 426.567056 -99.801768) (xy 426.607205 -99.763059) (xy 426.652563 -99.730608)
			(xy 426.702163 -99.705107) (xy 426.754947 -99.6871) (xy 426.80979 -99.67697) (xy 426.865524 -99.674933)
			(xy 426.920961 -99.681033) (xy 426.974918 -99.695139) (xy 427.026247 -99.716951) (xy 427.073853 -99.746005)
			(xy 427.116721 -99.78168) (xy 427.153938 -99.823217) (xy 427.184711 -99.86973) (xy 427.208383 -99.920227)
			(xy 427.224451 -99.973634) (xy 427.232571 -100.02881) (xy 427.23308 -100.056696) (xy 427.232571 -100.084582)
			(xy 427.224451 -100.139758) (xy 427.208383 -100.193165) (xy 427.184711 -100.243662) (xy 427.153938 -100.290175)
			(xy 427.116721 -100.331712) (xy 427.073853 -100.367387) (xy 427.031898 -100.392992) (xy 443.67399 -100.392992)
			(xy 443.678061 -100.33737) (xy 443.690187 -100.282933) (xy 443.71011 -100.230842) (xy 443.737406 -100.182207)
			(xy 443.771492 -100.138064) (xy 443.811641 -100.099355) (xy 443.856999 -100.066904) (xy 443.906599 -100.041403)
			(xy 443.959383 -100.023396) (xy 444.014226 -100.013266) (xy 444.06996 -100.011229) (xy 444.125397 -100.017329)
			(xy 444.179354 -100.031435) (xy 444.230683 -100.053247) (xy 444.278289 -100.082301) (xy 444.321157 -100.117976)
			(xy 444.358374 -100.159513) (xy 444.389147 -100.206026) (xy 444.412819 -100.256523) (xy 444.428887 -100.30993)
			(xy 444.437007 -100.365106) (xy 444.437516 -100.392992) (xy 444.437007 -100.420878) (xy 444.428887 -100.476054)
			(xy 444.412819 -100.529461) (xy 444.389147 -100.579958) (xy 444.358374 -100.626471) (xy 444.321157 -100.668008)
			(xy 444.278289 -100.703683) (xy 444.230683 -100.732737) (xy 444.179354 -100.754549) (xy 444.125397 -100.768655)
			(xy 444.06996 -100.774755) (xy 444.014226 -100.772718) (xy 443.959383 -100.762588) (xy 443.906599 -100.744581)
			(xy 443.856999 -100.71908) (xy 443.811641 -100.686629) (xy 443.771492 -100.64792) (xy 443.737406 -100.603777)
			(xy 443.71011 -100.555142) (xy 443.690187 -100.503051) (xy 443.678061 -100.448614) (xy 443.67399 -100.392992)
			(xy 427.031898 -100.392992) (xy 427.026247 -100.396441) (xy 426.974918 -100.418253) (xy 426.920961 -100.432359)
			(xy 426.865524 -100.438459) (xy 426.80979 -100.436422) (xy 426.754947 -100.426292) (xy 426.702163 -100.408285)
			(xy 426.652563 -100.382784) (xy 426.607205 -100.350333) (xy 426.567056 -100.311624) (xy 426.53297 -100.267481)
			(xy 426.505674 -100.218846) (xy 426.485751 -100.166755) (xy 426.473625 -100.112318) (xy 426.469554 -100.056696)
			(xy 422.940174 -100.056696) (xy 422.939971 -100.067818) (xy 422.931851 -100.122994) (xy 422.915783 -100.176401)
			(xy 422.892111 -100.226898) (xy 422.861338 -100.273411) (xy 422.824121 -100.314948) (xy 422.781253 -100.350623)
			(xy 422.733647 -100.379677) (xy 422.682318 -100.401489) (xy 422.628361 -100.415595) (xy 422.572924 -100.421695)
			(xy 422.51719 -100.419658) (xy 422.462347 -100.409528) (xy 422.409563 -100.391521) (xy 422.359963 -100.36602)
			(xy 422.314605 -100.333569) (xy 422.274456 -100.29486) (xy 422.24037 -100.250717) (xy 422.213074 -100.202082)
			(xy 422.193151 -100.149991) (xy 422.181025 -100.095554) (xy 422.176954 -100.039932) (xy 406.527531 -100.039932)
			(xy 406.502139 -100.061063) (xy 406.454533 -100.090117) (xy 406.403204 -100.111929) (xy 406.349247 -100.126035)
			(xy 406.29381 -100.132135) (xy 406.238076 -100.130098) (xy 406.183233 -100.119968) (xy 406.130449 -100.101961)
			(xy 406.080849 -100.07646) (xy 406.035491 -100.044009) (xy 405.995342 -100.0053) (xy 405.961256 -99.961157)
			(xy 405.93396 -99.912522) (xy 405.914037 -99.860431) (xy 405.901911 -99.805994) (xy 405.89784 -99.750372)
			(xy 402.854668 -99.750372) (xy 402.854668 -100.17633) (xy 402.85416 -100.196396) (xy 402.854344 -100.207843)
			(xy 402.863462 -100.228815) (xy 402.871686 -100.236782) (xy 402.896324 -100.258118) (xy 402.905312 -100.265214)
			(xy 402.927404 -100.27116) (xy 402.938742 -100.269548) (xy 402.955549 -100.26668) (xy 402.989511 -100.263632)
			(xy 403.00656 -100.263452) (xy 403.033812 -100.263993) (xy 403.087761 -100.271744) (xy 403.140059 -100.287095)
			(xy 403.189639 -100.309733) (xy 403.235492 -100.339197) (xy 403.276685 -100.374887) (xy 403.312379 -100.416076)
			(xy 403.341848 -100.461926) (xy 403.364491 -100.511504) (xy 403.379847 -100.563799) (xy 403.387605 -100.617748)
			(xy 403.387605 -100.672252) (xy 403.379847 -100.726201) (xy 403.368051 -100.766372) (xy 405.89784 -100.766372)
			(xy 405.901911 -100.71075) (xy 405.914037 -100.656313) (xy 405.93396 -100.604222) (xy 405.961256 -100.555587)
			(xy 405.995342 -100.511444) (xy 406.035491 -100.472735) (xy 406.080849 -100.440284) (xy 406.130449 -100.414783)
			(xy 406.183233 -100.396776) (xy 406.238076 -100.386646) (xy 406.29381 -100.384609) (xy 406.349247 -100.390709)
			(xy 406.403204 -100.404815) (xy 406.454533 -100.426627) (xy 406.502139 -100.455681) (xy 406.545007 -100.491356)
			(xy 406.582224 -100.532893) (xy 406.612997 -100.579406) (xy 406.636669 -100.629903) (xy 406.652737 -100.68331)
			(xy 406.660857 -100.738486) (xy 406.661366 -100.766372) (xy 406.660857 -100.794258) (xy 406.652737 -100.849434)
			(xy 406.636669 -100.902841) (xy 406.612997 -100.953338) (xy 406.582224 -100.999851) (xy 406.545007 -101.041388)
			(xy 406.502139 -101.077063) (xy 406.454533 -101.106117) (xy 406.403204 -101.127929) (xy 406.349247 -101.142035)
			(xy 406.29381 -101.148135) (xy 406.238076 -101.146098) (xy 406.183233 -101.135968) (xy 406.130449 -101.117961)
			(xy 406.080849 -101.09246) (xy 406.035491 -101.060009) (xy 405.995342 -101.0213) (xy 405.961256 -100.977157)
			(xy 405.93396 -100.928522) (xy 405.914037 -100.876431) (xy 405.901911 -100.821994) (xy 405.89784 -100.766372)
			(xy 403.368051 -100.766372) (xy 403.364491 -100.778496) (xy 403.341848 -100.828074) (xy 403.312379 -100.873924)
			(xy 403.276685 -100.915113) (xy 403.235492 -100.950803) (xy 403.189639 -100.980267) (xy 403.140059 -101.002905)
			(xy 403.087761 -101.018256) (xy 403.033812 -101.026007) (xy 403.00656 -101.026468) (xy 402.979552 -101.026024)
			(xy 402.926075 -101.018413) (xy 402.874207 -101.003334) (xy 402.824984 -100.981091) (xy 402.77939 -100.952126)
			(xy 402.738339 -100.91702) (xy 402.70265 -100.876474) (xy 402.673037 -100.831299) (xy 402.650092 -100.782398)
			(xy 402.634274 -100.730751) (xy 402.629624 -100.704142) (xy 402.6281 -100.693474) (xy 402.61667 -100.675694)
			(xy 402.545296 -100.628196) (xy 402.536357 -100.622866) (xy 402.515901 -100.619179) (xy 402.505672 -100.621084)
			(xy 402.50491 -100.621084) (xy 402.478339 -100.627193) (xy 402.42422 -100.63382) (xy 402.39696 -100.634292)
			(xy 402.369635 -100.633839) (xy 402.315387 -100.627216) (xy 402.288756 -100.621084) (xy 402.288248 -100.621084)
			(xy 402.278018 -100.619227) (xy 402.257572 -100.6229) (xy 402.248624 -100.628196) (xy 402.17725 -100.675694)
			(xy 402.16582 -100.693474) (xy 402.164296 -100.704142) (xy 402.159588 -100.730737) (xy 402.143765 -100.782374)
			(xy 402.120819 -100.831264) (xy 402.091208 -100.87643) (xy 402.055525 -100.91697) (xy 402.014481 -100.952073)
			(xy 401.968898 -100.981037) (xy 401.919687 -101.003285) (xy 401.86783 -101.018372) (xy 401.814363 -101.025996)
			(xy 401.78736 -101.026468) (xy 401.759991 -101.025975) (xy 401.705812 -101.018165) (xy 401.653309 -101.002682)
			(xy 401.603562 -100.979846) (xy 401.557594 -100.950127) (xy 401.536662 -100.932488) (xy 401.536408 -100.932234)
			(xy 401.529329 -100.926637) (xy 401.512406 -100.920398) (xy 401.503388 -100.920042) (xy 401.436332 -100.920042)
			(xy 401.427316 -100.920405) (xy 401.410398 -100.926648) (xy 401.403312 -100.932234) (xy 401.403312 -100.932488)
			(xy 401.403058 -100.932488) (xy 401.382113 -100.950111) (xy 401.336144 -100.979826) (xy 401.2864 -101.002665)
			(xy 401.233902 -101.01816) (xy 401.179728 -101.025992) (xy 401.15236 -101.026468) (xy 401.135248 -101.026273)
			(xy 401.101161 -101.023223) (xy 401.084288 -101.020372) (xy 401.072996 -101.019019) (xy 401.051107 -101.025082)
			(xy 401.042124 -101.032056) (xy 401.01774 -101.053138) (xy 401.009295 -101.06104) (xy 401.000041 -101.082212)
			(xy 400.99996 -101.093778) (xy 401.000468 -101.112574) (xy 401.000468 -101.240082) (xy 422.594022 -101.240082)
			(xy 422.598093 -101.18446) (xy 422.610219 -101.130023) (xy 422.630142 -101.077932) (xy 422.657438 -101.029297)
			(xy 422.691524 -100.985154) (xy 422.731673 -100.946445) (xy 422.777031 -100.913994) (xy 422.826631 -100.888493)
			(xy 422.879415 -100.870486) (xy 422.934258 -100.860356) (xy 422.989992 -100.858319) (xy 423.045429 -100.864419)
			(xy 423.099386 -100.878525) (xy 423.150715 -100.900337) (xy 423.198321 -100.929391) (xy 423.241189 -100.965066)
			(xy 423.278406 -101.006603) (xy 423.309179 -101.053116) (xy 423.316929 -101.069648) (xy 423.886374 -101.069648)
			(xy 423.890445 -101.014026) (xy 423.902571 -100.959589) (xy 423.922494 -100.907498) (xy 423.94979 -100.858863)
			(xy 423.983876 -100.81472) (xy 424.024025 -100.776011) (xy 424.069383 -100.74356) (xy 424.118983 -100.718059)
			(xy 424.171767 -100.700052) (xy 424.22661 -100.689922) (xy 424.282344 -100.687885) (xy 424.337781 -100.693985)
			(xy 424.391738 -100.708091) (xy 424.443067 -100.729903) (xy 424.490673 -100.758957) (xy 424.533541 -100.794632)
			(xy 424.570758 -100.836169) (xy 424.601531 -100.882682) (xy 424.625203 -100.933179) (xy 424.641271 -100.986586)
			(xy 424.649391 -101.041762) (xy 424.6499 -101.069648) (xy 426.469554 -101.069648) (xy 426.473625 -101.014026)
			(xy 426.485751 -100.959589) (xy 426.505674 -100.907498) (xy 426.53297 -100.858863) (xy 426.567056 -100.81472)
			(xy 426.607205 -100.776011) (xy 426.652563 -100.74356) (xy 426.702163 -100.718059) (xy 426.754947 -100.700052)
			(xy 426.80979 -100.689922) (xy 426.865524 -100.687885) (xy 426.920961 -100.693985) (xy 426.974918 -100.708091)
			(xy 427.026247 -100.729903) (xy 427.073853 -100.758957) (xy 427.116721 -100.794632) (xy 427.125082 -100.803964)
			(xy 438.651394 -100.803964) (xy 438.655465 -100.748342) (xy 438.667591 -100.693905) (xy 438.687514 -100.641814)
			(xy 438.71481 -100.593179) (xy 438.748896 -100.549036) (xy 438.789045 -100.510327) (xy 438.834403 -100.477876)
			(xy 438.884003 -100.452375) (xy 438.936787 -100.434368) (xy 438.99163 -100.424238) (xy 439.047364 -100.422201)
			(xy 439.102801 -100.428301) (xy 439.156758 -100.442407) (xy 439.208087 -100.464219) (xy 439.255693 -100.493273)
			(xy 439.298561 -100.528948) (xy 439.335778 -100.570485) (xy 439.366551 -100.616998) (xy 439.390223 -100.667495)
			(xy 439.406291 -100.720902) (xy 439.414411 -100.776078) (xy 439.41492 -100.803964) (xy 439.818016 -100.803964)
			(xy 439.822087 -100.748342) (xy 439.834213 -100.693905) (xy 439.854136 -100.641814) (xy 439.881432 -100.593179)
			(xy 439.915518 -100.549036) (xy 439.955667 -100.510327) (xy 440.001025 -100.477876) (xy 440.050625 -100.452375)
			(xy 440.103409 -100.434368) (xy 440.158252 -100.424238) (xy 440.213986 -100.422201) (xy 440.269423 -100.428301)
			(xy 440.32338 -100.442407) (xy 440.374709 -100.464219) (xy 440.422315 -100.493273) (xy 440.465183 -100.528948)
			(xy 440.5024 -100.570485) (xy 440.533173 -100.616998) (xy 440.556845 -100.667495) (xy 440.572913 -100.720902)
			(xy 440.581033 -100.776078) (xy 440.581542 -100.803964) (xy 440.581033 -100.83185) (xy 440.572913 -100.887026)
			(xy 440.556845 -100.940433) (xy 440.533173 -100.99093) (xy 440.5024 -101.037443) (xy 440.465183 -101.07898)
			(xy 440.422315 -101.114655) (xy 440.374709 -101.143709) (xy 440.32338 -101.165521) (xy 440.269423 -101.179627)
			(xy 440.213986 -101.185727) (xy 440.158252 -101.18369) (xy 440.103409 -101.17356) (xy 440.050625 -101.155553)
			(xy 440.001025 -101.130052) (xy 439.955667 -101.097601) (xy 439.915518 -101.058892) (xy 439.881432 -101.014749)
			(xy 439.854136 -100.966114) (xy 439.834213 -100.914023) (xy 439.822087 -100.859586) (xy 439.818016 -100.803964)
			(xy 439.41492 -100.803964) (xy 439.414411 -100.83185) (xy 439.406291 -100.887026) (xy 439.390223 -100.940433)
			(xy 439.366551 -100.99093) (xy 439.335778 -101.037443) (xy 439.298561 -101.07898) (xy 439.255693 -101.114655)
			(xy 439.208087 -101.143709) (xy 439.156758 -101.165521) (xy 439.102801 -101.179627) (xy 439.047364 -101.185727)
			(xy 438.99163 -101.18369) (xy 438.936787 -101.17356) (xy 438.884003 -101.155553) (xy 438.834403 -101.130052)
			(xy 438.789045 -101.097601) (xy 438.748896 -101.058892) (xy 438.71481 -101.014749) (xy 438.687514 -100.966114)
			(xy 438.667591 -100.914023) (xy 438.655465 -100.859586) (xy 438.651394 -100.803964) (xy 427.125082 -100.803964)
			(xy 427.153938 -100.836169) (xy 427.184711 -100.882682) (xy 427.208383 -100.933179) (xy 427.224451 -100.986586)
			(xy 427.232571 -101.041762) (xy 427.23308 -101.069648) (xy 427.232571 -101.097534) (xy 427.224451 -101.15271)
			(xy 427.213277 -101.18985) (xy 445.29349 -101.18985) (xy 445.29349 -101.13535) (xy 445.301246 -101.081404)
			(xy 445.316601 -101.029111) (xy 445.339241 -100.979536) (xy 445.368706 -100.933687) (xy 445.404396 -100.892499)
			(xy 445.445584 -100.856808) (xy 445.491433 -100.827343) (xy 445.541008 -100.804702) (xy 445.5933 -100.789347)
			(xy 445.647246 -100.781591) (xy 445.674496 -100.781104) (xy 445.701866 -100.781571) (xy 445.756045 -100.789389)
			(xy 445.808548 -100.804877) (xy 445.858295 -100.827719) (xy 445.904262 -100.857443) (xy 445.925194 -100.875084)
			(xy 445.925448 -100.875338) (xy 445.932542 -100.880913) (xy 445.949453 -100.887166) (xy 445.958468 -100.88753)
			(xy 446.025524 -100.88753) (xy 446.034541 -100.887178) (xy 446.051458 -100.880926) (xy 446.058544 -100.875338)
			(xy 446.058544 -100.875084) (xy 446.058798 -100.875084) (xy 446.079718 -100.85743) (xy 446.125694 -100.827721)
			(xy 446.175445 -100.804888) (xy 446.227948 -100.7894) (xy 446.282126 -100.781576) (xy 446.309496 -100.781104)
			(xy 446.33675 -100.781543) (xy 446.390703 -100.789299) (xy 446.443003 -100.804656) (xy 446.492585 -100.827299)
			(xy 446.53844 -100.856767) (xy 446.579635 -100.892462) (xy 446.61533 -100.933656) (xy 446.6448 -100.979511)
			(xy 446.667443 -101.029093) (xy 446.6828 -101.081393) (xy 446.690557 -101.135346) (xy 446.690557 -101.189854)
			(xy 446.6828 -101.243807) (xy 446.667443 -101.296107) (xy 446.650574 -101.333046) (xy 448.233798 -101.333046)
			(xy 448.237869 -101.277424) (xy 448.249995 -101.222987) (xy 448.269918 -101.170896) (xy 448.297214 -101.122261)
			(xy 448.3313 -101.078118) (xy 448.371449 -101.039409) (xy 448.416807 -101.006958) (xy 448.466407 -100.981457)
			(xy 448.519191 -100.96345) (xy 448.574034 -100.95332) (xy 448.629768 -100.951283) (xy 448.685205 -100.957383)
			(xy 448.739162 -100.971489) (xy 448.790491 -100.993301) (xy 448.838097 -101.022355) (xy 448.880965 -101.05803)
			(xy 448.918182 -101.099567) (xy 448.948955 -101.14608) (xy 448.972627 -101.196577) (xy 448.988695 -101.249984)
			(xy 448.996815 -101.30516) (xy 448.997324 -101.333046) (xy 448.996815 -101.360932) (xy 448.988695 -101.416108)
			(xy 448.972627 -101.469515) (xy 448.948955 -101.520012) (xy 448.918182 -101.566525) (xy 448.880965 -101.608062)
			(xy 448.838097 -101.643737) (xy 448.790491 -101.672791) (xy 448.739162 -101.694603) (xy 448.685205 -101.708709)
			(xy 448.629768 -101.714809) (xy 448.574034 -101.712772) (xy 448.519191 -101.702642) (xy 448.466407 -101.684635)
			(xy 448.416807 -101.659134) (xy 448.371449 -101.626683) (xy 448.3313 -101.587974) (xy 448.297214 -101.543831)
			(xy 448.269918 -101.495196) (xy 448.249995 -101.443105) (xy 448.237869 -101.388668) (xy 448.233798 -101.333046)
			(xy 446.650574 -101.333046) (xy 446.6448 -101.345689) (xy 446.61533 -101.391544) (xy 446.579635 -101.432738)
			(xy 446.53844 -101.468433) (xy 446.492585 -101.497901) (xy 446.443003 -101.520544) (xy 446.390703 -101.535901)
			(xy 446.33675 -101.543657) (xy 446.309496 -101.54412) (xy 446.282125 -101.543676) (xy 446.227944 -101.535856)
			(xy 446.17544 -101.520363) (xy 446.125693 -101.497515) (xy 446.079728 -101.467785) (xy 446.058798 -101.45014)
			(xy 446.058544 -101.449886) (xy 446.05145 -101.44431) (xy 446.034539 -101.438057) (xy 446.025524 -101.437694)
			(xy 445.958468 -101.437694) (xy 445.94945 -101.438037) (xy 445.932533 -101.444295) (xy 445.925448 -101.449886)
			(xy 445.925448 -101.45014) (xy 445.925194 -101.45014) (xy 445.90428 -101.467802) (xy 445.858302 -101.497509)
			(xy 445.80855 -101.52034) (xy 445.756045 -101.535826) (xy 445.701866 -101.543649) (xy 445.674496 -101.54412)
			(xy 445.647246 -101.543609) (xy 445.5933 -101.535853) (xy 445.541008 -101.520498) (xy 445.491433 -101.497857)
			(xy 445.445584 -101.468392) (xy 445.404396 -101.432701) (xy 445.368706 -101.391513) (xy 445.339241 -101.345664)
			(xy 445.316601 -101.296089) (xy 445.301246 -101.243796) (xy 445.29349 -101.18985) (xy 427.213277 -101.18985)
			(xy 427.208383 -101.206117) (xy 427.184711 -101.256614) (xy 427.153938 -101.303127) (xy 427.116721 -101.344664)
			(xy 427.073853 -101.380339) (xy 427.026247 -101.409393) (xy 426.974918 -101.431205) (xy 426.920961 -101.445311)
			(xy 426.865524 -101.451411) (xy 426.80979 -101.449374) (xy 426.754947 -101.439244) (xy 426.702163 -101.421237)
			(xy 426.652563 -101.395736) (xy 426.607205 -101.363285) (xy 426.567056 -101.324576) (xy 426.53297 -101.280433)
			(xy 426.505674 -101.231798) (xy 426.485751 -101.179707) (xy 426.473625 -101.12527) (xy 426.469554 -101.069648)
			(xy 424.6499 -101.069648) (xy 424.649391 -101.097534) (xy 424.641271 -101.15271) (xy 424.625203 -101.206117)
			(xy 424.601531 -101.256614) (xy 424.570758 -101.303127) (xy 424.533541 -101.344664) (xy 424.490673 -101.380339)
			(xy 424.443067 -101.409393) (xy 424.391738 -101.431205) (xy 424.337781 -101.445311) (xy 424.282344 -101.451411)
			(xy 424.22661 -101.449374) (xy 424.171767 -101.439244) (xy 424.118983 -101.421237) (xy 424.069383 -101.395736)
			(xy 424.024025 -101.363285) (xy 423.983876 -101.324576) (xy 423.94979 -101.280433) (xy 423.922494 -101.231798)
			(xy 423.902571 -101.179707) (xy 423.890445 -101.12527) (xy 423.886374 -101.069648) (xy 423.316929 -101.069648)
			(xy 423.332851 -101.103613) (xy 423.348919 -101.15702) (xy 423.357039 -101.212196) (xy 423.357548 -101.240082)
			(xy 423.357039 -101.267968) (xy 423.348919 -101.323144) (xy 423.332851 -101.376551) (xy 423.309179 -101.427048)
			(xy 423.278406 -101.473561) (xy 423.241189 -101.515098) (xy 423.198321 -101.550773) (xy 423.151788 -101.579172)
			(xy 436.070754 -101.579172) (xy 436.074825 -101.52355) (xy 436.086951 -101.469113) (xy 436.106874 -101.417022)
			(xy 436.13417 -101.368387) (xy 436.168256 -101.324244) (xy 436.208405 -101.285535) (xy 436.253763 -101.253084)
			(xy 436.303363 -101.227583) (xy 436.356147 -101.209576) (xy 436.41099 -101.199446) (xy 436.466724 -101.197409)
			(xy 436.522161 -101.203509) (xy 436.576118 -101.217615) (xy 436.627447 -101.239427) (xy 436.675053 -101.268481)
			(xy 436.717921 -101.304156) (xy 436.755138 -101.345693) (xy 436.785911 -101.392206) (xy 436.809583 -101.442703)
			(xy 436.825651 -101.49611) (xy 436.833771 -101.551286) (xy 436.83428 -101.579172) (xy 436.833771 -101.607058)
			(xy 436.825651 -101.662234) (xy 436.809583 -101.715641) (xy 436.785911 -101.766138) (xy 436.755138 -101.812651)
			(xy 436.717921 -101.854188) (xy 436.698003 -101.870764) (xy 441.53912 -101.870764) (xy 441.543191 -101.815142)
			(xy 441.555317 -101.760705) (xy 441.57524 -101.708614) (xy 441.602536 -101.659979) (xy 441.636622 -101.615836)
			(xy 441.676771 -101.577127) (xy 441.722129 -101.544676) (xy 441.771729 -101.519175) (xy 441.824513 -101.501168)
			(xy 441.879356 -101.491038) (xy 441.93509 -101.489001) (xy 441.990527 -101.495101) (xy 442.044484 -101.509207)
			(xy 442.095813 -101.531019) (xy 442.143419 -101.560073) (xy 442.186287 -101.595748) (xy 442.223504 -101.637285)
			(xy 442.254277 -101.683798) (xy 442.277949 -101.734295) (xy 442.294017 -101.787702) (xy 442.302137 -101.842878)
			(xy 442.302646 -101.870764) (xy 442.302137 -101.89865) (xy 442.294017 -101.953826) (xy 442.277949 -102.007233)
			(xy 442.254277 -102.05773) (xy 442.223504 -102.104243) (xy 442.200022 -102.130451) (xy 444.843152 -102.130451)
			(xy 444.843152 -102.075949) (xy 444.850908 -102.022002) (xy 444.866261 -101.969707) (xy 444.888901 -101.920129)
			(xy 444.918365 -101.874278) (xy 444.954054 -101.833086) (xy 444.995241 -101.797392) (xy 445.041089 -101.767923)
			(xy 445.090664 -101.745277) (xy 445.142957 -101.729917) (xy 445.196903 -101.722155) (xy 445.224154 -101.721666)
			(xy 445.251524 -101.722143) (xy 445.305703 -101.729956) (xy 445.358207 -101.745441) (xy 445.407954 -101.768281)
			(xy 445.453921 -101.798005) (xy 445.474852 -101.815646) (xy 445.475106 -101.8159) (xy 445.482187 -101.821495)
			(xy 445.499108 -101.827737) (xy 445.508126 -101.828092) (xy 445.575182 -101.828092) (xy 445.584198 -101.827728)
			(xy 445.601115 -101.821486) (xy 445.608202 -101.8159) (xy 445.608202 -101.815646) (xy 445.608456 -101.815646)
			(xy 445.6294 -101.798021) (xy 445.675369 -101.768306) (xy 445.725113 -101.745466) (xy 445.777611 -101.729972)
			(xy 445.831786 -101.722141) (xy 445.859154 -101.721666) (xy 445.886407 -101.722178) (xy 445.940359 -101.729929)
			(xy 445.992659 -101.74528) (xy 446.042242 -101.767919) (xy 446.088097 -101.797383) (xy 446.129293 -101.833075)
			(xy 446.164989 -101.874266) (xy 446.194459 -101.920118) (xy 446.217104 -101.969698) (xy 446.232461 -102.021996)
			(xy 446.240219 -102.075947) (xy 446.240219 -102.095046) (xy 447.598798 -102.095046) (xy 447.602869 -102.039424)
			(xy 447.614995 -101.984987) (xy 447.634918 -101.932896) (xy 447.662214 -101.884261) (xy 447.6963 -101.840118)
			(xy 447.736449 -101.801409) (xy 447.781807 -101.768958) (xy 447.831407 -101.743457) (xy 447.884191 -101.72545)
			(xy 447.939034 -101.71532) (xy 447.994768 -101.713283) (xy 448.050205 -101.719383) (xy 448.104162 -101.733489)
			(xy 448.155491 -101.755301) (xy 448.203097 -101.784355) (xy 448.245965 -101.82003) (xy 448.283182 -101.861567)
			(xy 448.313955 -101.90808) (xy 448.337627 -101.958577) (xy 448.353695 -102.011984) (xy 448.361815 -102.06716)
			(xy 448.362324 -102.095046) (xy 448.361815 -102.122932) (xy 448.353695 -102.178108) (xy 448.337627 -102.231515)
			(xy 448.313955 -102.282012) (xy 448.303142 -102.298356) (xy 449.396523 -102.298356) (xy 449.396523 -102.243844)
			(xy 449.404281 -102.189888) (xy 449.419639 -102.137584) (xy 449.442284 -102.087999) (xy 449.471756 -102.042142)
			(xy 449.507454 -102.000945) (xy 449.548651 -101.965249) (xy 449.59451 -101.935778) (xy 449.644096 -101.913135)
			(xy 449.696399 -101.897778) (xy 449.750356 -101.890022) (xy 449.777612 -101.88956) (xy 449.804983 -101.890004)
			(xy 449.859164 -101.897825) (xy 449.911668 -101.913319) (xy 449.961414 -101.936165) (xy 450.00738 -101.965896)
			(xy 450.02831 -101.98354) (xy 450.028564 -101.983794) (xy 450.035657 -101.989371) (xy 450.052569 -101.995624)
			(xy 450.061584 -101.995986) (xy 450.12864 -101.995986) (xy 450.137659 -101.995651) (xy 450.154576 -101.989388)
			(xy 450.16166 -101.983794) (xy 450.16166 -101.98354) (xy 450.161914 -101.98354) (xy 450.182873 -101.965934)
			(xy 450.228838 -101.936216) (xy 450.278578 -101.913373) (xy 450.331073 -101.897874) (xy 450.385245 -101.890038)
			(xy 450.412612 -101.88956) (xy 450.43986 -101.890111) (xy 450.493802 -101.897868) (xy 450.546091 -101.913223)
			(xy 450.595663 -101.935863) (xy 450.641508 -101.965327) (xy 450.682693 -102.001016) (xy 450.700783 -102.021894)
			(xy 451.256654 -102.021894) (xy 451.257103 -101.994523) (xy 451.264923 -101.940343) (xy 451.280415 -101.887839)
			(xy 451.303261 -101.838092) (xy 451.33299 -101.792127) (xy 451.350634 -101.771196) (xy 451.350888 -101.770942)
			(xy 451.356462 -101.763847) (xy 451.362717 -101.746937) (xy 451.36308 -101.737922) (xy 451.36308 -101.670866)
			(xy 451.362744 -101.661847) (xy 451.356482 -101.64493) (xy 451.350888 -101.637846) (xy 451.350634 -101.637846)
			(xy 451.350634 -101.637592) (xy 451.332987 -101.616664) (xy 451.303262 -101.570696) (xy 451.280417 -101.520949)
			(xy 451.264921 -101.468446) (xy 451.257092 -101.414266) (xy 451.257093 -101.359525) (xy 451.264922 -101.305345)
			(xy 451.28042 -101.252843) (xy 451.303266 -101.203096) (xy 451.332993 -101.157129) (xy 451.350634 -101.136196)
			(xy 451.350888 -101.135942) (xy 451.356462 -101.128847) (xy 451.362717 -101.111937) (xy 451.36308 -101.102922)
			(xy 451.36308 -101.035866) (xy 451.362744 -101.026847) (xy 451.356482 -101.00993) (xy 451.350888 -101.002846)
			(xy 451.350634 -101.002846) (xy 451.350634 -101.002592) (xy 451.332983 -100.981669) (xy 451.303272 -100.935695)
			(xy 451.280438 -100.885945) (xy 451.264949 -100.833442) (xy 451.257125 -100.779264) (xy 451.256654 -100.751894)
			(xy 451.25714 -100.724643) (xy 451.264896 -100.670695) (xy 451.280251 -100.6184) (xy 451.302893 -100.568823)
			(xy 451.332359 -100.522973) (xy 451.36805 -100.481782) (xy 451.409241 -100.446091) (xy 451.455091 -100.416625)
			(xy 451.504668 -100.393983) (xy 451.556963 -100.378628) (xy 451.610911 -100.370872) (xy 451.665413 -100.370872)
			(xy 451.719361 -100.378628) (xy 451.771656 -100.393983) (xy 451.821233 -100.416625) (xy 451.867083 -100.446091)
			(xy 451.908274 -100.481782) (xy 451.943965 -100.522973) (xy 451.973431 -100.568823) (xy 451.996073 -100.6184)
			(xy 452.011428 -100.670695) (xy 452.019184 -100.724643) (xy 452.01967 -100.751894) (xy 452.019208 -100.779264)
			(xy 452.01139 -100.833444) (xy 451.995901 -100.885947) (xy 451.973058 -100.935694) (xy 451.943332 -100.981661)
			(xy 451.92569 -101.002592) (xy 451.925436 -101.002846) (xy 451.919858 -101.009938) (xy 451.913608 -101.026851)
			(xy 451.913244 -101.035866) (xy 451.913244 -101.102922) (xy 451.913581 -101.111941) (xy 451.919841 -101.128858)
			(xy 451.925436 -101.135942) (xy 451.92569 -101.135942) (xy 451.92569 -101.136196) (xy 451.943324 -101.157134)
			(xy 451.973048 -101.203101) (xy 451.995893 -101.252847) (xy 452.011389 -101.305348) (xy 452.019217 -101.359525)
			(xy 452.019218 -101.414266) (xy 452.01139 -101.468443) (xy 451.995896 -101.520945) (xy 451.973052 -101.570691)
			(xy 451.94333 -101.616659) (xy 451.92569 -101.637592) (xy 451.925436 -101.637846) (xy 451.919858 -101.644938)
			(xy 451.913608 -101.661851) (xy 451.913244 -101.670866) (xy 451.913244 -101.737922) (xy 451.913581 -101.746941)
			(xy 451.919841 -101.763858) (xy 451.925436 -101.770942) (xy 451.92569 -101.770942) (xy 451.92569 -101.771196)
			(xy 451.943339 -101.79212) (xy 451.97305 -101.838095) (xy 451.995884 -101.887844) (xy 452.011373 -101.940347)
			(xy 452.019198 -101.994524) (xy 452.01967 -102.021894) (xy 454.313036 -102.021894) (xy 454.31349 -101.994523)
			(xy 454.321309 -101.940343) (xy 454.336801 -101.88784) (xy 454.359645 -101.838093) (xy 454.389373 -101.792127)
			(xy 454.407016 -101.771196) (xy 454.40727 -101.770942) (xy 454.412853 -101.763854) (xy 454.4191 -101.746938)
			(xy 454.419462 -101.737922) (xy 454.419462 -101.670866) (xy 454.41913 -101.661846) (xy 454.412866 -101.644929)
			(xy 454.40727 -101.637846) (xy 454.407016 -101.637846) (xy 454.407016 -101.637592) (xy 454.38937 -101.616664)
			(xy 454.359646 -101.570695) (xy 454.336802 -101.520948) (xy 454.321307 -101.468445) (xy 454.313479 -101.414266)
			(xy 454.313479 -101.359525) (xy 454.321308 -101.305346) (xy 454.336805 -101.252844) (xy 454.359651 -101.203097)
			(xy 454.389375 -101.157129) (xy 454.407016 -101.136196) (xy 454.40727 -101.135942) (xy 454.412853 -101.128854)
			(xy 454.4191 -101.111938) (xy 454.419462 -101.102922) (xy 454.419462 -101.035866) (xy 454.41913 -101.026846)
			(xy 454.412866 -101.009929) (xy 454.40727 -101.002846) (xy 454.407016 -101.002846) (xy 454.407016 -101.002592)
			(xy 454.389362 -100.981672) (xy 454.359652 -100.935696) (xy 454.336819 -100.885945) (xy 454.321331 -100.833442)
			(xy 454.313507 -100.779264) (xy 454.313036 -100.751894) (xy 454.313522 -100.724643) (xy 454.321278 -100.670695)
			(xy 454.336633 -100.6184) (xy 454.359275 -100.568823) (xy 454.388741 -100.522973) (xy 454.424432 -100.481782)
			(xy 454.465623 -100.446091) (xy 454.511473 -100.416625) (xy 454.56105 -100.393983) (xy 454.613345 -100.378628)
			(xy 454.667293 -100.370872) (xy 454.721795 -100.370872) (xy 454.775743 -100.378628) (xy 454.828038 -100.393983)
			(xy 454.877615 -100.416625) (xy 454.923465 -100.446091) (xy 454.964656 -100.481782) (xy 455.000347 -100.522973)
			(xy 455.029813 -100.568823) (xy 455.052455 -100.6184) (xy 455.06781 -100.670695) (xy 455.075566 -100.724643)
			(xy 455.076052 -100.751894) (xy 455.075594 -100.779265) (xy 455.067776 -100.833445) (xy 455.052286 -100.885948)
			(xy 455.029442 -100.935695) (xy 454.999715 -100.981661) (xy 454.982072 -101.002592) (xy 454.981818 -101.002846)
			(xy 454.97625 -101.009946) (xy 454.969992 -101.026852) (xy 454.969626 -101.035866) (xy 454.969626 -101.102922)
			(xy 454.969967 -101.111941) (xy 454.976225 -101.128858) (xy 454.981818 -101.135942) (xy 454.982072 -101.135942)
			(xy 454.982072 -101.136196) (xy 454.999707 -101.157133) (xy 455.029432 -101.2031) (xy 455.052278 -101.252846)
			(xy 455.067775 -101.305347) (xy 455.075604 -101.359525) (xy 455.075604 -101.414266) (xy 455.067776 -101.468444)
			(xy 455.052281 -101.520946) (xy 455.029436 -101.570692) (xy 454.999712 -101.616659) (xy 454.982072 -101.637592)
			(xy 454.981818 -101.637846) (xy 454.97625 -101.644946) (xy 454.969992 -101.661852) (xy 454.969626 -101.670866)
			(xy 454.969626 -101.737922) (xy 454.969967 -101.746941) (xy 454.976225 -101.763858) (xy 454.981818 -101.770942)
			(xy 454.982072 -101.770942) (xy 454.982072 -101.771196) (xy 454.999718 -101.792122) (xy 455.02943 -101.838096)
			(xy 455.052265 -101.887845) (xy 455.067754 -101.940347) (xy 455.07558 -101.994524) (xy 455.076052 -102.021894)
			(xy 455.075566 -102.049145) (xy 455.06781 -102.103093) (xy 455.052455 -102.155388) (xy 455.029813 -102.204965)
			(xy 455.000347 -102.250815) (xy 454.964656 -102.292006) (xy 454.923465 -102.327697) (xy 454.877615 -102.357163)
			(xy 454.828038 -102.379805) (xy 454.775743 -102.39516) (xy 454.721795 -102.402916) (xy 454.667293 -102.402916)
			(xy 454.613345 -102.39516) (xy 454.56105 -102.379805) (xy 454.511473 -102.357163) (xy 454.465623 -102.327697)
			(xy 454.424432 -102.292006) (xy 454.388741 -102.250815) (xy 454.359275 -102.204965) (xy 454.336633 -102.155388)
			(xy 454.321278 -102.103093) (xy 454.313522 -102.049145) (xy 454.313036 -102.021894) (xy 452.01967 -102.021894)
			(xy 452.019184 -102.049145) (xy 452.011428 -102.103093) (xy 451.996073 -102.155388) (xy 451.973431 -102.204965)
			(xy 451.943965 -102.250815) (xy 451.908274 -102.292006) (xy 451.867083 -102.327697) (xy 451.821233 -102.357163)
			(xy 451.771656 -102.379805) (xy 451.719361 -102.39516) (xy 451.665413 -102.402916) (xy 451.610911 -102.402916)
			(xy 451.556963 -102.39516) (xy 451.504668 -102.379805) (xy 451.455091 -102.357163) (xy 451.409241 -102.327697)
			(xy 451.36805 -102.292006) (xy 451.332359 -102.250815) (xy 451.302893 -102.204965) (xy 451.280251 -102.155388)
			(xy 451.264896 -102.103093) (xy 451.25714 -102.049145) (xy 451.256654 -102.021894) (xy 450.700783 -102.021894)
			(xy 450.71838 -102.042202) (xy 450.747843 -102.088048) (xy 450.770481 -102.13762) (xy 450.785834 -102.18991)
			(xy 450.79359 -102.243852) (xy 450.79359 -102.298348) (xy 450.785834 -102.35229) (xy 450.770481 -102.40458)
			(xy 450.747843 -102.454152) (xy 450.71838 -102.499998) (xy 450.682693 -102.541184) (xy 450.641508 -102.576873)
			(xy 450.595663 -102.606337) (xy 450.546091 -102.628977) (xy 450.493802 -102.644332) (xy 450.43986 -102.652089)
			(xy 450.412612 -102.652576) (xy 450.385242 -102.652109) (xy 450.331062 -102.644292) (xy 450.278559 -102.628804)
			(xy 450.228812 -102.605962) (xy 450.182846 -102.576237) (xy 450.161914 -102.558596) (xy 450.16166 -102.558342)
			(xy 450.154565 -102.552768) (xy 450.137655 -102.546515) (xy 450.12864 -102.54615) (xy 450.061584 -102.54615)
			(xy 450.052565 -102.546489) (xy 450.035648 -102.552748) (xy 450.028564 -102.558342) (xy 450.028564 -102.558596)
			(xy 450.02831 -102.558596) (xy 450.007384 -102.576243) (xy 449.96141 -102.605954) (xy 449.911661 -102.628788)
			(xy 449.859159 -102.644278) (xy 449.804982 -102.652103) (xy 449.777612 -102.652576) (xy 449.750356 -102.652178)
			(xy 449.696399 -102.644422) (xy 449.644096 -102.629065) (xy 449.59451 -102.606422) (xy 449.548651 -102.576951)
			(xy 449.507454 -102.541255) (xy 449.471756 -102.500058) (xy 449.442284 -102.454201) (xy 449.419639 -102.404616)
			(xy 449.404281 -102.352312) (xy 449.396523 -102.298356) (xy 448.303142 -102.298356) (xy 448.283182 -102.328525)
			(xy 448.245965 -102.370062) (xy 448.203097 -102.405737) (xy 448.155491 -102.434791) (xy 448.104162 -102.456603)
			(xy 448.050205 -102.470709) (xy 447.994768 -102.476809) (xy 447.939034 -102.474772) (xy 447.884191 -102.464642)
			(xy 447.831407 -102.446635) (xy 447.781807 -102.421134) (xy 447.736449 -102.388683) (xy 447.6963 -102.349974)
			(xy 447.662214 -102.305831) (xy 447.634918 -102.257196) (xy 447.614995 -102.205105) (xy 447.602869 -102.150668)
			(xy 447.598798 -102.095046) (xy 446.240219 -102.095046) (xy 446.240219 -102.130453) (xy 446.232461 -102.184404)
			(xy 446.217104 -102.236702) (xy 446.194459 -102.286282) (xy 446.164989 -102.332134) (xy 446.129293 -102.373325)
			(xy 446.088097 -102.409017) (xy 446.042242 -102.438481) (xy 445.992659 -102.46112) (xy 445.940359 -102.476471)
			(xy 445.886407 -102.484222) (xy 445.859154 -102.484682) (xy 445.831785 -102.484189) (xy 445.777607 -102.476378)
			(xy 445.725104 -102.460896) (xy 445.675356 -102.43806) (xy 445.629388 -102.408341) (xy 445.608456 -102.390702)
			(xy 445.608202 -102.390448) (xy 445.601124 -102.38485) (xy 445.5842 -102.378611) (xy 445.575182 -102.378256)
			(xy 445.508126 -102.378256) (xy 445.499109 -102.378613) (xy 445.482191 -102.384859) (xy 445.475106 -102.390448)
			(xy 445.475106 -102.390702) (xy 445.474852 -102.390702) (xy 445.453911 -102.40833) (xy 445.407941 -102.438044)
			(xy 445.358196 -102.460882) (xy 445.305697 -102.476375) (xy 445.251523 -102.484206) (xy 445.224154 -102.484682)
			(xy 445.196903 -102.484245) (xy 445.142957 -102.476483) (xy 445.090664 -102.461123) (xy 445.041089 -102.438477)
			(xy 444.995241 -102.409008) (xy 444.954054 -102.373314) (xy 444.918365 -102.332122) (xy 444.888901 -102.286271)
			(xy 444.866261 -102.236693) (xy 444.850908 -102.184398) (xy 444.843152 -102.130451) (xy 442.200022 -102.130451)
			(xy 442.186287 -102.14578) (xy 442.143419 -102.181455) (xy 442.095813 -102.210509) (xy 442.044484 -102.232321)
			(xy 441.990527 -102.246427) (xy 441.93509 -102.252527) (xy 441.879356 -102.25049) (xy 441.824513 -102.24036)
			(xy 441.771729 -102.222353) (xy 441.722129 -102.196852) (xy 441.676771 -102.164401) (xy 441.636622 -102.125692)
			(xy 441.602536 -102.081549) (xy 441.57524 -102.032914) (xy 441.555317 -101.980823) (xy 441.543191 -101.926386)
			(xy 441.53912 -101.870764) (xy 436.698003 -101.870764) (xy 436.675053 -101.889863) (xy 436.627447 -101.918917)
			(xy 436.576118 -101.940729) (xy 436.522161 -101.954835) (xy 436.466724 -101.960935) (xy 436.41099 -101.958898)
			(xy 436.356147 -101.948768) (xy 436.303363 -101.930761) (xy 436.253763 -101.90526) (xy 436.208405 -101.872809)
			(xy 436.168256 -101.8341) (xy 436.13417 -101.789957) (xy 436.106874 -101.741322) (xy 436.086951 -101.689231)
			(xy 436.074825 -101.634794) (xy 436.070754 -101.579172) (xy 423.151788 -101.579172) (xy 423.150715 -101.579827)
			(xy 423.099386 -101.601639) (xy 423.045429 -101.615745) (xy 422.989992 -101.621845) (xy 422.934258 -101.619808)
			(xy 422.879415 -101.609678) (xy 422.826631 -101.591671) (xy 422.777031 -101.56617) (xy 422.731673 -101.533719)
			(xy 422.691524 -101.49501) (xy 422.657438 -101.450867) (xy 422.630142 -101.402232) (xy 422.610219 -101.350141)
			(xy 422.598093 -101.295704) (xy 422.594022 -101.240082) (xy 401.000468 -101.240082) (xy 401.000468 -101.782372)
			(xy 405.89784 -101.782372) (xy 405.901911 -101.72675) (xy 405.914037 -101.672313) (xy 405.93396 -101.620222)
			(xy 405.961256 -101.571587) (xy 405.995342 -101.527444) (xy 406.035491 -101.488735) (xy 406.080849 -101.456284)
			(xy 406.130449 -101.430783) (xy 406.183233 -101.412776) (xy 406.238076 -101.402646) (xy 406.29381 -101.400609)
			(xy 406.349247 -101.406709) (xy 406.403204 -101.420815) (xy 406.454533 -101.442627) (xy 406.502139 -101.471681)
			(xy 406.545007 -101.507356) (xy 406.582224 -101.548893) (xy 406.612997 -101.595406) (xy 406.636669 -101.645903)
			(xy 406.652737 -101.69931) (xy 406.660857 -101.754486) (xy 406.661366 -101.782372) (xy 406.660857 -101.810258)
			(xy 406.652737 -101.865434) (xy 406.636669 -101.918841) (xy 406.612997 -101.969338) (xy 406.582224 -102.015851)
			(xy 406.545007 -102.057388) (xy 406.502139 -102.093063) (xy 406.454533 -102.122117) (xy 406.403204 -102.143929)
			(xy 406.349247 -102.158035) (xy 406.29381 -102.164135) (xy 406.238076 -102.162098) (xy 406.183233 -102.151968)
			(xy 406.130449 -102.133961) (xy 406.080849 -102.10846) (xy 406.035491 -102.076009) (xy 405.995342 -102.0373)
			(xy 405.961256 -101.993157) (xy 405.93396 -101.944522) (xy 405.914037 -101.892431) (xy 405.901911 -101.837994)
			(xy 405.89784 -101.782372) (xy 401.000468 -101.782372) (xy 401.000468 -101.976428) (xy 400.99996 -101.996494)
			(xy 401.000145 -102.007941) (xy 401.009262 -102.028913) (xy 401.017486 -102.03688) (xy 401.042124 -102.058216)
			(xy 401.051112 -102.065312) (xy 401.073204 -102.071258) (xy 401.084542 -102.069646) (xy 401.101349 -102.066778)
			(xy 401.135311 -102.06373) (xy 401.15236 -102.06355) (xy 401.17973 -102.064027) (xy 401.233909 -102.071841)
			(xy 401.286413 -102.087326) (xy 401.33616 -102.110166) (xy 401.382126 -102.139889) (xy 401.403058 -102.15753)
			(xy 401.409916 -102.163626) (xy 401.426934 -102.169976) (xy 401.512278 -102.169976) (xy 401.52955 -102.163372)
			(xy 401.536408 -102.157276) (xy 401.557362 -102.139663) (xy 401.603324 -102.109938) (xy 401.653066 -102.087092)
			(xy 401.705563 -102.071596) (xy 401.759738 -102.063768) (xy 401.787106 -102.063296) (xy 401.78736 -102.063296)
			(xy 401.814337 -102.063761) (xy 401.867754 -102.071349) (xy 401.919567 -102.086393) (xy 401.968741 -102.108593)
			(xy 402.014294 -102.137504) (xy 402.055316 -102.17255) (xy 402.090986 -102.213029) (xy 402.120591 -102.258134)
			(xy 402.143542 -102.306963) (xy 402.159378 -102.35854) (xy 402.164042 -102.385114) (xy 402.166216 -102.395341)
			(xy 402.17749 -102.41292) (xy 402.185886 -102.41915) (xy 402.25726 -102.466648) (xy 402.278342 -102.470458)
			(xy 402.288502 -102.467918) (xy 402.315204 -102.461846) (xy 402.369579 -102.455351) (xy 402.39696 -102.454964)
			(xy 402.424342 -102.455331) (xy 402.478718 -102.461831) (xy 402.505418 -102.467918) (xy 402.515578 -102.470458)
			(xy 402.53666 -102.466648) (xy 402.616924 -102.413308) (xy 402.6281 -102.395782) (xy 402.629878 -102.385114)
			(xy 402.634554 -102.358545) (xy 402.650407 -102.306979) (xy 402.673367 -102.258161) (xy 402.702978 -102.213066)
			(xy 402.738647 -102.172593) (xy 402.779664 -102.137551) (xy 402.825209 -102.108637) (xy 402.874374 -102.08643)
			(xy 402.926178 -102.071373) (xy 402.979586 -102.063766) (xy 403.00656 -102.063296) (xy 403.033815 -102.063749)
			(xy 403.087771 -102.071501) (xy 403.140074 -102.086854) (xy 403.18966 -102.109494) (xy 403.235518 -102.138961)
			(xy 403.276716 -102.174655) (xy 403.312415 -102.21585) (xy 403.341887 -102.261705) (xy 403.364532 -102.311288)
			(xy 403.37989 -102.36359) (xy 403.387649 -102.417545) (xy 403.387649 -102.472055) (xy 403.37989 -102.52601)
			(xy 403.364532 -102.578312) (xy 403.341887 -102.627895) (xy 403.312415 -102.67375) (xy 403.276716 -102.714945)
			(xy 403.235518 -102.750639) (xy 403.18966 -102.780106) (xy 403.149654 -102.798372) (xy 405.89784 -102.798372)
			(xy 405.901911 -102.74275) (xy 405.914037 -102.688313) (xy 405.93396 -102.636222) (xy 405.961256 -102.587587)
			(xy 405.995342 -102.543444) (xy 406.035491 -102.504735) (xy 406.080849 -102.472284) (xy 406.130449 -102.446783)
			(xy 406.183233 -102.428776) (xy 406.238076 -102.418646) (xy 406.29381 -102.416609) (xy 406.349247 -102.422709)
			(xy 406.403204 -102.436815) (xy 406.410647 -102.439978) (xy 415.230816 -102.439978) (xy 415.234887 -102.384356)
			(xy 415.247013 -102.329919) (xy 415.266936 -102.277828) (xy 415.294232 -102.229193) (xy 415.328318 -102.18505)
			(xy 415.368467 -102.146341) (xy 415.413825 -102.11389) (xy 415.463425 -102.088389) (xy 415.516209 -102.070382)
			(xy 415.571052 -102.060252) (xy 415.626786 -102.058215) (xy 415.682223 -102.064315) (xy 415.73618 -102.078421)
			(xy 415.787509 -102.100233) (xy 415.835115 -102.129287) (xy 415.877983 -102.164962) (xy 415.9152 -102.206499)
			(xy 415.945973 -102.253012) (xy 415.969645 -102.303509) (xy 415.985713 -102.356916) (xy 415.993833 -102.412092)
			(xy 415.994342 -102.439978) (xy 422.213022 -102.439978) (xy 422.217093 -102.384356) (xy 422.229219 -102.329919)
			(xy 422.249142 -102.277828) (xy 422.276438 -102.229193) (xy 422.310524 -102.18505) (xy 422.350673 -102.146341)
			(xy 422.396031 -102.11389) (xy 422.445631 -102.088389) (xy 422.498415 -102.070382) (xy 422.553258 -102.060252)
			(xy 422.608992 -102.058215) (xy 422.664429 -102.064315) (xy 422.718386 -102.078421) (xy 422.742566 -102.088696)
			(xy 426.469554 -102.088696) (xy 426.473625 -102.033074) (xy 426.485751 -101.978637) (xy 426.505674 -101.926546)
			(xy 426.53297 -101.877911) (xy 426.567056 -101.833768) (xy 426.607205 -101.795059) (xy 426.652563 -101.762608)
			(xy 426.702163 -101.737107) (xy 426.754947 -101.7191) (xy 426.80979 -101.70897) (xy 426.865524 -101.706933)
			(xy 426.920961 -101.713033) (xy 426.974918 -101.727139) (xy 427.026247 -101.748951) (xy 427.073853 -101.778005)
			(xy 427.116721 -101.81368) (xy 427.153938 -101.855217) (xy 427.184711 -101.90173) (xy 427.208383 -101.952227)
			(xy 427.224451 -102.005634) (xy 427.232571 -102.06081) (xy 427.23308 -102.088696) (xy 427.232571 -102.116582)
			(xy 427.224451 -102.171758) (xy 427.208383 -102.225165) (xy 427.184711 -102.275662) (xy 427.153938 -102.322175)
			(xy 427.116721 -102.363712) (xy 427.073853 -102.399387) (xy 427.026247 -102.428441) (xy 426.974918 -102.450253)
			(xy 426.920961 -102.464359) (xy 426.865524 -102.470459) (xy 426.80979 -102.468422) (xy 426.754947 -102.458292)
			(xy 426.702163 -102.440285) (xy 426.652563 -102.414784) (xy 426.607205 -102.382333) (xy 426.567056 -102.343624)
			(xy 426.53297 -102.299481) (xy 426.505674 -102.250846) (xy 426.485751 -102.198755) (xy 426.473625 -102.144318)
			(xy 426.469554 -102.088696) (xy 422.742566 -102.088696) (xy 422.769715 -102.100233) (xy 422.817321 -102.129287)
			(xy 422.860189 -102.164962) (xy 422.897406 -102.206499) (xy 422.928179 -102.253012) (xy 422.951851 -102.303509)
			(xy 422.967919 -102.356916) (xy 422.976039 -102.412092) (xy 422.976548 -102.439978) (xy 422.976039 -102.467864)
			(xy 422.972929 -102.489) (xy 423.102022 -102.489) (xy 423.106093 -102.433378) (xy 423.118219 -102.378941)
			(xy 423.138142 -102.32685) (xy 423.165438 -102.278215) (xy 423.199524 -102.234072) (xy 423.239673 -102.195363)
			(xy 423.285031 -102.162912) (xy 423.334631 -102.137411) (xy 423.387415 -102.119404) (xy 423.442258 -102.109274)
			(xy 423.497992 -102.107237) (xy 423.553429 -102.113337) (xy 423.607386 -102.127443) (xy 423.658715 -102.149255)
			(xy 423.706321 -102.178309) (xy 423.749189 -102.213984) (xy 423.786406 -102.255521) (xy 423.817179 -102.302034)
			(xy 423.840851 -102.352531) (xy 423.856919 -102.405938) (xy 423.865039 -102.461114) (xy 423.865548 -102.489)
			(xy 423.865039 -102.516886) (xy 423.856919 -102.572062) (xy 423.840851 -102.625469) (xy 423.817179 -102.675966)
			(xy 423.786406 -102.722479) (xy 423.749189 -102.764016) (xy 423.706321 -102.799691) (xy 423.658715 -102.828745)
			(xy 423.607386 -102.850557) (xy 423.553429 -102.864663) (xy 423.497992 -102.870763) (xy 423.442258 -102.868726)
			(xy 423.387415 -102.858596) (xy 423.334631 -102.840589) (xy 423.285031 -102.815088) (xy 423.239673 -102.782637)
			(xy 423.199524 -102.743928) (xy 423.165438 -102.699785) (xy 423.138142 -102.65115) (xy 423.118219 -102.599059)
			(xy 423.106093 -102.544622) (xy 423.102022 -102.489) (xy 422.972929 -102.489) (xy 422.967919 -102.52304)
			(xy 422.951851 -102.576447) (xy 422.928179 -102.626944) (xy 422.897406 -102.673457) (xy 422.860189 -102.714994)
			(xy 422.817321 -102.750669) (xy 422.769715 -102.779723) (xy 422.718386 -102.801535) (xy 422.664429 -102.815641)
			(xy 422.608992 -102.821741) (xy 422.553258 -102.819704) (xy 422.498415 -102.809574) (xy 422.445631 -102.791567)
			(xy 422.396031 -102.766066) (xy 422.350673 -102.733615) (xy 422.310524 -102.694906) (xy 422.276438 -102.650763)
			(xy 422.249142 -102.602128) (xy 422.229219 -102.550037) (xy 422.217093 -102.4956) (xy 422.213022 -102.439978)
			(xy 415.994342 -102.439978) (xy 415.993833 -102.467864) (xy 415.985713 -102.52304) (xy 415.969645 -102.576447)
			(xy 415.945973 -102.626944) (xy 415.9152 -102.673457) (xy 415.877983 -102.714994) (xy 415.835115 -102.750669)
			(xy 415.787509 -102.779723) (xy 415.73618 -102.801535) (xy 415.682223 -102.815641) (xy 415.626786 -102.821741)
			(xy 415.571052 -102.819704) (xy 415.516209 -102.809574) (xy 415.463425 -102.791567) (xy 415.413825 -102.766066)
			(xy 415.368467 -102.733615) (xy 415.328318 -102.694906) (xy 415.294232 -102.650763) (xy 415.266936 -102.602128)
			(xy 415.247013 -102.550037) (xy 415.234887 -102.4956) (xy 415.230816 -102.439978) (xy 406.410647 -102.439978)
			(xy 406.454533 -102.458627) (xy 406.502139 -102.487681) (xy 406.545007 -102.523356) (xy 406.582224 -102.564893)
			(xy 406.612997 -102.611406) (xy 406.636669 -102.661903) (xy 406.652737 -102.71531) (xy 406.660857 -102.770486)
			(xy 406.661366 -102.798372) (xy 406.660857 -102.826258) (xy 406.652737 -102.881434) (xy 406.636669 -102.934841)
			(xy 406.612997 -102.985338) (xy 406.582224 -103.031851) (xy 406.545007 -103.073388) (xy 406.507386 -103.104696)
			(xy 426.469554 -103.104696) (xy 426.473625 -103.049074) (xy 426.485751 -102.994637) (xy 426.505674 -102.942546)
			(xy 426.53297 -102.893911) (xy 426.567056 -102.849768) (xy 426.607205 -102.811059) (xy 426.652563 -102.778608)
			(xy 426.702163 -102.753107) (xy 426.754947 -102.7351) (xy 426.80979 -102.72497) (xy 426.865524 -102.722933)
			(xy 426.920961 -102.729033) (xy 426.974918 -102.743139) (xy 427.026247 -102.764951) (xy 427.073853 -102.794005)
			(xy 427.116721 -102.82968) (xy 427.153938 -102.871217) (xy 427.184711 -102.91773) (xy 427.208383 -102.968227)
			(xy 427.224451 -103.021634) (xy 427.232571 -103.07681) (xy 427.23308 -103.104696) (xy 427.232571 -103.132582)
			(xy 427.231591 -103.13924) (xy 437.807098 -103.13924) (xy 437.811169 -103.083618) (xy 437.823295 -103.029181)
			(xy 437.843218 -102.97709) (xy 437.870514 -102.928455) (xy 437.9046 -102.884312) (xy 437.944749 -102.845603)
			(xy 437.990107 -102.813152) (xy 438.039707 -102.787651) (xy 438.092491 -102.769644) (xy 438.147334 -102.759514)
			(xy 438.203068 -102.757477) (xy 438.258505 -102.763577) (xy 438.312462 -102.777683) (xy 438.363791 -102.799495)
			(xy 438.411397 -102.828549) (xy 438.454265 -102.864224) (xy 438.491482 -102.905761) (xy 438.522255 -102.952274)
			(xy 438.545927 -103.002771) (xy 438.561995 -103.056178) (xy 438.570115 -103.111354) (xy 438.570624 -103.13924)
			(xy 438.570115 -103.167126) (xy 438.561995 -103.222302) (xy 438.545927 -103.275709) (xy 438.522255 -103.326206)
			(xy 438.491482 -103.372719) (xy 438.454265 -103.414256) (xy 438.411397 -103.449931) (xy 438.363791 -103.478985)
			(xy 438.312462 -103.500797) (xy 438.258505 -103.514903) (xy 438.203068 -103.521003) (xy 438.147334 -103.518966)
			(xy 438.092491 -103.508836) (xy 438.039707 -103.490829) (xy 437.990107 -103.465328) (xy 437.944749 -103.432877)
			(xy 437.9046 -103.394168) (xy 437.870514 -103.350025) (xy 437.843218 -103.30139) (xy 437.823295 -103.249299)
			(xy 437.811169 -103.194862) (xy 437.807098 -103.13924) (xy 427.231591 -103.13924) (xy 427.224451 -103.187758)
			(xy 427.208383 -103.241165) (xy 427.184711 -103.291662) (xy 427.153938 -103.338175) (xy 427.116721 -103.379712)
			(xy 427.073853 -103.415387) (xy 427.026247 -103.444441) (xy 426.974918 -103.466253) (xy 426.920961 -103.480359)
			(xy 426.865524 -103.486459) (xy 426.80979 -103.484422) (xy 426.754947 -103.474292) (xy 426.702163 -103.456285)
			(xy 426.652563 -103.430784) (xy 426.607205 -103.398333) (xy 426.567056 -103.359624) (xy 426.53297 -103.315481)
			(xy 426.505674 -103.266846) (xy 426.485751 -103.214755) (xy 426.473625 -103.160318) (xy 426.469554 -103.104696)
			(xy 406.507386 -103.104696) (xy 406.502139 -103.109063) (xy 406.454533 -103.138117) (xy 406.403204 -103.159929)
			(xy 406.349247 -103.174035) (xy 406.29381 -103.180135) (xy 406.238076 -103.178098) (xy 406.183233 -103.167968)
			(xy 406.130449 -103.149961) (xy 406.080849 -103.12446) (xy 406.035491 -103.092009) (xy 405.995342 -103.0533)
			(xy 405.961256 -103.009157) (xy 405.93396 -102.960522) (xy 405.914037 -102.908431) (xy 405.901911 -102.853994)
			(xy 405.89784 -102.798372) (xy 403.149654 -102.798372) (xy 403.140074 -102.802746) (xy 403.087771 -102.818099)
			(xy 403.033815 -102.825851) (xy 403.00656 -102.826312) (xy 402.989448 -102.826118) (xy 402.955361 -102.823068)
			(xy 402.938488 -102.820216) (xy 402.927196 -102.818876) (xy 402.90531 -102.824932) (xy 402.896324 -102.8319)
			(xy 402.87194 -102.852982) (xy 402.863521 -102.860907) (xy 402.854253 -102.882061) (xy 402.85416 -102.893622)
			(xy 402.854668 -102.912418) (xy 402.854668 -103.776272) (xy 402.85416 -103.796338) (xy 402.854377 -103.807782)
			(xy 402.857235 -103.814372) (xy 405.89784 -103.814372) (xy 405.901911 -103.75875) (xy 405.914037 -103.704313)
			(xy 405.93396 -103.652222) (xy 405.961256 -103.603587) (xy 405.995342 -103.559444) (xy 406.035491 -103.520735)
			(xy 406.080849 -103.488284) (xy 406.130449 -103.462783) (xy 406.183233 -103.444776) (xy 406.238076 -103.434646)
			(xy 406.29381 -103.432609) (xy 406.349247 -103.438709) (xy 406.403204 -103.452815) (xy 406.454533 -103.474627)
			(xy 406.502139 -103.503681) (xy 406.545007 -103.539356) (xy 406.582224 -103.580893) (xy 406.612997 -103.627406)
			(xy 406.636669 -103.677903) (xy 406.652737 -103.73131) (xy 406.660857 -103.786486) (xy 406.661366 -103.814372)
			(xy 406.660857 -103.842258) (xy 406.652737 -103.897434) (xy 406.636669 -103.950841) (xy 406.612997 -104.001338)
			(xy 406.582224 -104.047851) (xy 406.545007 -104.089388) (xy 406.502139 -104.125063) (xy 406.454533 -104.154117)
			(xy 406.403204 -104.175929) (xy 406.349247 -104.190035) (xy 406.29381 -104.196135) (xy 406.238076 -104.194098)
			(xy 406.183233 -104.183968) (xy 406.130449 -104.165961) (xy 406.080849 -104.14046) (xy 406.035491 -104.108009)
			(xy 405.995342 -104.0693) (xy 405.961256 -104.025157) (xy 405.93396 -103.976522) (xy 405.914037 -103.924431)
			(xy 405.901911 -103.869994) (xy 405.89784 -103.814372) (xy 402.857235 -103.814372) (xy 402.863472 -103.828753)
			(xy 402.871686 -103.836724) (xy 402.896324 -103.85806) (xy 402.905309 -103.86516) (xy 402.927403 -103.871101)
			(xy 402.938742 -103.86949) (xy 402.955549 -103.866622) (xy 402.989511 -103.863574) (xy 403.00656 -103.863394)
			(xy 403.033815 -103.863851) (xy 403.08777 -103.871603) (xy 403.140073 -103.886956) (xy 403.189659 -103.909596)
			(xy 403.235517 -103.939063) (xy 403.276715 -103.974757) (xy 403.312413 -104.015951) (xy 403.341885 -104.061806)
			(xy 403.36453 -104.111389) (xy 403.379888 -104.16369) (xy 403.387647 -104.217645) (xy 403.387647 -104.240076)
			(xy 415.230816 -104.240076) (xy 415.234887 -104.184454) (xy 415.247013 -104.130017) (xy 415.266936 -104.077926)
			(xy 415.294232 -104.029291) (xy 415.328318 -103.985148) (xy 415.368467 -103.946439) (xy 415.413825 -103.913988)
			(xy 415.463425 -103.888487) (xy 415.516209 -103.87048) (xy 415.571052 -103.86035) (xy 415.626786 -103.858313)
			(xy 415.682223 -103.864413) (xy 415.73618 -103.878519) (xy 415.787509 -103.900331) (xy 415.835115 -103.929385)
			(xy 415.877983 -103.96506) (xy 415.9152 -104.006597) (xy 415.945973 -104.05311) (xy 415.969645 -104.103607)
			(xy 415.985713 -104.157014) (xy 415.993833 -104.21219) (xy 415.994342 -104.240076) (xy 422.213022 -104.240076)
			(xy 422.217093 -104.184454) (xy 422.229219 -104.130017) (xy 422.249142 -104.077926) (xy 422.276438 -104.029291)
			(xy 422.310524 -103.985148) (xy 422.350673 -103.946439) (xy 422.396031 -103.913988) (xy 422.445631 -103.888487)
			(xy 422.498415 -103.87048) (xy 422.553258 -103.86035) (xy 422.608992 -103.858313) (xy 422.664429 -103.864413)
			(xy 422.718386 -103.878519) (xy 422.735991 -103.886) (xy 423.610022 -103.886) (xy 423.614093 -103.830378)
			(xy 423.626219 -103.775941) (xy 423.646142 -103.72385) (xy 423.673438 -103.675215) (xy 423.707524 -103.631072)
			(xy 423.747673 -103.592363) (xy 423.793031 -103.559912) (xy 423.842631 -103.534411) (xy 423.895415 -103.516404)
			(xy 423.950258 -103.506274) (xy 424.005992 -103.504237) (xy 424.061429 -103.510337) (xy 424.115386 -103.524443)
			(xy 424.166715 -103.546255) (xy 424.214321 -103.575309) (xy 424.257189 -103.610984) (xy 424.294406 -103.652521)
			(xy 424.325179 -103.699034) (xy 424.348851 -103.749531) (xy 424.364919 -103.802938) (xy 424.373039 -103.858114)
			(xy 424.373548 -103.886) (xy 424.373039 -103.913886) (xy 424.364919 -103.969062) (xy 424.348851 -104.022469)
			(xy 424.325179 -104.072966) (xy 424.294406 -104.119479) (xy 424.293316 -104.120696) (xy 426.469554 -104.120696)
			(xy 426.473625 -104.065074) (xy 426.485751 -104.010637) (xy 426.505674 -103.958546) (xy 426.53297 -103.909911)
			(xy 426.567056 -103.865768) (xy 426.607205 -103.827059) (xy 426.652563 -103.794608) (xy 426.702163 -103.769107)
			(xy 426.754947 -103.7511) (xy 426.80979 -103.74097) (xy 426.865524 -103.738933) (xy 426.920961 -103.745033)
			(xy 426.974918 -103.759139) (xy 427.026247 -103.780951) (xy 427.073853 -103.810005) (xy 427.116721 -103.84568)
			(xy 427.153938 -103.887217) (xy 427.184711 -103.93373) (xy 427.208383 -103.984227) (xy 427.224451 -104.037634)
			(xy 427.232571 -104.09281) (xy 427.23308 -104.120696) (xy 427.232571 -104.148582) (xy 427.224451 -104.203758)
			(xy 427.208383 -104.257165) (xy 427.184711 -104.307662) (xy 427.153938 -104.354175) (xy 427.116721 -104.395712)
			(xy 427.073853 -104.431387) (xy 427.026247 -104.460441) (xy 426.974918 -104.482253) (xy 426.920961 -104.496359)
			(xy 426.865524 -104.502459) (xy 426.80979 -104.500422) (xy 426.754947 -104.490292) (xy 426.702163 -104.472285)
			(xy 426.652563 -104.446784) (xy 426.607205 -104.414333) (xy 426.567056 -104.375624) (xy 426.53297 -104.331481)
			(xy 426.505674 -104.282846) (xy 426.485751 -104.230755) (xy 426.473625 -104.176318) (xy 426.469554 -104.120696)
			(xy 424.293316 -104.120696) (xy 424.257189 -104.161016) (xy 424.214321 -104.196691) (xy 424.166715 -104.225745)
			(xy 424.115386 -104.247557) (xy 424.061429 -104.261663) (xy 424.005992 -104.267763) (xy 423.950258 -104.265726)
			(xy 423.895415 -104.255596) (xy 423.842631 -104.237589) (xy 423.793031 -104.212088) (xy 423.747673 -104.179637)
			(xy 423.707524 -104.140928) (xy 423.673438 -104.096785) (xy 423.646142 -104.04815) (xy 423.626219 -103.996059)
			(xy 423.614093 -103.941622) (xy 423.610022 -103.886) (xy 422.735991 -103.886) (xy 422.769715 -103.900331)
			(xy 422.817321 -103.929385) (xy 422.860189 -103.96506) (xy 422.897406 -104.006597) (xy 422.928179 -104.05311)
			(xy 422.951851 -104.103607) (xy 422.967919 -104.157014) (xy 422.976039 -104.21219) (xy 422.976548 -104.240076)
			(xy 422.976039 -104.267962) (xy 422.967919 -104.323138) (xy 422.951851 -104.376545) (xy 422.928179 -104.427042)
			(xy 422.897406 -104.473555) (xy 422.860189 -104.515092) (xy 422.817321 -104.550767) (xy 422.769715 -104.579821)
			(xy 422.718386 -104.601633) (xy 422.664429 -104.615739) (xy 422.608992 -104.621839) (xy 422.553258 -104.619802)
			(xy 422.498415 -104.609672) (xy 422.445631 -104.591665) (xy 422.396031 -104.566164) (xy 422.350673 -104.533713)
			(xy 422.310524 -104.495004) (xy 422.276438 -104.450861) (xy 422.249142 -104.402226) (xy 422.229219 -104.350135)
			(xy 422.217093 -104.295698) (xy 422.213022 -104.240076) (xy 415.994342 -104.240076) (xy 415.993833 -104.267962)
			(xy 415.985713 -104.323138) (xy 415.969645 -104.376545) (xy 415.945973 -104.427042) (xy 415.9152 -104.473555)
			(xy 415.877983 -104.515092) (xy 415.835115 -104.550767) (xy 415.787509 -104.579821) (xy 415.73618 -104.601633)
			(xy 415.682223 -104.615739) (xy 415.626786 -104.621839) (xy 415.571052 -104.619802) (xy 415.516209 -104.609672)
			(xy 415.463425 -104.591665) (xy 415.413825 -104.566164) (xy 415.368467 -104.533713) (xy 415.328318 -104.495004)
			(xy 415.294232 -104.450861) (xy 415.266936 -104.402226) (xy 415.247013 -104.350135) (xy 415.234887 -104.295698)
			(xy 415.230816 -104.240076) (xy 403.387647 -104.240076) (xy 403.387647 -104.272155) (xy 403.379888 -104.32611)
			(xy 403.36453 -104.378411) (xy 403.341885 -104.427994) (xy 403.312413 -104.473849) (xy 403.276715 -104.515043)
			(xy 403.235517 -104.550737) (xy 403.189659 -104.580204) (xy 403.140073 -104.602844) (xy 403.08777 -104.618197)
			(xy 403.033815 -104.625949) (xy 403.00656 -104.62641) (xy 402.97955 -104.626014) (xy 402.926069 -104.618402)
			(xy 402.874196 -104.603321) (xy 402.82497 -104.581073) (xy 402.779375 -104.552103) (xy 402.738323 -104.516991)
			(xy 402.702634 -104.476438) (xy 402.673023 -104.431257) (xy 402.650083 -104.38235) (xy 402.634271 -104.330695)
			(xy 402.629624 -104.304084) (xy 402.6281 -104.293416) (xy 402.61667 -104.275636) (xy 402.545296 -104.228138)
			(xy 402.536359 -104.222805) (xy 402.515902 -104.219121) (xy 402.505672 -104.221026) (xy 402.50491 -104.221026)
			(xy 402.478332 -104.227072) (xy 402.424213 -104.233569) (xy 402.39696 -104.23398) (xy 402.369642 -104.233588)
			(xy 402.315394 -104.227097) (xy 402.288756 -104.221026) (xy 402.288248 -104.221026) (xy 402.278018 -104.219163)
			(xy 402.257571 -104.222839) (xy 402.248624 -104.228138) (xy 402.17725 -104.275636) (xy 402.16582 -104.293416)
			(xy 402.164296 -104.304084) (xy 402.15962 -104.330685) (xy 402.143791 -104.382322) (xy 402.12084 -104.431212)
			(xy 402.091225 -104.476377) (xy 402.055538 -104.516916) (xy 402.014491 -104.552018) (xy 401.968906 -104.580981)
			(xy 401.919692 -104.603228) (xy 401.867832 -104.618314) (xy 401.814364 -104.625938) (xy 401.78736 -104.62641)
			(xy 401.759991 -104.625906) (xy 401.705814 -104.618097) (xy 401.653311 -104.602617) (xy 401.603564 -104.579783)
			(xy 401.557595 -104.550067) (xy 401.536662 -104.53243) (xy 401.536408 -104.532176) (xy 401.529325 -104.526584)
			(xy 401.512405 -104.520341) (xy 401.503388 -104.519984) (xy 401.436332 -104.519984) (xy 401.427317 -104.52036)
			(xy 401.4104 -104.526595) (xy 401.403312 -104.532176) (xy 401.403312 -104.53243) (xy 401.403058 -104.53243)
			(xy 401.382119 -104.55006) (xy 401.336147 -104.579772) (xy 401.286402 -104.602609) (xy 401.233903 -104.618103)
			(xy 401.179729 -104.625934) (xy 401.15236 -104.62641) (xy 401.135248 -104.626216) (xy 401.101161 -104.623166)
			(xy 401.084288 -104.620314) (xy 401.072996 -104.618975) (xy 401.05111 -104.625031) (xy 401.042124 -104.631998)
			(xy 401.01774 -104.65308) (xy 401.009322 -104.661006) (xy 401.000054 -104.68216) (xy 400.99996 -104.69372)
			(xy 401.000468 -104.712516) (xy 401.000468 -104.830372) (xy 405.89784 -104.830372) (xy 405.901911 -104.77475)
			(xy 405.914037 -104.720313) (xy 405.93396 -104.668222) (xy 405.961256 -104.619587) (xy 405.995342 -104.575444)
			(xy 406.035491 -104.536735) (xy 406.080849 -104.504284) (xy 406.130449 -104.478783) (xy 406.183233 -104.460776)
			(xy 406.238076 -104.450646) (xy 406.29381 -104.448609) (xy 406.349247 -104.454709) (xy 406.403204 -104.468815)
			(xy 406.454533 -104.490627) (xy 406.502139 -104.519681) (xy 406.545007 -104.555356) (xy 406.582224 -104.596893)
			(xy 406.612997 -104.643406) (xy 406.627772 -104.674924) (xy 436.859424 -104.674924) (xy 436.863495 -104.619302)
			(xy 436.875621 -104.564865) (xy 436.895544 -104.512774) (xy 436.92284 -104.464139) (xy 436.956926 -104.419996)
			(xy 436.997075 -104.381287) (xy 437.042433 -104.348836) (xy 437.092033 -104.323335) (xy 437.144817 -104.305328)
			(xy 437.19966 -104.295198) (xy 437.255394 -104.293161) (xy 437.310831 -104.299261) (xy 437.364788 -104.313367)
			(xy 437.416117 -104.335179) (xy 437.463723 -104.364233) (xy 437.506591 -104.399908) (xy 437.543808 -104.441445)
			(xy 437.574581 -104.487958) (xy 437.598253 -104.538455) (xy 437.614321 -104.591862) (xy 437.622441 -104.647038)
			(xy 437.62295 -104.674924) (xy 437.622441 -104.70281) (xy 437.614321 -104.757986) (xy 437.598253 -104.811393)
			(xy 437.574581 -104.86189) (xy 437.543808 -104.908403) (xy 437.506591 -104.94994) (xy 437.463723 -104.985615)
			(xy 437.416117 -105.014669) (xy 437.364788 -105.036481) (xy 437.310831 -105.050587) (xy 437.255394 -105.056687)
			(xy 437.19966 -105.05465) (xy 437.144817 -105.04452) (xy 437.092033 -105.026513) (xy 437.042433 -105.001012)
			(xy 436.997075 -104.968561) (xy 436.956926 -104.929852) (xy 436.92284 -104.885709) (xy 436.895544 -104.837074)
			(xy 436.875621 -104.784983) (xy 436.863495 -104.730546) (xy 436.859424 -104.674924) (xy 406.627772 -104.674924)
			(xy 406.636669 -104.693903) (xy 406.652737 -104.74731) (xy 406.660857 -104.802486) (xy 406.661366 -104.830372)
			(xy 406.660857 -104.858258) (xy 406.652737 -104.913434) (xy 406.636669 -104.966841) (xy 406.612997 -105.017338)
			(xy 406.582224 -105.063851) (xy 406.545007 -105.105388) (xy 406.502139 -105.141063) (xy 406.454533 -105.170117)
			(xy 406.403204 -105.191929) (xy 406.349247 -105.206035) (xy 406.29381 -105.212135) (xy 406.238076 -105.210098)
			(xy 406.183233 -105.199968) (xy 406.130449 -105.181961) (xy 406.080849 -105.15646) (xy 406.035491 -105.124009)
			(xy 405.995342 -105.0853) (xy 405.961256 -105.041157) (xy 405.93396 -104.992522) (xy 405.914037 -104.940431)
			(xy 405.901911 -104.885994) (xy 405.89784 -104.830372) (xy 401.000468 -104.830372) (xy 401.000468 -105.57637)
			(xy 400.99996 -105.596436) (xy 401.000179 -105.60788) (xy 401.009272 -105.628851) (xy 401.017486 -105.636822)
			(xy 401.042124 -105.658158) (xy 401.051109 -105.665257) (xy 401.073203 -105.6712) (xy 401.084542 -105.669588)
			(xy 401.101349 -105.66672) (xy 401.135311 -105.663672) (xy 401.15236 -105.663492) (xy 401.179729 -105.663983)
			(xy 401.233907 -105.671795) (xy 401.28641 -105.687279) (xy 401.336157 -105.710115) (xy 401.382125 -105.739834)
			(xy 401.403058 -105.757472) (xy 401.409916 -105.763568) (xy 401.426934 -105.769918) (xy 401.512278 -105.769918)
			(xy 401.52955 -105.763314) (xy 401.536408 -105.757218) (xy 401.557354 -105.739596) (xy 401.60332 -105.709874)
			(xy 401.653063 -105.687031) (xy 401.705562 -105.671537) (xy 401.759737 -105.66371) (xy 401.787106 -105.663238)
			(xy 401.78736 -105.663238) (xy 401.814338 -105.663668) (xy 401.867758 -105.671257) (xy 401.919574 -105.686303)
			(xy 401.968751 -105.708505) (xy 402.014306 -105.737421) (xy 402.055327 -105.772471) (xy 402.090997 -105.812955)
			(xy 402.120601 -105.858065) (xy 402.143548 -105.906898) (xy 402.15938 -105.95848) (xy 402.164042 -105.985056)
			(xy 402.166196 -105.995288) (xy 402.177485 -106.012865) (xy 402.185886 -106.019092) (xy 402.25726 -106.06659)
			(xy 402.278342 -106.0704) (xy 402.288502 -106.06786) (xy 402.315195 -106.061712) (xy 402.369572 -106.055096)
			(xy 402.39696 -106.054652) (xy 402.424348 -106.0551) (xy 402.478724 -106.061718) (xy 402.505418 -106.06786)
			(xy 402.515578 -106.0704) (xy 402.53666 -106.06659) (xy 402.616924 -106.01325) (xy 402.6281 -105.995724)
			(xy 402.629878 -105.985056) (xy 402.63451 -105.958478) (xy 402.65037 -105.906912) (xy 402.673338 -105.858095)
			(xy 402.702954 -105.813001) (xy 402.738629 -105.77253) (xy 402.77965 -105.737489) (xy 402.825199 -105.708577)
			(xy 402.874367 -105.686371) (xy 402.926174 -105.671315) (xy 402.979585 -105.663708) (xy 403.00656 -105.663238)
			(xy 403.033818 -105.663606) (xy 403.08778 -105.67136) (xy 403.140089 -105.686714) (xy 403.18968 -105.709357)
			(xy 403.235544 -105.738827) (xy 403.276746 -105.774525) (xy 403.312449 -105.815724) (xy 403.341924 -105.861585)
			(xy 403.364572 -105.911174) (xy 403.379932 -105.963481) (xy 403.387691 -106.017442) (xy 403.387691 -106.071958)
			(xy 403.379932 -106.125919) (xy 403.364572 -106.178226) (xy 403.341924 -106.227815) (xy 403.312449 -106.273676)
			(xy 403.276746 -106.314875) (xy 403.235544 -106.350573) (xy 403.18968 -106.380043) (xy 403.140089 -106.402686)
			(xy 403.08778 -106.41804) (xy 403.033818 -106.425794) (xy 403.00656 -106.426254) (xy 402.989448 -106.42606)
			(xy 402.955361 -106.423009) (xy 402.938488 -106.420158) (xy 402.927196 -106.418808) (xy 402.905308 -106.42487)
			(xy 402.896324 -106.431842) (xy 402.87194 -106.452924) (xy 402.863501 -106.460832) (xy 402.854244 -106.481999)
			(xy 402.85416 -106.493564) (xy 402.854668 -106.51236) (xy 402.854668 -107.210352) (xy 413.291526 -107.210352)
			(xy 413.295597 -107.15473) (xy 413.307723 -107.100293) (xy 413.327646 -107.048202) (xy 413.354942 -106.999567)
			(xy 413.389028 -106.955424) (xy 413.429177 -106.916715) (xy 413.474535 -106.884264) (xy 413.524135 -106.858763)
			(xy 413.576919 -106.840756) (xy 413.631762 -106.830626) (xy 413.687496 -106.828589) (xy 413.742933 -106.834689)
			(xy 413.79689 -106.848795) (xy 413.848219 -106.870607) (xy 413.895825 -106.899661) (xy 413.938693 -106.935336)
			(xy 413.97591 -106.976873) (xy 414.006683 -107.023386) (xy 414.030355 -107.073883) (xy 414.043754 -107.11842)
			(xy 415.137848 -107.11842) (xy 415.137848 -107.03152) (xy 415.145866 -106.944991) (xy 415.161834 -106.859571)
			(xy 415.185615 -106.775989) (xy 415.217007 -106.694957) (xy 415.255741 -106.617168) (xy 415.301488 -106.543284)
			(xy 415.353857 -106.473937) (xy 415.412401 -106.409717) (xy 415.476621 -106.351173) (xy 415.545968 -106.298804)
			(xy 415.619852 -106.253057) (xy 415.697641 -106.214323) (xy 415.778673 -106.182931) (xy 415.862255 -106.15915)
			(xy 415.947675 -106.143182) (xy 416.034204 -106.135164) (xy 416.121104 -106.135164) (xy 416.207633 -106.143182)
			(xy 416.293053 -106.15915) (xy 416.376635 -106.182931) (xy 416.457667 -106.214323) (xy 416.535456 -106.253057)
			(xy 416.60934 -106.298804) (xy 416.678687 -106.351173) (xy 416.742907 -106.409717) (xy 416.801451 -106.473937)
			(xy 416.85382 -106.543284) (xy 416.899567 -106.617168) (xy 416.938301 -106.694957) (xy 416.969693 -106.775989)
			(xy 416.993474 -106.859571) (xy 417.009442 -106.944991) (xy 417.01746 -107.03152) (xy 417.017962 -107.07497)
			(xy 417.01746 -107.11842) (xy 417.017458 -107.118439) (xy 417.390818 -107.118439) (xy 417.390818 -107.031561)
			(xy 417.398834 -106.945054) (xy 417.414797 -106.859655) (xy 417.438572 -106.776094) (xy 417.469956 -106.695082)
			(xy 417.50868 -106.617312) (xy 417.554415 -106.543447) (xy 417.60677 -106.474116) (xy 417.665298 -106.409912)
			(xy 417.729501 -106.351382) (xy 417.79883 -106.299026) (xy 417.872695 -106.25329) (xy 417.950464 -106.214564)
			(xy 418.031475 -106.183178) (xy 418.115036 -106.159402) (xy 418.200434 -106.143436) (xy 418.286941 -106.135419)
			(xy 418.33038 -106.134916) (xy 420.18458 -106.134916) (xy 420.228018 -106.135462) (xy 420.314524 -106.143476)
			(xy 420.399921 -106.159438) (xy 420.483481 -106.183211) (xy 420.564491 -106.214593) (xy 420.64226 -106.253316)
			(xy 420.716124 -106.299049) (xy 420.785453 -106.351403) (xy 420.849656 -106.40993) (xy 420.908185 -106.474132)
			(xy 420.96054 -106.54346) (xy 421.006275 -106.617323) (xy 421.044999 -106.695091) (xy 421.076383 -106.7761)
			(xy 421.100158 -106.85966) (xy 421.116121 -106.945057) (xy 421.124137 -107.031562) (xy 421.124137 -107.11842)
			(xy 422.507658 -107.11842) (xy 422.507658 -107.03152) (xy 422.515676 -106.944991) (xy 422.531644 -106.859571)
			(xy 422.555425 -106.775989) (xy 422.586817 -106.694957) (xy 422.625551 -106.617168) (xy 422.671298 -106.543284)
			(xy 422.723667 -106.473937) (xy 422.782211 -106.409717) (xy 422.846431 -106.351173) (xy 422.915778 -106.298804)
			(xy 422.989662 -106.253057) (xy 423.067451 -106.214323) (xy 423.148483 -106.182931) (xy 423.232065 -106.15915)
			(xy 423.317485 -106.143182) (xy 423.404014 -106.135164) (xy 423.490914 -106.135164) (xy 423.577443 -106.143182)
			(xy 423.662863 -106.15915) (xy 423.746445 -106.182931) (xy 423.827477 -106.214323) (xy 423.905266 -106.253057)
			(xy 423.97915 -106.298804) (xy 424.048497 -106.351173) (xy 424.085441 -106.384852) (xy 425.812964 -106.384852)
			(xy 425.817035 -106.32923) (xy 425.829161 -106.274793) (xy 425.849084 -106.222702) (xy 425.87638 -106.174067)
			(xy 425.910466 -106.129924) (xy 425.950615 -106.091215) (xy 425.995973 -106.058764) (xy 426.045573 -106.033263)
			(xy 426.098357 -106.015256) (xy 426.1532 -106.005126) (xy 426.208934 -106.003089) (xy 426.264371 -106.009189)
			(xy 426.318328 -106.023295) (xy 426.369657 -106.045107) (xy 426.417263 -106.074161) (xy 426.460131 -106.109836)
			(xy 426.497348 -106.151373) (xy 426.528121 -106.197886) (xy 426.551793 -106.248383) (xy 426.567861 -106.30179)
			(xy 426.575981 -106.356966) (xy 426.57649 -106.384852) (xy 426.575981 -106.412738) (xy 426.567861 -106.467914)
			(xy 426.551793 -106.521321) (xy 426.528121 -106.571818) (xy 426.497348 -106.618331) (xy 426.460131 -106.659868)
			(xy 426.417263 -106.695543) (xy 426.369657 -106.724597) (xy 426.318328 -106.746409) (xy 426.264371 -106.760515)
			(xy 426.208934 -106.766615) (xy 426.1532 -106.764578) (xy 426.098357 -106.754448) (xy 426.045573 -106.736441)
			(xy 425.995973 -106.71094) (xy 425.950615 -106.678489) (xy 425.910466 -106.63978) (xy 425.87638 -106.595637)
			(xy 425.849084 -106.547002) (xy 425.829161 -106.494911) (xy 425.817035 -106.440474) (xy 425.812964 -106.384852)
			(xy 424.085441 -106.384852) (xy 424.112717 -106.409717) (xy 424.171261 -106.473937) (xy 424.22363 -106.543284)
			(xy 424.269377 -106.617168) (xy 424.308111 -106.694957) (xy 424.339503 -106.775989) (xy 424.363284 -106.859571)
			(xy 424.379252 -106.944991) (xy 424.38727 -107.03152) (xy 424.387578 -107.058206) (xy 437.873902 -107.058206)
			(xy 437.874429 -107.029467) (xy 437.883051 -106.97264) (xy 437.9001 -106.917749) (xy 437.925191 -106.866037)
			(xy 437.957755 -106.818675) (xy 437.977026 -106.797348) (xy 437.98363 -106.79049) (xy 437.990742 -106.772456)
			(xy 437.990742 -106.683556) (xy 437.98363 -106.665522) (xy 437.977026 -106.658664) (xy 437.957761 -106.637332)
			(xy 437.925195 -106.589971) (xy 437.900103 -106.53826) (xy 437.883053 -106.48337) (xy 437.87443 -106.426543)
			(xy 437.874429 -106.369066) (xy 437.883051 -106.312239) (xy 437.9001 -106.257349) (xy 437.925191 -106.205637)
			(xy 437.957756 -106.158275) (xy 437.977026 -106.136948) (xy 437.98363 -106.13009) (xy 437.990742 -106.112056)
			(xy 437.990742 -106.023156) (xy 437.98363 -106.005122) (xy 437.977026 -105.998264) (xy 437.957756 -105.976936)
			(xy 437.92519 -105.929574) (xy 437.900098 -105.877863) (xy 437.883047 -105.822972) (xy 437.874423 -105.766145)
			(xy 437.873902 -105.737406) (xy 437.874388 -105.710155) (xy 437.882144 -105.656207) (xy 437.897499 -105.603912)
			(xy 437.920141 -105.554335) (xy 437.949607 -105.508485) (xy 437.985298 -105.467294) (xy 438.026489 -105.431603)
			(xy 438.072339 -105.402137) (xy 438.121916 -105.379495) (xy 438.174211 -105.36414) (xy 438.228159 -105.356384)
			(xy 438.282661 -105.356384) (xy 438.336609 -105.36414) (xy 438.388904 -105.379495) (xy 438.438481 -105.402137)
			(xy 438.484331 -105.431603) (xy 438.525522 -105.467294) (xy 438.561213 -105.508485) (xy 438.590679 -105.554335)
			(xy 438.613321 -105.603912) (xy 438.628676 -105.656207) (xy 438.636432 -105.710155) (xy 438.636918 -105.737406)
			(xy 438.636393 -105.766145) (xy 438.62777 -105.822972) (xy 438.61072 -105.877862) (xy 438.585629 -105.929574)
			(xy 438.553064 -105.976937) (xy 438.533794 -105.998264) (xy 438.52719 -106.005122) (xy 438.520078 -106.023156)
			(xy 438.520078 -106.112056) (xy 438.52719 -106.13009) (xy 438.533794 -106.136948) (xy 438.55307 -106.15827)
			(xy 438.585633 -106.205634) (xy 438.610724 -106.257346) (xy 438.627772 -106.312238) (xy 438.636394 -106.369065)
			(xy 438.636393 -106.426543) (xy 438.62777 -106.483371) (xy 438.61072 -106.538262) (xy 438.585629 -106.589974)
			(xy 438.553064 -106.637337) (xy 438.533794 -106.658664) (xy 438.52719 -106.665522) (xy 438.520078 -106.683556)
			(xy 438.520078 -106.772456) (xy 438.52719 -106.79049) (xy 438.533794 -106.797348) (xy 438.553056 -106.818683)
			(xy 438.585626 -106.866042) (xy 438.610721 -106.917751) (xy 438.627773 -106.972641) (xy 438.636397 -107.029467)
			(xy 438.636918 -107.058206) (xy 438.636432 -107.085457) (xy 438.628676 -107.139405) (xy 438.613321 -107.1917)
			(xy 438.590679 -107.241277) (xy 438.561213 -107.287127) (xy 438.525522 -107.328318) (xy 438.484331 -107.364009)
			(xy 438.438481 -107.393475) (xy 438.388904 -107.416117) (xy 438.336609 -107.431472) (xy 438.282661 -107.439228)
			(xy 438.228159 -107.439228) (xy 438.174211 -107.431472) (xy 438.121916 -107.416117) (xy 438.072339 -107.393475)
			(xy 438.026489 -107.364009) (xy 437.985298 -107.328318) (xy 437.949607 -107.287127) (xy 437.920141 -107.241277)
			(xy 437.897499 -107.1917) (xy 437.882144 -107.139405) (xy 437.874388 -107.085457) (xy 437.873902 -107.058206)
			(xy 424.387578 -107.058206) (xy 424.387772 -107.07497) (xy 424.38727 -107.11842) (xy 424.379252 -107.204949)
			(xy 424.363284 -107.290369) (xy 424.339503 -107.373951) (xy 424.308111 -107.454983) (xy 424.269377 -107.532772)
			(xy 424.22363 -107.606656) (xy 424.171261 -107.676003) (xy 424.112717 -107.740223) (xy 424.048497 -107.798767)
			(xy 423.97915 -107.851136) (xy 423.905266 -107.896883) (xy 423.827477 -107.935617) (xy 423.746445 -107.967009)
			(xy 423.662863 -107.99079) (xy 423.577443 -108.006758) (xy 423.490914 -108.014776) (xy 423.404014 -108.014776)
			(xy 423.317485 -108.006758) (xy 423.232065 -107.99079) (xy 423.148483 -107.967009) (xy 423.067451 -107.935617)
			(xy 422.989662 -107.896883) (xy 422.915778 -107.851136) (xy 422.846431 -107.798767) (xy 422.782211 -107.740223)
			(xy 422.723667 -107.676003) (xy 422.671298 -107.606656) (xy 422.625551 -107.532772) (xy 422.586817 -107.454983)
			(xy 422.555425 -107.373951) (xy 422.531644 -107.290369) (xy 422.515676 -107.204949) (xy 422.507658 -107.11842)
			(xy 421.124137 -107.11842) (xy 421.124137 -107.118438) (xy 421.116121 -107.204943) (xy 421.100158 -107.29034)
			(xy 421.076383 -107.3739) (xy 421.044999 -107.454909) (xy 421.006275 -107.532677) (xy 420.96054 -107.60654)
			(xy 420.908185 -107.675868) (xy 420.849656 -107.74007) (xy 420.785453 -107.798597) (xy 420.716124 -107.850951)
			(xy 420.64226 -107.896684) (xy 420.564491 -107.935407) (xy 420.483481 -107.966789) (xy 420.399921 -107.990562)
			(xy 420.314524 -108.006524) (xy 420.228018 -108.014538) (xy 420.18458 -108.015024) (xy 418.33038 -108.015024)
			(xy 418.286941 -108.014581) (xy 418.200434 -108.006564) (xy 418.115036 -107.990598) (xy 418.031475 -107.966822)
			(xy 417.950464 -107.935436) (xy 417.872695 -107.89671) (xy 417.79883 -107.850974) (xy 417.729501 -107.798618)
			(xy 417.665298 -107.740088) (xy 417.60677 -107.675884) (xy 417.554415 -107.606553) (xy 417.50868 -107.532688)
			(xy 417.469956 -107.454918) (xy 417.438572 -107.373906) (xy 417.414797 -107.290345) (xy 417.398834 -107.204946)
			(xy 417.390818 -107.118439) (xy 417.017458 -107.118439) (xy 417.009442 -107.204949) (xy 416.993474 -107.290369)
			(xy 416.969693 -107.373951) (xy 416.938301 -107.454983) (xy 416.899567 -107.532772) (xy 416.85382 -107.606656)
			(xy 416.801451 -107.676003) (xy 416.742907 -107.740223) (xy 416.678687 -107.798767) (xy 416.60934 -107.851136)
			(xy 416.535456 -107.896883) (xy 416.457667 -107.935617) (xy 416.376635 -107.967009) (xy 416.293053 -107.99079)
			(xy 416.207633 -108.006758) (xy 416.121104 -108.014776) (xy 416.034204 -108.014776) (xy 415.947675 -108.006758)
			(xy 415.862255 -107.99079) (xy 415.778673 -107.967009) (xy 415.697641 -107.935617) (xy 415.619852 -107.896883)
			(xy 415.545968 -107.851136) (xy 415.476621 -107.798767) (xy 415.412401 -107.740223) (xy 415.353857 -107.676003)
			(xy 415.301488 -107.606656) (xy 415.255741 -107.532772) (xy 415.217007 -107.454983) (xy 415.185615 -107.373951)
			(xy 415.161834 -107.290369) (xy 415.145866 -107.204949) (xy 415.137848 -107.11842) (xy 414.043754 -107.11842)
			(xy 414.046423 -107.12729) (xy 414.054543 -107.182466) (xy 414.055052 -107.210352) (xy 414.054543 -107.238238)
			(xy 414.046423 -107.293414) (xy 414.030355 -107.346821) (xy 414.006683 -107.397318) (xy 413.97591 -107.443831)
			(xy 413.938693 -107.485368) (xy 413.895825 -107.521043) (xy 413.848219 -107.550097) (xy 413.79689 -107.571909)
			(xy 413.742933 -107.586015) (xy 413.687496 -107.592115) (xy 413.631762 -107.590078) (xy 413.576919 -107.579948)
			(xy 413.524135 -107.561941) (xy 413.474535 -107.53644) (xy 413.429177 -107.503989) (xy 413.389028 -107.46528)
			(xy 413.354942 -107.421137) (xy 413.327646 -107.372502) (xy 413.307723 -107.320411) (xy 413.295597 -107.265974)
			(xy 413.291526 -107.210352) (xy 402.854668 -107.210352) (xy 402.854668 -107.376214) (xy 402.85416 -107.39628)
			(xy 402.854353 -107.407727) (xy 402.863464 -107.428698) (xy 402.871686 -107.436666) (xy 402.896324 -107.458002)
			(xy 402.905313 -107.465096) (xy 402.927404 -107.471043) (xy 402.938742 -107.469432) (xy 402.955549 -107.466565)
			(xy 402.989511 -107.463516) (xy 403.00656 -107.463336) (xy 403.033818 -107.463708) (xy 403.087779 -107.471461)
			(xy 403.140088 -107.486816) (xy 403.189679 -107.509459) (xy 403.235543 -107.538929) (xy 403.276745 -107.574627)
			(xy 403.312447 -107.615825) (xy 403.341922 -107.661686) (xy 403.36457 -107.711274) (xy 403.37993 -107.763581)
			(xy 403.387689 -107.817542) (xy 403.387689 -107.872058) (xy 403.37993 -107.926019) (xy 403.36457 -107.978326)
			(xy 403.341922 -108.027914) (xy 403.312447 -108.073775) (xy 403.276745 -108.114973) (xy 403.235543 -108.150671)
			(xy 403.189679 -108.180141) (xy 403.140088 -108.202784) (xy 403.087779 -108.218139) (xy 403.033818 -108.225892)
			(xy 403.00656 -108.226352) (xy 402.979551 -108.225921) (xy 402.926073 -108.21831) (xy 402.874204 -108.203231)
			(xy 402.82498 -108.180986) (xy 402.779386 -108.15202) (xy 402.738334 -108.116912) (xy 402.702645 -108.076364)
			(xy 402.673033 -108.031187) (xy 402.650089 -107.982285) (xy 402.634273 -107.930635) (xy 402.629624 -107.904026)
			(xy 402.6281 -107.893358) (xy 402.61667 -107.875578) (xy 402.545296 -107.82808) (xy 402.536358 -107.822749)
			(xy 402.515902 -107.819063) (xy 402.505672 -107.820968) (xy 402.50491 -107.820968) (xy 402.478339 -107.827077)
			(xy 402.42422 -107.833704) (xy 402.39696 -107.834176) (xy 402.369635 -107.833723) (xy 402.315387 -107.827101)
			(xy 402.288756 -107.820968) (xy 402.288248 -107.820968) (xy 402.278018 -107.819114) (xy 402.257572 -107.822785)
			(xy 402.248624 -107.82808) (xy 402.17725 -107.875578) (xy 402.16582 -107.893358) (xy 402.164296 -107.904026)
			(xy 402.159652 -107.930633) (xy 402.143818 -107.98227) (xy 402.120862 -108.03116) (xy 402.091242 -108.076324)
			(xy 402.055551 -108.116862) (xy 402.014501 -108.151962) (xy 401.968913 -108.180925) (xy 401.919696 -108.203171)
			(xy 401.867835 -108.218257) (xy 401.814365 -108.22588) (xy 401.78736 -108.226352) (xy 401.75999 -108.225862)
			(xy 401.705812 -108.218052) (xy 401.653309 -108.202569) (xy 401.603561 -108.179732) (xy 401.557594 -108.150012)
			(xy 401.536662 -108.132372) (xy 401.536408 -108.132118) (xy 401.529322 -108.126531) (xy 401.512405 -108.120284)
			(xy 401.503388 -108.119926) (xy 401.436332 -108.119926) (xy 401.427316 -108.120293) (xy 401.410399 -108.126533)
			(xy 401.403312 -108.132118) (xy 401.403312 -108.132372) (xy 401.403058 -108.132372) (xy 401.382111 -108.149993)
			(xy 401.336143 -108.179709) (xy 401.286399 -108.202548) (xy 401.233902 -108.218044) (xy 401.179728 -108.225876)
			(xy 401.15236 -108.226352) (xy 401.135248 -108.226158) (xy 401.101161 -108.223107) (xy 401.084288 -108.220256)
			(xy 401.072996 -108.218906) (xy 401.051108 -108.224968) (xy 401.042124 -108.23194) (xy 401.01774 -108.253022)
			(xy 401.009302 -108.26093) (xy 401.000045 -108.282098) (xy 400.99996 -108.293662) (xy 401.000468 -108.312458)
			(xy 401.000468 -108.462318) (xy 412.688022 -108.462318) (xy 412.692093 -108.406696) (xy 412.704219 -108.352259)
			(xy 412.724142 -108.300168) (xy 412.751438 -108.251533) (xy 412.785524 -108.20739) (xy 412.825673 -108.168681)
			(xy 412.871031 -108.13623) (xy 412.920631 -108.110729) (xy 412.973415 -108.092722) (xy 413.028258 -108.082592)
			(xy 413.083992 -108.080555) (xy 413.139429 -108.086655) (xy 413.193386 -108.100761) (xy 413.244715 -108.122573)
			(xy 413.292321 -108.151627) (xy 413.335189 -108.187302) (xy 413.372406 -108.228839) (xy 413.403179 -108.275352)
			(xy 413.426851 -108.325849) (xy 413.442844 -108.379006) (xy 438.762902 -108.379006) (xy 438.763429 -108.350267)
			(xy 438.772051 -108.29344) (xy 438.7891 -108.238549) (xy 438.814191 -108.186837) (xy 438.846755 -108.139475)
			(xy 438.866026 -108.118148) (xy 438.87263 -108.11129) (xy 438.879742 -108.093256) (xy 438.879742 -108.004356)
			(xy 438.87263 -107.986322) (xy 438.866026 -107.979464) (xy 438.846761 -107.958132) (xy 438.814195 -107.910771)
			(xy 438.789103 -107.85906) (xy 438.772053 -107.80417) (xy 438.76343 -107.747343) (xy 438.763429 -107.689866)
			(xy 438.772051 -107.633039) (xy 438.7891 -107.578149) (xy 438.814191 -107.526437) (xy 438.846756 -107.479075)
			(xy 438.866026 -107.457748) (xy 438.87263 -107.45089) (xy 438.879742 -107.432856) (xy 438.879742 -107.343956)
			(xy 438.87263 -107.325922) (xy 438.866026 -107.319064) (xy 438.846761 -107.297732) (xy 438.814195 -107.250371)
			(xy 438.789103 -107.19866) (xy 438.772053 -107.14377) (xy 438.76343 -107.086943) (xy 438.763429 -107.029466)
			(xy 438.772051 -106.972639) (xy 438.7891 -106.917749) (xy 438.814191 -106.866037) (xy 438.846756 -106.818675)
			(xy 438.866026 -106.797348) (xy 438.87263 -106.79049) (xy 438.879742 -106.772456) (xy 438.879742 -106.683556)
			(xy 438.87263 -106.665522) (xy 438.866026 -106.658664) (xy 438.846761 -106.637332) (xy 438.814195 -106.589971)
			(xy 438.789103 -106.53826) (xy 438.772053 -106.48337) (xy 438.76343 -106.426543) (xy 438.763429 -106.369066)
			(xy 438.772051 -106.312239) (xy 438.7891 -106.257349) (xy 438.814191 -106.205637) (xy 438.846756 -106.158275)
			(xy 438.866026 -106.136948) (xy 438.87263 -106.13009) (xy 438.879742 -106.112056) (xy 438.879742 -106.023156)
			(xy 438.87263 -106.005122) (xy 438.866026 -105.998264) (xy 438.846761 -105.976932) (xy 438.814195 -105.929571)
			(xy 438.789103 -105.87786) (xy 438.772053 -105.82297) (xy 438.76343 -105.766143) (xy 438.763429 -105.708666)
			(xy 438.772051 -105.651839) (xy 438.7891 -105.596949) (xy 438.814191 -105.545237) (xy 438.846756 -105.497875)
			(xy 438.866026 -105.476548) (xy 438.87263 -105.46969) (xy 438.879742 -105.451656) (xy 438.879742 -105.362756)
			(xy 438.87263 -105.344722) (xy 438.866026 -105.337864) (xy 438.846761 -105.316532) (xy 438.814195 -105.269171)
			(xy 438.789103 -105.21746) (xy 438.772053 -105.16257) (xy 438.76343 -105.105743) (xy 438.763429 -105.048266)
			(xy 438.772051 -104.991439) (xy 438.7891 -104.936549) (xy 438.814191 -104.884837) (xy 438.846756 -104.837475)
			(xy 438.866026 -104.816148) (xy 438.87263 -104.80929) (xy 438.879742 -104.791256) (xy 438.879742 -104.702356)
			(xy 438.87263 -104.684322) (xy 438.866026 -104.677464) (xy 438.846761 -104.656132) (xy 438.814195 -104.608771)
			(xy 438.789103 -104.55706) (xy 438.772053 -104.50217) (xy 438.76343 -104.445343) (xy 438.763429 -104.387866)
			(xy 438.772051 -104.331039) (xy 438.7891 -104.276149) (xy 438.814191 -104.224437) (xy 438.846756 -104.177075)
			(xy 438.866026 -104.155748) (xy 438.87263 -104.14889) (xy 438.879742 -104.130856) (xy 438.879742 -104.041956)
			(xy 438.87263 -104.023922) (xy 438.866026 -104.017064) (xy 438.846761 -103.995732) (xy 438.814195 -103.948371)
			(xy 438.789103 -103.89666) (xy 438.772053 -103.84177) (xy 438.76343 -103.784943) (xy 438.763429 -103.727466)
			(xy 438.772051 -103.670639) (xy 438.7891 -103.615749) (xy 438.814191 -103.564037) (xy 438.846756 -103.516675)
			(xy 438.866026 -103.495348) (xy 438.87263 -103.48849) (xy 438.879742 -103.470456) (xy 438.879742 -103.381556)
			(xy 438.87263 -103.363522) (xy 438.866026 -103.356664) (xy 438.846756 -103.335336) (xy 438.81419 -103.287974)
			(xy 438.789098 -103.236263) (xy 438.772047 -103.181372) (xy 438.763423 -103.124545) (xy 438.762902 -103.095806)
			(xy 438.763344 -103.068599) (xy 438.771069 -103.014735) (xy 438.786375 -102.962517) (xy 438.808953 -102.913008)
			(xy 438.838342 -102.867212) (xy 438.873946 -102.826063) (xy 438.915041 -102.790395) (xy 438.937654 -102.775258)
			(xy 438.946036 -102.769924) (xy 438.957212 -102.753668) (xy 438.9755 -102.674674) (xy 438.977308 -102.665045)
			(xy 438.974311 -102.645703) (xy 438.969658 -102.637082) (xy 438.969404 -102.637082) (xy 438.969404 -102.636574)
			(xy 438.956199 -102.614063) (xy 438.935343 -102.566221) (xy 438.921193 -102.515987) (xy 438.914009 -102.464294)
			(xy 438.913524 -102.4382) (xy 438.913955 -102.410946) (xy 438.921713 -102.356992) (xy 438.937071 -102.304692)
			(xy 438.959716 -102.255109) (xy 438.989187 -102.209255) (xy 439.024884 -102.168061) (xy 439.06608 -102.132367)
			(xy 439.111937 -102.1029) (xy 439.161522 -102.08026) (xy 439.213823 -102.064906) (xy 439.267778 -102.057153)
			(xy 439.295032 -102.056692) (xy 439.324508 -102.057276) (xy 439.382759 -102.066335) (xy 439.438923 -102.084247)
			(xy 439.491663 -102.110587) (xy 439.539723 -102.144726) (xy 439.561224 -102.164896) (xy 439.569606 -102.173024)
			(xy 439.591958 -102.180644) (xy 439.69559 -102.165404) (xy 439.714894 -102.152196) (xy 439.720736 -102.141782)
			(xy 439.735307 -102.116819) (xy 439.770832 -102.071224) (xy 439.812829 -102.031512) (xy 439.860339 -101.998592)
			(xy 439.912271 -101.973218) (xy 439.967438 -101.955971) (xy 440.024576 -101.947246) (xy 440.053476 -101.94671)
			(xy 440.080731 -101.947135) (xy 440.134687 -101.95489) (xy 440.186991 -101.970245) (xy 440.236576 -101.992887)
			(xy 440.282435 -102.022356) (xy 440.323632 -102.058051) (xy 440.35933 -102.099246) (xy 440.388802 -102.145103)
			(xy 440.411447 -102.194687) (xy 440.426805 -102.246989) (xy 440.434563 -102.300945) (xy 440.434563 -102.355455)
			(xy 440.426805 -102.409411) (xy 440.411447 -102.461713) (xy 440.388802 -102.511297) (xy 440.35933 -102.557154)
			(xy 440.323632 -102.598349) (xy 440.282435 -102.634044) (xy 440.236576 -102.663513) (xy 440.186991 -102.686155)
			(xy 440.134687 -102.70151) (xy 440.080731 -102.709265) (xy 440.053476 -102.709726) (xy 440.023997 -102.709222)
			(xy 439.965741 -102.700147) (xy 439.909575 -102.682217) (xy 439.856836 -102.655859) (xy 439.808781 -102.621701)
			(xy 439.787284 -102.601522) (xy 439.778902 -102.593394) (xy 439.75655 -102.585774) (xy 439.652918 -102.601014)
			(xy 439.633614 -102.614222) (xy 439.627772 -102.624636) (xy 439.612115 -102.65139) (xy 439.573481 -102.699865)
			(xy 439.527508 -102.741444) (xy 439.501788 -102.758748) (xy 439.493406 -102.764082) (xy 439.48223 -102.780338)
			(xy 439.463942 -102.859332) (xy 439.462138 -102.868962) (xy 439.465134 -102.888302) (xy 439.469784 -102.896924)
			(xy 439.470038 -102.896924) (xy 439.470038 -102.897432) (xy 439.48325 -102.919939) (xy 439.504103 -102.967783)
			(xy 439.518251 -103.018018) (xy 439.525433 -103.069712) (xy 439.525918 -103.095806) (xy 439.525393 -103.124545)
			(xy 439.51677 -103.181372) (xy 439.49972 -103.236262) (xy 439.474629 -103.287974) (xy 439.442064 -103.335337)
			(xy 439.422794 -103.356664) (xy 439.41619 -103.363522) (xy 439.409078 -103.381556) (xy 439.409078 -103.470456)
			(xy 439.41619 -103.48849) (xy 439.422794 -103.495348) (xy 439.44207 -103.51667) (xy 439.474633 -103.564034)
			(xy 439.499724 -103.615746) (xy 439.516772 -103.670638) (xy 439.525394 -103.727465) (xy 439.525393 -103.784943)
			(xy 439.51677 -103.841771) (xy 439.500507 -103.894128) (xy 440.513976 -103.894128) (xy 440.518047 -103.838506)
			(xy 440.530173 -103.784069) (xy 440.550096 -103.731978) (xy 440.577392 -103.683343) (xy 440.611478 -103.6392)
			(xy 440.651627 -103.600491) (xy 440.696985 -103.56804) (xy 440.746585 -103.542539) (xy 440.799369 -103.524532)
			(xy 440.854212 -103.514402) (xy 440.909946 -103.512365) (xy 440.965383 -103.518465) (xy 441.01934 -103.532571)
			(xy 441.070669 -103.554383) (xy 441.118275 -103.583437) (xy 441.161143 -103.619112) (xy 441.19836 -103.660649)
			(xy 441.229133 -103.707162) (xy 441.252805 -103.757659) (xy 441.268873 -103.811066) (xy 441.276993 -103.866242)
			(xy 441.277428 -103.890064) (xy 441.53912 -103.890064) (xy 441.543191 -103.834442) (xy 441.555317 -103.780005)
			(xy 441.57524 -103.727914) (xy 441.602536 -103.679279) (xy 441.636622 -103.635136) (xy 441.676771 -103.596427)
			(xy 441.722129 -103.563976) (xy 441.771729 -103.538475) (xy 441.824513 -103.520468) (xy 441.879356 -103.510338)
			(xy 441.93509 -103.508301) (xy 441.990527 -103.514401) (xy 442.044484 -103.528507) (xy 442.095813 -103.550319)
			(xy 442.143419 -103.579373) (xy 442.186287 -103.615048) (xy 442.223504 -103.656585) (xy 442.254277 -103.703098)
			(xy 442.277949 -103.753595) (xy 442.294017 -103.807002) (xy 442.302137 -103.862178) (xy 442.302646 -103.890064)
			(xy 442.302137 -103.91795) (xy 442.294017 -103.973126) (xy 442.27904 -104.022906) (xy 444.16599 -104.022906)
			(xy 444.166465 -103.996592) (xy 444.173698 -103.944464) (xy 444.188016 -103.893822) (xy 444.209147 -103.845623)
			(xy 444.236692 -103.800779) (xy 444.270129 -103.760139) (xy 444.28918 -103.741982) (xy 444.296589 -103.734466)
			(xy 444.30511 -103.715182) (xy 444.30569 -103.704644) (xy 444.30569 -103.629968) (xy 444.30514 -103.619421)
			(xy 444.29662 -103.600125) (xy 444.28918 -103.59263) (xy 444.270142 -103.574457) (xy 444.236684 -103.53383)
			(xy 444.209123 -103.488994) (xy 444.187982 -103.440796) (xy 444.173661 -103.390152) (xy 444.166431 -103.338021)
			(xy 444.16599 -103.311706) (xy 444.166461 -103.284453) (xy 444.174217 -103.230503) (xy 444.189572 -103.178205)
			(xy 444.212214 -103.128625) (xy 444.241681 -103.082772) (xy 444.277374 -103.04158) (xy 444.318566 -103.005886)
			(xy 444.364418 -102.976418) (xy 444.413998 -102.953775) (xy 444.466295 -102.938419) (xy 444.520245 -102.930661)
			(xy 444.547498 -102.930198) (xy 444.575163 -102.930713) (xy 444.629912 -102.938712) (xy 444.682933 -102.954528)
			(xy 444.733117 -102.977831) (xy 444.779413 -103.008132) (xy 444.820851 -103.044796) (xy 444.856564 -103.087057)
			(xy 444.871602 -103.110284) (xy 444.878229 -103.119969) (xy 444.898098 -103.132408) (xy 444.909702 -103.13416)
			(xy 444.989712 -103.142034) (xy 445.001351 -103.14267) (xy 445.023189 -103.134588) (xy 445.031622 -103.12654)
			(xy 445.031876 -103.126286) (xy 445.049936 -103.107683) (xy 445.090272 -103.075107) (xy 445.134651 -103.048297)
			(xy 445.182254 -103.027749) (xy 445.232202 -103.01384) (xy 445.283574 -103.006827) (xy 445.309498 -103.006398)
			(xy 445.336751 -103.006857) (xy 445.390702 -103.014614) (xy 445.443001 -103.02997) (xy 445.492581 -103.052613)
			(xy 445.538435 -103.082081) (xy 445.579628 -103.117775) (xy 445.615321 -103.158969) (xy 445.644789 -103.204822)
			(xy 445.667431 -103.254403) (xy 445.682787 -103.306701) (xy 445.690543 -103.360653) (xy 445.691006 -103.387906)
			(xy 445.690542 -103.415276) (xy 445.682723 -103.469455) (xy 445.667234 -103.521958) (xy 445.644392 -103.571705)
			(xy 445.614667 -103.617672) (xy 445.597026 -103.638604) (xy 445.596772 -103.638858) (xy 445.591194 -103.64595)
			(xy 445.584943 -103.662863) (xy 445.58458 -103.671878) (xy 445.58458 -103.738934) (xy 445.584925 -103.747952)
			(xy 445.591181 -103.764869) (xy 445.596772 -103.771954) (xy 445.597026 -103.771954) (xy 445.597026 -103.772208)
			(xy 445.614686 -103.793123) (xy 445.644394 -103.839101) (xy 445.667226 -103.888853) (xy 445.682712 -103.941357)
			(xy 445.690535 -103.995536) (xy 445.691006 -104.022906) (xy 445.690528 -104.050157) (xy 445.68277 -104.104106)
			(xy 445.67939 -104.115616) (xy 448.597274 -104.115616) (xy 448.59776 -104.089303) (xy 448.604993 -104.037175)
			(xy 448.619308 -103.986533) (xy 448.640437 -103.938335) (xy 448.66798 -103.893491) (xy 448.701414 -103.85285)
			(xy 448.720464 -103.834692) (xy 448.727866 -103.827171) (xy 448.736392 -103.807891) (xy 448.736974 -103.797354)
			(xy 448.736974 -103.722678) (xy 448.736424 -103.712131) (xy 448.727904 -103.692834) (xy 448.720464 -103.68534)
			(xy 448.701379 -103.667214) (xy 448.667926 -103.626577) (xy 448.640372 -103.58173) (xy 448.619239 -103.533524)
			(xy 448.604927 -103.482872) (xy 448.597709 -103.430734) (xy 448.597274 -103.404416) (xy 448.59776 -103.377165)
			(xy 448.605516 -103.323217) (xy 448.620871 -103.270922) (xy 448.643513 -103.221345) (xy 448.672979 -103.175495)
			(xy 448.70867 -103.134304) (xy 448.749861 -103.098613) (xy 448.795711 -103.069147) (xy 448.845288 -103.046505)
			(xy 448.897583 -103.03115) (xy 448.951531 -103.023394) (xy 449.006033 -103.023394) (xy 449.059981 -103.03115)
			(xy 449.112276 -103.046505) (xy 449.161853 -103.069147) (xy 449.207703 -103.098613) (xy 449.248894 -103.134304)
			(xy 449.284585 -103.175495) (xy 449.314051 -103.221345) (xy 449.336693 -103.270922) (xy 449.352048 -103.323217)
			(xy 449.359804 -103.377165) (xy 449.36029 -103.404416) (xy 449.359836 -103.43073) (xy 449.352599 -103.48286)
			(xy 449.338278 -103.533503) (xy 449.317143 -103.581702) (xy 449.289594 -103.626545) (xy 449.256153 -103.667184)
			(xy 449.2371 -103.68534) (xy 449.229679 -103.692845) (xy 449.221166 -103.712138) (xy 449.220722 -103.720256)
			(xy 451.873015 -103.720256) (xy 451.873015 -103.665744) (xy 451.880773 -103.611786) (xy 451.896131 -103.559482)
			(xy 451.918777 -103.509895) (xy 451.948249 -103.464037) (xy 451.983948 -103.42284) (xy 452.025147 -103.387142)
			(xy 452.071006 -103.357671) (xy 452.120593 -103.335027) (xy 452.172898 -103.319671) (xy 452.226856 -103.311914)
			(xy 452.254112 -103.311452) (xy 452.281483 -103.311898) (xy 452.335664 -103.319719) (xy 452.388167 -103.335212)
			(xy 452.437914 -103.358058) (xy 452.483879 -103.387788) (xy 452.50481 -103.405432) (xy 452.505064 -103.405686)
			(xy 452.512158 -103.411262) (xy 452.529069 -103.417516) (xy 452.538084 -103.417878) (xy 452.60514 -103.417878)
			(xy 452.614159 -103.417545) (xy 452.631076 -103.411281) (xy 452.63816 -103.405686) (xy 452.63816 -103.405432)
			(xy 452.638414 -103.405432) (xy 452.659347 -103.387791) (xy 452.705315 -103.358067) (xy 452.755061 -103.335221)
			(xy 452.807563 -103.319725) (xy 452.861741 -103.311896) (xy 452.916483 -103.311896) (xy 452.970661 -103.319725)
			(xy 453.023163 -103.335221) (xy 453.072909 -103.358067) (xy 453.118877 -103.387791) (xy 453.13981 -103.405432)
			(xy 453.140064 -103.405686) (xy 453.147158 -103.411262) (xy 453.164069 -103.417516) (xy 453.173084 -103.417878)
			(xy 453.24014 -103.417878) (xy 453.249159 -103.417545) (xy 453.266076 -103.411281) (xy 453.27316 -103.405686)
			(xy 453.27316 -103.405432) (xy 453.273414 -103.405432) (xy 453.294372 -103.387825) (xy 453.340337 -103.358107)
			(xy 453.390078 -103.335264) (xy 453.442573 -103.319766) (xy 453.496745 -103.31193) (xy 453.524112 -103.311452)
			(xy 453.55136 -103.312019) (xy 453.605301 -103.319776) (xy 453.657588 -103.335131) (xy 453.707159 -103.35777)
			(xy 453.753003 -103.387234) (xy 453.794187 -103.422921) (xy 453.829874 -103.464107) (xy 453.859336 -103.509952)
			(xy 453.881974 -103.559523) (xy 453.897326 -103.611811) (xy 453.905082 -103.665752) (xy 453.905082 -103.685653)
			(xy 456.792771 -103.685653) (xy 456.792771 -103.631147) (xy 456.800529 -103.577195) (xy 456.815886 -103.524896)
			(xy 456.838531 -103.475315) (xy 456.868001 -103.429462) (xy 456.903697 -103.38827) (xy 456.944893 -103.352578)
			(xy 456.990749 -103.323112) (xy 457.040332 -103.300473) (xy 457.092632 -103.285121) (xy 457.146585 -103.277369)
			(xy 457.173838 -103.276908) (xy 457.200153 -103.277348) (xy 457.252283 -103.284588) (xy 457.302926 -103.298912)
			(xy 457.351125 -103.32005) (xy 457.395968 -103.347601) (xy 457.436606 -103.381044) (xy 457.454762 -103.400098)
			(xy 457.462296 -103.407484) (xy 457.481567 -103.416017) (xy 457.4921 -103.416608) (xy 457.566776 -103.416608)
			(xy 457.577325 -103.416077) (xy 457.596621 -103.407543) (xy 457.604114 -103.400098) (xy 457.623934 -103.37931)
			(xy 457.668706 -103.343335) (xy 457.718364 -103.314475) (xy 457.771786 -103.293382) (xy 457.827765 -103.280533)
			(xy 457.885038 -103.276218) (xy 457.942311 -103.280533) (xy 457.99829 -103.293382) (xy 458.051712 -103.314475)
			(xy 458.10137 -103.343335) (xy 458.146142 -103.37931) (xy 458.165962 -103.400098) (xy 458.173496 -103.407484)
			(xy 458.192767 -103.416017) (xy 458.2033 -103.416608) (xy 458.277976 -103.416608) (xy 458.288525 -103.416077)
			(xy 458.307821 -103.407543) (xy 458.315314 -103.400098) (xy 458.333469 -103.381042) (xy 458.374099 -103.347585)
			(xy 458.418939 -103.320026) (xy 458.46714 -103.298888) (xy 458.517788 -103.284571) (xy 458.569922 -103.277346)
			(xy 458.596238 -103.276908) (xy 458.623489 -103.277364) (xy 458.677434 -103.285126) (xy 458.729727 -103.300485)
			(xy 458.779301 -103.323129) (xy 458.825149 -103.352598) (xy 458.866336 -103.388291) (xy 458.902025 -103.429482)
			(xy 458.931489 -103.475332) (xy 458.954129 -103.524909) (xy 458.969482 -103.577203) (xy 458.977238 -103.631149)
			(xy 458.977238 -103.685651) (xy 458.969482 -103.739597) (xy 458.954129 -103.791891) (xy 458.931489 -103.841468)
			(xy 458.902025 -103.887319) (xy 458.866336 -103.928509) (xy 458.825149 -103.964202) (xy 458.779301 -103.993671)
			(xy 458.729727 -104.016315) (xy 458.677434 -104.031674) (xy 458.623489 -104.039436) (xy 458.596238 -104.039924)
			(xy 458.569923 -104.03949) (xy 458.517793 -104.032247) (xy 458.46715 -104.017921) (xy 458.418952 -103.996782)
			(xy 458.374109 -103.969231) (xy 458.33347 -103.935788) (xy 458.315314 -103.916734) (xy 458.307785 -103.909341)
			(xy 458.288511 -103.900811) (xy 458.277976 -103.900224) (xy 458.2033 -103.900224) (xy 458.192748 -103.900733)
			(xy 458.173452 -103.909281) (xy 458.165962 -103.916734) (xy 458.146142 -103.937522) (xy 458.10137 -103.973497)
			(xy 458.051712 -104.002357) (xy 457.99829 -104.02345) (xy 457.942311 -104.036299) (xy 457.885038 -104.040614)
			(xy 457.827765 -104.036299) (xy 457.771786 -104.02345) (xy 457.718364 -104.002357) (xy 457.668706 -103.973497)
			(xy 457.623934 -103.937522) (xy 457.604114 -103.916734) (xy 457.596585 -103.909341) (xy 457.577311 -103.900811)
			(xy 457.566776 -103.900224) (xy 457.4921 -103.900224) (xy 457.481548 -103.900733) (xy 457.462252 -103.909281)
			(xy 457.454762 -103.916734) (xy 457.436625 -103.935807) (xy 457.39599 -103.969262) (xy 457.351146 -103.996817)
			(xy 457.302942 -104.017953) (xy 457.252291 -104.032266) (xy 457.200155 -104.039487) (xy 457.173838 -104.039924)
			(xy 457.146585 -104.039431) (xy 457.092632 -104.031679) (xy 457.040332 -104.016327) (xy 456.990749 -103.993688)
			(xy 456.944893 -103.964222) (xy 456.903697 -103.92853) (xy 456.868001 -103.887338) (xy 456.838531 -103.841485)
			(xy 456.815886 -103.791904) (xy 456.800529 -103.739605) (xy 456.792771 -103.685653) (xy 453.905082 -103.685653)
			(xy 453.905082 -103.720248) (xy 453.897326 -103.774189) (xy 453.881974 -103.826477) (xy 453.859336 -103.876048)
			(xy 453.829874 -103.921893) (xy 453.794187 -103.963079) (xy 453.753003 -103.998766) (xy 453.707159 -104.02823)
			(xy 453.657588 -104.050869) (xy 453.605301 -104.066224) (xy 453.55136 -104.073981) (xy 453.524112 -104.074468)
			(xy 453.496742 -104.074003) (xy 453.442562 -104.066186) (xy 453.390059 -104.050697) (xy 453.340312 -104.027855)
			(xy 453.294345 -103.99813) (xy 453.273414 -103.980488) (xy 453.27316 -103.980234) (xy 453.266066 -103.974659)
			(xy 453.249155 -103.968407) (xy 453.24014 -103.968042) (xy 453.173084 -103.968042) (xy 453.164065 -103.968382)
			(xy 453.147148 -103.97464) (xy 453.140064 -103.980234) (xy 453.13981 -103.980488) (xy 453.118877 -103.998129)
			(xy 453.072909 -104.027853) (xy 453.023163 -104.050699) (xy 452.970661 -104.066195) (xy 452.916483 -104.074024)
			(xy 452.861741 -104.074024) (xy 452.807563 -104.066195) (xy 452.755061 -104.050699) (xy 452.705315 -104.027853)
			(xy 452.659347 -103.998129) (xy 452.638414 -103.980488) (xy 452.63816 -103.980234) (xy 452.631066 -103.974659)
			(xy 452.614155 -103.968407) (xy 452.60514 -103.968042) (xy 452.538084 -103.968042) (xy 452.529065 -103.968382)
			(xy 452.512148 -103.97464) (xy 452.505064 -103.980234) (xy 452.505064 -103.980488) (xy 452.50481 -103.980488)
			(xy 452.483883 -103.998134) (xy 452.437909 -104.027845) (xy 452.38816 -104.05068) (xy 452.335658 -104.066169)
			(xy 452.281482 -104.073995) (xy 452.254112 -104.074468) (xy 452.226856 -104.074086) (xy 452.172898 -104.066329)
			(xy 452.120593 -104.050973) (xy 452.071006 -104.028329) (xy 452.025147 -103.998858) (xy 451.983948 -103.96316)
			(xy 451.948249 -103.921963) (xy 451.918777 -103.876105) (xy 451.896131 -103.826518) (xy 451.880773 -103.774214)
			(xy 451.873015 -103.720256) (xy 449.220722 -103.720256) (xy 449.22059 -103.722678) (xy 449.22059 -103.797354)
			(xy 449.221133 -103.807902) (xy 449.229659 -103.827197) (xy 449.2371 -103.834692) (xy 449.256145 -103.852859)
			(xy 449.289603 -103.893486) (xy 449.317163 -103.938324) (xy 449.338304 -103.986522) (xy 449.352623 -104.037168)
			(xy 449.35985 -104.0893) (xy 449.36029 -104.115616) (xy 449.359804 -104.142867) (xy 449.352048 -104.196815)
			(xy 449.336693 -104.24911) (xy 449.314051 -104.298687) (xy 449.284585 -104.344537) (xy 449.248894 -104.385728)
			(xy 449.207703 -104.421419) (xy 449.161853 -104.450885) (xy 449.112276 -104.473527) (xy 449.059981 -104.488882)
			(xy 449.006033 -104.496638) (xy 448.951531 -104.496638) (xy 448.897583 -104.488882) (xy 448.845288 -104.473527)
			(xy 448.795711 -104.450885) (xy 448.749861 -104.421419) (xy 448.70867 -104.385728) (xy 448.672979 -104.344537)
			(xy 448.643513 -104.298687) (xy 448.620871 -104.24911) (xy 448.605516 -104.196815) (xy 448.59776 -104.142867)
			(xy 448.597274 -104.115616) (xy 445.67939 -104.115616) (xy 445.667414 -104.156401) (xy 445.644772 -104.205978)
			(xy 445.615305 -104.251828) (xy 445.579613 -104.293019) (xy 445.538422 -104.32871) (xy 445.492571 -104.358176)
			(xy 445.442993 -104.380817) (xy 445.390698 -104.396172) (xy 445.336749 -104.403928) (xy 445.309498 -104.404414)
			(xy 445.280579 -104.40393) (xy 445.223405 -104.395198) (xy 445.168204 -104.377936) (xy 445.116242 -104.352538)
			(xy 445.068709 -104.319587) (xy 445.026696 -104.279838) (xy 445.008508 -104.257348) (xy 445.000897 -104.248546)
			(xy 444.979999 -104.238361) (xy 444.968376 -104.23779) (xy 444.88862 -104.23779) (xy 444.876992 -104.238359)
			(xy 444.856082 -104.248527) (xy 444.848488 -104.257348) (xy 444.830316 -104.279847) (xy 444.788291 -104.319579)
			(xy 444.740751 -104.352515) (xy 444.688787 -104.3779) (xy 444.633587 -104.395154) (xy 444.576415 -104.40388)
			(xy 444.547498 -104.404414) (xy 444.520247 -104.403924) (xy 444.4663 -104.396167) (xy 444.414005 -104.380812)
			(xy 444.364429 -104.358171) (xy 444.318578 -104.328706) (xy 444.277388 -104.293014) (xy 444.241697 -104.251825)
			(xy 444.21223 -104.205975) (xy 444.189589 -104.156398) (xy 444.174233 -104.104104) (xy 444.166476 -104.050157)
			(xy 444.16599 -104.022906) (xy 442.27904 -104.022906) (xy 442.277949 -104.026533) (xy 442.254277 -104.07703)
			(xy 442.223504 -104.123543) (xy 442.186287 -104.16508) (xy 442.143419 -104.200755) (xy 442.095813 -104.229809)
			(xy 442.044484 -104.251621) (xy 441.990527 -104.265727) (xy 441.93509 -104.271827) (xy 441.879356 -104.26979)
			(xy 441.824513 -104.25966) (xy 441.771729 -104.241653) (xy 441.722129 -104.216152) (xy 441.676771 -104.183701)
			(xy 441.636622 -104.144992) (xy 441.602536 -104.100849) (xy 441.57524 -104.052214) (xy 441.555317 -104.000123)
			(xy 441.543191 -103.945686) (xy 441.53912 -103.890064) (xy 441.277428 -103.890064) (xy 441.277502 -103.894128)
			(xy 441.276993 -103.922014) (xy 441.268873 -103.97719) (xy 441.252805 -104.030597) (xy 441.229133 -104.081094)
			(xy 441.19836 -104.127607) (xy 441.161143 -104.169144) (xy 441.118275 -104.204819) (xy 441.070669 -104.233873)
			(xy 441.01934 -104.255685) (xy 440.965383 -104.269791) (xy 440.909946 -104.275891) (xy 440.854212 -104.273854)
			(xy 440.799369 -104.263724) (xy 440.746585 -104.245717) (xy 440.696985 -104.220216) (xy 440.651627 -104.187765)
			(xy 440.611478 -104.149056) (xy 440.577392 -104.104913) (xy 440.550096 -104.056278) (xy 440.530173 -104.004187)
			(xy 440.518047 -103.94975) (xy 440.513976 -103.894128) (xy 439.500507 -103.894128) (xy 439.49972 -103.896662)
			(xy 439.474629 -103.948374) (xy 439.442064 -103.995737) (xy 439.422794 -104.017064) (xy 439.41619 -104.023922)
			(xy 439.409078 -104.041956) (xy 439.409078 -104.130856) (xy 439.41619 -104.14889) (xy 439.422794 -104.155748)
			(xy 439.44207 -104.17707) (xy 439.474633 -104.224434) (xy 439.499724 -104.276146) (xy 439.516772 -104.331038)
			(xy 439.525394 -104.387865) (xy 439.525393 -104.445343) (xy 439.51677 -104.502171) (xy 439.49972 -104.557062)
			(xy 439.474629 -104.608774) (xy 439.442064 -104.656137) (xy 439.422794 -104.677464) (xy 439.41619 -104.684322)
			(xy 439.409078 -104.702356) (xy 439.409078 -104.791256) (xy 439.41619 -104.80929) (xy 439.422794 -104.816148)
			(xy 439.44207 -104.83747) (xy 439.474633 -104.884834) (xy 439.499724 -104.936546) (xy 439.516772 -104.991438)
			(xy 439.525394 -105.048265) (xy 439.525393 -105.08445) (xy 444.044072 -105.08445) (xy 444.044072 -105.02995)
			(xy 444.051828 -104.976004) (xy 444.067181 -104.923711) (xy 444.089821 -104.874135) (xy 444.119285 -104.828285)
			(xy 444.154974 -104.787095) (xy 444.196161 -104.751403) (xy 444.242008 -104.721935) (xy 444.291582 -104.699292)
			(xy 444.343874 -104.683934) (xy 444.39782 -104.676174) (xy 444.42507 -104.675686) (xy 444.452439 -104.676173)
			(xy 444.506617 -104.683986) (xy 444.55912 -104.699471) (xy 444.608867 -104.722308) (xy 444.654835 -104.752027)
			(xy 444.675768 -104.769666) (xy 444.676022 -104.76992) (xy 444.683096 -104.775524) (xy 444.700023 -104.78176)
			(xy 444.709042 -104.782112) (xy 444.776098 -104.782112) (xy 444.785114 -104.781751) (xy 444.802031 -104.775506)
			(xy 444.809118 -104.76992) (xy 444.809118 -104.769666) (xy 444.809372 -104.769666) (xy 444.830305 -104.752025)
			(xy 444.876273 -104.722301) (xy 444.926019 -104.699455) (xy 444.978521 -104.683959) (xy 445.032699 -104.67613)
			(xy 445.087441 -104.67613) (xy 445.141619 -104.683959) (xy 445.194121 -104.699455) (xy 445.243867 -104.722301)
			(xy 445.289835 -104.752025) (xy 445.310768 -104.769666) (xy 445.311022 -104.76992) (xy 445.318096 -104.775524)
			(xy 445.335023 -104.78176) (xy 445.344042 -104.782112) (xy 445.411098 -104.782112) (xy 445.420114 -104.781751)
			(xy 445.437031 -104.775506) (xy 445.444118 -104.76992) (xy 445.444118 -104.769666) (xy 445.444372 -104.769666)
			(xy 445.465305 -104.752025) (xy 445.511273 -104.722301) (xy 445.561019 -104.699455) (xy 445.613521 -104.683959)
			(xy 445.667699 -104.67613) (xy 445.722441 -104.67613) (xy 445.776619 -104.683959) (xy 445.829121 -104.699455)
			(xy 445.878867 -104.722301) (xy 445.924835 -104.752025) (xy 445.945768 -104.769666) (xy 445.946022 -104.76992)
			(xy 445.953096 -104.775524) (xy 445.970023 -104.78176) (xy 445.979042 -104.782112) (xy 446.046098 -104.782112)
			(xy 446.055114 -104.781751) (xy 446.072031 -104.775506) (xy 446.079118 -104.76992) (xy 446.079118 -104.769666)
			(xy 446.079372 -104.769666) (xy 446.100299 -104.752021) (xy 446.146274 -104.722311) (xy 446.196023 -104.699477)
			(xy 446.248524 -104.683987) (xy 446.302701 -104.67616) (xy 446.33007 -104.675686) (xy 446.357324 -104.676159)
			(xy 446.411277 -104.683913) (xy 446.463578 -104.699266) (xy 446.513161 -104.721906) (xy 446.559017 -104.751373)
			(xy 446.600213 -104.787066) (xy 446.635909 -104.828259) (xy 446.665379 -104.874113) (xy 446.688024 -104.923694)
			(xy 446.703381 -104.975994) (xy 446.711139 -105.029946) (xy 446.711139 -105.08445) (xy 447.967872 -105.08445)
			(xy 447.967872 -105.02995) (xy 447.975627 -104.976005) (xy 447.990981 -104.923712) (xy 448.01362 -104.874137)
			(xy 448.043083 -104.828287) (xy 448.078771 -104.787098) (xy 448.119957 -104.751406) (xy 448.165803 -104.721938)
			(xy 448.215377 -104.699294) (xy 448.267668 -104.683935) (xy 448.321612 -104.676174) (xy 448.348862 -104.675686)
			(xy 448.375177 -104.676117) (xy 448.427307 -104.68336) (xy 448.47795 -104.697686) (xy 448.526149 -104.718826)
			(xy 448.570992 -104.746378) (xy 448.61163 -104.779822) (xy 448.629786 -104.798876) (xy 448.637314 -104.80627)
			(xy 448.656589 -104.8148) (xy 448.667124 -104.815386) (xy 448.7418 -104.815386) (xy 448.752352 -104.814874)
			(xy 448.771647 -104.806327) (xy 448.779138 -104.798876) (xy 448.797277 -104.779804) (xy 448.837911 -104.74635)
			(xy 448.882755 -104.718793) (xy 448.930959 -104.697658) (xy 448.981609 -104.683344) (xy 449.033745 -104.676123)
			(xy 449.060062 -104.675686) (xy 449.087431 -104.676178) (xy 449.141609 -104.68399) (xy 449.194112 -104.699473)
			(xy 449.243859 -104.722309) (xy 449.289827 -104.752028) (xy 449.31076 -104.769666) (xy 449.311014 -104.76992)
			(xy 449.318091 -104.775521) (xy 449.335015 -104.781758) (xy 449.344034 -104.782112) (xy 449.41109 -104.782112)
			(xy 449.420106 -104.781748) (xy 449.437023 -104.775505) (xy 449.44411 -104.76992) (xy 449.44411 -104.769666)
			(xy 449.444364 -104.769666) (xy 449.465297 -104.752025) (xy 449.511265 -104.722301) (xy 449.561011 -104.699455)
			(xy 449.613513 -104.683959) (xy 449.667691 -104.67613) (xy 449.722433 -104.67613) (xy 449.776611 -104.683959)
			(xy 449.829113 -104.699455) (xy 449.878859 -104.722301) (xy 449.924827 -104.752025) (xy 449.94576 -104.769666)
			(xy 449.946014 -104.76992) (xy 449.953091 -104.775521) (xy 449.970015 -104.781758) (xy 449.979034 -104.782112)
			(xy 450.04609 -104.782112) (xy 450.055106 -104.781748) (xy 450.072023 -104.775505) (xy 450.07911 -104.76992)
			(xy 450.07911 -104.769666) (xy 450.079364 -104.769666) (xy 450.100294 -104.752025) (xy 450.146268 -104.722315)
			(xy 450.196016 -104.69948) (xy 450.248517 -104.683989) (xy 450.302693 -104.67616) (xy 450.330062 -104.675686)
			(xy 450.357316 -104.676159) (xy 450.41127 -104.683911) (xy 450.463572 -104.699264) (xy 450.513156 -104.721904)
			(xy 450.559013 -104.75137) (xy 450.60021 -104.787063) (xy 450.635907 -104.828256) (xy 450.665378 -104.874111)
			(xy 450.688023 -104.923692) (xy 450.703381 -104.975992) (xy 450.711139 -105.029946) (xy 450.711139 -105.084454)
			(xy 450.703381 -105.138408) (xy 450.688023 -105.190708) (xy 450.665378 -105.240289) (xy 450.635907 -105.286144)
			(xy 450.60021 -105.327337) (xy 450.559013 -105.36303) (xy 450.513156 -105.392496) (xy 450.463572 -105.415136)
			(xy 450.41127 -105.430489) (xy 450.357316 -105.438241) (xy 450.330062 -105.438702) (xy 450.302693 -105.438199)
			(xy 450.248516 -105.43039) (xy 450.196013 -105.41491) (xy 450.146265 -105.392076) (xy 450.100297 -105.362359)
			(xy 450.079364 -105.344722) (xy 450.07911 -105.344468) (xy 450.072027 -105.338876) (xy 450.055107 -105.332634)
			(xy 450.04609 -105.332276) (xy 449.979034 -105.332276) (xy 449.970019 -105.332654) (xy 449.953103 -105.338888)
			(xy 449.946014 -105.344468) (xy 449.94576 -105.344722) (xy 449.924827 -105.362363) (xy 449.878859 -105.392087)
			(xy 449.829113 -105.414933) (xy 449.776611 -105.430429) (xy 449.722433 -105.438258) (xy 449.667691 -105.438258)
			(xy 449.613513 -105.430429) (xy 449.561011 -105.414933) (xy 449.511265 -105.392087) (xy 449.465297 -105.362363)
			(xy 449.444364 -105.344722) (xy 449.44411 -105.344468) (xy 449.437027 -105.338876) (xy 449.420107 -105.332634)
			(xy 449.41109 -105.332276) (xy 449.344034 -105.332276) (xy 449.335019 -105.332654) (xy 449.318103 -105.338888)
			(xy 449.311014 -105.344468) (xy 449.311014 -105.344722) (xy 449.31076 -105.344722) (xy 449.289819 -105.36235)
			(xy 449.243848 -105.392063) (xy 449.194103 -105.4149) (xy 449.141604 -105.430394) (xy 449.08743 -105.438226)
			(xy 449.060062 -105.438702) (xy 449.033747 -105.438259) (xy 448.981618 -105.431019) (xy 448.930974 -105.416695)
			(xy 448.882776 -105.395558) (xy 448.837933 -105.368008) (xy 448.797294 -105.334565) (xy 448.779138 -105.315512)
			(xy 448.771603 -105.308127) (xy 448.752333 -105.299593) (xy 448.7418 -105.299002) (xy 448.667124 -105.299002)
			(xy 448.656574 -105.29953) (xy 448.637279 -105.308066) (xy 448.629786 -105.315512) (xy 448.611633 -105.33457)
			(xy 448.571002 -105.368026) (xy 448.526161 -105.395585) (xy 448.47796 -105.416723) (xy 448.427312 -105.431039)
			(xy 448.375178 -105.438264) (xy 448.348862 -105.438702) (xy 448.321612 -105.438226) (xy 448.267668 -105.430465)
			(xy 448.215377 -105.415106) (xy 448.165803 -105.392462) (xy 448.119957 -105.362994) (xy 448.078771 -105.327302)
			(xy 448.043083 -105.286113) (xy 448.01362 -105.240263) (xy 447.990981 -105.190688) (xy 447.975627 -105.138395)
			(xy 447.967872 -105.08445) (xy 446.711139 -105.08445) (xy 446.711139 -105.084454) (xy 446.703381 -105.138406)
			(xy 446.688024 -105.190706) (xy 446.665379 -105.240287) (xy 446.635909 -105.286141) (xy 446.600213 -105.327334)
			(xy 446.559017 -105.363027) (xy 446.513161 -105.392494) (xy 446.463578 -105.415134) (xy 446.411277 -105.430487)
			(xy 446.357324 -105.438241) (xy 446.33007 -105.438702) (xy 446.302699 -105.438253) (xy 446.248519 -105.430431)
			(xy 446.196016 -105.414938) (xy 446.14627 -105.392092) (xy 446.100303 -105.362365) (xy 446.079372 -105.344722)
			(xy 446.079118 -105.344468) (xy 446.072033 -105.338879) (xy 446.055115 -105.332635) (xy 446.046098 -105.332276)
			(xy 445.979042 -105.332276) (xy 445.970028 -105.332658) (xy 445.953111 -105.338889) (xy 445.946022 -105.344468)
			(xy 445.945768 -105.344722) (xy 445.924835 -105.362363) (xy 445.878867 -105.392087) (xy 445.829121 -105.414933)
			(xy 445.776619 -105.430429) (xy 445.722441 -105.438258) (xy 445.667699 -105.438258) (xy 445.613521 -105.430429)
			(xy 445.561019 -105.414933) (xy 445.511273 -105.392087) (xy 445.465305 -105.362363) (xy 445.444372 -105.344722)
			(xy 445.444118 -105.344468) (xy 445.437033 -105.338879) (xy 445.420115 -105.332635) (xy 445.411098 -105.332276)
			(xy 445.344042 -105.332276) (xy 445.335028 -105.332658) (xy 445.318111 -105.338889) (xy 445.311022 -105.344468)
			(xy 445.311022 -105.344722) (xy 445.310768 -105.344722) (xy 445.289835 -105.362363) (xy 445.243867 -105.392087)
			(xy 445.194121 -105.414933) (xy 445.141619 -105.430429) (xy 445.087441 -105.438258) (xy 445.032699 -105.438258)
			(xy 444.978521 -105.430429) (xy 444.926019 -105.414933) (xy 444.876273 -105.392087) (xy 444.830305 -105.362363)
			(xy 444.809372 -105.344722) (xy 444.809118 -105.344468) (xy 444.802033 -105.338879) (xy 444.785115 -105.332635)
			(xy 444.776098 -105.332276) (xy 444.709042 -105.332276) (xy 444.700028 -105.332658) (xy 444.683111 -105.338889)
			(xy 444.676022 -105.344468) (xy 444.676022 -105.344722) (xy 444.675768 -105.344722) (xy 444.654824 -105.362346)
			(xy 444.608854 -105.392059) (xy 444.55911 -105.414898) (xy 444.506612 -105.430393) (xy 444.452438 -105.438225)
			(xy 444.42507 -105.438702) (xy 444.39782 -105.438226) (xy 444.343874 -105.430466) (xy 444.291582 -105.415108)
			(xy 444.242008 -105.392465) (xy 444.196161 -105.362997) (xy 444.154974 -105.327305) (xy 444.119285 -105.286115)
			(xy 444.089821 -105.240265) (xy 444.067181 -105.190689) (xy 444.051828 -105.138396) (xy 444.044072 -105.08445)
			(xy 439.525393 -105.08445) (xy 439.525393 -105.105743) (xy 439.51677 -105.162571) (xy 439.49972 -105.217462)
			(xy 439.474629 -105.269174) (xy 439.442064 -105.316537) (xy 439.422794 -105.337864) (xy 439.41619 -105.344722)
			(xy 439.409078 -105.362756) (xy 439.409078 -105.451656) (xy 439.41619 -105.46969) (xy 439.422794 -105.476548)
			(xy 439.44207 -105.49787) (xy 439.474633 -105.545234) (xy 439.499724 -105.596946) (xy 439.516772 -105.651838)
			(xy 439.525394 -105.708665) (xy 439.525393 -105.766143) (xy 439.51677 -105.822971) (xy 439.49972 -105.877862)
			(xy 439.474629 -105.929574) (xy 439.442064 -105.976937) (xy 439.422794 -105.998264) (xy 439.41619 -106.005122)
			(xy 439.409078 -106.023156) (xy 439.409078 -106.112056) (xy 439.41619 -106.13009) (xy 439.422794 -106.136948)
			(xy 439.44207 -106.15827) (xy 439.474633 -106.205634) (xy 439.499724 -106.257346) (xy 439.516772 -106.312238)
			(xy 439.525394 -106.369065) (xy 439.525393 -106.426543) (xy 439.51677 -106.483371) (xy 439.49972 -106.538262)
			(xy 439.474629 -106.589974) (xy 439.442064 -106.637337) (xy 439.422794 -106.658664) (xy 439.41619 -106.665522)
			(xy 439.409078 -106.683556) (xy 439.409078 -106.772456) (xy 439.41619 -106.79049) (xy 439.422794 -106.797348)
			(xy 439.431564 -106.807049) (xy 451.9031 -106.807049) (xy 451.9031 -106.752551) (xy 451.910856 -106.698608)
			(xy 451.926209 -106.646318) (xy 451.948848 -106.596744) (xy 451.978311 -106.550897) (xy 452.013999 -106.50971)
			(xy 452.055185 -106.474021) (xy 452.10103 -106.444556) (xy 452.150603 -106.421915) (xy 452.202892 -106.406559)
			(xy 452.256835 -106.398801) (xy 452.284084 -106.398314) (xy 452.311454 -106.398786) (xy 452.365633 -106.406602)
			(xy 452.418136 -106.422089) (xy 452.467883 -106.44493) (xy 452.51385 -106.474653) (xy 452.534782 -106.492294)
			(xy 452.535036 -106.492548) (xy 452.542133 -106.49812) (xy 452.559042 -106.504374) (xy 452.568056 -106.50474)
			(xy 452.635112 -106.50474) (xy 452.644131 -106.504402) (xy 452.661048 -106.498142) (xy 452.668132 -106.492548)
			(xy 452.668132 -106.492294) (xy 452.668386 -106.492294) (xy 452.689319 -106.474653) (xy 452.735287 -106.444929)
			(xy 452.785033 -106.422083) (xy 452.837535 -106.406587) (xy 452.891713 -106.398758) (xy 452.946455 -106.398758)
			(xy 453.000633 -106.406587) (xy 453.053135 -106.422083) (xy 453.102881 -106.444929) (xy 453.148849 -106.474653)
			(xy 453.169782 -106.492294) (xy 453.170036 -106.492548) (xy 453.177133 -106.49812) (xy 453.194042 -106.504374)
			(xy 453.203056 -106.50474) (xy 453.270112 -106.50474) (xy 453.279131 -106.504402) (xy 453.296048 -106.498142)
			(xy 453.303132 -106.492548) (xy 453.303132 -106.492294) (xy 453.303386 -106.492294) (xy 453.324312 -106.474647)
			(xy 453.370286 -106.444937) (xy 453.420036 -106.422102) (xy 453.472538 -106.406613) (xy 453.526714 -106.398787)
			(xy 453.554084 -106.398314) (xy 453.581339 -106.398732) (xy 453.635295 -106.406487) (xy 453.687598 -106.421843)
			(xy 453.737183 -106.444486) (xy 453.783041 -106.473955) (xy 453.824238 -106.509651) (xy 453.859935 -106.550846)
			(xy 453.889406 -106.596703) (xy 453.912051 -106.646287) (xy 453.927409 -106.698589) (xy 453.935167 -106.752545)
			(xy 453.935167 -106.802446) (xy 456.721028 -106.802446) (xy 456.721028 -106.747954) (xy 456.728782 -106.694018)
			(xy 456.744133 -106.641733) (xy 456.766768 -106.592166) (xy 456.796226 -106.546323) (xy 456.831909 -106.50514)
			(xy 456.873088 -106.469453) (xy 456.918927 -106.439989) (xy 456.968492 -106.417349) (xy 457.020775 -106.401992)
			(xy 457.07471 -106.394231) (xy 457.101956 -106.393742) (xy 457.128272 -106.394159) (xy 457.180403 -106.401402)
			(xy 457.231047 -106.41573) (xy 457.279246 -106.436872) (xy 457.324089 -106.464428) (xy 457.364725 -106.497876)
			(xy 457.38288 -106.516932) (xy 457.390416 -106.524317) (xy 457.409685 -106.532853) (xy 457.420218 -106.533442)
			(xy 457.494894 -106.533442) (xy 457.505443 -106.532911) (xy 457.524738 -106.524376) (xy 457.532232 -106.516932)
			(xy 457.552052 -106.496144) (xy 457.596824 -106.460169) (xy 457.646482 -106.431309) (xy 457.699904 -106.410216)
			(xy 457.755883 -106.397367) (xy 457.813156 -106.393052) (xy 457.870429 -106.397367) (xy 457.926408 -106.410216)
			(xy 457.97983 -106.431309) (xy 458.029488 -106.460169) (xy 458.07426 -106.496144) (xy 458.09408 -106.516932)
			(xy 458.101616 -106.524317) (xy 458.120885 -106.532853) (xy 458.131418 -106.533442) (xy 458.206094 -106.533442)
			(xy 458.216643 -106.532911) (xy 458.235938 -106.524376) (xy 458.243432 -106.516932) (xy 458.261585 -106.497874)
			(xy 458.302215 -106.464416) (xy 458.347055 -106.436856) (xy 458.395257 -106.415718) (xy 458.445905 -106.401402)
			(xy 458.49804 -106.394179) (xy 458.524356 -106.393742) (xy 458.551614 -106.394102) (xy 458.605577 -106.401855)
			(xy 458.657887 -106.417209) (xy 458.70748 -106.439852) (xy 458.753344 -106.469323) (xy 458.794548 -106.505021)
			(xy 458.830251 -106.54622) (xy 458.859727 -106.592082) (xy 458.882375 -106.641671) (xy 458.897736 -106.69398)
			(xy 458.905495 -106.747942) (xy 458.905495 -106.802458) (xy 458.897736 -106.85642) (xy 458.882375 -106.908729)
			(xy 458.859727 -106.958318) (xy 458.830251 -107.00418) (xy 458.794548 -107.045379) (xy 458.753344 -107.081077)
			(xy 458.70748 -107.110548) (xy 458.657887 -107.133191) (xy 458.605577 -107.148545) (xy 458.551615 -107.156298)
			(xy 458.524356 -107.156758) (xy 458.49804 -107.156333) (xy 458.44591 -107.149092) (xy 458.395265 -107.134765)
			(xy 458.347066 -107.113625) (xy 458.302224 -107.08607) (xy 458.261587 -107.052624) (xy 458.243432 -107.033568)
			(xy 458.235891 -107.026188) (xy 458.216626 -107.017649) (xy 458.206094 -107.017058) (xy 458.131418 -107.017058)
			(xy 458.12087 -107.017596) (xy 458.101575 -107.026126) (xy 458.09408 -107.033568) (xy 458.07426 -107.054356)
			(xy 458.029488 -107.090331) (xy 457.97983 -107.119191) (xy 457.926408 -107.140284) (xy 457.870429 -107.153133)
			(xy 457.813156 -107.157448) (xy 457.755883 -107.153133) (xy 457.699904 -107.140284) (xy 457.646482 -107.119191)
			(xy 457.596824 -107.090331) (xy 457.552052 -107.054356) (xy 457.532232 -107.033568) (xy 457.524691 -107.026188)
			(xy 457.505426 -107.017649) (xy 457.494894 -107.017058) (xy 457.420218 -107.017058) (xy 457.40967 -107.017596)
			(xy 457.390375 -107.026126) (xy 457.38288 -107.033568) (xy 457.364721 -107.05262) (xy 457.324093 -107.086079)
			(xy 457.279253 -107.113639) (xy 457.231053 -107.134778) (xy 457.180406 -107.149096) (xy 457.128272 -107.15632)
			(xy 457.101956 -107.156758) (xy 457.07471 -107.156169) (xy 457.020775 -107.148408) (xy 456.968492 -107.133051)
			(xy 456.918927 -107.110411) (xy 456.873088 -107.080947) (xy 456.831909 -107.04526) (xy 456.796226 -107.004077)
			(xy 456.766768 -106.958234) (xy 456.744133 -106.908667) (xy 456.728782 -106.856382) (xy 456.721028 -106.802446)
			(xy 453.935167 -106.802446) (xy 453.935167 -106.807055) (xy 453.927409 -106.861011) (xy 453.912051 -106.913313)
			(xy 453.889406 -106.962897) (xy 453.859935 -107.008754) (xy 453.824238 -107.049949) (xy 453.783041 -107.085645)
			(xy 453.737183 -107.115114) (xy 453.687598 -107.137757) (xy 453.635295 -107.153113) (xy 453.581339 -107.160868)
			(xy 453.554084 -107.16133) (xy 453.526713 -107.16089) (xy 453.472532 -107.153069) (xy 453.420028 -107.137574)
			(xy 453.370281 -107.114726) (xy 453.324316 -107.084995) (xy 453.303386 -107.06735) (xy 453.303132 -107.067096)
			(xy 453.296041 -107.061516) (xy 453.279128 -107.055266) (xy 453.270112 -107.054904) (xy 453.203056 -107.054904)
			(xy 453.194042 -107.055287) (xy 453.177125 -107.061517) (xy 453.170036 -107.067096) (xy 453.169782 -107.06735)
			(xy 453.148849 -107.084991) (xy 453.102881 -107.114715) (xy 453.053135 -107.137561) (xy 453.000633 -107.153057)
			(xy 452.946455 -107.160886) (xy 452.891713 -107.160886) (xy 452.837535 -107.153057) (xy 452.785033 -107.137561)
			(xy 452.735287 -107.114715) (xy 452.689319 -107.084991) (xy 452.668386 -107.06735) (xy 452.668132 -107.067096)
			(xy 452.661041 -107.061516) (xy 452.644128 -107.055266) (xy 452.635112 -107.054904) (xy 452.568056 -107.054904)
			(xy 452.559042 -107.055287) (xy 452.542125 -107.061517) (xy 452.535036 -107.067096) (xy 452.535036 -107.06735)
			(xy 452.534782 -107.06735) (xy 452.513823 -107.084956) (xy 452.467859 -107.114675) (xy 452.418118 -107.137518)
			(xy 452.365623 -107.153016) (xy 452.311451 -107.160852) (xy 452.284084 -107.16133) (xy 452.256835 -107.160799)
			(xy 452.202892 -107.153041) (xy 452.150603 -107.137685) (xy 452.10103 -107.115044) (xy 452.055185 -107.085579)
			(xy 452.013999 -107.04989) (xy 451.978311 -107.008703) (xy 451.948848 -106.962856) (xy 451.926209 -106.913282)
			(xy 451.910856 -106.860992) (xy 451.9031 -106.807049) (xy 439.431564 -106.807049) (xy 439.44207 -106.81867)
			(xy 439.474633 -106.866034) (xy 439.499724 -106.917746) (xy 439.516772 -106.972638) (xy 439.525394 -107.029465)
			(xy 439.525393 -107.086943) (xy 439.51677 -107.143771) (xy 439.49972 -107.198662) (xy 439.474629 -107.250374)
			(xy 439.442064 -107.297737) (xy 439.422794 -107.319064) (xy 439.41619 -107.325922) (xy 439.409078 -107.343956)
			(xy 439.409078 -107.432856) (xy 439.41619 -107.45089) (xy 439.422794 -107.457748) (xy 439.44207 -107.47907)
			(xy 439.474633 -107.526434) (xy 439.499724 -107.578146) (xy 439.516772 -107.633038) (xy 439.525394 -107.689865)
			(xy 439.525393 -107.740249) (xy 443.984396 -107.740249) (xy 443.984396 -107.685751) (xy 443.992152 -107.631808)
			(xy 444.007505 -107.579517) (xy 444.030144 -107.529944) (xy 444.059607 -107.484096) (xy 444.095294 -107.442909)
			(xy 444.13648 -107.407219) (xy 444.182326 -107.377753) (xy 444.231898 -107.355112) (xy 444.284188 -107.339756)
			(xy 444.338131 -107.331998) (xy 444.36538 -107.33151) (xy 444.39275 -107.331985) (xy 444.446929 -107.339801)
			(xy 444.499432 -107.355287) (xy 444.549179 -107.378127) (xy 444.595146 -107.40785) (xy 444.616078 -107.42549)
			(xy 444.616332 -107.425744) (xy 444.62343 -107.431314) (xy 444.640338 -107.437569) (xy 444.649352 -107.437936)
			(xy 444.716408 -107.437936) (xy 444.725424 -107.437575) (xy 444.742341 -107.43133) (xy 444.749428 -107.425744)
			(xy 444.749428 -107.42549) (xy 444.749682 -107.42549) (xy 444.770615 -107.407849) (xy 444.816583 -107.378125)
			(xy 444.866329 -107.355279) (xy 444.918831 -107.339783) (xy 444.973009 -107.331954) (xy 445.027751 -107.331954)
			(xy 445.081929 -107.339783) (xy 445.134431 -107.355279) (xy 445.184177 -107.378125) (xy 445.230145 -107.407849)
			(xy 445.251078 -107.42549) (xy 445.251332 -107.425744) (xy 445.25843 -107.431314) (xy 445.275338 -107.437569)
			(xy 445.284352 -107.437936) (xy 445.351408 -107.437936) (xy 445.360424 -107.437575) (xy 445.377341 -107.43133)
			(xy 445.384428 -107.425744) (xy 445.384428 -107.42549) (xy 445.384682 -107.42549) (xy 445.405615 -107.407849)
			(xy 445.451583 -107.378125) (xy 445.501329 -107.355279) (xy 445.553831 -107.339783) (xy 445.608009 -107.331954)
			(xy 445.662751 -107.331954) (xy 445.716929 -107.339783) (xy 445.769431 -107.355279) (xy 445.819177 -107.378125)
			(xy 445.865145 -107.407849) (xy 445.886078 -107.42549) (xy 445.886332 -107.425744) (xy 445.89343 -107.431314)
			(xy 445.910338 -107.437569) (xy 445.919352 -107.437936) (xy 445.986408 -107.437936) (xy 445.995424 -107.437575)
			(xy 446.012341 -107.43133) (xy 446.019428 -107.425744) (xy 446.019428 -107.42549) (xy 446.019682 -107.42549)
			(xy 446.040609 -107.407844) (xy 446.086583 -107.378134) (xy 446.136332 -107.355299) (xy 446.188834 -107.33981)
			(xy 446.24301 -107.331983) (xy 446.27038 -107.33151) (xy 446.297635 -107.331936) (xy 446.351591 -107.339691)
			(xy 446.403894 -107.355046) (xy 446.453479 -107.377688) (xy 446.499336 -107.407157) (xy 446.540534 -107.442852)
			(xy 446.576231 -107.484047) (xy 446.605702 -107.529904) (xy 446.628347 -107.579488) (xy 446.643705 -107.63179)
			(xy 446.651463 -107.685745) (xy 446.651463 -107.709056) (xy 447.952531 -107.709056) (xy 447.952531 -107.654544)
			(xy 447.960289 -107.600588) (xy 447.975647 -107.548285) (xy 447.998293 -107.4987) (xy 448.027765 -107.452843)
			(xy 448.063463 -107.411647) (xy 448.104661 -107.375951) (xy 448.15052 -107.346482) (xy 448.200106 -107.323839)
			(xy 448.25241 -107.308484) (xy 448.306366 -107.300729) (xy 448.333622 -107.300268) (xy 448.359936 -107.300731)
			(xy 448.412064 -107.307968) (xy 448.462707 -107.322289) (xy 448.510905 -107.343422) (xy 448.555749 -107.370969)
			(xy 448.596389 -107.404407) (xy 448.614546 -107.423458) (xy 448.622054 -107.430876) (xy 448.641344 -107.439392)
			(xy 448.651884 -107.439968) (xy 448.72656 -107.439968) (xy 448.73711 -107.43944) (xy 448.756406 -107.430905)
			(xy 448.763898 -107.423458) (xy 448.782053 -107.404402) (xy 448.822684 -107.370947) (xy 448.867525 -107.343389)
			(xy 448.915725 -107.322251) (xy 448.966372 -107.307933) (xy 449.018506 -107.300707) (xy 449.044822 -107.300268)
			(xy 449.072193 -107.300705) (xy 449.126375 -107.308527) (xy 449.178879 -107.324022) (xy 449.228625 -107.346871)
			(xy 449.27459 -107.376603) (xy 449.29552 -107.394248) (xy 449.295774 -107.394502) (xy 449.302864 -107.400084)
			(xy 449.319778 -107.406333) (xy 449.328794 -107.406694) (xy 449.39585 -107.406694) (xy 449.404865 -107.406314)
			(xy 449.421782 -107.400082) (xy 449.42887 -107.394502) (xy 449.42887 -107.394248) (xy 449.429124 -107.394248)
			(xy 449.450057 -107.376607) (xy 449.496025 -107.346883) (xy 449.545771 -107.324037) (xy 449.598273 -107.308541)
			(xy 449.652451 -107.300712) (xy 449.707193 -107.300712) (xy 449.761371 -107.308541) (xy 449.813873 -107.324037)
			(xy 449.863619 -107.346883) (xy 449.909587 -107.376607) (xy 449.93052 -107.394248) (xy 449.930774 -107.394502)
			(xy 449.937864 -107.400084) (xy 449.954778 -107.406333) (xy 449.963794 -107.406694) (xy 450.03085 -107.406694)
			(xy 450.039865 -107.406314) (xy 450.056782 -107.400082) (xy 450.06387 -107.394502) (xy 450.06387 -107.394248)
			(xy 450.064124 -107.394248) (xy 450.08508 -107.376639) (xy 450.131046 -107.346921) (xy 450.180787 -107.324078)
			(xy 450.233282 -107.30858) (xy 450.287454 -107.300745) (xy 450.314822 -107.300268) (xy 450.34207 -107.300804)
			(xy 450.396012 -107.308562) (xy 450.448301 -107.323918) (xy 450.497872 -107.346559) (xy 450.543717 -107.376024)
			(xy 450.584902 -107.411714) (xy 450.620589 -107.452901) (xy 450.650051 -107.498747) (xy 450.672689 -107.54832)
			(xy 450.688042 -107.600609) (xy 450.695798 -107.654551) (xy 450.695798 -107.709048) (xy 450.688042 -107.762991)
			(xy 450.672689 -107.81528) (xy 450.650051 -107.864853) (xy 450.620589 -107.910699) (xy 450.584902 -107.951886)
			(xy 450.543717 -107.987576) (xy 450.497872 -108.017041) (xy 450.448301 -108.039682) (xy 450.396012 -108.055038)
			(xy 450.34207 -108.062796) (xy 450.314822 -108.063284) (xy 450.287452 -108.062809) (xy 450.233273 -108.054994)
			(xy 450.18077 -108.039507) (xy 450.131023 -108.016667) (xy 450.085056 -107.986944) (xy 450.064124 -107.969304)
			(xy 450.06387 -107.96905) (xy 450.056772 -107.963481) (xy 450.039864 -107.957225) (xy 450.03085 -107.956858)
			(xy 449.963794 -107.956858) (xy 449.954775 -107.9572) (xy 449.937858 -107.963457) (xy 449.930774 -107.96905)
			(xy 449.93052 -107.969304) (xy 449.909587 -107.986945) (xy 449.863619 -108.016669) (xy 449.813873 -108.039515)
			(xy 449.761371 -108.055011) (xy 449.707193 -108.06284) (xy 449.652451 -108.06284) (xy 449.598273 -108.055011)
			(xy 449.545771 -108.039515) (xy 449.496025 -108.016669) (xy 449.450057 -107.986945) (xy 449.429124 -107.969304)
			(xy 449.42887 -107.96905) (xy 449.421772 -107.963481) (xy 449.404864 -107.957225) (xy 449.39585 -107.956858)
			(xy 449.328794 -107.956858) (xy 449.319775 -107.9572) (xy 449.302858 -107.963457) (xy 449.295774 -107.96905)
			(xy 449.295774 -107.969304) (xy 449.29552 -107.969304) (xy 449.274592 -107.986948) (xy 449.228618 -108.016659)
			(xy 449.178869 -108.039494) (xy 449.126368 -108.054984) (xy 449.072191 -108.062811) (xy 449.044822 -108.063284)
			(xy 449.018508 -108.062807) (xy 448.96638 -108.055575) (xy 448.915737 -108.041258) (xy 448.867538 -108.020127)
			(xy 448.822694 -107.992583) (xy 448.782055 -107.959145) (xy 448.763898 -107.940094) (xy 448.75638 -107.932689)
			(xy 448.737097 -107.924167) (xy 448.72656 -107.923584) (xy 448.651884 -107.923584) (xy 448.641332 -107.924096)
			(xy 448.622038 -107.932644) (xy 448.614546 -107.940094) (xy 448.596409 -107.959168) (xy 448.555775 -107.992623)
			(xy 448.510931 -108.02018) (xy 448.462727 -108.041315) (xy 448.412076 -108.055629) (xy 448.359939 -108.062848)
			(xy 448.333622 -108.063284) (xy 448.306366 -108.062871) (xy 448.25241 -108.055116) (xy 448.200106 -108.039761)
			(xy 448.15052 -108.017118) (xy 448.104661 -107.987649) (xy 448.063463 -107.951953) (xy 448.027765 -107.910757)
			(xy 447.998293 -107.8649) (xy 447.975647 -107.815315) (xy 447.960289 -107.763012) (xy 447.952531 -107.709056)
			(xy 446.651463 -107.709056) (xy 446.651463 -107.740255) (xy 446.643705 -107.79421) (xy 446.628347 -107.846512)
			(xy 446.605702 -107.896096) (xy 446.576231 -107.941953) (xy 446.540534 -107.983148) (xy 446.499336 -108.018843)
			(xy 446.453479 -108.048312) (xy 446.403894 -108.070954) (xy 446.351591 -108.086309) (xy 446.297635 -108.094064)
			(xy 446.27038 -108.094526) (xy 446.243008 -108.09409) (xy 446.188827 -108.086267) (xy 446.136323 -108.070772)
			(xy 446.086577 -108.047924) (xy 446.040612 -108.018191) (xy 446.019682 -108.000546) (xy 446.019428 -108.000292)
			(xy 446.012338 -107.99471) (xy 445.995424 -107.988461) (xy 445.986408 -107.9881) (xy 445.919352 -107.9881)
			(xy 445.910338 -107.988482) (xy 445.893421 -107.994712) (xy 445.886332 -108.000292) (xy 445.886078 -108.000546)
			(xy 445.865145 -108.018187) (xy 445.819177 -108.047911) (xy 445.769431 -108.070757) (xy 445.716929 -108.086253)
			(xy 445.662751 -108.094082) (xy 445.608009 -108.094082) (xy 445.553831 -108.086253) (xy 445.501329 -108.070757)
			(xy 445.451583 -108.047911) (xy 445.405615 -108.018187) (xy 445.384682 -108.000546) (xy 445.384428 -108.000292)
			(xy 445.377338 -107.99471) (xy 445.360424 -107.988461) (xy 445.351408 -107.9881) (xy 445.284352 -107.9881)
			(xy 445.275338 -107.988482) (xy 445.258421 -107.994712) (xy 445.251332 -108.000292) (xy 445.251332 -108.000546)
			(xy 445.251078 -108.000546) (xy 445.230145 -108.018187) (xy 445.184177 -108.047911) (xy 445.134431 -108.070757)
			(xy 445.081929 -108.086253) (xy 445.027751 -108.094082) (xy 444.973009 -108.094082) (xy 444.918831 -108.086253)
			(xy 444.866329 -108.070757) (xy 444.816583 -108.047911) (xy 444.770615 -108.018187) (xy 444.749682 -108.000546)
			(xy 444.749428 -108.000292) (xy 444.742338 -107.99471) (xy 444.725424 -107.988461) (xy 444.716408 -107.9881)
			(xy 444.649352 -107.9881) (xy 444.640338 -107.988482) (xy 444.623421 -107.994712) (xy 444.616332 -108.000292)
			(xy 444.616332 -108.000546) (xy 444.616078 -108.000546) (xy 444.59512 -108.018154) (xy 444.549155 -108.047872)
			(xy 444.499415 -108.070715) (xy 444.446919 -108.086213) (xy 444.392748 -108.094048) (xy 444.36538 -108.094526)
			(xy 444.338131 -108.094002) (xy 444.284188 -108.086244) (xy 444.231898 -108.070888) (xy 444.182326 -108.048247)
			(xy 444.13648 -108.018781) (xy 444.095294 -107.983091) (xy 444.059607 -107.941904) (xy 444.030144 -107.896056)
			(xy 444.007505 -107.846483) (xy 443.992152 -107.794192) (xy 443.984396 -107.740249) (xy 439.525393 -107.740249)
			(xy 439.525393 -107.747343) (xy 439.51677 -107.804171) (xy 439.49972 -107.859062) (xy 439.474629 -107.910774)
			(xy 439.442064 -107.958137) (xy 439.422794 -107.979464) (xy 439.41619 -107.986322) (xy 439.409078 -108.004356)
			(xy 439.409078 -108.093256) (xy 439.41619 -108.11129) (xy 439.422794 -108.118148) (xy 439.442056 -108.139483)
			(xy 439.474626 -108.186842) (xy 439.499721 -108.238551) (xy 439.516773 -108.293441) (xy 439.525397 -108.350267)
			(xy 439.525918 -108.379006) (xy 439.525687 -108.39196) (xy 452.52767 -108.39196) (xy 452.528154 -108.36459)
			(xy 452.535965 -108.310411) (xy 452.551449 -108.257908) (xy 452.574287 -108.20816) (xy 452.604009 -108.162193)
			(xy 452.62165 -108.141262) (xy 452.621904 -108.141008) (xy 452.627494 -108.133924) (xy 452.633738 -108.117005)
			(xy 452.634096 -108.107988) (xy 452.634096 -108.040932) (xy 452.633725 -108.031917) (xy 452.627487 -108.014999)
			(xy 452.621904 -108.007912) (xy 452.62165 -108.007912) (xy 452.62165 -108.007658) (xy 452.604032 -107.986708)
			(xy 452.574316 -107.940741) (xy 452.551475 -107.890998) (xy 452.535979 -107.838501) (xy 452.528146 -107.784328)
			(xy 452.52767 -107.75696) (xy 452.528156 -107.729709) (xy 452.535912 -107.675761) (xy 452.551267 -107.623466)
			(xy 452.573909 -107.573889) (xy 452.603375 -107.528039) (xy 452.639066 -107.486848) (xy 452.680257 -107.451157)
			(xy 452.726107 -107.421691) (xy 452.775684 -107.399049) (xy 452.827979 -107.383694) (xy 452.881927 -107.375938)
			(xy 452.936429 -107.375938) (xy 452.990377 -107.383694) (xy 453.042672 -107.399049) (xy 453.092249 -107.421691)
			(xy 453.138099 -107.451157) (xy 453.17929 -107.486848) (xy 453.214981 -107.528039) (xy 453.244447 -107.573889)
			(xy 453.267089 -107.623466) (xy 453.282444 -107.675761) (xy 453.2902 -107.729709) (xy 453.290686 -107.75696)
			(xy 453.2902 -107.78433) (xy 453.282387 -107.838508) (xy 453.266903 -107.891011) (xy 453.244066 -107.940758)
			(xy 453.214345 -107.986726) (xy 453.196706 -108.007658) (xy 453.196452 -108.007912) (xy 453.190848 -108.014987)
			(xy 453.184613 -108.031913) (xy 453.18426 -108.040932) (xy 453.18426 -108.107988) (xy 453.18461 -108.117006)
			(xy 453.190861 -108.133923) (xy 453.196452 -108.141008) (xy 453.196706 -108.141008) (xy 453.196706 -108.141262)
			(xy 453.214342 -108.162197) (xy 453.244054 -108.208169) (xy 453.26689 -108.257916) (xy 453.282382 -108.310416)
			(xy 453.290211 -108.364591) (xy 453.290686 -108.39196) (xy 453.2902 -108.419211) (xy 453.282444 -108.473159)
			(xy 453.267089 -108.525454) (xy 453.24697 -108.569506) (xy 455.161142 -108.569506) (xy 455.161601 -108.542135)
			(xy 455.169419 -108.487956) (xy 455.184909 -108.435452) (xy 455.207753 -108.385705) (xy 455.23748 -108.339739)
			(xy 455.255122 -108.318808) (xy 455.255376 -108.318554) (xy 455.260955 -108.311463) (xy 455.267204 -108.294549)
			(xy 455.267568 -108.285534) (xy 455.267568 -108.218478) (xy 455.267229 -108.209459) (xy 455.26097 -108.192542)
			(xy 455.255376 -108.185458) (xy 455.255122 -108.185458) (xy 455.255122 -108.185204) (xy 455.237475 -108.164278)
			(xy 455.207763 -108.118304) (xy 455.184929 -108.068555) (xy 455.16944 -108.016053) (xy 455.161614 -107.961876)
			(xy 455.161142 -107.934506) (xy 455.161628 -107.907255) (xy 455.169384 -107.853307) (xy 455.184739 -107.801012)
			(xy 455.207381 -107.751435) (xy 455.236847 -107.705585) (xy 455.272538 -107.664394) (xy 455.313729 -107.628703)
			(xy 455.359579 -107.599237) (xy 455.409156 -107.576595) (xy 455.461451 -107.56124) (xy 455.515399 -107.553484)
			(xy 455.569901 -107.553484) (xy 455.623849 -107.56124) (xy 455.676144 -107.576595) (xy 455.725721 -107.599237)
			(xy 455.771571 -107.628703) (xy 455.812762 -107.664394) (xy 455.848453 -107.705585) (xy 455.877919 -107.751435)
			(xy 455.900561 -107.801012) (xy 455.915916 -107.853307) (xy 455.923672 -107.907255) (xy 455.924158 -107.934506)
			(xy 455.923706 -107.961877) (xy 455.915886 -108.016057) (xy 455.900394 -108.068561) (xy 455.877549 -108.118307)
			(xy 455.847821 -108.164273) (xy 455.830178 -108.185204) (xy 455.829924 -108.185458) (xy 455.82434 -108.192546)
			(xy 455.818094 -108.209462) (xy 455.817732 -108.218478) (xy 455.817732 -108.285534) (xy 455.818066 -108.294553)
			(xy 455.824329 -108.311471) (xy 455.829924 -108.318554) (xy 455.830178 -108.318554) (xy 455.830178 -108.318808)
			(xy 455.847831 -108.339729) (xy 455.877541 -108.385705) (xy 455.900375 -108.435455) (xy 455.915863 -108.487958)
			(xy 455.923687 -108.542136) (xy 455.924158 -108.569506) (xy 455.923672 -108.596757) (xy 455.915916 -108.650705)
			(xy 455.900561 -108.703) (xy 455.877919 -108.752577) (xy 455.848453 -108.798427) (xy 455.812762 -108.839618)
			(xy 455.771571 -108.875309) (xy 455.725721 -108.904775) (xy 455.676144 -108.927417) (xy 455.623849 -108.942772)
			(xy 455.569901 -108.950528) (xy 455.515399 -108.950528) (xy 455.461451 -108.942772) (xy 455.409156 -108.927417)
			(xy 455.359579 -108.904775) (xy 455.313729 -108.875309) (xy 455.272538 -108.839618) (xy 455.236847 -108.798427)
			(xy 455.207381 -108.752577) (xy 455.184739 -108.703) (xy 455.169384 -108.650705) (xy 455.161628 -108.596757)
			(xy 455.161142 -108.569506) (xy 453.24697 -108.569506) (xy 453.244447 -108.575031) (xy 453.214981 -108.620881)
			(xy 453.17929 -108.662072) (xy 453.138099 -108.697763) (xy 453.092249 -108.727229) (xy 453.042672 -108.749871)
			(xy 452.990377 -108.765226) (xy 452.936429 -108.772982) (xy 452.881927 -108.772982) (xy 452.827979 -108.765226)
			(xy 452.775684 -108.749871) (xy 452.726107 -108.727229) (xy 452.680257 -108.697763) (xy 452.639066 -108.662072)
			(xy 452.603375 -108.620881) (xy 452.573909 -108.575031) (xy 452.551267 -108.525454) (xy 452.535912 -108.473159)
			(xy 452.528156 -108.419211) (xy 452.52767 -108.39196) (xy 439.525687 -108.39196) (xy 439.525432 -108.406257)
			(xy 439.517676 -108.460205) (xy 439.502321 -108.5125) (xy 439.479679 -108.562077) (xy 439.450213 -108.607927)
			(xy 439.414522 -108.649118) (xy 439.373331 -108.684809) (xy 439.327481 -108.714275) (xy 439.277904 -108.736917)
			(xy 439.225609 -108.752272) (xy 439.171661 -108.760028) (xy 439.117159 -108.760028) (xy 439.063211 -108.752272)
			(xy 439.010916 -108.736917) (xy 438.961339 -108.714275) (xy 438.915489 -108.684809) (xy 438.874298 -108.649118)
			(xy 438.838607 -108.607927) (xy 438.809141 -108.562077) (xy 438.786499 -108.5125) (xy 438.771144 -108.460205)
			(xy 438.763388 -108.406257) (xy 438.762902 -108.379006) (xy 413.442844 -108.379006) (xy 413.442919 -108.379256)
			(xy 413.451039 -108.434432) (xy 413.451548 -108.462318) (xy 413.451039 -108.490204) (xy 413.442919 -108.54538)
			(xy 413.426851 -108.598787) (xy 413.403179 -108.649284) (xy 413.372406 -108.695797) (xy 413.335189 -108.737334)
			(xy 413.292321 -108.773009) (xy 413.244715 -108.802063) (xy 413.193386 -108.823875) (xy 413.139429 -108.837981)
			(xy 413.083992 -108.844081) (xy 413.028258 -108.842044) (xy 412.973415 -108.831914) (xy 412.920631 -108.813907)
			(xy 412.871031 -108.788406) (xy 412.825673 -108.755955) (xy 412.785524 -108.717246) (xy 412.751438 -108.673103)
			(xy 412.724142 -108.624468) (xy 412.704219 -108.572377) (xy 412.692093 -108.51794) (xy 412.688022 -108.462318)
			(xy 401.000468 -108.462318) (xy 401.000468 -109.176312) (xy 400.99996 -109.196378) (xy 401.000154 -109.207825)
			(xy 401.009265 -109.228796) (xy 401.017486 -109.236764) (xy 401.042124 -109.2581) (xy 401.051113 -109.265194)
			(xy 401.073204 -109.271142) (xy 401.084542 -109.26953) (xy 401.101349 -109.266663) (xy 401.135311 -109.263614)
			(xy 401.15236 -109.263434) (xy 401.17973 -109.263915) (xy 401.233909 -109.271728) (xy 401.286412 -109.287213)
			(xy 401.336159 -109.310052) (xy 401.382126 -109.339774) (xy 401.403058 -109.357414) (xy 401.403312 -109.357668)
			(xy 401.410385 -109.363274) (xy 401.427312 -109.369507) (xy 401.436332 -109.36986) (xy 401.503388 -109.36986)
			(xy 401.512405 -109.369506) (xy 401.529323 -109.363257) (xy 401.536408 -109.357668) (xy 401.536408 -109.357414)
			(xy 401.536662 -109.357414) (xy 401.557599 -109.339781) (xy 401.60357 -109.310068) (xy 401.653317 -109.287231)
			(xy 401.705816 -109.271738) (xy 401.759991 -109.263909) (xy 401.78736 -109.263434) (xy 401.814338 -109.263867)
			(xy 401.867758 -109.271456) (xy 401.919574 -109.286502) (xy 401.96875 -109.308704) (xy 402.014304 -109.337619)
			(xy 402.055326 -109.372669) (xy 402.090996 -109.413153) (xy 402.1206 -109.458262) (xy 402.143548 -109.507095)
			(xy 402.15938 -109.558676) (xy 402.164042 -109.585252) (xy 402.166198 -109.595484) (xy 402.177485 -109.613061)
			(xy 402.185886 -109.619288) (xy 402.25726 -109.666786) (xy 402.278342 -109.670596) (xy 402.288502 -109.668056)
			(xy 402.315195 -109.661908) (xy 402.369572 -109.655292) (xy 402.39696 -109.654848) (xy 402.424348 -109.655296)
			(xy 402.478724 -109.661914) (xy 402.505418 -109.668056) (xy 402.515578 -109.670596) (xy 402.53666 -109.666786)
			(xy 402.616924 -109.613446) (xy 402.6281 -109.59592) (xy 402.629878 -109.585252) (xy 402.634507 -109.558674)
			(xy 402.650368 -109.507108) (xy 402.673336 -109.458291) (xy 402.702953 -109.413197) (xy 402.738628 -109.372725)
			(xy 402.779649 -109.337684) (xy 402.825199 -109.308773) (xy 402.874367 -109.286567) (xy 402.926174 -109.271511)
			(xy 402.979585 -109.263904) (xy 403.00656 -109.263434) (xy 403.033818 -109.26381) (xy 403.087779 -109.271563)
			(xy 403.140087 -109.286918) (xy 403.189678 -109.30956) (xy 403.235541 -109.339031) (xy 403.276743 -109.374728)
			(xy 403.312445 -109.415927) (xy 403.34192 -109.461787) (xy 403.350862 -109.481366) (xy 412.60979 -109.481366)
			(xy 412.613861 -109.425744) (xy 412.625987 -109.371307) (xy 412.64591 -109.319216) (xy 412.673206 -109.270581)
			(xy 412.707292 -109.226438) (xy 412.747441 -109.187729) (xy 412.792799 -109.155278) (xy 412.842399 -109.129777)
			(xy 412.895183 -109.11177) (xy 412.950026 -109.10164) (xy 413.00576 -109.099603) (xy 413.061197 -109.105703)
			(xy 413.115154 -109.119809) (xy 413.166483 -109.141621) (xy 413.214089 -109.170675) (xy 413.256957 -109.20635)
			(xy 413.294174 -109.247887) (xy 413.324947 -109.2944) (xy 413.348619 -109.344897) (xy 413.364687 -109.398304)
			(xy 413.372807 -109.45348) (xy 413.373316 -109.481366) (xy 413.372807 -109.509252) (xy 413.364687 -109.564428)
			(xy 413.348619 -109.617835) (xy 413.324947 -109.668332) (xy 413.294174 -109.714845) (xy 413.256957 -109.756382)
			(xy 413.214089 -109.792057) (xy 413.166483 -109.821111) (xy 413.115154 -109.842923) (xy 413.061197 -109.857029)
			(xy 413.00576 -109.863129) (xy 412.950026 -109.861092) (xy 412.895183 -109.850962) (xy 412.842399 -109.832955)
			(xy 412.792799 -109.807454) (xy 412.747441 -109.775003) (xy 412.707292 -109.736294) (xy 412.673206 -109.692151)
			(xy 412.64591 -109.643516) (xy 412.625987 -109.591425) (xy 412.613861 -109.536988) (xy 412.60979 -109.481366)
			(xy 403.350862 -109.481366) (xy 403.364568 -109.511375) (xy 403.379928 -109.563682) (xy 403.387687 -109.617642)
			(xy 403.387687 -109.672158) (xy 403.379928 -109.726118) (xy 403.364568 -109.778425) (xy 403.34192 -109.828013)
			(xy 403.312445 -109.873873) (xy 403.276743 -109.915072) (xy 403.235541 -109.950769) (xy 403.189678 -109.98024)
			(xy 403.140087 -110.002882) (xy 403.087779 -110.018237) (xy 403.033818 -110.02599) (xy 403.00656 -110.02645)
			(xy 402.989448 -110.026256) (xy 402.955361 -110.023205) (xy 402.938488 -110.020354) (xy 402.927196 -110.019005)
			(xy 402.905308 -110.025066) (xy 402.896324 -110.032038) (xy 402.87194 -110.05312) (xy 402.863503 -110.061029)
			(xy 402.854245 -110.082196) (xy 402.85416 -110.09376) (xy 402.854668 -110.112556) (xy 402.854668 -110.497366)
			(xy 412.373064 -110.497366) (xy 412.37355 -110.470115) (xy 412.381306 -110.416167) (xy 412.396661 -110.363872)
			(xy 412.419303 -110.314295) (xy 412.448769 -110.268445) (xy 412.48446 -110.227254) (xy 412.525651 -110.191563)
			(xy 412.571501 -110.162097) (xy 412.621078 -110.139455) (xy 412.673373 -110.1241) (xy 412.727321 -110.116344)
			(xy 412.781823 -110.116344) (xy 412.835771 -110.1241) (xy 412.888066 -110.139455) (xy 412.937643 -110.162097)
			(xy 412.983493 -110.191563) (xy 413.024684 -110.227254) (xy 413.060375 -110.268445) (xy 413.089841 -110.314295)
			(xy 413.112483 -110.363872) (xy 413.127838 -110.416167) (xy 413.135594 -110.470115) (xy 413.13608 -110.497366)
			(xy 413.135619 -110.525004) (xy 413.127657 -110.579703) (xy 413.11188 -110.63268) (xy 413.088619 -110.682823)
			(xy 413.058362 -110.729082) (xy 413.021742 -110.770487) (xy 413.000952 -110.788704) (xy 412.990682 -110.798065)
			(xy 412.975161 -110.821101) (xy 412.966423 -110.847467) (xy 412.965116 -110.875213) (xy 412.971336 -110.902284)
			(xy 412.984623 -110.926676) (xy 413.003992 -110.946585) (xy 413.028011 -110.960535) (xy 413.041338 -110.964472)
			(xy 413.068285 -110.971963) (xy 413.119821 -110.993691) (xy 413.167633 -111.022708) (xy 413.210698 -111.058393)
			(xy 413.248092 -111.099982) (xy 413.279015 -111.146584) (xy 413.302805 -111.1972) (xy 413.318952 -111.250747)
			(xy 413.327109 -111.306078) (xy 413.327596 -111.334042) (xy 413.32711 -111.361293) (xy 413.319354 -111.415241)
			(xy 413.303999 -111.467536) (xy 413.281357 -111.517113) (xy 413.251891 -111.562963) (xy 413.2162 -111.604154)
			(xy 413.175009 -111.639845) (xy 413.129159 -111.669311) (xy 413.079582 -111.691953) (xy 413.027287 -111.707308)
			(xy 412.973339 -111.715064) (xy 412.918837 -111.715064) (xy 412.864889 -111.707308) (xy 412.812594 -111.691953)
			(xy 412.763017 -111.669311) (xy 412.717167 -111.639845) (xy 412.675976 -111.604154) (xy 412.640285 -111.562963)
			(xy 412.610819 -111.517113) (xy 412.588177 -111.467536) (xy 412.572822 -111.415241) (xy 412.565066 -111.361293)
			(xy 412.56458 -111.334042) (xy 412.56506 -111.306405) (xy 412.57302 -111.251707) (xy 412.588794 -111.198732)
			(xy 412.612052 -111.148589) (xy 412.642305 -111.102329) (xy 412.67892 -111.060923) (xy 412.699708 -111.042704)
			(xy 412.709946 -111.033314) (xy 412.725455 -111.010283) (xy 412.734185 -110.983925) (xy 412.735491 -110.95619)
			(xy 412.729277 -110.929129) (xy 412.716 -110.904742) (xy 412.696645 -110.884835) (xy 412.672642 -110.870878)
			(xy 412.659322 -110.866936) (xy 412.63237 -110.859463) (xy 412.580835 -110.837732) (xy 412.533024 -110.808711)
			(xy 412.489961 -110.773023) (xy 412.452567 -110.731431) (xy 412.421645 -110.684828) (xy 412.397856 -110.63421)
			(xy 412.381709 -110.580662) (xy 412.373551 -110.525331) (xy 412.373064 -110.497366) (xy 402.854668 -110.497366)
			(xy 402.854668 -110.97641) (xy 402.85416 -110.996476) (xy 402.854355 -111.007922) (xy 402.863465 -111.028894)
			(xy 402.871686 -111.036862) (xy 402.896324 -111.058198) (xy 402.905313 -111.065292) (xy 402.927404 -111.07124)
			(xy 402.938742 -111.069628) (xy 402.955549 -111.066761) (xy 402.989511 -111.063712) (xy 403.00656 -111.063532)
			(xy 403.033818 -111.063912) (xy 403.087779 -111.071665) (xy 403.140087 -111.08702) (xy 403.189677 -111.109662)
			(xy 403.23554 -111.139132) (xy 403.276742 -111.17483) (xy 403.312444 -111.216028) (xy 403.341919 -111.261888)
			(xy 403.364566 -111.311476) (xy 403.379926 -111.363782) (xy 403.387685 -111.417742) (xy 403.387685 -111.472258)
			(xy 403.379926 -111.526218) (xy 403.364566 -111.578524) (xy 403.341919 -111.628112) (xy 403.312444 -111.673972)
			(xy 403.276742 -111.71517) (xy 403.23554 -111.750868) (xy 403.189677 -111.780338) (xy 403.140087 -111.80298)
			(xy 403.087779 -111.818335) (xy 403.033818 -111.826088) (xy 403.00656 -111.826548) (xy 402.979551 -111.82612)
			(xy 402.926073 -111.818509) (xy 402.874203 -111.80343) (xy 402.824979 -111.781185) (xy 402.779385 -111.752218)
			(xy 402.738333 -111.71711) (xy 402.702644 -111.676561) (xy 402.673032 -111.631384) (xy 402.650089 -111.582482)
			(xy 402.634273 -111.530832) (xy 402.629624 -111.504222) (xy 402.6281 -111.493554) (xy 402.61667 -111.475774)
			(xy 402.545296 -111.428276) (xy 402.536358 -111.422945) (xy 402.515902 -111.419259) (xy 402.505672 -111.421164)
			(xy 402.50491 -111.421164) (xy 402.478339 -111.427272) (xy 402.42422 -111.4339) (xy 402.39696 -111.434372)
			(xy 402.369636 -111.433917) (xy 402.315387 -111.427295) (xy 402.288756 -111.421164) (xy 402.288248 -111.421164)
			(xy 402.278018 -111.419311) (xy 402.257572 -111.422982) (xy 402.248624 -111.428276) (xy 402.17725 -111.475774)
			(xy 402.16582 -111.493554) (xy 402.164296 -111.504222) (xy 402.159649 -111.530828) (xy 402.143815 -111.582466)
			(xy 402.12086 -111.631355) (xy 402.091241 -111.67652) (xy 402.05555 -111.717057) (xy 402.0145 -111.752158)
			(xy 401.968912 -111.781121) (xy 401.919696 -111.803367) (xy 401.867835 -111.818453) (xy 401.814365 -111.826076)
			(xy 401.78736 -111.826548) (xy 401.75999 -111.826059) (xy 401.705812 -111.818249) (xy 401.653308 -111.802766)
			(xy 401.603561 -111.779929) (xy 401.557594 -111.750208) (xy 401.536662 -111.732568) (xy 401.536408 -111.732314)
			(xy 401.529322 -111.726726) (xy 401.512405 -111.72048) (xy 401.503388 -111.720122) (xy 401.436332 -111.720122)
			(xy 401.427316 -111.72049) (xy 401.410399 -111.726729) (xy 401.403312 -111.732314) (xy 401.403312 -111.732568)
			(xy 401.403058 -111.732568) (xy 401.382111 -111.750188) (xy 401.336143 -111.779904) (xy 401.286399 -111.802744)
			(xy 401.233902 -111.81824) (xy 401.179728 -111.826072) (xy 401.15236 -111.826548) (xy 401.135248 -111.826354)
			(xy 401.101161 -111.823303) (xy 401.084288 -111.820452) (xy 401.072996 -111.819103) (xy 401.051108 -111.825164)
			(xy 401.042124 -111.832136) (xy 401.01774 -111.853218) (xy 401.009304 -111.861128) (xy 401.000046 -111.882294)
			(xy 400.99996 -111.893858) (xy 401.000468 -111.912654) (xy 401.000468 -112.510824) (xy 412.102552 -112.510824)
			(xy 412.106623 -112.455202) (xy 412.118749 -112.400765) (xy 412.138672 -112.348674) (xy 412.165968 -112.300039)
			(xy 412.200054 -112.255896) (xy 412.240203 -112.217187) (xy 412.285561 -112.184736) (xy 412.335161 -112.159235)
			(xy 412.387945 -112.141228) (xy 412.442788 -112.131098) (xy 412.498522 -112.129061) (xy 412.553959 -112.135161)
			(xy 412.607916 -112.149267) (xy 412.659245 -112.171079) (xy 412.706851 -112.200133) (xy 412.749719 -112.235808)
			(xy 412.786936 -112.277345) (xy 412.817709 -112.323858) (xy 412.841381 -112.374355) (xy 412.857449 -112.427762)
			(xy 412.865569 -112.482938) (xy 412.866078 -112.510824) (xy 412.865569 -112.53871) (xy 412.857449 -112.593886)
			(xy 412.841381 -112.647293) (xy 412.817709 -112.69779) (xy 412.786936 -112.744303) (xy 412.749719 -112.78584)
			(xy 412.706851 -112.821515) (xy 412.659245 -112.850569) (xy 412.607916 -112.872381) (xy 412.553959 -112.886487)
			(xy 412.498522 -112.892587) (xy 412.442788 -112.89055) (xy 412.387945 -112.88042) (xy 412.335161 -112.862413)
			(xy 412.285561 -112.836912) (xy 412.240203 -112.804461) (xy 412.200054 -112.765752) (xy 412.165968 -112.721609)
			(xy 412.138672 -112.672974) (xy 412.118749 -112.620883) (xy 412.106623 -112.566446) (xy 412.102552 -112.510824)
			(xy 401.000468 -112.510824) (xy 401.000468 -112.776508) (xy 400.99996 -112.796574) (xy 401.000156 -112.80802)
			(xy 401.009265 -112.828991) (xy 401.017486 -112.83696) (xy 401.042124 -112.858296) (xy 401.051113 -112.86539)
			(xy 401.073204 -112.871338) (xy 401.084542 -112.869726) (xy 401.101349 -112.866859) (xy 401.135311 -112.86381)
			(xy 401.15236 -112.86363) (xy 401.179617 -112.864014) (xy 401.233578 -112.871767) (xy 401.285886 -112.887121)
			(xy 401.335476 -112.909764) (xy 401.381339 -112.939234) (xy 401.422541 -112.974931) (xy 401.458242 -113.016129)
			(xy 401.487717 -113.061989) (xy 401.510365 -113.111576) (xy 401.525724 -113.163883) (xy 401.533483 -113.217843)
			(xy 401.533483 -113.251742) (xy 412.606234 -113.251742) (xy 412.610305 -113.19612) (xy 412.622431 -113.141683)
			(xy 412.642354 -113.089592) (xy 412.66965 -113.040957) (xy 412.703736 -112.996814) (xy 412.743885 -112.958105)
			(xy 412.789243 -112.925654) (xy 412.838843 -112.900153) (xy 412.891627 -112.882146) (xy 412.94647 -112.872016)
			(xy 413.002204 -112.869979) (xy 413.057641 -112.876079) (xy 413.111598 -112.890185) (xy 413.162927 -112.911997)
			(xy 413.210533 -112.941051) (xy 413.253401 -112.976726) (xy 413.290618 -113.018263) (xy 413.321391 -113.064776)
			(xy 413.345063 -113.115273) (xy 413.361131 -113.16868) (xy 413.369251 -113.223856) (xy 413.36976 -113.251742)
			(xy 413.369251 -113.279628) (xy 413.361131 -113.334804) (xy 413.345063 -113.388211) (xy 413.321391 -113.438708)
			(xy 413.290618 -113.485221) (xy 413.253401 -113.526758) (xy 413.210533 -113.562433) (xy 413.162927 -113.591487)
			(xy 413.111598 -113.613299) (xy 413.057641 -113.627405) (xy 413.002204 -113.633505) (xy 412.94647 -113.631468)
			(xy 412.891627 -113.621338) (xy 412.838843 -113.603331) (xy 412.789243 -113.57783) (xy 412.743885 -113.545379)
			(xy 412.703736 -113.50667) (xy 412.66965 -113.462527) (xy 412.642354 -113.413892) (xy 412.622431 -113.361801)
			(xy 412.610305 -113.307364) (xy 412.606234 -113.251742) (xy 401.533483 -113.251742) (xy 401.533483 -113.272357)
			(xy 401.525724 -113.326317) (xy 401.510365 -113.378624) (xy 401.487717 -113.428211) (xy 401.458242 -113.474071)
			(xy 401.422541 -113.515269) (xy 401.381339 -113.550966) (xy 401.335476 -113.580436) (xy 401.285886 -113.603079)
			(xy 401.233578 -113.618433) (xy 401.179617 -113.626186) (xy 401.15236 -113.626646) (xy 401.125351 -113.62622)
			(xy 401.071873 -113.618609) (xy 401.020003 -113.603529) (xy 400.970779 -113.581284) (xy 400.925185 -113.552317)
			(xy 400.884133 -113.517209) (xy 400.848444 -113.47666) (xy 400.818832 -113.431483) (xy 400.795888 -113.38258)
			(xy 400.780073 -113.33093) (xy 400.775424 -113.30432) (xy 400.7739 -113.293652) (xy 400.76247 -113.275872)
			(xy 400.691096 -113.228374) (xy 400.682158 -113.223043) (xy 400.661702 -113.219357) (xy 400.651472 -113.221262)
			(xy 400.65071 -113.221262) (xy 400.624133 -113.227309) (xy 400.570013 -113.233805) (xy 400.54276 -113.234216)
			(xy 400.515442 -113.233825) (xy 400.461193 -113.227334) (xy 400.434556 -113.221262) (xy 400.434048 -113.221262)
			(xy 400.423818 -113.219409) (xy 400.403372 -113.22308) (xy 400.394424 -113.228374) (xy 400.32305 -113.275872)
			(xy 400.31162 -113.293652) (xy 400.310096 -113.30432) (xy 400.305448 -113.330926) (xy 400.289614 -113.382563)
			(xy 400.266659 -113.431453) (xy 400.23704 -113.476617) (xy 400.201349 -113.517155) (xy 400.1603 -113.552256)
			(xy 400.114712 -113.581219) (xy 400.065496 -113.603465) (xy 400.013635 -113.618551) (xy 399.960165 -113.626174)
			(xy 399.93316 -113.626646) (xy 399.905913 -113.626081) (xy 399.851975 -113.618321) (xy 399.799691 -113.602964)
			(xy 399.750124 -113.580323) (xy 399.704283 -113.550858) (xy 399.663101 -113.51517) (xy 399.627418 -113.473985)
			(xy 399.597958 -113.428141) (xy 399.575322 -113.378572) (xy 399.559971 -113.326285) (xy 399.552216 -113.272347)
			(xy 399.552216 -113.217853) (xy 399.559971 -113.163915) (xy 399.575322 -113.111628) (xy 399.597958 -113.062059)
			(xy 399.627418 -113.016215) (xy 399.663101 -112.97503) (xy 399.704283 -112.939342) (xy 399.750124 -112.909877)
			(xy 399.799691 -112.887236) (xy 399.851975 -112.871879) (xy 399.905913 -112.864119) (xy 399.93316 -112.86363)
			(xy 399.950208 -112.863827) (xy 399.984168 -112.866882) (xy 400.000978 -112.869726) (xy 400.012305 -112.871167)
			(xy 400.034323 -112.865229) (xy 400.043396 -112.858296) (xy 400.068034 -112.83696) (xy 400.076383 -112.829087)
			(xy 400.0855 -112.80805) (xy 400.08556 -112.796574) (xy 400.085052 -112.776508) (xy 400.085052 -111.912654)
			(xy 400.08556 -111.893858) (xy 400.085427 -111.882301) (xy 400.076189 -111.861145) (xy 400.06778 -111.853218)
			(xy 400.043396 -111.832136) (xy 400.034409 -111.825159) (xy 400.012523 -111.819075) (xy 400.001232 -111.820452)
			(xy 399.984361 -111.82332) (xy 399.950272 -111.826374) (xy 399.93316 -111.826548) (xy 399.905914 -111.825979)
			(xy 399.851976 -111.818219) (xy 399.799691 -111.802862) (xy 399.750124 -111.780221) (xy 399.704284 -111.750757)
			(xy 399.663103 -111.715069) (xy 399.627419 -111.673884) (xy 399.59796 -111.62804) (xy 399.575324 -111.578471)
			(xy 399.559973 -111.526185) (xy 399.552218 -111.472247) (xy 399.552218 -111.417753) (xy 399.559973 -111.363815)
			(xy 399.575324 -111.311529) (xy 399.59796 -111.26196) (xy 399.627419 -111.216116) (xy 399.663103 -111.174931)
			(xy 399.704284 -111.139243) (xy 399.750124 -111.109779) (xy 399.799691 -111.087138) (xy 399.851976 -111.071781)
			(xy 399.905914 -111.064021) (xy 399.93316 -111.063532) (xy 399.960138 -111.063967) (xy 400.013558 -111.071556)
			(xy 400.065373 -111.086602) (xy 400.11455 -111.108804) (xy 400.160104 -111.137718) (xy 400.201126 -111.172768)
			(xy 400.236795 -111.213251) (xy 400.2664 -111.25836) (xy 400.289347 -111.307193) (xy 400.30518 -111.358774)
			(xy 400.309842 -111.38535) (xy 400.311999 -111.395582) (xy 400.323285 -111.413159) (xy 400.331686 -111.419386)
			(xy 400.40306 -111.466884) (xy 400.424142 -111.470694) (xy 400.434302 -111.468154) (xy 400.461004 -111.462083)
			(xy 400.515379 -111.455587) (xy 400.54276 -111.4552) (xy 400.570142 -111.455568) (xy 400.624518 -111.462068)
			(xy 400.651218 -111.468154) (xy 400.661378 -111.470694) (xy 400.68246 -111.466884) (xy 400.762724 -111.413544)
			(xy 400.7739 -111.396018) (xy 400.775678 -111.38535) (xy 400.780306 -111.358772) (xy 400.796167 -111.307205)
			(xy 400.819135 -111.258388) (xy 400.848752 -111.213294) (xy 400.884427 -111.172823) (xy 400.925449 -111.137782)
			(xy 400.970998 -111.108871) (xy 401.020167 -111.086665) (xy 401.071974 -111.071609) (xy 401.125385 -111.064002)
			(xy 401.15236 -111.063532) (xy 401.17973 -111.064014) (xy 401.233908 -111.071827) (xy 401.286412 -111.087312)
			(xy 401.336159 -111.11015) (xy 401.382126 -111.139872) (xy 401.403058 -111.157512) (xy 401.403312 -111.157766)
			(xy 401.410385 -111.163372) (xy 401.427313 -111.169605) (xy 401.436332 -111.169958) (xy 401.503388 -111.169958)
			(xy 401.512405 -111.169604) (xy 401.529323 -111.163355) (xy 401.536408 -111.157766) (xy 401.536408 -111.157512)
			(xy 401.536662 -111.157512) (xy 401.557599 -111.139879) (xy 401.60357 -111.110166) (xy 401.653317 -111.087329)
			(xy 401.705816 -111.071836) (xy 401.759991 -111.064007) (xy 401.78736 -111.063532) (xy 401.804408 -111.063729)
			(xy 401.838368 -111.066784) (xy 401.855178 -111.069628) (xy 401.866505 -111.071068) (xy 401.888523 -111.06513)
			(xy 401.897596 -111.058198) (xy 401.922234 -111.036862) (xy 401.930582 -111.028988) (xy 401.9397 -111.007952)
			(xy 401.93976 -110.996476) (xy 401.939252 -110.97641) (xy 401.939252 -110.112556) (xy 401.93976 -110.09376)
			(xy 401.939626 -110.082203) (xy 401.930388 -110.061047) (xy 401.92198 -110.05312) (xy 401.897596 -110.032038)
			(xy 401.888616 -110.025052) (xy 401.866725 -110.018978) (xy 401.855432 -110.020354) (xy 401.838561 -110.023222)
			(xy 401.804472 -110.026276) (xy 401.78736 -110.02645) (xy 401.75999 -110.025961) (xy 401.705812 -110.018151)
			(xy 401.653309 -110.002668) (xy 401.603561 -109.979831) (xy 401.557594 -109.95011) (xy 401.536662 -109.93247)
			(xy 401.536408 -109.932216) (xy 401.529322 -109.926628) (xy 401.512405 -109.920382) (xy 401.503388 -109.920024)
			(xy 401.436332 -109.920024) (xy 401.427316 -109.920391) (xy 401.410399 -109.926631) (xy 401.403312 -109.932216)
			(xy 401.403312 -109.93247) (xy 401.403058 -109.93247) (xy 401.382111 -109.950091) (xy 401.336143 -109.979806)
			(xy 401.286399 -110.002646) (xy 401.233902 -110.018142) (xy 401.179728 -110.025974) (xy 401.15236 -110.02645)
			(xy 401.125351 -110.026021) (xy 401.071873 -110.018409) (xy 401.020004 -110.00333) (xy 400.97078 -109.981085)
			(xy 400.925186 -109.952119) (xy 400.884134 -109.917011) (xy 400.848445 -109.876463) (xy 400.818832 -109.831286)
			(xy 400.795889 -109.782383) (xy 400.780073 -109.730734) (xy 400.775424 -109.704124) (xy 400.7739 -109.693456)
			(xy 400.76247 -109.675676) (xy 400.691096 -109.628178) (xy 400.682158 -109.622847) (xy 400.661702 -109.619161)
			(xy 400.651472 -109.621066) (xy 400.65071 -109.621066) (xy 400.624133 -109.627113) (xy 400.570013 -109.633609)
			(xy 400.54276 -109.63402) (xy 400.515442 -109.633629) (xy 400.461193 -109.627138) (xy 400.434556 -109.621066)
			(xy 400.434048 -109.621066) (xy 400.423818 -109.619212) (xy 400.403372 -109.622883) (xy 400.394424 -109.628178)
			(xy 400.32305 -109.675676) (xy 400.31162 -109.693456) (xy 400.310096 -109.704124) (xy 400.305451 -109.730731)
			(xy 400.289617 -109.782368) (xy 400.266661 -109.831257) (xy 400.237041 -109.876422) (xy 400.20135 -109.916959)
			(xy 400.160301 -109.95206) (xy 400.114712 -109.981023) (xy 400.065496 -110.003269) (xy 400.013635 -110.018355)
			(xy 399.960165 -110.025978) (xy 399.93316 -110.02645) (xy 399.905914 -110.025877) (xy 399.851976 -110.018117)
			(xy 399.799692 -110.00276) (xy 399.750125 -109.980119) (xy 399.704285 -109.950655) (xy 399.663104 -109.914967)
			(xy 399.627421 -109.873783) (xy 399.597962 -109.827939) (xy 399.575326 -109.77837) (xy 399.559975 -109.726085)
			(xy 399.55222 -109.672146) (xy 399.55222 -109.617654) (xy 399.559975 -109.563715) (xy 399.575326 -109.51143)
			(xy 399.597962 -109.461861) (xy 399.627421 -109.416017) (xy 399.663104 -109.374833) (xy 399.704285 -109.339145)
			(xy 399.750125 -109.309681) (xy 399.799692 -109.28704) (xy 399.851976 -109.271683) (xy 399.905914 -109.263923)
			(xy 399.93316 -109.263434) (xy 399.950208 -109.263631) (xy 399.984168 -109.266686) (xy 400.000978 -109.26953)
			(xy 400.012305 -109.27097) (xy 400.034323 -109.265032) (xy 400.043396 -109.2581) (xy 400.068034 -109.236764)
			(xy 400.076381 -109.228889) (xy 400.085499 -109.207854) (xy 400.08556 -109.196378) (xy 400.085052 -109.176312)
			(xy 400.085052 -108.312458) (xy 400.08556 -108.293662) (xy 400.085425 -108.282106) (xy 400.076188 -108.260949)
			(xy 400.06778 -108.253022) (xy 400.043396 -108.23194) (xy 400.034416 -108.224954) (xy 400.012525 -108.21888)
			(xy 400.001232 -108.220256) (xy 399.984361 -108.223124) (xy 399.950272 -108.226178) (xy 399.93316 -108.226352)
			(xy 399.905914 -108.225775) (xy 399.851977 -108.218015) (xy 399.799693 -108.202658) (xy 399.750126 -108.180017)
			(xy 399.704286 -108.150553) (xy 399.663106 -108.114866) (xy 399.627423 -108.073682) (xy 399.597964 -108.027838)
			(xy 399.575328 -107.97827) (xy 399.559977 -107.925984) (xy 399.552222 -107.872046) (xy 399.552222 -107.817554)
			(xy 399.559977 -107.763616) (xy 399.575328 -107.71133) (xy 399.597964 -107.661762) (xy 399.627423 -107.615918)
			(xy 399.663106 -107.574734) (xy 399.704286 -107.539047) (xy 399.750126 -107.509583) (xy 399.799693 -107.486942)
			(xy 399.851977 -107.471585) (xy 399.905914 -107.463825) (xy 399.93316 -107.463336) (xy 399.960138 -107.463768)
			(xy 400.013558 -107.471357) (xy 400.065374 -107.486403) (xy 400.114551 -107.508605) (xy 400.160105 -107.53752)
			(xy 400.201127 -107.57257) (xy 400.236796 -107.613054) (xy 400.2664 -107.658163) (xy 400.289348 -107.706996)
			(xy 400.30518 -107.758578) (xy 400.309842 -107.785154) (xy 400.311997 -107.795386) (xy 400.323285 -107.812963)
			(xy 400.331686 -107.81919) (xy 400.40306 -107.866688) (xy 400.424142 -107.870498) (xy 400.434302 -107.867958)
			(xy 400.461004 -107.861887) (xy 400.515379 -107.855391) (xy 400.54276 -107.855004) (xy 400.570142 -107.855372)
			(xy 400.624518 -107.861872) (xy 400.651218 -107.867958) (xy 400.661378 -107.870498) (xy 400.68246 -107.866688)
			(xy 400.762724 -107.813348) (xy 400.7739 -107.795822) (xy 400.775678 -107.785154) (xy 400.780309 -107.758576)
			(xy 400.796169 -107.70701) (xy 400.819137 -107.658193) (xy 400.848754 -107.613099) (xy 400.884428 -107.572628)
			(xy 400.92545 -107.537587) (xy 400.970999 -107.508675) (xy 401.020167 -107.486469) (xy 401.071974 -107.471413)
			(xy 401.125385 -107.463806) (xy 401.15236 -107.463336) (xy 401.17973 -107.463817) (xy 401.233909 -107.47163)
			(xy 401.286412 -107.487115) (xy 401.336159 -107.509954) (xy 401.382126 -107.539676) (xy 401.403058 -107.557316)
			(xy 401.403312 -107.55757) (xy 401.410385 -107.563176) (xy 401.427312 -107.569409) (xy 401.436332 -107.569762)
			(xy 401.503388 -107.569762) (xy 401.512405 -107.569407) (xy 401.529323 -107.563159) (xy 401.536408 -107.55757)
			(xy 401.536408 -107.557316) (xy 401.536662 -107.557316) (xy 401.5576 -107.539684) (xy 401.603571 -107.50997)
			(xy 401.653317 -107.487133) (xy 401.705816 -107.47164) (xy 401.759991 -107.463811) (xy 401.78736 -107.463336)
			(xy 401.804408 -107.463533) (xy 401.838368 -107.466588) (xy 401.855178 -107.469432) (xy 401.866505 -107.470871)
			(xy 401.888523 -107.464934) (xy 401.897596 -107.458002) (xy 401.922234 -107.436666) (xy 401.93058 -107.42879)
			(xy 401.939699 -107.407756) (xy 401.93976 -107.39628) (xy 401.939252 -107.376214) (xy 401.939252 -106.51236)
			(xy 401.93976 -106.493564) (xy 401.939623 -106.482008) (xy 401.930388 -106.460851) (xy 401.92198 -106.452924)
			(xy 401.897596 -106.431842) (xy 401.888616 -106.424856) (xy 401.866725 -106.418782) (xy 401.855432 -106.420158)
			(xy 401.838561 -106.423026) (xy 401.804472 -106.42608) (xy 401.78736 -106.426254) (xy 401.759991 -106.425764)
			(xy 401.705812 -106.417954) (xy 401.653309 -106.402471) (xy 401.603561 -106.379634) (xy 401.557594 -106.349914)
			(xy 401.536662 -106.332274) (xy 401.529804 -106.326178) (xy 401.512786 -106.319828) (xy 401.427442 -106.319828)
			(xy 401.41017 -106.326432) (xy 401.403312 -106.332528) (xy 401.382389 -106.35018) (xy 401.336418 -106.379899)
			(xy 401.286669 -106.402737) (xy 401.234164 -106.418224) (xy 401.179985 -106.426042) (xy 401.152614 -106.426508)
			(xy 401.15236 -106.426508) (xy 401.125354 -106.42603) (xy 401.07188 -106.41842) (xy 401.020014 -106.403344)
			(xy 400.970793 -106.381103) (xy 400.925201 -106.352142) (xy 400.88415 -106.317039) (xy 400.84846 -106.276498)
			(xy 400.818846 -106.231328) (xy 400.795898 -106.182432) (xy 400.780077 -106.130789) (xy 400.775424 -106.104182)
			(xy 400.7739 -106.093514) (xy 400.76247 -106.075734) (xy 400.691096 -106.028236) (xy 400.682159 -106.022903)
			(xy 400.661702 -106.019219) (xy 400.651472 -106.021124) (xy 400.65071 -106.021124) (xy 400.624139 -106.027233)
			(xy 400.57002 -106.03386) (xy 400.54276 -106.034332) (xy 400.515436 -106.033878) (xy 400.461187 -106.027256)
			(xy 400.434556 -106.021124) (xy 400.434048 -106.021124) (xy 400.423818 -106.019261) (xy 400.403371 -106.022937)
			(xy 400.394424 -106.028236) (xy 400.32305 -106.075734) (xy 400.31162 -106.093514) (xy 400.310096 -106.104182)
			(xy 400.305419 -106.130783) (xy 400.28959 -106.18242) (xy 400.266639 -106.23131) (xy 400.237024 -106.276475)
			(xy 400.201337 -106.317014) (xy 400.160291 -106.352115) (xy 400.114705 -106.381079) (xy 400.065491 -106.403326)
			(xy 400.013632 -106.418412) (xy 399.960164 -106.426036) (xy 399.93316 -106.426508) (xy 399.905911 -106.426019)
			(xy 399.851967 -106.418258) (xy 399.799677 -106.4029) (xy 399.750105 -106.380256) (xy 399.70426 -106.350789)
			(xy 399.663074 -106.315097) (xy 399.627387 -106.273908) (xy 399.597924 -106.22806) (xy 399.575286 -106.178485)
			(xy 399.559933 -106.126194) (xy 399.552178 -106.072249) (xy 399.552178 -106.017751) (xy 399.559933 -105.963806)
			(xy 399.575286 -105.911515) (xy 399.597924 -105.86194) (xy 399.627387 -105.816092) (xy 399.663074 -105.774903)
			(xy 399.70426 -105.739211) (xy 399.750105 -105.709744) (xy 399.799677 -105.6871) (xy 399.851967 -105.671742)
			(xy 399.905911 -105.663981) (xy 399.93316 -105.663492) (xy 399.950208 -105.663688) (xy 399.984168 -105.666743)
			(xy 400.000978 -105.669588) (xy 400.012305 -105.671014) (xy 400.034321 -105.665084) (xy 400.043396 -105.658158)
			(xy 400.068034 -105.636822) (xy 400.076353 -105.628923) (xy 400.085487 -105.607906) (xy 400.08556 -105.596436)
			(xy 400.085052 -105.57637) (xy 400.085052 -104.712516) (xy 400.08556 -104.69372) (xy 400.085449 -104.682161)
			(xy 400.076195 -104.661004) (xy 400.06778 -104.65308) (xy 400.043396 -104.631998) (xy 400.034412 -104.625018)
			(xy 400.012524 -104.618938) (xy 400.001232 -104.620314) (xy 399.984361 -104.623181) (xy 399.950272 -104.626236)
			(xy 399.93316 -104.62641) (xy 399.905911 -104.625917) (xy 399.851968 -104.618156) (xy 399.799678 -104.602798)
			(xy 399.750106 -104.580155) (xy 399.704261 -104.550687) (xy 399.663076 -104.514996) (xy 399.627389 -104.473807)
			(xy 399.597926 -104.427959) (xy 399.575288 -104.378385) (xy 399.559935 -104.326093) (xy 399.55218 -104.272149)
			(xy 399.55218 -104.217651) (xy 399.559935 -104.163707) (xy 399.575288 -104.111415) (xy 399.597926 -104.061841)
			(xy 399.627389 -104.015993) (xy 399.663076 -103.974804) (xy 399.704261 -103.939113) (xy 399.750106 -103.909645)
			(xy 399.799678 -103.887002) (xy 399.851968 -103.871644) (xy 399.905911 -103.863883) (xy 399.93316 -103.863394)
			(xy 399.960137 -103.863861) (xy 400.013553 -103.871449) (xy 400.065367 -103.886493) (xy 400.114541 -103.908692)
			(xy 400.160094 -103.937603) (xy 400.201115 -103.972649) (xy 400.236785 -104.013128) (xy 400.266391 -104.058233)
			(xy 400.289341 -104.107061) (xy 400.305177 -104.158638) (xy 400.309842 -104.185212) (xy 400.312017 -104.195439)
			(xy 400.32329 -104.213018) (xy 400.331686 -104.219248) (xy 400.40306 -104.266746) (xy 400.424142 -104.270556)
			(xy 400.434302 -104.268016) (xy 400.460995 -104.261868) (xy 400.515372 -104.255251) (xy 400.54276 -104.254808)
			(xy 400.570148 -104.255257) (xy 400.624524 -104.261875) (xy 400.651218 -104.268016) (xy 400.661378 -104.270556)
			(xy 400.68246 -104.266746) (xy 400.762724 -104.213406) (xy 400.7739 -104.19588) (xy 400.775678 -104.185212)
			(xy 400.780353 -104.158642) (xy 400.796206 -104.107076) (xy 400.819166 -104.058259) (xy 400.848777 -104.013164)
			(xy 400.884447 -103.972691) (xy 400.925463 -103.937649) (xy 400.971009 -103.908735) (xy 401.020174 -103.886528)
			(xy 401.071978 -103.871471) (xy 401.125386 -103.863864) (xy 401.15236 -103.863394) (xy 401.179729 -103.863885)
			(xy 401.233907 -103.871697) (xy 401.28641 -103.88718) (xy 401.336157 -103.910016) (xy 401.382125 -103.939735)
			(xy 401.403058 -103.957374) (xy 401.403312 -103.957628) (xy 401.410389 -103.963229) (xy 401.427313 -103.969466)
			(xy 401.436332 -103.96982) (xy 401.503388 -103.96982) (xy 401.512404 -103.969453) (xy 401.529321 -103.963212)
			(xy 401.536408 -103.957628) (xy 401.536408 -103.957374) (xy 401.536662 -103.957374) (xy 401.557594 -103.939735)
			(xy 401.603567 -103.910024) (xy 401.653315 -103.887189) (xy 401.705815 -103.871697) (xy 401.759991 -103.863869)
			(xy 401.78736 -103.863394) (xy 401.804408 -103.86359) (xy 401.838368 -103.866645) (xy 401.855178 -103.86949)
			(xy 401.866505 -103.870916) (xy 401.888521 -103.864986) (xy 401.897596 -103.85806) (xy 401.922234 -103.836724)
			(xy 401.930552 -103.828824) (xy 401.939687 -103.807808) (xy 401.93976 -103.796338) (xy 401.939252 -103.776272)
			(xy 401.939252 -102.912418) (xy 401.93976 -102.893622) (xy 401.939648 -102.882063) (xy 401.930395 -102.860906)
			(xy 401.92198 -102.852982) (xy 401.897596 -102.8319) (xy 401.888612 -102.82492) (xy 401.866724 -102.81884)
			(xy 401.855432 -102.820216) (xy 401.838561 -102.823083) (xy 401.804472 -102.826138) (xy 401.78736 -102.826312)
			(xy 401.759991 -102.825808) (xy 401.705814 -102.817999) (xy 401.653311 -102.802518) (xy 401.603564 -102.779685)
			(xy 401.557595 -102.749969) (xy 401.536662 -102.732332) (xy 401.529804 -102.726236) (xy 401.512786 -102.719886)
			(xy 401.427442 -102.719886) (xy 401.41017 -102.72649) (xy 401.403312 -102.732586) (xy 401.382397 -102.750247)
			(xy 401.336423 -102.779962) (xy 401.286671 -102.802798) (xy 401.234166 -102.818283) (xy 401.179985 -102.8261)
			(xy 401.152614 -102.826566) (xy 401.15236 -102.826566) (xy 401.125352 -102.826123) (xy 401.071875 -102.818512)
			(xy 401.020006 -102.803434) (xy 400.970783 -102.78119) (xy 400.92519 -102.752225) (xy 400.884138 -102.717119)
			(xy 400.848449 -102.676572) (xy 400.818836 -102.631397) (xy 400.795892 -102.582497) (xy 400.780074 -102.530849)
			(xy 400.775424 -102.50424) (xy 400.7739 -102.493572) (xy 400.76247 -102.475792) (xy 400.691096 -102.428294)
			(xy 400.682157 -102.422964) (xy 400.661701 -102.419277) (xy 400.651472 -102.421182) (xy 400.65071 -102.421182)
			(xy 400.624133 -102.427229) (xy 400.570013 -102.433725) (xy 400.54276 -102.434136) (xy 400.515442 -102.433745)
			(xy 400.461194 -102.427253) (xy 400.434556 -102.421182) (xy 400.434048 -102.421182) (xy 400.423818 -102.419326)
			(xy 400.403372 -102.422998) (xy 400.394424 -102.428294) (xy 400.32305 -102.475792) (xy 400.31162 -102.493572)
			(xy 400.310096 -102.50424) (xy 400.305387 -102.530835) (xy 400.289564 -102.582472) (xy 400.266618 -102.631362)
			(xy 400.237007 -102.676528) (xy 400.201324 -102.717068) (xy 400.160281 -102.752171) (xy 400.114698 -102.781135)
			(xy 400.065487 -102.803383) (xy 400.01363 -102.81847) (xy 399.960163 -102.826094) (xy 399.93316 -102.826566)
			(xy 399.905908 -102.826161) (xy 399.851958 -102.818399) (xy 399.799663 -102.803039) (xy 399.750085 -102.780393)
			(xy 399.704235 -102.750923) (xy 399.663045 -102.715227) (xy 399.627353 -102.674033) (xy 399.597888 -102.62818)
			(xy 399.575247 -102.5786) (xy 399.559892 -102.526303) (xy 399.552136 -102.472352) (xy 395.729596 -102.472352)
			(xy 395.781178 -102.485837) (xy 395.832507 -102.507649) (xy 395.880113 -102.536703) (xy 395.922981 -102.572378)
			(xy 395.960198 -102.613915) (xy 395.990971 -102.660428) (xy 396.014643 -102.710925) (xy 396.030711 -102.764332)
			(xy 396.038831 -102.819508) (xy 396.03934 -102.847394) (xy 396.038831 -102.87528) (xy 396.030711 -102.930456)
			(xy 396.014643 -102.983863) (xy 395.990971 -103.03436) (xy 395.960198 -103.080873) (xy 395.922981 -103.12241)
			(xy 395.880113 -103.158085) (xy 395.832507 -103.187139) (xy 395.781178 -103.208951) (xy 395.727221 -103.223057)
			(xy 395.671784 -103.229157) (xy 395.61605 -103.22712) (xy 395.561207 -103.21699) (xy 395.508423 -103.198983)
			(xy 395.458823 -103.173482) (xy 395.413465 -103.141031) (xy 395.373316 -103.102322) (xy 395.33923 -103.058179)
			(xy 395.311934 -103.009544) (xy 395.292011 -102.957453) (xy 395.279885 -102.903016) (xy 395.275814 -102.847394)
			(xy 387.06051 -102.847394) (xy 387.059716 -102.850098) (xy 387.037074 -102.899676) (xy 387.007606 -102.945528)
			(xy 386.971913 -102.986719) (xy 386.930721 -103.022411) (xy 386.884869 -103.051878) (xy 386.83529 -103.074519)
			(xy 386.782994 -103.089874) (xy 386.729044 -103.097629) (xy 386.701792 -103.098092) (xy 386.686999 -103.097959)
			(xy 386.657501 -103.095669) (xy 386.642864 -103.09352) (xy 386.63189 -103.092376) (xy 386.610696 -103.098449)
			(xy 386.60197 -103.105204) (xy 386.543296 -103.155242) (xy 386.5353 -103.162839) (xy 386.526067 -103.182837)
			(xy 386.525516 -103.19385) (xy 386.525516 -103.498142) (xy 386.526026 -103.509164) (xy 386.535264 -103.529181)
			(xy 386.543296 -103.53675) (xy 386.60197 -103.586788) (xy 386.610683 -103.593572) (xy 386.631885 -103.599642)
			(xy 386.642864 -103.598472) (xy 386.657502 -103.596329) (xy 386.686999 -103.594042) (xy 386.701792 -103.5939)
			(xy 386.729046 -103.594347) (xy 386.782999 -103.602103) (xy 386.835299 -103.617459) (xy 386.884881 -103.640101)
			(xy 386.930736 -103.66957) (xy 386.97193 -103.705264) (xy 387.007626 -103.746458) (xy 387.037095 -103.792312)
			(xy 387.059739 -103.841894) (xy 387.075095 -103.894193) (xy 387.082853 -103.948146) (xy 387.082853 -104.002654)
			(xy 387.075095 -104.056607) (xy 387.059739 -104.108906) (xy 387.037095 -104.158488) (xy 387.007626 -104.204342)
			(xy 386.972479 -104.244902) (xy 392.969748 -104.244902) (xy 392.973819 -104.18928) (xy 392.985945 -104.134843)
			(xy 393.005868 -104.082752) (xy 393.033164 -104.034117) (xy 393.06725 -103.989974) (xy 393.107399 -103.951265)
			(xy 393.152757 -103.918814) (xy 393.202357 -103.893313) (xy 393.255141 -103.875306) (xy 393.309984 -103.865176)
			(xy 393.365718 -103.863139) (xy 393.421155 -103.869239) (xy 393.475112 -103.883345) (xy 393.526441 -103.905157)
			(xy 393.574047 -103.934211) (xy 393.616915 -103.969886) (xy 393.654132 -104.011423) (xy 393.684905 -104.057936)
			(xy 393.708577 -104.108433) (xy 393.724645 -104.16184) (xy 393.732765 -104.217016) (xy 393.733274 -104.244902)
			(xy 393.732765 -104.272788) (xy 393.724645 -104.327964) (xy 393.708577 -104.381371) (xy 393.684905 -104.431868)
			(xy 393.654132 -104.478381) (xy 393.616915 -104.519918) (xy 393.574047 -104.555593) (xy 393.526441 -104.584647)
			(xy 393.475112 -104.606459) (xy 393.421155 -104.620565) (xy 393.365718 -104.626665) (xy 393.309984 -104.624628)
			(xy 393.255141 -104.614498) (xy 393.202357 -104.596491) (xy 393.152757 -104.57099) (xy 393.107399 -104.538539)
			(xy 393.06725 -104.49983) (xy 393.033164 -104.455687) (xy 393.005868 -104.407052) (xy 392.985945 -104.354961)
			(xy 392.973819 -104.300524) (xy 392.969748 -104.244902) (xy 386.972479 -104.244902) (xy 386.97193 -104.245536)
			(xy 386.930736 -104.28123) (xy 386.884881 -104.310699) (xy 386.835299 -104.333341) (xy 386.782999 -104.348697)
			(xy 386.729046 -104.356453) (xy 386.701792 -104.356916) (xy 386.675885 -104.356426) (xy 386.62455 -104.349402)
			(xy 386.574638 -104.335498) (xy 386.527065 -104.314969) (xy 386.482706 -104.288193) (xy 386.442378 -104.255662)
			(xy 386.406822 -104.217974) (xy 386.391404 -104.19715) (xy 386.385665 -104.189818) (xy 386.370162 -104.179532)
			(xy 386.361178 -104.177084) (xy 386.330698 -104.170226) (xy 386.321419 -104.168496) (xy 386.302758 -104.171223)
			(xy 386.294376 -104.17556) (xy 386.268389 -104.189815) (xy 386.213524 -104.212247) (xy 386.156223 -104.227414)
			(xy 386.097445 -104.235061) (xy 386.038171 -104.235061) (xy 385.979393 -104.227414) (xy 385.922092 -104.212247)
			(xy 385.867227 -104.189815) (xy 385.84124 -104.17556) (xy 385.832822 -104.171324) (xy 385.814196 -104.168583)
			(xy 385.804918 -104.170226) (xy 385.774438 -104.177084) (xy 385.765446 -104.179514) (xy 385.749941 -104.189806)
			(xy 385.744212 -104.19715) (xy 385.728827 -104.218004) (xy 385.69328 -104.255714) (xy 385.652953 -104.288262)
			(xy 385.60859 -104.315048) (xy 385.561007 -104.33558) (xy 385.511083 -104.349478) (xy 385.459736 -104.356486)
			(xy 385.433824 -104.356916) (xy 385.406571 -104.356438) (xy 385.352618 -104.348684) (xy 385.300319 -104.333331)
			(xy 385.250736 -104.31069) (xy 385.204881 -104.281223) (xy 385.163687 -104.24553) (xy 385.127991 -104.204338)
			(xy 385.098522 -104.158485) (xy 385.075878 -104.108904) (xy 385.060521 -104.056605) (xy 385.052763 -104.002653)
			(xy 385.052763 -103.948147) (xy 385.060521 -103.894195) (xy 385.075878 -103.841896) (xy 385.098522 -103.792315)
			(xy 385.127991 -103.746462) (xy 385.163687 -103.70527) (xy 385.204881 -103.669577) (xy 385.250736 -103.64011)
			(xy 385.300319 -103.617469) (xy 385.352618 -103.602116) (xy 385.406571 -103.594362) (xy 385.433824 -103.5939)
			(xy 385.448617 -103.594031) (xy 385.478115 -103.596323) (xy 385.492752 -103.598472) (xy 385.503728 -103.599568)
			(xy 385.524917 -103.593529) (xy 385.533646 -103.586788) (xy 385.59232 -103.53675) (xy 385.600322 -103.529159)
			(xy 385.609551 -103.509156) (xy 385.6101 -103.498142) (xy 385.6101 -103.19385) (xy 385.609534 -103.182835)
			(xy 385.600334 -103.162818) (xy 385.59232 -103.155242) (xy 385.533646 -103.105204) (xy 385.524963 -103.098375)
			(xy 385.503737 -103.092332) (xy 385.492752 -103.09352) (xy 385.478114 -103.095661) (xy 385.448617 -103.097949)
			(xy 385.433824 -103.098092) (xy 385.406569 -103.097663) (xy 385.352613 -103.089908) (xy 385.30031 -103.074554)
			(xy 385.250725 -103.051912) (xy 385.204867 -103.022443) (xy 385.163669 -102.986748) (xy 385.127972 -102.945553)
			(xy 385.0985 -102.899696) (xy 385.075855 -102.850112) (xy 385.060497 -102.79781) (xy 385.052739 -102.743855)
			(xy 370.637195 -102.743855) (xy 370.630086 -102.750739) (xy 370.621273 -102.770349) (xy 370.620798 -102.7811)
			(xy 370.620798 -102.868984) (xy 370.629942 -102.888796) (xy 370.63807 -102.895908) (xy 370.658113 -102.91408)
			(xy 370.693309 -102.955171) (xy 370.722348 -103.00082) (xy 370.74465 -103.050112) (xy 370.759768 -103.10206)
			(xy 370.767398 -103.155622) (xy 370.767864 -103.182674) (xy 370.767378 -103.209925) (xy 370.759622 -103.263873)
			(xy 370.744267 -103.316168) (xy 370.721625 -103.365745) (xy 370.692159 -103.411595) (xy 370.656468 -103.452786)
			(xy 370.615277 -103.488477) (xy 370.569427 -103.517943) (xy 370.51985 -103.540585) (xy 370.467555 -103.55594)
			(xy 370.413607 -103.563696) (xy 370.359105 -103.563696) (xy 370.305157 -103.55594) (xy 370.252862 -103.540585)
			(xy 370.203285 -103.517943) (xy 370.157435 -103.488477) (xy 370.116244 -103.452786) (xy 370.080553 -103.411595)
			(xy 370.051087 -103.365745) (xy 370.028445 -103.316168) (xy 370.01309 -103.263873) (xy 370.005334 -103.209925)
			(xy 370.004848 -103.182674) (xy 370.00561 -103.158544) (xy 370.006626 -103.142796) (xy 369.99037 -103.115618)
			(xy 369.889278 -103.069898) (xy 369.879707 -103.066034) (xy 369.85909 -103.065581) (xy 369.839976 -103.07332)
			(xy 369.832382 -103.080312) (xy 369.73002 -103.182674) (xy 369.706443 -103.205559) (xy 369.655069 -103.246524)
			(xy 369.599431 -103.28148) (xy 369.540229 -103.309987) (xy 369.478208 -103.331687) (xy 369.414148 -103.346307)
			(xy 369.348854 -103.353664) (xy 369.316 -103.354124) (xy 364.08106 -103.354124) (xy 364.070988 -103.354522)
			(xy 364.05239 -103.362261) (xy 364.044992 -103.36911) (xy 363.563438 -103.850694) (xy 372.568468 -103.850694)
			(xy 372.572539 -103.795072) (xy 372.584665 -103.740635) (xy 372.604588 -103.688544) (xy 372.631884 -103.639909)
			(xy 372.66597 -103.595766) (xy 372.706119 -103.557057) (xy 372.751477 -103.524606) (xy 372.801077 -103.499105)
			(xy 372.853861 -103.481098) (xy 372.908704 -103.470968) (xy 372.964438 -103.468931) (xy 373.019875 -103.475031)
			(xy 373.073832 -103.489137) (xy 373.125161 -103.510949) (xy 373.172767 -103.540003) (xy 373.215635 -103.575678)
			(xy 373.252852 -103.617215) (xy 373.283625 -103.663728) (xy 373.307297 -103.714225) (xy 373.323365 -103.767632)
			(xy 373.331485 -103.822808) (xy 373.331994 -103.850694) (xy 373.331485 -103.87858) (xy 373.323365 -103.933756)
			(xy 373.307297 -103.987163) (xy 373.283625 -104.03766) (xy 373.252852 -104.084173) (xy 373.215635 -104.12571)
			(xy 373.172767 -104.161385) (xy 373.125161 -104.190439) (xy 373.073832 -104.212251) (xy 373.019875 -104.226357)
			(xy 372.964438 -104.232457) (xy 372.908704 -104.23042) (xy 372.853861 -104.22029) (xy 372.801077 -104.202283)
			(xy 372.751477 -104.176782) (xy 372.706119 -104.144331) (xy 372.66597 -104.105622) (xy 372.631884 -104.061479)
			(xy 372.604588 -104.012844) (xy 372.584665 -103.960753) (xy 372.572539 -103.906316) (xy 372.568468 -103.850694)
			(xy 363.563438 -103.850694) (xy 363.090266 -104.323896) (xy 373.852948 -104.323896) (xy 373.853474 -104.296647)
			(xy 373.86123 -104.242703) (xy 373.876583 -104.190411) (xy 373.899222 -104.140837) (xy 373.928684 -104.094989)
			(xy 373.964371 -104.0538) (xy 374.005557 -104.018108) (xy 374.051402 -103.988641) (xy 374.100974 -103.965997)
			(xy 374.153264 -103.950638) (xy 374.207207 -103.942877) (xy 374.234456 -103.942388) (xy 374.262991 -103.94288)
			(xy 374.319426 -103.951361) (xy 374.373968 -103.968156) (xy 374.425399 -103.99289) (xy 374.472571 -104.025009)
			(xy 374.514431 -104.063799) (xy 374.550045 -104.108392) (xy 374.578617 -104.157793) (xy 374.59951 -104.2109)
			(xy 374.612258 -104.266528) (xy 374.614948 -104.29494) (xy 374.616632 -104.309932) (xy 374.627573 -104.33803)
			(xy 374.646237 -104.361712) (xy 374.670999 -104.378918) (xy 374.699704 -104.388149) (xy 374.71477 -104.38892)
			(xy 374.741797 -104.389694) (xy 374.795223 -104.39801) (xy 374.846939 -104.413785) (xy 374.895911 -104.436703)
			(xy 374.941157 -104.466304) (xy 374.981771 -104.501997) (xy 375.01694 -104.543066) (xy 375.021703 -104.550555)
			(xy 382.410641 -104.550555) (xy 382.410641 -104.496045) (xy 382.418399 -104.442091) (xy 382.433756 -104.38979)
			(xy 382.456401 -104.340207) (xy 382.485871 -104.294351) (xy 382.521568 -104.253157) (xy 382.562764 -104.217462)
			(xy 382.608621 -104.187993) (xy 382.658205 -104.16535) (xy 382.710507 -104.149995) (xy 382.764461 -104.14224)
			(xy 382.791716 -104.141778) (xy 382.817623 -104.142264) (xy 382.868958 -104.149289) (xy 382.918871 -104.163194)
			(xy 382.966443 -104.183724) (xy 383.010802 -104.210501) (xy 383.05113 -104.243032) (xy 383.086686 -104.28072)
			(xy 383.102104 -104.301544) (xy 383.107841 -104.308878) (xy 383.123346 -104.319163) (xy 383.13233 -104.32161)
			(xy 383.16281 -104.328468) (xy 383.172088 -104.330203) (xy 383.19075 -104.327473) (xy 383.199132 -104.323134)
			(xy 383.225105 -104.308833) (xy 383.279958 -104.286323) (xy 383.337262 -104.271098) (xy 383.396054 -104.263414)
			(xy 383.4257 -104.262936) (xy 383.455343 -104.263428) (xy 383.514125 -104.271152) (xy 383.571423 -104.28638)
			(xy 383.626283 -104.30886) (xy 383.652268 -104.323134) (xy 383.660684 -104.327373) (xy 383.679311 -104.330112)
			(xy 383.68859 -104.328468) (xy 383.71907 -104.32161) (xy 383.728063 -104.319185) (xy 383.743568 -104.308889)
			(xy 383.749296 -104.301544) (xy 383.764674 -104.280685) (xy 383.800222 -104.242976) (xy 383.840551 -104.210428)
			(xy 383.884915 -104.183642) (xy 383.932499 -104.163112) (xy 383.982424 -104.149215) (xy 384.033772 -104.142207)
			(xy 384.059684 -104.141778) (xy 384.086937 -104.142268) (xy 384.140887 -104.150023) (xy 384.193185 -104.165377)
			(xy 384.242765 -104.188018) (xy 384.288619 -104.217484) (xy 384.329812 -104.253177) (xy 384.365506 -104.294368)
			(xy 384.394974 -104.34022) (xy 384.417617 -104.3898) (xy 384.432974 -104.442097) (xy 384.440731 -104.496047)
			(xy 384.440731 -104.550553) (xy 384.432974 -104.604503) (xy 384.417617 -104.6568) (xy 384.394974 -104.70638)
			(xy 384.365506 -104.752232) (xy 384.330149 -104.793034) (xy 395.01013 -104.793034) (xy 395.014201 -104.737412)
			(xy 395.026327 -104.682975) (xy 395.04625 -104.630884) (xy 395.073546 -104.582249) (xy 395.107632 -104.538106)
			(xy 395.147781 -104.499397) (xy 395.193139 -104.466946) (xy 395.242739 -104.441445) (xy 395.295523 -104.423438)
			(xy 395.350366 -104.413308) (xy 395.4061 -104.411271) (xy 395.461537 -104.417371) (xy 395.515494 -104.431477)
			(xy 395.566823 -104.453289) (xy 395.614429 -104.482343) (xy 395.657297 -104.518018) (xy 395.694514 -104.559555)
			(xy 395.725287 -104.606068) (xy 395.748959 -104.656565) (xy 395.765027 -104.709972) (xy 395.773147 -104.765148)
			(xy 395.773656 -104.793034) (xy 395.773147 -104.82092) (xy 395.765027 -104.876096) (xy 395.748959 -104.929503)
			(xy 395.725287 -104.98) (xy 395.694514 -105.026513) (xy 395.657297 -105.06805) (xy 395.614429 -105.103725)
			(xy 395.566823 -105.132779) (xy 395.515494 -105.154591) (xy 395.461537 -105.168697) (xy 395.4061 -105.174797)
			(xy 395.350366 -105.17276) (xy 395.295523 -105.16263) (xy 395.242739 -105.144623) (xy 395.193139 -105.119122)
			(xy 395.147781 -105.086671) (xy 395.107632 -105.047962) (xy 395.073546 -105.003819) (xy 395.04625 -104.955184)
			(xy 395.026327 -104.903093) (xy 395.014201 -104.848656) (xy 395.01013 -104.793034) (xy 384.330149 -104.793034)
			(xy 384.329812 -104.793423) (xy 384.288619 -104.829116) (xy 384.242765 -104.858582) (xy 384.193185 -104.881223)
			(xy 384.140887 -104.896577) (xy 384.086937 -104.904332) (xy 384.059684 -104.904794) (xy 384.044891 -104.904662)
			(xy 384.015393 -104.902371) (xy 384.000756 -104.900222) (xy 383.989782 -104.899073) (xy 383.968588 -104.905149)
			(xy 383.959862 -104.911906) (xy 383.901188 -104.961944) (xy 383.89319 -104.969539) (xy 383.883958 -104.989539)
			(xy 383.883408 -105.000552) (xy 383.883408 -105.304844) (xy 383.883975 -105.315859) (xy 383.893174 -105.335876)
			(xy 383.901188 -105.343452) (xy 383.926504 -105.365042) (xy 397.522952 -105.365042) (xy 397.527023 -105.30942)
			(xy 397.539149 -105.254983) (xy 397.559072 -105.202892) (xy 397.586368 -105.154257) (xy 397.620454 -105.110114)
			(xy 397.660603 -105.071405) (xy 397.705961 -105.038954) (xy 397.755561 -105.013453) (xy 397.808345 -104.995446)
			(xy 397.863188 -104.985316) (xy 397.918922 -104.983279) (xy 397.974359 -104.989379) (xy 398.028316 -105.003485)
			(xy 398.079645 -105.025297) (xy 398.127251 -105.054351) (xy 398.170119 -105.090026) (xy 398.207336 -105.131563)
			(xy 398.238109 -105.178076) (xy 398.261781 -105.228573) (xy 398.277849 -105.28198) (xy 398.285969 -105.337156)
			(xy 398.286478 -105.365042) (xy 398.285969 -105.392928) (xy 398.277849 -105.448104) (xy 398.261781 -105.501511)
			(xy 398.238109 -105.552008) (xy 398.207336 -105.598521) (xy 398.170119 -105.640058) (xy 398.127251 -105.675733)
			(xy 398.079645 -105.704787) (xy 398.028316 -105.726599) (xy 397.974359 -105.740705) (xy 397.918922 -105.746805)
			(xy 397.863188 -105.744768) (xy 397.808345 -105.734638) (xy 397.755561 -105.716631) (xy 397.705961 -105.69113)
			(xy 397.660603 -105.658679) (xy 397.620454 -105.61997) (xy 397.586368 -105.575827) (xy 397.559072 -105.527192)
			(xy 397.539149 -105.475101) (xy 397.527023 -105.420664) (xy 397.522952 -105.365042) (xy 383.926504 -105.365042)
			(xy 383.959862 -105.39349) (xy 383.968543 -105.400323) (xy 383.989771 -105.406364) (xy 384.000756 -105.405174)
			(xy 384.015394 -105.403032) (xy 384.044891 -105.400745) (xy 384.059684 -105.400602) (xy 384.086938 -105.401044)
			(xy 384.140892 -105.408799) (xy 384.193194 -105.424154) (xy 384.242777 -105.446796) (xy 384.288634 -105.476265)
			(xy 384.329829 -105.511959) (xy 384.365526 -105.553154) (xy 384.394996 -105.599009) (xy 384.41764 -105.648591)
			(xy 384.432997 -105.700892) (xy 384.440755 -105.754846) (xy 384.440755 -105.809354) (xy 384.432997 -105.863308)
			(xy 384.41764 -105.915609) (xy 384.394996 -105.965191) (xy 384.365526 -106.011046) (xy 384.329829 -106.052241)
			(xy 384.288634 -106.087935) (xy 384.242777 -106.117404) (xy 384.193194 -106.140046) (xy 384.140892 -106.155401)
			(xy 384.086938 -106.163156) (xy 384.059684 -106.163618) (xy 384.033777 -106.163133) (xy 383.982442 -106.156108)
			(xy 383.932529 -106.142203) (xy 383.884956 -106.121673) (xy 383.840598 -106.094896) (xy 383.80027 -106.062364)
			(xy 383.764714 -106.024676) (xy 383.749296 -106.003852) (xy 383.74356 -105.996518) (xy 383.728054 -105.986233)
			(xy 383.71907 -105.983786) (xy 383.68859 -105.976928) (xy 383.679312 -105.975193) (xy 383.66065 -105.977924)
			(xy 383.652268 -105.982262) (xy 383.626295 -105.996563) (xy 383.571442 -106.019073) (xy 383.514138 -106.034298)
			(xy 383.455346 -106.041982) (xy 383.4257 -106.04246) (xy 383.396057 -106.041969) (xy 383.337275 -106.034245)
			(xy 383.279977 -106.019016) (xy 383.225117 -105.996537) (xy 383.199132 -105.982262) (xy 383.190716 -105.978022)
			(xy 383.172089 -105.975284) (xy 383.16281 -105.976928) (xy 383.13233 -105.983786) (xy 383.123337 -105.986213)
			(xy 383.107833 -105.996507) (xy 383.102104 -106.003852) (xy 383.086725 -106.02471) (xy 383.051177 -106.06242)
			(xy 383.010849 -106.094967) (xy 382.966485 -106.121754) (xy 382.918901 -106.142284) (xy 382.868976 -106.156181)
			(xy 382.817628 -106.163189) (xy 382.791716 -106.163618) (xy 382.764463 -106.163136) (xy 382.710512 -106.155381)
			(xy 382.658213 -106.140027) (xy 382.608633 -106.117386) (xy 382.562779 -106.087919) (xy 382.521585 -106.052226)
			(xy 382.485891 -106.011034) (xy 382.456422 -105.965181) (xy 382.433779 -105.915602) (xy 382.418423 -105.863304)
			(xy 382.410665 -105.809353) (xy 382.410665 -105.754847) (xy 382.418423 -105.700896) (xy 382.433779 -105.648598)
			(xy 382.456422 -105.599019) (xy 382.485891 -105.553166) (xy 382.521585 -105.511974) (xy 382.562779 -105.476281)
			(xy 382.608633 -105.446814) (xy 382.658213 -105.424173) (xy 382.710512 -105.408819) (xy 382.764463 -105.401064)
			(xy 382.791716 -105.400602) (xy 382.806509 -105.400734) (xy 382.836007 -105.403025) (xy 382.850644 -105.405174)
			(xy 382.861618 -105.406324) (xy 382.882812 -105.400247) (xy 382.891538 -105.39349) (xy 382.950212 -105.343452)
			(xy 382.958211 -105.335859) (xy 382.967443 -105.315858) (xy 382.967992 -105.304844) (xy 382.967992 -105.000552)
			(xy 382.967428 -104.989536) (xy 382.958227 -104.969519) (xy 382.950212 -104.961944) (xy 382.891538 -104.911906)
			(xy 382.882858 -104.905073) (xy 382.861629 -104.899032) (xy 382.850644 -104.900222) (xy 382.836006 -104.902364)
			(xy 382.806509 -104.904651) (xy 382.791716 -104.904794) (xy 382.764461 -104.90436) (xy 382.710507 -104.896605)
			(xy 382.658205 -104.88125) (xy 382.608621 -104.858607) (xy 382.562764 -104.829138) (xy 382.521568 -104.793443)
			(xy 382.485871 -104.752249) (xy 382.456401 -104.706393) (xy 382.433756 -104.65681) (xy 382.418399 -104.604509)
			(xy 382.410641 -104.550555) (xy 375.021703 -104.550555) (xy 375.045958 -104.588688) (xy 375.068245 -104.63795)
			(xy 375.083355 -104.689865) (xy 375.090984 -104.743393) (xy 375.091452 -104.770428) (xy 375.090948 -104.797678)
			(xy 375.083189 -104.851623) (xy 375.067833 -104.903914) (xy 375.045192 -104.953489) (xy 375.015726 -104.999337)
			(xy 374.980037 -105.040526) (xy 374.93885 -105.076217) (xy 374.893003 -105.105684) (xy 374.843429 -105.128327)
			(xy 374.791138 -105.143686) (xy 374.737194 -105.151447) (xy 374.709944 -105.151936) (xy 374.68141 -105.151422)
			(xy 374.624977 -105.142941) (xy 374.570437 -105.126148) (xy 374.519007 -105.101416) (xy 374.471836 -105.069299)
			(xy 374.429977 -105.030512) (xy 374.394363 -104.985922) (xy 374.365789 -104.936524) (xy 374.344894 -104.88342)
			(xy 374.332143 -104.827795) (xy 374.329452 -104.799384) (xy 374.32775 -104.784394) (xy 374.316814 -104.756297)
			(xy 374.298156 -104.732614) (xy 374.273397 -104.715407) (xy 374.244695 -104.706175) (xy 374.22963 -104.705404)
			(xy 374.202605 -104.704606) (xy 374.149181 -104.696291) (xy 374.097466 -104.680517) (xy 374.048496 -104.657601)
			(xy 374.003251 -104.628002) (xy 373.962637 -104.592312) (xy 373.927469 -104.551246) (xy 373.89845 -104.505626)
			(xy 373.876161 -104.456367) (xy 373.86105 -104.404455) (xy 373.853418 -104.350929) (xy 373.852948 -104.323896)
			(xy 363.090266 -104.323896) (xy 361.521113 -105.893147) (xy 372.881708 -105.893147) (xy 372.881708 -105.838653)
			(xy 372.889463 -105.784714) (xy 372.904814 -105.732427) (xy 372.92745 -105.682857) (xy 372.956909 -105.637013)
			(xy 372.992593 -105.595827) (xy 373.033774 -105.560138) (xy 373.079615 -105.530673) (xy 373.129182 -105.508031)
			(xy 373.181467 -105.492673) (xy 373.235405 -105.484911) (xy 373.262652 -105.484422) (xy 373.291579 -105.48498)
			(xy 373.348769 -105.493709) (xy 373.403986 -105.510974) (xy 373.455963 -105.536379) (xy 373.503507 -105.569342)
			(xy 373.545528 -105.609107) (xy 373.581062 -105.654761) (xy 373.595646 -105.679748) (xy 373.60098 -105.6894)
			(xy 373.619268 -105.702608) (xy 373.718074 -105.721404) (xy 373.739918 -105.715816) (xy 373.748554 -105.708704)
			(xy 373.769084 -105.692422) (xy 373.813789 -105.665088) (xy 373.861814 -105.644127) (xy 373.912254 -105.629933)
			(xy 373.964162 -105.622773) (xy 373.990362 -105.622344) (xy 374.017613 -105.622901) (xy 374.071561 -105.630652)
			(xy 374.123857 -105.646003) (xy 374.173436 -105.668641) (xy 374.219288 -105.698104) (xy 374.26048 -105.733793)
			(xy 374.296173 -105.774981) (xy 374.325641 -105.820831) (xy 374.348284 -105.870407) (xy 374.36364 -105.922701)
			(xy 374.371397 -105.976649) (xy 374.371397 -106.031151) (xy 374.36364 -106.085099) (xy 374.348284 -106.137393)
			(xy 374.325641 -106.186969) (xy 374.296173 -106.232819) (xy 374.26048 -106.274007) (xy 374.219288 -106.309696)
			(xy 374.173436 -106.339159) (xy 374.163377 -106.343752) (xy 385.052781 -106.343752) (xy 385.052781 -106.289248)
			(xy 385.060538 -106.235299) (xy 385.075895 -106.183002) (xy 385.098537 -106.133424) (xy 385.128006 -106.087573)
			(xy 385.163699 -106.046382) (xy 385.204892 -106.010691) (xy 385.250745 -105.981226) (xy 385.300325 -105.958586)
			(xy 385.352622 -105.943233) (xy 385.406572 -105.93548) (xy 385.433824 -105.935018) (xy 385.459732 -105.935482)
			(xy 385.511068 -105.942509) (xy 385.560982 -105.956416) (xy 385.608556 -105.976949) (xy 385.652914 -106.00373)
			(xy 385.693241 -106.036265) (xy 385.728795 -106.073958) (xy 385.744212 -106.094784) (xy 385.749939 -106.102127)
			(xy 385.765451 -106.112405) (xy 385.774438 -106.11485) (xy 385.804918 -106.121708) (xy 385.814196 -106.123442)
			(xy 385.832857 -106.120711) (xy 385.84124 -106.116374) (xy 385.867208 -106.102064) (xy 385.922063 -106.079557)
			(xy 385.979369 -106.064335) (xy 386.038162 -106.056654) (xy 386.067808 -106.056176) (xy 386.097451 -106.056659)
			(xy 386.156234 -106.064385) (xy 386.213532 -106.079615) (xy 386.268392 -106.102098) (xy 386.294376 -106.116374)
			(xy 386.30279 -106.120618) (xy 386.321419 -106.123353) (xy 386.330698 -106.121708) (xy 386.361178 -106.11485)
			(xy 386.370179 -106.112447) (xy 386.385681 -106.102137) (xy 386.391404 -106.094784) (xy 386.406789 -106.07393)
			(xy 386.442335 -106.036219) (xy 386.482661 -106.003669) (xy 386.527025 -105.976882) (xy 386.574607 -105.956351)
			(xy 386.624533 -105.942454) (xy 386.67588 -105.935447) (xy 386.701792 -105.935018) (xy 386.729047 -105.935428)
			(xy 386.783003 -105.943185) (xy 386.835305 -105.958541) (xy 386.88489 -105.981185) (xy 386.930747 -106.010655)
			(xy 386.970384 -106.045) (xy 392.969748 -106.045) (xy 392.973819 -105.989378) (xy 392.985945 -105.934941)
			(xy 393.005868 -105.88285) (xy 393.033164 -105.834215) (xy 393.06725 -105.790072) (xy 393.107399 -105.751363)
			(xy 393.152757 -105.718912) (xy 393.202357 -105.693411) (xy 393.255141 -105.675404) (xy 393.309984 -105.665274)
			(xy 393.365718 -105.663237) (xy 393.421155 -105.669337) (xy 393.475112 -105.683443) (xy 393.526441 -105.705255)
			(xy 393.574047 -105.734309) (xy 393.616915 -105.769984) (xy 393.654132 -105.811521) (xy 393.684905 -105.858034)
			(xy 393.708577 -105.908531) (xy 393.724645 -105.961938) (xy 393.732765 -106.017114) (xy 393.733274 -106.045)
			(xy 393.732765 -106.072886) (xy 393.724645 -106.128062) (xy 393.708577 -106.181469) (xy 393.684905 -106.231966)
			(xy 393.654132 -106.278479) (xy 393.616915 -106.320016) (xy 393.574047 -106.355691) (xy 393.526441 -106.384745)
			(xy 393.475112 -106.406557) (xy 393.421155 -106.420663) (xy 393.365718 -106.426763) (xy 393.309984 -106.424726)
			(xy 393.255141 -106.414596) (xy 393.202357 -106.396589) (xy 393.152757 -106.371088) (xy 393.107399 -106.338637)
			(xy 393.06725 -106.299928) (xy 393.033164 -106.255785) (xy 393.005868 -106.20715) (xy 392.985945 -106.155059)
			(xy 392.973819 -106.100622) (xy 392.969748 -106.045) (xy 386.970384 -106.045) (xy 386.971943 -106.046351)
			(xy 387.00764 -106.087547) (xy 387.037111 -106.133403) (xy 387.059756 -106.182987) (xy 387.075113 -106.23529)
			(xy 387.082871 -106.289245) (xy 387.082871 -106.343755) (xy 387.075113 -106.39771) (xy 387.059756 -106.450013)
			(xy 387.037111 -106.499597) (xy 387.00764 -106.545453) (xy 386.971943 -106.586649) (xy 386.930747 -106.622345)
			(xy 386.88489 -106.651815) (xy 386.835305 -106.674459) (xy 386.783003 -106.689815) (xy 386.729047 -106.697572)
			(xy 386.701792 -106.698034) (xy 386.686999 -106.697902) (xy 386.657501 -106.695611) (xy 386.642864 -106.693462)
			(xy 386.63189 -106.692332) (xy 386.610698 -106.698397) (xy 386.60197 -106.705146) (xy 386.543296 -106.755184)
			(xy 386.535281 -106.762764) (xy 386.526058 -106.782775) (xy 386.525516 -106.793792) (xy 386.525516 -107.098084)
			(xy 386.526058 -107.109103) (xy 386.535274 -107.129119) (xy 386.543296 -107.136692) (xy 386.60197 -107.18673)
			(xy 386.610687 -107.193508) (xy 386.631886 -107.199584) (xy 386.642864 -107.198414) (xy 386.657502 -107.196271)
			(xy 386.686999 -107.193984) (xy 386.701792 -107.193842) (xy 386.729049 -107.194204) (xy 386.783008 -107.201961)
			(xy 386.835313 -107.217319) (xy 386.884901 -107.239964) (xy 386.930761 -107.269436) (xy 386.97196 -107.305134)
			(xy 387.00766 -107.346332) (xy 387.037132 -107.392192) (xy 387.044103 -107.407456) (xy 397.347184 -107.407456)
			(xy 397.351255 -107.351834) (xy 397.363381 -107.297397) (xy 397.383304 -107.245306) (xy 397.4106 -107.196671)
			(xy 397.444686 -107.152528) (xy 397.484835 -107.113819) (xy 397.530193 -107.081368) (xy 397.579793 -107.055867)
			(xy 397.632577 -107.03786) (xy 397.68742 -107.02773) (xy 397.743154 -107.025693) (xy 397.798591 -107.031793)
			(xy 397.852548 -107.045899) (xy 397.903877 -107.067711) (xy 397.951483 -107.096765) (xy 397.994351 -107.13244)
			(xy 398.031568 -107.173977) (xy 398.062341 -107.22049) (xy 398.086013 -107.270987) (xy 398.102081 -107.324394)
			(xy 398.110201 -107.37957) (xy 398.11071 -107.407456) (xy 398.110201 -107.435342) (xy 398.102081 -107.490518)
			(xy 398.086013 -107.543925) (xy 398.062341 -107.594422) (xy 398.031568 -107.640935) (xy 397.994351 -107.682472)
			(xy 397.951483 -107.718147) (xy 397.903877 -107.747201) (xy 397.852548 -107.769013) (xy 397.798591 -107.783119)
			(xy 397.743154 -107.789219) (xy 397.68742 -107.787182) (xy 397.632577 -107.777052) (xy 397.579793 -107.759045)
			(xy 397.530193 -107.733544) (xy 397.484835 -107.701093) (xy 397.444686 -107.662384) (xy 397.4106 -107.618241)
			(xy 397.383304 -107.569606) (xy 397.363381 -107.517515) (xy 397.351255 -107.463078) (xy 397.347184 -107.407456)
			(xy 387.044103 -107.407456) (xy 387.059778 -107.441779) (xy 387.075137 -107.494084) (xy 387.082895 -107.548043)
			(xy 387.082895 -107.602557) (xy 387.075137 -107.656516) (xy 387.059778 -107.708821) (xy 387.037132 -107.758408)
			(xy 387.00766 -107.804268) (xy 386.972279 -107.845098) (xy 392.969748 -107.845098) (xy 392.973819 -107.789476)
			(xy 392.985945 -107.735039) (xy 393.005868 -107.682948) (xy 393.033164 -107.634313) (xy 393.06725 -107.59017)
			(xy 393.107399 -107.551461) (xy 393.152757 -107.51901) (xy 393.202357 -107.493509) (xy 393.255141 -107.475502)
			(xy 393.309984 -107.465372) (xy 393.365718 -107.463335) (xy 393.421155 -107.469435) (xy 393.475112 -107.483541)
			(xy 393.526441 -107.505353) (xy 393.574047 -107.534407) (xy 393.616915 -107.570082) (xy 393.654132 -107.611619)
			(xy 393.684905 -107.658132) (xy 393.708577 -107.708629) (xy 393.724645 -107.762036) (xy 393.732765 -107.817212)
			(xy 393.733274 -107.845098) (xy 393.732765 -107.872984) (xy 393.724645 -107.92816) (xy 393.708577 -107.981567)
			(xy 393.684905 -108.032064) (xy 393.654132 -108.078577) (xy 393.616915 -108.120114) (xy 393.574047 -108.155789)
			(xy 393.526441 -108.184843) (xy 393.475112 -108.206655) (xy 393.421155 -108.220761) (xy 393.365718 -108.226861)
			(xy 393.309984 -108.224824) (xy 393.255141 -108.214694) (xy 393.202357 -108.196687) (xy 393.152757 -108.171186)
			(xy 393.107399 -108.138735) (xy 393.06725 -108.100026) (xy 393.033164 -108.055883) (xy 393.005868 -108.007248)
			(xy 392.985945 -107.955157) (xy 392.973819 -107.90072) (xy 392.969748 -107.845098) (xy 386.972279 -107.845098)
			(xy 386.97196 -107.845466) (xy 386.930761 -107.881164) (xy 386.884901 -107.910636) (xy 386.835313 -107.933281)
			(xy 386.783008 -107.948639) (xy 386.729049 -107.956396) (xy 386.701792 -107.956858) (xy 386.675884 -107.956392)
			(xy 386.624547 -107.949367) (xy 386.574633 -107.93546) (xy 386.527059 -107.914928) (xy 386.482701 -107.888148)
			(xy 386.442374 -107.855612) (xy 386.40682 -107.817919) (xy 386.391404 -107.797092) (xy 386.385657 -107.789767)
			(xy 386.37016 -107.779477) (xy 386.361178 -107.777026) (xy 386.330698 -107.770168) (xy 386.321419 -107.768445)
			(xy 386.302759 -107.771169) (xy 386.294376 -107.775502) (xy 386.268403 -107.789803) (xy 386.21355 -107.812313)
			(xy 386.156246 -107.827537) (xy 386.097454 -107.835221) (xy 386.067808 -107.8357) (xy 386.038165 -107.835213)
			(xy 385.979382 -107.827489) (xy 385.922084 -107.81226) (xy 385.867224 -107.789778) (xy 385.84124 -107.775502)
			(xy 385.832824 -107.771264) (xy 385.814197 -107.768526) (xy 385.804918 -107.770168) (xy 385.774438 -107.777026)
			(xy 385.765441 -107.779443) (xy 385.749938 -107.789743) (xy 385.744212 -107.797092) (xy 385.72881 -107.817933)
			(xy 385.693268 -107.855646) (xy 385.652945 -107.888197) (xy 385.608584 -107.914986) (xy 385.561004 -107.93552)
			(xy 385.511081 -107.949419) (xy 385.459735 -107.956428) (xy 385.433824 -107.956858) (xy 385.406574 -107.956296)
			(xy 385.352627 -107.948543) (xy 385.300333 -107.933191) (xy 385.250757 -107.910553) (xy 385.204906 -107.88109)
			(xy 385.163716 -107.845401) (xy 385.128025 -107.804213) (xy 385.098558 -107.758364) (xy 385.075917 -107.708789)
			(xy 385.060562 -107.656496) (xy 385.052805 -107.60255) (xy 385.052805 -107.54805) (xy 385.060562 -107.494104)
			(xy 385.075917 -107.441811) (xy 385.098558 -107.392236) (xy 385.128025 -107.346387) (xy 385.163716 -107.305199)
			(xy 385.204906 -107.26951) (xy 385.250757 -107.240047) (xy 385.300333 -107.217409) (xy 385.352627 -107.202057)
			(xy 385.406574 -107.194304) (xy 385.433824 -107.193842) (xy 385.448617 -107.193972) (xy 385.478115 -107.196265)
			(xy 385.492752 -107.198414) (xy 385.503728 -107.1995) (xy 385.524915 -107.193466) (xy 385.533646 -107.18673)
			(xy 385.59232 -107.136692) (xy 385.600348 -107.129124) (xy 385.609563 -107.109104) (xy 385.6101 -107.098084)
			(xy 385.6101 -106.793792) (xy 385.609567 -106.782773) (xy 385.600344 -106.762756) (xy 385.59232 -106.755184)
			(xy 385.533646 -106.705146) (xy 385.52496 -106.698321) (xy 385.503736 -106.692274) (xy 385.492752 -106.693462)
			(xy 385.478114 -106.695604) (xy 385.448617 -106.697891) (xy 385.433824 -106.698034) (xy 385.406572 -106.69752)
			(xy 385.352622 -106.689767) (xy 385.300325 -106.674414) (xy 385.250745 -106.651774) (xy 385.204892 -106.622309)
			(xy 385.163699 -106.586618) (xy 385.128006 -106.545427) (xy 385.098537 -106.499576) (xy 385.075895 -106.449998)
			(xy 385.060538 -106.397701) (xy 385.052781 -106.343752) (xy 374.163377 -106.343752) (xy 374.123857 -106.361797)
			(xy 374.071561 -106.377148) (xy 374.017613 -106.384899) (xy 373.990362 -106.38536) (xy 373.961432 -106.38488)
			(xy 373.904238 -106.376138) (xy 373.849019 -106.358859) (xy 373.797042 -106.333441) (xy 373.749499 -106.300466)
			(xy 373.70748 -106.26069) (xy 373.671949 -106.215026) (xy 373.657368 -106.190034) (xy 373.652034 -106.180382)
			(xy 373.633746 -106.167174) (xy 373.53494 -106.148378) (xy 373.513096 -106.153966) (xy 373.50446 -106.161078)
			(xy 373.483923 -106.177351) (xy 373.43922 -106.204687) (xy 373.391197 -106.22565) (xy 373.340758 -106.239846)
			(xy 373.288851 -106.247008) (xy 373.262652 -106.247438) (xy 373.235405 -106.246889) (xy 373.181467 -106.239127)
			(xy 373.129182 -106.223769) (xy 373.079615 -106.201127) (xy 373.033774 -106.171662) (xy 372.992593 -106.135973)
			(xy 372.956909 -106.094787) (xy 372.92745 -106.048943) (xy 372.904814 -105.999373) (xy 372.889463 -105.947086)
			(xy 372.881708 -105.893147) (xy 361.521113 -105.893147) (xy 359.99547 -107.418886) (xy 359.971918 -107.441798)
			(xy 359.920539 -107.48276) (xy 359.864896 -107.517713) (xy 359.80569 -107.546216) (xy 359.743666 -107.567912)
			(xy 359.679602 -107.582527) (xy 359.614305 -107.589879) (xy 359.58145 -107.590336) (xy 359.581196 -107.590336)
			(xy 359.545799 -107.589794) (xy 359.475521 -107.58126) (xy 359.406784 -107.564318) (xy 359.34059 -107.539214)
			(xy 359.277905 -107.506314) (xy 359.219642 -107.466099) (xy 359.166652 -107.419154) (xy 359.119706 -107.366164)
			(xy 359.07949 -107.307902) (xy 359.04659 -107.245217) (xy 359.021485 -107.179024) (xy 359.004541 -107.110287)
			(xy 358.996007 -107.040009) (xy 358.995472 -107.004612) (xy 358.995472 -107.004358) (xy 358.995931 -106.971505)
			(xy 359.003297 -106.906212) (xy 359.017923 -106.842153) (xy 359.039623 -106.780133) (xy 359.068125 -106.720929)
			(xy 359.103072 -106.665286) (xy 359.144025 -106.613903) (xy 359.166922 -106.590338) (xy 359.27919 -106.47807)
			(xy 359.285678 -106.470913) (xy 359.293257 -106.453162) (xy 359.293922 -106.443526) (xy 359.295954 -106.363516)
			(xy 359.289096 -106.345482) (xy 359.282492 -106.338116) (xy 359.263944 -106.316939) (xy 359.232643 -106.27015)
			(xy 359.208553 -106.219272) (xy 359.192198 -106.165406) (xy 359.183933 -106.109723) (xy 359.183432 -106.081576)
			(xy 359.18394 -106.059732) (xy 359.184448 -106.05008) (xy 359.178352 -106.031284) (xy 359.119424 -105.962704)
			(xy 359.102152 -105.953814) (xy 359.0925 -105.952798) (xy 359.091992 -105.952798) (xy 359.063988 -105.949601)
			(xy 359.00926 -105.936135) (xy 358.95711 -105.914761) (xy 358.908675 -105.885943) (xy 358.865009 -105.850309)
			(xy 358.827064 -105.808636) (xy 358.795667 -105.761831) (xy 358.771501 -105.710914) (xy 358.755094 -105.656995)
			(xy 358.746802 -105.601248) (xy 358.746298 -105.573068) (xy 358.746784 -105.545817) (xy 358.75454 -105.491869)
			(xy 358.769895 -105.439574) (xy 358.792537 -105.389997) (xy 358.822003 -105.344147) (xy 358.857694 -105.302956)
			(xy 358.898885 -105.267265) (xy 358.944735 -105.237799) (xy 358.994312 -105.215157) (xy 359.046607 -105.199802)
			(xy 359.100555 -105.192046) (xy 359.155057 -105.192046) (xy 359.209005 -105.199802) (xy 359.2613 -105.215157)
			(xy 359.310877 -105.237799) (xy 359.356727 -105.267265) (xy 359.397918 -105.302956) (xy 359.433609 -105.344147)
			(xy 359.463075 -105.389997) (xy 359.485717 -105.439574) (xy 359.501072 -105.491869) (xy 359.508828 -105.545817)
			(xy 359.509314 -105.573068) (xy 359.508806 -105.594912) (xy 359.508298 -105.604564) (xy 359.514394 -105.62336)
			(xy 359.573322 -105.69194) (xy 359.590594 -105.70083) (xy 359.600246 -105.701846) (xy 359.600754 -105.701846)
			(xy 359.631257 -105.705329) (xy 359.690673 -105.720767) (xy 359.746849 -105.745524) (xy 359.798334 -105.778958)
			(xy 359.82148 -105.799128) (xy 359.828846 -105.805732) (xy 359.84688 -105.81259) (xy 359.92689 -105.810558)
			(xy 359.936527 -105.809882) (xy 359.954287 -105.802324) (xy 359.961434 -105.795826) (xy 363.089444 -102.667816)
			(xy 363.09554 -102.637844) (xy 363.089444 -102.62362) (xy 363.085257 -102.614476) (xy 363.071069 -102.60024)
			(xy 363.052504 -102.592541) (xy 363.042454 -102.592124) (xy 362.36783 -102.592124) (xy 362.357762 -102.592559)
			(xy 362.339163 -102.600272) (xy 362.331762 -102.60711) (xy 361.311952 -103.627174) (xy 361.307834 -103.631565)
			(xy 361.301549 -103.641831) (xy 361.299506 -103.647494) (xy 361.299506 -103.648002) (xy 361.291113 -103.673565)
			(xy 361.268034 -103.72217) (xy 361.238357 -103.76705) (xy 361.202668 -103.807317) (xy 361.161677 -103.842171)
			(xy 361.116197 -103.87092) (xy 361.067128 -103.892996) (xy 361.015445 -103.907959) (xy 360.962173 -103.915513)
			(xy 360.93527 -103.915972) (xy 360.908015 -103.915573) (xy 360.85406 -103.907811) (xy 360.801758 -103.892449)
			(xy 360.752176 -103.869801) (xy 360.706321 -103.840326) (xy 360.665128 -103.804626) (xy 360.629434 -103.763426)
			(xy 360.599968 -103.717566) (xy 360.577328 -103.66798) (xy 360.561975 -103.615676) (xy 360.554222 -103.561719)
			(xy 360.553762 -103.534464) (xy 360.554256 -103.507555) (xy 360.561837 -103.454273) (xy 360.576828 -103.402585)
			(xy 360.598933 -103.353515) (xy 360.627712 -103.308038) (xy 360.662596 -103.267056) (xy 360.702892 -103.231381)
			(xy 360.7478 -103.201721) (xy 360.79643 -103.178666) (xy 360.821986 -103.170228) (xy 360.82224 -103.170228)
			(xy 360.827935 -103.168252) (xy 360.838209 -103.161954) (xy 360.84256 -103.157782) (xy 361.867958 -102.132384)
			(xy 361.874054 -102.102412) (xy 361.867958 -102.088188) (xy 361.863774 -102.079043) (xy 361.849583 -102.06481)
			(xy 361.831018 -102.057111) (xy 361.820968 -102.056692) (xy 357.538528 -102.056692) (xy 357.528457 -102.057108)
			(xy 357.509858 -102.064833) (xy 357.50246 -102.071678) (xy 356.799896 -102.774496) (xy 356.781097 -102.792498)
			(xy 356.738988 -102.823082) (xy 356.692619 -102.846715) (xy 356.643128 -102.862817) (xy 356.59173 -102.870992)
			(xy 356.565708 -102.871524) (xy 354.79101 -102.871524) (xy 354.764988 -102.870963) (xy 354.713586 -102.862804)
			(xy 354.664089 -102.846718) (xy 354.617713 -102.823098) (xy 354.575594 -102.792525) (xy 354.556822 -102.774496)
			(xy 353.107752 -101.325426) (xy 353.103358 -101.32131) (xy 353.093094 -101.315025) (xy 353.087432 -101.31298)
			(xy 353.086924 -101.31298) (xy 353.059005 -101.303653) (xy 353.006176 -101.277698) (xy 352.957953 -101.243947)
			(xy 352.915479 -101.203199) (xy 352.897186 -101.180138) (xy 352.890836 -101.171756) (xy 352.872802 -101.161596)
			(xy 352.778568 -101.151436) (xy 352.758756 -101.157278) (xy 352.750882 -101.164136) (xy 352.730118 -101.181021)
			(xy 352.68479 -101.20947) (xy 352.635933 -101.231312) (xy 352.584505 -101.246118) (xy 352.531514 -101.253598)
			(xy 352.504756 -101.254052) (xy 352.47751 -101.253475) (xy 352.423573 -101.245714) (xy 352.37129 -101.230357)
			(xy 352.321724 -101.207716) (xy 352.275884 -101.178252) (xy 352.234704 -101.142565) (xy 352.199022 -101.10138)
			(xy 352.169563 -101.055537) (xy 352.146928 -101.005969) (xy 352.131576 -100.953684) (xy 352.123822 -100.899746)
			(xy 352.123822 -100.845254) (xy 352.131576 -100.791316) (xy 352.146928 -100.739031) (xy 352.169563 -100.689463)
			(xy 352.199022 -100.64362) (xy 352.234704 -100.602435) (xy 352.275884 -100.566748) (xy 352.321724 -100.537284)
			(xy 352.37129 -100.514643) (xy 352.423573 -100.499286) (xy 352.47751 -100.491525) (xy 352.504756 -100.491036)
			(xy 352.533987 -100.491581) (xy 352.591762 -100.50052) (xy 352.647498 -100.518164) (xy 352.699892 -100.544102)
			(xy 352.747717 -100.577726) (xy 352.789856 -100.61825) (xy 352.808032 -100.64115) (xy 352.814382 -100.649532)
			(xy 352.832416 -100.659692) (xy 352.92665 -100.669852) (xy 352.946462 -100.66401) (xy 352.954336 -100.657152)
			(xy 352.975092 -100.640257) (xy 353.020423 -100.61181) (xy 353.069281 -100.58997) (xy 353.120711 -100.575166)
			(xy 353.173703 -100.567689) (xy 353.200462 -100.567236) (xy 353.228365 -100.567766) (xy 353.283576 -100.575903)
			(xy 353.337012 -100.591994) (xy 353.387536 -100.615696) (xy 353.434069 -100.646503) (xy 353.475619 -100.683759)
			(xy 353.493832 -100.704904) (xy 353.494086 -100.705158) (xy 353.502 -100.713719) (xy 353.52332 -100.723098)
			(xy 353.53498 -100.723192) (xy 353.62769 -100.719382) (xy 353.648518 -100.707952) (xy 353.655376 -100.6983)
			(xy 353.670737 -100.677075) (xy 353.706324 -100.638624) (xy 353.746841 -100.605407) (xy 353.791522 -100.578048)
			(xy 353.839529 -100.557064) (xy 353.889956 -100.542848) (xy 353.941854 -100.53567) (xy 353.96805 -100.535232)
			(xy 353.968558 -100.535232) (xy 353.993687 -100.535651) (xy 354.043508 -100.542271) (xy 354.067872 -100.54844)
			(xy 354.079302 -100.551488) (xy 354.102416 -100.546916) (xy 354.176076 -100.490782) (xy 354.184982 -100.483149)
			(xy 354.195298 -100.462111) (xy 354.195888 -100.450396) (xy 354.195888 -98.731324) (xy 354.19546 -98.721303)
			(xy 354.187796 -98.702784) (xy 354.173626 -98.688611) (xy 354.155109 -98.680942) (xy 354.145088 -98.680524)
			(xy 344.957146 -98.680524) (xy 344.924292 -98.680074) (xy 344.858999 -98.672706) (xy 344.79494 -98.658079)
			(xy 344.73292 -98.636378) (xy 344.673717 -98.607874) (xy 344.618074 -98.572926) (xy 344.56669 -98.531972)
			(xy 344.543126 -98.509074) (xy 342.672416 -96.63811) (xy 342.665003 -96.631286) (xy 342.646414 -96.623556)
			(xy 342.636348 -96.623124) (xy 335.8896 -96.623124) (xy 335.856747 -96.622639) (xy 335.791455 -96.615277)
			(xy 335.727397 -96.600656) (xy 335.665377 -96.57896) (xy 335.606173 -96.550462) (xy 335.55053 -96.515519)
			(xy 335.499145 -96.474569) (xy 335.47558 -96.451674) (xy 333.478124 -94.454218) (xy 333.470717 -94.447534)
			(xy 333.452277 -94.439962) (xy 333.44231 -94.439486) (xy 333.360522 -94.439232) (xy 333.34198 -94.446852)
			(xy 333.334868 -94.453964) (xy 333.313279 -94.474616) (xy 333.264874 -94.509631) (xy 333.211601 -94.536669)
			(xy 333.154764 -94.55507) (xy 333.095753 -94.564383) (xy 333.065882 -94.564962) (xy 333.039717 -94.564555)
			(xy 332.987879 -94.557394) (xy 332.937504 -94.543221) (xy 332.889536 -94.522304) (xy 332.844873 -94.495032)
			(xy 332.804353 -94.461918) (xy 332.786228 -94.443042) (xy 332.778608 -94.43466) (xy 332.758542 -94.426532)
			(xy 332.659482 -94.42958) (xy 332.63967 -94.439486) (xy 332.632812 -94.448122) (xy 332.614601 -94.469844)
			(xy 332.572847 -94.508177) (xy 332.525881 -94.53991) (xy 332.474736 -94.564344) (xy 332.420538 -94.58094)
			(xy 332.364481 -94.589333) (xy 332.33614 -94.589854) (xy 332.308892 -94.589285) (xy 332.25495 -94.581535)
			(xy 332.202659 -94.566187) (xy 332.153085 -94.543554) (xy 332.107237 -94.514096) (xy 332.066047 -94.478413)
			(xy 332.030355 -94.437232) (xy 332.000887 -94.39139) (xy 331.978243 -94.341821) (xy 331.962883 -94.289535)
			(xy 331.955121 -94.235594) (xy 331.954632 -94.208346) (xy 331.954861 -94.191102) (xy 331.958038 -94.156759)
			(xy 331.960982 -94.139766) (xy 331.960982 -94.139512) (xy 331.962099 -94.130798) (xy 331.959084 -94.113505)
			(xy 331.950394 -94.098253) (xy 331.943964 -94.092268) (xy 331.866748 -94.025974) (xy 331.840332 -94.020894)
			(xy 331.827632 -94.025466) (xy 331.79679 -94.035678) (xy 331.733421 -94.050012) (xy 331.668855 -94.057255)
			(xy 331.63637 -94.057724) (xy 331.47762 -94.057724) (xy 331.466477 -94.058307) (xy 331.446314 -94.067801)
			(xy 331.438758 -94.076012) (xy 331.381354 -94.144592) (xy 331.375512 -94.165928) (xy 331.377544 -94.177104)
			(xy 331.377544 -94.177612) (xy 331.380385 -94.194295) (xy 331.383436 -94.228) (xy 331.38364 -94.244922)
			(xy 331.383154 -94.272173) (xy 331.375398 -94.326121) (xy 331.360043 -94.378416) (xy 331.337401 -94.427993)
			(xy 331.307935 -94.473843) (xy 331.272244 -94.515034) (xy 331.231053 -94.550725) (xy 331.185203 -94.580191)
			(xy 331.135626 -94.602833) (xy 331.083331 -94.618188) (xy 331.029383 -94.625944) (xy 330.974881 -94.625944)
			(xy 330.920933 -94.618188) (xy 330.868638 -94.602833) (xy 330.819061 -94.580191) (xy 330.773211 -94.550725)
			(xy 330.73202 -94.515034) (xy 330.696329 -94.473843) (xy 330.666863 -94.427993) (xy 330.644221 -94.378416)
			(xy 330.628866 -94.326121) (xy 330.62111 -94.272173) (xy 330.620624 -94.244922) (xy 330.621265 -94.214344)
			(xy 330.631087 -94.153981) (xy 330.640182 -94.12478) (xy 330.642722 -94.116906) (xy 330.642722 -94.108524)
			(xy 330.642261 -94.098507) (xy 330.634603 -94.079995) (xy 330.620444 -94.065823) (xy 330.601939 -94.058148)
			(xy 330.591922 -94.057724) (xy 330.528422 -94.057724) (xy 330.517427 -94.058179) (xy 330.497415 -94.067289)
			(xy 330.489814 -94.07525) (xy 330.43241 -94.141798) (xy 330.426314 -94.16288) (xy 330.427838 -94.173802)
			(xy 330.429615 -94.187129) (xy 330.431521 -94.213951) (xy 330.431648 -94.227396) (xy 330.431648 -94.227904)
			(xy 330.431162 -94.255155) (xy 330.423406 -94.309103) (xy 330.408051 -94.361398) (xy 330.385409 -94.410975)
			(xy 330.355943 -94.456825) (xy 330.320252 -94.498016) (xy 330.279061 -94.533707) (xy 330.233211 -94.563173)
			(xy 330.183634 -94.585815) (xy 330.131339 -94.60117) (xy 330.077391 -94.608926) (xy 330.022889 -94.608926)
			(xy 329.968941 -94.60117) (xy 329.916646 -94.585815) (xy 329.867069 -94.563173) (xy 329.821219 -94.533707)
			(xy 329.780028 -94.498016) (xy 329.744337 -94.456825) (xy 329.714871 -94.410975) (xy 329.692229 -94.361398)
			(xy 329.676874 -94.309103) (xy 329.669118 -94.255155) (xy 329.668632 -94.227904) (xy 329.668632 -94.227396)
			(xy 329.668747 -94.213951) (xy 329.670657 -94.187129) (xy 329.672442 -94.173802) (xy 329.673966 -94.16288)
			(xy 329.66787 -94.141798) (xy 329.610466 -94.07525) (xy 329.602854 -94.067305) (xy 329.582849 -94.05821)
			(xy 329.571858 -94.057724) (xy 329.508104 -94.057724) (xy 329.496799 -94.058258) (xy 329.476353 -94.067896)
			(xy 329.468734 -94.076266) (xy 329.41895 -94.136972) (xy 329.412246 -94.145993) (xy 329.406717 -94.167751)
			(xy 329.408282 -94.178882) (xy 329.408282 -94.17939) (xy 329.411702 -94.197678) (xy 329.415388 -94.234701)
			(xy 329.415648 -94.253304) (xy 329.415162 -94.280555) (xy 329.407406 -94.334503) (xy 329.392051 -94.386798)
			(xy 329.369409 -94.436375) (xy 329.339943 -94.482225) (xy 329.304252 -94.523416) (xy 329.263061 -94.559107)
			(xy 329.217211 -94.588573) (xy 329.167634 -94.611215) (xy 329.115339 -94.62657) (xy 329.061391 -94.634326)
			(xy 329.006889 -94.634326) (xy 328.952941 -94.62657) (xy 328.900646 -94.611215) (xy 328.851069 -94.588573)
			(xy 328.805219 -94.559107) (xy 328.764028 -94.523416) (xy 328.728337 -94.482225) (xy 328.698871 -94.436375)
			(xy 328.676229 -94.386798) (xy 328.660874 -94.334503) (xy 328.653118 -94.280555) (xy 328.652632 -94.253304)
			(xy 328.65287 -94.234637) (xy 328.656559 -94.197485) (xy 328.659998 -94.179136) (xy 328.659998 -94.178882)
			(xy 328.661586 -94.167755) (xy 328.656027 -94.146001) (xy 328.64933 -94.136972) (xy 328.599546 -94.076266)
			(xy 328.5919 -94.067938) (xy 328.571466 -94.058324) (xy 328.560176 -94.057724) (xy 328.492866 -94.057724)
			(xy 328.481657 -94.058261) (xy 328.461356 -94.067761) (xy 328.45375 -94.076012) (xy 328.403712 -94.13621)
			(xy 328.396991 -94.145302) (xy 328.391436 -94.167184) (xy 328.393044 -94.178374) (xy 328.396141 -94.195862)
			(xy 328.399446 -94.231227) (xy 328.399648 -94.248986) (xy 328.399648 -94.24924) (xy 328.399162 -94.276491)
			(xy 328.391406 -94.330439) (xy 328.376051 -94.382734) (xy 328.353409 -94.432311) (xy 328.323943 -94.478161)
			(xy 328.288252 -94.519352) (xy 328.247061 -94.555043) (xy 328.201211 -94.584509) (xy 328.151634 -94.607151)
			(xy 328.099339 -94.622506) (xy 328.045391 -94.630262) (xy 327.990889 -94.630262) (xy 327.936941 -94.622506)
			(xy 327.884646 -94.607151) (xy 327.835069 -94.584509) (xy 327.789219 -94.555043) (xy 327.748028 -94.519352)
			(xy 327.712337 -94.478161) (xy 327.682871 -94.432311) (xy 327.660229 -94.382734) (xy 327.644874 -94.330439)
			(xy 327.637118 -94.276491) (xy 327.636632 -94.24924) (xy 327.636632 -94.248986) (xy 327.636841 -94.231227)
			(xy 327.640149 -94.195864) (xy 327.643236 -94.178374) (xy 327.644816 -94.167184) (xy 327.63928 -94.145302)
			(xy 327.632568 -94.13621) (xy 327.58253 -94.076012) (xy 327.574891 -94.067805) (xy 327.554609 -94.058315)
			(xy 327.543414 -94.057724) (xy 327.515728 -94.057724) (xy 327.50566 -94.058158) (xy 327.487061 -94.065872)
			(xy 327.47966 -94.07271) (xy 327.162922 -94.389448) (xy 327.155502 -94.396264) (xy 327.136918 -94.403999)
			(xy 327.126854 -94.404434) (xy 326.463914 -94.404434) (xy 326.43826 -94.421452) (xy 326.432418 -94.43593)
			(xy 326.429079 -94.445324) (xy 326.429072 -94.465237) (xy 326.436661 -94.483648) (xy 326.44334 -94.491048)
			(xy 326.71766 -94.765368) (xy 326.740576 -94.788947) (xy 326.781571 -94.840358) (xy 326.816558 -94.896032)
			(xy 326.845098 -94.955269) (xy 326.866833 -95.017328) (xy 326.881489 -95.081428) (xy 326.888884 -95.146765)
			(xy 326.889364 -95.179642) (xy 326.889364 -95.801942) (xy 326.889159 -95.821308) (xy 326.886488 -95.859948)
			(xy 326.88403 -95.879158) (xy 326.88403 -95.879412) (xy 326.883149 -95.890516) (xy 326.889877 -95.911727)
			(xy 326.896984 -95.920306) (xy 326.95769 -95.986092) (xy 326.978518 -95.994474) (xy 326.989948 -95.993966)
			(xy 327.008998 -95.993458) (xy 327.036249 -95.993989) (xy 327.090195 -96.001745) (xy 327.142488 -96.0171)
			(xy 327.192064 -96.03974) (xy 327.237914 -96.069205) (xy 327.279103 -96.104896) (xy 327.314793 -96.146085)
			(xy 327.344259 -96.191934) (xy 327.3669 -96.24151) (xy 327.380654 -96.288352) (xy 328.052174 -96.288352)
			(xy 328.056245 -96.23273) (xy 328.068371 -96.178293) (xy 328.088294 -96.126202) (xy 328.11559 -96.077567)
			(xy 328.149676 -96.033424) (xy 328.189825 -95.994715) (xy 328.235183 -95.962264) (xy 328.284783 -95.936763)
			(xy 328.337567 -95.918756) (xy 328.39241 -95.908626) (xy 328.448144 -95.906589) (xy 328.503581 -95.912689)
			(xy 328.557538 -95.926795) (xy 328.608867 -95.948607) (xy 328.656473 -95.977661) (xy 328.699341 -96.013336)
			(xy 328.736558 -96.054873) (xy 328.767331 -96.101386) (xy 328.791003 -96.151883) (xy 328.807071 -96.20529)
			(xy 328.815191 -96.260466) (xy 328.815422 -96.273112) (xy 329.397866 -96.273112) (xy 329.401937 -96.21749)
			(xy 329.414063 -96.163053) (xy 329.433986 -96.110962) (xy 329.461282 -96.062327) (xy 329.495368 -96.018184)
			(xy 329.535517 -95.979475) (xy 329.580875 -95.947024) (xy 329.630475 -95.921523) (xy 329.683259 -95.903516)
			(xy 329.738102 -95.893386) (xy 329.793836 -95.891349) (xy 329.849273 -95.897449) (xy 329.90323 -95.911555)
			(xy 329.954559 -95.933367) (xy 330.002165 -95.962421) (xy 330.045033 -95.998096) (xy 330.08225 -96.039633)
			(xy 330.113023 -96.086146) (xy 330.136695 -96.136643) (xy 330.152763 -96.19005) (xy 330.160883 -96.245226)
			(xy 330.161392 -96.273112) (xy 330.160883 -96.300998) (xy 330.152763 -96.356174) (xy 330.136695 -96.409581)
			(xy 330.133632 -96.416114) (xy 331.954122 -96.416114) (xy 331.958193 -96.360492) (xy 331.970319 -96.306055)
			(xy 331.990242 -96.253964) (xy 332.017538 -96.205329) (xy 332.051624 -96.161186) (xy 332.091773 -96.122477)
			(xy 332.137131 -96.090026) (xy 332.186731 -96.064525) (xy 332.239515 -96.046518) (xy 332.294358 -96.036388)
			(xy 332.350092 -96.034351) (xy 332.405529 -96.040451) (xy 332.459486 -96.054557) (xy 332.510815 -96.076369)
			(xy 332.558421 -96.105423) (xy 332.601289 -96.141098) (xy 332.638506 -96.182635) (xy 332.669279 -96.229148)
			(xy 332.692951 -96.279645) (xy 332.709019 -96.333052) (xy 332.717139 -96.388228) (xy 332.717648 -96.416114)
			(xy 332.717139 -96.444) (xy 332.709019 -96.499176) (xy 332.692951 -96.552583) (xy 332.669279 -96.60308)
			(xy 332.638506 -96.649593) (xy 332.601289 -96.69113) (xy 332.558421 -96.726805) (xy 332.510815 -96.755859)
			(xy 332.459486 -96.777671) (xy 332.405529 -96.791777) (xy 332.350092 -96.797877) (xy 332.294358 -96.79584)
			(xy 332.239515 -96.78571) (xy 332.186731 -96.767703) (xy 332.137131 -96.742202) (xy 332.091773 -96.709751)
			(xy 332.051624 -96.671042) (xy 332.017538 -96.626899) (xy 331.990242 -96.578264) (xy 331.970319 -96.526173)
			(xy 331.958193 -96.471736) (xy 331.954122 -96.416114) (xy 330.133632 -96.416114) (xy 330.113023 -96.460078)
			(xy 330.08225 -96.506591) (xy 330.045033 -96.548128) (xy 330.002165 -96.583803) (xy 329.954559 -96.612857)
			(xy 329.90323 -96.634669) (xy 329.849273 -96.648775) (xy 329.793836 -96.654875) (xy 329.738102 -96.652838)
			(xy 329.683259 -96.642708) (xy 329.630475 -96.624701) (xy 329.580875 -96.5992) (xy 329.535517 -96.566749)
			(xy 329.495368 -96.52804) (xy 329.461282 -96.483897) (xy 329.433986 -96.435262) (xy 329.414063 -96.383171)
			(xy 329.401937 -96.328734) (xy 329.397866 -96.273112) (xy 328.815422 -96.273112) (xy 328.8157 -96.288352)
			(xy 328.815191 -96.316238) (xy 328.807071 -96.371414) (xy 328.791003 -96.424821) (xy 328.767331 -96.475318)
			(xy 328.736558 -96.521831) (xy 328.699341 -96.563368) (xy 328.656473 -96.599043) (xy 328.608867 -96.628097)
			(xy 328.557538 -96.649909) (xy 328.503581 -96.664015) (xy 328.448144 -96.670115) (xy 328.39241 -96.668078)
			(xy 328.337567 -96.657948) (xy 328.284783 -96.639941) (xy 328.235183 -96.61444) (xy 328.189825 -96.581989)
			(xy 328.149676 -96.54328) (xy 328.11559 -96.499137) (xy 328.088294 -96.450502) (xy 328.068371 -96.398411)
			(xy 328.056245 -96.343974) (xy 328.052174 -96.288352) (xy 327.380654 -96.288352) (xy 327.382254 -96.293803)
			(xy 327.390011 -96.347749) (xy 327.390011 -96.402251) (xy 327.382254 -96.456197) (xy 327.3669 -96.50849)
			(xy 327.344259 -96.558066) (xy 327.314793 -96.603915) (xy 327.279103 -96.645104) (xy 327.237914 -96.680795)
			(xy 327.192064 -96.71026) (xy 327.142488 -96.7329) (xy 327.090195 -96.748255) (xy 327.036249 -96.756011)
			(xy 327.008998 -96.756474) (xy 326.982 -96.756022) (xy 326.92854 -96.748434) (xy 326.876685 -96.733381)
			(xy 326.827471 -96.711165) (xy 326.781883 -96.68223) (xy 326.740832 -96.647153) (xy 326.705138 -96.606637)
			(xy 326.675516 -96.561492) (xy 326.652558 -96.51262) (xy 326.636723 -96.460999) (xy 326.632062 -96.434402)
			(xy 326.630284 -96.423226) (xy 326.617838 -96.404684) (xy 326.540876 -96.35871) (xy 326.531025 -96.35351)
			(xy 326.508892 -96.351259) (xy 326.498204 -96.354392) (xy 326.49795 -96.354392) (xy 326.466617 -96.364986)
			(xy 326.402171 -96.379881) (xy 326.336458 -96.38742) (xy 326.303386 -96.38792) (xy 326.269034 -96.387409)
			(xy 326.200806 -96.379336) (xy 326.133991 -96.363338) (xy 326.069506 -96.339633) (xy 326.008236 -96.308548)
			(xy 325.951023 -96.27051) (xy 325.898653 -96.22604) (xy 325.874888 -96.20123) (xy 325.874634 -96.200976)
			(xy 325.867126 -96.193861) (xy 325.848134 -96.185722) (xy 325.837804 -96.185228) (xy 325.763128 -96.185228)
			(xy 325.752785 -96.185671) (xy 325.733772 -96.193812) (xy 325.726298 -96.200976) (xy 325.72579 -96.201484)
			(xy 325.702012 -96.226246) (xy 325.649668 -96.270667) (xy 325.592489 -96.308662) (xy 325.531258 -96.339709)
			(xy 325.466817 -96.363382) (xy 325.400049 -96.379357) (xy 325.331872 -96.387414) (xy 325.297546 -96.38792)
			(xy 325.264665 -96.387473) (xy 325.199316 -96.38011) (xy 325.135205 -96.365471) (xy 325.073137 -96.343741)
			(xy 325.013894 -96.315193) (xy 324.958224 -96.280187) (xy 324.906826 -96.239163) (xy 324.883272 -96.216216)
			(xy 324.11416 -95.447104) (xy 324.084188 -95.441008) (xy 324.069964 -95.447104) (xy 324.060829 -95.451306)
			(xy 324.046598 -95.465491) (xy 324.038893 -95.484047) (xy 324.038468 -95.494094) (xy 324.038468 -95.645732)
			(xy 324.038646 -95.651883) (xy 324.04161 -95.663824) (xy 324.04431 -95.669354) (xy 324.058134 -95.696886)
			(xy 324.077703 -95.7553) (xy 324.08764 -95.816098) (xy 324.088252 -95.8469) (xy 324.087766 -95.874151)
			(xy 324.08001 -95.928099) (xy 324.064655 -95.980394) (xy 324.042013 -96.029971) (xy 324.012547 -96.075821)
			(xy 323.976856 -96.117012) (xy 323.935665 -96.152703) (xy 323.889815 -96.182169) (xy 323.840238 -96.204811)
			(xy 323.787943 -96.220166) (xy 323.733995 -96.227922) (xy 323.679493 -96.227922) (xy 323.625545 -96.220166)
			(xy 323.57325 -96.204811) (xy 323.523673 -96.182169) (xy 323.477823 -96.152703) (xy 323.436632 -96.117012)
			(xy 323.400941 -96.075821) (xy 323.371475 -96.029971) (xy 323.348833 -95.980394) (xy 323.333478 -95.928099)
			(xy 323.325722 -95.874151) (xy 323.325236 -95.8469) (xy 323.325848 -95.816097) (xy 323.335772 -95.755296)
			(xy 323.355345 -95.696882) (xy 323.369178 -95.669354) (xy 323.371906 -95.663836) (xy 323.374855 -95.651886)
			(xy 323.37502 -95.645732) (xy 323.37502 -95.163894) (xy 323.374619 -95.153822) (xy 323.366883 -95.135223)
			(xy 323.360034 -95.127826) (xy 322.612258 -94.38005) (xy 322.605008 -94.373469) (xy 322.586999 -94.365835)
			(xy 322.567441 -94.365516) (xy 322.558156 -94.36862) (xy 322.471288 -94.402148) (xy 322.462348 -94.406116)
			(xy 322.448053 -94.419434) (xy 322.43976 -94.437123) (xy 322.438776 -94.446852) (xy 322.438776 -94.44736)
			(xy 322.436879 -94.475663) (xy 322.425773 -94.53129) (xy 322.406551 -94.584658) (xy 322.379638 -94.63459)
			(xy 322.345626 -94.679986) (xy 322.305266 -94.719845) (xy 322.259448 -94.753286) (xy 322.209182 -94.779573)
			(xy 322.155578 -94.798125) (xy 322.099817 -94.808535) (xy 322.071492 -94.810072) (xy 322.059574 -94.811143)
			(xy 322.038642 -94.822675) (xy 322.03136 -94.83217) (xy 321.985386 -94.899734) (xy 321.979198 -94.91006)
			(xy 321.976146 -94.933906) (xy 321.979544 -94.945454) (xy 321.989595 -94.976042) (xy 322.000446 -95.039502)
			(xy 322.001134 -95.071692) (xy 322.001134 -95.0722) (xy 322.000692 -95.098773) (xy 321.993329 -95.151405)
			(xy 321.97873 -95.202506) (xy 321.957179 -95.251086) (xy 321.929092 -95.296203) (xy 321.895015 -95.336985)
			(xy 321.855606 -95.372641) (xy 321.811629 -95.402481) (xy 321.763935 -95.425927) (xy 321.713448 -95.442526)
			(xy 321.661146 -95.451955) (xy 321.634612 -95.453454) (xy 321.62115 -95.453962) (xy 321.59829 -95.468186)
			(xy 321.550284 -95.556578) (xy 321.546351 -95.564461) (xy 321.543665 -95.581863) (xy 321.547076 -95.599137)
			(xy 321.5513 -95.60687) (xy 321.564012 -95.629099) (xy 321.584058 -95.676218) (xy 321.597628 -95.725593)
			(xy 321.604478 -95.776339) (xy 321.604894 -95.801942) (xy 321.857368 -95.801942) (xy 321.861439 -95.74632)
			(xy 321.873565 -95.691883) (xy 321.893488 -95.639792) (xy 321.920784 -95.591157) (xy 321.95487 -95.547014)
			(xy 321.995019 -95.508305) (xy 322.040377 -95.475854) (xy 322.089977 -95.450353) (xy 322.142761 -95.432346)
			(xy 322.197604 -95.422216) (xy 322.253338 -95.420179) (xy 322.308775 -95.426279) (xy 322.362732 -95.440385)
			(xy 322.414061 -95.462197) (xy 322.461667 -95.491251) (xy 322.504535 -95.526926) (xy 322.541752 -95.568463)
			(xy 322.572525 -95.614976) (xy 322.596197 -95.665473) (xy 322.612265 -95.71888) (xy 322.620385 -95.774056)
			(xy 322.620894 -95.801942) (xy 322.620385 -95.829828) (xy 322.612265 -95.885004) (xy 322.596197 -95.938411)
			(xy 322.572525 -95.988908) (xy 322.541752 -96.035421) (xy 322.504535 -96.076958) (xy 322.461667 -96.112633)
			(xy 322.414061 -96.141687) (xy 322.362732 -96.163499) (xy 322.308775 -96.177605) (xy 322.253338 -96.183705)
			(xy 322.197604 -96.181668) (xy 322.142761 -96.171538) (xy 322.089977 -96.153531) (xy 322.040377 -96.12803)
			(xy 321.995019 -96.095579) (xy 321.95487 -96.05687) (xy 321.920784 -96.012727) (xy 321.893488 -95.964092)
			(xy 321.873565 -95.912001) (xy 321.861439 -95.857564) (xy 321.857368 -95.801942) (xy 321.604894 -95.801942)
			(xy 321.604408 -95.829193) (xy 321.596652 -95.883141) (xy 321.581297 -95.935436) (xy 321.558655 -95.985013)
			(xy 321.529189 -96.030863) (xy 321.493498 -96.072054) (xy 321.452307 -96.107745) (xy 321.406457 -96.137211)
			(xy 321.35688 -96.159853) (xy 321.304585 -96.175208) (xy 321.250637 -96.182964) (xy 321.196135 -96.182964)
			(xy 321.142187 -96.175208) (xy 321.089892 -96.159853) (xy 321.040315 -96.137211) (xy 320.994465 -96.107745)
			(xy 320.953274 -96.072054) (xy 320.917583 -96.030863) (xy 320.888117 -95.985013) (xy 320.865475 -95.935436)
			(xy 320.85012 -95.883141) (xy 320.842364 -95.829193) (xy 320.841878 -95.801942) (xy 320.842349 -95.775372)
			(xy 320.849719 -95.722744) (xy 320.864321 -95.671649) (xy 320.885873 -95.623075) (xy 320.913957 -95.577961)
			(xy 320.948031 -95.537182) (xy 320.987435 -95.501527) (xy 321.031406 -95.471686) (xy 321.079092 -95.448235)
			(xy 321.129572 -95.43163) (xy 321.181868 -95.422192) (xy 321.2084 -95.420688) (xy 321.221862 -95.42018)
			(xy 321.244722 -95.405956) (xy 321.292728 -95.317564) (xy 321.296628 -95.309666) (xy 321.299324 -95.292274)
			(xy 321.295928 -95.275005) (xy 321.291712 -95.267272) (xy 321.278978 -95.245055) (xy 321.258937 -95.197932)
			(xy 321.245374 -95.148553) (xy 321.23853 -95.097804) (xy 321.238118 -95.0722) (xy 321.238564 -95.045572)
			(xy 321.24597 -94.992835) (xy 321.26064 -94.94164) (xy 321.282288 -94.892984) (xy 321.310493 -94.847811)
			(xy 321.344706 -94.807) (xy 321.384263 -94.771344) (xy 321.428395 -94.741536) (xy 321.476243 -94.718157)
			(xy 321.526879 -94.701659) (xy 321.579316 -94.692364) (xy 321.60591 -94.690946) (xy 321.617826 -94.689869)
			(xy 321.638758 -94.678341) (xy 321.646042 -94.668848) (xy 321.692016 -94.601284) (xy 321.698193 -94.590952)
			(xy 321.701252 -94.567111) (xy 321.697858 -94.555564) (xy 321.687812 -94.524974) (xy 321.676957 -94.461516)
			(xy 321.676268 -94.429326) (xy 321.676268 -94.428818) (xy 321.676732 -94.402403) (xy 321.684033 -94.350079)
			(xy 321.698483 -94.299263) (xy 321.719806 -94.250926) (xy 321.747594 -94.205994) (xy 321.781316 -94.165326)
			(xy 321.820327 -94.129699) (xy 321.86388 -94.099796) (xy 321.911142 -94.076188) (xy 321.961209 -94.059326)
			(xy 322.013125 -94.049534) (xy 322.039488 -94.047818) (xy 322.039742 -94.047818) (xy 322.049484 -94.046875)
			(xy 322.0672 -94.03859) (xy 322.08053 -94.024277) (xy 322.084446 -94.015306) (xy 322.117974 -93.928692)
			(xy 322.121084 -93.919362) (xy 322.120789 -93.899718) (xy 322.113156 -93.881614) (xy 322.106544 -93.874336)
			(xy 321.890644 -93.65869) (xy 321.883224 -93.651875) (xy 321.86464 -93.644141) (xy 321.854576 -93.643704)
			(xy 312.675016 -93.643704) (xy 312.664028 -93.644217) (xy 312.644016 -93.653287) (xy 312.636408 -93.66123)
			(xy 312.57875 -93.728032) (xy 312.572654 -93.749114) (xy 312.574432 -93.760036) (xy 312.576344 -93.773991)
			(xy 312.578382 -93.802086) (xy 312.578496 -93.81617) (xy 312.578017 -93.843423) (xy 312.570264 -93.897374)
			(xy 312.554911 -93.949672) (xy 312.532271 -93.999253) (xy 312.502805 -94.045107) (xy 312.467113 -94.0863)
			(xy 312.425921 -94.121994) (xy 312.380069 -94.151462) (xy 312.330489 -94.174104) (xy 312.278191 -94.18946)
			(xy 312.224241 -94.197215) (xy 312.196988 -94.197678) (xy 312.167644 -94.197169) (xy 312.109647 -94.18818)
			(xy 312.053712 -94.170414) (xy 312.001157 -94.144293) (xy 311.953222 -94.110431) (xy 311.911039 -94.069627)
			(xy 311.875601 -94.022845) (xy 311.8612 -93.997272) (xy 311.854596 -93.984826) (xy 311.830212 -93.970602)
			(xy 311.711848 -93.971618) (xy 311.687972 -93.986604) (xy 311.681368 -93.999304) (xy 311.669027 -94.022393)
			(xy 311.638994 -94.065275) (xy 311.603381 -94.103651) (xy 311.562859 -94.136799) (xy 311.518187 -94.164099)
			(xy 311.470203 -94.185037) (xy 311.419808 -94.199221) (xy 311.367947 -94.206386) (xy 311.34177 -94.206822)
			(xy 311.313864 -94.206316) (xy 311.258646 -94.198198) (xy 311.205198 -94.182126) (xy 311.154661 -94.158442)
			(xy 311.108111 -94.12765) (xy 311.066542 -94.090408) (xy 311.030839 -94.04751) (xy 311.015888 -94.023942)
			(xy 311.009284 -94.01302) (xy 310.987694 -94.00032) (xy 310.890412 -93.996002) (xy 310.87808 -93.996259)
			(xy 310.855791 -94.006726) (xy 310.84774 -94.016068) (xy 310.847232 -94.016576) (xy 310.829131 -94.04013)
			(xy 310.786855 -94.08186) (xy 310.738616 -94.116523) (xy 310.685582 -94.143282) (xy 310.629038 -94.161487)
			(xy 310.570355 -94.170697) (xy 310.540654 -94.171262) (xy 310.5134 -94.170865) (xy 310.459446 -94.163101)
			(xy 310.407147 -94.147738) (xy 310.357567 -94.125088) (xy 310.311714 -94.095612) (xy 310.270523 -94.059912)
			(xy 310.234832 -94.018712) (xy 310.205368 -93.972853) (xy 310.18273 -93.923267) (xy 310.16738 -93.870964)
			(xy 310.159629 -93.817009) (xy 310.159146 -93.789754) (xy 310.159696 -93.760788) (xy 310.168461 -93.703523)
			(xy 310.185782 -93.648241) (xy 310.211261 -93.596213) (xy 310.244313 -93.548635) (xy 310.284178 -93.5066)
			(xy 310.329939 -93.471075) (xy 310.35498 -93.456506) (xy 310.355234 -93.456506) (xy 310.365215 -93.450232)
			(xy 310.378453 -93.430755) (xy 310.380634 -93.419168) (xy 310.39181 -93.338904) (xy 310.39289 -93.327148)
			(xy 310.385469 -93.304766) (xy 310.377586 -93.295978) (xy 309.935372 -92.85351) (xy 309.927975 -92.846667)
			(xy 309.909373 -92.838948) (xy 309.899304 -92.838524) (xy 304.83302 -92.838524) (xy 304.823041 -92.838941)
			(xy 304.804571 -92.846495) (xy 304.790368 -92.860514) (xy 304.78603 -92.869512) (xy 304.743612 -92.970096)
			(xy 304.7492 -93.000068) (xy 304.759868 -93.01099) (xy 304.790937 -93.043845) (xy 304.847317 -93.114547)
			(xy 304.896645 -93.190338) (xy 304.938463 -93.270518) (xy 304.972385 -93.354345) (xy 304.998096 -93.441043)
			(xy 305.015359 -93.52981) (xy 305.024014 -93.619825) (xy 305.024536 -93.66504) (xy 305.024024 -93.710115)
			(xy 305.01546 -93.799855) (xy 304.998338 -93.888363) (xy 304.97691 -93.96095) (xy 308.78094 -93.96095)
			(xy 308.785011 -93.905328) (xy 308.797137 -93.850891) (xy 308.81706 -93.7988) (xy 308.844356 -93.750165)
			(xy 308.878442 -93.706022) (xy 308.918591 -93.667313) (xy 308.963949 -93.634862) (xy 309.013549 -93.609361)
			(xy 309.066333 -93.591354) (xy 309.121176 -93.581224) (xy 309.17691 -93.579187) (xy 309.232347 -93.585287)
			(xy 309.286304 -93.599393) (xy 309.337633 -93.621205) (xy 309.385239 -93.650259) (xy 309.428107 -93.685934)
			(xy 309.465324 -93.727471) (xy 309.496097 -93.773984) (xy 309.519769 -93.824481) (xy 309.535837 -93.877888)
			(xy 309.543957 -93.933064) (xy 309.544466 -93.96095) (xy 309.543957 -93.988836) (xy 309.535837 -94.044012)
			(xy 309.519769 -94.097419) (xy 309.496097 -94.147916) (xy 309.465324 -94.194429) (xy 309.428107 -94.235966)
			(xy 309.385239 -94.271641) (xy 309.337633 -94.300695) (xy 309.286304 -94.322507) (xy 309.232347 -94.336613)
			(xy 309.17691 -94.342713) (xy 309.121176 -94.340676) (xy 309.066333 -94.330546) (xy 309.013549 -94.312539)
			(xy 308.963949 -94.287038) (xy 308.918591 -94.254587) (xy 308.878442 -94.215878) (xy 308.844356 -94.171735)
			(xy 308.81706 -94.1231) (xy 308.797137 -94.071009) (xy 308.785011 -94.016572) (xy 308.78094 -93.96095)
			(xy 304.97691 -93.96095) (xy 304.972815 -93.974823) (xy 304.956464 -94.01683) (xy 304.952146 -94.027752)
			(xy 304.95367 -94.051374) (xy 305.006756 -94.14129) (xy 305.026568 -94.154244) (xy 305.038252 -94.155768)
			(xy 305.084224 -94.161952) (xy 305.174958 -94.181261) (xy 305.263675 -94.208372) (xy 305.349704 -94.243079)
			(xy 305.432397 -94.285121) (xy 305.511129 -94.33418) (xy 305.585307 -94.389887) (xy 305.654371 -94.451821)
			(xy 305.717799 -94.519514) (xy 305.775114 -94.592457) (xy 305.825883 -94.670098) (xy 305.869722 -94.751852)
			(xy 305.906302 -94.837102) (xy 305.935345 -94.925204) (xy 305.956634 -95.015495) (xy 305.970006 -95.107293)
			(xy 305.975362 -95.199904) (xy 305.972661 -95.292631) (xy 305.961923 -95.384774) (xy 305.94323 -95.475637)
			(xy 305.916722 -95.564536) (xy 305.882599 -95.650798) (xy 305.841119 -95.733774) (xy 305.792595 -95.812838)
			(xy 305.737393 -95.887392) (xy 305.675929 -95.956874) (xy 305.641424 -95.989648) (xy 307.763924 -95.989648)
			(xy 307.767995 -95.934026) (xy 307.780121 -95.879589) (xy 307.800044 -95.827498) (xy 307.82734 -95.778863)
			(xy 307.861426 -95.73472) (xy 307.901575 -95.696011) (xy 307.946933 -95.66356) (xy 307.996533 -95.638059)
			(xy 308.049317 -95.620052) (xy 308.10416 -95.609922) (xy 308.159894 -95.607885) (xy 308.215331 -95.613985)
			(xy 308.269288 -95.628091) (xy 308.320617 -95.649903) (xy 308.368223 -95.678957) (xy 308.411091 -95.714632)
			(xy 308.448308 -95.756169) (xy 308.479081 -95.802682) (xy 308.502753 -95.853179) (xy 308.518821 -95.906586)
			(xy 308.526941 -95.961762) (xy 308.52745 -95.989648) (xy 310.369456 -95.989648) (xy 310.373527 -95.934026)
			(xy 310.385653 -95.879589) (xy 310.405576 -95.827498) (xy 310.432872 -95.778863) (xy 310.466958 -95.73472)
			(xy 310.507107 -95.696011) (xy 310.552465 -95.66356) (xy 310.602065 -95.638059) (xy 310.654849 -95.620052)
			(xy 310.709692 -95.609922) (xy 310.765426 -95.607885) (xy 310.820863 -95.613985) (xy 310.87482 -95.628091)
			(xy 310.926149 -95.649903) (xy 310.973755 -95.678957) (xy 311.016623 -95.714632) (xy 311.05384 -95.756169)
			(xy 311.084613 -95.802682) (xy 311.108285 -95.853179) (xy 311.124353 -95.906586) (xy 311.132473 -95.961762)
			(xy 311.132982 -95.989648) (xy 311.132473 -96.017534) (xy 311.124353 -96.07271) (xy 311.108285 -96.126117)
			(xy 311.084613 -96.176614) (xy 311.05384 -96.223127) (xy 311.016623 -96.264664) (xy 310.973755 -96.300339)
			(xy 310.926149 -96.329393) (xy 310.87482 -96.351205) (xy 310.820863 -96.365311) (xy 310.765426 -96.371411)
			(xy 310.709692 -96.369374) (xy 310.654849 -96.359244) (xy 310.602065 -96.341237) (xy 310.552465 -96.315736)
			(xy 310.507107 -96.283285) (xy 310.466958 -96.244576) (xy 310.432872 -96.200433) (xy 310.405576 -96.151798)
			(xy 310.385653 -96.099707) (xy 310.373527 -96.04527) (xy 310.369456 -95.989648) (xy 308.52745 -95.989648)
			(xy 308.526941 -96.017534) (xy 308.518821 -96.07271) (xy 308.502753 -96.126117) (xy 308.479081 -96.176614)
			(xy 308.448308 -96.223127) (xy 308.411091 -96.264664) (xy 308.368223 -96.300339) (xy 308.320617 -96.329393)
			(xy 308.269288 -96.351205) (xy 308.215331 -96.365311) (xy 308.159894 -96.371411) (xy 308.10416 -96.369374)
			(xy 308.049317 -96.359244) (xy 307.996533 -96.341237) (xy 307.946933 -96.315736) (xy 307.901575 -96.283285)
			(xy 307.861426 -96.244576) (xy 307.82734 -96.200433) (xy 307.800044 -96.151798) (xy 307.780121 -96.099707)
			(xy 307.767995 -96.04527) (xy 307.763924 -95.989648) (xy 305.641424 -95.989648) (xy 305.608667 -96.020761)
			(xy 305.536115 -96.078569) (xy 305.45882 -96.129864) (xy 305.377366 -96.174257) (xy 305.292366 -96.211414)
			(xy 305.204463 -96.241054) (xy 305.114318 -96.262955) (xy 305.022614 -96.27695) (xy 304.930041 -96.282934)
			(xy 304.837297 -96.280862) (xy 304.745084 -96.270749) (xy 304.654096 -96.252673) (xy 304.565019 -96.226768)
			(xy 304.478527 -96.193232) (xy 304.395272 -96.152316) (xy 304.315881 -96.104329) (xy 304.240954 -96.049634)
			(xy 304.171056 -95.988643) (xy 304.106715 -95.921816) (xy 304.048416 -95.849658) (xy 303.996598 -95.772713)
			(xy 303.951653 -95.691562) (xy 303.91392 -95.606816) (xy 303.883684 -95.519116) (xy 303.861173 -95.429122)
			(xy 303.846556 -95.337515) (xy 303.839944 -95.244984) (xy 303.841386 -95.152229) (xy 303.850873 -95.059949)
			(xy 303.868332 -94.96884) (xy 303.893631 -94.87959) (xy 303.92658 -94.792873) (xy 303.946306 -94.75089)
			(xy 303.951894 -94.739206) (xy 303.950624 -94.713044) (xy 303.897792 -94.629224) (xy 303.892913 -94.622127)
			(xy 303.879456 -94.611397) (xy 303.863217 -94.605696) (xy 303.854612 -94.605348) (xy 302.230282 -94.605348)
			(xy 302.186835 -94.604884) (xy 302.100313 -94.596864) (xy 302.014899 -94.580893) (xy 301.931325 -94.557108)
			(xy 301.850301 -94.525712) (xy 301.772521 -94.486973) (xy 301.698648 -94.441221) (xy 301.629312 -94.388847)
			(xy 301.565105 -94.330299) (xy 301.506575 -94.266074) (xy 301.454222 -94.196723) (xy 301.408492 -94.122836)
			(xy 301.369776 -94.045044) (xy 301.338404 -93.964012) (xy 301.314643 -93.88043) (xy 301.298698 -93.795012)
			(xy 301.290703 -93.708487) (xy 301.290228 -93.66504) (xy 301.290761 -93.619827) (xy 301.299437 -93.529817)
			(xy 301.316714 -93.441057) (xy 301.342431 -93.354364) (xy 301.376351 -93.270541) (xy 301.418162 -93.190361)
			(xy 301.467475 -93.114564) (xy 301.523837 -93.043852) (xy 301.554896 -93.01099) (xy 301.565564 -93.000068)
			(xy 301.571152 -92.970096) (xy 301.528734 -92.869512) (xy 301.524382 -92.860521) (xy 301.510194 -92.846494)
			(xy 301.491722 -92.838959) (xy 301.481744 -92.838524) (xy 282.207462 -92.838524) (xy 282.197412 -92.838906)
			(xy 282.178853 -92.84663) (xy 282.164678 -92.860882) (xy 282.160472 -92.87002) (xy 282.11907 -92.97162)
			(xy 282.125166 -93.001846) (xy 282.136342 -93.012768) (xy 282.168338 -93.04498) (xy 282.226462 -93.114736)
			(xy 282.277392 -93.189905) (xy 282.320627 -93.269749) (xy 282.355741 -93.353482) (xy 282.382391 -93.440281)
			(xy 282.400312 -93.529292) (xy 282.40933 -93.619641) (xy 282.4099 -93.66504) (xy 282.409424 -93.707542)
			(xy 282.401536 -93.792178) (xy 282.38583 -93.875718) (xy 282.362444 -93.957442) (xy 282.331578 -94.036643)
			(xy 282.293498 -94.11264) (xy 282.248534 -94.184777) (xy 282.197071 -94.252432) (xy 282.139555 -94.315023)
			(xy 282.076482 -94.372008) (xy 282.008394 -94.422897) (xy 281.93588 -94.467251) (xy 281.859564 -94.504687)
			(xy 281.780105 -94.534883) (xy 281.698187 -94.557578) (xy 281.614517 -94.572577) (xy 281.572208 -94.576646)
			(xy 281.559676 -94.578328) (xy 281.538484 -94.592061) (xy 281.531822 -94.602808) (xy 281.484832 -94.687898)
			(xy 281.484578 -94.713044) (xy 281.49042 -94.724474) (xy 281.511366 -94.766034) (xy 281.546798 -94.852101)
			(xy 281.574602 -94.940926) (xy 281.594568 -95.031834) (xy 281.606544 -95.124135) (xy 281.610438 -95.217129)
			(xy 281.606222 -95.310108) (xy 281.593927 -95.402367) (xy 281.573646 -95.493206) (xy 281.545534 -95.581934)
			(xy 281.509804 -95.667877) (xy 281.466728 -95.750384) (xy 281.416632 -95.828827) (xy 281.359897 -95.902611)
			(xy 281.296954 -95.971176) (xy 281.22828 -96.034) (xy 281.154398 -96.090607) (xy 281.075868 -96.140567)
			(xy 280.993287 -96.183501) (xy 280.907282 -96.219082) (xy 280.818505 -96.24704) (xy 280.727632 -96.267163)
			(xy 280.635351 -96.279298) (xy 280.542365 -96.283354) (xy 280.449379 -96.279298) (xy 280.357098 -96.267163)
			(xy 280.266225 -96.24704) (xy 280.177448 -96.219082) (xy 280.091443 -96.183501) (xy 280.008862 -96.140567)
			(xy 279.930332 -96.090607) (xy 279.85645 -96.034) (xy 279.787776 -95.971176) (xy 279.724833 -95.902611)
			(xy 279.668098 -95.828827) (xy 279.618002 -95.750384) (xy 279.574926 -95.667877) (xy 279.539196 -95.581934)
			(xy 279.511084 -95.493206) (xy 279.490803 -95.402367) (xy 279.478508 -95.310108) (xy 279.474292 -95.217129)
			(xy 279.478186 -95.124135) (xy 279.490162 -95.031834) (xy 279.510128 -94.940926) (xy 279.537932 -94.852101)
			(xy 279.573364 -94.766034) (xy 279.59431 -94.724474) (xy 279.599454 -94.713035) (xy 279.599059 -94.687988)
			(xy 279.593548 -94.676722) (xy 279.552908 -94.602808) (xy 279.546249 -94.592058) (xy 279.525055 -94.578326)
			(xy 279.512522 -94.576646) (xy 279.470212 -94.572648) (xy 279.386557 -94.557627) (xy 279.304656 -94.534911)
			(xy 279.225214 -94.504698) (xy 279.148917 -94.467246) (xy 279.076423 -94.42288) (xy 279.008355 -94.371982)
			(xy 278.945302 -94.31499) (xy 278.887806 -94.252396) (xy 278.836363 -94.184739) (xy 278.791417 -94.112603)
			(xy 278.753355 -94.036609) (xy 278.722506 -93.957412) (xy 278.699134 -93.875696) (xy 278.683442 -93.792164)
			(xy 278.675565 -93.707537) (xy 278.675084 -93.66504) (xy 278.675624 -93.61964) (xy 278.684636 -93.529288)
			(xy 278.702556 -93.440274) (xy 278.729207 -93.353473) (xy 278.764328 -93.26974) (xy 278.807571 -93.189898)
			(xy 278.858513 -93.114734) (xy 278.916651 -93.044987) (xy 278.948642 -93.012768) (xy 278.959818 -93.001846)
			(xy 278.965914 -92.97162) (xy 278.924512 -92.87002) (xy 278.920275 -92.860903) (xy 278.906109 -92.846666)
			(xy 278.887564 -92.838953) (xy 278.877522 -92.838524) (xy 277.755096 -92.838524) (xy 277.745026 -92.838941)
			(xy 277.726428 -92.846667) (xy 277.719028 -92.85351) (xy 277.297896 -93.274896) (xy 277.279097 -93.292898)
			(xy 277.236988 -93.323482) (xy 277.190619 -93.347115) (xy 277.141128 -93.363217) (xy 277.08973 -93.371392)
			(xy 277.063708 -93.371924) (xy 269.890748 -93.371924) (xy 269.879755 -93.372393) (xy 269.859742 -93.381493)
			(xy 269.85214 -93.38945) (xy 269.794736 -93.455998) (xy 269.78864 -93.47708) (xy 269.790164 -93.488002)
			(xy 269.791942 -93.501329) (xy 269.793847 -93.528151) (xy 269.793974 -93.541596) (xy 269.793974 -93.542104)
			(xy 269.793488 -93.569355) (xy 269.785732 -93.623303) (xy 269.770377 -93.675598) (xy 269.747735 -93.725175)
			(xy 269.718269 -93.771025) (xy 269.682578 -93.812216) (xy 269.641387 -93.847907) (xy 269.595537 -93.877373)
			(xy 269.54596 -93.900015) (xy 269.493665 -93.91537) (xy 269.439717 -93.923126) (xy 269.385215 -93.923126)
			(xy 269.331267 -93.91537) (xy 269.278972 -93.900015) (xy 269.229395 -93.877373) (xy 269.183545 -93.847907)
			(xy 269.142354 -93.812216) (xy 269.106663 -93.771025) (xy 269.077197 -93.725175) (xy 269.054555 -93.675598)
			(xy 269.0392 -93.623303) (xy 269.031444 -93.569355) (xy 269.030958 -93.542104) (xy 269.030958 -93.541596)
			(xy 269.031073 -93.528151) (xy 269.032983 -93.501329) (xy 269.034768 -93.488002) (xy 269.036292 -93.47708)
			(xy 269.030196 -93.455998) (xy 268.972792 -93.38945) (xy 268.96521 -93.381472) (xy 268.945182 -93.372395)
			(xy 268.934184 -93.371924) (xy 268.02715 -93.371924) (xy 268.017083 -93.372369) (xy 267.998485 -93.380075)
			(xy 267.991082 -93.38691) (xy 267.82395 -93.554296) (xy 267.805171 -93.57232) (xy 267.763057 -93.602901)
			(xy 267.716682 -93.62653) (xy 267.667187 -93.642627) (xy 267.615785 -93.650796) (xy 267.589762 -93.651324)
			(xy 265.269726 -93.651324) (xy 265.259657 -93.651757) (xy 265.241059 -93.659471) (xy 265.233658 -93.66631)
			(xy 264.861802 -94.038166) (xy 264.854985 -94.045584) (xy 264.847252 -94.064169) (xy 264.846816 -94.074234)
			(xy 264.846816 -95.228947) (xy 276.740918 -95.228947) (xy 276.740918 -95.174453) (xy 276.748673 -95.120513)
			(xy 276.764025 -95.068226) (xy 276.786662 -95.018656) (xy 276.816123 -94.972811) (xy 276.851808 -94.931626)
			(xy 276.892991 -94.895938) (xy 276.938833 -94.866475) (xy 276.988402 -94.843834) (xy 277.040688 -94.828479)
			(xy 277.094627 -94.82072) (xy 277.121874 -94.820232) (xy 277.147583 -94.820672) (xy 277.198537 -94.827565)
			(xy 277.248103 -94.841241) (xy 277.295381 -94.861454) (xy 277.339515 -94.887836) (xy 277.359872 -94.903544)
			(xy 277.369524 -94.911164) (xy 277.392892 -94.91599) (xy 277.496016 -94.88805) (xy 277.513796 -94.871794)
			(xy 277.518114 -94.860364) (xy 277.530958 -94.828916) (xy 277.566093 -94.770786) (xy 277.587964 -94.744794)
			(xy 277.594241 -94.73696) (xy 277.600777 -94.718002) (xy 277.600664 -94.707964) (xy 277.5966 -94.637098)
			(xy 277.59552 -94.627208) (xy 277.586904 -94.609299) (xy 277.579836 -94.6023) (xy 277.560399 -94.584135)
			(xy 277.526279 -94.543315) (xy 277.498156 -94.498155) (xy 277.476573 -94.449529) (xy 277.461948 -94.398377)
			(xy 277.454565 -94.345691) (xy 277.454106 -94.31909) (xy 277.454592 -94.291839) (xy 277.462348 -94.237891)
			(xy 277.477703 -94.185596) (xy 277.500345 -94.136019) (xy 277.529811 -94.090169) (xy 277.565502 -94.048978)
			(xy 277.606693 -94.013287) (xy 277.652543 -93.983821) (xy 277.70212 -93.961179) (xy 277.754415 -93.945824)
			(xy 277.808363 -93.938068) (xy 277.862865 -93.938068) (xy 277.916813 -93.945824) (xy 277.969108 -93.961179)
			(xy 278.018685 -93.983821) (xy 278.064535 -94.013287) (xy 278.105726 -94.048978) (xy 278.141417 -94.090169)
			(xy 278.170883 -94.136019) (xy 278.193525 -94.185596) (xy 278.20888 -94.237891) (xy 278.216636 -94.291839)
			(xy 278.217122 -94.31909) (xy 278.216628 -94.346622) (xy 278.208707 -94.401114) (xy 278.193043 -94.453904)
			(xy 278.169959 -94.503896) (xy 278.139935 -94.550056) (xy 278.122126 -94.571058) (xy 278.11587 -94.578906)
			(xy 278.109322 -94.597853) (xy 278.109426 -94.607888) (xy 278.11349 -94.678754) (xy 278.114548 -94.688648)
			(xy 278.123179 -94.706555) (xy 278.130254 -94.713552) (xy 278.149666 -94.731743) (xy 278.183788 -94.772557)
			(xy 278.211915 -94.817711) (xy 278.233503 -94.866333) (xy 278.248132 -94.91748) (xy 278.255522 -94.970163)
			(xy 278.255984 -94.996762) (xy 278.255509 -95.024015) (xy 278.247757 -95.077967) (xy 278.232404 -95.130266)
			(xy 278.209765 -95.179847) (xy 278.180298 -95.225702) (xy 278.144606 -95.266896) (xy 278.103413 -95.30259)
			(xy 278.05756 -95.332058) (xy 278.007979 -95.3547) (xy 277.95568 -95.370054) (xy 277.901729 -95.377808)
			(xy 277.874476 -95.37827) (xy 277.848766 -95.377857) (xy 277.797811 -95.370958) (xy 277.748245 -95.357275)
			(xy 277.700967 -95.337056) (xy 277.656834 -95.310668) (xy 277.636478 -95.294958) (xy 277.626826 -95.287338)
			(xy 277.603458 -95.282512) (xy 277.500334 -95.310452) (xy 277.482554 -95.326708) (xy 277.478236 -95.338138)
			(xy 277.467422 -95.364786) (xy 277.439028 -95.414792) (xy 277.403452 -95.459972) (xy 277.361501 -95.499304)
			(xy 277.314124 -95.531896) (xy 277.262393 -95.557012) (xy 277.20748 -95.574082) (xy 277.150627 -95.582721)
			(xy 277.121874 -95.583248) (xy 277.094627 -95.58268) (xy 277.040688 -95.574921) (xy 276.988402 -95.559566)
			(xy 276.938833 -95.536925) (xy 276.892991 -95.507462) (xy 276.851808 -95.471774) (xy 276.816123 -95.430589)
			(xy 276.786662 -95.384744) (xy 276.764025 -95.335174) (xy 276.748673 -95.282887) (xy 276.740918 -95.228947)
			(xy 264.846816 -95.228947) (xy 264.846816 -96.1644) (xy 269.425418 -96.1644) (xy 269.429489 -96.108778)
			(xy 269.441615 -96.054341) (xy 269.461538 -96.00225) (xy 269.488834 -95.953615) (xy 269.52292 -95.909472)
			(xy 269.563069 -95.870763) (xy 269.608427 -95.838312) (xy 269.658027 -95.812811) (xy 269.710811 -95.794804)
			(xy 269.765654 -95.784674) (xy 269.821388 -95.782637) (xy 269.876825 -95.788737) (xy 269.930782 -95.802843)
			(xy 269.982111 -95.824655) (xy 270.029717 -95.853709) (xy 270.072585 -95.889384) (xy 270.109802 -95.930921)
			(xy 270.140575 -95.977434) (xy 270.164247 -96.027931) (xy 270.180315 -96.081338) (xy 270.188435 -96.136514)
			(xy 270.188944 -96.1644) (xy 270.188435 -96.192286) (xy 270.180315 -96.247462) (xy 270.164247 -96.300869)
			(xy 270.140575 -96.351366) (xy 270.109802 -96.397879) (xy 270.072585 -96.439416) (xy 270.029717 -96.475091)
			(xy 269.982111 -96.504145) (xy 269.930782 -96.525957) (xy 269.876825 -96.540063) (xy 269.821388 -96.546163)
			(xy 269.765654 -96.544126) (xy 269.710811 -96.533996) (xy 269.658027 -96.515989) (xy 269.608427 -96.490488)
			(xy 269.563069 -96.458037) (xy 269.52292 -96.419328) (xy 269.488834 -96.375185) (xy 269.461538 -96.32655)
			(xy 269.441615 -96.274459) (xy 269.429489 -96.220022) (xy 269.425418 -96.1644) (xy 264.846816 -96.1644)
			(xy 264.846816 -97.1804) (xy 269.425418 -97.1804) (xy 269.429489 -97.124778) (xy 269.441615 -97.070341)
			(xy 269.461538 -97.01825) (xy 269.488834 -96.969615) (xy 269.52292 -96.925472) (xy 269.563069 -96.886763)
			(xy 269.608427 -96.854312) (xy 269.658027 -96.828811) (xy 269.710811 -96.810804) (xy 269.765654 -96.800674)
			(xy 269.821388 -96.798637) (xy 269.876825 -96.804737) (xy 269.930782 -96.818843) (xy 269.982111 -96.840655)
			(xy 270.029717 -96.869709) (xy 270.072585 -96.905384) (xy 270.109802 -96.946921) (xy 270.140575 -96.993434)
			(xy 270.164247 -97.043931) (xy 270.167784 -97.055686) (xy 283.805374 -97.055686) (xy 283.809445 -97.000064)
			(xy 283.821571 -96.945627) (xy 283.841494 -96.893536) (xy 283.86879 -96.844901) (xy 283.902876 -96.800758)
			(xy 283.943025 -96.762049) (xy 283.988383 -96.729598) (xy 284.037983 -96.704097) (xy 284.090767 -96.68609)
			(xy 284.14561 -96.67596) (xy 284.201344 -96.673923) (xy 284.256781 -96.680023) (xy 284.310738 -96.694129)
			(xy 284.362067 -96.715941) (xy 284.409673 -96.744995) (xy 284.452541 -96.78067) (xy 284.489758 -96.822207)
			(xy 284.520531 -96.86872) (xy 284.535663 -96.901) (xy 301.521874 -96.901) (xy 301.525945 -96.845378)
			(xy 301.538071 -96.790941) (xy 301.557994 -96.73885) (xy 301.58529 -96.690215) (xy 301.619376 -96.646072)
			(xy 301.659525 -96.607363) (xy 301.704883 -96.574912) (xy 301.754483 -96.549411) (xy 301.807267 -96.531404)
			(xy 301.86211 -96.521274) (xy 301.917844 -96.519237) (xy 301.973281 -96.525337) (xy 302.027238 -96.539443)
			(xy 302.078567 -96.561255) (xy 302.126173 -96.590309) (xy 302.169041 -96.625984) (xy 302.206258 -96.667521)
			(xy 302.237031 -96.714034) (xy 302.260703 -96.764531) (xy 302.276771 -96.817938) (xy 302.284891 -96.873114)
			(xy 302.2854 -96.901) (xy 303.972974 -96.901) (xy 303.977045 -96.845378) (xy 303.989171 -96.790941)
			(xy 304.009094 -96.73885) (xy 304.03639 -96.690215) (xy 304.070476 -96.646072) (xy 304.110625 -96.607363)
			(xy 304.155983 -96.574912) (xy 304.205583 -96.549411) (xy 304.258367 -96.531404) (xy 304.31321 -96.521274)
			(xy 304.368944 -96.519237) (xy 304.424381 -96.525337) (xy 304.478338 -96.539443) (xy 304.529667 -96.561255)
			(xy 304.577273 -96.590309) (xy 304.620141 -96.625984) (xy 304.657358 -96.667521) (xy 304.688131 -96.714034)
			(xy 304.711803 -96.764531) (xy 304.727871 -96.817938) (xy 304.735991 -96.873114) (xy 304.7365 -96.901)
			(xy 304.735991 -96.928886) (xy 304.727871 -96.984062) (xy 304.711803 -97.037469) (xy 304.710646 -97.039938)
			(xy 306.92547 -97.039938) (xy 306.929541 -96.984316) (xy 306.941667 -96.929879) (xy 306.96159 -96.877788)
			(xy 306.988886 -96.829153) (xy 307.022972 -96.78501) (xy 307.063121 -96.746301) (xy 307.108479 -96.71385)
			(xy 307.158079 -96.688349) (xy 307.210863 -96.670342) (xy 307.265706 -96.660212) (xy 307.32144 -96.658175)
			(xy 307.376877 -96.664275) (xy 307.430834 -96.678381) (xy 307.482163 -96.700193) (xy 307.529769 -96.729247)
			(xy 307.572637 -96.764922) (xy 307.609854 -96.806459) (xy 307.640627 -96.852972) (xy 307.664299 -96.903469)
			(xy 307.680367 -96.956876) (xy 307.687545 -97.005648) (xy 310.369456 -97.005648) (xy 310.373527 -96.950026)
			(xy 310.385653 -96.895589) (xy 310.405576 -96.843498) (xy 310.432872 -96.794863) (xy 310.466958 -96.75072)
			(xy 310.507107 -96.712011) (xy 310.552465 -96.67956) (xy 310.602065 -96.654059) (xy 310.654849 -96.636052)
			(xy 310.709692 -96.625922) (xy 310.765426 -96.623885) (xy 310.820863 -96.629985) (xy 310.87482 -96.644091)
			(xy 310.926149 -96.665903) (xy 310.973755 -96.694957) (xy 311.016623 -96.730632) (xy 311.05384 -96.772169)
			(xy 311.084613 -96.818682) (xy 311.108285 -96.869179) (xy 311.124353 -96.922586) (xy 311.132473 -96.977762)
			(xy 311.132982 -97.005648) (xy 311.132473 -97.033534) (xy 311.124353 -97.08871) (xy 311.108285 -97.142117)
			(xy 311.084613 -97.192614) (xy 311.05384 -97.239127) (xy 311.016623 -97.280664) (xy 310.973755 -97.316339)
			(xy 310.926149 -97.345393) (xy 310.87482 -97.367205) (xy 310.820863 -97.381311) (xy 310.765426 -97.387411)
			(xy 310.709692 -97.385374) (xy 310.654849 -97.375244) (xy 310.602065 -97.357237) (xy 310.552465 -97.331736)
			(xy 310.507107 -97.299285) (xy 310.466958 -97.260576) (xy 310.432872 -97.216433) (xy 310.405576 -97.167798)
			(xy 310.385653 -97.115707) (xy 310.373527 -97.06127) (xy 310.369456 -97.005648) (xy 307.687545 -97.005648)
			(xy 307.688487 -97.012052) (xy 307.688996 -97.039938) (xy 307.688487 -97.067824) (xy 307.680367 -97.123)
			(xy 307.664299 -97.176407) (xy 307.640627 -97.226904) (xy 307.609854 -97.273417) (xy 307.572637 -97.314954)
			(xy 307.529769 -97.350629) (xy 307.482163 -97.379683) (xy 307.430834 -97.401495) (xy 307.376877 -97.415601)
			(xy 307.32144 -97.421701) (xy 307.265706 -97.419664) (xy 307.210863 -97.409534) (xy 307.158079 -97.391527)
			(xy 307.108479 -97.366026) (xy 307.063121 -97.333575) (xy 307.022972 -97.294866) (xy 306.988886 -97.250723)
			(xy 306.96159 -97.202088) (xy 306.941667 -97.149997) (xy 306.929541 -97.09556) (xy 306.92547 -97.039938)
			(xy 304.710646 -97.039938) (xy 304.688131 -97.087966) (xy 304.657358 -97.134479) (xy 304.620141 -97.176016)
			(xy 304.577273 -97.211691) (xy 304.529667 -97.240745) (xy 304.478338 -97.262557) (xy 304.424381 -97.276663)
			(xy 304.368944 -97.282763) (xy 304.31321 -97.280726) (xy 304.258367 -97.270596) (xy 304.205583 -97.252589)
			(xy 304.155983 -97.227088) (xy 304.110625 -97.194637) (xy 304.070476 -97.155928) (xy 304.03639 -97.111785)
			(xy 304.009094 -97.06315) (xy 303.989171 -97.011059) (xy 303.977045 -96.956622) (xy 303.972974 -96.901)
			(xy 302.2854 -96.901) (xy 302.284891 -96.928886) (xy 302.276771 -96.984062) (xy 302.260703 -97.037469)
			(xy 302.237031 -97.087966) (xy 302.206258 -97.134479) (xy 302.169041 -97.176016) (xy 302.126173 -97.211691)
			(xy 302.078567 -97.240745) (xy 302.027238 -97.262557) (xy 301.973281 -97.276663) (xy 301.917844 -97.282763)
			(xy 301.86211 -97.280726) (xy 301.807267 -97.270596) (xy 301.754483 -97.252589) (xy 301.704883 -97.227088)
			(xy 301.659525 -97.194637) (xy 301.619376 -97.155928) (xy 301.58529 -97.111785) (xy 301.557994 -97.06315)
			(xy 301.538071 -97.011059) (xy 301.525945 -96.956622) (xy 301.521874 -96.901) (xy 284.535663 -96.901)
			(xy 284.544203 -96.919217) (xy 284.560271 -96.972624) (xy 284.568391 -97.0278) (xy 284.5689 -97.055686)
			(xy 284.568391 -97.083572) (xy 284.560271 -97.138748) (xy 284.544203 -97.192155) (xy 284.520531 -97.242652)
			(xy 284.489758 -97.289165) (xy 284.452541 -97.330702) (xy 284.409673 -97.366377) (xy 284.362067 -97.395431)
			(xy 284.310738 -97.417243) (xy 284.256781 -97.431349) (xy 284.201344 -97.437449) (xy 284.14561 -97.435412)
			(xy 284.090767 -97.425282) (xy 284.037983 -97.407275) (xy 283.988383 -97.381774) (xy 283.943025 -97.349323)
			(xy 283.902876 -97.310614) (xy 283.86879 -97.266471) (xy 283.841494 -97.217836) (xy 283.821571 -97.165745)
			(xy 283.809445 -97.111308) (xy 283.805374 -97.055686) (xy 270.167784 -97.055686) (xy 270.180315 -97.097338)
			(xy 270.188435 -97.152514) (xy 270.188944 -97.1804) (xy 270.188435 -97.208286) (xy 270.180315 -97.263462)
			(xy 270.164247 -97.316869) (xy 270.140575 -97.367366) (xy 270.109802 -97.413879) (xy 270.072585 -97.455416)
			(xy 270.029717 -97.491091) (xy 269.982111 -97.520145) (xy 269.930782 -97.541957) (xy 269.876825 -97.556063)
			(xy 269.821388 -97.562163) (xy 269.765654 -97.560126) (xy 269.710811 -97.549996) (xy 269.658027 -97.531989)
			(xy 269.608427 -97.506488) (xy 269.563069 -97.474037) (xy 269.52292 -97.435328) (xy 269.488834 -97.391185)
			(xy 269.461538 -97.34255) (xy 269.441615 -97.290459) (xy 269.429489 -97.236022) (xy 269.425418 -97.1804)
			(xy 264.846816 -97.1804) (xy 264.846816 -97.64014) (xy 306.118004 -97.64014) (xy 306.122075 -97.584518)
			(xy 306.134201 -97.530081) (xy 306.154124 -97.47799) (xy 306.18142 -97.429355) (xy 306.215506 -97.385212)
			(xy 306.255655 -97.346503) (xy 306.301013 -97.314052) (xy 306.350613 -97.288551) (xy 306.403397 -97.270544)
			(xy 306.45824 -97.260414) (xy 306.513974 -97.258377) (xy 306.569411 -97.264477) (xy 306.623368 -97.278583)
			(xy 306.674697 -97.300395) (xy 306.722303 -97.329449) (xy 306.765171 -97.365124) (xy 306.802388 -97.406661)
			(xy 306.833161 -97.453174) (xy 306.856833 -97.503671) (xy 306.872901 -97.557078) (xy 306.881021 -97.612254)
			(xy 306.88153 -97.64014) (xy 306.881021 -97.668026) (xy 306.872901 -97.723202) (xy 306.856833 -97.776609)
			(xy 306.833161 -97.827106) (xy 306.802388 -97.873619) (xy 306.765171 -97.915156) (xy 306.722303 -97.950831)
			(xy 306.674697 -97.979885) (xy 306.623368 -98.001697) (xy 306.569411 -98.015803) (xy 306.513974 -98.021903)
			(xy 306.45824 -98.019866) (xy 306.403397 -98.009736) (xy 306.350613 -97.991729) (xy 306.301013 -97.966228)
			(xy 306.255655 -97.933777) (xy 306.215506 -97.895068) (xy 306.18142 -97.850925) (xy 306.154124 -97.80229)
			(xy 306.134201 -97.750199) (xy 306.122075 -97.695762) (xy 306.118004 -97.64014) (xy 264.846816 -97.64014)
			(xy 264.846816 -98.171) (xy 307.763924 -98.171) (xy 307.767995 -98.115378) (xy 307.780121 -98.060941)
			(xy 307.800044 -98.00885) (xy 307.82734 -97.960215) (xy 307.861426 -97.916072) (xy 307.901575 -97.877363)
			(xy 307.946933 -97.844912) (xy 307.996533 -97.819411) (xy 308.049317 -97.801404) (xy 308.10416 -97.791274)
			(xy 308.159894 -97.789237) (xy 308.215331 -97.795337) (xy 308.269288 -97.809443) (xy 308.320617 -97.831255)
			(xy 308.368223 -97.860309) (xy 308.411091 -97.895984) (xy 308.448308 -97.937521) (xy 308.479081 -97.984034)
			(xy 308.496714 -98.021648) (xy 310.369456 -98.021648) (xy 310.373527 -97.966026) (xy 310.385653 -97.911589)
			(xy 310.405576 -97.859498) (xy 310.432872 -97.810863) (xy 310.466958 -97.76672) (xy 310.507107 -97.728011)
			(xy 310.552465 -97.69556) (xy 310.602065 -97.670059) (xy 310.654849 -97.652052) (xy 310.709692 -97.641922)
			(xy 310.765426 -97.639885) (xy 310.820863 -97.645985) (xy 310.87482 -97.660091) (xy 310.926149 -97.681903)
			(xy 310.973755 -97.710957) (xy 311.016623 -97.746632) (xy 311.05384 -97.788169) (xy 311.084613 -97.834682)
			(xy 311.108285 -97.885179) (xy 311.124353 -97.938586) (xy 311.126559 -97.953576) (xy 320.542918 -97.953576)
			(xy 320.546989 -97.897954) (xy 320.559115 -97.843517) (xy 320.579038 -97.791426) (xy 320.606334 -97.742791)
			(xy 320.64042 -97.698648) (xy 320.680569 -97.659939) (xy 320.725927 -97.627488) (xy 320.775527 -97.601987)
			(xy 320.828311 -97.58398) (xy 320.883154 -97.57385) (xy 320.938888 -97.571813) (xy 320.994325 -97.577913)
			(xy 321.048282 -97.592019) (xy 321.099611 -97.613831) (xy 321.147217 -97.642885) (xy 321.190085 -97.67856)
			(xy 321.227302 -97.720097) (xy 321.258075 -97.76661) (xy 321.281747 -97.817107) (xy 321.282991 -97.821242)
			(xy 321.857368 -97.821242) (xy 321.861439 -97.76562) (xy 321.873565 -97.711183) (xy 321.893488 -97.659092)
			(xy 321.920784 -97.610457) (xy 321.95487 -97.566314) (xy 321.995019 -97.527605) (xy 322.040377 -97.495154)
			(xy 322.089977 -97.469653) (xy 322.142761 -97.451646) (xy 322.197604 -97.441516) (xy 322.253338 -97.439479)
			(xy 322.308775 -97.445579) (xy 322.362732 -97.459685) (xy 322.414061 -97.481497) (xy 322.461667 -97.510551)
			(xy 322.504535 -97.546226) (xy 322.541752 -97.587763) (xy 322.572525 -97.634276) (xy 322.596197 -97.684773)
			(xy 322.612265 -97.73818) (xy 322.620385 -97.793356) (xy 322.620894 -97.821242) (xy 322.620397 -97.848448)
			(xy 323.12842 -97.848448) (xy 323.12842 -97.793952) (xy 323.136175 -97.740012) (xy 323.151528 -97.687724)
			(xy 323.174166 -97.638153) (xy 323.203627 -97.592309) (xy 323.239313 -97.551123) (xy 323.280497 -97.515436)
			(xy 323.326341 -97.485972) (xy 323.375911 -97.463333) (xy 323.428198 -97.447978) (xy 323.482138 -97.440221)
			(xy 323.509386 -97.439734) (xy 323.538303 -97.44025) (xy 323.595475 -97.448977) (xy 323.650675 -97.466235)
			(xy 323.702636 -97.491627) (xy 323.75017 -97.524572) (xy 323.792186 -97.564314) (xy 323.810376 -97.5868)
			(xy 323.818003 -97.595586) (xy 323.838889 -97.605781) (xy 323.850508 -97.606358) (xy 323.930264 -97.606358)
			(xy 323.941901 -97.605856) (xy 323.962811 -97.595642) (xy 323.970396 -97.5868) (xy 323.988589 -97.564318)
			(xy 324.030609 -97.524583) (xy 324.078143 -97.491644) (xy 324.130104 -97.466255) (xy 324.185301 -97.448999)
			(xy 324.24247 -97.440269) (xy 324.271386 -97.439734) (xy 324.298643 -97.440112) (xy 324.352601 -97.447868)
			(xy 324.404906 -97.463225) (xy 324.454494 -97.485869) (xy 324.500354 -97.51534) (xy 324.541553 -97.551037)
			(xy 324.577252 -97.592235) (xy 324.606724 -97.638094) (xy 324.62937 -97.687681) (xy 324.644729 -97.739985)
			(xy 324.652487 -97.793943) (xy 324.652487 -97.821242) (xy 324.905368 -97.821242) (xy 324.909439 -97.76562)
			(xy 324.921565 -97.711183) (xy 324.941488 -97.659092) (xy 324.968784 -97.610457) (xy 325.00287 -97.566314)
			(xy 325.043019 -97.527605) (xy 325.088377 -97.495154) (xy 325.137977 -97.469653) (xy 325.190761 -97.451646)
			(xy 325.245604 -97.441516) (xy 325.301338 -97.439479) (xy 325.356775 -97.445579) (xy 325.410732 -97.459685)
			(xy 325.462061 -97.481497) (xy 325.509667 -97.510551) (xy 325.552535 -97.546226) (xy 325.589752 -97.587763)
			(xy 325.620525 -97.634276) (xy 325.644197 -97.684773) (xy 325.660265 -97.73818) (xy 325.668385 -97.793356)
			(xy 325.668894 -97.821242) (xy 325.668385 -97.849128) (xy 325.660265 -97.904304) (xy 325.644197 -97.957711)
			(xy 325.620525 -98.008208) (xy 325.589752 -98.054721) (xy 325.552535 -98.096258) (xy 325.509667 -98.131933)
			(xy 325.462061 -98.160987) (xy 325.410732 -98.182799) (xy 325.356775 -98.196905) (xy 325.301338 -98.203005)
			(xy 325.245604 -98.200968) (xy 325.190761 -98.190838) (xy 325.137977 -98.172831) (xy 325.088377 -98.14733)
			(xy 325.043019 -98.114879) (xy 325.00287 -98.07617) (xy 324.968784 -98.032027) (xy 324.941488 -97.983392)
			(xy 324.921565 -97.931301) (xy 324.909439 -97.876864) (xy 324.905368 -97.821242) (xy 324.652487 -97.821242)
			(xy 324.652487 -97.848457) (xy 324.644729 -97.902415) (xy 324.62937 -97.954719) (xy 324.606724 -98.004306)
			(xy 324.577252 -98.050165) (xy 324.541553 -98.091363) (xy 324.500354 -98.12706) (xy 324.454494 -98.156531)
			(xy 324.404906 -98.179175) (xy 324.352601 -98.194532) (xy 324.298643 -98.202288) (xy 324.271386 -98.20275)
			(xy 324.24247 -98.202189) (xy 324.1853 -98.193471) (xy 324.130102 -98.176223) (xy 324.078139 -98.15084)
			(xy 324.030605 -98.117902) (xy 323.988587 -98.078167) (xy 323.970396 -98.055684) (xy 323.962784 -98.046882)
			(xy 323.941887 -98.036696) (xy 323.930264 -98.036126) (xy 323.850508 -98.036126) (xy 323.838877 -98.036675)
			(xy 323.817967 -98.046856) (xy 323.810376 -98.055684) (xy 323.792194 -98.078176) (xy 323.750173 -98.117911)
			(xy 323.702637 -98.15085) (xy 323.650673 -98.176237) (xy 323.595474 -98.193491) (xy 323.538303 -98.202217)
			(xy 323.509386 -98.20275) (xy 323.482138 -98.202179) (xy 323.428198 -98.194422) (xy 323.375911 -98.179067)
			(xy 323.326341 -98.156428) (xy 323.280497 -98.126964) (xy 323.239313 -98.091277) (xy 323.203627 -98.050091)
			(xy 323.174166 -98.004247) (xy 323.151528 -97.954676) (xy 323.136175 -97.902388) (xy 323.12842 -97.848448)
			(xy 322.620397 -97.848448) (xy 322.620385 -97.849128) (xy 322.612265 -97.904304) (xy 322.596197 -97.957711)
			(xy 322.572525 -98.008208) (xy 322.541752 -98.054721) (xy 322.504535 -98.096258) (xy 322.461667 -98.131933)
			(xy 322.414061 -98.160987) (xy 322.362732 -98.182799) (xy 322.308775 -98.196905) (xy 322.253338 -98.203005)
			(xy 322.197604 -98.200968) (xy 322.142761 -98.190838) (xy 322.089977 -98.172831) (xy 322.040377 -98.14733)
			(xy 321.995019 -98.114879) (xy 321.95487 -98.07617) (xy 321.920784 -98.032027) (xy 321.893488 -97.983392)
			(xy 321.873565 -97.931301) (xy 321.861439 -97.876864) (xy 321.857368 -97.821242) (xy 321.282991 -97.821242)
			(xy 321.297815 -97.870514) (xy 321.305935 -97.92569) (xy 321.306444 -97.953576) (xy 321.305935 -97.981462)
			(xy 321.297815 -98.036638) (xy 321.281747 -98.090045) (xy 321.258075 -98.140542) (xy 321.227302 -98.187055)
			(xy 321.190085 -98.228592) (xy 321.147217 -98.264267) (xy 321.099611 -98.293321) (xy 321.048282 -98.315133)
			(xy 320.994325 -98.329239) (xy 320.938888 -98.335339) (xy 320.883154 -98.333302) (xy 320.828311 -98.323172)
			(xy 320.775527 -98.305165) (xy 320.725927 -98.279664) (xy 320.680569 -98.247213) (xy 320.64042 -98.208504)
			(xy 320.606334 -98.164361) (xy 320.579038 -98.115726) (xy 320.559115 -98.063635) (xy 320.546989 -98.009198)
			(xy 320.542918 -97.953576) (xy 311.126559 -97.953576) (xy 311.132473 -97.993762) (xy 311.132982 -98.021648)
			(xy 311.132473 -98.049534) (xy 311.124353 -98.10471) (xy 311.108285 -98.158117) (xy 311.084613 -98.208614)
			(xy 311.05384 -98.255127) (xy 311.016623 -98.296664) (xy 310.973755 -98.332339) (xy 310.926149 -98.361393)
			(xy 310.87482 -98.383205) (xy 310.820863 -98.397311) (xy 310.765426 -98.403411) (xy 310.709692 -98.401374)
			(xy 310.654849 -98.391244) (xy 310.602065 -98.373237) (xy 310.552465 -98.347736) (xy 310.507107 -98.315285)
			(xy 310.466958 -98.276576) (xy 310.432872 -98.232433) (xy 310.405576 -98.183798) (xy 310.385653 -98.131707)
			(xy 310.373527 -98.07727) (xy 310.369456 -98.021648) (xy 308.496714 -98.021648) (xy 308.502753 -98.034531)
			(xy 308.518821 -98.087938) (xy 308.526941 -98.143114) (xy 308.52745 -98.171) (xy 308.526941 -98.198886)
			(xy 308.518821 -98.254062) (xy 308.502753 -98.307469) (xy 308.479081 -98.357966) (xy 308.448308 -98.404479)
			(xy 308.411091 -98.446016) (xy 308.368223 -98.481691) (xy 308.320617 -98.510745) (xy 308.269288 -98.532557)
			(xy 308.215331 -98.546663) (xy 308.159894 -98.552763) (xy 308.10416 -98.550726) (xy 308.049317 -98.540596)
			(xy 307.996533 -98.522589) (xy 307.946933 -98.497088) (xy 307.901575 -98.464637) (xy 307.861426 -98.425928)
			(xy 307.82734 -98.381785) (xy 307.800044 -98.33315) (xy 307.780121 -98.281059) (xy 307.767995 -98.226622)
			(xy 307.763924 -98.171) (xy 264.846816 -98.171) (xy 264.846816 -100.402756) (xy 268.952621 -100.402756)
			(xy 268.952621 -100.348244) (xy 268.960379 -100.294285) (xy 268.975738 -100.241981) (xy 268.998385 -100.192394)
			(xy 269.027858 -100.146536) (xy 269.063557 -100.105339) (xy 269.104757 -100.069642) (xy 269.150617 -100.040172)
			(xy 269.200205 -100.017529) (xy 269.252511 -100.002174) (xy 269.306469 -99.994419) (xy 269.333726 -99.993958)
			(xy 269.348519 -99.994088) (xy 269.378017 -99.99638) (xy 269.392654 -99.99853) (xy 269.40363 -99.999614)
			(xy 269.424817 -99.993581) (xy 269.433548 -99.986846) (xy 269.491968 -99.936808) (xy 269.499996 -99.929241)
			(xy 269.509209 -99.90922) (xy 269.509748 -99.8982) (xy 269.509748 -99.593908) (xy 269.509222 -99.582887)
			(xy 269.499996 -99.56287) (xy 269.491968 -99.5553) (xy 269.424912 -99.497896) (xy 269.40383 -99.4918)
			(xy 269.392654 -99.493578) (xy 269.378016 -99.495719) (xy 269.348519 -99.498007) (xy 269.333726 -99.49815)
			(xy 269.306475 -99.497605) (xy 269.252527 -99.489851) (xy 269.200232 -99.474499) (xy 269.150654 -99.451861)
			(xy 269.104803 -99.422397) (xy 269.063611 -99.386707) (xy 269.027919 -99.345518) (xy 268.998452 -99.299669)
			(xy 268.97581 -99.250092) (xy 268.960454 -99.197798) (xy 268.952697 -99.143851) (xy 268.952697 -99.089349)
			(xy 268.960454 -99.035402) (xy 268.97581 -98.983108) (xy 268.998452 -98.933531) (xy 269.027919 -98.887682)
			(xy 269.063611 -98.846493) (xy 269.104803 -98.810803) (xy 269.150654 -98.781339) (xy 269.200232 -98.758701)
			(xy 269.252527 -98.743349) (xy 269.306475 -98.735595) (xy 269.333726 -98.735134) (xy 269.359634 -98.73559)
			(xy 269.410971 -98.742617) (xy 269.460886 -98.756526) (xy 269.508459 -98.77706) (xy 269.552818 -98.803842)
			(xy 269.593144 -98.836379) (xy 269.628698 -98.874073) (xy 269.644114 -98.8949) (xy 269.649836 -98.902246)
			(xy 269.665352 -98.912523) (xy 269.67434 -98.914966) (xy 269.70482 -98.921824) (xy 269.714098 -98.923558)
			(xy 269.732759 -98.920827) (xy 269.741142 -98.91649) (xy 269.767111 -98.902181) (xy 269.821965 -98.879674)
			(xy 269.879271 -98.864451) (xy 269.938064 -98.85677) (xy 269.96771 -98.856292) (xy 269.997352 -98.856815)
			(xy 270.056133 -98.864528) (xy 270.113431 -98.879748) (xy 270.168293 -98.902219) (xy 270.194278 -98.91649)
			(xy 270.202691 -98.920736) (xy 270.221321 -98.923469) (xy 270.2306 -98.921824) (xy 270.26108 -98.914966)
			(xy 270.27008 -98.912559) (xy 270.285582 -98.902252) (xy 270.291306 -98.8949) (xy 270.306694 -98.874049)
			(xy 270.342239 -98.836336) (xy 270.382565 -98.803787) (xy 270.426927 -98.776999) (xy 270.47451 -98.756467)
			(xy 270.524435 -98.74257) (xy 270.575782 -98.735563) (xy 270.601694 -98.735134) (xy 270.62895 -98.735513)
			(xy 270.682908 -98.74327) (xy 270.735212 -98.758627) (xy 270.784799 -98.781272) (xy 270.830657 -98.810743)
			(xy 270.870327 -98.845116) (xy 276.86965 -98.845116) (xy 276.873721 -98.789494) (xy 276.885847 -98.735057)
			(xy 276.90577 -98.682966) (xy 276.933066 -98.634331) (xy 276.967152 -98.590188) (xy 277.007301 -98.551479)
			(xy 277.052659 -98.519028) (xy 277.102259 -98.493527) (xy 277.155043 -98.47552) (xy 277.209886 -98.46539)
			(xy 277.26562 -98.463353) (xy 277.321057 -98.469453) (xy 277.375014 -98.483559) (xy 277.426343 -98.505371)
			(xy 277.473949 -98.534425) (xy 277.516817 -98.5701) (xy 277.554034 -98.611637) (xy 277.584807 -98.65815)
			(xy 277.608479 -98.708647) (xy 277.624547 -98.762054) (xy 277.632667 -98.81723) (xy 277.633176 -98.845116)
			(xy 278.85085 -98.845116) (xy 278.854921 -98.789494) (xy 278.867047 -98.735057) (xy 278.88697 -98.682966)
			(xy 278.914266 -98.634331) (xy 278.948352 -98.590188) (xy 278.988501 -98.551479) (xy 279.033859 -98.519028)
			(xy 279.083459 -98.493527) (xy 279.136243 -98.47552) (xy 279.191086 -98.46539) (xy 279.24682 -98.463353)
			(xy 279.302257 -98.469453) (xy 279.356214 -98.483559) (xy 279.407543 -98.505371) (xy 279.455149 -98.534425)
			(xy 279.498017 -98.5701) (xy 279.535234 -98.611637) (xy 279.566007 -98.65815) (xy 279.589679 -98.708647)
			(xy 279.605747 -98.762054) (xy 279.613867 -98.81723) (xy 279.614376 -98.845116) (xy 280.582876 -98.845116)
			(xy 280.586947 -98.789494) (xy 280.599073 -98.735057) (xy 280.618996 -98.682966) (xy 280.646292 -98.634331)
			(xy 280.680378 -98.590188) (xy 280.720527 -98.551479) (xy 280.765885 -98.519028) (xy 280.815485 -98.493527)
			(xy 280.868269 -98.47552) (xy 280.923112 -98.46539) (xy 280.978846 -98.463353) (xy 281.034283 -98.469453)
			(xy 281.08824 -98.483559) (xy 281.139569 -98.505371) (xy 281.187175 -98.534425) (xy 281.230043 -98.5701)
			(xy 281.26726 -98.611637) (xy 281.298033 -98.65815) (xy 281.321705 -98.708647) (xy 281.337773 -98.762054)
			(xy 281.345893 -98.81723) (xy 281.346402 -98.845116) (xy 283.451044 -98.845116) (xy 283.455115 -98.789494)
			(xy 283.467241 -98.735057) (xy 283.487164 -98.682966) (xy 283.51446 -98.634331) (xy 283.548546 -98.590188)
			(xy 283.588695 -98.551479) (xy 283.634053 -98.519028) (xy 283.683653 -98.493527) (xy 283.736437 -98.47552)
			(xy 283.79128 -98.46539) (xy 283.847014 -98.463353) (xy 283.902451 -98.469453) (xy 283.956408 -98.483559)
			(xy 284.007737 -98.505371) (xy 284.055343 -98.534425) (xy 284.098211 -98.5701) (xy 284.135428 -98.611637)
			(xy 284.166201 -98.65815) (xy 284.189873 -98.708647) (xy 284.205941 -98.762054) (xy 284.214061 -98.81723)
			(xy 284.21457 -98.845116) (xy 284.214061 -98.873002) (xy 284.205941 -98.928178) (xy 284.189873 -98.981585)
			(xy 284.166201 -99.032082) (xy 284.135428 -99.078595) (xy 284.098211 -99.120132) (xy 284.055343 -99.155807)
			(xy 284.007737 -99.184861) (xy 283.956408 -99.206673) (xy 283.902451 -99.220779) (xy 283.847014 -99.226879)
			(xy 283.79128 -99.224842) (xy 283.736437 -99.214712) (xy 283.683653 -99.196705) (xy 283.634053 -99.171204)
			(xy 283.588695 -99.138753) (xy 283.548546 -99.100044) (xy 283.51446 -99.055901) (xy 283.487164 -99.007266)
			(xy 283.467241 -98.955175) (xy 283.455115 -98.900738) (xy 283.451044 -98.845116) (xy 281.346402 -98.845116)
			(xy 281.345893 -98.873002) (xy 281.337773 -98.928178) (xy 281.321705 -98.981585) (xy 281.298033 -99.032082)
			(xy 281.26726 -99.078595) (xy 281.230043 -99.120132) (xy 281.187175 -99.155807) (xy 281.139569 -99.184861)
			(xy 281.08824 -99.206673) (xy 281.034283 -99.220779) (xy 280.978846 -99.226879) (xy 280.923112 -99.224842)
			(xy 280.868269 -99.214712) (xy 280.815485 -99.196705) (xy 280.765885 -99.171204) (xy 280.720527 -99.138753)
			(xy 280.680378 -99.100044) (xy 280.646292 -99.055901) (xy 280.618996 -99.007266) (xy 280.599073 -98.955175)
			(xy 280.586947 -98.900738) (xy 280.582876 -98.845116) (xy 279.614376 -98.845116) (xy 279.613867 -98.873002)
			(xy 279.605747 -98.928178) (xy 279.589679 -98.981585) (xy 279.566007 -99.032082) (xy 279.535234 -99.078595)
			(xy 279.498017 -99.120132) (xy 279.455149 -99.155807) (xy 279.407543 -99.184861) (xy 279.356214 -99.206673)
			(xy 279.302257 -99.220779) (xy 279.24682 -99.226879) (xy 279.191086 -99.224842) (xy 279.136243 -99.214712)
			(xy 279.083459 -99.196705) (xy 279.033859 -99.171204) (xy 278.988501 -99.138753) (xy 278.948352 -99.100044)
			(xy 278.914266 -99.055901) (xy 278.88697 -99.007266) (xy 278.867047 -98.955175) (xy 278.854921 -98.900738)
			(xy 278.85085 -98.845116) (xy 277.633176 -98.845116) (xy 277.632667 -98.873002) (xy 277.624547 -98.928178)
			(xy 277.608479 -98.981585) (xy 277.584807 -99.032082) (xy 277.554034 -99.078595) (xy 277.516817 -99.120132)
			(xy 277.473949 -99.155807) (xy 277.426343 -99.184861) (xy 277.375014 -99.206673) (xy 277.321057 -99.220779)
			(xy 277.26562 -99.226879) (xy 277.209886 -99.224842) (xy 277.155043 -99.214712) (xy 277.102259 -99.196705)
			(xy 277.052659 -99.171204) (xy 277.007301 -99.138753) (xy 276.967152 -99.100044) (xy 276.933066 -99.055901)
			(xy 276.90577 -99.007266) (xy 276.885847 -98.955175) (xy 276.873721 -98.900738) (xy 276.86965 -98.845116)
			(xy 270.870327 -98.845116) (xy 270.871855 -98.84644) (xy 270.907554 -98.887638) (xy 270.937026 -98.933496)
			(xy 270.959671 -98.983082) (xy 270.975029 -99.035386) (xy 270.982787 -99.089344) (xy 270.982787 -99.143856)
			(xy 270.975029 -99.197814) (xy 270.959671 -99.250118) (xy 270.937026 -99.299704) (xy 270.907554 -99.345562)
			(xy 270.871855 -99.38676) (xy 270.830657 -99.422457) (xy 270.784799 -99.451928) (xy 270.735212 -99.474573)
			(xy 270.682908 -99.48993) (xy 270.62895 -99.497687) (xy 270.601694 -99.49815) (xy 270.586901 -99.498018)
			(xy 270.557403 -99.495727) (xy 270.542766 -99.493578) (xy 270.531792 -99.492445) (xy 270.5106 -99.498511)
			(xy 270.501872 -99.505262) (xy 270.443452 -99.5553) (xy 270.435423 -99.562867) (xy 270.42621 -99.582888)
			(xy 270.425672 -99.593908) (xy 270.425672 -99.8982) (xy 270.426219 -99.909218) (xy 270.435433 -99.929234)
			(xy 270.443452 -99.936808) (xy 270.510508 -99.994212) (xy 270.53159 -100.000308) (xy 270.542766 -99.99853)
			(xy 270.557404 -99.996387) (xy 270.586901 -99.9941) (xy 270.601694 -99.993958) (xy 270.628945 -99.994489)
			(xy 270.682891 -100.002244) (xy 270.735185 -100.017599) (xy 270.784762 -100.040239) (xy 270.830612 -100.069704)
			(xy 270.871801 -100.105394) (xy 270.907492 -100.146584) (xy 270.936958 -100.192433) (xy 270.959599 -100.242009)
			(xy 270.974954 -100.294303) (xy 270.982711 -100.348249) (xy 270.982711 -100.402751) (xy 270.974954 -100.456697)
			(xy 270.959599 -100.508991) (xy 270.936958 -100.558567) (xy 270.907492 -100.604416) (xy 270.872361 -100.64496)
			(xy 276.86965 -100.64496) (xy 276.873721 -100.589338) (xy 276.885847 -100.534901) (xy 276.90577 -100.48281)
			(xy 276.933066 -100.434175) (xy 276.967152 -100.390032) (xy 277.007301 -100.351323) (xy 277.052659 -100.318872)
			(xy 277.102259 -100.293371) (xy 277.155043 -100.275364) (xy 277.209886 -100.265234) (xy 277.26562 -100.263197)
			(xy 277.321057 -100.269297) (xy 277.375014 -100.283403) (xy 277.426343 -100.305215) (xy 277.473949 -100.334269)
			(xy 277.516817 -100.369944) (xy 277.554034 -100.411481) (xy 277.584807 -100.457994) (xy 277.608479 -100.508491)
			(xy 277.624547 -100.561898) (xy 277.632667 -100.617074) (xy 277.633176 -100.64496) (xy 278.85085 -100.64496)
			(xy 278.854921 -100.589338) (xy 278.867047 -100.534901) (xy 278.88697 -100.48281) (xy 278.914266 -100.434175)
			(xy 278.948352 -100.390032) (xy 278.988501 -100.351323) (xy 279.033859 -100.318872) (xy 279.083459 -100.293371)
			(xy 279.136243 -100.275364) (xy 279.191086 -100.265234) (xy 279.24682 -100.263197) (xy 279.302257 -100.269297)
			(xy 279.356214 -100.283403) (xy 279.407543 -100.305215) (xy 279.455149 -100.334269) (xy 279.498017 -100.369944)
			(xy 279.535234 -100.411481) (xy 279.566007 -100.457994) (xy 279.589679 -100.508491) (xy 279.605747 -100.561898)
			(xy 279.613867 -100.617074) (xy 279.614376 -100.64496) (xy 280.209496 -100.64496) (xy 280.213567 -100.589338)
			(xy 280.225693 -100.534901) (xy 280.245616 -100.48281) (xy 280.272912 -100.434175) (xy 280.306998 -100.390032)
			(xy 280.347147 -100.351323) (xy 280.392505 -100.318872) (xy 280.442105 -100.293371) (xy 280.494889 -100.275364)
			(xy 280.549732 -100.265234) (xy 280.605466 -100.263197) (xy 280.660903 -100.269297) (xy 280.71486 -100.283403)
			(xy 280.766189 -100.305215) (xy 280.813795 -100.334269) (xy 280.856663 -100.369944) (xy 280.89388 -100.411481)
			(xy 280.924653 -100.457994) (xy 280.948325 -100.508491) (xy 280.964393 -100.561898) (xy 280.972513 -100.617074)
			(xy 280.973022 -100.64496) (xy 280.972513 -100.672846) (xy 280.964393 -100.728022) (xy 280.948325 -100.781429)
			(xy 280.924653 -100.831926) (xy 280.89388 -100.878439) (xy 280.856663 -100.919976) (xy 280.813795 -100.955651)
			(xy 280.766189 -100.984705) (xy 280.71486 -101.006517) (xy 280.660903 -101.020623) (xy 280.605466 -101.026723)
			(xy 280.549732 -101.024686) (xy 280.494889 -101.014556) (xy 280.442105 -100.996549) (xy 280.392505 -100.971048)
			(xy 280.347147 -100.938597) (xy 280.306998 -100.899888) (xy 280.272912 -100.855745) (xy 280.245616 -100.80711)
			(xy 280.225693 -100.755019) (xy 280.213567 -100.700582) (xy 280.209496 -100.64496) (xy 279.614376 -100.64496)
			(xy 279.613867 -100.672846) (xy 279.605747 -100.728022) (xy 279.589679 -100.781429) (xy 279.566007 -100.831926)
			(xy 279.535234 -100.878439) (xy 279.498017 -100.919976) (xy 279.455149 -100.955651) (xy 279.407543 -100.984705)
			(xy 279.356214 -101.006517) (xy 279.302257 -101.020623) (xy 279.24682 -101.026723) (xy 279.191086 -101.024686)
			(xy 279.136243 -101.014556) (xy 279.083459 -100.996549) (xy 279.033859 -100.971048) (xy 278.988501 -100.938597)
			(xy 278.948352 -100.899888) (xy 278.914266 -100.855745) (xy 278.88697 -100.80711) (xy 278.867047 -100.755019)
			(xy 278.854921 -100.700582) (xy 278.85085 -100.64496) (xy 277.633176 -100.64496) (xy 277.632667 -100.672846)
			(xy 277.624547 -100.728022) (xy 277.608479 -100.781429) (xy 277.584807 -100.831926) (xy 277.554034 -100.878439)
			(xy 277.516817 -100.919976) (xy 277.473949 -100.955651) (xy 277.426343 -100.984705) (xy 277.375014 -101.006517)
			(xy 277.321057 -101.020623) (xy 277.26562 -101.026723) (xy 277.209886 -101.024686) (xy 277.155043 -101.014556)
			(xy 277.102259 -100.996549) (xy 277.052659 -100.971048) (xy 277.007301 -100.938597) (xy 276.967152 -100.899888)
			(xy 276.933066 -100.855745) (xy 276.90577 -100.80711) (xy 276.885847 -100.755019) (xy 276.873721 -100.700582)
			(xy 276.86965 -100.64496) (xy 270.872361 -100.64496) (xy 270.871801 -100.645606) (xy 270.830612 -100.681296)
			(xy 270.784762 -100.710761) (xy 270.735185 -100.733401) (xy 270.682891 -100.748756) (xy 270.628945 -100.756511)
			(xy 270.601694 -100.756974) (xy 270.575787 -100.7565) (xy 270.52445 -100.749476) (xy 270.474536 -100.73557)
			(xy 270.426963 -100.715039) (xy 270.382605 -100.688259) (xy 270.342277 -100.655725) (xy 270.306723 -100.618034)
			(xy 270.291306 -100.597208) (xy 270.285575 -100.58987) (xy 270.270065 -100.579589) (xy 270.26108 -100.577142)
			(xy 270.2306 -100.570284) (xy 270.221321 -100.56856) (xy 270.202661 -100.571285) (xy 270.194278 -100.575618)
			(xy 270.168306 -100.58992) (xy 270.113452 -100.612429) (xy 270.056148 -100.627653) (xy 269.997356 -100.635337)
			(xy 269.96771 -100.635816) (xy 269.938067 -100.635326) (xy 269.879285 -100.627603) (xy 269.821986 -100.612374)
			(xy 269.767126 -100.589893) (xy 269.741142 -100.575618) (xy 269.732725 -100.571382) (xy 269.714098 -100.568643)
			(xy 269.70482 -100.570284) (xy 269.67434 -100.577142) (xy 269.665342 -100.579555) (xy 269.649839 -100.589858)
			(xy 269.644114 -100.597208) (xy 269.628716 -100.618052) (xy 269.593172 -100.655764) (xy 269.552848 -100.688314)
			(xy 269.508487 -100.715103) (xy 269.460907 -100.735636) (xy 269.410983 -100.749535) (xy 269.359637 -100.756544)
			(xy 269.333726 -100.756974) (xy 269.306469 -100.756581) (xy 269.252511 -100.748826) (xy 269.200205 -100.733471)
			(xy 269.150617 -100.710828) (xy 269.104757 -100.681358) (xy 269.063557 -100.645661) (xy 269.027858 -100.604464)
			(xy 268.998385 -100.558606) (xy 268.975738 -100.509019) (xy 268.960379 -100.456715) (xy 268.952621 -100.402756)
			(xy 264.846816 -100.402756) (xy 264.846816 -100.950354) (xy 266.920145 -100.950354) (xy 266.920145 -100.895846)
			(xy 266.927903 -100.841892) (xy 266.94326 -100.789591) (xy 266.965904 -100.740008) (xy 266.995375 -100.694153)
			(xy 267.031071 -100.652959) (xy 267.072267 -100.617264) (xy 267.118124 -100.587796) (xy 267.167708 -100.565154)
			(xy 267.220009 -100.549799) (xy 267.273964 -100.542044) (xy 267.301218 -100.541582) (xy 267.327125 -100.542065)
			(xy 267.37846 -100.549091) (xy 267.428373 -100.562996) (xy 267.475946 -100.583526) (xy 267.520304 -100.610303)
			(xy 267.560632 -100.642835) (xy 267.596188 -100.680524) (xy 267.611606 -100.701348) (xy 267.617342 -100.708683)
			(xy 267.632847 -100.718967) (xy 267.641832 -100.721414) (xy 267.672312 -100.728272) (xy 267.68159 -100.730008)
			(xy 267.700252 -100.727277) (xy 267.708634 -100.722938) (xy 267.734607 -100.708636) (xy 267.78946 -100.686126)
			(xy 267.846764 -100.670901) (xy 267.905556 -100.663218) (xy 267.935202 -100.66274) (xy 267.964845 -100.66323)
			(xy 268.023627 -100.670955) (xy 268.080925 -100.686183) (xy 268.135785 -100.708663) (xy 268.16177 -100.722938)
			(xy 268.170186 -100.727179) (xy 268.188813 -100.729917) (xy 268.198092 -100.728272) (xy 268.228572 -100.721414)
			(xy 268.237565 -100.718988) (xy 268.253069 -100.708693) (xy 268.258798 -100.701348) (xy 268.274176 -100.680489)
			(xy 268.309724 -100.642779) (xy 268.350052 -100.610232) (xy 268.394417 -100.583446) (xy 268.442 -100.562915)
			(xy 268.491926 -100.549018) (xy 268.543274 -100.542011) (xy 268.569186 -100.541582) (xy 268.596439 -100.542064)
			(xy 268.65039 -100.54982) (xy 268.702688 -100.565174) (xy 268.752269 -100.587815) (xy 268.798122 -100.617282)
			(xy 268.839315 -100.652975) (xy 268.87501 -100.694167) (xy 268.904478 -100.740019) (xy 268.927121 -100.789599)
			(xy 268.942478 -100.841896) (xy 268.950235 -100.895847) (xy 268.950235 -100.950353) (xy 268.942478 -101.004304)
			(xy 268.927121 -101.056601) (xy 268.904478 -101.106181) (xy 268.87501 -101.152033) (xy 268.839315 -101.193225)
			(xy 268.798122 -101.228918) (xy 268.752269 -101.258385) (xy 268.702688 -101.281026) (xy 268.65039 -101.29638)
			(xy 268.596439 -101.304136) (xy 268.569186 -101.304598) (xy 268.554393 -101.304466) (xy 268.524895 -101.302175)
			(xy 268.510258 -101.300026) (xy 268.499284 -101.298877) (xy 268.47809 -101.304953) (xy 268.469364 -101.31171)
			(xy 268.410944 -101.361748) (xy 268.402938 -101.369335) (xy 268.393712 -101.389341) (xy 268.393164 -101.400356)
			(xy 268.393164 -101.704648) (xy 268.393742 -101.715662) (xy 268.402934 -101.735678) (xy 268.410944 -101.743256)
			(xy 268.478 -101.80066) (xy 268.499082 -101.806756) (xy 268.510258 -101.804978) (xy 268.524896 -101.802836)
			(xy 268.554393 -101.800549) (xy 268.569186 -101.800406) (xy 268.596441 -101.80084) (xy 268.650395 -101.808596)
			(xy 268.702697 -101.823951) (xy 268.75228 -101.846594) (xy 268.798137 -101.876062) (xy 268.839333 -101.911757)
			(xy 268.875029 -101.952952) (xy 268.9045 -101.998807) (xy 268.927144 -102.04839) (xy 268.942501 -102.100691)
			(xy 268.950259 -102.154645) (xy 268.950259 -102.209155) (xy 268.942501 -102.263109) (xy 268.927144 -102.31541)
			(xy 268.9045 -102.364993) (xy 268.875029 -102.410848) (xy 268.839333 -102.452043) (xy 268.798137 -102.487738)
			(xy 268.75228 -102.517206) (xy 268.702697 -102.539849) (xy 268.650395 -102.555204) (xy 268.596441 -102.56296)
			(xy 268.569186 -102.563422) (xy 268.543279 -102.562934) (xy 268.491944 -102.555909) (xy 268.442032 -102.542005)
			(xy 268.394459 -102.521475) (xy 268.350101 -102.494699) (xy 268.309772 -102.462168) (xy 268.274216 -102.42448)
			(xy 268.258798 -102.403656) (xy 268.25306 -102.396323) (xy 268.237556 -102.386038) (xy 268.228572 -102.38359)
			(xy 268.198092 -102.376732) (xy 268.188814 -102.374998) (xy 268.170152 -102.377728) (xy 268.16177 -102.382066)
			(xy 268.135797 -102.396366) (xy 268.080944 -102.418877) (xy 268.02364 -102.434102) (xy 267.964848 -102.441786)
			(xy 267.935202 -102.442264) (xy 267.905559 -102.441771) (xy 267.846777 -102.434048) (xy 267.789479 -102.41882)
			(xy 267.734619 -102.39634) (xy 267.708634 -102.382066) (xy 267.700218 -102.377828) (xy 267.681591 -102.375088)
			(xy 267.672312 -102.376732) (xy 267.641832 -102.38359) (xy 267.632839 -102.386016) (xy 267.617335 -102.396311)
			(xy 267.611606 -102.403656) (xy 267.596227 -102.424514) (xy 267.560679 -102.462224) (xy 267.520351 -102.494771)
			(xy 267.475986 -102.521557) (xy 267.428403 -102.542088) (xy 267.378478 -102.555985) (xy 267.32713 -102.562993)
			(xy 267.301218 -102.563422) (xy 267.273965 -102.562932) (xy 267.220014 -102.555177) (xy 267.167716 -102.539823)
			(xy 267.118136 -102.517183) (xy 267.072282 -102.487716) (xy 267.031089 -102.452024) (xy 266.995394 -102.410832)
			(xy 266.965926 -102.36498) (xy 266.943283 -102.315401) (xy 266.927927 -102.263103) (xy 266.920169 -102.209153)
			(xy 266.920169 -102.154647) (xy 266.927927 -102.100697) (xy 266.943283 -102.048399) (xy 266.965926 -101.99882)
			(xy 266.995394 -101.952968) (xy 267.031089 -101.911776) (xy 267.072282 -101.876084) (xy 267.118136 -101.846617)
			(xy 267.167716 -101.823977) (xy 267.220014 -101.808623) (xy 267.273965 -101.800868) (xy 267.301218 -101.800406)
			(xy 267.316011 -101.800537) (xy 267.345509 -101.802829) (xy 267.360146 -101.804978) (xy 267.37112 -101.806128)
			(xy 267.392314 -101.800051) (xy 267.40104 -101.793294) (xy 267.45946 -101.743256) (xy 267.467465 -101.735668)
			(xy 267.476691 -101.715663) (xy 267.47724 -101.704648) (xy 267.47724 -101.400356) (xy 267.476658 -101.389343)
			(xy 267.467468 -101.369326) (xy 267.45946 -101.361748) (xy 267.392404 -101.304344) (xy 267.371322 -101.298248)
			(xy 267.360146 -101.300026) (xy 267.345508 -101.302168) (xy 267.316011 -101.304455) (xy 267.301218 -101.304598)
			(xy 267.273964 -101.304156) (xy 267.220009 -101.296401) (xy 267.167708 -101.281046) (xy 267.118124 -101.258404)
			(xy 267.072267 -101.228936) (xy 267.031071 -101.193241) (xy 266.995375 -101.152047) (xy 266.965904 -101.106192)
			(xy 266.94326 -101.056609) (xy 266.927903 -101.004308) (xy 266.920145 -100.950354) (xy 264.846816 -100.950354)
			(xy 264.846816 -101.72954) (xy 264.846434 -101.739615) (xy 264.838685 -101.758213) (xy 264.83183 -101.765608)
			(xy 263.853583 -102.743855) (xy 268.952639 -102.743855) (xy 268.952639 -102.689345) (xy 268.960397 -102.635389)
			(xy 268.975755 -102.583087) (xy 268.9984 -102.533503) (xy 269.027872 -102.487647) (xy 269.06357 -102.446452)
			(xy 269.104768 -102.410756) (xy 269.150626 -102.381288) (xy 269.200211 -102.358646) (xy 269.252515 -102.343291)
			(xy 269.306471 -102.335537) (xy 269.333726 -102.335076) (xy 269.359633 -102.335556) (xy 269.410968 -102.342582)
			(xy 269.460881 -102.356488) (xy 269.508454 -102.377019) (xy 269.552812 -102.403797) (xy 269.59314 -102.436329)
			(xy 269.628696 -102.474018) (xy 269.644114 -102.494842) (xy 269.649848 -102.502178) (xy 269.665355 -102.512462)
			(xy 269.67434 -102.514908) (xy 269.70482 -102.521766) (xy 269.714099 -102.523494) (xy 269.732759 -102.520765)
			(xy 269.741142 -102.516432) (xy 269.767129 -102.502177) (xy 269.821994 -102.479745) (xy 269.879295 -102.464578)
			(xy 269.938073 -102.456931) (xy 269.997347 -102.456931) (xy 270.056125 -102.464578) (xy 270.113426 -102.479745)
			(xy 270.168291 -102.502177) (xy 270.194278 -102.516432) (xy 270.202692 -102.520676) (xy 270.221321 -102.523412)
			(xy 270.2306 -102.521766) (xy 270.26108 -102.514908) (xy 270.270075 -102.512487) (xy 270.285578 -102.502189)
			(xy 270.291306 -102.494842) (xy 270.306677 -102.473978) (xy 270.342227 -102.436269) (xy 270.382556 -102.403722)
			(xy 270.426922 -102.376936) (xy 270.474507 -102.356407) (xy 270.524433 -102.342511) (xy 270.575782 -102.335505)
			(xy 270.601694 -102.335076) (xy 270.628946 -102.335571) (xy 270.682895 -102.343327) (xy 270.735192 -102.358682)
			(xy 270.78477 -102.381323) (xy 270.830622 -102.41079) (xy 270.870171 -102.445058) (xy 276.86965 -102.445058)
			(xy 276.873721 -102.389436) (xy 276.885847 -102.334999) (xy 276.90577 -102.282908) (xy 276.933066 -102.234273)
			(xy 276.967152 -102.19013) (xy 277.007301 -102.151421) (xy 277.052659 -102.11897) (xy 277.102259 -102.093469)
			(xy 277.155043 -102.075462) (xy 277.209886 -102.065332) (xy 277.26562 -102.063295) (xy 277.321057 -102.069395)
			(xy 277.375014 -102.083501) (xy 277.426343 -102.105313) (xy 277.473949 -102.134367) (xy 277.516817 -102.170042)
			(xy 277.554034 -102.211579) (xy 277.584807 -102.258092) (xy 277.608479 -102.308589) (xy 277.624547 -102.361996)
			(xy 277.632667 -102.417172) (xy 277.633176 -102.445058) (xy 277.632667 -102.472944) (xy 277.624547 -102.52812)
			(xy 277.608479 -102.581527) (xy 277.584807 -102.632024) (xy 277.554034 -102.678537) (xy 277.516817 -102.720074)
			(xy 277.473949 -102.755749) (xy 277.426343 -102.784803) (xy 277.375014 -102.806615) (xy 277.321057 -102.820721)
			(xy 277.26562 -102.826821) (xy 277.209886 -102.824784) (xy 277.155043 -102.814654) (xy 277.102259 -102.796647)
			(xy 277.052659 -102.771146) (xy 277.007301 -102.738695) (xy 276.967152 -102.699986) (xy 276.933066 -102.655843)
			(xy 276.90577 -102.607208) (xy 276.885847 -102.555117) (xy 276.873721 -102.50068) (xy 276.86965 -102.445058)
			(xy 270.870171 -102.445058) (xy 270.871814 -102.446482) (xy 270.907507 -102.487673) (xy 270.936974 -102.533524)
			(xy 270.959616 -102.583103) (xy 270.974972 -102.635399) (xy 270.982729 -102.689348) (xy 270.982729 -102.743852)
			(xy 270.974972 -102.797801) (xy 270.96041 -102.847394) (xy 279.175716 -102.847394) (xy 279.179787 -102.791772)
			(xy 279.191913 -102.737335) (xy 279.211836 -102.685244) (xy 279.239132 -102.636609) (xy 279.273218 -102.592466)
			(xy 279.313367 -102.553757) (xy 279.358725 -102.521306) (xy 279.408325 -102.495805) (xy 279.461109 -102.477798)
			(xy 279.515952 -102.467668) (xy 279.571686 -102.465631) (xy 279.627123 -102.471731) (xy 279.629502 -102.472353)
			(xy 283.452036 -102.472353) (xy 283.452036 -102.417847) (xy 283.459792 -102.363897) (xy 283.475147 -102.3116)
			(xy 283.497788 -102.26202) (xy 283.527254 -102.216166) (xy 283.562945 -102.174972) (xy 283.604135 -102.139277)
			(xy 283.649986 -102.109806) (xy 283.699564 -102.08716) (xy 283.75186 -102.0718) (xy 283.80581 -102.064038)
			(xy 283.833062 -102.06355) (xy 283.85011 -102.063747) (xy 283.88407 -102.066801) (xy 283.90088 -102.069646)
			(xy 283.912207 -102.071083) (xy 283.934224 -102.065147) (xy 283.943298 -102.058216) (xy 283.967682 -102.037134)
			(xy 283.976132 -102.029175) (xy 283.985246 -102.00785) (xy 283.985208 -101.99624) (xy 283.9847 -101.976428)
			(xy 283.9847 -101.112828) (xy 283.985208 -101.093778) (xy 283.985168 -101.082187) (xy 283.976054 -101.0609)
			(xy 283.967682 -101.052884) (xy 283.943298 -101.032056) (xy 283.934316 -101.025073) (xy 283.912426 -101.018996)
			(xy 283.901134 -101.020372) (xy 283.884263 -101.02324) (xy 283.850174 -101.026294) (xy 283.833062 -101.026468)
			(xy 283.80581 -101.02606) (xy 283.75186 -101.018298) (xy 283.699565 -101.002938) (xy 283.649987 -100.980292)
			(xy 283.604137 -100.950822) (xy 283.562947 -100.915126) (xy 283.527255 -100.873933) (xy 283.49779 -100.828079)
			(xy 283.475149 -100.7785) (xy 283.459794 -100.726202) (xy 283.452038 -100.672252) (xy 283.452038 -100.617748)
			(xy 283.459794 -100.563798) (xy 283.475149 -100.5115) (xy 283.49779 -100.46192) (xy 283.527255 -100.416067)
			(xy 283.562947 -100.374874) (xy 283.604137 -100.339178) (xy 283.649987 -100.309708) (xy 283.699565 -100.287062)
			(xy 283.75186 -100.271702) (xy 283.80581 -100.26394) (xy 283.833062 -100.263452) (xy 283.860041 -100.263868)
			(xy 283.913462 -100.271458) (xy 283.965279 -100.286505) (xy 284.014457 -100.308709) (xy 284.060011 -100.337625)
			(xy 284.101033 -100.372677) (xy 284.136703 -100.413163) (xy 284.166306 -100.458274) (xy 284.189252 -100.50711)
			(xy 284.205083 -100.558693) (xy 284.209744 -100.58527) (xy 284.211938 -100.595491) (xy 284.223198 -100.613074)
			(xy 284.231588 -100.619306) (xy 284.302962 -100.666804) (xy 284.324044 -100.670614) (xy 284.334204 -100.668074)
			(xy 284.360906 -100.662003) (xy 284.415281 -100.655507) (xy 284.442662 -100.65512) (xy 284.470044 -100.655488)
			(xy 284.52442 -100.661987) (xy 284.55112 -100.668074) (xy 284.56128 -100.670614) (xy 284.582362 -100.666804)
			(xy 284.662626 -100.613464) (xy 284.673802 -100.595938) (xy 284.67558 -100.58527) (xy 284.680221 -100.558694)
			(xy 284.696079 -100.507128) (xy 284.719045 -100.45831) (xy 284.748661 -100.413216) (xy 284.784334 -100.372744)
			(xy 284.825354 -100.337703) (xy 284.870903 -100.308791) (xy 284.920071 -100.286585) (xy 284.971877 -100.271528)
			(xy 285.025287 -100.263921) (xy 285.052262 -100.263452) (xy 285.079632 -100.263928) (xy 285.133811 -100.271741)
			(xy 285.186315 -100.287227) (xy 285.236062 -100.310067) (xy 285.282029 -100.339791) (xy 285.30296 -100.357432)
			(xy 285.303214 -100.357686) (xy 285.310294 -100.363283) (xy 285.327216 -100.369524) (xy 285.336234 -100.369878)
			(xy 285.40329 -100.369878) (xy 285.412307 -100.369521) (xy 285.429224 -100.363274) (xy 285.43631 -100.357686)
			(xy 285.43631 -100.357432) (xy 285.436564 -100.357432) (xy 285.457503 -100.339801) (xy 285.503473 -100.310087)
			(xy 285.553219 -100.287249) (xy 285.605718 -100.271756) (xy 285.659893 -100.263927) (xy 285.687262 -100.263452)
			(xy 285.70431 -100.263649) (xy 285.73827 -100.266703) (xy 285.75508 -100.269548) (xy 285.766407 -100.270985)
			(xy 285.788424 -100.265048) (xy 285.797498 -100.258118) (xy 285.821882 -100.237036) (xy 285.830331 -100.229076)
			(xy 285.839445 -100.207752) (xy 285.839408 -100.196142) (xy 285.8389 -100.17633) (xy 285.8389 -99.31273)
			(xy 285.839408 -99.29368) (xy 285.839366 -99.282089) (xy 285.830253 -99.260802) (xy 285.821882 -99.252786)
			(xy 285.797498 -99.231958) (xy 285.788516 -99.224975) (xy 285.766626 -99.218898) (xy 285.755334 -99.220274)
			(xy 285.738463 -99.223142) (xy 285.704374 -99.226196) (xy 285.687262 -99.22637) (xy 285.66001 -99.225958)
			(xy 285.606061 -99.218196) (xy 285.553765 -99.202836) (xy 285.504188 -99.18019) (xy 285.458338 -99.15072)
			(xy 285.417148 -99.115025) (xy 285.381457 -99.073832) (xy 285.351991 -99.027979) (xy 285.329351 -98.978399)
			(xy 285.313996 -98.926102) (xy 285.30624 -98.872152) (xy 285.30624 -98.817648) (xy 285.313996 -98.763698)
			(xy 285.329351 -98.711401) (xy 285.351991 -98.661821) (xy 285.381457 -98.615968) (xy 285.417148 -98.574775)
			(xy 285.458338 -98.53908) (xy 285.504188 -98.50961) (xy 285.553765 -98.486964) (xy 285.606061 -98.471604)
			(xy 285.66001 -98.463842) (xy 285.687262 -98.463354) (xy 285.714241 -98.463769) (xy 285.767662 -98.471358)
			(xy 285.819479 -98.486405) (xy 285.868657 -98.508609) (xy 285.914212 -98.537526) (xy 285.955234 -98.572578)
			(xy 285.990903 -98.613064) (xy 286.020507 -98.658176) (xy 286.043453 -98.707011) (xy 286.059283 -98.758595)
			(xy 286.063944 -98.785172) (xy 286.066137 -98.795394) (xy 286.077397 -98.812976) (xy 286.085788 -98.819208)
			(xy 286.157162 -98.866706) (xy 286.178244 -98.870516) (xy 286.188404 -98.867976) (xy 286.2151 -98.861844)
			(xy 286.269474 -98.855217) (xy 286.296862 -98.854768) (xy 286.32425 -98.855215) (xy 286.378626 -98.861834)
			(xy 286.40532 -98.867976) (xy 286.41548 -98.870516) (xy 286.436562 -98.866706) (xy 286.516826 -98.813366)
			(xy 286.528002 -98.79584) (xy 286.52978 -98.785172) (xy 286.534422 -98.758596) (xy 286.550281 -98.70703)
			(xy 286.573246 -98.658213) (xy 286.602861 -98.613118) (xy 286.638535 -98.572647) (xy 286.679555 -98.537605)
			(xy 286.725103 -98.508693) (xy 286.774271 -98.486487) (xy 286.826077 -98.47143) (xy 286.879487 -98.463823)
			(xy 286.906462 -98.463354) (xy 286.933714 -98.463891) (xy 286.987664 -98.471642) (xy 287.039961 -98.486994)
			(xy 287.089541 -98.509632) (xy 287.135394 -98.539096) (xy 287.176587 -98.574786) (xy 287.212281 -98.615975)
			(xy 287.24175 -98.661826) (xy 287.264393 -98.711404) (xy 287.279749 -98.763699) (xy 287.287507 -98.817648)
			(xy 287.287507 -98.872152) (xy 287.279749 -98.926101) (xy 287.264393 -98.978396) (xy 287.24175 -99.027974)
			(xy 287.212281 -99.073825) (xy 287.176587 -99.115014) (xy 287.135394 -99.150704) (xy 287.089541 -99.180168)
			(xy 287.074578 -99.187) (xy 301.521874 -99.187) (xy 301.525945 -99.131378) (xy 301.538071 -99.076941)
			(xy 301.557994 -99.02485) (xy 301.58529 -98.976215) (xy 301.619376 -98.932072) (xy 301.659525 -98.893363)
			(xy 301.704883 -98.860912) (xy 301.754483 -98.835411) (xy 301.807267 -98.817404) (xy 301.86211 -98.807274)
			(xy 301.917844 -98.805237) (xy 301.973281 -98.811337) (xy 302.027238 -98.825443) (xy 302.078567 -98.847255)
			(xy 302.126173 -98.876309) (xy 302.169041 -98.911984) (xy 302.206258 -98.953521) (xy 302.237031 -99.000034)
			(xy 302.254664 -99.037648) (xy 310.369456 -99.037648) (xy 310.373527 -98.982026) (xy 310.385653 -98.927589)
			(xy 310.405576 -98.875498) (xy 310.432872 -98.826863) (xy 310.466958 -98.78272) (xy 310.507107 -98.744011)
			(xy 310.552465 -98.71156) (xy 310.602065 -98.686059) (xy 310.654849 -98.668052) (xy 310.709692 -98.657922)
			(xy 310.765426 -98.655885) (xy 310.820863 -98.661985) (xy 310.87482 -98.676091) (xy 310.926149 -98.697903)
			(xy 310.973755 -98.726957) (xy 311.012881 -98.759518) (xy 331.371194 -98.759518) (xy 331.371672 -98.732148)
			(xy 331.379487 -98.67797) (xy 331.394974 -98.625467) (xy 331.417813 -98.57572) (xy 331.447534 -98.529752)
			(xy 331.465174 -98.50882) (xy 331.465428 -98.508566) (xy 331.470996 -98.501467) (xy 331.477253 -98.48456)
			(xy 331.47762 -98.475546) (xy 331.47762 -98.40849) (xy 331.477263 -98.399473) (xy 331.471015 -98.382557)
			(xy 331.465428 -98.37547) (xy 331.465174 -98.37547) (xy 331.465174 -98.375216) (xy 331.447549 -98.35427)
			(xy 331.41782 -98.308306) (xy 331.394971 -98.258562) (xy 331.379471 -98.206061) (xy 331.37164 -98.151884)
			(xy 331.371638 -98.097143) (xy 331.379465 -98.042965) (xy 331.394961 -97.990464) (xy 331.417807 -97.940718)
			(xy 331.447533 -97.894752) (xy 331.465174 -97.87382) (xy 331.465428 -97.873566) (xy 331.470996 -97.866467)
			(xy 331.477253 -97.84956) (xy 331.47762 -97.840546) (xy 331.47762 -97.77349) (xy 331.477263 -97.764473)
			(xy 331.471015 -97.747557) (xy 331.465428 -97.74047) (xy 331.465174 -97.74047) (xy 331.465174 -97.740216)
			(xy 331.447525 -97.719292) (xy 331.417815 -97.673317) (xy 331.394982 -97.623567) (xy 331.379493 -97.571065)
			(xy 331.371667 -97.516888) (xy 331.371194 -97.489518) (xy 331.37168 -97.462267) (xy 331.379436 -97.408319)
			(xy 331.394791 -97.356024) (xy 331.417433 -97.306447) (xy 331.446899 -97.260597) (xy 331.48259 -97.219406)
			(xy 331.523781 -97.183715) (xy 331.569631 -97.154249) (xy 331.619208 -97.131607) (xy 331.671503 -97.116252)
			(xy 331.725451 -97.108496) (xy 331.779953 -97.108496) (xy 331.833901 -97.116252) (xy 331.886196 -97.131607)
			(xy 331.935773 -97.154249) (xy 331.981623 -97.183715) (xy 332.022814 -97.219406) (xy 332.058505 -97.260597)
			(xy 332.087971 -97.306447) (xy 332.110613 -97.356024) (xy 332.125968 -97.408319) (xy 332.133724 -97.462267)
			(xy 332.13421 -97.489518) (xy 332.133752 -97.516888) (xy 332.125932 -97.571068) (xy 332.110441 -97.623571)
			(xy 332.087597 -97.673318) (xy 332.057872 -97.719284) (xy 332.04023 -97.740216) (xy 332.039976 -97.74047)
			(xy 332.034393 -97.747559) (xy 332.028145 -97.764474) (xy 332.027784 -97.77349) (xy 332.027784 -97.840546)
			(xy 332.02817 -97.84956) (xy 332.034398 -97.866477) (xy 332.039976 -97.873566) (xy 332.04023 -97.873566)
			(xy 332.04023 -97.87382) (xy 332.05789 -97.894738) (xy 332.087617 -97.940707) (xy 332.110464 -97.990455)
			(xy 332.125961 -98.04296) (xy 332.133789 -98.097142) (xy 332.133787 -98.151886) (xy 332.125955 -98.206066)
			(xy 332.110455 -98.25857) (xy 332.087604 -98.308317) (xy 332.057874 -98.354284) (xy 332.04023 -98.375216)
			(xy 332.039976 -98.37547) (xy 332.034393 -98.382559) (xy 332.028145 -98.399474) (xy 332.027784 -98.40849)
			(xy 332.027784 -98.475546) (xy 332.02817 -98.48456) (xy 332.034398 -98.501477) (xy 332.036031 -98.503552)
			(xy 333.025963 -98.503552) (xy 333.025963 -98.449048) (xy 333.03372 -98.395097) (xy 333.049076 -98.3428)
			(xy 333.071718 -98.293221) (xy 333.101186 -98.247369) (xy 333.13688 -98.206177) (xy 333.178072 -98.170484)
			(xy 333.223924 -98.141017) (xy 333.273504 -98.118375) (xy 333.325801 -98.103019) (xy 333.379752 -98.095263)
			(xy 333.407004 -98.0948) (xy 333.433318 -98.095265) (xy 333.485447 -98.1025) (xy 333.536089 -98.11682)
			(xy 333.584288 -98.137953) (xy 333.629132 -98.165499) (xy 333.669771 -98.198938) (xy 333.687928 -98.21799)
			(xy 333.695439 -98.225404) (xy 333.714727 -98.233922) (xy 333.725266 -98.2345) (xy 333.799942 -98.2345)
			(xy 333.81049 -98.233953) (xy 333.829785 -98.225431) (xy 333.83728 -98.21799) (xy 333.85545 -98.198949)
			(xy 333.896077 -98.165491) (xy 333.940914 -98.13793) (xy 333.989112 -98.116789) (xy 334.039757 -98.102469)
			(xy 334.091889 -98.095241) (xy 334.118204 -98.0948) (xy 334.145456 -98.09527) (xy 334.199404 -98.103027)
			(xy 334.251699 -98.118383) (xy 334.301277 -98.141025) (xy 334.347128 -98.170492) (xy 334.388319 -98.206184)
			(xy 334.424011 -98.247375) (xy 334.453477 -98.293226) (xy 334.473172 -98.336354) (xy 335.049368 -98.336354)
			(xy 335.049849 -98.308984) (xy 335.057661 -98.254805) (xy 335.073145 -98.202301) (xy 335.095984 -98.152554)
			(xy 335.125707 -98.106587) (xy 335.143348 -98.085656) (xy 335.143602 -98.085402) (xy 335.149194 -98.078319)
			(xy 335.155437 -98.0614) (xy 335.155794 -98.052382) (xy 335.155794 -97.985326) (xy 335.155426 -97.97631)
			(xy 335.149186 -97.959393) (xy 335.143602 -97.952306) (xy 335.143348 -97.952306) (xy 335.143348 -97.952052)
			(xy 335.125661 -97.931156) (xy 335.095937 -97.885182) (xy 335.073093 -97.83543) (xy 335.057599 -97.782922)
			(xy 335.049775 -97.728738) (xy 335.049779 -97.673992) (xy 335.057614 -97.61981) (xy 335.073117 -97.567305)
			(xy 335.09597 -97.517557) (xy 335.125703 -97.471588) (xy 335.143348 -97.450656) (xy 335.143602 -97.450402)
			(xy 335.149194 -97.443319) (xy 335.155437 -97.4264) (xy 335.155794 -97.417382) (xy 335.155794 -97.350326)
			(xy 335.155426 -97.34131) (xy 335.149186 -97.324393) (xy 335.143602 -97.317306) (xy 335.143348 -97.317306)
			(xy 335.143348 -97.317052) (xy 335.125727 -97.296105) (xy 335.096011 -97.250137) (xy 335.073171 -97.200393)
			(xy 335.057676 -97.147896) (xy 335.049844 -97.093722) (xy 335.049368 -97.066354) (xy 335.049854 -97.039103)
			(xy 335.05761 -96.985155) (xy 335.072965 -96.93286) (xy 335.095607 -96.883283) (xy 335.125073 -96.837433)
			(xy 335.160764 -96.796242) (xy 335.201955 -96.760551) (xy 335.247805 -96.731085) (xy 335.297382 -96.708443)
			(xy 335.349677 -96.693088) (xy 335.403625 -96.685332) (xy 335.458127 -96.685332) (xy 335.512075 -96.693088)
			(xy 335.56437 -96.708443) (xy 335.613947 -96.731085) (xy 335.659797 -96.760551) (xy 335.700988 -96.796242)
			(xy 335.736679 -96.837433) (xy 335.766145 -96.883283) (xy 335.788787 -96.93286) (xy 335.804142 -96.985155)
			(xy 335.811898 -97.039103) (xy 335.812384 -97.066354) (xy 335.811895 -97.093723) (xy 335.804083 -97.147902)
			(xy 335.7886 -97.200405) (xy 335.765763 -97.250152) (xy 335.736043 -97.29612) (xy 335.718404 -97.317052)
			(xy 335.71815 -97.317306) (xy 335.712549 -97.324382) (xy 335.706312 -97.341307) (xy 335.705958 -97.350326)
			(xy 335.705958 -97.417382) (xy 335.706311 -97.4264) (xy 335.71256 -97.443317) (xy 335.71815 -97.450402)
			(xy 335.718404 -97.450402) (xy 335.718404 -97.450656) (xy 335.735998 -97.471626) (xy 335.765723 -97.517588)
			(xy 335.788569 -97.567328) (xy 335.804067 -97.619824) (xy 335.8119 -97.673997) (xy 335.811904 -97.728733)
			(xy 335.804082 -97.782908) (xy 335.788593 -97.835407) (xy 335.765756 -97.885151) (xy 335.73604 -97.931119)
			(xy 335.718404 -97.952052) (xy 335.71815 -97.952306) (xy 335.712549 -97.959382) (xy 335.706312 -97.976307)
			(xy 335.705958 -97.985326) (xy 335.705958 -98.052382) (xy 335.706311 -98.0614) (xy 335.71256 -98.078317)
			(xy 335.71815 -98.085402) (xy 335.718404 -98.085402) (xy 335.718404 -98.085656) (xy 335.736037 -98.106593)
			(xy 335.765749 -98.152565) (xy 335.788586 -98.202311) (xy 335.792404 -98.215249) (xy 337.158596 -98.215249)
			(xy 337.158596 -98.160751) (xy 337.166352 -98.106807) (xy 337.181705 -98.054516) (xy 337.204344 -98.004942)
			(xy 337.233808 -97.959095) (xy 337.269496 -97.917907) (xy 337.310682 -97.882217) (xy 337.356528 -97.852752)
			(xy 337.406101 -97.830111) (xy 337.458391 -97.814755) (xy 337.512335 -97.806997) (xy 337.539584 -97.80651)
			(xy 337.569852 -97.807077) (xy 337.629627 -97.816648) (xy 337.687141 -97.835535) (xy 337.740952 -97.863266)
			(xy 337.78971 -97.899145) (xy 337.811364 -97.920302) (xy 337.818785 -97.927252) (xy 337.837527 -97.935099)
			(xy 337.847686 -97.935542) (xy 337.919822 -97.935542) (xy 337.929984 -97.935129) (xy 337.94872 -97.927256)
			(xy 337.956144 -97.920302) (xy 337.977796 -97.899144) (xy 338.026551 -97.863261) (xy 338.080363 -97.83553)
			(xy 338.137879 -97.816648) (xy 338.197656 -97.807089) (xy 338.227924 -97.80651) (xy 338.25776 -97.807056)
			(xy 338.316701 -97.816363) (xy 338.373475 -97.83473) (xy 338.426699 -97.861709) (xy 338.475075 -97.896644)
			(xy 338.496656 -97.917254) (xy 338.503768 -97.924366) (xy 338.52231 -97.931986) (xy 338.614004 -97.931986)
			(xy 338.632546 -97.924366) (xy 338.639658 -97.917254) (xy 338.661247 -97.896655) (xy 338.709619 -97.861718)
			(xy 338.762841 -97.834741) (xy 338.819615 -97.816382) (xy 338.878556 -97.807088) (xy 338.90839 -97.80651)
			(xy 338.935645 -97.806936) (xy 338.989599 -97.814692) (xy 339.041901 -97.830048) (xy 339.091485 -97.852691)
			(xy 339.137341 -97.88216) (xy 339.178537 -97.917856) (xy 339.214234 -97.959051) (xy 339.243704 -98.004907)
			(xy 339.266348 -98.05449) (xy 339.281705 -98.106791) (xy 339.289463 -98.160745) (xy 339.289463 -98.215255)
			(xy 339.281705 -98.269209) (xy 339.266348 -98.32151) (xy 339.243704 -98.371093) (xy 339.214234 -98.416949)
			(xy 339.178537 -98.458144) (xy 339.137341 -98.49384) (xy 339.091485 -98.523309) (xy 339.041901 -98.545952)
			(xy 338.989599 -98.561308) (xy 338.935645 -98.569064) (xy 338.90839 -98.569526) (xy 338.878555 -98.56896)
			(xy 338.819615 -98.559657) (xy 338.762842 -98.541294) (xy 338.709617 -98.514319) (xy 338.66124 -98.47939)
			(xy 338.639658 -98.458782) (xy 338.632546 -98.45167) (xy 338.614004 -98.44405) (xy 338.52231 -98.44405)
			(xy 338.503768 -98.45167) (xy 338.496656 -98.458782) (xy 338.475094 -98.479412) (xy 338.426716 -98.514346)
			(xy 338.373487 -98.541319) (xy 338.316707 -98.559671) (xy 338.25776 -98.568954) (xy 338.227924 -98.569526)
			(xy 338.197657 -98.568944) (xy 338.137883 -98.559375) (xy 338.080369 -98.540491) (xy 338.026558 -98.512763)
			(xy 337.977799 -98.476889) (xy 337.956144 -98.455734) (xy 337.948716 -98.448792) (xy 337.92998 -98.440939)
			(xy 337.919822 -98.440494) (xy 337.847686 -98.440494) (xy 337.837523 -98.440902) (xy 337.818786 -98.448778)
			(xy 337.811364 -98.455734) (xy 337.789714 -98.476895) (xy 337.740958 -98.512776) (xy 337.687146 -98.540506)
			(xy 337.629629 -98.559387) (xy 337.569852 -98.568947) (xy 337.539584 -98.569526) (xy 337.512335 -98.569003)
			(xy 337.458391 -98.561245) (xy 337.406101 -98.545889) (xy 337.356528 -98.523248) (xy 337.310682 -98.493783)
			(xy 337.269496 -98.458093) (xy 337.233808 -98.416905) (xy 337.204344 -98.371058) (xy 337.181705 -98.321484)
			(xy 337.166352 -98.269193) (xy 337.158596 -98.215249) (xy 335.792404 -98.215249) (xy 335.804079 -98.25481)
			(xy 335.811909 -98.308985) (xy 335.812384 -98.336354) (xy 335.811898 -98.363605) (xy 335.804142 -98.417553)
			(xy 335.788787 -98.469848) (xy 335.766145 -98.519425) (xy 335.736679 -98.565275) (xy 335.700988 -98.606466)
			(xy 335.659797 -98.642157) (xy 335.613947 -98.671623) (xy 335.56437 -98.694265) (xy 335.512075 -98.70962)
			(xy 335.458127 -98.717376) (xy 335.403625 -98.717376) (xy 335.349677 -98.70962) (xy 335.297382 -98.694265)
			(xy 335.247805 -98.671623) (xy 335.201955 -98.642157) (xy 335.160764 -98.606466) (xy 335.125073 -98.565275)
			(xy 335.095607 -98.519425) (xy 335.072965 -98.469848) (xy 335.05761 -98.417553) (xy 335.049854 -98.363605)
			(xy 335.049368 -98.336354) (xy 334.473172 -98.336354) (xy 334.476118 -98.342804) (xy 334.491474 -98.3951)
			(xy 334.49923 -98.449048) (xy 334.49923 -98.503552) (xy 334.491474 -98.5575) (xy 334.476118 -98.609796)
			(xy 334.453477 -98.659374) (xy 334.424011 -98.705225) (xy 334.388319 -98.746416) (xy 334.347128 -98.782108)
			(xy 334.301277 -98.811575) (xy 334.251699 -98.834217) (xy 334.199404 -98.849573) (xy 334.145456 -98.85733)
			(xy 334.118204 -98.857816) (xy 334.09189 -98.857341) (xy 334.039762 -98.850107) (xy 333.98912 -98.835789)
			(xy 333.940921 -98.814658) (xy 333.896077 -98.787113) (xy 333.855437 -98.753677) (xy 333.83728 -98.734626)
			(xy 333.829764 -98.727217) (xy 333.81048 -98.718696) (xy 333.799942 -98.718116) (xy 333.725266 -98.718116)
			(xy 333.714718 -98.718663) (xy 333.695422 -98.727185) (xy 333.687928 -98.734626) (xy 333.669757 -98.753666)
			(xy 333.62913 -98.787123) (xy 333.584293 -98.814684) (xy 333.536095 -98.835825) (xy 333.485451 -98.850146)
			(xy 333.433319 -98.857375) (xy 333.407004 -98.857816) (xy 333.379752 -98.857337) (xy 333.325801 -98.849581)
			(xy 333.273504 -98.834225) (xy 333.223924 -98.811583) (xy 333.178072 -98.782116) (xy 333.13688 -98.746423)
			(xy 333.101186 -98.705231) (xy 333.071718 -98.659379) (xy 333.049076 -98.6098) (xy 333.03372 -98.557503)
			(xy 333.025963 -98.503552) (xy 332.036031 -98.503552) (xy 332.039976 -98.508566) (xy 332.04023 -98.509074)
			(xy 332.051175 -98.521807) (xy 332.071016 -98.548899) (xy 332.079854 -98.563176) (xy 332.085188 -98.572066)
			(xy 332.102206 -98.584258) (xy 332.195424 -98.604578) (xy 332.215998 -98.60026) (xy 332.224634 -98.594418)
			(xy 332.248689 -98.578403) (xy 332.300623 -98.553064) (xy 332.355784 -98.535842) (xy 332.412911 -98.527132)
			(xy 332.441804 -98.5266) (xy 332.469056 -98.52707) (xy 332.523004 -98.534827) (xy 332.575299 -98.550183)
			(xy 332.624877 -98.572825) (xy 332.670728 -98.602292) (xy 332.711919 -98.637984) (xy 332.747611 -98.679175)
			(xy 332.777077 -98.725026) (xy 332.799718 -98.774604) (xy 332.815074 -98.8269) (xy 332.82283 -98.880848)
			(xy 332.82283 -98.935352) (xy 332.815074 -98.9893) (xy 332.799718 -99.041596) (xy 332.777077 -99.091174)
			(xy 332.747611 -99.137025) (xy 332.711919 -99.178216) (xy 332.670728 -99.213908) (xy 332.624877 -99.243375)
			(xy 332.575299 -99.266017) (xy 332.523004 -99.281373) (xy 332.469056 -99.28913) (xy 332.441804 -99.289616)
			(xy 332.413713 -99.289119) (xy 332.358135 -99.280892) (xy 332.304367 -99.264601) (xy 332.253569 -99.240599)
			(xy 332.206842 -99.209405) (xy 332.165197 -99.171693) (xy 332.129535 -99.12828) (xy 332.114652 -99.10445)
			(xy 332.109318 -99.09556) (xy 332.0923 -99.083368) (xy 331.999082 -99.063048) (xy 331.978508 -99.067366)
			(xy 331.969872 -99.073208) (xy 331.945818 -99.089223) (xy 331.893883 -99.114562) (xy 331.838722 -99.131784)
			(xy 331.781595 -99.140494) (xy 331.752702 -99.141026) (xy 331.725452 -99.14052) (xy 331.671506 -99.132765)
			(xy 331.619212 -99.117411) (xy 331.569636 -99.094771) (xy 331.523787 -99.065307) (xy 331.482597 -99.029617)
			(xy 331.446905 -98.988429) (xy 331.417439 -98.942581) (xy 331.394796 -98.893007) (xy 331.37944 -98.840714)
			(xy 331.371681 -98.786768) (xy 331.371194 -98.759518) (xy 311.012881 -98.759518) (xy 311.016623 -98.762632)
			(xy 311.05384 -98.804169) (xy 311.084613 -98.850682) (xy 311.108285 -98.901179) (xy 311.124353 -98.954586)
			(xy 311.132473 -99.009762) (xy 311.132982 -99.037648) (xy 311.132473 -99.065534) (xy 311.124353 -99.12071)
			(xy 311.108285 -99.174117) (xy 311.084613 -99.224614) (xy 311.05384 -99.271127) (xy 311.016623 -99.312664)
			(xy 310.973755 -99.348339) (xy 310.926149 -99.377393) (xy 310.87482 -99.399205) (xy 310.820863 -99.413311)
			(xy 310.765426 -99.419411) (xy 310.709692 -99.417374) (xy 310.654849 -99.407244) (xy 310.602065 -99.389237)
			(xy 310.552465 -99.363736) (xy 310.507107 -99.331285) (xy 310.466958 -99.292576) (xy 310.432872 -99.248433)
			(xy 310.405576 -99.199798) (xy 310.385653 -99.147707) (xy 310.373527 -99.09327) (xy 310.369456 -99.037648)
			(xy 302.254664 -99.037648) (xy 302.260703 -99.050531) (xy 302.276771 -99.103938) (xy 302.284891 -99.159114)
			(xy 302.2854 -99.187) (xy 302.284891 -99.214886) (xy 302.276771 -99.270062) (xy 302.260703 -99.323469)
			(xy 302.237031 -99.373966) (xy 302.206258 -99.420479) (xy 302.169041 -99.462016) (xy 302.126173 -99.497691)
			(xy 302.078567 -99.526745) (xy 302.027238 -99.548557) (xy 301.973281 -99.562663) (xy 301.917844 -99.568763)
			(xy 301.86211 -99.566726) (xy 301.807267 -99.556596) (xy 301.754483 -99.538589) (xy 301.704883 -99.513088)
			(xy 301.659525 -99.480637) (xy 301.619376 -99.441928) (xy 301.58529 -99.397785) (xy 301.557994 -99.34915)
			(xy 301.538071 -99.297059) (xy 301.525945 -99.242622) (xy 301.521874 -99.187) (xy 287.074578 -99.187)
			(xy 287.039961 -99.202806) (xy 286.987664 -99.218158) (xy 286.933714 -99.225909) (xy 286.906462 -99.22637)
			(xy 286.88935 -99.226175) (xy 286.855263 -99.223125) (xy 286.83839 -99.220274) (xy 286.827098 -99.218922)
			(xy 286.805209 -99.224984) (xy 286.796226 -99.231958) (xy 286.771842 -99.252786) (xy 286.763435 -99.260782)
			(xy 286.754296 -99.282079) (xy 286.754316 -99.29368) (xy 286.754824 -99.31273) (xy 286.754824 -99.750372)
			(xy 289.797742 -99.750372) (xy 289.801813 -99.69475) (xy 289.813939 -99.640313) (xy 289.833862 -99.588222)
			(xy 289.861158 -99.539587) (xy 289.895244 -99.495444) (xy 289.935393 -99.456735) (xy 289.980751 -99.424284)
			(xy 290.030351 -99.398783) (xy 290.083135 -99.380776) (xy 290.137978 -99.370646) (xy 290.193712 -99.368609)
			(xy 290.249149 -99.374709) (xy 290.303106 -99.388815) (xy 290.354435 -99.410627) (xy 290.402041 -99.439681)
			(xy 290.444909 -99.475356) (xy 290.482126 -99.516893) (xy 290.512899 -99.563406) (xy 290.536571 -99.613903)
			(xy 290.552639 -99.66731) (xy 290.560759 -99.722486) (xy 290.561073 -99.739704) (xy 302.321974 -99.739704)
			(xy 302.326045 -99.684082) (xy 302.338171 -99.629645) (xy 302.358094 -99.577554) (xy 302.38539 -99.528919)
			(xy 302.419476 -99.484776) (xy 302.459625 -99.446067) (xy 302.504983 -99.413616) (xy 302.554583 -99.388115)
			(xy 302.607367 -99.370108) (xy 302.66221 -99.359978) (xy 302.717944 -99.357941) (xy 302.773381 -99.364041)
			(xy 302.827338 -99.378147) (xy 302.878667 -99.399959) (xy 302.926273 -99.429013) (xy 302.939456 -99.439984)
			(xy 307.509924 -99.439984) (xy 307.513995 -99.384362) (xy 307.526121 -99.329925) (xy 307.546044 -99.277834)
			(xy 307.57334 -99.229199) (xy 307.607426 -99.185056) (xy 307.647575 -99.146347) (xy 307.692933 -99.113896)
			(xy 307.742533 -99.088395) (xy 307.795317 -99.070388) (xy 307.85016 -99.060258) (xy 307.905894 -99.058221)
			(xy 307.961331 -99.064321) (xy 308.015288 -99.078427) (xy 308.066617 -99.100239) (xy 308.114223 -99.129293)
			(xy 308.157091 -99.164968) (xy 308.194308 -99.206505) (xy 308.225081 -99.253018) (xy 308.248753 -99.303515)
			(xy 308.264821 -99.356922) (xy 308.272941 -99.412098) (xy 308.27345 -99.439984) (xy 308.273278 -99.449382)
			(xy 320.106038 -99.449382) (xy 320.110109 -99.39376) (xy 320.122235 -99.339323) (xy 320.142158 -99.287232)
			(xy 320.169454 -99.238597) (xy 320.20354 -99.194454) (xy 320.243689 -99.155745) (xy 320.289047 -99.123294)
			(xy 320.338647 -99.097793) (xy 320.391431 -99.079786) (xy 320.446274 -99.069656) (xy 320.502008 -99.067619)
			(xy 320.557445 -99.073719) (xy 320.611402 -99.087825) (xy 320.662731 -99.109637) (xy 320.710337 -99.138691)
			(xy 320.753205 -99.174366) (xy 320.790422 -99.215903) (xy 320.821195 -99.262416) (xy 320.844867 -99.312913)
			(xy 320.860935 -99.36632) (xy 320.869055 -99.421496) (xy 320.869564 -99.449382) (xy 320.869055 -99.477268)
			(xy 320.860935 -99.532444) (xy 320.844867 -99.585851) (xy 320.831445 -99.614482) (xy 322.539866 -99.614482)
			(xy 322.543937 -99.55886) (xy 322.556063 -99.504423) (xy 322.575986 -99.452332) (xy 322.603282 -99.403697)
			(xy 322.637368 -99.359554) (xy 322.677517 -99.320845) (xy 322.722875 -99.288394) (xy 322.772475 -99.262893)
			(xy 322.825259 -99.244886) (xy 322.880102 -99.234756) (xy 322.935836 -99.232719) (xy 322.991273 -99.238819)
			(xy 323.04523 -99.252925) (xy 323.096559 -99.274737) (xy 323.144165 -99.303791) (xy 323.187033 -99.339466)
			(xy 323.22425 -99.381003) (xy 323.255023 -99.427516) (xy 323.278695 -99.478013) (xy 323.294763 -99.53142)
			(xy 323.302883 -99.586596) (xy 323.303392 -99.614482) (xy 323.303183 -99.625912) (xy 323.706742 -99.625912)
			(xy 323.710813 -99.57029) (xy 323.722939 -99.515853) (xy 323.742862 -99.463762) (xy 323.770158 -99.415127)
			(xy 323.804244 -99.370984) (xy 323.844393 -99.332275) (xy 323.889751 -99.299824) (xy 323.939351 -99.274323)
			(xy 323.992135 -99.256316) (xy 324.046978 -99.246186) (xy 324.102712 -99.244149) (xy 324.158149 -99.250249)
			(xy 324.212106 -99.264355) (xy 324.263435 -99.286167) (xy 324.311041 -99.315221) (xy 324.353909 -99.350896)
			(xy 324.391126 -99.392433) (xy 324.421899 -99.438946) (xy 324.431078 -99.458526) (xy 325.838564 -99.458526)
			(xy 325.842635 -99.402904) (xy 325.854761 -99.348467) (xy 325.874684 -99.296376) (xy 325.90198 -99.247741)
			(xy 325.936066 -99.203598) (xy 325.976215 -99.164889) (xy 326.021573 -99.132438) (xy 326.071173 -99.106937)
			(xy 326.123957 -99.08893) (xy 326.1788 -99.0788) (xy 326.234534 -99.076763) (xy 326.289971 -99.082863)
			(xy 326.343928 -99.096969) (xy 326.395257 -99.118781) (xy 326.442863 -99.147835) (xy 326.485731 -99.18351)
			(xy 326.522948 -99.225047) (xy 326.553721 -99.27156) (xy 326.577393 -99.322057) (xy 326.593461 -99.375464)
			(xy 326.601581 -99.43064) (xy 326.60209 -99.458526) (xy 326.601581 -99.486412) (xy 326.593461 -99.541588)
			(xy 326.577393 -99.594995) (xy 326.553721 -99.645492) (xy 326.522948 -99.692005) (xy 326.485731 -99.733542)
			(xy 326.442863 -99.769217) (xy 326.395257 -99.798271) (xy 326.343928 -99.820083) (xy 326.289971 -99.834189)
			(xy 326.234534 -99.840289) (xy 326.1788 -99.838252) (xy 326.123957 -99.828122) (xy 326.071173 -99.810115)
			(xy 326.021573 -99.784614) (xy 325.976215 -99.752163) (xy 325.936066 -99.713454) (xy 325.90198 -99.669311)
			(xy 325.874684 -99.620676) (xy 325.854761 -99.568585) (xy 325.842635 -99.514148) (xy 325.838564 -99.458526)
			(xy 324.431078 -99.458526) (xy 324.445571 -99.489443) (xy 324.461639 -99.54285) (xy 324.469759 -99.598026)
			(xy 324.470268 -99.625912) (xy 324.469759 -99.653798) (xy 324.461639 -99.708974) (xy 324.445571 -99.762381)
			(xy 324.421899 -99.812878) (xy 324.391126 -99.859391) (xy 324.353909 -99.900928) (xy 324.311041 -99.936603)
			(xy 324.263435 -99.965657) (xy 324.212106 -99.987469) (xy 324.158149 -100.001575) (xy 324.102712 -100.007675)
			(xy 324.046978 -100.005638) (xy 323.992135 -99.995508) (xy 323.939351 -99.977501) (xy 323.889751 -99.952)
			(xy 323.844393 -99.919549) (xy 323.804244 -99.88084) (xy 323.770158 -99.836697) (xy 323.742862 -99.788062)
			(xy 323.722939 -99.735971) (xy 323.710813 -99.681534) (xy 323.706742 -99.625912) (xy 323.303183 -99.625912)
			(xy 323.302883 -99.642368) (xy 323.294763 -99.697544) (xy 323.278695 -99.750951) (xy 323.255023 -99.801448)
			(xy 323.22425 -99.847961) (xy 323.187033 -99.889498) (xy 323.144165 -99.925173) (xy 323.096559 -99.954227)
			(xy 323.04523 -99.976039) (xy 322.991273 -99.990145) (xy 322.935836 -99.996245) (xy 322.880102 -99.994208)
			(xy 322.825259 -99.984078) (xy 322.772475 -99.966071) (xy 322.722875 -99.94057) (xy 322.677517 -99.908119)
			(xy 322.637368 -99.86941) (xy 322.603282 -99.825267) (xy 322.575986 -99.776632) (xy 322.556063 -99.724541)
			(xy 322.543937 -99.670104) (xy 322.539866 -99.614482) (xy 320.831445 -99.614482) (xy 320.821195 -99.636348)
			(xy 320.790422 -99.682861) (xy 320.753205 -99.724398) (xy 320.710337 -99.760073) (xy 320.662731 -99.789127)
			(xy 320.611402 -99.810939) (xy 320.557445 -99.825045) (xy 320.502008 -99.831145) (xy 320.446274 -99.829108)
			(xy 320.391431 -99.818978) (xy 320.338647 -99.800971) (xy 320.289047 -99.77547) (xy 320.243689 -99.743019)
			(xy 320.20354 -99.70431) (xy 320.169454 -99.660167) (xy 320.142158 -99.611532) (xy 320.122235 -99.559441)
			(xy 320.110109 -99.505004) (xy 320.106038 -99.449382) (xy 308.273278 -99.449382) (xy 308.272941 -99.46787)
			(xy 308.264821 -99.523046) (xy 308.248753 -99.576453) (xy 308.225081 -99.62695) (xy 308.194308 -99.673463)
			(xy 308.157091 -99.715) (xy 308.114223 -99.750675) (xy 308.066617 -99.779729) (xy 308.015288 -99.801541)
			(xy 307.961331 -99.815647) (xy 307.905894 -99.821747) (xy 307.85016 -99.81971) (xy 307.795317 -99.80958)
			(xy 307.742533 -99.791573) (xy 307.692933 -99.766072) (xy 307.647575 -99.733621) (xy 307.607426 -99.694912)
			(xy 307.57334 -99.650769) (xy 307.546044 -99.602134) (xy 307.526121 -99.550043) (xy 307.513995 -99.495606)
			(xy 307.509924 -99.439984) (xy 302.939456 -99.439984) (xy 302.969141 -99.464688) (xy 303.006358 -99.506225)
			(xy 303.037131 -99.552738) (xy 303.060803 -99.603235) (xy 303.076871 -99.656642) (xy 303.084991 -99.711818)
			(xy 303.0855 -99.739704) (xy 303.084991 -99.76759) (xy 303.076871 -99.822766) (xy 303.060803 -99.876173)
			(xy 303.037131 -99.92667) (xy 303.006358 -99.973183) (xy 302.969141 -100.01472) (xy 302.938846 -100.039932)
			(xy 306.076856 -100.039932) (xy 306.080927 -99.98431) (xy 306.093053 -99.929873) (xy 306.112976 -99.877782)
			(xy 306.140272 -99.829147) (xy 306.174358 -99.785004) (xy 306.214507 -99.746295) (xy 306.259865 -99.713844)
			(xy 306.309465 -99.688343) (xy 306.362249 -99.670336) (xy 306.417092 -99.660206) (xy 306.472826 -99.658169)
			(xy 306.528263 -99.664269) (xy 306.58222 -99.678375) (xy 306.633549 -99.700187) (xy 306.681155 -99.729241)
			(xy 306.724023 -99.764916) (xy 306.76124 -99.806453) (xy 306.792013 -99.852966) (xy 306.815685 -99.903463)
			(xy 306.831753 -99.95687) (xy 306.839873 -100.012046) (xy 306.840382 -100.039932) (xy 306.840076 -100.056696)
			(xy 310.369456 -100.056696) (xy 310.373527 -100.001074) (xy 310.385653 -99.946637) (xy 310.405576 -99.894546)
			(xy 310.432872 -99.845911) (xy 310.466958 -99.801768) (xy 310.507107 -99.763059) (xy 310.552465 -99.730608)
			(xy 310.602065 -99.705107) (xy 310.654849 -99.6871) (xy 310.709692 -99.67697) (xy 310.765426 -99.674933)
			(xy 310.820863 -99.681033) (xy 310.87482 -99.695139) (xy 310.926149 -99.716951) (xy 310.973755 -99.746005)
			(xy 311.016623 -99.78168) (xy 311.05384 -99.823217) (xy 311.084613 -99.86973) (xy 311.108285 -99.920227)
			(xy 311.124353 -99.973634) (xy 311.132473 -100.02881) (xy 311.132982 -100.056696) (xy 311.132473 -100.084582)
			(xy 311.124353 -100.139758) (xy 311.108285 -100.193165) (xy 311.084613 -100.243662) (xy 311.05384 -100.290175)
			(xy 311.016623 -100.331712) (xy 310.973755 -100.367387) (xy 310.9318 -100.392992) (xy 327.573892 -100.392992)
			(xy 327.577963 -100.33737) (xy 327.590089 -100.282933) (xy 327.610012 -100.230842) (xy 327.637308 -100.182207)
			(xy 327.671394 -100.138064) (xy 327.711543 -100.099355) (xy 327.756901 -100.066904) (xy 327.806501 -100.041403)
			(xy 327.859285 -100.023396) (xy 327.914128 -100.013266) (xy 327.969862 -100.011229) (xy 328.025299 -100.017329)
			(xy 328.079256 -100.031435) (xy 328.130585 -100.053247) (xy 328.178191 -100.082301) (xy 328.221059 -100.117976)
			(xy 328.258276 -100.159513) (xy 328.289049 -100.206026) (xy 328.312721 -100.256523) (xy 328.328789 -100.30993)
			(xy 328.336909 -100.365106) (xy 328.337418 -100.392992) (xy 328.336909 -100.420878) (xy 328.328789 -100.476054)
			(xy 328.312721 -100.529461) (xy 328.289049 -100.579958) (xy 328.258276 -100.626471) (xy 328.221059 -100.668008)
			(xy 328.178191 -100.703683) (xy 328.130585 -100.732737) (xy 328.079256 -100.754549) (xy 328.025299 -100.768655)
			(xy 327.969862 -100.774755) (xy 327.914128 -100.772718) (xy 327.859285 -100.762588) (xy 327.806501 -100.744581)
			(xy 327.756901 -100.71908) (xy 327.711543 -100.686629) (xy 327.671394 -100.64792) (xy 327.637308 -100.603777)
			(xy 327.610012 -100.555142) (xy 327.590089 -100.503051) (xy 327.577963 -100.448614) (xy 327.573892 -100.392992)
			(xy 310.9318 -100.392992) (xy 310.926149 -100.396441) (xy 310.87482 -100.418253) (xy 310.820863 -100.432359)
			(xy 310.765426 -100.438459) (xy 310.709692 -100.436422) (xy 310.654849 -100.426292) (xy 310.602065 -100.408285)
			(xy 310.552465 -100.382784) (xy 310.507107 -100.350333) (xy 310.466958 -100.311624) (xy 310.432872 -100.267481)
			(xy 310.405576 -100.218846) (xy 310.385653 -100.166755) (xy 310.373527 -100.112318) (xy 310.369456 -100.056696)
			(xy 306.840076 -100.056696) (xy 306.839873 -100.067818) (xy 306.831753 -100.122994) (xy 306.815685 -100.176401)
			(xy 306.792013 -100.226898) (xy 306.76124 -100.273411) (xy 306.724023 -100.314948) (xy 306.681155 -100.350623)
			(xy 306.633549 -100.379677) (xy 306.58222 -100.401489) (xy 306.528263 -100.415595) (xy 306.472826 -100.421695)
			(xy 306.417092 -100.419658) (xy 306.362249 -100.409528) (xy 306.309465 -100.391521) (xy 306.259865 -100.36602)
			(xy 306.214507 -100.333569) (xy 306.174358 -100.29486) (xy 306.140272 -100.250717) (xy 306.112976 -100.202082)
			(xy 306.093053 -100.149991) (xy 306.080927 -100.095554) (xy 306.076856 -100.039932) (xy 302.938846 -100.039932)
			(xy 302.926273 -100.050395) (xy 302.878667 -100.079449) (xy 302.827338 -100.101261) (xy 302.773381 -100.115367)
			(xy 302.717944 -100.121467) (xy 302.66221 -100.11943) (xy 302.607367 -100.1093) (xy 302.554583 -100.091293)
			(xy 302.504983 -100.065792) (xy 302.459625 -100.033341) (xy 302.419476 -99.994632) (xy 302.38539 -99.950489)
			(xy 302.358094 -99.901854) (xy 302.338171 -99.849763) (xy 302.326045 -99.795326) (xy 302.321974 -99.739704)
			(xy 290.561073 -99.739704) (xy 290.561268 -99.750372) (xy 290.560759 -99.778258) (xy 290.552639 -99.833434)
			(xy 290.536571 -99.886841) (xy 290.512899 -99.937338) (xy 290.482126 -99.983851) (xy 290.444909 -100.025388)
			(xy 290.402041 -100.061063) (xy 290.354435 -100.090117) (xy 290.303106 -100.111929) (xy 290.249149 -100.126035)
			(xy 290.193712 -100.132135) (xy 290.137978 -100.130098) (xy 290.083135 -100.119968) (xy 290.030351 -100.101961)
			(xy 289.980751 -100.07646) (xy 289.935393 -100.044009) (xy 289.895244 -100.0053) (xy 289.861158 -99.961157)
			(xy 289.833862 -99.912522) (xy 289.813939 -99.860431) (xy 289.801813 -99.805994) (xy 289.797742 -99.750372)
			(xy 286.754824 -99.750372) (xy 286.754824 -100.17633) (xy 286.754316 -100.196142) (xy 286.754337 -100.207735)
			(xy 286.763464 -100.229023) (xy 286.771842 -100.237036) (xy 286.796226 -100.258118) (xy 286.805213 -100.265215)
			(xy 286.827306 -100.27116) (xy 286.838644 -100.269548) (xy 286.855451 -100.26668) (xy 286.889413 -100.263632)
			(xy 286.906462 -100.263452) (xy 286.933714 -100.263993) (xy 286.987663 -100.271744) (xy 287.03996 -100.287096)
			(xy 287.08954 -100.309734) (xy 287.135393 -100.339197) (xy 287.176586 -100.374887) (xy 287.21228 -100.416077)
			(xy 287.241748 -100.461927) (xy 287.264391 -100.511504) (xy 287.279748 -100.5638) (xy 287.287505 -100.617748)
			(xy 287.287505 -100.672252) (xy 287.279748 -100.7262) (xy 287.267951 -100.766372) (xy 289.797742 -100.766372)
			(xy 289.801813 -100.71075) (xy 289.813939 -100.656313) (xy 289.833862 -100.604222) (xy 289.861158 -100.555587)
			(xy 289.895244 -100.511444) (xy 289.935393 -100.472735) (xy 289.980751 -100.440284) (xy 290.030351 -100.414783)
			(xy 290.083135 -100.396776) (xy 290.137978 -100.386646) (xy 290.193712 -100.384609) (xy 290.249149 -100.390709)
			(xy 290.303106 -100.404815) (xy 290.354435 -100.426627) (xy 290.402041 -100.455681) (xy 290.444909 -100.491356)
			(xy 290.482126 -100.532893) (xy 290.512899 -100.579406) (xy 290.536571 -100.629903) (xy 290.552639 -100.68331)
			(xy 290.560759 -100.738486) (xy 290.561268 -100.766372) (xy 290.560759 -100.794258) (xy 290.552639 -100.849434)
			(xy 290.536571 -100.902841) (xy 290.512899 -100.953338) (xy 290.482126 -100.999851) (xy 290.444909 -101.041388)
			(xy 290.402041 -101.077063) (xy 290.354435 -101.106117) (xy 290.303106 -101.127929) (xy 290.249149 -101.142035)
			(xy 290.193712 -101.148135) (xy 290.137978 -101.146098) (xy 290.083135 -101.135968) (xy 290.030351 -101.117961)
			(xy 289.980751 -101.09246) (xy 289.935393 -101.060009) (xy 289.895244 -101.0213) (xy 289.861158 -100.977157)
			(xy 289.833862 -100.928522) (xy 289.813939 -100.876431) (xy 289.801813 -100.821994) (xy 289.797742 -100.766372)
			(xy 287.267951 -100.766372) (xy 287.264391 -100.778496) (xy 287.241748 -100.828073) (xy 287.21228 -100.873923)
			(xy 287.176586 -100.915113) (xy 287.135393 -100.950803) (xy 287.08954 -100.980267) (xy 287.03996 -101.002904)
			(xy 286.987663 -101.018256) (xy 286.933714 -101.026007) (xy 286.906462 -101.026468) (xy 286.879454 -101.026022)
			(xy 286.825977 -101.018411) (xy 286.774109 -101.003333) (xy 286.724886 -100.98109) (xy 286.679293 -100.952125)
			(xy 286.638241 -100.917019) (xy 286.602552 -100.876473) (xy 286.572939 -100.831298) (xy 286.549994 -100.782398)
			(xy 286.534176 -100.730751) (xy 286.529526 -100.704142) (xy 286.528002 -100.693474) (xy 286.516572 -100.675694)
			(xy 286.445198 -100.628196) (xy 286.436259 -100.622867) (xy 286.415803 -100.619179) (xy 286.405574 -100.621084)
			(xy 286.404812 -100.621084) (xy 286.378241 -100.627192) (xy 286.324122 -100.63382) (xy 286.296862 -100.634292)
			(xy 286.269537 -100.633838) (xy 286.215289 -100.627216) (xy 286.188658 -100.621084) (xy 286.18815 -100.621084)
			(xy 286.17792 -100.619229) (xy 286.157474 -100.6229) (xy 286.148526 -100.628196) (xy 286.077152 -100.675694)
			(xy 286.065722 -100.693474) (xy 286.064198 -100.704142) (xy 286.059488 -100.730737) (xy 286.043665 -100.782374)
			(xy 286.020719 -100.831264) (xy 285.991109 -100.87643) (xy 285.955425 -100.916969) (xy 285.914382 -100.952072)
			(xy 285.8688 -100.981037) (xy 285.819588 -101.003285) (xy 285.767731 -101.018372) (xy 285.714265 -101.025996)
			(xy 285.687262 -101.026468) (xy 285.659893 -101.025973) (xy 285.605715 -101.018164) (xy 285.553211 -101.002682)
			(xy 285.503464 -100.979846) (xy 285.457496 -100.950127) (xy 285.436564 -100.932488) (xy 285.43631 -100.932234)
			(xy 285.42923 -100.926638) (xy 285.412308 -100.920399) (xy 285.40329 -100.920042) (xy 285.336234 -100.920042)
			(xy 285.327218 -100.920406) (xy 285.3103 -100.926648) (xy 285.303214 -100.932234) (xy 285.303214 -100.932488)
			(xy 285.30296 -100.932488) (xy 285.282015 -100.950111) (xy 285.236046 -100.979825) (xy 285.186302 -101.002665)
			(xy 285.133804 -101.01816) (xy 285.07963 -101.025992) (xy 285.052262 -101.026468) (xy 285.03515 -101.026273)
			(xy 285.001063 -101.023223) (xy 284.98419 -101.020372) (xy 284.972898 -101.01902) (xy 284.95101 -101.025083)
			(xy 284.942026 -101.032056) (xy 284.917642 -101.052884) (xy 284.909236 -101.060881) (xy 284.900096 -101.082177)
			(xy 284.900116 -101.093778) (xy 284.900624 -101.112828) (xy 284.900624 -101.240082) (xy 306.493924 -101.240082)
			(xy 306.497995 -101.18446) (xy 306.510121 -101.130023) (xy 306.530044 -101.077932) (xy 306.55734 -101.029297)
			(xy 306.591426 -100.985154) (xy 306.631575 -100.946445) (xy 306.676933 -100.913994) (xy 306.726533 -100.888493)
			(xy 306.779317 -100.870486) (xy 306.83416 -100.860356) (xy 306.889894 -100.858319) (xy 306.945331 -100.864419)
			(xy 306.999288 -100.878525) (xy 307.050617 -100.900337) (xy 307.098223 -100.929391) (xy 307.141091 -100.965066)
			(xy 307.178308 -101.006603) (xy 307.209081 -101.053116) (xy 307.216831 -101.069648) (xy 307.786276 -101.069648)
			(xy 307.790347 -101.014026) (xy 307.802473 -100.959589) (xy 307.822396 -100.907498) (xy 307.849692 -100.858863)
			(xy 307.883778 -100.81472) (xy 307.923927 -100.776011) (xy 307.969285 -100.74356) (xy 308.018885 -100.718059)
			(xy 308.071669 -100.700052) (xy 308.126512 -100.689922) (xy 308.182246 -100.687885) (xy 308.237683 -100.693985)
			(xy 308.29164 -100.708091) (xy 308.342969 -100.729903) (xy 308.390575 -100.758957) (xy 308.433443 -100.794632)
			(xy 308.47066 -100.836169) (xy 308.501433 -100.882682) (xy 308.525105 -100.933179) (xy 308.541173 -100.986586)
			(xy 308.549293 -101.041762) (xy 308.549802 -101.069648) (xy 310.369456 -101.069648) (xy 310.373527 -101.014026)
			(xy 310.385653 -100.959589) (xy 310.405576 -100.907498) (xy 310.432872 -100.858863) (xy 310.466958 -100.81472)
			(xy 310.507107 -100.776011) (xy 310.552465 -100.74356) (xy 310.602065 -100.718059) (xy 310.654849 -100.700052)
			(xy 310.709692 -100.689922) (xy 310.765426 -100.687885) (xy 310.820863 -100.693985) (xy 310.87482 -100.708091)
			(xy 310.926149 -100.729903) (xy 310.973755 -100.758957) (xy 311.016623 -100.794632) (xy 311.024984 -100.803964)
			(xy 322.551296 -100.803964) (xy 322.555367 -100.748342) (xy 322.567493 -100.693905) (xy 322.587416 -100.641814)
			(xy 322.614712 -100.593179) (xy 322.648798 -100.549036) (xy 322.688947 -100.510327) (xy 322.734305 -100.477876)
			(xy 322.783905 -100.452375) (xy 322.836689 -100.434368) (xy 322.891532 -100.424238) (xy 322.947266 -100.422201)
			(xy 323.002703 -100.428301) (xy 323.05666 -100.442407) (xy 323.107989 -100.464219) (xy 323.155595 -100.493273)
			(xy 323.198463 -100.528948) (xy 323.23568 -100.570485) (xy 323.266453 -100.616998) (xy 323.290125 -100.667495)
			(xy 323.306193 -100.720902) (xy 323.314313 -100.776078) (xy 323.314822 -100.803964) (xy 323.717918 -100.803964)
			(xy 323.721989 -100.748342) (xy 323.734115 -100.693905) (xy 323.754038 -100.641814) (xy 323.781334 -100.593179)
			(xy 323.81542 -100.549036) (xy 323.855569 -100.510327) (xy 323.900927 -100.477876) (xy 323.950527 -100.452375)
			(xy 324.003311 -100.434368) (xy 324.058154 -100.424238) (xy 324.113888 -100.422201) (xy 324.169325 -100.428301)
			(xy 324.223282 -100.442407) (xy 324.274611 -100.464219) (xy 324.322217 -100.493273) (xy 324.365085 -100.528948)
			(xy 324.402302 -100.570485) (xy 324.433075 -100.616998) (xy 324.456747 -100.667495) (xy 324.472815 -100.720902)
			(xy 324.480935 -100.776078) (xy 324.481444 -100.803964) (xy 324.480935 -100.83185) (xy 324.472815 -100.887026)
			(xy 324.456747 -100.940433) (xy 324.433075 -100.99093) (xy 324.402302 -101.037443) (xy 324.365085 -101.07898)
			(xy 324.322217 -101.114655) (xy 324.274611 -101.143709) (xy 324.223282 -101.165521) (xy 324.169325 -101.179627)
			(xy 324.113888 -101.185727) (xy 324.058154 -101.18369) (xy 324.003311 -101.17356) (xy 323.950527 -101.155553)
			(xy 323.900927 -101.130052) (xy 323.855569 -101.097601) (xy 323.81542 -101.058892) (xy 323.781334 -101.014749)
			(xy 323.754038 -100.966114) (xy 323.734115 -100.914023) (xy 323.721989 -100.859586) (xy 323.717918 -100.803964)
			(xy 323.314822 -100.803964) (xy 323.314313 -100.83185) (xy 323.306193 -100.887026) (xy 323.290125 -100.940433)
			(xy 323.266453 -100.99093) (xy 323.23568 -101.037443) (xy 323.198463 -101.07898) (xy 323.155595 -101.114655)
			(xy 323.107989 -101.143709) (xy 323.05666 -101.165521) (xy 323.002703 -101.179627) (xy 322.947266 -101.185727)
			(xy 322.891532 -101.18369) (xy 322.836689 -101.17356) (xy 322.783905 -101.155553) (xy 322.734305 -101.130052)
			(xy 322.688947 -101.097601) (xy 322.648798 -101.058892) (xy 322.614712 -101.014749) (xy 322.587416 -100.966114)
			(xy 322.567493 -100.914023) (xy 322.555367 -100.859586) (xy 322.551296 -100.803964) (xy 311.024984 -100.803964)
			(xy 311.05384 -100.836169) (xy 311.084613 -100.882682) (xy 311.108285 -100.933179) (xy 311.124353 -100.986586)
			(xy 311.132473 -101.041762) (xy 311.132982 -101.069648) (xy 311.132473 -101.097534) (xy 311.124353 -101.15271)
			(xy 311.113179 -101.18985) (xy 329.19339 -101.18985) (xy 329.19339 -101.13535) (xy 329.201146 -101.081404)
			(xy 329.216501 -101.029111) (xy 329.239141 -100.979536) (xy 329.268606 -100.933687) (xy 329.304297 -100.892498)
			(xy 329.345485 -100.856808) (xy 329.391334 -100.827342) (xy 329.440909 -100.804702) (xy 329.493202 -100.789347)
			(xy 329.547148 -100.78159) (xy 329.574398 -100.781104) (xy 329.601768 -100.78157) (xy 329.655947 -100.789388)
			(xy 329.708451 -100.804877) (xy 329.758197 -100.827719) (xy 329.804164 -100.857443) (xy 329.825096 -100.875084)
			(xy 329.82535 -100.875338) (xy 329.832444 -100.880914) (xy 329.849355 -100.887166) (xy 329.85837 -100.88753)
			(xy 329.925426 -100.88753) (xy 329.934443 -100.887179) (xy 329.95136 -100.880927) (xy 329.958446 -100.875338)
			(xy 329.958446 -100.875084) (xy 329.9587 -100.875084) (xy 329.979619 -100.857429) (xy 330.025596 -100.82772)
			(xy 330.075347 -100.804887) (xy 330.12785 -100.7894) (xy 330.182028 -100.781576) (xy 330.209398 -100.781104)
			(xy 330.236652 -100.781543) (xy 330.290605 -100.7893) (xy 330.342905 -100.804656) (xy 330.392487 -100.827299)
			(xy 330.438341 -100.856768) (xy 330.479536 -100.892463) (xy 330.515231 -100.933657) (xy 330.5447 -100.979512)
			(xy 330.567343 -101.029094) (xy 330.5827 -101.081393) (xy 330.590457 -101.135346) (xy 330.590457 -101.189854)
			(xy 330.5827 -101.243807) (xy 330.567343 -101.296106) (xy 330.550473 -101.333046) (xy 332.1337 -101.333046)
			(xy 332.137771 -101.277424) (xy 332.149897 -101.222987) (xy 332.16982 -101.170896) (xy 332.197116 -101.122261)
			(xy 332.231202 -101.078118) (xy 332.271351 -101.039409) (xy 332.316709 -101.006958) (xy 332.366309 -100.981457)
			(xy 332.419093 -100.96345) (xy 332.473936 -100.95332) (xy 332.52967 -100.951283) (xy 332.585107 -100.957383)
			(xy 332.639064 -100.971489) (xy 332.690393 -100.993301) (xy 332.737999 -101.022355) (xy 332.780867 -101.05803)
			(xy 332.818084 -101.099567) (xy 332.848857 -101.14608) (xy 332.872529 -101.196577) (xy 332.888597 -101.249984)
			(xy 332.896717 -101.30516) (xy 332.897226 -101.333046) (xy 332.896717 -101.360932) (xy 332.888597 -101.416108)
			(xy 332.872529 -101.469515) (xy 332.848857 -101.520012) (xy 332.818084 -101.566525) (xy 332.780867 -101.608062)
			(xy 332.737999 -101.643737) (xy 332.690393 -101.672791) (xy 332.639064 -101.694603) (xy 332.585107 -101.708709)
			(xy 332.52967 -101.714809) (xy 332.473936 -101.712772) (xy 332.419093 -101.702642) (xy 332.366309 -101.684635)
			(xy 332.316709 -101.659134) (xy 332.271351 -101.626683) (xy 332.231202 -101.587974) (xy 332.197116 -101.543831)
			(xy 332.16982 -101.495196) (xy 332.149897 -101.443105) (xy 332.137771 -101.388668) (xy 332.1337 -101.333046)
			(xy 330.550473 -101.333046) (xy 330.5447 -101.345688) (xy 330.515231 -101.391543) (xy 330.479536 -101.432737)
			(xy 330.438341 -101.468432) (xy 330.392487 -101.497901) (xy 330.342905 -101.520544) (xy 330.290605 -101.5359)
			(xy 330.236652 -101.543657) (xy 330.209398 -101.54412) (xy 330.182027 -101.543675) (xy 330.127846 -101.535855)
			(xy 330.075342 -101.520362) (xy 330.025595 -101.497515) (xy 329.97963 -101.467784) (xy 329.9587 -101.45014)
			(xy 329.958446 -101.449886) (xy 329.951352 -101.444311) (xy 329.934441 -101.438058) (xy 329.925426 -101.437694)
			(xy 329.85837 -101.437694) (xy 329.849352 -101.438038) (xy 329.832435 -101.444295) (xy 329.82535 -101.449886)
			(xy 329.82535 -101.45014) (xy 329.825096 -101.45014) (xy 329.804182 -101.467801) (xy 329.758203 -101.497508)
			(xy 329.708451 -101.520339) (xy 329.655947 -101.535826) (xy 329.601768 -101.543649) (xy 329.574398 -101.54412)
			(xy 329.547148 -101.54361) (xy 329.493202 -101.535853) (xy 329.440909 -101.520498) (xy 329.391334 -101.497858)
			(xy 329.345485 -101.468392) (xy 329.304297 -101.432702) (xy 329.268606 -101.391513) (xy 329.239141 -101.345664)
			(xy 329.216501 -101.296089) (xy 329.201146 -101.243796) (xy 329.19339 -101.18985) (xy 311.113179 -101.18985)
			(xy 311.108285 -101.206117) (xy 311.084613 -101.256614) (xy 311.05384 -101.303127) (xy 311.016623 -101.344664)
			(xy 310.973755 -101.380339) (xy 310.926149 -101.409393) (xy 310.87482 -101.431205) (xy 310.820863 -101.445311)
			(xy 310.765426 -101.451411) (xy 310.709692 -101.449374) (xy 310.654849 -101.439244) (xy 310.602065 -101.421237)
			(xy 310.552465 -101.395736) (xy 310.507107 -101.363285) (xy 310.466958 -101.324576) (xy 310.432872 -101.280433)
			(xy 310.405576 -101.231798) (xy 310.385653 -101.179707) (xy 310.373527 -101.12527) (xy 310.369456 -101.069648)
			(xy 308.549802 -101.069648) (xy 308.549293 -101.097534) (xy 308.541173 -101.15271) (xy 308.525105 -101.206117)
			(xy 308.501433 -101.256614) (xy 308.47066 -101.303127) (xy 308.433443 -101.344664) (xy 308.390575 -101.380339)
			(xy 308.342969 -101.409393) (xy 308.29164 -101.431205) (xy 308.237683 -101.445311) (xy 308.182246 -101.451411)
			(xy 308.126512 -101.449374) (xy 308.071669 -101.439244) (xy 308.018885 -101.421237) (xy 307.969285 -101.395736)
			(xy 307.923927 -101.363285) (xy 307.883778 -101.324576) (xy 307.849692 -101.280433) (xy 307.822396 -101.231798)
			(xy 307.802473 -101.179707) (xy 307.790347 -101.12527) (xy 307.786276 -101.069648) (xy 307.216831 -101.069648)
			(xy 307.232753 -101.103613) (xy 307.248821 -101.15702) (xy 307.256941 -101.212196) (xy 307.25745 -101.240082)
			(xy 307.256941 -101.267968) (xy 307.248821 -101.323144) (xy 307.232753 -101.376551) (xy 307.209081 -101.427048)
			(xy 307.178308 -101.473561) (xy 307.141091 -101.515098) (xy 307.098223 -101.550773) (xy 307.05169 -101.579172)
			(xy 319.970656 -101.579172) (xy 319.974727 -101.52355) (xy 319.986853 -101.469113) (xy 320.006776 -101.417022)
			(xy 320.034072 -101.368387) (xy 320.068158 -101.324244) (xy 320.108307 -101.285535) (xy 320.153665 -101.253084)
			(xy 320.203265 -101.227583) (xy 320.256049 -101.209576) (xy 320.310892 -101.199446) (xy 320.366626 -101.197409)
			(xy 320.422063 -101.203509) (xy 320.47602 -101.217615) (xy 320.527349 -101.239427) (xy 320.574955 -101.268481)
			(xy 320.617823 -101.304156) (xy 320.65504 -101.345693) (xy 320.685813 -101.392206) (xy 320.709485 -101.442703)
			(xy 320.725553 -101.49611) (xy 320.733673 -101.551286) (xy 320.734182 -101.579172) (xy 320.733673 -101.607058)
			(xy 320.725553 -101.662234) (xy 320.709485 -101.715641) (xy 320.685813 -101.766138) (xy 320.65504 -101.812651)
			(xy 320.617823 -101.854188) (xy 320.597905 -101.870764) (xy 325.439022 -101.870764) (xy 325.443093 -101.815142)
			(xy 325.455219 -101.760705) (xy 325.475142 -101.708614) (xy 325.502438 -101.659979) (xy 325.536524 -101.615836)
			(xy 325.576673 -101.577127) (xy 325.622031 -101.544676) (xy 325.671631 -101.519175) (xy 325.724415 -101.501168)
			(xy 325.779258 -101.491038) (xy 325.834992 -101.489001) (xy 325.890429 -101.495101) (xy 325.944386 -101.509207)
			(xy 325.995715 -101.531019) (xy 326.043321 -101.560073) (xy 326.086189 -101.595748) (xy 326.123406 -101.637285)
			(xy 326.154179 -101.683798) (xy 326.177851 -101.734295) (xy 326.193919 -101.787702) (xy 326.202039 -101.842878)
			(xy 326.202548 -101.870764) (xy 326.202039 -101.89865) (xy 326.193919 -101.953826) (xy 326.177851 -102.007233)
			(xy 326.154179 -102.05773) (xy 326.123406 -102.104243) (xy 326.099924 -102.130451) (xy 328.743052 -102.130451)
			(xy 328.743052 -102.075949) (xy 328.750808 -102.022001) (xy 328.766162 -101.969707) (xy 328.788801 -101.920129)
			(xy 328.818265 -101.874277) (xy 328.853954 -101.833086) (xy 328.895142 -101.797392) (xy 328.94099 -101.767922)
			(xy 328.990565 -101.745277) (xy 329.042858 -101.729917) (xy 329.096805 -101.722155) (xy 329.124056 -101.721666)
			(xy 329.151426 -101.722142) (xy 329.205605 -101.729955) (xy 329.258109 -101.745441) (xy 329.307856 -101.768281)
			(xy 329.353823 -101.798005) (xy 329.374754 -101.815646) (xy 329.375008 -101.8159) (xy 329.382088 -101.821496)
			(xy 329.39901 -101.827737) (xy 329.408028 -101.828092) (xy 329.475084 -101.828092) (xy 329.4841 -101.827729)
			(xy 329.501017 -101.821486) (xy 329.508104 -101.8159) (xy 329.508104 -101.815646) (xy 329.508358 -101.815646)
			(xy 329.529301 -101.79802) (xy 329.57527 -101.768305) (xy 329.625015 -101.745466) (xy 329.677513 -101.729972)
			(xy 329.731687 -101.722141) (xy 329.759056 -101.721666) (xy 329.786309 -101.722178) (xy 329.840261 -101.72993)
			(xy 329.892561 -101.745281) (xy 329.942143 -101.767919) (xy 329.987998 -101.797384) (xy 330.029194 -101.833075)
			(xy 330.06489 -101.874266) (xy 330.09436 -101.920118) (xy 330.117004 -101.969698) (xy 330.132361 -102.021996)
			(xy 330.140119 -102.075947) (xy 330.140119 -102.095046) (xy 331.4987 -102.095046) (xy 331.502771 -102.039424)
			(xy 331.514897 -101.984987) (xy 331.53482 -101.932896) (xy 331.562116 -101.884261) (xy 331.596202 -101.840118)
			(xy 331.636351 -101.801409) (xy 331.681709 -101.768958) (xy 331.731309 -101.743457) (xy 331.784093 -101.72545)
			(xy 331.838936 -101.71532) (xy 331.89467 -101.713283) (xy 331.950107 -101.719383) (xy 332.004064 -101.733489)
			(xy 332.055393 -101.755301) (xy 332.102999 -101.784355) (xy 332.145867 -101.82003) (xy 332.183084 -101.861567)
			(xy 332.213857 -101.90808) (xy 332.237529 -101.958577) (xy 332.253597 -102.011984) (xy 332.261717 -102.06716)
			(xy 332.262226 -102.095046) (xy 332.261717 -102.122932) (xy 332.253597 -102.178108) (xy 332.237529 -102.231515)
			(xy 332.213857 -102.282012) (xy 332.203044 -102.298356) (xy 333.296423 -102.298356) (xy 333.296423 -102.243844)
			(xy 333.304181 -102.189887) (xy 333.319539 -102.137584) (xy 333.342184 -102.087999) (xy 333.371656 -102.042141)
			(xy 333.407354 -102.000945) (xy 333.448552 -101.965248) (xy 333.494411 -101.935778) (xy 333.543997 -101.913134)
			(xy 333.596301 -101.897778) (xy 333.650258 -101.890022) (xy 333.677514 -101.88956) (xy 333.704885 -101.890003)
			(xy 333.759066 -101.897824) (xy 333.81157 -101.913318) (xy 333.861316 -101.936165) (xy 333.907282 -101.965896)
			(xy 333.928212 -101.98354) (xy 333.928466 -101.983794) (xy 333.935559 -101.989372) (xy 333.952471 -101.995624)
			(xy 333.961486 -101.995986) (xy 334.028542 -101.995986) (xy 334.037556 -101.995604) (xy 334.054474 -101.989374)
			(xy 334.061562 -101.983794) (xy 334.061562 -101.98354) (xy 334.061816 -101.98354) (xy 334.082774 -101.965933)
			(xy 334.128739 -101.936215) (xy 334.17848 -101.913372) (xy 334.230975 -101.897874) (xy 334.285147 -101.890038)
			(xy 334.312514 -101.88956) (xy 334.339762 -101.890111) (xy 334.393704 -101.897869) (xy 334.445993 -101.913224)
			(xy 334.495564 -101.935864) (xy 334.541409 -101.965328) (xy 334.582594 -102.001016) (xy 334.600684 -102.021894)
			(xy 335.156556 -102.021894) (xy 335.157005 -101.994523) (xy 335.164825 -101.940343) (xy 335.180317 -101.887839)
			(xy 335.203163 -101.838092) (xy 335.232892 -101.792127) (xy 335.250536 -101.771196) (xy 335.25079 -101.770942)
			(xy 335.256364 -101.763847) (xy 335.262619 -101.746937) (xy 335.262982 -101.737922) (xy 335.262982 -101.670866)
			(xy 335.262645 -101.661847) (xy 335.256384 -101.64493) (xy 335.25079 -101.637846) (xy 335.250536 -101.637846)
			(xy 335.250536 -101.637592) (xy 335.232889 -101.616664) (xy 335.203164 -101.570696) (xy 335.180318 -101.520949)
			(xy 335.164822 -101.468446) (xy 335.156994 -101.414266) (xy 335.156994 -101.359524) (xy 335.164824 -101.305345)
			(xy 335.180321 -101.252843) (xy 335.203168 -101.203096) (xy 335.232895 -101.157129) (xy 335.250536 -101.136196)
			(xy 335.25079 -101.135942) (xy 335.256364 -101.128847) (xy 335.262619 -101.111937) (xy 335.262982 -101.102922)
			(xy 335.262982 -101.035866) (xy 335.262645 -101.026847) (xy 335.256384 -101.00993) (xy 335.25079 -101.002846)
			(xy 335.250536 -101.002846) (xy 335.250536 -101.002592) (xy 335.232885 -100.981669) (xy 335.203174 -100.935694)
			(xy 335.18034 -100.885945) (xy 335.164851 -100.833442) (xy 335.157027 -100.779264) (xy 335.156556 -100.751894)
			(xy 335.157042 -100.724643) (xy 335.164798 -100.670695) (xy 335.180153 -100.6184) (xy 335.202795 -100.568823)
			(xy 335.232261 -100.522973) (xy 335.267952 -100.481782) (xy 335.309143 -100.446091) (xy 335.354993 -100.416625)
			(xy 335.40457 -100.393983) (xy 335.456865 -100.378628) (xy 335.510813 -100.370872) (xy 335.565315 -100.370872)
			(xy 335.619263 -100.378628) (xy 335.671558 -100.393983) (xy 335.721135 -100.416625) (xy 335.766985 -100.446091)
			(xy 335.808176 -100.481782) (xy 335.843867 -100.522973) (xy 335.873333 -100.568823) (xy 335.895975 -100.6184)
			(xy 335.91133 -100.670695) (xy 335.919086 -100.724643) (xy 335.919572 -100.751894) (xy 335.919109 -100.779264)
			(xy 335.911292 -100.833444) (xy 335.895802 -100.885947) (xy 335.87296 -100.935694) (xy 335.843234 -100.981661)
			(xy 335.825592 -101.002592) (xy 335.825338 -101.002846) (xy 335.819761 -101.009939) (xy 335.81351 -101.026851)
			(xy 335.813146 -101.035866) (xy 335.813146 -101.102922) (xy 335.813482 -101.111941) (xy 335.819743 -101.128859)
			(xy 335.825338 -101.135942) (xy 335.825592 -101.135942) (xy 335.825592 -101.136196) (xy 335.843226 -101.157134)
			(xy 335.87295 -101.203101) (xy 335.895794 -101.252847) (xy 335.91129 -101.305348) (xy 335.919119 -101.359525)
			(xy 335.919119 -101.414266) (xy 335.911292 -101.468443) (xy 335.895797 -101.520945) (xy 335.872954 -101.570691)
			(xy 335.843231 -101.616659) (xy 335.825592 -101.637592) (xy 335.825338 -101.637846) (xy 335.819761 -101.644939)
			(xy 335.81351 -101.661851) (xy 335.813146 -101.670866) (xy 335.813146 -101.737922) (xy 335.813482 -101.746941)
			(xy 335.819743 -101.763859) (xy 335.825338 -101.770942) (xy 335.825592 -101.770942) (xy 335.825592 -101.771196)
			(xy 335.843241 -101.79212) (xy 335.872952 -101.838095) (xy 335.895786 -101.887844) (xy 335.911275 -101.940347)
			(xy 335.9191 -101.994524) (xy 335.919572 -102.021894) (xy 335.919087 -102.049072) (xy 338.212938 -102.049072)
			(xy 338.213378 -102.021701) (xy 338.221201 -101.96752) (xy 338.236696 -101.915016) (xy 338.259543 -101.86527)
			(xy 338.289274 -101.819305) (xy 338.306918 -101.798374) (xy 338.307172 -101.79812) (xy 338.312765 -101.791038)
			(xy 338.319006 -101.774117) (xy 338.319364 -101.7651) (xy 338.319364 -101.698044) (xy 338.318994 -101.689028)
			(xy 338.312756 -101.672111) (xy 338.307172 -101.665024) (xy 338.306918 -101.665024) (xy 338.306918 -101.66477)
			(xy 338.28925 -101.643859) (xy 338.259527 -101.597887) (xy 338.236684 -101.548138) (xy 338.22119 -101.495632)
			(xy 338.213365 -101.441451) (xy 338.213368 -101.386707) (xy 338.221199 -101.332527) (xy 338.236699 -101.280023)
			(xy 338.259548 -101.230276) (xy 338.289276 -101.184307) (xy 338.306918 -101.163374) (xy 338.307172 -101.16312)
			(xy 338.312765 -101.156038) (xy 338.319006 -101.139117) (xy 338.319364 -101.1301) (xy 338.319364 -101.063044)
			(xy 338.318994 -101.054028) (xy 338.312756 -101.037111) (xy 338.307172 -101.030024) (xy 338.306918 -101.030024)
			(xy 338.306918 -101.02977) (xy 338.289301 -101.00882) (xy 338.259585 -100.962852) (xy 338.236745 -100.91311)
			(xy 338.221249 -100.860613) (xy 338.213415 -100.80644) (xy 338.212938 -100.779072) (xy 338.213424 -100.751821)
			(xy 338.22118 -100.697873) (xy 338.236535 -100.645578) (xy 338.259177 -100.596001) (xy 338.288643 -100.550151)
			(xy 338.324334 -100.50896) (xy 338.365525 -100.473269) (xy 338.411375 -100.443803) (xy 338.460952 -100.421161)
			(xy 338.513247 -100.405806) (xy 338.567195 -100.39805) (xy 338.621697 -100.39805) (xy 338.675645 -100.405806)
			(xy 338.72794 -100.421161) (xy 338.777517 -100.443803) (xy 338.823367 -100.473269) (xy 338.864558 -100.50896)
			(xy 338.900249 -100.550151) (xy 338.929715 -100.596001) (xy 338.952357 -100.645578) (xy 338.967712 -100.697873)
			(xy 338.975468 -100.751821) (xy 338.975954 -100.779072) (xy 338.975483 -100.806442) (xy 338.967668 -100.860621)
			(xy 338.952181 -100.913125) (xy 338.92934 -100.962872) (xy 338.899615 -101.008839) (xy 338.881974 -101.02977)
			(xy 338.88172 -101.030024) (xy 338.876108 -101.037093) (xy 338.869879 -101.054024) (xy 338.869734 -101.057749)
			(xy 348.55101 -101.057749) (xy 348.55101 -101.003251) (xy 348.558766 -100.949309) (xy 348.574119 -100.897019)
			(xy 348.596758 -100.847447) (xy 348.626221 -100.801601) (xy 348.661909 -100.760414) (xy 348.703094 -100.724726)
			(xy 348.74894 -100.695262) (xy 348.798512 -100.672622) (xy 348.850801 -100.657268) (xy 348.904743 -100.649511)
			(xy 348.931992 -100.649024) (xy 348.959911 -100.649498) (xy 349.015153 -100.657636) (xy 349.068619 -100.673741)
			(xy 349.119165 -100.697467) (xy 349.165713 -100.728308) (xy 349.207269 -100.765605) (xy 349.242943 -100.808562)
			(xy 349.257874 -100.832158) (xy 349.266184 -100.844764) (xy 349.288719 -100.864836) (xy 349.316133 -100.877454)
			(xy 349.346036 -100.881518) (xy 349.375823 -100.876674) (xy 349.402897 -100.863344) (xy 349.4249 -100.84269)
			(xy 349.43288 -100.829872) (xy 349.447521 -100.80521) (xy 349.483094 -100.760222) (xy 349.525003 -100.72107)
			(xy 349.572303 -100.688635) (xy 349.623928 -100.663651) (xy 349.678712 -100.646679) (xy 349.73542 -100.638104)
			(xy 349.764096 -100.637594) (xy 349.791349 -100.638053) (xy 349.845301 -100.64581) (xy 349.897599 -100.661165)
			(xy 349.94718 -100.683808) (xy 349.993034 -100.713276) (xy 350.034228 -100.74897) (xy 350.069922 -100.790163)
			(xy 350.09939 -100.836016) (xy 350.122033 -100.885597) (xy 350.13739 -100.937895) (xy 350.145147 -100.991847)
			(xy 350.145147 -101.046353) (xy 350.13739 -101.100305) (xy 350.122033 -101.152603) (xy 350.09939 -101.202184)
			(xy 350.069922 -101.248037) (xy 350.034228 -101.28923) (xy 349.993034 -101.324924) (xy 349.94718 -101.354392)
			(xy 349.897599 -101.377035) (xy 349.845301 -101.39239) (xy 349.791349 -101.400147) (xy 349.764096 -101.40061)
			(xy 349.736177 -101.40013) (xy 349.680936 -101.39199) (xy 349.627472 -101.375886) (xy 349.576926 -101.35216)
			(xy 349.530378 -101.32132) (xy 349.488822 -101.284025) (xy 349.453146 -101.241071) (xy 349.438214 -101.217476)
			(xy 349.429914 -101.204866) (xy 349.407373 -101.184806) (xy 349.379958 -101.172198) (xy 349.350058 -101.168139)
			(xy 349.320274 -101.172981) (xy 349.2932 -101.186305) (xy 349.271193 -101.206949) (xy 349.263208 -101.219762)
			(xy 349.248518 -101.244393) (xy 349.212952 -101.289379) (xy 349.17105 -101.328531) (xy 349.123758 -101.360968)
			(xy 349.072142 -101.385958) (xy 349.017366 -101.402938) (xy 348.960666 -101.411524) (xy 348.931992 -101.41204)
			(xy 348.904743 -101.411489) (xy 348.850801 -101.403732) (xy 348.798512 -101.388378) (xy 348.74894 -101.365738)
			(xy 348.703094 -101.336274) (xy 348.661909 -101.300586) (xy 348.626221 -101.259399) (xy 348.596758 -101.213553)
			(xy 348.574119 -101.163981) (xy 348.558766 -101.111691) (xy 348.55101 -101.057749) (xy 338.869734 -101.057749)
			(xy 338.869528 -101.063044) (xy 338.869528 -101.1301) (xy 338.869879 -101.139118) (xy 338.87613 -101.156035)
			(xy 338.88172 -101.16312) (xy 338.881974 -101.16312) (xy 338.881974 -101.163374) (xy 338.899587 -101.184329)
			(xy 338.929313 -101.230293) (xy 338.95216 -101.280036) (xy 338.967658 -101.332534) (xy 338.97549 -101.38671)
			(xy 338.975493 -101.441448) (xy 338.967667 -101.495625) (xy 338.952175 -101.548125) (xy 338.929333 -101.59787)
			(xy 338.899613 -101.643837) (xy 338.881974 -101.66477) (xy 338.88172 -101.665024) (xy 338.876108 -101.672093)
			(xy 338.869879 -101.689024) (xy 338.869528 -101.698044) (xy 338.869528 -101.7651) (xy 338.869879 -101.774118)
			(xy 338.87613 -101.791035) (xy 338.88172 -101.79812) (xy 338.881974 -101.79812) (xy 338.881974 -101.798374)
			(xy 338.89961 -101.819308) (xy 338.929323 -101.86528) (xy 338.95216 -101.915027) (xy 338.967652 -101.967527)
			(xy 338.97548 -102.021703) (xy 338.975954 -102.049072) (xy 338.975468 -102.076323) (xy 338.967712 -102.130271)
			(xy 338.952357 -102.182566) (xy 338.929715 -102.232143) (xy 338.900249 -102.277993) (xy 338.864558 -102.319184)
			(xy 338.823367 -102.354875) (xy 338.777517 -102.384341) (xy 338.72794 -102.406983) (xy 338.675645 -102.422338)
			(xy 338.621697 -102.430094) (xy 338.567195 -102.430094) (xy 338.513247 -102.422338) (xy 338.460952 -102.406983)
			(xy 338.411375 -102.384341) (xy 338.365525 -102.354875) (xy 338.324334 -102.319184) (xy 338.288643 -102.277993)
			(xy 338.259177 -102.232143) (xy 338.236535 -102.182566) (xy 338.22118 -102.130271) (xy 338.213424 -102.076323)
			(xy 338.212938 -102.049072) (xy 335.919087 -102.049072) (xy 335.919086 -102.049145) (xy 335.91133 -102.103093)
			(xy 335.895975 -102.155388) (xy 335.873333 -102.204965) (xy 335.843867 -102.250815) (xy 335.808176 -102.292006)
			(xy 335.766985 -102.327697) (xy 335.721135 -102.357163) (xy 335.671558 -102.379805) (xy 335.619263 -102.39516)
			(xy 335.565315 -102.402916) (xy 335.510813 -102.402916) (xy 335.456865 -102.39516) (xy 335.40457 -102.379805)
			(xy 335.354993 -102.357163) (xy 335.309143 -102.327697) (xy 335.267952 -102.292006) (xy 335.232261 -102.250815)
			(xy 335.202795 -102.204965) (xy 335.180153 -102.155388) (xy 335.164798 -102.103093) (xy 335.157042 -102.049145)
			(xy 335.156556 -102.021894) (xy 334.600684 -102.021894) (xy 334.618281 -102.042203) (xy 334.647743 -102.088049)
			(xy 334.670381 -102.137621) (xy 334.685734 -102.18991) (xy 334.69349 -102.243852) (xy 334.69349 -102.298348)
			(xy 334.685734 -102.35229) (xy 334.670381 -102.404579) (xy 334.647743 -102.454151) (xy 334.618281 -102.499997)
			(xy 334.582594 -102.541184) (xy 334.541409 -102.576872) (xy 334.495564 -102.606336) (xy 334.445993 -102.628976)
			(xy 334.393704 -102.644331) (xy 334.339762 -102.652089) (xy 334.312514 -102.652576) (xy 334.285144 -102.652108)
			(xy 334.230965 -102.644291) (xy 334.178461 -102.628803) (xy 334.128714 -102.605962) (xy 334.082748 -102.576237)
			(xy 334.061816 -102.558596) (xy 334.061562 -102.558342) (xy 334.054467 -102.552768) (xy 334.037556 -102.546515)
			(xy 334.028542 -102.54615) (xy 333.961486 -102.54615) (xy 333.952467 -102.54649) (xy 333.93555 -102.552748)
			(xy 333.928466 -102.558342) (xy 333.928466 -102.558596) (xy 333.928212 -102.558596) (xy 333.907286 -102.576242)
			(xy 333.861311 -102.605953) (xy 333.811562 -102.628788) (xy 333.75906 -102.644277) (xy 333.704884 -102.652103)
			(xy 333.677514 -102.652576) (xy 333.650258 -102.652178) (xy 333.596301 -102.644422) (xy 333.543997 -102.629066)
			(xy 333.494411 -102.606422) (xy 333.448552 -102.576952) (xy 333.407354 -102.541255) (xy 333.371656 -102.500059)
			(xy 333.342184 -102.454201) (xy 333.319539 -102.404616) (xy 333.304181 -102.352313) (xy 333.296423 -102.298356)
			(xy 332.203044 -102.298356) (xy 332.183084 -102.328525) (xy 332.145867 -102.370062) (xy 332.102999 -102.405737)
			(xy 332.055393 -102.434791) (xy 332.004064 -102.456603) (xy 331.950107 -102.470709) (xy 331.89467 -102.476809)
			(xy 331.838936 -102.474772) (xy 331.784093 -102.464642) (xy 331.731309 -102.446635) (xy 331.681709 -102.421134)
			(xy 331.636351 -102.388683) (xy 331.596202 -102.349974) (xy 331.562116 -102.305831) (xy 331.53482 -102.257196)
			(xy 331.514897 -102.205105) (xy 331.502771 -102.150668) (xy 331.4987 -102.095046) (xy 330.140119 -102.095046)
			(xy 330.140119 -102.130453) (xy 330.132361 -102.184404) (xy 330.117004 -102.236702) (xy 330.09436 -102.286282)
			(xy 330.06489 -102.332134) (xy 330.029194 -102.373325) (xy 329.987998 -102.409016) (xy 329.942143 -102.438481)
			(xy 329.892561 -102.461119) (xy 329.840261 -102.47647) (xy 329.786309 -102.484222) (xy 329.759056 -102.484682)
			(xy 329.731687 -102.484187) (xy 329.677509 -102.476377) (xy 329.625006 -102.460895) (xy 329.575258 -102.438059)
			(xy 329.52929 -102.408341) (xy 329.508358 -102.390702) (xy 329.508104 -102.390448) (xy 329.501025 -102.384851)
			(xy 329.484102 -102.378612) (xy 329.475084 -102.378256) (xy 329.408028 -102.378256) (xy 329.399011 -102.378614)
			(xy 329.382093 -102.38486) (xy 329.375008 -102.390448) (xy 329.375008 -102.390702) (xy 329.374754 -102.390702)
			(xy 329.353813 -102.40833) (xy 329.307842 -102.438043) (xy 329.258097 -102.460881) (xy 329.205599 -102.476375)
			(xy 329.151425 -102.484206) (xy 329.124056 -102.484682) (xy 329.096805 -102.484245) (xy 329.042858 -102.476483)
			(xy 328.990565 -102.461123) (xy 328.94099 -102.438478) (xy 328.895142 -102.409008) (xy 328.853954 -102.373314)
			(xy 328.818265 -102.332123) (xy 328.788801 -102.286271) (xy 328.766162 -102.236693) (xy 328.750808 -102.184399)
			(xy 328.743052 -102.130451) (xy 326.099924 -102.130451) (xy 326.086189 -102.14578) (xy 326.043321 -102.181455)
			(xy 325.995715 -102.210509) (xy 325.944386 -102.232321) (xy 325.890429 -102.246427) (xy 325.834992 -102.252527)
			(xy 325.779258 -102.25049) (xy 325.724415 -102.24036) (xy 325.671631 -102.222353) (xy 325.622031 -102.196852)
			(xy 325.576673 -102.164401) (xy 325.536524 -102.125692) (xy 325.502438 -102.081549) (xy 325.475142 -102.032914)
			(xy 325.455219 -101.980823) (xy 325.443093 -101.926386) (xy 325.439022 -101.870764) (xy 320.597905 -101.870764)
			(xy 320.574955 -101.889863) (xy 320.527349 -101.918917) (xy 320.47602 -101.940729) (xy 320.422063 -101.954835)
			(xy 320.366626 -101.960935) (xy 320.310892 -101.958898) (xy 320.256049 -101.948768) (xy 320.203265 -101.930761)
			(xy 320.153665 -101.90526) (xy 320.108307 -101.872809) (xy 320.068158 -101.8341) (xy 320.034072 -101.789957)
			(xy 320.006776 -101.741322) (xy 319.986853 -101.689231) (xy 319.974727 -101.634794) (xy 319.970656 -101.579172)
			(xy 307.05169 -101.579172) (xy 307.050617 -101.579827) (xy 306.999288 -101.601639) (xy 306.945331 -101.615745)
			(xy 306.889894 -101.621845) (xy 306.83416 -101.619808) (xy 306.779317 -101.609678) (xy 306.726533 -101.591671)
			(xy 306.676933 -101.56617) (xy 306.631575 -101.533719) (xy 306.591426 -101.49501) (xy 306.55734 -101.450867)
			(xy 306.530044 -101.402232) (xy 306.510121 -101.350141) (xy 306.497995 -101.295704) (xy 306.493924 -101.240082)
			(xy 284.900624 -101.240082) (xy 284.900624 -101.782372) (xy 289.797742 -101.782372) (xy 289.801813 -101.72675)
			(xy 289.813939 -101.672313) (xy 289.833862 -101.620222) (xy 289.861158 -101.571587) (xy 289.895244 -101.527444)
			(xy 289.935393 -101.488735) (xy 289.980751 -101.456284) (xy 290.030351 -101.430783) (xy 290.083135 -101.412776)
			(xy 290.137978 -101.402646) (xy 290.193712 -101.400609) (xy 290.249149 -101.406709) (xy 290.303106 -101.420815)
			(xy 290.354435 -101.442627) (xy 290.402041 -101.471681) (xy 290.444909 -101.507356) (xy 290.482126 -101.548893)
			(xy 290.512899 -101.595406) (xy 290.536571 -101.645903) (xy 290.552639 -101.69931) (xy 290.560759 -101.754486)
			(xy 290.561268 -101.782372) (xy 290.560759 -101.810258) (xy 290.552639 -101.865434) (xy 290.536571 -101.918841)
			(xy 290.512899 -101.969338) (xy 290.482126 -102.015851) (xy 290.444909 -102.057388) (xy 290.402041 -102.093063)
			(xy 290.354435 -102.122117) (xy 290.303106 -102.143929) (xy 290.249149 -102.158035) (xy 290.193712 -102.164135)
			(xy 290.137978 -102.162098) (xy 290.083135 -102.151968) (xy 290.030351 -102.133961) (xy 289.980751 -102.10846)
			(xy 289.935393 -102.076009) (xy 289.895244 -102.0373) (xy 289.861158 -101.993157) (xy 289.833862 -101.944522)
			(xy 289.813939 -101.892431) (xy 289.801813 -101.837994) (xy 289.797742 -101.782372) (xy 284.900624 -101.782372)
			(xy 284.900624 -101.976428) (xy 284.900116 -101.99624) (xy 284.900139 -102.007833) (xy 284.909265 -102.02912)
			(xy 284.917642 -102.037134) (xy 284.942026 -102.058216) (xy 284.951013 -102.065313) (xy 284.973106 -102.071258)
			(xy 284.984444 -102.069646) (xy 285.001251 -102.066778) (xy 285.035213 -102.06373) (xy 285.052262 -102.06355)
			(xy 285.079632 -102.064026) (xy 285.133811 -102.07184) (xy 285.186315 -102.087326) (xy 285.236062 -102.110166)
			(xy 285.282029 -102.139889) (xy 285.30296 -102.15753) (xy 285.309818 -102.163626) (xy 285.326836 -102.169976)
			(xy 285.41218 -102.169976) (xy 285.429452 -102.163372) (xy 285.43631 -102.157276) (xy 285.457263 -102.139662)
			(xy 285.503226 -102.109937) (xy 285.552967 -102.087092) (xy 285.605465 -102.071596) (xy 285.659639 -102.063768)
			(xy 285.687008 -102.063296) (xy 285.687262 -102.063296) (xy 285.714239 -102.06376) (xy 285.767656 -102.071348)
			(xy 285.819469 -102.086392) (xy 285.868644 -102.108592) (xy 285.914197 -102.137503) (xy 285.955218 -102.172549)
			(xy 285.990888 -102.213029) (xy 286.020494 -102.258134) (xy 286.043444 -102.306963) (xy 286.05928 -102.35854)
			(xy 286.063944 -102.385114) (xy 286.066117 -102.395341) (xy 286.077392 -102.412921) (xy 286.085788 -102.41915)
			(xy 286.157162 -102.466648) (xy 286.178244 -102.470458) (xy 286.188404 -102.467918) (xy 286.215106 -102.461846)
			(xy 286.269481 -102.455351) (xy 286.296862 -102.454964) (xy 286.324244 -102.45533) (xy 286.37862 -102.461831)
			(xy 286.40532 -102.467918) (xy 286.41548 -102.470458) (xy 286.436562 -102.466648) (xy 286.516826 -102.413308)
			(xy 286.528002 -102.395782) (xy 286.52978 -102.385114) (xy 286.534454 -102.358544) (xy 286.550307 -102.306978)
			(xy 286.573268 -102.25816) (xy 286.602878 -102.213065) (xy 286.638548 -102.172593) (xy 286.679565 -102.13755)
			(xy 286.72511 -102.108637) (xy 286.774276 -102.08643) (xy 286.826079 -102.071373) (xy 286.879488 -102.063765)
			(xy 286.906462 -102.063296) (xy 286.933717 -102.063749) (xy 286.987673 -102.071501) (xy 287.039975 -102.086854)
			(xy 287.089561 -102.109495) (xy 287.135419 -102.138962) (xy 287.176617 -102.174656) (xy 287.212315 -102.21585)
			(xy 287.241787 -102.261706) (xy 287.264432 -102.311289) (xy 287.27979 -102.36359) (xy 287.287549 -102.417545)
			(xy 287.287549 -102.472055) (xy 287.27979 -102.52601) (xy 287.264432 -102.578311) (xy 287.241787 -102.627894)
			(xy 287.212315 -102.67375) (xy 287.176617 -102.714944) (xy 287.135419 -102.750638) (xy 287.089561 -102.780105)
			(xy 287.049554 -102.798372) (xy 289.797742 -102.798372) (xy 289.801813 -102.74275) (xy 289.813939 -102.688313)
			(xy 289.833862 -102.636222) (xy 289.861158 -102.587587) (xy 289.895244 -102.543444) (xy 289.935393 -102.504735)
			(xy 289.980751 -102.472284) (xy 290.030351 -102.446783) (xy 290.083135 -102.428776) (xy 290.137978 -102.418646)
			(xy 290.193712 -102.416609) (xy 290.249149 -102.422709) (xy 290.303106 -102.436815) (xy 290.310549 -102.439978)
			(xy 299.130718 -102.439978) (xy 299.134789 -102.384356) (xy 299.146915 -102.329919) (xy 299.166838 -102.277828)
			(xy 299.194134 -102.229193) (xy 299.22822 -102.18505) (xy 299.268369 -102.146341) (xy 299.313727 -102.11389)
			(xy 299.363327 -102.088389) (xy 299.416111 -102.070382) (xy 299.470954 -102.060252) (xy 299.526688 -102.058215)
			(xy 299.582125 -102.064315) (xy 299.636082 -102.078421) (xy 299.687411 -102.100233) (xy 299.735017 -102.129287)
			(xy 299.777885 -102.164962) (xy 299.815102 -102.206499) (xy 299.845875 -102.253012) (xy 299.869547 -102.303509)
			(xy 299.885615 -102.356916) (xy 299.893735 -102.412092) (xy 299.894244 -102.439978) (xy 306.112924 -102.439978)
			(xy 306.116995 -102.384356) (xy 306.129121 -102.329919) (xy 306.149044 -102.277828) (xy 306.17634 -102.229193)
			(xy 306.210426 -102.18505) (xy 306.250575 -102.146341) (xy 306.295933 -102.11389) (xy 306.345533 -102.088389)
			(xy 306.398317 -102.070382) (xy 306.45316 -102.060252) (xy 306.508894 -102.058215) (xy 306.564331 -102.064315)
			(xy 306.618288 -102.078421) (xy 306.642468 -102.088696) (xy 310.369456 -102.088696) (xy 310.373527 -102.033074)
			(xy 310.385653 -101.978637) (xy 310.405576 -101.926546) (xy 310.432872 -101.877911) (xy 310.466958 -101.833768)
			(xy 310.507107 -101.795059) (xy 310.552465 -101.762608) (xy 310.602065 -101.737107) (xy 310.654849 -101.7191)
			(xy 310.709692 -101.70897) (xy 310.765426 -101.706933) (xy 310.820863 -101.713033) (xy 310.87482 -101.727139)
			(xy 310.926149 -101.748951) (xy 310.973755 -101.778005) (xy 311.016623 -101.81368) (xy 311.05384 -101.855217)
			(xy 311.084613 -101.90173) (xy 311.108285 -101.952227) (xy 311.124353 -102.005634) (xy 311.132473 -102.06081)
			(xy 311.132982 -102.088696) (xy 311.132473 -102.116582) (xy 311.124353 -102.171758) (xy 311.108285 -102.225165)
			(xy 311.084613 -102.275662) (xy 311.05384 -102.322175) (xy 311.016623 -102.363712) (xy 310.973755 -102.399387)
			(xy 310.926149 -102.428441) (xy 310.87482 -102.450253) (xy 310.820863 -102.464359) (xy 310.765426 -102.470459)
			(xy 310.709692 -102.468422) (xy 310.654849 -102.458292) (xy 310.602065 -102.440285) (xy 310.552465 -102.414784)
			(xy 310.507107 -102.382333) (xy 310.466958 -102.343624) (xy 310.432872 -102.299481) (xy 310.405576 -102.250846)
			(xy 310.385653 -102.198755) (xy 310.373527 -102.144318) (xy 310.369456 -102.088696) (xy 306.642468 -102.088696)
			(xy 306.669617 -102.100233) (xy 306.717223 -102.129287) (xy 306.760091 -102.164962) (xy 306.797308 -102.206499)
			(xy 306.828081 -102.253012) (xy 306.851753 -102.303509) (xy 306.867821 -102.356916) (xy 306.875941 -102.412092)
			(xy 306.87645 -102.439978) (xy 306.875941 -102.467864) (xy 306.872831 -102.489) (xy 307.001924 -102.489)
			(xy 307.005995 -102.433378) (xy 307.018121 -102.378941) (xy 307.038044 -102.32685) (xy 307.06534 -102.278215)
			(xy 307.099426 -102.234072) (xy 307.139575 -102.195363) (xy 307.184933 -102.162912) (xy 307.234533 -102.137411)
			(xy 307.287317 -102.119404) (xy 307.34216 -102.109274) (xy 307.397894 -102.107237) (xy 307.453331 -102.113337)
			(xy 307.507288 -102.127443) (xy 307.558617 -102.149255) (xy 307.606223 -102.178309) (xy 307.649091 -102.213984)
			(xy 307.686308 -102.255521) (xy 307.717081 -102.302034) (xy 307.740753 -102.352531) (xy 307.756821 -102.405938)
			(xy 307.764941 -102.461114) (xy 307.76545 -102.489) (xy 307.764941 -102.516886) (xy 307.756821 -102.572062)
			(xy 307.740753 -102.625469) (xy 307.717081 -102.675966) (xy 307.686308 -102.722479) (xy 307.649091 -102.764016)
			(xy 307.606223 -102.799691) (xy 307.558617 -102.828745) (xy 307.507288 -102.850557) (xy 307.453331 -102.864663)
			(xy 307.397894 -102.870763) (xy 307.34216 -102.868726) (xy 307.287317 -102.858596) (xy 307.234533 -102.840589)
			(xy 307.184933 -102.815088) (xy 307.139575 -102.782637) (xy 307.099426 -102.743928) (xy 307.06534 -102.699785)
			(xy 307.038044 -102.65115) (xy 307.018121 -102.599059) (xy 307.005995 -102.544622) (xy 307.001924 -102.489)
			(xy 306.872831 -102.489) (xy 306.867821 -102.52304) (xy 306.851753 -102.576447) (xy 306.828081 -102.626944)
			(xy 306.797308 -102.673457) (xy 306.760091 -102.714994) (xy 306.717223 -102.750669) (xy 306.669617 -102.779723)
			(xy 306.618288 -102.801535) (xy 306.564331 -102.815641) (xy 306.508894 -102.821741) (xy 306.45316 -102.819704)
			(xy 306.398317 -102.809574) (xy 306.345533 -102.791567) (xy 306.295933 -102.766066) (xy 306.250575 -102.733615)
			(xy 306.210426 -102.694906) (xy 306.17634 -102.650763) (xy 306.149044 -102.602128) (xy 306.129121 -102.550037)
			(xy 306.116995 -102.4956) (xy 306.112924 -102.439978) (xy 299.894244 -102.439978) (xy 299.893735 -102.467864)
			(xy 299.885615 -102.52304) (xy 299.869547 -102.576447) (xy 299.845875 -102.626944) (xy 299.815102 -102.673457)
			(xy 299.777885 -102.714994) (xy 299.735017 -102.750669) (xy 299.687411 -102.779723) (xy 299.636082 -102.801535)
			(xy 299.582125 -102.815641) (xy 299.526688 -102.821741) (xy 299.470954 -102.819704) (xy 299.416111 -102.809574)
			(xy 299.363327 -102.791567) (xy 299.313727 -102.766066) (xy 299.268369 -102.733615) (xy 299.22822 -102.694906)
			(xy 299.194134 -102.650763) (xy 299.166838 -102.602128) (xy 299.146915 -102.550037) (xy 299.134789 -102.4956)
			(xy 299.130718 -102.439978) (xy 290.310549 -102.439978) (xy 290.354435 -102.458627) (xy 290.402041 -102.487681)
			(xy 290.444909 -102.523356) (xy 290.482126 -102.564893) (xy 290.512899 -102.611406) (xy 290.536571 -102.661903)
			(xy 290.552639 -102.71531) (xy 290.560759 -102.770486) (xy 290.561268 -102.798372) (xy 290.560759 -102.826258)
			(xy 290.552639 -102.881434) (xy 290.536571 -102.934841) (xy 290.512899 -102.985338) (xy 290.482126 -103.031851)
			(xy 290.444909 -103.073388) (xy 290.407288 -103.104696) (xy 310.369456 -103.104696) (xy 310.373527 -103.049074)
			(xy 310.385653 -102.994637) (xy 310.405576 -102.942546) (xy 310.432872 -102.893911) (xy 310.466958 -102.849768)
			(xy 310.507107 -102.811059) (xy 310.552465 -102.778608) (xy 310.602065 -102.753107) (xy 310.654849 -102.7351)
			(xy 310.709692 -102.72497) (xy 310.765426 -102.722933) (xy 310.820863 -102.729033) (xy 310.87482 -102.743139)
			(xy 310.926149 -102.764951) (xy 310.973755 -102.794005) (xy 311.016623 -102.82968) (xy 311.05384 -102.871217)
			(xy 311.084613 -102.91773) (xy 311.108285 -102.968227) (xy 311.124353 -103.021634) (xy 311.132473 -103.07681)
			(xy 311.132982 -103.104696) (xy 311.132473 -103.132582) (xy 311.131493 -103.13924) (xy 321.707 -103.13924)
			(xy 321.711071 -103.083618) (xy 321.723197 -103.029181) (xy 321.74312 -102.97709) (xy 321.770416 -102.928455)
			(xy 321.804502 -102.884312) (xy 321.844651 -102.845603) (xy 321.890009 -102.813152) (xy 321.939609 -102.787651)
			(xy 321.992393 -102.769644) (xy 322.047236 -102.759514) (xy 322.10297 -102.757477) (xy 322.158407 -102.763577)
			(xy 322.212364 -102.777683) (xy 322.263693 -102.799495) (xy 322.311299 -102.828549) (xy 322.354167 -102.864224)
			(xy 322.391384 -102.905761) (xy 322.422157 -102.952274) (xy 322.445829 -103.002771) (xy 322.461897 -103.056178)
			(xy 322.470017 -103.111354) (xy 322.470526 -103.13924) (xy 322.470017 -103.167126) (xy 322.461897 -103.222302)
			(xy 322.445829 -103.275709) (xy 322.422157 -103.326206) (xy 322.391384 -103.372719) (xy 322.354167 -103.414256)
			(xy 322.311299 -103.449931) (xy 322.263693 -103.478985) (xy 322.212364 -103.500797) (xy 322.158407 -103.514903)
			(xy 322.10297 -103.521003) (xy 322.047236 -103.518966) (xy 321.992393 -103.508836) (xy 321.939609 -103.490829)
			(xy 321.890009 -103.465328) (xy 321.844651 -103.432877) (xy 321.804502 -103.394168) (xy 321.770416 -103.350025)
			(xy 321.74312 -103.30139) (xy 321.723197 -103.249299) (xy 321.711071 -103.194862) (xy 321.707 -103.13924)
			(xy 311.131493 -103.13924) (xy 311.124353 -103.187758) (xy 311.108285 -103.241165) (xy 311.084613 -103.291662)
			(xy 311.05384 -103.338175) (xy 311.016623 -103.379712) (xy 310.973755 -103.415387) (xy 310.926149 -103.444441)
			(xy 310.87482 -103.466253) (xy 310.820863 -103.480359) (xy 310.765426 -103.486459) (xy 310.709692 -103.484422)
			(xy 310.654849 -103.474292) (xy 310.602065 -103.456285) (xy 310.552465 -103.430784) (xy 310.507107 -103.398333)
			(xy 310.466958 -103.359624) (xy 310.432872 -103.315481) (xy 310.405576 -103.266846) (xy 310.385653 -103.214755)
			(xy 310.373527 -103.160318) (xy 310.369456 -103.104696) (xy 290.407288 -103.104696) (xy 290.402041 -103.109063)
			(xy 290.354435 -103.138117) (xy 290.303106 -103.159929) (xy 290.249149 -103.174035) (xy 290.193712 -103.180135)
			(xy 290.137978 -103.178098) (xy 290.083135 -103.167968) (xy 290.030351 -103.149961) (xy 289.980751 -103.12446)
			(xy 289.935393 -103.092009) (xy 289.895244 -103.0533) (xy 289.861158 -103.009157) (xy 289.833862 -102.960522)
			(xy 289.813939 -102.908431) (xy 289.801813 -102.853994) (xy 289.797742 -102.798372) (xy 287.049554 -102.798372)
			(xy 287.039975 -102.802746) (xy 286.987673 -102.818099) (xy 286.933717 -102.825851) (xy 286.906462 -102.826312)
			(xy 286.88935 -102.826118) (xy 286.855263 -102.823068) (xy 286.83839 -102.820216) (xy 286.827098 -102.818877)
			(xy 286.805212 -102.824933) (xy 286.796226 -102.8319) (xy 286.771842 -102.852728) (xy 286.763415 -102.860706)
			(xy 286.754287 -102.882017) (xy 286.754316 -102.893622) (xy 286.754824 -102.912672) (xy 286.754824 -103.776272)
			(xy 286.754316 -103.796084) (xy 286.754371 -103.807674) (xy 286.757235 -103.814372) (xy 289.797742 -103.814372)
			(xy 289.801813 -103.75875) (xy 289.813939 -103.704313) (xy 289.833862 -103.652222) (xy 289.861158 -103.603587)
			(xy 289.895244 -103.559444) (xy 289.935393 -103.520735) (xy 289.980751 -103.488284) (xy 290.030351 -103.462783)
			(xy 290.083135 -103.444776) (xy 290.137978 -103.434646) (xy 290.193712 -103.432609) (xy 290.249149 -103.438709)
			(xy 290.303106 -103.452815) (xy 290.354435 -103.474627) (xy 290.402041 -103.503681) (xy 290.444909 -103.539356)
			(xy 290.482126 -103.580893) (xy 290.512899 -103.627406) (xy 290.536571 -103.677903) (xy 290.552639 -103.73131)
			(xy 290.560759 -103.786486) (xy 290.561268 -103.814372) (xy 290.560759 -103.842258) (xy 290.552639 -103.897434)
			(xy 290.536571 -103.950841) (xy 290.512899 -104.001338) (xy 290.482126 -104.047851) (xy 290.444909 -104.089388)
			(xy 290.402041 -104.125063) (xy 290.354435 -104.154117) (xy 290.303106 -104.175929) (xy 290.249149 -104.190035)
			(xy 290.193712 -104.196135) (xy 290.137978 -104.194098) (xy 290.083135 -104.183968) (xy 290.030351 -104.165961)
			(xy 289.980751 -104.14046) (xy 289.935393 -104.108009) (xy 289.895244 -104.0693) (xy 289.861158 -104.025157)
			(xy 289.833862 -103.976522) (xy 289.813939 -103.924431) (xy 289.801813 -103.869994) (xy 289.797742 -103.814372)
			(xy 286.757235 -103.814372) (xy 286.763474 -103.828961) (xy 286.771842 -103.836978) (xy 286.796226 -103.85806)
			(xy 286.80521 -103.865161) (xy 286.827305 -103.871102) (xy 286.838644 -103.86949) (xy 286.855451 -103.866622)
			(xy 286.889413 -103.863574) (xy 286.906462 -103.863394) (xy 286.933717 -103.863851) (xy 286.987672 -103.871603)
			(xy 287.039975 -103.886956) (xy 287.08956 -103.909597) (xy 287.135418 -103.939064) (xy 287.176615 -103.974758)
			(xy 287.212313 -104.015951) (xy 287.241785 -104.061807) (xy 287.264431 -104.11139) (xy 287.279789 -104.163691)
			(xy 287.287547 -104.217645) (xy 287.287547 -104.240076) (xy 299.130718 -104.240076) (xy 299.134789 -104.184454)
			(xy 299.146915 -104.130017) (xy 299.166838 -104.077926) (xy 299.194134 -104.029291) (xy 299.22822 -103.985148)
			(xy 299.268369 -103.946439) (xy 299.313727 -103.913988) (xy 299.363327 -103.888487) (xy 299.416111 -103.87048)
			(xy 299.470954 -103.86035) (xy 299.526688 -103.858313) (xy 299.582125 -103.864413) (xy 299.636082 -103.878519)
			(xy 299.687411 -103.900331) (xy 299.735017 -103.929385) (xy 299.777885 -103.96506) (xy 299.815102 -104.006597)
			(xy 299.845875 -104.05311) (xy 299.869547 -104.103607) (xy 299.885615 -104.157014) (xy 299.893735 -104.21219)
			(xy 299.894244 -104.240076) (xy 306.112924 -104.240076) (xy 306.116995 -104.184454) (xy 306.129121 -104.130017)
			(xy 306.149044 -104.077926) (xy 306.17634 -104.029291) (xy 306.210426 -103.985148) (xy 306.250575 -103.946439)
			(xy 306.295933 -103.913988) (xy 306.345533 -103.888487) (xy 306.398317 -103.87048) (xy 306.45316 -103.86035)
			(xy 306.508894 -103.858313) (xy 306.564331 -103.864413) (xy 306.618288 -103.878519) (xy 306.635893 -103.886)
			(xy 307.509924 -103.886) (xy 307.513995 -103.830378) (xy 307.526121 -103.775941) (xy 307.546044 -103.72385)
			(xy 307.57334 -103.675215) (xy 307.607426 -103.631072) (xy 307.647575 -103.592363) (xy 307.692933 -103.559912)
			(xy 307.742533 -103.534411) (xy 307.795317 -103.516404) (xy 307.85016 -103.506274) (xy 307.905894 -103.504237)
			(xy 307.961331 -103.510337) (xy 308.015288 -103.524443) (xy 308.066617 -103.546255) (xy 308.114223 -103.575309)
			(xy 308.157091 -103.610984) (xy 308.194308 -103.652521) (xy 308.225081 -103.699034) (xy 308.248753 -103.749531)
			(xy 308.264821 -103.802938) (xy 308.272941 -103.858114) (xy 308.27345 -103.886) (xy 308.272941 -103.913886)
			(xy 308.264821 -103.969062) (xy 308.248753 -104.022469) (xy 308.225081 -104.072966) (xy 308.194308 -104.119479)
			(xy 308.193218 -104.120696) (xy 310.369456 -104.120696) (xy 310.373527 -104.065074) (xy 310.385653 -104.010637)
			(xy 310.405576 -103.958546) (xy 310.432872 -103.909911) (xy 310.466958 -103.865768) (xy 310.507107 -103.827059)
			(xy 310.552465 -103.794608) (xy 310.602065 -103.769107) (xy 310.654849 -103.7511) (xy 310.709692 -103.74097)
			(xy 310.765426 -103.738933) (xy 310.820863 -103.745033) (xy 310.87482 -103.759139) (xy 310.926149 -103.780951)
			(xy 310.973755 -103.810005) (xy 311.016623 -103.84568) (xy 311.05384 -103.887217) (xy 311.084613 -103.93373)
			(xy 311.108285 -103.984227) (xy 311.124353 -104.037634) (xy 311.132473 -104.09281) (xy 311.132982 -104.120696)
			(xy 311.132473 -104.148582) (xy 311.124353 -104.203758) (xy 311.108285 -104.257165) (xy 311.084613 -104.307662)
			(xy 311.05384 -104.354175) (xy 311.016623 -104.395712) (xy 310.973755 -104.431387) (xy 310.926149 -104.460441)
			(xy 310.87482 -104.482253) (xy 310.820863 -104.496359) (xy 310.765426 -104.502459) (xy 310.709692 -104.500422)
			(xy 310.654849 -104.490292) (xy 310.602065 -104.472285) (xy 310.552465 -104.446784) (xy 310.507107 -104.414333)
			(xy 310.466958 -104.375624) (xy 310.432872 -104.331481) (xy 310.405576 -104.282846) (xy 310.385653 -104.230755)
			(xy 310.373527 -104.176318) (xy 310.369456 -104.120696) (xy 308.193218 -104.120696) (xy 308.157091 -104.161016)
			(xy 308.114223 -104.196691) (xy 308.066617 -104.225745) (xy 308.015288 -104.247557) (xy 307.961331 -104.261663)
			(xy 307.905894 -104.267763) (xy 307.85016 -104.265726) (xy 307.795317 -104.255596) (xy 307.742533 -104.237589)
			(xy 307.692933 -104.212088) (xy 307.647575 -104.179637) (xy 307.607426 -104.140928) (xy 307.57334 -104.096785)
			(xy 307.546044 -104.04815) (xy 307.526121 -103.996059) (xy 307.513995 -103.941622) (xy 307.509924 -103.886)
			(xy 306.635893 -103.886) (xy 306.669617 -103.900331) (xy 306.717223 -103.929385) (xy 306.760091 -103.96506)
			(xy 306.797308 -104.006597) (xy 306.828081 -104.05311) (xy 306.851753 -104.103607) (xy 306.867821 -104.157014)
			(xy 306.875941 -104.21219) (xy 306.87645 -104.240076) (xy 306.875941 -104.267962) (xy 306.867821 -104.323138)
			(xy 306.851753 -104.376545) (xy 306.828081 -104.427042) (xy 306.797308 -104.473555) (xy 306.760091 -104.515092)
			(xy 306.717223 -104.550767) (xy 306.669617 -104.579821) (xy 306.618288 -104.601633) (xy 306.564331 -104.615739)
			(xy 306.508894 -104.621839) (xy 306.45316 -104.619802) (xy 306.398317 -104.609672) (xy 306.345533 -104.591665)
			(xy 306.295933 -104.566164) (xy 306.250575 -104.533713) (xy 306.210426 -104.495004) (xy 306.17634 -104.450861)
			(xy 306.149044 -104.402226) (xy 306.129121 -104.350135) (xy 306.116995 -104.295698) (xy 306.112924 -104.240076)
			(xy 299.894244 -104.240076) (xy 299.893735 -104.267962) (xy 299.885615 -104.323138) (xy 299.869547 -104.376545)
			(xy 299.845875 -104.427042) (xy 299.815102 -104.473555) (xy 299.777885 -104.515092) (xy 299.735017 -104.550767)
			(xy 299.687411 -104.579821) (xy 299.636082 -104.601633) (xy 299.582125 -104.615739) (xy 299.526688 -104.621839)
			(xy 299.470954 -104.619802) (xy 299.416111 -104.609672) (xy 299.363327 -104.591665) (xy 299.313727 -104.566164)
			(xy 299.268369 -104.533713) (xy 299.22822 -104.495004) (xy 299.194134 -104.450861) (xy 299.166838 -104.402226)
			(xy 299.146915 -104.350135) (xy 299.134789 -104.295698) (xy 299.130718 -104.240076) (xy 287.287547 -104.240076)
			(xy 287.287547 -104.272155) (xy 287.279789 -104.326109) (xy 287.264431 -104.37841) (xy 287.241785 -104.427993)
			(xy 287.212313 -104.473849) (xy 287.176615 -104.515042) (xy 287.135418 -104.550736) (xy 287.08956 -104.580203)
			(xy 287.039975 -104.602844) (xy 286.987672 -104.618197) (xy 286.933717 -104.625949) (xy 286.906462 -104.62641)
			(xy 286.879452 -104.626013) (xy 286.825971 -104.6184) (xy 286.774099 -104.60332) (xy 286.724872 -104.581072)
			(xy 286.679277 -104.552103) (xy 286.638225 -104.51699) (xy 286.602536 -104.476438) (xy 286.572925 -104.431256)
			(xy 286.549985 -104.38235) (xy 286.534173 -104.330695) (xy 286.529526 -104.304084) (xy 286.528002 -104.293416)
			(xy 286.516572 -104.275636) (xy 286.445198 -104.228138) (xy 286.436261 -104.222806) (xy 286.415804 -104.219122)
			(xy 286.405574 -104.221026) (xy 286.404812 -104.221026) (xy 286.378234 -104.227072) (xy 286.324115 -104.233569)
			(xy 286.296862 -104.23398) (xy 286.269544 -104.233587) (xy 286.215296 -104.227097) (xy 286.188658 -104.221026)
			(xy 286.18815 -104.221026) (xy 286.17792 -104.219164) (xy 286.157473 -104.222839) (xy 286.148526 -104.228138)
			(xy 286.077152 -104.275636) (xy 286.065722 -104.293416) (xy 286.064198 -104.304084) (xy 286.05952 -104.330685)
			(xy 286.043692 -104.382322) (xy 286.020741 -104.431211) (xy 285.991126 -104.476376) (xy 285.955439 -104.516915)
			(xy 285.914392 -104.552017) (xy 285.868807 -104.580981) (xy 285.819593 -104.603228) (xy 285.767734 -104.618314)
			(xy 285.714266 -104.625938) (xy 285.687262 -104.62641) (xy 285.659893 -104.625905) (xy 285.605716 -104.618096)
			(xy 285.553213 -104.602616) (xy 285.503466 -104.579783) (xy 285.457497 -104.550067) (xy 285.436564 -104.53243)
			(xy 285.43631 -104.532176) (xy 285.429227 -104.526585) (xy 285.412307 -104.520342) (xy 285.40329 -104.519984)
			(xy 285.336234 -104.519984) (xy 285.327219 -104.520361) (xy 285.310302 -104.526595) (xy 285.303214 -104.532176)
			(xy 285.303214 -104.53243) (xy 285.30296 -104.53243) (xy 285.28202 -104.550059) (xy 285.236049 -104.579771)
			(xy 285.186303 -104.602609) (xy 285.133805 -104.618102) (xy 285.079631 -104.625934) (xy 285.052262 -104.62641)
			(xy 285.03515 -104.626216) (xy 285.001063 -104.623166) (xy 284.98419 -104.620314) (xy 284.972898 -104.618976)
			(xy 284.951012 -104.625031) (xy 284.942026 -104.631998) (xy 284.917642 -104.652826) (xy 284.909216 -104.660805)
			(xy 284.900087 -104.682115) (xy 284.900116 -104.69372) (xy 284.900624 -104.71277) (xy 284.900624 -104.830372)
			(xy 289.797742 -104.830372) (xy 289.801813 -104.77475) (xy 289.813939 -104.720313) (xy 289.833862 -104.668222)
			(xy 289.861158 -104.619587) (xy 289.895244 -104.575444) (xy 289.935393 -104.536735) (xy 289.980751 -104.504284)
			(xy 290.030351 -104.478783) (xy 290.083135 -104.460776) (xy 290.137978 -104.450646) (xy 290.193712 -104.448609)
			(xy 290.249149 -104.454709) (xy 290.303106 -104.468815) (xy 290.354435 -104.490627) (xy 290.402041 -104.519681)
			(xy 290.444909 -104.555356) (xy 290.482126 -104.596893) (xy 290.512899 -104.643406) (xy 290.527674 -104.674924)
			(xy 320.759326 -104.674924) (xy 320.763397 -104.619302) (xy 320.775523 -104.564865) (xy 320.795446 -104.512774)
			(xy 320.822742 -104.464139) (xy 320.856828 -104.419996) (xy 320.896977 -104.381287) (xy 320.942335 -104.348836)
			(xy 320.991935 -104.323335) (xy 321.044719 -104.305328) (xy 321.099562 -104.295198) (xy 321.155296 -104.293161)
			(xy 321.210733 -104.299261) (xy 321.26469 -104.313367) (xy 321.316019 -104.335179) (xy 321.363625 -104.364233)
			(xy 321.406493 -104.399908) (xy 321.44371 -104.441445) (xy 321.474483 -104.487958) (xy 321.498155 -104.538455)
			(xy 321.514223 -104.591862) (xy 321.522343 -104.647038) (xy 321.522852 -104.674924) (xy 321.522343 -104.70281)
			(xy 321.514223 -104.757986) (xy 321.498155 -104.811393) (xy 321.474483 -104.86189) (xy 321.44371 -104.908403)
			(xy 321.406493 -104.94994) (xy 321.363625 -104.985615) (xy 321.316019 -105.014669) (xy 321.26469 -105.036481)
			(xy 321.210733 -105.050587) (xy 321.155296 -105.056687) (xy 321.099562 -105.05465) (xy 321.044719 -105.04452)
			(xy 320.991935 -105.026513) (xy 320.942335 -105.001012) (xy 320.896977 -104.968561) (xy 320.856828 -104.929852)
			(xy 320.822742 -104.885709) (xy 320.795446 -104.837074) (xy 320.775523 -104.784983) (xy 320.763397 -104.730546)
			(xy 320.759326 -104.674924) (xy 290.527674 -104.674924) (xy 290.536571 -104.693903) (xy 290.552639 -104.74731)
			(xy 290.560759 -104.802486) (xy 290.561268 -104.830372) (xy 290.560759 -104.858258) (xy 290.552639 -104.913434)
			(xy 290.536571 -104.966841) (xy 290.512899 -105.017338) (xy 290.482126 -105.063851) (xy 290.444909 -105.105388)
			(xy 290.402041 -105.141063) (xy 290.354435 -105.170117) (xy 290.303106 -105.191929) (xy 290.249149 -105.206035)
			(xy 290.193712 -105.212135) (xy 290.137978 -105.210098) (xy 290.083135 -105.199968) (xy 290.030351 -105.181961)
			(xy 289.980751 -105.15646) (xy 289.935393 -105.124009) (xy 289.895244 -105.0853) (xy 289.861158 -105.041157)
			(xy 289.833862 -104.992522) (xy 289.813939 -104.940431) (xy 289.801813 -104.885994) (xy 289.797742 -104.830372)
			(xy 284.900624 -104.830372) (xy 284.900624 -105.57637) (xy 284.900116 -105.596182) (xy 284.900173 -105.607772)
			(xy 284.909275 -105.629059) (xy 284.917642 -105.637076) (xy 284.942026 -105.658158) (xy 284.95101 -105.665259)
			(xy 284.973105 -105.6712) (xy 284.984444 -105.669588) (xy 285.001251 -105.66672) (xy 285.035213 -105.663672)
			(xy 285.052262 -105.663492) (xy 285.079631 -105.663982) (xy 285.133809 -105.671795) (xy 285.186312 -105.687278)
			(xy 285.236059 -105.710114) (xy 285.282027 -105.739833) (xy 285.30296 -105.757472) (xy 285.309818 -105.763568)
			(xy 285.326836 -105.769918) (xy 285.41218 -105.769918) (xy 285.429452 -105.763314) (xy 285.43631 -105.757218)
			(xy 285.457255 -105.739595) (xy 285.503221 -105.709873) (xy 285.552965 -105.687031) (xy 285.605464 -105.671537)
			(xy 285.659639 -105.66371) (xy 285.687008 -105.663238) (xy 285.687262 -105.663238) (xy 285.71424 -105.663666)
			(xy 285.76766 -105.671255) (xy 285.819477 -105.686302) (xy 285.868653 -105.708504) (xy 285.914208 -105.73742)
			(xy 285.955229 -105.77247) (xy 285.990899 -105.812954) (xy 286.020503 -105.858064) (xy 286.04345 -105.906898)
			(xy 286.059282 -105.958479) (xy 286.063944 -105.985056) (xy 286.066097 -105.995289) (xy 286.077386 -106.012865)
			(xy 286.085788 -106.019092) (xy 286.157162 -106.06659) (xy 286.178244 -106.0704) (xy 286.188404 -106.06786)
			(xy 286.2151 -106.061729) (xy 286.269475 -106.055101) (xy 286.296862 -106.054652) (xy 286.32425 -106.055099)
			(xy 286.378626 -106.061718) (xy 286.40532 -106.06786) (xy 286.41548 -106.0704) (xy 286.436562 -106.06659)
			(xy 286.516826 -106.01325) (xy 286.528002 -105.995724) (xy 286.52978 -105.985056) (xy 286.53441 -105.958478)
			(xy 286.550271 -105.906912) (xy 286.573238 -105.858095) (xy 286.602855 -105.813) (xy 286.63853 -105.772529)
			(xy 286.679551 -105.737488) (xy 286.7251 -105.708576) (xy 286.774269 -105.686371) (xy 286.826076 -105.671314)
			(xy 286.879487 -105.663707) (xy 286.906462 -105.663238) (xy 286.93372 -105.663606) (xy 286.987682 -105.67136)
			(xy 287.03999 -105.686714) (xy 287.089581 -105.709358) (xy 287.135445 -105.738828) (xy 287.176647 -105.774526)
			(xy 287.212349 -105.815725) (xy 287.241824 -105.861585) (xy 287.264472 -105.911174) (xy 287.279832 -105.963481)
			(xy 287.287591 -106.017442) (xy 287.287591 -106.071958) (xy 287.279832 -106.125919) (xy 287.264472 -106.178226)
			(xy 287.241824 -106.227815) (xy 287.212349 -106.273675) (xy 287.176647 -106.314874) (xy 287.135445 -106.350572)
			(xy 287.089581 -106.380042) (xy 287.03999 -106.402686) (xy 286.987682 -106.41804) (xy 286.93372 -106.425794)
			(xy 286.906462 -106.426254) (xy 286.88935 -106.426059) (xy 286.855263 -106.423009) (xy 286.83839 -106.420158)
			(xy 286.827098 -106.41881) (xy 286.80521 -106.42487) (xy 286.796226 -106.431842) (xy 286.771842 -106.45267)
			(xy 286.763394 -106.460631) (xy 286.754278 -106.481954) (xy 286.754316 -106.493564) (xy 286.754824 -106.512614)
			(xy 286.754824 -107.210352) (xy 297.165012 -107.210352) (xy 297.169083 -107.15473) (xy 297.181209 -107.100293)
			(xy 297.201132 -107.048202) (xy 297.228428 -106.999567) (xy 297.262514 -106.955424) (xy 297.302663 -106.916715)
			(xy 297.348021 -106.884264) (xy 297.397621 -106.858763) (xy 297.450405 -106.840756) (xy 297.505248 -106.830626)
			(xy 297.560982 -106.828589) (xy 297.616419 -106.834689) (xy 297.670376 -106.848795) (xy 297.721705 -106.870607)
			(xy 297.769311 -106.899661) (xy 297.812179 -106.935336) (xy 297.849396 -106.976873) (xy 297.880169 -107.023386)
			(xy 297.903841 -107.073883) (xy 297.91724 -107.11842) (xy 299.03775 -107.11842) (xy 299.03775 -107.03152)
			(xy 299.045768 -106.944991) (xy 299.061736 -106.859571) (xy 299.085517 -106.775989) (xy 299.116909 -106.694957)
			(xy 299.155643 -106.617168) (xy 299.20139 -106.543284) (xy 299.253759 -106.473937) (xy 299.312303 -106.409717)
			(xy 299.376523 -106.351173) (xy 299.44587 -106.298804) (xy 299.519754 -106.253057) (xy 299.597543 -106.214323)
			(xy 299.678575 -106.182931) (xy 299.762157 -106.15915) (xy 299.847577 -106.143182) (xy 299.934106 -106.135164)
			(xy 300.021006 -106.135164) (xy 300.107535 -106.143182) (xy 300.192955 -106.15915) (xy 300.276537 -106.182931)
			(xy 300.357569 -106.214323) (xy 300.435358 -106.253057) (xy 300.509242 -106.298804) (xy 300.578589 -106.351173)
			(xy 300.642809 -106.409717) (xy 300.701353 -106.473937) (xy 300.753722 -106.543284) (xy 300.799469 -106.617168)
			(xy 300.838203 -106.694957) (xy 300.869595 -106.775989) (xy 300.893376 -106.859571) (xy 300.909344 -106.944991)
			(xy 300.917362 -107.03152) (xy 300.917864 -107.07497) (xy 300.917362 -107.11842) (xy 300.91736 -107.118439)
			(xy 301.290718 -107.118439) (xy 301.290718 -107.031561) (xy 301.298734 -106.945054) (xy 301.314697 -106.859655)
			(xy 301.338472 -106.776093) (xy 301.369856 -106.695082) (xy 301.40858 -106.617312) (xy 301.454315 -106.543446)
			(xy 301.50667 -106.474116) (xy 301.565199 -106.409912) (xy 301.629402 -106.351382) (xy 301.698731 -106.299025)
			(xy 301.772596 -106.253289) (xy 301.850365 -106.214563) (xy 301.931376 -106.183178) (xy 302.014937 -106.159401)
			(xy 302.100336 -106.143436) (xy 302.186843 -106.135418) (xy 302.230282 -106.134916) (xy 304.084482 -106.134916)
			(xy 304.12792 -106.135462) (xy 304.214425 -106.143476) (xy 304.299822 -106.159438) (xy 304.383382 -106.183211)
			(xy 304.464392 -106.214594) (xy 304.542161 -106.253316) (xy 304.616025 -106.29905) (xy 304.685354 -106.351403)
			(xy 304.749557 -106.409931) (xy 304.808085 -106.474132) (xy 304.86044 -106.54346) (xy 304.906175 -106.617323)
			(xy 304.944899 -106.695091) (xy 304.976283 -106.776101) (xy 305.000058 -106.85966) (xy 305.016021 -106.945057)
			(xy 305.024037 -107.031562) (xy 305.024037 -107.11842) (xy 306.40756 -107.11842) (xy 306.40756 -107.03152)
			(xy 306.415578 -106.944991) (xy 306.431546 -106.859571) (xy 306.455327 -106.775989) (xy 306.486719 -106.694957)
			(xy 306.525453 -106.617168) (xy 306.5712 -106.543284) (xy 306.623569 -106.473937) (xy 306.682113 -106.409717)
			(xy 306.746333 -106.351173) (xy 306.81568 -106.298804) (xy 306.889564 -106.253057) (xy 306.967353 -106.214323)
			(xy 307.048385 -106.182931) (xy 307.131967 -106.15915) (xy 307.217387 -106.143182) (xy 307.303916 -106.135164)
			(xy 307.390816 -106.135164) (xy 307.477345 -106.143182) (xy 307.562765 -106.15915) (xy 307.646347 -106.182931)
			(xy 307.727379 -106.214323) (xy 307.805168 -106.253057) (xy 307.879052 -106.298804) (xy 307.948399 -106.351173)
			(xy 308.012619 -106.409717) (xy 308.071163 -106.473937) (xy 308.123532 -106.543284) (xy 308.169279 -106.617168)
			(xy 308.208013 -106.694957) (xy 308.239405 -106.775989) (xy 308.263186 -106.859571) (xy 308.279154 -106.944991)
			(xy 308.287172 -107.03152) (xy 308.287674 -107.07497) (xy 308.287172 -107.11842) (xy 308.279154 -107.204949)
			(xy 308.278144 -107.210352) (xy 317.942722 -107.210352) (xy 317.943237 -107.181613) (xy 317.951865 -107.124786)
			(xy 317.968918 -107.069896) (xy 317.994011 -107.018185) (xy 318.026576 -106.970822) (xy 318.045846 -106.949494)
			(xy 318.05245 -106.942636) (xy 318.059562 -106.924602) (xy 318.059562 -106.835702) (xy 318.05245 -106.817668)
			(xy 318.045846 -106.81081) (xy 318.026527 -106.789525) (xy 317.993961 -106.742156) (xy 317.968871 -106.690438)
			(xy 317.951823 -106.63554) (xy 317.943204 -106.578707) (xy 317.94321 -106.521223) (xy 317.951839 -106.464391)
			(xy 317.968896 -106.409497) (xy 317.993996 -106.357783) (xy 318.026571 -106.31042) (xy 318.045846 -106.289094)
			(xy 318.05245 -106.282236) (xy 318.059562 -106.264202) (xy 318.059562 -106.175302) (xy 318.05245 -106.157268)
			(xy 318.045846 -106.15041) (xy 318.026554 -106.129101) (xy 317.99399 -106.081735) (xy 317.968902 -106.030018)
			(xy 317.951856 -105.975123) (xy 317.943239 -105.918292) (xy 317.942722 -105.889552) (xy 317.943208 -105.862301)
			(xy 317.950964 -105.808353) (xy 317.966319 -105.756058) (xy 317.988961 -105.706481) (xy 318.018427 -105.660631)
			(xy 318.054118 -105.61944) (xy 318.095309 -105.583749) (xy 318.141159 -105.554283) (xy 318.190736 -105.531641)
			(xy 318.243031 -105.516286) (xy 318.296979 -105.50853) (xy 318.351481 -105.50853) (xy 318.405429 -105.516286)
			(xy 318.457724 -105.531641) (xy 318.507301 -105.554283) (xy 318.553151 -105.583749) (xy 318.594342 -105.61944)
			(xy 318.630033 -105.660631) (xy 318.659499 -105.706481) (xy 318.682141 -105.756058) (xy 318.697496 -105.808353)
			(xy 318.705252 -105.862301) (xy 318.705738 -105.889552) (xy 318.705236 -105.918292) (xy 318.696606 -105.975119)
			(xy 318.679551 -106.03001) (xy 318.654455 -106.081721) (xy 318.621886 -106.129083) (xy 318.602614 -106.15041)
			(xy 318.59601 -106.157268) (xy 318.588898 -106.175302) (xy 318.588898 -106.264202) (xy 318.59601 -106.282236)
			(xy 318.602614 -106.289094) (xy 318.621836 -106.310463) (xy 318.654399 -106.357819) (xy 318.679491 -106.409524)
			(xy 318.696543 -106.464408) (xy 318.705169 -106.521229) (xy 318.705174 -106.578701) (xy 318.696558 -106.635523)
			(xy 318.679517 -106.69041) (xy 318.654434 -106.74212) (xy 318.62188 -106.789482) (xy 318.602614 -106.81081)
			(xy 318.59601 -106.817668) (xy 318.588898 -106.835702) (xy 318.588898 -106.924602) (xy 318.59601 -106.942636)
			(xy 318.602614 -106.949494) (xy 318.621901 -106.970807) (xy 318.654467 -107.018172) (xy 318.67389 -107.058206)
			(xy 321.773804 -107.058206) (xy 321.77433 -107.029467) (xy 321.782952 -106.97264) (xy 321.800001 -106.917749)
			(xy 321.825093 -106.866037) (xy 321.857657 -106.818675) (xy 321.876928 -106.797348) (xy 321.883532 -106.79049)
			(xy 321.890644 -106.772456) (xy 321.890644 -106.683556) (xy 321.883532 -106.665522) (xy 321.876928 -106.658664)
			(xy 321.857663 -106.637332) (xy 321.825097 -106.589971) (xy 321.800005 -106.53826) (xy 321.782954 -106.48337)
			(xy 321.774331 -106.426543) (xy 321.77433 -106.369066) (xy 321.782952 -106.312239) (xy 321.800002 -106.257348)
			(xy 321.825093 -106.205637) (xy 321.857657 -106.158275) (xy 321.876928 -106.136948) (xy 321.883532 -106.13009)
			(xy 321.890644 -106.112056) (xy 321.890644 -106.023156) (xy 321.883532 -106.005122) (xy 321.876928 -105.998264)
			(xy 321.857659 -105.976936) (xy 321.825092 -105.929574) (xy 321.8 -105.877863) (xy 321.782949 -105.822972)
			(xy 321.774325 -105.766145) (xy 321.773804 -105.737406) (xy 321.77429 -105.710155) (xy 321.782046 -105.656207)
			(xy 321.797401 -105.603912) (xy 321.820043 -105.554335) (xy 321.849509 -105.508485) (xy 321.8852 -105.467294)
			(xy 321.926391 -105.431603) (xy 321.972241 -105.402137) (xy 322.021818 -105.379495) (xy 322.074113 -105.36414)
			(xy 322.128061 -105.356384) (xy 322.182563 -105.356384) (xy 322.236511 -105.36414) (xy 322.288806 -105.379495)
			(xy 322.338383 -105.402137) (xy 322.384233 -105.431603) (xy 322.425424 -105.467294) (xy 322.461115 -105.508485)
			(xy 322.490581 -105.554335) (xy 322.513223 -105.603912) (xy 322.528578 -105.656207) (xy 322.536334 -105.710155)
			(xy 322.53682 -105.737406) (xy 322.536295 -105.766145) (xy 322.527672 -105.822972) (xy 322.510622 -105.877862)
			(xy 322.485531 -105.929574) (xy 322.452966 -105.976937) (xy 322.433696 -105.998264) (xy 322.427092 -106.005122)
			(xy 322.41998 -106.023156) (xy 322.41998 -106.112056) (xy 322.427092 -106.13009) (xy 322.433696 -106.136948)
			(xy 322.452972 -106.15827) (xy 322.485535 -106.205634) (xy 322.510625 -106.257347) (xy 322.527674 -106.312238)
			(xy 322.536295 -106.369065) (xy 322.536295 -106.426543) (xy 322.527672 -106.483371) (xy 322.510622 -106.538262)
			(xy 322.485531 -106.589974) (xy 322.452966 -106.637337) (xy 322.433696 -106.658664) (xy 322.427092 -106.665522)
			(xy 322.41998 -106.683556) (xy 322.41998 -106.772456) (xy 322.427092 -106.79049) (xy 322.433696 -106.797348)
			(xy 322.452958 -106.818683) (xy 322.485528 -106.866041) (xy 322.510623 -106.917751) (xy 322.527676 -106.972641)
			(xy 322.536299 -107.029467) (xy 322.53682 -107.058206) (xy 322.536334 -107.085457) (xy 322.528578 -107.139405)
			(xy 322.513223 -107.1917) (xy 322.490581 -107.241277) (xy 322.461115 -107.287127) (xy 322.425424 -107.328318)
			(xy 322.384233 -107.364009) (xy 322.338383 -107.393475) (xy 322.288806 -107.416117) (xy 322.236511 -107.431472)
			(xy 322.182563 -107.439228) (xy 322.128061 -107.439228) (xy 322.074113 -107.431472) (xy 322.021818 -107.416117)
			(xy 321.972241 -107.393475) (xy 321.926391 -107.364009) (xy 321.8852 -107.328318) (xy 321.849509 -107.287127)
			(xy 321.820043 -107.241277) (xy 321.797401 -107.1917) (xy 321.782046 -107.139405) (xy 321.77429 -107.085457)
			(xy 321.773804 -107.058206) (xy 318.67389 -107.058206) (xy 318.679557 -107.069887) (xy 318.696604 -107.124781)
			(xy 318.705221 -107.181612) (xy 318.705738 -107.210352) (xy 318.705252 -107.237603) (xy 318.697496 -107.291551)
			(xy 318.682141 -107.343846) (xy 318.659499 -107.393423) (xy 318.630033 -107.439273) (xy 318.594342 -107.480464)
			(xy 318.553151 -107.516155) (xy 318.507301 -107.545621) (xy 318.457724 -107.568263) (xy 318.405429 -107.583618)
			(xy 318.351481 -107.591374) (xy 318.296979 -107.591374) (xy 318.243031 -107.583618) (xy 318.190736 -107.568263)
			(xy 318.141159 -107.545621) (xy 318.095309 -107.516155) (xy 318.054118 -107.480464) (xy 318.018427 -107.439273)
			(xy 317.988961 -107.393423) (xy 317.966319 -107.343846) (xy 317.950964 -107.291551) (xy 317.943208 -107.237603)
			(xy 317.942722 -107.210352) (xy 308.278144 -107.210352) (xy 308.263186 -107.290369) (xy 308.239405 -107.373951)
			(xy 308.208013 -107.454983) (xy 308.169279 -107.532772) (xy 308.123532 -107.606656) (xy 308.071163 -107.676003)
			(xy 308.012619 -107.740223) (xy 307.948399 -107.798767) (xy 307.879052 -107.851136) (xy 307.805168 -107.896883)
			(xy 307.727379 -107.935617) (xy 307.646347 -107.967009) (xy 307.562765 -107.99079) (xy 307.477345 -108.006758)
			(xy 307.390816 -108.014776) (xy 307.303916 -108.014776) (xy 307.217387 -108.006758) (xy 307.131967 -107.99079)
			(xy 307.048385 -107.967009) (xy 306.967353 -107.935617) (xy 306.889564 -107.896883) (xy 306.81568 -107.851136)
			(xy 306.746333 -107.798767) (xy 306.682113 -107.740223) (xy 306.623569 -107.676003) (xy 306.5712 -107.606656)
			(xy 306.525453 -107.532772) (xy 306.486719 -107.454983) (xy 306.455327 -107.373951) (xy 306.431546 -107.290369)
			(xy 306.415578 -107.204949) (xy 306.40756 -107.11842) (xy 305.024037 -107.11842) (xy 305.024037 -107.118438)
			(xy 305.016021 -107.204943) (xy 305.000058 -107.29034) (xy 304.976283 -107.373899) (xy 304.944899 -107.454909)
			(xy 304.906175 -107.532677) (xy 304.86044 -107.60654) (xy 304.808085 -107.675868) (xy 304.749557 -107.740069)
			(xy 304.685354 -107.798597) (xy 304.616025 -107.85095) (xy 304.542161 -107.896684) (xy 304.464392 -107.935406)
			(xy 304.383382 -107.966789) (xy 304.299822 -107.990562) (xy 304.214425 -108.006524) (xy 304.12792 -108.014538)
			(xy 304.084482 -108.015024) (xy 302.230282 -108.015024) (xy 302.186843 -108.014582) (xy 302.100336 -108.006564)
			(xy 302.014937 -107.990599) (xy 301.931376 -107.966822) (xy 301.850365 -107.935437) (xy 301.772596 -107.896711)
			(xy 301.698731 -107.850975) (xy 301.629402 -107.798618) (xy 301.565199 -107.740088) (xy 301.50667 -107.675884)
			(xy 301.454315 -107.606554) (xy 301.40858 -107.532688) (xy 301.369856 -107.454918) (xy 301.338472 -107.373907)
			(xy 301.314697 -107.290345) (xy 301.298734 -107.204946) (xy 301.290718 -107.118439) (xy 300.91736 -107.118439)
			(xy 300.909344 -107.204949) (xy 300.893376 -107.290369) (xy 300.869595 -107.373951) (xy 300.838203 -107.454983)
			(xy 300.799469 -107.532772) (xy 300.753722 -107.606656) (xy 300.701353 -107.676003) (xy 300.642809 -107.740223)
			(xy 300.578589 -107.798767) (xy 300.509242 -107.851136) (xy 300.435358 -107.896883) (xy 300.357569 -107.935617)
			(xy 300.276537 -107.967009) (xy 300.192955 -107.99079) (xy 300.107535 -108.006758) (xy 300.021006 -108.014776)
			(xy 299.934106 -108.014776) (xy 299.847577 -108.006758) (xy 299.762157 -107.99079) (xy 299.678575 -107.967009)
			(xy 299.597543 -107.935617) (xy 299.519754 -107.896883) (xy 299.44587 -107.851136) (xy 299.376523 -107.798767)
			(xy 299.312303 -107.740223) (xy 299.253759 -107.676003) (xy 299.20139 -107.606656) (xy 299.155643 -107.532772)
			(xy 299.116909 -107.454983) (xy 299.085517 -107.373951) (xy 299.061736 -107.290369) (xy 299.045768 -107.204949)
			(xy 299.03775 -107.11842) (xy 297.91724 -107.11842) (xy 297.919909 -107.12729) (xy 297.928029 -107.182466)
			(xy 297.928538 -107.210352) (xy 297.928029 -107.238238) (xy 297.919909 -107.293414) (xy 297.903841 -107.346821)
			(xy 297.880169 -107.397318) (xy 297.849396 -107.443831) (xy 297.812179 -107.485368) (xy 297.769311 -107.521043)
			(xy 297.721705 -107.550097) (xy 297.670376 -107.571909) (xy 297.616419 -107.586015) (xy 297.560982 -107.592115)
			(xy 297.505248 -107.590078) (xy 297.450405 -107.579948) (xy 297.397621 -107.561941) (xy 297.348021 -107.53644)
			(xy 297.302663 -107.503989) (xy 297.262514 -107.46528) (xy 297.228428 -107.421137) (xy 297.201132 -107.372502)
			(xy 297.181209 -107.320411) (xy 297.169083 -107.265974) (xy 297.165012 -107.210352) (xy 286.754824 -107.210352)
			(xy 286.754824 -107.376214) (xy 286.754316 -107.396026) (xy 286.754347 -107.407618) (xy 286.763467 -107.428906)
			(xy 286.771842 -107.43692) (xy 286.796226 -107.458002) (xy 286.805214 -107.465097) (xy 286.827306 -107.471044)
			(xy 286.838644 -107.469432) (xy 286.855451 -107.466565) (xy 286.889413 -107.463516) (xy 286.906462 -107.463336)
			(xy 286.93372 -107.463708) (xy 286.987681 -107.471462) (xy 287.03999 -107.486816) (xy 287.08958 -107.509459)
			(xy 287.135444 -107.53893) (xy 287.176646 -107.574628) (xy 287.212347 -107.615826) (xy 287.241822 -107.661686)
			(xy 287.26447 -107.711275) (xy 287.27983 -107.763582) (xy 287.287589 -107.817542) (xy 287.287589 -107.872058)
			(xy 287.27983 -107.926018) (xy 287.26447 -107.978325) (xy 287.241822 -108.027914) (xy 287.212347 -108.073774)
			(xy 287.176646 -108.114972) (xy 287.135444 -108.15067) (xy 287.08958 -108.180141) (xy 287.03999 -108.202784)
			(xy 286.987681 -108.218138) (xy 286.93372 -108.225892) (xy 286.906462 -108.226352) (xy 286.879454 -108.225919)
			(xy 286.825976 -108.218308) (xy 286.774106 -108.203229) (xy 286.724882 -108.180985) (xy 286.679288 -108.152019)
			(xy 286.638236 -108.116911) (xy 286.602547 -108.076363) (xy 286.572935 -108.031187) (xy 286.549991 -107.982285)
			(xy 286.534175 -107.930635) (xy 286.529526 -107.904026) (xy 286.528002 -107.893358) (xy 286.516572 -107.875578)
			(xy 286.445198 -107.82808) (xy 286.436259 -107.82275) (xy 286.415803 -107.819063) (xy 286.405574 -107.820968)
			(xy 286.404812 -107.820968) (xy 286.378241 -107.827076) (xy 286.324122 -107.833704) (xy 286.296862 -107.834176)
			(xy 286.269537 -107.833723) (xy 286.215289 -107.827101) (xy 286.188658 -107.820968) (xy 286.18815 -107.820968)
			(xy 286.17792 -107.819115) (xy 286.157474 -107.822786) (xy 286.148526 -107.82808) (xy 286.077152 -107.875578)
			(xy 286.065722 -107.893358) (xy 286.064198 -107.904026) (xy 286.059552 -107.930632) (xy 286.043718 -107.98227)
			(xy 286.020762 -108.031159) (xy 285.991143 -108.076323) (xy 285.955452 -108.116861) (xy 285.914402 -108.151962)
			(xy 285.868814 -108.180925) (xy 285.819598 -108.203171) (xy 285.767737 -108.218256) (xy 285.714267 -108.22588)
			(xy 285.687262 -108.226352) (xy 285.659893 -108.225861) (xy 285.605714 -108.218051) (xy 285.553211 -108.202569)
			(xy 285.503463 -108.179732) (xy 285.457496 -108.150012) (xy 285.436564 -108.132372) (xy 285.43631 -108.132118)
			(xy 285.429223 -108.126532) (xy 285.412307 -108.120285) (xy 285.40329 -108.119926) (xy 285.336234 -108.119926)
			(xy 285.327218 -108.120294) (xy 285.310301 -108.126533) (xy 285.303214 -108.132118) (xy 285.303214 -108.132372)
			(xy 285.30296 -108.132372) (xy 285.282013 -108.149992) (xy 285.236044 -108.179708) (xy 285.186301 -108.202548)
			(xy 285.133803 -108.218043) (xy 285.07963 -108.225876) (xy 285.052262 -108.226352) (xy 285.03515 -108.226157)
			(xy 285.001063 -108.223107) (xy 284.98419 -108.220256) (xy 284.972898 -108.218908) (xy 284.95101 -108.224968)
			(xy 284.942026 -108.23194) (xy 284.917642 -108.252768) (xy 284.909195 -108.260729) (xy 284.900078 -108.282053)
			(xy 284.900116 -108.293662) (xy 284.900624 -108.312712) (xy 284.900624 -108.462318) (xy 296.587924 -108.462318)
			(xy 296.591995 -108.406696) (xy 296.604121 -108.352259) (xy 296.624044 -108.300168) (xy 296.65134 -108.251533)
			(xy 296.685426 -108.20739) (xy 296.725575 -108.168681) (xy 296.770933 -108.13623) (xy 296.820533 -108.110729)
			(xy 296.873317 -108.092722) (xy 296.92816 -108.082592) (xy 296.983894 -108.080555) (xy 297.039331 -108.086655)
			(xy 297.093288 -108.100761) (xy 297.144617 -108.122573) (xy 297.192223 -108.151627) (xy 297.235091 -108.187302)
			(xy 297.272308 -108.228839) (xy 297.303081 -108.275352) (xy 297.326753 -108.325849) (xy 297.342746 -108.379006)
			(xy 322.662804 -108.379006) (xy 322.66333 -108.350267) (xy 322.671952 -108.29344) (xy 322.689001 -108.238549)
			(xy 322.714093 -108.186837) (xy 322.746657 -108.139475) (xy 322.765928 -108.118148) (xy 322.772532 -108.11129)
			(xy 322.779644 -108.093256) (xy 322.779644 -108.004356) (xy 322.772532 -107.986322) (xy 322.765928 -107.979464)
			(xy 322.746663 -107.958132) (xy 322.714097 -107.910771) (xy 322.689005 -107.85906) (xy 322.671954 -107.80417)
			(xy 322.663331 -107.747343) (xy 322.66333 -107.689866) (xy 322.671952 -107.633039) (xy 322.689002 -107.578148)
			(xy 322.714093 -107.526437) (xy 322.746657 -107.479075) (xy 322.765928 -107.457748) (xy 322.772532 -107.45089)
			(xy 322.779644 -107.432856) (xy 322.779644 -107.343956) (xy 322.772532 -107.325922) (xy 322.765928 -107.319064)
			(xy 322.746663 -107.297732) (xy 322.714097 -107.250371) (xy 322.689005 -107.19866) (xy 322.671954 -107.14377)
			(xy 322.663331 -107.086943) (xy 322.66333 -107.029466) (xy 322.671952 -106.972639) (xy 322.689002 -106.917748)
			(xy 322.714093 -106.866037) (xy 322.746657 -106.818675) (xy 322.765928 -106.797348) (xy 322.772532 -106.79049)
			(xy 322.779644 -106.772456) (xy 322.779644 -106.683556) (xy 322.772532 -106.665522) (xy 322.765928 -106.658664)
			(xy 322.746663 -106.637332) (xy 322.714097 -106.589971) (xy 322.689005 -106.53826) (xy 322.671954 -106.48337)
			(xy 322.663331 -106.426543) (xy 322.66333 -106.369066) (xy 322.671952 -106.312239) (xy 322.689002 -106.257348)
			(xy 322.714093 -106.205637) (xy 322.746657 -106.158275) (xy 322.765928 -106.136948) (xy 322.772532 -106.13009)
			(xy 322.779644 -106.112056) (xy 322.779644 -106.023156) (xy 322.772532 -106.005122) (xy 322.765928 -105.998264)
			(xy 322.746663 -105.976932) (xy 322.714097 -105.929571) (xy 322.689005 -105.87786) (xy 322.671954 -105.82297)
			(xy 322.663331 -105.766143) (xy 322.66333 -105.708666) (xy 322.671952 -105.651839) (xy 322.689002 -105.596948)
			(xy 322.714093 -105.545237) (xy 322.746657 -105.497875) (xy 322.765928 -105.476548) (xy 322.772532 -105.46969)
			(xy 322.779644 -105.451656) (xy 322.779644 -105.362756) (xy 322.772532 -105.344722) (xy 322.765928 -105.337864)
			(xy 322.746663 -105.316532) (xy 322.714097 -105.269171) (xy 322.689005 -105.21746) (xy 322.671954 -105.16257)
			(xy 322.663331 -105.105743) (xy 322.66333 -105.048266) (xy 322.671952 -104.991439) (xy 322.689002 -104.936548)
			(xy 322.714093 -104.884837) (xy 322.746657 -104.837475) (xy 322.765928 -104.816148) (xy 322.772532 -104.80929)
			(xy 322.779644 -104.791256) (xy 322.779644 -104.702356) (xy 322.772532 -104.684322) (xy 322.765928 -104.677464)
			(xy 322.746663 -104.656132) (xy 322.714097 -104.608771) (xy 322.689005 -104.55706) (xy 322.671954 -104.50217)
			(xy 322.663331 -104.445343) (xy 322.66333 -104.387866) (xy 322.671952 -104.331039) (xy 322.689002 -104.276148)
			(xy 322.714093 -104.224437) (xy 322.746657 -104.177075) (xy 322.765928 -104.155748) (xy 322.772532 -104.14889)
			(xy 322.779644 -104.130856) (xy 322.779644 -104.041956) (xy 322.772532 -104.023922) (xy 322.765928 -104.017064)
			(xy 322.746663 -103.995732) (xy 322.714097 -103.948371) (xy 322.689005 -103.89666) (xy 322.671954 -103.84177)
			(xy 322.663331 -103.784943) (xy 322.66333 -103.727466) (xy 322.671952 -103.670639) (xy 322.689002 -103.615748)
			(xy 322.714093 -103.564037) (xy 322.746657 -103.516675) (xy 322.765928 -103.495348) (xy 322.772532 -103.48849)
			(xy 322.779644 -103.470456) (xy 322.779644 -103.381556) (xy 322.772532 -103.363522) (xy 322.765928 -103.356664)
			(xy 322.746659 -103.335336) (xy 322.714092 -103.287974) (xy 322.689 -103.236263) (xy 322.671949 -103.181372)
			(xy 322.663325 -103.124545) (xy 322.662804 -103.095806) (xy 322.663245 -103.068599) (xy 322.67097 -103.014735)
			(xy 322.686276 -102.962517) (xy 322.708854 -102.913007) (xy 322.738244 -102.867212) (xy 322.773848 -102.826063)
			(xy 322.814943 -102.790395) (xy 322.837556 -102.775258) (xy 322.845938 -102.769924) (xy 322.857114 -102.753668)
			(xy 322.875402 -102.674674) (xy 322.87721 -102.665045) (xy 322.874213 -102.645704) (xy 322.86956 -102.637082)
			(xy 322.869306 -102.637082) (xy 322.869306 -102.636574) (xy 322.856101 -102.614063) (xy 322.835245 -102.566221)
			(xy 322.821095 -102.515987) (xy 322.813911 -102.464294) (xy 322.813426 -102.4382) (xy 322.813855 -102.410946)
			(xy 322.821613 -102.356992) (xy 322.836971 -102.304691) (xy 322.859616 -102.255109) (xy 322.889087 -102.209254)
			(xy 322.924785 -102.16806) (xy 322.965981 -102.132367) (xy 323.011839 -102.1029) (xy 323.061423 -102.080259)
			(xy 323.113725 -102.064906) (xy 323.16768 -102.057153) (xy 323.194934 -102.056692) (xy 323.22441 -102.057275)
			(xy 323.282661 -102.066334) (xy 323.338825 -102.084247) (xy 323.391565 -102.110586) (xy 323.439625 -102.144726)
			(xy 323.461126 -102.164896) (xy 323.469508 -102.173024) (xy 323.49186 -102.180644) (xy 323.595492 -102.165404)
			(xy 323.614796 -102.152196) (xy 323.620638 -102.141782) (xy 323.635208 -102.116818) (xy 323.670732 -102.071223)
			(xy 323.71273 -102.031511) (xy 323.76024 -101.998592) (xy 323.812173 -101.973218) (xy 323.86734 -101.955971)
			(xy 323.924478 -101.947246) (xy 323.953378 -101.94671) (xy 323.980633 -101.947135) (xy 324.034589 -101.95489)
			(xy 324.086892 -101.970245) (xy 324.136477 -101.992887) (xy 324.182336 -102.022356) (xy 324.223533 -102.058052)
			(xy 324.259231 -102.099247) (xy 324.288702 -102.145103) (xy 324.311347 -102.194687) (xy 324.326705 -102.246989)
			(xy 324.334463 -102.300945) (xy 324.334463 -102.355455) (xy 324.326705 -102.409411) (xy 324.311347 -102.461713)
			(xy 324.288702 -102.511297) (xy 324.259231 -102.557153) (xy 324.223533 -102.598348) (xy 324.182336 -102.634044)
			(xy 324.136477 -102.663513) (xy 324.086892 -102.686155) (xy 324.034589 -102.70151) (xy 323.980633 -102.709265)
			(xy 323.953378 -102.709726) (xy 323.923899 -102.70922) (xy 323.865643 -102.700146) (xy 323.809477 -102.682216)
			(xy 323.756738 -102.655859) (xy 323.708683 -102.621701) (xy 323.687186 -102.601522) (xy 323.678804 -102.593394)
			(xy 323.656452 -102.585774) (xy 323.55282 -102.601014) (xy 323.533516 -102.614222) (xy 323.527674 -102.624636)
			(xy 323.512017 -102.65139) (xy 323.473383 -102.699864) (xy 323.42741 -102.741443) (xy 323.40169 -102.758748)
			(xy 323.393308 -102.764082) (xy 323.382132 -102.780338) (xy 323.363844 -102.859332) (xy 323.36204 -102.868962)
			(xy 323.365036 -102.888302) (xy 323.369686 -102.896924) (xy 323.36994 -102.896924) (xy 323.36994 -102.897432)
			(xy 323.383152 -102.919939) (xy 323.404005 -102.967783) (xy 323.418153 -103.018018) (xy 323.425335 -103.069712)
			(xy 323.42582 -103.095806) (xy 323.425295 -103.124545) (xy 323.416672 -103.181372) (xy 323.399622 -103.236262)
			(xy 323.374531 -103.287974) (xy 323.341966 -103.335337) (xy 323.322696 -103.356664) (xy 323.316092 -103.363522)
			(xy 323.30898 -103.381556) (xy 323.30898 -103.470456) (xy 323.316092 -103.48849) (xy 323.322696 -103.495348)
			(xy 323.341972 -103.51667) (xy 323.374535 -103.564034) (xy 323.399625 -103.615747) (xy 323.416674 -103.670638)
			(xy 323.425295 -103.727465) (xy 323.425295 -103.784943) (xy 323.416672 -103.841771) (xy 323.400409 -103.894128)
			(xy 324.413878 -103.894128) (xy 324.417949 -103.838506) (xy 324.430075 -103.784069) (xy 324.449998 -103.731978)
			(xy 324.477294 -103.683343) (xy 324.51138 -103.6392) (xy 324.551529 -103.600491) (xy 324.596887 -103.56804)
			(xy 324.646487 -103.542539) (xy 324.699271 -103.524532) (xy 324.754114 -103.514402) (xy 324.809848 -103.512365)
			(xy 324.865285 -103.518465) (xy 324.919242 -103.532571) (xy 324.970571 -103.554383) (xy 325.018177 -103.583437)
			(xy 325.061045 -103.619112) (xy 325.098262 -103.660649) (xy 325.129035 -103.707162) (xy 325.152707 -103.757659)
			(xy 325.168775 -103.811066) (xy 325.176895 -103.866242) (xy 325.17733 -103.890064) (xy 325.439022 -103.890064)
			(xy 325.443093 -103.834442) (xy 325.455219 -103.780005) (xy 325.475142 -103.727914) (xy 325.502438 -103.679279)
			(xy 325.536524 -103.635136) (xy 325.576673 -103.596427) (xy 325.622031 -103.563976) (xy 325.671631 -103.538475)
			(xy 325.724415 -103.520468) (xy 325.779258 -103.510338) (xy 325.834992 -103.508301) (xy 325.890429 -103.514401)
			(xy 325.944386 -103.528507) (xy 325.995715 -103.550319) (xy 326.043321 -103.579373) (xy 326.086189 -103.615048)
			(xy 326.123406 -103.656585) (xy 326.154179 -103.703098) (xy 326.177851 -103.753595) (xy 326.193919 -103.807002)
			(xy 326.202039 -103.862178) (xy 326.202548 -103.890064) (xy 326.202039 -103.91795) (xy 326.193919 -103.973126)
			(xy 326.178942 -104.022906) (xy 328.065892 -104.022906) (xy 328.066366 -103.996592) (xy 328.0736 -103.944464)
			(xy 328.087918 -103.893822) (xy 328.109049 -103.845623) (xy 328.136594 -103.800779) (xy 328.170031 -103.760139)
			(xy 328.189082 -103.741982) (xy 328.196491 -103.734467) (xy 328.205012 -103.715182) (xy 328.205592 -103.704644)
			(xy 328.205592 -103.629968) (xy 328.205042 -103.619421) (xy 328.196522 -103.600125) (xy 328.189082 -103.59263)
			(xy 328.170045 -103.574456) (xy 328.136586 -103.53383) (xy 328.109025 -103.488994) (xy 328.087884 -103.440796)
			(xy 328.073563 -103.390152) (xy 328.066333 -103.338021) (xy 328.065892 -103.311706) (xy 328.066361 -103.284453)
			(xy 328.074117 -103.230503) (xy 328.089472 -103.178205) (xy 328.112114 -103.128625) (xy 328.141582 -103.082772)
			(xy 328.177275 -103.041579) (xy 328.218467 -103.005885) (xy 328.264319 -102.976417) (xy 328.313899 -102.953774)
			(xy 328.366197 -102.938418) (xy 328.420147 -102.930661) (xy 328.4474 -102.930198) (xy 328.475065 -102.930711)
			(xy 328.529814 -102.938711) (xy 328.582836 -102.954527) (xy 328.633019 -102.97783) (xy 328.679315 -103.008131)
			(xy 328.720753 -103.044796) (xy 328.756466 -103.087057) (xy 328.771504 -103.110284) (xy 328.77813 -103.11997)
			(xy 328.797999 -103.132408) (xy 328.809604 -103.13416) (xy 328.889614 -103.142034) (xy 328.901253 -103.142672)
			(xy 328.923091 -103.134588) (xy 328.931524 -103.12654) (xy 328.931778 -103.126286) (xy 328.949884 -103.107731)
			(xy 328.990211 -103.07515) (xy 329.03458 -103.048334) (xy 329.082173 -103.027777) (xy 329.132113 -103.013858)
			(xy 329.183478 -103.006834) (xy 329.2094 -103.006398) (xy 329.236653 -103.006855) (xy 329.290605 -103.014612)
			(xy 329.342903 -103.029969) (xy 329.392483 -103.052612) (xy 329.438337 -103.08208) (xy 329.47953 -103.117775)
			(xy 329.515223 -103.158968) (xy 329.544691 -103.204822) (xy 329.567333 -103.254403) (xy 329.582689 -103.306701)
			(xy 329.590445 -103.360653) (xy 329.590908 -103.387906) (xy 329.590443 -103.415276) (xy 329.582625 -103.469455)
			(xy 329.567135 -103.521958) (xy 329.544293 -103.571705) (xy 329.514569 -103.617672) (xy 329.496928 -103.638604)
			(xy 329.496674 -103.638858) (xy 329.491096 -103.64595) (xy 329.484845 -103.662863) (xy 329.484482 -103.671878)
			(xy 329.484482 -103.738934) (xy 329.484826 -103.747952) (xy 329.491083 -103.764869) (xy 329.496674 -103.771954)
			(xy 329.496928 -103.771954) (xy 329.496928 -103.772208) (xy 329.514589 -103.793123) (xy 329.544296 -103.839101)
			(xy 329.567128 -103.888853) (xy 329.582614 -103.941357) (xy 329.590437 -103.995536) (xy 329.590908 -104.022906)
			(xy 329.590428 -104.050157) (xy 329.58267 -104.104105) (xy 329.57929 -104.115616) (xy 332.497176 -104.115616)
			(xy 332.497662 -104.089303) (xy 332.504894 -104.037175) (xy 332.51921 -103.986533) (xy 332.540339 -103.938334)
			(xy 332.567881 -103.89349) (xy 332.601316 -103.85285) (xy 332.620366 -103.834692) (xy 332.627768 -103.827171)
			(xy 332.636294 -103.807891) (xy 332.636876 -103.797354) (xy 332.636876 -103.722678) (xy 332.636325 -103.712131)
			(xy 332.627806 -103.692835) (xy 332.620366 -103.68534) (xy 332.601282 -103.667213) (xy 332.567829 -103.626577)
			(xy 332.540274 -103.58173) (xy 332.519141 -103.533524) (xy 332.50483 -103.482872) (xy 332.497611 -103.430734)
			(xy 332.497176 -103.404416) (xy 332.497662 -103.377165) (xy 332.505418 -103.323217) (xy 332.520773 -103.270922)
			(xy 332.543415 -103.221345) (xy 332.572881 -103.175495) (xy 332.608572 -103.134304) (xy 332.649763 -103.098613)
			(xy 332.695613 -103.069147) (xy 332.74519 -103.046505) (xy 332.797485 -103.03115) (xy 332.851433 -103.023394)
			(xy 332.905935 -103.023394) (xy 332.959883 -103.03115) (xy 333.012178 -103.046505) (xy 333.061755 -103.069147)
			(xy 333.107605 -103.098613) (xy 333.148796 -103.134304) (xy 333.184487 -103.175495) (xy 333.213953 -103.221345)
			(xy 333.236595 -103.270922) (xy 333.25195 -103.323217) (xy 333.259706 -103.377165) (xy 333.260192 -103.404416)
			(xy 333.259738 -103.43073) (xy 333.252501 -103.48286) (xy 333.238179 -103.533503) (xy 333.217044 -103.581702)
			(xy 333.189496 -103.626545) (xy 333.156055 -103.667184) (xy 333.137002 -103.68534) (xy 333.129581 -103.692845)
			(xy 333.121068 -103.712138) (xy 333.120624 -103.720256) (xy 335.772915 -103.720256) (xy 335.772915 -103.665744)
			(xy 335.780673 -103.611786) (xy 335.796032 -103.559481) (xy 335.818677 -103.509895) (xy 335.84815 -103.464036)
			(xy 335.883849 -103.422839) (xy 335.925048 -103.387141) (xy 335.970907 -103.357671) (xy 336.020494 -103.335027)
			(xy 336.072799 -103.31967) (xy 336.126758 -103.311914) (xy 336.154014 -103.311452) (xy 336.181385 -103.311897)
			(xy 336.235566 -103.319718) (xy 336.288069 -103.335211) (xy 336.337816 -103.358058) (xy 336.383781 -103.387788)
			(xy 336.404712 -103.405432) (xy 336.404966 -103.405686) (xy 336.412059 -103.411263) (xy 336.428971 -103.417516)
			(xy 336.437986 -103.417878) (xy 336.505042 -103.417878) (xy 336.514057 -103.417498) (xy 336.530974 -103.411267)
			(xy 336.538062 -103.405686) (xy 336.538062 -103.405432) (xy 336.538316 -103.405432) (xy 336.559249 -103.387791)
			(xy 336.605217 -103.358067) (xy 336.654963 -103.335221) (xy 336.707465 -103.319725) (xy 336.761643 -103.311896)
			(xy 336.816385 -103.311896) (xy 336.870563 -103.319725) (xy 336.923065 -103.335221) (xy 336.972811 -103.358067)
			(xy 337.018779 -103.387791) (xy 337.039712 -103.405432) (xy 337.039966 -103.405686) (xy 337.047059 -103.411263)
			(xy 337.063971 -103.417516) (xy 337.072986 -103.417878) (xy 337.140042 -103.417878) (xy 337.149057 -103.417498)
			(xy 337.165974 -103.411267) (xy 337.173062 -103.405686) (xy 337.173062 -103.405432) (xy 337.173316 -103.405432)
			(xy 337.194273 -103.387824) (xy 337.240238 -103.358106) (xy 337.28998 -103.335264) (xy 337.342475 -103.319766)
			(xy 337.396646 -103.31193) (xy 337.424014 -103.311452) (xy 337.451262 -103.312019) (xy 337.505202 -103.319776)
			(xy 337.55749 -103.335131) (xy 337.60706 -103.357771) (xy 337.652904 -103.387234) (xy 337.694088 -103.422922)
			(xy 337.729774 -103.464107) (xy 337.759236 -103.509952) (xy 337.781874 -103.559523) (xy 337.797227 -103.611811)
			(xy 337.804982 -103.665752) (xy 337.804982 -103.685654) (xy 340.692671 -103.685654) (xy 340.692671 -103.631146)
			(xy 340.700429 -103.577194) (xy 340.715787 -103.524895) (xy 340.738431 -103.475315) (xy 340.767901 -103.429462)
			(xy 340.803598 -103.38827) (xy 340.844794 -103.352577) (xy 340.89065 -103.323112) (xy 340.940233 -103.300473)
			(xy 340.992533 -103.285121) (xy 341.046486 -103.277369) (xy 341.07374 -103.276908) (xy 341.100055 -103.277346)
			(xy 341.152185 -103.284587) (xy 341.202828 -103.298911) (xy 341.251027 -103.320049) (xy 341.29587 -103.347601)
			(xy 341.336508 -103.381044) (xy 341.354664 -103.400098) (xy 341.362197 -103.407485) (xy 341.381469 -103.416018)
			(xy 341.392002 -103.416608) (xy 341.466678 -103.416608) (xy 341.477227 -103.416078) (xy 341.496523 -103.407543)
			(xy 341.504016 -103.400098) (xy 341.523836 -103.37931) (xy 341.568608 -103.343335) (xy 341.618266 -103.314475)
			(xy 341.671688 -103.293382) (xy 341.727667 -103.280533) (xy 341.78494 -103.276218) (xy 341.842213 -103.280533)
			(xy 341.898192 -103.293382) (xy 341.951614 -103.314475) (xy 342.001272 -103.343335) (xy 342.046044 -103.37931)
			(xy 342.065864 -103.400098) (xy 342.073397 -103.407485) (xy 342.092669 -103.416018) (xy 342.103202 -103.416608)
			(xy 342.177878 -103.416608) (xy 342.188427 -103.416078) (xy 342.207723 -103.407543) (xy 342.215216 -103.400098)
			(xy 342.23337 -103.381041) (xy 342.274 -103.347584) (xy 342.318841 -103.320026) (xy 342.367042 -103.298887)
			(xy 342.41769 -103.28457) (xy 342.469824 -103.277346) (xy 342.49614 -103.276908) (xy 342.523391 -103.277365)
			(xy 342.577336 -103.285126) (xy 342.629628 -103.300485) (xy 342.679203 -103.32313) (xy 342.72505 -103.352598)
			(xy 342.766237 -103.388291) (xy 342.801926 -103.429482) (xy 342.83139 -103.475333) (xy 342.854029 -103.524909)
			(xy 342.869383 -103.577203) (xy 342.877138 -103.631149) (xy 342.877138 -103.685651) (xy 342.869383 -103.739597)
			(xy 342.859942 -103.771753) (xy 352.499877 -103.771753) (xy 352.499877 -103.717247) (xy 352.507635 -103.663297)
			(xy 352.522991 -103.611) (xy 352.545635 -103.56142) (xy 352.575104 -103.515568) (xy 352.610799 -103.474377)
			(xy 352.651993 -103.438686) (xy 352.697847 -103.40922) (xy 352.747428 -103.386581) (xy 352.799726 -103.371228)
			(xy 352.853677 -103.363475) (xy 352.88093 -103.363014) (xy 352.909889 -103.363609) (xy 352.967141 -103.372376)
			(xy 353.022411 -103.389688) (xy 353.068071 -103.412036) (xy 359.492802 -103.412036) (xy 359.496873 -103.356414)
			(xy 359.508999 -103.301977) (xy 359.528922 -103.249886) (xy 359.556218 -103.201251) (xy 359.590304 -103.157108)
			(xy 359.630453 -103.118399) (xy 359.675811 -103.085948) (xy 359.725411 -103.060447) (xy 359.778195 -103.04244)
			(xy 359.833038 -103.03231) (xy 359.888772 -103.030273) (xy 359.944209 -103.036373) (xy 359.998166 -103.050479)
			(xy 360.049495 -103.072291) (xy 360.097101 -103.101345) (xy 360.139969 -103.13702) (xy 360.177186 -103.178557)
			(xy 360.207959 -103.22507) (xy 360.231631 -103.275567) (xy 360.247699 -103.328974) (xy 360.255819 -103.38415)
			(xy 360.256328 -103.412036) (xy 360.255819 -103.439922) (xy 360.247699 -103.495098) (xy 360.231631 -103.548505)
			(xy 360.207959 -103.599002) (xy 360.177186 -103.645515) (xy 360.139969 -103.687052) (xy 360.097101 -103.722727)
			(xy 360.049495 -103.751781) (xy 359.998166 -103.773593) (xy 359.944209 -103.787699) (xy 359.888772 -103.793799)
			(xy 359.833038 -103.791762) (xy 359.778195 -103.781632) (xy 359.725411 -103.763625) (xy 359.675811 -103.738124)
			(xy 359.630453 -103.705673) (xy 359.590304 -103.666964) (xy 359.556218 -103.622821) (xy 359.528922 -103.574186)
			(xy 359.508999 -103.522095) (xy 359.496873 -103.467658) (xy 359.492802 -103.412036) (xy 353.068071 -103.412036)
			(xy 353.074433 -103.41515) (xy 353.122013 -103.448176) (xy 353.16406 -103.488009) (xy 353.199608 -103.533735)
			(xy 353.227842 -103.584306) (xy 353.248116 -103.638561) (xy 353.254564 -103.666798) (xy 353.256596 -103.677212)
			(xy 353.26828 -103.693976) (xy 353.3394 -103.73868) (xy 353.348382 -103.743691) (xy 353.368692 -103.746834)
			(xy 353.37877 -103.744776) (xy 353.401751 -103.739316) (xy 353.448624 -103.733461) (xy 353.472242 -103.733092)
			(xy 353.499491 -103.733581) (xy 353.553434 -103.741342) (xy 353.605724 -103.756701) (xy 353.655296 -103.779344)
			(xy 353.701141 -103.808812) (xy 353.742326 -103.844503) (xy 353.778013 -103.885692) (xy 353.807476 -103.931541)
			(xy 353.830114 -103.981115) (xy 353.845467 -104.033407) (xy 353.853222 -104.087351) (xy 353.853222 -104.141849)
			(xy 353.845467 -104.195793) (xy 353.830114 -104.248085) (xy 353.807476 -104.297659) (xy 353.778013 -104.343508)
			(xy 353.742326 -104.384697) (xy 353.721919 -104.402382) (xy 357.210358 -104.402382) (xy 357.214429 -104.34676)
			(xy 357.226555 -104.292323) (xy 357.246478 -104.240232) (xy 357.273774 -104.191597) (xy 357.30786 -104.147454)
			(xy 357.348009 -104.108745) (xy 357.393367 -104.076294) (xy 357.442967 -104.050793) (xy 357.495751 -104.032786)
			(xy 357.550594 -104.022656) (xy 357.606328 -104.020619) (xy 357.661765 -104.026719) (xy 357.715722 -104.040825)
			(xy 357.767051 -104.062637) (xy 357.814657 -104.091691) (xy 357.857525 -104.127366) (xy 357.894742 -104.168903)
			(xy 357.925515 -104.215416) (xy 357.949187 -104.265913) (xy 357.965255 -104.31932) (xy 357.973375 -104.374496)
			(xy 357.973884 -104.402382) (xy 357.973375 -104.430268) (xy 357.965255 -104.485444) (xy 357.949187 -104.538851)
			(xy 357.925515 -104.589348) (xy 357.894742 -104.635861) (xy 357.857525 -104.677398) (xy 357.814657 -104.713073)
			(xy 357.767051 -104.742127) (xy 357.715722 -104.763939) (xy 357.661765 -104.778045) (xy 357.606328 -104.784145)
			(xy 357.550594 -104.782108) (xy 357.495751 -104.771978) (xy 357.442967 -104.753971) (xy 357.393367 -104.72847)
			(xy 357.348009 -104.696019) (xy 357.30786 -104.65731) (xy 357.273774 -104.613167) (xy 357.246478 -104.564532)
			(xy 357.226555 -104.512441) (xy 357.214429 -104.458004) (xy 357.210358 -104.402382) (xy 353.721919 -104.402382)
			(xy 353.701141 -104.420388) (xy 353.655296 -104.449856) (xy 353.605724 -104.472499) (xy 353.553434 -104.487858)
			(xy 353.499491 -104.495619) (xy 353.472242 -104.496108) (xy 353.443279 -104.4956) (xy 353.386021 -104.486827)
			(xy 353.330745 -104.469506) (xy 353.278719 -104.444035) (xy 353.231137 -104.410998) (xy 353.189091 -104.371153)
			(xy 353.153546 -104.325415) (xy 353.125316 -104.274832) (xy 353.105051 -104.220567) (xy 353.098608 -104.192324)
			(xy 353.096576 -104.18191) (xy 353.084892 -104.165146) (xy 353.013772 -104.120442) (xy 353.004796 -104.115417)
			(xy 352.984481 -104.112282) (xy 352.974402 -104.114346) (xy 352.951418 -104.119793) (xy 352.904548 -104.125657)
			(xy 352.88093 -104.12603) (xy 352.853677 -104.125525) (xy 352.799726 -104.117772) (xy 352.747428 -104.102419)
			(xy 352.697847 -104.07978) (xy 352.651993 -104.050314) (xy 352.610799 -104.014623) (xy 352.575104 -103.973432)
			(xy 352.545635 -103.92758) (xy 352.522991 -103.878) (xy 352.507635 -103.825703) (xy 352.499877 -103.771753)
			(xy 342.859942 -103.771753) (xy 342.854029 -103.791891) (xy 342.83139 -103.841467) (xy 342.801926 -103.887318)
			(xy 342.766237 -103.928509) (xy 342.72505 -103.964202) (xy 342.679203 -103.99367) (xy 342.629628 -104.016315)
			(xy 342.577336 -104.031674) (xy 342.523391 -104.039435) (xy 342.49614 -104.039924) (xy 342.469825 -104.039489)
			(xy 342.417695 -104.032246) (xy 342.367052 -104.01792) (xy 342.318854 -103.996782) (xy 342.274011 -103.969231)
			(xy 342.233372 -103.935787) (xy 342.215216 -103.916734) (xy 342.207686 -103.909342) (xy 342.188413 -103.900811)
			(xy 342.177878 -103.900224) (xy 342.103202 -103.900224) (xy 342.09265 -103.900734) (xy 342.073354 -103.909282)
			(xy 342.065864 -103.916734) (xy 342.046044 -103.937522) (xy 342.001272 -103.973497) (xy 341.951614 -104.002357)
			(xy 341.898192 -104.02345) (xy 341.842213 -104.036299) (xy 341.78494 -104.040614) (xy 341.727667 -104.036299)
			(xy 341.671688 -104.02345) (xy 341.618266 -104.002357) (xy 341.568608 -103.973497) (xy 341.523836 -103.937522)
			(xy 341.504016 -103.916734) (xy 341.496486 -103.909342) (xy 341.477213 -103.900811) (xy 341.466678 -103.900224)
			(xy 341.392002 -103.900224) (xy 341.38145 -103.900734) (xy 341.362154 -103.909282) (xy 341.354664 -103.916734)
			(xy 341.336526 -103.935806) (xy 341.295891 -103.969261) (xy 341.251047 -103.996817) (xy 341.202843 -104.017952)
			(xy 341.152193 -104.032266) (xy 341.100057 -104.039487) (xy 341.07374 -104.039924) (xy 341.046486 -104.039431)
			(xy 340.992533 -104.031679) (xy 340.940233 -104.016327) (xy 340.89065 -103.993688) (xy 340.844794 -103.964223)
			(xy 340.803598 -103.92853) (xy 340.767901 -103.887338) (xy 340.738431 -103.841485) (xy 340.715787 -103.791905)
			(xy 340.700429 -103.739606) (xy 340.692671 -103.685654) (xy 337.804982 -103.685654) (xy 337.804982 -103.720248)
			(xy 337.797227 -103.774189) (xy 337.781874 -103.826477) (xy 337.759236 -103.876048) (xy 337.729774 -103.921893)
			(xy 337.694088 -103.963078) (xy 337.652904 -103.998766) (xy 337.60706 -104.028229) (xy 337.55749 -104.050869)
			(xy 337.505202 -104.066224) (xy 337.451262 -104.073981) (xy 337.424014 -104.074468) (xy 337.396644 -104.074002)
			(xy 337.342464 -104.066185) (xy 337.289961 -104.050696) (xy 337.240214 -104.027855) (xy 337.194247 -103.99813)
			(xy 337.173316 -103.980488) (xy 337.173062 -103.980234) (xy 337.165968 -103.974659) (xy 337.149057 -103.968407)
			(xy 337.140042 -103.968042) (xy 337.072986 -103.968042) (xy 337.063967 -103.968383) (xy 337.04705 -103.974641)
			(xy 337.039966 -103.980234) (xy 337.039712 -103.980488) (xy 337.018779 -103.998129) (xy 336.972811 -104.027853)
			(xy 336.923065 -104.050699) (xy 336.870563 -104.066195) (xy 336.816385 -104.074024) (xy 336.761643 -104.074024)
			(xy 336.707465 -104.066195) (xy 336.654963 -104.050699) (xy 336.605217 -104.027853) (xy 336.559249 -103.998129)
			(xy 336.538316 -103.980488) (xy 336.538062 -103.980234) (xy 336.530968 -103.974659) (xy 336.514057 -103.968407)
			(xy 336.505042 -103.968042) (xy 336.437986 -103.968042) (xy 336.428967 -103.968383) (xy 336.41205 -103.974641)
			(xy 336.404966 -103.980234) (xy 336.404966 -103.980488) (xy 336.404712 -103.980488) (xy 336.383785 -103.998133)
			(xy 336.337811 -104.027844) (xy 336.288062 -104.050679) (xy 336.23556 -104.066169) (xy 336.181384 -104.073995)
			(xy 336.154014 -104.074468) (xy 336.126758 -104.074086) (xy 336.072799 -104.06633) (xy 336.020494 -104.050973)
			(xy 335.970907 -104.028329) (xy 335.925048 -103.998859) (xy 335.883849 -103.963161) (xy 335.84815 -103.921964)
			(xy 335.818677 -103.876105) (xy 335.796032 -103.826519) (xy 335.780673 -103.774214) (xy 335.772915 -103.720256)
			(xy 333.120624 -103.720256) (xy 333.120492 -103.722678) (xy 333.120492 -103.797354) (xy 333.121035 -103.807902)
			(xy 333.129561 -103.827197) (xy 333.137002 -103.834692) (xy 333.156047 -103.852858) (xy 333.189505 -103.893486)
			(xy 333.217065 -103.938324) (xy 333.238206 -103.986522) (xy 333.252525 -104.037168) (xy 333.259752 -104.0893)
			(xy 333.260192 -104.115616) (xy 333.259706 -104.142867) (xy 333.25195 -104.196815) (xy 333.236595 -104.24911)
			(xy 333.213953 -104.298687) (xy 333.184487 -104.344537) (xy 333.148796 -104.385728) (xy 333.107605 -104.421419)
			(xy 333.061755 -104.450885) (xy 333.012178 -104.473527) (xy 332.959883 -104.488882) (xy 332.905935 -104.496638)
			(xy 332.851433 -104.496638) (xy 332.797485 -104.488882) (xy 332.74519 -104.473527) (xy 332.695613 -104.450885)
			(xy 332.649763 -104.421419) (xy 332.608572 -104.385728) (xy 332.572881 -104.344537) (xy 332.543415 -104.298687)
			(xy 332.520773 -104.24911) (xy 332.505418 -104.196815) (xy 332.497662 -104.142867) (xy 332.497176 -104.115616)
			(xy 329.57929 -104.115616) (xy 329.567315 -104.1564) (xy 329.544673 -104.205977) (xy 329.515206 -104.251828)
			(xy 329.479514 -104.293018) (xy 329.438323 -104.328709) (xy 329.392472 -104.358176) (xy 329.342895 -104.380817)
			(xy 329.290599 -104.396172) (xy 329.236651 -104.403928) (xy 329.2094 -104.404414) (xy 329.180481 -104.403928)
			(xy 329.123307 -104.395197) (xy 329.068106 -104.377935) (xy 329.016144 -104.352537) (xy 328.968611 -104.319586)
			(xy 328.926598 -104.279837) (xy 328.90841 -104.257348) (xy 328.900798 -104.248546) (xy 328.879901 -104.238362)
			(xy 328.868278 -104.23779) (xy 328.788522 -104.23779) (xy 328.776894 -104.23836) (xy 328.755985 -104.248527)
			(xy 328.74839 -104.257348) (xy 328.730217 -104.279846) (xy 328.688192 -104.319578) (xy 328.640653 -104.352514)
			(xy 328.588688 -104.3779) (xy 328.533488 -104.395153) (xy 328.476317 -104.40388) (xy 328.4474 -104.404414)
			(xy 328.420149 -104.403922) (xy 328.366202 -104.396166) (xy 328.313908 -104.380811) (xy 328.264331 -104.35817)
			(xy 328.218481 -104.328705) (xy 328.177291 -104.293014) (xy 328.141599 -104.251824) (xy 328.112133 -104.205975)
			(xy 328.089491 -104.156398) (xy 328.074135 -104.104104) (xy 328.066378 -104.050157) (xy 328.065892 -104.022906)
			(xy 326.178942 -104.022906) (xy 326.177851 -104.026533) (xy 326.154179 -104.07703) (xy 326.123406 -104.123543)
			(xy 326.086189 -104.16508) (xy 326.043321 -104.200755) (xy 325.995715 -104.229809) (xy 325.944386 -104.251621)
			(xy 325.890429 -104.265727) (xy 325.834992 -104.271827) (xy 325.779258 -104.26979) (xy 325.724415 -104.25966)
			(xy 325.671631 -104.241653) (xy 325.622031 -104.216152) (xy 325.576673 -104.183701) (xy 325.536524 -104.144992)
			(xy 325.502438 -104.100849) (xy 325.475142 -104.052214) (xy 325.455219 -104.000123) (xy 325.443093 -103.945686)
			(xy 325.439022 -103.890064) (xy 325.17733 -103.890064) (xy 325.177404 -103.894128) (xy 325.176895 -103.922014)
			(xy 325.168775 -103.97719) (xy 325.152707 -104.030597) (xy 325.129035 -104.081094) (xy 325.098262 -104.127607)
			(xy 325.061045 -104.169144) (xy 325.018177 -104.204819) (xy 324.970571 -104.233873) (xy 324.919242 -104.255685)
			(xy 324.865285 -104.269791) (xy 324.809848 -104.275891) (xy 324.754114 -104.273854) (xy 324.699271 -104.263724)
			(xy 324.646487 -104.245717) (xy 324.596887 -104.220216) (xy 324.551529 -104.187765) (xy 324.51138 -104.149056)
			(xy 324.477294 -104.104913) (xy 324.449998 -104.056278) (xy 324.430075 -104.004187) (xy 324.417949 -103.94975)
			(xy 324.413878 -103.894128) (xy 323.400409 -103.894128) (xy 323.399622 -103.896662) (xy 323.374531 -103.948374)
			(xy 323.341966 -103.995737) (xy 323.322696 -104.017064) (xy 323.316092 -104.023922) (xy 323.30898 -104.041956)
			(xy 323.30898 -104.130856) (xy 323.316092 -104.14889) (xy 323.322696 -104.155748) (xy 323.341972 -104.17707)
			(xy 323.374535 -104.224434) (xy 323.399625 -104.276147) (xy 323.416674 -104.331038) (xy 323.425295 -104.387865)
			(xy 323.425295 -104.445343) (xy 323.416672 -104.502171) (xy 323.399622 -104.557062) (xy 323.374531 -104.608774)
			(xy 323.341966 -104.656137) (xy 323.322696 -104.677464) (xy 323.316092 -104.684322) (xy 323.30898 -104.702356)
			(xy 323.30898 -104.791256) (xy 323.316092 -104.80929) (xy 323.322696 -104.816148) (xy 323.341972 -104.83747)
			(xy 323.374535 -104.884834) (xy 323.399625 -104.936547) (xy 323.416674 -104.991438) (xy 323.425295 -105.048265)
			(xy 323.425295 -105.08445) (xy 327.943972 -105.08445) (xy 327.943972 -105.02995) (xy 327.951728 -104.976003)
			(xy 327.967082 -104.92371) (xy 327.989721 -104.874134) (xy 328.019185 -104.828284) (xy 328.054874 -104.787094)
			(xy 328.096062 -104.751402) (xy 328.141909 -104.721934) (xy 328.191484 -104.699291) (xy 328.243776 -104.683934)
			(xy 328.297722 -104.676174) (xy 328.324972 -104.675686) (xy 328.352341 -104.676172) (xy 328.40652 -104.683985)
			(xy 328.459022 -104.69947) (xy 328.50877 -104.722307) (xy 328.554737 -104.752027) (xy 328.57567 -104.769666)
			(xy 328.575924 -104.76992) (xy 328.582998 -104.775525) (xy 328.599924 -104.78176) (xy 328.608944 -104.782112)
			(xy 328.676 -104.782112) (xy 328.685017 -104.781752) (xy 328.701933 -104.775506) (xy 328.70902 -104.76992)
			(xy 328.70902 -104.769666) (xy 328.709274 -104.769666) (xy 328.730207 -104.752025) (xy 328.776175 -104.722301)
			(xy 328.825921 -104.699455) (xy 328.878423 -104.683959) (xy 328.932601 -104.67613) (xy 328.987343 -104.67613)
			(xy 329.041521 -104.683959) (xy 329.094023 -104.699455) (xy 329.143769 -104.722301) (xy 329.189737 -104.752025)
			(xy 329.21067 -104.769666) (xy 329.210924 -104.76992) (xy 329.217998 -104.775525) (xy 329.234924 -104.78176)
			(xy 329.243944 -104.782112) (xy 329.311 -104.782112) (xy 329.320017 -104.781752) (xy 329.336933 -104.775506)
			(xy 329.34402 -104.76992) (xy 329.34402 -104.769666) (xy 329.344274 -104.769666) (xy 329.365207 -104.752025)
			(xy 329.411175 -104.722301) (xy 329.460921 -104.699455) (xy 329.513423 -104.683959) (xy 329.567601 -104.67613)
			(xy 329.622343 -104.67613) (xy 329.676521 -104.683959) (xy 329.729023 -104.699455) (xy 329.778769 -104.722301)
			(xy 329.824737 -104.752025) (xy 329.84567 -104.769666) (xy 329.845924 -104.76992) (xy 329.852998 -104.775525)
			(xy 329.869924 -104.78176) (xy 329.878944 -104.782112) (xy 329.946 -104.782112) (xy 329.955017 -104.781752)
			(xy 329.971933 -104.775506) (xy 329.97902 -104.76992) (xy 329.97902 -104.769666) (xy 329.979274 -104.769666)
			(xy 330.000201 -104.75202) (xy 330.046176 -104.722311) (xy 330.095924 -104.699477) (xy 330.148426 -104.683987)
			(xy 330.202603 -104.67616) (xy 330.229972 -104.675686) (xy 330.257226 -104.676159) (xy 330.311179 -104.683913)
			(xy 330.363479 -104.699266) (xy 330.413062 -104.721907) (xy 330.458918 -104.751374) (xy 330.500113 -104.787067)
			(xy 330.535809 -104.82826) (xy 330.56528 -104.874113) (xy 330.587924 -104.923695) (xy 330.603281 -104.975994)
			(xy 330.611039 -105.029946) (xy 330.611039 -105.08445) (xy 331.867772 -105.08445) (xy 331.867772 -105.02995)
			(xy 331.875527 -104.976005) (xy 331.890881 -104.923712) (xy 331.91352 -104.874136) (xy 331.942983 -104.828287)
			(xy 331.978671 -104.787097) (xy 332.019858 -104.751405) (xy 332.065705 -104.721937) (xy 332.115278 -104.699294)
			(xy 332.167569 -104.683935) (xy 332.221514 -104.676174) (xy 332.248764 -104.675686) (xy 332.275079 -104.676115)
			(xy 332.327209 -104.683359) (xy 332.377852 -104.697685) (xy 332.426051 -104.718825) (xy 332.470894 -104.746378)
			(xy 332.511532 -104.779822) (xy 332.529688 -104.798876) (xy 332.537215 -104.806271) (xy 332.556491 -104.8148)
			(xy 332.567026 -104.815386) (xy 332.641702 -104.815386) (xy 332.652254 -104.814875) (xy 332.671549 -104.806328)
			(xy 332.67904 -104.798876) (xy 332.697178 -104.779803) (xy 332.737812 -104.746349) (xy 332.782656 -104.718793)
			(xy 332.83086 -104.697657) (xy 332.881511 -104.683343) (xy 332.933647 -104.676123) (xy 332.959964 -104.675686)
			(xy 332.987333 -104.676177) (xy 333.041511 -104.683989) (xy 333.094014 -104.699473) (xy 333.143761 -104.722309)
			(xy 333.189729 -104.752028) (xy 333.210662 -104.769666) (xy 333.210916 -104.76992) (xy 333.217992 -104.775522)
			(xy 333.234917 -104.781759) (xy 333.243936 -104.782112) (xy 333.310992 -104.782112) (xy 333.320008 -104.781749)
			(xy 333.336925 -104.775505) (xy 333.344012 -104.76992) (xy 333.344012 -104.769666) (xy 333.344266 -104.769666)
			(xy 333.365199 -104.752025) (xy 333.411167 -104.722301) (xy 333.460913 -104.699455) (xy 333.513415 -104.683959)
			(xy 333.567593 -104.67613) (xy 333.622335 -104.67613) (xy 333.676513 -104.683959) (xy 333.729015 -104.699455)
			(xy 333.778761 -104.722301) (xy 333.824729 -104.752025) (xy 333.845662 -104.769666) (xy 333.845916 -104.76992)
			(xy 333.852992 -104.775522) (xy 333.869917 -104.781759) (xy 333.878936 -104.782112) (xy 333.945992 -104.782112)
			(xy 333.955008 -104.781749) (xy 333.971925 -104.775505) (xy 333.979012 -104.76992) (xy 333.979012 -104.769666)
			(xy 333.979266 -104.769666) (xy 334.000196 -104.752024) (xy 334.04617 -104.722314) (xy 334.095918 -104.699479)
			(xy 334.148419 -104.683988) (xy 334.202595 -104.67616) (xy 334.229964 -104.675686) (xy 334.257218 -104.676159)
			(xy 334.311172 -104.683912) (xy 334.363473 -104.699264) (xy 334.413057 -104.721904) (xy 334.458914 -104.751371)
			(xy 334.500111 -104.787064) (xy 334.535808 -104.828257) (xy 334.565278 -104.874111) (xy 334.587923 -104.923693)
			(xy 334.603281 -104.975993) (xy 334.611039 -105.029946) (xy 334.611039 -105.084454) (xy 334.603281 -105.138407)
			(xy 334.587923 -105.190707) (xy 334.583705 -105.199942) (xy 351.867978 -105.199942) (xy 351.868464 -105.172691)
			(xy 351.87622 -105.118743) (xy 351.891575 -105.066448) (xy 351.914217 -105.016871) (xy 351.943683 -104.971021)
			(xy 351.979374 -104.92983) (xy 352.020565 -104.894139) (xy 352.066415 -104.864673) (xy 352.115992 -104.842031)
			(xy 352.168287 -104.826676) (xy 352.222235 -104.81892) (xy 352.276737 -104.81892) (xy 352.330685 -104.826676)
			(xy 352.38298 -104.842031) (xy 352.432557 -104.864673) (xy 352.478407 -104.894139) (xy 352.519598 -104.92983)
			(xy 352.555289 -104.971021) (xy 352.584755 -105.016871) (xy 352.607397 -105.066448) (xy 352.622752 -105.118743)
			(xy 352.630508 -105.172691) (xy 352.630994 -105.199942) (xy 352.630509 -105.227847) (xy 352.622361 -105.283059)
			(xy 352.606261 -105.336496) (xy 352.58255 -105.387019) (xy 352.551736 -105.433551) (xy 352.514474 -105.475099)
			(xy 352.493326 -105.493312) (xy 352.484155 -105.501843) (xy 352.47469 -105.524999) (xy 352.475292 -105.537508)
			(xy 352.48469 -105.634028) (xy 352.49866 -105.654856) (xy 352.51009 -105.660952) (xy 352.533868 -105.674278)
			(xy 352.577748 -105.706615) (xy 352.616582 -105.744864) (xy 352.649581 -105.788246) (xy 352.663252 -105.811828)
			(xy 352.669908 -105.822454) (xy 352.69096 -105.836029) (xy 352.703384 -105.837736) (xy 352.800158 -105.845864)
			(xy 352.823272 -105.835958) (xy 352.831146 -105.826052) (xy 352.849353 -105.804165) (xy 352.891198 -105.765563)
			(xy 352.93831 -105.733602) (xy 352.989647 -105.708991) (xy 353.044068 -105.692276) (xy 353.100369 -105.683827)
			(xy 353.128834 -105.683304) (xy 353.156085 -105.683768) (xy 353.21003 -105.691529) (xy 353.262323 -105.706887)
			(xy 353.311897 -105.729531) (xy 353.357745 -105.758999) (xy 353.398932 -105.794692) (xy 353.434621 -105.835883)
			(xy 353.464085 -105.881733) (xy 353.486725 -105.931309) (xy 353.502078 -105.983603) (xy 353.509834 -106.037549)
			(xy 353.509834 -106.092051) (xy 353.502078 -106.145997) (xy 353.486725 -106.198291) (xy 353.464085 -106.247867)
			(xy 353.434621 -106.293717) (xy 353.398932 -106.334908) (xy 353.357745 -106.370601) (xy 353.311897 -106.400069)
			(xy 353.262323 -106.422713) (xy 353.21003 -106.438071) (xy 353.156085 -106.445832) (xy 353.128834 -106.44632)
			(xy 353.099842 -106.445776) (xy 353.042527 -106.436985) (xy 352.9872 -106.419633) (xy 352.935132 -106.394116)
			(xy 352.887519 -106.361021) (xy 352.845456 -106.32111) (xy 352.809909 -106.275299) (xy 352.795332 -106.250232)
			(xy 352.788694 -106.239592) (xy 352.767628 -106.226026) (xy 352.7552 -106.224324) (xy 352.658426 -106.216196)
			(xy 352.635312 -106.226102) (xy 352.627438 -106.236008) (xy 352.609175 -106.257846) (xy 352.567343 -106.296453)
			(xy 352.520242 -106.328421) (xy 352.468917 -106.353041) (xy 352.414505 -106.369766) (xy 352.358212 -106.378226)
			(xy 352.32975 -106.378756) (xy 352.302501 -106.378198) (xy 352.248556 -106.370449) (xy 352.196262 -106.355102)
			(xy 352.146686 -106.332469) (xy 352.100835 -106.303011) (xy 352.059643 -106.267327) (xy 352.023948 -106.226144)
			(xy 351.994478 -106.180301) (xy 351.971832 -106.13073) (xy 351.956471 -106.07844) (xy 351.948709 -106.024497)
			(xy 351.948242 -105.997248) (xy 351.948707 -105.969342) (xy 351.956857 -105.914129) (xy 351.972961 -105.860691)
			(xy 351.996675 -105.810168) (xy 352.027494 -105.763636) (xy 352.06476 -105.722089) (xy 352.08591 -105.703878)
			(xy 352.095092 -105.695357) (xy 352.104549 -105.672193) (xy 352.103944 -105.659682) (xy 352.094546 -105.563162)
			(xy 352.080576 -105.542334) (xy 352.069146 -105.536238) (xy 352.043478 -105.521869) (xy 351.996529 -105.486428)
			(xy 351.955575 -105.444203) (xy 351.921585 -105.396194) (xy 351.895364 -105.343538) (xy 351.877534 -105.287482)
			(xy 351.868517 -105.229354) (xy 351.867978 -105.199942) (xy 334.583705 -105.199942) (xy 334.565278 -105.240289)
			(xy 334.535808 -105.286143) (xy 334.500111 -105.327336) (xy 334.458914 -105.363029) (xy 334.413057 -105.392496)
			(xy 334.363473 -105.415136) (xy 334.311172 -105.430488) (xy 334.257218 -105.438241) (xy 334.229964 -105.438702)
			(xy 334.202593 -105.438257) (xy 334.148413 -105.430434) (xy 334.09591 -105.41494) (xy 334.046163 -105.392093)
			(xy 334.000197 -105.362365) (xy 333.979266 -105.344722) (xy 333.979012 -105.344468) (xy 333.971929 -105.338877)
			(xy 333.955009 -105.332634) (xy 333.945992 -105.332276) (xy 333.878936 -105.332276) (xy 333.869922 -105.332655)
			(xy 333.853005 -105.338888) (xy 333.845916 -105.344468) (xy 333.845662 -105.344722) (xy 333.824729 -105.362363)
			(xy 333.778761 -105.392087) (xy 333.729015 -105.414933) (xy 333.676513 -105.430429) (xy 333.622335 -105.438258)
			(xy 333.567593 -105.438258) (xy 333.513415 -105.430429) (xy 333.460913 -105.414933) (xy 333.411167 -105.392087)
			(xy 333.365199 -105.362363) (xy 333.344266 -105.344722) (xy 333.344012 -105.344468) (xy 333.336929 -105.338877)
			(xy 333.320009 -105.332634) (xy 333.310992 -105.332276) (xy 333.243936 -105.332276) (xy 333.234922 -105.332655)
			(xy 333.218005 -105.338888) (xy 333.210916 -105.344468) (xy 333.210916 -105.344722) (xy 333.210662 -105.344722)
			(xy 333.18972 -105.362349) (xy 333.14375 -105.392062) (xy 333.094005 -105.4149) (xy 333.041506 -105.430394)
			(xy 332.987332 -105.438226) (xy 332.959964 -105.438702) (xy 332.933649 -105.438258) (xy 332.88152 -105.431018)
			(xy 332.830877 -105.416694) (xy 332.782678 -105.395558) (xy 332.737835 -105.368008) (xy 332.697196 -105.334565)
			(xy 332.67904 -105.315512) (xy 332.671504 -105.308128) (xy 332.652235 -105.299593) (xy 332.641702 -105.299002)
			(xy 332.567026 -105.299002) (xy 332.556476 -105.299531) (xy 332.537181 -105.308066) (xy 332.529688 -105.315512)
			(xy 332.511534 -105.334569) (xy 332.470903 -105.368025) (xy 332.426063 -105.395584) (xy 332.377862 -105.416722)
			(xy 332.327214 -105.431039) (xy 332.27508 -105.438264) (xy 332.248764 -105.438702) (xy 332.221514 -105.438226)
			(xy 332.167569 -105.430465) (xy 332.115278 -105.415106) (xy 332.065705 -105.392463) (xy 332.019858 -105.362995)
			(xy 331.978671 -105.327303) (xy 331.942983 -105.286113) (xy 331.91352 -105.240264) (xy 331.890881 -105.190688)
			(xy 331.875527 -105.138395) (xy 331.867772 -105.08445) (xy 330.611039 -105.08445) (xy 330.611039 -105.084454)
			(xy 330.603281 -105.138406) (xy 330.587924 -105.190705) (xy 330.56528 -105.240287) (xy 330.535809 -105.28614)
			(xy 330.500113 -105.327333) (xy 330.458918 -105.363026) (xy 330.413062 -105.392493) (xy 330.363479 -105.415134)
			(xy 330.311179 -105.430487) (xy 330.257226 -105.438241) (xy 330.229972 -105.438702) (xy 330.202601 -105.438252)
			(xy 330.148421 -105.43043) (xy 330.095918 -105.414937) (xy 330.046172 -105.392092) (xy 330.000205 -105.362365)
			(xy 329.979274 -105.344722) (xy 329.97902 -105.344468) (xy 329.971935 -105.33888) (xy 329.955017 -105.332635)
			(xy 329.946 -105.332276) (xy 329.878944 -105.332276) (xy 329.86993 -105.332659) (xy 329.853013 -105.338889)
			(xy 329.845924 -105.344468) (xy 329.84567 -105.344722) (xy 329.824737 -105.362363) (xy 329.778769 -105.392087)
			(xy 329.729023 -105.414933) (xy 329.676521 -105.430429) (xy 329.622343 -105.438258) (xy 329.567601 -105.438258)
			(xy 329.513423 -105.430429) (xy 329.460921 -105.414933) (xy 329.411175 -105.392087) (xy 329.365207 -105.362363)
			(xy 329.344274 -105.344722) (xy 329.34402 -105.344468) (xy 329.336935 -105.33888) (xy 329.320017 -105.332635)
			(xy 329.311 -105.332276) (xy 329.243944 -105.332276) (xy 329.23493 -105.332659) (xy 329.218013 -105.338889)
			(xy 329.210924 -105.344468) (xy 329.210924 -105.344722) (xy 329.21067 -105.344722) (xy 329.189737 -105.362363)
			(xy 329.143769 -105.392087) (xy 329.094023 -105.414933) (xy 329.041521 -105.430429) (xy 328.987343 -105.438258)
			(xy 328.932601 -105.438258) (xy 328.878423 -105.430429) (xy 328.825921 -105.414933) (xy 328.776175 -105.392087)
			(xy 328.730207 -105.362363) (xy 328.709274 -105.344722) (xy 328.70902 -105.344468) (xy 328.701935 -105.33888)
			(xy 328.685017 -105.332635) (xy 328.676 -105.332276) (xy 328.608944 -105.332276) (xy 328.59993 -105.332659)
			(xy 328.583013 -105.338889) (xy 328.575924 -105.344468) (xy 328.575924 -105.344722) (xy 328.57567 -105.344722)
			(xy 328.554725 -105.362345) (xy 328.508756 -105.392059) (xy 328.459011 -105.414897) (xy 328.406514 -105.430392)
			(xy 328.35234 -105.438225) (xy 328.324972 -105.438702) (xy 328.297722 -105.438226) (xy 328.243776 -105.430466)
			(xy 328.191484 -105.415109) (xy 328.141909 -105.392466) (xy 328.096062 -105.362998) (xy 328.054874 -105.327306)
			(xy 328.019185 -105.286116) (xy 327.989721 -105.240266) (xy 327.967082 -105.19069) (xy 327.951728 -105.138397)
			(xy 327.943972 -105.08445) (xy 323.425295 -105.08445) (xy 323.425295 -105.105743) (xy 323.416672 -105.162571)
			(xy 323.399622 -105.217462) (xy 323.374531 -105.269174) (xy 323.341966 -105.316537) (xy 323.322696 -105.337864)
			(xy 323.316092 -105.344722) (xy 323.30898 -105.362756) (xy 323.30898 -105.451656) (xy 323.316092 -105.46969)
			(xy 323.322696 -105.476548) (xy 323.341972 -105.49787) (xy 323.374535 -105.545234) (xy 323.399625 -105.596947)
			(xy 323.416674 -105.651838) (xy 323.425295 -105.708665) (xy 323.425295 -105.766143) (xy 323.416672 -105.822971)
			(xy 323.399622 -105.877862) (xy 323.374531 -105.929574) (xy 323.341966 -105.976937) (xy 323.322696 -105.998264)
			(xy 323.316092 -106.005122) (xy 323.30898 -106.023156) (xy 323.30898 -106.112056) (xy 323.316092 -106.13009)
			(xy 323.322696 -106.136948) (xy 323.341972 -106.15827) (xy 323.374535 -106.205634) (xy 323.399625 -106.257347)
			(xy 323.416674 -106.312238) (xy 323.425295 -106.369065) (xy 323.425295 -106.426543) (xy 323.416672 -106.483371)
			(xy 323.399622 -106.538262) (xy 323.374531 -106.589974) (xy 323.341966 -106.637337) (xy 323.322696 -106.658664)
			(xy 323.316092 -106.665522) (xy 323.30898 -106.683556) (xy 323.30898 -106.772456) (xy 323.316092 -106.79049)
			(xy 323.322696 -106.797348) (xy 323.331466 -106.807049) (xy 335.803 -106.807049) (xy 335.803 -106.752551)
			(xy 335.810756 -106.698608) (xy 335.826109 -106.646317) (xy 335.848748 -106.596744) (xy 335.878211 -106.550897)
			(xy 335.913899 -106.509709) (xy 335.955085 -106.47402) (xy 336.000931 -106.444555) (xy 336.050504 -106.421914)
			(xy 336.102794 -106.406559) (xy 336.156737 -106.398801) (xy 336.183986 -106.398314) (xy 336.211356 -106.398785)
			(xy 336.265535 -106.406601) (xy 336.318038 -106.422089) (xy 336.367785 -106.44493) (xy 336.413752 -106.474653)
			(xy 336.434684 -106.492294) (xy 336.434938 -106.492548) (xy 336.442034 -106.498121) (xy 336.458944 -106.504374)
			(xy 336.467958 -106.50474) (xy 336.535014 -106.50474) (xy 336.544033 -106.504403) (xy 336.560951 -106.498143)
			(xy 336.568034 -106.492548) (xy 336.568034 -106.492294) (xy 336.568288 -106.492294) (xy 336.589221 -106.474653)
			(xy 336.635189 -106.444929) (xy 336.684935 -106.422083) (xy 336.737437 -106.406587) (xy 336.791615 -106.398758)
			(xy 336.846357 -106.398758) (xy 336.900535 -106.406587) (xy 336.953037 -106.422083) (xy 337.002783 -106.444929)
			(xy 337.048751 -106.474653) (xy 337.069684 -106.492294) (xy 337.069938 -106.492548) (xy 337.077034 -106.498121)
			(xy 337.093944 -106.504374) (xy 337.102958 -106.50474) (xy 337.170014 -106.50474) (xy 337.179033 -106.504403)
			(xy 337.195951 -106.498143) (xy 337.203034 -106.492548) (xy 337.203034 -106.492294) (xy 337.203288 -106.492294)
			(xy 337.224213 -106.474646) (xy 337.270188 -106.444936) (xy 337.319937 -106.422102) (xy 337.372439 -106.406613)
			(xy 337.426616 -106.398787) (xy 337.453986 -106.398314) (xy 337.481241 -106.398732) (xy 337.535197 -106.406488)
			(xy 337.587499 -106.421843) (xy 337.637084 -106.444486) (xy 337.682942 -106.473956) (xy 337.724138 -106.509652)
			(xy 337.759836 -106.550847) (xy 337.789307 -106.596704) (xy 337.811952 -106.646288) (xy 337.827309 -106.69859)
			(xy 337.835067 -106.752545) (xy 337.835067 -106.802446) (xy 340.620928 -106.802446) (xy 340.620928 -106.747954)
			(xy 340.628682 -106.694017) (xy 340.644033 -106.641733) (xy 340.666668 -106.592165) (xy 340.696127 -106.546323)
			(xy 340.731809 -106.505139) (xy 340.772989 -106.469452) (xy 340.818828 -106.439989) (xy 340.868393 -106.417348)
			(xy 340.920676 -106.401991) (xy 340.974612 -106.394231) (xy 341.001858 -106.393742) (xy 341.028174 -106.394157)
			(xy 341.080305 -106.401401) (xy 341.130949 -106.415729) (xy 341.179149 -106.436871) (xy 341.223991 -106.464427)
			(xy 341.264627 -106.497876) (xy 341.282782 -106.516932) (xy 341.290317 -106.524318) (xy 341.309587 -106.532854)
			(xy 341.32012 -106.533442) (xy 341.394796 -106.533442) (xy 341.405345 -106.532912) (xy 341.42464 -106.524376)
			(xy 341.432134 -106.516932) (xy 341.451954 -106.496144) (xy 341.496726 -106.460169) (xy 341.546384 -106.431309)
			(xy 341.599806 -106.410216) (xy 341.655785 -106.397367) (xy 341.713058 -106.393052) (xy 341.770331 -106.397367)
			(xy 341.82631 -106.410216) (xy 341.879732 -106.431309) (xy 341.92939 -106.460169) (xy 341.974162 -106.496144)
			(xy 341.993982 -106.516932) (xy 342.001517 -106.524318) (xy 342.020787 -106.532854) (xy 342.03132 -106.533442)
			(xy 342.105996 -106.533442) (xy 342.116545 -106.532912) (xy 342.13584 -106.524376) (xy 342.143334 -106.516932)
			(xy 342.161486 -106.497873) (xy 342.202116 -106.464415) (xy 342.246957 -106.436856) (xy 342.295158 -106.415718)
			(xy 342.345807 -106.401402) (xy 342.397942 -106.394179) (xy 342.424258 -106.393742) (xy 342.451516 -106.394102)
			(xy 342.505479 -106.401855) (xy 342.557789 -106.41721) (xy 342.607381 -106.439853) (xy 342.653245 -106.469324)
			(xy 342.694448 -106.505022) (xy 342.730151 -106.546221) (xy 342.759627 -106.592082) (xy 342.782276 -106.641672)
			(xy 342.797636 -106.69398) (xy 342.805395 -106.747942) (xy 342.805395 -106.802458) (xy 342.797636 -106.85642)
			(xy 342.786938 -106.892852) (xy 348.895414 -106.892852) (xy 348.899485 -106.83723) (xy 348.911611 -106.782793)
			(xy 348.931534 -106.730702) (xy 348.95883 -106.682067) (xy 348.992916 -106.637924) (xy 349.033065 -106.599215)
			(xy 349.078423 -106.566764) (xy 349.128023 -106.541263) (xy 349.180807 -106.523256) (xy 349.23565 -106.513126)
			(xy 349.291384 -106.511089) (xy 349.346821 -106.517189) (xy 349.400778 -106.531295) (xy 349.452107 -106.553107)
			(xy 349.499713 -106.582161) (xy 349.542581 -106.617836) (xy 349.579798 -106.659373) (xy 349.610571 -106.705886)
			(xy 349.634243 -106.756383) (xy 349.650311 -106.80979) (xy 349.658431 -106.864966) (xy 349.65894 -106.892852)
			(xy 349.658431 -106.920738) (xy 349.650311 -106.975914) (xy 349.634243 -107.029321) (xy 349.610571 -107.079818)
			(xy 349.607393 -107.084622) (xy 352.533966 -107.084622) (xy 352.534452 -107.057371) (xy 352.542208 -107.003423)
			(xy 352.557563 -106.951128) (xy 352.580205 -106.901551) (xy 352.609671 -106.855701) (xy 352.645362 -106.81451)
			(xy 352.686553 -106.778819) (xy 352.732403 -106.749353) (xy 352.78198 -106.726711) (xy 352.834275 -106.711356)
			(xy 352.888223 -106.7036) (xy 352.942725 -106.7036) (xy 352.996673 -106.711356) (xy 353.048968 -106.726711)
			(xy 353.098545 -106.749353) (xy 353.144395 -106.778819) (xy 353.185586 -106.81451) (xy 353.221277 -106.855701)
			(xy 353.250743 -106.901551) (xy 353.273385 -106.951128) (xy 353.28874 -107.003423) (xy 353.296496 -107.057371)
			(xy 353.296982 -107.084622) (xy 353.296399 -107.113443) (xy 353.28772 -107.170427) (xy 353.270564 -107.225456)
			(xy 353.245321 -107.277276) (xy 353.212566 -107.324707) (xy 353.173045 -107.366667) (xy 353.150678 -107.38485)
			(xy 353.140129 -107.393712) (xy 353.123807 -107.415893) (xy 353.114002 -107.441629) (xy 353.111428 -107.469048)
			(xy 353.116271 -107.496158) (xy 353.12818 -107.52099) (xy 353.146289 -107.541738) (xy 353.157536 -107.549696)
			(xy 353.179741 -107.564939) (xy 353.220077 -107.600626) (xy 353.254996 -107.64163) (xy 353.283805 -107.687134)
			(xy 353.305931 -107.736237) (xy 353.320934 -107.787963) (xy 353.328517 -107.841283) (xy 353.328986 -107.868212)
			(xy 353.3285 -107.895463) (xy 353.327817 -107.900216) (xy 353.48545 -107.900216) (xy 353.485936 -107.872965)
			(xy 353.493692 -107.819017) (xy 353.509047 -107.766722) (xy 353.531689 -107.717145) (xy 353.561155 -107.671295)
			(xy 353.596846 -107.630104) (xy 353.638037 -107.594413) (xy 353.683887 -107.564947) (xy 353.733464 -107.542305)
			(xy 353.785759 -107.52695) (xy 353.839707 -107.519194) (xy 353.894209 -107.519194) (xy 353.948157 -107.52695)
			(xy 354.000452 -107.542305) (xy 354.050029 -107.564947) (xy 354.095879 -107.594413) (xy 354.116677 -107.612434)
			(xy 372.040656 -107.612434) (xy 372.044727 -107.556812) (xy 372.056853 -107.502375) (xy 372.076776 -107.450284)
			(xy 372.104072 -107.401649) (xy 372.138158 -107.357506) (xy 372.178307 -107.318797) (xy 372.223665 -107.286346)
			(xy 372.273265 -107.260845) (xy 372.326049 -107.242838) (xy 372.380892 -107.232708) (xy 372.436626 -107.230671)
			(xy 372.492063 -107.236771) (xy 372.54602 -107.250877) (xy 372.597349 -107.272689) (xy 372.644955 -107.301743)
			(xy 372.687823 -107.337418) (xy 372.72504 -107.378955) (xy 372.755813 -107.425468) (xy 372.779485 -107.475965)
			(xy 372.795553 -107.529372) (xy 372.803673 -107.584548) (xy 372.804182 -107.612434) (xy 372.803673 -107.64032)
			(xy 372.795553 -107.695496) (xy 372.779485 -107.748903) (xy 372.755813 -107.7994) (xy 372.72504 -107.845913)
			(xy 372.687823 -107.88745) (xy 372.644955 -107.923125) (xy 372.597349 -107.952179) (xy 372.54602 -107.973991)
			(xy 372.492063 -107.988097) (xy 372.436626 -107.994197) (xy 372.380892 -107.99216) (xy 372.326049 -107.98203)
			(xy 372.273265 -107.964023) (xy 372.223665 -107.938522) (xy 372.178307 -107.906071) (xy 372.138158 -107.867362)
			(xy 372.104072 -107.823219) (xy 372.076776 -107.774584) (xy 372.056853 -107.722493) (xy 372.044727 -107.668056)
			(xy 372.040656 -107.612434) (xy 354.116677 -107.612434) (xy 354.13707 -107.630104) (xy 354.172761 -107.671295)
			(xy 354.202227 -107.717145) (xy 354.224869 -107.766722) (xy 354.240224 -107.819017) (xy 354.24798 -107.872965)
			(xy 354.248466 -107.900216) (xy 354.247923 -107.928663) (xy 354.239485 -107.984929) (xy 354.222783 -108.039316)
			(xy 354.198188 -108.09062) (xy 354.166245 -108.137701) (xy 354.127663 -108.179516) (xy 354.083299 -108.215136)
			(xy 354.058982 -108.229908) (xy 354.047044 -108.236766) (xy 354.033582 -108.260388) (xy 354.034598 -108.36275)
			(xy 354.035083 -108.371609) (xy 354.041257 -108.388222) (xy 354.052739 -108.401723) (xy 354.060252 -108.406438)
			(xy 354.060506 -108.406438) (xy 354.08554 -108.421021) (xy 354.131307 -108.456539) (xy 354.171178 -108.498568)
			(xy 354.204235 -108.546144) (xy 354.229717 -108.598171) (xy 354.247038 -108.653454) (xy 354.255801 -108.71072)
			(xy 354.25634 -108.739686) (xy 354.255884 -108.767139) (xy 354.247996 -108.821475) (xy 354.232395 -108.874117)
			(xy 354.226433 -108.887047) (xy 372.148906 -108.887047) (xy 372.148906 -108.832553) (xy 372.156661 -108.778612)
			(xy 372.172013 -108.726324) (xy 372.19465 -108.676753) (xy 372.22411 -108.630908) (xy 372.259795 -108.589722)
			(xy 372.300978 -108.554033) (xy 372.34682 -108.524568) (xy 372.396389 -108.501926) (xy 372.448675 -108.486569)
			(xy 372.502615 -108.478809) (xy 372.529862 -108.47832) (xy 372.557181 -108.478775) (xy 372.611261 -108.486571)
			(xy 372.663674 -108.502008) (xy 372.713345 -108.524771) (xy 372.759258 -108.554392) (xy 372.80047 -108.590265)
			(xy 372.81866 -108.610654) (xy 372.825405 -108.617714) (xy 372.842769 -108.626602) (xy 372.852442 -108.627926)
			(xy 372.93296 -108.635038) (xy 372.95201 -108.62945) (xy 372.95963 -108.6231) (xy 372.980109 -108.606961)
			(xy 373.024659 -108.579866) (xy 373.072485 -108.559091) (xy 373.122694 -108.545024) (xy 373.174351 -108.537925)
			(xy 373.200422 -108.537502) (xy 373.227673 -108.537969) (xy 373.28162 -108.545729) (xy 373.333913 -108.561086)
			(xy 373.383489 -108.583729) (xy 373.429338 -108.613197) (xy 373.470526 -108.648889) (xy 373.506217 -108.69008)
			(xy 373.535682 -108.73593) (xy 373.558322 -108.785507) (xy 373.573676 -108.837802) (xy 373.581432 -108.891749)
			(xy 373.581432 -108.946251) (xy 373.573676 -109.000198) (xy 373.558322 -109.052493) (xy 373.535682 -109.10207)
			(xy 373.506217 -109.14792) (xy 373.470526 -109.189111) (xy 373.429338 -109.224803) (xy 373.383489 -109.254271)
			(xy 373.333913 -109.276914) (xy 373.28162 -109.292271) (xy 373.227673 -109.300031) (xy 373.200422 -109.300518)
			(xy 373.173103 -109.300061) (xy 373.119024 -109.292264) (xy 373.066612 -109.276826) (xy 373.016941 -109.254064)
			(xy 372.971028 -109.224443) (xy 372.929814 -109.188572) (xy 372.911624 -109.168184) (xy 372.904879 -109.161124)
			(xy 372.887515 -109.152235) (xy 372.877842 -109.150912) (xy 372.797324 -109.1438) (xy 372.778274 -109.149388)
			(xy 372.770654 -109.155738) (xy 372.750173 -109.171875) (xy 372.705624 -109.198972) (xy 372.657799 -109.219748)
			(xy 372.60759 -109.233816) (xy 372.555933 -109.240913) (xy 372.529862 -109.241336) (xy 372.502615 -109.240791)
			(xy 372.448675 -109.233031) (xy 372.396389 -109.217674) (xy 372.34682 -109.195032) (xy 372.300978 -109.165567)
			(xy 372.259795 -109.129878) (xy 372.22411 -109.088692) (xy 372.19465 -109.042847) (xy 372.172013 -108.993276)
			(xy 372.156661 -108.940988) (xy 372.148906 -108.887047) (xy 354.226433 -108.887047) (xy 354.209405 -108.923978)
			(xy 354.1795 -108.970024) (xy 354.143299 -109.011306) (xy 354.122736 -109.0295) (xy 354.122482 -109.029754)
			(xy 354.114082 -109.037669) (xy 354.104967 -109.058851) (xy 354.104956 -109.070394) (xy 354.10902 -109.162088)
			(xy 354.120196 -109.182408) (xy 354.129594 -109.189266) (xy 354.150381 -109.204676) (xy 354.187972 -109.240236)
			(xy 354.220414 -109.280548) (xy 354.239173 -109.311694) (xy 364.215678 -109.311694) (xy 364.219749 -109.256072)
			(xy 364.231875 -109.201635) (xy 364.251798 -109.149544) (xy 364.279094 -109.100909) (xy 364.31318 -109.056766)
			(xy 364.353329 -109.018057) (xy 364.398687 -108.985606) (xy 364.448287 -108.960105) (xy 364.501071 -108.942098)
			(xy 364.555914 -108.931968) (xy 364.611648 -108.929931) (xy 364.667085 -108.936031) (xy 364.721042 -108.950137)
			(xy 364.772371 -108.971949) (xy 364.819977 -109.001003) (xy 364.862845 -109.036678) (xy 364.900062 -109.078215)
			(xy 364.930835 -109.124728) (xy 364.954507 -109.175225) (xy 364.970575 -109.228632) (xy 364.978695 -109.283808)
			(xy 364.979204 -109.311694) (xy 364.978695 -109.33958) (xy 364.970575 -109.394756) (xy 364.966182 -109.409357)
			(xy 382.410607 -109.409357) (xy 382.410607 -109.354843) (xy 382.418365 -109.300884) (xy 382.433724 -109.248578)
			(xy 382.456371 -109.198991) (xy 382.485844 -109.153131) (xy 382.521544 -109.111933) (xy 382.562744 -109.076234)
			(xy 382.608605 -109.046763) (xy 382.658193 -109.024119) (xy 382.710499 -109.008762) (xy 382.764459 -109.001006)
			(xy 382.791716 -109.000544) (xy 382.806509 -109.000675) (xy 382.836007 -109.002967) (xy 382.850644 -109.005116)
			(xy 382.861618 -109.006256) (xy 382.882811 -109.000185) (xy 382.891538 -108.993432) (xy 382.950212 -108.943394)
			(xy 382.958238 -108.935824) (xy 382.967454 -108.915805) (xy 382.967992 -108.904786) (xy 382.967992 -108.600494)
			(xy 382.96746 -108.589474) (xy 382.958236 -108.569458) (xy 382.950212 -108.561886) (xy 382.891538 -108.511848)
			(xy 382.882855 -108.505019) (xy 382.861629 -108.498974) (xy 382.850644 -108.500164) (xy 382.836006 -108.502306)
			(xy 382.806509 -108.504593) (xy 382.791716 -108.504736) (xy 382.764464 -108.504218) (xy 382.710516 -108.496463)
			(xy 382.65822 -108.48111) (xy 382.608641 -108.45847) (xy 382.56279 -108.429004) (xy 382.521598 -108.393313)
			(xy 382.485905 -108.352123) (xy 382.456438 -108.306273) (xy 382.433796 -108.256695) (xy 382.41844 -108.2044)
			(xy 382.410683 -108.150452) (xy 382.410683 -108.095948) (xy 382.41844 -108.042) (xy 382.433796 -107.989705)
			(xy 382.456438 -107.940127) (xy 382.485905 -107.894277) (xy 382.521598 -107.853087) (xy 382.56279 -107.817396)
			(xy 382.608641 -107.78793) (xy 382.65822 -107.76529) (xy 382.710516 -107.749937) (xy 382.764464 -107.742182)
			(xy 382.791716 -107.74172) (xy 382.817623 -107.742189) (xy 382.86896 -107.749215) (xy 382.918874 -107.763122)
			(xy 382.966447 -107.783654) (xy 383.010806 -107.810433) (xy 383.051133 -107.842968) (xy 383.086687 -107.88066)
			(xy 383.102104 -107.901486) (xy 383.107833 -107.908827) (xy 383.123344 -107.919106) (xy 383.13233 -107.921552)
			(xy 383.16281 -107.92841) (xy 383.172089 -107.93014) (xy 383.190749 -107.927411) (xy 383.199132 -107.923076)
			(xy 383.225119 -107.908821) (xy 383.279984 -107.886389) (xy 383.337285 -107.871222) (xy 383.396063 -107.863575)
			(xy 383.455337 -107.863575) (xy 383.514115 -107.871222) (xy 383.571416 -107.886389) (xy 383.626281 -107.908821)
			(xy 383.652268 -107.923076) (xy 383.660683 -107.927317) (xy 383.679311 -107.930053) (xy 383.68859 -107.92841)
			(xy 383.71907 -107.921552) (xy 383.72807 -107.919145) (xy 383.743572 -107.908838) (xy 383.749296 -107.901486)
			(xy 383.764686 -107.880636) (xy 383.800231 -107.842925) (xy 383.840557 -107.810375) (xy 383.884919 -107.783587)
			(xy 383.932501 -107.763055) (xy 383.982426 -107.749157) (xy 384.033772 -107.742149) (xy 384.059684 -107.74172)
			(xy 384.08694 -107.742126) (xy 384.140896 -107.749882) (xy 384.1932 -107.765237) (xy 384.242786 -107.787881)
			(xy 384.288644 -107.81735) (xy 384.329842 -107.853047) (xy 384.36554 -107.894243) (xy 384.395012 -107.9401)
			(xy 384.417657 -107.989685) (xy 384.433015 -108.041988) (xy 384.440773 -108.095944) (xy 384.440773 -108.150456)
			(xy 384.433015 -108.204412) (xy 384.417657 -108.256715) (xy 384.407048 -108.279946) (xy 395.311628 -108.279946)
			(xy 395.315699 -108.224324) (xy 395.327825 -108.169887) (xy 395.347748 -108.117796) (xy 395.375044 -108.069161)
			(xy 395.40913 -108.025018) (xy 395.449279 -107.986309) (xy 395.494637 -107.953858) (xy 395.544237 -107.928357)
			(xy 395.597021 -107.91035) (xy 395.651864 -107.90022) (xy 395.707598 -107.898183) (xy 395.763035 -107.904283)
			(xy 395.816992 -107.918389) (xy 395.868321 -107.940201) (xy 395.915927 -107.969255) (xy 395.958795 -108.00493)
			(xy 395.996012 -108.046467) (xy 396.026785 -108.09298) (xy 396.050457 -108.143477) (xy 396.066525 -108.196884)
			(xy 396.074645 -108.25206) (xy 396.075154 -108.279946) (xy 396.074645 -108.307832) (xy 396.066525 -108.363008)
			(xy 396.050457 -108.416415) (xy 396.026785 -108.466912) (xy 395.996012 -108.513425) (xy 395.958795 -108.554962)
			(xy 395.915927 -108.590637) (xy 395.868321 -108.619691) (xy 395.816992 -108.641503) (xy 395.763035 -108.655609)
			(xy 395.707598 -108.661709) (xy 395.651864 -108.659672) (xy 395.597021 -108.649542) (xy 395.544237 -108.631535)
			(xy 395.494637 -108.606034) (xy 395.449279 -108.573583) (xy 395.40913 -108.534874) (xy 395.375044 -108.490731)
			(xy 395.347748 -108.442096) (xy 395.327825 -108.390005) (xy 395.315699 -108.335568) (xy 395.311628 -108.279946)
			(xy 384.407048 -108.279946) (xy 384.395012 -108.3063) (xy 384.36554 -108.352157) (xy 384.329842 -108.393353)
			(xy 384.288644 -108.42905) (xy 384.242786 -108.458519) (xy 384.1932 -108.481163) (xy 384.140896 -108.496518)
			(xy 384.08694 -108.504274) (xy 384.059684 -108.504736) (xy 384.044891 -108.504605) (xy 384.015393 -108.502313)
			(xy 384.000756 -108.500164) (xy 383.989782 -108.499029) (xy 383.96859 -108.505097) (xy 383.959862 -108.511848)
			(xy 383.901188 -108.561886) (xy 383.893171 -108.569464) (xy 383.88395 -108.589477) (xy 383.883408 -108.600494)
			(xy 383.883408 -108.904786) (xy 383.883951 -108.915804) (xy 383.893167 -108.935821) (xy 383.901188 -108.943394)
			(xy 383.959862 -108.993432) (xy 383.968547 -109.000259) (xy 383.989771 -109.006306) (xy 384.000756 -109.005116)
			(xy 384.015394 -109.002974) (xy 384.044891 -109.000687) (xy 384.059684 -109.000544) (xy 384.086934 -109.001102)
			(xy 384.14088 -109.008856) (xy 384.193173 -109.024209) (xy 384.242749 -109.046848) (xy 384.288599 -109.076312)
			(xy 384.329788 -109.112001) (xy 384.365479 -109.153189) (xy 384.380993 -109.177328) (xy 397.364964 -109.177328)
			(xy 397.369035 -109.121706) (xy 397.381161 -109.067269) (xy 397.401084 -109.015178) (xy 397.42838 -108.966543)
			(xy 397.462466 -108.9224) (xy 397.502615 -108.883691) (xy 397.547973 -108.85124) (xy 397.597573 -108.825739)
			(xy 397.650357 -108.807732) (xy 397.7052 -108.797602) (xy 397.760934 -108.795565) (xy 397.816371 -108.801665)
			(xy 397.870328 -108.815771) (xy 397.921657 -108.837583) (xy 397.969263 -108.866637) (xy 398.012131 -108.902312)
			(xy 398.049348 -108.943849) (xy 398.080121 -108.990362) (xy 398.103793 -109.040859) (xy 398.119861 -109.094266)
			(xy 398.127981 -109.149442) (xy 398.12849 -109.177328) (xy 398.127981 -109.205214) (xy 398.119861 -109.26039)
			(xy 398.103793 -109.313797) (xy 398.080121 -109.364294) (xy 398.049348 -109.410807) (xy 398.012131 -109.452344)
			(xy 397.969263 -109.488019) (xy 397.921657 -109.517073) (xy 397.870328 -109.538885) (xy 397.816371 -109.552991)
			(xy 397.760934 -109.559091) (xy 397.7052 -109.557054) (xy 397.650357 -109.546924) (xy 397.597573 -109.528917)
			(xy 397.547973 -109.503416) (xy 397.502615 -109.470965) (xy 397.462466 -109.432256) (xy 397.42838 -109.388113)
			(xy 397.401084 -109.339478) (xy 397.381161 -109.287387) (xy 397.369035 -109.23295) (xy 397.364964 -109.177328)
			(xy 384.380993 -109.177328) (xy 384.394945 -109.199037) (xy 384.417585 -109.248612) (xy 384.43294 -109.300904)
			(xy 384.440697 -109.35485) (xy 384.440697 -109.40935) (xy 384.43294 -109.463296) (xy 384.417585 -109.515588)
			(xy 384.394945 -109.565163) (xy 384.365479 -109.611011) (xy 384.329788 -109.652199) (xy 384.288599 -109.687888)
			(xy 384.242749 -109.717352) (xy 384.193173 -109.739991) (xy 384.14088 -109.755344) (xy 384.086934 -109.763098)
			(xy 384.059684 -109.76356) (xy 384.033776 -109.7631) (xy 383.982439 -109.756073) (xy 383.932524 -109.742166)
			(xy 383.884951 -109.721632) (xy 383.840593 -109.694851) (xy 383.800266 -109.662314) (xy 383.764712 -109.624621)
			(xy 383.749296 -109.603794) (xy 383.743551 -109.596467) (xy 383.728052 -109.586178) (xy 383.71907 -109.583728)
			(xy 383.68859 -109.57687) (xy 383.679311 -109.575142) (xy 383.660651 -109.57787) (xy 383.652268 -109.582204)
			(xy 383.626281 -109.596459) (xy 383.571416 -109.618891) (xy 383.514115 -109.634058) (xy 383.455337 -109.641705)
			(xy 383.396063 -109.641705) (xy 383.337285 -109.634058) (xy 383.279984 -109.618891) (xy 383.225119 -109.596459)
			(xy 383.199132 -109.582204) (xy 383.190717 -109.577962) (xy 383.172089 -109.575227) (xy 383.16281 -109.57687)
			(xy 383.13233 -109.583728) (xy 383.123332 -109.586141) (xy 383.107829 -109.596444) (xy 383.102104 -109.603794)
			(xy 383.086708 -109.624639) (xy 383.051165 -109.662352) (xy 383.01084 -109.694903) (xy 382.966479 -109.721691)
			(xy 382.918898 -109.742224) (xy 382.868974 -109.756123) (xy 382.817627 -109.763131) (xy 382.791716 -109.76356)
			(xy 382.764459 -109.763194) (xy 382.710499 -109.755438) (xy 382.658193 -109.740081) (xy 382.608605 -109.717437)
			(xy 382.562744 -109.687966) (xy 382.521544 -109.652267) (xy 382.485844 -109.611069) (xy 382.456371 -109.565209)
			(xy 382.433724 -109.515622) (xy 382.418365 -109.463316) (xy 382.410607 -109.409357) (xy 364.966182 -109.409357)
			(xy 364.954507 -109.448163) (xy 364.930835 -109.49866) (xy 364.900062 -109.545173) (xy 364.862845 -109.58671)
			(xy 364.819977 -109.622385) (xy 364.772371 -109.651439) (xy 364.721042 -109.673251) (xy 364.667085 -109.687357)
			(xy 364.611648 -109.693457) (xy 364.555914 -109.69142) (xy 364.501071 -109.68129) (xy 364.448287 -109.663283)
			(xy 364.398687 -109.637782) (xy 364.353329 -109.605331) (xy 364.31318 -109.566622) (xy 364.279094 -109.522479)
			(xy 364.251798 -109.473844) (xy 364.231875 -109.421753) (xy 364.219749 -109.367316) (xy 364.215678 -109.311694)
			(xy 354.239173 -109.311694) (xy 354.247111 -109.324874) (xy 354.267575 -109.372401) (xy 354.28143 -109.422257)
			(xy 354.288421 -109.473527) (xy 354.288852 -109.4994) (xy 354.288366 -109.526651) (xy 354.28061 -109.580599)
			(xy 354.265255 -109.632894) (xy 354.242613 -109.682471) (xy 354.213147 -109.728321) (xy 354.177456 -109.769512)
			(xy 354.136265 -109.805203) (xy 354.090415 -109.834669) (xy 354.040838 -109.857311) (xy 353.988543 -109.872666)
			(xy 353.934595 -109.880422) (xy 353.880093 -109.880422) (xy 353.826145 -109.872666) (xy 353.77385 -109.857311)
			(xy 353.724273 -109.834669) (xy 353.678423 -109.805203) (xy 353.637232 -109.769512) (xy 353.601541 -109.728321)
			(xy 353.572075 -109.682471) (xy 353.549433 -109.632894) (xy 353.534078 -109.580599) (xy 353.526322 -109.526651)
			(xy 353.525836 -109.4994) (xy 353.52636 -109.47195) (xy 353.534235 -109.417617) (xy 353.549823 -109.364976)
			(xy 353.572801 -109.315116) (xy 353.602693 -109.269067) (xy 353.638882 -109.227783) (xy 353.65944 -109.209586)
			(xy 353.659694 -109.209332) (xy 353.66805 -109.201378) (xy 353.677191 -109.180226) (xy 353.67722 -109.168692)
			(xy 353.673156 -109.076998) (xy 353.66198 -109.056678) (xy 353.652582 -109.04982) (xy 353.631831 -109.034364)
			(xy 353.59424 -108.998812) (xy 353.561796 -108.958507) (xy 353.535094 -108.914189) (xy 353.514624 -108.86667)
			(xy 353.500762 -108.816821) (xy 353.493761 -108.765556) (xy 353.493324 -108.739686) (xy 353.493873 -108.711239)
			(xy 353.502311 -108.654974) (xy 353.519012 -108.600587) (xy 353.543607 -108.549283) (xy 353.575548 -108.502202)
			(xy 353.614129 -108.460387) (xy 353.658492 -108.424766) (xy 353.682808 -108.409994) (xy 353.694746 -108.403136)
			(xy 353.708208 -108.379514) (xy 353.707192 -108.277152) (xy 353.70671 -108.268293) (xy 353.700535 -108.251679)
			(xy 353.689052 -108.238179) (xy 353.681538 -108.233464) (xy 353.681284 -108.233464) (xy 353.656249 -108.218883)
			(xy 353.610482 -108.183365) (xy 353.570611 -108.141335) (xy 353.537555 -108.093758) (xy 353.512074 -108.041731)
			(xy 353.494752 -107.986448) (xy 353.485989 -107.929182) (xy 353.48545 -107.900216) (xy 353.327817 -107.900216)
			(xy 353.320744 -107.949411) (xy 353.305389 -108.001706) (xy 353.282747 -108.051283) (xy 353.253281 -108.097133)
			(xy 353.21759 -108.138324) (xy 353.176399 -108.174015) (xy 353.130549 -108.203481) (xy 353.080972 -108.226123)
			(xy 353.028677 -108.241478) (xy 352.974729 -108.249234) (xy 352.920227 -108.249234) (xy 352.866279 -108.241478)
			(xy 352.813984 -108.226123) (xy 352.764407 -108.203481) (xy 352.718557 -108.174015) (xy 352.677366 -108.138324)
			(xy 352.641675 -108.097133) (xy 352.612209 -108.051283) (xy 352.589567 -108.001706) (xy 352.574212 -107.949411)
			(xy 352.566456 -107.895463) (xy 352.56597 -107.868212) (xy 352.566486 -107.839389) (xy 352.575176 -107.7824)
			(xy 352.592344 -107.727369) (xy 352.6176 -107.675549) (xy 352.650368 -107.62812) (xy 352.689901 -107.586164)
			(xy 352.712274 -107.567984) (xy 352.722781 -107.559078) (xy 352.739095 -107.536905) (xy 352.748896 -107.511181)
			(xy 352.751473 -107.483774) (xy 352.746639 -107.456673) (xy 352.734745 -107.431848) (xy 352.716653 -107.411099)
			(xy 352.705416 -107.403138) (xy 352.683192 -107.387921) (xy 352.642854 -107.352231) (xy 352.607934 -107.311224)
			(xy 352.579127 -107.265715) (xy 352.557004 -107.216607) (xy 352.542006 -107.164877) (xy 352.53443 -107.111552)
			(xy 352.533966 -107.084622) (xy 349.607393 -107.084622) (xy 349.579798 -107.126331) (xy 349.542581 -107.167868)
			(xy 349.499713 -107.203543) (xy 349.452107 -107.232597) (xy 349.400778 -107.254409) (xy 349.346821 -107.268515)
			(xy 349.291384 -107.274615) (xy 349.23565 -107.272578) (xy 349.180807 -107.262448) (xy 349.128023 -107.244441)
			(xy 349.078423 -107.21894) (xy 349.033065 -107.186489) (xy 348.992916 -107.14778) (xy 348.95883 -107.103637)
			(xy 348.931534 -107.055002) (xy 348.911611 -107.002911) (xy 348.899485 -106.948474) (xy 348.895414 -106.892852)
			(xy 342.786938 -106.892852) (xy 342.782276 -106.908728) (xy 342.759627 -106.958318) (xy 342.730151 -107.004179)
			(xy 342.694448 -107.045378) (xy 342.653245 -107.081076) (xy 342.607381 -107.110547) (xy 342.557789 -107.13319)
			(xy 342.505479 -107.148545) (xy 342.451516 -107.156298) (xy 342.424258 -107.156758) (xy 342.397942 -107.156332)
			(xy 342.345812 -107.149091) (xy 342.295168 -107.134764) (xy 342.246968 -107.113624) (xy 342.202126 -107.08607)
			(xy 342.161489 -107.052623) (xy 342.143334 -107.033568) (xy 342.135793 -107.026189) (xy 342.116528 -107.017649)
			(xy 342.105996 -107.017058) (xy 342.03132 -107.017058) (xy 342.020772 -107.017597) (xy 342.001477 -107.026127)
			(xy 341.993982 -107.033568) (xy 341.974162 -107.054356) (xy 341.92939 -107.090331) (xy 341.879732 -107.119191)
			(xy 341.82631 -107.140284) (xy 341.770331 -107.153133) (xy 341.713058 -107.157448) (xy 341.655785 -107.153133)
			(xy 341.599806 -107.140284) (xy 341.546384 -107.119191) (xy 341.496726 -107.090331) (xy 341.451954 -107.054356)
			(xy 341.432134 -107.033568) (xy 341.424593 -107.026189) (xy 341.405328 -107.017649) (xy 341.394796 -107.017058)
			(xy 341.32012 -107.017058) (xy 341.309572 -107.017597) (xy 341.290277 -107.026127) (xy 341.282782 -107.033568)
			(xy 341.264622 -107.052619) (xy 341.223994 -107.086078) (xy 341.179155 -107.113638) (xy 341.130955 -107.134778)
			(xy 341.080308 -107.149095) (xy 341.028174 -107.15632) (xy 341.001858 -107.156758) (xy 340.974612 -107.156169)
			(xy 340.920676 -107.148409) (xy 340.868393 -107.133052) (xy 340.818828 -107.110411) (xy 340.772989 -107.080948)
			(xy 340.731809 -107.045261) (xy 340.696127 -107.004077) (xy 340.666668 -106.958235) (xy 340.644033 -106.908667)
			(xy 340.628682 -106.856383) (xy 340.620928 -106.802446) (xy 337.835067 -106.802446) (xy 337.835067 -106.807055)
			(xy 337.827309 -106.86101) (xy 337.811952 -106.913312) (xy 337.789307 -106.962896) (xy 337.759836 -107.008753)
			(xy 337.724138 -107.049948) (xy 337.682942 -107.085644) (xy 337.637084 -107.115114) (xy 337.587499 -107.137757)
			(xy 337.535197 -107.153112) (xy 337.481241 -107.160868) (xy 337.453986 -107.16133) (xy 337.426615 -107.160889)
			(xy 337.372434 -107.153068) (xy 337.31993 -107.137574) (xy 337.270183 -107.114726) (xy 337.224218 -107.084995)
			(xy 337.203288 -107.06735) (xy 337.203034 -107.067096) (xy 337.195942 -107.061517) (xy 337.179029 -107.055266)
			(xy 337.170014 -107.054904) (xy 337.102958 -107.054904) (xy 337.093944 -107.055288) (xy 337.077027 -107.061517)
			(xy 337.069938 -107.067096) (xy 337.069684 -107.06735) (xy 337.048751 -107.084991) (xy 337.002783 -107.114715)
			(xy 336.953037 -107.137561) (xy 336.900535 -107.153057) (xy 336.846357 -107.160886) (xy 336.791615 -107.160886)
			(xy 336.737437 -107.153057) (xy 336.684935 -107.137561) (xy 336.635189 -107.114715) (xy 336.589221 -107.084991)
			(xy 336.568288 -107.06735) (xy 336.568034 -107.067096) (xy 336.560942 -107.061517) (xy 336.544029 -107.055266)
			(xy 336.535014 -107.054904) (xy 336.467958 -107.054904) (xy 336.458944 -107.055288) (xy 336.442027 -107.061517)
			(xy 336.434938 -107.067096) (xy 336.434938 -107.06735) (xy 336.434684 -107.06735) (xy 336.413725 -107.084955)
			(xy 336.36776 -107.114674) (xy 336.31802 -107.137517) (xy 336.265525 -107.153016) (xy 336.211353 -107.160852)
			(xy 336.183986 -107.16133) (xy 336.156737 -107.160799) (xy 336.102794 -107.153041) (xy 336.050504 -107.137686)
			(xy 336.000931 -107.115045) (xy 335.955085 -107.08558) (xy 335.913899 -107.049891) (xy 335.878211 -107.008703)
			(xy 335.848748 -106.962856) (xy 335.826109 -106.913283) (xy 335.810756 -106.860992) (xy 335.803 -106.807049)
			(xy 323.331466 -106.807049) (xy 323.341972 -106.81867) (xy 323.374535 -106.866034) (xy 323.399625 -106.917747)
			(xy 323.416674 -106.972638) (xy 323.425295 -107.029465) (xy 323.425295 -107.086943) (xy 323.416672 -107.143771)
			(xy 323.399622 -107.198662) (xy 323.374531 -107.250374) (xy 323.341966 -107.297737) (xy 323.322696 -107.319064)
			(xy 323.316092 -107.325922) (xy 323.30898 -107.343956) (xy 323.30898 -107.432856) (xy 323.316092 -107.45089)
			(xy 323.322696 -107.457748) (xy 323.341972 -107.47907) (xy 323.374535 -107.526434) (xy 323.399625 -107.578147)
			(xy 323.416674 -107.633038) (xy 323.425295 -107.689865) (xy 323.425295 -107.740249) (xy 327.884296 -107.740249)
			(xy 327.884296 -107.685751) (xy 327.892052 -107.631807) (xy 327.907405 -107.579517) (xy 327.930044 -107.529943)
			(xy 327.959507 -107.484096) (xy 327.995195 -107.442908) (xy 328.036381 -107.407218) (xy 328.082227 -107.377753)
			(xy 328.1318 -107.355112) (xy 328.18409 -107.339756) (xy 328.238033 -107.331997) (xy 328.265282 -107.33151)
			(xy 328.292652 -107.331984) (xy 328.346831 -107.3398) (xy 328.399334 -107.355287) (xy 328.449081 -107.378127)
			(xy 328.495048 -107.40785) (xy 328.51598 -107.42549) (xy 328.516234 -107.425744) (xy 328.523331 -107.431314)
			(xy 328.54024 -107.43757) (xy 328.549254 -107.437936) (xy 328.61631 -107.437936) (xy 328.625326 -107.437576)
			(xy 328.642243 -107.43133) (xy 328.64933 -107.425744) (xy 328.64933 -107.42549) (xy 328.649584 -107.42549)
			(xy 328.670517 -107.407849) (xy 328.716485 -107.378125) (xy 328.766231 -107.355279) (xy 328.818733 -107.339783)
			(xy 328.872911 -107.331954) (xy 328.927653 -107.331954) (xy 328.981831 -107.339783) (xy 329.034333 -107.355279)
			(xy 329.084079 -107.378125) (xy 329.130047 -107.407849) (xy 329.15098 -107.42549) (xy 329.151234 -107.425744)
			(xy 329.158331 -107.431314) (xy 329.17524 -107.43757) (xy 329.184254 -107.437936) (xy 329.25131 -107.437936)
			(xy 329.260326 -107.437576) (xy 329.277243 -107.43133) (xy 329.28433 -107.425744) (xy 329.28433 -107.42549)
			(xy 329.284584 -107.42549) (xy 329.305517 -107.407849) (xy 329.351485 -107.378125) (xy 329.401231 -107.355279)
			(xy 329.453733 -107.339783) (xy 329.507911 -107.331954) (xy 329.562653 -107.331954) (xy 329.616831 -107.339783)
			(xy 329.669333 -107.355279) (xy 329.719079 -107.378125) (xy 329.765047 -107.407849) (xy 329.78598 -107.42549)
			(xy 329.786234 -107.425744) (xy 329.793331 -107.431314) (xy 329.81024 -107.43757) (xy 329.819254 -107.437936)
			(xy 329.88631 -107.437936) (xy 329.895326 -107.437576) (xy 329.912243 -107.43133) (xy 329.91933 -107.425744)
			(xy 329.91933 -107.42549) (xy 329.919584 -107.42549) (xy 329.94051 -107.407843) (xy 329.986485 -107.378133)
			(xy 330.036234 -107.355299) (xy 330.088736 -107.339809) (xy 330.142912 -107.331983) (xy 330.170282 -107.33151)
			(xy 330.197537 -107.331936) (xy 330.251492 -107.339691) (xy 330.303795 -107.355046) (xy 330.35338 -107.377689)
			(xy 330.399237 -107.407158) (xy 330.440434 -107.442853) (xy 330.476132 -107.484048) (xy 330.505603 -107.529904)
			(xy 330.528248 -107.579488) (xy 330.543605 -107.63179) (xy 330.551363 -107.685745) (xy 330.551363 -107.709056)
			(xy 331.852431 -107.709056) (xy 331.852431 -107.654544) (xy 331.860189 -107.600588) (xy 331.875547 -107.548285)
			(xy 331.898193 -107.4987) (xy 331.927665 -107.452843) (xy 331.963364 -107.411647) (xy 332.004562 -107.375951)
			(xy 332.050421 -107.346481) (xy 332.100007 -107.323839) (xy 332.152311 -107.308484) (xy 332.206268 -107.300729)
			(xy 332.233524 -107.300268) (xy 332.259838 -107.30073) (xy 332.311966 -107.307967) (xy 332.362609 -107.322288)
			(xy 332.410808 -107.343422) (xy 332.455651 -107.370968) (xy 332.496291 -107.404407) (xy 332.514448 -107.423458)
			(xy 332.521956 -107.430876) (xy 332.541246 -107.439392) (xy 332.551786 -107.439968) (xy 332.626462 -107.439968)
			(xy 332.637012 -107.439441) (xy 332.656308 -107.430905) (xy 332.6638 -107.423458) (xy 332.681954 -107.404401)
			(xy 332.722585 -107.370946) (xy 332.767426 -107.343388) (xy 332.815627 -107.32225) (xy 332.866274 -107.307933)
			(xy 332.918408 -107.300707) (xy 332.944724 -107.300268) (xy 332.972096 -107.300703) (xy 333.026277 -107.308526)
			(xy 333.078781 -107.324021) (xy 333.128527 -107.34687) (xy 333.174492 -107.376603) (xy 333.195422 -107.394248)
			(xy 333.195676 -107.394502) (xy 333.202765 -107.400085) (xy 333.21968 -107.406334) (xy 333.228696 -107.406694)
			(xy 333.295752 -107.406694) (xy 333.304767 -107.406315) (xy 333.321684 -107.400083) (xy 333.328772 -107.394502)
			(xy 333.328772 -107.394248) (xy 333.329026 -107.394248) (xy 333.349959 -107.376607) (xy 333.395927 -107.346883)
			(xy 333.445673 -107.324037) (xy 333.498175 -107.308541) (xy 333.552353 -107.300712) (xy 333.607095 -107.300712)
			(xy 333.661273 -107.308541) (xy 333.713775 -107.324037) (xy 333.763521 -107.346883) (xy 333.809489 -107.376607)
			(xy 333.830422 -107.394248) (xy 333.830676 -107.394502) (xy 333.837765 -107.400085) (xy 333.85468 -107.406334)
			(xy 333.863696 -107.406694) (xy 333.930752 -107.406694) (xy 333.939767 -107.406315) (xy 333.956684 -107.400083)
			(xy 333.963772 -107.394502) (xy 333.963772 -107.394248) (xy 333.964026 -107.394248) (xy 333.984981 -107.376638)
			(xy 334.030947 -107.34692) (xy 334.080688 -107.324078) (xy 334.133184 -107.30858) (xy 334.187356 -107.300745)
			(xy 334.214724 -107.300268) (xy 334.241972 -107.300804) (xy 334.295914 -107.308563) (xy 334.348203 -107.323919)
			(xy 334.397774 -107.34656) (xy 334.443618 -107.376025) (xy 334.484803 -107.411714) (xy 334.520489 -107.452901)
			(xy 334.549952 -107.498747) (xy 334.57259 -107.54832) (xy 334.587942 -107.600609) (xy 334.595698 -107.654552)
			(xy 334.595698 -107.709048) (xy 334.587942 -107.762991) (xy 334.57259 -107.81528) (xy 334.549952 -107.864853)
			(xy 334.520489 -107.910699) (xy 334.484803 -107.951886) (xy 334.443618 -107.987575) (xy 334.397774 -108.01704)
			(xy 334.348203 -108.039681) (xy 334.295914 -108.055037) (xy 334.241972 -108.062796) (xy 334.214724 -108.063284)
			(xy 334.187354 -108.062808) (xy 334.133175 -108.054993) (xy 334.080672 -108.039506) (xy 334.030925 -108.016667)
			(xy 333.984958 -107.986944) (xy 333.964026 -107.969304) (xy 333.963772 -107.96905) (xy 333.956673 -107.963481)
			(xy 333.939766 -107.957225) (xy 333.930752 -107.956858) (xy 333.863696 -107.956858) (xy 333.854677 -107.957201)
			(xy 333.83776 -107.963457) (xy 333.830676 -107.96905) (xy 333.830422 -107.969304) (xy 333.809489 -107.986945)
			(xy 333.763521 -108.016669) (xy 333.713775 -108.039515) (xy 333.661273 -108.055011) (xy 333.607095 -108.06284)
			(xy 333.552353 -108.06284) (xy 333.498175 -108.055011) (xy 333.445673 -108.039515) (xy 333.395927 -108.016669)
			(xy 333.349959 -107.986945) (xy 333.329026 -107.969304) (xy 333.328772 -107.96905) (xy 333.321673 -107.963481)
			(xy 333.304766 -107.957225) (xy 333.295752 -107.956858) (xy 333.228696 -107.956858) (xy 333.219677 -107.957201)
			(xy 333.20276 -107.963457) (xy 333.195676 -107.96905) (xy 333.195676 -107.969304) (xy 333.195422 -107.969304)
			(xy 333.174493 -107.986947) (xy 333.128519 -108.016658) (xy 333.078771 -108.039493) (xy 333.02627 -108.054983)
			(xy 332.972093 -108.062811) (xy 332.944724 -108.063284) (xy 332.91841 -108.062806) (xy 332.866282 -108.055574)
			(xy 332.815639 -108.041257) (xy 332.76744 -108.020127) (xy 332.722597 -107.992582) (xy 332.681957 -107.959145)
			(xy 332.6638 -107.940094) (xy 332.656281 -107.93269) (xy 332.636999 -107.924167) (xy 332.626462 -107.923584)
			(xy 332.551786 -107.923584) (xy 332.541235 -107.924097) (xy 332.52194 -107.932644) (xy 332.514448 -107.940094)
			(xy 332.49631 -107.959167) (xy 332.455676 -107.992622) (xy 332.410832 -108.020179) (xy 332.362628 -108.041315)
			(xy 332.311978 -108.055628) (xy 332.259841 -108.062848) (xy 332.233524 -108.063284) (xy 332.206268 -108.062871)
			(xy 332.152311 -108.055116) (xy 332.100007 -108.039761) (xy 332.050421 -108.017119) (xy 332.004562 -107.987649)
			(xy 331.963364 -107.951953) (xy 331.927665 -107.910757) (xy 331.898193 -107.8649) (xy 331.875547 -107.815315)
			(xy 331.860189 -107.763012) (xy 331.852431 -107.709056) (xy 330.551363 -107.709056) (xy 330.551363 -107.740255)
			(xy 330.543605 -107.79421) (xy 330.528248 -107.846512) (xy 330.505603 -107.896096) (xy 330.476132 -107.941952)
			(xy 330.440434 -107.983147) (xy 330.399237 -108.018842) (xy 330.35338 -108.048311) (xy 330.303795 -108.070954)
			(xy 330.251492 -108.086309) (xy 330.197537 -108.094064) (xy 330.170282 -108.094526) (xy 330.142911 -108.094089)
			(xy 330.088729 -108.086267) (xy 330.036225 -108.070772) (xy 329.986479 -108.047923) (xy 329.940514 -108.018191)
			(xy 329.919584 -108.000546) (xy 329.91933 -108.000292) (xy 329.91224 -107.994711) (xy 329.895326 -107.988461)
			(xy 329.88631 -107.9881) (xy 329.819254 -107.9881) (xy 329.81024 -107.988483) (xy 329.793323 -107.994713)
			(xy 329.786234 -108.000292) (xy 329.78598 -108.000546) (xy 329.765047 -108.018187) (xy 329.719079 -108.047911)
			(xy 329.669333 -108.070757) (xy 329.616831 -108.086253) (xy 329.562653 -108.094082) (xy 329.507911 -108.094082)
			(xy 329.453733 -108.086253) (xy 329.401231 -108.070757) (xy 329.351485 -108.047911) (xy 329.305517 -108.018187)
			(xy 329.284584 -108.000546) (xy 329.28433 -108.000292) (xy 329.27724 -107.994711) (xy 329.260326 -107.988461)
			(xy 329.25131 -107.9881) (xy 329.184254 -107.9881) (xy 329.17524 -107.988483) (xy 329.158323 -107.994713)
			(xy 329.151234 -108.000292) (xy 329.151234 -108.000546) (xy 329.15098 -108.000546) (xy 329.130047 -108.018187)
			(xy 329.084079 -108.047911) (xy 329.034333 -108.070757) (xy 328.981831 -108.086253) (xy 328.927653 -108.094082)
			(xy 328.872911 -108.094082) (xy 328.818733 -108.086253) (xy 328.766231 -108.070757) (xy 328.716485 -108.047911)
			(xy 328.670517 -108.018187) (xy 328.649584 -108.000546) (xy 328.64933 -108.000292) (xy 328.64224 -107.994711)
			(xy 328.625326 -107.988461) (xy 328.61631 -107.9881) (xy 328.549254 -107.9881) (xy 328.54024 -107.988483)
			(xy 328.523323 -107.994713) (xy 328.516234 -108.000292) (xy 328.516234 -108.000546) (xy 328.51598 -108.000546)
			(xy 328.495022 -108.018153) (xy 328.449057 -108.047871) (xy 328.399316 -108.070714) (xy 328.346821 -108.086213)
			(xy 328.29265 -108.094048) (xy 328.265282 -108.094526) (xy 328.238033 -108.094003) (xy 328.18409 -108.086244)
			(xy 328.1318 -108.070888) (xy 328.082227 -108.048247) (xy 328.036381 -108.018782) (xy 327.995195 -107.983092)
			(xy 327.959507 -107.941904) (xy 327.930044 -107.896057) (xy 327.907405 -107.846483) (xy 327.892052 -107.794193)
			(xy 327.884296 -107.740249) (xy 323.425295 -107.740249) (xy 323.425295 -107.747343) (xy 323.416672 -107.804171)
			(xy 323.399622 -107.859062) (xy 323.374531 -107.910774) (xy 323.341966 -107.958137) (xy 323.322696 -107.979464)
			(xy 323.316092 -107.986322) (xy 323.30898 -108.004356) (xy 323.30898 -108.093256) (xy 323.316092 -108.11129)
			(xy 323.322696 -108.118148) (xy 323.341958 -108.139483) (xy 323.374528 -108.186841) (xy 323.399623 -108.238551)
			(xy 323.416676 -108.293441) (xy 323.425299 -108.350267) (xy 323.42582 -108.379006) (xy 323.425589 -108.39196)
			(xy 336.427572 -108.39196) (xy 336.428056 -108.36459) (xy 336.435867 -108.310411) (xy 336.451351 -108.257908)
			(xy 336.474189 -108.20816) (xy 336.503911 -108.162193) (xy 336.521552 -108.141262) (xy 336.521806 -108.141008)
			(xy 336.527396 -108.133924) (xy 336.53364 -108.117005) (xy 336.533998 -108.107988) (xy 336.533998 -108.040932)
			(xy 336.533626 -108.031917) (xy 336.527389 -108.014999) (xy 336.521806 -108.007912) (xy 336.521552 -108.007912)
			(xy 336.521552 -108.007658) (xy 336.503935 -107.986708) (xy 336.474218 -107.940741) (xy 336.451377 -107.890998)
			(xy 336.435881 -107.838501) (xy 336.428048 -107.784328) (xy 336.427572 -107.75696) (xy 336.428058 -107.729709)
			(xy 336.435814 -107.675761) (xy 336.451169 -107.623466) (xy 336.473811 -107.573889) (xy 336.503277 -107.528039)
			(xy 336.538968 -107.486848) (xy 336.580159 -107.451157) (xy 336.626009 -107.421691) (xy 336.675586 -107.399049)
			(xy 336.727881 -107.383694) (xy 336.781829 -107.375938) (xy 336.836331 -107.375938) (xy 336.890279 -107.383694)
			(xy 336.942574 -107.399049) (xy 336.992151 -107.421691) (xy 337.038001 -107.451157) (xy 337.079192 -107.486848)
			(xy 337.114883 -107.528039) (xy 337.144349 -107.573889) (xy 337.166991 -107.623466) (xy 337.182346 -107.675761)
			(xy 337.190102 -107.729709) (xy 337.190588 -107.75696) (xy 337.190101 -107.78433) (xy 337.182289 -107.838508)
			(xy 337.166805 -107.891011) (xy 337.143968 -107.940758) (xy 337.114247 -107.986726) (xy 337.096608 -108.007658)
			(xy 337.096354 -108.007912) (xy 337.090751 -108.014987) (xy 337.084515 -108.031913) (xy 337.084162 -108.040932)
			(xy 337.084162 -108.107988) (xy 337.084533 -108.117003) (xy 337.090772 -108.13392) (xy 337.096354 -108.141008)
			(xy 337.096608 -108.141008) (xy 337.096608 -108.141262) (xy 337.114244 -108.162197) (xy 337.143956 -108.208169)
			(xy 337.166792 -108.257916) (xy 337.182284 -108.310416) (xy 337.190113 -108.364591) (xy 337.190588 -108.39196)
			(xy 337.190102 -108.419211) (xy 337.182346 -108.473159) (xy 337.166991 -108.525454) (xy 337.146872 -108.569506)
			(xy 339.061044 -108.569506) (xy 339.061503 -108.542135) (xy 339.069321 -108.487956) (xy 339.084811 -108.435452)
			(xy 339.107655 -108.385705) (xy 339.137381 -108.339739) (xy 339.155024 -108.318808) (xy 339.155278 -108.318554)
			(xy 339.160857 -108.311463) (xy 339.167106 -108.294549) (xy 339.16747 -108.285534) (xy 339.16747 -108.218478)
			(xy 339.16713 -108.209459) (xy 339.160871 -108.192542) (xy 339.155278 -108.185458) (xy 339.155024 -108.185458)
			(xy 339.155024 -108.185204) (xy 339.137377 -108.164278) (xy 339.107666 -108.118304) (xy 339.084831 -108.068555)
			(xy 339.069342 -108.016053) (xy 339.061516 -107.961876) (xy 339.061044 -107.934506) (xy 339.06153 -107.907255)
			(xy 339.069286 -107.853307) (xy 339.084641 -107.801012) (xy 339.107283 -107.751435) (xy 339.136749 -107.705585)
			(xy 339.17244 -107.664394) (xy 339.213631 -107.628703) (xy 339.259481 -107.599237) (xy 339.309058 -107.576595)
			(xy 339.361353 -107.56124) (xy 339.415301 -107.553484) (xy 339.469803 -107.553484) (xy 339.523751 -107.56124)
			(xy 339.576046 -107.576595) (xy 339.625623 -107.599237) (xy 339.671473 -107.628703) (xy 339.712664 -107.664394)
			(xy 339.748355 -107.705585) (xy 339.777821 -107.751435) (xy 339.800463 -107.801012) (xy 339.814452 -107.848654)
			(xy 345.240608 -107.848654) (xy 345.244679 -107.793032) (xy 345.256805 -107.738595) (xy 345.276728 -107.686504)
			(xy 345.304024 -107.637869) (xy 345.33811 -107.593726) (xy 345.378259 -107.555017) (xy 345.423617 -107.522566)
			(xy 345.473217 -107.497065) (xy 345.526001 -107.479058) (xy 345.580844 -107.468928) (xy 345.636578 -107.466891)
			(xy 345.692015 -107.472991) (xy 345.745972 -107.487097) (xy 345.797301 -107.508909) (xy 345.844907 -107.537963)
			(xy 345.887775 -107.573638) (xy 345.924992 -107.615175) (xy 345.955765 -107.661688) (xy 345.979437 -107.712185)
			(xy 345.995505 -107.765592) (xy 346.003625 -107.820768) (xy 346.004134 -107.848654) (xy 346.003625 -107.87654)
			(xy 346.002496 -107.884214) (xy 348.911416 -107.884214) (xy 348.915487 -107.828592) (xy 348.927613 -107.774155)
			(xy 348.947536 -107.722064) (xy 348.974832 -107.673429) (xy 349.008918 -107.629286) (xy 349.049067 -107.590577)
			(xy 349.094425 -107.558126) (xy 349.144025 -107.532625) (xy 349.196809 -107.514618) (xy 349.251652 -107.504488)
			(xy 349.307386 -107.502451) (xy 349.362823 -107.508551) (xy 349.41678 -107.522657) (xy 349.468109 -107.544469)
			(xy 349.515715 -107.573523) (xy 349.558583 -107.609198) (xy 349.5958 -107.650735) (xy 349.626573 -107.697248)
			(xy 349.650245 -107.747745) (xy 349.666313 -107.801152) (xy 349.674433 -107.856328) (xy 349.674942 -107.884214)
			(xy 349.674433 -107.9121) (xy 349.666313 -107.967276) (xy 349.650245 -108.020683) (xy 349.626573 -108.07118)
			(xy 349.5958 -108.117693) (xy 349.558583 -108.15923) (xy 349.515715 -108.194905) (xy 349.468109 -108.223959)
			(xy 349.41678 -108.245771) (xy 349.362823 -108.259877) (xy 349.307386 -108.265977) (xy 349.251652 -108.26394)
			(xy 349.196809 -108.25381) (xy 349.144025 -108.235803) (xy 349.094425 -108.210302) (xy 349.049067 -108.177851)
			(xy 349.008918 -108.139142) (xy 348.974832 -108.094999) (xy 348.947536 -108.046364) (xy 348.927613 -107.994273)
			(xy 348.915487 -107.939836) (xy 348.911416 -107.884214) (xy 346.002496 -107.884214) (xy 345.995505 -107.931716)
			(xy 345.979437 -107.985123) (xy 345.955765 -108.03562) (xy 345.924992 -108.082133) (xy 345.887775 -108.12367)
			(xy 345.844907 -108.159345) (xy 345.797301 -108.188399) (xy 345.745972 -108.210211) (xy 345.692015 -108.224317)
			(xy 345.636578 -108.230417) (xy 345.580844 -108.22838) (xy 345.526001 -108.21825) (xy 345.473217 -108.200243)
			(xy 345.423617 -108.174742) (xy 345.378259 -108.142291) (xy 345.33811 -108.103582) (xy 345.304024 -108.059439)
			(xy 345.276728 -108.010804) (xy 345.256805 -107.958713) (xy 345.244679 -107.904276) (xy 345.240608 -107.848654)
			(xy 339.814452 -107.848654) (xy 339.815818 -107.853307) (xy 339.823574 -107.907255) (xy 339.82406 -107.934506)
			(xy 339.823607 -107.961877) (xy 339.815788 -108.016057) (xy 339.800296 -108.068561) (xy 339.777451 -108.118307)
			(xy 339.747723 -108.164273) (xy 339.73008 -108.185204) (xy 339.729826 -108.185458) (xy 339.724242 -108.192546)
			(xy 339.717996 -108.209462) (xy 339.717634 -108.218478) (xy 339.717634 -108.285534) (xy 339.717967 -108.294553)
			(xy 339.724231 -108.311471) (xy 339.729826 -108.318554) (xy 339.73008 -108.318554) (xy 339.73008 -108.318808)
			(xy 339.747733 -108.339729) (xy 339.777444 -108.385704) (xy 339.800277 -108.435455) (xy 339.815765 -108.487958)
			(xy 339.823589 -108.542136) (xy 339.82406 -108.569506) (xy 339.823574 -108.596757) (xy 339.815818 -108.650705)
			(xy 339.800463 -108.703) (xy 339.777821 -108.752577) (xy 339.748355 -108.798427) (xy 339.712664 -108.839618)
			(xy 339.671473 -108.875309) (xy 339.625623 -108.904775) (xy 339.576046 -108.927417) (xy 339.523751 -108.942772)
			(xy 339.469803 -108.950528) (xy 339.415301 -108.950528) (xy 339.361353 -108.942772) (xy 339.309058 -108.927417)
			(xy 339.259481 -108.904775) (xy 339.213631 -108.875309) (xy 339.17244 -108.839618) (xy 339.136749 -108.798427)
			(xy 339.107283 -108.752577) (xy 339.084641 -108.703) (xy 339.069286 -108.650705) (xy 339.06153 -108.596757)
			(xy 339.061044 -108.569506) (xy 337.146872 -108.569506) (xy 337.144349 -108.575031) (xy 337.114883 -108.620881)
			(xy 337.079192 -108.662072) (xy 337.038001 -108.697763) (xy 336.992151 -108.727229) (xy 336.942574 -108.749871)
			(xy 336.890279 -108.765226) (xy 336.836331 -108.772982) (xy 336.781829 -108.772982) (xy 336.727881 -108.765226)
			(xy 336.675586 -108.749871) (xy 336.626009 -108.727229) (xy 336.580159 -108.697763) (xy 336.538968 -108.662072)
			(xy 336.503277 -108.620881) (xy 336.473811 -108.575031) (xy 336.451169 -108.525454) (xy 336.435814 -108.473159)
			(xy 336.428058 -108.419211) (xy 336.427572 -108.39196) (xy 323.425589 -108.39196) (xy 323.425334 -108.406257)
			(xy 323.417578 -108.460205) (xy 323.402223 -108.5125) (xy 323.379581 -108.562077) (xy 323.350115 -108.607927)
			(xy 323.314424 -108.649118) (xy 323.273233 -108.684809) (xy 323.227383 -108.714275) (xy 323.177806 -108.736917)
			(xy 323.125511 -108.752272) (xy 323.071563 -108.760028) (xy 323.017061 -108.760028) (xy 322.963113 -108.752272)
			(xy 322.910818 -108.736917) (xy 322.861241 -108.714275) (xy 322.815391 -108.684809) (xy 322.7742 -108.649118)
			(xy 322.738509 -108.607927) (xy 322.709043 -108.562077) (xy 322.686401 -108.5125) (xy 322.671046 -108.460205)
			(xy 322.66329 -108.406257) (xy 322.662804 -108.379006) (xy 297.342746 -108.379006) (xy 297.342821 -108.379256)
			(xy 297.350941 -108.434432) (xy 297.35145 -108.462318) (xy 297.350941 -108.490204) (xy 297.342821 -108.54538)
			(xy 297.326753 -108.598787) (xy 297.303081 -108.649284) (xy 297.272308 -108.695797) (xy 297.235091 -108.737334)
			(xy 297.192223 -108.773009) (xy 297.144617 -108.802063) (xy 297.093288 -108.823875) (xy 297.039331 -108.837981)
			(xy 296.983894 -108.844081) (xy 296.92816 -108.842044) (xy 296.873317 -108.831914) (xy 296.820533 -108.813907)
			(xy 296.770933 -108.788406) (xy 296.725575 -108.755955) (xy 296.685426 -108.717246) (xy 296.65134 -108.673103)
			(xy 296.624044 -108.624468) (xy 296.604121 -108.572377) (xy 296.591995 -108.51794) (xy 296.587924 -108.462318)
			(xy 284.900624 -108.462318) (xy 284.900624 -109.176312) (xy 284.900116 -109.196124) (xy 284.900148 -109.207716)
			(xy 284.909267 -109.229003) (xy 284.917642 -109.237018) (xy 284.942026 -109.2581) (xy 284.951015 -109.265195)
			(xy 284.973106 -109.271142) (xy 284.984444 -109.26953) (xy 285.001251 -109.266663) (xy 285.035213 -109.263614)
			(xy 285.052262 -109.263434) (xy 285.079632 -109.263914) (xy 285.133811 -109.271727) (xy 285.186314 -109.287213)
			(xy 285.236061 -109.310051) (xy 285.282028 -109.339774) (xy 285.30296 -109.357414) (xy 285.303214 -109.357668)
			(xy 285.310287 -109.363275) (xy 285.327214 -109.369507) (xy 285.336234 -109.36986) (xy 285.40329 -109.36986)
			(xy 285.412307 -109.369507) (xy 285.429225 -109.363257) (xy 285.43631 -109.357668) (xy 285.43631 -109.357414)
			(xy 285.436564 -109.357414) (xy 285.457501 -109.339781) (xy 285.503472 -109.310067) (xy 285.553218 -109.28723)
			(xy 285.605718 -109.271738) (xy 285.659893 -109.263908) (xy 285.687262 -109.263434) (xy 285.71424 -109.263866)
			(xy 285.76766 -109.271455) (xy 285.819476 -109.286501) (xy 285.868652 -109.308703) (xy 285.914207 -109.337618)
			(xy 285.955228 -109.372668) (xy 285.990898 -109.413152) (xy 286.020502 -109.458261) (xy 286.04345 -109.507095)
			(xy 286.059282 -109.558676) (xy 286.063944 -109.585252) (xy 286.066099 -109.595484) (xy 286.077387 -109.613061)
			(xy 286.085788 -109.619288) (xy 286.157162 -109.666786) (xy 286.178244 -109.670596) (xy 286.188404 -109.668056)
			(xy 286.2151 -109.661925) (xy 286.269475 -109.655297) (xy 286.296862 -109.654848) (xy 286.32425 -109.655295)
			(xy 286.378626 -109.661914) (xy 286.40532 -109.668056) (xy 286.41548 -109.670596) (xy 286.436562 -109.666786)
			(xy 286.516826 -109.613446) (xy 286.528002 -109.59592) (xy 286.52978 -109.585252) (xy 286.534407 -109.558673)
			(xy 286.550268 -109.507107) (xy 286.573236 -109.45829) (xy 286.602853 -109.413196) (xy 286.638529 -109.372725)
			(xy 286.67955 -109.337684) (xy 286.7251 -109.308772) (xy 286.774268 -109.286566) (xy 286.826075 -109.27151)
			(xy 286.879487 -109.263903) (xy 286.906462 -109.263434) (xy 286.93372 -109.26381) (xy 286.987681 -109.271564)
			(xy 287.039989 -109.286918) (xy 287.089579 -109.309561) (xy 287.135442 -109.339031) (xy 287.176644 -109.374729)
			(xy 287.212346 -109.415927) (xy 287.241821 -109.461787) (xy 287.250763 -109.481366) (xy 296.51909 -109.481366)
			(xy 296.523161 -109.425744) (xy 296.535287 -109.371307) (xy 296.55521 -109.319216) (xy 296.582506 -109.270581)
			(xy 296.616592 -109.226438) (xy 296.656741 -109.187729) (xy 296.702099 -109.155278) (xy 296.751699 -109.129777)
			(xy 296.804483 -109.11177) (xy 296.859326 -109.10164) (xy 296.91506 -109.099603) (xy 296.970497 -109.105703)
			(xy 297.024454 -109.119809) (xy 297.075783 -109.141621) (xy 297.123389 -109.170675) (xy 297.166257 -109.20635)
			(xy 297.203474 -109.247887) (xy 297.234247 -109.2944) (xy 297.257919 -109.344897) (xy 297.273987 -109.398304)
			(xy 297.282107 -109.45348) (xy 297.282616 -109.481366) (xy 297.282107 -109.509252) (xy 297.273987 -109.564428)
			(xy 297.257919 -109.617835) (xy 297.234247 -109.668332) (xy 297.203474 -109.714845) (xy 297.166257 -109.756382)
			(xy 297.123389 -109.792057) (xy 297.075783 -109.821111) (xy 297.024454 -109.842923) (xy 296.970497 -109.857029)
			(xy 296.91506 -109.863129) (xy 296.859326 -109.861092) (xy 296.804483 -109.850962) (xy 296.751699 -109.832955)
			(xy 296.702099 -109.807454) (xy 296.656741 -109.775003) (xy 296.616592 -109.736294) (xy 296.582506 -109.692151)
			(xy 296.55521 -109.643516) (xy 296.535287 -109.591425) (xy 296.523161 -109.536988) (xy 296.51909 -109.481366)
			(xy 287.250763 -109.481366) (xy 287.264468 -109.511375) (xy 287.279828 -109.563682) (xy 287.287587 -109.617642)
			(xy 287.287587 -109.672158) (xy 287.279828 -109.726118) (xy 287.264468 -109.778425) (xy 287.241821 -109.828013)
			(xy 287.212346 -109.873873) (xy 287.176644 -109.915071) (xy 287.135442 -109.950769) (xy 287.089579 -109.980239)
			(xy 287.039989 -110.002882) (xy 286.987681 -110.018236) (xy 286.93372 -110.02599) (xy 286.906462 -110.02645)
			(xy 286.88935 -110.026255) (xy 286.855263 -110.023205) (xy 286.83839 -110.020354) (xy 286.827098 -110.019006)
			(xy 286.80521 -110.025066) (xy 286.796226 -110.032038) (xy 286.771842 -110.052866) (xy 286.763396 -110.060828)
			(xy 286.754279 -110.082151) (xy 286.754316 -110.09376) (xy 286.754824 -110.11281) (xy 286.754824 -110.497366)
			(xy 296.272966 -110.497366) (xy 296.273452 -110.470115) (xy 296.281208 -110.416167) (xy 296.296563 -110.363872)
			(xy 296.319205 -110.314295) (xy 296.348671 -110.268445) (xy 296.384362 -110.227254) (xy 296.425553 -110.191563)
			(xy 296.471403 -110.162097) (xy 296.52098 -110.139455) (xy 296.573275 -110.1241) (xy 296.627223 -110.116344)
			(xy 296.681725 -110.116344) (xy 296.735673 -110.1241) (xy 296.787968 -110.139455) (xy 296.837545 -110.162097)
			(xy 296.883395 -110.191563) (xy 296.924586 -110.227254) (xy 296.960277 -110.268445) (xy 296.989743 -110.314295)
			(xy 297.012385 -110.363872) (xy 297.02774 -110.416167) (xy 297.035496 -110.470115) (xy 297.035982 -110.497366)
			(xy 297.035521 -110.525004) (xy 297.027558 -110.579703) (xy 297.011782 -110.632679) (xy 296.988521 -110.682822)
			(xy 296.958264 -110.729081) (xy 296.921644 -110.770487) (xy 296.900854 -110.788704) (xy 296.890583 -110.798065)
			(xy 296.875062 -110.8211) (xy 296.866324 -110.847467) (xy 296.865017 -110.875213) (xy 296.871237 -110.902284)
			(xy 296.884523 -110.926677) (xy 296.903893 -110.946585) (xy 296.927913 -110.960536) (xy 296.94124 -110.964472)
			(xy 296.968188 -110.971962) (xy 297.019723 -110.99369) (xy 297.067535 -111.022707) (xy 297.1106 -111.058392)
			(xy 297.147994 -111.099981) (xy 297.178918 -111.146583) (xy 297.202707 -111.1972) (xy 297.218854 -111.250747)
			(xy 297.227011 -111.306078) (xy 297.227498 -111.334042) (xy 297.227012 -111.361293) (xy 297.219256 -111.415241)
			(xy 297.203901 -111.467536) (xy 297.181259 -111.517113) (xy 297.151793 -111.562963) (xy 297.116102 -111.604154)
			(xy 297.074911 -111.639845) (xy 297.029061 -111.669311) (xy 296.979484 -111.691953) (xy 296.927189 -111.707308)
			(xy 296.873241 -111.715064) (xy 296.818739 -111.715064) (xy 296.764791 -111.707308) (xy 296.712496 -111.691953)
			(xy 296.662919 -111.669311) (xy 296.617069 -111.639845) (xy 296.575878 -111.604154) (xy 296.540187 -111.562963)
			(xy 296.510721 -111.517113) (xy 296.488079 -111.467536) (xy 296.472724 -111.415241) (xy 296.464968 -111.361293)
			(xy 296.464482 -111.334042) (xy 296.464962 -111.306405) (xy 296.472922 -111.251707) (xy 296.488696 -111.198732)
			(xy 296.511953 -111.148589) (xy 296.542207 -111.102329) (xy 296.578822 -111.060923) (xy 296.59961 -111.042704)
			(xy 296.609848 -111.033313) (xy 296.625356 -111.010282) (xy 296.634086 -110.983925) (xy 296.635392 -110.95619)
			(xy 296.629177 -110.929129) (xy 296.615901 -110.904743) (xy 296.596546 -110.884835) (xy 296.572544 -110.870879)
			(xy 296.559224 -110.866936) (xy 296.532272 -110.859462) (xy 296.480737 -110.837731) (xy 296.432926 -110.80871)
			(xy 296.389863 -110.773022) (xy 296.35247 -110.731431) (xy 296.321547 -110.684827) (xy 296.297758 -110.63421)
			(xy 296.281611 -110.580662) (xy 296.273453 -110.525331) (xy 296.272966 -110.497366) (xy 286.754824 -110.497366)
			(xy 286.754824 -110.97641) (xy 286.754316 -110.996222) (xy 286.754349 -111.007814) (xy 286.763468 -111.029101)
			(xy 286.771842 -111.037116) (xy 286.796226 -111.058198) (xy 286.805215 -111.065293) (xy 286.827306 -111.07124)
			(xy 286.838644 -111.069628) (xy 286.855451 -111.066761) (xy 286.889413 -111.063712) (xy 286.906462 -111.063532)
			(xy 286.93372 -111.063912) (xy 286.98768 -111.071666) (xy 287.039988 -111.08702) (xy 287.089578 -111.109663)
			(xy 287.135441 -111.139133) (xy 287.176643 -111.17483) (xy 287.212344 -111.216028) (xy 287.241819 -111.261888)
			(xy 287.264467 -111.311476) (xy 287.279826 -111.363783) (xy 287.287585 -111.417743) (xy 287.287585 -111.472257)
			(xy 287.279826 -111.526217) (xy 287.264467 -111.578524) (xy 287.241819 -111.628112) (xy 287.212344 -111.673972)
			(xy 287.176643 -111.71517) (xy 287.135441 -111.750867) (xy 287.089578 -111.780337) (xy 287.079602 -111.784892)
			(xy 299.368464 -111.784892) (xy 299.36891 -111.757521) (xy 299.37673 -111.70334) (xy 299.392223 -111.650836)
			(xy 299.41507 -111.60109) (xy 299.4448 -111.555124) (xy 299.462444 -111.534194) (xy 299.462698 -111.53394)
			(xy 299.468274 -111.526846) (xy 299.474527 -111.509935) (xy 299.47489 -111.50092) (xy 299.47489 -111.433864)
			(xy 299.474552 -111.424845) (xy 299.468291 -111.407928) (xy 299.462698 -111.400844) (xy 299.462444 -111.400844)
			(xy 299.462444 -111.40059) (xy 299.444795 -111.379664) (xy 299.415069 -111.333695) (xy 299.392223 -111.283948)
			(xy 299.376727 -111.231445) (xy 299.368898 -111.177265) (xy 299.368899 -111.122523) (xy 299.376729 -111.068343)
			(xy 299.392227 -111.015841) (xy 299.415075 -110.966094) (xy 299.444802 -110.920126) (xy 299.462444 -110.899194)
			(xy 299.462698 -110.89894) (xy 299.468274 -110.891846) (xy 299.474527 -110.874935) (xy 299.47489 -110.86592)
			(xy 299.47489 -110.798864) (xy 299.474552 -110.789845) (xy 299.468291 -110.772928) (xy 299.462698 -110.765844)
			(xy 299.462444 -110.765844) (xy 299.462444 -110.76559) (xy 299.444795 -110.744664) (xy 299.415069 -110.698695)
			(xy 299.392223 -110.648948) (xy 299.376727 -110.596445) (xy 299.368898 -110.542265) (xy 299.368899 -110.487523)
			(xy 299.376729 -110.433343) (xy 299.392227 -110.380841) (xy 299.415075 -110.331094) (xy 299.444802 -110.285126)
			(xy 299.462444 -110.264194) (xy 299.462698 -110.26394) (xy 299.468274 -110.256846) (xy 299.474527 -110.239935)
			(xy 299.47489 -110.23092) (xy 299.47489 -110.163864) (xy 299.474552 -110.154845) (xy 299.468291 -110.137928)
			(xy 299.462698 -110.130844) (xy 299.462444 -110.130844) (xy 299.462444 -110.13059) (xy 299.444795 -110.109664)
			(xy 299.415069 -110.063695) (xy 299.392223 -110.013948) (xy 299.376727 -109.961445) (xy 299.368898 -109.907265)
			(xy 299.368899 -109.852523) (xy 299.376729 -109.798343) (xy 299.392227 -109.745841) (xy 299.415075 -109.696094)
			(xy 299.444802 -109.650126) (xy 299.462444 -109.629194) (xy 299.462698 -109.62894) (xy 299.468274 -109.621846)
			(xy 299.474527 -109.604935) (xy 299.47489 -109.59592) (xy 299.47489 -109.528864) (xy 299.474552 -109.519845)
			(xy 299.468291 -109.502928) (xy 299.462698 -109.495844) (xy 299.462444 -109.495844) (xy 299.462444 -109.49559)
			(xy 299.444794 -109.474667) (xy 299.415082 -109.428692) (xy 299.392247 -109.378943) (xy 299.376759 -109.32644)
			(xy 299.368935 -109.272262) (xy 299.368464 -109.244892) (xy 299.36895 -109.217641) (xy 299.376706 -109.163693)
			(xy 299.392061 -109.111398) (xy 299.414703 -109.061821) (xy 299.444169 -109.015971) (xy 299.47986 -108.97478)
			(xy 299.521051 -108.939089) (xy 299.566901 -108.909623) (xy 299.616478 -108.886981) (xy 299.668773 -108.871626)
			(xy 299.722721 -108.86387) (xy 299.777223 -108.86387) (xy 299.831171 -108.871626) (xy 299.883466 -108.886981)
			(xy 299.933043 -108.909623) (xy 299.978893 -108.939089) (xy 300.020084 -108.97478) (xy 300.055775 -109.015971)
			(xy 300.085241 -109.061821) (xy 300.107883 -109.111398) (xy 300.123238 -109.163693) (xy 300.130994 -109.217641)
			(xy 300.13148 -109.244892) (xy 300.131014 -109.272262) (xy 300.123197 -109.326442) (xy 300.107708 -109.378945)
			(xy 300.092053 -109.41304) (xy 304.029364 -109.41304) (xy 304.02985 -109.385789) (xy 304.037606 -109.331841)
			(xy 304.052961 -109.279546) (xy 304.075603 -109.229969) (xy 304.105069 -109.184119) (xy 304.14076 -109.142928)
			(xy 304.181951 -109.107237) (xy 304.227801 -109.077771) (xy 304.277378 -109.055129) (xy 304.329673 -109.039774)
			(xy 304.383621 -109.032018) (xy 304.438123 -109.032018) (xy 304.492071 -109.039774) (xy 304.544366 -109.055129)
			(xy 304.593943 -109.077771) (xy 304.639793 -109.107237) (xy 304.680984 -109.142928) (xy 304.716675 -109.184119)
			(xy 304.746141 -109.229969) (xy 304.768783 -109.279546) (xy 304.784138 -109.331841) (xy 304.791894 -109.385789)
			(xy 304.79238 -109.41304) (xy 304.791958 -109.439235) (xy 304.784789 -109.491133) (xy 304.770591 -109.541563)
			(xy 304.749631 -109.589579) (xy 304.722303 -109.634277) (xy 304.689119 -109.674819) (xy 304.670206 -109.692948)
			(xy 304.662851 -109.700564) (xy 304.654442 -109.719966) (xy 304.65395 -109.73054) (xy 304.654458 -109.816392)
			(xy 304.663094 -109.83595) (xy 304.671222 -109.843062) (xy 304.690781 -109.861206) (xy 304.725109 -109.902043)
			(xy 304.75341 -109.947268) (xy 304.775131 -109.995995) (xy 304.789848 -110.047275) (xy 304.797274 -110.100105)
			(xy 304.797714 -110.12678) (xy 304.797228 -110.154031) (xy 304.789472 -110.207979) (xy 304.774117 -110.260274)
			(xy 304.751475 -110.309851) (xy 304.722009 -110.355701) (xy 304.686318 -110.396892) (xy 304.645127 -110.432583)
			(xy 304.599277 -110.462049) (xy 304.5497 -110.484691) (xy 304.497405 -110.500046) (xy 304.443457 -110.507802)
			(xy 304.388955 -110.507802) (xy 304.335007 -110.500046) (xy 304.282712 -110.484691) (xy 304.233135 -110.462049)
			(xy 304.187285 -110.432583) (xy 304.146094 -110.396892) (xy 304.110403 -110.355701) (xy 304.080937 -110.309851)
			(xy 304.058295 -110.260274) (xy 304.04294 -110.207979) (xy 304.035184 -110.154031) (xy 304.034698 -110.12678)
			(xy 304.03514 -110.100585) (xy 304.042306 -110.048689) (xy 304.0565 -109.998259) (xy 304.077457 -109.950244)
			(xy 304.104781 -109.905545) (xy 304.137961 -109.865002) (xy 304.156872 -109.846872) (xy 304.164273 -109.839296)
			(xy 304.172653 -109.819863) (xy 304.173128 -109.80928) (xy 304.17262 -109.723428) (xy 304.163984 -109.70387)
			(xy 304.155856 -109.696758) (xy 304.136303 -109.678609) (xy 304.101975 -109.637772) (xy 304.073673 -109.592549)
			(xy 304.051951 -109.543822) (xy 304.037233 -109.492544) (xy 304.029806 -109.439715) (xy 304.029364 -109.41304)
			(xy 300.092053 -109.41304) (xy 300.084866 -109.428692) (xy 300.055141 -109.474658) (xy 300.0375 -109.49559)
			(xy 300.037246 -109.495844) (xy 300.03167 -109.502938) (xy 300.025418 -109.519849) (xy 300.025054 -109.528864)
			(xy 300.025054 -109.59592) (xy 300.02539 -109.604939) (xy 300.031651 -109.621857) (xy 300.037246 -109.62894)
			(xy 300.0375 -109.62894) (xy 300.0375 -109.629194) (xy 300.055132 -109.650134) (xy 300.084855 -109.696101)
			(xy 300.107699 -109.745846) (xy 300.123195 -109.798347) (xy 300.131023 -109.852524) (xy 300.131024 -109.907264)
			(xy 300.123197 -109.961441) (xy 300.107703 -110.013943) (xy 300.084861 -110.063689) (xy 300.055139 -110.109657)
			(xy 300.0375 -110.13059) (xy 300.037246 -110.130844) (xy 300.03167 -110.137938) (xy 300.025418 -110.154849)
			(xy 300.025054 -110.163864) (xy 300.025054 -110.23092) (xy 300.02539 -110.239939) (xy 300.031651 -110.256857)
			(xy 300.037246 -110.26394) (xy 300.0375 -110.26394) (xy 300.0375 -110.264194) (xy 300.055132 -110.285134)
			(xy 300.084855 -110.331101) (xy 300.107699 -110.380846) (xy 300.123195 -110.433347) (xy 300.131023 -110.487524)
			(xy 300.131024 -110.530132) (xy 302.62906 -110.530132) (xy 302.633131 -110.47451) (xy 302.645257 -110.420073)
			(xy 302.66518 -110.367982) (xy 302.692476 -110.319347) (xy 302.726562 -110.275204) (xy 302.766711 -110.236495)
			(xy 302.812069 -110.204044) (xy 302.861669 -110.178543) (xy 302.914453 -110.160536) (xy 302.969296 -110.150406)
			(xy 303.02503 -110.148369) (xy 303.080467 -110.154469) (xy 303.134424 -110.168575) (xy 303.185753 -110.190387)
			(xy 303.233359 -110.219441) (xy 303.276227 -110.255116) (xy 303.313444 -110.296653) (xy 303.344217 -110.343166)
			(xy 303.367889 -110.393663) (xy 303.383957 -110.44707) (xy 303.392077 -110.502246) (xy 303.392586 -110.530132)
			(xy 303.392077 -110.558018) (xy 303.383957 -110.613194) (xy 303.367889 -110.666601) (xy 303.344217 -110.717098)
			(xy 303.313444 -110.763611) (xy 303.276227 -110.805148) (xy 303.233359 -110.840823) (xy 303.185753 -110.869877)
			(xy 303.134424 -110.891689) (xy 303.080467 -110.905795) (xy 303.02503 -110.911895) (xy 302.969296 -110.909858)
			(xy 302.914453 -110.899728) (xy 302.861669 -110.881721) (xy 302.812069 -110.85622) (xy 302.766711 -110.823769)
			(xy 302.726562 -110.78506) (xy 302.692476 -110.740917) (xy 302.66518 -110.692282) (xy 302.645257 -110.640191)
			(xy 302.633131 -110.585754) (xy 302.62906 -110.530132) (xy 300.131024 -110.530132) (xy 300.131024 -110.542264)
			(xy 300.123197 -110.596441) (xy 300.107703 -110.648943) (xy 300.084861 -110.698689) (xy 300.055139 -110.744657)
			(xy 300.0375 -110.76559) (xy 300.037246 -110.765844) (xy 300.03167 -110.772938) (xy 300.025418 -110.789849)
			(xy 300.025054 -110.798864) (xy 300.025054 -110.86592) (xy 300.02539 -110.874939) (xy 300.031651 -110.891857)
			(xy 300.037246 -110.89894) (xy 300.0375 -110.89894) (xy 300.0375 -110.899194) (xy 300.055132 -110.920134)
			(xy 300.084855 -110.966101) (xy 300.107699 -111.015846) (xy 300.107829 -111.016288) (xy 303.987962 -111.016288)
			(xy 303.988448 -110.989037) (xy 303.996204 -110.935089) (xy 304.011559 -110.882794) (xy 304.034201 -110.833217)
			(xy 304.063667 -110.787367) (xy 304.099358 -110.746176) (xy 304.140549 -110.710485) (xy 304.186399 -110.681019)
			(xy 304.235976 -110.658377) (xy 304.288271 -110.643022) (xy 304.342219 -110.635266) (xy 304.396721 -110.635266)
			(xy 304.450669 -110.643022) (xy 304.502964 -110.658377) (xy 304.552541 -110.681019) (xy 304.598391 -110.710485)
			(xy 304.639582 -110.746176) (xy 304.675273 -110.787367) (xy 304.704739 -110.833217) (xy 304.727381 -110.882794)
			(xy 304.742736 -110.935089) (xy 304.750492 -110.989037) (xy 304.750978 -111.016288) (xy 304.750513 -111.043308)
			(xy 304.742901 -111.09681) (xy 304.727812 -111.148701) (xy 304.705549 -111.197942) (xy 304.676557 -111.243548)
			(xy 304.641419 -111.284604) (xy 304.621438 -111.3028) (xy 304.613474 -111.310452) (xy 304.604531 -111.330622)
			(xy 304.604166 -111.341662) (xy 304.605436 -111.418878) (xy 304.606107 -111.429889) (xy 304.615592 -111.449778)
			(xy 304.623724 -111.457232) (xy 304.644852 -111.475468) (xy 304.682132 -111.517001) (xy 304.712958 -111.563525)
			(xy 304.736673 -111.614046) (xy 304.75277 -111.667483) (xy 304.760906 -111.722697) (xy 304.761392 -111.750602)
			(xy 304.76077 -111.780394) (xy 304.75152 -111.839255) (xy 304.733231 -111.895962) (xy 304.706346 -111.949135)
			(xy 304.68359 -111.980726) (xy 306.101496 -111.980726) (xy 306.102037 -111.951988) (xy 306.110655 -111.895161)
			(xy 306.127701 -111.840271) (xy 306.152789 -111.788559) (xy 306.185351 -111.741195) (xy 306.20462 -111.719868)
			(xy 306.211224 -111.71301) (xy 306.218336 -111.694976) (xy 306.218336 -111.606076) (xy 306.211224 -111.588042)
			(xy 306.20462 -111.581184) (xy 306.185375 -111.559835) (xy 306.152809 -111.512476) (xy 306.127717 -111.460768)
			(xy 306.110665 -111.405881) (xy 306.10204 -111.349056) (xy 306.102037 -111.291581) (xy 306.110656 -111.234756)
			(xy 306.127703 -111.179867) (xy 306.15279 -111.128157) (xy 306.185351 -111.080795) (xy 306.20462 -111.059468)
			(xy 306.211224 -111.05261) (xy 306.218336 -111.034576) (xy 306.218336 -110.945676) (xy 306.211224 -110.927642)
			(xy 306.20462 -110.920784) (xy 306.185375 -110.899435) (xy 306.152809 -110.852076) (xy 306.127717 -110.800368)
			(xy 306.110665 -110.745481) (xy 306.10204 -110.688656) (xy 306.102037 -110.631181) (xy 306.110656 -110.574356)
			(xy 306.127703 -110.519467) (xy 306.15279 -110.467757) (xy 306.185351 -110.420395) (xy 306.20462 -110.399068)
			(xy 306.211224 -110.39221) (xy 306.218336 -110.374176) (xy 306.218336 -110.285276) (xy 306.211224 -110.267242)
			(xy 306.20462 -110.260384) (xy 306.185375 -110.239035) (xy 306.152809 -110.191676) (xy 306.127717 -110.139968)
			(xy 306.110665 -110.085081) (xy 306.10204 -110.028256) (xy 306.102037 -109.970781) (xy 306.110656 -109.913956)
			(xy 306.127703 -109.859067) (xy 306.15279 -109.807357) (xy 306.185351 -109.759995) (xy 306.20462 -109.738668)
			(xy 306.211224 -109.73181) (xy 306.218336 -109.713776) (xy 306.218336 -109.624876) (xy 306.211224 -109.606842)
			(xy 306.20462 -109.599984) (xy 306.185359 -109.578649) (xy 306.152792 -109.531289) (xy 306.127698 -109.479579)
			(xy 306.110645 -109.42469) (xy 306.102019 -109.367864) (xy 306.101496 -109.339126) (xy 306.10198 -109.311874)
			(xy 306.109733 -109.257923) (xy 306.125086 -109.205625) (xy 306.147726 -109.156045) (xy 306.177191 -109.110192)
			(xy 306.212883 -109.068999) (xy 306.254074 -109.033305) (xy 306.299926 -109.003836) (xy 306.349505 -108.981194)
			(xy 306.401802 -108.965838) (xy 306.455752 -108.958081) (xy 306.483004 -108.957618) (xy 306.509318 -108.958077)
			(xy 306.561447 -108.965313) (xy 306.612091 -108.979633) (xy 306.66029 -109.000767) (xy 306.705133 -109.028315)
			(xy 306.745772 -109.061755) (xy 306.763928 -109.080808) (xy 306.771436 -109.088225) (xy 306.790727 -109.09674)
			(xy 306.801266 -109.097318) (xy 306.875942 -109.097318) (xy 306.886489 -109.096766) (xy 306.905784 -109.088246)
			(xy 306.91328 -109.080808) (xy 306.931454 -109.061771) (xy 306.972079 -109.028312) (xy 307.016916 -109.00075)
			(xy 307.065113 -108.979608) (xy 307.115757 -108.965287) (xy 307.167889 -108.958059) (xy 307.194204 -108.957618)
			(xy 307.221458 -108.958052) (xy 307.275411 -108.96581) (xy 307.327711 -108.981168) (xy 307.377293 -109.003813)
			(xy 307.423148 -109.033283) (xy 307.464341 -109.06898) (xy 307.500035 -109.110176) (xy 307.529502 -109.156033)
			(xy 307.552143 -109.205617) (xy 307.567496 -109.257918) (xy 307.57525 -109.311872) (xy 307.575712 -109.339126)
			(xy 307.575201 -109.367865) (xy 307.566575 -109.424693) (xy 307.549522 -109.479584) (xy 307.538426 -109.502448)
			(xy 341.615014 -109.502448) (xy 341.6155 -109.475197) (xy 341.623256 -109.421249) (xy 341.638611 -109.368954)
			(xy 341.661253 -109.319377) (xy 341.690719 -109.273527) (xy 341.72641 -109.232336) (xy 341.767601 -109.196645)
			(xy 341.813451 -109.167179) (xy 341.863028 -109.144537) (xy 341.915323 -109.129182) (xy 341.969271 -109.121426)
			(xy 342.023773 -109.121426) (xy 342.077721 -109.129182) (xy 342.130016 -109.144537) (xy 342.179593 -109.167179)
			(xy 342.225443 -109.196645) (xy 342.266634 -109.232336) (xy 342.302325 -109.273527) (xy 342.331791 -109.319377)
			(xy 342.354433 -109.368954) (xy 342.369788 -109.421249) (xy 342.377544 -109.475197) (xy 342.37803 -109.502448)
			(xy 342.377596 -109.527979) (xy 342.370792 -109.578586) (xy 342.357298 -109.627833) (xy 342.337356 -109.67484)
			(xy 342.32469 -109.697012) (xy 342.318086 -109.708188) (xy 342.31707 -109.734096) (xy 342.344124 -109.787436)
			(xy 348.959932 -109.787436) (xy 348.960434 -109.75953) (xy 348.968555 -109.704312) (xy 348.98463 -109.650866)
			(xy 349.008315 -109.600329) (xy 349.039107 -109.55378) (xy 349.076348 -109.512211) (xy 349.119245 -109.476507)
			(xy 349.142812 -109.461554) (xy 349.154242 -109.454696) (xy 349.167196 -109.431582) (xy 349.167704 -109.332014)
			(xy 349.167399 -109.323336) (xy 349.161651 -109.30696) (xy 349.150774 -109.293437) (xy 349.143574 -109.28858)
			(xy 349.120376 -109.273545) (xy 349.078162 -109.237855) (xy 349.041541 -109.196447) (xy 349.011278 -109.150187)
			(xy 348.988007 -109.100045) (xy 348.972216 -109.047069) (xy 348.964235 -108.99237) (xy 348.963742 -108.96473)
			(xy 348.964228 -108.937479) (xy 348.971984 -108.883531) (xy 348.987339 -108.831236) (xy 349.009981 -108.781659)
			(xy 349.039447 -108.735809) (xy 349.075138 -108.694618) (xy 349.116329 -108.658927) (xy 349.162179 -108.629461)
			(xy 349.211756 -108.606819) (xy 349.264051 -108.591464) (xy 349.317999 -108.583708) (xy 349.372501 -108.583708)
			(xy 349.426449 -108.591464) (xy 349.478744 -108.606819) (xy 349.528321 -108.629461) (xy 349.574171 -108.658927)
			(xy 349.615362 -108.694618) (xy 349.651053 -108.735809) (xy 349.680519 -108.781659) (xy 349.689074 -108.800392)
			(xy 352.370134 -108.800392) (xy 352.374205 -108.74477) (xy 352.386331 -108.690333) (xy 352.406254 -108.638242)
			(xy 352.43355 -108.589607) (xy 352.467636 -108.545464) (xy 352.507785 -108.506755) (xy 352.553143 -108.474304)
			(xy 352.602743 -108.448803) (xy 352.655527 -108.430796) (xy 352.71037 -108.420666) (xy 352.766104 -108.418629)
			(xy 352.821541 -108.424729) (xy 352.875498 -108.438835) (xy 352.926827 -108.460647) (xy 352.974433 -108.489701)
			(xy 353.017301 -108.525376) (xy 353.054518 -108.566913) (xy 353.085291 -108.613426) (xy 353.108963 -108.663923)
			(xy 353.125031 -108.71733) (xy 353.133151 -108.772506) (xy 353.13366 -108.800392) (xy 353.133151 -108.828278)
			(xy 353.125031 -108.883454) (xy 353.108963 -108.936861) (xy 353.085291 -108.987358) (xy 353.054518 -109.033871)
			(xy 353.017301 -109.075408) (xy 352.974433 -109.111083) (xy 352.926827 -109.140137) (xy 352.875498 -109.161949)
			(xy 352.821541 -109.176055) (xy 352.766104 -109.182155) (xy 352.71037 -109.180118) (xy 352.655527 -109.169988)
			(xy 352.602743 -109.151981) (xy 352.553143 -109.12648) (xy 352.507785 -109.094029) (xy 352.467636 -109.05532)
			(xy 352.43355 -109.011177) (xy 352.406254 -108.962542) (xy 352.386331 -108.910451) (xy 352.374205 -108.856014)
			(xy 352.370134 -108.800392) (xy 349.689074 -108.800392) (xy 349.703161 -108.831236) (xy 349.718516 -108.883531)
			(xy 349.726272 -108.937479) (xy 349.726758 -108.96473) (xy 349.726235 -108.992635) (xy 349.718118 -109.047852)
			(xy 349.702047 -109.101298) (xy 349.678365 -109.151835) (xy 349.647577 -109.198385) (xy 349.610339 -109.239955)
			(xy 349.567444 -109.275659) (xy 349.543878 -109.290612) (xy 349.532448 -109.29747) (xy 349.519494 -109.320584)
			(xy 349.518986 -109.420152) (xy 349.519319 -109.428828) (xy 349.525055 -109.445202) (xy 349.535921 -109.458727)
			(xy 349.543116 -109.463586) (xy 349.566342 -109.47858) (xy 349.608556 -109.514276) (xy 349.645176 -109.555691)
			(xy 349.675436 -109.601958) (xy 349.698702 -109.652107) (xy 349.714487 -109.705089) (xy 349.72246 -109.759794)
			(xy 349.722948 -109.787436) (xy 349.722475 -109.815341) (xy 349.714327 -109.870555) (xy 349.698225 -109.923993)
			(xy 349.674513 -109.974516) (xy 349.643695 -110.021047) (xy 349.606429 -110.062594) (xy 349.58528 -110.080806)
			(xy 349.57639 -110.088172) (xy 349.566738 -110.109) (xy 349.568008 -110.211108) (xy 349.578168 -110.231682)
			(xy 349.587312 -110.238794) (xy 349.609606 -110.257002) (xy 349.64901 -110.298958) (xy 349.681665 -110.346357)
			(xy 349.690743 -110.365032) (xy 362.080808 -110.365032) (xy 362.084879 -110.30941) (xy 362.097005 -110.254973)
			(xy 362.116928 -110.202882) (xy 362.144224 -110.154247) (xy 362.17831 -110.110104) (xy 362.218459 -110.071395)
			(xy 362.263817 -110.038944) (xy 362.313417 -110.013443) (xy 362.366201 -109.995436) (xy 362.421044 -109.985306)
			(xy 362.476778 -109.983269) (xy 362.532215 -109.989369) (xy 362.586172 -110.003475) (xy 362.637501 -110.025287)
			(xy 362.685107 -110.054341) (xy 362.727975 -110.090016) (xy 362.765192 -110.131553) (xy 362.795965 -110.178066)
			(xy 362.819637 -110.228563) (xy 362.835705 -110.28197) (xy 362.843825 -110.337146) (xy 362.844334 -110.365032)
			(xy 363.096808 -110.365032) (xy 363.100879 -110.30941) (xy 363.113005 -110.254973) (xy 363.132928 -110.202882)
			(xy 363.160224 -110.154247) (xy 363.19431 -110.110104) (xy 363.234459 -110.071395) (xy 363.279817 -110.038944)
			(xy 363.329417 -110.013443) (xy 363.382201 -109.995436) (xy 363.437044 -109.985306) (xy 363.492778 -109.983269)
			(xy 363.548215 -109.989369) (xy 363.602172 -110.003475) (xy 363.653501 -110.025287) (xy 363.701107 -110.054341)
			(xy 363.743975 -110.090016) (xy 363.781192 -110.131553) (xy 363.811965 -110.178066) (xy 363.835637 -110.228563)
			(xy 363.851705 -110.28197) (xy 363.859825 -110.337146) (xy 363.860334 -110.365032) (xy 364.112808 -110.365032)
			(xy 364.116879 -110.30941) (xy 364.129005 -110.254973) (xy 364.148928 -110.202882) (xy 364.176224 -110.154247)
			(xy 364.21031 -110.110104) (xy 364.250459 -110.071395) (xy 364.295817 -110.038944) (xy 364.345417 -110.013443)
			(xy 364.398201 -109.995436) (xy 364.453044 -109.985306) (xy 364.508778 -109.983269) (xy 364.564215 -109.989369)
			(xy 364.618172 -110.003475) (xy 364.635777 -110.010956) (xy 371.610126 -110.010956) (xy 371.614197 -109.955334)
			(xy 371.626323 -109.900897) (xy 371.646246 -109.848806) (xy 371.673542 -109.800171) (xy 371.707628 -109.756028)
			(xy 371.747777 -109.717319) (xy 371.793135 -109.684868) (xy 371.842735 -109.659367) (xy 371.895519 -109.64136)
			(xy 371.950362 -109.63123) (xy 372.006096 -109.629193) (xy 372.061533 -109.635293) (xy 372.11549 -109.649399)
			(xy 372.166819 -109.671211) (xy 372.214425 -109.700265) (xy 372.257293 -109.73594) (xy 372.29451 -109.777477)
			(xy 372.325283 -109.82399) (xy 372.348955 -109.874487) (xy 372.365023 -109.927894) (xy 372.373143 -109.98307)
			(xy 372.373652 -110.010956) (xy 372.37315 -110.038448) (xy 373.348288 -110.038448) (xy 373.348288 -109.983952)
			(xy 373.356043 -109.93001) (xy 373.371395 -109.877721) (xy 373.394032 -109.828148) (xy 373.423493 -109.782301)
			(xy 373.459178 -109.741114) (xy 373.500361 -109.705423) (xy 373.546204 -109.675956) (xy 373.595774 -109.653313)
			(xy 373.648061 -109.637954) (xy 373.702002 -109.630192) (xy 373.72925 -109.629702) (xy 373.756726 -109.630158)
			(xy 373.811107 -109.638057) (xy 373.863789 -109.653685) (xy 373.913682 -109.676716) (xy 373.959749 -109.706674)
			(xy 373.98071 -109.724444) (xy 373.987822 -109.73054) (xy 374.005094 -109.737144) (xy 374.091708 -109.736382)
			(xy 374.108472 -109.730032) (xy 374.115584 -109.723682) (xy 374.136706 -109.705377) (xy 374.183272 -109.674466)
			(xy 374.233852 -109.650684) (xy 374.287361 -109.634541) (xy 374.342654 -109.626382) (xy 374.3706 -109.625892)
			(xy 374.397851 -109.626378) (xy 374.451799 -109.634134) (xy 374.504094 -109.649489) (xy 374.553671 -109.672131)
			(xy 374.599521 -109.701597) (xy 374.640712 -109.737288) (xy 374.676403 -109.778479) (xy 374.705869 -109.824329)
			(xy 374.728511 -109.873906) (xy 374.743866 -109.926201) (xy 374.746418 -109.943952) (xy 385.052777 -109.943952)
			(xy 385.052777 -109.889448) (xy 385.060535 -109.835498) (xy 385.075891 -109.783201) (xy 385.098534 -109.733622)
			(xy 385.128002 -109.68777) (xy 385.163697 -109.64658) (xy 385.20489 -109.610888) (xy 385.250743 -109.581422)
			(xy 385.300323 -109.558782) (xy 385.352621 -109.543429) (xy 385.406572 -109.535676) (xy 385.433824 -109.535214)
			(xy 385.459731 -109.535679) (xy 385.511068 -109.542706) (xy 385.560982 -109.556614) (xy 385.608555 -109.577147)
			(xy 385.652914 -109.603927) (xy 385.693241 -109.636462) (xy 385.728795 -109.674154) (xy 385.744212 -109.69498)
			(xy 385.749939 -109.702322) (xy 385.765451 -109.712601) (xy 385.774438 -109.715046) (xy 385.804918 -109.721904)
			(xy 385.814196 -109.723639) (xy 385.832857 -109.720907) (xy 385.84124 -109.71657) (xy 385.867208 -109.70226)
			(xy 385.922063 -109.679753) (xy 385.979369 -109.664531) (xy 386.038162 -109.65685) (xy 386.067808 -109.656372)
			(xy 386.097451 -109.656856) (xy 386.156234 -109.664581) (xy 386.213532 -109.679812) (xy 386.268392 -109.702294)
			(xy 386.294376 -109.71657) (xy 386.30279 -109.720814) (xy 386.321419 -109.723549) (xy 386.330698 -109.721904)
			(xy 386.361178 -109.715046) (xy 386.370169 -109.712613) (xy 386.385673 -109.702322) (xy 386.391404 -109.69498)
			(xy 386.406788 -109.674125) (xy 386.442334 -109.636414) (xy 386.482661 -109.603865) (xy 386.527024 -109.577078)
			(xy 386.574607 -109.556547) (xy 386.624533 -109.54265) (xy 386.67588 -109.535643) (xy 386.701792 -109.535214)
			(xy 386.729047 -109.535632) (xy 386.783002 -109.543389) (xy 386.835304 -109.558745) (xy 386.884888 -109.581388)
			(xy 386.930745 -109.610858) (xy 386.970081 -109.644942) (xy 392.969748 -109.644942) (xy 392.973819 -109.58932)
			(xy 392.985945 -109.534883) (xy 393.005868 -109.482792) (xy 393.033164 -109.434157) (xy 393.06725 -109.390014)
			(xy 393.107399 -109.351305) (xy 393.152757 -109.318854) (xy 393.202357 -109.293353) (xy 393.255141 -109.275346)
			(xy 393.309984 -109.265216) (xy 393.365718 -109.263179) (xy 393.421155 -109.269279) (xy 393.475112 -109.283385)
			(xy 393.526441 -109.305197) (xy 393.574047 -109.334251) (xy 393.616915 -109.369926) (xy 393.654132 -109.411463)
			(xy 393.684905 -109.457976) (xy 393.708577 -109.508473) (xy 393.724645 -109.56188) (xy 393.732765 -109.617056)
			(xy 393.733274 -109.644942) (xy 393.732765 -109.672828) (xy 393.724645 -109.728004) (xy 393.708577 -109.781411)
			(xy 393.684905 -109.831908) (xy 393.654132 -109.878421) (xy 393.616915 -109.919958) (xy 393.574047 -109.955633)
			(xy 393.526441 -109.984687) (xy 393.475112 -110.006499) (xy 393.421155 -110.020605) (xy 393.365718 -110.026705)
			(xy 393.309984 -110.024668) (xy 393.255141 -110.014538) (xy 393.202357 -109.996531) (xy 393.152757 -109.97103)
			(xy 393.107399 -109.938579) (xy 393.06725 -109.89987) (xy 393.033164 -109.855727) (xy 393.005868 -109.807092)
			(xy 392.985945 -109.755001) (xy 392.973819 -109.700564) (xy 392.969748 -109.644942) (xy 386.970081 -109.644942)
			(xy 386.971941 -109.646554) (xy 387.007637 -109.687749) (xy 387.037108 -109.733605) (xy 387.059752 -109.783189)
			(xy 387.075109 -109.83549) (xy 387.082867 -109.889445) (xy 387.082867 -109.943955) (xy 387.075109 -109.99791)
			(xy 387.059752 -110.050211) (xy 387.037108 -110.099795) (xy 387.007637 -110.145651) (xy 386.971941 -110.186846)
			(xy 386.930745 -110.222542) (xy 386.884888 -110.252012) (xy 386.835304 -110.274655) (xy 386.783002 -110.290011)
			(xy 386.729047 -110.297768) (xy 386.701792 -110.29823) (xy 386.686999 -110.298098) (xy 386.657501 -110.295807)
			(xy 386.642864 -110.293658) (xy 386.63189 -110.292529) (xy 386.610698 -110.298593) (xy 386.60197 -110.305342)
			(xy 386.543296 -110.35538) (xy 386.535283 -110.362961) (xy 386.526059 -110.382971) (xy 386.525516 -110.393988)
			(xy 386.525516 -110.69828) (xy 386.52606 -110.709298) (xy 386.535275 -110.729315) (xy 386.543296 -110.736888)
			(xy 386.60197 -110.786926) (xy 386.610688 -110.793704) (xy 386.631886 -110.79978) (xy 386.642864 -110.79861)
			(xy 386.657502 -110.796467) (xy 386.686999 -110.79418) (xy 386.701792 -110.794038) (xy 386.729049 -110.794408)
			(xy 386.783007 -110.802165) (xy 386.835312 -110.817523) (xy 386.884899 -110.840167) (xy 386.911929 -110.857538)
			(xy 397.264634 -110.857538) (xy 397.268705 -110.801916) (xy 397.280831 -110.747479) (xy 397.300754 -110.695388)
			(xy 397.32805 -110.646753) (xy 397.362136 -110.60261) (xy 397.402285 -110.563901) (xy 397.447643 -110.53145)
			(xy 397.497243 -110.505949) (xy 397.550027 -110.487942) (xy 397.60487 -110.477812) (xy 397.660604 -110.475775)
			(xy 397.716041 -110.481875) (xy 397.769998 -110.495981) (xy 397.821327 -110.517793) (xy 397.868933 -110.546847)
			(xy 397.911801 -110.582522) (xy 397.949018 -110.624059) (xy 397.979791 -110.670572) (xy 398.003463 -110.721069)
			(xy 398.019531 -110.774476) (xy 398.027651 -110.829652) (xy 398.02816 -110.857538) (xy 398.027651 -110.885424)
			(xy 398.019531 -110.9406) (xy 398.003463 -110.994007) (xy 397.979791 -111.044504) (xy 397.949018 -111.091017)
			(xy 397.911801 -111.132554) (xy 397.868933 -111.168229) (xy 397.821327 -111.197283) (xy 397.769998 -111.219095)
			(xy 397.716041 -111.233201) (xy 397.660604 -111.239301) (xy 397.60487 -111.237264) (xy 397.550027 -111.227134)
			(xy 397.497243 -111.209127) (xy 397.447643 -111.183626) (xy 397.402285 -111.151175) (xy 397.362136 -111.112466)
			(xy 397.32805 -111.068323) (xy 397.300754 -111.019688) (xy 397.280831 -110.967597) (xy 397.268705 -110.91316)
			(xy 397.264634 -110.857538) (xy 386.911929 -110.857538) (xy 386.930759 -110.869639) (xy 386.971958 -110.905337)
			(xy 387.007656 -110.946535) (xy 387.037129 -110.992394) (xy 387.059775 -111.04198) (xy 387.075133 -111.094285)
			(xy 387.082891 -111.148243) (xy 387.082891 -111.202757) (xy 387.075133 -111.256715) (xy 387.059775 -111.30902)
			(xy 387.037129 -111.358606) (xy 387.007656 -111.404465) (xy 386.972498 -111.44504) (xy 392.969748 -111.44504)
			(xy 392.973819 -111.389418) (xy 392.985945 -111.334981) (xy 393.005868 -111.28289) (xy 393.033164 -111.234255)
			(xy 393.06725 -111.190112) (xy 393.107399 -111.151403) (xy 393.152757 -111.118952) (xy 393.202357 -111.093451)
			(xy 393.255141 -111.075444) (xy 393.309984 -111.065314) (xy 393.365718 -111.063277) (xy 393.421155 -111.069377)
			(xy 393.475112 -111.083483) (xy 393.526441 -111.105295) (xy 393.574047 -111.134349) (xy 393.616915 -111.170024)
			(xy 393.654132 -111.211561) (xy 393.684905 -111.258074) (xy 393.708577 -111.308571) (xy 393.724645 -111.361978)
			(xy 393.732765 -111.417154) (xy 393.733274 -111.44504) (xy 393.732765 -111.472926) (xy 393.724645 -111.528102)
			(xy 393.708577 -111.581509) (xy 393.684905 -111.632006) (xy 393.654132 -111.678519) (xy 393.616915 -111.720056)
			(xy 393.574047 -111.755731) (xy 393.526441 -111.784785) (xy 393.475112 -111.806597) (xy 393.421155 -111.820703)
			(xy 393.365718 -111.826803) (xy 393.309984 -111.824766) (xy 393.255141 -111.814636) (xy 393.202357 -111.796629)
			(xy 393.152757 -111.771128) (xy 393.107399 -111.738677) (xy 393.06725 -111.699968) (xy 393.033164 -111.655825)
			(xy 393.005868 -111.60719) (xy 392.985945 -111.555099) (xy 392.973819 -111.500662) (xy 392.969748 -111.44504)
			(xy 386.972498 -111.44504) (xy 386.971958 -111.445663) (xy 386.930759 -111.481361) (xy 386.884899 -111.510833)
			(xy 386.835312 -111.533477) (xy 386.783007 -111.548835) (xy 386.729049 -111.556592) (xy 386.701792 -111.557054)
			(xy 386.675884 -111.55659) (xy 386.624547 -111.549565) (xy 386.574633 -111.535658) (xy 386.527059 -111.515125)
			(xy 386.4827 -111.488344) (xy 386.442374 -111.455808) (xy 386.40682 -111.418115) (xy 386.391404 -111.397288)
			(xy 386.385657 -111.389963) (xy 386.37016 -111.379672) (xy 386.361178 -111.377222) (xy 386.330698 -111.370364)
			(xy 386.321418 -111.368641) (xy 386.302759 -111.371365) (xy 386.294376 -111.375698) (xy 386.268403 -111.389999)
			(xy 386.21355 -111.412509) (xy 386.156246 -111.427733) (xy 386.097454 -111.435417) (xy 386.067808 -111.435896)
			(xy 386.038165 -111.435397) (xy 385.979384 -111.427674) (xy 385.922086 -111.412448) (xy 385.867225 -111.389971)
			(xy 385.84124 -111.375698) (xy 385.832822 -111.371464) (xy 385.814196 -111.368721) (xy 385.804918 -111.370364)
			(xy 385.774438 -111.377222) (xy 385.765442 -111.37964) (xy 385.749938 -111.38994) (xy 385.744212 -111.397288)
			(xy 385.728809 -111.418128) (xy 385.693267 -111.455841) (xy 385.652944 -111.488392) (xy 385.608584 -111.515182)
			(xy 385.561004 -111.535715) (xy 385.511081 -111.549615) (xy 385.459735 -111.556624) (xy 385.433824 -111.557054)
			(xy 385.406573 -111.5565) (xy 385.352626 -111.548747) (xy 385.300332 -111.533395) (xy 385.250755 -111.510757)
			(xy 385.204904 -111.481293) (xy 385.163714 -111.445603) (xy 385.128022 -111.404415) (xy 385.098555 -111.358566)
			(xy 385.075913 -111.308991) (xy 385.060558 -111.256697) (xy 385.052801 -111.202751) (xy 385.052801 -111.148249)
			(xy 385.060558 -111.094303) (xy 385.075913 -111.042009) (xy 385.098555 -110.992434) (xy 385.128022 -110.946585)
			(xy 385.163714 -110.905397) (xy 385.204904 -110.869707) (xy 385.250755 -110.840243) (xy 385.300332 -110.817605)
			(xy 385.352626 -110.802253) (xy 385.406573 -110.7945) (xy 385.433824 -110.794038) (xy 385.448617 -110.794168)
			(xy 385.478115 -110.796461) (xy 385.492752 -110.79861) (xy 385.503728 -110.799697) (xy 385.524915 -110.793662)
			(xy 385.533646 -110.786926) (xy 385.59232 -110.736888) (xy 385.600349 -110.729322) (xy 385.609563 -110.7093)
			(xy 385.6101 -110.69828) (xy 385.6101 -110.393988) (xy 385.609569 -110.382968) (xy 385.600345 -110.362952)
			(xy 385.59232 -110.35538) (xy 385.533646 -110.305342) (xy 385.52496 -110.298517) (xy 385.503736 -110.29247)
			(xy 385.492752 -110.293658) (xy 385.478114 -110.2958) (xy 385.448617 -110.298087) (xy 385.433824 -110.29823)
			(xy 385.406572 -110.297724) (xy 385.352621 -110.289971) (xy 385.300323 -110.274618) (xy 385.250743 -110.251978)
			(xy 385.20489 -110.222512) (xy 385.163697 -110.18682) (xy 385.128002 -110.14563) (xy 385.098534 -110.099778)
			(xy 385.075891 -110.050199) (xy 385.060535 -109.997902) (xy 385.052777 -109.943952) (xy 374.746418 -109.943952)
			(xy 374.751622 -109.980149) (xy 374.751622 -110.034651) (xy 374.743866 -110.088599) (xy 374.728511 -110.140894)
			(xy 374.705869 -110.190471) (xy 374.676403 -110.236321) (xy 374.640712 -110.277512) (xy 374.599521 -110.313203)
			(xy 374.553671 -110.342669) (xy 374.504094 -110.365311) (xy 374.451799 -110.380666) (xy 374.397851 -110.388422)
			(xy 374.3706 -110.388908) (xy 374.343125 -110.38842) (xy 374.288746 -110.380528) (xy 374.236064 -110.364908)
			(xy 374.186171 -110.341884) (xy 374.140102 -110.311933) (xy 374.11914 -110.294166) (xy 374.112028 -110.28807)
			(xy 374.094756 -110.281466) (xy 374.008142 -110.282228) (xy 373.991378 -110.288578) (xy 373.984266 -110.294928)
			(xy 373.963165 -110.313259) (xy 373.916593 -110.344165) (xy 373.866008 -110.367942) (xy 373.812494 -110.38408)
			(xy 373.757197 -110.392232) (xy 373.72925 -110.392718) (xy 373.702002 -110.392208) (xy 373.648061 -110.384446)
			(xy 373.595774 -110.369087) (xy 373.546204 -110.346444) (xy 373.500361 -110.316977) (xy 373.459178 -110.281286)
			(xy 373.423493 -110.240099) (xy 373.394032 -110.194252) (xy 373.371395 -110.144679) (xy 373.356043 -110.09239)
			(xy 373.348288 -110.038448) (xy 372.37315 -110.038448) (xy 372.373143 -110.038842) (xy 372.365023 -110.094018)
			(xy 372.348955 -110.147425) (xy 372.325283 -110.197922) (xy 372.29451 -110.244435) (xy 372.257293 -110.285972)
			(xy 372.214425 -110.321647) (xy 372.166819 -110.350701) (xy 372.11549 -110.372513) (xy 372.061533 -110.386619)
			(xy 372.006096 -110.392719) (xy 371.950362 -110.390682) (xy 371.895519 -110.380552) (xy 371.842735 -110.362545)
			(xy 371.793135 -110.337044) (xy 371.747777 -110.304593) (xy 371.707628 -110.265884) (xy 371.673542 -110.221741)
			(xy 371.646246 -110.173106) (xy 371.626323 -110.121015) (xy 371.614197 -110.066578) (xy 371.610126 -110.010956)
			(xy 364.635777 -110.010956) (xy 364.669501 -110.025287) (xy 364.717107 -110.054341) (xy 364.759975 -110.090016)
			(xy 364.797192 -110.131553) (xy 364.827965 -110.178066) (xy 364.851637 -110.228563) (xy 364.867705 -110.28197)
			(xy 364.875825 -110.337146) (xy 364.876334 -110.365032) (xy 364.875825 -110.392918) (xy 364.867705 -110.448094)
			(xy 364.851637 -110.501501) (xy 364.827965 -110.551998) (xy 364.797192 -110.598511) (xy 364.759975 -110.640048)
			(xy 364.717107 -110.675723) (xy 364.669501 -110.704777) (xy 364.618172 -110.726589) (xy 364.564215 -110.740695)
			(xy 364.508778 -110.746795) (xy 364.453044 -110.744758) (xy 364.398201 -110.734628) (xy 364.345417 -110.716621)
			(xy 364.295817 -110.69112) (xy 364.250459 -110.658669) (xy 364.21031 -110.61996) (xy 364.176224 -110.575817)
			(xy 364.148928 -110.527182) (xy 364.129005 -110.475091) (xy 364.116879 -110.420654) (xy 364.112808 -110.365032)
			(xy 363.860334 -110.365032) (xy 363.859825 -110.392918) (xy 363.851705 -110.448094) (xy 363.835637 -110.501501)
			(xy 363.811965 -110.551998) (xy 363.781192 -110.598511) (xy 363.743975 -110.640048) (xy 363.701107 -110.675723)
			(xy 363.653501 -110.704777) (xy 363.602172 -110.726589) (xy 363.548215 -110.740695) (xy 363.492778 -110.746795)
			(xy 363.437044 -110.744758) (xy 363.382201 -110.734628) (xy 363.329417 -110.716621) (xy 363.279817 -110.69112)
			(xy 363.234459 -110.658669) (xy 363.19431 -110.61996) (xy 363.160224 -110.575817) (xy 363.132928 -110.527182)
			(xy 363.113005 -110.475091) (xy 363.100879 -110.420654) (xy 363.096808 -110.365032) (xy 362.844334 -110.365032)
			(xy 362.843825 -110.392918) (xy 362.835705 -110.448094) (xy 362.819637 -110.501501) (xy 362.795965 -110.551998)
			(xy 362.765192 -110.598511) (xy 362.727975 -110.640048) (xy 362.685107 -110.675723) (xy 362.637501 -110.704777)
			(xy 362.586172 -110.726589) (xy 362.532215 -110.740695) (xy 362.476778 -110.746795) (xy 362.421044 -110.744758)
			(xy 362.366201 -110.734628) (xy 362.313417 -110.716621) (xy 362.263817 -110.69112) (xy 362.218459 -110.658669)
			(xy 362.17831 -110.61996) (xy 362.144224 -110.575817) (xy 362.116928 -110.527182) (xy 362.097005 -110.475091)
			(xy 362.084879 -110.420654) (xy 362.080808 -110.365032) (xy 349.690743 -110.365032) (xy 349.706829 -110.398124)
			(xy 349.72393 -110.453084) (xy 349.732582 -110.509989) (xy 349.733108 -110.538768) (xy 349.732622 -110.566019)
			(xy 349.724866 -110.619967) (xy 349.709511 -110.672262) (xy 349.686869 -110.721839) (xy 349.657403 -110.767689)
			(xy 349.621712 -110.80888) (xy 349.580521 -110.844571) (xy 349.534671 -110.874037) (xy 349.485094 -110.896679)
			(xy 349.432799 -110.912034) (xy 349.378851 -110.91979) (xy 349.324349 -110.91979) (xy 349.270401 -110.912034)
			(xy 349.218106 -110.896679) (xy 349.168529 -110.874037) (xy 349.122679 -110.844571) (xy 349.081488 -110.80888)
			(xy 349.045797 -110.767689) (xy 349.016331 -110.721839) (xy 348.993689 -110.672262) (xy 348.978334 -110.619967)
			(xy 348.970578 -110.566019) (xy 348.970092 -110.538768) (xy 348.970553 -110.510862) (xy 348.978702 -110.455648)
			(xy 348.994805 -110.402209) (xy 349.018519 -110.351685) (xy 349.04934 -110.305154) (xy 349.086609 -110.263608)
			(xy 349.10776 -110.245398) (xy 349.11665 -110.238032) (xy 349.126302 -110.217204) (xy 349.125032 -110.115096)
			(xy 349.114872 -110.094522) (xy 349.105728 -110.08741) (xy 349.083444 -110.06919) (xy 349.044037 -110.027237)
			(xy 349.01138 -109.979841) (xy 348.986215 -109.928076) (xy 348.969111 -109.873119) (xy 348.960459 -109.816215)
			(xy 348.959932 -109.787436) (xy 342.344124 -109.787436) (xy 342.361774 -109.822234) (xy 342.365939 -109.82969)
			(xy 342.378224 -109.84154) (xy 342.393703 -109.848732) (xy 342.40216 -109.84992) (xy 342.402414 -109.84992)
			(xy 342.430384 -109.853101) (xy 342.485019 -109.866667) (xy 342.537066 -109.888115) (xy 342.585395 -109.91698)
			(xy 342.628958 -109.952634) (xy 342.666807 -109.994303) (xy 342.698121 -110.041083) (xy 342.72222 -110.091957)
			(xy 342.73858 -110.14582) (xy 342.746846 -110.201503) (xy 342.747346 -110.22965) (xy 342.746775 -110.25781)
			(xy 342.738501 -110.313519) (xy 342.722127 -110.367406) (xy 342.698008 -110.4183) (xy 342.666667 -110.465095)
			(xy 342.628787 -110.506773) (xy 342.617928 -110.515654) (xy 343.028014 -110.515654) (xy 343.032085 -110.460032)
			(xy 343.044211 -110.405595) (xy 343.064134 -110.353504) (xy 343.09143 -110.304869) (xy 343.125516 -110.260726)
			(xy 343.165665 -110.222017) (xy 343.211023 -110.189566) (xy 343.260623 -110.164065) (xy 343.313407 -110.146058)
			(xy 343.36825 -110.135928) (xy 343.423984 -110.133891) (xy 343.479421 -110.139991) (xy 343.533378 -110.154097)
			(xy 343.584707 -110.175909) (xy 343.632313 -110.204963) (xy 343.675181 -110.240638) (xy 343.712398 -110.282175)
			(xy 343.743171 -110.328688) (xy 343.766843 -110.379185) (xy 343.782911 -110.432592) (xy 343.791031 -110.487768)
			(xy 343.79154 -110.515654) (xy 343.791031 -110.54354) (xy 343.782911 -110.598716) (xy 343.766843 -110.652123)
			(xy 343.743171 -110.70262) (xy 343.712398 -110.749133) (xy 343.675181 -110.79067) (xy 343.632313 -110.826345)
			(xy 343.584707 -110.855399) (xy 343.533378 -110.877211) (xy 343.479421 -110.891317) (xy 343.423984 -110.897417)
			(xy 343.36825 -110.89538) (xy 343.313407 -110.88525) (xy 343.260623 -110.867243) (xy 343.211023 -110.841742)
			(xy 343.165665 -110.809291) (xy 343.125516 -110.770582) (xy 343.09143 -110.726439) (xy 343.064134 -110.677804)
			(xy 343.044211 -110.625713) (xy 343.032085 -110.571276) (xy 343.028014 -110.515654) (xy 342.617928 -110.515654)
			(xy 342.585191 -110.542429) (xy 342.536827 -110.571287) (xy 342.484744 -110.592721) (xy 342.457532 -110.599982)
			(xy 342.448279 -110.60271) (xy 342.432614 -110.613944) (xy 342.427052 -110.621826) (xy 342.383872 -110.688374)
			(xy 342.380062 -110.706916) (xy 342.38184 -110.716822) (xy 342.384791 -110.733878) (xy 342.387971 -110.768348)
			(xy 342.38819 -110.785656) (xy 342.387704 -110.812907) (xy 342.379948 -110.866855) (xy 342.364593 -110.91915)
			(xy 342.341951 -110.968727) (xy 342.312485 -111.014577) (xy 342.276794 -111.055768) (xy 342.235603 -111.091459)
			(xy 342.189753 -111.120925) (xy 342.140176 -111.143567) (xy 342.087881 -111.158922) (xy 342.033933 -111.166678)
			(xy 341.979431 -111.166678) (xy 341.925483 -111.158922) (xy 341.873188 -111.143567) (xy 341.823611 -111.120925)
			(xy 341.777761 -111.091459) (xy 341.73657 -111.055768) (xy 341.700879 -111.014577) (xy 341.671413 -110.968727)
			(xy 341.648771 -110.91915) (xy 341.633416 -110.866855) (xy 341.62566 -110.812907) (xy 341.625174 -110.785656)
			(xy 341.625735 -110.757495) (xy 341.634009 -110.701785) (xy 341.650383 -110.647897) (xy 341.674503 -110.597002)
			(xy 341.705845 -110.550207) (xy 341.743726 -110.508529) (xy 341.787324 -110.472873) (xy 341.835691 -110.444016)
			(xy 341.887775 -110.422584) (xy 341.914988 -110.415324) (xy 341.924243 -110.412602) (xy 341.939907 -110.401364)
			(xy 341.945468 -110.39348) (xy 341.988648 -110.326932) (xy 341.992458 -110.30839) (xy 341.99068 -110.298484)
			(xy 341.98773 -110.281428) (xy 341.984549 -110.246958) (xy 341.98433 -110.22965) (xy 341.984754 -110.204118)
			(xy 341.99156 -110.153511) (xy 342.005057 -110.104264) (xy 342.025002 -110.057257) (xy 342.03767 -110.035086)
			(xy 342.044274 -110.02391) (xy 342.04529 -109.998002) (xy 342.000586 -109.909864) (xy 341.996445 -109.902392)
			(xy 341.98415 -109.890545) (xy 341.968661 -109.88336) (xy 341.9602 -109.882178) (xy 341.959946 -109.882178)
			(xy 341.931971 -109.879032) (xy 341.877336 -109.86546) (xy 341.825289 -109.844007) (xy 341.77696 -109.815138)
			(xy 341.733398 -109.779479) (xy 341.69555 -109.737806) (xy 341.664236 -109.691023) (xy 341.640139 -109.640147)
			(xy 341.623779 -109.586281) (xy 341.615514 -109.530596) (xy 341.615014 -109.502448) (xy 307.538426 -109.502448)
			(xy 307.524427 -109.531295) (xy 307.49186 -109.578657) (xy 307.472588 -109.599984) (xy 307.465984 -109.606842)
			(xy 307.458872 -109.624876) (xy 307.458872 -109.713776) (xy 307.465984 -109.73181) (xy 307.472588 -109.738668)
			(xy 307.491884 -109.759973) (xy 307.524447 -109.807339) (xy 307.549537 -109.859055) (xy 307.566584 -109.913949)
			(xy 307.575204 -109.970779) (xy 307.575201 -110.028259) (xy 307.566576 -110.085088) (xy 307.549523 -110.139981)
			(xy 307.524428 -110.191694) (xy 307.49186 -110.239057) (xy 307.472588 -110.260384) (xy 307.465984 -110.267242)
			(xy 307.458872 -110.285276) (xy 307.458872 -110.374176) (xy 307.465984 -110.39221) (xy 307.472588 -110.399068)
			(xy 307.491884 -110.420373) (xy 307.524447 -110.467739) (xy 307.549537 -110.519455) (xy 307.566584 -110.574349)
			(xy 307.573747 -110.621572) (xy 322.761102 -110.621572) (xy 322.76155 -110.595257) (xy 322.768789 -110.543128)
			(xy 322.783112 -110.492485) (xy 322.804248 -110.444286) (xy 322.831797 -110.399443) (xy 322.865239 -110.358804)
			(xy 322.884292 -110.340648) (xy 322.891717 -110.333147) (xy 322.900228 -110.313851) (xy 322.900802 -110.30331)
			(xy 322.900802 -110.228634) (xy 322.900267 -110.218085) (xy 322.891736 -110.19879) (xy 322.884292 -110.191296)
			(xy 322.86524 -110.173137) (xy 322.831783 -110.132508) (xy 322.804224 -110.087668) (xy 322.783085 -110.039468)
			(xy 322.768767 -109.988821) (xy 322.761541 -109.936688) (xy 322.761102 -109.910372) (xy 322.761588 -109.883121)
			(xy 322.769344 -109.829173) (xy 322.784699 -109.776878) (xy 322.807341 -109.727301) (xy 322.836807 -109.681451)
			(xy 322.872498 -109.64026) (xy 322.913689 -109.604569) (xy 322.959539 -109.575103) (xy 323.009116 -109.552461)
			(xy 323.061411 -109.537106) (xy 323.115359 -109.52935) (xy 323.169861 -109.52935) (xy 323.223809 -109.537106)
			(xy 323.276104 -109.552461) (xy 323.325681 -109.575103) (xy 323.371531 -109.604569) (xy 323.412722 -109.64026)
			(xy 323.448413 -109.681451) (xy 323.477879 -109.727301) (xy 323.500521 -109.776878) (xy 323.515876 -109.829173)
			(xy 323.523632 -109.883121) (xy 323.524118 -109.910372) (xy 323.523693 -109.936687) (xy 323.516449 -109.988817)
			(xy 323.502121 -110.039461) (xy 323.48098 -110.087659) (xy 323.453427 -110.132502) (xy 323.419982 -110.17314)
			(xy 323.400928 -110.191296) (xy 323.39353 -110.198821) (xy 323.385003 -110.218098) (xy 323.384418 -110.228634)
			(xy 323.384418 -110.30331) (xy 323.384923 -110.313863) (xy 323.393475 -110.333158) (xy 323.400928 -110.340648)
			(xy 323.420005 -110.358782) (xy 323.453459 -110.399417) (xy 323.481015 -110.444262) (xy 323.502149 -110.492467)
			(xy 323.516462 -110.543118) (xy 323.523682 -110.595255) (xy 323.524118 -110.621572) (xy 323.523632 -110.648823)
			(xy 323.515876 -110.702771) (xy 323.500521 -110.755066) (xy 323.477879 -110.804643) (xy 323.448413 -110.850493)
			(xy 323.412722 -110.891684) (xy 323.371531 -110.927375) (xy 323.325681 -110.956841) (xy 323.276104 -110.979483)
			(xy 323.223809 -110.994838) (xy 323.169861 -111.002594) (xy 323.115359 -111.002594) (xy 323.061411 -110.994838)
			(xy 323.009116 -110.979483) (xy 322.959539 -110.956841) (xy 322.913689 -110.927375) (xy 322.872498 -110.891684)
			(xy 322.836807 -110.850493) (xy 322.807341 -110.804643) (xy 322.784699 -110.755066) (xy 322.769344 -110.702771)
			(xy 322.761588 -110.648823) (xy 322.761102 -110.621572) (xy 307.573747 -110.621572) (xy 307.575204 -110.631179)
			(xy 307.575201 -110.688659) (xy 307.566576 -110.745488) (xy 307.549523 -110.800381) (xy 307.524428 -110.852094)
			(xy 307.49186 -110.899457) (xy 307.472588 -110.920784) (xy 307.465984 -110.927642) (xy 307.458872 -110.945676)
			(xy 307.458872 -111.034576) (xy 307.465984 -111.05261) (xy 307.472588 -111.059468) (xy 307.491884 -111.080773)
			(xy 307.524447 -111.128139) (xy 307.549537 -111.179855) (xy 307.566584 -111.234749) (xy 307.575204 -111.291579)
			(xy 307.575201 -111.349059) (xy 307.566576 -111.405888) (xy 307.549523 -111.460781) (xy 307.524428 -111.512494)
			(xy 307.49186 -111.559857) (xy 307.472588 -111.581184) (xy 307.465984 -111.588042) (xy 307.458872 -111.606076)
			(xy 307.458872 -111.694976) (xy 307.465984 -111.71301) (xy 307.472588 -111.719868) (xy 307.491875 -111.741181)
			(xy 307.524438 -111.788547) (xy 307.549527 -111.840262) (xy 307.566574 -111.895156) (xy 307.575193 -111.951986)
			(xy 307.575712 -111.980726) (xy 307.575246 -112.007978) (xy 307.567486 -112.061926) (xy 307.552128 -112.114221)
			(xy 307.529484 -112.163798) (xy 307.500016 -112.209648) (xy 307.464322 -112.250838) (xy 307.42313 -112.286529)
			(xy 307.377279 -112.315995) (xy 307.3277 -112.338636) (xy 307.275404 -112.353991) (xy 307.221456 -112.361748)
			(xy 307.194204 -112.362234) (xy 307.167891 -112.361753) (xy 307.115763 -112.354519) (xy 307.065121 -112.340202)
			(xy 307.016922 -112.319072) (xy 306.972078 -112.291529) (xy 306.931438 -112.258094) (xy 306.91328 -112.239044)
			(xy 306.905762 -112.231638) (xy 306.886479 -112.223115) (xy 306.875942 -112.222534) (xy 306.801266 -112.222534)
			(xy 306.790717 -112.223075) (xy 306.771421 -112.231601) (xy 306.763928 -112.239044) (xy 306.74576 -112.258087)
			(xy 306.705132 -112.291544) (xy 306.660294 -112.319103) (xy 306.612096 -112.340244) (xy 306.561451 -112.354564)
			(xy 306.509319 -112.361793) (xy 306.483004 -112.362234) (xy 306.455754 -112.361719) (xy 306.401809 -112.353963)
			(xy 306.349516 -112.33861) (xy 306.299941 -112.315971) (xy 306.254091 -112.286508) (xy 306.212902 -112.250819)
			(xy 306.17721 -112.209633) (xy 306.147743 -112.163786) (xy 306.125101 -112.114212) (xy 306.109743 -112.061921)
			(xy 306.101984 -112.007976) (xy 306.101496 -111.980726) (xy 304.68359 -111.980726) (xy 304.67152 -111.997482)
			(xy 304.629601 -112.039825) (xy 304.605944 -112.057942) (xy 304.599164 -112.063299) (xy 304.589434 -112.077569)
			(xy 304.585015 -112.094265) (xy 304.58537 -112.1029) (xy 304.591974 -112.188752) (xy 304.592888 -112.197266)
			(xy 304.599662 -112.212983) (xy 304.61125 -112.225579) (xy 304.618644 -112.2299) (xy 304.618898 -112.2299)
			(xy 304.641711 -112.242282) (xy 304.684004 -112.272377) (xy 304.721824 -112.30793) (xy 304.754472 -112.348285)
			(xy 304.781345 -112.392695) (xy 304.784319 -112.399572) (xy 322.761102 -112.399572) (xy 322.76155 -112.373257)
			(xy 322.768789 -112.321128) (xy 322.783112 -112.270485) (xy 322.804248 -112.222286) (xy 322.831797 -112.177443)
			(xy 322.865239 -112.136804) (xy 322.884292 -112.118648) (xy 322.891717 -112.111147) (xy 322.900228 -112.091851)
			(xy 322.900802 -112.08131) (xy 322.900802 -112.006634) (xy 322.900267 -111.996085) (xy 322.891736 -111.97679)
			(xy 322.884292 -111.969296) (xy 322.86524 -111.951137) (xy 322.831783 -111.910508) (xy 322.804224 -111.865668)
			(xy 322.783085 -111.817468) (xy 322.768767 -111.766821) (xy 322.761541 -111.714688) (xy 322.761102 -111.688372)
			(xy 322.761588 -111.661121) (xy 322.769344 -111.607173) (xy 322.784699 -111.554878) (xy 322.807341 -111.505301)
			(xy 322.836807 -111.459451) (xy 322.872498 -111.41826) (xy 322.913689 -111.382569) (xy 322.959539 -111.353103)
			(xy 323.009116 -111.330461) (xy 323.061411 -111.315106) (xy 323.115359 -111.30735) (xy 323.169861 -111.30735)
			(xy 323.223809 -111.315106) (xy 323.276104 -111.330461) (xy 323.325681 -111.353103) (xy 323.371531 -111.382569)
			(xy 323.412722 -111.41826) (xy 323.448413 -111.459451) (xy 323.477879 -111.505301) (xy 323.500521 -111.554878)
			(xy 323.515876 -111.607173) (xy 323.523632 -111.661121) (xy 323.524118 -111.688372) (xy 323.523693 -111.714687)
			(xy 323.516449 -111.766817) (xy 323.502121 -111.817461) (xy 323.48098 -111.865659) (xy 323.453427 -111.910502)
			(xy 323.419982 -111.95114) (xy 323.400928 -111.969296) (xy 323.39353 -111.976821) (xy 323.385003 -111.996098)
			(xy 323.384418 -112.006634) (xy 323.384418 -112.08131) (xy 323.384923 -112.091863) (xy 323.393475 -112.111158)
			(xy 323.400928 -112.118648) (xy 323.420005 -112.136782) (xy 323.453459 -112.177417) (xy 323.481015 -112.222262)
			(xy 323.502149 -112.270467) (xy 323.509921 -112.297972) (xy 325.26986 -112.297972) (xy 325.27029 -112.271657)
			(xy 325.277529 -112.219526) (xy 325.291855 -112.168881) (xy 325.312994 -112.120682) (xy 325.340548 -112.07584)
			(xy 325.373994 -112.035203) (xy 325.39305 -112.017048) (xy 325.400469 -112.009541) (xy 325.408985 -111.99025)
			(xy 325.40956 -111.97971) (xy 325.40956 -111.905034) (xy 325.409038 -111.894483) (xy 325.400499 -111.875187)
			(xy 325.39305 -111.867696) (xy 325.37399 -111.849545) (xy 325.340535 -111.808913) (xy 325.312978 -111.764072)
			(xy 325.291841 -111.71587) (xy 325.277524 -111.665222) (xy 325.270299 -111.613088) (xy 325.26986 -111.586772)
			(xy 325.270346 -111.559521) (xy 325.278102 -111.505573) (xy 325.293457 -111.453278) (xy 325.316099 -111.403701)
			(xy 325.345565 -111.357851) (xy 325.381256 -111.31666) (xy 325.422447 -111.280969) (xy 325.468297 -111.251503)
			(xy 325.517874 -111.228861) (xy 325.570169 -111.213506) (xy 325.624117 -111.20575) (xy 325.678619 -111.20575)
			(xy 325.732567 -111.213506) (xy 325.784862 -111.228861) (xy 325.834439 -111.251503) (xy 325.880289 -111.280969)
			(xy 325.92148 -111.31666) (xy 325.957171 -111.357851) (xy 325.986637 -111.403701) (xy 326.009279 -111.453278)
			(xy 326.024634 -111.505573) (xy 326.03239 -111.559521) (xy 326.032876 -111.586772) (xy 326.032464 -111.613088)
			(xy 326.025219 -111.665219) (xy 326.01089 -111.715863) (xy 325.989747 -111.764062) (xy 325.962191 -111.808904)
			(xy 325.928742 -111.849541) (xy 325.909686 -111.867696) (xy 325.902282 -111.875215) (xy 325.893759 -111.894497)
			(xy 325.893176 -111.905034) (xy 325.893176 -111.97971) (xy 325.893693 -111.990261) (xy 325.902238 -112.009556)
			(xy 325.909686 -112.017048) (xy 325.928755 -112.03519) (xy 325.962212 -112.075822) (xy 325.989769 -112.120665)
			(xy 326.010905 -112.168869) (xy 326.025219 -112.219519) (xy 326.03244 -112.271655) (xy 326.032876 -112.297972)
			(xy 327.30186 -112.297972) (xy 327.30229 -112.271657) (xy 327.309529 -112.219526) (xy 327.323855 -112.168881)
			(xy 327.344994 -112.120682) (xy 327.372548 -112.07584) (xy 327.405994 -112.035203) (xy 327.42505 -112.017048)
			(xy 327.432469 -112.009541) (xy 327.440985 -111.99025) (xy 327.44156 -111.97971) (xy 327.44156 -111.905034)
			(xy 327.441038 -111.894483) (xy 327.432499 -111.875187) (xy 327.42505 -111.867696) (xy 327.40599 -111.849545)
			(xy 327.372535 -111.808913) (xy 327.344978 -111.764072) (xy 327.323841 -111.71587) (xy 327.309524 -111.665222)
			(xy 327.302299 -111.613088) (xy 327.30186 -111.586772) (xy 327.302346 -111.559521) (xy 327.310102 -111.505573)
			(xy 327.325457 -111.453278) (xy 327.348099 -111.403701) (xy 327.377565 -111.357851) (xy 327.413256 -111.31666)
			(xy 327.454447 -111.280969) (xy 327.500297 -111.251503) (xy 327.549874 -111.228861) (xy 327.602169 -111.213506)
			(xy 327.656117 -111.20575) (xy 327.710619 -111.20575) (xy 327.764567 -111.213506) (xy 327.816862 -111.228861)
			(xy 327.866439 -111.251503) (xy 327.912289 -111.280969) (xy 327.95348 -111.31666) (xy 327.989171 -111.357851)
			(xy 328.018637 -111.403701) (xy 328.041279 -111.453278) (xy 328.056634 -111.505573) (xy 328.06439 -111.559521)
			(xy 328.064876 -111.586772) (xy 328.064464 -111.613088) (xy 328.057219 -111.665219) (xy 328.04289 -111.715863)
			(xy 328.021747 -111.764062) (xy 327.994191 -111.808904) (xy 327.960742 -111.849541) (xy 327.941686 -111.867696)
			(xy 327.934282 -111.875215) (xy 327.925759 -111.894497) (xy 327.925176 -111.905034) (xy 327.925176 -111.97971)
			(xy 327.925693 -111.990261) (xy 327.934238 -112.009556) (xy 327.941686 -112.017048) (xy 327.960755 -112.03519)
			(xy 327.962752 -112.037615) (xy 329.756103 -112.037615) (xy 329.760416 -111.980345) (xy 329.773262 -111.924368)
			(xy 329.79435 -111.870948) (xy 329.823205 -111.821291) (xy 329.859175 -111.776519) (xy 329.87996 -111.756698)
			(xy 329.887358 -111.749174) (xy 329.895886 -111.729896) (xy 329.89647 -111.71936) (xy 329.89647 -111.644684)
			(xy 329.895972 -111.63413) (xy 329.887416 -111.614835) (xy 329.87996 -111.607346) (xy 329.860878 -111.589218)
			(xy 329.827424 -111.548581) (xy 329.79987 -111.503735) (xy 329.778736 -111.455529) (xy 329.764425 -111.404877)
			(xy 329.757206 -111.35274) (xy 329.75677 -111.326422) (xy 329.757256 -111.299171) (xy 329.765012 -111.245223)
			(xy 329.780367 -111.192928) (xy 329.803009 -111.143351) (xy 329.832475 -111.097501) (xy 329.868166 -111.05631)
			(xy 329.909357 -111.020619) (xy 329.955207 -110.991153) (xy 330.004784 -110.968511) (xy 330.057079 -110.953156)
			(xy 330.111027 -110.9454) (xy 330.165529 -110.9454) (xy 330.219477 -110.953156) (xy 330.271772 -110.968511)
			(xy 330.321349 -110.991153) (xy 330.367199 -111.020619) (xy 330.40839 -111.05631) (xy 330.444081 -111.097501)
			(xy 330.473547 -111.143351) (xy 330.496189 -111.192928) (xy 330.511544 -111.245223) (xy 330.5193 -111.299171)
			(xy 330.519786 -111.326422) (xy 330.519338 -111.352737) (xy 330.5121 -111.404866) (xy 330.497777 -111.455509)
			(xy 330.476641 -111.503708) (xy 330.449091 -111.548551) (xy 330.415649 -111.58919) (xy 330.396596 -111.607346)
			(xy 330.389172 -111.614848) (xy 330.380661 -111.634143) (xy 330.380086 -111.644684) (xy 330.380086 -111.71936)
			(xy 330.380627 -111.729908) (xy 330.389154 -111.749203) (xy 330.396596 -111.756698) (xy 330.417407 -111.776495)
			(xy 330.453384 -111.82127) (xy 330.482245 -111.870931) (xy 330.503337 -111.924356) (xy 330.516186 -111.980339)
			(xy 330.520499 -112.037615) (xy 332.294318 -112.037615) (xy 332.298631 -111.980344) (xy 332.311478 -111.924367)
			(xy 332.332567 -111.870947) (xy 332.361424 -111.82129) (xy 332.397396 -111.776518) (xy 332.418182 -111.756698)
			(xy 332.425584 -111.749177) (xy 332.434109 -111.729897) (xy 332.434692 -111.71936) (xy 332.434692 -111.644684)
			(xy 332.434188 -111.634131) (xy 332.425635 -111.614836) (xy 332.418182 -111.607346) (xy 332.399104 -111.589213)
			(xy 332.365649 -111.548578) (xy 332.338094 -111.503733) (xy 332.316959 -111.455528) (xy 332.302647 -111.404877)
			(xy 332.295428 -111.352739) (xy 332.294992 -111.326422) (xy 332.295478 -111.299171) (xy 332.303234 -111.245223)
			(xy 332.318589 -111.192928) (xy 332.341231 -111.143351) (xy 332.370697 -111.097501) (xy 332.406388 -111.05631)
			(xy 332.447579 -111.020619) (xy 332.493429 -110.991153) (xy 332.543006 -110.968511) (xy 332.595301 -110.953156)
			(xy 332.649249 -110.9454) (xy 332.703751 -110.9454) (xy 332.757699 -110.953156) (xy 332.809994 -110.968511)
			(xy 332.859571 -110.991153) (xy 332.905421 -111.020619) (xy 332.946612 -111.05631) (xy 332.982303 -111.097501)
			(xy 333.011769 -111.143351) (xy 333.034411 -111.192928) (xy 333.049766 -111.245223) (xy 333.057522 -111.299171)
			(xy 333.058008 -111.326422) (xy 333.057553 -111.352736) (xy 333.050315 -111.404865) (xy 333.035993 -111.455508)
			(xy 333.014859 -111.503707) (xy 332.987311 -111.54855) (xy 332.95387 -111.58919) (xy 332.934818 -111.607346)
			(xy 332.927397 -111.614851) (xy 332.918883 -111.634144) (xy 332.918308 -111.644684) (xy 332.918308 -111.71936)
			(xy 332.918843 -111.729909) (xy 332.927374 -111.749205) (xy 332.934818 -111.756698) (xy 332.955628 -111.776496)
			(xy 332.991603 -111.821272) (xy 333.020462 -111.870933) (xy 333.041553 -111.924357) (xy 333.054401 -111.98034)
			(xy 333.055424 -111.993923) (xy 336.497253 -111.993923) (xy 336.501565 -111.936653) (xy 336.514411 -111.880675)
			(xy 336.535502 -111.827255) (xy 336.564359 -111.777599) (xy 336.600333 -111.732829) (xy 336.62112 -111.71301)
			(xy 336.628522 -111.705489) (xy 336.637046 -111.686208) (xy 336.63763 -111.675672) (xy 336.63763 -111.600996)
			(xy 336.637108 -111.590446) (xy 336.628567 -111.571151) (xy 336.62112 -111.563658) (xy 336.600364 -111.543805)
			(xy 336.564385 -111.499039) (xy 336.535522 -111.449386) (xy 336.514425 -111.395969) (xy 336.501572 -111.339993)
			(xy 336.497253 -111.282723) (xy 336.501565 -111.225453) (xy 336.514411 -111.169475) (xy 336.535502 -111.116055)
			(xy 336.564359 -111.066399) (xy 336.600333 -111.021629) (xy 336.62112 -111.00181) (xy 336.628522 -110.994289)
			(xy 336.637046 -110.975008) (xy 336.63763 -110.964472) (xy 336.63763 -110.889796) (xy 336.637108 -110.879246)
			(xy 336.628567 -110.859951) (xy 336.62112 -110.852458) (xy 336.602055 -110.834312) (xy 336.568598 -110.793681)
			(xy 336.54104 -110.748839) (xy 336.519903 -110.700636) (xy 336.505588 -110.649986) (xy 336.498366 -110.597851)
			(xy 336.49793 -110.571534) (xy 336.498387 -110.54428) (xy 336.50614 -110.490327) (xy 336.521494 -110.438027)
			(xy 336.544135 -110.388444) (xy 336.573603 -110.342589) (xy 336.609298 -110.301395) (xy 336.650492 -110.265701)
			(xy 336.696348 -110.236233) (xy 336.745931 -110.213593) (xy 336.798231 -110.19824) (xy 336.852184 -110.190487)
			(xy 336.879438 -110.190026) (xy 336.905753 -110.19046) (xy 336.957884 -110.1977) (xy 337.008527 -110.212025)
			(xy 337.056726 -110.233164) (xy 337.101569 -110.260717) (xy 337.142207 -110.294161) (xy 337.160362 -110.313216)
			(xy 337.167894 -110.320605) (xy 337.187166 -110.329136) (xy 337.1977 -110.329726) (xy 337.272376 -110.329726)
			(xy 337.282925 -110.32919) (xy 337.30222 -110.320659) (xy 337.309714 -110.313216) (xy 337.327873 -110.294164)
			(xy 337.368502 -110.260706) (xy 337.413341 -110.233146) (xy 337.461541 -110.212007) (xy 337.512188 -110.197689)
			(xy 337.564322 -110.190464) (xy 337.590638 -110.190026) (xy 337.617892 -110.190443) (xy 337.671844 -110.198205)
			(xy 337.724142 -110.213567) (xy 337.773721 -110.236215) (xy 337.813342 -110.261683) (xy 339.114448 -110.261683)
			(xy 339.114448 -110.209717) (xy 339.122577 -110.158392) (xy 339.138635 -110.108969) (xy 339.162226 -110.062667)
			(xy 339.192769 -110.020626) (xy 339.229514 -109.98388) (xy 339.271554 -109.953334) (xy 339.317854 -109.929741)
			(xy 339.367276 -109.913681) (xy 339.418601 -109.905549) (xy 339.444584 -109.905038) (xy 339.47123 -109.905495)
			(xy 339.523833 -109.914032) (xy 339.574384 -109.930903) (xy 339.62157 -109.955671) (xy 339.664168 -109.987694)
			(xy 339.701072 -110.026139) (xy 339.716618 -110.047786) (xy 339.724982 -110.059072) (xy 339.746655 -110.076927)
			(xy 339.772369 -110.08821) (xy 339.800184 -110.092068) (xy 339.827999 -110.08821) (xy 339.853713 -110.076927)
			(xy 339.875386 -110.059072) (xy 339.88375 -110.047786) (xy 339.899313 -110.026158) (xy 339.936232 -109.987742)
			(xy 339.978833 -109.955743) (xy 340.026014 -109.930989) (xy 340.076553 -109.91412) (xy 340.129144 -109.905574)
			(xy 340.155784 -109.905038) (xy 340.181778 -109.905428) (xy 340.233125 -109.913558) (xy 340.282569 -109.929622)
			(xy 340.328891 -109.953222) (xy 340.37095 -109.983778) (xy 340.407712 -110.020538) (xy 340.43827 -110.062596)
			(xy 340.461872 -110.108916) (xy 340.477938 -110.158359) (xy 340.486071 -110.209706) (xy 340.486071 -110.261694)
			(xy 340.477938 -110.313041) (xy 340.461872 -110.362484) (xy 340.43827 -110.408804) (xy 340.407712 -110.450862)
			(xy 340.37095 -110.487622) (xy 340.328891 -110.518178) (xy 340.282569 -110.541778) (xy 340.233125 -110.557842)
			(xy 340.181778 -110.565972) (xy 340.155784 -110.566454) (xy 340.12914 -110.56595) (xy 340.076539 -110.557423)
			(xy 340.025989 -110.540562) (xy 339.978802 -110.515803) (xy 339.936203 -110.483788) (xy 339.899297 -110.44535)
			(xy 339.88375 -110.423706) (xy 339.875386 -110.41242) (xy 339.853713 -110.394565) (xy 339.827999 -110.383282)
			(xy 339.800184 -110.379424) (xy 339.772369 -110.383282) (xy 339.746655 -110.394565) (xy 339.724982 -110.41242)
			(xy 339.716618 -110.423706) (xy 339.701011 -110.4453) (xy 339.664101 -110.483718) (xy 339.621509 -110.515721)
			(xy 339.574337 -110.540481) (xy 339.523805 -110.557357) (xy 339.471222 -110.565912) (xy 339.444584 -110.566454)
			(xy 339.418601 -110.565851) (xy 339.367276 -110.557719) (xy 339.317854 -110.541659) (xy 339.271554 -110.518066)
			(xy 339.229514 -110.48752) (xy 339.192769 -110.450774) (xy 339.162226 -110.408733) (xy 339.138635 -110.362431)
			(xy 339.122577 -110.313008) (xy 339.114448 -110.261683) (xy 337.813342 -110.261683) (xy 337.819573 -110.265688)
			(xy 337.860764 -110.301387) (xy 337.896455 -110.342584) (xy 337.92592 -110.388442) (xy 337.948558 -110.438026)
			(xy 337.96391 -110.490327) (xy 337.971663 -110.54428) (xy 337.972146 -110.571534) (xy 337.971718 -110.59785)
			(xy 337.964478 -110.64998) (xy 337.950152 -110.700625) (xy 337.929012 -110.748824) (xy 337.901458 -110.793666)
			(xy 337.868012 -110.834303) (xy 337.848956 -110.852458) (xy 337.841579 -110.860001) (xy 337.833039 -110.879264)
			(xy 337.832446 -110.889796) (xy 337.832446 -110.964472) (xy 337.832963 -110.975023) (xy 337.841505 -110.994319)
			(xy 337.848956 -111.00181) (xy 337.869776 -111.021597) (xy 337.905747 -111.066376) (xy 337.934603 -111.116039)
			(xy 337.9527 -111.161885) (xy 339.114423 -111.161885) (xy 339.114423 -111.109915) (xy 339.122553 -111.058586)
			(xy 339.138612 -111.00916) (xy 339.162205 -110.962855) (xy 339.192751 -110.92081) (xy 339.229498 -110.884061)
			(xy 339.271541 -110.853513) (xy 339.317845 -110.829918) (xy 339.36727 -110.813857) (xy 339.418599 -110.805725)
			(xy 339.444584 -110.805214) (xy 339.471229 -110.805681) (xy 339.523832 -110.814218) (xy 339.574382 -110.831088)
			(xy 339.621568 -110.855854) (xy 339.664166 -110.887874) (xy 339.701071 -110.926316) (xy 339.716618 -110.947962)
			(xy 339.724982 -110.959248) (xy 339.746655 -110.977103) (xy 339.772369 -110.988386) (xy 339.800184 -110.992244)
			(xy 339.827999 -110.988386) (xy 339.853713 -110.977103) (xy 339.875386 -110.959248) (xy 339.88375 -110.947962)
			(xy 339.899306 -110.926329) (xy 339.936227 -110.887914) (xy 339.97883 -110.855916) (xy 340.026012 -110.831163)
			(xy 340.076552 -110.814296) (xy 340.129144 -110.80575) (xy 340.155784 -110.805214) (xy 340.181776 -110.805652)
			(xy 340.23312 -110.813782) (xy 340.28256 -110.829844) (xy 340.328878 -110.853442) (xy 340.370935 -110.883996)
			(xy 340.407693 -110.920753) (xy 340.438249 -110.962808) (xy 340.46185 -111.009126) (xy 340.477914 -111.058565)
			(xy 340.486047 -111.109908) (xy 340.486047 -111.161892) (xy 340.477914 -111.213235) (xy 340.46185 -111.262674)
			(xy 340.438249 -111.308992) (xy 340.407693 -111.351047) (xy 340.370935 -111.387804) (xy 340.328878 -111.418358)
			(xy 340.28256 -111.441956) (xy 340.23312 -111.458018) (xy 340.181776 -111.466148) (xy 340.155784 -111.46663)
			(xy 340.129139 -111.466136) (xy 340.076537 -111.457609) (xy 340.025987 -111.440746) (xy 339.9788 -111.415985)
			(xy 339.936201 -111.383968) (xy 339.899296 -111.345527) (xy 339.88375 -111.323882) (xy 339.875386 -111.312596)
			(xy 339.853713 -111.294741) (xy 339.827999 -111.283458) (xy 339.800184 -111.2796) (xy 339.772369 -111.283458)
			(xy 339.746655 -111.294741) (xy 339.724982 -111.312596) (xy 339.716618 -111.323882) (xy 339.701033 -111.345493)
			(xy 339.664116 -111.383906) (xy 339.621519 -111.415905) (xy 339.574343 -111.440661) (xy 339.523808 -111.457534)
			(xy 339.471222 -111.466088) (xy 339.444584 -111.46663) (xy 339.418599 -111.466075) (xy 339.36727 -111.457943)
			(xy 339.317845 -111.441882) (xy 339.271541 -111.418287) (xy 339.229498 -111.387739) (xy 339.192751 -111.35099)
			(xy 339.162205 -111.308945) (xy 339.138612 -111.26264) (xy 339.122553 -111.213214) (xy 339.114423 -111.161885)
			(xy 337.9527 -111.161885) (xy 337.955692 -111.169465) (xy 337.968537 -111.225448) (xy 337.972849 -111.282723)
			(xy 337.96853 -111.339998) (xy 337.955678 -111.395979) (xy 337.934583 -111.449403) (xy 337.905721 -111.499063)
			(xy 337.869745 -111.543837) (xy 337.848956 -111.563658) (xy 337.841579 -111.571201) (xy 337.833039 -111.590464)
			(xy 337.832446 -111.600996) (xy 337.832446 -111.675672) (xy 337.832963 -111.686223) (xy 337.841505 -111.705519)
			(xy 337.848956 -111.71301) (xy 337.869776 -111.732797) (xy 337.905747 -111.777576) (xy 337.934603 -111.827239)
			(xy 337.955692 -111.880665) (xy 337.968537 -111.936648) (xy 337.972849 -111.993923) (xy 337.96853 -112.051198)
			(xy 337.9661 -112.061783) (xy 339.114446 -112.061783) (xy 339.114446 -112.009817) (xy 339.122575 -111.958491)
			(xy 339.138633 -111.909069) (xy 339.162224 -111.862766) (xy 339.192768 -111.820725) (xy 339.229512 -111.783978)
			(xy 339.271553 -111.753432) (xy 339.317854 -111.729839) (xy 339.367275 -111.713779) (xy 339.418601 -111.705647)
			(xy 339.444584 -111.705136) (xy 339.47123 -111.705594) (xy 339.523833 -111.714131) (xy 339.574384 -111.731002)
			(xy 339.62157 -111.75577) (xy 339.664168 -111.787792) (xy 339.701072 -111.826237) (xy 339.716618 -111.847884)
			(xy 339.724982 -111.85917) (xy 339.746655 -111.877025) (xy 339.772369 -111.888308) (xy 339.800184 -111.892166)
			(xy 339.827999 -111.888308) (xy 339.853713 -111.877025) (xy 339.875386 -111.85917) (xy 339.88375 -111.847884)
			(xy 339.899312 -111.826256) (xy 339.936231 -111.78784) (xy 339.978832 -111.755841) (xy 340.026013 -111.731087)
			(xy 340.076553 -111.714218) (xy 340.129144 -111.705672) (xy 340.155784 -111.705136) (xy 340.181778 -111.70553)
			(xy 340.233125 -111.71366) (xy 340.282568 -111.729723) (xy 340.32889 -111.753323) (xy 340.370949 -111.783879)
			(xy 340.372724 -111.785654) (xy 341.657684 -111.785654) (xy 341.661755 -111.730032) (xy 341.673881 -111.675595)
			(xy 341.693804 -111.623504) (xy 341.7211 -111.574869) (xy 341.755186 -111.530726) (xy 341.795335 -111.492017)
			(xy 341.840693 -111.459566) (xy 341.890293 -111.434065) (xy 341.943077 -111.416058) (xy 341.99792 -111.405928)
			(xy 342.053654 -111.403891) (xy 342.109091 -111.409991) (xy 342.163048 -111.424097) (xy 342.214377 -111.445909)
			(xy 342.261983 -111.474963) (xy 342.304851 -111.510638) (xy 342.342068 -111.552175) (xy 342.372841 -111.598688)
			(xy 342.396513 -111.649185) (xy 342.412581 -111.702592) (xy 342.419625 -111.750456) (xy 382.410625 -111.750456)
			(xy 382.410625 -111.695944) (xy 382.418383 -111.641988) (xy 382.433741 -111.589684) (xy 382.456387 -111.540099)
			(xy 382.485858 -111.494242) (xy 382.521557 -111.453045) (xy 382.562754 -111.417349) (xy 382.608613 -111.387879)
			(xy 382.658199 -111.365235) (xy 382.710503 -111.34988) (xy 382.76446 -111.342124) (xy 382.791716 -111.341662)
			(xy 382.817624 -111.342113) (xy 382.868962 -111.34914) (xy 382.918877 -111.363049) (xy 382.966451 -111.383583)
			(xy 383.01081 -111.410366) (xy 383.051136 -111.442904) (xy 383.086689 -111.4806) (xy 383.102104 -111.501428)
			(xy 383.107845 -111.508759) (xy 383.123347 -111.519045) (xy 383.13233 -111.521494) (xy 383.16281 -111.528352)
			(xy 383.172089 -111.530077) (xy 383.190749 -111.527351) (xy 383.199132 -111.523018) (xy 383.225104 -111.508715)
			(xy 383.279957 -111.486206) (xy 383.337262 -111.470982) (xy 383.396054 -111.463298) (xy 383.4257 -111.46282)
			(xy 383.455343 -111.463314) (xy 383.514125 -111.471037) (xy 383.571423 -111.486265) (xy 383.626283 -111.508744)
			(xy 383.652268 -111.523018) (xy 383.660684 -111.527257) (xy 383.679311 -111.529996) (xy 383.68859 -111.528352)
			(xy 383.71907 -111.521494) (xy 383.728065 -111.519074) (xy 383.743569 -111.508775) (xy 383.749296 -111.501428)
			(xy 383.764698 -111.480587) (xy 383.80024 -111.442874) (xy 383.840563 -111.410322) (xy 383.884923 -111.383533)
			(xy 383.932504 -111.362999) (xy 383.982427 -111.3491) (xy 384.033773 -111.342091) (xy 384.059684 -111.341662)
			(xy 384.086935 -111.342184) (xy 384.140884 -111.349939) (xy 384.19318 -111.365292) (xy 384.242758 -111.387932)
			(xy 384.288609 -111.417397) (xy 384.329801 -111.453088) (xy 384.365493 -111.494278) (xy 384.39496 -111.540128)
			(xy 384.417602 -111.589705) (xy 384.432958 -111.642) (xy 384.440715 -111.695949) (xy 384.440715 -111.750451)
			(xy 384.432958 -111.8044) (xy 384.417602 -111.856695) (xy 384.39496 -111.906272) (xy 384.365493 -111.952122)
			(xy 384.329801 -111.993312) (xy 384.288609 -112.029003) (xy 384.242758 -112.058468) (xy 384.19318 -112.081108)
			(xy 384.140884 -112.096461) (xy 384.086935 -112.104216) (xy 384.059684 -112.104678) (xy 384.044891 -112.104546)
			(xy 384.015393 -112.102255) (xy 384.000756 -112.100106) (xy 383.989782 -112.098961) (xy 383.968588 -112.105034)
			(xy 383.959862 -112.11179) (xy 383.901188 -112.161828) (xy 383.893152 -112.169389) (xy 383.883942 -112.189414)
			(xy 383.883408 -112.200436) (xy 383.883408 -112.504728) (xy 383.883928 -112.515749) (xy 383.89316 -112.535766)
			(xy 383.901188 -112.543336) (xy 383.959862 -112.593374) (xy 383.968544 -112.600206) (xy 383.989771 -112.606248)
			(xy 384.000756 -112.605058) (xy 384.015394 -112.602916) (xy 384.044891 -112.600629) (xy 384.059684 -112.600486)
			(xy 384.086937 -112.60096) (xy 384.140889 -112.608715) (xy 384.193188 -112.62407) (xy 384.242769 -112.646711)
			(xy 384.288624 -112.676178) (xy 384.329818 -112.711871) (xy 384.365512 -112.753063) (xy 384.394981 -112.798917)
			(xy 384.417625 -112.848497) (xy 384.432981 -112.900795) (xy 384.440739 -112.954747) (xy 384.440739 -113.009253)
			(xy 384.432981 -113.063205) (xy 384.417625 -113.115503) (xy 384.394981 -113.165083) (xy 384.365512 -113.210937)
			(xy 384.335876 -113.245138) (xy 392.969748 -113.245138) (xy 392.973819 -113.189516) (xy 392.985945 -113.135079)
			(xy 393.005868 -113.082988) (xy 393.033164 -113.034353) (xy 393.06725 -112.99021) (xy 393.107399 -112.951501)
			(xy 393.152757 -112.91905) (xy 393.202357 -112.893549) (xy 393.255141 -112.875542) (xy 393.309984 -112.865412)
			(xy 393.365718 -112.863375) (xy 393.421155 -112.869475) (xy 393.475112 -112.883581) (xy 393.526441 -112.905393)
			(xy 393.574047 -112.934447) (xy 393.616915 -112.970122) (xy 393.654132 -113.011659) (xy 393.684905 -113.058172)
			(xy 393.708577 -113.108669) (xy 393.724645 -113.162076) (xy 393.732765 -113.217252) (xy 393.733274 -113.245138)
			(xy 395.390622 -113.245138) (xy 395.394693 -113.189516) (xy 395.406819 -113.135079) (xy 395.426742 -113.082988)
			(xy 395.454038 -113.034353) (xy 395.488124 -112.99021) (xy 395.528273 -112.951501) (xy 395.573631 -112.91905)
			(xy 395.623231 -112.893549) (xy 395.676015 -112.875542) (xy 395.730858 -112.865412) (xy 395.786592 -112.863375)
			(xy 395.842029 -112.869475) (xy 395.895986 -112.883581) (xy 395.947315 -112.905393) (xy 395.994921 -112.934447)
			(xy 396.037789 -112.970122) (xy 396.075006 -113.011659) (xy 396.105779 -113.058172) (xy 396.129451 -113.108669)
			(xy 396.145519 -113.162076) (xy 396.153639 -113.217252) (xy 396.154148 -113.245138) (xy 396.153639 -113.273024)
			(xy 396.145519 -113.3282) (xy 396.129451 -113.381607) (xy 396.105779 -113.432104) (xy 396.075006 -113.478617)
			(xy 396.037789 -113.520154) (xy 395.994921 -113.555829) (xy 395.947315 -113.584883) (xy 395.895986 -113.606695)
			(xy 395.842029 -113.620801) (xy 395.786592 -113.626901) (xy 395.730858 -113.624864) (xy 395.676015 -113.614734)
			(xy 395.623231 -113.596727) (xy 395.573631 -113.571226) (xy 395.528273 -113.538775) (xy 395.488124 -113.500066)
			(xy 395.454038 -113.455923) (xy 395.426742 -113.407288) (xy 395.406819 -113.355197) (xy 395.394693 -113.30076)
			(xy 395.390622 -113.245138) (xy 393.733274 -113.245138) (xy 393.732765 -113.273024) (xy 393.724645 -113.3282)
			(xy 393.708577 -113.381607) (xy 393.684905 -113.432104) (xy 393.654132 -113.478617) (xy 393.616915 -113.520154)
			(xy 393.574047 -113.555829) (xy 393.526441 -113.584883) (xy 393.475112 -113.606695) (xy 393.421155 -113.620801)
			(xy 393.365718 -113.626901) (xy 393.309984 -113.624864) (xy 393.255141 -113.614734) (xy 393.202357 -113.596727)
			(xy 393.152757 -113.571226) (xy 393.107399 -113.538775) (xy 393.06725 -113.500066) (xy 393.033164 -113.455923)
			(xy 393.005868 -113.407288) (xy 392.985945 -113.355197) (xy 392.973819 -113.30076) (xy 392.969748 -113.245138)
			(xy 384.335876 -113.245138) (xy 384.329818 -113.252129) (xy 384.288624 -113.287822) (xy 384.242769 -113.317289)
			(xy 384.193188 -113.33993) (xy 384.140889 -113.355285) (xy 384.086937 -113.36304) (xy 384.059684 -113.363502)
			(xy 384.033777 -113.363024) (xy 383.982441 -113.355999) (xy 383.932528 -113.342093) (xy 383.884955 -113.321562)
			(xy 383.840597 -113.294784) (xy 383.800269 -113.262251) (xy 383.764713 -113.224561) (xy 383.749296 -113.203736)
			(xy 383.743563 -113.196399) (xy 383.728055 -113.186117) (xy 383.71907 -113.18367) (xy 383.68859 -113.176812)
			(xy 383.679311 -113.175079) (xy 383.66065 -113.177809) (xy 383.652268 -113.182146) (xy 383.626299 -113.196454)
			(xy 383.571444 -113.218961) (xy 383.514139 -113.234184) (xy 383.455346 -113.241866) (xy 383.4257 -113.242344)
			(xy 383.396057 -113.241855) (xy 383.337275 -113.234131) (xy 383.279977 -113.218902) (xy 383.225116 -113.196421)
			(xy 383.199132 -113.182146) (xy 383.190716 -113.177906) (xy 383.172089 -113.175168) (xy 383.16281 -113.176812)
			(xy 383.13233 -113.18367) (xy 383.123339 -113.186102) (xy 383.107834 -113.196393) (xy 383.102104 -113.203736)
			(xy 383.08672 -113.224591) (xy 383.051173 -113.262301) (xy 383.010847 -113.29485) (xy 382.966483 -113.321636)
			(xy 382.9189 -113.342168) (xy 382.868975 -113.356065) (xy 382.817628 -113.363073) (xy 382.791716 -113.363502)
			(xy 382.764462 -113.363052) (xy 382.710508 -113.355296) (xy 382.658208 -113.339942) (xy 382.608625 -113.3173)
			(xy 382.562769 -113.287832) (xy 382.521574 -113.252137) (xy 382.485878 -113.210944) (xy 382.456408 -113.165089)
			(xy 382.433764 -113.115507) (xy 382.418407 -113.063207) (xy 382.410649 -113.009254) (xy 382.410649 -112.954746)
			(xy 382.418407 -112.900793) (xy 382.433764 -112.848493) (xy 382.456408 -112.798911) (xy 382.485878 -112.753056)
			(xy 382.521574 -112.711863) (xy 382.562769 -112.676168) (xy 382.608625 -112.6467) (xy 382.658208 -112.624058)
			(xy 382.710508 -112.608704) (xy 382.764462 -112.600948) (xy 382.791716 -112.600486) (xy 382.806509 -112.600618)
			(xy 382.836007 -112.602909) (xy 382.850644 -112.605058) (xy 382.861618 -112.606211) (xy 382.882813 -112.600133)
			(xy 382.891538 -112.593374) (xy 382.950212 -112.543336) (xy 382.958219 -112.535749) (xy 382.967446 -112.515743)
			(xy 382.967992 -112.504728) (xy 382.967992 -112.200436) (xy 382.967437 -112.189419) (xy 382.95823 -112.169402)
			(xy 382.950212 -112.161828) (xy 382.891538 -112.11179) (xy 382.882852 -112.104965) (xy 382.861628 -112.098916)
			(xy 382.850644 -112.100106) (xy 382.836006 -112.102248) (xy 382.806509 -112.104535) (xy 382.791716 -112.104678)
			(xy 382.76446 -112.104276) (xy 382.710503 -112.09652) (xy 382.658199 -112.081165) (xy 382.608613 -112.058521)
			(xy 382.562754 -112.029051) (xy 382.521557 -111.993355) (xy 382.485858 -111.952158) (xy 382.456387 -111.906301)
			(xy 382.433741 -111.856716) (xy 382.418383 -111.804412) (xy 382.410625 -111.750456) (xy 342.419625 -111.750456)
			(xy 342.420701 -111.757768) (xy 342.42121 -111.785654) (xy 342.420701 -111.81354) (xy 342.412581 -111.868716)
			(xy 342.396513 -111.922123) (xy 342.372841 -111.97262) (xy 342.342068 -112.019133) (xy 342.304851 -112.06067)
			(xy 342.261983 -112.096345) (xy 342.214377 -112.125399) (xy 342.163048 -112.147211) (xy 342.109091 -112.161317)
			(xy 342.053654 -112.167417) (xy 341.99792 -112.16538) (xy 341.943077 -112.15525) (xy 341.890293 -112.137243)
			(xy 341.840693 -112.111742) (xy 341.795335 -112.079291) (xy 341.755186 -112.040582) (xy 341.7211 -111.996439)
			(xy 341.693804 -111.947804) (xy 341.673881 -111.895713) (xy 341.661755 -111.841276) (xy 341.657684 -111.785654)
			(xy 340.372724 -111.785654) (xy 340.40771 -111.820639) (xy 340.438268 -111.862697) (xy 340.461871 -111.909017)
			(xy 340.477936 -111.95846) (xy 340.486069 -112.009806) (xy 340.486069 -112.061794) (xy 340.477936 -112.11314)
			(xy 340.461871 -112.162583) (xy 340.438268 -112.208903) (xy 340.40771 -112.250961) (xy 340.370949 -112.287721)
			(xy 340.358237 -112.296956) (xy 343.094816 -112.296956) (xy 343.098887 -112.241334) (xy 343.111013 -112.186897)
			(xy 343.130936 -112.134806) (xy 343.158232 -112.086171) (xy 343.192318 -112.042028) (xy 343.232467 -112.003319)
			(xy 343.277825 -111.970868) (xy 343.327425 -111.945367) (xy 343.380209 -111.92736) (xy 343.435052 -111.91723)
			(xy 343.490786 -111.915193) (xy 343.546223 -111.921293) (xy 343.60018 -111.935399) (xy 343.651509 -111.957211)
			(xy 343.699115 -111.986265) (xy 343.741983 -112.02194) (xy 343.7792 -112.063477) (xy 343.809973 -112.10999)
			(xy 343.833645 -112.160487) (xy 343.849713 -112.213894) (xy 343.857833 -112.26907) (xy 343.858342 -112.296956)
			(xy 343.857833 -112.324842) (xy 343.849713 -112.380018) (xy 343.833645 -112.433425) (xy 343.809973 -112.483922)
			(xy 343.7792 -112.530435) (xy 343.770599 -112.540034) (xy 362.10621 -112.540034) (xy 362.106696 -112.512783)
			(xy 362.114452 -112.458835) (xy 362.129807 -112.40654) (xy 362.152449 -112.356963) (xy 362.181915 -112.311113)
			(xy 362.217606 -112.269922) (xy 362.258797 -112.234231) (xy 362.304647 -112.204765) (xy 362.354224 -112.182123)
			(xy 362.406519 -112.166768) (xy 362.460467 -112.159012) (xy 362.514969 -112.159012) (xy 362.568917 -112.166768)
			(xy 362.621212 -112.182123) (xy 362.670789 -112.204765) (xy 362.716639 -112.234231) (xy 362.75783 -112.269922)
			(xy 362.793521 -112.311113) (xy 362.822987 -112.356963) (xy 362.839894 -112.393982) (xy 364.108114 -112.393982)
			(xy 364.115867 -112.340025) (xy 364.131219 -112.287721) (xy 364.153859 -112.238133) (xy 364.183325 -112.192273)
			(xy 364.219018 -112.151072) (xy 364.260212 -112.115371) (xy 364.306066 -112.085895) (xy 364.355649 -112.063246)
			(xy 364.407951 -112.047883) (xy 364.461906 -112.04012) (xy 364.516418 -112.040114) (xy 364.570375 -112.047867)
			(xy 364.622679 -112.063219) (xy 364.672267 -112.085859) (xy 364.718127 -112.115325) (xy 364.759328 -112.151018)
			(xy 364.795029 -112.192212) (xy 364.824505 -112.238066) (xy 364.847154 -112.287649) (xy 364.862517 -112.339951)
			(xy 364.87028 -112.393906) (xy 364.870746 -112.421162) (xy 364.870746 -112.428528) (xy 364.870492 -112.442244)
			(xy 364.883954 -112.466374) (xy 364.985046 -112.524794) (xy 365.012732 -112.52454) (xy 365.02467 -112.517428)
			(xy 365.047012 -112.504457) (xy 365.094467 -112.484037) (xy 365.144245 -112.470215) (xy 365.195435 -112.463244)
			(xy 365.221266 -112.462818) (xy 365.248519 -112.463287) (xy 365.302471 -112.47104) (xy 365.354771 -112.486393)
			(xy 365.404352 -112.509034) (xy 365.450207 -112.5385) (xy 365.491401 -112.574194) (xy 365.527095 -112.615387)
			(xy 365.556563 -112.661241) (xy 365.579204 -112.710822) (xy 365.594558 -112.763121) (xy 365.602312 -112.817073)
			(xy 365.602774 -112.844326) (xy 365.602215 -112.873663) (xy 365.593216 -112.931644) (xy 365.57545 -112.987564)
			(xy 365.549334 -113.040106) (xy 365.515485 -113.088033) (xy 365.4747 -113.130214) (xy 365.451644 -113.148364)
			(xy 365.443017 -113.155591) (xy 365.432604 -113.17551) (xy 365.431578 -113.186718) (xy 365.427768 -113.276634)
			(xy 365.436404 -113.297462) (xy 365.44504 -113.305082) (xy 365.464644 -113.323221) (xy 365.499035 -113.364086)
			(xy 365.527389 -113.409349) (xy 365.549152 -113.458125) (xy 365.5639 -113.509459) (xy 365.571342 -113.562349)
			(xy 365.571786 -113.589054) (xy 365.5713 -113.616305) (xy 365.563544 -113.670253) (xy 365.548189 -113.722548)
			(xy 365.525547 -113.772125) (xy 365.520446 -113.780062) (xy 397.781524 -113.780062) (xy 397.785595 -113.72444)
			(xy 397.797721 -113.670003) (xy 397.817644 -113.617912) (xy 397.84494 -113.569277) (xy 397.879026 -113.525134)
			(xy 397.919175 -113.486425) (xy 397.964533 -113.453974) (xy 398.014133 -113.428473) (xy 398.066917 -113.410466)
			(xy 398.12176 -113.400336) (xy 398.177494 -113.398299) (xy 398.232931 -113.404399) (xy 398.286888 -113.418505)
			(xy 398.338217 -113.440317) (xy 398.385823 -113.469371) (xy 398.428691 -113.505046) (xy 398.465908 -113.546583)
			(xy 398.496681 -113.593096) (xy 398.520353 -113.643593) (xy 398.536421 -113.697) (xy 398.544541 -113.752176)
			(xy 398.54505 -113.780062) (xy 398.544541 -113.807948) (xy 398.536421 -113.863124) (xy 398.520353 -113.916531)
			(xy 398.496681 -113.967028) (xy 398.465908 -114.013541) (xy 398.428691 -114.055078) (xy 398.385823 -114.090753)
			(xy 398.338217 -114.119807) (xy 398.286888 -114.141619) (xy 398.232931 -114.155725) (xy 398.177494 -114.161825)
			(xy 398.12176 -114.159788) (xy 398.066917 -114.149658) (xy 398.014133 -114.131651) (xy 397.964533 -114.10615)
			(xy 397.919175 -114.073699) (xy 397.879026 -114.03499) (xy 397.84494 -113.990847) (xy 397.817644 -113.942212)
			(xy 397.797721 -113.890121) (xy 397.785595 -113.835684) (xy 397.781524 -113.780062) (xy 365.520446 -113.780062)
			(xy 365.496081 -113.817975) (xy 365.46039 -113.859166) (xy 365.419199 -113.894857) (xy 365.373349 -113.924323)
			(xy 365.323772 -113.946965) (xy 365.271477 -113.96232) (xy 365.217529 -113.970076) (xy 365.163027 -113.970076)
			(xy 365.109079 -113.96232) (xy 365.056784 -113.946965) (xy 365.007207 -113.924323) (xy 364.961357 -113.894857)
			(xy 364.920166 -113.859166) (xy 364.884475 -113.817975) (xy 364.855009 -113.772125) (xy 364.832367 -113.722548)
			(xy 364.817012 -113.670253) (xy 364.809256 -113.616305) (xy 364.80877 -113.589054) (xy 364.809336 -113.559717)
			(xy 364.818337 -113.501738) (xy 364.836103 -113.445819) (xy 364.862218 -113.393277) (xy 364.896064 -113.34535)
			(xy 364.936846 -113.303167) (xy 364.9599 -113.285016) (xy 364.968543 -113.277806) (xy 364.978946 -113.257874)
			(xy 364.979966 -113.246662) (xy 364.983776 -113.156746) (xy 364.97514 -113.135918) (xy 364.966504 -113.128298)
			(xy 364.946947 -113.11011) (xy 364.912551 -113.069256) (xy 364.884189 -113.024004) (xy 364.862417 -112.975238)
			(xy 364.847661 -112.923912) (xy 364.840207 -112.871029) (xy 364.839758 -112.844326) (xy 364.839758 -112.83696)
			(xy 364.840012 -112.823244) (xy 364.82655 -112.799114) (xy 364.725458 -112.740694) (xy 364.697772 -112.740948)
			(xy 364.685834 -112.74806) (xy 364.66349 -112.761028) (xy 364.616036 -112.781449) (xy 364.566258 -112.795273)
			(xy 364.515069 -112.802244) (xy 364.489238 -112.80267) (xy 364.461982 -112.802286) (xy 364.408025 -112.794533)
			(xy 364.355721 -112.779181) (xy 364.306133 -112.756541) (xy 364.260273 -112.727075) (xy 364.219072 -112.691382)
			(xy 364.183371 -112.650188) (xy 364.153895 -112.604334) (xy 364.131246 -112.554751) (xy 364.115883 -112.502449)
			(xy 364.10812 -112.448494) (xy 364.108114 -112.393982) (xy 362.839894 -112.393982) (xy 362.845629 -112.40654)
			(xy 362.860984 -112.458835) (xy 362.86874 -112.512783) (xy 362.869226 -112.540034) (xy 362.869226 -112.540542)
			(xy 362.868569 -112.571872) (xy 362.858279 -112.633683) (xy 362.838033 -112.692984) (xy 362.82376 -112.720882)
			(xy 362.817117 -112.734304) (xy 362.811179 -112.763643) (xy 362.814008 -112.793444) (xy 362.825362 -112.821141)
			(xy 362.844264 -112.844354) (xy 362.869086 -112.861084) (xy 362.897695 -112.869893) (xy 362.91266 -112.870488)
			(xy 362.939817 -112.871095) (xy 362.993544 -112.87909) (xy 363.045595 -112.894623) (xy 363.094916 -112.917382)
			(xy 363.140511 -112.946905) (xy 363.181458 -112.982597) (xy 363.216929 -113.023736) (xy 363.246207 -113.06949)
			(xy 363.268699 -113.118933) (xy 363.283952 -113.171067) (xy 363.291657 -113.224836) (xy 363.292136 -113.251996)
			(xy 363.29165 -113.279247) (xy 363.283894 -113.333195) (xy 363.268539 -113.38549) (xy 363.245897 -113.435067)
			(xy 363.216431 -113.480917) (xy 363.18074 -113.522108) (xy 363.139549 -113.557799) (xy 363.093699 -113.587265)
			(xy 363.044122 -113.609907) (xy 362.991827 -113.625262) (xy 362.937879 -113.633018) (xy 362.883377 -113.633018)
			(xy 362.829429 -113.625262) (xy 362.777134 -113.609907) (xy 362.727557 -113.587265) (xy 362.681707 -113.557799)
			(xy 362.640516 -113.522108) (xy 362.604825 -113.480917) (xy 362.575359 -113.435067) (xy 362.552717 -113.38549)
			(xy 362.537362 -113.333195) (xy 362.529606 -113.279247) (xy 362.52912 -113.251996) (xy 362.52912 -113.251488)
			(xy 362.529784 -113.220158) (xy 362.540069 -113.158347) (xy 362.560313 -113.099046) (xy 362.574586 -113.071148)
			(xy 362.581153 -113.057693) (xy 362.587091 -113.028369) (xy 362.584267 -112.998582) (xy 362.572925 -112.970896)
			(xy 362.55404 -112.94769) (xy 362.529235 -112.930959) (xy 362.500643 -112.922143) (xy 362.485686 -112.921542)
			(xy 362.458532 -112.920862) (xy 362.404809 -112.912875) (xy 362.352761 -112.897349) (xy 362.303442 -112.874597)
			(xy 362.257848 -112.845081) (xy 362.216902 -112.809397) (xy 362.18143 -112.768266) (xy 362.152151 -112.722519)
			(xy 362.129656 -112.673082) (xy 362.1144 -112.620955) (xy 362.106692 -112.567191) (xy 362.10621 -112.540034)
			(xy 343.770599 -112.540034) (xy 343.741983 -112.571972) (xy 343.699115 -112.607647) (xy 343.651509 -112.636701)
			(xy 343.60018 -112.658513) (xy 343.546223 -112.672619) (xy 343.490786 -112.678719) (xy 343.435052 -112.676682)
			(xy 343.380209 -112.666552) (xy 343.327425 -112.648545) (xy 343.277825 -112.623044) (xy 343.232467 -112.590593)
			(xy 343.192318 -112.551884) (xy 343.158232 -112.507741) (xy 343.130936 -112.459106) (xy 343.111013 -112.407015)
			(xy 343.098887 -112.352578) (xy 343.094816 -112.296956) (xy 340.358237 -112.296956) (xy 340.32889 -112.318277)
			(xy 340.282568 -112.341877) (xy 340.233125 -112.35794) (xy 340.181778 -112.36607) (xy 340.155784 -112.366552)
			(xy 340.12914 -112.366049) (xy 340.076538 -112.357522) (xy 340.025989 -112.34066) (xy 339.978802 -112.315901)
			(xy 339.936203 -112.283887) (xy 339.899297 -112.245448) (xy 339.88375 -112.223804) (xy 339.875386 -112.212518)
			(xy 339.853713 -112.194663) (xy 339.827999 -112.18338) (xy 339.800184 -112.179522) (xy 339.772369 -112.18338)
			(xy 339.746655 -112.194663) (xy 339.724982 -112.212518) (xy 339.716618 -112.223804) (xy 339.70101 -112.245398)
			(xy 339.664101 -112.283816) (xy 339.621509 -112.315819) (xy 339.574337 -112.340579) (xy 339.523805 -112.357455)
			(xy 339.471221 -112.36601) (xy 339.444584 -112.366552) (xy 339.418601 -112.365953) (xy 339.367275 -112.357821)
			(xy 339.317854 -112.341761) (xy 339.271553 -112.318168) (xy 339.229512 -112.287622) (xy 339.192768 -112.250875)
			(xy 339.162224 -112.208834) (xy 339.138633 -112.162531) (xy 339.122575 -112.113109) (xy 339.114446 -112.061783)
			(xy 337.9661 -112.061783) (xy 337.955678 -112.107179) (xy 337.934583 -112.160603) (xy 337.905721 -112.210263)
			(xy 337.869745 -112.255037) (xy 337.848956 -112.274858) (xy 337.841579 -112.282401) (xy 337.833039 -112.301664)
			(xy 337.832446 -112.312196) (xy 337.832446 -112.386872) (xy 337.832963 -112.397423) (xy 337.841505 -112.416719)
			(xy 337.848956 -112.42421) (xy 337.86802 -112.442357) (xy 337.901474 -112.48299) (xy 337.929031 -112.527832)
			(xy 337.950167 -112.576034) (xy 337.964483 -112.626683) (xy 337.971708 -112.678818) (xy 337.972146 -112.705134)
			(xy 337.971654 -112.732384) (xy 337.963894 -112.78633) (xy 337.948536 -112.838622) (xy 337.925894 -112.888197)
			(xy 337.896428 -112.934045) (xy 337.872387 -112.961789) (xy 339.114368 -112.961789) (xy 339.114368 -112.909811)
			(xy 339.122498 -112.858473) (xy 339.13856 -112.809038) (xy 339.162157 -112.762725) (xy 339.192708 -112.720674)
			(xy 339.229461 -112.683919) (xy 339.271512 -112.653365) (xy 339.317824 -112.629766) (xy 339.367257 -112.613702)
			(xy 339.418595 -112.605569) (xy 339.444584 -112.605058) (xy 339.47123 -112.605507) (xy 339.523835 -112.614044)
			(xy 339.574386 -112.630917) (xy 339.621572 -112.655686) (xy 339.66417 -112.68771) (xy 339.701073 -112.726158)
			(xy 339.716618 -112.747806) (xy 339.724982 -112.759092) (xy 339.746655 -112.776947) (xy 339.772369 -112.78823)
			(xy 339.800184 -112.792088) (xy 339.827999 -112.78823) (xy 339.853713 -112.776947) (xy 339.875386 -112.759092)
			(xy 339.88375 -112.747806) (xy 339.899289 -112.726161) (xy 339.936216 -112.687749) (xy 339.978822 -112.655755)
			(xy 340.026008 -112.631004) (xy 340.07655 -112.614139) (xy 340.129143 -112.605594) (xy 340.155784 -112.605058)
			(xy 340.181771 -112.605608) (xy 340.233107 -112.613736) (xy 340.282538 -112.629795) (xy 340.328849 -112.65339)
			(xy 340.370898 -112.683939) (xy 340.407651 -112.72069) (xy 340.438202 -112.762737) (xy 340.461798 -112.809047)
			(xy 340.47786 -112.858478) (xy 340.485991 -112.909813) (xy 340.485991 -112.961787) (xy 340.47786 -113.013122)
			(xy 340.461798 -113.062553) (xy 340.438202 -113.108863) (xy 340.407651 -113.15091) (xy 340.370898 -113.187661)
			(xy 340.328849 -113.21821) (xy 340.282538 -113.241805) (xy 340.233107 -113.257864) (xy 340.181771 -113.265992)
			(xy 340.155784 -113.266474) (xy 340.12914 -113.265961) (xy 340.07654 -113.257435) (xy 340.025991 -113.240575)
			(xy 339.978804 -113.215817) (xy 339.936205 -113.183805) (xy 339.899297 -113.145369) (xy 339.88375 -113.123726)
			(xy 339.875386 -113.11244) (xy 339.853713 -113.094585) (xy 339.827999 -113.083302) (xy 339.800184 -113.079444)
			(xy 339.772369 -113.083302) (xy 339.746655 -113.094585) (xy 339.724982 -113.11244) (xy 339.716618 -113.123726)
			(xy 339.701017 -113.145325) (xy 339.664105 -113.183741) (xy 339.621512 -113.215743) (xy 339.574339 -113.240502)
			(xy 339.523806 -113.257377) (xy 339.471222 -113.265932) (xy 339.444584 -113.266474) (xy 339.418595 -113.266031)
			(xy 339.367257 -113.257898) (xy 339.317824 -113.241834) (xy 339.271512 -113.218235) (xy 339.229461 -113.187681)
			(xy 339.192708 -113.150926) (xy 339.162157 -113.108875) (xy 339.13856 -113.062562) (xy 339.122498 -113.013127)
			(xy 339.114368 -112.961789) (xy 337.872387 -112.961789) (xy 337.860737 -112.975234) (xy 337.819549 -113.010925)
			(xy 337.773701 -113.040392) (xy 337.724126 -113.063035) (xy 337.671834 -113.078393) (xy 337.617888 -113.086154)
			(xy 337.590638 -113.086642) (xy 337.564322 -113.086234) (xy 337.51219 -113.07899) (xy 337.461545 -113.06466)
			(xy 337.413346 -113.043517) (xy 337.368504 -113.015959) (xy 337.327868 -112.982509) (xy 337.309714 -112.963452)
			(xy 337.302182 -112.956062) (xy 337.28291 -112.947529) (xy 337.272376 -112.946942) (xy 337.1977 -112.946942)
			(xy 337.187147 -112.947445) (xy 337.167851 -112.955997) (xy 337.160362 -112.963452) (xy 337.142228 -112.982529)
			(xy 337.101593 -113.015982) (xy 337.056747 -113.043537) (xy 337.008543 -113.064671) (xy 336.957892 -113.078985)
			(xy 336.905755 -113.086205) (xy 336.879438 -113.086642) (xy 336.852188 -113.086109) (xy 336.798241 -113.078359)
			(xy 336.745946 -113.063009) (xy 336.696369 -113.040373) (xy 336.650517 -113.010913) (xy 336.609325 -112.975226)
			(xy 336.573631 -112.934041) (xy 336.544161 -112.888195) (xy 336.521516 -112.838621) (xy 336.506157 -112.786329)
			(xy 336.498396 -112.732384) (xy 336.49793 -112.705134) (xy 336.498344 -112.678818) (xy 336.505588 -112.626687)
			(xy 336.519917 -112.576043) (xy 336.54106 -112.527844) (xy 336.568616 -112.483002) (xy 336.602064 -112.442365)
			(xy 336.62112 -112.42421) (xy 336.628522 -112.416689) (xy 336.637046 -112.397408) (xy 336.63763 -112.386872)
			(xy 336.63763 -112.312196) (xy 336.637108 -112.301646) (xy 336.628567 -112.282351) (xy 336.62112 -112.274858)
			(xy 336.600364 -112.255005) (xy 336.564385 -112.210239) (xy 336.535522 -112.160586) (xy 336.514425 -112.107169)
			(xy 336.501572 -112.051193) (xy 336.497253 -111.993923) (xy 333.055424 -111.993923) (xy 333.058714 -112.037615)
			(xy 333.054396 -112.09489) (xy 333.041544 -112.150871) (xy 333.020449 -112.204294) (xy 332.991586 -112.253953)
			(xy 332.955607 -112.298726) (xy 332.934818 -112.318546) (xy 332.927397 -112.326051) (xy 332.918883 -112.345344)
			(xy 332.918308 -112.355884) (xy 332.918308 -112.43056) (xy 332.918843 -112.441109) (xy 332.927374 -112.460405)
			(xy 332.934818 -112.467898) (xy 332.953869 -112.486058) (xy 332.987326 -112.526687) (xy 333.014885 -112.571527)
			(xy 333.036024 -112.619726) (xy 333.050343 -112.670373) (xy 333.057569 -112.722506) (xy 333.058008 -112.748822)
			(xy 333.057522 -112.776073) (xy 333.049766 -112.830021) (xy 333.034411 -112.882316) (xy 333.011769 -112.931893)
			(xy 332.982303 -112.977743) (xy 332.946612 -113.018934) (xy 332.905421 -113.054625) (xy 332.859571 -113.084091)
			(xy 332.809994 -113.106733) (xy 332.757699 -113.122088) (xy 332.703751 -113.129844) (xy 332.649249 -113.129844)
			(xy 332.595301 -113.122088) (xy 332.543006 -113.106733) (xy 332.493429 -113.084091) (xy 332.447579 -113.054625)
			(xy 332.406388 -113.018934) (xy 332.370697 -112.977743) (xy 332.341231 -112.931893) (xy 332.318589 -112.882316)
			(xy 332.303234 -112.830021) (xy 332.295478 -112.776073) (xy 332.294992 -112.748822) (xy 332.295477 -112.722509)
			(xy 332.302708 -112.670381) (xy 332.317024 -112.619739) (xy 332.338153 -112.57154) (xy 332.365696 -112.526696)
			(xy 332.399132 -112.486055) (xy 332.418182 -112.467898) (xy 332.425584 -112.460377) (xy 332.434109 -112.441097)
			(xy 332.434692 -112.43056) (xy 332.434692 -112.355884) (xy 332.434188 -112.345331) (xy 332.425635 -112.326036)
			(xy 332.418182 -112.318546) (xy 332.397416 -112.298704) (xy 332.361441 -112.253935) (xy 332.33258 -112.20428)
			(xy 332.311487 -112.150861) (xy 332.298636 -112.094885) (xy 332.294318 -112.037615) (xy 330.520499 -112.037615)
			(xy 330.516181 -112.094891) (xy 330.503328 -112.150872) (xy 330.482232 -112.204296) (xy 330.453367 -112.253954)
			(xy 330.417387 -112.298727) (xy 330.396596 -112.318546) (xy 330.389172 -112.326048) (xy 330.380661 -112.345343)
			(xy 330.380086 -112.355884) (xy 330.380086 -112.43056) (xy 330.380627 -112.441108) (xy 330.389154 -112.460403)
			(xy 330.396596 -112.467898) (xy 330.415643 -112.486062) (xy 330.449101 -112.52669) (xy 330.476661 -112.571528)
			(xy 330.497801 -112.619728) (xy 330.51212 -112.670374) (xy 330.519347 -112.722506) (xy 330.519786 -112.748822)
			(xy 330.5193 -112.776073) (xy 330.511544 -112.830021) (xy 330.496189 -112.882316) (xy 330.473547 -112.931893)
			(xy 330.444081 -112.977743) (xy 330.40839 -113.018934) (xy 330.367199 -113.054625) (xy 330.321349 -113.084091)
			(xy 330.271772 -113.106733) (xy 330.219477 -113.122088) (xy 330.165529 -113.129844) (xy 330.111027 -113.129844)
			(xy 330.057079 -113.122088) (xy 330.004784 -113.106733) (xy 329.955207 -113.084091) (xy 329.909357 -113.054625)
			(xy 329.868166 -113.018934) (xy 329.832475 -112.977743) (xy 329.803009 -112.931893) (xy 329.780367 -112.882316)
			(xy 329.765012 -112.830021) (xy 329.757256 -112.776073) (xy 329.75677 -112.748822) (xy 329.757262 -112.722509)
			(xy 329.764493 -112.670382) (xy 329.778808 -112.61974) (xy 329.799936 -112.571541) (xy 329.827477 -112.526697)
			(xy 329.860911 -112.486056) (xy 329.87996 -112.467898) (xy 329.887358 -112.460374) (xy 329.895886 -112.441096)
			(xy 329.89647 -112.43056) (xy 329.89647 -112.355884) (xy 329.895972 -112.34533) (xy 329.887416 -112.326035)
			(xy 329.87996 -112.318546) (xy 329.859195 -112.298703) (xy 329.823222 -112.253933) (xy 329.794363 -112.204279)
			(xy 329.773271 -112.15086) (xy 329.760421 -112.094884) (xy 329.756103 -112.037615) (xy 327.962752 -112.037615)
			(xy 327.994212 -112.075822) (xy 328.021769 -112.120665) (xy 328.042905 -112.168869) (xy 328.057219 -112.219519)
			(xy 328.06444 -112.271655) (xy 328.064876 -112.297972) (xy 328.06439 -112.325223) (xy 328.056634 -112.379171)
			(xy 328.041279 -112.431466) (xy 328.018637 -112.481043) (xy 327.989171 -112.526893) (xy 327.95348 -112.568084)
			(xy 327.912289 -112.603775) (xy 327.866439 -112.633241) (xy 327.816862 -112.655883) (xy 327.764567 -112.671238)
			(xy 327.710619 -112.678994) (xy 327.656117 -112.678994) (xy 327.602169 -112.671238) (xy 327.549874 -112.655883)
			(xy 327.500297 -112.633241) (xy 327.454447 -112.603775) (xy 327.413256 -112.568084) (xy 327.377565 -112.526893)
			(xy 327.348099 -112.481043) (xy 327.325457 -112.431466) (xy 327.310102 -112.379171) (xy 327.302346 -112.325223)
			(xy 327.30186 -112.297972) (xy 326.032876 -112.297972) (xy 326.03239 -112.325223) (xy 326.024634 -112.379171)
			(xy 326.009279 -112.431466) (xy 325.986637 -112.481043) (xy 325.957171 -112.526893) (xy 325.92148 -112.568084)
			(xy 325.880289 -112.603775) (xy 325.834439 -112.633241) (xy 325.784862 -112.655883) (xy 325.732567 -112.671238)
			(xy 325.678619 -112.678994) (xy 325.624117 -112.678994) (xy 325.570169 -112.671238) (xy 325.517874 -112.655883)
			(xy 325.468297 -112.633241) (xy 325.422447 -112.603775) (xy 325.381256 -112.568084) (xy 325.345565 -112.526893)
			(xy 325.316099 -112.481043) (xy 325.293457 -112.431466) (xy 325.278102 -112.379171) (xy 325.270346 -112.325223)
			(xy 325.26986 -112.297972) (xy 323.509921 -112.297972) (xy 323.516462 -112.321118) (xy 323.523682 -112.373255)
			(xy 323.524118 -112.399572) (xy 323.523632 -112.426823) (xy 323.515876 -112.480771) (xy 323.500521 -112.533066)
			(xy 323.477879 -112.582643) (xy 323.448413 -112.628493) (xy 323.412722 -112.669684) (xy 323.371531 -112.705375)
			(xy 323.325681 -112.734841) (xy 323.276104 -112.757483) (xy 323.223809 -112.772838) (xy 323.169861 -112.780594)
			(xy 323.115359 -112.780594) (xy 323.061411 -112.772838) (xy 323.009116 -112.757483) (xy 322.959539 -112.734841)
			(xy 322.913689 -112.705375) (xy 322.872498 -112.669684) (xy 322.836807 -112.628493) (xy 322.807341 -112.582643)
			(xy 322.784699 -112.533066) (xy 322.769344 -112.480771) (xy 322.761588 -112.426823) (xy 322.761102 -112.399572)
			(xy 304.784319 -112.399572) (xy 304.801946 -112.44034) (xy 304.815894 -112.490338) (xy 304.822932 -112.541766)
			(xy 304.823368 -112.56772) (xy 304.822882 -112.594971) (xy 304.815126 -112.648919) (xy 304.799771 -112.701214)
			(xy 304.777129 -112.750791) (xy 304.747663 -112.796641) (xy 304.711972 -112.837832) (xy 304.670781 -112.873523)
			(xy 304.624931 -112.902989) (xy 304.575354 -112.925631) (xy 304.523059 -112.940986) (xy 304.469111 -112.948742)
			(xy 304.414609 -112.948742) (xy 304.360661 -112.940986) (xy 304.308366 -112.925631) (xy 304.258789 -112.902989)
			(xy 304.212939 -112.873523) (xy 304.171748 -112.837832) (xy 304.136057 -112.796641) (xy 304.106591 -112.750791)
			(xy 304.083949 -112.701214) (xy 304.068594 -112.648919) (xy 304.060838 -112.594971) (xy 304.060352 -112.56772)
			(xy 304.060899 -112.537925) (xy 304.070162 -112.479059) (xy 304.088465 -112.42235) (xy 304.115364 -112.369177)
			(xy 304.150203 -112.320833) (xy 304.192137 -112.278494) (xy 304.2158 -112.26038) (xy 304.222559 -112.254998)
			(xy 304.232298 -112.240742) (xy 304.236725 -112.224054) (xy 304.236374 -112.215422) (xy 304.22977 -112.12957)
			(xy 304.228869 -112.121053) (xy 304.222093 -112.105333) (xy 304.210498 -112.09274) (xy 304.2031 -112.088422)
			(xy 304.202846 -112.088422) (xy 304.180052 -112.076006) (xy 304.137758 -112.045917) (xy 304.099936 -112.010369)
			(xy 304.067286 -111.97002) (xy 304.04041 -111.925615) (xy 304.019806 -111.877975) (xy 304.005855 -111.82798)
			(xy 303.998814 -111.776554) (xy 303.998376 -111.750602) (xy 303.998816 -111.723581) (xy 304.006431 -111.670077)
			(xy 304.021524 -111.618185) (xy 304.043791 -111.568943) (xy 304.072788 -111.523338) (xy 304.107932 -111.482284)
			(xy 304.127916 -111.46409) (xy 304.135877 -111.456436) (xy 304.144824 -111.436268) (xy 304.145188 -111.425228)
			(xy 304.143918 -111.348012) (xy 304.143268 -111.336998) (xy 304.133769 -111.317109) (xy 304.12563 -111.309658)
			(xy 304.104487 -111.291438) (xy 304.067211 -111.2499) (xy 304.036388 -111.203373) (xy 304.012676 -111.152849)
			(xy 303.996581 -111.099409) (xy 303.988448 -111.044194) (xy 303.987962 -111.016288) (xy 300.107829 -111.016288)
			(xy 300.123195 -111.068347) (xy 300.131023 -111.122524) (xy 300.131024 -111.177264) (xy 300.123197 -111.231441)
			(xy 300.107703 -111.283943) (xy 300.084861 -111.333689) (xy 300.055139 -111.379657) (xy 300.0375 -111.40059)
			(xy 300.037246 -111.400844) (xy 300.03167 -111.407938) (xy 300.025418 -111.424849) (xy 300.025054 -111.433864)
			(xy 300.025054 -111.50092) (xy 300.02539 -111.509939) (xy 300.031651 -111.526857) (xy 300.037246 -111.53394)
			(xy 300.0375 -111.53394) (xy 300.0375 -111.534194) (xy 300.05515 -111.555117) (xy 300.08486 -111.601093)
			(xy 300.107694 -111.650842) (xy 300.123182 -111.703345) (xy 300.131008 -111.757522) (xy 300.13148 -111.784892)
			(xy 300.130994 -111.812143) (xy 300.123238 -111.866091) (xy 300.117919 -111.884206) (xy 302.56429 -111.884206)
			(xy 302.568361 -111.828584) (xy 302.580487 -111.774147) (xy 302.60041 -111.722056) (xy 302.627706 -111.673421)
			(xy 302.661792 -111.629278) (xy 302.701941 -111.590569) (xy 302.747299 -111.558118) (xy 302.796899 -111.532617)
			(xy 302.849683 -111.51461) (xy 302.904526 -111.50448) (xy 302.96026 -111.502443) (xy 303.015697 -111.508543)
			(xy 303.069654 -111.522649) (xy 303.120983 -111.544461) (xy 303.168589 -111.573515) (xy 303.211457 -111.60919)
			(xy 303.248674 -111.650727) (xy 303.279447 -111.69724) (xy 303.303119 -111.747737) (xy 303.319187 -111.801144)
			(xy 303.327307 -111.85632) (xy 303.327816 -111.884206) (xy 303.327307 -111.912092) (xy 303.319187 -111.967268)
			(xy 303.303119 -112.020675) (xy 303.279447 -112.071172) (xy 303.248674 -112.117685) (xy 303.211457 -112.159222)
			(xy 303.168589 -112.194897) (xy 303.120983 -112.223951) (xy 303.069654 -112.245763) (xy 303.015697 -112.259869)
			(xy 302.96026 -112.265969) (xy 302.904526 -112.263932) (xy 302.849683 -112.253802) (xy 302.796899 -112.235795)
			(xy 302.747299 -112.210294) (xy 302.701941 -112.177843) (xy 302.661792 -112.139134) (xy 302.627706 -112.094991)
			(xy 302.60041 -112.046356) (xy 302.580487 -111.994265) (xy 302.568361 -111.939828) (xy 302.56429 -111.884206)
			(xy 300.117919 -111.884206) (xy 300.107883 -111.918386) (xy 300.085241 -111.967963) (xy 300.055775 -112.013813)
			(xy 300.020084 -112.055004) (xy 299.978893 -112.090695) (xy 299.933043 -112.120161) (xy 299.883466 -112.142803)
			(xy 299.831171 -112.158158) (xy 299.777223 -112.165914) (xy 299.722721 -112.165914) (xy 299.668773 -112.158158)
			(xy 299.616478 -112.142803) (xy 299.566901 -112.120161) (xy 299.521051 -112.090695) (xy 299.47986 -112.055004)
			(xy 299.444169 -112.013813) (xy 299.414703 -111.967963) (xy 299.392061 -111.918386) (xy 299.376706 -111.866091)
			(xy 299.36895 -111.812143) (xy 299.368464 -111.784892) (xy 287.079602 -111.784892) (xy 287.039988 -111.80298)
			(xy 286.98768 -111.818334) (xy 286.93372 -111.826088) (xy 286.906462 -111.826548) (xy 286.879453 -111.826119)
			(xy 286.825975 -111.818507) (xy 286.774105 -111.803429) (xy 286.724881 -111.781184) (xy 286.679287 -111.752217)
			(xy 286.638235 -111.717109) (xy 286.602546 -111.676561) (xy 286.572934 -111.631384) (xy 286.549991 -111.582481)
			(xy 286.534175 -111.530832) (xy 286.529526 -111.504222) (xy 286.528002 -111.493554) (xy 286.516572 -111.475774)
			(xy 286.445198 -111.428276) (xy 286.436259 -111.422946) (xy 286.415803 -111.419259) (xy 286.405574 -111.421164)
			(xy 286.404812 -111.421164) (xy 286.378241 -111.427272) (xy 286.324122 -111.4339) (xy 286.296862 -111.434372)
			(xy 286.269538 -111.433916) (xy 286.21529 -111.427295) (xy 286.188658 -111.421164) (xy 286.18815 -111.421164)
			(xy 286.177919 -111.419312) (xy 286.157474 -111.422982) (xy 286.148526 -111.428276) (xy 286.077152 -111.475774)
			(xy 286.065722 -111.493554) (xy 286.064198 -111.504222) (xy 286.059549 -111.530828) (xy 286.043716 -111.582465)
			(xy 286.02076 -111.631354) (xy 285.991141 -111.676519) (xy 285.955451 -111.717057) (xy 285.914401 -111.752157)
			(xy 285.868813 -111.78112) (xy 285.819597 -111.803367) (xy 285.767737 -111.818452) (xy 285.714267 -111.826076)
			(xy 285.687262 -111.826548) (xy 285.659892 -111.826058) (xy 285.605714 -111.818248) (xy 285.553211 -111.802765)
			(xy 285.503463 -111.779928) (xy 285.457496 -111.750208) (xy 285.436564 -111.732568) (xy 285.43631 -111.732314)
			(xy 285.429224 -111.726727) (xy 285.412307 -111.72048) (xy 285.40329 -111.720122) (xy 285.336234 -111.720122)
			(xy 285.327218 -111.720491) (xy 285.310301 -111.72673) (xy 285.303214 -111.732314) (xy 285.303214 -111.732568)
			(xy 285.30296 -111.732568) (xy 285.282012 -111.750187) (xy 285.236044 -111.779903) (xy 285.186301 -111.802744)
			(xy 285.133803 -111.818239) (xy 285.07963 -111.826072) (xy 285.052262 -111.826548) (xy 285.03515 -111.826354)
			(xy 285.001063 -111.823303) (xy 284.98419 -111.820452) (xy 284.972898 -111.819105) (xy 284.95101 -111.825164)
			(xy 284.942026 -111.832136) (xy 284.917642 -111.852964) (xy 284.909197 -111.860927) (xy 284.900079 -111.882249)
			(xy 284.900116 -111.893858) (xy 284.900624 -111.912908) (xy 284.900624 -112.510824) (xy 296.002454 -112.510824)
			(xy 296.006525 -112.455202) (xy 296.018651 -112.400765) (xy 296.038574 -112.348674) (xy 296.06587 -112.300039)
			(xy 296.099956 -112.255896) (xy 296.140105 -112.217187) (xy 296.185463 -112.184736) (xy 296.235063 -112.159235)
			(xy 296.287847 -112.141228) (xy 296.34269 -112.131098) (xy 296.398424 -112.129061) (xy 296.453861 -112.135161)
			(xy 296.507818 -112.149267) (xy 296.559147 -112.171079) (xy 296.606753 -112.200133) (xy 296.649621 -112.235808)
			(xy 296.686838 -112.277345) (xy 296.717611 -112.323858) (xy 296.741283 -112.374355) (xy 296.757351 -112.427762)
			(xy 296.765471 -112.482938) (xy 296.765516 -112.485424) (xy 298.851064 -112.485424) (xy 298.855135 -112.429802)
			(xy 298.867261 -112.375365) (xy 298.887184 -112.323274) (xy 298.91448 -112.274639) (xy 298.948566 -112.230496)
			(xy 298.988715 -112.191787) (xy 299.034073 -112.159336) (xy 299.083673 -112.133835) (xy 299.136457 -112.115828)
			(xy 299.1913 -112.105698) (xy 299.247034 -112.103661) (xy 299.302471 -112.109761) (xy 299.356428 -112.123867)
			(xy 299.407757 -112.145679) (xy 299.455363 -112.174733) (xy 299.498231 -112.210408) (xy 299.535448 -112.251945)
			(xy 299.566221 -112.298458) (xy 299.589893 -112.348955) (xy 299.605961 -112.402362) (xy 299.60884 -112.421924)
			(xy 301.65497 -112.421924) (xy 301.659041 -112.366302) (xy 301.671167 -112.311865) (xy 301.69109 -112.259774)
			(xy 301.718386 -112.211139) (xy 301.752472 -112.166996) (xy 301.792621 -112.128287) (xy 301.837979 -112.095836)
			(xy 301.887579 -112.070335) (xy 301.940363 -112.052328) (xy 301.995206 -112.042198) (xy 302.05094 -112.040161)
			(xy 302.106377 -112.046261) (xy 302.160334 -112.060367) (xy 302.211663 -112.082179) (xy 302.259269 -112.111233)
			(xy 302.302137 -112.146908) (xy 302.339354 -112.188445) (xy 302.370127 -112.234958) (xy 302.393799 -112.285455)
			(xy 302.409867 -112.338862) (xy 302.417987 -112.394038) (xy 302.418496 -112.421924) (xy 302.417987 -112.44981)
			(xy 302.409867 -112.504986) (xy 302.393799 -112.558393) (xy 302.370127 -112.60889) (xy 302.339354 -112.655403)
			(xy 302.302137 -112.69694) (xy 302.259269 -112.732615) (xy 302.211663 -112.761669) (xy 302.160334 -112.783481)
			(xy 302.106377 -112.797587) (xy 302.05094 -112.803687) (xy 301.995206 -112.80165) (xy 301.940363 -112.79152)
			(xy 301.887579 -112.773513) (xy 301.837979 -112.748012) (xy 301.792621 -112.715561) (xy 301.752472 -112.676852)
			(xy 301.718386 -112.632709) (xy 301.69109 -112.584074) (xy 301.671167 -112.531983) (xy 301.659041 -112.477546)
			(xy 301.65497 -112.421924) (xy 299.60884 -112.421924) (xy 299.614081 -112.457538) (xy 299.61459 -112.485424)
			(xy 299.614081 -112.51331) (xy 299.605961 -112.568486) (xy 299.589893 -112.621893) (xy 299.566221 -112.67239)
			(xy 299.535448 -112.718903) (xy 299.498231 -112.76044) (xy 299.455363 -112.796115) (xy 299.407757 -112.825169)
			(xy 299.356428 -112.846981) (xy 299.302471 -112.861087) (xy 299.247034 -112.867187) (xy 299.1913 -112.86515)
			(xy 299.136457 -112.85502) (xy 299.083673 -112.837013) (xy 299.034073 -112.811512) (xy 298.988715 -112.779061)
			(xy 298.948566 -112.740352) (xy 298.91448 -112.696209) (xy 298.887184 -112.647574) (xy 298.867261 -112.595483)
			(xy 298.855135 -112.541046) (xy 298.851064 -112.485424) (xy 296.765516 -112.485424) (xy 296.76598 -112.510824)
			(xy 296.765471 -112.53871) (xy 296.757351 -112.593886) (xy 296.741283 -112.647293) (xy 296.717611 -112.69779)
			(xy 296.686838 -112.744303) (xy 296.649621 -112.78584) (xy 296.606753 -112.821515) (xy 296.559147 -112.850569)
			(xy 296.507818 -112.872381) (xy 296.453861 -112.886487) (xy 296.398424 -112.892587) (xy 296.34269 -112.89055)
			(xy 296.287847 -112.88042) (xy 296.235063 -112.862413) (xy 296.185463 -112.836912) (xy 296.140105 -112.804461)
			(xy 296.099956 -112.765752) (xy 296.06587 -112.721609) (xy 296.038574 -112.672974) (xy 296.018651 -112.620883)
			(xy 296.006525 -112.566446) (xy 296.002454 -112.510824) (xy 284.900624 -112.510824) (xy 284.900624 -112.776508)
			(xy 284.900116 -112.79632) (xy 284.90015 -112.807912) (xy 284.909268 -112.829199) (xy 284.917642 -112.837214)
			(xy 284.942026 -112.858296) (xy 284.951015 -112.865391) (xy 284.973106 -112.871338) (xy 284.984444 -112.869726)
			(xy 285.001251 -112.866859) (xy 285.035213 -112.86381) (xy 285.052262 -112.86363) (xy 285.079519 -112.864014)
			(xy 285.13348 -112.871768) (xy 285.185788 -112.887122) (xy 285.235377 -112.909765) (xy 285.28124 -112.939235)
			(xy 285.322441 -112.974932) (xy 285.358143 -113.01613) (xy 285.387617 -113.061989) (xy 285.410265 -113.111577)
			(xy 285.425624 -113.163883) (xy 285.433383 -113.217843) (xy 285.433383 -113.251742) (xy 296.506136 -113.251742)
			(xy 296.510207 -113.19612) (xy 296.522333 -113.141683) (xy 296.542256 -113.089592) (xy 296.569552 -113.040957)
			(xy 296.603638 -112.996814) (xy 296.643787 -112.958105) (xy 296.689145 -112.925654) (xy 296.738745 -112.900153)
			(xy 296.791529 -112.882146) (xy 296.846372 -112.872016) (xy 296.902106 -112.869979) (xy 296.957543 -112.876079)
			(xy 297.0115 -112.890185) (xy 297.062829 -112.911997) (xy 297.110435 -112.941051) (xy 297.153303 -112.976726)
			(xy 297.164851 -112.989614) (xy 302.639982 -112.989614) (xy 302.644053 -112.933992) (xy 302.656179 -112.879555)
			(xy 302.676102 -112.827464) (xy 302.703398 -112.778829) (xy 302.737484 -112.734686) (xy 302.777633 -112.695977)
			(xy 302.822991 -112.663526) (xy 302.872591 -112.638025) (xy 302.925375 -112.620018) (xy 302.980218 -112.609888)
			(xy 303.035952 -112.607851) (xy 303.091389 -112.613951) (xy 303.145346 -112.628057) (xy 303.196675 -112.649869)
			(xy 303.244281 -112.678923) (xy 303.287149 -112.714598) (xy 303.324366 -112.756135) (xy 303.355139 -112.802648)
			(xy 303.378811 -112.853145) (xy 303.394879 -112.906552) (xy 303.402999 -112.961728) (xy 303.403508 -112.989614)
			(xy 303.402999 -113.0175) (xy 303.394879 -113.072676) (xy 303.378811 -113.126083) (xy 303.355139 -113.17658)
			(xy 303.324366 -113.223093) (xy 303.290731 -113.260632) (xy 307.638702 -113.260632) (xy 307.642773 -113.20501)
			(xy 307.654899 -113.150573) (xy 307.674822 -113.098482) (xy 307.702118 -113.049847) (xy 307.736204 -113.005704)
			(xy 307.776353 -112.966995) (xy 307.821711 -112.934544) (xy 307.871311 -112.909043) (xy 307.924095 -112.891036)
			(xy 307.978938 -112.880906) (xy 308.034672 -112.878869) (xy 308.090109 -112.884969) (xy 308.144066 -112.899075)
			(xy 308.195395 -112.920887) (xy 308.243001 -112.949941) (xy 308.285869 -112.985616) (xy 308.323086 -113.027153)
			(xy 308.353859 -113.073666) (xy 308.377531 -113.124163) (xy 308.393599 -113.17757) (xy 308.4013 -113.229898)
			(xy 308.642002 -113.229898) (xy 308.646073 -113.174276) (xy 308.658199 -113.119839) (xy 308.678122 -113.067748)
			(xy 308.705418 -113.019113) (xy 308.739504 -112.97497) (xy 308.779653 -112.936261) (xy 308.825011 -112.90381)
			(xy 308.874611 -112.878309) (xy 308.927395 -112.860302) (xy 308.982238 -112.850172) (xy 309.037972 -112.848135)
			(xy 309.093409 -112.854235) (xy 309.147366 -112.868341) (xy 309.198695 -112.890153) (xy 309.246301 -112.919207)
			(xy 309.289169 -112.954882) (xy 309.326386 -112.996419) (xy 309.357159 -113.042932) (xy 309.380831 -113.093429)
			(xy 309.396899 -113.146836) (xy 309.405019 -113.202012) (xy 309.405528 -113.229898) (xy 309.405019 -113.257784)
			(xy 309.396899 -113.31296) (xy 309.380831 -113.366367) (xy 309.357159 -113.416864) (xy 309.326386 -113.463377)
			(xy 309.289169 -113.504914) (xy 309.246301 -113.540589) (xy 309.198695 -113.569643) (xy 309.147366 -113.591455)
			(xy 309.093409 -113.605561) (xy 309.037972 -113.611661) (xy 308.982238 -113.609624) (xy 308.927395 -113.599494)
			(xy 308.874611 -113.581487) (xy 308.825011 -113.555986) (xy 308.779653 -113.523535) (xy 308.739504 -113.484826)
			(xy 308.705418 -113.440683) (xy 308.678122 -113.392048) (xy 308.658199 -113.339957) (xy 308.646073 -113.28552)
			(xy 308.642002 -113.229898) (xy 308.4013 -113.229898) (xy 308.401719 -113.232746) (xy 308.402228 -113.260632)
			(xy 308.401719 -113.288518) (xy 308.393599 -113.343694) (xy 308.377531 -113.397101) (xy 308.353859 -113.447598)
			(xy 308.323086 -113.494111) (xy 308.285869 -113.535648) (xy 308.243001 -113.571323) (xy 308.195395 -113.600377)
			(xy 308.144066 -113.622189) (xy 308.090109 -113.636295) (xy 308.034672 -113.642395) (xy 307.978938 -113.640358)
			(xy 307.924095 -113.630228) (xy 307.871311 -113.612221) (xy 307.821711 -113.58672) (xy 307.776353 -113.554269)
			(xy 307.736204 -113.51556) (xy 307.702118 -113.471417) (xy 307.674822 -113.422782) (xy 307.654899 -113.370691)
			(xy 307.642773 -113.316254) (xy 307.638702 -113.260632) (xy 303.290731 -113.260632) (xy 303.287149 -113.26463)
			(xy 303.244281 -113.300305) (xy 303.196675 -113.329359) (xy 303.145346 -113.351171) (xy 303.091389 -113.365277)
			(xy 303.035952 -113.371377) (xy 302.980218 -113.36934) (xy 302.925375 -113.35921) (xy 302.872591 -113.341203)
			(xy 302.822991 -113.315702) (xy 302.777633 -113.283251) (xy 302.737484 -113.244542) (xy 302.703398 -113.200399)
			(xy 302.676102 -113.151764) (xy 302.656179 -113.099673) (xy 302.644053 -113.045236) (xy 302.639982 -112.989614)
			(xy 297.164851 -112.989614) (xy 297.19052 -113.018263) (xy 297.221293 -113.064776) (xy 297.244965 -113.115273)
			(xy 297.261033 -113.16868) (xy 297.269153 -113.223856) (xy 297.269662 -113.251742) (xy 297.269153 -113.279628)
			(xy 297.261033 -113.334804) (xy 297.244965 -113.388211) (xy 297.22297 -113.43513) (xy 299.130718 -113.43513)
			(xy 299.134789 -113.379508) (xy 299.146915 -113.325071) (xy 299.166838 -113.27298) (xy 299.194134 -113.224345)
			(xy 299.22822 -113.180202) (xy 299.268369 -113.141493) (xy 299.313727 -113.109042) (xy 299.363327 -113.083541)
			(xy 299.416111 -113.065534) (xy 299.470954 -113.055404) (xy 299.526688 -113.053367) (xy 299.582125 -113.059467)
			(xy 299.636082 -113.073573) (xy 299.687411 -113.095385) (xy 299.735017 -113.124439) (xy 299.777885 -113.160114)
			(xy 299.815102 -113.201651) (xy 299.845875 -113.248164) (xy 299.869547 -113.298661) (xy 299.885615 -113.352068)
			(xy 299.893735 -113.407244) (xy 299.894244 -113.43513) (xy 299.894193 -113.437924) (xy 301.557688 -113.437924)
			(xy 301.561759 -113.382302) (xy 301.573885 -113.327865) (xy 301.593808 -113.275774) (xy 301.621104 -113.227139)
			(xy 301.65519 -113.182996) (xy 301.695339 -113.144287) (xy 301.740697 -113.111836) (xy 301.790297 -113.086335)
			(xy 301.843081 -113.068328) (xy 301.897924 -113.058198) (xy 301.953658 -113.056161) (xy 302.009095 -113.062261)
			(xy 302.063052 -113.076367) (xy 302.114381 -113.098179) (xy 302.161987 -113.127233) (xy 302.204855 -113.162908)
			(xy 302.242072 -113.204445) (xy 302.272845 -113.250958) (xy 302.296517 -113.301455) (xy 302.312585 -113.354862)
			(xy 302.320705 -113.410038) (xy 302.321214 -113.437924) (xy 302.320705 -113.46581) (xy 302.312585 -113.520986)
			(xy 302.296517 -113.574393) (xy 302.272845 -113.62489) (xy 302.248661 -113.661444) (xy 320.070224 -113.661444)
			(xy 320.074295 -113.605822) (xy 320.086421 -113.551385) (xy 320.106344 -113.499294) (xy 320.13364 -113.450659)
			(xy 320.167726 -113.406516) (xy 320.207875 -113.367807) (xy 320.253233 -113.335356) (xy 320.302833 -113.309855)
			(xy 320.355617 -113.291848) (xy 320.41046 -113.281718) (xy 320.466194 -113.279681) (xy 320.521631 -113.285781)
			(xy 320.575588 -113.299887) (xy 320.626917 -113.321699) (xy 320.674523 -113.350753) (xy 320.717391 -113.386428)
			(xy 320.754608 -113.427965) (xy 320.785381 -113.474478) (xy 320.809053 -113.524975) (xy 320.825121 -113.578382)
			(xy 320.833241 -113.633558) (xy 320.83375 -113.661444) (xy 320.833241 -113.68933) (xy 320.825121 -113.744506)
			(xy 320.809053 -113.797913) (xy 320.785381 -113.84841) (xy 320.754608 -113.894923) (xy 320.717391 -113.93646)
			(xy 320.674523 -113.972135) (xy 320.626917 -114.001189) (xy 320.575588 -114.023001) (xy 320.521631 -114.037107)
			(xy 320.466194 -114.043207) (xy 320.41046 -114.04117) (xy 320.355617 -114.03104) (xy 320.302833 -114.013033)
			(xy 320.253233 -113.987532) (xy 320.207875 -113.955081) (xy 320.167726 -113.916372) (xy 320.13364 -113.872229)
			(xy 320.106344 -113.823594) (xy 320.086421 -113.771503) (xy 320.074295 -113.717066) (xy 320.070224 -113.661444)
			(xy 302.248661 -113.661444) (xy 302.242072 -113.671403) (xy 302.204855 -113.71294) (xy 302.161987 -113.748615)
			(xy 302.114381 -113.777669) (xy 302.063052 -113.799481) (xy 302.009095 -113.813587) (xy 301.953658 -113.819687)
			(xy 301.897924 -113.81765) (xy 301.843081 -113.80752) (xy 301.790297 -113.789513) (xy 301.740697 -113.764012)
			(xy 301.695339 -113.731561) (xy 301.65519 -113.692852) (xy 301.621104 -113.648709) (xy 301.593808 -113.600074)
			(xy 301.573885 -113.547983) (xy 301.561759 -113.493546) (xy 301.557688 -113.437924) (xy 299.894193 -113.437924)
			(xy 299.893735 -113.463016) (xy 299.885615 -113.518192) (xy 299.869547 -113.571599) (xy 299.845875 -113.622096)
			(xy 299.815102 -113.668609) (xy 299.777885 -113.710146) (xy 299.735017 -113.745821) (xy 299.687411 -113.774875)
			(xy 299.636082 -113.796687) (xy 299.582125 -113.810793) (xy 299.526688 -113.816893) (xy 299.470954 -113.814856)
			(xy 299.416111 -113.804726) (xy 299.363327 -113.786719) (xy 299.313727 -113.761218) (xy 299.268369 -113.728767)
			(xy 299.22822 -113.690058) (xy 299.194134 -113.645915) (xy 299.166838 -113.59728) (xy 299.146915 -113.545189)
			(xy 299.134789 -113.490752) (xy 299.130718 -113.43513) (xy 297.22297 -113.43513) (xy 297.221293 -113.438708)
			(xy 297.19052 -113.485221) (xy 297.153303 -113.526758) (xy 297.110435 -113.562433) (xy 297.062829 -113.591487)
			(xy 297.0115 -113.613299) (xy 296.957543 -113.627405) (xy 296.902106 -113.633505) (xy 296.846372 -113.631468)
			(xy 296.791529 -113.621338) (xy 296.738745 -113.603331) (xy 296.689145 -113.57783) (xy 296.643787 -113.545379)
			(xy 296.603638 -113.50667) (xy 296.569552 -113.462527) (xy 296.542256 -113.413892) (xy 296.522333 -113.361801)
			(xy 296.510207 -113.307364) (xy 296.506136 -113.251742) (xy 285.433383 -113.251742) (xy 285.433383 -113.272357)
			(xy 285.425624 -113.326317) (xy 285.410265 -113.378623) (xy 285.387617 -113.428211) (xy 285.358143 -113.47407)
			(xy 285.322441 -113.515268) (xy 285.28124 -113.550965) (xy 285.235377 -113.580435) (xy 285.185788 -113.603078)
			(xy 285.13348 -113.618432) (xy 285.079519 -113.626186) (xy 285.052262 -113.626646) (xy 285.025253 -113.626218)
			(xy 284.971775 -113.618607) (xy 284.919905 -113.603528) (xy 284.870681 -113.581283) (xy 284.825087 -113.552317)
			(xy 284.784035 -113.517208) (xy 284.748346 -113.47666) (xy 284.718734 -113.431483) (xy 284.69579 -113.38258)
			(xy 284.679975 -113.33093) (xy 284.675326 -113.30432) (xy 284.673802 -113.293652) (xy 284.662372 -113.275872)
			(xy 284.590998 -113.228374) (xy 284.582059 -113.223044) (xy 284.561604 -113.219357) (xy 284.551374 -113.221262)
			(xy 284.550612 -113.221262) (xy 284.524034 -113.227308) (xy 284.469915 -113.233805) (xy 284.442662 -113.234216)
			(xy 284.415344 -113.233825) (xy 284.361096 -113.227334) (xy 284.334458 -113.221262) (xy 284.33395 -113.221262)
			(xy 284.323719 -113.21941) (xy 284.303274 -113.22308) (xy 284.294326 -113.228374) (xy 284.222952 -113.275872)
			(xy 284.211522 -113.293652) (xy 284.209998 -113.30432) (xy 284.205348 -113.330926) (xy 284.189514 -113.382563)
			(xy 284.166559 -113.431452) (xy 284.13694 -113.476617) (xy 284.10125 -113.517154) (xy 284.060201 -113.552255)
			(xy 284.014613 -113.581218) (xy 283.965397 -113.603465) (xy 283.913537 -113.61855) (xy 283.860067 -113.626174)
			(xy 283.833062 -113.626646) (xy 283.805815 -113.626081) (xy 283.751877 -113.618321) (xy 283.699592 -113.602964)
			(xy 283.650025 -113.580323) (xy 283.604184 -113.550859) (xy 283.563002 -113.515171) (xy 283.527318 -113.473986)
			(xy 283.497859 -113.428142) (xy 283.475222 -113.378572) (xy 283.459871 -113.326286) (xy 283.452116 -113.272347)
			(xy 283.452116 -113.217853) (xy 283.459871 -113.163914) (xy 283.475222 -113.111628) (xy 283.497859 -113.062058)
			(xy 283.527318 -113.016214) (xy 283.563002 -112.975029) (xy 283.604184 -112.939341) (xy 283.650025 -112.909877)
			(xy 283.699592 -112.887236) (xy 283.751877 -112.871879) (xy 283.805815 -112.864119) (xy 283.833062 -112.86363)
			(xy 283.85011 -112.863827) (xy 283.88407 -112.866882) (xy 283.90088 -112.869726) (xy 283.912207 -112.871168)
			(xy 283.934225 -112.865229) (xy 283.943298 -112.858296) (xy 283.967682 -112.837214) (xy 283.976093 -112.829221)
			(xy 283.985229 -112.807922) (xy 283.985208 -112.79632) (xy 283.9847 -112.776508) (xy 283.9847 -111.912908)
			(xy 283.985208 -111.893858) (xy 283.985179 -111.882266) (xy 283.976057 -111.860979) (xy 283.967682 -111.852964)
			(xy 283.943298 -111.832136) (xy 283.93431 -111.825161) (xy 283.912425 -111.819076) (xy 283.901134 -111.820452)
			(xy 283.884263 -111.823319) (xy 283.850174 -111.826374) (xy 283.833062 -111.826548) (xy 283.805815 -111.825979)
			(xy 283.751878 -111.818219) (xy 283.699593 -111.802862) (xy 283.650026 -111.780221) (xy 283.604185 -111.750757)
			(xy 283.563004 -111.71507) (xy 283.52732 -111.673885) (xy 283.49786 -111.628041) (xy 283.475224 -111.578471)
			(xy 283.459873 -111.526185) (xy 283.452118 -111.472247) (xy 283.452118 -111.417753) (xy 283.459873 -111.363815)
			(xy 283.475224 -111.311529) (xy 283.49786 -111.261959) (xy 283.52732 -111.216115) (xy 283.563004 -111.17493)
			(xy 283.604185 -111.139243) (xy 283.650026 -111.109779) (xy 283.699593 -111.087138) (xy 283.751878 -111.071781)
			(xy 283.805815 -111.064021) (xy 283.833062 -111.063532) (xy 283.86004 -111.063965) (xy 283.91346 -111.071554)
			(xy 283.965276 -111.0866) (xy 284.014452 -111.108803) (xy 284.060006 -111.137717) (xy 284.101028 -111.172767)
			(xy 284.136697 -111.213251) (xy 284.166302 -111.25836) (xy 284.189249 -111.307193) (xy 284.205082 -111.358774)
			(xy 284.209744 -111.38535) (xy 284.2119 -111.395582) (xy 284.223187 -111.413159) (xy 284.231588 -111.419386)
			(xy 284.302962 -111.466884) (xy 284.324044 -111.470694) (xy 284.334204 -111.468154) (xy 284.360906 -111.462083)
			(xy 284.415281 -111.455587) (xy 284.442662 -111.4552) (xy 284.470044 -111.455568) (xy 284.52442 -111.462068)
			(xy 284.55112 -111.468154) (xy 284.56128 -111.470694) (xy 284.582362 -111.466884) (xy 284.662626 -111.413544)
			(xy 284.673802 -111.396018) (xy 284.67558 -111.38535) (xy 284.680206 -111.358771) (xy 284.696067 -111.307205)
			(xy 284.719035 -111.258388) (xy 284.748652 -111.213294) (xy 284.784328 -111.172822) (xy 284.82535 -111.137782)
			(xy 284.870899 -111.10887) (xy 284.920068 -111.086664) (xy 284.971875 -111.071608) (xy 285.025287 -111.064001)
			(xy 285.052262 -111.063532) (xy 285.079632 -111.064013) (xy 285.133811 -111.071826) (xy 285.186314 -111.087311)
			(xy 285.236061 -111.11015) (xy 285.282028 -111.139872) (xy 285.30296 -111.157512) (xy 285.303214 -111.157766)
			(xy 285.310287 -111.163372) (xy 285.327214 -111.169605) (xy 285.336234 -111.169958) (xy 285.40329 -111.169958)
			(xy 285.412307 -111.169605) (xy 285.429225 -111.163356) (xy 285.43631 -111.157766) (xy 285.43631 -111.157512)
			(xy 285.436564 -111.157512) (xy 285.4575 -111.139878) (xy 285.503472 -111.110165) (xy 285.553218 -111.087328)
			(xy 285.605718 -111.071836) (xy 285.659893 -111.064006) (xy 285.687262 -111.063532) (xy 285.70431 -111.063729)
			(xy 285.73827 -111.066784) (xy 285.75508 -111.069628) (xy 285.766407 -111.071069) (xy 285.788425 -111.065131)
			(xy 285.797498 -111.058198) (xy 285.821882 -111.037116) (xy 285.830292 -111.029122) (xy 285.839428 -111.007824)
			(xy 285.839408 -110.996222) (xy 285.8389 -110.97641) (xy 285.8389 -110.11281) (xy 285.839408 -110.09376)
			(xy 285.839378 -110.082168) (xy 285.830257 -110.060881) (xy 285.821882 -110.052866) (xy 285.797498 -110.032038)
			(xy 285.788517 -110.025053) (xy 285.766627 -110.018978) (xy 285.755334 -110.020354) (xy 285.738463 -110.023221)
			(xy 285.704374 -110.026276) (xy 285.687262 -110.02645) (xy 285.659892 -110.02596) (xy 285.605714 -110.01815)
			(xy 285.553211 -110.002667) (xy 285.503463 -109.97983) (xy 285.457496 -109.95011) (xy 285.436564 -109.93247)
			(xy 285.43631 -109.932216) (xy 285.429223 -109.926629) (xy 285.412307 -109.920382) (xy 285.40329 -109.920024)
			(xy 285.336234 -109.920024) (xy 285.327218 -109.920392) (xy 285.310301 -109.926632) (xy 285.303214 -109.932216)
			(xy 285.303214 -109.93247) (xy 285.30296 -109.93247) (xy 285.282012 -109.95009) (xy 285.236044 -109.979806)
			(xy 285.186301 -110.002646) (xy 285.133803 -110.018141) (xy 285.07963 -110.025974) (xy 285.052262 -110.02645)
			(xy 285.025253 -110.026019) (xy 284.971775 -110.018408) (xy 284.919906 -110.003329) (xy 284.870682 -109.981084)
			(xy 284.825088 -109.952118) (xy 284.784036 -109.91701) (xy 284.748347 -109.876462) (xy 284.718735 -109.831285)
			(xy 284.695791 -109.782383) (xy 284.679975 -109.730733) (xy 284.675326 -109.704124) (xy 284.673802 -109.693456)
			(xy 284.662372 -109.675676) (xy 284.590998 -109.628178) (xy 284.582059 -109.622848) (xy 284.561603 -109.619161)
			(xy 284.551374 -109.621066) (xy 284.550612 -109.621066) (xy 284.524034 -109.627113) (xy 284.469915 -109.633609)
			(xy 284.442662 -109.63402) (xy 284.415344 -109.633629) (xy 284.361096 -109.627138) (xy 284.334458 -109.621066)
			(xy 284.33395 -109.621066) (xy 284.32372 -109.619213) (xy 284.303274 -109.622884) (xy 284.294326 -109.628178)
			(xy 284.222952 -109.675676) (xy 284.211522 -109.693456) (xy 284.209998 -109.704124) (xy 284.205351 -109.73073)
			(xy 284.189517 -109.782367) (xy 284.166561 -109.831257) (xy 284.136942 -109.876421) (xy 284.101251 -109.916959)
			(xy 284.060202 -109.95206) (xy 284.014614 -109.981022) (xy 283.965398 -110.003269) (xy 283.913537 -110.018354)
			(xy 283.860067 -110.025978) (xy 283.833062 -110.02645) (xy 283.805816 -110.025877) (xy 283.751878 -110.018117)
			(xy 283.699594 -110.00276) (xy 283.650027 -109.98012) (xy 283.604186 -109.950656) (xy 283.563005 -109.914968)
			(xy 283.527322 -109.873783) (xy 283.497862 -109.82794) (xy 283.475226 -109.778371) (xy 283.459875 -109.726085)
			(xy 283.45212 -109.672146) (xy 283.45212 -109.617654) (xy 283.459875 -109.563715) (xy 283.475226 -109.511429)
			(xy 283.497862 -109.46186) (xy 283.527322 -109.416017) (xy 283.563005 -109.374832) (xy 283.604186 -109.339144)
			(xy 283.650027 -109.30968) (xy 283.699594 -109.28704) (xy 283.751878 -109.271683) (xy 283.805816 -109.263923)
			(xy 283.833062 -109.263434) (xy 283.85011 -109.263631) (xy 283.88407 -109.266686) (xy 283.90088 -109.26953)
			(xy 283.912207 -109.270971) (xy 283.934225 -109.265033) (xy 283.943298 -109.2581) (xy 283.967682 -109.237018)
			(xy 283.976091 -109.229023) (xy 283.985228 -109.207726) (xy 283.985208 -109.196124) (xy 283.9847 -109.176312)
			(xy 283.9847 -108.312712) (xy 283.985208 -108.293662) (xy 283.985177 -108.28207) (xy 283.976056 -108.260783)
			(xy 283.967682 -108.252768) (xy 283.943298 -108.23194) (xy 283.934317 -108.224955) (xy 283.912427 -108.21888)
			(xy 283.901134 -108.220256) (xy 283.884263 -108.223123) (xy 283.850174 -108.226178) (xy 283.833062 -108.226352)
			(xy 283.805816 -108.225775) (xy 283.751878 -108.218015) (xy 283.699594 -108.202659) (xy 283.650028 -108.180018)
			(xy 283.604187 -108.150554) (xy 283.563006 -108.114867) (xy 283.527323 -108.073682) (xy 283.497864 -108.027839)
			(xy 283.475228 -107.97827) (xy 283.459877 -107.925984) (xy 283.452122 -107.872046) (xy 283.452122 -107.817554)
			(xy 283.459877 -107.763616) (xy 283.475228 -107.71133) (xy 283.497864 -107.661761) (xy 283.527323 -107.615918)
			(xy 283.563006 -107.574733) (xy 283.604187 -107.539046) (xy 283.650028 -107.509582) (xy 283.699594 -107.486941)
			(xy 283.751878 -107.471585) (xy 283.805816 -107.463825) (xy 283.833062 -107.463336) (xy 283.86004 -107.463766)
			(xy 283.91346 -107.471355) (xy 283.965276 -107.486401) (xy 284.014453 -107.508604) (xy 284.060007 -107.537519)
			(xy 284.101029 -107.572569) (xy 284.136698 -107.613053) (xy 284.166303 -107.658163) (xy 284.18925 -107.706996)
			(xy 284.205082 -107.758578) (xy 284.209744 -107.785154) (xy 284.211898 -107.795386) (xy 284.223186 -107.812963)
			(xy 284.231588 -107.81919) (xy 284.302962 -107.866688) (xy 284.324044 -107.870498) (xy 284.334204 -107.867958)
			(xy 284.360906 -107.861887) (xy 284.415281 -107.855391) (xy 284.442662 -107.855004) (xy 284.470044 -107.855372)
			(xy 284.52442 -107.861872) (xy 284.55112 -107.867958) (xy 284.56128 -107.870498) (xy 284.582362 -107.866688)
			(xy 284.662626 -107.813348) (xy 284.673802 -107.795822) (xy 284.67558 -107.785154) (xy 284.680209 -107.758576)
			(xy 284.696069 -107.707009) (xy 284.719037 -107.658192) (xy 284.748654 -107.613098) (xy 284.784329 -107.572627)
			(xy 284.825351 -107.537586) (xy 284.8709 -107.508674) (xy 284.920069 -107.486469) (xy 284.971875 -107.471412)
			(xy 285.025287 -107.463805) (xy 285.052262 -107.463336) (xy 285.079632 -107.463816) (xy 285.133811 -107.471629)
			(xy 285.186314 -107.487114) (xy 285.236061 -107.509953) (xy 285.282028 -107.539676) (xy 285.30296 -107.557316)
			(xy 285.303214 -107.55757) (xy 285.310286 -107.563177) (xy 285.327214 -107.569409) (xy 285.336234 -107.569762)
			(xy 285.40329 -107.569762) (xy 285.412307 -107.569408) (xy 285.429225 -107.563159) (xy 285.43631 -107.55757)
			(xy 285.43631 -107.557316) (xy 285.436564 -107.557316) (xy 285.457501 -107.539683) (xy 285.503472 -107.50997)
			(xy 285.553218 -107.487132) (xy 285.605718 -107.47164) (xy 285.659893 -107.46381) (xy 285.687262 -107.463336)
			(xy 285.70431 -107.463533) (xy 285.73827 -107.466588) (xy 285.75508 -107.469432) (xy 285.766407 -107.470872)
			(xy 285.788425 -107.464934) (xy 285.797498 -107.458002) (xy 285.821882 -107.43692) (xy 285.83029 -107.428925)
			(xy 285.839428 -107.407627) (xy 285.839408 -107.396026) (xy 285.8389 -107.376214) (xy 285.8389 -106.512614)
			(xy 285.839408 -106.493564) (xy 285.839376 -106.481972) (xy 285.830256 -106.460685) (xy 285.821882 -106.45267)
			(xy 285.797498 -106.431842) (xy 285.788517 -106.424857) (xy 285.766627 -106.418782) (xy 285.755334 -106.420158)
			(xy 285.738463 -106.423025) (xy 285.704374 -106.42608) (xy 285.687262 -106.426254) (xy 285.659893 -106.425763)
			(xy 285.605714 -106.417953) (xy 285.553211 -106.40247) (xy 285.503463 -106.379634) (xy 285.457496 -106.349913)
			(xy 285.436564 -106.332274) (xy 285.429706 -106.326178) (xy 285.412688 -106.319828) (xy 285.327344 -106.319828)
			(xy 285.310072 -106.326432) (xy 285.303214 -106.332528) (xy 285.28229 -106.350179) (xy 285.236319 -106.379898)
			(xy 285.18657 -106.402736) (xy 285.134066 -106.418223) (xy 285.079886 -106.426041) (xy 285.052516 -106.426508)
			(xy 285.052262 -106.426508) (xy 285.025256 -106.426028) (xy 284.971782 -106.418418) (xy 284.919916 -106.403342)
			(xy 284.870695 -106.381102) (xy 284.825103 -106.352141) (xy 284.784052 -106.317039) (xy 284.748362 -106.276497)
			(xy 284.718748 -106.231327) (xy 284.6958 -106.182432) (xy 284.679979 -106.130789) (xy 284.675326 -106.104182)
			(xy 284.673802 -106.093514) (xy 284.662372 -106.075734) (xy 284.590998 -106.028236) (xy 284.582061 -106.022904)
			(xy 284.561604 -106.01922) (xy 284.551374 -106.021124) (xy 284.550612 -106.021124) (xy 284.524041 -106.027233)
			(xy 284.469922 -106.03386) (xy 284.442662 -106.034332) (xy 284.415338 -106.033877) (xy 284.361089 -106.027256)
			(xy 284.334458 -106.021124) (xy 284.33395 -106.021124) (xy 284.32372 -106.019263) (xy 284.303273 -106.022937)
			(xy 284.294326 -106.028236) (xy 284.222952 -106.075734) (xy 284.211522 -106.093514) (xy 284.209998 -106.104182)
			(xy 284.205319 -106.130782) (xy 284.18949 -106.182419) (xy 284.16654 -106.231309) (xy 284.136925 -106.276474)
			(xy 284.101238 -106.317013) (xy 284.060192 -106.352115) (xy 284.014607 -106.381079) (xy 283.965393 -106.403326)
			(xy 283.913534 -106.418412) (xy 283.860066 -106.426036) (xy 283.833062 -106.426508) (xy 283.805813 -106.42602)
			(xy 283.751869 -106.418259) (xy 283.699579 -106.4029) (xy 283.650006 -106.380257) (xy 283.604161 -106.35079)
			(xy 283.562975 -106.315098) (xy 283.527288 -106.273909) (xy 283.497825 -106.22806) (xy 283.475186 -106.178486)
			(xy 283.459833 -106.126194) (xy 283.452078 -106.07225) (xy 283.452078 -106.01775) (xy 283.459833 -105.963806)
			(xy 283.475186 -105.911514) (xy 283.497825 -105.86194) (xy 283.527288 -105.816091) (xy 283.562975 -105.774902)
			(xy 283.604161 -105.73921) (xy 283.650006 -105.709743) (xy 283.699579 -105.6871) (xy 283.751869 -105.671741)
			(xy 283.805813 -105.66398) (xy 283.833062 -105.663492) (xy 283.85011 -105.663688) (xy 283.88407 -105.666743)
			(xy 283.90088 -105.669588) (xy 283.912207 -105.671016) (xy 283.934223 -105.665084) (xy 283.943298 -105.658158)
			(xy 283.967682 -105.637076) (xy 283.976111 -105.629099) (xy 283.985237 -105.607788) (xy 283.985208 -105.596182)
			(xy 283.9847 -105.57637) (xy 283.9847 -104.71277) (xy 283.985208 -104.69372) (xy 283.985143 -104.682131)
			(xy 283.976046 -104.660844) (xy 283.967682 -104.652826) (xy 283.943298 -104.631998) (xy 283.934313 -104.625019)
			(xy 283.912426 -104.618938) (xy 283.901134 -104.620314) (xy 283.884262 -104.623181) (xy 283.850174 -104.626236)
			(xy 283.833062 -104.62641) (xy 283.805813 -104.625918) (xy 283.751869 -104.618157) (xy 283.699579 -104.602798)
			(xy 283.650007 -104.580155) (xy 283.604162 -104.550688) (xy 283.562976 -104.514997) (xy 283.527289 -104.473808)
			(xy 283.497827 -104.427959) (xy 283.475188 -104.378385) (xy 283.459835 -104.326093) (xy 283.45208 -104.272149)
			(xy 283.45208 -104.217651) (xy 283.459835 -104.163707) (xy 283.475188 -104.111415) (xy 283.497827 -104.061841)
			(xy 283.527289 -104.015992) (xy 283.562976 -103.974803) (xy 283.604162 -103.939112) (xy 283.650007 -103.909645)
			(xy 283.699579 -103.887002) (xy 283.751869 -103.871643) (xy 283.805813 -103.863882) (xy 283.833062 -103.863394)
			(xy 283.860039 -103.863859) (xy 283.913456 -103.871447) (xy 283.965269 -103.886492) (xy 284.014443 -103.908691)
			(xy 284.059996 -103.937603) (xy 284.101017 -103.972648) (xy 284.136687 -104.013128) (xy 284.166293 -104.058232)
			(xy 284.189243 -104.107061) (xy 284.205079 -104.158638) (xy 284.209744 -104.185212) (xy 284.211918 -104.195439)
			(xy 284.223192 -104.213018) (xy 284.231588 -104.219248) (xy 284.302962 -104.266746) (xy 284.324044 -104.270556)
			(xy 284.334204 -104.268016) (xy 284.3609 -104.261885) (xy 284.415274 -104.255257) (xy 284.442662 -104.254808)
			(xy 284.47005 -104.255256) (xy 284.524426 -104.261875) (xy 284.55112 -104.268016) (xy 284.56128 -104.270556)
			(xy 284.582362 -104.266746) (xy 284.662626 -104.213406) (xy 284.673802 -104.19588) (xy 284.67558 -104.185212)
			(xy 284.680253 -104.158642) (xy 284.696106 -104.107076) (xy 284.719067 -104.058258) (xy 284.748678 -104.013163)
			(xy 284.784347 -103.97269) (xy 284.825364 -103.937648) (xy 284.87091 -103.908735) (xy 284.920075 -103.886528)
			(xy 284.971879 -103.871471) (xy 285.025288 -103.863863) (xy 285.052262 -103.863394) (xy 285.079631 -103.863884)
			(xy 285.133809 -103.871696) (xy 285.186312 -103.88718) (xy 285.236059 -103.910016) (xy 285.282027 -103.939735)
			(xy 285.30296 -103.957374) (xy 285.303214 -103.957628) (xy 285.31029 -103.96323) (xy 285.327215 -103.969466)
			(xy 285.336234 -103.96982) (xy 285.40329 -103.96982) (xy 285.412306 -103.969454) (xy 285.429223 -103.963212)
			(xy 285.43631 -103.957628) (xy 285.43631 -103.957374) (xy 285.436564 -103.957374) (xy 285.457495 -103.939734)
			(xy 285.503469 -103.910023) (xy 285.553217 -103.887188) (xy 285.605717 -103.871697) (xy 285.659893 -103.863868)
			(xy 285.687262 -103.863394) (xy 285.70431 -103.86359) (xy 285.73827 -103.866645) (xy 285.75508 -103.86949)
			(xy 285.766407 -103.870917) (xy 285.788423 -103.864986) (xy 285.797498 -103.85806) (xy 285.821882 -103.836978)
			(xy 285.83031 -103.829001) (xy 285.839436 -103.80769) (xy 285.839408 -103.796084) (xy 285.8389 -103.776272)
			(xy 285.8389 -102.912672) (xy 285.839408 -102.893622) (xy 285.839342 -102.882033) (xy 285.830246 -102.860747)
			(xy 285.821882 -102.852728) (xy 285.797498 -102.8319) (xy 285.788513 -102.824921) (xy 285.766626 -102.81884)
			(xy 285.755334 -102.820216) (xy 285.738462 -102.823083) (xy 285.704374 -102.826138) (xy 285.687262 -102.826312)
			(xy 285.659893 -102.825807) (xy 285.605716 -102.817998) (xy 285.553213 -102.802518) (xy 285.503466 -102.779685)
			(xy 285.457497 -102.749969) (xy 285.436564 -102.732332) (xy 285.429706 -102.726236) (xy 285.412688 -102.719886)
			(xy 285.327344 -102.719886) (xy 285.310072 -102.72649) (xy 285.303214 -102.732586) (xy 285.282298 -102.750246)
			(xy 285.236324 -102.779962) (xy 285.186573 -102.802797) (xy 285.134067 -102.818283) (xy 285.079887 -102.8261)
			(xy 285.052516 -102.826566) (xy 285.052262 -102.826566) (xy 285.025254 -102.826121) (xy 284.971777 -102.818511)
			(xy 284.919909 -102.803433) (xy 284.870685 -102.781189) (xy 284.825092 -102.752224) (xy 284.78404 -102.717118)
			(xy 284.748351 -102.676572) (xy 284.718738 -102.631397) (xy 284.695794 -102.582497) (xy 284.679976 -102.530849)
			(xy 284.675326 -102.50424) (xy 284.673802 -102.493572) (xy 284.662372 -102.475792) (xy 284.590998 -102.428294)
			(xy 284.582059 -102.422965) (xy 284.561603 -102.419277) (xy 284.551374 -102.421182) (xy 284.550612 -102.421182)
			(xy 284.524035 -102.427229) (xy 284.469915 -102.433725) (xy 284.442662 -102.434136) (xy 284.415344 -102.433744)
			(xy 284.361096 -102.427253) (xy 284.334458 -102.421182) (xy 284.33395 -102.421182) (xy 284.32372 -102.419327)
			(xy 284.303274 -102.422998) (xy 284.294326 -102.428294) (xy 284.222952 -102.475792) (xy 284.211522 -102.493572)
			(xy 284.209998 -102.50424) (xy 284.205287 -102.530834) (xy 284.189464 -102.582471) (xy 284.166518 -102.631361)
			(xy 284.136908 -102.676527) (xy 284.101225 -102.717067) (xy 284.060182 -102.75217) (xy 284.014599 -102.781135)
			(xy 283.965388 -102.803383) (xy 283.913531 -102.81847) (xy 283.860065 -102.826094) (xy 283.833062 -102.826566)
			(xy 283.80581 -102.826162) (xy 283.75186 -102.8184) (xy 283.699564 -102.80304) (xy 283.649986 -102.780394)
			(xy 283.604135 -102.750923) (xy 283.562945 -102.715228) (xy 283.527254 -102.674034) (xy 283.497788 -102.62818)
			(xy 283.475147 -102.5786) (xy 283.459792 -102.526303) (xy 283.452036 -102.472353) (xy 279.629502 -102.472353)
			(xy 279.68108 -102.485837) (xy 279.732409 -102.507649) (xy 279.780015 -102.536703) (xy 279.822883 -102.572378)
			(xy 279.8601 -102.613915) (xy 279.890873 -102.660428) (xy 279.914545 -102.710925) (xy 279.930613 -102.764332)
			(xy 279.938733 -102.819508) (xy 279.939242 -102.847394) (xy 279.938733 -102.87528) (xy 279.930613 -102.930456)
			(xy 279.914545 -102.983863) (xy 279.890873 -103.03436) (xy 279.8601 -103.080873) (xy 279.822883 -103.12241)
			(xy 279.780015 -103.158085) (xy 279.732409 -103.187139) (xy 279.68108 -103.208951) (xy 279.627123 -103.223057)
			(xy 279.571686 -103.229157) (xy 279.515952 -103.22712) (xy 279.461109 -103.21699) (xy 279.408325 -103.198983)
			(xy 279.358725 -103.173482) (xy 279.313367 -103.141031) (xy 279.273218 -103.102322) (xy 279.239132 -103.058179)
			(xy 279.211836 -103.009544) (xy 279.191913 -102.957453) (xy 279.179787 -102.903016) (xy 279.175716 -102.847394)
			(xy 270.96041 -102.847394) (xy 270.959616 -102.850097) (xy 270.936974 -102.899676) (xy 270.907507 -102.945527)
			(xy 270.871814 -102.986718) (xy 270.830622 -103.02241) (xy 270.78477 -103.051877) (xy 270.735192 -103.074518)
			(xy 270.682895 -103.089873) (xy 270.628946 -103.097629) (xy 270.601694 -103.098092) (xy 270.586901 -103.097959)
			(xy 270.557403 -103.095669) (xy 270.542766 -103.09352) (xy 270.531792 -103.092378) (xy 270.510598 -103.098449)
			(xy 270.501872 -103.105204) (xy 270.443452 -103.155242) (xy 270.43545 -103.162832) (xy 270.426221 -103.182836)
			(xy 270.425672 -103.19385) (xy 270.425672 -103.498142) (xy 270.426195 -103.509162) (xy 270.435426 -103.529178)
			(xy 270.443452 -103.53675) (xy 270.510508 -103.594154) (xy 270.53159 -103.60025) (xy 270.542766 -103.598472)
			(xy 270.557404 -103.596329) (xy 270.586901 -103.594042) (xy 270.601694 -103.5939) (xy 270.628948 -103.594347)
			(xy 270.6829 -103.602103) (xy 270.7352 -103.617459) (xy 270.784782 -103.640102) (xy 270.830637 -103.66957)
			(xy 270.871831 -103.705265) (xy 270.907526 -103.746458) (xy 270.936995 -103.792313) (xy 270.959639 -103.841894)
			(xy 270.974995 -103.894194) (xy 270.982753 -103.948146) (xy 270.982753 -104.002654) (xy 270.974995 -104.056606)
			(xy 270.959639 -104.108906) (xy 270.936995 -104.158487) (xy 270.907526 -104.204342) (xy 270.87238 -104.244902)
			(xy 276.86965 -104.244902) (xy 276.873721 -104.18928) (xy 276.885847 -104.134843) (xy 276.90577 -104.082752)
			(xy 276.933066 -104.034117) (xy 276.967152 -103.989974) (xy 277.007301 -103.951265) (xy 277.052659 -103.918814)
			(xy 277.102259 -103.893313) (xy 277.155043 -103.875306) (xy 277.209886 -103.865176) (xy 277.26562 -103.863139)
			(xy 277.321057 -103.869239) (xy 277.375014 -103.883345) (xy 277.426343 -103.905157) (xy 277.473949 -103.934211)
			(xy 277.516817 -103.969886) (xy 277.554034 -104.011423) (xy 277.584807 -104.057936) (xy 277.608479 -104.108433)
			(xy 277.624547 -104.16184) (xy 277.632667 -104.217016) (xy 277.633176 -104.244902) (xy 277.632667 -104.272788)
			(xy 277.624547 -104.327964) (xy 277.608479 -104.381371) (xy 277.584807 -104.431868) (xy 277.554034 -104.478381)
			(xy 277.516817 -104.519918) (xy 277.473949 -104.555593) (xy 277.426343 -104.584647) (xy 277.375014 -104.606459)
			(xy 277.321057 -104.620565) (xy 277.26562 -104.626665) (xy 277.209886 -104.624628) (xy 277.155043 -104.614498)
			(xy 277.102259 -104.596491) (xy 277.052659 -104.57099) (xy 277.007301 -104.538539) (xy 276.967152 -104.49983)
			(xy 276.933066 -104.455687) (xy 276.90577 -104.407052) (xy 276.885847 -104.354961) (xy 276.873721 -104.300524)
			(xy 276.86965 -104.244902) (xy 270.87238 -104.244902) (xy 270.871831 -104.245535) (xy 270.830637 -104.28123)
			(xy 270.784782 -104.310698) (xy 270.7352 -104.333341) (xy 270.6829 -104.348697) (xy 270.628948 -104.356453)
			(xy 270.601694 -104.356916) (xy 270.575788 -104.356425) (xy 270.524453 -104.349401) (xy 270.47454 -104.335497)
			(xy 270.426967 -104.314968) (xy 270.382609 -104.288192) (xy 270.34228 -104.255661) (xy 270.306724 -104.217974)
			(xy 270.291306 -104.19715) (xy 270.285566 -104.189819) (xy 270.270063 -104.179533) (xy 270.26108 -104.177084)
			(xy 270.2306 -104.170226) (xy 270.221321 -104.168497) (xy 270.20266 -104.171224) (xy 270.194278 -104.17556)
			(xy 270.168291 -104.189815) (xy 270.113426 -104.212247) (xy 270.056125 -104.227414) (xy 269.997347 -104.235061)
			(xy 269.938073 -104.235061) (xy 269.879295 -104.227414) (xy 269.821994 -104.212247) (xy 269.767129 -104.189815)
			(xy 269.741142 -104.17556) (xy 269.732724 -104.171325) (xy 269.714098 -104.168584) (xy 269.70482 -104.170226)
			(xy 269.67434 -104.177084) (xy 269.665349 -104.179515) (xy 269.649844 -104.189807) (xy 269.644114 -104.19715)
			(xy 269.628728 -104.218003) (xy 269.593181 -104.255713) (xy 269.552855 -104.288261) (xy 269.508491 -104.315048)
			(xy 269.460909 -104.335579) (xy 269.410984 -104.349478) (xy 269.359638 -104.356486) (xy 269.333726 -104.356916)
			(xy 269.306473 -104.356438) (xy 269.25252 -104.348685) (xy 269.20022 -104.333331) (xy 269.150638 -104.310691)
			(xy 269.104782 -104.281224) (xy 269.063587 -104.245531) (xy 269.027892 -104.204339) (xy 268.998422 -104.158485)
			(xy 268.975778 -104.108904) (xy 268.960421 -104.056606) (xy 268.952663 -104.002653) (xy 268.952663 -103.948147)
			(xy 268.960421 -103.894194) (xy 268.975778 -103.841896) (xy 268.998422 -103.792315) (xy 269.027892 -103.746461)
			(xy 269.063587 -103.705269) (xy 269.104782 -103.669576) (xy 269.150638 -103.640109) (xy 269.20022 -103.617469)
			(xy 269.25252 -103.602115) (xy 269.306473 -103.594362) (xy 269.333726 -103.5939) (xy 269.348519 -103.594031)
			(xy 269.378017 -103.596323) (xy 269.392654 -103.598472) (xy 269.40363 -103.599569) (xy 269.424819 -103.593529)
			(xy 269.433548 -103.586788) (xy 269.491968 -103.53675) (xy 269.499977 -103.529166) (xy 269.509201 -103.509158)
			(xy 269.509748 -103.498142) (xy 269.509748 -103.19385) (xy 269.509199 -103.182832) (xy 269.499989 -103.162814)
			(xy 269.491968 -103.155242) (xy 269.424912 -103.097838) (xy 269.40383 -103.091742) (xy 269.392654 -103.09352)
			(xy 269.378016 -103.095661) (xy 269.348519 -103.097949) (xy 269.333726 -103.098092) (xy 269.306471 -103.097663)
			(xy 269.252515 -103.089909) (xy 269.200211 -103.074554) (xy 269.150626 -103.051912) (xy 269.104768 -103.022444)
			(xy 269.06357 -102.986748) (xy 269.027872 -102.945553) (xy 268.9984 -102.899697) (xy 268.975755 -102.850113)
			(xy 268.960397 -102.797811) (xy 268.952639 -102.743855) (xy 263.853583 -102.743855) (xy 262.672576 -103.924862)
			(xy 262.665174 -103.9317) (xy 262.646576 -103.939422) (xy 262.636508 -103.939848) (xy 259.742686 -103.939848)
			(xy 259.740654 -103.940102) (xy 259.630689 -103.948789) (xy 259.41027 -103.958062) (xy 259.299964 -103.958644)
			(xy 259.189658 -103.95806) (xy 258.96924 -103.948786) (xy 258.859274 -103.940102) (xy 258.857242 -103.939848)
			(xy 252.243336 -103.939848) (xy 252.234026 -103.940277) (xy 252.216624 -103.946893) (xy 252.202742 -103.9593)
			(xy 252.19422 -103.975852) (xy 252.19279 -103.98506) (xy 252.19279 -103.985314) (xy 252.189312 -104.013023)
			(xy 252.175293 -104.067079) (xy 252.153541 -104.118513) (xy 252.124522 -104.166226) (xy 252.088855 -104.209197)
			(xy 252.047304 -104.246508) (xy 252.000757 -104.277362) (xy 251.950208 -104.301099) (xy 251.896738 -104.317211)
			(xy 251.84149 -104.325354) (xy 251.785646 -104.325354) (xy 251.730398 -104.317211) (xy 251.676928 -104.301099)
			(xy 251.626379 -104.277362) (xy 251.579832 -104.246508) (xy 251.538281 -104.209197) (xy 251.502614 -104.166226)
			(xy 251.473595 -104.118513) (xy 251.451843 -104.067079) (xy 251.437824 -104.013023) (xy 251.434346 -103.985314)
			(xy 251.434346 -103.98506) (xy 251.432969 -103.975844) (xy 251.424409 -103.959301) (xy 251.410516 -103.946896)
			(xy 251.393113 -103.940257) (xy 251.3838 -103.939848) (xy 251.273564 -103.939848) (xy 251.263491 -103.939455)
			(xy 251.244893 -103.931713) (xy 251.237496 -103.924862) (xy 248.99239 -101.68001) (xy 248.984986 -101.673174)
			(xy 248.96639 -101.665452) (xy 248.956322 -101.665024) (xy 233.357928 -101.665024) (xy 233.331841 -101.664527)
			(xy 233.28031 -101.656364) (xy 233.230692 -101.640234) (xy 233.184211 -101.616536) (xy 233.142013 -101.585853)
			(xy 233.123232 -101.567742) (xy 232.787698 -101.231954) (xy 232.780771 -101.225634) (xy 232.763621 -101.21809)
			(xy 232.744906 -101.217211) (xy 232.735882 -101.219762) (xy 232.649522 -101.24821) (xy 232.640809 -101.251538)
			(xy 232.626356 -101.263297) (xy 232.617079 -101.279455) (xy 232.615232 -101.288596) (xy 232.615232 -101.28885)
			(xy 232.610715 -101.31554) (xy 232.595168 -101.36739) (xy 232.572444 -101.416519) (xy 232.542999 -101.461941)
			(xy 232.52557 -101.482652) (xy 232.525316 -101.482906) (xy 232.519723 -101.489988) (xy 232.513479 -101.506908)
			(xy 232.513124 -101.515926) (xy 232.513124 -101.582982) (xy 232.513485 -101.591999) (xy 232.519729 -101.608916)
			(xy 232.525316 -101.616002) (xy 232.52557 -101.616002) (xy 232.52557 -101.616256) (xy 232.543166 -101.637225)
			(xy 232.572893 -101.683187) (xy 232.595741 -101.732927) (xy 232.611241 -101.785423) (xy 232.619074 -101.839597)
			(xy 232.619079 -101.894334) (xy 232.611256 -101.948509) (xy 232.595765 -102.001008) (xy 232.572926 -102.050753)
			(xy 232.543208 -102.096719) (xy 232.52557 -102.117652) (xy 232.525316 -102.117906) (xy 232.519723 -102.124988)
			(xy 232.513479 -102.141908) (xy 232.513124 -102.150926) (xy 232.513124 -102.201726) (xy 245.578374 -102.201726)
			(xy 245.582445 -102.146104) (xy 245.594571 -102.091667) (xy 245.614494 -102.039576) (xy 245.64179 -101.990941)
			(xy 245.675876 -101.946798) (xy 245.716025 -101.908089) (xy 245.761383 -101.875638) (xy 245.810983 -101.850137)
			(xy 245.863767 -101.83213) (xy 245.91861 -101.822) (xy 245.974344 -101.819963) (xy 246.029781 -101.826063)
			(xy 246.083738 -101.840169) (xy 246.135067 -101.861981) (xy 246.182673 -101.891035) (xy 246.225541 -101.92671)
			(xy 246.262758 -101.968247) (xy 246.293531 -102.01476) (xy 246.317203 -102.065257) (xy 246.333271 -102.118664)
			(xy 246.341391 -102.17384) (xy 246.3419 -102.201726) (xy 246.341391 -102.229612) (xy 246.333271 -102.284788)
			(xy 246.317203 -102.338195) (xy 246.293531 -102.388692) (xy 246.262758 -102.435205) (xy 246.225541 -102.476742)
			(xy 246.182673 -102.512417) (xy 246.135067 -102.541471) (xy 246.083738 -102.563283) (xy 246.029781 -102.577389)
			(xy 245.974344 -102.583489) (xy 245.91861 -102.581452) (xy 245.863767 -102.571322) (xy 245.810983 -102.553315)
			(xy 245.761383 -102.527814) (xy 245.716025 -102.495363) (xy 245.675876 -102.456654) (xy 245.64179 -102.412511)
			(xy 245.614494 -102.363876) (xy 245.594571 -102.311785) (xy 245.582445 -102.257348) (xy 245.578374 -102.201726)
			(xy 232.513124 -102.201726) (xy 232.513124 -102.217982) (xy 232.513485 -102.226999) (xy 232.519729 -102.243916)
			(xy 232.525316 -102.251002) (xy 232.52557 -102.251002) (xy 232.52557 -102.251256) (xy 232.543197 -102.272198)
			(xy 232.572912 -102.318167) (xy 232.595751 -102.367912) (xy 232.611244 -102.420411) (xy 232.619075 -102.474585)
			(xy 232.61955 -102.501954) (xy 232.619064 -102.529205) (xy 232.611308 -102.583153) (xy 232.595953 -102.635448)
			(xy 232.573311 -102.685025) (xy 232.543845 -102.730875) (xy 232.508154 -102.772066) (xy 232.466963 -102.807757)
			(xy 232.421113 -102.837223) (xy 232.371536 -102.859865) (xy 232.319241 -102.87522) (xy 232.265293 -102.882976)
			(xy 232.210791 -102.882976) (xy 232.156843 -102.87522) (xy 232.104548 -102.859865) (xy 232.054971 -102.837223)
			(xy 232.009121 -102.807757) (xy 231.96793 -102.772066) (xy 231.932239 -102.730875) (xy 231.902773 -102.685025)
			(xy 231.880131 -102.635448) (xy 231.864776 -102.583153) (xy 231.85702 -102.529205) (xy 231.856534 -102.501954)
			(xy 231.857023 -102.474585) (xy 231.864834 -102.420406) (xy 231.880318 -102.367903) (xy 231.903154 -102.318156)
			(xy 231.932875 -102.272188) (xy 231.950514 -102.251256) (xy 231.950768 -102.251002) (xy 231.956368 -102.243925)
			(xy 231.962605 -102.227001) (xy 231.96296 -102.217982) (xy 231.96296 -102.150926) (xy 231.962599 -102.141909)
			(xy 231.956355 -102.124992) (xy 231.950768 -102.117906) (xy 231.950514 -102.117906) (xy 231.950514 -102.117652)
			(xy 231.932829 -102.096755) (xy 231.903107 -102.050781) (xy 231.880265 -102.001029) (xy 231.864773 -101.948521)
			(xy 231.856949 -101.894338) (xy 231.856954 -101.839593) (xy 231.864788 -101.785411) (xy 231.880289 -101.732906)
			(xy 231.90314 -101.683158) (xy 231.932871 -101.637189) (xy 231.950514 -101.616256) (xy 231.950768 -101.616002)
			(xy 231.956368 -101.608925) (xy 231.962605 -101.592001) (xy 231.96296 -101.582982) (xy 231.96296 -101.515926)
			(xy 231.962599 -101.506909) (xy 231.956355 -101.489992) (xy 231.950768 -101.482906) (xy 231.950514 -101.482906)
			(xy 231.950514 -101.482652) (xy 231.932888 -101.461709) (xy 231.903174 -101.41574) (xy 231.880335 -101.365995)
			(xy 231.864841 -101.313496) (xy 231.85701 -101.259322) (xy 231.856534 -101.231954) (xy 231.856953 -101.206195)
			(xy 231.863901 -101.155149) (xy 231.877666 -101.105505) (xy 231.897994 -101.058168) (xy 231.91089 -101.035866)
			(xy 231.915173 -101.028) (xy 231.918484 -101.010412) (xy 231.915525 -100.99276) (xy 231.911398 -100.984812)
			(xy 231.86771 -100.90785) (xy 231.862993 -100.900231) (xy 231.849295 -100.888689) (xy 231.83247 -100.882543)
			(xy 231.823514 -100.882196) (xy 229.466648 -100.882196) (xy 229.457855 -100.882538) (xy 229.441311 -100.888502)
			(xy 229.427759 -100.89971) (xy 229.42296 -100.907088) (xy 229.371398 -100.99421) (xy 229.371144 -101.02088)
			(xy 229.377748 -101.032818) (xy 229.392649 -101.061204) (xy 229.413806 -101.121719) (xy 229.424564 -101.184916)
			(xy 229.425246 -101.216968) (xy 229.424774 -101.244338) (xy 229.41696 -101.298518) (xy 229.401473 -101.351021)
			(xy 229.378632 -101.400768) (xy 229.348907 -101.446735) (xy 229.331266 -101.467666) (xy 229.331012 -101.46792)
			(xy 229.325412 -101.474998) (xy 229.319173 -101.491921) (xy 229.31882 -101.50094) (xy 229.31882 -101.567996)
			(xy 229.319174 -101.577013) (xy 229.325423 -101.59393) (xy 229.331012 -101.601016) (xy 229.331266 -101.601016)
			(xy 229.331266 -101.60127) (xy 229.348876 -101.622228) (xy 229.378602 -101.668191) (xy 229.40145 -101.717933)
			(xy 229.416949 -101.770432) (xy 229.424781 -101.824607) (xy 229.424784 -101.879345) (xy 229.416959 -101.933521)
			(xy 229.401467 -101.986022) (xy 229.378625 -102.035766) (xy 229.348905 -102.081733) (xy 229.331266 -102.102666)
			(xy 229.331012 -102.10292) (xy 229.325412 -102.109998) (xy 229.319173 -102.126921) (xy 229.31882 -102.13594)
			(xy 229.31882 -102.202996) (xy 229.319174 -102.212013) (xy 229.325423 -102.22893) (xy 229.331012 -102.236016)
			(xy 229.331266 -102.236016) (xy 229.331266 -102.23627) (xy 229.348899 -102.257207) (xy 229.378613 -102.303178)
			(xy 229.401451 -102.352924) (xy 229.416943 -102.405424) (xy 229.424772 -102.459599) (xy 229.425246 -102.486968)
			(xy 229.42476 -102.514219) (xy 229.417004 -102.568167) (xy 229.401649 -102.620462) (xy 229.379007 -102.670039)
			(xy 229.349541 -102.715889) (xy 229.31385 -102.75708) (xy 229.272659 -102.792771) (xy 229.226809 -102.822237)
			(xy 229.177232 -102.844879) (xy 229.124937 -102.860234) (xy 229.070989 -102.86799) (xy 229.016487 -102.86799)
			(xy 228.962539 -102.860234) (xy 228.910244 -102.844879) (xy 228.860667 -102.822237) (xy 228.814817 -102.792771)
			(xy 228.773626 -102.75708) (xy 228.737935 -102.715889) (xy 228.708469 -102.670039) (xy 228.685827 -102.620462)
			(xy 228.670472 -102.568167) (xy 228.662716 -102.514219) (xy 228.66223 -102.486968) (xy 228.66267 -102.459597)
			(xy 228.670493 -102.405416) (xy 228.685988 -102.352913) (xy 228.708835 -102.303166) (xy 228.738566 -102.257201)
			(xy 228.75621 -102.23627) (xy 228.756464 -102.236016) (xy 228.762058 -102.228935) (xy 228.768298 -102.212014)
			(xy 228.768656 -102.202996) (xy 228.768656 -102.13594) (xy 228.768289 -102.126924) (xy 228.76205 -102.110006)
			(xy 228.756464 -102.10292) (xy 228.75621 -102.10292) (xy 228.75621 -102.102666) (xy 228.738539 -102.081758)
			(xy 228.708816 -102.035786) (xy 228.685974 -101.986035) (xy 228.670481 -101.93353) (xy 228.662656 -101.879348)
			(xy 228.662659 -101.824604) (xy 228.670491 -101.770423) (xy 228.685991 -101.71792) (xy 228.70884 -101.668172)
			(xy 228.738568 -101.622203) (xy 228.75621 -101.60127) (xy 228.756464 -101.601016) (xy 228.762058 -101.593935)
			(xy 228.768298 -101.577014) (xy 228.768656 -101.567996) (xy 228.768656 -101.50094) (xy 228.768289 -101.491924)
			(xy 228.76205 -101.475006) (xy 228.756464 -101.46792) (xy 228.75621 -101.46792) (xy 228.75621 -101.467666)
			(xy 228.73859 -101.446719) (xy 228.708875 -101.40075) (xy 228.686035 -101.351007) (xy 228.67054 -101.298509)
			(xy 228.662707 -101.244336) (xy 228.66223 -101.216968) (xy 228.662892 -101.184913) (xy 228.673639 -101.121711)
			(xy 228.694808 -101.061196) (xy 228.709728 -101.032818) (xy 228.713639 -101.024929) (xy 228.716431 -101.00756)
			(xy 228.713135 -100.99028) (xy 228.708966 -100.982526) (xy 228.664516 -100.907088) (xy 228.659705 -100.899722)
			(xy 228.646156 -100.888524) (xy 228.629617 -100.882569) (xy 228.620828 -100.882196) (xy 221.886272 -100.882196)
			(xy 221.860186 -100.881679) (xy 221.808655 -100.873522) (xy 221.759037 -100.857398) (xy 221.712556 -100.833704)
			(xy 221.670357 -100.803024) (xy 221.651576 -100.784914) (xy 221.533974 -100.667312) (xy 221.526576 -100.66047)
			(xy 221.507975 -100.652751) (xy 221.497906 -100.652326) (xy 221.457266 -100.652326) (xy 221.447192 -100.651938)
			(xy 221.428593 -100.644193) (xy 221.421198 -100.63734) (xy 220.824552 -100.040694) (xy 220.816487 -100.033351)
			(xy 220.796085 -100.025707) (xy 220.785182 -100.025962) (xy 220.697552 -100.032312) (xy 220.678248 -100.042472)
			(xy 220.671644 -100.051108) (xy 220.671644 -100.051616) (xy 220.653492 -100.074796) (xy 220.611277 -100.11583)
			(xy 220.563253 -100.149883) (xy 220.510563 -100.176143) (xy 220.45446 -100.193986) (xy 220.39628 -100.202987)
			(xy 220.366844 -100.203508) (xy 220.339592 -100.203004) (xy 220.285643 -100.195253) (xy 220.233346 -100.179902)
			(xy 220.183766 -100.157265) (xy 220.137912 -100.127802) (xy 220.096719 -100.092112) (xy 220.061025 -100.050923)
			(xy 220.031556 -100.005073) (xy 220.008913 -99.955496) (xy 219.993557 -99.9032) (xy 219.985799 -99.849252)
			(xy 219.985336 -99.822) (xy 219.98585 -99.792555) (xy 219.994925 -99.734369) (xy 220.012829 -99.678266)
			(xy 220.039136 -99.625579) (xy 220.073224 -99.577557) (xy 220.114283 -99.535341) (xy 220.137482 -99.5172)
			(xy 220.145774 -99.510216) (xy 220.15603 -99.491137) (xy 220.157294 -99.48037) (xy 220.162882 -99.403662)
			(xy 220.163076 -99.392768) (xy 220.15545 -99.37238) (xy 220.14815 -99.364292) (xy 218.827858 -98.044)
			(xy 218.82102 -98.036599) (xy 218.8133 -98.018) (xy 218.812872 -98.007932) (xy 218.812872 -97.74936)
			(xy 218.812263 -97.737707) (xy 218.801932 -97.716809) (xy 218.79306 -97.709228) (xy 218.719908 -97.652586)
			(xy 218.697302 -97.648014) (xy 218.685618 -97.651062) (xy 218.661846 -97.656868) (xy 218.613311 -97.663113)
			(xy 218.588844 -97.663508) (xy 218.568524 -97.663) (xy 218.557602 -97.662492) (xy 218.537536 -97.670112)
			(xy 218.468956 -97.738692) (xy 218.461336 -97.758758) (xy 218.461844 -97.76968) (xy 218.462352 -97.79)
			(xy 218.461845 -97.817254) (xy 218.454087 -97.871206) (xy 218.43873 -97.923505) (xy 218.416087 -97.973086)
			(xy 218.386618 -98.01894) (xy 218.350922 -98.060133) (xy 218.309728 -98.095826) (xy 218.263873 -98.125294)
			(xy 218.214291 -98.147936) (xy 218.161991 -98.16329) (xy 218.108039 -98.171046) (xy 218.053532 -98.171044)
			(xy 217.99958 -98.163284) (xy 217.947282 -98.147925) (xy 217.897701 -98.12528) (xy 217.851849 -98.095809)
			(xy 217.810657 -98.060112) (xy 217.774965 -98.018916) (xy 217.745499 -97.97306) (xy 217.722859 -97.923477)
			(xy 217.707506 -97.871177) (xy 217.699753 -97.817224) (xy 217.699757 -97.762717) (xy 217.707519 -97.708766)
			(xy 217.72288 -97.656468) (xy 217.745527 -97.606888) (xy 217.775 -97.561037) (xy 217.810698 -97.519847)
			(xy 217.851896 -97.484156) (xy 217.897753 -97.454692) (xy 217.947337 -97.432054) (xy 217.999637 -97.416703)
			(xy 218.05359 -97.408952) (xy 218.080844 -97.408492) (xy 218.101164 -97.409) (xy 218.112086 -97.409508)
			(xy 218.132152 -97.401888) (xy 218.200732 -97.333308) (xy 218.208352 -97.313242) (xy 218.207844 -97.30232)
			(xy 218.207336 -97.282) (xy 218.207755 -97.254745) (xy 218.215514 -97.20079) (xy 218.230872 -97.148489)
			(xy 218.253518 -97.098906) (xy 218.28299 -97.053051) (xy 218.318688 -97.011857) (xy 218.359886 -96.976163)
			(xy 218.405745 -96.946696) (xy 218.45533 -96.924056) (xy 218.507633 -96.908704) (xy 218.561589 -96.900952)
			(xy 218.588844 -96.900492) (xy 218.589098 -96.900492) (xy 218.613504 -96.90086) (xy 218.661916 -96.907104)
			(xy 218.685618 -96.912938) (xy 218.697302 -96.915986) (xy 218.719908 -96.911414) (xy 218.79306 -96.854772)
			(xy 218.801958 -96.84721) (xy 218.812292 -96.826302) (xy 218.812872 -96.81464) (xy 218.812872 -95.70593)
			(xy 218.812438 -95.695862) (xy 218.804724 -95.677263) (xy 218.797886 -95.669862) (xy 218.50731 -95.379286)
			(xy 218.49973 -95.372396) (xy 218.480721 -95.364807) (xy 218.47048 -95.364554) (xy 218.386406 -95.366078)
			(xy 218.368118 -95.374206) (xy 218.360752 -95.38208) (xy 218.342653 -95.401039) (xy 218.302136 -95.434291)
			(xy 218.257444 -95.461676) (xy 218.209421 -95.482678) (xy 218.158973 -95.496901) (xy 218.107051 -95.504076)
			(xy 218.080844 -95.504508) (xy 218.053592 -95.504004) (xy 217.999643 -95.496253) (xy 217.947346 -95.480902)
			(xy 217.897766 -95.458265) (xy 217.851912 -95.428802) (xy 217.810719 -95.393112) (xy 217.775025 -95.351923)
			(xy 217.745556 -95.306073) (xy 217.722913 -95.256496) (xy 217.707557 -95.2042) (xy 217.699799 -95.150252)
			(xy 217.699336 -95.123) (xy 217.69976 -95.096794) (xy 217.70695 -95.044876) (xy 217.721183 -94.994433)
			(xy 217.742189 -94.946414) (xy 217.769573 -94.901723) (xy 217.802819 -94.861204) (xy 217.821764 -94.843092)
			(xy 217.828931 -94.835818) (xy 217.83731 -94.817212) (xy 217.83802 -94.807024) (xy 217.83929 -94.733364)
			(xy 217.839055 -94.723122) (xy 217.831446 -94.704119) (xy 217.824558 -94.696534) (xy 217.488262 -94.360238)
			(xy 217.480865 -94.353394) (xy 217.462264 -94.345675) (xy 217.452194 -94.345252) (xy 213.196678 -94.345252)
			(xy 213.186606 -94.344851) (xy 213.168007 -94.337115) (xy 213.16061 -94.330266) (xy 211.607654 -92.77731)
			(xy 211.600228 -92.770502) (xy 211.581649 -92.762763) (xy 211.571586 -92.762324) (xy 197.867524 -92.762324)
			(xy 197.857455 -92.762755) (xy 197.838857 -92.770471) (xy 197.831456 -92.77731) (xy 196.452998 -94.155768)
			(xy 196.446336 -94.163196) (xy 196.438741 -94.181622) (xy 196.438736 -94.201552) (xy 196.446321 -94.219983)
			(xy 196.452998 -94.227396) (xy 200.925684 -98.700082) (xy 203.041004 -98.700082) (xy 203.045008 -98.494894)
			(xy 203.057015 -98.290018) (xy 203.077006 -98.085767) (xy 203.104951 -97.882452) (xy 203.140807 -97.680381)
			(xy 203.184521 -97.479863) (xy 203.236024 -97.281204) (xy 203.295239 -97.084705) (xy 203.362075 -96.890666)
			(xy 203.436431 -96.699383) (xy 203.518194 -96.511146) (xy 203.607239 -96.326243) (xy 203.70343 -96.144955)
			(xy 203.806621 -95.967558) (xy 203.916655 -95.794321) (xy 204.033364 -95.62551) (xy 204.15657 -95.461381)
			(xy 204.286087 -95.302184) (xy 204.421716 -95.148162) (xy 204.563251 -94.999548) (xy 204.710476 -94.85657)
			(xy 204.863168 -94.719445) (xy 205.021094 -94.588381) (xy 205.184013 -94.463579) (xy 205.351678 -94.345229)
			(xy 205.523832 -94.23351) (xy 205.700214 -94.128593) (xy 205.880555 -94.030638) (xy 206.064581 -93.939794)
			(xy 206.252011 -93.856198) (xy 206.44256 -93.779979) (xy 206.635937 -93.711253) (xy 206.831849 -93.650124)
			(xy 207.029996 -93.596685) (xy 207.230078 -93.551018) (xy 207.431789 -93.513191) (xy 207.634822 -93.483264)
			(xy 207.838869 -93.461281) (xy 208.043618 -93.447276) (xy 208.248757 -93.44127) (xy 208.453974 -93.443272)
			(xy 208.658957 -93.45328) (xy 208.863394 -93.471277) (xy 209.066972 -93.497237) (xy 209.269383 -93.53112)
			(xy 209.470317 -93.572875) (xy 209.66947 -93.622438) (xy 209.866537 -93.679733) (xy 210.061219 -93.744673)
			(xy 210.253219 -93.817159) (xy 210.442244 -93.897082) (xy 210.628007 -93.984318) (xy 210.810225 -94.078736)
			(xy 210.988621 -94.180191) (xy 211.162922 -94.28853) (xy 211.332864 -94.403586) (xy 211.498187 -94.525186)
			(xy 211.65864 -94.653143) (xy 211.813979 -94.787262) (xy 211.963966 -94.927341) (xy 212.108374 -95.073165)
			(xy 212.154015 -95.123) (xy 216.555826 -95.123) (xy 216.559897 -95.067378) (xy 216.572023 -95.012941)
			(xy 216.591946 -94.96085) (xy 216.619242 -94.912215) (xy 216.653328 -94.868072) (xy 216.693477 -94.829363)
			(xy 216.738835 -94.796912) (xy 216.788435 -94.771411) (xy 216.841219 -94.753404) (xy 216.896062 -94.743274)
			(xy 216.951796 -94.741237) (xy 217.007233 -94.747337) (xy 217.06119 -94.761443) (xy 217.112519 -94.783255)
			(xy 217.160125 -94.812309) (xy 217.202993 -94.847984) (xy 217.24021 -94.889521) (xy 217.270983 -94.936034)
			(xy 217.294655 -94.986531) (xy 217.310723 -95.039938) (xy 217.318843 -95.095114) (xy 217.319352 -95.123)
			(xy 217.318843 -95.150886) (xy 217.310723 -95.206062) (xy 217.294655 -95.259469) (xy 217.270983 -95.309966)
			(xy 217.24021 -95.356479) (xy 217.202993 -95.398016) (xy 217.160125 -95.433691) (xy 217.112519 -95.462745)
			(xy 217.06119 -95.484557) (xy 217.007233 -95.498663) (xy 216.951796 -95.504763) (xy 216.896062 -95.502726)
			(xy 216.841219 -95.492596) (xy 216.788435 -95.474589) (xy 216.738835 -95.449088) (xy 216.693477 -95.416637)
			(xy 216.653328 -95.377928) (xy 216.619242 -95.333785) (xy 216.591946 -95.28515) (xy 216.572023 -95.233059)
			(xy 216.559897 -95.178622) (xy 216.555826 -95.123) (xy 212.154015 -95.123) (xy 212.246982 -95.224511)
			(xy 212.37958 -95.381151) (xy 212.505966 -95.542845) (xy 212.625946 -95.709347) (xy 212.739339 -95.880403)
			(xy 212.845972 -96.055753) (xy 212.945682 -96.23513) (xy 213.038318 -96.41826) (xy 213.123738 -96.604866)
			(xy 213.201812 -96.794662) (xy 213.272422 -96.98736) (xy 213.335459 -97.182666) (xy 213.390829 -97.380282)
			(xy 213.438446 -97.579909) (xy 213.478238 -97.781241) (xy 213.479617 -97.79) (xy 216.555826 -97.79)
			(xy 216.559897 -97.734378) (xy 216.572023 -97.679941) (xy 216.591946 -97.62785) (xy 216.619242 -97.579215)
			(xy 216.653328 -97.535072) (xy 216.693477 -97.496363) (xy 216.738835 -97.463912) (xy 216.788435 -97.438411)
			(xy 216.841219 -97.420404) (xy 216.896062 -97.410274) (xy 216.951796 -97.408237) (xy 217.007233 -97.414337)
			(xy 217.06119 -97.428443) (xy 217.112519 -97.450255) (xy 217.160125 -97.479309) (xy 217.202993 -97.514984)
			(xy 217.24021 -97.556521) (xy 217.270983 -97.603034) (xy 217.294655 -97.653531) (xy 217.310723 -97.706938)
			(xy 217.318843 -97.762114) (xy 217.319352 -97.79) (xy 217.318843 -97.817886) (xy 217.310723 -97.873062)
			(xy 217.294655 -97.926469) (xy 217.270983 -97.976966) (xy 217.24021 -98.023479) (xy 217.202993 -98.065016)
			(xy 217.160125 -98.100691) (xy 217.112519 -98.129745) (xy 217.06119 -98.151557) (xy 217.007233 -98.165663)
			(xy 216.951796 -98.171763) (xy 216.896062 -98.169726) (xy 216.841219 -98.159596) (xy 216.788435 -98.141589)
			(xy 216.738835 -98.116088) (xy 216.693477 -98.083637) (xy 216.653328 -98.044928) (xy 216.619242 -98.000785)
			(xy 216.591946 -97.95215) (xy 216.572023 -97.900059) (xy 216.559897 -97.845622) (xy 216.555826 -97.79)
			(xy 213.479617 -97.79) (xy 213.510145 -97.983973) (xy 213.534118 -98.187795) (xy 213.55012 -98.392398)
			(xy 213.558127 -98.597468) (xy 213.558628 -98.700082) (xy 213.558127 -98.802696) (xy 213.55012 -99.007766)
			(xy 213.534118 -99.212369) (xy 213.510145 -99.416191) (xy 213.478238 -99.618923) (xy 213.438446 -99.820255)
			(xy 213.43809 -99.821746) (xy 216.555826 -99.821746) (xy 216.559897 -99.766124) (xy 216.572023 -99.711687)
			(xy 216.591946 -99.659596) (xy 216.619242 -99.610961) (xy 216.653328 -99.566818) (xy 216.693477 -99.528109)
			(xy 216.738835 -99.495658) (xy 216.788435 -99.470157) (xy 216.841219 -99.45215) (xy 216.896062 -99.44202)
			(xy 216.951796 -99.439983) (xy 217.007233 -99.446083) (xy 217.06119 -99.460189) (xy 217.112519 -99.482001)
			(xy 217.160125 -99.511055) (xy 217.202993 -99.54673) (xy 217.24021 -99.588267) (xy 217.270983 -99.63478)
			(xy 217.294655 -99.685277) (xy 217.310723 -99.738684) (xy 217.318843 -99.79386) (xy 217.319352 -99.821746)
			(xy 217.318843 -99.849632) (xy 217.310723 -99.904808) (xy 217.294655 -99.958215) (xy 217.270983 -100.008712)
			(xy 217.24021 -100.055225) (xy 217.221596 -100.076) (xy 218.371672 -100.076) (xy 218.375743 -100.020378)
			(xy 218.387869 -99.965941) (xy 218.407792 -99.91385) (xy 218.435088 -99.865215) (xy 218.469174 -99.821072)
			(xy 218.509323 -99.782363) (xy 218.554681 -99.749912) (xy 218.604281 -99.724411) (xy 218.657065 -99.706404)
			(xy 218.711908 -99.696274) (xy 218.767642 -99.694237) (xy 218.823079 -99.700337) (xy 218.877036 -99.714443)
			(xy 218.928365 -99.736255) (xy 218.975971 -99.765309) (xy 219.018839 -99.800984) (xy 219.056056 -99.842521)
			(xy 219.086829 -99.889034) (xy 219.110501 -99.939531) (xy 219.126569 -99.992938) (xy 219.134689 -100.048114)
			(xy 219.135198 -100.076) (xy 219.134689 -100.103886) (xy 219.126569 -100.159062) (xy 219.110501 -100.212469)
			(xy 219.086829 -100.262966) (xy 219.056056 -100.309479) (xy 219.018839 -100.351016) (xy 218.975971 -100.386691)
			(xy 218.928365 -100.415745) (xy 218.877036 -100.437557) (xy 218.823079 -100.451663) (xy 218.767642 -100.457763)
			(xy 218.711908 -100.455726) (xy 218.657065 -100.445596) (xy 218.604281 -100.427589) (xy 218.554681 -100.402088)
			(xy 218.509323 -100.369637) (xy 218.469174 -100.330928) (xy 218.435088 -100.286785) (xy 218.407792 -100.23815)
			(xy 218.387869 -100.186059) (xy 218.375743 -100.131622) (xy 218.371672 -100.076) (xy 217.221596 -100.076)
			(xy 217.202993 -100.096762) (xy 217.160125 -100.132437) (xy 217.112519 -100.161491) (xy 217.06119 -100.183303)
			(xy 217.007233 -100.197409) (xy 216.951796 -100.203509) (xy 216.896062 -100.201472) (xy 216.841219 -100.191342)
			(xy 216.788435 -100.173335) (xy 216.738835 -100.147834) (xy 216.693477 -100.115383) (xy 216.653328 -100.076674)
			(xy 216.619242 -100.032531) (xy 216.591946 -99.983896) (xy 216.572023 -99.931805) (xy 216.559897 -99.877368)
			(xy 216.555826 -99.821746) (xy 213.43809 -99.821746) (xy 213.390829 -100.019882) (xy 213.335459 -100.217498)
			(xy 213.272422 -100.412804) (xy 213.201812 -100.605502) (xy 213.123738 -100.795298) (xy 213.038318 -100.981904)
			(xy 212.945682 -101.165034) (xy 212.915684 -101.219) (xy 220.238826 -101.219) (xy 220.242897 -101.163378)
			(xy 220.255023 -101.108941) (xy 220.274946 -101.05685) (xy 220.302242 -101.008215) (xy 220.336328 -100.964072)
			(xy 220.376477 -100.925363) (xy 220.421835 -100.892912) (xy 220.471435 -100.867411) (xy 220.524219 -100.849404)
			(xy 220.579062 -100.839274) (xy 220.634796 -100.837237) (xy 220.690233 -100.843337) (xy 220.74419 -100.857443)
			(xy 220.795519 -100.879255) (xy 220.843125 -100.908309) (xy 220.885993 -100.943984) (xy 220.92321 -100.985521)
			(xy 220.953983 -101.032034) (xy 220.977655 -101.082531) (xy 220.993723 -101.135938) (xy 221.001843 -101.191114)
			(xy 221.002352 -101.219) (xy 221.001843 -101.246886) (xy 220.993723 -101.302062) (xy 220.977655 -101.355469)
			(xy 220.953983 -101.405966) (xy 220.92321 -101.452479) (xy 220.885993 -101.494016) (xy 220.843125 -101.529691)
			(xy 220.795519 -101.558745) (xy 220.74419 -101.580557) (xy 220.690233 -101.594663) (xy 220.634796 -101.600763)
			(xy 220.579062 -101.598726) (xy 220.524219 -101.588596) (xy 220.471435 -101.570589) (xy 220.421835 -101.545088)
			(xy 220.376477 -101.512637) (xy 220.336328 -101.473928) (xy 220.302242 -101.429785) (xy 220.274946 -101.38115)
			(xy 220.255023 -101.329059) (xy 220.242897 -101.274622) (xy 220.238826 -101.219) (xy 212.915684 -101.219)
			(xy 212.845972 -101.344411) (xy 212.739339 -101.519761) (xy 212.655167 -101.646736) (xy 217.531694 -101.646736)
			(xy 217.535765 -101.591114) (xy 217.547891 -101.536677) (xy 217.567814 -101.484586) (xy 217.59511 -101.435951)
			(xy 217.629196 -101.391808) (xy 217.669345 -101.353099) (xy 217.714703 -101.320648) (xy 217.764303 -101.295147)
			(xy 217.817087 -101.27714) (xy 217.87193 -101.26701) (xy 217.927664 -101.264973) (xy 217.983101 -101.271073)
			(xy 218.037058 -101.285179) (xy 218.088387 -101.306991) (xy 218.135993 -101.336045) (xy 218.178861 -101.37172)
			(xy 218.216078 -101.413257) (xy 218.246851 -101.45977) (xy 218.270523 -101.510267) (xy 218.286591 -101.563674)
			(xy 218.294711 -101.61885) (xy 218.29522 -101.646736) (xy 218.295011 -101.658166) (xy 218.69857 -101.658166)
			(xy 218.702641 -101.602544) (xy 218.714767 -101.548107) (xy 218.73469 -101.496016) (xy 218.761986 -101.447381)
			(xy 218.796072 -101.403238) (xy 218.836221 -101.364529) (xy 218.881579 -101.332078) (xy 218.931179 -101.306577)
			(xy 218.983963 -101.28857) (xy 219.038806 -101.27844) (xy 219.09454 -101.276403) (xy 219.149977 -101.282503)
			(xy 219.203934 -101.296609) (xy 219.255263 -101.318421) (xy 219.302869 -101.347475) (xy 219.345737 -101.38315)
			(xy 219.382954 -101.424687) (xy 219.413727 -101.4712) (xy 219.437399 -101.521697) (xy 219.453467 -101.575104)
			(xy 219.461587 -101.63028) (xy 219.462096 -101.658166) (xy 219.461587 -101.686052) (xy 219.453467 -101.741228)
			(xy 219.437399 -101.794635) (xy 219.413727 -101.845132) (xy 219.382954 -101.891645) (xy 219.345737 -101.933182)
			(xy 219.302869 -101.968857) (xy 219.255263 -101.997911) (xy 219.203934 -102.019723) (xy 219.149977 -102.033829)
			(xy 219.09454 -102.039929) (xy 219.038806 -102.037892) (xy 218.983963 -102.027762) (xy 218.931179 -102.009755)
			(xy 218.881579 -101.984254) (xy 218.836221 -101.951803) (xy 218.796072 -101.913094) (xy 218.761986 -101.868951)
			(xy 218.73469 -101.820316) (xy 218.714767 -101.768225) (xy 218.702641 -101.713788) (xy 218.69857 -101.658166)
			(xy 218.295011 -101.658166) (xy 218.294711 -101.674622) (xy 218.286591 -101.729798) (xy 218.270523 -101.783205)
			(xy 218.246851 -101.833702) (xy 218.216078 -101.880215) (xy 218.178861 -101.921752) (xy 218.135993 -101.957427)
			(xy 218.088387 -101.986481) (xy 218.037058 -102.008293) (xy 217.983101 -102.022399) (xy 217.927664 -102.028499)
			(xy 217.87193 -102.026462) (xy 217.817087 -102.016332) (xy 217.764303 -101.998325) (xy 217.714703 -101.972824)
			(xy 217.669345 -101.940373) (xy 217.629196 -101.901664) (xy 217.59511 -101.857521) (xy 217.567814 -101.808886)
			(xy 217.547891 -101.756795) (xy 217.535765 -101.702358) (xy 217.531694 -101.646736) (xy 212.655167 -101.646736)
			(xy 212.625946 -101.690817) (xy 212.505966 -101.857319) (xy 212.37958 -102.019013) (xy 212.246982 -102.175653)
			(xy 212.108374 -102.326999) (xy 211.963966 -102.472823) (xy 211.813979 -102.612902) (xy 211.65864 -102.747021)
			(xy 211.546791 -102.836218) (xy 217.543124 -102.836218) (xy 217.547195 -102.780596) (xy 217.559321 -102.726159)
			(xy 217.579244 -102.674068) (xy 217.60654 -102.625433) (xy 217.640626 -102.58129) (xy 217.680775 -102.542581)
			(xy 217.726133 -102.51013) (xy 217.775733 -102.484629) (xy 217.828517 -102.466622) (xy 217.88336 -102.456492)
			(xy 217.939094 -102.454455) (xy 217.994531 -102.460555) (xy 218.048488 -102.474661) (xy 218.099817 -102.496473)
			(xy 218.147423 -102.525527) (xy 218.190291 -102.561202) (xy 218.227508 -102.602739) (xy 218.258281 -102.649252)
			(xy 218.281953 -102.699749) (xy 218.298021 -102.753156) (xy 218.306141 -102.808332) (xy 218.30665 -102.836218)
			(xy 218.709746 -102.836218) (xy 218.713817 -102.780596) (xy 218.725943 -102.726159) (xy 218.745866 -102.674068)
			(xy 218.773162 -102.625433) (xy 218.807248 -102.58129) (xy 218.847397 -102.542581) (xy 218.892755 -102.51013)
			(xy 218.942355 -102.484629) (xy 218.995139 -102.466622) (xy 219.049982 -102.456492) (xy 219.105716 -102.454455)
			(xy 219.161153 -102.460555) (xy 219.21511 -102.474661) (xy 219.266439 -102.496473) (xy 219.314045 -102.525527)
			(xy 219.356913 -102.561202) (xy 219.39413 -102.602739) (xy 219.424903 -102.649252) (xy 219.448575 -102.699749)
			(xy 219.464643 -102.753156) (xy 219.472763 -102.808332) (xy 219.473272 -102.836218) (xy 219.472763 -102.864104)
			(xy 219.465989 -102.910132) (xy 224.984056 -102.910132) (xy 224.984527 -102.882762) (xy 224.992342 -102.828582)
			(xy 225.007829 -102.776079) (xy 225.03067 -102.726332) (xy 225.060394 -102.680365) (xy 225.078036 -102.659434)
			(xy 225.07829 -102.65918) (xy 225.08389 -102.652103) (xy 225.090129 -102.635179) (xy 225.090482 -102.62616)
			(xy 225.090482 -102.559104) (xy 225.090127 -102.550087) (xy 225.083879 -102.53317) (xy 225.07829 -102.526084)
			(xy 225.078036 -102.526084) (xy 225.078036 -102.52583) (xy 225.060426 -102.504872) (xy 225.0307 -102.458909)
			(xy 225.007852 -102.409167) (xy 224.992353 -102.356669) (xy 224.984521 -102.302493) (xy 224.984517 -102.247755)
			(xy 224.992342 -102.193579) (xy 225.007835 -102.141078) (xy 225.030676 -102.091333) (xy 225.060397 -102.045367)
			(xy 225.078036 -102.024434) (xy 225.07829 -102.02418) (xy 225.08389 -102.017103) (xy 225.090129 -102.000179)
			(xy 225.090482 -101.99116) (xy 225.090482 -101.924104) (xy 225.090127 -101.915087) (xy 225.083879 -101.89817)
			(xy 225.07829 -101.891084) (xy 225.078036 -101.891084) (xy 225.078036 -101.89083) (xy 225.060403 -101.869893)
			(xy 225.030689 -101.823922) (xy 225.007851 -101.774176) (xy 224.992359 -101.721676) (xy 224.98453 -101.667501)
			(xy 224.984056 -101.640132) (xy 224.984542 -101.612881) (xy 224.992298 -101.558933) (xy 225.007653 -101.506638)
			(xy 225.030295 -101.457061) (xy 225.059761 -101.411211) (xy 225.095452 -101.37002) (xy 225.136643 -101.334329)
			(xy 225.182493 -101.304863) (xy 225.23207 -101.282221) (xy 225.284365 -101.266866) (xy 225.338313 -101.25911)
			(xy 225.392815 -101.25911) (xy 225.446763 -101.266866) (xy 225.499058 -101.282221) (xy 225.548635 -101.304863)
			(xy 225.594485 -101.334329) (xy 225.635676 -101.37002) (xy 225.671367 -101.411211) (xy 225.700833 -101.457061)
			(xy 225.723475 -101.506638) (xy 225.73883 -101.558933) (xy 225.746586 -101.612881) (xy 225.747072 -101.640132)
			(xy 225.746632 -101.667503) (xy 225.738809 -101.721684) (xy 225.723314 -101.774187) (xy 225.700466 -101.823934)
			(xy 225.670736 -101.869899) (xy 225.653092 -101.89083) (xy 225.652838 -101.891084) (xy 225.647245 -101.898166)
			(xy 225.641004 -101.915086) (xy 225.640646 -101.924104) (xy 225.640646 -101.99116) (xy 225.641012 -102.000176)
			(xy 225.647252 -102.017094) (xy 225.652838 -102.02418) (xy 225.653092 -102.02418) (xy 225.653092 -102.024434)
			(xy 225.670763 -102.045342) (xy 225.700485 -102.091314) (xy 225.723328 -102.141065) (xy 225.738821 -102.193571)
			(xy 225.746646 -102.247752) (xy 225.746642 -102.302496) (xy 225.73881 -102.356677) (xy 225.723311 -102.40918)
			(xy 225.700462 -102.458928) (xy 225.670734 -102.504897) (xy 225.653092 -102.52583) (xy 225.652838 -102.526084)
			(xy 225.647245 -102.533166) (xy 225.641004 -102.550086) (xy 225.640646 -102.559104) (xy 225.640646 -102.62616)
			(xy 225.641012 -102.635176) (xy 225.647252 -102.652094) (xy 225.648871 -102.654148) (xy 226.6389 -102.654148)
			(xy 226.6389 -102.599652) (xy 226.646655 -102.54571) (xy 226.662008 -102.493421) (xy 226.684645 -102.443849)
			(xy 226.714107 -102.398003) (xy 226.749792 -102.356816) (xy 226.790976 -102.321127) (xy 226.836819 -102.291661)
			(xy 226.886389 -102.26902) (xy 226.938677 -102.253663) (xy 226.992618 -102.245903) (xy 227.019866 -102.245414)
			(xy 227.046182 -102.245833) (xy 227.098312 -102.253077) (xy 227.148956 -102.267405) (xy 227.197155 -102.288547)
			(xy 227.241997 -102.316102) (xy 227.282635 -102.349549) (xy 227.30079 -102.368604) (xy 227.308313 -102.376004)
			(xy 227.327592 -102.384529) (xy 227.338128 -102.385114) (xy 227.412804 -102.385114) (xy 227.423355 -102.384596)
			(xy 227.44265 -102.376053) (xy 227.450142 -102.368604) (xy 227.468285 -102.349536) (xy 227.508917 -102.31608)
			(xy 227.55376 -102.288522) (xy 227.601963 -102.267386) (xy 227.652613 -102.253072) (xy 227.704749 -102.24585)
			(xy 227.731066 -102.245414) (xy 227.758322 -102.245831) (xy 227.81228 -102.253584) (xy 227.864585 -102.268938)
			(xy 227.914172 -102.29158) (xy 227.960032 -102.321049) (xy 228.001231 -102.356745) (xy 228.036931 -102.397941)
			(xy 228.066404 -102.443798) (xy 228.08905 -102.493383) (xy 228.104409 -102.545687) (xy 228.112167 -102.599644)
			(xy 228.112167 -102.654156) (xy 228.104409 -102.708113) (xy 228.08905 -102.760417) (xy 228.066404 -102.810002)
			(xy 228.036931 -102.855859) (xy 228.001231 -102.897055) (xy 227.960032 -102.932751) (xy 227.914172 -102.96222)
			(xy 227.864585 -102.984862) (xy 227.817145 -102.998788) (xy 245.903133 -102.998788) (xy 245.910884 -102.944834)
			(xy 245.926235 -102.892532) (xy 245.948873 -102.842947) (xy 245.978337 -102.797088) (xy 246.014028 -102.755889)
			(xy 246.055219 -102.720189) (xy 246.101071 -102.690714) (xy 246.150651 -102.668065) (xy 246.20295 -102.652702)
			(xy 246.256903 -102.644939) (xy 246.311411 -102.644933) (xy 246.365365 -102.652684) (xy 246.417668 -102.668035)
			(xy 246.467253 -102.690673) (xy 246.513112 -102.720137) (xy 246.55431 -102.755828) (xy 246.590011 -102.797018)
			(xy 246.619485 -102.84287) (xy 246.642135 -102.89245) (xy 246.657497 -102.944749) (xy 246.665261 -102.998702)
			(xy 246.66575 -103.025956) (xy 246.665643 -103.038952) (xy 246.663863 -103.064883) (xy 246.662194 -103.077772)
			(xy 246.661141 -103.089375) (xy 246.668426 -103.111479) (xy 246.676164 -103.12019) (xy 246.74068 -103.185976)
			(xy 246.76227 -103.19385) (xy 246.773954 -103.19258) (xy 246.774462 -103.19258) (xy 246.785093 -103.191423)
			(xy 246.806441 -103.19015) (xy 246.817134 -103.19004) (xy 246.844382 -103.190515) (xy 246.898321 -103.198274)
			(xy 246.950608 -103.213631) (xy 247.000177 -103.236273) (xy 247.046019 -103.265738) (xy 247.087202 -103.301427)
			(xy 247.122886 -103.342614) (xy 247.152347 -103.388459) (xy 247.174983 -103.43803) (xy 247.190334 -103.490319)
			(xy 247.198088 -103.544259) (xy 247.198087 -103.598754) (xy 247.190331 -103.652695) (xy 247.174978 -103.704982)
			(xy 247.15234 -103.754553) (xy 247.122878 -103.800397) (xy 247.087192 -103.841582) (xy 247.046008 -103.87727)
			(xy 247.000165 -103.906733) (xy 246.950595 -103.929373) (xy 246.898308 -103.944728) (xy 246.844368 -103.952486)
			(xy 246.789873 -103.952489) (xy 246.735932 -103.944737) (xy 246.683644 -103.929388) (xy 246.634071 -103.906753)
			(xy 246.588225 -103.877295) (xy 246.547037 -103.841612) (xy 246.511347 -103.80043) (xy 246.48188 -103.754589)
			(xy 246.459236 -103.705021) (xy 246.443877 -103.652735) (xy 246.436116 -103.598795) (xy 246.435626 -103.571548)
			(xy 246.435733 -103.558552) (xy 246.437513 -103.532621) (xy 246.439182 -103.519732) (xy 246.440239 -103.508129)
			(xy 246.432952 -103.486024) (xy 246.425212 -103.477314) (xy 246.360696 -103.411528) (xy 246.339106 -103.403654)
			(xy 246.327422 -103.404924) (xy 246.326914 -103.404924) (xy 246.316283 -103.406083) (xy 246.294935 -103.407355)
			(xy 246.284242 -103.407464) (xy 246.256988 -103.407067) (xy 246.203033 -103.399316) (xy 246.150731 -103.383965)
			(xy 246.101146 -103.361327) (xy 246.055287 -103.331862) (xy 246.014089 -103.296171) (xy 245.978389 -103.254981)
			(xy 245.948914 -103.209128) (xy 245.926265 -103.159548) (xy 245.910902 -103.10725) (xy 245.903139 -103.053297)
			(xy 245.903133 -102.998788) (xy 227.817145 -102.998788) (xy 227.81228 -103.000216) (xy 227.758322 -103.007969)
			(xy 227.731066 -103.00843) (xy 227.704752 -103.007976) (xy 227.652623 -103.000737) (xy 227.60198 -102.986414)
			(xy 227.553782 -102.96528) (xy 227.508938 -102.937732) (xy 227.468299 -102.904292) (xy 227.450142 -102.88524)
			(xy 227.442601 -102.877861) (xy 227.423336 -102.869322) (xy 227.412804 -102.86873) (xy 227.338128 -102.86873)
			(xy 227.327577 -102.869252) (xy 227.308281 -102.877791) (xy 227.30079 -102.88524) (xy 227.28264 -102.904301)
			(xy 227.242008 -102.937756) (xy 227.197167 -102.965313) (xy 227.148965 -102.986451) (xy 227.098317 -103.000767)
			(xy 227.046182 -103.007991) (xy 227.019866 -103.00843) (xy 226.992618 -103.007897) (xy 226.938677 -103.000137)
			(xy 226.886389 -102.98478) (xy 226.836819 -102.962139) (xy 226.790976 -102.932673) (xy 226.749792 -102.896984)
			(xy 226.714107 -102.855797) (xy 226.684645 -102.809951) (xy 226.662008 -102.760379) (xy 226.646655 -102.70809)
			(xy 226.6389 -102.654148) (xy 225.648871 -102.654148) (xy 225.652838 -102.65918) (xy 225.653092 -102.659688)
			(xy 225.664036 -102.672422) (xy 225.683877 -102.699514) (xy 225.692716 -102.71379) (xy 225.69805 -102.72268)
			(xy 225.715068 -102.734872) (xy 225.808286 -102.755192) (xy 225.82886 -102.750874) (xy 225.837496 -102.745032)
			(xy 225.861562 -102.729035) (xy 225.913492 -102.703691) (xy 225.96865 -102.686464) (xy 226.025774 -102.677749)
			(xy 226.054666 -102.677214) (xy 226.081922 -102.677631) (xy 226.13588 -102.685384) (xy 226.188185 -102.700738)
			(xy 226.237772 -102.72338) (xy 226.283632 -102.752849) (xy 226.324831 -102.788545) (xy 226.360531 -102.829741)
			(xy 226.390004 -102.875598) (xy 226.41265 -102.925183) (xy 226.428009 -102.977487) (xy 226.435767 -103.031444)
			(xy 226.435767 -103.085956) (xy 226.428009 -103.139913) (xy 226.41265 -103.192217) (xy 226.390004 -103.241802)
			(xy 226.360531 -103.287659) (xy 226.324831 -103.328855) (xy 226.283632 -103.364551) (xy 226.237772 -103.39402)
			(xy 226.188185 -103.416662) (xy 226.13588 -103.432016) (xy 226.081922 -103.439769) (xy 226.054666 -103.44023)
			(xy 226.026574 -103.439756) (xy 225.970996 -103.431525) (xy 225.917227 -103.415229) (xy 225.866429 -103.391223)
			(xy 225.819703 -103.360025) (xy 225.778058 -103.322311) (xy 225.742396 -103.278895) (xy 225.727514 -103.255064)
			(xy 225.72218 -103.246174) (xy 225.705162 -103.233982) (xy 225.611944 -103.213662) (xy 225.59137 -103.21798)
			(xy 225.582734 -103.223822) (xy 225.558664 -103.239812) (xy 225.506735 -103.265157) (xy 225.451579 -103.282385)
			(xy 225.394456 -103.291103) (xy 225.365564 -103.29164) (xy 225.338313 -103.291156) (xy 225.284367 -103.283395)
			(xy 225.232074 -103.268037) (xy 225.182499 -103.245394) (xy 225.13665 -103.215927) (xy 225.095462 -103.180236)
			(xy 225.059771 -103.139046) (xy 225.030304 -103.093197) (xy 225.007661 -103.043622) (xy 224.992304 -102.991329)
			(xy 224.984544 -102.937383) (xy 224.984056 -102.910132) (xy 219.465989 -102.910132) (xy 219.464643 -102.91928)
			(xy 219.448575 -102.972687) (xy 219.424903 -103.023184) (xy 219.39413 -103.069697) (xy 219.356913 -103.111234)
			(xy 219.314045 -103.146909) (xy 219.266439 -103.175963) (xy 219.21511 -103.197775) (xy 219.161153 -103.211881)
			(xy 219.105716 -103.217981) (xy 219.049982 -103.215944) (xy 218.995139 -103.205814) (xy 218.942355 -103.187807)
			(xy 218.892755 -103.162306) (xy 218.847397 -103.129855) (xy 218.807248 -103.091146) (xy 218.773162 -103.047003)
			(xy 218.745866 -102.998368) (xy 218.725943 -102.946277) (xy 218.713817 -102.89184) (xy 218.709746 -102.836218)
			(xy 218.30665 -102.836218) (xy 218.306141 -102.864104) (xy 218.298021 -102.91928) (xy 218.281953 -102.972687)
			(xy 218.258281 -103.023184) (xy 218.227508 -103.069697) (xy 218.190291 -103.111234) (xy 218.147423 -103.146909)
			(xy 218.099817 -103.175963) (xy 218.048488 -103.197775) (xy 217.994531 -103.211881) (xy 217.939094 -103.217981)
			(xy 217.88336 -103.215944) (xy 217.828517 -103.205814) (xy 217.775733 -103.187807) (xy 217.726133 -103.162306)
			(xy 217.680775 -103.129855) (xy 217.640626 -103.091146) (xy 217.60654 -103.047003) (xy 217.579244 -102.998368)
			(xy 217.559321 -102.946277) (xy 217.547195 -102.89184) (xy 217.543124 -102.836218) (xy 211.546791 -102.836218)
			(xy 211.498187 -102.874978) (xy 211.332864 -102.996578) (xy 211.162922 -103.111634) (xy 210.988621 -103.219973)
			(xy 210.810225 -103.321428) (xy 210.628007 -103.415846) (xy 210.442244 -103.503082) (xy 210.253219 -103.583005)
			(xy 210.061219 -103.655491) (xy 209.866537 -103.720431) (xy 209.66947 -103.777726) (xy 209.525282 -103.81361)
			(xy 214.526874 -103.81361) (xy 214.530945 -103.757988) (xy 214.543071 -103.703551) (xy 214.562994 -103.65146)
			(xy 214.59029 -103.602825) (xy 214.624376 -103.558682) (xy 214.664525 -103.519973) (xy 214.709883 -103.487522)
			(xy 214.759483 -103.462021) (xy 214.812267 -103.444014) (xy 214.86711 -103.433884) (xy 214.922844 -103.431847)
			(xy 214.978281 -103.437947) (xy 215.032238 -103.452053) (xy 215.083567 -103.473865) (xy 215.131173 -103.502919)
			(xy 215.174041 -103.538594) (xy 215.1973 -103.564553) (xy 220.431836 -103.564553) (xy 220.431836 -103.510047)
			(xy 220.439592 -103.456096) (xy 220.454948 -103.403798) (xy 220.477589 -103.354218) (xy 220.507055 -103.308364)
			(xy 220.542747 -103.26717) (xy 220.583938 -103.231475) (xy 220.62979 -103.202004) (xy 220.679368 -103.179359)
			(xy 220.731665 -103.163999) (xy 220.785615 -103.156238) (xy 220.812868 -103.15575) (xy 220.839962 -103.156196)
			(xy 220.893606 -103.163859) (xy 220.945626 -103.179037) (xy 220.994974 -103.201424) (xy 221.040658 -103.230568)
			(xy 221.081757 -103.265884) (xy 221.117446 -103.306661) (xy 221.147005 -103.352077) (xy 221.16984 -103.40122)
			(xy 221.17812 -103.427022) (xy 221.182542 -103.440368) (xy 221.197638 -103.464076) (xy 221.218626 -103.48277)
			(xy 221.243916 -103.495034) (xy 221.271592 -103.499938) (xy 221.299556 -103.49711) (xy 221.325689 -103.486766)
			(xy 221.337124 -103.478584) (xy 221.357132 -103.463741) (xy 221.400296 -103.438866) (xy 221.446336 -103.419833)
			(xy 221.494466 -103.406969) (xy 221.543862 -103.400493) (xy 221.568772 -103.400098) (xy 221.596027 -103.400547)
			(xy 221.649981 -103.408301) (xy 221.702283 -103.423655) (xy 221.751868 -103.446296) (xy 221.797725 -103.475764)
			(xy 221.838922 -103.511458) (xy 221.874619 -103.552652) (xy 221.90409 -103.598508) (xy 221.926735 -103.64809)
			(xy 221.942093 -103.700391) (xy 221.949851 -103.754345) (xy 221.949851 -103.808855) (xy 221.942093 -103.862809)
			(xy 221.926735 -103.91511) (xy 221.90409 -103.964692) (xy 221.874619 -104.010548) (xy 221.838922 -104.051742)
			(xy 221.797725 -104.087436) (xy 221.751868 -104.116904) (xy 221.702283 -104.139545) (xy 221.649981 -104.154899)
			(xy 221.596027 -104.162653) (xy 221.568772 -104.163114) (xy 221.541681 -104.162587) (xy 221.488042 -104.154931)
			(xy 221.436027 -104.139761) (xy 221.386682 -104.117384) (xy 221.340999 -104.08825) (xy 221.299899 -104.052944)
			(xy 221.264208 -104.012178) (xy 221.234645 -103.966772) (xy 221.211804 -103.91764) (xy 221.20352 -103.891842)
			(xy 221.199018 -103.878525) (xy 221.183941 -103.854816) (xy 221.162969 -103.836117) (xy 221.137692 -103.823848)
			(xy 221.110027 -103.818939) (xy 221.082072 -103.821761) (xy 221.055947 -103.832101) (xy 221.044516 -103.84028)
			(xy 221.024492 -103.8551) (xy 220.981332 -103.87998) (xy 220.935296 -103.899017) (xy 220.88717 -103.911887)
			(xy 220.837777 -103.918368) (xy 220.812868 -103.918766) (xy 220.785615 -103.918362) (xy 220.731665 -103.910601)
			(xy 220.679368 -103.895241) (xy 220.62979 -103.872596) (xy 220.583938 -103.843125) (xy 220.542747 -103.80743)
			(xy 220.507055 -103.766236) (xy 220.477589 -103.720382) (xy 220.454948 -103.670802) (xy 220.439592 -103.618504)
			(xy 220.431836 -103.564553) (xy 215.1973 -103.564553) (xy 215.211258 -103.580131) (xy 215.242031 -103.626644)
			(xy 215.265703 -103.677141) (xy 215.281771 -103.730548) (xy 215.289891 -103.785724) (xy 215.2904 -103.81361)
			(xy 215.289891 -103.841496) (xy 215.281771 -103.896672) (xy 215.265703 -103.950079) (xy 215.242031 -104.000576)
			(xy 215.211258 -104.047089) (xy 215.174041 -104.088626) (xy 215.131173 -104.124301) (xy 215.083567 -104.153355)
			(xy 215.032238 -104.175167) (xy 214.978281 -104.189273) (xy 214.922844 -104.195373) (xy 214.86711 -104.193336)
			(xy 214.812267 -104.183206) (xy 214.759483 -104.165199) (xy 214.709883 -104.139698) (xy 214.664525 -104.107247)
			(xy 214.624376 -104.068538) (xy 214.59029 -104.024395) (xy 214.562994 -103.97576) (xy 214.543071 -103.923669)
			(xy 214.530945 -103.869232) (xy 214.526874 -103.81361) (xy 209.525282 -103.81361) (xy 209.470317 -103.827289)
			(xy 209.269383 -103.869044) (xy 209.066972 -103.902927) (xy 208.863394 -103.928887) (xy 208.658957 -103.946884)
			(xy 208.453974 -103.956892) (xy 208.248757 -103.958894) (xy 208.043618 -103.952888) (xy 207.838869 -103.938883)
			(xy 207.634822 -103.9169) (xy 207.431789 -103.886973) (xy 207.230078 -103.849146) (xy 207.029996 -103.803479)
			(xy 206.831849 -103.75004) (xy 206.635937 -103.688911) (xy 206.44256 -103.620185) (xy 206.252011 -103.543966)
			(xy 206.064581 -103.46037) (xy 205.880555 -103.369526) (xy 205.700214 -103.271571) (xy 205.523832 -103.166654)
			(xy 205.351678 -103.054935) (xy 205.184013 -102.936585) (xy 205.021094 -102.811783) (xy 204.863168 -102.680719)
			(xy 204.710476 -102.543594) (xy 204.563251 -102.400616) (xy 204.421716 -102.252002) (xy 204.286087 -102.09798)
			(xy 204.15657 -101.938783) (xy 204.033364 -101.774654) (xy 203.916655 -101.605843) (xy 203.806621 -101.432606)
			(xy 203.70343 -101.255209) (xy 203.607239 -101.073921) (xy 203.518194 -100.889018) (xy 203.436431 -100.700781)
			(xy 203.362075 -100.509498) (xy 203.295239 -100.315459) (xy 203.236024 -100.11896) (xy 203.184521 -99.920301)
			(xy 203.140807 -99.719783) (xy 203.104951 -99.517712) (xy 203.077006 -99.314397) (xy 203.057015 -99.110146)
			(xy 203.045008 -98.90527) (xy 203.041004 -98.700082) (xy 200.925684 -98.700082) (xy 200.967848 -98.742246)
			(xy 200.990751 -98.765838) (xy 201.031747 -98.817246) (xy 201.066736 -98.872917) (xy 201.095278 -98.932153)
			(xy 201.117015 -98.994209) (xy 201.131674 -99.058308) (xy 201.139071 -99.123644) (xy 201.139552 -99.15652)
			(xy 201.139552 -102.750112) (xy 201.140066 -102.7611) (xy 201.149136 -102.781111) (xy 201.157078 -102.78872)
			(xy 201.215244 -102.838758) (xy 201.223818 -102.845531) (xy 201.244751 -102.851715) (xy 201.25563 -102.850696)
			(xy 201.255884 -102.850696) (xy 201.269649 -102.848801) (xy 201.297362 -102.846768) (xy 201.311256 -102.846632)
			(xy 201.33851 -102.847096) (xy 201.392463 -102.854848) (xy 201.444763 -102.870201) (xy 201.494345 -102.892841)
			(xy 201.540201 -102.922308) (xy 201.581395 -102.958002) (xy 201.617089 -102.999196) (xy 201.646557 -103.045051)
			(xy 201.669198 -103.094633) (xy 201.684551 -103.146934) (xy 201.692303 -103.200886) (xy 201.692764 -103.22814)
			(xy 201.692764 -103.228394) (xy 201.692447 -103.25044) (xy 201.687349 -103.294238) (xy 201.682604 -103.31577)
			(xy 201.680064 -103.325676) (xy 201.68362 -103.345996) (xy 201.734928 -103.425244) (xy 201.751438 -103.436674)
			(xy 201.761598 -103.438706) (xy 201.762106 -103.438706) (xy 201.794983 -103.445691) (xy 201.859011 -103.466138)
			(xy 201.920278 -103.493778) (xy 201.97798 -103.528247) (xy 202.031359 -103.569093) (xy 202.079713 -103.615779)
			(xy 202.122406 -103.667692) (xy 202.158879 -103.724149) (xy 202.188652 -103.784409) (xy 202.211333 -103.84768)
			(xy 202.226625 -103.91313) (xy 202.234327 -103.979901) (xy 202.2348 -104.013508) (xy 202.234298 -104.048897)
			(xy 202.225768 -104.119159) (xy 202.208833 -104.18788) (xy 202.18374 -104.254061) (xy 202.150855 -104.316735)
			(xy 202.110657 -104.374989) (xy 202.063732 -104.427975) (xy 202.010764 -104.47492) (xy 201.985233 -104.492552)
			(xy 215.414096 -104.492552) (xy 215.418167 -104.43693) (xy 215.430293 -104.382493) (xy 215.450216 -104.330402)
			(xy 215.477512 -104.281767) (xy 215.511598 -104.237624) (xy 215.551747 -104.198915) (xy 215.597105 -104.166464)
			(xy 215.646705 -104.140963) (xy 215.699489 -104.122956) (xy 215.754332 -104.112826) (xy 215.810066 -104.110789)
			(xy 215.865503 -104.116889) (xy 215.91946 -104.130995) (xy 215.970789 -104.152807) (xy 216.018395 -104.181861)
			(xy 216.061263 -104.217536) (xy 216.09848 -104.259073) (xy 216.129253 -104.305586) (xy 216.152925 -104.356083)
			(xy 216.168993 -104.40949) (xy 216.177113 -104.464666) (xy 216.177622 -104.492552) (xy 216.177113 -104.520438)
			(xy 216.168993 -104.575614) (xy 216.152925 -104.629021) (xy 216.147719 -104.640126) (xy 216.7923 -104.640126)
			(xy 216.796371 -104.584504) (xy 216.808497 -104.530067) (xy 216.82842 -104.477976) (xy 216.855716 -104.429341)
			(xy 216.889802 -104.385198) (xy 216.929951 -104.346489) (xy 216.975309 -104.314038) (xy 217.024909 -104.288537)
			(xy 217.077693 -104.27053) (xy 217.132536 -104.2604) (xy 217.18827 -104.258363) (xy 217.243707 -104.264463)
			(xy 217.297664 -104.278569) (xy 217.348993 -104.300381) (xy 217.396599 -104.329435) (xy 217.439467 -104.36511)
			(xy 217.442366 -104.368346) (xy 218.571062 -104.368346) (xy 218.575133 -104.312724) (xy 218.587259 -104.258287)
			(xy 218.607182 -104.206196) (xy 218.634478 -104.157561) (xy 218.668564 -104.113418) (xy 218.708713 -104.074709)
			(xy 218.754071 -104.042258) (xy 218.803671 -104.016757) (xy 218.856455 -103.99875) (xy 218.911298 -103.98862)
			(xy 218.967032 -103.986583) (xy 219.022469 -103.992683) (xy 219.076426 -104.006789) (xy 219.127755 -104.028601)
			(xy 219.175361 -104.057655) (xy 219.218229 -104.09333) (xy 219.255446 -104.134867) (xy 219.286219 -104.18138)
			(xy 219.309891 -104.231877) (xy 219.325959 -104.285284) (xy 219.334079 -104.34046) (xy 219.334588 -104.368346)
			(xy 219.334079 -104.396232) (xy 219.325959 -104.451408) (xy 219.309891 -104.504815) (xy 219.286219 -104.555312)
			(xy 219.270912 -104.578448) (xy 222.806304 -104.578448) (xy 222.806304 -104.523952) (xy 222.814059 -104.470012)
			(xy 222.829411 -104.417724) (xy 222.852048 -104.368153) (xy 222.881508 -104.322308) (xy 222.917193 -104.281121)
			(xy 222.958376 -104.245432) (xy 223.004218 -104.215967) (xy 223.053787 -104.193325) (xy 223.106073 -104.177968)
			(xy 223.160013 -104.170207) (xy 223.18726 -104.169718) (xy 223.21463 -104.170203) (xy 223.268808 -104.178016)
			(xy 223.321311 -104.1935) (xy 223.371058 -104.216338) (xy 223.417026 -104.246058) (xy 223.437958 -104.263698)
			(xy 223.438212 -104.263952) (xy 223.445286 -104.269556) (xy 223.462213 -104.275791) (xy 223.471232 -104.276144)
			(xy 223.538288 -104.276144) (xy 223.547306 -104.275793) (xy 223.564223 -104.269543) (xy 223.571308 -104.263952)
			(xy 223.571308 -104.263698) (xy 223.571562 -104.263698) (xy 223.592497 -104.246063) (xy 223.638469 -104.216351)
			(xy 223.688216 -104.193514) (xy 223.740716 -104.178022) (xy 223.794891 -104.170193) (xy 223.82226 -104.169718)
			(xy 223.849517 -104.170126) (xy 223.903476 -104.177879) (xy 223.955782 -104.193233) (xy 224.00537 -104.215874)
			(xy 224.051232 -104.245343) (xy 224.092432 -104.28104) (xy 224.128133 -104.322236) (xy 224.157606 -104.368094)
			(xy 224.180253 -104.417681) (xy 224.195612 -104.469985) (xy 224.203371 -104.523943) (xy 224.203371 -104.578457)
			(xy 224.195612 -104.632415) (xy 224.180253 -104.684719) (xy 224.157606 -104.734306) (xy 224.128133 -104.780164)
			(xy 224.092432 -104.82136) (xy 224.051232 -104.857057) (xy 224.00537 -104.886526) (xy 223.955782 -104.909167)
			(xy 223.903476 -104.924521) (xy 223.849517 -104.932274) (xy 223.82226 -104.932734) (xy 223.79489 -104.932249)
			(xy 223.740711 -104.924438) (xy 223.688208 -104.908954) (xy 223.638461 -104.886116) (xy 223.592494 -104.856394)
			(xy 223.571562 -104.838754) (xy 223.571308 -104.8385) (xy 223.564223 -104.832911) (xy 223.547305 -104.826666)
			(xy 223.538288 -104.826308) (xy 223.471232 -104.826308) (xy 223.462216 -104.826678) (xy 223.445299 -104.832916)
			(xy 223.438212 -104.8385) (xy 223.438212 -104.838754) (xy 223.437958 -104.838754) (xy 223.417009 -104.856372)
			(xy 223.371042 -104.886089) (xy 223.321298 -104.908929) (xy 223.268801 -104.924425) (xy 223.214628 -104.932258)
			(xy 223.18726 -104.932734) (xy 223.160013 -104.932193) (xy 223.106073 -104.924432) (xy 223.053787 -104.909075)
			(xy 223.004218 -104.886433) (xy 222.958376 -104.856968) (xy 222.917193 -104.821279) (xy 222.881508 -104.780092)
			(xy 222.852048 -104.734247) (xy 222.829411 -104.684676) (xy 222.814059 -104.632388) (xy 222.806304 -104.578448)
			(xy 219.270912 -104.578448) (xy 219.255446 -104.601825) (xy 219.218229 -104.643362) (xy 219.175361 -104.679037)
			(xy 219.127755 -104.708091) (xy 219.076426 -104.729903) (xy 219.022469 -104.744009) (xy 218.967032 -104.750109)
			(xy 218.911298 -104.748072) (xy 218.856455 -104.737942) (xy 218.803671 -104.719935) (xy 218.754071 -104.694434)
			(xy 218.708713 -104.661983) (xy 218.668564 -104.623274) (xy 218.634478 -104.579131) (xy 218.607182 -104.530496)
			(xy 218.587259 -104.478405) (xy 218.575133 -104.423968) (xy 218.571062 -104.368346) (xy 217.442366 -104.368346)
			(xy 217.476684 -104.406647) (xy 217.507457 -104.45316) (xy 217.531129 -104.503657) (xy 217.547197 -104.557064)
			(xy 217.555317 -104.61224) (xy 217.555826 -104.640126) (xy 217.555317 -104.668012) (xy 217.547197 -104.723188)
			(xy 217.531129 -104.776595) (xy 217.507457 -104.827092) (xy 217.476684 -104.873605) (xy 217.439467 -104.915142)
			(xy 217.396599 -104.950817) (xy 217.348993 -104.979871) (xy 217.297664 -105.001683) (xy 217.243707 -105.015789)
			(xy 217.18827 -105.021889) (xy 217.132536 -105.019852) (xy 217.077693 -105.009722) (xy 217.024909 -104.991715)
			(xy 216.975309 -104.966214) (xy 216.929951 -104.933763) (xy 216.889802 -104.895054) (xy 216.855716 -104.850911)
			(xy 216.82842 -104.802276) (xy 216.808497 -104.750185) (xy 216.796371 -104.695748) (xy 216.7923 -104.640126)
			(xy 216.147719 -104.640126) (xy 216.129253 -104.679518) (xy 216.09848 -104.726031) (xy 216.061263 -104.767568)
			(xy 216.018395 -104.803243) (xy 215.970789 -104.832297) (xy 215.91946 -104.854109) (xy 215.865503 -104.868215)
			(xy 215.810066 -104.874315) (xy 215.754332 -104.872278) (xy 215.699489 -104.862148) (xy 215.646705 -104.844141)
			(xy 215.597105 -104.81864) (xy 215.551747 -104.786189) (xy 215.511598 -104.74748) (xy 215.477512 -104.703337)
			(xy 215.450216 -104.654702) (xy 215.430293 -104.602611) (xy 215.418167 -104.548174) (xy 215.414096 -104.492552)
			(xy 201.985233 -104.492552) (xy 201.952525 -104.51514) (xy 201.889863 -104.548049) (xy 201.823692 -104.573167)
			(xy 201.754977 -104.590128) (xy 201.684719 -104.598685) (xy 201.64933 -104.599232) (xy 200.863454 -104.599232)
			(xy 200.830601 -104.598775) (xy 200.765308 -104.591408) (xy 200.701249 -104.576782) (xy 200.639229 -104.555082)
			(xy 200.580025 -104.526579) (xy 200.524383 -104.491632) (xy 200.472999 -104.450679) (xy 200.449434 -104.427782)
			(xy 199.636126 -103.614474) (xy 199.613219 -103.590918) (xy 199.572255 -103.53954) (xy 199.537302 -103.483898)
			(xy 199.508798 -103.424693) (xy 199.487101 -103.362669) (xy 199.472485 -103.298606) (xy 199.465134 -103.233309)
			(xy 199.464676 -103.200454) (xy 199.464676 -99.730052) (xy 199.46423 -99.719985) (xy 199.456524 -99.701387)
			(xy 199.44969 -99.693984) (xy 191.288416 -91.53271) (xy 191.281003 -91.525886) (xy 191.262414 -91.518156)
			(xy 191.252348 -91.517724) (xy 182.813452 -91.517724) (xy 182.803385 -91.51817) (xy 182.784787 -91.525876)
			(xy 182.777384 -91.53271) (xy 182.202074 -92.108274) (xy 182.178518 -92.131181) (xy 182.12714 -92.172145)
			(xy 182.071498 -92.207098) (xy 182.012293 -92.235602) (xy 181.950269 -92.257299) (xy 181.886206 -92.271915)
			(xy 181.820909 -92.279266) (xy 181.788054 -92.279724) (xy 180.161946 -92.279724) (xy 180.129092 -92.279274)
			(xy 180.063799 -92.271906) (xy 179.99974 -92.257279) (xy 179.93772 -92.235578) (xy 179.878517 -92.207074)
			(xy 179.822874 -92.172126) (xy 179.77149 -92.131172) (xy 179.747926 -92.108274) (xy 179.528216 -91.88831)
			(xy 179.520803 -91.881486) (xy 179.502214 -91.873756) (xy 179.492148 -91.873324) (xy 157.235652 -91.873324)
			(xy 157.225585 -91.87377) (xy 157.206987 -91.881476) (xy 157.199584 -91.88831) (xy 155.422892 -93.66504)
			(xy 162.57524 -93.66504) (xy 162.575718 -93.622771) (xy 162.583514 -93.538592) (xy 162.599042 -93.455491)
			(xy 162.622171 -93.374178) (xy 162.652704 -93.295345) (xy 162.690378 -93.219665) (xy 162.734875 -93.147784)
			(xy 162.785813 -93.080315) (xy 162.842758 -93.017832) (xy 162.905225 -92.96087) (xy 162.972681 -92.909914)
			(xy 163.04455 -92.865398) (xy 163.12022 -92.827703) (xy 163.199045 -92.79715) (xy 163.280352 -92.773999)
			(xy 163.363448 -92.758448) (xy 163.447625 -92.75063) (xy 163.489894 -92.750132) (xy 165.394894 -92.750132)
			(xy 165.43715 -92.750639) (xy 165.521303 -92.758435) (xy 165.604378 -92.773961) (xy 165.685666 -92.797084)
			(xy 165.764474 -92.827608) (xy 165.84013 -92.865272) (xy 165.911989 -92.909755) (xy 165.979438 -92.960677)
			(xy 166.041902 -93.017604) (xy 166.098848 -93.080051) (xy 166.14979 -93.147484) (xy 166.194295 -93.21933)
			(xy 166.231981 -93.294975) (xy 166.262528 -93.373774) (xy 166.285676 -93.455055) (xy 166.301227 -93.538125)
			(xy 166.309048 -93.622276) (xy 166.309548 -93.664532) (xy 166.309548 -93.66504) (xy 166.309072 -93.707527)
			(xy 166.308986 -93.708448) (xy 185.190434 -93.708448) (xy 185.190434 -93.621552) (xy 185.198451 -93.535028)
			(xy 185.214418 -93.449612) (xy 185.238198 -93.366034) (xy 185.269588 -93.285007) (xy 185.30832 -93.207222)
			(xy 185.354064 -93.133342) (xy 185.406429 -93.063998) (xy 185.464969 -92.999781) (xy 185.529185 -92.941239)
			(xy 185.598528 -92.888873) (xy 185.672408 -92.843128) (xy 185.750192 -92.804394) (xy 185.831219 -92.773003)
			(xy 185.914797 -92.749222) (xy 186.000212 -92.733254) (xy 186.086736 -92.725235) (xy 186.130184 -92.724732)
			(xy 187.984384 -92.724732) (xy 188.027835 -92.725194) (xy 188.114368 -92.733211) (xy 188.199791 -92.749178)
			(xy 188.283377 -92.77296) (xy 188.364412 -92.804353) (xy 188.442204 -92.843089) (xy 188.51609 -92.888838)
			(xy 188.58544 -92.941209) (xy 188.649661 -92.999756) (xy 188.708206 -93.063979) (xy 188.760576 -93.13333)
			(xy 188.806323 -93.207217) (xy 188.845057 -93.28501) (xy 188.876448 -93.366046) (xy 188.900227 -93.449632)
			(xy 188.916192 -93.535056) (xy 188.924207 -93.621588) (xy 188.924692 -93.66504) (xy 188.924132 -93.710119)
			(xy 188.915488 -93.799862) (xy 188.898303 -93.888367) (xy 188.872734 -93.974824) (xy 188.856366 -94.01683)
			(xy 188.852048 -94.027752) (xy 188.853572 -94.051374) (xy 188.900562 -94.130876) (xy 188.907025 -94.140659)
			(xy 188.926603 -94.153507) (xy 188.938154 -94.155514) (xy 188.983803 -94.1616) (xy 189.073904 -94.180689)
			(xy 189.162025 -94.20747) (xy 189.247512 -94.241743) (xy 189.329728 -94.283254) (xy 189.408061 -94.331694)
			(xy 189.481931 -94.386703) (xy 189.550786 -94.447871) (xy 189.614115 -94.514744) (xy 189.671447 -94.586825)
			(xy 189.722356 -94.663577) (xy 189.766463 -94.744429) (xy 189.80344 -94.828782) (xy 189.833013 -94.916006)
			(xy 189.85496 -95.005454) (xy 189.86912 -95.09646) (xy 189.875386 -95.188347) (xy 189.873712 -95.280433)
			(xy 189.864111 -95.372032) (xy 189.846654 -95.462464) (xy 189.821471 -95.551055) (xy 189.788748 -95.637147)
			(xy 189.74873 -95.7201) (xy 189.701714 -95.799296) (xy 189.64805 -95.874148) (xy 189.588136 -95.944097)
			(xy 189.541746 -95.989648) (xy 191.663826 -95.989648) (xy 191.667897 -95.934026) (xy 191.680023 -95.879589)
			(xy 191.699946 -95.827498) (xy 191.727242 -95.778863) (xy 191.761328 -95.73472) (xy 191.801477 -95.696011)
			(xy 191.846835 -95.66356) (xy 191.896435 -95.638059) (xy 191.949219 -95.620052) (xy 192.004062 -95.609922)
			(xy 192.059796 -95.607885) (xy 192.115233 -95.613985) (xy 192.16919 -95.628091) (xy 192.220519 -95.649903)
			(xy 192.268125 -95.678957) (xy 192.310993 -95.714632) (xy 192.34821 -95.756169) (xy 192.378983 -95.802682)
			(xy 192.402655 -95.853179) (xy 192.418723 -95.906586) (xy 192.426843 -95.961762) (xy 192.427352 -95.989648)
			(xy 194.269358 -95.989648) (xy 194.273429 -95.934026) (xy 194.285555 -95.879589) (xy 194.305478 -95.827498)
			(xy 194.332774 -95.778863) (xy 194.36686 -95.73472) (xy 194.407009 -95.696011) (xy 194.452367 -95.66356)
			(xy 194.501967 -95.638059) (xy 194.554751 -95.620052) (xy 194.609594 -95.609922) (xy 194.665328 -95.607885)
			(xy 194.720765 -95.613985) (xy 194.774722 -95.628091) (xy 194.826051 -95.649903) (xy 194.873657 -95.678957)
			(xy 194.916525 -95.714632) (xy 194.953742 -95.756169) (xy 194.984515 -95.802682) (xy 195.008187 -95.853179)
			(xy 195.024255 -95.906586) (xy 195.032375 -95.961762) (xy 195.032884 -95.989648) (xy 195.032375 -96.017534)
			(xy 195.024255 -96.07271) (xy 195.008187 -96.126117) (xy 194.984515 -96.176614) (xy 194.953742 -96.223127)
			(xy 194.916525 -96.264664) (xy 194.873657 -96.300339) (xy 194.826051 -96.329393) (xy 194.774722 -96.351205)
			(xy 194.720765 -96.365311) (xy 194.665328 -96.371411) (xy 194.609594 -96.369374) (xy 194.554751 -96.359244)
			(xy 194.501967 -96.341237) (xy 194.452367 -96.315736) (xy 194.407009 -96.283285) (xy 194.36686 -96.244576)
			(xy 194.332774 -96.200433) (xy 194.305478 -96.151798) (xy 194.285555 -96.099707) (xy 194.273429 -96.04527)
			(xy 194.269358 -95.989648) (xy 192.427352 -95.989648) (xy 192.426843 -96.017534) (xy 192.418723 -96.07271)
			(xy 192.402655 -96.126117) (xy 192.378983 -96.176614) (xy 192.34821 -96.223127) (xy 192.310993 -96.264664)
			(xy 192.268125 -96.300339) (xy 192.220519 -96.329393) (xy 192.16919 -96.351205) (xy 192.115233 -96.365311)
			(xy 192.059796 -96.371411) (xy 192.004062 -96.369374) (xy 191.949219 -96.359244) (xy 191.896435 -96.341237)
			(xy 191.846835 -96.315736) (xy 191.801477 -96.283285) (xy 191.761328 -96.244576) (xy 191.727242 -96.200433)
			(xy 191.699946 -96.151798) (xy 191.680023 -96.099707) (xy 191.667897 -96.04527) (xy 191.663826 -95.989648)
			(xy 189.541746 -95.989648) (xy 189.522419 -96.008625) (xy 189.451386 -96.067251) (xy 189.375567 -96.119539)
			(xy 189.295525 -96.1651) (xy 189.211855 -96.203596) (xy 189.12518 -96.23474) (xy 189.036143 -96.258301)
			(xy 188.945408 -96.274103) (xy 188.853649 -96.28203) (xy 188.807598 -96.28251) (xy 188.807344 -96.28251)
			(xy 188.760445 -96.28198) (xy 188.667008 -96.273761) (xy 188.574652 -96.257374) (xy 188.484091 -96.232946)
			(xy 188.396023 -96.200664) (xy 188.311128 -96.160779) (xy 188.230061 -96.113597) (xy 188.153447 -96.059482)
			(xy 188.081877 -95.998854) (xy 188.015904 -95.932178) (xy 187.956037 -95.85997) (xy 187.902738 -95.782787)
			(xy 187.856418 -95.701224) (xy 187.817434 -95.615911) (xy 187.786087 -95.527506) (xy 187.76262 -95.436691)
			(xy 187.747212 -95.344167) (xy 187.739984 -95.250648) (xy 187.740991 -95.156856) (xy 187.750225 -95.063513)
			(xy 187.767614 -94.971341) (xy 187.793025 -94.881051) (xy 187.826262 -94.793339) (xy 187.846208 -94.75089)
			(xy 187.851796 -94.739206) (xy 187.850526 -94.713044) (xy 187.797694 -94.629224) (xy 187.792814 -94.622128)
			(xy 187.779357 -94.611398) (xy 187.763119 -94.605696) (xy 187.754514 -94.605348) (xy 186.130184 -94.605348)
			(xy 186.086736 -94.604765) (xy 186.000212 -94.596746) (xy 185.914797 -94.580778) (xy 185.831219 -94.556997)
			(xy 185.750192 -94.525606) (xy 185.672408 -94.486872) (xy 185.598528 -94.441127) (xy 185.529185 -94.388761)
			(xy 185.464969 -94.330219) (xy 185.406429 -94.266002) (xy 185.354064 -94.196658) (xy 185.30832 -94.122778)
			(xy 185.269588 -94.044993) (xy 185.238198 -93.963966) (xy 185.214418 -93.880388) (xy 185.198451 -93.794972)
			(xy 185.190434 -93.708448) (xy 166.308986 -93.708448) (xy 166.301189 -93.792133) (xy 166.285496 -93.875645)
			(xy 166.262127 -93.957342) (xy 166.231284 -94.03652) (xy 166.193232 -94.112497) (xy 166.1483 -94.184619)
			(xy 166.096874 -94.252263) (xy 166.039398 -94.314849) (xy 165.976366 -94.371835) (xy 165.908322 -94.422732)
			(xy 165.835852 -94.4671) (xy 165.75958 -94.504558) (xy 165.680164 -94.534782) (xy 165.598287 -94.557513)
			(xy 165.514656 -94.572554) (xy 165.472364 -94.576646) (xy 165.459827 -94.578303) (xy 165.438636 -94.592054)
			(xy 165.431978 -94.602808) (xy 165.384988 -94.687898) (xy 165.384734 -94.713044) (xy 165.390576 -94.724474)
			(xy 165.411052 -94.76517) (xy 165.445866 -94.849364) (xy 165.473378 -94.936219) (xy 165.493387 -95.025103)
			(xy 165.505747 -95.115369) (xy 165.51037 -95.206359) (xy 165.50722 -95.297413) (xy 165.496322 -95.387867)
			(xy 165.477754 -95.477063) (xy 165.451651 -95.564351) (xy 165.429758 -95.619824) (xy 174.129952 -95.619824)
			(xy 174.134023 -95.564202) (xy 174.146149 -95.509765) (xy 174.166072 -95.457674) (xy 174.193368 -95.409039)
			(xy 174.227454 -95.364896) (xy 174.267603 -95.326187) (xy 174.312961 -95.293736) (xy 174.362561 -95.268235)
			(xy 174.415345 -95.250228) (xy 174.470188 -95.240098) (xy 174.525922 -95.238061) (xy 174.581359 -95.244161)
			(xy 174.635316 -95.258267) (xy 174.686645 -95.280079) (xy 174.734251 -95.309133) (xy 174.777119 -95.344808)
			(xy 174.814336 -95.386345) (xy 174.845109 -95.432858) (xy 174.868781 -95.483355) (xy 174.884849 -95.536762)
			(xy 174.892969 -95.591938) (xy 174.893478 -95.619824) (xy 174.892969 -95.64771) (xy 174.884849 -95.702886)
			(xy 174.868781 -95.756293) (xy 174.845109 -95.80679) (xy 174.814336 -95.853303) (xy 174.777119 -95.89484)
			(xy 174.734251 -95.930515) (xy 174.686645 -95.959569) (xy 174.635316 -95.981381) (xy 174.581359 -95.995487)
			(xy 174.525922 -96.001587) (xy 174.470188 -95.99955) (xy 174.415345 -95.98942) (xy 174.362561 -95.971413)
			(xy 174.312961 -95.945912) (xy 174.267603 -95.913461) (xy 174.227454 -95.874752) (xy 174.193368 -95.830609)
			(xy 174.166072 -95.781974) (xy 174.146149 -95.729883) (xy 174.134023 -95.675446) (xy 174.129952 -95.619824)
			(xy 165.429758 -95.619824) (xy 165.418204 -95.649098) (xy 165.377655 -95.730685) (xy 165.330301 -95.80852)
			(xy 165.276485 -95.882035) (xy 165.216599 -95.950697) (xy 165.151079 -96.014004) (xy 165.080402 -96.071497)
			(xy 165.005082 -96.122757) (xy 164.925668 -96.167411) (xy 164.842736 -96.205134) (xy 164.756891 -96.235651)
			(xy 164.668757 -96.258741) (xy 164.578977 -96.274236) (xy 164.488202 -96.282022) (xy 164.442648 -96.28251)
			(xy 164.442394 -96.28251) (xy 164.396837 -96.281932) (xy 164.306054 -96.274166) (xy 164.216264 -96.25869)
			(xy 164.12812 -96.235616) (xy 164.042263 -96.205114) (xy 163.959318 -96.167405) (xy 163.879889 -96.122763)
			(xy 163.804555 -96.071514) (xy 163.733863 -96.01403) (xy 163.668327 -95.95073) (xy 163.608426 -95.882074)
			(xy 163.554594 -95.808562) (xy 163.507224 -95.73073) (xy 163.466661 -95.649143) (xy 163.433199 -95.564396)
			(xy 163.407082 -95.477105) (xy 163.388501 -95.387905) (xy 163.37759 -95.297447) (xy 163.374429 -95.206387)
			(xy 163.379041 -95.11539) (xy 163.391393 -95.025117) (xy 163.411393 -94.936225) (xy 163.438898 -94.849361)
			(xy 163.473707 -94.765158) (xy 163.494212 -94.724474) (xy 163.499356 -94.713035) (xy 163.498961 -94.687988)
			(xy 163.49345 -94.676722) (xy 163.45281 -94.602808) (xy 163.44615 -94.592059) (xy 163.424957 -94.578327)
			(xy 163.412424 -94.576646) (xy 163.370132 -94.572556) (xy 163.286501 -94.557513) (xy 163.204626 -94.534782)
			(xy 163.12521 -94.504557) (xy 163.048939 -94.467099) (xy 162.97647 -94.42273) (xy 162.908426 -94.371833)
			(xy 162.845395 -94.314846) (xy 162.78792 -94.252261) (xy 162.736494 -94.184616) (xy 162.691563 -94.112495)
			(xy 162.653511 -94.036518) (xy 162.622669 -93.95734) (xy 162.5993 -93.875644) (xy 162.583607 -93.792133)
			(xy 162.575725 -93.707526) (xy 162.57524 -93.66504) (xy 155.422892 -93.66504) (xy 152.923586 -96.1644)
			(xy 153.32532 -96.1644) (xy 153.329391 -96.108778) (xy 153.341517 -96.054341) (xy 153.36144 -96.00225)
			(xy 153.388736 -95.953615) (xy 153.422822 -95.909472) (xy 153.462971 -95.870763) (xy 153.508329 -95.838312)
			(xy 153.557929 -95.812811) (xy 153.610713 -95.794804) (xy 153.665556 -95.784674) (xy 153.72129 -95.782637)
			(xy 153.776727 -95.788737) (xy 153.830684 -95.802843) (xy 153.882013 -95.824655) (xy 153.929619 -95.853709)
			(xy 153.972487 -95.889384) (xy 154.009704 -95.930921) (xy 154.040477 -95.977434) (xy 154.064149 -96.027931)
			(xy 154.080217 -96.081338) (xy 154.088337 -96.136514) (xy 154.088846 -96.1644) (xy 154.088337 -96.192286)
			(xy 154.080217 -96.247462) (xy 154.064149 -96.300869) (xy 154.040477 -96.351366) (xy 154.009704 -96.397879)
			(xy 153.978345 -96.432878) (xy 183.362598 -96.432878) (xy 183.366669 -96.377256) (xy 183.378795 -96.322819)
			(xy 183.398718 -96.270728) (xy 183.426014 -96.222093) (xy 183.4601 -96.17795) (xy 183.500249 -96.139241)
			(xy 183.545607 -96.10679) (xy 183.595207 -96.081289) (xy 183.647991 -96.063282) (xy 183.702834 -96.053152)
			(xy 183.758568 -96.051115) (xy 183.814005 -96.057215) (xy 183.867962 -96.071321) (xy 183.919291 -96.093133)
			(xy 183.966897 -96.122187) (xy 184.009765 -96.157862) (xy 184.046982 -96.199399) (xy 184.077755 -96.245912)
			(xy 184.101427 -96.296409) (xy 184.117495 -96.349816) (xy 184.125615 -96.404992) (xy 184.125684 -96.408748)
			(xy 186.207906 -96.408748) (xy 186.211977 -96.353126) (xy 186.224103 -96.298689) (xy 186.244026 -96.246598)
			(xy 186.271322 -96.197963) (xy 186.305408 -96.15382) (xy 186.345557 -96.115111) (xy 186.390915 -96.08266)
			(xy 186.440515 -96.057159) (xy 186.493299 -96.039152) (xy 186.548142 -96.029022) (xy 186.603876 -96.026985)
			(xy 186.659313 -96.033085) (xy 186.71327 -96.047191) (xy 186.764599 -96.069003) (xy 186.812205 -96.098057)
			(xy 186.855073 -96.133732) (xy 186.89229 -96.175269) (xy 186.923063 -96.221782) (xy 186.946735 -96.272279)
			(xy 186.962803 -96.325686) (xy 186.970923 -96.380862) (xy 186.971432 -96.408748) (xy 186.970923 -96.436634)
			(xy 186.962803 -96.49181) (xy 186.946735 -96.545217) (xy 186.923063 -96.595714) (xy 186.89229 -96.642227)
			(xy 186.855073 -96.683764) (xy 186.812205 -96.719439) (xy 186.764599 -96.748493) (xy 186.71327 -96.770305)
			(xy 186.659313 -96.784411) (xy 186.603876 -96.790511) (xy 186.548142 -96.788474) (xy 186.493299 -96.778344)
			(xy 186.440515 -96.760337) (xy 186.390915 -96.734836) (xy 186.345557 -96.702385) (xy 186.305408 -96.663676)
			(xy 186.271322 -96.619533) (xy 186.244026 -96.570898) (xy 186.224103 -96.518807) (xy 186.211977 -96.46437)
			(xy 186.207906 -96.408748) (xy 184.125684 -96.408748) (xy 184.126124 -96.432878) (xy 184.125615 -96.460764)
			(xy 184.117495 -96.51594) (xy 184.101427 -96.569347) (xy 184.077755 -96.619844) (xy 184.046982 -96.666357)
			(xy 184.009765 -96.707894) (xy 183.966897 -96.743569) (xy 183.919291 -96.772623) (xy 183.867962 -96.794435)
			(xy 183.83634 -96.802702) (xy 185.421776 -96.802702) (xy 185.425847 -96.74708) (xy 185.437973 -96.692643)
			(xy 185.457896 -96.640552) (xy 185.485192 -96.591917) (xy 185.519278 -96.547774) (xy 185.559427 -96.509065)
			(xy 185.604785 -96.476614) (xy 185.654385 -96.451113) (xy 185.707169 -96.433106) (xy 185.762012 -96.422976)
			(xy 185.817746 -96.420939) (xy 185.873183 -96.427039) (xy 185.92714 -96.441145) (xy 185.978469 -96.462957)
			(xy 186.026075 -96.492011) (xy 186.068943 -96.527686) (xy 186.10616 -96.569223) (xy 186.136933 -96.615736)
			(xy 186.160605 -96.666233) (xy 186.176673 -96.71964) (xy 186.184793 -96.774816) (xy 186.185302 -96.802702)
			(xy 186.184793 -96.830588) (xy 186.176673 -96.885764) (xy 186.172089 -96.901) (xy 187.872876 -96.901)
			(xy 187.876947 -96.845378) (xy 187.889073 -96.790941) (xy 187.908996 -96.73885) (xy 187.936292 -96.690215)
			(xy 187.970378 -96.646072) (xy 188.010527 -96.607363) (xy 188.055885 -96.574912) (xy 188.105485 -96.549411)
			(xy 188.158269 -96.531404) (xy 188.213112 -96.521274) (xy 188.268846 -96.519237) (xy 188.324283 -96.525337)
			(xy 188.37824 -96.539443) (xy 188.429569 -96.561255) (xy 188.477175 -96.590309) (xy 188.520043 -96.625984)
			(xy 188.55726 -96.667521) (xy 188.588033 -96.714034) (xy 188.611705 -96.764531) (xy 188.627773 -96.817938)
			(xy 188.635893 -96.873114) (xy 188.636402 -96.901) (xy 188.635893 -96.928886) (xy 188.627773 -96.984062)
			(xy 188.611705 -97.037469) (xy 188.610548 -97.039938) (xy 190.825372 -97.039938) (xy 190.829443 -96.984316)
			(xy 190.841569 -96.929879) (xy 190.861492 -96.877788) (xy 190.888788 -96.829153) (xy 190.922874 -96.78501)
			(xy 190.963023 -96.746301) (xy 191.008381 -96.71385) (xy 191.057981 -96.688349) (xy 191.110765 -96.670342)
			(xy 191.165608 -96.660212) (xy 191.221342 -96.658175) (xy 191.276779 -96.664275) (xy 191.330736 -96.678381)
			(xy 191.382065 -96.700193) (xy 191.429671 -96.729247) (xy 191.472539 -96.764922) (xy 191.509756 -96.806459)
			(xy 191.512312 -96.810322) (xy 192.159634 -96.810322) (xy 192.163705 -96.7547) (xy 192.175831 -96.700263)
			(xy 192.195754 -96.648172) (xy 192.22305 -96.599537) (xy 192.257136 -96.555394) (xy 192.297285 -96.516685)
			(xy 192.342643 -96.484234) (xy 192.392243 -96.458733) (xy 192.445027 -96.440726) (xy 192.49987 -96.430596)
			(xy 192.555604 -96.428559) (xy 192.611041 -96.434659) (xy 192.664998 -96.448765) (xy 192.716327 -96.470577)
			(xy 192.763933 -96.499631) (xy 192.806801 -96.535306) (xy 192.844018 -96.576843) (xy 192.874791 -96.623356)
			(xy 192.898463 -96.673853) (xy 192.914531 -96.72726) (xy 192.922651 -96.782436) (xy 192.92316 -96.810322)
			(xy 192.922651 -96.838208) (xy 192.914531 -96.893384) (xy 192.898463 -96.946791) (xy 192.874791 -96.997288)
			(xy 192.86926 -97.005648) (xy 194.269358 -97.005648) (xy 194.273429 -96.950026) (xy 194.285555 -96.895589)
			(xy 194.305478 -96.843498) (xy 194.332774 -96.794863) (xy 194.36686 -96.75072) (xy 194.407009 -96.712011)
			(xy 194.452367 -96.67956) (xy 194.501967 -96.654059) (xy 194.554751 -96.636052) (xy 194.609594 -96.625922)
			(xy 194.665328 -96.623885) (xy 194.720765 -96.629985) (xy 194.774722 -96.644091) (xy 194.826051 -96.665903)
			(xy 194.873657 -96.694957) (xy 194.916525 -96.730632) (xy 194.953742 -96.772169) (xy 194.984515 -96.818682)
			(xy 195.008187 -96.869179) (xy 195.024255 -96.922586) (xy 195.032375 -96.977762) (xy 195.032884 -97.005648)
			(xy 195.032375 -97.033534) (xy 195.024255 -97.08871) (xy 195.008187 -97.142117) (xy 194.984515 -97.192614)
			(xy 194.953742 -97.239127) (xy 194.916525 -97.280664) (xy 194.873657 -97.316339) (xy 194.826051 -97.345393)
			(xy 194.774722 -97.367205) (xy 194.720765 -97.381311) (xy 194.665328 -97.387411) (xy 194.609594 -97.385374)
			(xy 194.554751 -97.375244) (xy 194.501967 -97.357237) (xy 194.452367 -97.331736) (xy 194.407009 -97.299285)
			(xy 194.36686 -97.260576) (xy 194.332774 -97.216433) (xy 194.305478 -97.167798) (xy 194.285555 -97.115707)
			(xy 194.273429 -97.06127) (xy 194.269358 -97.005648) (xy 192.86926 -97.005648) (xy 192.844018 -97.043801)
			(xy 192.806801 -97.085338) (xy 192.763933 -97.121013) (xy 192.716327 -97.150067) (xy 192.664998 -97.171879)
			(xy 192.611041 -97.185985) (xy 192.555604 -97.192085) (xy 192.49987 -97.190048) (xy 192.445027 -97.179918)
			(xy 192.392243 -97.161911) (xy 192.342643 -97.13641) (xy 192.297285 -97.103959) (xy 192.257136 -97.06525)
			(xy 192.22305 -97.021107) (xy 192.195754 -96.972472) (xy 192.175831 -96.920381) (xy 192.163705 -96.865944)
			(xy 192.159634 -96.810322) (xy 191.512312 -96.810322) (xy 191.540529 -96.852972) (xy 191.564201 -96.903469)
			(xy 191.580269 -96.956876) (xy 191.588389 -97.012052) (xy 191.588898 -97.039938) (xy 191.588389 -97.067824)
			(xy 191.580269 -97.123) (xy 191.564201 -97.176407) (xy 191.540529 -97.226904) (xy 191.509756 -97.273417)
			(xy 191.472539 -97.314954) (xy 191.429671 -97.350629) (xy 191.382065 -97.379683) (xy 191.330736 -97.401495)
			(xy 191.276779 -97.415601) (xy 191.221342 -97.421701) (xy 191.165608 -97.419664) (xy 191.110765 -97.409534)
			(xy 191.057981 -97.391527) (xy 191.008381 -97.366026) (xy 190.963023 -97.333575) (xy 190.922874 -97.294866)
			(xy 190.888788 -97.250723) (xy 190.861492 -97.202088) (xy 190.841569 -97.149997) (xy 190.829443 -97.09556)
			(xy 190.825372 -97.039938) (xy 188.610548 -97.039938) (xy 188.588033 -97.087966) (xy 188.55726 -97.134479)
			(xy 188.520043 -97.176016) (xy 188.477175 -97.211691) (xy 188.429569 -97.240745) (xy 188.37824 -97.262557)
			(xy 188.324283 -97.276663) (xy 188.268846 -97.282763) (xy 188.213112 -97.280726) (xy 188.158269 -97.270596)
			(xy 188.105485 -97.252589) (xy 188.055885 -97.227088) (xy 188.010527 -97.194637) (xy 187.970378 -97.155928)
			(xy 187.936292 -97.111785) (xy 187.908996 -97.06315) (xy 187.889073 -97.011059) (xy 187.876947 -96.956622)
			(xy 187.872876 -96.901) (xy 186.172089 -96.901) (xy 186.160605 -96.939171) (xy 186.136933 -96.989668)
			(xy 186.10616 -97.036181) (xy 186.068943 -97.077718) (xy 186.026075 -97.113393) (xy 185.978469 -97.142447)
			(xy 185.92714 -97.164259) (xy 185.873183 -97.178365) (xy 185.817746 -97.184465) (xy 185.762012 -97.182428)
			(xy 185.707169 -97.172298) (xy 185.654385 -97.154291) (xy 185.604785 -97.12879) (xy 185.559427 -97.096339)
			(xy 185.519278 -97.05763) (xy 185.485192 -97.013487) (xy 185.457896 -96.964852) (xy 185.437973 -96.912761)
			(xy 185.425847 -96.858324) (xy 185.421776 -96.802702) (xy 183.83634 -96.802702) (xy 183.814005 -96.808541)
			(xy 183.758568 -96.814641) (xy 183.702834 -96.812604) (xy 183.647991 -96.802474) (xy 183.595207 -96.784467)
			(xy 183.545607 -96.758966) (xy 183.500249 -96.726515) (xy 183.4601 -96.687806) (xy 183.426014 -96.643663)
			(xy 183.398718 -96.595028) (xy 183.378795 -96.542937) (xy 183.366669 -96.4885) (xy 183.362598 -96.432878)
			(xy 153.978345 -96.432878) (xy 153.972487 -96.439416) (xy 153.929619 -96.475091) (xy 153.882013 -96.504145)
			(xy 153.830684 -96.525957) (xy 153.776727 -96.540063) (xy 153.72129 -96.546163) (xy 153.665556 -96.544126)
			(xy 153.610713 -96.533996) (xy 153.557929 -96.515989) (xy 153.508329 -96.490488) (xy 153.462971 -96.458037)
			(xy 153.422822 -96.419328) (xy 153.388736 -96.375185) (xy 153.36144 -96.32655) (xy 153.341517 -96.274459)
			(xy 153.329391 -96.220022) (xy 153.32532 -96.1644) (xy 152.923586 -96.1644) (xy 151.907608 -97.1804)
			(xy 153.32532 -97.1804) (xy 153.329391 -97.124778) (xy 153.341517 -97.070341) (xy 153.36144 -97.01825)
			(xy 153.388736 -96.969615) (xy 153.422822 -96.925472) (xy 153.462971 -96.886763) (xy 153.508329 -96.854312)
			(xy 153.557929 -96.828811) (xy 153.610713 -96.810804) (xy 153.665556 -96.800674) (xy 153.72129 -96.798637)
			(xy 153.776727 -96.804737) (xy 153.830684 -96.818843) (xy 153.882013 -96.840655) (xy 153.929619 -96.869709)
			(xy 153.972487 -96.905384) (xy 154.009704 -96.946921) (xy 154.040477 -96.993434) (xy 154.064149 -97.043931)
			(xy 154.067686 -97.055686) (xy 167.705276 -97.055686) (xy 167.709347 -97.000064) (xy 167.721473 -96.945627)
			(xy 167.741396 -96.893536) (xy 167.768692 -96.844901) (xy 167.802778 -96.800758) (xy 167.842927 -96.762049)
			(xy 167.888285 -96.729598) (xy 167.937885 -96.704097) (xy 167.990669 -96.68609) (xy 168.045512 -96.67596)
			(xy 168.101246 -96.673923) (xy 168.156683 -96.680023) (xy 168.21064 -96.694129) (xy 168.261969 -96.715941)
			(xy 168.309575 -96.744995) (xy 168.352443 -96.78067) (xy 168.38966 -96.822207) (xy 168.420433 -96.86872)
			(xy 168.444105 -96.919217) (xy 168.460173 -96.972624) (xy 168.468293 -97.0278) (xy 168.468802 -97.055686)
			(xy 168.468293 -97.083572) (xy 168.460173 -97.138748) (xy 168.444105 -97.192155) (xy 168.420433 -97.242652)
			(xy 168.38966 -97.289165) (xy 168.352443 -97.330702) (xy 168.309575 -97.366377) (xy 168.261969 -97.395431)
			(xy 168.21064 -97.417243) (xy 168.156683 -97.431349) (xy 168.101246 -97.437449) (xy 168.045512 -97.435412)
			(xy 167.990669 -97.425282) (xy 167.937885 -97.407275) (xy 167.888285 -97.381774) (xy 167.842927 -97.349323)
			(xy 167.802778 -97.310614) (xy 167.768692 -97.266471) (xy 167.741396 -97.217836) (xy 167.721473 -97.165745)
			(xy 167.709347 -97.111308) (xy 167.705276 -97.055686) (xy 154.067686 -97.055686) (xy 154.080217 -97.097338)
			(xy 154.088337 -97.152514) (xy 154.088846 -97.1804) (xy 154.088337 -97.208286) (xy 154.080217 -97.263462)
			(xy 154.064149 -97.316869) (xy 154.040477 -97.367366) (xy 154.009704 -97.413879) (xy 153.972487 -97.455416)
			(xy 153.929619 -97.491091) (xy 153.882013 -97.520145) (xy 153.830684 -97.541957) (xy 153.776727 -97.556063)
			(xy 153.72129 -97.562163) (xy 153.665556 -97.560126) (xy 153.610713 -97.549996) (xy 153.557929 -97.531989)
			(xy 153.508329 -97.506488) (xy 153.462971 -97.474037) (xy 153.422822 -97.435328) (xy 153.388736 -97.391185)
			(xy 153.36144 -97.34255) (xy 153.341517 -97.290459) (xy 153.329391 -97.236022) (xy 153.32532 -97.1804)
			(xy 151.907608 -97.1804) (xy 151.425018 -97.663) (xy 182.980582 -97.663) (xy 182.984653 -97.607378)
			(xy 182.996779 -97.552941) (xy 183.016702 -97.50085) (xy 183.043998 -97.452215) (xy 183.078084 -97.408072)
			(xy 183.118233 -97.369363) (xy 183.163591 -97.336912) (xy 183.213191 -97.311411) (xy 183.265975 -97.293404)
			(xy 183.320818 -97.283274) (xy 183.376552 -97.281237) (xy 183.431989 -97.287337) (xy 183.485946 -97.301443)
			(xy 183.537275 -97.323255) (xy 183.584881 -97.352309) (xy 183.627749 -97.387984) (xy 183.664966 -97.429521)
			(xy 183.695739 -97.476034) (xy 183.719411 -97.526531) (xy 183.735479 -97.579938) (xy 183.743599 -97.635114)
			(xy 183.743691 -97.64014) (xy 190.017906 -97.64014) (xy 190.021977 -97.584518) (xy 190.034103 -97.530081)
			(xy 190.054026 -97.47799) (xy 190.081322 -97.429355) (xy 190.115408 -97.385212) (xy 190.155557 -97.346503)
			(xy 190.200915 -97.314052) (xy 190.250515 -97.288551) (xy 190.303299 -97.270544) (xy 190.358142 -97.260414)
			(xy 190.413876 -97.258377) (xy 190.469313 -97.264477) (xy 190.52327 -97.278583) (xy 190.574599 -97.300395)
			(xy 190.622205 -97.329449) (xy 190.665073 -97.365124) (xy 190.70229 -97.406661) (xy 190.733063 -97.453174)
			(xy 190.756735 -97.503671) (xy 190.772803 -97.557078) (xy 190.780923 -97.612254) (xy 190.781432 -97.64014)
			(xy 190.780923 -97.668026) (xy 190.772803 -97.723202) (xy 190.756735 -97.776609) (xy 190.733063 -97.827106)
			(xy 190.70229 -97.873619) (xy 190.665073 -97.915156) (xy 190.622205 -97.950831) (xy 190.574599 -97.979885)
			(xy 190.52327 -98.001697) (xy 190.469313 -98.015803) (xy 190.413876 -98.021903) (xy 190.358142 -98.019866)
			(xy 190.303299 -98.009736) (xy 190.250515 -97.991729) (xy 190.200915 -97.966228) (xy 190.155557 -97.933777)
			(xy 190.115408 -97.895068) (xy 190.081322 -97.850925) (xy 190.054026 -97.80229) (xy 190.034103 -97.750199)
			(xy 190.021977 -97.695762) (xy 190.017906 -97.64014) (xy 183.743691 -97.64014) (xy 183.744108 -97.663)
			(xy 183.743599 -97.690886) (xy 183.735479 -97.746062) (xy 183.719411 -97.799469) (xy 183.695739 -97.849966)
			(xy 183.664966 -97.896479) (xy 183.627749 -97.938016) (xy 183.584881 -97.973691) (xy 183.537275 -98.002745)
			(xy 183.485946 -98.024557) (xy 183.431989 -98.038663) (xy 183.376552 -98.044763) (xy 183.320818 -98.042726)
			(xy 183.265975 -98.032596) (xy 183.213191 -98.014589) (xy 183.163591 -97.989088) (xy 183.118233 -97.956637)
			(xy 183.078084 -97.917928) (xy 183.043998 -97.873785) (xy 183.016702 -97.82515) (xy 182.996779 -97.773059)
			(xy 182.984653 -97.718622) (xy 182.980582 -97.663) (xy 151.425018 -97.663) (xy 150.917029 -98.171)
			(xy 191.663826 -98.171) (xy 191.667897 -98.115378) (xy 191.680023 -98.060941) (xy 191.699946 -98.00885)
			(xy 191.727242 -97.960215) (xy 191.761328 -97.916072) (xy 191.801477 -97.877363) (xy 191.846835 -97.844912)
			(xy 191.896435 -97.819411) (xy 191.949219 -97.801404) (xy 192.004062 -97.791274) (xy 192.059796 -97.789237)
			(xy 192.115233 -97.795337) (xy 192.16919 -97.809443) (xy 192.220519 -97.831255) (xy 192.268125 -97.860309)
			(xy 192.310993 -97.895984) (xy 192.34821 -97.937521) (xy 192.378983 -97.984034) (xy 192.396616 -98.021648)
			(xy 194.269358 -98.021648) (xy 194.273429 -97.966026) (xy 194.285555 -97.911589) (xy 194.305478 -97.859498)
			(xy 194.332774 -97.810863) (xy 194.36686 -97.76672) (xy 194.407009 -97.728011) (xy 194.452367 -97.69556)
			(xy 194.501967 -97.670059) (xy 194.554751 -97.652052) (xy 194.609594 -97.641922) (xy 194.665328 -97.639885)
			(xy 194.720765 -97.645985) (xy 194.774722 -97.660091) (xy 194.826051 -97.681903) (xy 194.873657 -97.710957)
			(xy 194.916525 -97.746632) (xy 194.953742 -97.788169) (xy 194.984515 -97.834682) (xy 195.008187 -97.885179)
			(xy 195.024255 -97.938586) (xy 195.032375 -97.993762) (xy 195.032884 -98.021648) (xy 195.032375 -98.049534)
			(xy 195.024255 -98.10471) (xy 195.008187 -98.158117) (xy 194.984515 -98.208614) (xy 194.953742 -98.255127)
			(xy 194.916525 -98.296664) (xy 194.873657 -98.332339) (xy 194.826051 -98.361393) (xy 194.774722 -98.383205)
			(xy 194.720765 -98.397311) (xy 194.665328 -98.403411) (xy 194.609594 -98.401374) (xy 194.554751 -98.391244)
			(xy 194.501967 -98.373237) (xy 194.452367 -98.347736) (xy 194.407009 -98.315285) (xy 194.36686 -98.276576)
			(xy 194.332774 -98.232433) (xy 194.305478 -98.183798) (xy 194.285555 -98.131707) (xy 194.273429 -98.07727)
			(xy 194.269358 -98.021648) (xy 192.396616 -98.021648) (xy 192.402655 -98.034531) (xy 192.418723 -98.087938)
			(xy 192.426843 -98.143114) (xy 192.427352 -98.171) (xy 192.426843 -98.198886) (xy 192.418723 -98.254062)
			(xy 192.402655 -98.307469) (xy 192.378983 -98.357966) (xy 192.34821 -98.404479) (xy 192.310993 -98.446016)
			(xy 192.268125 -98.481691) (xy 192.220519 -98.510745) (xy 192.16919 -98.532557) (xy 192.115233 -98.546663)
			(xy 192.059796 -98.552763) (xy 192.004062 -98.550726) (xy 191.949219 -98.540596) (xy 191.896435 -98.522589)
			(xy 191.846835 -98.497088) (xy 191.801477 -98.464637) (xy 191.761328 -98.425928) (xy 191.727242 -98.381785)
			(xy 191.699946 -98.33315) (xy 191.680023 -98.281059) (xy 191.667897 -98.226622) (xy 191.663826 -98.171)
			(xy 150.917029 -98.171) (xy 148.685321 -100.402757) (xy 152.852521 -100.402757) (xy 152.852521 -100.348243)
			(xy 152.860279 -100.294285) (xy 152.875638 -100.24198) (xy 152.898285 -100.192394) (xy 152.927758 -100.146535)
			(xy 152.963458 -100.105338) (xy 153.004658 -100.069641) (xy 153.050519 -100.040171) (xy 153.100107 -100.017528)
			(xy 153.152413 -100.002173) (xy 153.206371 -99.994419) (xy 153.233628 -99.993958) (xy 153.234136 -99.993958)
			(xy 153.248865 -99.994106) (xy 153.278235 -99.996394) (xy 153.29281 -99.99853) (xy 153.303785 -99.999647)
			(xy 153.324975 -99.993591) (xy 153.333704 -99.986846) (xy 153.392124 -99.936808) (xy 153.400145 -99.929235)
			(xy 153.409364 -99.909218) (xy 153.409904 -99.8982) (xy 153.409904 -99.593908) (xy 153.40936 -99.58289)
			(xy 153.400145 -99.562873) (xy 153.392124 -99.5553) (xy 153.325068 -99.497896) (xy 153.303986 -99.4918)
			(xy 153.29281 -99.493578) (xy 153.278234 -99.495706) (xy 153.248865 -99.497998) (xy 153.234136 -99.49815)
			(xy 153.233628 -99.49815) (xy 153.206377 -99.497605) (xy 153.152429 -99.489852) (xy 153.100133 -99.4745)
			(xy 153.050555 -99.451861) (xy 153.004704 -99.422397) (xy 152.963512 -99.386708) (xy 152.927819 -99.345519)
			(xy 152.898352 -99.299669) (xy 152.87571 -99.250093) (xy 152.860354 -99.197799) (xy 152.852597 -99.143851)
			(xy 152.852597 -99.089349) (xy 152.860354 -99.035401) (xy 152.87571 -98.983107) (xy 152.898352 -98.933531)
			(xy 152.927819 -98.887681) (xy 152.963512 -98.846492) (xy 153.004704 -98.810803) (xy 153.050555 -98.781339)
			(xy 153.100133 -98.7587) (xy 153.152429 -98.743348) (xy 153.206377 -98.735595) (xy 153.233628 -98.735134)
			(xy 153.259564 -98.735597) (xy 153.310959 -98.742617) (xy 153.360928 -98.756537) (xy 153.40855 -98.777101)
			(xy 153.452946 -98.803929) (xy 153.493297 -98.836525) (xy 153.528857 -98.87429) (xy 153.54427 -98.895154)
			(xy 153.550092 -98.902487) (xy 153.565711 -98.912781) (xy 153.57475 -98.91522) (xy 153.604722 -98.922078)
			(xy 153.614018 -98.923776) (xy 153.632682 -98.920894) (xy 153.641044 -98.91649) (xy 153.66705 -98.902189)
			(xy 153.721975 -98.879698) (xy 153.779341 -98.864477) (xy 153.838191 -98.856781) (xy 153.867866 -98.856292)
			(xy 153.897502 -98.856751) (xy 153.956278 -98.864401) (xy 154.013578 -98.879564) (xy 154.068444 -98.901987)
			(xy 154.094434 -98.916236) (xy 154.102816 -98.920573) (xy 154.121455 -98.92343) (xy 154.130756 -98.921824)
			(xy 154.160728 -98.914966) (xy 154.169824 -98.912657) (xy 154.185482 -98.902336) (xy 154.191208 -98.8949)
			(xy 154.206595 -98.874048) (xy 154.24214 -98.836336) (xy 154.282466 -98.803786) (xy 154.326829 -98.776998)
			(xy 154.374412 -98.756466) (xy 154.424337 -98.742569) (xy 154.475684 -98.735562) (xy 154.501596 -98.735134)
			(xy 154.528852 -98.735513) (xy 154.582809 -98.74327) (xy 154.635114 -98.758627) (xy 154.6847 -98.781272)
			(xy 154.730558 -98.810743) (xy 154.770227 -98.845116) (xy 160.769552 -98.845116) (xy 160.773623 -98.789494)
			(xy 160.785749 -98.735057) (xy 160.805672 -98.682966) (xy 160.832968 -98.634331) (xy 160.867054 -98.590188)
			(xy 160.907203 -98.551479) (xy 160.952561 -98.519028) (xy 161.002161 -98.493527) (xy 161.054945 -98.47552)
			(xy 161.109788 -98.46539) (xy 161.165522 -98.463353) (xy 161.220959 -98.469453) (xy 161.274916 -98.483559)
			(xy 161.326245 -98.505371) (xy 161.373851 -98.534425) (xy 161.416719 -98.5701) (xy 161.453936 -98.611637)
			(xy 161.484709 -98.65815) (xy 161.508381 -98.708647) (xy 161.524449 -98.762054) (xy 161.532569 -98.81723)
			(xy 161.533078 -98.845116) (xy 162.750752 -98.845116) (xy 162.754823 -98.789494) (xy 162.766949 -98.735057)
			(xy 162.786872 -98.682966) (xy 162.814168 -98.634331) (xy 162.848254 -98.590188) (xy 162.888403 -98.551479)
			(xy 162.933761 -98.519028) (xy 162.983361 -98.493527) (xy 163.036145 -98.47552) (xy 163.090988 -98.46539)
			(xy 163.146722 -98.463353) (xy 163.202159 -98.469453) (xy 163.256116 -98.483559) (xy 163.307445 -98.505371)
			(xy 163.355051 -98.534425) (xy 163.397919 -98.5701) (xy 163.435136 -98.611637) (xy 163.465909 -98.65815)
			(xy 163.489581 -98.708647) (xy 163.505649 -98.762054) (xy 163.513769 -98.81723) (xy 163.514278 -98.845116)
			(xy 164.482778 -98.845116) (xy 164.486849 -98.789494) (xy 164.498975 -98.735057) (xy 164.518898 -98.682966)
			(xy 164.546194 -98.634331) (xy 164.58028 -98.590188) (xy 164.620429 -98.551479) (xy 164.665787 -98.519028)
			(xy 164.715387 -98.493527) (xy 164.768171 -98.47552) (xy 164.823014 -98.46539) (xy 164.878748 -98.463353)
			(xy 164.934185 -98.469453) (xy 164.988142 -98.483559) (xy 165.039471 -98.505371) (xy 165.087077 -98.534425)
			(xy 165.129945 -98.5701) (xy 165.167162 -98.611637) (xy 165.197935 -98.65815) (xy 165.221607 -98.708647)
			(xy 165.237675 -98.762054) (xy 165.245795 -98.81723) (xy 165.246304 -98.845116) (xy 167.350946 -98.845116)
			(xy 167.355017 -98.789494) (xy 167.367143 -98.735057) (xy 167.387066 -98.682966) (xy 167.414362 -98.634331)
			(xy 167.448448 -98.590188) (xy 167.488597 -98.551479) (xy 167.533955 -98.519028) (xy 167.583555 -98.493527)
			(xy 167.636339 -98.47552) (xy 167.691182 -98.46539) (xy 167.746916 -98.463353) (xy 167.802353 -98.469453)
			(xy 167.85631 -98.483559) (xy 167.907639 -98.505371) (xy 167.955245 -98.534425) (xy 167.998113 -98.5701)
			(xy 168.03533 -98.611637) (xy 168.066103 -98.65815) (xy 168.089775 -98.708647) (xy 168.105843 -98.762054)
			(xy 168.113963 -98.81723) (xy 168.114472 -98.845116) (xy 168.113963 -98.873002) (xy 168.105843 -98.928178)
			(xy 168.089775 -98.981585) (xy 168.066103 -99.032082) (xy 168.03533 -99.078595) (xy 167.998113 -99.120132)
			(xy 167.955245 -99.155807) (xy 167.907639 -99.184861) (xy 167.85631 -99.206673) (xy 167.802353 -99.220779)
			(xy 167.746916 -99.226879) (xy 167.691182 -99.224842) (xy 167.636339 -99.214712) (xy 167.583555 -99.196705)
			(xy 167.533955 -99.171204) (xy 167.488597 -99.138753) (xy 167.448448 -99.100044) (xy 167.414362 -99.055901)
			(xy 167.387066 -99.007266) (xy 167.367143 -98.955175) (xy 167.355017 -98.900738) (xy 167.350946 -98.845116)
			(xy 165.246304 -98.845116) (xy 165.245795 -98.873002) (xy 165.237675 -98.928178) (xy 165.221607 -98.981585)
			(xy 165.197935 -99.032082) (xy 165.167162 -99.078595) (xy 165.129945 -99.120132) (xy 165.087077 -99.155807)
			(xy 165.039471 -99.184861) (xy 164.988142 -99.206673) (xy 164.934185 -99.220779) (xy 164.878748 -99.226879)
			(xy 164.823014 -99.224842) (xy 164.768171 -99.214712) (xy 164.715387 -99.196705) (xy 164.665787 -99.171204)
			(xy 164.620429 -99.138753) (xy 164.58028 -99.100044) (xy 164.546194 -99.055901) (xy 164.518898 -99.007266)
			(xy 164.498975 -98.955175) (xy 164.486849 -98.900738) (xy 164.482778 -98.845116) (xy 163.514278 -98.845116)
			(xy 163.513769 -98.873002) (xy 163.505649 -98.928178) (xy 163.489581 -98.981585) (xy 163.465909 -99.032082)
			(xy 163.435136 -99.078595) (xy 163.397919 -99.120132) (xy 163.355051 -99.155807) (xy 163.307445 -99.184861)
			(xy 163.256116 -99.206673) (xy 163.202159 -99.220779) (xy 163.146722 -99.226879) (xy 163.090988 -99.224842)
			(xy 163.036145 -99.214712) (xy 162.983361 -99.196705) (xy 162.933761 -99.171204) (xy 162.888403 -99.138753)
			(xy 162.848254 -99.100044) (xy 162.814168 -99.055901) (xy 162.786872 -99.007266) (xy 162.766949 -98.955175)
			(xy 162.754823 -98.900738) (xy 162.750752 -98.845116) (xy 161.533078 -98.845116) (xy 161.532569 -98.873002)
			(xy 161.524449 -98.928178) (xy 161.508381 -98.981585) (xy 161.484709 -99.032082) (xy 161.453936 -99.078595)
			(xy 161.416719 -99.120132) (xy 161.373851 -99.155807) (xy 161.326245 -99.184861) (xy 161.274916 -99.206673)
			(xy 161.220959 -99.220779) (xy 161.165522 -99.226879) (xy 161.109788 -99.224842) (xy 161.054945 -99.214712)
			(xy 161.002161 -99.196705) (xy 160.952561 -99.171204) (xy 160.907203 -99.138753) (xy 160.867054 -99.100044)
			(xy 160.832968 -99.055901) (xy 160.805672 -99.007266) (xy 160.785749 -98.955175) (xy 160.773623 -98.900738)
			(xy 160.769552 -98.845116) (xy 154.770227 -98.845116) (xy 154.771756 -98.846441) (xy 154.807454 -98.887638)
			(xy 154.836926 -98.933497) (xy 154.859571 -98.983083) (xy 154.874929 -99.035387) (xy 154.882687 -99.089344)
			(xy 154.882687 -99.143856) (xy 154.874929 -99.197813) (xy 154.859571 -99.250117) (xy 154.836926 -99.299703)
			(xy 154.807454 -99.345562) (xy 154.771756 -99.386759) (xy 154.730558 -99.422457) (xy 154.6847 -99.451928)
			(xy 154.635114 -99.474573) (xy 154.582809 -99.48993) (xy 154.528852 -99.497687) (xy 154.501596 -99.49815)
			(xy 154.486867 -99.497999) (xy 154.457497 -99.495713) (xy 154.442922 -99.493578) (xy 154.431947 -99.492478)
			(xy 154.410758 -99.498522) (xy 154.402028 -99.505262) (xy 154.343608 -99.5553) (xy 154.335588 -99.562875)
			(xy 154.326368 -99.58289) (xy 154.325828 -99.593908) (xy 154.325828 -99.8982) (xy 154.326357 -99.90922)
			(xy 154.335582 -99.929237) (xy 154.343608 -99.936808) (xy 154.410664 -99.994212) (xy 154.431746 -100.000308)
			(xy 154.442922 -99.99853) (xy 154.457497 -99.996399) (xy 154.486867 -99.994109) (xy 154.501596 -99.993958)
			(xy 154.528847 -99.994489) (xy 154.582793 -100.002245) (xy 154.635087 -100.017599) (xy 154.684663 -100.040239)
			(xy 154.730513 -100.069705) (xy 154.771702 -100.105395) (xy 154.807393 -100.146584) (xy 154.836859 -100.192433)
			(xy 154.859499 -100.242009) (xy 154.874854 -100.294303) (xy 154.882611 -100.348249) (xy 154.882611 -100.402751)
			(xy 154.874854 -100.456697) (xy 154.859499 -100.508991) (xy 154.836859 -100.558567) (xy 154.807393 -100.604416)
			(xy 154.772261 -100.64496) (xy 160.769552 -100.64496) (xy 160.773623 -100.589338) (xy 160.785749 -100.534901)
			(xy 160.805672 -100.48281) (xy 160.832968 -100.434175) (xy 160.867054 -100.390032) (xy 160.907203 -100.351323)
			(xy 160.952561 -100.318872) (xy 161.002161 -100.293371) (xy 161.054945 -100.275364) (xy 161.109788 -100.265234)
			(xy 161.165522 -100.263197) (xy 161.220959 -100.269297) (xy 161.274916 -100.283403) (xy 161.326245 -100.305215)
			(xy 161.373851 -100.334269) (xy 161.416719 -100.369944) (xy 161.453936 -100.411481) (xy 161.484709 -100.457994)
			(xy 161.508381 -100.508491) (xy 161.524449 -100.561898) (xy 161.532569 -100.617074) (xy 161.533078 -100.64496)
			(xy 162.750752 -100.64496) (xy 162.754823 -100.589338) (xy 162.766949 -100.534901) (xy 162.786872 -100.48281)
			(xy 162.814168 -100.434175) (xy 162.848254 -100.390032) (xy 162.888403 -100.351323) (xy 162.933761 -100.318872)
			(xy 162.983361 -100.293371) (xy 163.036145 -100.275364) (xy 163.090988 -100.265234) (xy 163.146722 -100.263197)
			(xy 163.202159 -100.269297) (xy 163.256116 -100.283403) (xy 163.307445 -100.305215) (xy 163.355051 -100.334269)
			(xy 163.397919 -100.369944) (xy 163.435136 -100.411481) (xy 163.465909 -100.457994) (xy 163.489581 -100.508491)
			(xy 163.505649 -100.561898) (xy 163.513769 -100.617074) (xy 163.514278 -100.64496) (xy 164.109398 -100.64496)
			(xy 164.113469 -100.589338) (xy 164.125595 -100.534901) (xy 164.145518 -100.48281) (xy 164.172814 -100.434175)
			(xy 164.2069 -100.390032) (xy 164.247049 -100.351323) (xy 164.292407 -100.318872) (xy 164.342007 -100.293371)
			(xy 164.394791 -100.275364) (xy 164.449634 -100.265234) (xy 164.505368 -100.263197) (xy 164.560805 -100.269297)
			(xy 164.614762 -100.283403) (xy 164.666091 -100.305215) (xy 164.713697 -100.334269) (xy 164.756565 -100.369944)
			(xy 164.793782 -100.411481) (xy 164.824555 -100.457994) (xy 164.848227 -100.508491) (xy 164.864295 -100.561898)
			(xy 164.872415 -100.617074) (xy 164.872924 -100.64496) (xy 164.872415 -100.672846) (xy 164.864295 -100.728022)
			(xy 164.848227 -100.781429) (xy 164.824555 -100.831926) (xy 164.793782 -100.878439) (xy 164.756565 -100.919976)
			(xy 164.713697 -100.955651) (xy 164.666091 -100.984705) (xy 164.614762 -101.006517) (xy 164.560805 -101.020623)
			(xy 164.505368 -101.026723) (xy 164.449634 -101.024686) (xy 164.394791 -101.014556) (xy 164.342007 -100.996549)
			(xy 164.292407 -100.971048) (xy 164.247049 -100.938597) (xy 164.2069 -100.899888) (xy 164.172814 -100.855745)
			(xy 164.145518 -100.80711) (xy 164.125595 -100.755019) (xy 164.113469 -100.700582) (xy 164.109398 -100.64496)
			(xy 163.514278 -100.64496) (xy 163.513769 -100.672846) (xy 163.505649 -100.728022) (xy 163.489581 -100.781429)
			(xy 163.465909 -100.831926) (xy 163.435136 -100.878439) (xy 163.397919 -100.919976) (xy 163.355051 -100.955651)
			(xy 163.307445 -100.984705) (xy 163.256116 -101.006517) (xy 163.202159 -101.020623) (xy 163.146722 -101.026723)
			(xy 163.090988 -101.024686) (xy 163.036145 -101.014556) (xy 162.983361 -100.996549) (xy 162.933761 -100.971048)
			(xy 162.888403 -100.938597) (xy 162.848254 -100.899888) (xy 162.814168 -100.855745) (xy 162.786872 -100.80711)
			(xy 162.766949 -100.755019) (xy 162.754823 -100.700582) (xy 162.750752 -100.64496) (xy 161.533078 -100.64496)
			(xy 161.532569 -100.672846) (xy 161.524449 -100.728022) (xy 161.508381 -100.781429) (xy 161.484709 -100.831926)
			(xy 161.453936 -100.878439) (xy 161.416719 -100.919976) (xy 161.373851 -100.955651) (xy 161.326245 -100.984705)
			(xy 161.274916 -101.006517) (xy 161.220959 -101.020623) (xy 161.165522 -101.026723) (xy 161.109788 -101.024686)
			(xy 161.054945 -101.014556) (xy 161.002161 -100.996549) (xy 160.952561 -100.971048) (xy 160.907203 -100.938597)
			(xy 160.867054 -100.899888) (xy 160.832968 -100.855745) (xy 160.805672 -100.80711) (xy 160.785749 -100.755019)
			(xy 160.773623 -100.700582) (xy 160.769552 -100.64496) (xy 154.772261 -100.64496) (xy 154.771702 -100.645605)
			(xy 154.730513 -100.681295) (xy 154.684663 -100.710761) (xy 154.635087 -100.733401) (xy 154.582793 -100.748755)
			(xy 154.528847 -100.756511) (xy 154.501596 -100.756974) (xy 154.475689 -100.756499) (xy 154.424352 -100.749474)
			(xy 154.374439 -100.735569) (xy 154.326865 -100.715038) (xy 154.282507 -100.688259) (xy 154.242179 -100.655725)
			(xy 154.206625 -100.618034) (xy 154.191208 -100.597208) (xy 154.185402 -100.589861) (xy 154.169771 -100.579576)
			(xy 154.160728 -100.577142) (xy 154.130756 -100.570284) (xy 154.121455 -100.568633) (xy 154.102798 -100.571485)
			(xy 154.094434 -100.575872) (xy 154.06845 -100.590132) (xy 154.013582 -100.612554) (xy 153.95628 -100.627711)
			(xy 153.897502 -100.635351) (xy 153.867866 -100.635816) (xy 153.838189 -100.635342) (xy 153.779333 -100.62767)
			(xy 153.721964 -100.612446) (xy 153.667048 -100.589926) (xy 153.641044 -100.575618) (xy 153.632666 -100.571272)
			(xy 153.614023 -100.568419) (xy 153.604722 -100.57003) (xy 153.57475 -100.576888) (xy 153.565656 -100.579202)
			(xy 153.549998 -100.589521) (xy 153.54427 -100.596954) (xy 153.528853 -100.617815) (xy 153.49329 -100.655579)
			(xy 153.45294 -100.688177) (xy 153.408546 -100.715008) (xy 153.360926 -100.735577) (xy 153.310958 -100.749506)
			(xy 153.259564 -100.756537) (xy 153.233628 -100.756974) (xy 153.206371 -100.756581) (xy 153.152413 -100.748827)
			(xy 153.100107 -100.733472) (xy 153.050519 -100.710829) (xy 153.004658 -100.681359) (xy 152.963458 -100.645662)
			(xy 152.927758 -100.604465) (xy 152.898285 -100.558606) (xy 152.875638 -100.50902) (xy 152.860279 -100.456715)
			(xy 152.852521 -100.402757) (xy 148.685321 -100.402757) (xy 148.137735 -100.950355) (xy 150.820045 -100.950355)
			(xy 150.820045 -100.895845) (xy 150.827803 -100.841891) (xy 150.84316 -100.78959) (xy 150.865805 -100.740008)
			(xy 150.895275 -100.694152) (xy 150.930972 -100.652958) (xy 150.972168 -100.617263) (xy 151.018025 -100.587795)
			(xy 151.067609 -100.565153) (xy 151.119911 -100.549798) (xy 151.173865 -100.542044) (xy 151.20112 -100.541582)
			(xy 151.227057 -100.541998) (xy 151.278454 -100.549029) (xy 151.328423 -100.562959) (xy 151.376044 -100.583531)
			(xy 151.420439 -100.610365) (xy 151.460789 -100.642967) (xy 151.49635 -100.680736) (xy 151.511762 -100.701602)
			(xy 151.517597 -100.708924) (xy 151.533206 -100.719226) (xy 151.542242 -100.721668) (xy 151.572214 -100.728526)
			(xy 151.581511 -100.730213) (xy 151.600173 -100.727337) (xy 151.608536 -100.722938) (xy 151.634546 -100.708645)
			(xy 151.689469 -100.686151) (xy 151.746834 -100.670928) (xy 151.805683 -100.66323) (xy 151.835358 -100.66274)
			(xy 151.864993 -100.663209) (xy 151.923769 -100.670857) (xy 151.981068 -100.686017) (xy 152.035936 -100.708437)
			(xy 152.061926 -100.722684) (xy 152.070311 -100.727015) (xy 152.088948 -100.729877) (xy 152.098248 -100.728272)
			(xy 152.12822 -100.721414) (xy 152.137309 -100.719087) (xy 152.15297 -100.708777) (xy 152.1587 -100.701348)
			(xy 152.174077 -100.680488) (xy 152.209625 -100.642778) (xy 152.249954 -100.610231) (xy 152.294318 -100.583445)
			(xy 152.341902 -100.562915) (xy 152.391828 -100.549018) (xy 152.443176 -100.542011) (xy 152.469088 -100.541582)
			(xy 152.496341 -100.542064) (xy 152.550292 -100.54982) (xy 152.602589 -100.565174) (xy 152.65217 -100.587816)
			(xy 152.698023 -100.617283) (xy 152.739216 -100.652975) (xy 152.77491 -100.694167) (xy 152.804379 -100.74002)
			(xy 152.827021 -100.789599) (xy 152.842378 -100.841897) (xy 152.850135 -100.895847) (xy 152.850135 -100.950353)
			(xy 152.842378 -101.004303) (xy 152.827021 -101.056601) (xy 152.804379 -101.10618) (xy 152.77491 -101.152033)
			(xy 152.739216 -101.193225) (xy 152.698023 -101.228917) (xy 152.65217 -101.258384) (xy 152.602589 -101.281026)
			(xy 152.550292 -101.29638) (xy 152.496341 -101.304136) (xy 152.469088 -101.304598) (xy 152.454359 -101.304448)
			(xy 152.424989 -101.302161) (xy 152.410414 -101.300026) (xy 152.399439 -101.298911) (xy 152.378248 -101.304963)
			(xy 152.36952 -101.31171) (xy 152.3111 -101.361748) (xy 152.303102 -101.369343) (xy 152.29387 -101.389343)
			(xy 152.29332 -101.400356) (xy 152.29332 -101.704648) (xy 152.29388 -101.715664) (xy 152.303083 -101.735682)
			(xy 152.3111 -101.743256) (xy 152.378156 -101.80066) (xy 152.399238 -101.806756) (xy 152.410414 -101.804978)
			(xy 152.424989 -101.802847) (xy 152.454359 -101.800558) (xy 152.469088 -101.800406) (xy 152.496342 -101.80084)
			(xy 152.550297 -101.808596) (xy 152.602598 -101.823952) (xy 152.652181 -101.846594) (xy 152.698038 -101.876063)
			(xy 152.739234 -101.911758) (xy 152.77493 -101.952953) (xy 152.8044 -101.998808) (xy 152.827044 -102.048391)
			(xy 152.842402 -102.100692) (xy 152.850159 -102.154646) (xy 152.850159 -102.209154) (xy 152.842402 -102.263108)
			(xy 152.827044 -102.315409) (xy 152.8044 -102.364992) (xy 152.77493 -102.410847) (xy 152.739234 -102.452042)
			(xy 152.698038 -102.487737) (xy 152.652181 -102.517206) (xy 152.602598 -102.539848) (xy 152.550297 -102.555204)
			(xy 152.496342 -102.56296) (xy 152.469088 -102.563422) (xy 152.443181 -102.562933) (xy 152.391847 -102.555908)
			(xy 152.341934 -102.542004) (xy 152.294361 -102.521474) (xy 152.250003 -102.494698) (xy 152.209675 -102.462167)
			(xy 152.174118 -102.42448) (xy 152.1587 -102.403656) (xy 152.152887 -102.396315) (xy 152.137261 -102.386025)
			(xy 152.12822 -102.38359) (xy 152.098248 -102.376732) (xy 152.088948 -102.37507) (xy 152.070289 -102.377928)
			(xy 152.061926 -102.38232) (xy 152.035941 -102.396579) (xy 151.981074 -102.419001) (xy 151.923772 -102.434159)
			(xy 151.864994 -102.4418) (xy 151.835358 -102.442264) (xy 151.80568 -102.4418) (xy 151.746824 -102.434126)
			(xy 151.689455 -102.418899) (xy 151.63454 -102.396376) (xy 151.608536 -102.382066) (xy 151.600139 -102.377765)
			(xy 151.581512 -102.374886) (xy 151.572214 -102.376478) (xy 151.542242 -102.383336) (xy 151.533153 -102.385664)
			(xy 151.517494 -102.395974) (xy 151.511762 -102.403402) (xy 151.496334 -102.424255) (xy 151.460775 -102.462021)
			(xy 151.420427 -102.494621) (xy 151.376035 -102.521454) (xy 151.328416 -102.542025) (xy 151.278449 -102.555954)
			(xy 151.227056 -102.562985) (xy 151.20112 -102.563422) (xy 151.173867 -102.562932) (xy 151.119916 -102.555178)
			(xy 151.067618 -102.539824) (xy 151.018037 -102.517183) (xy 150.972183 -102.487717) (xy 150.930989 -102.452025)
			(xy 150.895295 -102.410833) (xy 150.865826 -102.364981) (xy 150.843183 -102.315401) (xy 150.827827 -102.263103)
			(xy 150.820069 -102.209153) (xy 150.820069 -102.154647) (xy 150.827827 -102.100697) (xy 150.843183 -102.048399)
			(xy 150.865826 -101.998819) (xy 150.895295 -101.952967) (xy 150.930989 -101.911775) (xy 150.972183 -101.876083)
			(xy 151.018037 -101.846617) (xy 151.067618 -101.823976) (xy 151.119916 -101.808622) (xy 151.173867 -101.800868)
			(xy 151.20112 -101.800406) (xy 151.201628 -101.800406) (xy 151.216357 -101.800554) (xy 151.245727 -101.802842)
			(xy 151.260302 -101.804978) (xy 151.271277 -101.806102) (xy 151.292469 -101.800043) (xy 151.301196 -101.793294)
			(xy 151.359616 -101.743256) (xy 151.367614 -101.735662) (xy 151.376846 -101.715661) (xy 151.377396 -101.704648)
			(xy 151.377396 -101.400356) (xy 151.376828 -101.389341) (xy 151.36763 -101.369324) (xy 151.359616 -101.361748)
			(xy 151.29256 -101.304344) (xy 151.271478 -101.298248) (xy 151.260302 -101.300026) (xy 151.245727 -101.302154)
			(xy 151.216357 -101.304446) (xy 151.201628 -101.304598) (xy 151.20112 -101.304598) (xy 151.173865 -101.304156)
			(xy 151.119911 -101.296402) (xy 151.067609 -101.281047) (xy 151.018025 -101.258405) (xy 150.972168 -101.228937)
			(xy 150.930972 -101.193242) (xy 150.895275 -101.152048) (xy 150.865805 -101.106192) (xy 150.84316 -101.05661)
			(xy 150.827803 -101.004309) (xy 150.820045 -100.950355) (xy 148.137735 -100.950355) (xy 146.344274 -102.743855)
			(xy 152.852539 -102.743855) (xy 152.852539 -102.689345) (xy 152.860297 -102.635389) (xy 152.875655 -102.583087)
			(xy 152.898301 -102.533503) (xy 152.927772 -102.487646) (xy 152.963471 -102.446451) (xy 153.004669 -102.410756)
			(xy 153.050527 -102.381287) (xy 153.100113 -102.358645) (xy 153.152416 -102.343291) (xy 153.206373 -102.335537)
			(xy 153.233628 -102.335076) (xy 153.259563 -102.335563) (xy 153.310956 -102.342582) (xy 153.360924 -102.3565)
			(xy 153.408545 -102.37706) (xy 153.45294 -102.403884) (xy 153.493292 -102.436476) (xy 153.528855 -102.474234)
			(xy 153.54427 -102.495096) (xy 153.550083 -102.502436) (xy 153.565709 -102.512725) (xy 153.57475 -102.515162)
			(xy 153.604722 -102.52202) (xy 153.614018 -102.523712) (xy 153.632681 -102.520832) (xy 153.641044 -102.516432)
			(xy 153.667057 -102.502161) (xy 153.72199 -102.479732) (xy 153.779356 -102.464576) (xy 153.838198 -102.456945)
			(xy 153.867866 -102.456488) (xy 153.897494 -102.456916) (xy 153.956262 -102.4645) (xy 154.013562 -102.479599)
			(xy 154.068437 -102.501959) (xy 154.094434 -102.516178) (xy 154.102817 -102.520512) (xy 154.121456 -102.523373)
			(xy 154.130756 -102.521766) (xy 154.160728 -102.514908) (xy 154.169819 -102.512586) (xy 154.185479 -102.502273)
			(xy 154.191208 -102.494842) (xy 154.206578 -102.473977) (xy 154.242128 -102.436268) (xy 154.282457 -102.403721)
			(xy 154.326823 -102.376936) (xy 154.374408 -102.356406) (xy 154.424335 -102.34251) (xy 154.475684 -102.335504)
			(xy 154.501596 -102.335076) (xy 154.528848 -102.335571) (xy 154.582797 -102.343327) (xy 154.635093 -102.358682)
			(xy 154.684672 -102.381324) (xy 154.730523 -102.41079) (xy 154.770072 -102.445058) (xy 160.769552 -102.445058)
			(xy 160.773623 -102.389436) (xy 160.785749 -102.334999) (xy 160.805672 -102.282908) (xy 160.832968 -102.234273)
			(xy 160.867054 -102.19013) (xy 160.907203 -102.151421) (xy 160.952561 -102.11897) (xy 161.002161 -102.093469)
			(xy 161.054945 -102.075462) (xy 161.109788 -102.065332) (xy 161.165522 -102.063295) (xy 161.220959 -102.069395)
			(xy 161.274916 -102.083501) (xy 161.326245 -102.105313) (xy 161.373851 -102.134367) (xy 161.416719 -102.170042)
			(xy 161.453936 -102.211579) (xy 161.484709 -102.258092) (xy 161.508381 -102.308589) (xy 161.524449 -102.361996)
			(xy 161.532569 -102.417172) (xy 161.533078 -102.445058) (xy 161.532569 -102.472944) (xy 161.524449 -102.52812)
			(xy 161.508381 -102.581527) (xy 161.484709 -102.632024) (xy 161.453936 -102.678537) (xy 161.416719 -102.720074)
			(xy 161.373851 -102.755749) (xy 161.326245 -102.784803) (xy 161.274916 -102.806615) (xy 161.220959 -102.820721)
			(xy 161.165522 -102.826821) (xy 161.109788 -102.824784) (xy 161.054945 -102.814654) (xy 161.002161 -102.796647)
			(xy 160.952561 -102.771146) (xy 160.907203 -102.738695) (xy 160.867054 -102.699986) (xy 160.832968 -102.655843)
			(xy 160.805672 -102.607208) (xy 160.785749 -102.555117) (xy 160.773623 -102.50068) (xy 160.769552 -102.445058)
			(xy 154.770072 -102.445058) (xy 154.771715 -102.446482) (xy 154.807407 -102.487673) (xy 154.836875 -102.533525)
			(xy 154.859516 -102.583103) (xy 154.874872 -102.635399) (xy 154.882629 -102.689348) (xy 154.882629 -102.743852)
			(xy 154.874872 -102.797801) (xy 154.86031 -102.847394) (xy 163.075618 -102.847394) (xy 163.079689 -102.791772)
			(xy 163.091815 -102.737335) (xy 163.111738 -102.685244) (xy 163.139034 -102.636609) (xy 163.17312 -102.592466)
			(xy 163.213269 -102.553757) (xy 163.258627 -102.521306) (xy 163.308227 -102.495805) (xy 163.361011 -102.477798)
			(xy 163.415854 -102.467668) (xy 163.471588 -102.465631) (xy 163.527025 -102.471731) (xy 163.529404 -102.472353)
			(xy 167.351936 -102.472353) (xy 167.351936 -102.417847) (xy 167.359692 -102.363897) (xy 167.375047 -102.311599)
			(xy 167.397688 -102.262019) (xy 167.427154 -102.216165) (xy 167.462846 -102.174971) (xy 167.504036 -102.139276)
			(xy 167.549887 -102.109805) (xy 167.599465 -102.08716) (xy 167.651762 -102.0718) (xy 167.705711 -102.064038)
			(xy 167.732964 -102.06355) (xy 167.750076 -102.063741) (xy 167.784163 -102.066793) (xy 167.801036 -102.069646)
			(xy 167.812364 -102.071056) (xy 167.834378 -102.065138) (xy 167.843454 -102.058216) (xy 167.867838 -102.037134)
			(xy 167.876281 -102.029169) (xy 167.8854 -102.007849) (xy 167.885364 -101.99624) (xy 167.884856 -101.976428)
			(xy 167.884856 -101.112828) (xy 167.885364 -101.093524) (xy 167.88531 -101.081933) (xy 167.876207 -101.060646)
			(xy 167.867838 -101.05263) (xy 167.843454 -101.031802) (xy 167.834441 -101.024889) (xy 167.812556 -101.01894)
			(xy 167.80129 -101.020372) (xy 167.784356 -101.023252) (xy 167.75014 -101.026304) (xy 167.732964 -101.026468)
			(xy 167.705712 -101.02606) (xy 167.651762 -101.018298) (xy 167.599466 -101.002938) (xy 167.549888 -100.980293)
			(xy 167.504038 -100.950822) (xy 167.462847 -100.915127) (xy 167.427156 -100.873934) (xy 167.39769 -100.82808)
			(xy 167.375049 -100.7785) (xy 167.359694 -100.726203) (xy 167.351938 -100.672252) (xy 167.351938 -100.617748)
			(xy 167.359694 -100.563797) (xy 167.375049 -100.5115) (xy 167.39769 -100.46192) (xy 167.427156 -100.416066)
			(xy 167.462847 -100.374873) (xy 167.504038 -100.339178) (xy 167.549888 -100.309707) (xy 167.599466 -100.287062)
			(xy 167.651762 -100.271702) (xy 167.705712 -100.26394) (xy 167.732964 -100.263452) (xy 167.759943 -100.263867)
			(xy 167.813364 -100.271456) (xy 167.865181 -100.286504) (xy 167.914359 -100.308708) (xy 167.959914 -100.337624)
			(xy 168.000936 -100.372676) (xy 168.036605 -100.413162) (xy 168.066208 -100.458274) (xy 168.089155 -100.50711)
			(xy 168.104985 -100.558693) (xy 168.109646 -100.58527) (xy 168.109646 -100.585524) (xy 168.111846 -100.595787)
			(xy 168.123267 -100.61337) (xy 168.131744 -100.61956) (xy 168.203118 -100.667058) (xy 168.223692 -100.670614)
			(xy 168.234106 -100.668074) (xy 168.260871 -100.661993) (xy 168.315373 -100.655496) (xy 168.342818 -100.65512)
			(xy 168.370136 -100.655516) (xy 168.424384 -100.662004) (xy 168.451022 -100.668074) (xy 168.451276 -100.668074)
			(xy 168.461504 -100.669951) (xy 168.481954 -100.666266) (xy 168.4909 -100.660962) (xy 168.562528 -100.613464)
			(xy 168.573704 -100.595938) (xy 168.575482 -100.58527) (xy 168.580121 -100.558694) (xy 168.59598 -100.507127)
			(xy 168.618946 -100.45831) (xy 168.648561 -100.413215) (xy 168.684235 -100.372744) (xy 168.725255 -100.337702)
			(xy 168.770804 -100.30879) (xy 168.819972 -100.286584) (xy 168.871778 -100.271528) (xy 168.925189 -100.263921)
			(xy 168.952164 -100.263452) (xy 168.979534 -100.263926) (xy 169.033713 -100.27174) (xy 169.086217 -100.287227)
			(xy 169.135964 -100.310067) (xy 169.181931 -100.339791) (xy 169.202862 -100.357432) (xy 169.203116 -100.357686)
			(xy 169.210195 -100.363284) (xy 169.227118 -100.369524) (xy 169.236136 -100.369878) (xy 169.303192 -100.369878)
			(xy 169.312209 -100.369522) (xy 169.329126 -100.363274) (xy 169.336212 -100.357686) (xy 169.336212 -100.357432)
			(xy 169.336466 -100.357432) (xy 169.357404 -100.3398) (xy 169.403375 -100.310086) (xy 169.453121 -100.287248)
			(xy 169.50562 -100.271756) (xy 169.559795 -100.263926) (xy 169.587164 -100.263452) (xy 169.604276 -100.263643)
			(xy 169.638363 -100.266695) (xy 169.655236 -100.269548) (xy 169.666564 -100.270957) (xy 169.688578 -100.26504)
			(xy 169.697654 -100.258118) (xy 169.722038 -100.237036) (xy 169.73048 -100.22907) (xy 169.7396 -100.20775)
			(xy 169.739564 -100.196142) (xy 169.739056 -100.17633) (xy 169.739056 -99.31273) (xy 169.739564 -99.293426)
			(xy 169.739509 -99.281836) (xy 169.730407 -99.260548) (xy 169.722038 -99.252532) (xy 169.697654 -99.231704)
			(xy 169.688641 -99.224791) (xy 169.666756 -99.218842) (xy 169.65549 -99.220274) (xy 169.638556 -99.223154)
			(xy 169.60434 -99.226206) (xy 169.587164 -99.22637) (xy 169.559912 -99.225958) (xy 169.505963 -99.218196)
			(xy 169.453667 -99.202836) (xy 169.404089 -99.180191) (xy 169.358239 -99.150721) (xy 169.317049 -99.115026)
			(xy 169.281358 -99.073832) (xy 169.251892 -99.027979) (xy 169.229251 -98.978399) (xy 169.213896 -98.926102)
			(xy 169.20614 -98.872152) (xy 169.20614 -98.817648) (xy 169.213896 -98.763698) (xy 169.229251 -98.711401)
			(xy 169.251892 -98.661821) (xy 169.281358 -98.615968) (xy 169.317049 -98.574774) (xy 169.358239 -98.539079)
			(xy 169.404089 -98.509609) (xy 169.453667 -98.486964) (xy 169.505963 -98.471604) (xy 169.559912 -98.463842)
			(xy 169.587164 -98.463354) (xy 169.614143 -98.463767) (xy 169.667564 -98.471357) (xy 169.719382 -98.486404)
			(xy 169.768559 -98.508608) (xy 169.814114 -98.537525) (xy 169.855136 -98.572577) (xy 169.890805 -98.613064)
			(xy 169.920409 -98.658176) (xy 169.943355 -98.707011) (xy 169.959185 -98.758595) (xy 169.963846 -98.785172)
			(xy 169.963846 -98.785426) (xy 169.966046 -98.795689) (xy 169.977467 -98.813272) (xy 169.985944 -98.819462)
			(xy 170.057318 -98.86696) (xy 170.077892 -98.870516) (xy 170.088306 -98.867976) (xy 170.115065 -98.861833)
			(xy 170.169567 -98.855206) (xy 170.197018 -98.854768) (xy 170.224342 -98.855226) (xy 170.27859 -98.861845)
			(xy 170.305222 -98.867976) (xy 170.305476 -98.867976) (xy 170.315704 -98.869852) (xy 170.336154 -98.866168)
			(xy 170.3451 -98.860864) (xy 170.416728 -98.813366) (xy 170.427904 -98.79584) (xy 170.429682 -98.785172)
			(xy 170.434323 -98.758596) (xy 170.450181 -98.707029) (xy 170.473147 -98.658212) (xy 170.502762 -98.613118)
			(xy 170.538436 -98.572646) (xy 170.579456 -98.537604) (xy 170.625004 -98.508692) (xy 170.674172 -98.486486)
			(xy 170.725978 -98.47143) (xy 170.779389 -98.463823) (xy 170.806364 -98.463354) (xy 170.833616 -98.463891)
			(xy 170.887565 -98.471643) (xy 170.939862 -98.486994) (xy 170.989442 -98.509632) (xy 171.035295 -98.539096)
			(xy 171.076488 -98.574787) (xy 171.112182 -98.615976) (xy 171.14165 -98.661826) (xy 171.164293 -98.711404)
			(xy 171.17965 -98.7637) (xy 171.187407 -98.817648) (xy 171.187407 -98.872152) (xy 171.17965 -98.9261)
			(xy 171.164293 -98.978396) (xy 171.14165 -99.027974) (xy 171.112182 -99.073824) (xy 171.076488 -99.115013)
			(xy 171.035295 -99.150704) (xy 170.989442 -99.180168) (xy 170.939862 -99.202806) (xy 170.887565 -99.218157)
			(xy 170.833616 -99.225909) (xy 170.806364 -99.22637) (xy 170.805856 -99.22637) (xy 170.788935 -99.22615)
			(xy 170.755231 -99.223096) (xy 170.738546 -99.220274) (xy 170.727255 -99.218894) (xy 170.705364 -99.224976)
			(xy 170.696382 -99.231958) (xy 170.671998 -99.252786) (xy 170.6636 -99.260791) (xy 170.654453 -99.28208)
			(xy 170.654472 -99.29368) (xy 170.65498 -99.31273) (xy 170.65498 -99.750372) (xy 173.697644 -99.750372)
			(xy 173.701715 -99.69475) (xy 173.713841 -99.640313) (xy 173.733764 -99.588222) (xy 173.76106 -99.539587)
			(xy 173.795146 -99.495444) (xy 173.835295 -99.456735) (xy 173.880653 -99.424284) (xy 173.930253 -99.398783)
			(xy 173.983037 -99.380776) (xy 174.03788 -99.370646) (xy 174.093614 -99.368609) (xy 174.149051 -99.374709)
			(xy 174.203008 -99.388815) (xy 174.254337 -99.410627) (xy 174.301943 -99.439681) (xy 174.302307 -99.439984)
			(xy 183.371742 -99.439984) (xy 183.375813 -99.384362) (xy 183.387939 -99.329925) (xy 183.407862 -99.277834)
			(xy 183.435158 -99.229199) (xy 183.469244 -99.185056) (xy 183.509393 -99.146347) (xy 183.554751 -99.113896)
			(xy 183.604351 -99.088395) (xy 183.657135 -99.070388) (xy 183.711978 -99.060258) (xy 183.767712 -99.058221)
			(xy 183.823149 -99.064321) (xy 183.877106 -99.078427) (xy 183.928435 -99.100239) (xy 183.976041 -99.129293)
			(xy 184.018909 -99.164968) (xy 184.03865 -99.187) (xy 185.421776 -99.187) (xy 185.425847 -99.131378)
			(xy 185.437973 -99.076941) (xy 185.457896 -99.02485) (xy 185.485192 -98.976215) (xy 185.519278 -98.932072)
			(xy 185.559427 -98.893363) (xy 185.604785 -98.860912) (xy 185.654385 -98.835411) (xy 185.707169 -98.817404)
			(xy 185.762012 -98.807274) (xy 185.817746 -98.805237) (xy 185.873183 -98.811337) (xy 185.92714 -98.825443)
			(xy 185.978469 -98.847255) (xy 186.026075 -98.876309) (xy 186.068943 -98.911984) (xy 186.10616 -98.953521)
			(xy 186.136933 -99.000034) (xy 186.154566 -99.037648) (xy 194.269358 -99.037648) (xy 194.273429 -98.982026)
			(xy 194.285555 -98.927589) (xy 194.305478 -98.875498) (xy 194.332774 -98.826863) (xy 194.36686 -98.78272)
			(xy 194.407009 -98.744011) (xy 194.452367 -98.71156) (xy 194.501967 -98.686059) (xy 194.554751 -98.668052)
			(xy 194.609594 -98.657922) (xy 194.665328 -98.655885) (xy 194.720765 -98.661985) (xy 194.774722 -98.676091)
			(xy 194.826051 -98.697903) (xy 194.873657 -98.726957) (xy 194.916525 -98.762632) (xy 194.953742 -98.804169)
			(xy 194.984515 -98.850682) (xy 195.008187 -98.901179) (xy 195.024255 -98.954586) (xy 195.032375 -99.009762)
			(xy 195.032884 -99.037648) (xy 195.032375 -99.065534) (xy 195.024255 -99.12071) (xy 195.008187 -99.174117)
			(xy 194.984515 -99.224614) (xy 194.953742 -99.271127) (xy 194.916525 -99.312664) (xy 194.873657 -99.348339)
			(xy 194.826051 -99.377393) (xy 194.774722 -99.399205) (xy 194.720765 -99.413311) (xy 194.665328 -99.419411)
			(xy 194.609594 -99.417374) (xy 194.554751 -99.407244) (xy 194.501967 -99.389237) (xy 194.452367 -99.363736)
			(xy 194.407009 -99.331285) (xy 194.36686 -99.292576) (xy 194.332774 -99.248433) (xy 194.305478 -99.199798)
			(xy 194.285555 -99.147707) (xy 194.273429 -99.09327) (xy 194.269358 -99.037648) (xy 186.154566 -99.037648)
			(xy 186.160605 -99.050531) (xy 186.176673 -99.103938) (xy 186.184793 -99.159114) (xy 186.185302 -99.187)
			(xy 186.184793 -99.214886) (xy 186.176673 -99.270062) (xy 186.160605 -99.323469) (xy 186.136933 -99.373966)
			(xy 186.10616 -99.420479) (xy 186.088684 -99.439984) (xy 191.409826 -99.439984) (xy 191.413897 -99.384362)
			(xy 191.426023 -99.329925) (xy 191.445946 -99.277834) (xy 191.473242 -99.229199) (xy 191.507328 -99.185056)
			(xy 191.547477 -99.146347) (xy 191.592835 -99.113896) (xy 191.642435 -99.088395) (xy 191.695219 -99.070388)
			(xy 191.750062 -99.060258) (xy 191.805796 -99.058221) (xy 191.861233 -99.064321) (xy 191.91519 -99.078427)
			(xy 191.966519 -99.100239) (xy 192.014125 -99.129293) (xy 192.056993 -99.164968) (xy 192.09421 -99.206505)
			(xy 192.124983 -99.253018) (xy 192.148655 -99.303515) (xy 192.164723 -99.356922) (xy 192.172843 -99.412098)
			(xy 192.173352 -99.439984) (xy 192.172843 -99.46787) (xy 192.164723 -99.523046) (xy 192.148655 -99.576453)
			(xy 192.124983 -99.62695) (xy 192.09421 -99.673463) (xy 192.056993 -99.715) (xy 192.014125 -99.750675)
			(xy 191.966519 -99.779729) (xy 191.91519 -99.801541) (xy 191.861233 -99.815647) (xy 191.805796 -99.821747)
			(xy 191.750062 -99.81971) (xy 191.695219 -99.80958) (xy 191.642435 -99.791573) (xy 191.592835 -99.766072)
			(xy 191.547477 -99.733621) (xy 191.507328 -99.694912) (xy 191.473242 -99.650769) (xy 191.445946 -99.602134)
			(xy 191.426023 -99.550043) (xy 191.413897 -99.495606) (xy 191.409826 -99.439984) (xy 186.088684 -99.439984)
			(xy 186.068943 -99.462016) (xy 186.026075 -99.497691) (xy 185.978469 -99.526745) (xy 185.92714 -99.548557)
			(xy 185.873183 -99.562663) (xy 185.817746 -99.568763) (xy 185.762012 -99.566726) (xy 185.707169 -99.556596)
			(xy 185.654385 -99.538589) (xy 185.604785 -99.513088) (xy 185.559427 -99.480637) (xy 185.519278 -99.441928)
			(xy 185.485192 -99.397785) (xy 185.457896 -99.34915) (xy 185.437973 -99.297059) (xy 185.425847 -99.242622)
			(xy 185.421776 -99.187) (xy 184.03865 -99.187) (xy 184.056126 -99.206505) (xy 184.086899 -99.253018)
			(xy 184.110571 -99.303515) (xy 184.126639 -99.356922) (xy 184.134759 -99.412098) (xy 184.135268 -99.439984)
			(xy 184.134759 -99.46787) (xy 184.126639 -99.523046) (xy 184.110571 -99.576453) (xy 184.086899 -99.62695)
			(xy 184.056126 -99.673463) (xy 184.018909 -99.715) (xy 183.976041 -99.750675) (xy 183.928435 -99.779729)
			(xy 183.877106 -99.801541) (xy 183.823149 -99.815647) (xy 183.767712 -99.821747) (xy 183.711978 -99.81971)
			(xy 183.657135 -99.80958) (xy 183.604351 -99.791573) (xy 183.554751 -99.766072) (xy 183.509393 -99.733621)
			(xy 183.469244 -99.694912) (xy 183.435158 -99.650769) (xy 183.407862 -99.602134) (xy 183.387939 -99.550043)
			(xy 183.375813 -99.495606) (xy 183.371742 -99.439984) (xy 174.302307 -99.439984) (xy 174.344811 -99.475356)
			(xy 174.382028 -99.516893) (xy 174.412801 -99.563406) (xy 174.436473 -99.613903) (xy 174.452541 -99.66731)
			(xy 174.460661 -99.722486) (xy 174.46117 -99.750372) (xy 174.460661 -99.778258) (xy 174.452541 -99.833434)
			(xy 174.436473 -99.886841) (xy 174.412801 -99.937338) (xy 174.382735 -99.982782) (xy 186.221876 -99.982782)
			(xy 186.225947 -99.92716) (xy 186.238073 -99.872723) (xy 186.257996 -99.820632) (xy 186.285292 -99.771997)
			(xy 186.319378 -99.727854) (xy 186.359527 -99.689145) (xy 186.404885 -99.656694) (xy 186.454485 -99.631193)
			(xy 186.507269 -99.613186) (xy 186.562112 -99.603056) (xy 186.617846 -99.601019) (xy 186.673283 -99.607119)
			(xy 186.72724 -99.621225) (xy 186.778569 -99.643037) (xy 186.826175 -99.672091) (xy 186.869043 -99.707766)
			(xy 186.90626 -99.749303) (xy 186.937033 -99.795816) (xy 186.960705 -99.846313) (xy 186.976773 -99.89972)
			(xy 186.984893 -99.954896) (xy 186.985402 -99.982782) (xy 186.984893 -100.010668) (xy 186.980586 -100.039932)
			(xy 189.976758 -100.039932) (xy 189.980829 -99.98431) (xy 189.992955 -99.929873) (xy 190.012878 -99.877782)
			(xy 190.040174 -99.829147) (xy 190.07426 -99.785004) (xy 190.114409 -99.746295) (xy 190.159767 -99.713844)
			(xy 190.209367 -99.688343) (xy 190.262151 -99.670336) (xy 190.316994 -99.660206) (xy 190.372728 -99.658169)
			(xy 190.428165 -99.664269) (xy 190.482122 -99.678375) (xy 190.533451 -99.700187) (xy 190.581057 -99.729241)
			(xy 190.623925 -99.764916) (xy 190.661142 -99.806453) (xy 190.691915 -99.852966) (xy 190.715587 -99.903463)
			(xy 190.731655 -99.95687) (xy 190.739775 -100.012046) (xy 190.740284 -100.039932) (xy 190.739775 -100.067818)
			(xy 190.731655 -100.122994) (xy 190.715587 -100.176401) (xy 190.691915 -100.226898) (xy 190.661142 -100.273411)
			(xy 190.623925 -100.314948) (xy 190.581057 -100.350623) (xy 190.533451 -100.379677) (xy 190.482122 -100.401489)
			(xy 190.428165 -100.415595) (xy 190.372728 -100.421695) (xy 190.316994 -100.419658) (xy 190.262151 -100.409528)
			(xy 190.209367 -100.391521) (xy 190.159767 -100.36602) (xy 190.114409 -100.333569) (xy 190.07426 -100.29486)
			(xy 190.040174 -100.250717) (xy 190.012878 -100.202082) (xy 189.992955 -100.149991) (xy 189.980829 -100.095554)
			(xy 189.976758 -100.039932) (xy 186.980586 -100.039932) (xy 186.976773 -100.065844) (xy 186.960705 -100.119251)
			(xy 186.937033 -100.169748) (xy 186.90626 -100.216261) (xy 186.869043 -100.257798) (xy 186.826175 -100.293473)
			(xy 186.778569 -100.322527) (xy 186.72724 -100.344339) (xy 186.673283 -100.358445) (xy 186.617846 -100.364545)
			(xy 186.562112 -100.362508) (xy 186.507269 -100.352378) (xy 186.454485 -100.334371) (xy 186.404885 -100.30887)
			(xy 186.359527 -100.276419) (xy 186.319378 -100.23771) (xy 186.285292 -100.193567) (xy 186.257996 -100.144932)
			(xy 186.238073 -100.092841) (xy 186.225947 -100.038404) (xy 186.221876 -99.982782) (xy 174.382735 -99.982782)
			(xy 174.382028 -99.983851) (xy 174.344811 -100.025388) (xy 174.301943 -100.061063) (xy 174.254337 -100.090117)
			(xy 174.203008 -100.111929) (xy 174.149051 -100.126035) (xy 174.093614 -100.132135) (xy 174.03788 -100.130098)
			(xy 173.983037 -100.119968) (xy 173.930253 -100.101961) (xy 173.880653 -100.07646) (xy 173.835295 -100.044009)
			(xy 173.795146 -100.0053) (xy 173.76106 -99.961157) (xy 173.733764 -99.912522) (xy 173.713841 -99.860431)
			(xy 173.701715 -99.805994) (xy 173.697644 -99.750372) (xy 170.65498 -99.750372) (xy 170.65498 -100.17633)
			(xy 170.654472 -100.196142) (xy 170.654476 -100.207737) (xy 170.663613 -100.229026) (xy 170.671998 -100.237036)
			(xy 170.696382 -100.257864) (xy 170.705341 -100.264883) (xy 170.727249 -100.270942) (xy 170.738546 -100.269548)
			(xy 170.75523 -100.266715) (xy 170.788935 -100.263659) (xy 170.805856 -100.263452) (xy 170.806364 -100.263452)
			(xy 170.833616 -100.263993) (xy 170.887565 -100.271745) (xy 170.939862 -100.287096) (xy 170.989441 -100.309734)
			(xy 171.035294 -100.339198) (xy 171.076486 -100.374888) (xy 171.11218 -100.416077) (xy 171.141649 -100.461927)
			(xy 171.164291 -100.511505) (xy 171.179648 -100.5638) (xy 171.187405 -100.617748) (xy 171.187405 -100.672252)
			(xy 171.179648 -100.7262) (xy 171.167851 -100.766372) (xy 173.697644 -100.766372) (xy 173.701715 -100.71075)
			(xy 173.713841 -100.656313) (xy 173.733764 -100.604222) (xy 173.76106 -100.555587) (xy 173.795146 -100.511444)
			(xy 173.835295 -100.472735) (xy 173.880653 -100.440284) (xy 173.930253 -100.414783) (xy 173.983037 -100.396776)
			(xy 174.03788 -100.386646) (xy 174.093614 -100.384609) (xy 174.149051 -100.390709) (xy 174.203008 -100.404815)
			(xy 174.254337 -100.426627) (xy 174.301943 -100.455681) (xy 174.344811 -100.491356) (xy 174.382028 -100.532893)
			(xy 174.412801 -100.579406) (xy 174.436473 -100.629903) (xy 174.452541 -100.68331) (xy 174.460661 -100.738486)
			(xy 174.46117 -100.766372) (xy 174.460661 -100.794258) (xy 174.452541 -100.849434) (xy 174.436473 -100.902841)
			(xy 174.412801 -100.953338) (xy 174.382028 -100.999851) (xy 174.344811 -101.041388) (xy 174.301943 -101.077063)
			(xy 174.254337 -101.106117) (xy 174.203008 -101.127929) (xy 174.149051 -101.142035) (xy 174.093614 -101.148135)
			(xy 174.03788 -101.146098) (xy 173.983037 -101.135968) (xy 173.930253 -101.117961) (xy 173.880653 -101.09246)
			(xy 173.835295 -101.060009) (xy 173.795146 -101.0213) (xy 173.76106 -100.977157) (xy 173.733764 -100.928522)
			(xy 173.713841 -100.876431) (xy 173.701715 -100.821994) (xy 173.697644 -100.766372) (xy 171.167851 -100.766372)
			(xy 171.164291 -100.778495) (xy 171.141649 -100.828073) (xy 171.11218 -100.873923) (xy 171.076486 -100.915112)
			(xy 171.035294 -100.950802) (xy 170.989441 -100.980266) (xy 170.939862 -101.002904) (xy 170.887565 -101.018255)
			(xy 170.833616 -101.026007) (xy 170.806364 -101.026468) (xy 170.779356 -101.02602) (xy 170.72588 -101.018409)
			(xy 170.674011 -101.003332) (xy 170.624788 -100.981089) (xy 170.579195 -100.952124) (xy 170.538143 -100.917018)
			(xy 170.502454 -100.876473) (xy 170.472841 -100.831298) (xy 170.449896 -100.782398) (xy 170.434078 -100.73075)
			(xy 170.429428 -100.704142) (xy 170.427904 -100.693474) (xy 170.416474 -100.675694) (xy 170.33621 -100.622354)
			(xy 170.315636 -100.618798) (xy 170.305222 -100.621338) (xy 170.278584 -100.627406) (xy 170.224336 -100.633897)
			(xy 170.197018 -100.634292) (xy 170.16963 -100.633847) (xy 170.115254 -100.627226) (xy 170.08856 -100.621084)
			(xy 170.078146 -100.618544) (xy 170.057572 -100.6221) (xy 169.977054 -100.675694) (xy 169.965624 -100.693474)
			(xy 169.9641 -100.704142) (xy 169.959388 -100.730736) (xy 169.943565 -100.782373) (xy 169.92062 -100.831263)
			(xy 169.891009 -100.876429) (xy 169.855326 -100.916968) (xy 169.814283 -100.952071) (xy 169.768701 -100.981036)
			(xy 169.71949 -101.003284) (xy 169.667633 -101.018371) (xy 169.614167 -101.025995) (xy 169.587164 -101.026468)
			(xy 169.559793 -101.026031) (xy 169.505612 -101.018207) (xy 169.453108 -101.002712) (xy 169.403362 -100.979863)
			(xy 169.357397 -100.950132) (xy 169.336466 -100.932488) (xy 169.336212 -100.932234) (xy 169.329132 -100.926639)
			(xy 169.31221 -100.920399) (xy 169.303192 -100.920042) (xy 169.236136 -100.920042) (xy 169.22712 -100.920407)
			(xy 169.210202 -100.926648) (xy 169.203116 -100.932234) (xy 169.203116 -100.932488) (xy 169.202862 -100.932488)
			(xy 169.181916 -100.95011) (xy 169.135947 -100.979824) (xy 169.086203 -101.002664) (xy 169.033706 -101.018159)
			(xy 168.979532 -101.025992) (xy 168.952164 -101.026468) (xy 168.951656 -101.026468) (xy 168.934735 -101.026248)
			(xy 168.901031 -101.023194) (xy 168.884346 -101.020372) (xy 168.873055 -101.018993) (xy 168.851164 -101.025074)
			(xy 168.842182 -101.032056) (xy 168.817798 -101.052884) (xy 168.809401 -101.06089) (xy 168.800254 -101.082178)
			(xy 168.800272 -101.093778) (xy 168.80078 -101.112828) (xy 168.80078 -101.240082) (xy 183.371742 -101.240082)
			(xy 183.375813 -101.18446) (xy 183.387939 -101.130023) (xy 183.407862 -101.077932) (xy 183.435158 -101.029297)
			(xy 183.469244 -100.985154) (xy 183.509393 -100.946445) (xy 183.554751 -100.913994) (xy 183.604351 -100.888493)
			(xy 183.657135 -100.870486) (xy 183.711978 -100.860356) (xy 183.767712 -100.858319) (xy 183.823149 -100.864419)
			(xy 183.877106 -100.878525) (xy 183.928435 -100.900337) (xy 183.976041 -100.929391) (xy 184.018909 -100.965066)
			(xy 184.056126 -101.006603) (xy 184.086899 -101.053116) (xy 184.110571 -101.103613) (xy 184.126639 -101.15702)
			(xy 184.134759 -101.212196) (xy 184.135268 -101.240082) (xy 190.393826 -101.240082) (xy 190.397897 -101.18446)
			(xy 190.410023 -101.130023) (xy 190.429946 -101.077932) (xy 190.457242 -101.029297) (xy 190.491328 -100.985154)
			(xy 190.531477 -100.946445) (xy 190.576835 -100.913994) (xy 190.626435 -100.888493) (xy 190.679219 -100.870486)
			(xy 190.734062 -100.860356) (xy 190.789796 -100.858319) (xy 190.845233 -100.864419) (xy 190.89919 -100.878525)
			(xy 190.950519 -100.900337) (xy 190.998125 -100.929391) (xy 191.040993 -100.965066) (xy 191.07821 -101.006603)
			(xy 191.108983 -101.053116) (xy 191.129477 -101.096834) (xy 191.687225 -101.096834) (xy 191.687227 -101.04234)
			(xy 191.694984 -100.988401) (xy 191.710338 -100.936114) (xy 191.732977 -100.886545) (xy 191.762439 -100.840703)
			(xy 191.798126 -100.799519) (xy 191.83931 -100.763834) (xy 191.885154 -100.734372) (xy 191.934723 -100.711735)
			(xy 191.98701 -100.696382) (xy 192.040949 -100.688626) (xy 192.068196 -100.68814) (xy 192.06845 -100.68814)
			(xy 192.089911 -100.688436) (xy 192.132558 -100.693275) (xy 192.15354 -100.697792) (xy 192.166979 -100.700473)
			(xy 192.194349 -100.699239) (xy 192.220407 -100.690776) (xy 192.243279 -100.675693) (xy 192.261322 -100.655076)
			(xy 192.273238 -100.630405) (xy 192.278171 -100.603455) (xy 192.275765 -100.576163) (xy 192.271396 -100.563172)
			(xy 192.260195 -100.531041) (xy 192.248058 -100.464094) (xy 192.247266 -100.430076) (xy 192.247266 -100.429314)
			(xy 192.24774 -100.402059) (xy 192.255496 -100.348105) (xy 192.270851 -100.295804) (xy 192.293493 -100.24622)
			(xy 192.322962 -100.200363) (xy 192.358657 -100.159167) (xy 192.399852 -100.123471) (xy 192.445707 -100.094)
			(xy 192.49529 -100.071356) (xy 192.547591 -100.055999) (xy 192.601545 -100.048241) (xy 192.656054 -100.048241)
			(xy 192.710008 -100.055998) (xy 192.712385 -100.056696) (xy 194.269358 -100.056696) (xy 194.273429 -100.001074)
			(xy 194.285555 -99.946637) (xy 194.305478 -99.894546) (xy 194.332774 -99.845911) (xy 194.36686 -99.801768)
			(xy 194.407009 -99.763059) (xy 194.452367 -99.730608) (xy 194.501967 -99.705107) (xy 194.554751 -99.6871)
			(xy 194.609594 -99.67697) (xy 194.665328 -99.674933) (xy 194.720765 -99.681033) (xy 194.774722 -99.695139)
			(xy 194.826051 -99.716951) (xy 194.873657 -99.746005) (xy 194.916525 -99.78168) (xy 194.953742 -99.823217)
			(xy 194.984515 -99.86973) (xy 195.008187 -99.920227) (xy 195.024255 -99.973634) (xy 195.032375 -100.02881)
			(xy 195.032884 -100.056696) (xy 195.032375 -100.084582) (xy 195.024255 -100.139758) (xy 195.008187 -100.193165)
			(xy 194.984515 -100.243662) (xy 194.953742 -100.290175) (xy 194.916525 -100.331712) (xy 194.873657 -100.367387)
			(xy 194.826051 -100.396441) (xy 194.774722 -100.418253) (xy 194.720765 -100.432359) (xy 194.665328 -100.438459)
			(xy 194.609594 -100.436422) (xy 194.554751 -100.426292) (xy 194.501967 -100.408285) (xy 194.452367 -100.382784)
			(xy 194.407009 -100.350333) (xy 194.36686 -100.311624) (xy 194.332774 -100.267481) (xy 194.305478 -100.218846)
			(xy 194.285555 -100.166755) (xy 194.273429 -100.112318) (xy 194.269358 -100.056696) (xy 192.712385 -100.056696)
			(xy 192.762309 -100.071356) (xy 192.811892 -100.094) (xy 192.857747 -100.12347) (xy 192.898942 -100.159166)
			(xy 192.934637 -100.200362) (xy 192.964106 -100.246219) (xy 192.986749 -100.295802) (xy 193.002104 -100.348104)
			(xy 193.00986 -100.402058) (xy 193.009858 -100.456567) (xy 193.002099 -100.510521) (xy 192.98674 -100.562821)
			(xy 192.964094 -100.612404) (xy 192.934622 -100.658258) (xy 192.898924 -100.699451) (xy 192.857727 -100.735145)
			(xy 192.81187 -100.764612) (xy 192.762285 -100.787253) (xy 192.709983 -100.802607) (xy 192.656029 -100.810361)
			(xy 192.628774 -100.810822) (xy 192.62852 -100.810822) (xy 192.607059 -100.810532) (xy 192.564412 -100.805689)
			(xy 192.54343 -100.80117) (xy 192.529971 -100.798611) (xy 192.502615 -100.79983) (xy 192.476568 -100.808276)
			(xy 192.453702 -100.823341) (xy 192.435662 -100.843941) (xy 192.423746 -100.868594) (xy 192.41881 -100.895528)
			(xy 192.421209 -100.922806) (xy 192.425574 -100.93579) (xy 192.436765 -100.967924) (xy 192.448908 -101.034869)
			(xy 192.449704 -101.068886) (xy 192.449704 -101.069648) (xy 194.269358 -101.069648) (xy 194.273429 -101.014026)
			(xy 194.285555 -100.959589) (xy 194.305478 -100.907498) (xy 194.332774 -100.858863) (xy 194.36686 -100.81472)
			(xy 194.407009 -100.776011) (xy 194.452367 -100.74356) (xy 194.501967 -100.718059) (xy 194.554751 -100.700052)
			(xy 194.609594 -100.689922) (xy 194.665328 -100.687885) (xy 194.720765 -100.693985) (xy 194.774722 -100.708091)
			(xy 194.826051 -100.729903) (xy 194.873657 -100.758957) (xy 194.916525 -100.794632) (xy 194.953742 -100.836169)
			(xy 194.984515 -100.882682) (xy 195.008187 -100.933179) (xy 195.024255 -100.986586) (xy 195.032375 -101.041762)
			(xy 195.032884 -101.069648) (xy 195.032375 -101.097534) (xy 195.024255 -101.15271) (xy 195.008187 -101.206117)
			(xy 194.984515 -101.256614) (xy 194.953742 -101.303127) (xy 194.916525 -101.344664) (xy 194.873657 -101.380339)
			(xy 194.826051 -101.409393) (xy 194.774722 -101.431205) (xy 194.720765 -101.445311) (xy 194.665328 -101.451411)
			(xy 194.609594 -101.449374) (xy 194.554751 -101.439244) (xy 194.501967 -101.421237) (xy 194.452367 -101.395736)
			(xy 194.407009 -101.363285) (xy 194.36686 -101.324576) (xy 194.332774 -101.280433) (xy 194.305478 -101.231798)
			(xy 194.285555 -101.179707) (xy 194.273429 -101.12527) (xy 194.269358 -101.069648) (xy 192.449704 -101.069648)
			(xy 192.44917 -101.096895) (xy 192.441409 -101.150833) (xy 192.42605 -101.203118) (xy 192.403406 -101.252685)
			(xy 192.37394 -101.298525) (xy 192.338249 -101.339705) (xy 192.297062 -101.375387) (xy 192.251216 -101.404844)
			(xy 192.201644 -101.427477) (xy 192.149356 -101.442825) (xy 192.095416 -101.450576) (xy 192.040922 -101.450572)
			(xy 191.986984 -101.442812) (xy 191.934698 -101.427456) (xy 191.88513 -101.404815) (xy 191.839289 -101.37535)
			(xy 191.798107 -101.339662) (xy 191.762423 -101.298476) (xy 191.732964 -101.252631) (xy 191.710329 -101.203061)
			(xy 191.694978 -101.150773) (xy 191.687225 -101.096834) (xy 191.129477 -101.096834) (xy 191.132655 -101.103613)
			(xy 191.148723 -101.15702) (xy 191.156843 -101.212196) (xy 191.157352 -101.240082) (xy 191.156843 -101.267968)
			(xy 191.148723 -101.323144) (xy 191.132655 -101.376551) (xy 191.108983 -101.427048) (xy 191.07821 -101.473561)
			(xy 191.040993 -101.515098) (xy 190.998125 -101.550773) (xy 190.950519 -101.579827) (xy 190.89919 -101.601639)
			(xy 190.845233 -101.615745) (xy 190.789796 -101.621845) (xy 190.734062 -101.619808) (xy 190.679219 -101.609678)
			(xy 190.626435 -101.591671) (xy 190.576835 -101.56617) (xy 190.531477 -101.533719) (xy 190.491328 -101.49501)
			(xy 190.457242 -101.450867) (xy 190.429946 -101.402232) (xy 190.410023 -101.350141) (xy 190.397897 -101.295704)
			(xy 190.393826 -101.240082) (xy 184.135268 -101.240082) (xy 184.134759 -101.267968) (xy 184.126639 -101.323144)
			(xy 184.110571 -101.376551) (xy 184.086899 -101.427048) (xy 184.056126 -101.473561) (xy 184.018909 -101.515098)
			(xy 183.976041 -101.550773) (xy 183.928435 -101.579827) (xy 183.877106 -101.601639) (xy 183.823149 -101.615745)
			(xy 183.767712 -101.621845) (xy 183.711978 -101.619808) (xy 183.657135 -101.609678) (xy 183.604351 -101.591671)
			(xy 183.554751 -101.56617) (xy 183.509393 -101.533719) (xy 183.469244 -101.49501) (xy 183.435158 -101.450867)
			(xy 183.407862 -101.402232) (xy 183.387939 -101.350141) (xy 183.375813 -101.295704) (xy 183.371742 -101.240082)
			(xy 168.80078 -101.240082) (xy 168.80078 -101.782372) (xy 173.697644 -101.782372) (xy 173.701715 -101.72675)
			(xy 173.713841 -101.672313) (xy 173.733764 -101.620222) (xy 173.76106 -101.571587) (xy 173.795146 -101.527444)
			(xy 173.835295 -101.488735) (xy 173.880653 -101.456284) (xy 173.930253 -101.430783) (xy 173.983037 -101.412776)
			(xy 174.03788 -101.402646) (xy 174.093614 -101.400609) (xy 174.149051 -101.406709) (xy 174.203008 -101.420815)
			(xy 174.254337 -101.442627) (xy 174.301943 -101.471681) (xy 174.344811 -101.507356) (xy 174.382028 -101.548893)
			(xy 174.412801 -101.595406) (xy 174.436473 -101.645903) (xy 174.452541 -101.69931) (xy 174.460661 -101.754486)
			(xy 174.46117 -101.782372) (xy 174.460661 -101.810258) (xy 174.452541 -101.865434) (xy 174.436473 -101.918841)
			(xy 174.412801 -101.969338) (xy 174.382028 -102.015851) (xy 174.344811 -102.057388) (xy 174.301943 -102.093063)
			(xy 174.254337 -102.122117) (xy 174.203008 -102.143929) (xy 174.149051 -102.158035) (xy 174.093614 -102.164135)
			(xy 174.03788 -102.162098) (xy 173.983037 -102.151968) (xy 173.930253 -102.133961) (xy 173.880653 -102.10846)
			(xy 173.835295 -102.076009) (xy 173.795146 -102.0373) (xy 173.76106 -101.993157) (xy 173.733764 -101.944522)
			(xy 173.713841 -101.892431) (xy 173.701715 -101.837994) (xy 173.697644 -101.782372) (xy 168.80078 -101.782372)
			(xy 168.80078 -101.976428) (xy 168.800272 -101.99624) (xy 168.800277 -102.007835) (xy 168.809413 -102.029124)
			(xy 168.817798 -102.037134) (xy 168.842182 -102.057962) (xy 168.851134 -102.06499) (xy 168.873048 -102.071039)
			(xy 168.884346 -102.069646) (xy 168.90103 -102.066813) (xy 168.934735 -102.063757) (xy 168.951656 -102.06355)
			(xy 168.952164 -102.06355) (xy 168.979534 -102.064025) (xy 169.033713 -102.071839) (xy 169.086217 -102.087325)
			(xy 169.135964 -102.110165) (xy 169.181931 -102.139889) (xy 169.202862 -102.15753) (xy 169.20972 -102.163626)
			(xy 169.226738 -102.169976) (xy 169.312082 -102.169976) (xy 169.329354 -102.163372) (xy 169.336212 -102.157276)
			(xy 169.357164 -102.139661) (xy 169.403127 -102.109936) (xy 169.452869 -102.087091) (xy 169.505367 -102.071595)
			(xy 169.559541 -102.063768) (xy 169.58691 -102.063296) (xy 169.587164 -102.063296) (xy 169.614141 -102.063758)
			(xy 169.667558 -102.071346) (xy 169.719371 -102.086391) (xy 169.768546 -102.108591) (xy 169.814099 -102.137503)
			(xy 169.85512 -102.172549) (xy 169.89079 -102.213029) (xy 169.920396 -102.258134) (xy 169.943346 -102.306962)
			(xy 169.959182 -102.35854) (xy 169.963846 -102.385114) (xy 169.963846 -102.385368) (xy 169.966026 -102.395637)
			(xy 169.977461 -102.413217) (xy 169.985944 -102.419404) (xy 170.057318 -102.466902) (xy 170.077892 -102.470458)
			(xy 170.088306 -102.467918) (xy 170.115071 -102.461836) (xy 170.169573 -102.45534) (xy 170.197018 -102.454964)
			(xy 170.224336 -102.455359) (xy 170.278584 -102.461848) (xy 170.305222 -102.467918) (xy 170.305476 -102.467918)
			(xy 170.315705 -102.469788) (xy 170.336153 -102.466106) (xy 170.3451 -102.460806) (xy 170.416728 -102.413308)
			(xy 170.427904 -102.395782) (xy 170.429682 -102.385114) (xy 170.434355 -102.358544) (xy 170.450207 -102.306978)
			(xy 170.473168 -102.25816) (xy 170.502779 -102.213065) (xy 170.538449 -102.172592) (xy 170.579466 -102.137549)
			(xy 170.625012 -102.108636) (xy 170.674177 -102.086429) (xy 170.725981 -102.071372) (xy 170.77939 -102.063765)
			(xy 170.806364 -102.063296) (xy 170.833619 -102.063749) (xy 170.887574 -102.071502) (xy 170.939877 -102.086855)
			(xy 170.989462 -102.109496) (xy 171.03532 -102.138963) (xy 171.076518 -102.174657) (xy 171.112216 -102.215851)
			(xy 171.141687 -102.261706) (xy 171.164333 -102.311289) (xy 171.179691 -102.363591) (xy 171.187449 -102.417545)
			(xy 171.187449 -102.472055) (xy 171.179691 -102.526009) (xy 171.164333 -102.578311) (xy 171.141687 -102.627894)
			(xy 171.112216 -102.673749) (xy 171.076518 -102.714943) (xy 171.03532 -102.750637) (xy 170.989462 -102.780104)
			(xy 170.949454 -102.798372) (xy 173.697644 -102.798372) (xy 173.701715 -102.74275) (xy 173.713841 -102.688313)
			(xy 173.733764 -102.636222) (xy 173.76106 -102.587587) (xy 173.795146 -102.543444) (xy 173.835295 -102.504735)
			(xy 173.880653 -102.472284) (xy 173.930253 -102.446783) (xy 173.983037 -102.428776) (xy 174.03788 -102.418646)
			(xy 174.093614 -102.416609) (xy 174.149051 -102.422709) (xy 174.203008 -102.436815) (xy 174.254337 -102.458627)
			(xy 174.301943 -102.487681) (xy 174.344811 -102.523356) (xy 174.382028 -102.564893) (xy 174.412801 -102.611406)
			(xy 174.436473 -102.661903) (xy 174.448186 -102.700836) (xy 181.842662 -102.700836) (xy 181.846733 -102.645214)
			(xy 181.858859 -102.590777) (xy 181.878782 -102.538686) (xy 181.906078 -102.490051) (xy 181.940164 -102.445908)
			(xy 181.980313 -102.407199) (xy 182.025671 -102.374748) (xy 182.075271 -102.349247) (xy 182.128055 -102.33124)
			(xy 182.182898 -102.32111) (xy 182.238632 -102.319073) (xy 182.294069 -102.325173) (xy 182.348026 -102.339279)
			(xy 182.399355 -102.361091) (xy 182.446961 -102.390145) (xy 182.489829 -102.42582) (xy 182.502515 -102.439978)
			(xy 183.03062 -102.439978) (xy 183.034691 -102.384356) (xy 183.046817 -102.329919) (xy 183.06674 -102.277828)
			(xy 183.094036 -102.229193) (xy 183.128122 -102.18505) (xy 183.168271 -102.146341) (xy 183.213629 -102.11389)
			(xy 183.263229 -102.088389) (xy 183.316013 -102.070382) (xy 183.370856 -102.060252) (xy 183.42659 -102.058215)
			(xy 183.482027 -102.064315) (xy 183.535984 -102.078421) (xy 183.587313 -102.100233) (xy 183.634919 -102.129287)
			(xy 183.677787 -102.164962) (xy 183.715004 -102.206499) (xy 183.745777 -102.253012) (xy 183.769449 -102.303509)
			(xy 183.785517 -102.356916) (xy 183.793637 -102.412092) (xy 183.794146 -102.439978) (xy 190.012826 -102.439978)
			(xy 190.016897 -102.384356) (xy 190.029023 -102.329919) (xy 190.048946 -102.277828) (xy 190.076242 -102.229193)
			(xy 190.110328 -102.18505) (xy 190.150477 -102.146341) (xy 190.195835 -102.11389) (xy 190.245435 -102.088389)
			(xy 190.298219 -102.070382) (xy 190.353062 -102.060252) (xy 190.408796 -102.058215) (xy 190.464233 -102.064315)
			(xy 190.51819 -102.078421) (xy 190.54237 -102.088696) (xy 194.269358 -102.088696) (xy 194.273429 -102.033074)
			(xy 194.285555 -101.978637) (xy 194.305478 -101.926546) (xy 194.332774 -101.877911) (xy 194.36686 -101.833768)
			(xy 194.407009 -101.795059) (xy 194.452367 -101.762608) (xy 194.501967 -101.737107) (xy 194.554751 -101.7191)
			(xy 194.609594 -101.70897) (xy 194.665328 -101.706933) (xy 194.720765 -101.713033) (xy 194.774722 -101.727139)
			(xy 194.826051 -101.748951) (xy 194.873657 -101.778005) (xy 194.916525 -101.81368) (xy 194.953742 -101.855217)
			(xy 194.984515 -101.90173) (xy 195.008187 -101.952227) (xy 195.024255 -102.005634) (xy 195.032375 -102.06081)
			(xy 195.032884 -102.088696) (xy 195.032375 -102.116582) (xy 195.024255 -102.171758) (xy 195.008187 -102.225165)
			(xy 194.984515 -102.275662) (xy 194.953742 -102.322175) (xy 194.916525 -102.363712) (xy 194.873657 -102.399387)
			(xy 194.826051 -102.428441) (xy 194.774722 -102.450253) (xy 194.720765 -102.464359) (xy 194.665328 -102.470459)
			(xy 194.609594 -102.468422) (xy 194.554751 -102.458292) (xy 194.501967 -102.440285) (xy 194.452367 -102.414784)
			(xy 194.407009 -102.382333) (xy 194.36686 -102.343624) (xy 194.332774 -102.299481) (xy 194.305478 -102.250846)
			(xy 194.285555 -102.198755) (xy 194.273429 -102.144318) (xy 194.269358 -102.088696) (xy 190.54237 -102.088696)
			(xy 190.569519 -102.100233) (xy 190.617125 -102.129287) (xy 190.659993 -102.164962) (xy 190.69721 -102.206499)
			(xy 190.727983 -102.253012) (xy 190.751655 -102.303509) (xy 190.767723 -102.356916) (xy 190.775843 -102.412092)
			(xy 190.776352 -102.439978) (xy 190.775843 -102.467864) (xy 190.772733 -102.489) (xy 190.901826 -102.489)
			(xy 190.905897 -102.433378) (xy 190.918023 -102.378941) (xy 190.937946 -102.32685) (xy 190.965242 -102.278215)
			(xy 190.999328 -102.234072) (xy 191.039477 -102.195363) (xy 191.084835 -102.162912) (xy 191.134435 -102.137411)
			(xy 191.187219 -102.119404) (xy 191.242062 -102.109274) (xy 191.297796 -102.107237) (xy 191.353233 -102.113337)
			(xy 191.40719 -102.127443) (xy 191.458519 -102.149255) (xy 191.506125 -102.178309) (xy 191.548993 -102.213984)
			(xy 191.58621 -102.255521) (xy 191.616983 -102.302034) (xy 191.640655 -102.352531) (xy 191.656723 -102.405938)
			(xy 191.664843 -102.461114) (xy 191.665352 -102.489) (xy 191.664843 -102.516886) (xy 191.656836 -102.571296)
			(xy 191.845182 -102.571296) (xy 191.849253 -102.515674) (xy 191.861379 -102.461237) (xy 191.881302 -102.409146)
			(xy 191.908598 -102.360511) (xy 191.942684 -102.316368) (xy 191.982833 -102.277659) (xy 192.028191 -102.245208)
			(xy 192.077791 -102.219707) (xy 192.130575 -102.2017) (xy 192.185418 -102.19157) (xy 192.241152 -102.189533)
			(xy 192.296589 -102.195633) (xy 192.350546 -102.209739) (xy 192.401875 -102.231551) (xy 192.449481 -102.260605)
			(xy 192.492349 -102.29628) (xy 192.529566 -102.337817) (xy 192.560339 -102.38433) (xy 192.584011 -102.434827)
			(xy 192.600079 -102.488234) (xy 192.608199 -102.54341) (xy 192.608708 -102.571296) (xy 192.608199 -102.599182)
			(xy 192.600079 -102.654358) (xy 192.584011 -102.707765) (xy 192.560339 -102.758262) (xy 192.529566 -102.804775)
			(xy 192.492349 -102.846312) (xy 192.449481 -102.881987) (xy 192.401875 -102.911041) (xy 192.350546 -102.932853)
			(xy 192.296589 -102.946959) (xy 192.241152 -102.953059) (xy 192.185418 -102.951022) (xy 192.130575 -102.940892)
			(xy 192.077791 -102.922885) (xy 192.028191 -102.897384) (xy 191.982833 -102.864933) (xy 191.942684 -102.826224)
			(xy 191.908598 -102.782081) (xy 191.881302 -102.733446) (xy 191.861379 -102.681355) (xy 191.849253 -102.626918)
			(xy 191.845182 -102.571296) (xy 191.656836 -102.571296) (xy 191.656723 -102.572062) (xy 191.640655 -102.625469)
			(xy 191.616983 -102.675966) (xy 191.58621 -102.722479) (xy 191.548993 -102.764016) (xy 191.506125 -102.799691)
			(xy 191.458519 -102.828745) (xy 191.40719 -102.850557) (xy 191.353233 -102.864663) (xy 191.297796 -102.870763)
			(xy 191.242062 -102.868726) (xy 191.187219 -102.858596) (xy 191.134435 -102.840589) (xy 191.084835 -102.815088)
			(xy 191.039477 -102.782637) (xy 190.999328 -102.743928) (xy 190.965242 -102.699785) (xy 190.937946 -102.65115)
			(xy 190.918023 -102.599059) (xy 190.905897 -102.544622) (xy 190.901826 -102.489) (xy 190.772733 -102.489)
			(xy 190.767723 -102.52304) (xy 190.751655 -102.576447) (xy 190.727983 -102.626944) (xy 190.69721 -102.673457)
			(xy 190.659993 -102.714994) (xy 190.617125 -102.750669) (xy 190.569519 -102.779723) (xy 190.51819 -102.801535)
			(xy 190.464233 -102.815641) (xy 190.408796 -102.821741) (xy 190.353062 -102.819704) (xy 190.298219 -102.809574)
			(xy 190.245435 -102.791567) (xy 190.195835 -102.766066) (xy 190.150477 -102.733615) (xy 190.110328 -102.694906)
			(xy 190.076242 -102.650763) (xy 190.048946 -102.602128) (xy 190.029023 -102.550037) (xy 190.016897 -102.4956)
			(xy 190.012826 -102.439978) (xy 183.794146 -102.439978) (xy 183.793637 -102.467864) (xy 183.785517 -102.52304)
			(xy 183.769449 -102.576447) (xy 183.745777 -102.626944) (xy 183.715004 -102.673457) (xy 183.677787 -102.714994)
			(xy 183.634919 -102.750669) (xy 183.587313 -102.779723) (xy 183.535984 -102.801535) (xy 183.482027 -102.815641)
			(xy 183.42659 -102.821741) (xy 183.370856 -102.819704) (xy 183.316013 -102.809574) (xy 183.263229 -102.791567)
			(xy 183.213629 -102.766066) (xy 183.168271 -102.733615) (xy 183.128122 -102.694906) (xy 183.094036 -102.650763)
			(xy 183.06674 -102.602128) (xy 183.046817 -102.550037) (xy 183.034691 -102.4956) (xy 183.03062 -102.439978)
			(xy 182.502515 -102.439978) (xy 182.527046 -102.467357) (xy 182.557819 -102.51387) (xy 182.581491 -102.564367)
			(xy 182.597559 -102.617774) (xy 182.605679 -102.67295) (xy 182.606188 -102.700836) (xy 182.605679 -102.728722)
			(xy 182.597559 -102.783898) (xy 182.581491 -102.837305) (xy 182.557819 -102.887802) (xy 182.527046 -102.934315)
			(xy 182.489829 -102.975852) (xy 182.446961 -103.011527) (xy 182.399355 -103.040581) (xy 182.348026 -103.062393)
			(xy 182.294069 -103.076499) (xy 182.238632 -103.082599) (xy 182.182898 -103.080562) (xy 182.128055 -103.070432)
			(xy 182.075271 -103.052425) (xy 182.025671 -103.026924) (xy 181.980313 -102.994473) (xy 181.940164 -102.955764)
			(xy 181.906078 -102.911621) (xy 181.878782 -102.862986) (xy 181.858859 -102.810895) (xy 181.846733 -102.756458)
			(xy 181.842662 -102.700836) (xy 174.448186 -102.700836) (xy 174.452541 -102.71531) (xy 174.460661 -102.770486)
			(xy 174.46117 -102.798372) (xy 174.460661 -102.826258) (xy 174.452541 -102.881434) (xy 174.436473 -102.934841)
			(xy 174.412801 -102.985338) (xy 174.382028 -103.031851) (xy 174.344811 -103.073388) (xy 174.301943 -103.109063)
			(xy 174.254337 -103.138117) (xy 174.203008 -103.159929) (xy 174.149051 -103.174035) (xy 174.093614 -103.180135)
			(xy 174.03788 -103.178098) (xy 173.983037 -103.167968) (xy 173.930253 -103.149961) (xy 173.880653 -103.12446)
			(xy 173.835295 -103.092009) (xy 173.795146 -103.0533) (xy 173.76106 -103.009157) (xy 173.733764 -102.960522)
			(xy 173.713841 -102.908431) (xy 173.701715 -102.853994) (xy 173.697644 -102.798372) (xy 170.949454 -102.798372)
			(xy 170.939877 -102.802745) (xy 170.887574 -102.818098) (xy 170.833619 -102.825851) (xy 170.806364 -102.826312)
			(xy 170.805856 -102.826312) (xy 170.788935 -102.826091) (xy 170.755231 -102.823038) (xy 170.738546 -102.820216)
			(xy 170.727255 -102.81885) (xy 170.705366 -102.824924) (xy 170.696382 -102.8319) (xy 170.671998 -102.852728)
			(xy 170.663579 -102.860715) (xy 170.654445 -102.882018) (xy 170.654472 -102.893622) (xy 170.65498 -102.912672)
			(xy 170.65498 -103.388358) (xy 190.71354 -103.388358) (xy 190.721296 -103.334405) (xy 190.736651 -103.282104)
			(xy 190.759293 -103.232521) (xy 190.788761 -103.186665) (xy 190.824454 -103.14547) (xy 190.865648 -103.109774)
			(xy 190.911502 -103.080303) (xy 190.961084 -103.057658) (xy 191.013383 -103.0423) (xy 191.067336 -103.034542)
			(xy 191.121844 -103.03454) (xy 191.175797 -103.042296) (xy 191.228098 -103.057651) (xy 191.27768 -103.080294)
			(xy 191.315653 -103.104696) (xy 194.269358 -103.104696) (xy 194.273429 -103.049074) (xy 194.285555 -102.994637)
			(xy 194.305478 -102.942546) (xy 194.332774 -102.893911) (xy 194.36686 -102.849768) (xy 194.407009 -102.811059)
			(xy 194.452367 -102.778608) (xy 194.501967 -102.753107) (xy 194.554751 -102.7351) (xy 194.609594 -102.72497)
			(xy 194.665328 -102.722933) (xy 194.720765 -102.729033) (xy 194.774722 -102.743139) (xy 194.826051 -102.764951)
			(xy 194.873657 -102.794005) (xy 194.916525 -102.82968) (xy 194.953742 -102.871217) (xy 194.984515 -102.91773)
			(xy 195.008187 -102.968227) (xy 195.024255 -103.021634) (xy 195.032375 -103.07681) (xy 195.032884 -103.104696)
			(xy 195.032375 -103.132582) (xy 195.024255 -103.187758) (xy 195.008187 -103.241165) (xy 194.984515 -103.291662)
			(xy 194.953742 -103.338175) (xy 194.916525 -103.379712) (xy 194.873657 -103.415387) (xy 194.826051 -103.444441)
			(xy 194.774722 -103.466253) (xy 194.720765 -103.480359) (xy 194.665328 -103.486459) (xy 194.609594 -103.484422)
			(xy 194.554751 -103.474292) (xy 194.501967 -103.456285) (xy 194.452367 -103.430784) (xy 194.407009 -103.398333)
			(xy 194.36686 -103.359624) (xy 194.332774 -103.315481) (xy 194.305478 -103.266846) (xy 194.285555 -103.214755)
			(xy 194.273429 -103.160318) (xy 194.269358 -103.104696) (xy 191.315653 -103.104696) (xy 191.323536 -103.109762)
			(xy 191.364731 -103.145456) (xy 191.400427 -103.186649) (xy 191.429898 -103.232504) (xy 191.452542 -103.282085)
			(xy 191.4679 -103.334385) (xy 191.475659 -103.388338) (xy 191.476122 -103.415592) (xy 191.474852 -103.445564)
			(xy 191.474203 -103.459014) (xy 191.479134 -103.485477) (xy 191.490807 -103.509732) (xy 191.508411 -103.530095)
			(xy 191.530724 -103.545152) (xy 191.556196 -103.553857) (xy 191.583057 -103.555605) (xy 191.609441 -103.550274)
			(xy 191.621664 -103.544624) (xy 191.648235 -103.531988) (xy 191.704294 -103.514125) (xy 191.762427 -103.50506)
			(xy 191.791844 -103.504492) (xy 191.819091 -103.505025) (xy 191.873031 -103.512787) (xy 191.925316 -103.528145)
			(xy 191.974884 -103.550789) (xy 192.020725 -103.580255) (xy 192.061906 -103.615946) (xy 192.097589 -103.657134)
			(xy 192.127047 -103.70298) (xy 192.14968 -103.752552) (xy 192.165029 -103.804841) (xy 192.17278 -103.858782)
			(xy 192.172776 -103.913277) (xy 192.165016 -103.967216) (xy 192.14966 -104.019503) (xy 192.127019 -104.069071)
			(xy 192.097554 -104.114913) (xy 192.092542 -104.120696) (xy 194.269358 -104.120696) (xy 194.273429 -104.065074)
			(xy 194.285555 -104.010637) (xy 194.305478 -103.958546) (xy 194.332774 -103.909911) (xy 194.36686 -103.865768)
			(xy 194.407009 -103.827059) (xy 194.452367 -103.794608) (xy 194.501967 -103.769107) (xy 194.554751 -103.7511)
			(xy 194.609594 -103.74097) (xy 194.665328 -103.738933) (xy 194.720765 -103.745033) (xy 194.774722 -103.759139)
			(xy 194.826051 -103.780951) (xy 194.873657 -103.810005) (xy 194.916525 -103.84568) (xy 194.953742 -103.887217)
			(xy 194.984515 -103.93373) (xy 195.008187 -103.984227) (xy 195.024255 -104.037634) (xy 195.032375 -104.09281)
			(xy 195.032884 -104.120696) (xy 195.032375 -104.148582) (xy 195.024255 -104.203758) (xy 195.008187 -104.257165)
			(xy 194.984515 -104.307662) (xy 194.953742 -104.354175) (xy 194.916525 -104.395712) (xy 194.873657 -104.431387)
			(xy 194.826051 -104.460441) (xy 194.774722 -104.482253) (xy 194.720765 -104.496359) (xy 194.665328 -104.502459)
			(xy 194.609594 -104.500422) (xy 194.554751 -104.490292) (xy 194.501967 -104.472285) (xy 194.452367 -104.446784)
			(xy 194.407009 -104.414333) (xy 194.36686 -104.375624) (xy 194.332774 -104.331481) (xy 194.305478 -104.282846)
			(xy 194.285555 -104.230755) (xy 194.273429 -104.176318) (xy 194.269358 -104.120696) (xy 192.092542 -104.120696)
			(xy 192.061865 -104.156096) (xy 192.020678 -104.19178) (xy 191.974833 -104.22124) (xy 191.925261 -104.243875)
			(xy 191.872973 -104.259226) (xy 191.819033 -104.266979) (xy 191.764538 -104.266977) (xy 191.710598 -104.25922)
			(xy 191.658311 -104.243865) (xy 191.608742 -104.221226) (xy 191.562898 -104.191762) (xy 191.521715 -104.156075)
			(xy 191.486029 -104.11489) (xy 191.456567 -104.069046) (xy 191.43393 -104.019475) (xy 191.418577 -103.967188)
			(xy 191.410822 -103.913247) (xy 191.410336 -103.886) (xy 191.411606 -103.856028) (xy 191.412322 -103.842578)
			(xy 191.407387 -103.816106) (xy 191.395707 -103.791842) (xy 191.378093 -103.771474) (xy 191.355769 -103.756415)
			(xy 191.330285 -103.747713) (xy 191.303413 -103.745971) (xy 191.27702 -103.751312) (xy 191.264794 -103.756968)
			(xy 191.238229 -103.769618) (xy 191.182167 -103.787475) (xy 191.124032 -103.796535) (xy 191.094614 -103.7971)
			(xy 191.06736 -103.79666) (xy 191.013407 -103.788905) (xy 190.961106 -103.77355) (xy 190.911523 -103.750908)
			(xy 190.865667 -103.721441) (xy 190.824471 -103.685747) (xy 190.788775 -103.644554) (xy 190.759304 -103.5987)
			(xy 190.736659 -103.549118) (xy 190.721301 -103.496819) (xy 190.713542 -103.442866) (xy 190.71354 -103.388358)
			(xy 170.65498 -103.388358) (xy 170.65498 -103.776272) (xy 170.654472 -103.796084) (xy 170.65451 -103.807676)
			(xy 170.657376 -103.814372) (xy 173.697644 -103.814372) (xy 173.701715 -103.75875) (xy 173.713841 -103.704313)
			(xy 173.733764 -103.652222) (xy 173.76106 -103.603587) (xy 173.795146 -103.559444) (xy 173.835295 -103.520735)
			(xy 173.880653 -103.488284) (xy 173.930253 -103.462783) (xy 173.983037 -103.444776) (xy 174.03788 -103.434646)
			(xy 174.093614 -103.432609) (xy 174.149051 -103.438709) (xy 174.203008 -103.452815) (xy 174.254337 -103.474627)
			(xy 174.301943 -103.503681) (xy 174.344811 -103.539356) (xy 174.382028 -103.580893) (xy 174.412801 -103.627406)
			(xy 174.436473 -103.677903) (xy 174.452541 -103.73131) (xy 174.460661 -103.786486) (xy 174.46117 -103.814372)
			(xy 174.460661 -103.842258) (xy 174.452541 -103.897434) (xy 174.436473 -103.950841) (xy 174.412801 -104.001338)
			(xy 174.382028 -104.047851) (xy 174.344811 -104.089388) (xy 174.301943 -104.125063) (xy 174.254337 -104.154117)
			(xy 174.203008 -104.175929) (xy 174.149051 -104.190035) (xy 174.093614 -104.196135) (xy 174.03788 -104.194098)
			(xy 173.983037 -104.183968) (xy 173.930253 -104.165961) (xy 173.880653 -104.14046) (xy 173.835295 -104.108009)
			(xy 173.795146 -104.0693) (xy 173.76106 -104.025157) (xy 173.733764 -103.976522) (xy 173.713841 -103.924431)
			(xy 173.701715 -103.869994) (xy 173.697644 -103.814372) (xy 170.657376 -103.814372) (xy 170.663623 -103.828965)
			(xy 170.671998 -103.836978) (xy 170.696382 -103.857806) (xy 170.705338 -103.864829) (xy 170.727249 -103.870884)
			(xy 170.738546 -103.86949) (xy 170.75523 -103.866657) (xy 170.788935 -103.8636) (xy 170.805856 -103.863394)
			(xy 170.806364 -103.863394) (xy 170.833619 -103.863851) (xy 170.887574 -103.871604) (xy 170.939876 -103.886957)
			(xy 170.989461 -103.909597) (xy 171.035319 -103.939064) (xy 171.076516 -103.974758) (xy 171.112214 -104.015952)
			(xy 171.141685 -104.061807) (xy 171.164331 -104.11139) (xy 171.179689 -104.163691) (xy 171.187447 -104.217645)
			(xy 171.187447 -104.272155) (xy 171.179689 -104.326109) (xy 171.164331 -104.37841) (xy 171.161387 -104.384856)
			(xy 181.762652 -104.384856) (xy 181.766723 -104.329234) (xy 181.778849 -104.274797) (xy 181.798772 -104.222706)
			(xy 181.826068 -104.174071) (xy 181.860154 -104.129928) (xy 181.900303 -104.091219) (xy 181.945661 -104.058768)
			(xy 181.995261 -104.033267) (xy 182.048045 -104.01526) (xy 182.102888 -104.00513) (xy 182.158622 -104.003093)
			(xy 182.214059 -104.009193) (xy 182.268016 -104.023299) (xy 182.319345 -104.045111) (xy 182.366951 -104.074165)
			(xy 182.409819 -104.10984) (xy 182.447036 -104.151377) (xy 182.477809 -104.19789) (xy 182.497585 -104.240076)
			(xy 183.03062 -104.240076) (xy 183.034691 -104.184454) (xy 183.046817 -104.130017) (xy 183.06674 -104.077926)
			(xy 183.094036 -104.029291) (xy 183.128122 -103.985148) (xy 183.168271 -103.946439) (xy 183.213629 -103.913988)
			(xy 183.263229 -103.888487) (xy 183.316013 -103.87048) (xy 183.370856 -103.86035) (xy 183.42659 -103.858313)
			(xy 183.482027 -103.864413) (xy 183.535984 -103.878519) (xy 183.587313 -103.900331) (xy 183.634919 -103.929385)
			(xy 183.677787 -103.96506) (xy 183.715004 -104.006597) (xy 183.745777 -104.05311) (xy 183.769449 -104.103607)
			(xy 183.785517 -104.157014) (xy 183.793637 -104.21219) (xy 183.794146 -104.240076) (xy 190.012826 -104.240076)
			(xy 190.016897 -104.184454) (xy 190.029023 -104.130017) (xy 190.048946 -104.077926) (xy 190.076242 -104.029291)
			(xy 190.110328 -103.985148) (xy 190.150477 -103.946439) (xy 190.195835 -103.913988) (xy 190.245435 -103.888487)
			(xy 190.298219 -103.87048) (xy 190.353062 -103.86035) (xy 190.408796 -103.858313) (xy 190.464233 -103.864413)
			(xy 190.51819 -103.878519) (xy 190.569519 -103.900331) (xy 190.617125 -103.929385) (xy 190.659993 -103.96506)
			(xy 190.69721 -104.006597) (xy 190.727983 -104.05311) (xy 190.751655 -104.103607) (xy 190.767723 -104.157014)
			(xy 190.775843 -104.21219) (xy 190.776352 -104.240076) (xy 190.775843 -104.267962) (xy 190.767723 -104.323138)
			(xy 190.751655 -104.376545) (xy 190.727983 -104.427042) (xy 190.69721 -104.473555) (xy 190.659993 -104.515092)
			(xy 190.617125 -104.550767) (xy 190.569519 -104.579821) (xy 190.51819 -104.601633) (xy 190.464233 -104.615739)
			(xy 190.408796 -104.621839) (xy 190.353062 -104.619802) (xy 190.298219 -104.609672) (xy 190.245435 -104.591665)
			(xy 190.195835 -104.566164) (xy 190.150477 -104.533713) (xy 190.110328 -104.495004) (xy 190.076242 -104.450861)
			(xy 190.048946 -104.402226) (xy 190.029023 -104.350135) (xy 190.016897 -104.295698) (xy 190.012826 -104.240076)
			(xy 183.794146 -104.240076) (xy 183.793637 -104.267962) (xy 183.785517 -104.323138) (xy 183.769449 -104.376545)
			(xy 183.745777 -104.427042) (xy 183.715004 -104.473555) (xy 183.677787 -104.515092) (xy 183.634919 -104.550767)
			(xy 183.587313 -104.579821) (xy 183.535984 -104.601633) (xy 183.482027 -104.615739) (xy 183.42659 -104.621839)
			(xy 183.370856 -104.619802) (xy 183.316013 -104.609672) (xy 183.263229 -104.591665) (xy 183.213629 -104.566164)
			(xy 183.168271 -104.533713) (xy 183.128122 -104.495004) (xy 183.094036 -104.450861) (xy 183.06674 -104.402226)
			(xy 183.046817 -104.350135) (xy 183.034691 -104.295698) (xy 183.03062 -104.240076) (xy 182.497585 -104.240076)
			(xy 182.501481 -104.248387) (xy 182.517549 -104.301794) (xy 182.525669 -104.35697) (xy 182.526178 -104.384856)
			(xy 182.525669 -104.412742) (xy 182.517549 -104.467918) (xy 182.501481 -104.521325) (xy 182.477809 -104.571822)
			(xy 182.447036 -104.618335) (xy 182.409819 -104.659872) (xy 182.366951 -104.695547) (xy 182.319345 -104.724601)
			(xy 182.268016 -104.746413) (xy 182.214059 -104.760519) (xy 182.158622 -104.766619) (xy 182.102888 -104.764582)
			(xy 182.048045 -104.754452) (xy 181.995261 -104.736445) (xy 181.945661 -104.710944) (xy 181.900303 -104.678493)
			(xy 181.860154 -104.639784) (xy 181.826068 -104.595641) (xy 181.798772 -104.547006) (xy 181.778849 -104.494915)
			(xy 181.766723 -104.440478) (xy 181.762652 -104.384856) (xy 171.161387 -104.384856) (xy 171.141685 -104.427993)
			(xy 171.112214 -104.473848) (xy 171.076516 -104.515042) (xy 171.035319 -104.550736) (xy 170.989461 -104.580203)
			(xy 170.939876 -104.602843) (xy 170.887574 -104.618196) (xy 170.833619 -104.625949) (xy 170.806364 -104.62641)
			(xy 170.779354 -104.626011) (xy 170.725873 -104.618399) (xy 170.674001 -104.603318) (xy 170.624775 -104.581071)
			(xy 170.579179 -104.552102) (xy 170.538127 -104.51699) (xy 170.502438 -104.476438) (xy 170.472828 -104.431256)
			(xy 170.449887 -104.382349) (xy 170.434075 -104.330695) (xy 170.429428 -104.304084) (xy 170.427904 -104.293416)
			(xy 170.416474 -104.275636) (xy 170.33621 -104.222296) (xy 170.315636 -104.21874) (xy 170.305222 -104.22128)
			(xy 170.278577 -104.227284) (xy 170.224329 -104.233646) (xy 170.197018 -104.23398) (xy 170.169636 -104.233598)
			(xy 170.11526 -104.227108) (xy 170.08856 -104.221026) (xy 170.078146 -104.218486) (xy 170.057572 -104.222042)
			(xy 169.977054 -104.275636) (xy 169.965624 -104.293416) (xy 169.9641 -104.304084) (xy 169.95942 -104.330684)
			(xy 169.943592 -104.382321) (xy 169.920641 -104.431211) (xy 169.891026 -104.476376) (xy 169.855339 -104.516914)
			(xy 169.814293 -104.552016) (xy 169.768708 -104.58098) (xy 169.719495 -104.603227) (xy 169.667636 -104.618314)
			(xy 169.614168 -104.625938) (xy 169.587164 -104.62641) (xy 169.559793 -104.625963) (xy 169.505613 -104.61814)
			(xy 169.45311 -104.602646) (xy 169.403364 -104.579801) (xy 169.357397 -104.550073) (xy 169.336466 -104.53243)
			(xy 169.336212 -104.532176) (xy 169.329128 -104.526586) (xy 169.312209 -104.520342) (xy 169.303192 -104.519984)
			(xy 169.236136 -104.519984) (xy 169.227121 -104.520362) (xy 169.210204 -104.526595) (xy 169.203116 -104.532176)
			(xy 169.203116 -104.53243) (xy 169.202862 -104.53243) (xy 169.181921 -104.550058) (xy 169.13595 -104.579771)
			(xy 169.086205 -104.602608) (xy 169.033706 -104.618102) (xy 168.979532 -104.625934) (xy 168.952164 -104.62641)
			(xy 168.951656 -104.62641) (xy 168.934735 -104.626189) (xy 168.901031 -104.623136) (xy 168.884346 -104.620314)
			(xy 168.873055 -104.618949) (xy 168.851166 -104.625022) (xy 168.842182 -104.631998) (xy 168.817798 -104.652826)
			(xy 168.80938 -104.660814) (xy 168.800245 -104.682116) (xy 168.800272 -104.69372) (xy 168.80078 -104.71277)
			(xy 168.80078 -104.830372) (xy 173.697644 -104.830372) (xy 173.701715 -104.77475) (xy 173.713841 -104.720313)
			(xy 173.733764 -104.668222) (xy 173.76106 -104.619587) (xy 173.795146 -104.575444) (xy 173.835295 -104.536735)
			(xy 173.880653 -104.504284) (xy 173.930253 -104.478783) (xy 173.983037 -104.460776) (xy 174.03788 -104.450646)
			(xy 174.093614 -104.448609) (xy 174.149051 -104.454709) (xy 174.203008 -104.468815) (xy 174.254337 -104.490627)
			(xy 174.301943 -104.519681) (xy 174.344811 -104.555356) (xy 174.382028 -104.596893) (xy 174.412801 -104.643406)
			(xy 174.436473 -104.693903) (xy 174.452541 -104.74731) (xy 174.460661 -104.802486) (xy 174.46117 -104.830372)
			(xy 174.460661 -104.858258) (xy 174.452541 -104.913434) (xy 174.436473 -104.966841) (xy 174.412801 -105.017338)
			(xy 174.382028 -105.063851) (xy 174.344811 -105.105388) (xy 174.301943 -105.141063) (xy 174.254337 -105.170117)
			(xy 174.203008 -105.191929) (xy 174.149051 -105.206035) (xy 174.093614 -105.212135) (xy 174.03788 -105.210098)
			(xy 173.983037 -105.199968) (xy 173.930253 -105.181961) (xy 173.880653 -105.15646) (xy 173.835295 -105.124009)
			(xy 173.795146 -105.0853) (xy 173.76106 -105.041157) (xy 173.733764 -104.992522) (xy 173.713841 -104.940431)
			(xy 173.701715 -104.885994) (xy 173.697644 -104.830372) (xy 168.80078 -104.830372) (xy 168.80078 -105.57637)
			(xy 168.800272 -105.596182) (xy 168.800311 -105.607774) (xy 168.809423 -105.629062) (xy 168.817798 -105.637076)
			(xy 168.842182 -105.657904) (xy 168.851138 -105.664927) (xy 168.873049 -105.670982) (xy 168.884346 -105.669588)
			(xy 168.90103 -105.666755) (xy 168.934735 -105.663698) (xy 168.951656 -105.663492) (xy 168.952164 -105.663492)
			(xy 168.979533 -105.663981) (xy 169.033711 -105.671794) (xy 169.086214 -105.687277) (xy 169.135961 -105.710114)
			(xy 169.181929 -105.739833) (xy 169.202862 -105.757472) (xy 169.20972 -105.763568) (xy 169.226738 -105.769918)
			(xy 169.312082 -105.769918) (xy 169.329354 -105.763314) (xy 169.336212 -105.757218) (xy 169.357157 -105.739594)
			(xy 169.403123 -105.709872) (xy 169.452866 -105.68703) (xy 169.505366 -105.671536) (xy 169.559541 -105.66371)
			(xy 169.58691 -105.663238) (xy 169.587164 -105.663238) (xy 169.614142 -105.663664) (xy 169.667563 -105.671254)
			(xy 169.719379 -105.6863) (xy 169.768555 -105.708503) (xy 169.81411 -105.737419) (xy 169.855132 -105.772469)
			(xy 169.890801 -105.812954) (xy 169.920405 -105.858064) (xy 169.943352 -105.906898) (xy 169.959184 -105.958479)
			(xy 169.963846 -105.985056) (xy 169.963846 -105.98531) (xy 169.966053 -105.995571) (xy 169.977469 -106.013155)
			(xy 169.985944 -106.019346) (xy 170.057318 -106.066844) (xy 170.077892 -106.0704) (xy 170.088306 -106.06786)
			(xy 170.115065 -106.061716) (xy 170.169567 -106.05509) (xy 170.197018 -106.054652) (xy 170.224342 -106.055111)
			(xy 170.27859 -106.06173) (xy 170.305222 -106.06786) (xy 170.305476 -106.06786) (xy 170.315704 -106.069739)
			(xy 170.336154 -106.066053) (xy 170.3451 -106.060748) (xy 170.416728 -106.01325) (xy 170.427904 -105.995724)
			(xy 170.429682 -105.985056) (xy 170.43431 -105.958478) (xy 170.450171 -105.906911) (xy 170.473139 -105.858094)
			(xy 170.502755 -105.813) (xy 170.538431 -105.772528) (xy 170.579452 -105.737487) (xy 170.625002 -105.708575)
			(xy 170.67417 -105.68637) (xy 170.725977 -105.671314) (xy 170.779389 -105.663707) (xy 170.806364 -105.663238)
			(xy 170.833622 -105.663607) (xy 170.887583 -105.67136) (xy 170.939892 -105.686715) (xy 170.989482 -105.709358)
			(xy 171.035346 -105.738829) (xy 171.076548 -105.774527) (xy 171.11225 -105.815725) (xy 171.141724 -105.861586)
			(xy 171.164372 -105.911174) (xy 171.179732 -105.963482) (xy 171.187491 -106.017442) (xy 171.187491 -106.071958)
			(xy 171.179732 -106.125918) (xy 171.164372 -106.178226) (xy 171.141724 -106.227814) (xy 171.11225 -106.273675)
			(xy 171.076548 -106.314873) (xy 171.035346 -106.350571) (xy 170.989482 -106.380042) (xy 170.939892 -106.402685)
			(xy 170.887583 -106.41804) (xy 170.833622 -106.425793) (xy 170.806364 -106.426254) (xy 170.805856 -106.426254)
			(xy 170.788935 -106.426032) (xy 170.755231 -106.42298) (xy 170.738546 -106.420158) (xy 170.727255 -106.418782)
			(xy 170.705364 -106.424862) (xy 170.696382 -106.431842) (xy 170.671998 -106.45267) (xy 170.663559 -106.460639)
			(xy 170.654436 -106.481956) (xy 170.654472 -106.493564) (xy 170.65498 -106.512614) (xy 170.65498 -107.11842)
			(xy 182.937652 -107.11842) (xy 182.937652 -107.03152) (xy 182.94567 -106.944991) (xy 182.961638 -106.859571)
			(xy 182.985419 -106.775989) (xy 183.016811 -106.694957) (xy 183.055545 -106.617168) (xy 183.101292 -106.543284)
			(xy 183.153661 -106.473937) (xy 183.212205 -106.409717) (xy 183.276425 -106.351173) (xy 183.345772 -106.298804)
			(xy 183.419656 -106.253057) (xy 183.497445 -106.214323) (xy 183.578477 -106.182931) (xy 183.662059 -106.15915)
			(xy 183.747479 -106.143182) (xy 183.834008 -106.135164) (xy 183.920908 -106.135164) (xy 184.007437 -106.143182)
			(xy 184.092857 -106.15915) (xy 184.176439 -106.182931) (xy 184.257471 -106.214323) (xy 184.33526 -106.253057)
			(xy 184.409144 -106.298804) (xy 184.478491 -106.351173) (xy 184.542711 -106.409717) (xy 184.601255 -106.473937)
			(xy 184.653624 -106.543284) (xy 184.699371 -106.617168) (xy 184.738105 -106.694957) (xy 184.769497 -106.775989)
			(xy 184.793278 -106.859571) (xy 184.809246 -106.944991) (xy 184.817264 -107.03152) (xy 184.817766 -107.07497)
			(xy 184.817264 -107.11842) (xy 184.817262 -107.118439) (xy 185.190618 -107.118439) (xy 185.190618 -107.031561)
			(xy 185.198634 -106.945053) (xy 185.214597 -106.859655) (xy 185.238372 -106.776093) (xy 185.269756 -106.695081)
			(xy 185.30848 -106.617311) (xy 185.354215 -106.543446) (xy 185.406571 -106.474115) (xy 185.4651 -106.409911)
			(xy 185.529303 -106.351381) (xy 185.598632 -106.299025) (xy 185.672497 -106.253288) (xy 185.750267 -106.214562)
			(xy 185.831278 -106.183177) (xy 185.914839 -106.159401) (xy 186.000238 -106.143436) (xy 186.086745 -106.135418)
			(xy 186.130184 -106.134916) (xy 187.984384 -106.134916) (xy 188.027822 -106.135462) (xy 188.114327 -106.143476)
			(xy 188.199724 -106.159438) (xy 188.283284 -106.183212) (xy 188.364293 -106.214594) (xy 188.442062 -106.253317)
			(xy 188.515926 -106.29905) (xy 188.585255 -106.351404) (xy 188.649457 -106.409931) (xy 188.707986 -106.474133)
			(xy 188.76034 -106.543461) (xy 188.806075 -106.617324) (xy 188.844799 -106.695092) (xy 188.876183 -106.776101)
			(xy 188.899958 -106.85966) (xy 188.915921 -106.945057) (xy 188.923937 -107.031562) (xy 188.923937 -107.11842)
			(xy 190.307462 -107.11842) (xy 190.307462 -107.03152) (xy 190.31548 -106.944991) (xy 190.331448 -106.859571)
			(xy 190.355229 -106.775989) (xy 190.386621 -106.694957) (xy 190.425355 -106.617168) (xy 190.471102 -106.543284)
			(xy 190.523471 -106.473937) (xy 190.582015 -106.409717) (xy 190.646235 -106.351173) (xy 190.715582 -106.298804)
			(xy 190.789466 -106.253057) (xy 190.867255 -106.214323) (xy 190.948287 -106.182931) (xy 191.031869 -106.15915)
			(xy 191.117289 -106.143182) (xy 191.203818 -106.135164) (xy 191.290718 -106.135164) (xy 191.377247 -106.143182)
			(xy 191.462667 -106.15915) (xy 191.546249 -106.182931) (xy 191.627281 -106.214323) (xy 191.70507 -106.253057)
			(xy 191.778954 -106.298804) (xy 191.848301 -106.351173) (xy 191.912521 -106.409717) (xy 191.971065 -106.473937)
			(xy 192.023434 -106.543284) (xy 192.069181 -106.617168) (xy 192.107915 -106.694957) (xy 192.139307 -106.775989)
			(xy 192.163088 -106.859571) (xy 192.177001 -106.934) (xy 198.903336 -106.934) (xy 198.903793 -106.906629)
			(xy 198.911612 -106.85245) (xy 198.927103 -106.799946) (xy 198.949946 -106.750199) (xy 198.979673 -106.704233)
			(xy 198.997316 -106.683302) (xy 198.99757 -106.683048) (xy 199.003151 -106.675958) (xy 199.009399 -106.659044)
			(xy 199.009762 -106.650028) (xy 199.009762 -106.582972) (xy 199.009427 -106.573953) (xy 199.003165 -106.557035)
			(xy 198.99757 -106.549952) (xy 198.997316 -106.549952) (xy 198.997316 -106.549698) (xy 198.979676 -106.528765)
			(xy 198.949952 -106.482797) (xy 198.927107 -106.433051) (xy 198.911611 -106.380549) (xy 198.903783 -106.32637)
			(xy 198.903783 -106.27163) (xy 198.911611 -106.217451) (xy 198.927107 -106.164949) (xy 198.949952 -106.115203)
			(xy 198.979676 -106.069235) (xy 198.997316 -106.048302) (xy 198.99757 -106.048048) (xy 199.003151 -106.040958)
			(xy 199.009399 -106.024044) (xy 199.009762 -106.015028) (xy 199.009762 -105.947972) (xy 199.009427 -105.938953)
			(xy 199.003165 -105.922035) (xy 198.99757 -105.914952) (xy 198.997316 -105.914952) (xy 198.997316 -105.914698)
			(xy 198.979676 -105.893765) (xy 198.949952 -105.847797) (xy 198.927107 -105.798051) (xy 198.911611 -105.745549)
			(xy 198.903783 -105.69137) (xy 198.903783 -105.63663) (xy 198.911611 -105.582451) (xy 198.927107 -105.529949)
			(xy 198.949952 -105.480203) (xy 198.979676 -105.434235) (xy 198.997316 -105.413302) (xy 198.99757 -105.413048)
			(xy 199.003151 -105.405958) (xy 199.009399 -105.389044) (xy 199.009762 -105.380028) (xy 199.009762 -105.312972)
			(xy 199.009427 -105.303953) (xy 199.003165 -105.287035) (xy 198.99757 -105.279952) (xy 198.997316 -105.279952)
			(xy 198.997316 -105.279698) (xy 198.979665 -105.258775) (xy 198.949954 -105.2128) (xy 198.92712 -105.16305)
			(xy 198.911632 -105.110548) (xy 198.903808 -105.05637) (xy 198.903336 -105.029) (xy 198.903822 -105.001749)
			(xy 198.911578 -104.947801) (xy 198.926933 -104.895506) (xy 198.949575 -104.845929) (xy 198.979041 -104.800079)
			(xy 199.014732 -104.758888) (xy 199.055923 -104.723197) (xy 199.101773 -104.693731) (xy 199.15135 -104.671089)
			(xy 199.203645 -104.655734) (xy 199.257593 -104.647978) (xy 199.312095 -104.647978) (xy 199.366043 -104.655734)
			(xy 199.418338 -104.671089) (xy 199.467915 -104.693731) (xy 199.513765 -104.723197) (xy 199.554956 -104.758888)
			(xy 199.590647 -104.800079) (xy 199.620113 -104.845929) (xy 199.642755 -104.895506) (xy 199.65811 -104.947801)
			(xy 199.665866 -105.001749) (xy 199.666352 -105.029) (xy 199.665898 -105.056371) (xy 199.658079 -105.110551)
			(xy 199.652913 -105.12806) (xy 217.654632 -105.12806) (xy 217.655118 -105.100809) (xy 217.662874 -105.046861)
			(xy 217.678229 -104.994566) (xy 217.700871 -104.944989) (xy 217.730337 -104.899139) (xy 217.766028 -104.857948)
			(xy 217.807219 -104.822257) (xy 217.853069 -104.792791) (xy 217.902646 -104.770149) (xy 217.954941 -104.754794)
			(xy 218.008889 -104.747038) (xy 218.063391 -104.747038) (xy 218.117339 -104.754794) (xy 218.169634 -104.770149)
			(xy 218.219211 -104.792791) (xy 218.265061 -104.822257) (xy 218.306252 -104.857948) (xy 218.341943 -104.899139)
			(xy 218.371409 -104.944989) (xy 218.394051 -104.994566) (xy 218.409406 -105.046861) (xy 218.417162 -105.100809)
			(xy 218.417648 -105.12806) (xy 218.417163 -105.155052) (xy 218.409562 -105.208499) (xy 218.394508 -105.260343)
			(xy 218.372299 -105.309548) (xy 218.34338 -105.355133) (xy 218.326208 -105.375964) (xy 218.319096 -105.384092)
			(xy 218.313 -105.404666) (xy 218.323922 -105.49001) (xy 218.32568 -105.500559) (xy 218.336746 -105.51884)
			(xy 218.337029 -105.519055) (xy 222.355843 -105.519055) (xy 222.355843 -105.464545) (xy 222.363601 -105.410591)
			(xy 222.378958 -105.35829) (xy 222.401603 -105.308707) (xy 222.431073 -105.262852) (xy 222.46677 -105.221657)
			(xy 222.507966 -105.185962) (xy 222.553823 -105.156494) (xy 222.603407 -105.133852) (xy 222.655709 -105.118497)
			(xy 222.709663 -105.110742) (xy 222.736918 -105.11028) (xy 222.76429 -105.110716) (xy 222.818471 -105.118538)
			(xy 222.870975 -105.134033) (xy 222.920721 -105.156882) (xy 222.966686 -105.186615) (xy 222.987616 -105.20426)
			(xy 222.98787 -105.204514) (xy 222.99496 -105.210096) (xy 223.011874 -105.216345) (xy 223.02089 -105.216706)
			(xy 223.087946 -105.216706) (xy 223.09696 -105.216322) (xy 223.113877 -105.210093) (xy 223.120966 -105.204514)
			(xy 223.120966 -105.20426) (xy 223.12122 -105.20426) (xy 223.142166 -105.186638) (xy 223.188136 -105.156925)
			(xy 223.23788 -105.134086) (xy 223.290377 -105.118591) (xy 223.34455 -105.110757) (xy 223.371918 -105.11028)
			(xy 223.399168 -105.110791) (xy 223.453112 -105.11855) (xy 223.505402 -105.133906) (xy 223.554976 -105.156547)
			(xy 223.600822 -105.186013) (xy 223.642009 -105.221704) (xy 223.677698 -105.262892) (xy 223.707161 -105.30874)
			(xy 223.7298 -105.358314) (xy 223.745154 -105.410606) (xy 223.75291 -105.46455) (xy 223.75291 -105.510953)
			(xy 225.112538 -105.510953) (xy 225.112538 -105.456447) (xy 225.120295 -105.402495) (xy 225.13565 -105.350197)
			(xy 225.158292 -105.300615) (xy 225.18776 -105.254761) (xy 225.223453 -105.213567) (xy 225.264645 -105.177872)
			(xy 225.310498 -105.148402) (xy 225.360078 -105.125757) (xy 225.412376 -105.110399) (xy 225.466327 -105.102639)
			(xy 225.49358 -105.102152) (xy 225.52095 -105.102617) (xy 225.57513 -105.110433) (xy 225.627634 -105.125922)
			(xy 225.677381 -105.148764) (xy 225.723347 -105.17849) (xy 225.744278 -105.196132) (xy 225.744532 -105.196386)
			(xy 225.751635 -105.201949) (xy 225.768539 -105.20821) (xy 225.777552 -105.208578) (xy 225.844608 -105.208578)
			(xy 225.853626 -105.20823) (xy 225.870543 -105.201977) (xy 225.877628 -105.196386) (xy 225.877628 -105.196132)
			(xy 225.877882 -105.196132) (xy 225.898814 -105.178493) (xy 225.944786 -105.14878) (xy 225.994534 -105.125943)
			(xy 226.047035 -105.110453) (xy 226.101211 -105.102625) (xy 226.12858 -105.102152) (xy 226.155831 -105.102694)
			(xy 226.209778 -105.110448) (xy 226.262073 -105.1258) (xy 226.311651 -105.148439) (xy 226.357501 -105.177904)
			(xy 226.398692 -105.213594) (xy 226.434384 -105.254783) (xy 226.463851 -105.300632) (xy 226.486493 -105.350208)
			(xy 226.501848 -105.402502) (xy 226.509605 -105.456449) (xy 226.509605 -105.510951) (xy 226.501848 -105.564898)
			(xy 226.486493 -105.617192) (xy 226.463851 -105.666768) (xy 226.434384 -105.712617) (xy 226.398692 -105.753806)
			(xy 226.357501 -105.789496) (xy 226.311651 -105.818961) (xy 226.262073 -105.8416) (xy 226.209778 -105.856952)
			(xy 226.155831 -105.864706) (xy 226.12858 -105.865168) (xy 226.101209 -105.864721) (xy 226.047029 -105.8569)
			(xy 225.994525 -105.841407) (xy 225.944779 -105.818561) (xy 225.898813 -105.788831) (xy 225.877882 -105.771188)
			(xy 225.877628 -105.770934) (xy 225.870543 -105.765345) (xy 225.853625 -105.759102) (xy 225.844608 -105.758742)
			(xy 225.777552 -105.758742) (xy 225.768537 -105.759115) (xy 225.751619 -105.76535) (xy 225.744532 -105.770934)
			(xy 225.744532 -105.771188) (xy 225.744278 -105.771188) (xy 225.723326 -105.788802) (xy 225.677359 -105.818518)
			(xy 225.627616 -105.841359) (xy 225.57512 -105.856856) (xy 225.520948 -105.864691) (xy 225.49358 -105.865168)
			(xy 225.466327 -105.864761) (xy 225.412376 -105.857001) (xy 225.360078 -105.841643) (xy 225.310498 -105.818998)
			(xy 225.264645 -105.789528) (xy 225.223453 -105.753833) (xy 225.18776 -105.712639) (xy 225.158292 -105.666785)
			(xy 225.13565 -105.617203) (xy 225.120295 -105.564905) (xy 225.112538 -105.510953) (xy 223.75291 -105.510953)
			(xy 223.75291 -105.51905) (xy 223.745154 -105.572994) (xy 223.7298 -105.625286) (xy 223.707161 -105.67486)
			(xy 223.677698 -105.720708) (xy 223.642009 -105.761896) (xy 223.600822 -105.797587) (xy 223.554976 -105.827053)
			(xy 223.505402 -105.849694) (xy 223.453112 -105.86505) (xy 223.399168 -105.872809) (xy 223.371918 -105.873296)
			(xy 223.344548 -105.87282) (xy 223.290369 -105.865005) (xy 223.237866 -105.849518) (xy 223.188119 -105.826679)
			(xy 223.142152 -105.796956) (xy 223.12122 -105.779316) (xy 223.120966 -105.779062) (xy 223.113868 -105.773493)
			(xy 223.09696 -105.767237) (xy 223.087946 -105.76687) (xy 223.02089 -105.76687) (xy 223.011873 -105.767229)
			(xy 222.994957 -105.773476) (xy 222.98787 -105.779062) (xy 222.98787 -105.779316) (xy 222.987616 -105.779316)
			(xy 222.966691 -105.796964) (xy 222.920716 -105.826674) (xy 222.870967 -105.849508) (xy 222.818464 -105.864997)
			(xy 222.764288 -105.872823) (xy 222.736918 -105.873296) (xy 222.709663 -105.872858) (xy 222.655709 -105.865103)
			(xy 222.603407 -105.849748) (xy 222.553823 -105.827106) (xy 222.507966 -105.797638) (xy 222.46677 -105.761943)
			(xy 222.431073 -105.720748) (xy 222.401603 -105.674893) (xy 222.378958 -105.62531) (xy 222.363601 -105.573009)
			(xy 222.355843 -105.519055) (xy 218.337029 -105.519055) (xy 218.345258 -105.525316) (xy 218.369563 -105.542923)
			(xy 218.41282 -105.584522) (xy 218.431364 -105.60812) (xy 218.437206 -105.615994) (xy 218.454732 -105.626408)
			(xy 218.545156 -105.639616) (xy 218.56446 -105.63479) (xy 218.572334 -105.628948) (xy 218.572588 -105.628948)
			(xy 218.597318 -105.611424) (xy 218.651176 -105.583625) (xy 218.708752 -105.564695) (xy 218.768598 -105.555109)
			(xy 218.798902 -105.554526) (xy 218.826156 -105.554954) (xy 218.88011 -105.562712) (xy 218.932411 -105.57807)
			(xy 218.981993 -105.600715) (xy 219.027848 -105.630186) (xy 219.069042 -105.665884) (xy 219.104735 -105.707081)
			(xy 219.134202 -105.752938) (xy 219.156843 -105.802523) (xy 219.172196 -105.854825) (xy 219.179949 -105.90878)
			(xy 219.18041 -105.936034) (xy 219.179985 -105.962068) (xy 219.172893 -106.013652) (xy 219.158859 -106.063794)
			(xy 219.151679 -106.080351) (xy 219.615483 -106.080351) (xy 219.615483 -106.025849) (xy 219.62324 -105.971901)
			(xy 219.638596 -105.919606) (xy 219.661237 -105.870028) (xy 219.690704 -105.824178) (xy 219.726397 -105.782988)
			(xy 219.767588 -105.747297) (xy 219.813439 -105.717831) (xy 219.863017 -105.695191) (xy 219.915312 -105.679837)
			(xy 219.969261 -105.672082) (xy 219.996512 -105.67162) (xy 220.022854 -105.672053) (xy 220.075035 -105.67931)
			(xy 220.125723 -105.69367) (xy 220.173956 -105.714862) (xy 220.218819 -105.742483) (xy 220.259459 -105.776008)
			(xy 220.295105 -105.814801) (xy 220.310456 -105.836212) (xy 220.319216 -105.847982) (xy 220.342029 -105.866408)
			(xy 220.369139 -105.877587) (xy 220.398308 -105.880599) (xy 220.42713 -105.875195) (xy 220.453227 -105.86182)
			(xy 220.474445 -105.841578) (xy 220.48216 -105.8291) (xy 220.496878 -105.804579) (xy 220.532477 -105.759821)
			(xy 220.574356 -105.720878) (xy 220.621579 -105.688621) (xy 220.673087 -105.663773) (xy 220.727727 -105.64689)
			(xy 220.784274 -105.63835) (xy 220.812868 -105.637838) (xy 220.840126 -105.638207) (xy 220.894087 -105.645961)
			(xy 220.946395 -105.661316) (xy 220.995985 -105.68396) (xy 221.041848 -105.71343) (xy 221.083049 -105.749128)
			(xy 221.118751 -105.790327) (xy 221.148225 -105.836187) (xy 221.170873 -105.885775) (xy 221.186232 -105.938082)
			(xy 221.193991 -105.992042) (xy 221.193991 -106.046558) (xy 221.186232 -106.100518) (xy 221.170873 -106.152825)
			(xy 221.148225 -106.202413) (xy 221.118751 -106.248273) (xy 221.083049 -106.289472) (xy 221.041848 -106.32517)
			(xy 220.995985 -106.35464) (xy 220.946395 -106.377284) (xy 220.894087 -106.392639) (xy 220.840126 -106.400393)
			(xy 220.812868 -106.400854) (xy 220.786528 -106.400372) (xy 220.734349 -106.393125) (xy 220.683661 -106.378774)
			(xy 220.635427 -106.35759) (xy 220.590564 -106.329977) (xy 220.549923 -106.296458) (xy 220.514276 -106.25767)
			(xy 220.498924 -106.236262) (xy 220.490198 -106.224461) (xy 220.467381 -106.206021) (xy 220.440262 -106.194833)
			(xy 220.41108 -106.191821) (xy 220.382247 -106.197234) (xy 220.356145 -106.210624) (xy 220.33493 -106.230886)
			(xy 220.32722 -106.243374) (xy 220.312507 -106.267898) (xy 220.276908 -106.312657) (xy 220.235028 -106.351601)
			(xy 220.187804 -106.383858) (xy 220.136295 -106.408706) (xy 220.081655 -106.425588) (xy 220.025107 -106.434125)
			(xy 219.996512 -106.434636) (xy 219.969261 -106.434118) (xy 219.915312 -106.426363) (xy 219.863017 -106.411009)
			(xy 219.813439 -106.388369) (xy 219.767588 -106.358903) (xy 219.726397 -106.323212) (xy 219.690704 -106.282022)
			(xy 219.661237 -106.236172) (xy 219.638596 -106.186594) (xy 219.62324 -106.134299) (xy 219.615483 -106.080351)
			(xy 219.151679 -106.080351) (xy 219.138143 -106.111565) (xy 219.111129 -106.156079) (xy 219.095066 -106.176572)
			(xy 219.089322 -106.184327) (xy 219.083584 -106.202739) (xy 219.08389 -106.212386) (xy 219.09024 -106.292142)
			(xy 219.098876 -106.309922) (xy 219.106242 -106.316272) (xy 219.125887 -106.334454) (xy 219.160411 -106.37536)
			(xy 219.188882 -106.420688) (xy 219.21074 -106.46955) (xy 219.225557 -106.520986) (xy 219.233042 -106.573988)
			(xy 219.233496 -106.600752) (xy 219.233 -106.628004) (xy 219.225249 -106.681955) (xy 219.209899 -106.734253)
			(xy 219.187261 -106.783833) (xy 219.157797 -106.829687) (xy 219.122106 -106.870881) (xy 219.080916 -106.906575)
			(xy 219.035065 -106.936044) (xy 218.985486 -106.958686) (xy 218.93319 -106.974042) (xy 218.87924 -106.981797)
			(xy 218.851988 -106.98226) (xy 218.823214 -106.981747) (xy 218.76632 -106.973091) (xy 218.71137 -106.955991)
			(xy 218.65961 -106.930835) (xy 218.612213 -106.898194) (xy 218.590876 -106.878882) (xy 218.583002 -106.871516)
			(xy 218.56319 -106.864404) (xy 218.466924 -106.87177) (xy 218.448128 -106.881676) (xy 218.441524 -106.890058)
			(xy 218.42332 -106.91226) (xy 218.381381 -106.95147) (xy 218.334041 -106.983954) (xy 218.282369 -107.00898)
			(xy 218.227531 -107.025982) (xy 218.170765 -107.034577) (xy 218.142058 -107.035092) (xy 218.114805 -107.034661)
			(xy 218.060854 -107.026899) (xy 218.008558 -107.011537) (xy 217.958979 -106.98889) (xy 217.913128 -106.959418)
			(xy 217.871938 -106.923721) (xy 217.836247 -106.882525) (xy 217.806782 -106.83667) (xy 217.784142 -106.787088)
			(xy 217.768789 -106.734789) (xy 217.761035 -106.680837) (xy 217.76055 -106.653584) (xy 217.761021 -106.626682)
			(xy 217.768594 -106.573413) (xy 217.783573 -106.521736) (xy 217.805662 -106.472675) (xy 217.834423 -106.427203)
			(xy 217.869285 -106.386221) (xy 217.909558 -106.350541) (xy 217.931746 -106.335322) (xy 217.942668 -106.32821)
			(xy 217.954606 -106.30535) (xy 217.952574 -106.193082) (xy 217.93962 -106.17073) (xy 217.928444 -106.163872)
			(xy 217.904851 -106.148937) (xy 217.861897 -106.113262) (xy 217.824601 -106.071707) (xy 217.793762 -106.02516)
			(xy 217.770037 -105.974614) (xy 217.753934 -105.921149) (xy 217.745796 -105.865908) (xy 217.74531 -105.83799)
			(xy 217.745776 -105.810997) (xy 217.753383 -105.75755) (xy 217.768442 -105.705707) (xy 217.790655 -105.656502)
			(xy 217.819577 -105.610917) (xy 217.83675 -105.590086) (xy 217.843862 -105.581958) (xy 217.849958 -105.561384)
			(xy 217.839036 -105.47604) (xy 217.837233 -105.465503) (xy 217.826198 -105.447218) (xy 217.8177 -105.440734)
			(xy 217.79648 -105.425367) (xy 217.758029 -105.38978) (xy 217.724811 -105.349265) (xy 217.697452 -105.304585)
			(xy 217.676467 -105.256579) (xy 217.66225 -105.206153) (xy 217.65507 -105.154256) (xy 217.654632 -105.12806)
			(xy 199.652913 -105.12806) (xy 199.642588 -105.163055) (xy 199.619743 -105.212801) (xy 199.590015 -105.258767)
			(xy 199.572372 -105.279698) (xy 199.572118 -105.279952) (xy 199.566548 -105.28705) (xy 199.560291 -105.303958)
			(xy 199.559926 -105.312972) (xy 199.559926 -105.380028) (xy 199.560264 -105.389047) (xy 199.566524 -105.405964)
			(xy 199.572118 -105.413048) (xy 199.572372 -105.413048) (xy 199.572372 -105.413302) (xy 199.590013 -105.434235)
			(xy 199.619738 -105.480202) (xy 199.642583 -105.529949) (xy 199.658079 -105.582451) (xy 199.665908 -105.636629)
			(xy 199.665908 -105.691371) (xy 199.658079 -105.745549) (xy 199.642583 -105.798051) (xy 199.619738 -105.847798)
			(xy 199.590013 -105.893765) (xy 199.572372 -105.914698) (xy 199.572118 -105.914952) (xy 199.566548 -105.92205)
			(xy 199.560291 -105.938958) (xy 199.559926 -105.947972) (xy 199.559926 -106.015028) (xy 199.560264 -106.024047)
			(xy 199.566524 -106.040964) (xy 199.572118 -106.048048) (xy 199.572372 -106.048048) (xy 199.572372 -106.048302)
			(xy 199.590013 -106.069235) (xy 199.619738 -106.115202) (xy 199.642583 -106.164949) (xy 199.658079 -106.217451)
			(xy 199.665908 -106.271629) (xy 199.665908 -106.326371) (xy 199.658079 -106.380549) (xy 199.642583 -106.433051)
			(xy 199.619738 -106.482798) (xy 199.590013 -106.528765) (xy 199.572372 -106.549698) (xy 199.572118 -106.549952)
			(xy 199.566548 -106.55705) (xy 199.560291 -106.573958) (xy 199.559926 -106.582972) (xy 199.559926 -106.650028)
			(xy 199.560264 -106.659047) (xy 199.566524 -106.675964) (xy 199.572118 -106.683048) (xy 199.572372 -106.683048)
			(xy 199.572372 -106.683302) (xy 199.590021 -106.704226) (xy 199.619732 -106.750201) (xy 199.642567 -106.79995)
			(xy 199.658055 -106.852453) (xy 199.66588 -106.90663) (xy 199.666352 -106.934) (xy 199.665866 -106.961251)
			(xy 199.65811 -107.015199) (xy 199.642755 -107.067494) (xy 199.620113 -107.117071) (xy 199.590647 -107.162921)
			(xy 199.554956 -107.204112) (xy 199.513765 -107.239803) (xy 199.467915 -107.269269) (xy 199.418338 -107.291911)
			(xy 199.366043 -107.307266) (xy 199.312095 -107.315022) (xy 199.257593 -107.315022) (xy 199.203645 -107.307266)
			(xy 199.15135 -107.291911) (xy 199.101773 -107.269269) (xy 199.055923 -107.239803) (xy 199.014732 -107.204112)
			(xy 198.979041 -107.162921) (xy 198.949575 -107.117071) (xy 198.926933 -107.067494) (xy 198.911578 -107.015199)
			(xy 198.903822 -106.961251) (xy 198.903336 -106.934) (xy 192.177001 -106.934) (xy 192.179056 -106.944991)
			(xy 192.187074 -107.03152) (xy 192.187576 -107.07497) (xy 192.187074 -107.11842) (xy 192.179056 -107.204949)
			(xy 192.163088 -107.290369) (xy 192.139307 -107.373951) (xy 192.124753 -107.41152) (xy 221.678754 -107.41152)
			(xy 221.679217 -107.385206) (xy 221.686451 -107.333076) (xy 221.700769 -107.282433) (xy 221.721902 -107.234233)
			(xy 221.74945 -107.18939) (xy 221.782891 -107.148752) (xy 221.801944 -107.130596) (xy 221.809341 -107.12307)
			(xy 221.81787 -107.103794) (xy 221.818454 -107.093258) (xy 221.818454 -107.018582) (xy 221.817907 -107.008034)
			(xy 221.809386 -106.988738) (xy 221.801944 -106.981244) (xy 221.782858 -106.96312) (xy 221.749405 -106.922482)
			(xy 221.721852 -106.877635) (xy 221.700719 -106.829428) (xy 221.686408 -106.778776) (xy 221.679189 -106.726638)
			(xy 221.678754 -106.70032) (xy 221.679297 -106.673071) (xy 221.68705 -106.619127) (xy 221.7024 -106.566836)
			(xy 221.725036 -106.517261) (xy 221.754497 -106.471413) (xy 221.790182 -106.430223) (xy 221.831366 -106.394532)
			(xy 221.877211 -106.365064) (xy 221.926782 -106.34242) (xy 221.979071 -106.327062) (xy 222.033013 -106.319301)
			(xy 222.060262 -106.318812) (xy 222.087926 -106.319348) (xy 222.142675 -106.327343) (xy 222.195696 -106.343155)
			(xy 222.24588 -106.366454) (xy 222.292176 -106.396751) (xy 222.333615 -106.433413) (xy 222.369328 -106.475672)
			(xy 222.384366 -106.498898) (xy 222.391031 -106.508552) (xy 222.410871 -106.52101) (xy 222.422466 -106.522774)
			(xy 222.502476 -106.530648) (xy 222.514114 -106.531258) (xy 222.53595 -106.523193) (xy 222.544386 -106.515154)
			(xy 222.54464 -106.5149) (xy 222.562719 -106.496317) (xy 222.603052 -106.463739) (xy 222.647426 -106.436926)
			(xy 222.695025 -106.416374) (xy 222.74497 -106.402461) (xy 222.796339 -106.395444) (xy 222.822262 -106.395012)
			(xy 222.849515 -106.395491) (xy 222.903466 -106.403243) (xy 222.955765 -106.418595) (xy 223.005346 -106.441235)
			(xy 223.051201 -106.470701) (xy 223.092394 -106.506393) (xy 223.128089 -106.547585) (xy 223.157557 -106.593438)
			(xy 223.180198 -106.643018) (xy 223.195553 -106.695316) (xy 223.203308 -106.749267) (xy 223.20377 -106.77652)
			(xy 223.203323 -106.803891) (xy 223.195502 -106.858071) (xy 223.180009 -106.910575) (xy 223.157162 -106.960321)
			(xy 223.127433 -107.006287) (xy 223.10979 -107.027218) (xy 223.109536 -107.027472) (xy 223.103947 -107.034557)
			(xy 223.097704 -107.051475) (xy 223.097344 -107.060492) (xy 223.097344 -107.127548) (xy 223.097716 -107.136564)
			(xy 223.103952 -107.153481) (xy 223.109536 -107.160568) (xy 223.10979 -107.160568) (xy 223.10979 -107.160822)
			(xy 223.127404 -107.181774) (xy 223.15712 -107.227741) (xy 223.179961 -107.277484) (xy 223.195458 -107.32998)
			(xy 223.203293 -107.384152) (xy 223.20377 -107.41152) (xy 223.203364 -107.438775) (xy 223.195603 -107.49273)
			(xy 223.192225 -107.50423) (xy 226.110038 -107.50423) (xy 226.110447 -107.477914) (xy 226.117692 -107.425782)
			(xy 226.132022 -107.375138) (xy 226.153165 -107.326939) (xy 226.180722 -107.282097) (xy 226.214171 -107.24146)
			(xy 226.233228 -107.223306) (xy 226.240618 -107.215775) (xy 226.249152 -107.196502) (xy 226.249738 -107.185968)
			(xy 226.249738 -107.111292) (xy 226.249215 -107.100742) (xy 226.240674 -107.081447) (xy 226.233228 -107.073954)
			(xy 226.214162 -107.055808) (xy 226.180705 -107.015177) (xy 226.153147 -106.970335) (xy 226.13201 -106.922132)
			(xy 226.117695 -106.871483) (xy 226.110474 -106.819347) (xy 226.110038 -106.79303) (xy 226.110524 -106.765779)
			(xy 226.11828 -106.711831) (xy 226.133635 -106.659536) (xy 226.156277 -106.609959) (xy 226.185743 -106.564109)
			(xy 226.221434 -106.522918) (xy 226.262625 -106.487227) (xy 226.308475 -106.457761) (xy 226.358052 -106.435119)
			(xy 226.410347 -106.419764) (xy 226.464295 -106.412008) (xy 226.518797 -106.412008) (xy 226.572745 -106.419764)
			(xy 226.62504 -106.435119) (xy 226.655327 -106.448951) (xy 226.90936 -106.448951) (xy 226.90936 -106.394449)
			(xy 226.917116 -106.3405) (xy 226.932471 -106.288205) (xy 226.955111 -106.238627) (xy 226.984577 -106.192776)
			(xy 227.020267 -106.151584) (xy 227.061456 -106.115891) (xy 227.107306 -106.086423) (xy 227.156883 -106.063779)
			(xy 227.209177 -106.048421) (xy 227.263125 -106.040661) (xy 227.290376 -106.040174) (xy 227.317747 -106.040636)
			(xy 227.371927 -106.048452) (xy 227.42443 -106.063941) (xy 227.474177 -106.086784) (xy 227.520143 -106.116511)
			(xy 227.541074 -106.134154) (xy 227.541328 -106.134408) (xy 227.54843 -106.139971) (xy 227.565335 -106.146232)
			(xy 227.574348 -106.1466) (xy 227.641404 -106.1466) (xy 227.650421 -106.146245) (xy 227.667338 -106.139996)
			(xy 227.674424 -106.134408) (xy 227.674424 -106.134154) (xy 227.674678 -106.134154) (xy 227.695614 -106.11652)
			(xy 227.741585 -106.086806) (xy 227.791332 -106.063968) (xy 227.843832 -106.048476) (xy 227.898007 -106.040648)
			(xy 227.925376 -106.040174) (xy 227.952629 -106.040672) (xy 228.00658 -106.048425) (xy 228.058878 -106.063779)
			(xy 228.108459 -106.086419) (xy 228.154313 -106.115885) (xy 228.195506 -106.151577) (xy 228.213644 -106.172508)
			(xy 228.769418 -106.172508) (xy 228.769884 -106.145138) (xy 228.777701 -106.090958) (xy 228.79319 -106.038455)
			(xy 228.816032 -105.988708) (xy 228.845757 -105.942742) (xy 228.863398 -105.92181) (xy 228.863652 -105.921556)
			(xy 228.869227 -105.914462) (xy 228.87548 -105.897551) (xy 228.875844 -105.888536) (xy 228.875844 -105.82148)
			(xy 228.875508 -105.812461) (xy 228.869247 -105.795543) (xy 228.863652 -105.78846) (xy 228.863398 -105.78846)
			(xy 228.863398 -105.788206) (xy 228.845766 -105.767266) (xy 228.816043 -105.721299) (xy 228.793199 -105.671554)
			(xy 228.777704 -105.619053) (xy 228.769875 -105.564876) (xy 228.769874 -105.510136) (xy 228.777701 -105.455959)
			(xy 228.793195 -105.403458) (xy 228.816038 -105.353712) (xy 228.845759 -105.307743) (xy 228.863398 -105.28681)
			(xy 228.863652 -105.286556) (xy 228.869227 -105.279462) (xy 228.87548 -105.262551) (xy 228.875844 -105.253536)
			(xy 228.875844 -105.18648) (xy 228.875508 -105.177461) (xy 228.869247 -105.160543) (xy 228.863652 -105.15346)
			(xy 228.863398 -105.15346) (xy 228.863398 -105.153206) (xy 228.845748 -105.132283) (xy 228.816038 -105.086307)
			(xy 228.793204 -105.036558) (xy 228.777716 -104.984055) (xy 228.76989 -104.929878) (xy 228.769418 -104.902508)
			(xy 228.769904 -104.875257) (xy 228.77766 -104.821309) (xy 228.793015 -104.769014) (xy 228.815657 -104.719437)
			(xy 228.845123 -104.673587) (xy 228.880814 -104.632396) (xy 228.922005 -104.596705) (xy 228.967855 -104.567239)
			(xy 229.017432 -104.544597) (xy 229.069727 -104.529242) (xy 229.123675 -104.521486) (xy 229.178177 -104.521486)
			(xy 229.232125 -104.529242) (xy 229.28442 -104.544597) (xy 229.333997 -104.567239) (xy 229.379847 -104.596705)
			(xy 229.421038 -104.632396) (xy 229.456729 -104.673587) (xy 229.486195 -104.719437) (xy 229.508837 -104.769014)
			(xy 229.524192 -104.821309) (xy 229.531948 -104.875257) (xy 229.532434 -104.902508) (xy 229.531989 -104.929879)
			(xy 229.524168 -104.98406) (xy 229.508675 -105.036564) (xy 229.485829 -105.08631) (xy 229.456098 -105.132276)
			(xy 229.438454 -105.153206) (xy 229.4382 -105.15346) (xy 229.432624 -105.160554) (xy 229.426371 -105.177465)
			(xy 229.426008 -105.18648) (xy 229.426008 -105.253536) (xy 229.426346 -105.262555) (xy 229.432607 -105.279472)
			(xy 229.4382 -105.286556) (xy 229.438454 -105.286556) (xy 229.438454 -105.28681) (xy 229.456103 -105.307736)
			(xy 229.485829 -105.353704) (xy 229.508675 -105.403452) (xy 229.524172 -105.455955) (xy 229.532 -105.510135)
			(xy 229.531999 -105.564877) (xy 229.524169 -105.619057) (xy 229.508671 -105.67156) (xy 229.485823 -105.721306)
			(xy 229.456096 -105.767274) (xy 229.438454 -105.788206) (xy 229.4382 -105.78846) (xy 229.432624 -105.795554)
			(xy 229.426371 -105.812465) (xy 229.426008 -105.82148) (xy 229.426008 -105.888536) (xy 229.426346 -105.897555)
			(xy 229.432607 -105.914472) (xy 229.4382 -105.921556) (xy 229.438454 -105.921556) (xy 229.438454 -105.92181)
			(xy 229.456104 -105.942733) (xy 229.485816 -105.988708) (xy 229.50865 -106.038457) (xy 229.524139 -106.09096)
			(xy 229.531963 -106.145138) (xy 229.532434 -106.172508) (xy 231.8258 -106.172508) (xy 231.826271 -106.145138)
			(xy 231.834087 -106.090959) (xy 231.849575 -106.038456) (xy 231.872416 -105.988709) (xy 231.902139 -105.942742)
			(xy 231.91978 -105.92181) (xy 231.920034 -105.921556) (xy 231.925607 -105.91446) (xy 231.931861 -105.89755)
			(xy 231.932226 -105.888536) (xy 231.932226 -105.82148) (xy 231.931873 -105.812463) (xy 231.925622 -105.795546)
			(xy 231.920034 -105.78846) (xy 231.91978 -105.78846) (xy 231.91978 -105.788206) (xy 231.902149 -105.767266)
			(xy 231.872428 -105.721298) (xy 231.849585 -105.671553) (xy 231.83409 -105.619052) (xy 231.826261 -105.564876)
			(xy 231.826261 -105.510136) (xy 231.834087 -105.455959) (xy 231.84958 -105.403458) (xy 231.872422 -105.353712)
			(xy 231.902142 -105.307744) (xy 231.91978 -105.28681) (xy 231.920034 -105.286556) (xy 231.925607 -105.27946)
			(xy 231.931861 -105.26255) (xy 231.932226 -105.253536) (xy 231.932226 -105.18648) (xy 231.931873 -105.177463)
			(xy 231.925622 -105.160546) (xy 231.920034 -105.15346) (xy 231.91978 -105.15346) (xy 231.91978 -105.153206)
			(xy 231.902127 -105.132285) (xy 231.872418 -105.086309) (xy 231.849585 -105.036559) (xy 231.834097 -104.984055)
			(xy 231.826272 -104.929878) (xy 231.8258 -104.902508) (xy 231.826286 -104.875257) (xy 231.834042 -104.821309)
			(xy 231.849397 -104.769014) (xy 231.872039 -104.719437) (xy 231.901505 -104.673587) (xy 231.937196 -104.632396)
			(xy 231.978387 -104.596705) (xy 232.024237 -104.567239) (xy 232.073814 -104.544597) (xy 232.126109 -104.529242)
			(xy 232.180057 -104.521486) (xy 232.234559 -104.521486) (xy 232.288507 -104.529242) (xy 232.340802 -104.544597)
			(xy 232.353848 -104.550555) (xy 266.310541 -104.550555) (xy 266.310541 -104.496045) (xy 266.318299 -104.442091)
			(xy 266.333656 -104.389789) (xy 266.356301 -104.340206) (xy 266.385772 -104.294351) (xy 266.421469 -104.253156)
			(xy 266.462665 -104.217461) (xy 266.508522 -104.187992) (xy 266.558106 -104.16535) (xy 266.610408 -104.149995)
			(xy 266.664363 -104.14224) (xy 266.691618 -104.141778) (xy 266.717525 -104.142263) (xy 266.76886 -104.149288)
			(xy 266.818773 -104.163194) (xy 266.866346 -104.183723) (xy 266.910704 -104.2105) (xy 266.951032 -104.243032)
			(xy 266.986588 -104.28072) (xy 267.002006 -104.301544) (xy 267.007742 -104.308878) (xy 267.023248 -104.319163)
			(xy 267.032232 -104.32161) (xy 267.062712 -104.328468) (xy 267.07199 -104.330204) (xy 267.090652 -104.327473)
			(xy 267.099034 -104.323134) (xy 267.125006 -104.308832) (xy 267.179859 -104.286322) (xy 267.237164 -104.271097)
			(xy 267.295956 -104.263414) (xy 267.325602 -104.262936) (xy 267.355245 -104.263427) (xy 267.414027 -104.271151)
			(xy 267.471325 -104.28638) (xy 267.526185 -104.308859) (xy 267.55217 -104.323134) (xy 267.560586 -104.327374)
			(xy 267.579213 -104.330113) (xy 267.588492 -104.328468) (xy 267.618972 -104.32161) (xy 267.627966 -104.319186)
			(xy 267.64347 -104.308889) (xy 267.649198 -104.301544) (xy 267.664575 -104.280684) (xy 267.700123 -104.242975)
			(xy 267.740452 -104.210427) (xy 267.784817 -104.183641) (xy 267.8324 -104.163111) (xy 267.882326 -104.149214)
			(xy 267.933674 -104.142207) (xy 267.959586 -104.141778) (xy 267.986839 -104.142268) (xy 268.040789 -104.150023)
			(xy 268.093087 -104.165378) (xy 268.142667 -104.188019) (xy 268.18852 -104.217485) (xy 268.229713 -104.253177)
			(xy 268.265407 -104.294369) (xy 268.294875 -104.340221) (xy 268.317517 -104.3898) (xy 268.332874 -104.442097)
			(xy 268.340631 -104.496048) (xy 268.340631 -104.550552) (xy 268.332874 -104.604503) (xy 268.317517 -104.6568)
			(xy 268.294875 -104.706379) (xy 268.265407 -104.752231) (xy 268.23005 -104.793034) (xy 278.910032 -104.793034)
			(xy 278.914103 -104.737412) (xy 278.926229 -104.682975) (xy 278.946152 -104.630884) (xy 278.973448 -104.582249)
			(xy 279.007534 -104.538106) (xy 279.047683 -104.499397) (xy 279.093041 -104.466946) (xy 279.142641 -104.441445)
			(xy 279.195425 -104.423438) (xy 279.250268 -104.413308) (xy 279.306002 -104.411271) (xy 279.361439 -104.417371)
			(xy 279.415396 -104.431477) (xy 279.466725 -104.453289) (xy 279.514331 -104.482343) (xy 279.557199 -104.518018)
			(xy 279.594416 -104.559555) (xy 279.625189 -104.606068) (xy 279.648861 -104.656565) (xy 279.664929 -104.709972)
			(xy 279.673049 -104.765148) (xy 279.673558 -104.793034) (xy 279.673049 -104.82092) (xy 279.664929 -104.876096)
			(xy 279.648861 -104.929503) (xy 279.625189 -104.98) (xy 279.594416 -105.026513) (xy 279.557199 -105.06805)
			(xy 279.514331 -105.103725) (xy 279.466725 -105.132779) (xy 279.415396 -105.154591) (xy 279.361439 -105.168697)
			(xy 279.306002 -105.174797) (xy 279.250268 -105.17276) (xy 279.195425 -105.16263) (xy 279.142641 -105.144623)
			(xy 279.093041 -105.119122) (xy 279.047683 -105.086671) (xy 279.007534 -105.047962) (xy 278.973448 -105.003819)
			(xy 278.946152 -104.955184) (xy 278.926229 -104.903093) (xy 278.914103 -104.848656) (xy 278.910032 -104.793034)
			(xy 268.23005 -104.793034) (xy 268.229713 -104.793423) (xy 268.18852 -104.829115) (xy 268.142667 -104.858581)
			(xy 268.093087 -104.881222) (xy 268.040789 -104.896577) (xy 267.986839 -104.904332) (xy 267.959586 -104.904794)
			(xy 267.944793 -104.904662) (xy 267.915295 -104.902371) (xy 267.900658 -104.900222) (xy 267.889684 -104.899074)
			(xy 267.86849 -104.905149) (xy 267.859764 -104.911906) (xy 267.801344 -104.961944) (xy 267.79334 -104.969532)
			(xy 267.784113 -104.989537) (xy 267.783564 -105.000552) (xy 267.783564 -105.304844) (xy 267.784144 -105.315857)
			(xy 267.793335 -105.335874) (xy 267.801344 -105.343452) (xy 267.826564 -105.365042) (xy 281.422854 -105.365042)
			(xy 281.426925 -105.30942) (xy 281.439051 -105.254983) (xy 281.458974 -105.202892) (xy 281.48627 -105.154257)
			(xy 281.520356 -105.110114) (xy 281.560505 -105.071405) (xy 281.605863 -105.038954) (xy 281.655463 -105.013453)
			(xy 281.708247 -104.995446) (xy 281.76309 -104.985316) (xy 281.818824 -104.983279) (xy 281.874261 -104.989379)
			(xy 281.928218 -105.003485) (xy 281.979547 -105.025297) (xy 282.027153 -105.054351) (xy 282.070021 -105.090026)
			(xy 282.107238 -105.131563) (xy 282.138011 -105.178076) (xy 282.161683 -105.228573) (xy 282.177751 -105.28198)
			(xy 282.185871 -105.337156) (xy 282.18638 -105.365042) (xy 282.185871 -105.392928) (xy 282.177751 -105.448104)
			(xy 282.161683 -105.501511) (xy 282.138011 -105.552008) (xy 282.107238 -105.598521) (xy 282.070021 -105.640058)
			(xy 282.027153 -105.675733) (xy 281.979547 -105.704787) (xy 281.928218 -105.726599) (xy 281.874261 -105.740705)
			(xy 281.818824 -105.746805) (xy 281.76309 -105.744768) (xy 281.708247 -105.734638) (xy 281.655463 -105.716631)
			(xy 281.605863 -105.69113) (xy 281.560505 -105.658679) (xy 281.520356 -105.61997) (xy 281.48627 -105.575827)
			(xy 281.458974 -105.527192) (xy 281.439051 -105.475101) (xy 281.426925 -105.420664) (xy 281.422854 -105.365042)
			(xy 267.826564 -105.365042) (xy 267.8684 -105.400856) (xy 267.889482 -105.406952) (xy 267.900658 -105.405174)
			(xy 267.915296 -105.403032) (xy 267.944793 -105.400745) (xy 267.959586 -105.400602) (xy 267.98684 -105.401044)
			(xy 268.040794 -105.408799) (xy 268.093095 -105.424155) (xy 268.142678 -105.446797) (xy 268.188535 -105.476265)
			(xy 268.22973 -105.51196) (xy 268.265426 -105.553154) (xy 268.294896 -105.599009) (xy 268.31754 -105.648592)
			(xy 268.332898 -105.700892) (xy 268.340655 -105.754846) (xy 268.340655 -105.809354) (xy 268.332898 -105.863308)
			(xy 268.31754 -105.915608) (xy 268.294896 -105.965191) (xy 268.265426 -106.011046) (xy 268.22973 -106.05224)
			(xy 268.188535 -106.087935) (xy 268.142678 -106.117403) (xy 268.093095 -106.140045) (xy 268.040794 -106.155401)
			(xy 267.98684 -106.163156) (xy 267.959586 -106.163618) (xy 267.933679 -106.163132) (xy 267.882344 -106.156107)
			(xy 267.832431 -106.142202) (xy 267.784858 -106.121672) (xy 267.7405 -106.094896) (xy 267.700172 -106.062364)
			(xy 267.664616 -106.024676) (xy 267.649198 -106.003852) (xy 267.643461 -105.996518) (xy 267.627956 -105.986234)
			(xy 267.618972 -105.983786) (xy 267.588492 -105.976928) (xy 267.579214 -105.975194) (xy 267.560552 -105.977924)
			(xy 267.55217 -105.982262) (xy 267.526197 -105.996562) (xy 267.471344 -106.019073) (xy 267.41404 -106.034298)
			(xy 267.355248 -106.041982) (xy 267.325602 -106.04246) (xy 267.295959 -106.041968) (xy 267.237177 -106.034244)
			(xy 267.179879 -106.019016) (xy 267.125019 -105.996536) (xy 267.099034 -105.982262) (xy 267.090618 -105.978023)
			(xy 267.071991 -105.975284) (xy 267.062712 -105.976928) (xy 267.032232 -105.983786) (xy 267.023239 -105.986213)
			(xy 267.007735 -105.996507) (xy 267.002006 -106.003852) (xy 266.986626 -106.024709) (xy 266.951078 -106.062419)
			(xy 266.91075 -106.094967) (xy 266.866386 -106.121753) (xy 266.818803 -106.142284) (xy 266.768877 -106.156181)
			(xy 266.71753 -106.163189) (xy 266.691618 -106.163618) (xy 266.664365 -106.163136) (xy 266.610414 -106.155381)
			(xy 266.558115 -106.140027) (xy 266.508534 -106.117386) (xy 266.46268 -106.08792) (xy 266.421486 -106.052227)
			(xy 266.385791 -106.011035) (xy 266.356322 -105.965182) (xy 266.333679 -105.915602) (xy 266.318323 -105.863304)
			(xy 266.310565 -105.809353) (xy 266.310565 -105.754847) (xy 266.318323 -105.700896) (xy 266.333679 -105.648598)
			(xy 266.356322 -105.599018) (xy 266.385791 -105.553165) (xy 266.421486 -105.511973) (xy 266.46268 -105.47628)
			(xy 266.508534 -105.446814) (xy 266.558115 -105.424173) (xy 266.610414 -105.408819) (xy 266.664365 -105.401064)
			(xy 266.691618 -105.400602) (xy 266.706411 -105.400733) (xy 266.735909 -105.403025) (xy 266.750546 -105.405174)
			(xy 266.76152 -105.406325) (xy 266.782714 -105.400248) (xy 266.79144 -105.39349) (xy 266.84986 -105.343452)
			(xy 266.857867 -105.335866) (xy 266.867092 -105.315859) (xy 266.86764 -105.304844) (xy 266.86764 -105.000552)
			(xy 266.867061 -104.989539) (xy 266.857869 -104.969522) (xy 266.84986 -104.961944) (xy 266.782804 -104.90454)
			(xy 266.761722 -104.898444) (xy 266.750546 -104.900222) (xy 266.735908 -104.902364) (xy 266.706411 -104.904651)
			(xy 266.691618 -104.904794) (xy 266.664363 -104.90436) (xy 266.610408 -104.896605) (xy 266.558106 -104.88125)
			(xy 266.508522 -104.858608) (xy 266.462665 -104.829139) (xy 266.421469 -104.793444) (xy 266.385772 -104.752249)
			(xy 266.356301 -104.706394) (xy 266.333656 -104.656811) (xy 266.318299 -104.604509) (xy 266.310541 -104.550555)
			(xy 232.353848 -104.550555) (xy 232.390379 -104.567239) (xy 232.436229 -104.596705) (xy 232.47742 -104.632396)
			(xy 232.513111 -104.673587) (xy 232.542577 -104.719437) (xy 232.565219 -104.769014) (xy 232.580574 -104.821309)
			(xy 232.58833 -104.875257) (xy 232.588816 -104.902508) (xy 232.588375 -104.929879) (xy 232.580554 -104.98406)
			(xy 232.565061 -105.036565) (xy 232.542213 -105.086311) (xy 232.512481 -105.132276) (xy 232.494836 -105.153206)
			(xy 232.494582 -105.15346) (xy 232.489004 -105.160552) (xy 232.482753 -105.177465) (xy 232.48239 -105.18648)
			(xy 232.48239 -105.253536) (xy 232.482732 -105.262554) (xy 232.48899 -105.279471) (xy 232.494582 -105.286556)
			(xy 232.494836 -105.286556) (xy 232.494836 -105.28681) (xy 232.512486 -105.307736) (xy 232.542213 -105.353704)
			(xy 232.565061 -105.403451) (xy 232.580558 -105.455954) (xy 232.588386 -105.510135) (xy 232.588386 -105.564877)
			(xy 232.580555 -105.619057) (xy 232.565056 -105.67156) (xy 232.542208 -105.721307) (xy 232.512479 -105.767274)
			(xy 232.494836 -105.788206) (xy 232.494582 -105.78846) (xy 232.489004 -105.795552) (xy 232.482753 -105.812465)
			(xy 232.48239 -105.82148) (xy 232.48239 -105.888536) (xy 232.482732 -105.897554) (xy 232.48899 -105.914471)
			(xy 232.494582 -105.921556) (xy 232.494836 -105.921556) (xy 232.494836 -105.92181) (xy 232.512499 -105.942723)
			(xy 232.542206 -105.988702) (xy 232.565037 -106.038454) (xy 232.580522 -106.090959) (xy 232.588345 -106.145138)
			(xy 232.588816 -106.172508) (xy 232.58833 -106.199759) (xy 232.580574 -106.253707) (xy 232.565219 -106.306002)
			(xy 232.547978 -106.343752) (xy 268.952681 -106.343752) (xy 268.952681 -106.289248) (xy 268.960438 -106.235298)
			(xy 268.975795 -106.183002) (xy 268.998438 -106.133423) (xy 269.027906 -106.087572) (xy 269.0636 -106.046382)
			(xy 269.104793 -106.01069) (xy 269.150646 -105.981225) (xy 269.200226 -105.958586) (xy 269.252524 -105.943233)
			(xy 269.306474 -105.935479) (xy 269.333726 -105.935018) (xy 269.359634 -105.93548) (xy 269.41097 -105.942507)
			(xy 269.460884 -105.956415) (xy 269.508458 -105.976949) (xy 269.552816 -106.003729) (xy 269.593143 -106.036265)
			(xy 269.628697 -106.073958) (xy 269.644114 -106.094784) (xy 269.64984 -106.102127) (xy 269.665353 -106.112406)
			(xy 269.67434 -106.11485) (xy 269.70482 -106.121708) (xy 269.714098 -106.123443) (xy 269.732759 -106.120711)
			(xy 269.741142 -106.116374) (xy 269.76711 -106.102063) (xy 269.821965 -106.079557) (xy 269.879271 -106.064335)
			(xy 269.938064 -106.056654) (xy 269.96771 -106.056176) (xy 269.997352 -106.056701) (xy 270.056133 -106.064414)
			(xy 270.113431 -106.079633) (xy 270.168293 -106.102104) (xy 270.194278 -106.116374) (xy 270.202691 -106.120619)
			(xy 270.221321 -106.123353) (xy 270.2306 -106.121708) (xy 270.26108 -106.11485) (xy 270.270082 -106.112448)
			(xy 270.285583 -106.102137) (xy 270.291306 -106.094784) (xy 270.306689 -106.073929) (xy 270.342236 -106.036218)
			(xy 270.382562 -106.003669) (xy 270.426926 -105.976882) (xy 270.474509 -105.95635) (xy 270.524434 -105.942453)
			(xy 270.575782 -105.935447) (xy 270.601694 -105.935018) (xy 270.628949 -105.935428) (xy 270.682904 -105.943185)
			(xy 270.735207 -105.958542) (xy 270.784791 -105.981186) (xy 270.830648 -106.010655) (xy 270.870284 -106.045)
			(xy 276.86965 -106.045) (xy 276.873721 -105.989378) (xy 276.885847 -105.934941) (xy 276.90577 -105.88285)
			(xy 276.933066 -105.834215) (xy 276.967152 -105.790072) (xy 277.007301 -105.751363) (xy 277.052659 -105.718912)
			(xy 277.102259 -105.693411) (xy 277.155043 -105.675404) (xy 277.209886 -105.665274) (xy 277.26562 -105.663237)
			(xy 277.321057 -105.669337) (xy 277.375014 -105.683443) (xy 277.426343 -105.705255) (xy 277.473949 -105.734309)
			(xy 277.516817 -105.769984) (xy 277.554034 -105.811521) (xy 277.584807 -105.858034) (xy 277.608479 -105.908531)
			(xy 277.624547 -105.961938) (xy 277.632667 -106.017114) (xy 277.633176 -106.045) (xy 277.632667 -106.072886)
			(xy 277.624547 -106.128062) (xy 277.608479 -106.181469) (xy 277.584807 -106.231966) (xy 277.554034 -106.278479)
			(xy 277.516817 -106.320016) (xy 277.473949 -106.355691) (xy 277.426343 -106.384745) (xy 277.375014 -106.406557)
			(xy 277.321057 -106.420663) (xy 277.26562 -106.426763) (xy 277.209886 -106.424726) (xy 277.155043 -106.414596)
			(xy 277.102259 -106.396589) (xy 277.052659 -106.371088) (xy 277.007301 -106.338637) (xy 276.967152 -106.299928)
			(xy 276.933066 -106.255785) (xy 276.90577 -106.20715) (xy 276.885847 -106.155059) (xy 276.873721 -106.100622)
			(xy 276.86965 -106.045) (xy 270.870284 -106.045) (xy 270.871844 -106.046352) (xy 270.907541 -106.087547)
			(xy 270.937012 -106.133404) (xy 270.959656 -106.182988) (xy 270.975013 -106.23529) (xy 270.982771 -106.289245)
			(xy 270.982771 -106.343755) (xy 270.975013 -106.39771) (xy 270.959656 -106.450012) (xy 270.937012 -106.499596)
			(xy 270.907541 -106.545453) (xy 270.871844 -106.586648) (xy 270.830648 -106.622345) (xy 270.784791 -106.651814)
			(xy 270.735207 -106.674458) (xy 270.682904 -106.689815) (xy 270.628949 -106.697572) (xy 270.601694 -106.698034)
			(xy 270.586901 -106.697902) (xy 270.557403 -106.695611) (xy 270.542766 -106.693462) (xy 270.531792 -106.692333)
			(xy 270.5106 -106.698397) (xy 270.501872 -106.705146) (xy 270.443452 -106.755184) (xy 270.435431 -106.762757)
			(xy 270.426213 -106.782774) (xy 270.425672 -106.793792) (xy 270.425672 -107.098084) (xy 270.426227 -107.109101)
			(xy 270.435435 -107.129117) (xy 270.443452 -107.136692) (xy 270.510508 -107.194096) (xy 270.53159 -107.200192)
			(xy 270.542766 -107.198414) (xy 270.557404 -107.196271) (xy 270.586901 -107.193984) (xy 270.601694 -107.193842)
			(xy 270.628951 -107.194205) (xy 270.682909 -107.201962) (xy 270.735215 -107.217319) (xy 270.784802 -107.239965)
			(xy 270.830662 -107.269436) (xy 270.871861 -107.305135) (xy 270.90756 -107.346333) (xy 270.937033 -107.392192)
			(xy 270.944004 -107.407456) (xy 281.247086 -107.407456) (xy 281.251157 -107.351834) (xy 281.263283 -107.297397)
			(xy 281.283206 -107.245306) (xy 281.310502 -107.196671) (xy 281.344588 -107.152528) (xy 281.384737 -107.113819)
			(xy 281.430095 -107.081368) (xy 281.479695 -107.055867) (xy 281.532479 -107.03786) (xy 281.587322 -107.02773)
			(xy 281.643056 -107.025693) (xy 281.698493 -107.031793) (xy 281.75245 -107.045899) (xy 281.803779 -107.067711)
			(xy 281.851385 -107.096765) (xy 281.894253 -107.13244) (xy 281.93147 -107.173977) (xy 281.962243 -107.22049)
			(xy 281.985915 -107.270987) (xy 282.001983 -107.324394) (xy 282.010103 -107.37957) (xy 282.010612 -107.407456)
			(xy 282.010103 -107.435342) (xy 282.001983 -107.490518) (xy 281.985915 -107.543925) (xy 281.962243 -107.594422)
			(xy 281.93147 -107.640935) (xy 281.894253 -107.682472) (xy 281.851385 -107.718147) (xy 281.803779 -107.747201)
			(xy 281.75245 -107.769013) (xy 281.698493 -107.783119) (xy 281.643056 -107.789219) (xy 281.587322 -107.787182)
			(xy 281.532479 -107.777052) (xy 281.479695 -107.759045) (xy 281.430095 -107.733544) (xy 281.384737 -107.701093)
			(xy 281.344588 -107.662384) (xy 281.310502 -107.618241) (xy 281.283206 -107.569606) (xy 281.263283 -107.517515)
			(xy 281.251157 -107.463078) (xy 281.247086 -107.407456) (xy 270.944004 -107.407456) (xy 270.959678 -107.441779)
			(xy 270.975037 -107.494085) (xy 270.982795 -107.548043) (xy 270.982795 -107.602557) (xy 270.975037 -107.656515)
			(xy 270.959678 -107.708821) (xy 270.937033 -107.758408) (xy 270.90756 -107.804267) (xy 270.872179 -107.845098)
			(xy 276.86965 -107.845098) (xy 276.873721 -107.789476) (xy 276.885847 -107.735039) (xy 276.90577 -107.682948)
			(xy 276.933066 -107.634313) (xy 276.967152 -107.59017) (xy 277.007301 -107.551461) (xy 277.052659 -107.51901)
			(xy 277.102259 -107.493509) (xy 277.155043 -107.475502) (xy 277.209886 -107.465372) (xy 277.26562 -107.463335)
			(xy 277.321057 -107.469435) (xy 277.375014 -107.483541) (xy 277.426343 -107.505353) (xy 277.473949 -107.534407)
			(xy 277.516817 -107.570082) (xy 277.554034 -107.611619) (xy 277.584807 -107.658132) (xy 277.608479 -107.708629)
			(xy 277.624547 -107.762036) (xy 277.632667 -107.817212) (xy 277.633176 -107.845098) (xy 277.632667 -107.872984)
			(xy 277.624547 -107.92816) (xy 277.608479 -107.981567) (xy 277.584807 -108.032064) (xy 277.554034 -108.078577)
			(xy 277.516817 -108.120114) (xy 277.473949 -108.155789) (xy 277.426343 -108.184843) (xy 277.375014 -108.206655)
			(xy 277.321057 -108.220761) (xy 277.26562 -108.226861) (xy 277.209886 -108.224824) (xy 277.155043 -108.214694)
			(xy 277.102259 -108.196687) (xy 277.052659 -108.171186) (xy 277.007301 -108.138735) (xy 276.967152 -108.100026)
			(xy 276.933066 -108.055883) (xy 276.90577 -108.007248) (xy 276.885847 -107.955157) (xy 276.873721 -107.90072)
			(xy 276.86965 -107.845098) (xy 270.872179 -107.845098) (xy 270.871861 -107.845465) (xy 270.830662 -107.881164)
			(xy 270.784802 -107.910635) (xy 270.735215 -107.933281) (xy 270.682909 -107.948638) (xy 270.628951 -107.956395)
			(xy 270.601694 -107.956858) (xy 270.575786 -107.956391) (xy 270.524449 -107.949366) (xy 270.474535 -107.935459)
			(xy 270.426961 -107.914927) (xy 270.382603 -107.888147) (xy 270.342276 -107.855611) (xy 270.306722 -107.817918)
			(xy 270.291306 -107.797092) (xy 270.285558 -107.789768) (xy 270.270062 -107.779477) (xy 270.26108 -107.777026)
			(xy 270.2306 -107.770168) (xy 270.22132 -107.768446) (xy 270.202661 -107.771169) (xy 270.194278 -107.775502)
			(xy 270.168305 -107.789803) (xy 270.113452 -107.812312) (xy 270.056148 -107.827537) (xy 269.997356 -107.835221)
			(xy 269.96771 -107.8357) (xy 269.938067 -107.835212) (xy 269.879284 -107.827489) (xy 269.821986 -107.812259)
			(xy 269.767126 -107.789778) (xy 269.741142 -107.775502) (xy 269.732725 -107.771265) (xy 269.714099 -107.768526)
			(xy 269.70482 -107.770168) (xy 269.67434 -107.777026) (xy 269.665344 -107.779444) (xy 269.64984 -107.789744)
			(xy 269.644114 -107.797092) (xy 269.628711 -107.817932) (xy 269.593169 -107.855645) (xy 269.552846 -107.888196)
			(xy 269.508486 -107.914985) (xy 269.460906 -107.935519) (xy 269.410983 -107.949419) (xy 269.359637 -107.956428)
			(xy 269.333726 -107.956858) (xy 269.306475 -107.956297) (xy 269.252529 -107.948544) (xy 269.200235 -107.933192)
			(xy 269.150658 -107.910554) (xy 269.104807 -107.88109) (xy 269.063617 -107.845401) (xy 269.027925 -107.804213)
			(xy 268.998459 -107.758365) (xy 268.975817 -107.70879) (xy 268.960462 -107.656497) (xy 268.952705 -107.60255)
			(xy 268.952705 -107.54805) (xy 268.960462 -107.494103) (xy 268.975817 -107.44181) (xy 268.998459 -107.392235)
			(xy 269.027925 -107.346387) (xy 269.063617 -107.305199) (xy 269.104807 -107.26951) (xy 269.150658 -107.240046)
			(xy 269.200235 -107.217408) (xy 269.252529 -107.202056) (xy 269.306476 -107.194303) (xy 269.333726 -107.193842)
			(xy 269.348519 -107.193972) (xy 269.378017 -107.196265) (xy 269.392654 -107.198414) (xy 269.40363 -107.199501)
			(xy 269.424817 -107.193466) (xy 269.433548 -107.18673) (xy 269.491968 -107.136692) (xy 269.500003 -107.129132)
			(xy 269.509212 -107.109105) (xy 269.509748 -107.098084) (xy 269.509748 -106.793792) (xy 269.509231 -106.78277)
			(xy 269.499999 -106.762753) (xy 269.491968 -106.755184) (xy 269.424912 -106.69778) (xy 269.40383 -106.691684)
			(xy 269.392654 -106.693462) (xy 269.378016 -106.695603) (xy 269.348519 -106.697891) (xy 269.333726 -106.698034)
			(xy 269.306474 -106.697521) (xy 269.252524 -106.689767) (xy 269.200226 -106.674414) (xy 269.150646 -106.651775)
			(xy 269.104793 -106.62231) (xy 269.0636 -106.586618) (xy 269.027906 -106.545428) (xy 268.998438 -106.499577)
			(xy 268.975795 -106.449998) (xy 268.960438 -106.397702) (xy 268.952681 -106.343752) (xy 232.547978 -106.343752)
			(xy 232.542577 -106.355579) (xy 232.513111 -106.401429) (xy 232.47742 -106.44262) (xy 232.436229 -106.478311)
			(xy 232.390379 -106.507777) (xy 232.340802 -106.530419) (xy 232.288507 -106.545774) (xy 232.234559 -106.55353)
			(xy 232.180057 -106.55353) (xy 232.126109 -106.545774) (xy 232.073814 -106.530419) (xy 232.024237 -106.507777)
			(xy 231.978387 -106.478311) (xy 231.937196 -106.44262) (xy 231.901505 -106.401429) (xy 231.872039 -106.355579)
			(xy 231.849397 -106.306002) (xy 231.834042 -106.253707) (xy 231.826286 -106.199759) (xy 231.8258 -106.172508)
			(xy 229.532434 -106.172508) (xy 229.531948 -106.199759) (xy 229.524192 -106.253707) (xy 229.508837 -106.306002)
			(xy 229.486195 -106.355579) (xy 229.456729 -106.401429) (xy 229.421038 -106.44262) (xy 229.379847 -106.478311)
			(xy 229.333997 -106.507777) (xy 229.28442 -106.530419) (xy 229.232125 -106.545774) (xy 229.178177 -106.55353)
			(xy 229.123675 -106.55353) (xy 229.069727 -106.545774) (xy 229.017432 -106.530419) (xy 228.967855 -106.507777)
			(xy 228.922005 -106.478311) (xy 228.880814 -106.44262) (xy 228.845123 -106.401429) (xy 228.815657 -106.355579)
			(xy 228.793015 -106.306002) (xy 228.77766 -106.253707) (xy 228.769904 -106.199759) (xy 228.769418 -106.172508)
			(xy 228.213644 -106.172508) (xy 228.231201 -106.192768) (xy 228.26067 -106.23862) (xy 228.283313 -106.2882)
			(xy 228.298669 -106.340497) (xy 228.306427 -106.394447) (xy 228.306427 -106.448953) (xy 228.298669 -106.502903)
			(xy 228.283313 -106.5552) (xy 228.26067 -106.60478) (xy 228.231201 -106.650632) (xy 228.195506 -106.691823)
			(xy 228.154313 -106.727515) (xy 228.108459 -106.756981) (xy 228.058878 -106.779621) (xy 228.00658 -106.794975)
			(xy 227.952629 -106.802728) (xy 227.925376 -106.80319) (xy 227.898005 -106.80274) (xy 227.843825 -106.794919)
			(xy 227.791322 -106.779426) (xy 227.741575 -106.756581) (xy 227.695609 -106.726853) (xy 227.674678 -106.70921)
			(xy 227.674424 -106.708956) (xy 227.667339 -106.703368) (xy 227.650421 -106.697123) (xy 227.641404 -106.696764)
			(xy 227.574348 -106.696764) (xy 227.565334 -106.697152) (xy 227.548418 -106.703379) (xy 227.541328 -106.708956)
			(xy 227.541328 -106.70921) (xy 227.541074 -106.70921) (xy 227.520126 -106.726829) (xy 227.474158 -106.756544)
			(xy 227.424414 -106.779383) (xy 227.371917 -106.794879) (xy 227.317744 -106.802713) (xy 227.290376 -106.80319)
			(xy 227.263125 -106.802739) (xy 227.209177 -106.794979) (xy 227.156883 -106.779621) (xy 227.107306 -106.756977)
			(xy 227.061456 -106.727509) (xy 227.020267 -106.691816) (xy 226.984577 -106.650624) (xy 226.955111 -106.604773)
			(xy 226.932471 -106.555195) (xy 226.917116 -106.5029) (xy 226.90936 -106.448951) (xy 226.655327 -106.448951)
			(xy 226.674617 -106.457761) (xy 226.720467 -106.487227) (xy 226.761658 -106.522918) (xy 226.797349 -106.564109)
			(xy 226.826815 -106.609959) (xy 226.849457 -106.659536) (xy 226.864812 -106.711831) (xy 226.872568 -106.765779)
			(xy 226.873054 -106.79303) (xy 226.872621 -106.819345) (xy 226.865381 -106.871476) (xy 226.851057 -106.92212)
			(xy 226.829918 -106.970319) (xy 226.802365 -107.015162) (xy 226.768919 -107.055799) (xy 226.749864 -107.073954)
			(xy 226.742446 -107.081462) (xy 226.733929 -107.100752) (xy 226.733354 -107.111292) (xy 226.733354 -107.185968)
			(xy 226.7339 -107.196515) (xy 226.742425 -107.21581) (xy 226.749864 -107.223306) (xy 226.768928 -107.241453)
			(xy 226.802382 -107.282086) (xy 226.829938 -107.326929) (xy 226.851075 -107.375131) (xy 226.865391 -107.425779)
			(xy 226.872615 -107.477914) (xy 226.873054 -107.50423) (xy 226.872568 -107.531481) (xy 226.864812 -107.585429)
			(xy 226.849457 -107.637724) (xy 226.826815 -107.687301) (xy 226.797349 -107.733151) (xy 226.761658 -107.774342)
			(xy 226.720467 -107.810033) (xy 226.674617 -107.839499) (xy 226.62504 -107.862141) (xy 226.595373 -107.870852)
			(xy 228.877852 -107.870852) (xy 228.877852 -107.816348) (xy 228.885608 -107.762399) (xy 228.900963 -107.710102)
			(xy 228.923604 -107.660523) (xy 228.95307 -107.614671) (xy 228.988762 -107.573479) (xy 229.029952 -107.537785)
			(xy 229.075802 -107.508316) (xy 229.12538 -107.485672) (xy 229.177675 -107.470313) (xy 229.231624 -107.462553)
			(xy 229.258876 -107.462066) (xy 229.286246 -107.46253) (xy 229.340426 -107.470346) (xy 229.39293 -107.485835)
			(xy 229.442677 -107.508677) (xy 229.488643 -107.538404) (xy 229.509574 -107.556046) (xy 229.509828 -107.5563)
			(xy 229.516931 -107.561863) (xy 229.533835 -107.568124) (xy 229.542848 -107.568492) (xy 229.609904 -107.568492)
			(xy 229.618921 -107.568139) (xy 229.635838 -107.561889) (xy 229.642924 -107.5563) (xy 229.642924 -107.556046)
			(xy 229.643178 -107.556046) (xy 229.664111 -107.538405) (xy 229.710079 -107.508681) (xy 229.759825 -107.485835)
			(xy 229.812327 -107.470339) (xy 229.866505 -107.46251) (xy 229.921247 -107.46251) (xy 229.975425 -107.470339)
			(xy 230.027927 -107.485835) (xy 230.077673 -107.508681) (xy 230.123641 -107.538405) (xy 230.144574 -107.556046)
			(xy 230.144828 -107.5563) (xy 230.151931 -107.561863) (xy 230.168835 -107.568124) (xy 230.177848 -107.568492)
			(xy 230.244904 -107.568492) (xy 230.253921 -107.568139) (xy 230.270838 -107.561889) (xy 230.277924 -107.5563)
			(xy 230.277924 -107.556046) (xy 230.278178 -107.556046) (xy 230.299113 -107.538411) (xy 230.345085 -107.508697)
			(xy 230.394831 -107.485859) (xy 230.447331 -107.470368) (xy 230.501507 -107.46254) (xy 230.528876 -107.462066)
			(xy 230.556128 -107.46258) (xy 230.610078 -107.470333) (xy 230.662375 -107.485686) (xy 230.711955 -107.508326)
			(xy 230.757808 -107.537791) (xy 230.799001 -107.573482) (xy 230.834694 -107.614673) (xy 230.864163 -107.660524)
			(xy 230.886805 -107.710102) (xy 230.902162 -107.762399) (xy 230.909919 -107.816348) (xy 230.909919 -107.836251)
			(xy 233.797585 -107.836251) (xy 233.797585 -107.781749) (xy 233.805342 -107.727802) (xy 233.820697 -107.675508)
			(xy 233.843337 -107.625932) (xy 233.872803 -107.580082) (xy 233.908494 -107.538893) (xy 233.949684 -107.503202)
			(xy 233.995534 -107.473737) (xy 234.04511 -107.451096) (xy 234.097404 -107.435741) (xy 234.151351 -107.427985)
			(xy 234.178602 -107.427522) (xy 234.204916 -107.427981) (xy 234.257045 -107.435217) (xy 234.307689 -107.449537)
			(xy 234.355888 -107.470671) (xy 234.400731 -107.498219) (xy 234.44137 -107.531659) (xy 234.459526 -107.550712)
			(xy 234.467034 -107.558129) (xy 234.486325 -107.566644) (xy 234.496864 -107.567222) (xy 234.57154 -107.567222)
			(xy 234.582087 -107.566667) (xy 234.601382 -107.558149) (xy 234.608878 -107.550712) (xy 234.628698 -107.529924)
			(xy 234.67347 -107.493949) (xy 234.723128 -107.465089) (xy 234.77655 -107.443996) (xy 234.832529 -107.431147)
			(xy 234.889802 -107.426832) (xy 234.947075 -107.431147) (xy 235.003054 -107.443996) (xy 235.056476 -107.465089)
			(xy 235.106134 -107.493949) (xy 235.150906 -107.529924) (xy 235.170726 -107.550712) (xy 235.178234 -107.558129)
			(xy 235.197525 -107.566644) (xy 235.208064 -107.567222) (xy 235.28274 -107.567222) (xy 235.293287 -107.566667)
			(xy 235.312582 -107.558149) (xy 235.320078 -107.550712) (xy 235.338254 -107.531676) (xy 235.378879 -107.498217)
			(xy 235.423715 -107.470655) (xy 235.471912 -107.449513) (xy 235.522556 -107.435192) (xy 235.574687 -107.427963)
			(xy 235.601002 -107.427522) (xy 235.628255 -107.427948) (xy 235.682207 -107.435705) (xy 235.734506 -107.451062)
			(xy 235.784087 -107.473705) (xy 235.82994 -107.503174) (xy 235.871134 -107.538868) (xy 235.906828 -107.580061)
			(xy 235.936296 -107.625915) (xy 235.958939 -107.675496) (xy 235.974295 -107.727795) (xy 235.982052 -107.781747)
			(xy 235.982052 -107.836253) (xy 235.974295 -107.890205) (xy 235.958939 -107.942504) (xy 235.936296 -107.992085)
			(xy 235.906828 -108.037939) (xy 235.871134 -108.079132) (xy 235.82994 -108.114826) (xy 235.784087 -108.144295)
			(xy 235.734506 -108.166938) (xy 235.682207 -108.182295) (xy 235.628255 -108.190052) (xy 235.601002 -108.190538)
			(xy 235.574687 -108.190089) (xy 235.522557 -108.182853) (xy 235.471913 -108.168532) (xy 235.423714 -108.147396)
			(xy 235.378871 -108.119846) (xy 235.338233 -108.086402) (xy 235.320078 -108.067348) (xy 235.31256 -108.059942)
			(xy 235.293278 -108.051419) (xy 235.28274 -108.050838) (xy 235.208064 -108.050838) (xy 235.197515 -108.051377)
			(xy 235.178219 -108.059904) (xy 235.170726 -108.067348) (xy 235.150906 -108.088136) (xy 235.106134 -108.124111)
			(xy 235.056476 -108.152971) (xy 235.003054 -108.174064) (xy 234.947075 -108.186913) (xy 234.889802 -108.191228)
			(xy 234.832529 -108.186913) (xy 234.77655 -108.174064) (xy 234.723128 -108.152971) (xy 234.67347 -108.124111)
			(xy 234.628698 -108.088136) (xy 234.608878 -108.067348) (xy 234.60136 -108.059942) (xy 234.582078 -108.051419)
			(xy 234.57154 -108.050838) (xy 234.496864 -108.050838) (xy 234.486315 -108.051377) (xy 234.467019 -108.059904)
			(xy 234.459526 -108.067348) (xy 234.44136 -108.086393) (xy 234.400732 -108.119849) (xy 234.355893 -108.147409)
			(xy 234.307695 -108.168548) (xy 234.257049 -108.182868) (xy 234.204917 -108.190097) (xy 234.178602 -108.190538)
			(xy 234.151351 -108.190015) (xy 234.097404 -108.182259) (xy 234.04511 -108.166904) (xy 233.995534 -108.144263)
			(xy 233.949684 -108.114798) (xy 233.908494 -108.079107) (xy 233.872803 -108.037918) (xy 233.843337 -107.992068)
			(xy 233.820697 -107.942492) (xy 233.805342 -107.890198) (xy 233.797585 -107.836251) (xy 230.909919 -107.836251)
			(xy 230.909919 -107.870852) (xy 230.902162 -107.924801) (xy 230.886805 -107.977098) (xy 230.864163 -108.026676)
			(xy 230.834694 -108.072527) (xy 230.799001 -108.113718) (xy 230.757808 -108.149409) (xy 230.711955 -108.178874)
			(xy 230.662375 -108.201514) (xy 230.610078 -108.216867) (xy 230.556128 -108.22462) (xy 230.528876 -108.225082)
			(xy 230.501505 -108.224634) (xy 230.447325 -108.216813) (xy 230.394822 -108.20132) (xy 230.345075 -108.178474)
			(xy 230.299109 -108.148745) (xy 230.278178 -108.131102) (xy 230.277924 -108.130848) (xy 230.270839 -108.125259)
			(xy 230.253921 -108.119015) (xy 230.244904 -108.118656) (xy 230.177848 -108.118656) (xy 230.168832 -108.119024)
			(xy 230.151914 -108.125262) (xy 230.144828 -108.130848) (xy 230.144574 -108.131102) (xy 230.123641 -108.148743)
			(xy 230.077673 -108.178467) (xy 230.027927 -108.201313) (xy 229.975425 -108.216809) (xy 229.921247 -108.224638)
			(xy 229.866505 -108.224638) (xy 229.812327 -108.216809) (xy 229.759825 -108.201313) (xy 229.710079 -108.178467)
			(xy 229.664111 -108.148743) (xy 229.643178 -108.131102) (xy 229.642924 -108.130848) (xy 229.635839 -108.125259)
			(xy 229.618921 -108.119015) (xy 229.609904 -108.118656) (xy 229.542848 -108.118656) (xy 229.533832 -108.119024)
			(xy 229.516914 -108.125262) (xy 229.509828 -108.130848) (xy 229.509828 -108.131102) (xy 229.509574 -108.131102)
			(xy 229.488625 -108.14872) (xy 229.442657 -108.178435) (xy 229.392914 -108.201275) (xy 229.340417 -108.216771)
			(xy 229.286244 -108.224605) (xy 229.258876 -108.225082) (xy 229.231624 -108.224647) (xy 229.177675 -108.216887)
			(xy 229.12538 -108.201528) (xy 229.075802 -108.178884) (xy 229.029952 -108.149415) (xy 228.988762 -108.113721)
			(xy 228.95307 -108.072529) (xy 228.923604 -108.026677) (xy 228.900963 -107.977098) (xy 228.885608 -107.924801)
			(xy 228.877852 -107.870852) (xy 226.595373 -107.870852) (xy 226.572745 -107.877496) (xy 226.518797 -107.885252)
			(xy 226.464295 -107.885252) (xy 226.410347 -107.877496) (xy 226.358052 -107.862141) (xy 226.308475 -107.839499)
			(xy 226.262625 -107.810033) (xy 226.221434 -107.774342) (xy 226.185743 -107.733151) (xy 226.156277 -107.687301)
			(xy 226.133635 -107.637724) (xy 226.11828 -107.585429) (xy 226.110524 -107.531481) (xy 226.110038 -107.50423)
			(xy 223.192225 -107.50423) (xy 223.180242 -107.545031) (xy 223.157595 -107.594614) (xy 223.128121 -107.640469)
			(xy 223.092421 -107.681663) (xy 223.051223 -107.717356) (xy 223.005363 -107.746823) (xy 222.955777 -107.769463)
			(xy 222.903473 -107.784815) (xy 222.849517 -107.792568) (xy 222.822262 -107.793028) (xy 222.793345 -107.792492)
			(xy 222.736174 -107.783771) (xy 222.680974 -107.766518) (xy 222.629012 -107.74113) (xy 222.581478 -107.708188)
			(xy 222.539462 -107.668447) (xy 222.521272 -107.645962) (xy 222.513674 -107.637146) (xy 222.492766 -107.626969)
			(xy 222.48114 -107.626404) (xy 222.401384 -107.626404) (xy 222.389753 -107.626947) (xy 222.368843 -107.637133)
			(xy 222.361252 -107.645962) (xy 222.343022 -107.668413) (xy 222.301012 -107.708152) (xy 222.253485 -107.741096)
			(xy 222.201531 -107.76649) (xy 222.14634 -107.783753) (xy 222.089176 -107.792489) (xy 222.060262 -107.793028)
			(xy 222.033011 -107.792558) (xy 221.979063 -107.784796) (xy 221.92677 -107.769437) (xy 221.877194 -107.746793)
			(xy 221.831344 -107.717325) (xy 221.790155 -107.681632) (xy 221.754464 -107.640441) (xy 221.724998 -107.594591)
			(xy 221.702356 -107.545013) (xy 221.687 -107.492719) (xy 221.679241 -107.438771) (xy 221.678754 -107.41152)
			(xy 192.124753 -107.41152) (xy 192.107915 -107.454983) (xy 192.069181 -107.532772) (xy 192.023434 -107.606656)
			(xy 191.971065 -107.676003) (xy 191.912521 -107.740223) (xy 191.848301 -107.798767) (xy 191.778954 -107.851136)
			(xy 191.70507 -107.896883) (xy 191.627281 -107.935617) (xy 191.546249 -107.967009) (xy 191.462667 -107.99079)
			(xy 191.377247 -108.006758) (xy 191.290718 -108.014776) (xy 191.203818 -108.014776) (xy 191.117289 -108.006758)
			(xy 191.031869 -107.99079) (xy 190.948287 -107.967009) (xy 190.867255 -107.935617) (xy 190.789466 -107.896883)
			(xy 190.715582 -107.851136) (xy 190.646235 -107.798767) (xy 190.582015 -107.740223) (xy 190.523471 -107.676003)
			(xy 190.471102 -107.606656) (xy 190.425355 -107.532772) (xy 190.386621 -107.454983) (xy 190.355229 -107.373951)
			(xy 190.331448 -107.290369) (xy 190.31548 -107.204949) (xy 190.307462 -107.11842) (xy 188.923937 -107.11842)
			(xy 188.923937 -107.118438) (xy 188.915921 -107.204943) (xy 188.899958 -107.29034) (xy 188.876183 -107.373899)
			(xy 188.844799 -107.454908) (xy 188.806075 -107.532676) (xy 188.76034 -107.606539) (xy 188.707986 -107.675867)
			(xy 188.649457 -107.740069) (xy 188.585255 -107.798596) (xy 188.515926 -107.85095) (xy 188.442062 -107.896683)
			(xy 188.364293 -107.935406) (xy 188.283284 -107.966788) (xy 188.199724 -107.990562) (xy 188.114327 -108.006524)
			(xy 188.027822 -108.014538) (xy 187.984384 -108.015024) (xy 186.130184 -108.015024) (xy 186.086745 -108.014582)
			(xy 186.000238 -108.006564) (xy 185.914839 -107.990599) (xy 185.831278 -107.966823) (xy 185.750267 -107.935438)
			(xy 185.672497 -107.896712) (xy 185.598632 -107.850975) (xy 185.529303 -107.798619) (xy 185.4651 -107.740089)
			(xy 185.406571 -107.675885) (xy 185.354215 -107.606554) (xy 185.30848 -107.532689) (xy 185.269756 -107.454919)
			(xy 185.238372 -107.373907) (xy 185.214597 -107.290345) (xy 185.198634 -107.204947) (xy 185.190618 -107.118439)
			(xy 184.817262 -107.118439) (xy 184.809246 -107.204949) (xy 184.793278 -107.290369) (xy 184.769497 -107.373951)
			(xy 184.738105 -107.454983) (xy 184.699371 -107.532772) (xy 184.653624 -107.606656) (xy 184.601255 -107.676003)
			(xy 184.542711 -107.740223) (xy 184.478491 -107.798767) (xy 184.409144 -107.851136) (xy 184.33526 -107.896883)
			(xy 184.257471 -107.935617) (xy 184.176439 -107.967009) (xy 184.092857 -107.99079) (xy 184.007437 -108.006758)
			(xy 183.920908 -108.014776) (xy 183.834008 -108.014776) (xy 183.747479 -108.006758) (xy 183.662059 -107.99079)
			(xy 183.578477 -107.967009) (xy 183.497445 -107.935617) (xy 183.419656 -107.896883) (xy 183.345772 -107.851136)
			(xy 183.276425 -107.798767) (xy 183.212205 -107.740223) (xy 183.153661 -107.676003) (xy 183.101292 -107.606656)
			(xy 183.055545 -107.532772) (xy 183.016811 -107.454983) (xy 182.985419 -107.373951) (xy 182.961638 -107.290369)
			(xy 182.94567 -107.204949) (xy 182.937652 -107.11842) (xy 170.65498 -107.11842) (xy 170.65498 -107.376214)
			(xy 170.654472 -107.396026) (xy 170.654485 -107.40762) (xy 170.663616 -107.428909) (xy 170.671998 -107.43692)
			(xy 170.696382 -107.457748) (xy 170.705335 -107.464775) (xy 170.727248 -107.470826) (xy 170.738546 -107.469432)
			(xy 170.75523 -107.466599) (xy 170.788935 -107.463543) (xy 170.805856 -107.463336) (xy 170.806364 -107.463336)
			(xy 170.833622 -107.463708) (xy 170.887583 -107.471462) (xy 170.939891 -107.486817) (xy 170.989481 -107.50946)
			(xy 171.035344 -107.53893) (xy 171.076546 -107.574628) (xy 171.112248 -107.615827) (xy 171.141723 -107.661687)
			(xy 171.16437 -107.711275) (xy 171.17973 -107.763582) (xy 171.187489 -107.817542) (xy 171.187489 -107.872058)
			(xy 171.17973 -107.926018) (xy 171.16437 -107.978325) (xy 171.141723 -108.027913) (xy 171.131233 -108.044234)
			(xy 198.958708 -108.044234) (xy 198.959194 -108.016983) (xy 198.96695 -107.963035) (xy 198.982305 -107.91074)
			(xy 199.004947 -107.861163) (xy 199.034413 -107.815313) (xy 199.070104 -107.774122) (xy 199.111295 -107.738431)
			(xy 199.157145 -107.708965) (xy 199.206722 -107.686323) (xy 199.259017 -107.670968) (xy 199.312965 -107.663212)
			(xy 199.367467 -107.663212) (xy 199.421415 -107.670968) (xy 199.47371 -107.686323) (xy 199.523287 -107.708965)
			(xy 199.569137 -107.738431) (xy 199.610328 -107.774122) (xy 199.646019 -107.815313) (xy 199.675485 -107.861163)
			(xy 199.698127 -107.91074) (xy 199.713482 -107.963035) (xy 199.721238 -108.016983) (xy 199.721724 -108.044234)
			(xy 199.721188 -108.071805) (xy 199.713246 -108.126373) (xy 199.697531 -108.17923) (xy 199.674372 -108.229273)
			(xy 199.644251 -108.275463) (xy 199.607794 -108.316835) (xy 199.565762 -108.352529) (xy 199.542654 -108.367576)
			(xy 199.530079 -108.376034) (xy 199.510215 -108.398904) (xy 199.497933 -108.426595) (xy 199.494314 -108.45667)
			(xy 199.49726 -108.473054) (xy 221.556763 -108.473054) (xy 221.556763 -108.418546) (xy 221.564521 -108.364593)
			(xy 221.579879 -108.312294) (xy 221.602523 -108.262713) (xy 221.631994 -108.216859) (xy 221.66769 -108.175666)
			(xy 221.708886 -108.139973) (xy 221.754742 -108.110507) (xy 221.804326 -108.087867) (xy 221.856627 -108.072514)
			(xy 221.91058 -108.064761) (xy 221.937834 -108.0643) (xy 221.965205 -108.064746) (xy 222.019385 -108.072569)
			(xy 222.071888 -108.088063) (xy 222.121635 -108.110909) (xy 222.167601 -108.140637) (xy 222.188532 -108.15828)
			(xy 222.188786 -108.158534) (xy 222.19587 -108.164125) (xy 222.212789 -108.170368) (xy 222.221806 -108.170726)
			(xy 222.288862 -108.170726) (xy 222.297876 -108.170345) (xy 222.314793 -108.164114) (xy 222.321882 -108.158534)
			(xy 222.321882 -108.15828) (xy 222.322136 -108.15828) (xy 222.343069 -108.140639) (xy 222.389037 -108.110915)
			(xy 222.438783 -108.088069) (xy 222.491285 -108.072573) (xy 222.545463 -108.064744) (xy 222.600205 -108.064744)
			(xy 222.654383 -108.072573) (xy 222.706885 -108.088069) (xy 222.756631 -108.110915) (xy 222.802599 -108.140639)
			(xy 222.823532 -108.15828) (xy 222.823786 -108.158534) (xy 222.83087 -108.164125) (xy 222.847789 -108.170368)
			(xy 222.856806 -108.170726) (xy 222.923862 -108.170726) (xy 222.932876 -108.170345) (xy 222.949793 -108.164114)
			(xy 222.956882 -108.158534) (xy 222.956882 -108.15828) (xy 222.957136 -108.15828) (xy 222.978069 -108.140639)
			(xy 223.024037 -108.110915) (xy 223.073783 -108.088069) (xy 223.126285 -108.072573) (xy 223.180463 -108.064744)
			(xy 223.235205 -108.064744) (xy 223.289383 -108.072573) (xy 223.341885 -108.088069) (xy 223.391631 -108.110915)
			(xy 223.437599 -108.140639) (xy 223.458532 -108.15828) (xy 223.458786 -108.158534) (xy 223.46587 -108.164125)
			(xy 223.482789 -108.170368) (xy 223.491806 -108.170726) (xy 223.558862 -108.170726) (xy 223.567876 -108.170345)
			(xy 223.584793 -108.164114) (xy 223.591882 -108.158534) (xy 223.591882 -108.15828) (xy 223.592136 -108.15828)
			(xy 223.613079 -108.140654) (xy 223.659049 -108.110941) (xy 223.708794 -108.088103) (xy 223.761292 -108.072609)
			(xy 223.815466 -108.064776) (xy 223.842834 -108.0643) (xy 223.870084 -108.064772) (xy 223.924029 -108.072533)
			(xy 223.976321 -108.087891) (xy 224.025895 -108.110535) (xy 224.071742 -108.140002) (xy 224.112929 -108.175695)
			(xy 224.148618 -108.216885) (xy 224.178082 -108.262735) (xy 224.200721 -108.312311) (xy 224.216075 -108.364604)
			(xy 224.22383 -108.41855) (xy 224.22383 -108.47305) (xy 224.22383 -108.473053) (xy 225.480563 -108.473053)
			(xy 225.480563 -108.418547) (xy 225.488321 -108.364594) (xy 225.503678 -108.312296) (xy 225.526322 -108.262715)
			(xy 225.555792 -108.216861) (xy 225.591487 -108.175669) (xy 225.632682 -108.139976) (xy 225.678538 -108.110509)
			(xy 225.72812 -108.087869) (xy 225.78042 -108.072515) (xy 225.834373 -108.064762) (xy 225.861626 -108.0643)
			(xy 225.887941 -108.06475) (xy 225.94007 -108.071988) (xy 225.990713 -108.086311) (xy 226.038912 -108.107447)
			(xy 226.083755 -108.134996) (xy 226.124394 -108.168437) (xy 226.14255 -108.18749) (xy 226.150052 -108.194914)
			(xy 226.169347 -108.203426) (xy 226.179888 -108.204) (xy 226.254564 -108.204) (xy 226.265113 -108.203465)
			(xy 226.284408 -108.194934) (xy 226.291902 -108.18749) (xy 226.310062 -108.168439) (xy 226.350691 -108.134981)
			(xy 226.39553 -108.107422) (xy 226.44373 -108.086283) (xy 226.494377 -108.071965) (xy 226.54651 -108.064739)
			(xy 226.572826 -108.0643) (xy 226.600197 -108.064751) (xy 226.654377 -108.072572) (xy 226.70688 -108.088065)
			(xy 226.756626 -108.11091) (xy 226.802593 -108.140637) (xy 226.823524 -108.15828) (xy 226.823778 -108.158534)
			(xy 226.830864 -108.164121) (xy 226.847781 -108.170366) (xy 226.856798 -108.170726) (xy 226.923854 -108.170726)
			(xy 226.932868 -108.170341) (xy 226.949785 -108.164112) (xy 226.956874 -108.158534) (xy 226.956874 -108.15828)
			(xy 226.957128 -108.15828) (xy 226.978061 -108.140639) (xy 227.024029 -108.110915) (xy 227.073775 -108.088069)
			(xy 227.126277 -108.072573) (xy 227.180455 -108.064744) (xy 227.235197 -108.064744) (xy 227.289375 -108.072573)
			(xy 227.341877 -108.088069) (xy 227.391623 -108.110915) (xy 227.437591 -108.140639) (xy 227.458524 -108.15828)
			(xy 227.458778 -108.158534) (xy 227.465864 -108.164121) (xy 227.482781 -108.170366) (xy 227.491798 -108.170726)
			(xy 227.558854 -108.170726) (xy 227.567868 -108.170341) (xy 227.584785 -108.164112) (xy 227.591874 -108.158534)
			(xy 227.591874 -108.15828) (xy 227.592128 -108.15828) (xy 227.613074 -108.140658) (xy 227.659043 -108.110944)
			(xy 227.708787 -108.088105) (xy 227.761285 -108.07261) (xy 227.815458 -108.064777) (xy 227.842826 -108.0643)
			(xy 227.870077 -108.064772) (xy 227.924023 -108.072531) (xy 227.976315 -108.087889) (xy 228.02589 -108.110532)
			(xy 228.071738 -108.14) (xy 228.112926 -108.175692) (xy 228.148616 -108.216882) (xy 228.17808 -108.262732)
			(xy 228.20072 -108.312309) (xy 228.206075 -108.330548) (xy 244.367592 -108.330548) (xy 244.367592 -108.276052)
			(xy 244.375347 -108.22211) (xy 244.3907 -108.16982) (xy 244.413337 -108.120248) (xy 244.442798 -108.074401)
			(xy 244.478484 -108.033214) (xy 244.519667 -107.997523) (xy 244.565511 -107.968057) (xy 244.615081 -107.945414)
			(xy 244.667369 -107.930056) (xy 244.72131 -107.922295) (xy 244.748558 -107.921806) (xy 244.776103 -107.92236)
			(xy 244.830622 -107.930265) (xy 244.883436 -107.945932) (xy 244.933448 -107.969033) (xy 244.979615 -107.999089)
			(xy 245.020979 -108.035475) (xy 245.056677 -108.077432) (xy 245.085968 -108.124089) (xy 245.108242 -108.174475)
			(xy 245.123035 -108.227541) (xy 245.127018 -108.2548) (xy 245.128796 -108.26877) (xy 245.146068 -108.290614)
			(xy 245.255288 -108.333032) (xy 245.282974 -108.328206) (xy 245.293388 -108.319316) (xy 245.314181 -108.3023)
			(xy 245.359606 -108.27361) (xy 245.408609 -108.251578) (xy 245.460218 -108.236643) (xy 245.513413 -108.229099)
			(xy 245.540276 -108.228638) (xy 245.568957 -108.229202) (xy 245.625669 -108.237809) (xy 245.680456 -108.254802)
			(xy 245.732084 -108.2798) (xy 245.779392 -108.312239) (xy 245.821316 -108.351389) (xy 245.856911 -108.396371)
			(xy 245.885378 -108.446171) (xy 245.906074 -108.499669) (xy 245.918535 -108.55566) (xy 245.921022 -108.584238)
			(xy 245.922038 -108.593333) (xy 245.929585 -108.609991) (xy 245.935754 -108.61675) (xy 245.989602 -108.670598)
			(xy 246.006112 -108.678218) (xy 246.015256 -108.678726) (xy 246.043842 -108.681195) (xy 246.099854 -108.693625)
			(xy 246.153373 -108.7143) (xy 246.203194 -108.742756) (xy 246.248193 -108.778351) (xy 246.258577 -108.78947)
			(xy 257.477512 -108.78947) (xy 257.481583 -108.733848) (xy 257.493709 -108.679411) (xy 257.513632 -108.62732)
			(xy 257.540928 -108.578685) (xy 257.575014 -108.534542) (xy 257.615163 -108.495833) (xy 257.660521 -108.463382)
			(xy 257.710121 -108.437881) (xy 257.762905 -108.419874) (xy 257.817748 -108.409744) (xy 257.873482 -108.407707)
			(xy 257.928919 -108.413807) (xy 257.982876 -108.427913) (xy 258.034205 -108.449725) (xy 258.081811 -108.478779)
			(xy 258.124679 -108.514454) (xy 258.161896 -108.555991) (xy 258.192669 -108.602504) (xy 258.216341 -108.653001)
			(xy 258.232409 -108.706408) (xy 258.240529 -108.761584) (xy 258.241038 -108.78947) (xy 258.240529 -108.817356)
			(xy 258.232409 -108.872532) (xy 258.216341 -108.925939) (xy 258.192669 -108.976436) (xy 258.161896 -109.022949)
			(xy 258.124679 -109.064486) (xy 258.081811 -109.100161) (xy 258.034205 -109.129215) (xy 257.982876 -109.151027)
			(xy 257.928919 -109.165133) (xy 257.873482 -109.171233) (xy 257.817748 -109.169196) (xy 257.762905 -109.159066)
			(xy 257.710121 -109.141059) (xy 257.660521 -109.115558) (xy 257.615163 -109.083107) (xy 257.575014 -109.044398)
			(xy 257.540928 -109.000255) (xy 257.513632 -108.95162) (xy 257.493709 -108.899529) (xy 257.481583 -108.845092)
			(xy 257.477512 -108.78947) (xy 246.258577 -108.78947) (xy 246.287354 -108.820282) (xy 246.319797 -108.867604)
			(xy 246.344788 -108.91925) (xy 246.361765 -108.974055) (xy 246.370345 -109.030785) (xy 246.370856 -109.059472)
			(xy 246.370296 -109.08672) (xy 246.362544 -109.140663) (xy 246.347195 -109.192953) (xy 246.324561 -109.242527)
			(xy 246.308516 -109.267498) (xy 246.461786 -109.267498) (xy 246.465857 -109.211876) (xy 246.477983 -109.157439)
			(xy 246.497906 -109.105348) (xy 246.525202 -109.056713) (xy 246.559288 -109.01257) (xy 246.599437 -108.973861)
			(xy 246.644795 -108.94141) (xy 246.694395 -108.915909) (xy 246.747179 -108.897902) (xy 246.802022 -108.887772)
			(xy 246.857756 -108.885735) (xy 246.913193 -108.891835) (xy 246.96715 -108.905941) (xy 247.018479 -108.927753)
			(xy 247.066085 -108.956807) (xy 247.108953 -108.992482) (xy 247.14617 -109.034019) (xy 247.176943 -109.080532)
			(xy 247.200615 -109.131029) (xy 247.216683 -109.184436) (xy 247.224803 -109.239612) (xy 247.225312 -109.267498)
			(xy 247.224803 -109.295384) (xy 247.216683 -109.35056) (xy 247.200615 -109.403967) (xy 247.198088 -109.409357)
			(xy 266.310507 -109.409357) (xy 266.310507 -109.354843) (xy 266.318265 -109.300884) (xy 266.333624 -109.248578)
			(xy 266.356271 -109.19899) (xy 266.385744 -109.15313) (xy 266.421445 -109.111932) (xy 266.462645 -109.076234)
			(xy 266.508506 -109.046762) (xy 266.558094 -109.024118) (xy 266.610401 -109.008762) (xy 266.664361 -109.001006)
			(xy 266.691618 -109.000544) (xy 266.706411 -109.000675) (xy 266.735909 -109.002967) (xy 266.750546 -109.005116)
			(xy 266.76152 -109.006257) (xy 266.782713 -109.000185) (xy 266.79144 -108.993432) (xy 266.84986 -108.943394)
			(xy 266.857893 -108.935831) (xy 266.867103 -108.915807) (xy 266.86764 -108.904786) (xy 266.86764 -108.600494)
			(xy 266.867093 -108.589477) (xy 266.857878 -108.569461) (xy 266.84986 -108.561886) (xy 266.782804 -108.504482)
			(xy 266.761722 -108.498386) (xy 266.750546 -108.500164) (xy 266.735908 -108.502306) (xy 266.706411 -108.504593)
			(xy 266.691618 -108.504736) (xy 266.664366 -108.504218) (xy 266.610417 -108.496464) (xy 266.558121 -108.48111)
			(xy 266.508542 -108.45847) (xy 266.46269 -108.429005) (xy 266.421499 -108.393314) (xy 266.385806 -108.352124)
			(xy 266.356338 -108.306273) (xy 266.333696 -108.256696) (xy 266.31834 -108.2044) (xy 266.310583 -108.150452)
			(xy 266.310583 -108.095948) (xy 266.31834 -108.042) (xy 266.333696 -107.989704) (xy 266.356338 -107.940127)
			(xy 266.385806 -107.894276) (xy 266.421499 -107.853086) (xy 266.46269 -107.817395) (xy 266.508542 -107.78793)
			(xy 266.558121 -107.76529) (xy 266.610417 -107.749936) (xy 266.664366 -107.742182) (xy 266.691618 -107.74172)
			(xy 266.717525 -107.742187) (xy 266.768862 -107.749213) (xy 266.818776 -107.763121) (xy 266.86635 -107.783653)
			(xy 266.910708 -107.810433) (xy 266.951035 -107.842968) (xy 266.986589 -107.88066) (xy 267.002006 -107.901486)
			(xy 267.007734 -107.908827) (xy 267.023246 -107.919107) (xy 267.032232 -107.921552) (xy 267.062712 -107.92841)
			(xy 267.071991 -107.930141) (xy 267.090651 -107.927412) (xy 267.099034 -107.923076) (xy 267.125021 -107.908821)
			(xy 267.179886 -107.886389) (xy 267.237187 -107.871222) (xy 267.295965 -107.863575) (xy 267.355239 -107.863575)
			(xy 267.414017 -107.871222) (xy 267.471318 -107.886389) (xy 267.526183 -107.908821) (xy 267.55217 -107.923076)
			(xy 267.560585 -107.927318) (xy 267.579213 -107.930054) (xy 267.588492 -107.92841) (xy 267.618972 -107.921552)
			(xy 267.627972 -107.919146) (xy 267.643474 -107.908838) (xy 267.649198 -107.901486) (xy 267.664587 -107.880635)
			(xy 267.700132 -107.842924) (xy 267.740458 -107.810374) (xy 267.784821 -107.783587) (xy 267.832403 -107.763055)
			(xy 267.882327 -107.749157) (xy 267.933674 -107.742149) (xy 267.959586 -107.74172) (xy 267.986842 -107.742126)
			(xy 268.040798 -107.749882) (xy 268.093101 -107.765238) (xy 268.142687 -107.787881) (xy 268.188545 -107.817351)
			(xy 268.229743 -107.853047) (xy 268.265441 -107.894243) (xy 268.294912 -107.940101) (xy 268.317557 -107.989685)
			(xy 268.332915 -108.041988) (xy 268.340673 -108.095944) (xy 268.340673 -108.150456) (xy 268.332915 -108.204412)
			(xy 268.317557 -108.256715) (xy 268.306947 -108.279946) (xy 279.21153 -108.279946) (xy 279.215601 -108.224324)
			(xy 279.227727 -108.169887) (xy 279.24765 -108.117796) (xy 279.274946 -108.069161) (xy 279.309032 -108.025018)
			(xy 279.349181 -107.986309) (xy 279.394539 -107.953858) (xy 279.444139 -107.928357) (xy 279.496923 -107.91035)
			(xy 279.551766 -107.90022) (xy 279.6075 -107.898183) (xy 279.662937 -107.904283) (xy 279.716894 -107.918389)
			(xy 279.768223 -107.940201) (xy 279.815829 -107.969255) (xy 279.858697 -108.00493) (xy 279.895914 -108.046467)
			(xy 279.926687 -108.09298) (xy 279.950359 -108.143477) (xy 279.966427 -108.196884) (xy 279.974547 -108.25206)
			(xy 279.975056 -108.279946) (xy 279.974547 -108.307832) (xy 279.966427 -108.363008) (xy 279.950359 -108.416415)
			(xy 279.926687 -108.466912) (xy 279.895914 -108.513425) (xy 279.858697 -108.554962) (xy 279.815829 -108.590637)
			(xy 279.768223 -108.619691) (xy 279.716894 -108.641503) (xy 279.662937 -108.655609) (xy 279.6075 -108.661709)
			(xy 279.551766 -108.659672) (xy 279.496923 -108.649542) (xy 279.444139 -108.631535) (xy 279.394539 -108.606034)
			(xy 279.349181 -108.573583) (xy 279.309032 -108.534874) (xy 279.274946 -108.490731) (xy 279.24765 -108.442096)
			(xy 279.227727 -108.390005) (xy 279.215601 -108.335568) (xy 279.21153 -108.279946) (xy 268.306947 -108.279946)
			(xy 268.294912 -108.306299) (xy 268.265441 -108.352157) (xy 268.229743 -108.393353) (xy 268.188545 -108.429049)
			(xy 268.142687 -108.458519) (xy 268.093101 -108.481162) (xy 268.040798 -108.496518) (xy 267.986842 -108.504274)
			(xy 267.959586 -108.504736) (xy 267.944793 -108.504605) (xy 267.915295 -108.502313) (xy 267.900658 -108.500164)
			(xy 267.889684 -108.49903) (xy 267.868492 -108.505098) (xy 267.859764 -108.511848) (xy 267.801344 -108.561886)
			(xy 267.793321 -108.569457) (xy 267.784105 -108.589475) (xy 267.783564 -108.600494) (xy 267.783564 -108.904786)
			(xy 267.784121 -108.915802) (xy 267.793328 -108.935818) (xy 267.801344 -108.943394) (xy 267.8684 -109.000798)
			(xy 267.889482 -109.006894) (xy 267.900658 -109.005116) (xy 267.915296 -109.002974) (xy 267.944793 -109.000687)
			(xy 267.959586 -109.000544) (xy 267.986836 -109.001102) (xy 268.040782 -109.008857) (xy 268.093075 -109.02421)
			(xy 268.14265 -109.046848) (xy 268.188499 -109.076312) (xy 268.229689 -109.112001) (xy 268.265379 -109.153189)
			(xy 268.280893 -109.177328) (xy 281.264866 -109.177328) (xy 281.268937 -109.121706) (xy 281.281063 -109.067269)
			(xy 281.300986 -109.015178) (xy 281.328282 -108.966543) (xy 281.362368 -108.9224) (xy 281.402517 -108.883691)
			(xy 281.447875 -108.85124) (xy 281.497475 -108.825739) (xy 281.550259 -108.807732) (xy 281.605102 -108.797602)
			(xy 281.660836 -108.795565) (xy 281.716273 -108.801665) (xy 281.77023 -108.815771) (xy 281.821559 -108.837583)
			(xy 281.869165 -108.866637) (xy 281.912033 -108.902312) (xy 281.94925 -108.943849) (xy 281.980023 -108.990362)
			(xy 282.003695 -109.040859) (xy 282.019763 -109.094266) (xy 282.027883 -109.149442) (xy 282.028392 -109.177328)
			(xy 282.027883 -109.205214) (xy 282.019763 -109.26039) (xy 282.003695 -109.313797) (xy 281.980023 -109.364294)
			(xy 281.94925 -109.410807) (xy 281.912033 -109.452344) (xy 281.869165 -109.488019) (xy 281.821559 -109.517073)
			(xy 281.77023 -109.538885) (xy 281.716273 -109.552991) (xy 281.660836 -109.559091) (xy 281.605102 -109.557054)
			(xy 281.550259 -109.546924) (xy 281.497475 -109.528917) (xy 281.447875 -109.503416) (xy 281.402517 -109.470965)
			(xy 281.362368 -109.432256) (xy 281.328282 -109.388113) (xy 281.300986 -109.339478) (xy 281.281063 -109.287387)
			(xy 281.268937 -109.23295) (xy 281.264866 -109.177328) (xy 268.280893 -109.177328) (xy 268.294845 -109.199037)
			(xy 268.317486 -109.248612) (xy 268.33284 -109.300905) (xy 268.340597 -109.35485) (xy 268.340597 -109.40935)
			(xy 268.33284 -109.463295) (xy 268.317486 -109.515588) (xy 268.294845 -109.565163) (xy 268.265379 -109.611011)
			(xy 268.229689 -109.652199) (xy 268.188499 -109.687888) (xy 268.14265 -109.717352) (xy 268.093075 -109.73999)
			(xy 268.040782 -109.755343) (xy 267.986836 -109.763098) (xy 267.959586 -109.76356) (xy 267.933678 -109.763098)
			(xy 267.882341 -109.756072) (xy 267.832427 -109.742165) (xy 267.784853 -109.721632) (xy 267.740495 -109.694851)
			(xy 267.700168 -109.662314) (xy 267.664614 -109.624621) (xy 267.649198 -109.603794) (xy 267.643452 -109.596468)
			(xy 267.627954 -109.586178) (xy 267.618972 -109.583728) (xy 267.588492 -109.57687) (xy 267.579213 -109.575143)
			(xy 267.560553 -109.57787) (xy 267.55217 -109.582204) (xy 267.526183 -109.596459) (xy 267.471318 -109.618891)
			(xy 267.414017 -109.634058) (xy 267.355239 -109.641705) (xy 267.295965 -109.641705) (xy 267.237187 -109.634058)
			(xy 267.179886 -109.618891) (xy 267.125021 -109.596459) (xy 267.099034 -109.582204) (xy 267.090619 -109.577963)
			(xy 267.071991 -109.575227) (xy 267.062712 -109.57687) (xy 267.032232 -109.583728) (xy 267.023234 -109.586142)
			(xy 267.007732 -109.596445) (xy 267.002006 -109.603794) (xy 266.986609 -109.624638) (xy 266.951066 -109.662351)
			(xy 266.910742 -109.694902) (xy 266.86638 -109.72169) (xy 266.818799 -109.742223) (xy 266.768876 -109.756122)
			(xy 266.717529 -109.763131) (xy 266.691618 -109.76356) (xy 266.664361 -109.763194) (xy 266.610401 -109.755438)
			(xy 266.558094 -109.740082) (xy 266.508506 -109.717438) (xy 266.462645 -109.687966) (xy 266.421445 -109.652268)
			(xy 266.385744 -109.61107) (xy 266.356271 -109.56521) (xy 266.333624 -109.515622) (xy 266.318265 -109.463316)
			(xy 266.310507 -109.409357) (xy 247.198088 -109.409357) (xy 247.176943 -109.454464) (xy 247.14617 -109.500977)
			(xy 247.108953 -109.542514) (xy 247.066085 -109.578189) (xy 247.018479 -109.607243) (xy 246.96715 -109.629055)
			(xy 246.913193 -109.643161) (xy 246.857756 -109.649261) (xy 246.802022 -109.647224) (xy 246.747179 -109.637094)
			(xy 246.694395 -109.619087) (xy 246.644795 -109.593586) (xy 246.599437 -109.561135) (xy 246.559288 -109.522426)
			(xy 246.525202 -109.478283) (xy 246.497906 -109.429648) (xy 246.477983 -109.377557) (xy 246.465857 -109.32312)
			(xy 246.461786 -109.267498) (xy 246.308516 -109.267498) (xy 246.295102 -109.288375) (xy 246.259418 -109.329565)
			(xy 246.218236 -109.365256) (xy 246.172394 -109.394724) (xy 246.122825 -109.417369) (xy 246.070537 -109.432728)
			(xy 246.016596 -109.44049) (xy 245.989348 -109.44098) (xy 245.960666 -109.440469) (xy 245.903953 -109.431852)
			(xy 245.849166 -109.41485) (xy 245.797538 -109.389845) (xy 245.750231 -109.357399) (xy 245.708309 -109.318243)
			(xy 245.672714 -109.273257) (xy 245.644249 -109.223454) (xy 245.623552 -109.169953) (xy 245.611089 -109.113959)
			(xy 245.608602 -109.08538) (xy 245.607572 -109.076288) (xy 245.600034 -109.059629) (xy 245.59387 -109.052868)
			(xy 245.540022 -108.99902) (xy 245.523512 -108.9914) (xy 245.514368 -108.990892) (xy 245.485303 -108.988355)
			(xy 245.428381 -108.975565) (xy 245.374069 -108.954261) (xy 245.323632 -108.92494) (xy 245.278244 -108.888286)
			(xy 245.238963 -108.84515) (xy 245.206704 -108.79654) (xy 245.182218 -108.743586) (xy 245.166076 -108.687523)
			(xy 245.161816 -108.65866) (xy 245.160038 -108.64469) (xy 245.142766 -108.622846) (xy 245.033546 -108.580428)
			(xy 245.00586 -108.585254) (xy 244.995446 -108.594144) (xy 244.974684 -108.611199) (xy 244.92925 -108.639882)
			(xy 244.880239 -108.661905) (xy 244.828623 -108.676831) (xy 244.775423 -108.684366) (xy 244.748558 -108.684822)
			(xy 244.72131 -108.684305) (xy 244.667369 -108.676544) (xy 244.615081 -108.661186) (xy 244.565511 -108.638543)
			(xy 244.519667 -108.609077) (xy 244.478484 -108.573386) (xy 244.442798 -108.532199) (xy 244.413337 -108.486352)
			(xy 244.3907 -108.43678) (xy 244.375347 -108.38449) (xy 244.367592 -108.330548) (xy 228.206075 -108.330548)
			(xy 228.216074 -108.364603) (xy 228.22383 -108.418549) (xy 228.22383 -108.473051) (xy 228.216074 -108.526997)
			(xy 228.20072 -108.579291) (xy 228.17808 -108.628868) (xy 228.148616 -108.674718) (xy 228.112926 -108.715908)
			(xy 228.071738 -108.7516) (xy 228.02589 -108.781068) (xy 227.976315 -108.803711) (xy 227.924023 -108.819069)
			(xy 227.870077 -108.826828) (xy 227.842826 -108.827316) (xy 227.815455 -108.826855) (xy 227.761275 -108.819039)
			(xy 227.708771 -108.80355) (xy 227.659024 -108.780707) (xy 227.613059 -108.750979) (xy 227.592128 -108.733336)
			(xy 227.591874 -108.733082) (xy 227.584772 -108.727518) (xy 227.567867 -108.721258) (xy 227.558854 -108.72089)
			(xy 227.491798 -108.72089) (xy 227.482781 -108.721248) (xy 227.465864 -108.727495) (xy 227.458778 -108.733082)
			(xy 227.458524 -108.733336) (xy 227.437591 -108.750977) (xy 227.391623 -108.780701) (xy 227.341877 -108.803547)
			(xy 227.289375 -108.819043) (xy 227.235197 -108.826872) (xy 227.180455 -108.826872) (xy 227.126277 -108.819043)
			(xy 227.073775 -108.803547) (xy 227.024029 -108.780701) (xy 226.978061 -108.750977) (xy 226.957128 -108.733336)
			(xy 226.956874 -108.733082) (xy 226.949772 -108.727518) (xy 226.932867 -108.721258) (xy 226.923854 -108.72089)
			(xy 226.856798 -108.72089) (xy 226.847781 -108.721248) (xy 226.830864 -108.727495) (xy 226.823778 -108.733082)
			(xy 226.823778 -108.733336) (xy 226.823524 -108.733336) (xy 226.802598 -108.750983) (xy 226.756623 -108.780692)
			(xy 226.706874 -108.803526) (xy 226.654372 -108.819016) (xy 226.600196 -108.826842) (xy 226.572826 -108.827316)
			(xy 226.546513 -108.826826) (xy 226.494386 -108.819595) (xy 226.443743 -108.80528) (xy 226.395544 -108.784152)
			(xy 226.3507 -108.75661) (xy 226.310059 -108.723176) (xy 226.291902 -108.704126) (xy 226.284378 -108.696727)
			(xy 226.2651 -108.6882) (xy 226.254564 -108.687616) (xy 226.179888 -108.687616) (xy 226.169335 -108.688121)
			(xy 226.15004 -108.696673) (xy 226.14255 -108.704126) (xy 226.124417 -108.723204) (xy 226.083782 -108.756658)
			(xy 226.038937 -108.784213) (xy 225.990732 -108.805348) (xy 225.94008 -108.81966) (xy 225.887943 -108.82688)
			(xy 225.861626 -108.827316) (xy 225.834373 -108.826838) (xy 225.78042 -108.819085) (xy 225.72812 -108.803731)
			(xy 225.678538 -108.781091) (xy 225.632682 -108.751624) (xy 225.591487 -108.715931) (xy 225.555792 -108.674739)
			(xy 225.526322 -108.628885) (xy 225.503678 -108.579304) (xy 225.488321 -108.527006) (xy 225.480563 -108.473053)
			(xy 224.22383 -108.473053) (xy 224.216075 -108.526996) (xy 224.200721 -108.579289) (xy 224.178082 -108.628865)
			(xy 224.148618 -108.674715) (xy 224.112929 -108.715905) (xy 224.071742 -108.751598) (xy 224.025895 -108.781065)
			(xy 223.976321 -108.803709) (xy 223.924029 -108.819067) (xy 223.870084 -108.826828) (xy 223.842834 -108.827316)
			(xy 223.815464 -108.82685) (xy 223.761284 -108.819036) (xy 223.70878 -108.803548) (xy 223.659033 -108.780705)
			(xy 223.613067 -108.750979) (xy 223.592136 -108.733336) (xy 223.591882 -108.733082) (xy 223.584806 -108.72748)
			(xy 223.567881 -108.721243) (xy 223.558862 -108.72089) (xy 223.491806 -108.72089) (xy 223.48279 -108.721252)
			(xy 223.465873 -108.727496) (xy 223.458786 -108.733082) (xy 223.458532 -108.733336) (xy 223.437599 -108.750977)
			(xy 223.391631 -108.780701) (xy 223.341885 -108.803547) (xy 223.289383 -108.819043) (xy 223.235205 -108.826872)
			(xy 223.180463 -108.826872) (xy 223.126285 -108.819043) (xy 223.073783 -108.803547) (xy 223.024037 -108.780701)
			(xy 222.978069 -108.750977) (xy 222.957136 -108.733336) (xy 222.956882 -108.733082) (xy 222.949806 -108.72748)
			(xy 222.932881 -108.721243) (xy 222.923862 -108.72089) (xy 222.856806 -108.72089) (xy 222.84779 -108.721252)
			(xy 222.830873 -108.727496) (xy 222.823786 -108.733082) (xy 222.823786 -108.733336) (xy 222.823532 -108.733336)
			(xy 222.802599 -108.750977) (xy 222.756631 -108.780701) (xy 222.706885 -108.803547) (xy 222.654383 -108.819043)
			(xy 222.600205 -108.826872) (xy 222.545463 -108.826872) (xy 222.491285 -108.819043) (xy 222.438783 -108.803547)
			(xy 222.389037 -108.780701) (xy 222.343069 -108.750977) (xy 222.322136 -108.733336) (xy 222.321882 -108.733082)
			(xy 222.314806 -108.72748) (xy 222.297881 -108.721243) (xy 222.288862 -108.72089) (xy 222.221806 -108.72089)
			(xy 222.21279 -108.721252) (xy 222.195873 -108.727496) (xy 222.188786 -108.733082) (xy 222.188786 -108.733336)
			(xy 222.188532 -108.733336) (xy 222.167603 -108.750979) (xy 222.121629 -108.780689) (xy 222.071881 -108.803524)
			(xy 222.019379 -108.819014) (xy 221.965203 -108.826842) (xy 221.937834 -108.827316) (xy 221.91058 -108.826839)
			(xy 221.856627 -108.819086) (xy 221.804326 -108.803733) (xy 221.754742 -108.781093) (xy 221.708886 -108.751627)
			(xy 221.66769 -108.715934) (xy 221.631994 -108.674741) (xy 221.602523 -108.628887) (xy 221.579879 -108.579306)
			(xy 221.564521 -108.527007) (xy 221.556763 -108.473054) (xy 199.49726 -108.473054) (xy 199.499675 -108.486484)
			(xy 199.513547 -108.513414) (xy 199.534707 -108.53509) (xy 199.547734 -108.542836) (xy 199.573125 -108.557309)
			(xy 199.619559 -108.592795) (xy 199.660042 -108.634944) (xy 199.693626 -108.682772) (xy 199.719528 -108.73516)
			(xy 199.737142 -108.790884) (xy 199.746056 -108.848641) (xy 199.746616 -108.877862) (xy 199.74613 -108.905113)
			(xy 199.738374 -108.959061) (xy 199.723019 -109.011356) (xy 199.700377 -109.060933) (xy 199.670911 -109.106783)
			(xy 199.63522 -109.147974) (xy 199.594029 -109.183665) (xy 199.548179 -109.213131) (xy 199.498602 -109.235773)
			(xy 199.446307 -109.251128) (xy 199.392359 -109.258884) (xy 199.337857 -109.258884) (xy 199.283909 -109.251128)
			(xy 199.231614 -109.235773) (xy 199.182037 -109.213131) (xy 199.136187 -109.183665) (xy 199.094996 -109.147974)
			(xy 199.059305 -109.106783) (xy 199.029839 -109.060933) (xy 199.007197 -109.011356) (xy 198.991842 -108.959061)
			(xy 198.984086 -108.905113) (xy 198.9836 -108.877862) (xy 198.984122 -108.85029) (xy 198.992065 -108.795721)
			(xy 199.007781 -108.742864) (xy 199.030943 -108.692819) (xy 199.061066 -108.64663) (xy 199.097525 -108.605259)
			(xy 199.13956 -108.569566) (xy 199.16267 -108.55452) (xy 199.175246 -108.546064) (xy 199.195105 -108.523192)
			(xy 199.207383 -108.495502) (xy 199.211001 -108.465428) (xy 199.20564 -108.435615) (xy 199.191772 -108.408686)
			(xy 199.170615 -108.387008) (xy 199.15759 -108.37926) (xy 199.132203 -108.36478) (xy 199.085768 -108.329297)
			(xy 199.045284 -108.287149) (xy 199.011698 -108.239323) (xy 198.985795 -108.186935) (xy 198.968181 -108.131212)
			(xy 198.959268 -108.073455) (xy 198.958708 -108.044234) (xy 171.131233 -108.044234) (xy 171.112248 -108.073773)
			(xy 171.076546 -108.114972) (xy 171.035344 -108.15067) (xy 170.989481 -108.18014) (xy 170.939891 -108.202783)
			(xy 170.887583 -108.218138) (xy 170.833622 -108.225892) (xy 170.806364 -108.226352) (xy 170.779356 -108.225917)
			(xy 170.725878 -108.218307) (xy 170.674008 -108.203228) (xy 170.624784 -108.180984) (xy 170.579191 -108.152018)
			(xy 170.538139 -108.11691) (xy 170.50245 -108.076363) (xy 170.472837 -108.031187) (xy 170.449893 -107.982285)
			(xy 170.434077 -107.930635) (xy 170.429428 -107.904026) (xy 170.427904 -107.893358) (xy 170.416474 -107.875578)
			(xy 170.33621 -107.822238) (xy 170.315636 -107.818682) (xy 170.305222 -107.821222) (xy 170.278584 -107.82729)
			(xy 170.224336 -107.833781) (xy 170.197018 -107.834176) (xy 170.16963 -107.833732) (xy 170.115254 -107.827111)
			(xy 170.08856 -107.820968) (xy 170.078146 -107.818428) (xy 170.057572 -107.821984) (xy 169.977054 -107.875578)
			(xy 169.965624 -107.893358) (xy 169.9641 -107.904026) (xy 169.959452 -107.930632) (xy 169.943618 -107.982269)
			(xy 169.920662 -108.031158) (xy 169.891043 -108.076323) (xy 169.855353 -108.11686) (xy 169.814303 -108.151961)
			(xy 169.768715 -108.180924) (xy 169.719499 -108.20317) (xy 169.667639 -108.218256) (xy 169.614169 -108.22588)
			(xy 169.587164 -108.226352) (xy 169.559792 -108.225919) (xy 169.505611 -108.218095) (xy 169.453108 -108.202599)
			(xy 169.403361 -108.179749) (xy 169.357396 -108.150017) (xy 169.336466 -108.132372) (xy 169.336212 -108.132118)
			(xy 169.329124 -108.126533) (xy 169.312208 -108.120285) (xy 169.303192 -108.119926) (xy 169.236136 -108.119926)
			(xy 169.22712 -108.120295) (xy 169.210203 -108.126534) (xy 169.203116 -108.132118) (xy 169.203116 -108.132372)
			(xy 169.202862 -108.132372) (xy 169.181914 -108.149991) (xy 169.135946 -108.179707) (xy 169.086202 -108.202547)
			(xy 169.033705 -108.218043) (xy 168.979532 -108.225876) (xy 168.952164 -108.226352) (xy 168.951656 -108.226352)
			(xy 168.934735 -108.22613) (xy 168.901031 -108.223078) (xy 168.884346 -108.220256) (xy 168.873055 -108.218881)
			(xy 168.851164 -108.22496) (xy 168.842182 -108.23194) (xy 168.817798 -108.252768) (xy 168.80936 -108.260738)
			(xy 168.800236 -108.282054) (xy 168.800272 -108.293662) (xy 168.80078 -108.312712) (xy 168.80078 -109.176312)
			(xy 168.800272 -109.196124) (xy 168.800286 -109.207718) (xy 168.809416 -109.229007) (xy 168.817798 -109.237018)
			(xy 168.842182 -109.257846) (xy 168.851135 -109.264873) (xy 168.873048 -109.270924) (xy 168.884346 -109.26953)
			(xy 168.90103 -109.266697) (xy 168.934735 -109.263641) (xy 168.951656 -109.263434) (xy 168.952164 -109.263434)
			(xy 168.979534 -109.263913) (xy 169.033713 -109.271726) (xy 169.086216 -109.287212) (xy 169.135963 -109.310051)
			(xy 169.18193 -109.339774) (xy 169.202862 -109.357414) (xy 169.203116 -109.357668) (xy 169.210188 -109.363275)
			(xy 169.227116 -109.369508) (xy 169.236136 -109.36986) (xy 169.303192 -109.36986) (xy 169.31221 -109.369508)
			(xy 169.329127 -109.363258) (xy 169.336212 -109.357668) (xy 169.336212 -109.357414) (xy 169.336466 -109.357414)
			(xy 169.357402 -109.33978) (xy 169.403373 -109.310067) (xy 169.45312 -109.287229) (xy 169.50562 -109.271737)
			(xy 169.559795 -109.263908) (xy 169.587164 -109.263434) (xy 169.614142 -109.263864) (xy 169.667562 -109.271453)
			(xy 169.719378 -109.286499) (xy 169.768555 -109.308702) (xy 169.814109 -109.337617) (xy 169.855131 -109.372667)
			(xy 169.8908 -109.413152) (xy 169.920404 -109.458261) (xy 169.943352 -109.507094) (xy 169.959184 -109.558676)
			(xy 169.963846 -109.585252) (xy 169.963846 -109.585506) (xy 169.966055 -109.595766) (xy 169.977469 -109.613351)
			(xy 169.985944 -109.619542) (xy 170.057318 -109.66704) (xy 170.077892 -109.670596) (xy 170.088306 -109.668056)
			(xy 170.115065 -109.661912) (xy 170.169567 -109.655286) (xy 170.197018 -109.654848) (xy 170.224342 -109.655307)
			(xy 170.27859 -109.661926) (xy 170.305222 -109.668056) (xy 170.305476 -109.668056) (xy 170.315704 -109.669936)
			(xy 170.336154 -109.666249) (xy 170.3451 -109.660944) (xy 170.416728 -109.613446) (xy 170.427904 -109.59592)
			(xy 170.429682 -109.585252) (xy 170.434307 -109.558673) (xy 170.450168 -109.507107) (xy 170.473137 -109.458289)
			(xy 170.502754 -109.413195) (xy 170.538429 -109.372724) (xy 170.579451 -109.337683) (xy 170.625001 -109.308771)
			(xy 170.67417 -109.286566) (xy 170.725977 -109.27151) (xy 170.779389 -109.263903) (xy 170.806364 -109.263434)
			(xy 170.833622 -109.26381) (xy 170.887582 -109.271564) (xy 170.93989 -109.286919) (xy 170.989481 -109.309562)
			(xy 171.035343 -109.339032) (xy 171.076545 -109.37473) (xy 171.112246 -109.415928) (xy 171.141721 -109.461788)
			(xy 171.164369 -109.511376) (xy 171.179728 -109.563682) (xy 171.187487 -109.617642) (xy 171.187487 -109.672158)
			(xy 171.179728 -109.726118) (xy 171.164369 -109.778424) (xy 171.141721 -109.828012) (xy 171.112246 -109.873872)
			(xy 171.076545 -109.91507) (xy 171.035343 -109.950768) (xy 170.989481 -109.980238) (xy 170.93989 -110.002881)
			(xy 170.887582 -110.018236) (xy 170.833622 -110.02599) (xy 170.806364 -110.02645) (xy 170.805856 -110.02645)
			(xy 170.788935 -110.026228) (xy 170.755231 -110.023176) (xy 170.738546 -110.020354) (xy 170.727255 -110.018979)
			(xy 170.705365 -110.025058) (xy 170.696382 -110.032038) (xy 170.671998 -110.052866) (xy 170.663561 -110.060836)
			(xy 170.654436 -110.082152) (xy 170.654472 -110.09376) (xy 170.65498 -110.11281) (xy 170.65498 -110.361222)
			(xy 180.76113 -110.361222) (xy 180.765201 -110.3056) (xy 180.777327 -110.251163) (xy 180.79725 -110.199072)
			(xy 180.824546 -110.150437) (xy 180.858632 -110.106294) (xy 180.898781 -110.067585) (xy 180.944139 -110.035134)
			(xy 180.993739 -110.009633) (xy 181.046523 -109.991626) (xy 181.101366 -109.981496) (xy 181.1571 -109.979459)
			(xy 181.212537 -109.985559) (xy 181.266494 -109.999665) (xy 181.317823 -110.021477) (xy 181.365429 -110.050531)
			(xy 181.408297 -110.086206) (xy 181.445514 -110.127743) (xy 181.476287 -110.174256) (xy 181.499959 -110.224753)
			(xy 181.516027 -110.27816) (xy 181.524147 -110.333336) (xy 181.524656 -110.361222) (xy 181.524147 -110.389108)
			(xy 181.516027 -110.444284) (xy 181.499959 -110.497691) (xy 181.476287 -110.548188) (xy 181.445514 -110.594701)
			(xy 181.408297 -110.636238) (xy 181.365429 -110.671913) (xy 181.317823 -110.700967) (xy 181.266494 -110.722779)
			(xy 181.212537 -110.736885) (xy 181.1571 -110.742985) (xy 181.101366 -110.740948) (xy 181.046523 -110.730818)
			(xy 180.993739 -110.712811) (xy 180.944139 -110.68731) (xy 180.898781 -110.654859) (xy 180.858632 -110.61615)
			(xy 180.824546 -110.572007) (xy 180.79725 -110.523372) (xy 180.777327 -110.471281) (xy 180.765201 -110.416844)
			(xy 180.76113 -110.361222) (xy 170.65498 -110.361222) (xy 170.65498 -110.97641) (xy 170.654472 -110.996222)
			(xy 170.654487 -111.007816) (xy 170.663616 -111.029105) (xy 170.671998 -111.037116) (xy 170.696382 -111.057944)
			(xy 170.705335 -111.064971) (xy 170.727248 -111.071022) (xy 170.738546 -111.069628) (xy 170.75523 -111.066795)
			(xy 170.788935 -111.063739) (xy 170.805856 -111.063532) (xy 170.806364 -111.063532) (xy 170.833621 -111.063912)
			(xy 170.887582 -111.071666) (xy 170.93989 -111.087021) (xy 170.98948 -111.109663) (xy 171.035342 -111.139134)
			(xy 171.076543 -111.174831) (xy 171.112245 -111.216029) (xy 171.141719 -111.261889) (xy 171.164367 -111.311477)
			(xy 171.170993 -111.334042) (xy 180.363874 -111.334042) (xy 180.367945 -111.27842) (xy 180.380071 -111.223983)
			(xy 180.399994 -111.171892) (xy 180.42729 -111.123257) (xy 180.461376 -111.079114) (xy 180.501525 -111.040405)
			(xy 180.546883 -111.007954) (xy 180.596483 -110.982453) (xy 180.649267 -110.964446) (xy 180.70411 -110.954316)
			(xy 180.759844 -110.952279) (xy 180.815281 -110.958379) (xy 180.869238 -110.972485) (xy 180.920567 -110.994297)
			(xy 180.968173 -111.023351) (xy 181.011041 -111.059026) (xy 181.048258 -111.100563) (xy 181.079031 -111.147076)
			(xy 181.102703 -111.197573) (xy 181.118771 -111.25098) (xy 181.126891 -111.306156) (xy 181.1274 -111.334042)
			(xy 181.126891 -111.361928) (xy 181.118771 -111.417104) (xy 181.102703 -111.470511) (xy 181.079031 -111.521008)
			(xy 181.048258 -111.567521) (xy 181.011041 -111.609058) (xy 180.968173 -111.644733) (xy 180.920567 -111.673787)
			(xy 180.869238 -111.695599) (xy 180.815281 -111.709705) (xy 180.759844 -111.715805) (xy 180.70411 -111.713768)
			(xy 180.649267 -111.703638) (xy 180.596483 -111.685631) (xy 180.546883 -111.66013) (xy 180.501525 -111.627679)
			(xy 180.461376 -111.58897) (xy 180.42729 -111.544827) (xy 180.399994 -111.496192) (xy 180.380071 -111.444101)
			(xy 180.367945 -111.389664) (xy 180.363874 -111.334042) (xy 171.170993 -111.334042) (xy 171.179726 -111.363783)
			(xy 171.187485 -111.417743) (xy 171.187485 -111.472257) (xy 171.179726 -111.526217) (xy 171.164367 -111.578523)
			(xy 171.141719 -111.628111) (xy 171.112245 -111.673971) (xy 171.076543 -111.715169) (xy 171.035342 -111.750866)
			(xy 170.98948 -111.780336) (xy 170.93989 -111.802979) (xy 170.887582 -111.818334) (xy 170.833621 -111.826088)
			(xy 170.806364 -111.826548) (xy 170.779355 -111.826117) (xy 170.725877 -111.818506) (xy 170.674007 -111.803427)
			(xy 170.624783 -111.781182) (xy 170.579189 -111.752216) (xy 170.538137 -111.717108) (xy 170.502448 -111.676561)
			(xy 170.472836 -111.631384) (xy 170.449893 -111.582481) (xy 170.434077 -111.530831) (xy 170.429428 -111.504222)
			(xy 170.427904 -111.493554) (xy 170.416474 -111.475774) (xy 170.33621 -111.422434) (xy 170.315636 -111.418878)
			(xy 170.305222 -111.421418) (xy 170.278584 -111.427486) (xy 170.224336 -111.433977) (xy 170.197018 -111.434372)
			(xy 170.16963 -111.433928) (xy 170.115254 -111.427307) (xy 170.08856 -111.421164) (xy 170.078146 -111.418624)
			(xy 170.057572 -111.42218) (xy 169.977054 -111.475774) (xy 169.965624 -111.493554) (xy 169.9641 -111.504222)
			(xy 169.959449 -111.530828) (xy 169.943616 -111.582465) (xy 169.92066 -111.631354) (xy 169.891042 -111.676518)
			(xy 169.855351 -111.717056) (xy 169.814302 -111.752157) (xy 169.768715 -111.78112) (xy 169.719499 -111.803366)
			(xy 169.667638 -111.818452) (xy 169.614169 -111.826076) (xy 169.587164 -111.826548) (xy 169.559792 -111.826116)
			(xy 169.505611 -111.818292) (xy 169.453107 -111.802795) (xy 169.403361 -111.779946) (xy 169.357396 -111.750213)
			(xy 169.336466 -111.732568) (xy 169.336212 -111.732314) (xy 169.329125 -111.726728) (xy 169.312209 -111.72048)
			(xy 169.303192 -111.720122) (xy 169.236136 -111.720122) (xy 169.22712 -111.720492) (xy 169.210203 -111.72673)
			(xy 169.203116 -111.732314) (xy 169.203116 -111.732568) (xy 169.202862 -111.732568) (xy 169.181913 -111.750187)
			(xy 169.135946 -111.779903) (xy 169.086202 -111.802743) (xy 169.033705 -111.818239) (xy 168.979532 -111.826072)
			(xy 168.952164 -111.826548) (xy 168.951656 -111.826548) (xy 168.934735 -111.826326) (xy 168.901031 -111.823274)
			(xy 168.884346 -111.820452) (xy 168.873055 -111.819078) (xy 168.851165 -111.825156) (xy 168.842182 -111.832136)
			(xy 168.817798 -111.852964) (xy 168.809362 -111.860935) (xy 168.800237 -111.882251) (xy 168.800272 -111.893858)
			(xy 168.80078 -111.912908) (xy 168.80078 -112.510824) (xy 179.902356 -112.510824) (xy 179.906427 -112.455202)
			(xy 179.918553 -112.400765) (xy 179.938476 -112.348674) (xy 179.965772 -112.300039) (xy 179.999858 -112.255896)
			(xy 180.040007 -112.217187) (xy 180.085365 -112.184736) (xy 180.134965 -112.159235) (xy 180.187749 -112.141228)
			(xy 180.242592 -112.131098) (xy 180.298326 -112.129061) (xy 180.353763 -112.135161) (xy 180.40772 -112.149267)
			(xy 180.459049 -112.171079) (xy 180.506655 -112.200133) (xy 180.549523 -112.235808) (xy 180.58674 -112.277345)
			(xy 180.617513 -112.323858) (xy 180.641185 -112.374355) (xy 180.657253 -112.427762) (xy 180.665373 -112.482938)
			(xy 180.665882 -112.510824) (xy 180.665373 -112.53871) (xy 180.657253 -112.593886) (xy 180.641185 -112.647293)
			(xy 180.617513 -112.69779) (xy 180.58674 -112.744303) (xy 180.549523 -112.78584) (xy 180.506655 -112.821515)
			(xy 180.459049 -112.850569) (xy 180.40772 -112.872381) (xy 180.353763 -112.886487) (xy 180.298326 -112.892587)
			(xy 180.242592 -112.89055) (xy 180.187749 -112.88042) (xy 180.134965 -112.862413) (xy 180.085365 -112.836912)
			(xy 180.040007 -112.804461) (xy 179.999858 -112.765752) (xy 179.965772 -112.721609) (xy 179.938476 -112.672974)
			(xy 179.918553 -112.620883) (xy 179.906427 -112.566446) (xy 179.902356 -112.510824) (xy 168.80078 -112.510824)
			(xy 168.80078 -112.776508) (xy 168.800272 -112.79632) (xy 168.800288 -112.807914) (xy 168.809417 -112.829203)
			(xy 168.817798 -112.837214) (xy 168.842182 -112.858042) (xy 168.851135 -112.865069) (xy 168.873048 -112.87112)
			(xy 168.884346 -112.869726) (xy 168.90103 -112.866893) (xy 168.934735 -112.863837) (xy 168.951656 -112.86363)
			(xy 168.952164 -112.86363) (xy 168.979421 -112.864014) (xy 169.033382 -112.871768) (xy 169.085689 -112.887123)
			(xy 169.135279 -112.909765) (xy 169.181141 -112.939235) (xy 169.222342 -112.974933) (xy 169.258043 -113.01613)
			(xy 169.287517 -113.06199) (xy 169.310165 -113.111577) (xy 169.325524 -113.163883) (xy 169.333283 -113.217843)
			(xy 169.333283 -113.251742) (xy 180.406038 -113.251742) (xy 180.410109 -113.19612) (xy 180.422235 -113.141683)
			(xy 180.442158 -113.089592) (xy 180.469454 -113.040957) (xy 180.50354 -112.996814) (xy 180.543689 -112.958105)
			(xy 180.589047 -112.925654) (xy 180.638647 -112.900153) (xy 180.691431 -112.882146) (xy 180.746274 -112.872016)
			(xy 180.802008 -112.869979) (xy 180.857445 -112.876079) (xy 180.911402 -112.890185) (xy 180.962731 -112.911997)
			(xy 181.010337 -112.941051) (xy 181.053205 -112.976726) (xy 181.090422 -113.018263) (xy 181.121195 -113.064776)
			(xy 181.144867 -113.115273) (xy 181.160935 -113.16868) (xy 181.169055 -113.223856) (xy 181.169564 -113.251742)
			(xy 181.169055 -113.279628) (xy 181.160935 -113.334804) (xy 181.144867 -113.388211) (xy 181.121195 -113.438708)
			(xy 181.090422 -113.485221) (xy 181.053205 -113.526758) (xy 181.010337 -113.562433) (xy 180.962731 -113.591487)
			(xy 180.911402 -113.613299) (xy 180.857445 -113.627405) (xy 180.802008 -113.633505) (xy 180.746274 -113.631468)
			(xy 180.691431 -113.621338) (xy 180.638647 -113.603331) (xy 180.589047 -113.57783) (xy 180.543689 -113.545379)
			(xy 180.50354 -113.50667) (xy 180.469454 -113.462527) (xy 180.442158 -113.413892) (xy 180.422235 -113.361801)
			(xy 180.410109 -113.307364) (xy 180.406038 -113.251742) (xy 169.333283 -113.251742) (xy 169.333283 -113.272357)
			(xy 169.325524 -113.326317) (xy 169.310165 -113.378623) (xy 169.287517 -113.42821) (xy 169.258043 -113.47407)
			(xy 169.222342 -113.515267) (xy 169.181141 -113.550965) (xy 169.135279 -113.580435) (xy 169.085689 -113.603077)
			(xy 169.033382 -113.618432) (xy 168.979421 -113.626186) (xy 168.952164 -113.626646) (xy 168.925155 -113.626216)
			(xy 168.871677 -113.618605) (xy 168.819807 -113.603527) (xy 168.770583 -113.581282) (xy 168.724989 -113.552316)
			(xy 168.683937 -113.517207) (xy 168.648248 -113.476659) (xy 168.618636 -113.431482) (xy 168.595692 -113.38258)
			(xy 168.579877 -113.33093) (xy 168.575228 -113.30432) (xy 168.573704 -113.293652) (xy 168.562274 -113.275872)
			(xy 168.48201 -113.222532) (xy 168.461436 -113.218976) (xy 168.451022 -113.221516) (xy 168.424377 -113.227519)
			(xy 168.370129 -113.233882) (xy 168.342818 -113.234216) (xy 168.315436 -113.233836) (xy 168.26106 -113.227345)
			(xy 168.23436 -113.221262) (xy 168.223946 -113.218722) (xy 168.203372 -113.222278) (xy 168.122854 -113.275872)
			(xy 168.111424 -113.293652) (xy 168.1099 -113.30432) (xy 168.105248 -113.330925) (xy 168.089415 -113.382562)
			(xy 168.066459 -113.431452) (xy 168.036841 -113.476616) (xy 168.001151 -113.517154) (xy 167.960102 -113.552255)
			(xy 167.914514 -113.581218) (xy 167.865299 -113.603464) (xy 167.813438 -113.61855) (xy 167.759969 -113.626174)
			(xy 167.732964 -113.626646) (xy 167.705717 -113.626081) (xy 167.651779 -113.618321) (xy 167.599494 -113.602965)
			(xy 167.549926 -113.580324) (xy 167.504085 -113.55086) (xy 167.462903 -113.515172) (xy 167.427219 -113.473986)
			(xy 167.397759 -113.428142) (xy 167.375123 -113.378573) (xy 167.359771 -113.326286) (xy 167.352016 -113.272347)
			(xy 167.352016 -113.217853) (xy 167.359771 -113.163914) (xy 167.375123 -113.111627) (xy 167.397759 -113.062058)
			(xy 167.427219 -113.016214) (xy 167.462903 -112.975028) (xy 167.504085 -112.93934) (xy 167.549926 -112.909876)
			(xy 167.599494 -112.887235) (xy 167.651779 -112.871879) (xy 167.705717 -112.864119) (xy 167.732964 -112.86363)
			(xy 167.750076 -112.863821) (xy 167.784163 -112.866874) (xy 167.801036 -112.869726) (xy 167.812364 -112.871141)
			(xy 167.834379 -112.86522) (xy 167.843454 -112.858296) (xy 167.867838 -112.837214) (xy 167.876242 -112.829215)
			(xy 167.885383 -112.807921) (xy 167.885364 -112.79632) (xy 167.884856 -112.776508) (xy 167.884856 -111.912908)
			(xy 167.885364 -111.893604) (xy 167.885322 -111.882013) (xy 167.87621 -111.860725) (xy 167.867838 -111.85271)
			(xy 167.843454 -111.831882) (xy 167.834443 -111.824967) (xy 167.812556 -111.81902) (xy 167.80129 -111.820452)
			(xy 167.784356 -111.823332) (xy 167.75014 -111.826384) (xy 167.732964 -111.826548) (xy 167.705717 -111.825979)
			(xy 167.651779 -111.81822) (xy 167.599494 -111.802863) (xy 167.549927 -111.780222) (xy 167.504086 -111.750758)
			(xy 167.462904 -111.71507) (xy 167.42722 -111.673885) (xy 167.397761 -111.628041) (xy 167.375125 -111.578472)
			(xy 167.359773 -111.526186) (xy 167.352018 -111.472247) (xy 167.352018 -111.417753) (xy 167.359773 -111.363814)
			(xy 167.375125 -111.311528) (xy 167.397761 -111.261959) (xy 167.42722 -111.216115) (xy 167.462904 -111.17493)
			(xy 167.504086 -111.139242) (xy 167.549927 -111.109778) (xy 167.599494 -111.087137) (xy 167.651779 -111.07178)
			(xy 167.705717 -111.064021) (xy 167.732964 -111.063532) (xy 167.759942 -111.063963) (xy 167.813362 -111.071553)
			(xy 167.865178 -111.086599) (xy 167.914354 -111.108802) (xy 167.959908 -111.137717) (xy 168.00093 -111.172766)
			(xy 168.036599 -111.21325) (xy 168.066204 -111.25836) (xy 168.089151 -111.307193) (xy 168.104984 -111.358774)
			(xy 168.109646 -111.38535) (xy 168.109646 -111.385604) (xy 168.111856 -111.395864) (xy 168.12327 -111.413449)
			(xy 168.131744 -111.41964) (xy 168.203118 -111.467138) (xy 168.223692 -111.470694) (xy 168.234106 -111.468154)
			(xy 168.260871 -111.462072) (xy 168.315373 -111.455576) (xy 168.342818 -111.4552) (xy 168.370136 -111.455594)
			(xy 168.424384 -111.462083) (xy 168.451022 -111.468154) (xy 168.451276 -111.468154) (xy 168.461504 -111.470034)
			(xy 168.481954 -111.466348) (xy 168.4909 -111.461042) (xy 168.562528 -111.413544) (xy 168.573704 -111.396018)
			(xy 168.575482 -111.38535) (xy 168.580106 -111.358771) (xy 168.595967 -111.307204) (xy 168.618935 -111.258387)
			(xy 168.648553 -111.213293) (xy 168.684229 -111.172822) (xy 168.725251 -111.137781) (xy 168.770801 -111.108869)
			(xy 168.81997 -111.086664) (xy 168.871777 -111.071608) (xy 168.925189 -111.064001) (xy 168.952164 -111.063532)
			(xy 168.979534 -111.064011) (xy 169.033713 -111.071825) (xy 169.086216 -111.08731) (xy 169.135963 -111.110149)
			(xy 169.18193 -111.139872) (xy 169.202862 -111.157512) (xy 169.203116 -111.157766) (xy 169.210188 -111.163373)
			(xy 169.227116 -111.169606) (xy 169.236136 -111.169958) (xy 169.303192 -111.169958) (xy 169.31221 -111.169606)
			(xy 169.329127 -111.163356) (xy 169.336212 -111.157766) (xy 169.336212 -111.157512) (xy 169.336466 -111.157512)
			(xy 169.357402 -111.139877) (xy 169.403373 -111.110164) (xy 169.45312 -111.087327) (xy 169.50562 -111.071835)
			(xy 169.559795 -111.064006) (xy 169.587164 -111.063532) (xy 169.604276 -111.063723) (xy 169.638363 -111.066776)
			(xy 169.655236 -111.069628) (xy 169.666564 -111.071042) (xy 169.688579 -111.065122) (xy 169.697654 -111.058198)
			(xy 169.722038 -111.037116) (xy 169.730441 -111.029116) (xy 169.739583 -111.007823) (xy 169.739564 -110.996222)
			(xy 169.739056 -110.97641) (xy 169.739056 -110.11281) (xy 169.739564 -110.093506) (xy 169.739521 -110.081915)
			(xy 169.73041 -110.060627) (xy 169.722038 -110.052612) (xy 169.697654 -110.031784) (xy 169.688643 -110.024869)
			(xy 169.666756 -110.018922) (xy 169.65549 -110.020354) (xy 169.638556 -110.023234) (xy 169.60434 -110.026286)
			(xy 169.587164 -110.02645) (xy 169.559792 -110.026017) (xy 169.505611 -110.018193) (xy 169.453107 -110.002697)
			(xy 169.403361 -109.979848) (xy 169.357396 -109.950115) (xy 169.336466 -109.93247) (xy 169.336212 -109.932216)
			(xy 169.329125 -109.92663) (xy 169.312209 -109.920383) (xy 169.303192 -109.920024) (xy 169.236136 -109.920024)
			(xy 169.22712 -109.920393) (xy 169.210203 -109.926632) (xy 169.203116 -109.932216) (xy 169.203116 -109.93247)
			(xy 169.202862 -109.93247) (xy 169.181914 -109.950089) (xy 169.135946 -109.979805) (xy 169.086202 -110.002645)
			(xy 169.033705 -110.018141) (xy 168.979532 -110.025974) (xy 168.952164 -110.02645) (xy 168.925155 -110.026017)
			(xy 168.871677 -110.018406) (xy 168.819808 -110.003328) (xy 168.770584 -109.981083) (xy 168.72499 -109.952117)
			(xy 168.683938 -109.917009) (xy 168.648249 -109.876462) (xy 168.618637 -109.831285) (xy 168.595693 -109.782383)
			(xy 168.579877 -109.730733) (xy 168.575228 -109.704124) (xy 168.573704 -109.693456) (xy 168.562274 -109.675676)
			(xy 168.48201 -109.622336) (xy 168.461436 -109.61878) (xy 168.451022 -109.62132) (xy 168.424377 -109.627323)
			(xy 168.370129 -109.633686) (xy 168.342818 -109.63402) (xy 168.315436 -109.63364) (xy 168.26106 -109.627149)
			(xy 168.23436 -109.621066) (xy 168.223946 -109.618526) (xy 168.203372 -109.622082) (xy 168.122854 -109.675676)
			(xy 168.111424 -109.693456) (xy 168.1099 -109.704124) (xy 168.105251 -109.73073) (xy 168.089417 -109.782367)
			(xy 168.066461 -109.831256) (xy 168.036842 -109.87642) (xy 168.001152 -109.916958) (xy 167.960103 -109.952059)
			(xy 167.914515 -109.981022) (xy 167.865299 -110.003268) (xy 167.813439 -110.018354) (xy 167.759969 -110.025978)
			(xy 167.732964 -110.02645) (xy 167.705717 -110.025877) (xy 167.65178 -110.018118) (xy 167.599495 -110.002761)
			(xy 167.549928 -109.98012) (xy 167.504087 -109.950656) (xy 167.462906 -109.914969) (xy 167.427222 -109.873784)
			(xy 167.397762 -109.827941) (xy 167.375126 -109.778371) (xy 167.359775 -109.726085) (xy 167.35202 -109.672147)
			(xy 167.35202 -109.617653) (xy 167.359775 -109.563715) (xy 167.375126 -109.511429) (xy 167.397762 -109.461859)
			(xy 167.427222 -109.416016) (xy 167.462906 -109.374831) (xy 167.504087 -109.339144) (xy 167.549928 -109.30968)
			(xy 167.599495 -109.287039) (xy 167.65178 -109.271682) (xy 167.705717 -109.263923) (xy 167.732964 -109.263434)
			(xy 167.750076 -109.263625) (xy 167.784163 -109.266678) (xy 167.801036 -109.26953) (xy 167.812364 -109.270944)
			(xy 167.834379 -109.265024) (xy 167.843454 -109.2581) (xy 167.867838 -109.237018) (xy 167.87624 -109.229017)
			(xy 167.885383 -109.207724) (xy 167.885364 -109.196124) (xy 167.884856 -109.176312) (xy 167.884856 -108.312712)
			(xy 167.885364 -108.293408) (xy 167.88532 -108.281817) (xy 167.87621 -108.260529) (xy 167.867838 -108.252514)
			(xy 167.843454 -108.231686) (xy 167.834443 -108.224771) (xy 167.812556 -108.218824) (xy 167.80129 -108.220256)
			(xy 167.784356 -108.223136) (xy 167.75014 -108.226188) (xy 167.732964 -108.226352) (xy 167.705718 -108.225775)
			(xy 167.65178 -108.218016) (xy 167.599496 -108.202659) (xy 167.549929 -108.180019) (xy 167.504088 -108.150555)
			(xy 167.462907 -108.114867) (xy 167.427224 -108.073683) (xy 167.397764 -108.02784) (xy 167.375128 -107.978271)
			(xy 167.359777 -107.925985) (xy 167.352022 -107.872046) (xy 167.352022 -107.817554) (xy 167.359777 -107.763615)
			(xy 167.375128 -107.711329) (xy 167.397764 -107.66176) (xy 167.427224 -107.615917) (xy 167.462907 -107.574733)
			(xy 167.504088 -107.539045) (xy 167.549929 -107.509581) (xy 167.599496 -107.486941) (xy 167.65178 -107.471584)
			(xy 167.705718 -107.463825) (xy 167.732964 -107.463336) (xy 167.759942 -107.463764) (xy 167.813362 -107.471354)
			(xy 167.865178 -107.4864) (xy 167.914355 -107.508603) (xy 167.959909 -107.537518) (xy 168.000931 -107.572568)
			(xy 168.0366 -107.613053) (xy 168.066205 -107.658163) (xy 168.089152 -107.706996) (xy 168.104984 -107.758578)
			(xy 168.109646 -107.785154) (xy 168.109646 -107.785408) (xy 168.111854 -107.795669) (xy 168.123269 -107.813253)
			(xy 168.131744 -107.819444) (xy 168.203118 -107.866942) (xy 168.223692 -107.870498) (xy 168.234106 -107.867958)
			(xy 168.260871 -107.861876) (xy 168.315373 -107.85538) (xy 168.342818 -107.855004) (xy 168.370136 -107.855398)
			(xy 168.424384 -107.861887) (xy 168.451022 -107.867958) (xy 168.451276 -107.867958) (xy 168.461504 -107.869837)
			(xy 168.481954 -107.866151) (xy 168.4909 -107.860846) (xy 168.562528 -107.813348) (xy 168.573704 -107.795822)
			(xy 168.575482 -107.785154) (xy 168.580109 -107.758575) (xy 168.595969 -107.707009) (xy 168.618938 -107.658192)
			(xy 168.648555 -107.613097) (xy 168.68423 -107.572626) (xy 168.725252 -107.537585) (xy 168.770801 -107.508673)
			(xy 168.81997 -107.486468) (xy 168.871777 -107.471412) (xy 168.925189 -107.463805) (xy 168.952164 -107.463336)
			(xy 168.979534 -107.463814) (xy 169.033713 -107.471628) (xy 169.086216 -107.487114) (xy 169.135963 -107.509953)
			(xy 169.18193 -107.539675) (xy 169.202862 -107.557316) (xy 169.203116 -107.55757) (xy 169.210188 -107.563178)
			(xy 169.227116 -107.56941) (xy 169.236136 -107.569762) (xy 169.303192 -107.569762) (xy 169.312209 -107.569409)
			(xy 169.329127 -107.563159) (xy 169.336212 -107.55757) (xy 169.336212 -107.557316) (xy 169.336466 -107.557316)
			(xy 169.357402 -107.539682) (xy 169.403374 -107.509969) (xy 169.45312 -107.487132) (xy 169.50562 -107.471639)
			(xy 169.559795 -107.46381) (xy 169.587164 -107.463336) (xy 169.604276 -107.463527) (xy 169.638363 -107.46658)
			(xy 169.655236 -107.469432) (xy 169.666564 -107.470845) (xy 169.688579 -107.464926) (xy 169.697654 -107.458002)
			(xy 169.722038 -107.43692) (xy 169.730439 -107.428918) (xy 169.739582 -107.407626) (xy 169.739564 -107.396026)
			(xy 169.739056 -107.376214) (xy 169.739056 -106.512614) (xy 169.739564 -106.49331) (xy 169.739519 -106.481719)
			(xy 169.73041 -106.460431) (xy 169.722038 -106.452416) (xy 169.697654 -106.431588) (xy 169.688642 -106.424674)
			(xy 169.666756 -106.418726) (xy 169.65549 -106.420158) (xy 169.638556 -106.423038) (xy 169.60434 -106.42609)
			(xy 169.587164 -106.426254) (xy 169.559792 -106.42582) (xy 169.505612 -106.417996) (xy 169.453108 -106.4025)
			(xy 169.403361 -106.379651) (xy 169.357396 -106.349919) (xy 169.336466 -106.332274) (xy 169.329608 -106.326178)
			(xy 169.31259 -106.319828) (xy 169.227246 -106.319828) (xy 169.209974 -106.326432) (xy 169.203116 -106.332528)
			(xy 169.182192 -106.350178) (xy 169.136221 -106.379897) (xy 169.086472 -106.402735) (xy 169.033968 -106.418223)
			(xy 168.979788 -106.426041) (xy 168.952418 -106.426508) (xy 168.952164 -106.426508) (xy 168.925158 -106.426026)
			(xy 168.871684 -106.418417) (xy 168.819818 -106.403341) (xy 168.770597 -106.381101) (xy 168.725005 -106.35214)
			(xy 168.683954 -106.317038) (xy 168.648264 -106.276497) (xy 168.61865 -106.231327) (xy 168.595702 -106.182432)
			(xy 168.579881 -106.130789) (xy 168.575228 -106.104182) (xy 168.573704 -106.093514) (xy 168.562274 -106.075734)
			(xy 168.48201 -106.022394) (xy 168.461436 -106.018838) (xy 168.451022 -106.021378) (xy 168.424384 -106.027447)
			(xy 168.370136 -106.033937) (xy 168.342818 -106.034332) (xy 168.31543 -106.033889) (xy 168.261054 -106.027267)
			(xy 168.23436 -106.021124) (xy 168.223946 -106.018584) (xy 168.203372 -106.02214) (xy 168.122854 -106.075734)
			(xy 168.111424 -106.093514) (xy 168.1099 -106.104182) (xy 168.105219 -106.130782) (xy 168.089391 -106.182419)
			(xy 168.06644 -106.231308) (xy 168.036825 -106.276474) (xy 168.001139 -106.317012) (xy 167.960093 -106.352114)
			(xy 167.914508 -106.381078) (xy 167.865294 -106.403325) (xy 167.813436 -106.418412) (xy 167.759968 -106.426036)
			(xy 167.732964 -106.426508) (xy 167.705714 -106.42602) (xy 167.651771 -106.418259) (xy 167.59948 -106.402901)
			(xy 167.549907 -106.380258) (xy 167.504062 -106.35079) (xy 167.462876 -106.315099) (xy 167.427188 -106.27391)
			(xy 167.397725 -106.228061) (xy 167.375087 -106.178486) (xy 167.359733 -106.126194) (xy 167.351978 -106.07225)
			(xy 167.351978 -106.01775) (xy 167.359733 -105.963806) (xy 167.375087 -105.911514) (xy 167.397725 -105.861939)
			(xy 167.427188 -105.81609) (xy 167.462876 -105.774901) (xy 167.504062 -105.73921) (xy 167.549907 -105.709742)
			(xy 167.59948 -105.687099) (xy 167.651771 -105.671741) (xy 167.705714 -105.66398) (xy 167.732964 -105.663492)
			(xy 167.750076 -105.663684) (xy 167.784163 -105.666736) (xy 167.801036 -105.669588) (xy 167.812364 -105.670988)
			(xy 167.834377 -105.665075) (xy 167.843454 -105.658158) (xy 167.867838 -105.637076) (xy 167.87626 -105.629093)
			(xy 167.885391 -105.607786) (xy 167.885364 -105.596182) (xy 167.884856 -105.57637) (xy 167.884856 -104.71277)
			(xy 167.885364 -104.693466) (xy 167.885344 -104.681873) (xy 167.876217 -104.660585) (xy 167.867838 -104.652572)
			(xy 167.843454 -104.631744) (xy 167.834438 -104.624835) (xy 167.812555 -104.618882) (xy 167.80129 -104.620314)
			(xy 167.784356 -104.623195) (xy 167.75014 -104.626246) (xy 167.732964 -104.62641) (xy 167.705715 -104.625918)
			(xy 167.651771 -104.618157) (xy 167.599481 -104.602799) (xy 167.549908 -104.580156) (xy 167.504063 -104.550689)
			(xy 167.462877 -104.514997) (xy 167.42719 -104.473808) (xy 167.397727 -104.42796) (xy 167.375088 -104.378385)
			(xy 167.359735 -104.326094) (xy 167.35198 -104.272149) (xy 167.35198 -104.217651) (xy 167.359735 -104.163706)
			(xy 167.375088 -104.111415) (xy 167.397727 -104.06184) (xy 167.42719 -104.015992) (xy 167.462877 -103.974803)
			(xy 167.504063 -103.939111) (xy 167.549908 -103.909644) (xy 167.599481 -103.887001) (xy 167.651771 -103.871643)
			(xy 167.705715 -103.863882) (xy 167.732964 -103.863394) (xy 167.759941 -103.863857) (xy 167.813358 -103.871446)
			(xy 167.865171 -103.88649) (xy 167.914345 -103.90869) (xy 167.959898 -103.937602) (xy 168.000919 -103.972648)
			(xy 168.036589 -104.013127) (xy 168.066195 -104.058232) (xy 168.089145 -104.107061) (xy 168.104981 -104.158638)
			(xy 168.109646 -104.185212) (xy 168.109646 -104.185466) (xy 168.111827 -104.195734) (xy 168.123262 -104.213315)
			(xy 168.131744 -104.219502) (xy 168.203118 -104.267) (xy 168.223692 -104.270556) (xy 168.234106 -104.268016)
			(xy 168.260865 -104.261873) (xy 168.315367 -104.255246) (xy 168.342818 -104.254808) (xy 168.370142 -104.255265)
			(xy 168.424391 -104.261885) (xy 168.451022 -104.268016) (xy 168.451276 -104.268016) (xy 168.461505 -104.269886)
			(xy 168.481953 -104.266205) (xy 168.4909 -104.260904) (xy 168.562528 -104.213406) (xy 168.573704 -104.19588)
			(xy 168.575482 -104.185212) (xy 168.580153 -104.158641) (xy 168.596006 -104.107075) (xy 168.618967 -104.058257)
			(xy 168.648578 -104.013162) (xy 168.684248 -103.97269) (xy 168.725265 -103.937647) (xy 168.770811 -103.908734)
			(xy 168.819977 -103.886527) (xy 168.871781 -103.87147) (xy 168.92519 -103.863863) (xy 168.952164 -103.863394)
			(xy 168.979533 -103.863883) (xy 169.033711 -103.871695) (xy 169.086214 -103.887179) (xy 169.135961 -103.910016)
			(xy 169.181929 -103.939735) (xy 169.202862 -103.957374) (xy 169.203116 -103.957628) (xy 169.210192 -103.963231)
			(xy 169.227117 -103.969467) (xy 169.236136 -103.96982) (xy 169.303192 -103.96982) (xy 169.312208 -103.969455)
			(xy 169.329125 -103.963212) (xy 169.336212 -103.957628) (xy 169.336212 -103.957374) (xy 169.336466 -103.957374)
			(xy 169.357397 -103.939733) (xy 169.40337 -103.910023) (xy 169.453118 -103.887187) (xy 169.505619 -103.871697)
			(xy 169.559795 -103.863868) (xy 169.587164 -103.863394) (xy 169.604276 -103.863586) (xy 169.638363 -103.866638)
			(xy 169.655236 -103.86949) (xy 169.666564 -103.87089) (xy 169.688577 -103.864977) (xy 169.697654 -103.85806)
			(xy 169.722038 -103.836978) (xy 169.730459 -103.828994) (xy 169.739591 -103.807688) (xy 169.739564 -103.796084)
			(xy 169.739056 -103.776272) (xy 169.739056 -102.912672) (xy 169.739564 -102.893368) (xy 169.739543 -102.881775)
			(xy 169.730417 -102.860487) (xy 169.722038 -102.852474) (xy 169.697654 -102.831646) (xy 169.688638 -102.824737)
			(xy 169.666755 -102.818784) (xy 169.65549 -102.820216) (xy 169.638556 -102.823097) (xy 169.60434 -102.826148)
			(xy 169.587164 -102.826312) (xy 169.559793 -102.825864) (xy 169.505613 -102.818041) (xy 169.45311 -102.802548)
			(xy 169.403364 -102.779702) (xy 169.357397 -102.749975) (xy 169.336466 -102.732332) (xy 169.329608 -102.726236)
			(xy 169.31259 -102.719886) (xy 169.227246 -102.719886) (xy 169.209974 -102.72649) (xy 169.203116 -102.732586)
			(xy 169.182199 -102.750245) (xy 169.136225 -102.779961) (xy 169.086475 -102.802797) (xy 169.033969 -102.818282)
			(xy 168.979789 -102.826099) (xy 168.952418 -102.826566) (xy 168.952164 -102.826566) (xy 168.925156 -102.82612)
			(xy 168.871679 -102.818509) (xy 168.819811 -102.803431) (xy 168.770588 -102.781188) (xy 168.724994 -102.752223)
			(xy 168.683943 -102.717117) (xy 168.648253 -102.676571) (xy 168.61864 -102.631397) (xy 168.595696 -102.582496)
			(xy 168.579878 -102.530849) (xy 168.575228 -102.50424) (xy 168.573704 -102.493572) (xy 168.562274 -102.475792)
			(xy 168.48201 -102.422452) (xy 168.461436 -102.418896) (xy 168.451022 -102.421436) (xy 168.424377 -102.427439)
			(xy 168.370129 -102.433802) (xy 168.342818 -102.434136) (xy 168.315436 -102.433755) (xy 168.26106 -102.427265)
			(xy 168.23436 -102.421182) (xy 168.223946 -102.418642) (xy 168.203372 -102.422198) (xy 168.122854 -102.475792)
			(xy 168.111424 -102.493572) (xy 168.1099 -102.50424) (xy 168.105187 -102.530834) (xy 168.089364 -102.582471)
			(xy 168.066418 -102.631361) (xy 168.036808 -102.676527) (xy 168.001126 -102.717066) (xy 167.960083 -102.752169)
			(xy 167.914501 -102.781134) (xy 167.86529 -102.803382) (xy 167.813433 -102.818469) (xy 167.759967 -102.826093)
			(xy 167.732964 -102.826566) (xy 167.705711 -102.826162) (xy 167.651762 -102.8184) (xy 167.599465 -102.80304)
			(xy 167.549887 -102.780395) (xy 167.504036 -102.750924) (xy 167.462846 -102.715229) (xy 167.427154 -102.674035)
			(xy 167.397688 -102.628181) (xy 167.375047 -102.578601) (xy 167.359692 -102.526303) (xy 167.351936 -102.472353)
			(xy 163.529404 -102.472353) (xy 163.580982 -102.485837) (xy 163.632311 -102.507649) (xy 163.679917 -102.536703)
			(xy 163.722785 -102.572378) (xy 163.760002 -102.613915) (xy 163.790775 -102.660428) (xy 163.814447 -102.710925)
			(xy 163.830515 -102.764332) (xy 163.838635 -102.819508) (xy 163.839144 -102.847394) (xy 163.838635 -102.87528)
			(xy 163.830515 -102.930456) (xy 163.814447 -102.983863) (xy 163.790775 -103.03436) (xy 163.760002 -103.080873)
			(xy 163.722785 -103.12241) (xy 163.679917 -103.158085) (xy 163.632311 -103.187139) (xy 163.580982 -103.208951)
			(xy 163.527025 -103.223057) (xy 163.471588 -103.229157) (xy 163.415854 -103.22712) (xy 163.361011 -103.21699)
			(xy 163.308227 -103.198983) (xy 163.258627 -103.173482) (xy 163.213269 -103.141031) (xy 163.17312 -103.102322)
			(xy 163.139034 -103.058179) (xy 163.111738 -103.009544) (xy 163.091815 -102.957453) (xy 163.079689 -102.903016)
			(xy 163.075618 -102.847394) (xy 154.86031 -102.847394) (xy 154.859516 -102.850097) (xy 154.836875 -102.899675)
			(xy 154.807407 -102.945527) (xy 154.771715 -102.986718) (xy 154.730523 -103.02241) (xy 154.684672 -103.051876)
			(xy 154.635093 -103.074518) (xy 154.582797 -103.089873) (xy 154.528848 -103.097629) (xy 154.501596 -103.098092)
			(xy 154.486867 -103.09794) (xy 154.457497 -103.095654) (xy 154.442922 -103.09352) (xy 154.431947 -103.092411)
			(xy 154.410757 -103.09846) (xy 154.402028 -103.105204) (xy 154.343608 -103.155242) (xy 154.335614 -103.162841)
			(xy 154.326379 -103.182837) (xy 154.325828 -103.19385) (xy 154.325828 -103.498142) (xy 154.326334 -103.509165)
			(xy 154.335575 -103.529182) (xy 154.343608 -103.53675) (xy 154.410664 -103.594154) (xy 154.431746 -103.60025)
			(xy 154.442922 -103.598472) (xy 154.457497 -103.596341) (xy 154.486867 -103.594051) (xy 154.501596 -103.5939)
			(xy 154.52885 -103.594347) (xy 154.582802 -103.602104) (xy 154.635102 -103.61746) (xy 154.684683 -103.640102)
			(xy 154.730538 -103.669571) (xy 154.771732 -103.705265) (xy 154.807427 -103.746459) (xy 154.836896 -103.792313)
			(xy 154.859539 -103.841895) (xy 154.874895 -103.894194) (xy 154.882653 -103.948146) (xy 154.882653 -104.002654)
			(xy 154.874895 -104.056606) (xy 154.859539 -104.108905) (xy 154.836896 -104.158487) (xy 154.807427 -104.204341)
			(xy 154.772281 -104.244902) (xy 160.769552 -104.244902) (xy 160.773623 -104.18928) (xy 160.785749 -104.134843)
			(xy 160.805672 -104.082752) (xy 160.832968 -104.034117) (xy 160.867054 -103.989974) (xy 160.907203 -103.951265)
			(xy 160.952561 -103.918814) (xy 161.002161 -103.893313) (xy 161.054945 -103.875306) (xy 161.109788 -103.865176)
			(xy 161.165522 -103.863139) (xy 161.220959 -103.869239) (xy 161.274916 -103.883345) (xy 161.326245 -103.905157)
			(xy 161.373851 -103.934211) (xy 161.416719 -103.969886) (xy 161.453936 -104.011423) (xy 161.484709 -104.057936)
			(xy 161.508381 -104.108433) (xy 161.524449 -104.16184) (xy 161.532569 -104.217016) (xy 161.533078 -104.244902)
			(xy 161.532569 -104.272788) (xy 161.524449 -104.327964) (xy 161.508381 -104.381371) (xy 161.484709 -104.431868)
			(xy 161.453936 -104.478381) (xy 161.416719 -104.519918) (xy 161.373851 -104.555593) (xy 161.326245 -104.584647)
			(xy 161.274916 -104.606459) (xy 161.220959 -104.620565) (xy 161.165522 -104.626665) (xy 161.109788 -104.624628)
			(xy 161.054945 -104.614498) (xy 161.002161 -104.596491) (xy 160.952561 -104.57099) (xy 160.907203 -104.538539)
			(xy 160.867054 -104.49983) (xy 160.832968 -104.455687) (xy 160.805672 -104.407052) (xy 160.785749 -104.354961)
			(xy 160.773623 -104.300524) (xy 160.769552 -104.244902) (xy 154.772281 -104.244902) (xy 154.771732 -104.245535)
			(xy 154.730538 -104.281229) (xy 154.684683 -104.310698) (xy 154.635102 -104.33334) (xy 154.582802 -104.348696)
			(xy 154.52885 -104.356453) (xy 154.501596 -104.356916) (xy 154.47569 -104.356423) (xy 154.424355 -104.3494)
			(xy 154.374442 -104.335496) (xy 154.326869 -104.314967) (xy 154.282511 -104.288192) (xy 154.242182 -104.255661)
			(xy 154.206626 -104.217974) (xy 154.191208 -104.19715) (xy 154.185393 -104.189811) (xy 154.169769 -104.17952)
			(xy 154.160728 -104.177084) (xy 154.130756 -104.170226) (xy 154.121455 -104.16857) (xy 154.102797 -104.171424)
			(xy 154.094434 -104.175814) (xy 154.068443 -104.190044) (xy 154.013567 -104.212403) (xy 153.956265 -104.227496)
			(xy 153.897495 -104.235072) (xy 153.867866 -104.235504) (xy 153.838196 -104.235076) (xy 153.779347 -104.227467)
			(xy 153.721978 -104.212303) (xy 153.667055 -104.189841) (xy 153.641044 -104.17556) (xy 153.632667 -104.171212)
			(xy 153.614024 -104.168362) (xy 153.604722 -104.169972) (xy 153.57475 -104.17683) (xy 153.565652 -104.179131)
			(xy 153.549995 -104.189458) (xy 153.54427 -104.196896) (xy 153.528835 -104.217744) (xy 153.493278 -104.255511)
			(xy 153.452931 -104.288111) (xy 153.40854 -104.314945) (xy 153.360922 -104.335516) (xy 153.310956 -104.349446)
			(xy 153.259564 -104.356478) (xy 153.233628 -104.356916) (xy 153.206374 -104.356439) (xy 153.152422 -104.348685)
			(xy 153.100121 -104.333332) (xy 153.050539 -104.310691) (xy 153.004683 -104.281225) (xy 152.963488 -104.245532)
			(xy 152.927792 -104.204339) (xy 152.898322 -104.158486) (xy 152.875678 -104.108905) (xy 152.860321 -104.056606)
			(xy 152.852563 -104.002654) (xy 152.852563 -103.948146) (xy 152.860321 -103.894194) (xy 152.875678 -103.841895)
			(xy 152.898322 -103.792314) (xy 152.927792 -103.746461) (xy 152.963488 -103.705268) (xy 153.004683 -103.669575)
			(xy 153.050539 -103.640109) (xy 153.100121 -103.617468) (xy 153.152422 -103.602115) (xy 153.206374 -103.594361)
			(xy 153.233628 -103.5939) (xy 153.234136 -103.5939) (xy 153.248865 -103.594047) (xy 153.278236 -103.596336)
			(xy 153.29281 -103.598472) (xy 153.303785 -103.599602) (xy 153.324977 -103.59354) (xy 153.333704 -103.586788)
			(xy 153.392124 -103.53675) (xy 153.400127 -103.52916) (xy 153.409356 -103.509156) (xy 153.409904 -103.498142)
			(xy 153.409904 -103.19385) (xy 153.409337 -103.182835) (xy 153.400138 -103.162818) (xy 153.392124 -103.155242)
			(xy 153.325068 -103.097838) (xy 153.303986 -103.091742) (xy 153.29281 -103.09352) (xy 153.278235 -103.095648)
			(xy 153.248865 -103.09794) (xy 153.234136 -103.098092) (xy 153.233628 -103.098092) (xy 153.206373 -103.097663)
			(xy 153.152416 -103.089909) (xy 153.100113 -103.074555) (xy 153.050527 -103.051913) (xy 153.004669 -103.022444)
			(xy 152.963471 -102.986749) (xy 152.927773 -102.945554) (xy 152.898301 -102.899697) (xy 152.875655 -102.850113)
			(xy 152.860297 -102.797811) (xy 152.852539 -102.743855) (xy 146.344274 -102.743855) (xy 145.448274 -103.639874)
			(xy 145.424718 -103.662781) (xy 145.37334 -103.703745) (xy 145.317698 -103.738698) (xy 145.258493 -103.767202)
			(xy 145.196469 -103.788899) (xy 145.132406 -103.803515) (xy 145.067109 -103.810866) (xy 145.034254 -103.811324)
			(xy 114.50447 -103.811324) (xy 114.471617 -103.810859) (xy 114.406324 -103.803493) (xy 114.342266 -103.788869)
			(xy 114.280245 -103.76717) (xy 114.221042 -103.738669) (xy 114.165399 -103.703723) (xy 114.114015 -103.662771)
			(xy 114.09045 -103.639874) (xy 108.159804 -97.709228) (xy 108.152393 -97.702401) (xy 108.133802 -97.694673)
			(xy 108.123736 -97.694242) (xy 106.836464 -97.694242) (xy 106.807254 -97.721674) (xy 106.805984 -97.74174)
			(xy 106.803324 -97.772674) (xy 106.789187 -97.833127) (xy 106.765445 -97.890492) (xy 106.732724 -97.943254)
			(xy 106.712766 -97.967038) (xy 106.712512 -97.967292) (xy 106.706924 -97.974378) (xy 106.700678 -97.991295)
			(xy 106.70032 -98.000312) (xy 106.70032 -98.067368) (xy 106.700688 -98.076384) (xy 106.706928 -98.093301)
			(xy 106.712512 -98.100388) (xy 106.712766 -98.100388) (xy 106.712766 -98.100642) (xy 106.730386 -98.121589)
			(xy 106.760102 -98.167558) (xy 106.782942 -98.217301) (xy 106.798437 -98.269799) (xy 106.80627 -98.323972)
			(xy 106.806746 -98.35134) (xy 106.80626 -98.378591) (xy 106.798504 -98.432539) (xy 106.783149 -98.484834)
			(xy 106.760507 -98.534411) (xy 106.731041 -98.580261) (xy 106.69535 -98.621452) (xy 106.654159 -98.657143)
			(xy 106.608309 -98.686609) (xy 106.558732 -98.709251) (xy 106.506437 -98.724606) (xy 106.452489 -98.732362)
			(xy 106.397987 -98.732362) (xy 106.344039 -98.724606) (xy 106.291744 -98.709251) (xy 106.242167 -98.686609)
			(xy 106.196317 -98.657143) (xy 106.155126 -98.621452) (xy 106.119435 -98.580261) (xy 106.089969 -98.534411)
			(xy 106.067327 -98.484834) (xy 106.051972 -98.432539) (xy 106.044216 -98.378591) (xy 106.04373 -98.35134)
			(xy 106.044212 -98.32397) (xy 106.052025 -98.269792) (xy 106.06751 -98.217288) (xy 106.090348 -98.167541)
			(xy 106.12007 -98.121574) (xy 106.13771 -98.100642) (xy 106.137964 -98.100388) (xy 106.143569 -98.093315)
			(xy 106.149803 -98.076387) (xy 106.150156 -98.067368) (xy 106.150156 -98.000312) (xy 106.149803 -97.991295)
			(xy 106.143553 -97.974377) (xy 106.137964 -97.967292) (xy 106.13771 -97.967292) (xy 106.13771 -97.966784)
			(xy 106.117771 -97.943028) (xy 106.0851 -97.890314) (xy 106.061371 -97.833015) (xy 106.047207 -97.772636)
			(xy 106.044492 -97.74174) (xy 106.043222 -97.721674) (xy 106.014012 -97.694242) (xy 104.636316 -97.694242)
			(xy 104.626246 -97.693823) (xy 104.607647 -97.6861) (xy 104.600248 -97.679256) (xy 104.092502 -97.17151)
			(xy 104.085094 -97.16468) (xy 104.066501 -97.156954) (xy 104.056434 -97.156524) (xy 103.62311 -97.156524)
			(xy 103.596948 -97.17532) (xy 103.591614 -97.190814) (xy 103.583268 -97.213827) (xy 103.561487 -97.257669)
			(xy 103.534275 -97.298365) (xy 103.518462 -97.317052) (xy 103.518208 -97.317306) (xy 103.512614 -97.324387)
			(xy 103.506371 -97.341308) (xy 103.506016 -97.350326) (xy 103.506016 -97.417382) (xy 103.506378 -97.426398)
			(xy 103.512622 -97.443316) (xy 103.518208 -97.450402) (xy 103.518462 -97.450402) (xy 103.518462 -97.450656)
			(xy 103.536058 -97.471625) (xy 103.565786 -97.517586) (xy 103.588634 -97.567326) (xy 103.604135 -97.619823)
			(xy 103.611968 -97.673997) (xy 103.611973 -97.728734) (xy 103.604149 -97.782909) (xy 103.588659 -97.835409)
			(xy 103.565819 -97.885153) (xy 103.5361 -97.93112) (xy 103.518462 -97.952052) (xy 103.518208 -97.952306)
			(xy 103.512614 -97.959387) (xy 103.506371 -97.976308) (xy 103.506016 -97.985326) (xy 103.506016 -98.052382)
			(xy 103.506378 -98.061398) (xy 103.512622 -98.078316) (xy 103.518208 -98.085402) (xy 103.518462 -98.085402)
			(xy 103.518462 -98.085656) (xy 103.536088 -98.106599) (xy 103.565803 -98.152568) (xy 103.588642 -98.202313)
			(xy 103.604136 -98.254811) (xy 103.611967 -98.308985) (xy 103.612442 -98.336354) (xy 103.611956 -98.363605)
			(xy 103.6042 -98.417553) (xy 103.588845 -98.469848) (xy 103.566203 -98.519425) (xy 103.536737 -98.565275)
			(xy 103.501046 -98.606466) (xy 103.459855 -98.642157) (xy 103.414005 -98.671623) (xy 103.364428 -98.694265)
			(xy 103.312133 -98.70962) (xy 103.258185 -98.717376) (xy 103.203683 -98.717376) (xy 103.149735 -98.70962)
			(xy 103.09744 -98.694265) (xy 103.047863 -98.671623) (xy 103.002013 -98.642157) (xy 102.960822 -98.606466)
			(xy 102.925131 -98.565275) (xy 102.895665 -98.519425) (xy 102.873023 -98.469848) (xy 102.857668 -98.417553)
			(xy 102.849912 -98.363605) (xy 102.849426 -98.336354) (xy 102.849917 -98.308985) (xy 102.857728 -98.254806)
			(xy 102.873211 -98.202303) (xy 102.896047 -98.152556) (xy 102.925767 -98.106588) (xy 102.943406 -98.085656)
			(xy 102.94366 -98.085402) (xy 102.949259 -98.078324) (xy 102.955497 -98.0614) (xy 102.955852 -98.052382)
			(xy 102.955852 -97.985326) (xy 102.955493 -97.976309) (xy 102.949248 -97.959392) (xy 102.94366 -97.952306)
			(xy 102.943406 -97.952306) (xy 102.943406 -97.952052) (xy 102.925721 -97.931155) (xy 102.896 -97.885181)
			(xy 102.873158 -97.835428) (xy 102.857667 -97.782921) (xy 102.849843 -97.728738) (xy 102.849848 -97.673993)
			(xy 102.857681 -97.619811) (xy 102.873183 -97.567307) (xy 102.896033 -97.517558) (xy 102.925763 -97.471589)
			(xy 102.943406 -97.450656) (xy 102.94366 -97.450402) (xy 102.949259 -97.443324) (xy 102.955497 -97.4264)
			(xy 102.955852 -97.417382) (xy 102.955852 -97.350326) (xy 102.955493 -97.341309) (xy 102.949248 -97.324392)
			(xy 102.94366 -97.317306) (xy 102.943406 -97.317306) (xy 102.943406 -97.317052) (xy 102.925779 -97.29611)
			(xy 102.896065 -97.25014) (xy 102.873227 -97.200395) (xy 102.857733 -97.147897) (xy 102.849902 -97.093723)
			(xy 102.849426 -97.066354) (xy 102.84999 -97.037383) (xy 102.858788 -96.980111) (xy 102.866952 -96.952308)
			(xy 102.866952 -96.952054) (xy 102.869331 -96.943168) (xy 102.868232 -96.924819) (xy 102.860711 -96.908046)
			(xy 102.854506 -96.901254) (xy 100.467922 -94.51467) (xy 100.460873 -94.508112) (xy 100.443233 -94.500423)
			(xy 100.433632 -94.499684) (xy 100.40366 -94.498668) (xy 100.394767 -94.498671) (xy 100.377857 -94.504139)
			(xy 100.37064 -94.509336) (xy 100.350472 -94.524544) (xy 100.306868 -94.550045) (xy 100.260282 -94.569572)
			(xy 100.211526 -94.582782) (xy 100.161455 -94.589445) (xy 100.136198 -94.589854) (xy 100.109493 -94.58939)
			(xy 100.056607 -94.581927) (xy 100.005278 -94.567162) (xy 99.956511 -94.545382) (xy 99.911257 -94.517014)
			(xy 99.870402 -94.482611) (xy 99.834745 -94.442848) (xy 99.804981 -94.398499) (xy 99.781693 -94.350434)
			(xy 99.765336 -94.29959) (xy 99.75623 -94.246962) (xy 99.754944 -94.220284) (xy 99.754944 -94.22003)
			(xy 99.754124 -94.210321) (xy 99.746153 -94.192558) (xy 99.73945 -94.185486) (xy 99.68865 -94.13621)
			(xy 99.681284 -94.129751) (xy 99.66313 -94.122433) (xy 99.653344 -94.121986) (xy 99.34829 -94.121986)
			(xy 99.33792 -94.122468) (xy 99.318904 -94.13075) (xy 99.31146 -94.137988) (xy 99.253294 -94.199456)
			(xy 99.246436 -94.21876) (xy 99.246944 -94.229174) (xy 99.246944 -94.229428) (xy 99.247706 -94.251526)
			(xy 99.247706 -94.252034) (xy 99.247203 -94.279273) (xy 99.239417 -94.333194) (xy 99.22404 -94.385458)
			(xy 99.201384 -94.435003) (xy 99.171911 -94.480822) (xy 99.13622 -94.521982) (xy 99.095036 -94.557646)
			(xy 99.049198 -94.587088) (xy 98.999638 -94.609711) (xy 98.947363 -94.625053) (xy 98.893438 -94.632803)
			(xy 98.838958 -94.632803) (xy 98.785033 -94.625053) (xy 98.732758 -94.609711) (xy 98.683198 -94.587088)
			(xy 98.63736 -94.557646) (xy 98.596176 -94.521982) (xy 98.560485 -94.480822) (xy 98.531012 -94.435003)
			(xy 98.508356 -94.385458) (xy 98.492979 -94.333194) (xy 98.485193 -94.279273) (xy 98.48469 -94.252034)
			(xy 98.48469 -94.251526) (xy 98.485452 -94.229428) (xy 98.48596 -94.21876) (xy 98.479102 -94.199456)
			(xy 98.420936 -94.137988) (xy 98.413475 -94.130782) (xy 98.394465 -94.122526) (xy 98.384106 -94.121986)
			(xy 98.333306 -94.121986) (xy 98.323234 -94.122392) (xy 98.304635 -94.130124) (xy 98.297238 -94.136972)
			(xy 98.246438 -94.18828) (xy 98.239623 -94.195755) (xy 98.232037 -94.214491) (xy 98.231706 -94.224602)
			(xy 98.231706 -94.227904) (xy 98.23122 -94.255155) (xy 98.223464 -94.309103) (xy 98.208109 -94.361398)
			(xy 98.185467 -94.410975) (xy 98.156001 -94.456825) (xy 98.12031 -94.498016) (xy 98.079119 -94.533707)
			(xy 98.033269 -94.563173) (xy 97.983692 -94.585815) (xy 97.931397 -94.60117) (xy 97.877449 -94.608926)
			(xy 97.822947 -94.608926) (xy 97.768999 -94.60117) (xy 97.716704 -94.585815) (xy 97.667127 -94.563173)
			(xy 97.621277 -94.533707) (xy 97.580086 -94.498016) (xy 97.544395 -94.456825) (xy 97.514929 -94.410975)
			(xy 97.492287 -94.361398) (xy 97.476932 -94.309103) (xy 97.469176 -94.255155) (xy 97.46869 -94.227904)
			(xy 97.46869 -94.224602) (xy 97.46836 -94.214491) (xy 97.460768 -94.19576) (xy 97.453958 -94.18828)
			(xy 97.403158 -94.136972) (xy 97.39577 -94.130117) (xy 97.377161 -94.122407) (xy 97.36709 -94.121986)
			(xy 97.31629 -94.121986) (xy 97.30592 -94.122468) (xy 97.286904 -94.13075) (xy 97.27946 -94.137988)
			(xy 97.22866 -94.191836) (xy 97.221893 -94.199739) (xy 97.21481 -94.219279) (xy 97.214944 -94.229682)
			(xy 97.214944 -94.23019) (xy 97.215706 -94.253304) (xy 97.21522 -94.280555) (xy 97.207464 -94.334503)
			(xy 97.192109 -94.386798) (xy 97.169467 -94.436375) (xy 97.140001 -94.482225) (xy 97.10431 -94.523416)
			(xy 97.063119 -94.559107) (xy 97.017269 -94.588573) (xy 96.967692 -94.611215) (xy 96.915397 -94.62657)
			(xy 96.861449 -94.634326) (xy 96.806947 -94.634326) (xy 96.752999 -94.62657) (xy 96.700704 -94.611215)
			(xy 96.651127 -94.588573) (xy 96.605277 -94.559107) (xy 96.564086 -94.523416) (xy 96.528395 -94.482225)
			(xy 96.498929 -94.436375) (xy 96.476287 -94.386798) (xy 96.460932 -94.334503) (xy 96.453176 -94.280555)
			(xy 96.45269 -94.253304) (xy 96.453452 -94.229936) (xy 96.453452 -94.229682) (xy 96.453599 -94.219281)
			(xy 96.446496 -94.199745) (xy 96.439736 -94.191836) (xy 96.388936 -94.137988) (xy 96.381475 -94.130782)
			(xy 96.362465 -94.122526) (xy 96.352106 -94.121986) (xy 96.300544 -94.121986) (xy 96.290204 -94.122449)
			(xy 96.271191 -94.130577) (xy 96.263714 -94.137734) (xy 96.205802 -94.198694) (xy 96.19869 -94.218506)
			(xy 96.199198 -94.22892) (xy 96.199706 -94.24924) (xy 96.19922 -94.276491) (xy 96.191464 -94.330439)
			(xy 96.176109 -94.382734) (xy 96.153467 -94.432311) (xy 96.124001 -94.478161) (xy 96.08831 -94.519352)
			(xy 96.047119 -94.555043) (xy 96.001269 -94.584509) (xy 95.951692 -94.607151) (xy 95.899397 -94.622506)
			(xy 95.845449 -94.630262) (xy 95.790947 -94.630262) (xy 95.736999 -94.622506) (xy 95.684704 -94.607151)
			(xy 95.635127 -94.584509) (xy 95.589277 -94.555043) (xy 95.548086 -94.519352) (xy 95.512395 -94.478161)
			(xy 95.482929 -94.432311) (xy 95.460287 -94.382734) (xy 95.444932 -94.330439) (xy 95.437176 -94.276491)
			(xy 95.43669 -94.24924) (xy 95.437198 -94.22892) (xy 95.437706 -94.218506) (xy 95.430594 -94.198694)
			(xy 95.372682 -94.137734) (xy 95.365198 -94.13059) (xy 95.346188 -94.12247) (xy 95.335852 -94.121986)
			(xy 95.197422 -94.121986) (xy 95.18792 -94.122343) (xy 95.170203 -94.129206) (xy 95.156218 -94.142067)
			(xy 95.151702 -94.150434) (xy 95.138746 -94.175692) (xy 95.106494 -94.222402) (xy 95.067678 -94.263819)
			(xy 95.023155 -94.299029) (xy 94.973906 -94.327254) (xy 94.92102 -94.347872) (xy 94.865663 -94.360428)
			(xy 94.809056 -94.364644) (xy 94.752449 -94.360428) (xy 94.697092 -94.347872) (xy 94.644206 -94.327254)
			(xy 94.594957 -94.299029) (xy 94.550434 -94.263819) (xy 94.511618 -94.222402) (xy 94.479366 -94.175692)
			(xy 94.46641 -94.150434) (xy 94.461864 -94.142094) (xy 94.447866 -94.129275) (xy 94.43018 -94.122382)
			(xy 94.42069 -94.121986) (xy 89.707466 -94.121986) (xy 89.697458 -94.12246) (xy 89.678968 -94.130128)
			(xy 89.664817 -94.144285) (xy 89.657156 -94.162778) (xy 89.656666 -94.172786) (xy 89.656666 -94.323916)
			(xy 89.656258 -94.333987) (xy 89.648526 -94.352586) (xy 89.64168 -94.359984) (xy 89.56167 -94.439994)
			(xy 89.554812 -94.465394) (xy 89.558114 -94.478602) (xy 89.563667 -94.501765) (xy 89.569653 -94.54902)
			(xy 89.570052 -94.572836) (xy 89.569556 -94.600086) (xy 89.561796 -94.654031) (xy 89.546438 -94.706323)
			(xy 89.523796 -94.755897) (xy 89.49433 -94.801746) (xy 89.45864 -94.842934) (xy 89.417452 -94.878625)
			(xy 89.371605 -94.908092) (xy 89.322031 -94.930735) (xy 89.269739 -94.946094) (xy 89.215794 -94.953855)
			(xy 89.188544 -94.954344) (xy 89.164728 -94.953952) (xy 89.117472 -94.947966) (xy 89.09431 -94.942406)
			(xy 89.081102 -94.939104) (xy 89.055702 -94.945962) (xy 88.919534 -95.08213) (xy 92.311972 -95.08213)
			(xy 92.311975 -95.027627) (xy 92.319735 -94.973679) (xy 92.335093 -94.921384) (xy 92.357737 -94.871807)
			(xy 92.387207 -94.825958) (xy 92.422901 -94.784769) (xy 92.464095 -94.749079) (xy 92.509948 -94.719615)
			(xy 92.559527 -94.696977) (xy 92.611824 -94.681625) (xy 92.665773 -94.673872) (xy 92.720276 -94.673875)
			(xy 92.774225 -94.681635) (xy 92.826519 -94.696994) (xy 92.876096 -94.719639) (xy 92.921945 -94.749109)
			(xy 92.963133 -94.784804) (xy 92.998823 -94.825997) (xy 93.028286 -94.871851) (xy 93.050924 -94.92143)
			(xy 93.066276 -94.973727) (xy 93.074029 -95.027676) (xy 93.07449 -95.054928) (xy 93.073991 -95.082516)
			(xy 93.066056 -95.137119) (xy 93.050341 -95.19001) (xy 93.027175 -95.240087) (xy 93.012514 -95.263462)
			(xy 93.005444 -95.275154) (xy 92.997141 -95.301173) (xy 92.996038 -95.328463) (xy 93.002215 -95.355067)
			(xy 93.015229 -95.379078) (xy 93.034148 -95.398776) (xy 93.057615 -95.412749) (xy 93.083948 -95.419994)
			(xy 93.097604 -95.420434) (xy 93.124854 -95.420882) (xy 93.1788 -95.428639) (xy 93.231093 -95.443993)
			(xy 93.280668 -95.466634) (xy 93.326517 -95.496099) (xy 93.367706 -95.531789) (xy 93.403397 -95.572977)
			(xy 93.432863 -95.618825) (xy 93.455504 -95.6684) (xy 93.47086 -95.720693) (xy 93.478617 -95.774638)
			(xy 93.478618 -95.801942) (xy 93.721426 -95.801942) (xy 93.725497 -95.74632) (xy 93.737623 -95.691883)
			(xy 93.757546 -95.639792) (xy 93.784842 -95.591157) (xy 93.818928 -95.547014) (xy 93.859077 -95.508305)
			(xy 93.904435 -95.475854) (xy 93.954035 -95.450353) (xy 94.006819 -95.432346) (xy 94.061662 -95.422216)
			(xy 94.117396 -95.420179) (xy 94.172833 -95.426279) (xy 94.22679 -95.440385) (xy 94.278119 -95.462197)
			(xy 94.325725 -95.491251) (xy 94.368593 -95.526926) (xy 94.40581 -95.568463) (xy 94.436583 -95.614976)
			(xy 94.460255 -95.665473) (xy 94.476323 -95.71888) (xy 94.484443 -95.774056) (xy 94.484952 -95.801942)
			(xy 94.484443 -95.829828) (xy 94.476323 -95.885004) (xy 94.460255 -95.938411) (xy 94.436583 -95.988908)
			(xy 94.40581 -96.035421) (xy 94.368593 -96.076958) (xy 94.325725 -96.112633) (xy 94.278119 -96.141687)
			(xy 94.22679 -96.163499) (xy 94.172833 -96.177605) (xy 94.117396 -96.183705) (xy 94.061662 -96.181668)
			(xy 94.006819 -96.171538) (xy 93.954035 -96.153531) (xy 93.904435 -96.12803) (xy 93.859077 -96.095579)
			(xy 93.818928 -96.05687) (xy 93.784842 -96.012727) (xy 93.757546 -95.964092) (xy 93.737623 -95.912001)
			(xy 93.725497 -95.857564) (xy 93.721426 -95.801942) (xy 93.478618 -95.801942) (xy 93.478619 -95.829139)
			(xy 93.470865 -95.883085) (xy 93.455512 -95.935378) (xy 93.432874 -95.984955) (xy 93.403411 -96.030805)
			(xy 93.367722 -96.071995) (xy 93.326535 -96.107688) (xy 93.280688 -96.137155) (xy 93.231114 -96.159799)
			(xy 93.178822 -96.175157) (xy 93.124877 -96.182916) (xy 93.070376 -96.18292) (xy 93.01643 -96.175168)
			(xy 92.964136 -96.159817) (xy 92.914559 -96.137181) (xy 92.868707 -96.10772) (xy 92.827516 -96.072033)
			(xy 92.791821 -96.030848) (xy 92.762352 -95.985002) (xy 92.739707 -95.935428) (xy 92.724347 -95.883137)
			(xy 92.716585 -95.829192) (xy 92.716096 -95.801942) (xy 92.716583 -95.774353) (xy 92.724522 -95.71975)
			(xy 92.74024 -95.66686) (xy 92.76341 -95.616783) (xy 92.778072 -95.593408) (xy 92.78519 -95.581743)
			(xy 92.793492 -95.555715) (xy 92.794591 -95.528418) (xy 92.788407 -95.501808) (xy 92.775386 -95.477792)
			(xy 92.756459 -95.458091) (xy 92.732983 -95.444118) (xy 92.706642 -95.436874) (xy 92.692982 -95.436436)
			(xy 92.66573 -95.435925) (xy 92.611782 -95.428166) (xy 92.559487 -95.412808) (xy 92.50991 -95.390164)
			(xy 92.46406 -95.360695) (xy 92.422871 -95.325001) (xy 92.387181 -95.283808) (xy 92.357717 -95.237955)
			(xy 92.335078 -95.188376) (xy 92.319725 -95.13608) (xy 92.311972 -95.08213) (xy 88.919534 -95.08213)
			(xy 88.900762 -95.100902) (xy 88.896444 -95.135446) (xy 88.905588 -95.150686) (xy 88.921088 -95.17749)
			(xy 88.944207 -95.234924) (xy 88.957773 -95.295333) (xy 88.960198 -95.3262) (xy 88.960706 -95.335344)
			(xy 88.968072 -95.352362) (xy 89.027762 -95.413322) (xy 89.044272 -95.420942) (xy 89.053416 -95.421704)
			(xy 89.081761 -95.424468) (xy 89.137243 -95.437314) (xy 89.190197 -95.458268) (xy 89.239446 -95.486864)
			(xy 89.283895 -95.522465) (xy 89.322556 -95.564281) (xy 89.354568 -95.611381) (xy 89.37922 -95.662718)
			(xy 89.395964 -95.717151) (xy 89.404427 -95.773467) (xy 89.404952 -95.801942) (xy 89.657426 -95.801942)
			(xy 89.661497 -95.74632) (xy 89.673623 -95.691883) (xy 89.693546 -95.639792) (xy 89.720842 -95.591157)
			(xy 89.754928 -95.547014) (xy 89.795077 -95.508305) (xy 89.840435 -95.475854) (xy 89.890035 -95.450353)
			(xy 89.942819 -95.432346) (xy 89.997662 -95.422216) (xy 90.053396 -95.420179) (xy 90.108833 -95.426279)
			(xy 90.16279 -95.440385) (xy 90.214119 -95.462197) (xy 90.261725 -95.491251) (xy 90.304593 -95.526926)
			(xy 90.34181 -95.568463) (xy 90.372583 -95.614976) (xy 90.396255 -95.665473) (xy 90.412323 -95.71888)
			(xy 90.420443 -95.774056) (xy 90.420952 -95.801942) (xy 90.674696 -95.801942) (xy 90.678767 -95.74632)
			(xy 90.690893 -95.691883) (xy 90.710816 -95.639792) (xy 90.738112 -95.591157) (xy 90.772198 -95.547014)
			(xy 90.812347 -95.508305) (xy 90.857705 -95.475854) (xy 90.907305 -95.450353) (xy 90.960089 -95.432346)
			(xy 91.014932 -95.422216) (xy 91.070666 -95.420179) (xy 91.126103 -95.426279) (xy 91.18006 -95.440385)
			(xy 91.231389 -95.462197) (xy 91.278995 -95.491251) (xy 91.321863 -95.526926) (xy 91.35908 -95.568463)
			(xy 91.389853 -95.614976) (xy 91.413525 -95.665473) (xy 91.429593 -95.71888) (xy 91.437713 -95.774056)
			(xy 91.438222 -95.801942) (xy 91.437713 -95.829828) (xy 91.429593 -95.885004) (xy 91.413525 -95.938411)
			(xy 91.389853 -95.988908) (xy 91.35908 -96.035421) (xy 91.321863 -96.076958) (xy 91.278995 -96.112633)
			(xy 91.231389 -96.141687) (xy 91.18006 -96.163499) (xy 91.126103 -96.177605) (xy 91.070666 -96.183705)
			(xy 91.014932 -96.181668) (xy 90.960089 -96.171538) (xy 90.907305 -96.153531) (xy 90.857705 -96.12803)
			(xy 90.812347 -96.095579) (xy 90.772198 -96.05687) (xy 90.738112 -96.012727) (xy 90.710816 -95.964092)
			(xy 90.690893 -95.912001) (xy 90.678767 -95.857564) (xy 90.674696 -95.801942) (xy 90.420952 -95.801942)
			(xy 90.420443 -95.829828) (xy 90.412323 -95.885004) (xy 90.396255 -95.938411) (xy 90.372583 -95.988908)
			(xy 90.34181 -96.035421) (xy 90.304593 -96.076958) (xy 90.261725 -96.112633) (xy 90.214119 -96.141687)
			(xy 90.16279 -96.163499) (xy 90.108833 -96.177605) (xy 90.053396 -96.183705) (xy 89.997662 -96.181668)
			(xy 89.942819 -96.171538) (xy 89.890035 -96.153531) (xy 89.840435 -96.12803) (xy 89.795077 -96.095579)
			(xy 89.754928 -96.05687) (xy 89.720842 -96.012727) (xy 89.693546 -95.964092) (xy 89.673623 -95.912001)
			(xy 89.661497 -95.857564) (xy 89.657426 -95.801942) (xy 89.404952 -95.801942) (xy 89.404461 -95.829192)
			(xy 89.3967 -95.883138) (xy 89.381342 -95.935429) (xy 89.358699 -95.985004) (xy 89.329233 -96.030852)
			(xy 89.293542 -96.072041) (xy 89.252354 -96.107731) (xy 89.206506 -96.137198) (xy 89.156931 -96.159841)
			(xy 89.104639 -96.1752) (xy 89.050694 -96.182961) (xy 89.023444 -96.18345) (xy 88.994553 -96.182864)
			(xy 88.937428 -96.174184) (xy 88.882265 -96.156986) (xy 88.830328 -96.131664) (xy 88.782805 -96.098797)
			(xy 88.740785 -96.059137) (xy 88.705227 -96.013592) (xy 88.676947 -95.963205) (xy 88.656592 -95.909128)
			(xy 88.644627 -95.852599) (xy 88.642444 -95.823786) (xy 88.641936 -95.814642) (xy 88.63457 -95.797624)
			(xy 88.57488 -95.736664) (xy 88.55837 -95.729044) (xy 88.549226 -95.728282) (xy 88.519772 -95.72541)
			(xy 88.462206 -95.711703) (xy 88.407447 -95.689268) (xy 88.38184 -95.674434) (xy 88.3666 -95.66529)
			(xy 88.332056 -95.669608) (xy 87.626698 -96.374966) (xy 94.427038 -96.374966) (xy 94.431109 -96.319344)
			(xy 94.443235 -96.264907) (xy 94.463158 -96.212816) (xy 94.490454 -96.164181) (xy 94.52454 -96.120038)
			(xy 94.564689 -96.081329) (xy 94.610047 -96.048878) (xy 94.659647 -96.023377) (xy 94.712431 -96.00537)
			(xy 94.767274 -95.99524) (xy 94.823008 -95.993203) (xy 94.878445 -95.999303) (xy 94.932402 -96.013409)
			(xy 94.983731 -96.035221) (xy 95.031337 -96.064275) (xy 95.074205 -96.09995) (xy 95.111422 -96.141487)
			(xy 95.142195 -96.188) (xy 95.165867 -96.238497) (xy 95.180866 -96.288352) (xy 95.852232 -96.288352)
			(xy 95.856303 -96.23273) (xy 95.868429 -96.178293) (xy 95.888352 -96.126202) (xy 95.915648 -96.077567)
			(xy 95.949734 -96.033424) (xy 95.989883 -95.994715) (xy 96.035241 -95.962264) (xy 96.084841 -95.936763)
			(xy 96.137625 -95.918756) (xy 96.192468 -95.908626) (xy 96.248202 -95.906589) (xy 96.303639 -95.912689)
			(xy 96.357596 -95.926795) (xy 96.408925 -95.948607) (xy 96.456531 -95.977661) (xy 96.499399 -96.013336)
			(xy 96.536616 -96.054873) (xy 96.567389 -96.101386) (xy 96.591061 -96.151883) (xy 96.607129 -96.20529)
			(xy 96.615249 -96.260466) (xy 96.61548 -96.273112) (xy 97.197924 -96.273112) (xy 97.201995 -96.21749)
			(xy 97.214121 -96.163053) (xy 97.234044 -96.110962) (xy 97.26134 -96.062327) (xy 97.295426 -96.018184)
			(xy 97.335575 -95.979475) (xy 97.380933 -95.947024) (xy 97.430533 -95.921523) (xy 97.483317 -95.903516)
			(xy 97.53816 -95.893386) (xy 97.593894 -95.891349) (xy 97.649331 -95.897449) (xy 97.703288 -95.911555)
			(xy 97.754617 -95.933367) (xy 97.802223 -95.962421) (xy 97.845091 -95.998096) (xy 97.882308 -96.039633)
			(xy 97.913081 -96.086146) (xy 97.936753 -96.136643) (xy 97.952821 -96.19005) (xy 97.960941 -96.245226)
			(xy 97.96145 -96.273112) (xy 97.960941 -96.300998) (xy 97.952821 -96.356174) (xy 97.936753 -96.409581)
			(xy 97.93369 -96.416114) (xy 99.75418 -96.416114) (xy 99.758251 -96.360492) (xy 99.770377 -96.306055)
			(xy 99.7903 -96.253964) (xy 99.817596 -96.205329) (xy 99.851682 -96.161186) (xy 99.891831 -96.122477)
			(xy 99.937189 -96.090026) (xy 99.986789 -96.064525) (xy 100.039573 -96.046518) (xy 100.094416 -96.036388)
			(xy 100.15015 -96.034351) (xy 100.205587 -96.040451) (xy 100.259544 -96.054557) (xy 100.310873 -96.076369)
			(xy 100.358479 -96.105423) (xy 100.401347 -96.141098) (xy 100.438564 -96.182635) (xy 100.469337 -96.229148)
			(xy 100.493009 -96.279645) (xy 100.509077 -96.333052) (xy 100.517197 -96.388228) (xy 100.517706 -96.416114)
			(xy 100.517197 -96.444) (xy 100.509077 -96.499176) (xy 100.493009 -96.552583) (xy 100.469337 -96.60308)
			(xy 100.438564 -96.649593) (xy 100.401347 -96.69113) (xy 100.358479 -96.726805) (xy 100.310873 -96.755859)
			(xy 100.259544 -96.777671) (xy 100.205587 -96.791777) (xy 100.15015 -96.797877) (xy 100.094416 -96.79584)
			(xy 100.039573 -96.78571) (xy 99.986789 -96.767703) (xy 99.937189 -96.742202) (xy 99.891831 -96.709751)
			(xy 99.851682 -96.671042) (xy 99.817596 -96.626899) (xy 99.7903 -96.578264) (xy 99.770377 -96.526173)
			(xy 99.758251 -96.471736) (xy 99.75418 -96.416114) (xy 97.93369 -96.416114) (xy 97.913081 -96.460078)
			(xy 97.882308 -96.506591) (xy 97.845091 -96.548128) (xy 97.802223 -96.583803) (xy 97.754617 -96.612857)
			(xy 97.703288 -96.634669) (xy 97.649331 -96.648775) (xy 97.593894 -96.654875) (xy 97.53816 -96.652838)
			(xy 97.483317 -96.642708) (xy 97.430533 -96.624701) (xy 97.380933 -96.5992) (xy 97.335575 -96.566749)
			(xy 97.295426 -96.52804) (xy 97.26134 -96.483897) (xy 97.234044 -96.435262) (xy 97.214121 -96.383171)
			(xy 97.201995 -96.328734) (xy 97.197924 -96.273112) (xy 96.61548 -96.273112) (xy 96.615758 -96.288352)
			(xy 96.615249 -96.316238) (xy 96.607129 -96.371414) (xy 96.591061 -96.424821) (xy 96.567389 -96.475318)
			(xy 96.536616 -96.521831) (xy 96.499399 -96.563368) (xy 96.456531 -96.599043) (xy 96.408925 -96.628097)
			(xy 96.357596 -96.649909) (xy 96.303639 -96.664015) (xy 96.248202 -96.670115) (xy 96.192468 -96.668078)
			(xy 96.137625 -96.657948) (xy 96.084841 -96.639941) (xy 96.035241 -96.61444) (xy 95.989883 -96.581989)
			(xy 95.949734 -96.54328) (xy 95.915648 -96.499137) (xy 95.888352 -96.450502) (xy 95.868429 -96.398411)
			(xy 95.856303 -96.343974) (xy 95.852232 -96.288352) (xy 95.180866 -96.288352) (xy 95.181935 -96.291904)
			(xy 95.190055 -96.34708) (xy 95.190564 -96.374966) (xy 95.190055 -96.402852) (xy 95.181935 -96.458028)
			(xy 95.165867 -96.511435) (xy 95.142195 -96.561932) (xy 95.111422 -96.608445) (xy 95.074205 -96.649982)
			(xy 95.031337 -96.685657) (xy 94.983731 -96.714711) (xy 94.932402 -96.736523) (xy 94.878445 -96.750629)
			(xy 94.823008 -96.756729) (xy 94.767274 -96.754692) (xy 94.712431 -96.744562) (xy 94.659647 -96.726555)
			(xy 94.610047 -96.701054) (xy 94.564689 -96.668603) (xy 94.52454 -96.629894) (xy 94.490454 -96.585751)
			(xy 94.463158 -96.537116) (xy 94.443235 -96.485025) (xy 94.431109 -96.430588) (xy 94.427038 -96.374966)
			(xy 87.626698 -96.374966) (xy 86.048088 -97.953576) (xy 88.342976 -97.953576) (xy 88.347047 -97.897954)
			(xy 88.359173 -97.843517) (xy 88.379096 -97.791426) (xy 88.406392 -97.742791) (xy 88.440478 -97.698648)
			(xy 88.480627 -97.659939) (xy 88.525985 -97.627488) (xy 88.575585 -97.601987) (xy 88.628369 -97.58398)
			(xy 88.683212 -97.57385) (xy 88.738946 -97.571813) (xy 88.794383 -97.577913) (xy 88.84834 -97.592019)
			(xy 88.899669 -97.613831) (xy 88.947275 -97.642885) (xy 88.990143 -97.67856) (xy 89.02736 -97.720097)
			(xy 89.058133 -97.76661) (xy 89.081805 -97.817107) (xy 89.083049 -97.821242) (xy 89.657426 -97.821242)
			(xy 89.661497 -97.76562) (xy 89.673623 -97.711183) (xy 89.693546 -97.659092) (xy 89.720842 -97.610457)
			(xy 89.754928 -97.566314) (xy 89.795077 -97.527605) (xy 89.840435 -97.495154) (xy 89.890035 -97.469653)
			(xy 89.942819 -97.451646) (xy 89.997662 -97.441516) (xy 90.053396 -97.439479) (xy 90.108833 -97.445579)
			(xy 90.16279 -97.459685) (xy 90.214119 -97.481497) (xy 90.261725 -97.510551) (xy 90.304593 -97.546226)
			(xy 90.34181 -97.587763) (xy 90.372583 -97.634276) (xy 90.396255 -97.684773) (xy 90.412323 -97.73818)
			(xy 90.420443 -97.793356) (xy 90.420952 -97.821242) (xy 90.420455 -97.848452) (xy 90.928397 -97.848452)
			(xy 90.928397 -97.793948) (xy 90.936155 -97.739999) (xy 90.951511 -97.687704) (xy 90.974154 -97.638126)
			(xy 91.003623 -97.592276) (xy 91.039318 -97.551087) (xy 91.080511 -97.515397) (xy 91.126365 -97.485933)
			(xy 91.175945 -97.463296) (xy 91.228242 -97.447945) (xy 91.282192 -97.440194) (xy 91.309444 -97.439734)
			(xy 91.33836 -97.44028) (xy 91.395531 -97.449001) (xy 91.450729 -97.466253) (xy 91.502692 -97.491639)
			(xy 91.550226 -97.524579) (xy 91.592244 -97.564316) (xy 91.610434 -97.5868) (xy 91.618036 -97.595613)
			(xy 91.638941 -97.605793) (xy 91.650566 -97.606358) (xy 91.730322 -97.606358) (xy 91.741956 -97.605832)
			(xy 91.762866 -97.595635) (xy 91.770454 -97.5868) (xy 91.788671 -97.564339) (xy 91.830685 -97.524602)
			(xy 91.878215 -97.49166) (xy 91.930171 -97.466268) (xy 91.985364 -97.449007) (xy 92.04253 -97.440272)
			(xy 92.071444 -97.439734) (xy 92.098696 -97.440139) (xy 92.152645 -97.447901) (xy 92.20494 -97.463262)
			(xy 92.254517 -97.485908) (xy 92.300367 -97.515379) (xy 92.341557 -97.551074) (xy 92.377248 -97.592268)
			(xy 92.406713 -97.638121) (xy 92.429353 -97.687701) (xy 92.444708 -97.739998) (xy 92.452464 -97.793948)
			(xy 92.452464 -97.821242) (xy 92.705426 -97.821242) (xy 92.709497 -97.76562) (xy 92.721623 -97.711183)
			(xy 92.741546 -97.659092) (xy 92.768842 -97.610457) (xy 92.802928 -97.566314) (xy 92.843077 -97.527605)
			(xy 92.888435 -97.495154) (xy 92.938035 -97.469653) (xy 92.990819 -97.451646) (xy 93.045662 -97.441516)
			(xy 93.101396 -97.439479) (xy 93.156833 -97.445579) (xy 93.21079 -97.459685) (xy 93.262119 -97.481497)
			(xy 93.309725 -97.510551) (xy 93.352593 -97.546226) (xy 93.38981 -97.587763) (xy 93.420583 -97.634276)
			(xy 93.444255 -97.684773) (xy 93.460323 -97.73818) (xy 93.468443 -97.793356) (xy 93.468952 -97.821242)
			(xy 93.468443 -97.849128) (xy 93.460323 -97.904304) (xy 93.444255 -97.957711) (xy 93.420583 -98.008208)
			(xy 93.38981 -98.054721) (xy 93.352593 -98.096258) (xy 93.309725 -98.131933) (xy 93.262119 -98.160987)
			(xy 93.21079 -98.182799) (xy 93.156833 -98.196905) (xy 93.101396 -98.203005) (xy 93.045662 -98.200968)
			(xy 92.990819 -98.190838) (xy 92.938035 -98.172831) (xy 92.888435 -98.14733) (xy 92.843077 -98.114879)
			(xy 92.802928 -98.07617) (xy 92.768842 -98.032027) (xy 92.741546 -97.983392) (xy 92.721623 -97.931301)
			(xy 92.709497 -97.876864) (xy 92.705426 -97.821242) (xy 92.452464 -97.821242) (xy 92.452464 -97.848452)
			(xy 92.444708 -97.902402) (xy 92.429353 -97.954699) (xy 92.406713 -98.004279) (xy 92.377248 -98.050132)
			(xy 92.341557 -98.091326) (xy 92.300367 -98.127021) (xy 92.254517 -98.156492) (xy 92.20494 -98.179138)
			(xy 92.152645 -98.194499) (xy 92.098696 -98.202261) (xy 92.071444 -98.20275) (xy 92.042527 -98.202219)
			(xy 91.985356 -98.193495) (xy 91.930156 -98.176241) (xy 91.878194 -98.150852) (xy 91.83066 -98.11791)
			(xy 91.788644 -98.078169) (xy 91.770454 -98.055684) (xy 91.76286 -98.046863) (xy 91.741949 -98.036687)
			(xy 91.730322 -98.036126) (xy 91.650566 -98.036126) (xy 91.638932 -98.036651) (xy 91.618022 -98.046849)
			(xy 91.610434 -98.055684) (xy 91.59222 -98.078148) (xy 91.550205 -98.117885) (xy 91.502675 -98.150827)
			(xy 91.450719 -98.176219) (xy 91.395525 -98.193479) (xy 91.338359 -98.202213) (xy 91.309444 -98.20275)
			(xy 91.282192 -98.202206) (xy 91.228242 -98.194455) (xy 91.175945 -98.179104) (xy 91.126365 -98.156467)
			(xy 91.080511 -98.127003) (xy 91.039318 -98.091313) (xy 91.003623 -98.050124) (xy 90.974154 -98.004274)
			(xy 90.951511 -97.954696) (xy 90.936155 -97.902401) (xy 90.928397 -97.848452) (xy 90.420455 -97.848452)
			(xy 90.420443 -97.849128) (xy 90.412323 -97.904304) (xy 90.396255 -97.957711) (xy 90.372583 -98.008208)
			(xy 90.34181 -98.054721) (xy 90.304593 -98.096258) (xy 90.261725 -98.131933) (xy 90.214119 -98.160987)
			(xy 90.16279 -98.182799) (xy 90.108833 -98.196905) (xy 90.053396 -98.203005) (xy 89.997662 -98.200968)
			(xy 89.942819 -98.190838) (xy 89.890035 -98.172831) (xy 89.840435 -98.14733) (xy 89.795077 -98.114879)
			(xy 89.754928 -98.07617) (xy 89.720842 -98.032027) (xy 89.693546 -97.983392) (xy 89.673623 -97.931301)
			(xy 89.661497 -97.876864) (xy 89.657426 -97.821242) (xy 89.083049 -97.821242) (xy 89.097873 -97.870514)
			(xy 89.105993 -97.92569) (xy 89.106502 -97.953576) (xy 89.105993 -97.981462) (xy 89.097873 -98.036638)
			(xy 89.081805 -98.090045) (xy 89.058133 -98.140542) (xy 89.02736 -98.187055) (xy 88.990143 -98.228592)
			(xy 88.947275 -98.264267) (xy 88.899669 -98.293321) (xy 88.84834 -98.315133) (xy 88.794383 -98.329239)
			(xy 88.738946 -98.335339) (xy 88.683212 -98.333302) (xy 88.628369 -98.323172) (xy 88.575585 -98.305165)
			(xy 88.525985 -98.279664) (xy 88.480627 -98.247213) (xy 88.440478 -98.208504) (xy 88.406392 -98.164361)
			(xy 88.379096 -98.115726) (xy 88.359173 -98.063635) (xy 88.347047 -98.009198) (xy 88.342976 -97.953576)
			(xy 86.048088 -97.953576) (xy 85.242146 -98.759518) (xy 99.171252 -98.759518) (xy 99.171716 -98.732148)
			(xy 99.179532 -98.677968) (xy 99.195021 -98.625464) (xy 99.217864 -98.575717) (xy 99.24759 -98.529751)
			(xy 99.265232 -98.50882) (xy 99.265486 -98.508566) (xy 99.27105 -98.501464) (xy 99.277311 -98.484559)
			(xy 99.277678 -98.475546) (xy 99.277678 -98.40849) (xy 99.277331 -98.399472) (xy 99.271077 -98.382555)
			(xy 99.265486 -98.37547) (xy 99.265232 -98.37547) (xy 99.265232 -98.375216) (xy 99.247609 -98.354269)
			(xy 99.217883 -98.308304) (xy 99.195036 -98.25856) (xy 99.179538 -98.20606) (xy 99.171708 -98.151883)
			(xy 99.171706 -98.097144) (xy 99.179532 -98.042966) (xy 99.195027 -97.990465) (xy 99.21787 -97.94072)
			(xy 99.247592 -97.894753) (xy 99.265232 -97.87382) (xy 99.265486 -97.873566) (xy 99.27105 -97.866464)
			(xy 99.277311 -97.849559) (xy 99.277678 -97.840546) (xy 99.277678 -97.77349) (xy 99.277331 -97.764472)
			(xy 99.271077 -97.747555) (xy 99.265486 -97.74047) (xy 99.265232 -97.74047) (xy 99.265232 -97.740216)
			(xy 99.247592 -97.719285) (xy 99.217879 -97.673312) (xy 99.195043 -97.623565) (xy 99.179552 -97.571063)
			(xy 99.171725 -97.516887) (xy 99.171252 -97.489518) (xy 99.171738 -97.462267) (xy 99.179494 -97.408319)
			(xy 99.194849 -97.356024) (xy 99.217491 -97.306447) (xy 99.246957 -97.260597) (xy 99.282648 -97.219406)
			(xy 99.323839 -97.183715) (xy 99.369689 -97.154249) (xy 99.419266 -97.131607) (xy 99.471561 -97.116252)
			(xy 99.525509 -97.108496) (xy 99.580011 -97.108496) (xy 99.633959 -97.116252) (xy 99.686254 -97.131607)
			(xy 99.735831 -97.154249) (xy 99.781681 -97.183715) (xy 99.822872 -97.219406) (xy 99.858563 -97.260597)
			(xy 99.888029 -97.306447) (xy 99.910671 -97.356024) (xy 99.926026 -97.408319) (xy 99.933782 -97.462267)
			(xy 99.934268 -97.489518) (xy 99.93382 -97.516889) (xy 99.925999 -97.571069) (xy 99.910506 -97.623573)
			(xy 99.88766 -97.673319) (xy 99.857931 -97.719285) (xy 99.840288 -97.740216) (xy 99.840034 -97.74047)
			(xy 99.834446 -97.747555) (xy 99.828202 -97.764473) (xy 99.827842 -97.77349) (xy 99.827842 -97.840546)
			(xy 99.828216 -97.849561) (xy 99.834451 -97.866479) (xy 99.840034 -97.873566) (xy 99.840288 -97.873566)
			(xy 99.840288 -97.87382) (xy 99.857946 -97.894739) (xy 99.887669 -97.940709) (xy 99.910512 -97.990458)
			(xy 99.926006 -98.042962) (xy 99.933833 -98.097142) (xy 99.933831 -98.151885) (xy 99.926 -98.206064)
			(xy 99.910502 -98.258567) (xy 99.887656 -98.308314) (xy 99.857929 -98.354283) (xy 99.840288 -98.375216)
			(xy 99.840034 -98.37547) (xy 99.834446 -98.382555) (xy 99.828202 -98.399473) (xy 99.827842 -98.40849)
			(xy 99.827842 -98.475546) (xy 99.828216 -98.484561) (xy 99.834451 -98.501479) (xy 99.836082 -98.503549)
			(xy 100.826086 -98.503549) (xy 100.826086 -98.449051) (xy 100.833841 -98.395108) (xy 100.849194 -98.342817)
			(xy 100.871832 -98.293244) (xy 100.901294 -98.247396) (xy 100.936981 -98.206207) (xy 100.978165 -98.170517)
			(xy 101.02401 -98.14105) (xy 101.073582 -98.118407) (xy 101.125871 -98.103049) (xy 101.179813 -98.095288)
			(xy 101.207062 -98.0948) (xy 101.233377 -98.095226) (xy 101.285508 -98.102469) (xy 101.336151 -98.116797)
			(xy 101.38435 -98.137937) (xy 101.429192 -98.16549) (xy 101.46983 -98.198935) (xy 101.487986 -98.21799)
			(xy 101.495512 -98.225386) (xy 101.514789 -98.233914) (xy 101.525324 -98.2345) (xy 101.6 -98.2345)
			(xy 101.610551 -98.233985) (xy 101.629847 -98.22544) (xy 101.637338 -98.21799) (xy 101.65548 -98.198921)
			(xy 101.696113 -98.165466) (xy 101.740956 -98.137909) (xy 101.789159 -98.116772) (xy 101.839809 -98.102458)
			(xy 101.891945 -98.095237) (xy 101.918262 -98.0948) (xy 101.945517 -98.095245) (xy 101.999473 -98.102998)
			(xy 102.051777 -98.118351) (xy 102.101363 -98.140991) (xy 102.147222 -98.170459) (xy 102.18842 -98.206153)
			(xy 102.224118 -98.247348) (xy 102.25359 -98.293204) (xy 102.276236 -98.342787) (xy 102.291594 -98.395089)
			(xy 102.299353 -98.449045) (xy 102.299353 -98.503555) (xy 102.291594 -98.557511) (xy 102.276236 -98.609813)
			(xy 102.25359 -98.659396) (xy 102.224118 -98.705252) (xy 102.18842 -98.746447) (xy 102.147222 -98.782141)
			(xy 102.101363 -98.811609) (xy 102.051777 -98.834249) (xy 101.999473 -98.849602) (xy 101.945517 -98.857355)
			(xy 101.918262 -98.857816) (xy 101.891947 -98.857369) (xy 101.839818 -98.850129) (xy 101.789175 -98.835806)
			(xy 101.740977 -98.814669) (xy 101.696134 -98.78712) (xy 101.655494 -98.753679) (xy 101.637338 -98.734626)
			(xy 101.629801 -98.727243) (xy 101.610533 -98.718707) (xy 101.6 -98.718116) (xy 101.525324 -98.718116)
			(xy 101.514774 -98.71864) (xy 101.495478 -98.727178) (xy 101.487986 -98.734626) (xy 101.469835 -98.753686)
			(xy 101.429204 -98.787142) (xy 101.384363 -98.8147) (xy 101.336161 -98.835837) (xy 101.285513 -98.850154)
			(xy 101.233378 -98.857378) (xy 101.207062 -98.857816) (xy 101.179813 -98.857312) (xy 101.125871 -98.849551)
			(xy 101.073582 -98.834193) (xy 101.02401 -98.81155) (xy 100.978165 -98.782083) (xy 100.936981 -98.746393)
			(xy 100.901294 -98.705204) (xy 100.871832 -98.659356) (xy 100.849194 -98.609783) (xy 100.833841 -98.557492)
			(xy 100.826086 -98.503549) (xy 99.836082 -98.503549) (xy 99.840034 -98.508566) (xy 99.840288 -98.509074)
			(xy 99.851231 -98.521809) (xy 99.871073 -98.5489) (xy 99.879912 -98.563176) (xy 99.885246 -98.572066)
			(xy 99.902264 -98.584258) (xy 99.995482 -98.604578) (xy 100.016056 -98.60026) (xy 100.024692 -98.594418)
			(xy 100.048758 -98.578421) (xy 100.100688 -98.553077) (xy 100.155846 -98.535851) (xy 100.21297 -98.527135)
			(xy 100.241862 -98.5266) (xy 100.269117 -98.527045) (xy 100.323073 -98.534798) (xy 100.375377 -98.550151)
			(xy 100.424963 -98.572791) (xy 100.470822 -98.602259) (xy 100.51202 -98.637953) (xy 100.547718 -98.679148)
			(xy 100.57719 -98.725004) (xy 100.599836 -98.774587) (xy 100.615194 -98.826889) (xy 100.622953 -98.880845)
			(xy 100.622953 -98.935355) (xy 100.615194 -98.989311) (xy 100.599836 -99.041613) (xy 100.57719 -99.091196)
			(xy 100.547718 -99.137052) (xy 100.51202 -99.178247) (xy 100.470822 -99.213941) (xy 100.424963 -99.243409)
			(xy 100.375377 -99.266049) (xy 100.323073 -99.281402) (xy 100.269117 -99.289155) (xy 100.241862 -99.289616)
			(xy 100.213769 -99.289152) (xy 100.158191 -99.28092) (xy 100.104421 -99.264623) (xy 100.053623 -99.240615)
			(xy 100.006897 -99.209416) (xy 99.965253 -99.171699) (xy 99.929592 -99.128282) (xy 99.91471 -99.10445)
			(xy 99.909376 -99.09556) (xy 99.892358 -99.083368) (xy 99.79914 -99.063048) (xy 99.778566 -99.067366)
			(xy 99.76993 -99.073208) (xy 99.74586 -99.089198) (xy 99.693931 -99.114543) (xy 99.638775 -99.131771)
			(xy 99.581652 -99.14049) (xy 99.55276 -99.141026) (xy 99.525509 -99.140559) (xy 99.471561 -99.132798)
			(xy 99.419267 -99.117439) (xy 99.369691 -99.094794) (xy 99.323842 -99.065325) (xy 99.282652 -99.029632)
			(xy 99.246961 -98.988441) (xy 99.217495 -98.94259) (xy 99.194854 -98.893012) (xy 99.179497 -98.840717)
			(xy 99.171739 -98.786769) (xy 99.171252 -98.759518) (xy 85.242146 -98.759518) (xy 84.552282 -99.449382)
			(xy 87.906096 -99.449382) (xy 87.910167 -99.39376) (xy 87.922293 -99.339323) (xy 87.942216 -99.287232)
			(xy 87.969512 -99.238597) (xy 88.003598 -99.194454) (xy 88.043747 -99.155745) (xy 88.089105 -99.123294)
			(xy 88.138705 -99.097793) (xy 88.191489 -99.079786) (xy 88.246332 -99.069656) (xy 88.302066 -99.067619)
			(xy 88.357503 -99.073719) (xy 88.41146 -99.087825) (xy 88.462789 -99.109637) (xy 88.510395 -99.138691)
			(xy 88.553263 -99.174366) (xy 88.59048 -99.215903) (xy 88.621253 -99.262416) (xy 88.644925 -99.312913)
			(xy 88.660993 -99.36632) (xy 88.669113 -99.421496) (xy 88.669622 -99.449382) (xy 88.669113 -99.477268)
			(xy 88.660993 -99.532444) (xy 88.644925 -99.585851) (xy 88.631503 -99.614482) (xy 90.339924 -99.614482)
			(xy 90.343995 -99.55886) (xy 90.356121 -99.504423) (xy 90.376044 -99.452332) (xy 90.40334 -99.403697)
			(xy 90.437426 -99.359554) (xy 90.477575 -99.320845) (xy 90.522933 -99.288394) (xy 90.572533 -99.262893)
			(xy 90.625317 -99.244886) (xy 90.68016 -99.234756) (xy 90.735894 -99.232719) (xy 90.791331 -99.238819)
			(xy 90.845288 -99.252925) (xy 90.896617 -99.274737) (xy 90.944223 -99.303791) (xy 90.987091 -99.339466)
			(xy 91.024308 -99.381003) (xy 91.055081 -99.427516) (xy 91.078753 -99.478013) (xy 91.094821 -99.53142)
			(xy 91.102941 -99.586596) (xy 91.10345 -99.614482) (xy 91.103241 -99.625912) (xy 91.5068 -99.625912)
			(xy 91.510871 -99.57029) (xy 91.522997 -99.515853) (xy 91.54292 -99.463762) (xy 91.570216 -99.415127)
			(xy 91.604302 -99.370984) (xy 91.644451 -99.332275) (xy 91.689809 -99.299824) (xy 91.739409 -99.274323)
			(xy 91.792193 -99.256316) (xy 91.847036 -99.246186) (xy 91.90277 -99.244149) (xy 91.958207 -99.250249)
			(xy 92.012164 -99.264355) (xy 92.063493 -99.286167) (xy 92.111099 -99.315221) (xy 92.153967 -99.350896)
			(xy 92.191184 -99.392433) (xy 92.221957 -99.438946) (xy 92.231136 -99.458526) (xy 93.638622 -99.458526)
			(xy 93.642693 -99.402904) (xy 93.654819 -99.348467) (xy 93.674742 -99.296376) (xy 93.702038 -99.247741)
			(xy 93.736124 -99.203598) (xy 93.776273 -99.164889) (xy 93.821631 -99.132438) (xy 93.871231 -99.106937)
			(xy 93.924015 -99.08893) (xy 93.978858 -99.0788) (xy 94.034592 -99.076763) (xy 94.090029 -99.082863)
			(xy 94.143986 -99.096969) (xy 94.195315 -99.118781) (xy 94.242921 -99.147835) (xy 94.285789 -99.18351)
			(xy 94.323006 -99.225047) (xy 94.353779 -99.27156) (xy 94.377451 -99.322057) (xy 94.393519 -99.375464)
			(xy 94.401639 -99.43064) (xy 94.402148 -99.458526) (xy 94.401639 -99.486412) (xy 94.393519 -99.541588)
			(xy 94.377451 -99.594995) (xy 94.353779 -99.645492) (xy 94.323006 -99.692005) (xy 94.285789 -99.733542)
			(xy 94.242921 -99.769217) (xy 94.195315 -99.798271) (xy 94.143986 -99.820083) (xy 94.090029 -99.834189)
			(xy 94.034592 -99.840289) (xy 93.978858 -99.838252) (xy 93.924015 -99.828122) (xy 93.871231 -99.810115)
			(xy 93.821631 -99.784614) (xy 93.776273 -99.752163) (xy 93.736124 -99.713454) (xy 93.702038 -99.669311)
			(xy 93.674742 -99.620676) (xy 93.654819 -99.568585) (xy 93.642693 -99.514148) (xy 93.638622 -99.458526)
			(xy 92.231136 -99.458526) (xy 92.245629 -99.489443) (xy 92.261697 -99.54285) (xy 92.269817 -99.598026)
			(xy 92.270326 -99.625912) (xy 92.269817 -99.653798) (xy 92.261697 -99.708974) (xy 92.245629 -99.762381)
			(xy 92.221957 -99.812878) (xy 92.191184 -99.859391) (xy 92.153967 -99.900928) (xy 92.111099 -99.936603)
			(xy 92.063493 -99.965657) (xy 92.012164 -99.987469) (xy 91.958207 -100.001575) (xy 91.90277 -100.007675)
			(xy 91.847036 -100.005638) (xy 91.792193 -99.995508) (xy 91.739409 -99.977501) (xy 91.689809 -99.952)
			(xy 91.644451 -99.919549) (xy 91.604302 -99.88084) (xy 91.570216 -99.836697) (xy 91.54292 -99.788062)
			(xy 91.522997 -99.735971) (xy 91.510871 -99.681534) (xy 91.5068 -99.625912) (xy 91.103241 -99.625912)
			(xy 91.102941 -99.642368) (xy 91.094821 -99.697544) (xy 91.078753 -99.750951) (xy 91.055081 -99.801448)
			(xy 91.024308 -99.847961) (xy 90.987091 -99.889498) (xy 90.944223 -99.925173) (xy 90.896617 -99.954227)
			(xy 90.845288 -99.976039) (xy 90.791331 -99.990145) (xy 90.735894 -99.996245) (xy 90.68016 -99.994208)
			(xy 90.625317 -99.984078) (xy 90.572533 -99.966071) (xy 90.522933 -99.94057) (xy 90.477575 -99.908119)
			(xy 90.437426 -99.86941) (xy 90.40334 -99.825267) (xy 90.376044 -99.776632) (xy 90.356121 -99.724541)
			(xy 90.343995 -99.670104) (xy 90.339924 -99.614482) (xy 88.631503 -99.614482) (xy 88.621253 -99.636348)
			(xy 88.59048 -99.682861) (xy 88.553263 -99.724398) (xy 88.510395 -99.760073) (xy 88.462789 -99.789127)
			(xy 88.41146 -99.810939) (xy 88.357503 -99.825045) (xy 88.302066 -99.831145) (xy 88.246332 -99.829108)
			(xy 88.191489 -99.818978) (xy 88.138705 -99.800971) (xy 88.089105 -99.77547) (xy 88.043747 -99.743019)
			(xy 88.003598 -99.70431) (xy 87.969512 -99.660167) (xy 87.942216 -99.611532) (xy 87.922293 -99.559441)
			(xy 87.910167 -99.505004) (xy 87.906096 -99.449382) (xy 84.552282 -99.449382) (xy 83.608672 -100.392992)
			(xy 95.37395 -100.392992) (xy 95.378021 -100.33737) (xy 95.390147 -100.282933) (xy 95.41007 -100.230842)
			(xy 95.437366 -100.182207) (xy 95.471452 -100.138064) (xy 95.511601 -100.099355) (xy 95.556959 -100.066904)
			(xy 95.606559 -100.041403) (xy 95.659343 -100.023396) (xy 95.714186 -100.013266) (xy 95.76992 -100.011229)
			(xy 95.825357 -100.017329) (xy 95.879314 -100.031435) (xy 95.930643 -100.053247) (xy 95.978249 -100.082301)
			(xy 96.021117 -100.117976) (xy 96.058334 -100.159513) (xy 96.089107 -100.206026) (xy 96.112779 -100.256523)
			(xy 96.128847 -100.30993) (xy 96.136967 -100.365106) (xy 96.137476 -100.392992) (xy 96.136967 -100.420878)
			(xy 96.128847 -100.476054) (xy 96.112779 -100.529461) (xy 96.089107 -100.579958) (xy 96.058334 -100.626471)
			(xy 96.021117 -100.668008) (xy 95.978249 -100.703683) (xy 95.930643 -100.732737) (xy 95.879314 -100.754549)
			(xy 95.825357 -100.768655) (xy 95.76992 -100.774755) (xy 95.714186 -100.772718) (xy 95.659343 -100.762588)
			(xy 95.606559 -100.744581) (xy 95.556959 -100.71908) (xy 95.511601 -100.686629) (xy 95.471452 -100.64792)
			(xy 95.437366 -100.603777) (xy 95.41007 -100.555142) (xy 95.390147 -100.503051) (xy 95.378021 -100.448614)
			(xy 95.37395 -100.392992) (xy 83.608672 -100.392992) (xy 83.1977 -100.803964) (xy 90.351354 -100.803964)
			(xy 90.355425 -100.748342) (xy 90.367551 -100.693905) (xy 90.387474 -100.641814) (xy 90.41477 -100.593179)
			(xy 90.448856 -100.549036) (xy 90.489005 -100.510327) (xy 90.534363 -100.477876) (xy 90.583963 -100.452375)
			(xy 90.636747 -100.434368) (xy 90.69159 -100.424238) (xy 90.747324 -100.422201) (xy 90.802761 -100.428301)
			(xy 90.856718 -100.442407) (xy 90.908047 -100.464219) (xy 90.955653 -100.493273) (xy 90.998521 -100.528948)
			(xy 91.035738 -100.570485) (xy 91.066511 -100.616998) (xy 91.090183 -100.667495) (xy 91.106251 -100.720902)
			(xy 91.114371 -100.776078) (xy 91.11488 -100.803964) (xy 91.517976 -100.803964) (xy 91.522047 -100.748342)
			(xy 91.534173 -100.693905) (xy 91.554096 -100.641814) (xy 91.581392 -100.593179) (xy 91.615478 -100.549036)
			(xy 91.655627 -100.510327) (xy 91.700985 -100.477876) (xy 91.750585 -100.452375) (xy 91.803369 -100.434368)
			(xy 91.858212 -100.424238) (xy 91.913946 -100.422201) (xy 91.969383 -100.428301) (xy 92.02334 -100.442407)
			(xy 92.074669 -100.464219) (xy 92.122275 -100.493273) (xy 92.165143 -100.528948) (xy 92.20236 -100.570485)
			(xy 92.233133 -100.616998) (xy 92.256805 -100.667495) (xy 92.272873 -100.720902) (xy 92.280993 -100.776078)
			(xy 92.281502 -100.803964) (xy 92.280993 -100.83185) (xy 92.272873 -100.887026) (xy 92.256805 -100.940433)
			(xy 92.233133 -100.99093) (xy 92.20236 -101.037443) (xy 92.165143 -101.07898) (xy 92.122275 -101.114655)
			(xy 92.074669 -101.143709) (xy 92.02334 -101.165521) (xy 91.969383 -101.179627) (xy 91.913946 -101.185727)
			(xy 91.858212 -101.18369) (xy 91.803369 -101.17356) (xy 91.750585 -101.155553) (xy 91.700985 -101.130052)
			(xy 91.655627 -101.097601) (xy 91.615478 -101.058892) (xy 91.581392 -101.014749) (xy 91.554096 -100.966114)
			(xy 91.534173 -100.914023) (xy 91.522047 -100.859586) (xy 91.517976 -100.803964) (xy 91.11488 -100.803964)
			(xy 91.114371 -100.83185) (xy 91.106251 -100.887026) (xy 91.090183 -100.940433) (xy 91.066511 -100.99093)
			(xy 91.035738 -101.037443) (xy 90.998521 -101.07898) (xy 90.955653 -101.114655) (xy 90.908047 -101.143709)
			(xy 90.856718 -101.165521) (xy 90.802761 -101.179627) (xy 90.747324 -101.185727) (xy 90.69159 -101.18369)
			(xy 90.636747 -101.17356) (xy 90.583963 -101.155553) (xy 90.534363 -101.130052) (xy 90.489005 -101.097601)
			(xy 90.448856 -101.058892) (xy 90.41477 -101.014749) (xy 90.387474 -100.966114) (xy 90.367551 -100.914023)
			(xy 90.355425 -100.859586) (xy 90.351354 -100.803964) (xy 83.1977 -100.803964) (xy 82.973672 -101.027992)
			(xy 82.966275 -101.034836) (xy 82.947673 -101.042554) (xy 82.937604 -101.042978) (xy 76.379578 -101.042978)
			(xy 76.350368 -101.070664) (xy 76.349352 -101.090984) (xy 76.345796 -101.124258) (xy 76.344018 -101.136958)
			(xy 76.352146 -101.160072) (xy 76.384463 -101.189848) (xy 96.99349 -101.189848) (xy 96.99349 -101.135352)
			(xy 97.001245 -101.08141) (xy 97.016598 -101.02912) (xy 97.039235 -100.979547) (xy 97.068696 -100.933701)
			(xy 97.104382 -100.892513) (xy 97.145565 -100.856822) (xy 97.191409 -100.827356) (xy 97.240979 -100.804713)
			(xy 97.293266 -100.789355) (xy 97.347208 -100.781593) (xy 97.374456 -100.781104) (xy 97.401825 -100.781595)
			(xy 97.456003 -100.789407) (xy 97.508506 -100.80489) (xy 97.558254 -100.827726) (xy 97.604221 -100.857445)
			(xy 97.625154 -100.875084) (xy 97.625408 -100.875338) (xy 97.632485 -100.880938) (xy 97.649409 -100.887176)
			(xy 97.658428 -100.88753) (xy 97.725484 -100.88753) (xy 97.734499 -100.887159) (xy 97.751416 -100.88092)
			(xy 97.758504 -100.875338) (xy 97.758504 -100.875084) (xy 97.758758 -100.875084) (xy 97.779693 -100.857449)
			(xy 97.825665 -100.827737) (xy 97.875412 -100.8049) (xy 97.927912 -100.789408) (xy 97.982087 -100.781579)
			(xy 98.009456 -100.781104) (xy 98.036712 -100.78154) (xy 98.090669 -100.789292) (xy 98.142974 -100.804645)
			(xy 98.192561 -100.827285) (xy 98.238422 -100.856753) (xy 98.279621 -100.892448) (xy 98.31532 -100.933643)
			(xy 98.344793 -100.9795) (xy 98.36744 -101.029085) (xy 98.382799 -101.081388) (xy 98.390557 -101.135344)
			(xy 98.390557 -101.189856) (xy 98.382799 -101.243812) (xy 98.36744 -101.296115) (xy 98.350572 -101.333046)
			(xy 99.933758 -101.333046) (xy 99.937829 -101.277424) (xy 99.949955 -101.222987) (xy 99.969878 -101.170896)
			(xy 99.997174 -101.122261) (xy 100.03126 -101.078118) (xy 100.071409 -101.039409) (xy 100.116767 -101.006958)
			(xy 100.166367 -100.981457) (xy 100.219151 -100.96345) (xy 100.273994 -100.95332) (xy 100.329728 -100.951283)
			(xy 100.385165 -100.957383) (xy 100.439122 -100.971489) (xy 100.490451 -100.993301) (xy 100.538057 -101.022355)
			(xy 100.580925 -101.05803) (xy 100.618142 -101.099567) (xy 100.648915 -101.14608) (xy 100.672587 -101.196577)
			(xy 100.688655 -101.249984) (xy 100.696775 -101.30516) (xy 100.697284 -101.333046) (xy 100.696775 -101.360932)
			(xy 100.688655 -101.416108) (xy 100.672587 -101.469515) (xy 100.648915 -101.520012) (xy 100.618142 -101.566525)
			(xy 100.580925 -101.608062) (xy 100.538057 -101.643737) (xy 100.490451 -101.672791) (xy 100.439122 -101.694603)
			(xy 100.385165 -101.708709) (xy 100.329728 -101.714809) (xy 100.273994 -101.712772) (xy 100.219151 -101.702642)
			(xy 100.166367 -101.684635) (xy 100.116767 -101.659134) (xy 100.071409 -101.626683) (xy 100.03126 -101.587974)
			(xy 99.997174 -101.543831) (xy 99.969878 -101.495196) (xy 99.949955 -101.443105) (xy 99.937829 -101.388668)
			(xy 99.933758 -101.333046) (xy 98.350572 -101.333046) (xy 98.344793 -101.3457) (xy 98.31532 -101.391557)
			(xy 98.279621 -101.432752) (xy 98.238422 -101.468447) (xy 98.192561 -101.497915) (xy 98.142974 -101.520555)
			(xy 98.090669 -101.535908) (xy 98.036712 -101.54366) (xy 98.009456 -101.54412) (xy 97.982086 -101.543641)
			(xy 97.927907 -101.535829) (xy 97.875403 -101.520344) (xy 97.825656 -101.497505) (xy 97.779689 -101.467781)
			(xy 97.758758 -101.45014) (xy 97.758504 -101.449886) (xy 97.751422 -101.444293) (xy 97.734502 -101.438051)
			(xy 97.725484 -101.437694) (xy 97.658428 -101.437694) (xy 97.649413 -101.438066) (xy 97.632496 -101.444303)
			(xy 97.625408 -101.449886) (xy 97.625408 -101.45014) (xy 97.625154 -101.45014) (xy 97.604218 -101.467774)
			(xy 97.558246 -101.497485) (xy 97.508499 -101.520322) (xy 97.455999 -101.535814) (xy 97.401825 -101.543645)
			(xy 97.374456 -101.54412) (xy 97.347208 -101.543607) (xy 97.293266 -101.535845) (xy 97.240979 -101.520487)
			(xy 97.191409 -101.497844) (xy 97.145565 -101.468378) (xy 97.104382 -101.432687) (xy 97.068696 -101.391499)
			(xy 97.039235 -101.345653) (xy 97.016598 -101.29608) (xy 97.001245 -101.24379) (xy 96.99349 -101.189848)
			(xy 76.384463 -101.189848) (xy 76.432918 -101.234494) (xy 76.456794 -101.240844) (xy 76.468986 -101.23805)
			(xy 76.489908 -101.233563) (xy 76.532426 -101.228727) (xy 76.553822 -101.228398) (xy 76.581071 -101.228902)
			(xy 76.635014 -101.236661) (xy 76.687305 -101.252017) (xy 76.736877 -101.274659) (xy 76.782722 -101.304126)
			(xy 76.823908 -101.339817) (xy 76.859595 -101.381005) (xy 76.889057 -101.426854) (xy 76.911695 -101.476428)
			(xy 76.927047 -101.528719) (xy 76.934299 -101.579172) (xy 87.770714 -101.579172) (xy 87.774785 -101.52355)
			(xy 87.786911 -101.469113) (xy 87.806834 -101.417022) (xy 87.83413 -101.368387) (xy 87.868216 -101.324244)
			(xy 87.908365 -101.285535) (xy 87.953723 -101.253084) (xy 88.003323 -101.227583) (xy 88.056107 -101.209576)
			(xy 88.11095 -101.199446) (xy 88.166684 -101.197409) (xy 88.222121 -101.203509) (xy 88.276078 -101.217615)
			(xy 88.327407 -101.239427) (xy 88.375013 -101.268481) (xy 88.417881 -101.304156) (xy 88.455098 -101.345693)
			(xy 88.485871 -101.392206) (xy 88.509543 -101.442703) (xy 88.525611 -101.49611) (xy 88.533731 -101.551286)
			(xy 88.53424 -101.579172) (xy 88.533731 -101.607058) (xy 88.525611 -101.662234) (xy 88.509543 -101.715641)
			(xy 88.485871 -101.766138) (xy 88.455098 -101.812651) (xy 88.417881 -101.854188) (xy 88.397963 -101.870764)
			(xy 93.23908 -101.870764) (xy 93.243151 -101.815142) (xy 93.255277 -101.760705) (xy 93.2752 -101.708614)
			(xy 93.302496 -101.659979) (xy 93.336582 -101.615836) (xy 93.376731 -101.577127) (xy 93.422089 -101.544676)
			(xy 93.471689 -101.519175) (xy 93.524473 -101.501168) (xy 93.579316 -101.491038) (xy 93.63505 -101.489001)
			(xy 93.690487 -101.495101) (xy 93.744444 -101.509207) (xy 93.795773 -101.531019) (xy 93.843379 -101.560073)
			(xy 93.886247 -101.595748) (xy 93.923464 -101.637285) (xy 93.954237 -101.683798) (xy 93.977909 -101.734295)
			(xy 93.993977 -101.787702) (xy 94.002097 -101.842878) (xy 94.002606 -101.870764) (xy 94.002097 -101.89865)
			(xy 93.993977 -101.953826) (xy 93.977909 -102.007233) (xy 93.954237 -102.05773) (xy 93.923464 -102.104243)
			(xy 93.899978 -102.130455) (xy 96.543029 -102.130455) (xy 96.543029 -102.075945) (xy 96.550787 -102.021989)
			(xy 96.566145 -101.969686) (xy 96.58879 -101.920102) (xy 96.618261 -101.874245) (xy 96.653959 -101.833049)
			(xy 96.695156 -101.797353) (xy 96.741014 -101.767883) (xy 96.790599 -101.74524) (xy 96.842902 -101.729884)
			(xy 96.896859 -101.722128) (xy 96.924114 -101.721666) (xy 96.951485 -101.722108) (xy 97.005666 -101.729929)
			(xy 97.05817 -101.745423) (xy 97.107917 -101.76827) (xy 97.153882 -101.798001) (xy 97.174812 -101.815646)
			(xy 97.175066 -101.8159) (xy 97.182158 -101.821478) (xy 97.199071 -101.82773) (xy 97.208086 -101.828092)
			(xy 97.275142 -101.828092) (xy 97.284156 -101.827709) (xy 97.301073 -101.82148) (xy 97.308162 -101.8159)
			(xy 97.308162 -101.815646) (xy 97.308416 -101.815646) (xy 97.329375 -101.79804) (xy 97.37534 -101.768322)
			(xy 97.42508 -101.745479) (xy 97.477575 -101.72998) (xy 97.531747 -101.722144) (xy 97.559114 -101.721666)
			(xy 97.586363 -101.722205) (xy 97.640305 -101.729963) (xy 97.692595 -101.745318) (xy 97.742167 -101.767958)
			(xy 97.788012 -101.797423) (xy 97.829198 -101.833112) (xy 97.864885 -101.874299) (xy 97.894348 -101.920146)
			(xy 97.916987 -101.969719) (xy 97.93234 -102.022009) (xy 97.940096 -102.075951) (xy 97.940096 -102.095046)
			(xy 99.298758 -102.095046) (xy 99.302829 -102.039424) (xy 99.314955 -101.984987) (xy 99.334878 -101.932896)
			(xy 99.362174 -101.884261) (xy 99.39626 -101.840118) (xy 99.436409 -101.801409) (xy 99.481767 -101.768958)
			(xy 99.531367 -101.743457) (xy 99.584151 -101.72545) (xy 99.638994 -101.71532) (xy 99.694728 -101.713283)
			(xy 99.750165 -101.719383) (xy 99.804122 -101.733489) (xy 99.855451 -101.755301) (xy 99.903057 -101.784355)
			(xy 99.945925 -101.82003) (xy 99.983142 -101.861567) (xy 100.013915 -101.90808) (xy 100.037587 -101.958577)
			(xy 100.053655 -102.011984) (xy 100.061775 -102.06716) (xy 100.062284 -102.095046) (xy 100.061775 -102.122932)
			(xy 100.053655 -102.178108) (xy 100.037587 -102.231515) (xy 100.013915 -102.282012) (xy 100.003104 -102.298352)
			(xy 101.096546 -102.298352) (xy 101.096546 -102.243848) (xy 101.104302 -102.189898) (xy 101.119657 -102.137601)
			(xy 101.142298 -102.088022) (xy 101.171764 -102.042169) (xy 101.207456 -102.000976) (xy 101.248646 -101.965281)
			(xy 101.294497 -101.935812) (xy 101.344075 -101.913167) (xy 101.396371 -101.897808) (xy 101.45032 -101.890048)
			(xy 101.477572 -101.88956) (xy 101.504942 -101.890028) (xy 101.559122 -101.897843) (xy 101.611626 -101.913331)
			(xy 101.661373 -101.936173) (xy 101.707339 -101.965898) (xy 101.72827 -101.98354) (xy 101.728524 -101.983794)
			(xy 101.7356 -101.989396) (xy 101.752525 -101.995634) (xy 101.761544 -101.995986) (xy 101.8286 -101.995986)
			(xy 101.837617 -101.995632) (xy 101.854534 -101.989383) (xy 101.86162 -101.983794) (xy 101.86162 -101.98354)
			(xy 101.861874 -101.98354) (xy 101.88281 -101.965906) (xy 101.928781 -101.936192) (xy 101.978528 -101.913354)
			(xy 102.031028 -101.897862) (xy 102.085203 -101.890034) (xy 102.112572 -101.88956) (xy 102.139824 -101.890085)
			(xy 102.193773 -101.897838) (xy 102.24607 -101.913191) (xy 102.29565 -101.93583) (xy 102.341502 -101.965295)
			(xy 102.382695 -102.000985) (xy 102.400814 -102.021894) (xy 102.956614 -102.021894) (xy 102.957073 -101.994523)
			(xy 102.964892 -101.940344) (xy 102.980383 -101.887841) (xy 103.003226 -101.838094) (xy 103.032952 -101.792127)
			(xy 103.050594 -101.771196) (xy 103.050848 -101.770942) (xy 103.056429 -101.763852) (xy 103.062678 -101.746938)
			(xy 103.06304 -101.737922) (xy 103.06304 -101.670866) (xy 103.062712 -101.661846) (xy 103.056446 -101.644928)
			(xy 103.050848 -101.637846) (xy 103.050594 -101.637846) (xy 103.050594 -101.637592) (xy 103.032949 -101.616663)
			(xy 103.003227 -101.570694) (xy 102.980384 -101.520947) (xy 102.964889 -101.468445) (xy 102.957062 -101.414266)
			(xy 102.957063 -101.359525) (xy 102.964891 -101.305347) (xy 102.980387 -101.252845) (xy 103.003231 -101.203098)
			(xy 103.032954 -101.157129) (xy 103.050594 -101.136196) (xy 103.050848 -101.135942) (xy 103.056429 -101.128852)
			(xy 103.062678 -101.111938) (xy 103.06304 -101.102922) (xy 103.06304 -101.035866) (xy 103.062712 -101.026846)
			(xy 103.056446 -101.009928) (xy 103.050848 -101.002846) (xy 103.050594 -101.002846) (xy 103.050594 -101.002592)
			(xy 103.032937 -100.981675) (xy 103.003228 -100.935698) (xy 102.980396 -100.885946) (xy 102.964909 -100.833443)
			(xy 102.957085 -100.779264) (xy 102.956614 -100.751894) (xy 102.9571 -100.724643) (xy 102.964856 -100.670695)
			(xy 102.980211 -100.6184) (xy 103.002853 -100.568823) (xy 103.032319 -100.522973) (xy 103.06801 -100.481782)
			(xy 103.109201 -100.446091) (xy 103.155051 -100.416625) (xy 103.204628 -100.393983) (xy 103.256923 -100.378628)
			(xy 103.310871 -100.370872) (xy 103.365373 -100.370872) (xy 103.419321 -100.378628) (xy 103.471616 -100.393983)
			(xy 103.521193 -100.416625) (xy 103.567043 -100.446091) (xy 103.608234 -100.481782) (xy 103.643925 -100.522973)
			(xy 103.673391 -100.568823) (xy 103.696033 -100.6184) (xy 103.711388 -100.670695) (xy 103.719144 -100.724643)
			(xy 103.71963 -100.751894) (xy 103.719177 -100.779265) (xy 103.711359 -100.833445) (xy 103.695868 -100.885949)
			(xy 103.673023 -100.935696) (xy 103.643294 -100.981661) (xy 103.62565 -101.002592) (xy 103.625396 -101.002846)
			(xy 103.619825 -101.009944) (xy 103.613569 -101.026852) (xy 103.613204 -101.035866) (xy 103.613204 -101.102922)
			(xy 103.61355 -101.11194) (xy 103.619805 -101.128857) (xy 103.625396 -101.135942) (xy 103.62565 -101.135942)
			(xy 103.62565 -101.136196) (xy 103.643286 -101.157133) (xy 103.673013 -101.2031) (xy 103.69586 -101.252845)
			(xy 103.711357 -101.305347) (xy 103.719187 -101.359525) (xy 103.719188 -101.414266) (xy 103.711359 -101.468445)
			(xy 103.695863 -101.520947) (xy 103.673017 -101.570693) (xy 103.643291 -101.61666) (xy 103.62565 -101.637592)
			(xy 103.625396 -101.637846) (xy 103.619825 -101.644944) (xy 103.613569 -101.661852) (xy 103.613204 -101.670866)
			(xy 103.613204 -101.737922) (xy 103.61355 -101.74694) (xy 103.619805 -101.763857) (xy 103.625396 -101.770942)
			(xy 103.62565 -101.770942) (xy 103.62565 -101.771196) (xy 103.643293 -101.792125) (xy 103.673006 -101.838098)
			(xy 103.695842 -101.887846) (xy 103.711332 -101.940348) (xy 103.719158 -101.994524) (xy 103.71963 -102.021894)
			(xy 106.012996 -102.021894) (xy 106.01346 -101.994524) (xy 106.021278 -101.940345) (xy 106.036768 -101.887841)
			(xy 106.05961 -101.838095) (xy 106.089335 -101.792128) (xy 106.106976 -101.771196) (xy 106.10723 -101.770942)
			(xy 106.112808 -101.76385) (xy 106.119059 -101.746937) (xy 106.119422 -101.737922) (xy 106.119422 -101.670866)
			(xy 106.119077 -101.661848) (xy 106.112821 -101.644931) (xy 106.10723 -101.637846) (xy 106.106976 -101.637846)
			(xy 106.106976 -101.637592) (xy 106.089327 -101.616665) (xy 106.059599 -101.570697) (xy 106.036751 -101.520951)
			(xy 106.021253 -101.468447) (xy 106.013424 -101.414267) (xy 106.013425 -101.359524) (xy 106.021255 -101.305344)
			(xy 106.036754 -101.252841) (xy 106.059603 -101.203095) (xy 106.089333 -101.157128) (xy 106.106976 -101.136196)
			(xy 106.10723 -101.135942) (xy 106.112808 -101.12885) (xy 106.119059 -101.111937) (xy 106.119422 -101.102922)
			(xy 106.119422 -101.035866) (xy 106.119077 -101.026848) (xy 106.112821 -101.009931) (xy 106.10723 -101.002846)
			(xy 106.106976 -101.002846) (xy 106.106976 -101.002592) (xy 106.089316 -100.981677) (xy 106.059608 -100.935699)
			(xy 106.036777 -100.885947) (xy 106.02129 -100.833443) (xy 106.013467 -100.779264) (xy 106.012996 -100.751894)
			(xy 106.013482 -100.724643) (xy 106.021238 -100.670695) (xy 106.036593 -100.6184) (xy 106.059235 -100.568823)
			(xy 106.088701 -100.522973) (xy 106.124392 -100.481782) (xy 106.165583 -100.446091) (xy 106.211433 -100.416625)
			(xy 106.26101 -100.393983) (xy 106.313305 -100.378628) (xy 106.367253 -100.370872) (xy 106.421755 -100.370872)
			(xy 106.475703 -100.378628) (xy 106.527998 -100.393983) (xy 106.577575 -100.416625) (xy 106.623425 -100.446091)
			(xy 106.664616 -100.481782) (xy 106.700307 -100.522973) (xy 106.729773 -100.568823) (xy 106.752415 -100.6184)
			(xy 106.76777 -100.670695) (xy 106.775526 -100.724643) (xy 106.776012 -100.751894) (xy 106.775539 -100.779264)
			(xy 106.767723 -100.833443) (xy 106.752235 -100.885946) (xy 106.729395 -100.935693) (xy 106.699672 -100.98166)
			(xy 106.682032 -101.002592) (xy 106.681778 -101.002846) (xy 106.676205 -101.009942) (xy 106.669951 -101.026852)
			(xy 106.669586 -101.035866) (xy 106.669586 -101.102922) (xy 106.669936 -101.11194) (xy 106.676189 -101.128856)
			(xy 106.681778 -101.135942) (xy 106.682032 -101.135942) (xy 106.682032 -101.136196) (xy 106.699669 -101.157133)
			(xy 106.729397 -101.203099) (xy 106.752245 -101.252844) (xy 106.767743 -101.305346) (xy 106.775573 -101.359525)
			(xy 106.775574 -101.414266) (xy 106.767745 -101.468445) (xy 106.752248 -101.520947) (xy 106.729401 -101.570693)
			(xy 106.699674 -101.61666) (xy 106.682032 -101.637592) (xy 106.681778 -101.637846) (xy 106.676205 -101.644942)
			(xy 106.669951 -101.661852) (xy 106.669586 -101.670866) (xy 106.669586 -101.737922) (xy 106.669936 -101.74694)
			(xy 106.676189 -101.763856) (xy 106.681778 -101.770942) (xy 106.682032 -101.770942) (xy 106.682032 -101.771196)
			(xy 106.699688 -101.792115) (xy 106.729396 -101.838092) (xy 106.752228 -101.887843) (xy 106.767715 -101.940346)
			(xy 106.77554 -101.994524) (xy 106.776012 -102.021894) (xy 106.775526 -102.049145) (xy 106.76777 -102.103093)
			(xy 106.752415 -102.155388) (xy 106.729773 -102.204965) (xy 106.700307 -102.250815) (xy 106.664616 -102.292006)
			(xy 106.623425 -102.327697) (xy 106.577575 -102.357163) (xy 106.527998 -102.379805) (xy 106.475703 -102.39516)
			(xy 106.421755 -102.402916) (xy 106.367253 -102.402916) (xy 106.313305 -102.39516) (xy 106.26101 -102.379805)
			(xy 106.211433 -102.357163) (xy 106.165583 -102.327697) (xy 106.124392 -102.292006) (xy 106.088701 -102.250815)
			(xy 106.059235 -102.204965) (xy 106.036593 -102.155388) (xy 106.021238 -102.103093) (xy 106.013482 -102.049145)
			(xy 106.012996 -102.021894) (xy 103.71963 -102.021894) (xy 103.719144 -102.049145) (xy 103.711388 -102.103093)
			(xy 103.696033 -102.155388) (xy 103.673391 -102.204965) (xy 103.643925 -102.250815) (xy 103.608234 -102.292006)
			(xy 103.567043 -102.327697) (xy 103.521193 -102.357163) (xy 103.471616 -102.379805) (xy 103.419321 -102.39516)
			(xy 103.365373 -102.402916) (xy 103.310871 -102.402916) (xy 103.256923 -102.39516) (xy 103.204628 -102.379805)
			(xy 103.155051 -102.357163) (xy 103.109201 -102.327697) (xy 103.06801 -102.292006) (xy 103.032319 -102.250815)
			(xy 103.002853 -102.204965) (xy 102.980211 -102.155388) (xy 102.964856 -102.103093) (xy 102.9571 -102.049145)
			(xy 102.956614 -102.021894) (xy 102.400814 -102.021894) (xy 102.418389 -102.042175) (xy 102.447857 -102.088026)
			(xy 102.470499 -102.137604) (xy 102.485856 -102.189899) (xy 102.493613 -102.243848) (xy 102.493613 -102.298352)
			(xy 102.485856 -102.352301) (xy 102.470499 -102.404596) (xy 102.447857 -102.454174) (xy 102.418389 -102.500025)
			(xy 102.382695 -102.541215) (xy 102.341502 -102.576905) (xy 102.29565 -102.60637) (xy 102.24607 -102.629009)
			(xy 102.193773 -102.644362) (xy 102.139824 -102.652115) (xy 102.112572 -102.652576) (xy 102.085201 -102.652132)
			(xy 102.031021 -102.64431) (xy 101.978517 -102.628816) (xy 101.928771 -102.605969) (xy 101.882805 -102.57624)
			(xy 101.861874 -102.558596) (xy 101.86162 -102.558342) (xy 101.854537 -102.552751) (xy 101.837617 -102.546508)
			(xy 101.8286 -102.54615) (xy 101.761544 -102.54615) (xy 101.752528 -102.546517) (xy 101.73561 -102.552756)
			(xy 101.728524 -102.558342) (xy 101.728524 -102.558596) (xy 101.72827 -102.558596) (xy 101.707322 -102.576215)
			(xy 101.661354 -102.60593) (xy 101.61161 -102.62877) (xy 101.559113 -102.644266) (xy 101.50494 -102.652099)
			(xy 101.477572 -102.652576) (xy 101.45032 -102.652152) (xy 101.396371 -102.644392) (xy 101.344075 -102.629033)
			(xy 101.294497 -102.606388) (xy 101.248646 -102.576919) (xy 101.207456 -102.541224) (xy 101.171764 -102.500031)
			(xy 101.142298 -102.454178) (xy 101.119657 -102.404599) (xy 101.104302 -102.352302) (xy 101.096546 -102.298352)
			(xy 100.003104 -102.298352) (xy 99.983142 -102.328525) (xy 99.945925 -102.370062) (xy 99.903057 -102.405737)
			(xy 99.855451 -102.434791) (xy 99.804122 -102.456603) (xy 99.750165 -102.470709) (xy 99.694728 -102.476809)
			(xy 99.638994 -102.474772) (xy 99.584151 -102.464642) (xy 99.531367 -102.446635) (xy 99.481767 -102.421134)
			(xy 99.436409 -102.388683) (xy 99.39626 -102.349974) (xy 99.362174 -102.305831) (xy 99.334878 -102.257196)
			(xy 99.314955 -102.205105) (xy 99.302829 -102.150668) (xy 99.298758 -102.095046) (xy 97.940096 -102.095046)
			(xy 97.940096 -102.130449) (xy 97.93234 -102.184391) (xy 97.916987 -102.236681) (xy 97.894348 -102.286254)
			(xy 97.864885 -102.332101) (xy 97.829198 -102.373288) (xy 97.788012 -102.408977) (xy 97.742167 -102.438442)
			(xy 97.692595 -102.461082) (xy 97.640305 -102.476437) (xy 97.586363 -102.484195) (xy 97.559114 -102.484682)
			(xy 97.531744 -102.484212) (xy 97.477565 -102.476396) (xy 97.425062 -102.460908) (xy 97.375315 -102.438067)
			(xy 97.329348 -102.408343) (xy 97.308416 -102.390702) (xy 97.308162 -102.390448) (xy 97.301066 -102.384875)
			(xy 97.284156 -102.378621) (xy 97.275142 -102.378256) (xy 97.208086 -102.378256) (xy 97.199067 -102.378594)
			(xy 97.18215 -102.384854) (xy 97.175066 -102.390448) (xy 97.175066 -102.390702) (xy 97.174812 -102.390702)
			(xy 97.153886 -102.408349) (xy 97.107912 -102.43806) (xy 97.058163 -102.460894) (xy 97.005661 -102.476383)
			(xy 96.951484 -102.484209) (xy 96.924114 -102.484682) (xy 96.896859 -102.484272) (xy 96.842902 -102.476516)
			(xy 96.790599 -102.46116) (xy 96.741014 -102.438517) (xy 96.695156 -102.409047) (xy 96.653959 -102.373351)
			(xy 96.618261 -102.332155) (xy 96.58879 -102.286298) (xy 96.566145 -102.236714) (xy 96.550787 -102.184411)
			(xy 96.543029 -102.130455) (xy 93.899978 -102.130455) (xy 93.886247 -102.14578) (xy 93.843379 -102.181455)
			(xy 93.795773 -102.210509) (xy 93.744444 -102.232321) (xy 93.690487 -102.246427) (xy 93.63505 -102.252527)
			(xy 93.579316 -102.25049) (xy 93.524473 -102.24036) (xy 93.471689 -102.222353) (xy 93.422089 -102.196852)
			(xy 93.376731 -102.164401) (xy 93.336582 -102.125692) (xy 93.302496 -102.081549) (xy 93.2752 -102.032914)
			(xy 93.255277 -101.980823) (xy 93.243151 -101.926386) (xy 93.23908 -101.870764) (xy 88.397963 -101.870764)
			(xy 88.375013 -101.889863) (xy 88.327407 -101.918917) (xy 88.276078 -101.940729) (xy 88.222121 -101.954835)
			(xy 88.166684 -101.960935) (xy 88.11095 -101.958898) (xy 88.056107 -101.948768) (xy 88.003323 -101.930761)
			(xy 87.953723 -101.90526) (xy 87.908365 -101.872809) (xy 87.868216 -101.8341) (xy 87.83413 -101.789957)
			(xy 87.806834 -101.741322) (xy 87.786911 -101.689231) (xy 87.774785 -101.634794) (xy 87.770714 -101.579172)
			(xy 76.934299 -101.579172) (xy 76.934801 -101.582663) (xy 76.934799 -101.637162) (xy 76.927041 -101.691105)
			(xy 76.911686 -101.743396) (xy 76.889045 -101.792969) (xy 76.85958 -101.838815) (xy 76.82389 -101.880001)
			(xy 76.782702 -101.915689) (xy 76.736855 -101.945153) (xy 76.687281 -101.967791) (xy 76.63499 -101.983145)
			(xy 76.581046 -101.9909) (xy 76.526547 -101.9909) (xy 76.472604 -101.983143) (xy 76.420313 -101.967789)
			(xy 76.37074 -101.94515) (xy 76.324893 -101.915685) (xy 76.283705 -101.879997) (xy 76.248016 -101.83881)
			(xy 76.218552 -101.792963) (xy 76.195912 -101.74339) (xy 76.180557 -101.691099) (xy 76.172801 -101.637155)
			(xy 76.172314 -101.609906) (xy 76.17246 -101.596202) (xy 76.174496 -101.568871) (xy 76.176378 -101.555296)
			(xy 76.178156 -101.542596) (xy 76.170028 -101.519482) (xy 76.089256 -101.44506) (xy 76.06538 -101.43871)
			(xy 76.053188 -101.441504) (xy 76.032266 -101.445994) (xy 75.989748 -101.450829) (xy 75.968352 -101.451156)
			(xy 75.939436 -101.450619) (xy 75.882263 -101.441912) (xy 75.827059 -101.424674) (xy 75.775091 -101.399299)
			(xy 75.727548 -101.366371) (xy 75.685522 -101.326643) (xy 75.649974 -101.281026) (xy 75.621719 -101.230566)
			(xy 75.601406 -101.176419) (xy 75.589499 -101.119825) (xy 75.587352 -101.090984) (xy 75.586336 -101.070664)
			(xy 75.557126 -101.042978) (xy 75.14971 -101.042978) (xy 75.138407 -101.04353) (xy 75.117963 -101.053157)
			(xy 75.11034 -101.06152) (xy 75.060302 -101.12248) (xy 75.053691 -101.131545) (xy 75.048276 -101.153288)
			(xy 75.049888 -101.16439) (xy 75.049888 -101.164898) (xy 75.053424 -101.183493) (xy 75.057238 -101.221155)
			(xy 75.057508 -101.240082) (xy 75.057064 -101.267336) (xy 75.049309 -101.321291) (xy 75.033955 -101.373592)
			(xy 75.011313 -101.423176) (xy 74.981845 -101.469033) (xy 74.946151 -101.51023) (xy 74.904958 -101.545927)
			(xy 74.859103 -101.575399) (xy 74.809521 -101.598044) (xy 74.75722 -101.613403) (xy 74.703266 -101.621162)
			(xy 74.648758 -101.621164) (xy 74.594803 -101.613408) (xy 74.542502 -101.598053) (xy 74.492918 -101.57541)
			(xy 74.447062 -101.545942) (xy 74.405866 -101.510247) (xy 74.370169 -101.469053) (xy 74.340698 -101.423198)
			(xy 74.318054 -101.373615) (xy 74.302696 -101.321314) (xy 74.294937 -101.26736) (xy 74.294936 -101.212852)
			(xy 74.302693 -101.158897) (xy 74.318049 -101.106596) (xy 74.340693 -101.057013) (xy 74.370162 -101.011157)
			(xy 74.405857 -100.969962) (xy 74.447052 -100.934265) (xy 74.492908 -100.904796) (xy 74.542491 -100.882151)
			(xy 74.594792 -100.866794) (xy 74.648746 -100.859037) (xy 74.676 -100.858574) (xy 74.7014 -100.859336)
			(xy 74.7119 -100.859542) (xy 74.731699 -100.85261) (xy 74.739754 -100.845874) (xy 74.793856 -100.795074)
			(xy 74.801088 -100.787551) (xy 74.80935 -100.768412) (xy 74.809858 -100.75799) (xy 74.809858 -100.195888)
			(xy 74.80945 -100.185817) (xy 74.801718 -100.167218) (xy 74.794872 -100.15982) (xy 74.78014 -100.145088)
			(xy 74.770683 -100.136657) (xy 74.746433 -100.129446) (xy 74.733912 -100.131372) (xy 74.650854 -100.148644)
			(xy 74.638549 -100.151807) (xy 74.619085 -100.16809) (xy 74.61377 -100.179632) (xy 74.61377 -100.179886)
			(xy 74.602847 -100.206225) (xy 74.574278 -100.255572) (xy 74.53868 -100.300114) (xy 74.496846 -100.338859)
			(xy 74.44971 -100.370944) (xy 74.398322 -100.395652) (xy 74.343828 -100.412434) (xy 74.287442 -100.420914)
			(xy 74.258932 -100.42144) (xy 74.231683 -100.420892) (xy 74.177739 -100.413141) (xy 74.125448 -100.397791)
			(xy 74.075873 -100.375156) (xy 74.030024 -100.345696) (xy 73.988834 -100.310011) (xy 73.953142 -100.268828)
			(xy 73.923674 -100.222984) (xy 73.901031 -100.173412) (xy 73.885673 -100.121123) (xy 73.877912 -100.067181)
			(xy 73.877424 -100.039932) (xy 73.877957 -100.011826) (xy 73.886239 -99.956226) (xy 73.893934 -99.929188)
			(xy 73.89749 -99.917758) (xy 73.893172 -99.893882) (xy 73.837292 -99.818698) (xy 73.829649 -99.80951)
			(xy 73.808331 -99.798775) (xy 73.796398 -99.798124) (xy 70.824598 -99.798124) (xy 70.814528 -99.798542)
			(xy 70.79593 -99.806267) (xy 70.78853 -99.81311) (xy 70.714362 -99.887532) (xy 70.706933 -99.895697)
			(xy 70.699287 -99.916377) (xy 70.69963 -99.92741) (xy 70.706742 -100.015802) (xy 70.717664 -100.035106)
			(xy 70.726808 -100.04171) (xy 70.7475 -100.057157) (xy 70.784977 -100.092675) (xy 70.817318 -100.132926)
			(xy 70.843933 -100.177173) (xy 70.864335 -100.224606) (xy 70.87815 -100.274358) (xy 70.885125 -100.325519)
			(xy 70.885558 -100.351336) (xy 70.885178 -100.378592) (xy 70.877415 -100.432549) (xy 70.862052 -100.484851)
			(xy 70.839402 -100.534435) (xy 70.809925 -100.58029) (xy 70.774223 -100.621484) (xy 70.733021 -100.657177)
			(xy 70.687159 -100.686643) (xy 70.63757 -100.709282) (xy 70.585264 -100.724634) (xy 70.531306 -100.732385)
			(xy 70.50405 -100.732844) (xy 70.475281 -100.732243) (xy 70.418396 -100.723609) (xy 70.363452 -100.70653)
			(xy 70.311697 -100.681393) (xy 70.264304 -100.648769) (xy 70.222347 -100.609397) (xy 70.18678 -100.56417)
			(xy 70.158408 -100.514115) (xy 70.137876 -100.460366) (xy 70.125649 -100.404143) (xy 70.123304 -100.375466)
			(xy 70.122296 -100.366034) (xy 70.114326 -100.348834) (xy 70.10781 -100.341938) (xy 70.070218 -100.30587)
			(xy 70.052946 -100.306124) (xy 69.148452 -100.306124) (xy 69.138385 -100.30657) (xy 69.119787 -100.314276)
			(xy 69.112384 -100.32111) (xy 67.483482 -101.950266) (xy 67.475625 -101.959002) (xy 67.468077 -101.981226)
			(xy 67.469004 -101.992938) (xy 67.479418 -102.072694) (xy 67.481527 -102.084106) (xy 67.49435 -102.103418)
			(xy 67.504056 -102.109778) (xy 67.50431 -102.110032) (xy 67.528675 -102.124801) (xy 67.573148 -102.160409)
			(xy 67.611832 -102.202235) (xy 67.643865 -102.249349) (xy 67.668536 -102.300702) (xy 67.685296 -102.355154)
			(xy 67.693772 -102.411492) (xy 67.694302 -102.439978) (xy 73.912982 -102.439978) (xy 73.917053 -102.384356)
			(xy 73.929179 -102.329919) (xy 73.949102 -102.277828) (xy 73.976398 -102.229193) (xy 74.010484 -102.18505)
			(xy 74.050633 -102.146341) (xy 74.095991 -102.11389) (xy 74.145591 -102.088389) (xy 74.198375 -102.070382)
			(xy 74.253218 -102.060252) (xy 74.308952 -102.058215) (xy 74.364389 -102.064315) (xy 74.418346 -102.078421)
			(xy 74.442526 -102.088696) (xy 78.169514 -102.088696) (xy 78.173585 -102.033074) (xy 78.185711 -101.978637)
			(xy 78.205634 -101.926546) (xy 78.23293 -101.877911) (xy 78.267016 -101.833768) (xy 78.307165 -101.795059)
			(xy 78.352523 -101.762608) (xy 78.402123 -101.737107) (xy 78.454907 -101.7191) (xy 78.50975 -101.70897)
			(xy 78.565484 -101.706933) (xy 78.620921 -101.713033) (xy 78.674878 -101.727139) (xy 78.726207 -101.748951)
			(xy 78.773813 -101.778005) (xy 78.816681 -101.81368) (xy 78.853898 -101.855217) (xy 78.884671 -101.90173)
			(xy 78.908343 -101.952227) (xy 78.924411 -102.005634) (xy 78.932531 -102.06081) (xy 78.93304 -102.088696)
			(xy 78.932531 -102.116582) (xy 78.924411 -102.171758) (xy 78.908343 -102.225165) (xy 78.884671 -102.275662)
			(xy 78.853898 -102.322175) (xy 78.816681 -102.363712) (xy 78.773813 -102.399387) (xy 78.726207 -102.428441)
			(xy 78.674878 -102.450253) (xy 78.620921 -102.464359) (xy 78.565484 -102.470459) (xy 78.50975 -102.468422)
			(xy 78.454907 -102.458292) (xy 78.402123 -102.440285) (xy 78.352523 -102.414784) (xy 78.307165 -102.382333)
			(xy 78.267016 -102.343624) (xy 78.23293 -102.299481) (xy 78.205634 -102.250846) (xy 78.185711 -102.198755)
			(xy 78.173585 -102.144318) (xy 78.169514 -102.088696) (xy 74.442526 -102.088696) (xy 74.469675 -102.100233)
			(xy 74.517281 -102.129287) (xy 74.560149 -102.164962) (xy 74.597366 -102.206499) (xy 74.628139 -102.253012)
			(xy 74.651811 -102.303509) (xy 74.667879 -102.356916) (xy 74.675999 -102.412092) (xy 74.676508 -102.439978)
			(xy 74.675999 -102.467864) (xy 74.672889 -102.489) (xy 74.801982 -102.489) (xy 74.806053 -102.433378)
			(xy 74.818179 -102.378941) (xy 74.838102 -102.32685) (xy 74.865398 -102.278215) (xy 74.899484 -102.234072)
			(xy 74.939633 -102.195363) (xy 74.984991 -102.162912) (xy 75.034591 -102.137411) (xy 75.087375 -102.119404)
			(xy 75.142218 -102.109274) (xy 75.197952 -102.107237) (xy 75.253389 -102.113337) (xy 75.307346 -102.127443)
			(xy 75.358675 -102.149255) (xy 75.406281 -102.178309) (xy 75.449149 -102.213984) (xy 75.486366 -102.255521)
			(xy 75.517139 -102.302034) (xy 75.540811 -102.352531) (xy 75.556879 -102.405938) (xy 75.564999 -102.461114)
			(xy 75.565508 -102.489) (xy 75.564999 -102.516886) (xy 75.556879 -102.572062) (xy 75.540811 -102.625469)
			(xy 75.517139 -102.675966) (xy 75.486366 -102.722479) (xy 75.449149 -102.764016) (xy 75.406281 -102.799691)
			(xy 75.358675 -102.828745) (xy 75.307346 -102.850557) (xy 75.253389 -102.864663) (xy 75.197952 -102.870763)
			(xy 75.142218 -102.868726) (xy 75.087375 -102.858596) (xy 75.034591 -102.840589) (xy 74.984991 -102.815088)
			(xy 74.939633 -102.782637) (xy 74.899484 -102.743928) (xy 74.865398 -102.699785) (xy 74.838102 -102.65115)
			(xy 74.818179 -102.599059) (xy 74.806053 -102.544622) (xy 74.801982 -102.489) (xy 74.672889 -102.489)
			(xy 74.667879 -102.52304) (xy 74.651811 -102.576447) (xy 74.628139 -102.626944) (xy 74.597366 -102.673457)
			(xy 74.560149 -102.714994) (xy 74.517281 -102.750669) (xy 74.469675 -102.779723) (xy 74.418346 -102.801535)
			(xy 74.364389 -102.815641) (xy 74.308952 -102.821741) (xy 74.253218 -102.819704) (xy 74.198375 -102.809574)
			(xy 74.145591 -102.791567) (xy 74.095991 -102.766066) (xy 74.050633 -102.733615) (xy 74.010484 -102.694906)
			(xy 73.976398 -102.650763) (xy 73.949102 -102.602128) (xy 73.929179 -102.550037) (xy 73.917053 -102.4956)
			(xy 73.912982 -102.439978) (xy 67.694302 -102.439978) (xy 67.693785 -102.467752) (xy 67.685732 -102.522712)
			(xy 67.669794 -102.575924) (xy 67.646306 -102.626262) (xy 67.615767 -102.67266) (xy 67.578821 -102.71414)
			(xy 67.53625 -102.749822) (xy 67.488954 -102.778953) (xy 67.437934 -102.800917) (xy 67.384267 -102.81525)
			(xy 67.356736 -102.818946) (xy 67.356482 -102.818946) (xy 67.347327 -102.820472) (xy 67.330887 -102.829049)
			(xy 67.318559 -102.842899) (xy 67.311945 -102.860222) (xy 67.311524 -102.869492) (xy 67.311524 -103.104696)
			(xy 78.169514 -103.104696) (xy 78.173585 -103.049074) (xy 78.185711 -102.994637) (xy 78.205634 -102.942546)
			(xy 78.23293 -102.893911) (xy 78.267016 -102.849768) (xy 78.307165 -102.811059) (xy 78.352523 -102.778608)
			(xy 78.402123 -102.753107) (xy 78.454907 -102.7351) (xy 78.50975 -102.72497) (xy 78.565484 -102.722933)
			(xy 78.620921 -102.729033) (xy 78.674878 -102.743139) (xy 78.726207 -102.764951) (xy 78.773813 -102.794005)
			(xy 78.816681 -102.82968) (xy 78.853898 -102.871217) (xy 78.884671 -102.91773) (xy 78.908343 -102.968227)
			(xy 78.924411 -103.021634) (xy 78.932531 -103.07681) (xy 78.93304 -103.104696) (xy 78.932531 -103.132582)
			(xy 78.931551 -103.13924) (xy 89.507058 -103.13924) (xy 89.511129 -103.083618) (xy 89.523255 -103.029181)
			(xy 89.543178 -102.97709) (xy 89.570474 -102.928455) (xy 89.60456 -102.884312) (xy 89.644709 -102.845603)
			(xy 89.690067 -102.813152) (xy 89.739667 -102.787651) (xy 89.792451 -102.769644) (xy 89.847294 -102.759514)
			(xy 89.903028 -102.757477) (xy 89.958465 -102.763577) (xy 90.012422 -102.777683) (xy 90.063751 -102.799495)
			(xy 90.111357 -102.828549) (xy 90.154225 -102.864224) (xy 90.191442 -102.905761) (xy 90.222215 -102.952274)
			(xy 90.245887 -103.002771) (xy 90.261955 -103.056178) (xy 90.270075 -103.111354) (xy 90.270584 -103.13924)
			(xy 90.270075 -103.167126) (xy 90.261955 -103.222302) (xy 90.245887 -103.275709) (xy 90.222215 -103.326206)
			(xy 90.191442 -103.372719) (xy 90.154225 -103.414256) (xy 90.111357 -103.449931) (xy 90.063751 -103.478985)
			(xy 90.012422 -103.500797) (xy 89.958465 -103.514903) (xy 89.903028 -103.521003) (xy 89.847294 -103.518966)
			(xy 89.792451 -103.508836) (xy 89.739667 -103.490829) (xy 89.690067 -103.465328) (xy 89.644709 -103.432877)
			(xy 89.60456 -103.394168) (xy 89.570474 -103.350025) (xy 89.543178 -103.30139) (xy 89.523255 -103.249299)
			(xy 89.511129 -103.194862) (xy 89.507058 -103.13924) (xy 78.931551 -103.13924) (xy 78.924411 -103.187758)
			(xy 78.908343 -103.241165) (xy 78.884671 -103.291662) (xy 78.853898 -103.338175) (xy 78.816681 -103.379712)
			(xy 78.773813 -103.415387) (xy 78.726207 -103.444441) (xy 78.674878 -103.466253) (xy 78.620921 -103.480359)
			(xy 78.565484 -103.486459) (xy 78.50975 -103.484422) (xy 78.454907 -103.474292) (xy 78.402123 -103.456285)
			(xy 78.352523 -103.430784) (xy 78.307165 -103.398333) (xy 78.267016 -103.359624) (xy 78.23293 -103.315481)
			(xy 78.205634 -103.266846) (xy 78.185711 -103.214755) (xy 78.173585 -103.160318) (xy 78.169514 -103.104696)
			(xy 67.311524 -103.104696) (xy 67.311524 -103.810562) (xy 67.311855 -103.819853) (xy 67.318442 -103.837227)
			(xy 67.330799 -103.851104) (xy 67.347297 -103.859653) (xy 67.356482 -103.861108) (xy 67.356736 -103.861108)
			(xy 67.384261 -103.864851) (xy 67.437925 -103.879182) (xy 67.488945 -103.901144) (xy 67.536239 -103.930272)
			(xy 67.57881 -103.965952) (xy 67.615756 -104.007428) (xy 67.646296 -104.053824) (xy 67.669785 -104.104158)
			(xy 67.685726 -104.157367) (xy 67.693781 -104.212325) (xy 67.693781 -104.240076) (xy 73.912982 -104.240076)
			(xy 73.917053 -104.184454) (xy 73.929179 -104.130017) (xy 73.949102 -104.077926) (xy 73.976398 -104.029291)
			(xy 74.010484 -103.985148) (xy 74.050633 -103.946439) (xy 74.095991 -103.913988) (xy 74.145591 -103.888487)
			(xy 74.198375 -103.87048) (xy 74.253218 -103.86035) (xy 74.308952 -103.858313) (xy 74.364389 -103.864413)
			(xy 74.418346 -103.878519) (xy 74.435951 -103.886) (xy 75.309982 -103.886) (xy 75.314053 -103.830378)
			(xy 75.326179 -103.775941) (xy 75.346102 -103.72385) (xy 75.373398 -103.675215) (xy 75.407484 -103.631072)
			(xy 75.447633 -103.592363) (xy 75.492991 -103.559912) (xy 75.542591 -103.534411) (xy 75.595375 -103.516404)
			(xy 75.650218 -103.506274) (xy 75.705952 -103.504237) (xy 75.761389 -103.510337) (xy 75.815346 -103.524443)
			(xy 75.866675 -103.546255) (xy 75.914281 -103.575309) (xy 75.957149 -103.610984) (xy 75.994366 -103.652521)
			(xy 76.025139 -103.699034) (xy 76.048811 -103.749531) (xy 76.064879 -103.802938) (xy 76.072999 -103.858114)
			(xy 76.073508 -103.886) (xy 76.072999 -103.913886) (xy 76.064879 -103.969062) (xy 76.048811 -104.022469)
			(xy 76.025139 -104.072966) (xy 75.994366 -104.119479) (xy 75.993276 -104.120696) (xy 78.169514 -104.120696)
			(xy 78.173585 -104.065074) (xy 78.185711 -104.010637) (xy 78.205634 -103.958546) (xy 78.23293 -103.909911)
			(xy 78.267016 -103.865768) (xy 78.307165 -103.827059) (xy 78.352523 -103.794608) (xy 78.402123 -103.769107)
			(xy 78.454907 -103.7511) (xy 78.50975 -103.74097) (xy 78.565484 -103.738933) (xy 78.620921 -103.745033)
			(xy 78.674878 -103.759139) (xy 78.726207 -103.780951) (xy 78.773813 -103.810005) (xy 78.816681 -103.84568)
			(xy 78.853898 -103.887217) (xy 78.884671 -103.93373) (xy 78.908343 -103.984227) (xy 78.924411 -104.037634)
			(xy 78.932531 -104.09281) (xy 78.93304 -104.120696) (xy 78.932531 -104.148582) (xy 78.924411 -104.203758)
			(xy 78.908343 -104.257165) (xy 78.884671 -104.307662) (xy 78.853898 -104.354175) (xy 78.816681 -104.395712)
			(xy 78.773813 -104.431387) (xy 78.726207 -104.460441) (xy 78.674878 -104.482253) (xy 78.620921 -104.496359)
			(xy 78.565484 -104.502459) (xy 78.50975 -104.500422) (xy 78.454907 -104.490292) (xy 78.402123 -104.472285)
			(xy 78.352523 -104.446784) (xy 78.307165 -104.414333) (xy 78.267016 -104.375624) (xy 78.23293 -104.331481)
			(xy 78.205634 -104.282846) (xy 78.185711 -104.230755) (xy 78.173585 -104.176318) (xy 78.169514 -104.120696)
			(xy 75.993276 -104.120696) (xy 75.957149 -104.161016) (xy 75.914281 -104.196691) (xy 75.866675 -104.225745)
			(xy 75.815346 -104.247557) (xy 75.761389 -104.261663) (xy 75.705952 -104.267763) (xy 75.650218 -104.265726)
			(xy 75.595375 -104.255596) (xy 75.542591 -104.237589) (xy 75.492991 -104.212088) (xy 75.447633 -104.179637)
			(xy 75.407484 -104.140928) (xy 75.373398 -104.096785) (xy 75.346102 -104.04815) (xy 75.326179 -103.996059)
			(xy 75.314053 -103.941622) (xy 75.309982 -103.886) (xy 74.435951 -103.886) (xy 74.469675 -103.900331)
			(xy 74.517281 -103.929385) (xy 74.560149 -103.96506) (xy 74.597366 -104.006597) (xy 74.628139 -104.05311)
			(xy 74.651811 -104.103607) (xy 74.667879 -104.157014) (xy 74.675999 -104.21219) (xy 74.676508 -104.240076)
			(xy 74.675999 -104.267962) (xy 74.667879 -104.323138) (xy 74.651811 -104.376545) (xy 74.628139 -104.427042)
			(xy 74.597366 -104.473555) (xy 74.560149 -104.515092) (xy 74.517281 -104.550767) (xy 74.469675 -104.579821)
			(xy 74.418346 -104.601633) (xy 74.364389 -104.615739) (xy 74.308952 -104.621839) (xy 74.253218 -104.619802)
			(xy 74.198375 -104.609672) (xy 74.145591 -104.591665) (xy 74.095991 -104.566164) (xy 74.050633 -104.533713)
			(xy 74.010484 -104.495004) (xy 73.976398 -104.450861) (xy 73.949102 -104.402226) (xy 73.929179 -104.350135)
			(xy 73.917053 -104.295698) (xy 73.912982 -104.240076) (xy 67.693781 -104.240076) (xy 67.693782 -104.26787)
			(xy 67.685727 -104.322828) (xy 67.669787 -104.376037) (xy 67.646299 -104.426371) (xy 67.615759 -104.472768)
			(xy 67.578814 -104.514244) (xy 67.536244 -104.549924) (xy 67.488949 -104.579054) (xy 67.437931 -104.601016)
			(xy 67.384266 -104.615348) (xy 67.356736 -104.619044) (xy 67.356482 -104.619044) (xy 67.347327 -104.620572)
			(xy 67.330888 -104.629148) (xy 67.31856 -104.642998) (xy 67.311945 -104.66032) (xy 67.311524 -104.66959)
			(xy 67.311524 -104.674924) (xy 88.559384 -104.674924) (xy 88.563455 -104.619302) (xy 88.575581 -104.564865)
			(xy 88.595504 -104.512774) (xy 88.6228 -104.464139) (xy 88.656886 -104.419996) (xy 88.697035 -104.381287)
			(xy 88.742393 -104.348836) (xy 88.791993 -104.323335) (xy 88.844777 -104.305328) (xy 88.89962 -104.295198)
			(xy 88.955354 -104.293161) (xy 89.010791 -104.299261) (xy 89.064748 -104.313367) (xy 89.116077 -104.335179)
			(xy 89.163683 -104.364233) (xy 89.206551 -104.399908) (xy 89.243768 -104.441445) (xy 89.274541 -104.487958)
			(xy 89.298213 -104.538455) (xy 89.314281 -104.591862) (xy 89.322401 -104.647038) (xy 89.32291 -104.674924)
			(xy 89.322401 -104.70281) (xy 89.314281 -104.757986) (xy 89.298213 -104.811393) (xy 89.274541 -104.86189)
			(xy 89.243768 -104.908403) (xy 89.206551 -104.94994) (xy 89.163683 -104.985615) (xy 89.116077 -105.014669)
			(xy 89.064748 -105.036481) (xy 89.010791 -105.050587) (xy 88.955354 -105.056687) (xy 88.89962 -105.05465)
			(xy 88.844777 -105.04452) (xy 88.791993 -105.026513) (xy 88.742393 -105.001012) (xy 88.697035 -104.968561)
			(xy 88.656886 -104.929852) (xy 88.6228 -104.885709) (xy 88.595504 -104.837074) (xy 88.575581 -104.784983)
			(xy 88.563455 -104.730546) (xy 88.559384 -104.674924) (xy 67.311524 -104.674924) (xy 67.311524 -106.098848)
			(xy 67.312261 -106.111194) (xy 67.323664 -106.133093) (xy 67.333368 -106.140758) (xy 67.402202 -106.188256)
			(xy 67.412605 -106.194618) (xy 67.436765 -106.197655) (xy 67.44843 -106.194098) (xy 67.448684 -106.194098)
			(xy 67.488199 -106.179819) (xy 67.569222 -106.157555) (xy 67.651909 -106.142617) (xy 67.735601 -106.135123)
			(xy 67.777614 -106.134662) (xy 67.821062 -106.135224) (xy 67.907587 -106.143243) (xy 67.993004 -106.159212)
			(xy 68.076582 -106.182993) (xy 68.15761 -106.214384) (xy 68.235396 -106.253118) (xy 68.309276 -106.298864)
			(xy 68.37862 -106.351231) (xy 68.442837 -106.409773) (xy 68.501378 -106.47399) (xy 68.553744 -106.543335)
			(xy 68.599489 -106.617216) (xy 68.638221 -106.695003) (xy 68.669611 -106.776031) (xy 68.693392 -106.85961)
			(xy 68.709358 -106.945026) (xy 68.717376 -107.031552) (xy 68.717376 -107.118441) (xy 69.090703 -107.118441)
			(xy 69.090703 -107.031559) (xy 69.098719 -106.945046) (xy 69.114685 -106.859643) (xy 69.138462 -106.776077)
			(xy 69.169848 -106.695062) (xy 69.208576 -106.617288) (xy 69.254315 -106.543419) (xy 69.306675 -106.474086)
			(xy 69.365209 -106.409881) (xy 69.429417 -106.351349) (xy 69.498753 -106.298993) (xy 69.572623 -106.253257)
			(xy 69.650398 -106.214532) (xy 69.731415 -106.183149) (xy 69.814982 -106.159375) (xy 69.900386 -106.143414)
			(xy 69.986899 -106.135401) (xy 70.03034 -106.134916) (xy 71.88454 -106.134916) (xy 71.927976 -106.135479)
			(xy 72.014476 -106.143498) (xy 72.099867 -106.159464) (xy 72.183421 -106.18324) (xy 72.264425 -106.214624)
			(xy 72.342188 -106.253349) (xy 72.416046 -106.299082) (xy 72.485369 -106.351436) (xy 72.549566 -106.409962)
			(xy 72.60809 -106.474162) (xy 72.66044 -106.543487) (xy 72.706171 -106.617347) (xy 72.744892 -106.695111)
			(xy 72.776272 -106.776117) (xy 72.800045 -106.859672) (xy 72.816007 -106.945064) (xy 72.824022 -107.031564)
			(xy 72.824022 -107.11842) (xy 74.207618 -107.11842) (xy 74.207618 -107.03152) (xy 74.215636 -106.944991)
			(xy 74.231604 -106.859571) (xy 74.255385 -106.775989) (xy 74.286777 -106.694957) (xy 74.325511 -106.617168)
			(xy 74.371258 -106.543284) (xy 74.423627 -106.473937) (xy 74.482171 -106.409717) (xy 74.546391 -106.351173)
			(xy 74.615738 -106.298804) (xy 74.689622 -106.253057) (xy 74.767411 -106.214323) (xy 74.848443 -106.182931)
			(xy 74.932025 -106.15915) (xy 75.017445 -106.143182) (xy 75.103974 -106.135164) (xy 75.190874 -106.135164)
			(xy 75.277403 -106.143182) (xy 75.362823 -106.15915) (xy 75.446405 -106.182931) (xy 75.527437 -106.214323)
			(xy 75.605226 -106.253057) (xy 75.67911 -106.298804) (xy 75.748457 -106.351173) (xy 75.785401 -106.384852)
			(xy 77.512924 -106.384852) (xy 77.516995 -106.32923) (xy 77.529121 -106.274793) (xy 77.549044 -106.222702)
			(xy 77.57634 -106.174067) (xy 77.610426 -106.129924) (xy 77.650575 -106.091215) (xy 77.695933 -106.058764)
			(xy 77.745533 -106.033263) (xy 77.798317 -106.015256) (xy 77.85316 -106.005126) (xy 77.908894 -106.003089)
			(xy 77.964331 -106.009189) (xy 78.018288 -106.023295) (xy 78.069617 -106.045107) (xy 78.117223 -106.074161)
			(xy 78.160091 -106.109836) (xy 78.197308 -106.151373) (xy 78.228081 -106.197886) (xy 78.251753 -106.248383)
			(xy 78.267821 -106.30179) (xy 78.275941 -106.356966) (xy 78.27645 -106.384852) (xy 78.275941 -106.412738)
			(xy 78.267821 -106.467914) (xy 78.251753 -106.521321) (xy 78.228081 -106.571818) (xy 78.197308 -106.618331)
			(xy 78.160091 -106.659868) (xy 78.117223 -106.695543) (xy 78.069617 -106.724597) (xy 78.018288 -106.746409)
			(xy 77.964331 -106.760515) (xy 77.908894 -106.766615) (xy 77.85316 -106.764578) (xy 77.798317 -106.754448)
			(xy 77.745533 -106.736441) (xy 77.695933 -106.71094) (xy 77.650575 -106.678489) (xy 77.610426 -106.63978)
			(xy 77.57634 -106.595637) (xy 77.549044 -106.547002) (xy 77.529121 -106.494911) (xy 77.516995 -106.440474)
			(xy 77.512924 -106.384852) (xy 75.785401 -106.384852) (xy 75.812677 -106.409717) (xy 75.871221 -106.473937)
			(xy 75.92359 -106.543284) (xy 75.969337 -106.617168) (xy 76.008071 -106.694957) (xy 76.039463 -106.775989)
			(xy 76.063244 -106.859571) (xy 76.079212 -106.944991) (xy 76.08723 -107.03152) (xy 76.087732 -107.07497)
			(xy 76.08723 -107.11842) (xy 76.079212 -107.204949) (xy 76.078202 -107.210352) (xy 85.74278 -107.210352)
			(xy 85.74328 -107.181612) (xy 85.751909 -107.124784) (xy 85.768965 -107.069893) (xy 85.794062 -107.018182)
			(xy 85.826631 -106.97082) (xy 85.845904 -106.949494) (xy 85.852508 -106.942636) (xy 85.85962 -106.924602)
			(xy 85.85962 -106.835702) (xy 85.852508 -106.817668) (xy 85.845904 -106.81081) (xy 85.826587 -106.789524)
			(xy 85.794025 -106.742154) (xy 85.768937 -106.690435) (xy 85.751891 -106.635539) (xy 85.743274 -106.578706)
			(xy 85.743279 -106.521224) (xy 85.751907 -106.464393) (xy 85.768963 -106.409499) (xy 85.79406 -106.357785)
			(xy 85.826631 -106.310421) (xy 85.845904 -106.289094) (xy 85.852508 -106.282236) (xy 85.85962 -106.264202)
			(xy 85.85962 -106.175302) (xy 85.852508 -106.157268) (xy 85.845904 -106.15041) (xy 85.826622 -106.129093)
			(xy 85.794055 -106.081729) (xy 85.768963 -106.030015) (xy 85.751916 -105.975122) (xy 85.743298 -105.918292)
			(xy 85.74278 -105.889552) (xy 85.743266 -105.862301) (xy 85.751022 -105.808353) (xy 85.766377 -105.756058)
			(xy 85.789019 -105.706481) (xy 85.818485 -105.660631) (xy 85.854176 -105.61944) (xy 85.895367 -105.583749)
			(xy 85.941217 -105.554283) (xy 85.990794 -105.531641) (xy 86.043089 -105.516286) (xy 86.097037 -105.50853)
			(xy 86.151539 -105.50853) (xy 86.205487 -105.516286) (xy 86.257782 -105.531641) (xy 86.307359 -105.554283)
			(xy 86.353209 -105.583749) (xy 86.3944 -105.61944) (xy 86.430091 -105.660631) (xy 86.459557 -105.706481)
			(xy 86.482199 -105.756058) (xy 86.497554 -105.808353) (xy 86.50531 -105.862301) (xy 86.505796 -105.889552)
			(xy 86.505305 -105.918292) (xy 86.496675 -105.975121) (xy 86.479617 -106.030012) (xy 86.454518 -106.081723)
			(xy 86.421946 -106.129084) (xy 86.402672 -106.15041) (xy 86.396068 -106.157268) (xy 86.388956 -106.175302)
			(xy 86.388956 -106.264202) (xy 86.396068 -106.282236) (xy 86.402672 -106.289094) (xy 86.421895 -106.310462)
			(xy 86.454463 -106.357817) (xy 86.479557 -106.409522) (xy 86.496611 -106.464407) (xy 86.505238 -106.521229)
			(xy 86.505243 -106.578702) (xy 86.496626 -106.635525) (xy 86.479583 -106.690412) (xy 86.454498 -106.742122)
			(xy 86.421939 -106.789483) (xy 86.402672 -106.81081) (xy 86.396068 -106.817668) (xy 86.388956 -106.835702)
			(xy 86.388956 -106.924602) (xy 86.396068 -106.942636) (xy 86.402672 -106.949494) (xy 86.421969 -106.970798)
			(xy 86.454531 -107.018167) (xy 86.473954 -107.058206) (xy 89.573862 -107.058206) (xy 89.5744 -107.029468)
			(xy 89.58302 -106.972641) (xy 89.600068 -106.917751) (xy 89.625156 -106.866039) (xy 89.657717 -106.818676)
			(xy 89.676986 -106.797348) (xy 89.68359 -106.79049) (xy 89.690702 -106.772456) (xy 89.690702 -106.683556)
			(xy 89.68359 -106.665522) (xy 89.676986 -106.658664) (xy 89.657723 -106.637331) (xy 89.625161 -106.589969)
			(xy 89.600071 -106.538258) (xy 89.583023 -106.483368) (xy 89.5744 -106.426542) (xy 89.5744 -106.369066)
			(xy 89.583021 -106.31224) (xy 89.600068 -106.257351) (xy 89.625156 -106.205639) (xy 89.657717 -106.158276)
			(xy 89.676986 -106.136948) (xy 89.68359 -106.13009) (xy 89.690702 -106.112056) (xy 89.690702 -106.023156)
			(xy 89.68359 -106.005122) (xy 89.676986 -105.998264) (xy 89.657726 -105.976927) (xy 89.625156 -105.929569)
			(xy 89.600061 -105.87786) (xy 89.583008 -105.822971) (xy 89.574384 -105.766145) (xy 89.573862 -105.737406)
			(xy 89.574348 -105.710155) (xy 89.582104 -105.656207) (xy 89.597459 -105.603912) (xy 89.620101 -105.554335)
			(xy 89.649567 -105.508485) (xy 89.685258 -105.467294) (xy 89.726449 -105.431603) (xy 89.772299 -105.402137)
			(xy 89.821876 -105.379495) (xy 89.874171 -105.36414) (xy 89.928119 -105.356384) (xy 89.982621 -105.356384)
			(xy 90.036569 -105.36414) (xy 90.088864 -105.379495) (xy 90.138441 -105.402137) (xy 90.184291 -105.431603)
			(xy 90.225482 -105.467294) (xy 90.261173 -105.508485) (xy 90.290639 -105.554335) (xy 90.313281 -105.603912)
			(xy 90.328636 -105.656207) (xy 90.336392 -105.710155) (xy 90.336878 -105.737406) (xy 90.336337 -105.766144)
			(xy 90.327715 -105.82297) (xy 90.310668 -105.877859) (xy 90.285581 -105.929571) (xy 90.253022 -105.976936)
			(xy 90.233754 -105.998264) (xy 90.22715 -106.005122) (xy 90.220038 -106.023156) (xy 90.220038 -106.112056)
			(xy 90.22715 -106.13009) (xy 90.233754 -106.136948) (xy 90.253032 -106.158269) (xy 90.285599 -106.205632)
			(xy 90.310691 -106.257344) (xy 90.327742 -106.312236) (xy 90.336365 -106.369065) (xy 90.336364 -106.426544)
			(xy 90.32774 -106.483372) (xy 90.310688 -106.538264) (xy 90.285594 -106.589976) (xy 90.253026 -106.637338)
			(xy 90.233754 -106.658664) (xy 90.22715 -106.665522) (xy 90.220038 -106.683556) (xy 90.220038 -106.772456)
			(xy 90.22715 -106.79049) (xy 90.233754 -106.797348) (xy 90.253026 -106.818674) (xy 90.285593 -106.866036)
			(xy 90.310685 -106.917748) (xy 90.327735 -106.972639) (xy 90.336357 -107.029467) (xy 90.336878 -107.058206)
			(xy 90.336392 -107.085457) (xy 90.328636 -107.139405) (xy 90.313281 -107.1917) (xy 90.290639 -107.241277)
			(xy 90.261173 -107.287127) (xy 90.225482 -107.328318) (xy 90.184291 -107.364009) (xy 90.138441 -107.393475)
			(xy 90.088864 -107.416117) (xy 90.036569 -107.431472) (xy 89.982621 -107.439228) (xy 89.928119 -107.439228)
			(xy 89.874171 -107.431472) (xy 89.821876 -107.416117) (xy 89.772299 -107.393475) (xy 89.726449 -107.364009)
			(xy 89.685258 -107.328318) (xy 89.649567 -107.287127) (xy 89.620101 -107.241277) (xy 89.597459 -107.1917)
			(xy 89.582104 -107.139405) (xy 89.574348 -107.085457) (xy 89.573862 -107.058206) (xy 86.473954 -107.058206)
			(xy 86.479619 -107.069884) (xy 86.496663 -107.12478) (xy 86.505279 -107.181611) (xy 86.505796 -107.210352)
			(xy 86.50531 -107.237603) (xy 86.497554 -107.291551) (xy 86.482199 -107.343846) (xy 86.459557 -107.393423)
			(xy 86.430091 -107.439273) (xy 86.3944 -107.480464) (xy 86.353209 -107.516155) (xy 86.307359 -107.545621)
			(xy 86.257782 -107.568263) (xy 86.205487 -107.583618) (xy 86.151539 -107.591374) (xy 86.097037 -107.591374)
			(xy 86.043089 -107.583618) (xy 85.990794 -107.568263) (xy 85.941217 -107.545621) (xy 85.895367 -107.516155)
			(xy 85.854176 -107.480464) (xy 85.818485 -107.439273) (xy 85.789019 -107.393423) (xy 85.766377 -107.343846)
			(xy 85.751022 -107.291551) (xy 85.743266 -107.237603) (xy 85.74278 -107.210352) (xy 76.078202 -107.210352)
			(xy 76.063244 -107.290369) (xy 76.039463 -107.373951) (xy 76.008071 -107.454983) (xy 75.969337 -107.532772)
			(xy 75.92359 -107.606656) (xy 75.871221 -107.676003) (xy 75.812677 -107.740223) (xy 75.748457 -107.798767)
			(xy 75.67911 -107.851136) (xy 75.605226 -107.896883) (xy 75.527437 -107.935617) (xy 75.446405 -107.967009)
			(xy 75.362823 -107.99079) (xy 75.277403 -108.006758) (xy 75.190874 -108.014776) (xy 75.103974 -108.014776)
			(xy 75.017445 -108.006758) (xy 74.932025 -107.99079) (xy 74.848443 -107.967009) (xy 74.767411 -107.935617)
			(xy 74.689622 -107.896883) (xy 74.615738 -107.851136) (xy 74.546391 -107.798767) (xy 74.482171 -107.740223)
			(xy 74.423627 -107.676003) (xy 74.371258 -107.606656) (xy 74.325511 -107.532772) (xy 74.286777 -107.454983)
			(xy 74.255385 -107.373951) (xy 74.231604 -107.290369) (xy 74.215636 -107.204949) (xy 74.207618 -107.11842)
			(xy 72.824022 -107.11842) (xy 72.824022 -107.118436) (xy 72.816007 -107.204936) (xy 72.800045 -107.290328)
			(xy 72.776272 -107.373883) (xy 72.744892 -107.454889) (xy 72.706171 -107.532653) (xy 72.66044 -107.606513)
			(xy 72.60809 -107.675838) (xy 72.549566 -107.740038) (xy 72.485369 -107.798564) (xy 72.416046 -107.850918)
			(xy 72.342188 -107.896651) (xy 72.264425 -107.935376) (xy 72.183421 -107.96676) (xy 72.099867 -107.990536)
			(xy 72.014476 -108.006502) (xy 71.927976 -108.014521) (xy 71.88454 -108.015024) (xy 70.03034 -108.015024)
			(xy 69.986899 -108.014599) (xy 69.900386 -108.006586) (xy 69.814982 -107.990625) (xy 69.731415 -107.966851)
			(xy 69.650398 -107.935468) (xy 69.572623 -107.896743) (xy 69.498753 -107.851007) (xy 69.429417 -107.798651)
			(xy 69.365209 -107.740119) (xy 69.306675 -107.675914) (xy 69.254315 -107.606581) (xy 69.208576 -107.532712)
			(xy 69.169848 -107.454938) (xy 69.138462 -107.373923) (xy 69.114685 -107.290357) (xy 69.098719 -107.204954)
			(xy 69.090703 -107.118441) (xy 68.717376 -107.118441) (xy 68.717376 -107.118448) (xy 68.709358 -107.204974)
			(xy 68.693392 -107.29039) (xy 68.669611 -107.373969) (xy 68.638221 -107.454997) (xy 68.599489 -107.532784)
			(xy 68.553744 -107.606665) (xy 68.501378 -107.67601) (xy 68.442837 -107.740227) (xy 68.37862 -107.798769)
			(xy 68.309276 -107.851136) (xy 68.235396 -107.896882) (xy 68.15761 -107.935616) (xy 68.076582 -107.967007)
			(xy 67.993004 -107.990788) (xy 67.907587 -108.006757) (xy 67.821062 -108.014776) (xy 67.777614 -108.015278)
			(xy 67.735602 -108.014797) (xy 67.651914 -108.00729) (xy 67.569229 -107.992351) (xy 67.488205 -107.970101)
			(xy 67.448684 -107.955842) (xy 67.44843 -107.955842) (xy 67.43676 -107.952353) (xy 67.412631 -107.955394)
			(xy 67.402202 -107.961684) (xy 67.333368 -108.009182) (xy 67.323541 -108.016748) (xy 67.312077 -108.038704)
			(xy 67.311524 -108.051092) (xy 67.311524 -108.379006) (xy 90.462862 -108.379006) (xy 90.4634 -108.350268)
			(xy 90.47202 -108.293441) (xy 90.489068 -108.238551) (xy 90.514156 -108.186839) (xy 90.546717 -108.139476)
			(xy 90.565986 -108.118148) (xy 90.57259 -108.11129) (xy 90.579702 -108.093256) (xy 90.579702 -108.004356)
			(xy 90.57259 -107.986322) (xy 90.565986 -107.979464) (xy 90.546723 -107.958131) (xy 90.514161 -107.910769)
			(xy 90.489071 -107.859058) (xy 90.472023 -107.804168) (xy 90.4634 -107.747342) (xy 90.4634 -107.689866)
			(xy 90.472021 -107.63304) (xy 90.489068 -107.578151) (xy 90.514156 -107.526439) (xy 90.546717 -107.479076)
			(xy 90.565986 -107.457748) (xy 90.57259 -107.45089) (xy 90.579702 -107.432856) (xy 90.579702 -107.343956)
			(xy 90.57259 -107.325922) (xy 90.565986 -107.319064) (xy 90.546723 -107.297731) (xy 90.514161 -107.250369)
			(xy 90.489071 -107.198658) (xy 90.472023 -107.143768) (xy 90.4634 -107.086942) (xy 90.4634 -107.029466)
			(xy 90.472021 -106.97264) (xy 90.489068 -106.917751) (xy 90.514156 -106.866039) (xy 90.546717 -106.818676)
			(xy 90.565986 -106.797348) (xy 90.57259 -106.79049) (xy 90.579702 -106.772456) (xy 90.579702 -106.683556)
			(xy 90.57259 -106.665522) (xy 90.565986 -106.658664) (xy 90.546723 -106.637331) (xy 90.514161 -106.589969)
			(xy 90.489071 -106.538258) (xy 90.472023 -106.483368) (xy 90.4634 -106.426542) (xy 90.4634 -106.369066)
			(xy 90.472021 -106.31224) (xy 90.489068 -106.257351) (xy 90.514156 -106.205639) (xy 90.546717 -106.158276)
			(xy 90.565986 -106.136948) (xy 90.57259 -106.13009) (xy 90.579702 -106.112056) (xy 90.579702 -106.023156)
			(xy 90.57259 -106.005122) (xy 90.565986 -105.998264) (xy 90.546723 -105.976931) (xy 90.514161 -105.929569)
			(xy 90.489071 -105.877858) (xy 90.472023 -105.822968) (xy 90.4634 -105.766142) (xy 90.4634 -105.708666)
			(xy 90.472021 -105.65184) (xy 90.489068 -105.596951) (xy 90.514156 -105.545239) (xy 90.546717 -105.497876)
			(xy 90.565986 -105.476548) (xy 90.57259 -105.46969) (xy 90.579702 -105.451656) (xy 90.579702 -105.362756)
			(xy 90.57259 -105.344722) (xy 90.565986 -105.337864) (xy 90.546723 -105.316531) (xy 90.514161 -105.269169)
			(xy 90.489071 -105.217458) (xy 90.472023 -105.162568) (xy 90.4634 -105.105742) (xy 90.4634 -105.048266)
			(xy 90.472021 -104.99144) (xy 90.489068 -104.936551) (xy 90.514156 -104.884839) (xy 90.546717 -104.837476)
			(xy 90.565986 -104.816148) (xy 90.57259 -104.80929) (xy 90.579702 -104.791256) (xy 90.579702 -104.702356)
			(xy 90.57259 -104.684322) (xy 90.565986 -104.677464) (xy 90.546723 -104.656131) (xy 90.514161 -104.608769)
			(xy 90.489071 -104.557058) (xy 90.472023 -104.502168) (xy 90.4634 -104.445342) (xy 90.4634 -104.387866)
			(xy 90.472021 -104.33104) (xy 90.489068 -104.276151) (xy 90.514156 -104.224439) (xy 90.546717 -104.177076)
			(xy 90.565986 -104.155748) (xy 90.57259 -104.14889) (xy 90.579702 -104.130856) (xy 90.579702 -104.041956)
			(xy 90.57259 -104.023922) (xy 90.565986 -104.017064) (xy 90.546723 -103.995731) (xy 90.514161 -103.948369)
			(xy 90.489071 -103.896658) (xy 90.472023 -103.841768) (xy 90.4634 -103.784942) (xy 90.4634 -103.727466)
			(xy 90.472021 -103.67064) (xy 90.489068 -103.615751) (xy 90.514156 -103.564039) (xy 90.546717 -103.516676)
			(xy 90.565986 -103.495348) (xy 90.57259 -103.48849) (xy 90.579702 -103.470456) (xy 90.579702 -103.381556)
			(xy 90.57259 -103.363522) (xy 90.565986 -103.356664) (xy 90.546726 -103.335327) (xy 90.514156 -103.287969)
			(xy 90.489061 -103.23626) (xy 90.472008 -103.181371) (xy 90.463384 -103.124545) (xy 90.462862 -103.095806)
			(xy 90.463323 -103.068599) (xy 90.471046 -103.014737) (xy 90.486351 -102.962521) (xy 90.508926 -102.913012)
			(xy 90.538312 -102.867217) (xy 90.573912 -102.826066) (xy 90.615003 -102.790397) (xy 90.637614 -102.775258)
			(xy 90.645996 -102.769924) (xy 90.657172 -102.753668) (xy 90.67546 -102.674674) (xy 90.67726 -102.665044)
			(xy 90.674266 -102.645705) (xy 90.669618 -102.637082) (xy 90.669364 -102.637082) (xy 90.669364 -102.636574)
			(xy 90.656155 -102.614065) (xy 90.635301 -102.566222) (xy 90.621152 -102.515987) (xy 90.613969 -102.464294)
			(xy 90.613484 -102.4382) (xy 90.613978 -102.410949) (xy 90.621734 -102.357002) (xy 90.637089 -102.304708)
			(xy 90.659729 -102.255131) (xy 90.689195 -102.209281) (xy 90.724886 -102.168091) (xy 90.766075 -102.1324)
			(xy 90.811924 -102.102933) (xy 90.8615 -102.080292) (xy 90.913794 -102.064936) (xy 90.967741 -102.057178)
			(xy 90.994992 -102.056692) (xy 91.024469 -102.057239) (xy 91.082722 -102.066307) (xy 91.138887 -102.084228)
			(xy 91.191626 -102.110576) (xy 91.239684 -102.144722) (xy 91.261184 -102.164896) (xy 91.269566 -102.173024)
			(xy 91.291918 -102.180644) (xy 91.39555 -102.165404) (xy 91.414854 -102.152196) (xy 91.420696 -102.141782)
			(xy 91.435295 -102.116836) (xy 91.470816 -102.071242) (xy 91.512809 -102.031529) (xy 91.560313 -101.998607)
			(xy 91.612241 -101.97323) (xy 91.667404 -101.955979) (xy 91.724538 -101.947249) (xy 91.753436 -101.94671)
			(xy 91.780687 -101.947162) (xy 91.834633 -101.954923) (xy 91.886926 -101.970282) (xy 91.936501 -101.992927)
			(xy 91.982349 -102.022395) (xy 92.023537 -102.058088) (xy 92.059226 -102.09928) (xy 92.088691 -102.14513)
			(xy 92.11133 -102.194708) (xy 92.126684 -102.247002) (xy 92.13444 -102.300949) (xy 92.13444 -102.355451)
			(xy 92.126684 -102.409398) (xy 92.11133 -102.461692) (xy 92.088691 -102.51127) (xy 92.059226 -102.55712)
			(xy 92.023537 -102.598312) (xy 91.982349 -102.634005) (xy 91.936501 -102.663473) (xy 91.886926 -102.686118)
			(xy 91.834633 -102.701477) (xy 91.780687 -102.709238) (xy 91.753436 -102.709726) (xy 91.723958 -102.709184)
			(xy 91.665704 -102.700118) (xy 91.609539 -102.682197) (xy 91.556799 -102.655848) (xy 91.508743 -102.621697)
			(xy 91.487244 -102.601522) (xy 91.478862 -102.593394) (xy 91.45651 -102.585774) (xy 91.352878 -102.601014)
			(xy 91.333574 -102.614222) (xy 91.327732 -102.624636) (xy 91.312085 -102.651397) (xy 91.273447 -102.699869)
			(xy 91.22747 -102.741445) (xy 91.201748 -102.758748) (xy 91.193366 -102.764082) (xy 91.18219 -102.780338)
			(xy 91.163902 -102.859332) (xy 91.16209 -102.868961) (xy 91.16509 -102.888303) (xy 91.169744 -102.896924)
			(xy 91.169998 -102.896924) (xy 91.169998 -102.897432) (xy 91.183206 -102.919942) (xy 91.204061 -102.967784)
			(xy 91.218211 -103.018019) (xy 91.225393 -103.069712) (xy 91.225878 -103.095806) (xy 91.225337 -103.124544)
			(xy 91.216715 -103.18137) (xy 91.199668 -103.236259) (xy 91.174581 -103.287971) (xy 91.142022 -103.335336)
			(xy 91.122754 -103.356664) (xy 91.11615 -103.363522) (xy 91.109038 -103.381556) (xy 91.109038 -103.470456)
			(xy 91.11615 -103.48849) (xy 91.122754 -103.495348) (xy 91.142032 -103.516669) (xy 91.174599 -103.564032)
			(xy 91.199691 -103.615744) (xy 91.216742 -103.670636) (xy 91.225365 -103.727465) (xy 91.225364 -103.784944)
			(xy 91.21674 -103.841772) (xy 91.200476 -103.894128) (xy 92.213936 -103.894128) (xy 92.218007 -103.838506)
			(xy 92.230133 -103.784069) (xy 92.250056 -103.731978) (xy 92.277352 -103.683343) (xy 92.311438 -103.6392)
			(xy 92.351587 -103.600491) (xy 92.396945 -103.56804) (xy 92.446545 -103.542539) (xy 92.499329 -103.524532)
			(xy 92.554172 -103.514402) (xy 92.609906 -103.512365) (xy 92.665343 -103.518465) (xy 92.7193 -103.532571)
			(xy 92.770629 -103.554383) (xy 92.818235 -103.583437) (xy 92.861103 -103.619112) (xy 92.89832 -103.660649)
			(xy 92.929093 -103.707162) (xy 92.952765 -103.757659) (xy 92.968833 -103.811066) (xy 92.976953 -103.866242)
			(xy 92.977388 -103.890064) (xy 93.23908 -103.890064) (xy 93.243151 -103.834442) (xy 93.255277 -103.780005)
			(xy 93.2752 -103.727914) (xy 93.302496 -103.679279) (xy 93.336582 -103.635136) (xy 93.376731 -103.596427)
			(xy 93.422089 -103.563976) (xy 93.471689 -103.538475) (xy 93.524473 -103.520468) (xy 93.579316 -103.510338)
			(xy 93.63505 -103.508301) (xy 93.690487 -103.514401) (xy 93.744444 -103.528507) (xy 93.795773 -103.550319)
			(xy 93.843379 -103.579373) (xy 93.886247 -103.615048) (xy 93.923464 -103.656585) (xy 93.954237 -103.703098)
			(xy 93.977909 -103.753595) (xy 93.993977 -103.807002) (xy 94.002097 -103.862178) (xy 94.002606 -103.890064)
			(xy 94.002097 -103.91795) (xy 93.993977 -103.973126) (xy 93.979 -104.022906) (xy 95.86595 -104.022906)
			(xy 95.866405 -103.996591) (xy 95.873641 -103.944462) (xy 95.887961 -103.893818) (xy 95.909095 -103.845619)
			(xy 95.936644 -103.800776) (xy 95.970087 -103.760138) (xy 95.98914 -103.741982) (xy 95.996543 -103.734461)
			(xy 96.005069 -103.715181) (xy 96.00565 -103.704644) (xy 96.00565 -103.629968) (xy 96.005083 -103.619423)
			(xy 95.996573 -103.600128) (xy 95.98914 -103.59263) (xy 95.970095 -103.574465) (xy 95.936639 -103.533836)
			(xy 95.90908 -103.488997) (xy 95.88794 -103.440798) (xy 95.87362 -103.390153) (xy 95.866391 -103.338021)
			(xy 95.86595 -103.311706) (xy 95.866483 -103.284457) (xy 95.874238 -103.230513) (xy 95.88959 -103.178222)
			(xy 95.912227 -103.128647) (xy 95.941689 -103.082799) (xy 95.977376 -103.04161) (xy 96.01856 -103.005918)
			(xy 96.064405 -102.97645) (xy 96.113977 -102.953807) (xy 96.166266 -102.938448) (xy 96.220209 -102.930687)
			(xy 96.247458 -102.930198) (xy 96.275122 -102.930744) (xy 96.329869 -102.938737) (xy 96.38289 -102.954548)
			(xy 96.433074 -102.977846) (xy 96.47937 -103.008142) (xy 96.520809 -103.044802) (xy 96.556524 -103.087059)
			(xy 96.571562 -103.110284) (xy 96.578207 -103.119953) (xy 96.598063 -103.1324) (xy 96.609662 -103.13416)
			(xy 96.689672 -103.142034) (xy 96.70131 -103.142646) (xy 96.723146 -103.13458) (xy 96.731582 -103.12654)
			(xy 96.731836 -103.126286) (xy 96.749915 -103.107703) (xy 96.790247 -103.075125) (xy 96.834622 -103.048312)
			(xy 96.882221 -103.02776) (xy 96.932166 -103.013847) (xy 96.983535 -103.00683) (xy 97.009458 -103.006398)
			(xy 97.03671 -103.006894) (xy 97.09066 -103.014646) (xy 97.142958 -103.029997) (xy 97.192538 -103.052635)
			(xy 97.238392 -103.082099) (xy 97.279585 -103.117789) (xy 97.315279 -103.158979) (xy 97.344748 -103.20483)
			(xy 97.367391 -103.254408) (xy 97.382747 -103.306705) (xy 97.390503 -103.360654) (xy 97.390966 -103.387906)
			(xy 97.390512 -103.415277) (xy 97.382692 -103.469457) (xy 97.367201 -103.52196) (xy 97.344356 -103.571707)
			(xy 97.314629 -103.617673) (xy 97.296986 -103.638604) (xy 97.296732 -103.638858) (xy 97.291149 -103.645947)
			(xy 97.284902 -103.662862) (xy 97.28454 -103.671878) (xy 97.28454 -103.738934) (xy 97.284872 -103.747954)
			(xy 97.291136 -103.764871) (xy 97.296732 -103.771954) (xy 97.296986 -103.771954) (xy 97.296986 -103.772208)
			(xy 97.31464 -103.793128) (xy 97.34435 -103.839104) (xy 97.367183 -103.888854) (xy 97.382671 -103.941358)
			(xy 97.390495 -103.995536) (xy 97.390966 -104.022906) (xy 97.39055 -104.050161) (xy 97.382791 -104.104116)
			(xy 97.379414 -104.115616) (xy 100.297234 -104.115616) (xy 100.297701 -104.089302) (xy 100.304935 -104.037173)
			(xy 100.319253 -103.98653) (xy 100.340385 -103.938331) (xy 100.367932 -103.893487) (xy 100.401372 -103.852848)
			(xy 100.420424 -103.834692) (xy 100.42782 -103.827165) (xy 100.43635 -103.80789) (xy 100.436934 -103.797354)
			(xy 100.436934 -103.722678) (xy 100.436366 -103.712133) (xy 100.427857 -103.692838) (xy 100.420424 -103.68534)
			(xy 100.401351 -103.667202) (xy 100.367894 -103.626569) (xy 100.340337 -103.581725) (xy 100.319202 -103.533521)
			(xy 100.304888 -103.48287) (xy 100.297669 -103.430733) (xy 100.297234 -103.404416) (xy 100.29772 -103.377165)
			(xy 100.305476 -103.323217) (xy 100.320831 -103.270922) (xy 100.343473 -103.221345) (xy 100.372939 -103.175495)
			(xy 100.40863 -103.134304) (xy 100.449821 -103.098613) (xy 100.495671 -103.069147) (xy 100.545248 -103.046505)
			(xy 100.597543 -103.03115) (xy 100.651491 -103.023394) (xy 100.705993 -103.023394) (xy 100.759941 -103.03115)
			(xy 100.812236 -103.046505) (xy 100.861813 -103.069147) (xy 100.907663 -103.098613) (xy 100.948854 -103.134304)
			(xy 100.984545 -103.175495) (xy 101.014011 -103.221345) (xy 101.036653 -103.270922) (xy 101.052008 -103.323217)
			(xy 101.059764 -103.377165) (xy 101.06025 -103.404416) (xy 101.059809 -103.430731) (xy 101.052571 -103.482861)
			(xy 101.038248 -103.533505) (xy 101.017111 -103.581704) (xy 100.989559 -103.626547) (xy 100.956115 -103.667185)
			(xy 100.93706 -103.68534) (xy 100.929648 -103.692853) (xy 100.921127 -103.712139) (xy 100.920683 -103.720253)
			(xy 103.573038 -103.720253) (xy 103.573038 -103.665747) (xy 103.580794 -103.611796) (xy 103.59615 -103.559498)
			(xy 103.618791 -103.509918) (xy 103.648258 -103.464064) (xy 103.68395 -103.42287) (xy 103.725141 -103.387175)
			(xy 103.770993 -103.357705) (xy 103.820572 -103.33506) (xy 103.872869 -103.3197) (xy 103.926819 -103.31194)
			(xy 103.954072 -103.311452) (xy 103.981442 -103.311922) (xy 104.035622 -103.319737) (xy 104.088125 -103.335224)
			(xy 104.137872 -103.358066) (xy 104.183839 -103.38779) (xy 104.20477 -103.405432) (xy 104.205024 -103.405686)
			(xy 104.212101 -103.411287) (xy 104.229025 -103.417526) (xy 104.238044 -103.417878) (xy 104.3051 -103.417878)
			(xy 104.314117 -103.417526) (xy 104.331035 -103.411276) (xy 104.33812 -103.405686) (xy 104.33812 -103.405432)
			(xy 104.338374 -103.405432) (xy 104.359307 -103.387791) (xy 104.405275 -103.358067) (xy 104.455021 -103.335221)
			(xy 104.507523 -103.319725) (xy 104.561701 -103.311896) (xy 104.616443 -103.311896) (xy 104.670621 -103.319725)
			(xy 104.723123 -103.335221) (xy 104.772869 -103.358067) (xy 104.818837 -103.387791) (xy 104.83977 -103.405432)
			(xy 104.840024 -103.405686) (xy 104.847101 -103.411287) (xy 104.864025 -103.417526) (xy 104.873044 -103.417878)
			(xy 104.9401 -103.417878) (xy 104.949117 -103.417526) (xy 104.966035 -103.411276) (xy 104.97312 -103.405686)
			(xy 104.97312 -103.405432) (xy 104.973374 -103.405432) (xy 104.994309 -103.387797) (xy 105.040281 -103.358083)
			(xy 105.090027 -103.335246) (xy 105.142527 -103.319754) (xy 105.196703 -103.311926) (xy 105.224072 -103.311452)
			(xy 105.251323 -103.311993) (xy 105.305272 -103.319746) (xy 105.357567 -103.335098) (xy 105.407146 -103.357737)
			(xy 105.452998 -103.387201) (xy 105.494189 -103.422891) (xy 105.529882 -103.46408) (xy 105.55935 -103.50993)
			(xy 105.581992 -103.559506) (xy 105.597348 -103.611801) (xy 105.605105 -103.665749) (xy 105.605105 -103.68565)
			(xy 108.492794 -103.68565) (xy 108.492794 -103.63115) (xy 108.50055 -103.577205) (xy 108.515905 -103.524912)
			(xy 108.538545 -103.475338) (xy 108.56801 -103.429489) (xy 108.603699 -103.388301) (xy 108.644888 -103.352611)
			(xy 108.690736 -103.323146) (xy 108.740311 -103.300505) (xy 108.792603 -103.285151) (xy 108.846548 -103.277394)
			(xy 108.873798 -103.276908) (xy 108.900112 -103.277374) (xy 108.952241 -103.284609) (xy 109.002884 -103.298928)
			(xy 109.051083 -103.320061) (xy 109.095926 -103.347607) (xy 109.136566 -103.381046) (xy 109.154722 -103.400098)
			(xy 109.162234 -103.407511) (xy 109.181521 -103.416029) (xy 109.19206 -103.416608) (xy 109.266736 -103.416608)
			(xy 109.277283 -103.416056) (xy 109.296579 -103.407537) (xy 109.304074 -103.400098) (xy 109.323894 -103.37931)
			(xy 109.368666 -103.343335) (xy 109.418324 -103.314475) (xy 109.471746 -103.293382) (xy 109.527725 -103.280533)
			(xy 109.584998 -103.276218) (xy 109.642271 -103.280533) (xy 109.69825 -103.293382) (xy 109.751672 -103.314475)
			(xy 109.80133 -103.343335) (xy 109.846102 -103.37931) (xy 109.865922 -103.400098) (xy 109.873434 -103.407511)
			(xy 109.892721 -103.416029) (xy 109.90326 -103.416608) (xy 109.977936 -103.416608) (xy 109.988483 -103.416056)
			(xy 110.007779 -103.407537) (xy 110.015274 -103.400098) (xy 110.033449 -103.381062) (xy 110.074074 -103.347603)
			(xy 110.118911 -103.320041) (xy 110.167108 -103.2989) (xy 110.217752 -103.284578) (xy 110.269883 -103.277349)
			(xy 110.296198 -103.276908) (xy 110.323452 -103.277339) (xy 110.377406 -103.285096) (xy 110.429706 -103.300452)
			(xy 110.479288 -103.323096) (xy 110.525144 -103.352565) (xy 110.566338 -103.38826) (xy 110.602034 -103.429455)
			(xy 110.631503 -103.47531) (xy 110.654147 -103.524892) (xy 110.669504 -103.577192) (xy 110.677261 -103.631146)
			(xy 110.677261 -103.685654) (xy 110.669504 -103.739608) (xy 110.654147 -103.791908) (xy 110.631503 -103.84149)
			(xy 110.602034 -103.887345) (xy 110.566338 -103.92854) (xy 110.525144 -103.964235) (xy 110.479288 -103.993704)
			(xy 110.429706 -104.016348) (xy 110.377406 -104.031704) (xy 110.323452 -104.039461) (xy 110.296198 -104.039924)
			(xy 110.269884 -104.03945) (xy 110.217756 -104.032216) (xy 110.167114 -104.017897) (xy 110.118915 -103.996766)
			(xy 110.074072 -103.969221) (xy 110.033431 -103.935785) (xy 110.015274 -103.916734) (xy 110.00776 -103.909324)
			(xy 109.988474 -103.900803) (xy 109.977936 -103.900224) (xy 109.90326 -103.900224) (xy 109.892712 -103.900765)
			(xy 109.873416 -103.909291) (xy 109.865922 -103.916734) (xy 109.846102 -103.937522) (xy 109.80133 -103.973497)
			(xy 109.751672 -104.002357) (xy 109.69825 -104.02345) (xy 109.642271 -104.036299) (xy 109.584998 -104.040614)
			(xy 109.527725 -104.036299) (xy 109.471746 -104.02345) (xy 109.418324 -104.002357) (xy 109.368666 -103.973497)
			(xy 109.323894 -103.937522) (xy 109.304074 -103.916734) (xy 109.29656 -103.909324) (xy 109.277274 -103.900803)
			(xy 109.266736 -103.900224) (xy 109.19206 -103.900224) (xy 109.181512 -103.900765) (xy 109.162216 -103.909291)
			(xy 109.154722 -103.916734) (xy 109.136555 -103.935778) (xy 109.095927 -103.969235) (xy 109.051089 -103.996795)
			(xy 109.002891 -104.017935) (xy 108.952245 -104.032255) (xy 108.900113 -104.039483) (xy 108.873798 -104.039924)
			(xy 108.846548 -104.039406) (xy 108.792603 -104.031649) (xy 108.740311 -104.016295) (xy 108.690736 -103.993654)
			(xy 108.644888 -103.964189) (xy 108.603699 -103.928499) (xy 108.56801 -103.887311) (xy 108.538545 -103.841462)
			(xy 108.515905 -103.791888) (xy 108.50055 -103.739595) (xy 108.492794 -103.68565) (xy 105.605105 -103.68565)
			(xy 105.605105 -103.720251) (xy 105.597348 -103.774199) (xy 105.581992 -103.826494) (xy 105.55935 -103.87607)
			(xy 105.529882 -103.92192) (xy 105.494189 -103.963109) (xy 105.452998 -103.998799) (xy 105.407146 -104.028263)
			(xy 105.357567 -104.050902) (xy 105.305272 -104.066254) (xy 105.251323 -104.074007) (xy 105.224072 -104.074468)
			(xy 105.196701 -104.074026) (xy 105.14252 -104.066204) (xy 105.090017 -104.050709) (xy 105.04027 -104.027862)
			(xy 104.994305 -103.998132) (xy 104.973374 -103.980488) (xy 104.97312 -103.980234) (xy 104.966038 -103.974642)
			(xy 104.949117 -103.9684) (xy 104.9401 -103.968042) (xy 104.873044 -103.968042) (xy 104.864028 -103.968411)
			(xy 104.847111 -103.974649) (xy 104.840024 -103.980234) (xy 104.83977 -103.980488) (xy 104.818837 -103.998129)
			(xy 104.772869 -104.027853) (xy 104.723123 -104.050699) (xy 104.670621 -104.066195) (xy 104.616443 -104.074024)
			(xy 104.561701 -104.074024) (xy 104.507523 -104.066195) (xy 104.455021 -104.050699) (xy 104.405275 -104.027853)
			(xy 104.359307 -103.998129) (xy 104.338374 -103.980488) (xy 104.33812 -103.980234) (xy 104.331038 -103.974642)
			(xy 104.314117 -103.9684) (xy 104.3051 -103.968042) (xy 104.238044 -103.968042) (xy 104.229028 -103.968411)
			(xy 104.212111 -103.974649) (xy 104.205024 -103.980234) (xy 104.205024 -103.980488) (xy 104.20477 -103.980488)
			(xy 104.183821 -103.998106) (xy 104.137853 -104.027821) (xy 104.08811 -104.050662) (xy 104.035613 -104.066158)
			(xy 103.98144 -104.073991) (xy 103.954072 -104.074468) (xy 103.926819 -104.07406) (xy 103.872869 -104.0663)
			(xy 103.820572 -104.05094) (xy 103.770993 -104.028295) (xy 103.725141 -103.998825) (xy 103.68395 -103.96313)
			(xy 103.648258 -103.921936) (xy 103.618791 -103.876082) (xy 103.59615 -103.826502) (xy 103.580794 -103.774204)
			(xy 103.573038 -103.720253) (xy 100.920683 -103.720253) (xy 100.92055 -103.722678) (xy 100.92055 -103.797354)
			(xy 100.921105 -103.8079) (xy 100.929624 -103.827195) (xy 100.93706 -103.834692) (xy 100.956116 -103.852847)
			(xy 100.989571 -103.893478) (xy 101.017128 -103.938319) (xy 101.038266 -103.98652) (xy 101.052584 -104.037167)
			(xy 101.05981 -104.0893) (xy 101.06025 -104.115616) (xy 101.059764 -104.142867) (xy 101.052008 -104.196815)
			(xy 101.036653 -104.24911) (xy 101.014011 -104.298687) (xy 100.984545 -104.344537) (xy 100.948854 -104.385728)
			(xy 100.907663 -104.421419) (xy 100.861813 -104.450885) (xy 100.812236 -104.473527) (xy 100.759941 -104.488882)
			(xy 100.705993 -104.496638) (xy 100.651491 -104.496638) (xy 100.597543 -104.488882) (xy 100.545248 -104.473527)
			(xy 100.495671 -104.450885) (xy 100.449821 -104.421419) (xy 100.40863 -104.385728) (xy 100.372939 -104.344537)
			(xy 100.343473 -104.298687) (xy 100.320831 -104.24911) (xy 100.305476 -104.196815) (xy 100.29772 -104.142867)
			(xy 100.297234 -104.115616) (xy 97.379414 -104.115616) (xy 97.367432 -104.156417) (xy 97.344786 -104.206)
			(xy 97.315314 -104.251855) (xy 97.279615 -104.293049) (xy 97.238417 -104.328742) (xy 97.192558 -104.358209)
			(xy 97.142972 -104.380849) (xy 97.090669 -104.396201) (xy 97.036713 -104.403954) (xy 97.009458 -104.404414)
			(xy 96.980541 -104.403886) (xy 96.923369 -104.395164) (xy 96.868169 -104.37791) (xy 96.816206 -104.35252)
			(xy 96.768673 -104.319576) (xy 96.726657 -104.279834) (xy 96.708468 -104.257348) (xy 96.700874 -104.248527)
			(xy 96.679963 -104.238353) (xy 96.668336 -104.23779) (xy 96.58858 -104.23779) (xy 96.576949 -104.238336)
			(xy 96.55604 -104.24852) (xy 96.548448 -104.257348) (xy 96.530242 -104.279818) (xy 96.488224 -104.319552)
			(xy 96.440692 -104.352491) (xy 96.388734 -104.377882) (xy 96.333539 -104.395141) (xy 96.276373 -104.403876)
			(xy 96.247458 -104.404414) (xy 96.220206 -104.403961) (xy 96.166257 -104.396199) (xy 96.113962 -104.380839)
			(xy 96.064385 -104.358193) (xy 96.018536 -104.328723) (xy 95.977346 -104.293029) (xy 95.941655 -104.251836)
			(xy 95.912189 -104.205983) (xy 95.889548 -104.156404) (xy 95.874193 -104.104107) (xy 95.866436 -104.050158)
			(xy 95.86595 -104.022906) (xy 93.979 -104.022906) (xy 93.977909 -104.026533) (xy 93.954237 -104.07703)
			(xy 93.923464 -104.123543) (xy 93.886247 -104.16508) (xy 93.843379 -104.200755) (xy 93.795773 -104.229809)
			(xy 93.744444 -104.251621) (xy 93.690487 -104.265727) (xy 93.63505 -104.271827) (xy 93.579316 -104.26979)
			(xy 93.524473 -104.25966) (xy 93.471689 -104.241653) (xy 93.422089 -104.216152) (xy 93.376731 -104.183701)
			(xy 93.336582 -104.144992) (xy 93.302496 -104.100849) (xy 93.2752 -104.052214) (xy 93.255277 -104.000123)
			(xy 93.243151 -103.945686) (xy 93.23908 -103.890064) (xy 92.977388 -103.890064) (xy 92.977462 -103.894128)
			(xy 92.976953 -103.922014) (xy 92.968833 -103.97719) (xy 92.952765 -104.030597) (xy 92.929093 -104.081094)
			(xy 92.89832 -104.127607) (xy 92.861103 -104.169144) (xy 92.818235 -104.204819) (xy 92.770629 -104.233873)
			(xy 92.7193 -104.255685) (xy 92.665343 -104.269791) (xy 92.609906 -104.275891) (xy 92.554172 -104.273854)
			(xy 92.499329 -104.263724) (xy 92.446545 -104.245717) (xy 92.396945 -104.220216) (xy 92.351587 -104.187765)
			(xy 92.311438 -104.149056) (xy 92.277352 -104.104913) (xy 92.250056 -104.056278) (xy 92.230133 -104.004187)
			(xy 92.218007 -103.94975) (xy 92.213936 -103.894128) (xy 91.200476 -103.894128) (xy 91.199688 -103.896664)
			(xy 91.174594 -103.948376) (xy 91.142026 -103.995738) (xy 91.122754 -104.017064) (xy 91.11615 -104.023922)
			(xy 91.109038 -104.041956) (xy 91.109038 -104.130856) (xy 91.11615 -104.14889) (xy 91.122754 -104.155748)
			(xy 91.142032 -104.177069) (xy 91.174599 -104.224432) (xy 91.199691 -104.276144) (xy 91.216742 -104.331036)
			(xy 91.225365 -104.387865) (xy 91.225364 -104.445344) (xy 91.21674 -104.502172) (xy 91.199688 -104.557064)
			(xy 91.174594 -104.608776) (xy 91.142026 -104.656138) (xy 91.122754 -104.677464) (xy 91.11615 -104.684322)
			(xy 91.109038 -104.702356) (xy 91.109038 -104.791256) (xy 91.11615 -104.80929) (xy 91.122754 -104.816148)
			(xy 91.142032 -104.837469) (xy 91.174599 -104.884832) (xy 91.199691 -104.936544) (xy 91.216742 -104.991436)
			(xy 91.225365 -105.048265) (xy 91.225364 -105.084455) (xy 95.743949 -105.084455) (xy 95.743949 -105.029945)
			(xy 95.751707 -104.975991) (xy 95.767065 -104.92369) (xy 95.78971 -104.874107) (xy 95.819181 -104.828252)
			(xy 95.854879 -104.787058) (xy 95.896076 -104.751363) (xy 95.941933 -104.721896) (xy 95.991518 -104.699255)
			(xy 96.04382 -104.683901) (xy 96.097775 -104.676147) (xy 96.12503 -104.675686) (xy 96.152401 -104.676138)
			(xy 96.20658 -104.68396) (xy 96.259083 -104.699452) (xy 96.30883 -104.722297) (xy 96.354796 -104.752024)
			(xy 96.375728 -104.769666) (xy 96.375982 -104.76992) (xy 96.383068 -104.775507) (xy 96.399985 -104.781753)
			(xy 96.409002 -104.782112) (xy 96.476058 -104.782112) (xy 96.485073 -104.781732) (xy 96.50199 -104.7755)
			(xy 96.509078 -104.76992) (xy 96.509078 -104.769666) (xy 96.509332 -104.769666) (xy 96.530265 -104.752025)
			(xy 96.576233 -104.722301) (xy 96.625979 -104.699455) (xy 96.678481 -104.683959) (xy 96.732659 -104.67613)
			(xy 96.787401 -104.67613) (xy 96.841579 -104.683959) (xy 96.894081 -104.699455) (xy 96.943827 -104.722301)
			(xy 96.989795 -104.752025) (xy 97.010728 -104.769666) (xy 97.010982 -104.76992) (xy 97.018068 -104.775507)
			(xy 97.034985 -104.781753) (xy 97.044002 -104.782112) (xy 97.111058 -104.782112) (xy 97.120073 -104.781732)
			(xy 97.13699 -104.7755) (xy 97.144078 -104.76992) (xy 97.144078 -104.769666) (xy 97.144332 -104.769666)
			(xy 97.165265 -104.752025) (xy 97.211233 -104.722301) (xy 97.260979 -104.699455) (xy 97.313481 -104.683959)
			(xy 97.367659 -104.67613) (xy 97.422401 -104.67613) (xy 97.476579 -104.683959) (xy 97.529081 -104.699455)
			(xy 97.578827 -104.722301) (xy 97.624795 -104.752025) (xy 97.645728 -104.769666) (xy 97.645982 -104.76992)
			(xy 97.653068 -104.775507) (xy 97.669985 -104.781753) (xy 97.679002 -104.782112) (xy 97.746058 -104.782112)
			(xy 97.755073 -104.781732) (xy 97.77199 -104.7755) (xy 97.779078 -104.76992) (xy 97.779078 -104.769666)
			(xy 97.779332 -104.769666) (xy 97.800275 -104.75204) (xy 97.846245 -104.722327) (xy 97.89599 -104.699489)
			(xy 97.948488 -104.683995) (xy 98.002662 -104.676163) (xy 98.03003 -104.675686) (xy 98.057279 -104.676186)
			(xy 98.111223 -104.683946) (xy 98.163513 -104.699303) (xy 98.213086 -104.721946) (xy 98.258932 -104.751412)
			(xy 98.300118 -104.787103) (xy 98.335806 -104.828292) (xy 98.365269 -104.87414) (xy 98.387907 -104.923715)
			(xy 98.403261 -104.976006) (xy 98.411016 -105.029951) (xy 98.411016 -105.084449) (xy 98.411015 -105.084454)
			(xy 99.667749 -105.084454) (xy 99.667749 -105.029946) (xy 99.675507 -104.975992) (xy 99.690864 -104.923692)
			(xy 99.713509 -104.874109) (xy 99.742979 -104.828254) (xy 99.778676 -104.78706) (xy 99.819872 -104.751366)
			(xy 99.865729 -104.721898) (xy 99.915312 -104.699257) (xy 99.967614 -104.683902) (xy 100.021568 -104.676148)
			(xy 100.048822 -104.675686) (xy 100.075136 -104.676143) (xy 100.127265 -104.683381) (xy 100.177908 -104.697702)
			(xy 100.226107 -104.718837) (xy 100.27095 -104.746384) (xy 100.311589 -104.779824) (xy 100.329746 -104.798876)
			(xy 100.337252 -104.806296) (xy 100.356544 -104.814811) (xy 100.367084 -104.815386) (xy 100.44176 -104.815386)
			(xy 100.452309 -104.814853) (xy 100.471605 -104.806321) (xy 100.479098 -104.798876) (xy 100.497257 -104.779824)
			(xy 100.537886 -104.746367) (xy 100.582726 -104.718808) (xy 100.630926 -104.69767) (xy 100.681573 -104.683351)
			(xy 100.733706 -104.676125) (xy 100.760022 -104.675686) (xy 100.787393 -104.676143) (xy 100.841572 -104.683963)
			(xy 100.894075 -104.699455) (xy 100.943822 -104.722298) (xy 100.989788 -104.752024) (xy 101.01072 -104.769666)
			(xy 101.010974 -104.76992) (xy 101.018062 -104.775504) (xy 101.034978 -104.781752) (xy 101.043994 -104.782112)
			(xy 101.11105 -104.782112) (xy 101.120064 -104.781729) (xy 101.136981 -104.775499) (xy 101.14407 -104.76992)
			(xy 101.14407 -104.769666) (xy 101.144324 -104.769666) (xy 101.165257 -104.752025) (xy 101.211225 -104.722301)
			(xy 101.260971 -104.699455) (xy 101.313473 -104.683959) (xy 101.367651 -104.67613) (xy 101.422393 -104.67613)
			(xy 101.476571 -104.683959) (xy 101.529073 -104.699455) (xy 101.578819 -104.722301) (xy 101.624787 -104.752025)
			(xy 101.64572 -104.769666) (xy 101.645974 -104.76992) (xy 101.653062 -104.775504) (xy 101.669978 -104.781752)
			(xy 101.678994 -104.782112) (xy 101.74605 -104.782112) (xy 101.755064 -104.781729) (xy 101.771981 -104.775499)
			(xy 101.77907 -104.76992) (xy 101.77907 -104.769666) (xy 101.779324 -104.769666) (xy 101.80027 -104.752044)
			(xy 101.846239 -104.722331) (xy 101.895983 -104.699492) (xy 101.948481 -104.683997) (xy 102.002654 -104.676163)
			(xy 102.030022 -104.675686) (xy 102.057272 -104.676185) (xy 102.111216 -104.683944) (xy 102.163508 -104.699301)
			(xy 102.213081 -104.721943) (xy 102.233191 -104.734868) (xy 124.328172 -104.734868) (xy 124.332243 -104.679246)
			(xy 124.344369 -104.624809) (xy 124.364292 -104.572718) (xy 124.391588 -104.524083) (xy 124.425674 -104.47994)
			(xy 124.465823 -104.441231) (xy 124.511181 -104.40878) (xy 124.560781 -104.383279) (xy 124.613565 -104.365272)
			(xy 124.668408 -104.355142) (xy 124.724142 -104.353105) (xy 124.779579 -104.359205) (xy 124.833536 -104.373311)
			(xy 124.884865 -104.395123) (xy 124.932471 -104.424177) (xy 124.975339 -104.459852) (xy 125.012556 -104.501389)
			(xy 125.043329 -104.547902) (xy 125.044573 -104.550555) (xy 150.210441 -104.550555) (xy 150.210441 -104.496045)
			(xy 150.218199 -104.44209) (xy 150.233556 -104.389789) (xy 150.256201 -104.340206) (xy 150.285672 -104.29435)
			(xy 150.321369 -104.253155) (xy 150.362566 -104.21746) (xy 150.408423 -104.187992) (xy 150.458008 -104.165349)
			(xy 150.51031 -104.149994) (xy 150.564265 -104.14224) (xy 150.59152 -104.141778) (xy 150.617457 -104.142195)
			(xy 150.668853 -104.149226) (xy 150.718823 -104.163156) (xy 150.766444 -104.183728) (xy 150.810839 -104.210562)
			(xy 150.851189 -104.243164) (xy 150.88675 -104.280932) (xy 150.902162 -104.301798) (xy 150.907978 -104.309136)
			(xy 150.923602 -104.319426) (xy 150.932642 -104.321864) (xy 150.962614 -104.328722) (xy 150.971911 -104.33041)
			(xy 150.990573 -104.327533) (xy 150.998936 -104.323134) (xy 151.024946 -104.30884) (xy 151.079869 -104.286347)
			(xy 151.137234 -104.271124) (xy 151.196083 -104.263426) (xy 151.225758 -104.262936) (xy 151.255393 -104.263406)
			(xy 151.314169 -104.271054) (xy 151.371468 -104.286214) (xy 151.426336 -104.308633) (xy 151.452326 -104.32288)
			(xy 151.460711 -104.327211) (xy 151.479348 -104.330073) (xy 151.488648 -104.328468) (xy 151.51862 -104.32161)
			(xy 151.52771 -104.319284) (xy 151.54337 -104.308974) (xy 151.5491 -104.301544) (xy 151.564475 -104.280683)
			(xy 151.600024 -104.242974) (xy 151.640353 -104.210426) (xy 151.684718 -104.183641) (xy 151.732302 -104.16311)
			(xy 151.782228 -104.149214) (xy 151.833576 -104.142207) (xy 151.859488 -104.141778) (xy 151.88674 -104.142268)
			(xy 151.940691 -104.150024) (xy 151.992988 -104.165378) (xy 152.042568 -104.188019) (xy 152.088421 -104.217486)
			(xy 152.129613 -104.253178) (xy 152.165307 -104.29437) (xy 152.194775 -104.340222) (xy 152.217418 -104.389801)
			(xy 152.232774 -104.442098) (xy 152.240531 -104.496048) (xy 152.240531 -104.550552) (xy 152.232774 -104.604502)
			(xy 152.217418 -104.656799) (xy 152.194775 -104.706378) (xy 152.165307 -104.75223) (xy 152.129949 -104.793034)
			(xy 162.809934 -104.793034) (xy 162.814005 -104.737412) (xy 162.826131 -104.682975) (xy 162.846054 -104.630884)
			(xy 162.87335 -104.582249) (xy 162.907436 -104.538106) (xy 162.947585 -104.499397) (xy 162.992943 -104.466946)
			(xy 163.042543 -104.441445) (xy 163.095327 -104.423438) (xy 163.15017 -104.413308) (xy 163.205904 -104.411271)
			(xy 163.261341 -104.417371) (xy 163.315298 -104.431477) (xy 163.366627 -104.453289) (xy 163.414233 -104.482343)
			(xy 163.457101 -104.518018) (xy 163.494318 -104.559555) (xy 163.525091 -104.606068) (xy 163.548763 -104.656565)
			(xy 163.564831 -104.709972) (xy 163.572951 -104.765148) (xy 163.57346 -104.793034) (xy 163.572951 -104.82092)
			(xy 163.564831 -104.876096) (xy 163.548763 -104.929503) (xy 163.525091 -104.98) (xy 163.494318 -105.026513)
			(xy 163.457101 -105.06805) (xy 163.414233 -105.103725) (xy 163.366627 -105.132779) (xy 163.315298 -105.154591)
			(xy 163.261341 -105.168697) (xy 163.205904 -105.174797) (xy 163.15017 -105.17276) (xy 163.095327 -105.16263)
			(xy 163.042543 -105.144623) (xy 162.992943 -105.119122) (xy 162.947585 -105.086671) (xy 162.907436 -105.047962)
			(xy 162.87335 -105.003819) (xy 162.846054 -104.955184) (xy 162.826131 -104.903093) (xy 162.814005 -104.848656)
			(xy 162.809934 -104.793034) (xy 152.129949 -104.793034) (xy 152.129613 -104.793422) (xy 152.088421 -104.829114)
			(xy 152.042568 -104.858581) (xy 151.992988 -104.881222) (xy 151.940691 -104.896576) (xy 151.88674 -104.904332)
			(xy 151.859488 -104.904794) (xy 151.844759 -104.904644) (xy 151.815389 -104.902357) (xy 151.800814 -104.900222)
			(xy 151.789839 -104.899108) (xy 151.768648 -104.90516) (xy 151.75992 -104.911906) (xy 151.7015 -104.961944)
			(xy 151.693504 -104.969541) (xy 151.68427 -104.989539) (xy 151.68372 -105.000552) (xy 151.68372 -105.304844)
			(xy 151.684283 -105.31586) (xy 151.693484 -105.335877) (xy 151.7015 -105.343452) (xy 151.72672 -105.365042)
			(xy 165.322756 -105.365042) (xy 165.326827 -105.30942) (xy 165.338953 -105.254983) (xy 165.358876 -105.202892)
			(xy 165.386172 -105.154257) (xy 165.420258 -105.110114) (xy 165.460407 -105.071405) (xy 165.505765 -105.038954)
			(xy 165.555365 -105.013453) (xy 165.608149 -104.995446) (xy 165.662992 -104.985316) (xy 165.718726 -104.983279)
			(xy 165.774163 -104.989379) (xy 165.82812 -105.003485) (xy 165.879449 -105.025297) (xy 165.927055 -105.054351)
			(xy 165.969923 -105.090026) (xy 166.00714 -105.131563) (xy 166.037913 -105.178076) (xy 166.061585 -105.228573)
			(xy 166.077653 -105.28198) (xy 166.085773 -105.337156) (xy 166.086282 -105.365042) (xy 166.085773 -105.392928)
			(xy 166.077653 -105.448104) (xy 166.061585 -105.501511) (xy 166.037913 -105.552008) (xy 166.00714 -105.598521)
			(xy 165.969923 -105.640058) (xy 165.927055 -105.675733) (xy 165.879449 -105.704787) (xy 165.82812 -105.726599)
			(xy 165.774163 -105.740705) (xy 165.718726 -105.746805) (xy 165.662992 -105.744768) (xy 165.608149 -105.734638)
			(xy 165.555365 -105.716631) (xy 165.505765 -105.69113) (xy 165.460407 -105.658679) (xy 165.420258 -105.61997)
			(xy 165.386172 -105.575827) (xy 165.358876 -105.527192) (xy 165.338953 -105.475101) (xy 165.326827 -105.420664)
			(xy 165.322756 -105.365042) (xy 151.72672 -105.365042) (xy 151.768556 -105.400856) (xy 151.789638 -105.406952)
			(xy 151.800814 -105.405174) (xy 151.815389 -105.403044) (xy 151.844759 -105.400754) (xy 151.859488 -105.400602)
			(xy 151.886742 -105.401044) (xy 151.940696 -105.4088) (xy 151.992997 -105.424155) (xy 152.04258 -105.446798)
			(xy 152.088435 -105.476266) (xy 152.129631 -105.511961) (xy 152.165327 -105.553155) (xy 152.194797 -105.59901)
			(xy 152.217441 -105.648592) (xy 152.232798 -105.700892) (xy 152.240555 -105.754846) (xy 152.240555 -105.809354)
			(xy 152.232798 -105.863308) (xy 152.217441 -105.915608) (xy 152.194797 -105.96519) (xy 152.165327 -106.011045)
			(xy 152.129631 -106.052239) (xy 152.088435 -106.087934) (xy 152.04258 -106.117402) (xy 151.992997 -106.140045)
			(xy 151.940696 -106.1554) (xy 151.886742 -106.163156) (xy 151.859488 -106.163618) (xy 151.833581 -106.16313)
			(xy 151.782246 -106.156106) (xy 151.732333 -106.142201) (xy 151.684761 -106.121672) (xy 151.640402 -106.094895)
			(xy 151.600074 -106.062364) (xy 151.564518 -106.024676) (xy 151.5491 -106.003852) (xy 151.543288 -105.996511)
			(xy 151.527661 -105.986221) (xy 151.51862 -105.983786) (xy 151.488648 -105.976928) (xy 151.479348 -105.975267)
			(xy 151.460689 -105.978125) (xy 151.452326 -105.982516) (xy 151.426341 -105.996774) (xy 151.371474 -106.019197)
			(xy 151.314172 -106.034355) (xy 151.255394 -106.041996) (xy 151.225758 -106.04246) (xy 151.19608 -106.041997)
			(xy 151.137224 -106.034323) (xy 151.079855 -106.019096) (xy 151.02494 -105.996572) (xy 150.998936 -105.982262)
			(xy 150.990539 -105.977961) (xy 150.971912 -105.975082) (xy 150.962614 -105.976674) (xy 150.932642 -105.983532)
			(xy 150.923542 -105.985829) (xy 150.907886 -105.996159) (xy 150.902162 -106.003598) (xy 150.886733 -106.02445)
			(xy 150.851174 -106.062217) (xy 150.810827 -106.094817) (xy 150.766434 -106.12165) (xy 150.718816 -106.142221)
			(xy 150.668849 -106.15615) (xy 150.617456 -106.163181) (xy 150.59152 -106.163618) (xy 150.564267 -106.163136)
			(xy 150.510315 -106.155382) (xy 150.458016 -106.140028) (xy 150.408435 -106.117387) (xy 150.362581 -106.08792)
			(xy 150.321387 -106.052228) (xy 150.285692 -106.011035) (xy 150.256223 -105.965183) (xy 150.233579 -105.915602)
			(xy 150.218223 -105.863304) (xy 150.210465 -105.809353) (xy 150.210465 -105.754847) (xy 150.218223 -105.700896)
			(xy 150.233579 -105.648598) (xy 150.256223 -105.599017) (xy 150.285692 -105.553165) (xy 150.321387 -105.511972)
			(xy 150.362581 -105.47628) (xy 150.408435 -105.446813) (xy 150.458016 -105.424172) (xy 150.510315 -105.408818)
			(xy 150.564267 -105.401064) (xy 150.59152 -105.400602) (xy 150.592028 -105.400602) (xy 150.606757 -105.40075)
			(xy 150.636127 -105.403038) (xy 150.650702 -105.405174) (xy 150.661677 -105.406299) (xy 150.682869 -105.40024)
			(xy 150.691596 -105.39349) (xy 150.750016 -105.343452) (xy 150.758016 -105.335859) (xy 150.767247 -105.315858)
			(xy 150.767796 -105.304844) (xy 150.767796 -105.000552) (xy 150.76723 -104.989536) (xy 150.758031 -104.96952)
			(xy 150.750016 -104.961944) (xy 150.68296 -104.90454) (xy 150.661878 -104.898444) (xy 150.650702 -104.900222)
			(xy 150.636127 -104.902351) (xy 150.606757 -104.904642) (xy 150.592028 -104.904794) (xy 150.59152 -104.904794)
			(xy 150.564265 -104.90436) (xy 150.51031 -104.896606) (xy 150.458008 -104.881251) (xy 150.408423 -104.858608)
			(xy 150.362566 -104.82914) (xy 150.321369 -104.793445) (xy 150.285672 -104.75225) (xy 150.256201 -104.706394)
			(xy 150.233556 -104.656811) (xy 150.218199 -104.60451) (xy 150.210441 -104.550555) (xy 125.044573 -104.550555)
			(xy 125.067001 -104.598399) (xy 125.083069 -104.651806) (xy 125.091189 -104.706982) (xy 125.091698 -104.734868)
			(xy 125.091189 -104.762754) (xy 125.083069 -104.81793) (xy 125.067001 -104.871337) (xy 125.043329 -104.921834)
			(xy 125.012556 -104.968347) (xy 124.975339 -105.009884) (xy 124.932471 -105.045559) (xy 124.884865 -105.074613)
			(xy 124.833536 -105.096425) (xy 124.779579 -105.110531) (xy 124.724142 -105.116631) (xy 124.668408 -105.114594)
			(xy 124.613565 -105.104464) (xy 124.560781 -105.086457) (xy 124.511181 -105.060956) (xy 124.465823 -105.028505)
			(xy 124.425674 -104.989796) (xy 124.391588 -104.945653) (xy 124.364292 -104.897018) (xy 124.344369 -104.844927)
			(xy 124.332243 -104.79049) (xy 124.328172 -104.734868) (xy 102.233191 -104.734868) (xy 102.258928 -104.751409)
			(xy 102.300115 -104.7871) (xy 102.335804 -104.828289) (xy 102.365268 -104.874138) (xy 102.387907 -104.923713)
			(xy 102.40326 -104.976005) (xy 102.411016 -105.02995) (xy 102.411016 -105.08445) (xy 102.40326 -105.138395)
			(xy 102.387907 -105.190687) (xy 102.365268 -105.240262) (xy 102.335804 -105.286111) (xy 102.300115 -105.3273)
			(xy 102.258928 -105.362991) (xy 102.213081 -105.392457) (xy 102.163508 -105.415099) (xy 102.111216 -105.430456)
			(xy 102.057272 -105.438215) (xy 102.030022 -105.438702) (xy 102.002652 -105.438223) (xy 101.948474 -105.430408)
			(xy 101.895971 -105.414922) (xy 101.846224 -105.392083) (xy 101.800256 -105.362362) (xy 101.779324 -105.344722)
			(xy 101.77907 -105.344468) (xy 101.77197 -105.338901) (xy 101.755063 -105.332644) (xy 101.74605 -105.332276)
			(xy 101.678994 -105.332276) (xy 101.669978 -105.332636) (xy 101.653061 -105.338882) (xy 101.645974 -105.344468)
			(xy 101.64572 -105.344722) (xy 101.624787 -105.362363) (xy 101.578819 -105.392087) (xy 101.529073 -105.414933)
			(xy 101.476571 -105.430429) (xy 101.422393 -105.438258) (xy 101.367651 -105.438258) (xy 101.313473 -105.430429)
			(xy 101.260971 -105.414933) (xy 101.211225 -105.392087) (xy 101.165257 -105.362363) (xy 101.144324 -105.344722)
			(xy 101.14407 -105.344468) (xy 101.13697 -105.338901) (xy 101.120063 -105.332644) (xy 101.11105 -105.332276)
			(xy 101.043994 -105.332276) (xy 101.034978 -105.332636) (xy 101.018061 -105.338882) (xy 101.010974 -105.344468)
			(xy 101.010974 -105.344722) (xy 101.01072 -105.344722) (xy 100.989794 -105.362369) (xy 100.943819 -105.392079)
			(xy 100.89407 -105.414913) (xy 100.841568 -105.430402) (xy 100.787392 -105.438229) (xy 100.760022 -105.438702)
			(xy 100.733709 -105.438219) (xy 100.681581 -105.430987) (xy 100.630938 -105.416671) (xy 100.582739 -105.395542)
			(xy 100.537895 -105.367998) (xy 100.497255 -105.334562) (xy 100.479098 -105.315512) (xy 100.471577 -105.308109)
			(xy 100.452297 -105.299585) (xy 100.44176 -105.299002) (xy 100.367084 -105.299002) (xy 100.356532 -105.299508)
			(xy 100.337236 -105.308059) (xy 100.329746 -105.315512) (xy 100.311612 -105.334589) (xy 100.270977 -105.368044)
			(xy 100.226133 -105.3956) (xy 100.177928 -105.416734) (xy 100.127276 -105.431047) (xy 100.075139 -105.438266)
			(xy 100.048822 -105.438702) (xy 100.021568 -105.438252) (xy 99.967614 -105.430498) (xy 99.915312 -105.415143)
			(xy 99.865729 -105.392502) (xy 99.819872 -105.363034) (xy 99.778676 -105.32734) (xy 99.742979 -105.286146)
			(xy 99.713509 -105.240291) (xy 99.690864 -105.190708) (xy 99.675507 -105.138408) (xy 99.667749 -105.084454)
			(xy 98.411015 -105.084454) (xy 98.403261 -105.138394) (xy 98.387907 -105.190685) (xy 98.365269 -105.24026)
			(xy 98.335806 -105.286108) (xy 98.300118 -105.327297) (xy 98.258932 -105.362988) (xy 98.213086 -105.392454)
			(xy 98.163513 -105.415097) (xy 98.111223 -105.430454) (xy 98.057279 -105.438214) (xy 98.03003 -105.438702)
			(xy 98.00266 -105.438218) (xy 97.948482 -105.430404) (xy 97.895979 -105.414919) (xy 97.846232 -105.392082)
			(xy 97.800264 -105.362361) (xy 97.779332 -105.344722) (xy 97.779078 -105.344468) (xy 97.772005 -105.338863)
			(xy 97.755078 -105.332628) (xy 97.746058 -105.332276) (xy 97.679002 -105.332276) (xy 97.669986 -105.332639)
			(xy 97.653069 -105.338883) (xy 97.645982 -105.344468) (xy 97.645728 -105.344722) (xy 97.624795 -105.362363)
			(xy 97.578827 -105.392087) (xy 97.529081 -105.414933) (xy 97.476579 -105.430429) (xy 97.422401 -105.438258)
			(xy 97.367659 -105.438258) (xy 97.313481 -105.430429) (xy 97.260979 -105.414933) (xy 97.211233 -105.392087)
			(xy 97.165265 -105.362363) (xy 97.144332 -105.344722) (xy 97.144078 -105.344468) (xy 97.137005 -105.338863)
			(xy 97.120078 -105.332628) (xy 97.111058 -105.332276) (xy 97.044002 -105.332276) (xy 97.034986 -105.332639)
			(xy 97.018069 -105.338883) (xy 97.010982 -105.344468) (xy 97.010982 -105.344722) (xy 97.010728 -105.344722)
			(xy 96.989795 -105.362363) (xy 96.943827 -105.392087) (xy 96.894081 -105.414933) (xy 96.841579 -105.430429)
			(xy 96.787401 -105.438258) (xy 96.732659 -105.438258) (xy 96.678481 -105.430429) (xy 96.625979 -105.414933)
			(xy 96.576233 -105.392087) (xy 96.530265 -105.362363) (xy 96.509332 -105.344722) (xy 96.509078 -105.344468)
			(xy 96.502005 -105.338863) (xy 96.485078 -105.332628) (xy 96.476058 -105.332276) (xy 96.409002 -105.332276)
			(xy 96.399986 -105.332639) (xy 96.383069 -105.338883) (xy 96.375982 -105.344468) (xy 96.375982 -105.344722)
			(xy 96.375728 -105.344722) (xy 96.354799 -105.362365) (xy 96.308825 -105.392075) (xy 96.259077 -105.41491)
			(xy 96.206575 -105.4304) (xy 96.152399 -105.438228) (xy 96.12503 -105.438702) (xy 96.097775 -105.438253)
			(xy 96.04382 -105.430499) (xy 95.991518 -105.415145) (xy 95.941933 -105.392504) (xy 95.896076 -105.363037)
			(xy 95.854879 -105.327342) (xy 95.819181 -105.286148) (xy 95.78971 -105.240293) (xy 95.767065 -105.19071)
			(xy 95.751707 -105.138409) (xy 95.743949 -105.084455) (xy 91.225364 -105.084455) (xy 91.225364 -105.105744)
			(xy 91.21674 -105.162572) (xy 91.199688 -105.217464) (xy 91.174594 -105.269176) (xy 91.142026 -105.316538)
			(xy 91.122754 -105.337864) (xy 91.11615 -105.344722) (xy 91.109038 -105.362756) (xy 91.109038 -105.451656)
			(xy 91.11615 -105.46969) (xy 91.122754 -105.476548) (xy 91.142032 -105.497869) (xy 91.174599 -105.545232)
			(xy 91.199691 -105.596944) (xy 91.216742 -105.651836) (xy 91.225365 -105.708665) (xy 91.225364 -105.766144)
			(xy 91.21674 -105.822972) (xy 91.199688 -105.877864) (xy 91.174594 -105.929576) (xy 91.142026 -105.976938)
			(xy 91.122754 -105.998264) (xy 91.11615 -106.005122) (xy 91.109038 -106.023156) (xy 91.109038 -106.112056)
			(xy 91.11615 -106.13009) (xy 91.122754 -106.136948) (xy 91.142032 -106.158269) (xy 91.174599 -106.205632)
			(xy 91.199691 -106.257344) (xy 91.20979 -106.289856) (xy 122.18111 -106.289856) (xy 122.185181 -106.234234)
			(xy 122.197307 -106.179797) (xy 122.21723 -106.127706) (xy 122.244526 -106.079071) (xy 122.278612 -106.034928)
			(xy 122.318761 -105.996219) (xy 122.364119 -105.963768) (xy 122.413719 -105.938267) (xy 122.466503 -105.92026)
			(xy 122.521346 -105.91013) (xy 122.57708 -105.908093) (xy 122.632517 -105.914193) (xy 122.686474 -105.928299)
			(xy 122.737803 -105.950111) (xy 122.785409 -105.979165) (xy 122.828277 -106.01484) (xy 122.865494 -106.056377)
			(xy 122.896267 -106.10289) (xy 122.919939 -106.153387) (xy 122.936007 -106.206794) (xy 122.944127 -106.26197)
			(xy 122.944418 -106.277918) (xy 123.681234 -106.277918) (xy 123.685305 -106.222296) (xy 123.697431 -106.167859)
			(xy 123.717354 -106.115768) (xy 123.74465 -106.067133) (xy 123.778736 -106.02299) (xy 123.818885 -105.984281)
			(xy 123.864243 -105.95183) (xy 123.913843 -105.926329) (xy 123.966627 -105.908322) (xy 124.02147 -105.898192)
			(xy 124.077204 -105.896155) (xy 124.132641 -105.902255) (xy 124.186598 -105.916361) (xy 124.237927 -105.938173)
			(xy 124.285533 -105.967227) (xy 124.328401 -106.002902) (xy 124.365618 -106.044439) (xy 124.396391 -106.090952)
			(xy 124.420063 -106.141449) (xy 124.436131 -106.194856) (xy 124.444251 -106.250032) (xy 124.44476 -106.277918)
			(xy 124.444251 -106.305804) (xy 124.438666 -106.343752) (xy 152.852581 -106.343752) (xy 152.852581 -106.289248)
			(xy 152.860339 -106.235298) (xy 152.875695 -106.183002) (xy 152.898338 -106.133423) (xy 152.927807 -106.087572)
			(xy 152.963501 -106.046381) (xy 153.004694 -106.01069) (xy 153.050547 -105.981224) (xy 153.100128 -105.958585)
			(xy 153.152425 -105.943233) (xy 153.206376 -105.935479) (xy 153.233628 -105.935018) (xy 153.259564 -105.935488)
			(xy 153.310958 -105.942507) (xy 153.360927 -105.956427) (xy 153.408549 -105.97699) (xy 153.452944 -106.003816)
			(xy 153.493295 -106.036412) (xy 153.528857 -106.074174) (xy 153.54427 -106.095038) (xy 153.550095 -106.102368)
			(xy 153.565712 -106.112664) (xy 153.57475 -106.115104) (xy 153.604722 -106.121962) (xy 153.614018 -106.123662)
			(xy 153.632682 -106.120778) (xy 153.641044 -106.116374) (xy 153.667049 -106.102072) (xy 153.721974 -106.079581)
			(xy 153.779341 -106.064361) (xy 153.838191 -106.056665) (xy 153.867866 -106.056176) (xy 153.897502 -106.056637)
			(xy 153.956278 -106.064287) (xy 154.013577 -106.079449) (xy 154.068444 -106.101871) (xy 154.094434 -106.11612)
			(xy 154.102816 -106.120456) (xy 154.121455 -106.123314) (xy 154.130756 -106.121708) (xy 154.160728 -106.11485)
			(xy 154.169814 -106.112514) (xy 154.185475 -106.10221) (xy 154.191208 -106.094784) (xy 154.20659 -106.073928)
			(xy 154.242137 -106.036217) (xy 154.282464 -106.003668) (xy 154.326827 -105.976881) (xy 154.374411 -105.95635)
			(xy 154.424336 -105.942453) (xy 154.475684 -105.935446) (xy 154.501596 -105.935018) (xy 154.528851 -105.935429)
			(xy 154.582806 -105.943186) (xy 154.635108 -105.958542) (xy 154.684692 -105.981186) (xy 154.730549 -106.010656)
			(xy 154.770185 -106.045) (xy 160.769552 -106.045) (xy 160.773623 -105.989378) (xy 160.785749 -105.934941)
			(xy 160.805672 -105.88285) (xy 160.832968 -105.834215) (xy 160.867054 -105.790072) (xy 160.907203 -105.751363)
			(xy 160.952561 -105.718912) (xy 161.002161 -105.693411) (xy 161.054945 -105.675404) (xy 161.109788 -105.665274)
			(xy 161.165522 -105.663237) (xy 161.220959 -105.669337) (xy 161.274916 -105.683443) (xy 161.326245 -105.705255)
			(xy 161.373851 -105.734309) (xy 161.416719 -105.769984) (xy 161.453936 -105.811521) (xy 161.484709 -105.858034)
			(xy 161.508381 -105.908531) (xy 161.524449 -105.961938) (xy 161.532569 -106.017114) (xy 161.533078 -106.045)
			(xy 161.532569 -106.072886) (xy 161.524449 -106.128062) (xy 161.508381 -106.181469) (xy 161.484709 -106.231966)
			(xy 161.453936 -106.278479) (xy 161.416719 -106.320016) (xy 161.373851 -106.355691) (xy 161.326245 -106.384745)
			(xy 161.274916 -106.406557) (xy 161.220959 -106.420663) (xy 161.165522 -106.426763) (xy 161.109788 -106.424726)
			(xy 161.054945 -106.414596) (xy 161.002161 -106.396589) (xy 160.952561 -106.371088) (xy 160.907203 -106.338637)
			(xy 160.867054 -106.299928) (xy 160.832968 -106.255785) (xy 160.805672 -106.20715) (xy 160.785749 -106.155059)
			(xy 160.773623 -106.100622) (xy 160.769552 -106.045) (xy 154.770185 -106.045) (xy 154.771745 -106.046352)
			(xy 154.807441 -106.087548) (xy 154.836912 -106.133404) (xy 154.859556 -106.182988) (xy 154.874913 -106.23529)
			(xy 154.882671 -106.289245) (xy 154.882671 -106.343755) (xy 154.874913 -106.39771) (xy 154.859556 -106.450012)
			(xy 154.836912 -106.499596) (xy 154.807441 -106.545452) (xy 154.771745 -106.586648) (xy 154.730549 -106.622344)
			(xy 154.684692 -106.651814) (xy 154.635108 -106.674458) (xy 154.582806 -106.689814) (xy 154.528851 -106.697571)
			(xy 154.501596 -106.698034) (xy 154.486867 -106.697883) (xy 154.457497 -106.695597) (xy 154.442922 -106.693462)
			(xy 154.431947 -106.692366) (xy 154.410759 -106.698408) (xy 154.402028 -106.705146) (xy 154.343608 -106.755184)
			(xy 154.335595 -106.762766) (xy 154.326371 -106.782775) (xy 154.325828 -106.793792) (xy 154.325828 -107.098084)
			(xy 154.326366 -107.109103) (xy 154.335584 -107.12912) (xy 154.343608 -107.136692) (xy 154.410664 -107.194096)
			(xy 154.431746 -107.200192) (xy 154.442922 -107.198414) (xy 154.457497 -107.196283) (xy 154.486867 -107.193993)
			(xy 154.501596 -107.193842) (xy 154.528853 -107.194205) (xy 154.582811 -107.201962) (xy 154.635116 -107.21732)
			(xy 154.684704 -107.239965) (xy 154.730563 -107.269437) (xy 154.771762 -107.305135) (xy 154.807461 -107.346334)
			(xy 154.836933 -107.392193) (xy 154.843903 -107.407456) (xy 165.146988 -107.407456) (xy 165.151059 -107.351834)
			(xy 165.163185 -107.297397) (xy 165.183108 -107.245306) (xy 165.210404 -107.196671) (xy 165.24449 -107.152528)
			(xy 165.284639 -107.113819) (xy 165.329997 -107.081368) (xy 165.379597 -107.055867) (xy 165.432381 -107.03786)
			(xy 165.487224 -107.02773) (xy 165.542958 -107.025693) (xy 165.598395 -107.031793) (xy 165.652352 -107.045899)
			(xy 165.703681 -107.067711) (xy 165.751287 -107.096765) (xy 165.794155 -107.13244) (xy 165.831372 -107.173977)
			(xy 165.862145 -107.22049) (xy 165.885817 -107.270987) (xy 165.901885 -107.324394) (xy 165.910005 -107.37957)
			(xy 165.910514 -107.407456) (xy 165.910005 -107.435342) (xy 165.901885 -107.490518) (xy 165.885817 -107.543925)
			(xy 165.862145 -107.594422) (xy 165.831372 -107.640935) (xy 165.794155 -107.682472) (xy 165.751287 -107.718147)
			(xy 165.703681 -107.747201) (xy 165.652352 -107.769013) (xy 165.598395 -107.783119) (xy 165.542958 -107.789219)
			(xy 165.487224 -107.787182) (xy 165.432381 -107.777052) (xy 165.379597 -107.759045) (xy 165.329997 -107.733544)
			(xy 165.284639 -107.701093) (xy 165.24449 -107.662384) (xy 165.210404 -107.618241) (xy 165.183108 -107.569606)
			(xy 165.163185 -107.517515) (xy 165.151059 -107.463078) (xy 165.146988 -107.407456) (xy 154.843903 -107.407456)
			(xy 154.859579 -107.44178) (xy 154.874937 -107.494085) (xy 154.882695 -107.548043) (xy 154.882695 -107.602557)
			(xy 154.874937 -107.656515) (xy 154.859579 -107.70882) (xy 154.836933 -107.758407) (xy 154.807461 -107.804266)
			(xy 154.77208 -107.845098) (xy 160.769552 -107.845098) (xy 160.773623 -107.789476) (xy 160.785749 -107.735039)
			(xy 160.805672 -107.682948) (xy 160.832968 -107.634313) (xy 160.867054 -107.59017) (xy 160.907203 -107.551461)
			(xy 160.952561 -107.51901) (xy 161.002161 -107.493509) (xy 161.054945 -107.475502) (xy 161.109788 -107.465372)
			(xy 161.165522 -107.463335) (xy 161.220959 -107.469435) (xy 161.274916 -107.483541) (xy 161.326245 -107.505353)
			(xy 161.373851 -107.534407) (xy 161.416719 -107.570082) (xy 161.453936 -107.611619) (xy 161.484709 -107.658132)
			(xy 161.508381 -107.708629) (xy 161.524449 -107.762036) (xy 161.532569 -107.817212) (xy 161.533078 -107.845098)
			(xy 161.532569 -107.872984) (xy 161.524449 -107.92816) (xy 161.508381 -107.981567) (xy 161.484709 -108.032064)
			(xy 161.453936 -108.078577) (xy 161.416719 -108.120114) (xy 161.373851 -108.155789) (xy 161.326245 -108.184843)
			(xy 161.274916 -108.206655) (xy 161.220959 -108.220761) (xy 161.165522 -108.226861) (xy 161.109788 -108.224824)
			(xy 161.054945 -108.214694) (xy 161.002161 -108.196687) (xy 160.952561 -108.171186) (xy 160.907203 -108.138735)
			(xy 160.867054 -108.100026) (xy 160.832968 -108.055883) (xy 160.805672 -108.007248) (xy 160.785749 -107.955157)
			(xy 160.773623 -107.90072) (xy 160.769552 -107.845098) (xy 154.77208 -107.845098) (xy 154.771762 -107.845465)
			(xy 154.730563 -107.881163) (xy 154.684704 -107.910635) (xy 154.635116 -107.93328) (xy 154.582811 -107.948638)
			(xy 154.528853 -107.956395) (xy 154.501596 -107.956858) (xy 154.475688 -107.956389) (xy 154.424352 -107.949365)
			(xy 154.374437 -107.935458) (xy 154.326863 -107.914927) (xy 154.282505 -107.888147) (xy 154.242178 -107.855611)
			(xy 154.206624 -107.817918) (xy 154.191208 -107.797092) (xy 154.185385 -107.78976) (xy 154.169767 -107.779464)
			(xy 154.160728 -107.777026) (xy 154.130756 -107.770168) (xy 154.121456 -107.768506) (xy 154.102797 -107.771363)
			(xy 154.094434 -107.775756) (xy 154.068449 -107.790015) (xy 154.013582 -107.812437) (xy 153.95628 -107.827595)
			(xy 153.897502 -107.835235) (xy 153.867866 -107.8357) (xy 153.838189 -107.835228) (xy 153.779333 -107.827556)
			(xy 153.721964 -107.812331) (xy 153.667048 -107.789811) (xy 153.641044 -107.775502) (xy 153.632666 -107.771156)
			(xy 153.614023 -107.768304) (xy 153.604722 -107.769914) (xy 153.57475 -107.776772) (xy 153.565658 -107.779092)
			(xy 153.549999 -107.789407) (xy 153.54427 -107.796838) (xy 153.528848 -107.817696) (xy 153.493287 -107.85546)
			(xy 153.452938 -107.888059) (xy 153.408544 -107.91489) (xy 153.360925 -107.93546) (xy 153.310958 -107.949389)
			(xy 153.259564 -107.956421) (xy 153.233628 -107.956858) (xy 153.206377 -107.956297) (xy 153.152431 -107.948544)
			(xy 153.100136 -107.933192) (xy 153.050559 -107.910554) (xy 153.004708 -107.881091) (xy 152.963518 -107.845402)
			(xy 152.927826 -107.804214) (xy 152.898359 -107.758366) (xy 152.875717 -107.70879) (xy 152.860362 -107.656497)
			(xy 152.852605 -107.602551) (xy 152.852605 -107.548049) (xy 152.860362 -107.494103) (xy 152.875717 -107.44181)
			(xy 152.898359 -107.392234) (xy 152.927826 -107.346386) (xy 152.963518 -107.305198) (xy 153.004708 -107.269509)
			(xy 153.050559 -107.240046) (xy 153.100136 -107.217408) (xy 153.152431 -107.202056) (xy 153.206377 -107.194303)
			(xy 153.233628 -107.193842) (xy 153.234136 -107.193842) (xy 153.248865 -107.19399) (xy 153.278235 -107.196278)
			(xy 153.29281 -107.198414) (xy 153.303785 -107.199534) (xy 153.324975 -107.193477) (xy 153.333704 -107.18673)
			(xy 153.392124 -107.136692) (xy 153.400153 -107.129125) (xy 153.409367 -107.109104) (xy 153.409904 -107.098084)
			(xy 153.409904 -106.793792) (xy 153.409369 -106.782773) (xy 153.400148 -106.762756) (xy 153.392124 -106.755184)
			(xy 153.325068 -106.69778) (xy 153.303986 -106.691684) (xy 153.29281 -106.693462) (xy 153.278234 -106.69559)
			(xy 153.248865 -106.697881) (xy 153.234136 -106.698034) (xy 153.233628 -106.698034) (xy 153.206376 -106.697521)
			(xy 153.152425 -106.689767) (xy 153.100128 -106.674415) (xy 153.050547 -106.651776) (xy 153.004694 -106.62231)
			(xy 152.963501 -106.586619) (xy 152.927807 -106.545428) (xy 152.898338 -106.499577) (xy 152.875695 -106.449998)
			(xy 152.860339 -106.397702) (xy 152.852581 -106.343752) (xy 124.438666 -106.343752) (xy 124.436131 -106.36098)
			(xy 124.420063 -106.414387) (xy 124.396391 -106.464884) (xy 124.365618 -106.511397) (xy 124.328401 -106.552934)
			(xy 124.285533 -106.588609) (xy 124.237927 -106.617663) (xy 124.186598 -106.639475) (xy 124.132641 -106.653581)
			(xy 124.077204 -106.659681) (xy 124.02147 -106.657644) (xy 123.966627 -106.647514) (xy 123.913843 -106.629507)
			(xy 123.864243 -106.604006) (xy 123.818885 -106.571555) (xy 123.778736 -106.532846) (xy 123.74465 -106.488703)
			(xy 123.717354 -106.440068) (xy 123.697431 -106.387977) (xy 123.685305 -106.33354) (xy 123.681234 -106.277918)
			(xy 122.944418 -106.277918) (xy 122.944636 -106.289856) (xy 122.944127 -106.317742) (xy 122.936007 -106.372918)
			(xy 122.919939 -106.426325) (xy 122.896267 -106.476822) (xy 122.865494 -106.523335) (xy 122.828277 -106.564872)
			(xy 122.785409 -106.600547) (xy 122.737803 -106.629601) (xy 122.686474 -106.651413) (xy 122.632517 -106.665519)
			(xy 122.57708 -106.671619) (xy 122.521346 -106.669582) (xy 122.466503 -106.659452) (xy 122.413719 -106.641445)
			(xy 122.364119 -106.615944) (xy 122.318761 -106.583493) (xy 122.278612 -106.544784) (xy 122.244526 -106.500641)
			(xy 122.21723 -106.452006) (xy 122.197307 -106.399915) (xy 122.185181 -106.345478) (xy 122.18111 -106.289856)
			(xy 91.20979 -106.289856) (xy 91.216742 -106.312236) (xy 91.225365 -106.369065) (xy 91.225364 -106.426544)
			(xy 91.21674 -106.483372) (xy 91.199688 -106.538264) (xy 91.174594 -106.589976) (xy 91.142026 -106.637338)
			(xy 91.122754 -106.658664) (xy 91.11615 -106.665522) (xy 91.109038 -106.683556) (xy 91.109038 -106.772456)
			(xy 91.11615 -106.79049) (xy 91.122754 -106.797348) (xy 91.131529 -106.807053) (xy 103.602977 -106.807053)
			(xy 103.602977 -106.752547) (xy 103.610735 -106.698595) (xy 103.626092 -106.646297) (xy 103.648737 -106.596716)
			(xy 103.678207 -106.550864) (xy 103.713904 -106.509672) (xy 103.755099 -106.473981) (xy 103.800955 -106.444516)
			(xy 103.850538 -106.421877) (xy 103.902838 -106.406526) (xy 103.956791 -106.398774) (xy 103.984044 -106.398314)
			(xy 104.011413 -106.398809) (xy 104.065591 -106.40662) (xy 104.118094 -106.422102) (xy 104.167841 -106.444937)
			(xy 104.213809 -106.474656) (xy 104.234742 -106.492294) (xy 104.234996 -106.492548) (xy 104.242075 -106.498145)
			(xy 104.258998 -106.504384) (xy 104.268016 -106.50474) (xy 104.335072 -106.50474) (xy 104.344089 -106.504383)
			(xy 104.361007 -106.498137) (xy 104.368092 -106.492548) (xy 104.368092 -106.492294) (xy 104.368346 -106.492294)
			(xy 104.389279 -106.474653) (xy 104.435247 -106.444929) (xy 104.484993 -106.422083) (xy 104.537495 -106.406587)
			(xy 104.591673 -106.398758) (xy 104.646415 -106.398758) (xy 104.700593 -106.406587) (xy 104.753095 -106.422083)
			(xy 104.802841 -106.444929) (xy 104.848809 -106.474653) (xy 104.869742 -106.492294) (xy 104.869996 -106.492548)
			(xy 104.877075 -106.498145) (xy 104.893998 -106.504384) (xy 104.903016 -106.50474) (xy 104.970072 -106.50474)
			(xy 104.979089 -106.504383) (xy 104.996007 -106.498137) (xy 105.003092 -106.492548) (xy 105.003092 -106.492294)
			(xy 105.003346 -106.492294) (xy 105.024287 -106.474666) (xy 105.070257 -106.444953) (xy 105.120003 -106.422115)
			(xy 105.172501 -106.406621) (xy 105.226675 -106.39879) (xy 105.254044 -106.398314) (xy 105.281295 -106.398759)
			(xy 105.335241 -106.406521) (xy 105.387533 -106.421881) (xy 105.437108 -106.444526) (xy 105.482955 -106.473995)
			(xy 105.524143 -106.509688) (xy 105.559832 -106.55088) (xy 105.589295 -106.596731) (xy 105.611935 -106.646308)
			(xy 105.627288 -106.698602) (xy 105.635044 -106.752549) (xy 105.635044 -106.80245) (xy 108.420905 -106.80245)
			(xy 108.420905 -106.74795) (xy 108.428662 -106.694005) (xy 108.444016 -106.641712) (xy 108.466657 -106.592138)
			(xy 108.496123 -106.54629) (xy 108.531814 -106.505102) (xy 108.573003 -106.469413) (xy 108.618852 -106.439949)
			(xy 108.668427 -106.417311) (xy 108.72072 -106.401958) (xy 108.774666 -106.394204) (xy 108.801916 -106.393742)
			(xy 108.828231 -106.394185) (xy 108.880361 -106.401423) (xy 108.931005 -106.415746) (xy 108.979204 -106.436883)
			(xy 109.024047 -106.464434) (xy 109.064685 -106.497878) (xy 109.08284 -106.516932) (xy 109.090354 -106.524343)
			(xy 109.109639 -106.532865) (xy 109.120178 -106.533442) (xy 109.194854 -106.533442) (xy 109.205401 -106.532889)
			(xy 109.224695 -106.524369) (xy 109.232192 -106.516932) (xy 109.252012 -106.496144) (xy 109.296784 -106.460169)
			(xy 109.346442 -106.431309) (xy 109.399864 -106.410216) (xy 109.455843 -106.397367) (xy 109.513116 -106.393052)
			(xy 109.570389 -106.397367) (xy 109.626368 -106.410216) (xy 109.67979 -106.431309) (xy 109.729448 -106.460169)
			(xy 109.77422 -106.496144) (xy 109.79404 -106.516932) (xy 109.801554 -106.524343) (xy 109.820839 -106.532865)
			(xy 109.831378 -106.533442) (xy 109.906054 -106.533442) (xy 109.916601 -106.532889) (xy 109.935895 -106.524369)
			(xy 109.943392 -106.516932) (xy 109.961565 -106.497893) (xy 110.00219 -106.464434) (xy 110.047026 -106.436871)
			(xy 110.095224 -106.41573) (xy 110.145869 -106.401409) (xy 110.198001 -106.394182) (xy 110.224316 -106.393742)
			(xy 110.25157 -106.394129) (xy 110.305523 -106.401888) (xy 110.357823 -106.417247) (xy 110.407405 -106.439892)
			(xy 110.453259 -106.469362) (xy 110.494453 -106.505059) (xy 110.530147 -106.546254) (xy 110.559616 -106.59211)
			(xy 110.582259 -106.641692) (xy 110.597615 -106.693993) (xy 110.605372 -106.747946) (xy 110.605372 -106.802454)
			(xy 110.597615 -106.856407) (xy 110.582259 -106.908708) (xy 110.559616 -106.95829) (xy 110.530147 -107.004146)
			(xy 110.494453 -107.045341) (xy 110.453259 -107.081038) (xy 110.407405 -107.110508) (xy 110.357823 -107.133153)
			(xy 110.305523 -107.148512) (xy 110.25157 -107.156271) (xy 110.224316 -107.156758) (xy 110.198002 -107.156293)
			(xy 110.145873 -107.14906) (xy 110.095229 -107.134741) (xy 110.04703 -107.113608) (xy 110.002187 -107.086061)
			(xy 109.961548 -107.052621) (xy 109.943392 -107.033568) (xy 109.935866 -107.026171) (xy 109.91659 -107.017642)
			(xy 109.906054 -107.017058) (xy 109.831378 -107.017058) (xy 109.820833 -107.017628) (xy 109.801538 -107.026136)
			(xy 109.79404 -107.033568) (xy 109.77422 -107.054356) (xy 109.729448 -107.090331) (xy 109.67979 -107.119191)
			(xy 109.626368 -107.140284) (xy 109.570389 -107.153133) (xy 109.513116 -107.157448) (xy 109.455843 -107.153133)
			(xy 109.399864 -107.140284) (xy 109.346442 -107.119191) (xy 109.296784 -107.090331) (xy 109.252012 -107.054356)
			(xy 109.232192 -107.033568) (xy 109.224666 -107.026171) (xy 109.20539 -107.017642) (xy 109.194854 -107.017058)
			(xy 109.120178 -107.017058) (xy 109.109633 -107.017628) (xy 109.090338 -107.026136) (xy 109.08284 -107.033568)
			(xy 109.0647 -107.05264) (xy 109.024068 -107.086096) (xy 108.979225 -107.113654) (xy 108.931021 -107.13479)
			(xy 108.88037 -107.149103) (xy 108.828233 -107.156323) (xy 108.801916 -107.156758) (xy 108.774666 -107.156196)
			(xy 108.72072 -107.148442) (xy 108.668427 -107.133089) (xy 108.618852 -107.110451) (xy 108.573003 -107.080987)
			(xy 108.531813 -107.045298) (xy 108.496123 -107.00411) (xy 108.466657 -106.958262) (xy 108.444016 -106.908688)
			(xy 108.428662 -106.856395) (xy 108.420905 -106.80245) (xy 105.635044 -106.80245) (xy 105.635044 -106.807051)
			(xy 105.627288 -106.860998) (xy 105.611935 -106.913292) (xy 105.589295 -106.962869) (xy 105.559832 -107.00872)
			(xy 105.524143 -107.049912) (xy 105.482955 -107.085605) (xy 105.437108 -107.115074) (xy 105.387533 -107.137719)
			(xy 105.335241 -107.153079) (xy 105.281295 -107.160841) (xy 105.254044 -107.16133) (xy 105.226674 -107.160855)
			(xy 105.172494 -107.153042) (xy 105.119991 -107.137556) (xy 105.070244 -107.114716) (xy 105.024277 -107.084991)
			(xy 105.003346 -107.06735) (xy 105.003092 -107.067096) (xy 104.996012 -107.061499) (xy 104.97909 -107.055259)
			(xy 104.970072 -107.054904) (xy 104.903016 -107.054904) (xy 104.894 -107.055268) (xy 104.877083 -107.06151)
			(xy 104.869996 -107.067096) (xy 104.869742 -107.06735) (xy 104.848809 -107.084991) (xy 104.802841 -107.114715)
			(xy 104.753095 -107.137561) (xy 104.700593 -107.153057) (xy 104.646415 -107.160886) (xy 104.591673 -107.160886)
			(xy 104.537495 -107.153057) (xy 104.484993 -107.137561) (xy 104.435247 -107.114715) (xy 104.389279 -107.084991)
			(xy 104.368346 -107.06735) (xy 104.368092 -107.067096) (xy 104.361012 -107.061499) (xy 104.34409 -107.055259)
			(xy 104.335072 -107.054904) (xy 104.268016 -107.054904) (xy 104.259 -107.055268) (xy 104.242083 -107.06151)
			(xy 104.234996 -107.067096) (xy 104.234996 -107.06735) (xy 104.234742 -107.06735) (xy 104.213798 -107.084975)
			(xy 104.16783 -107.114691) (xy 104.118085 -107.13753) (xy 104.065587 -107.153024) (xy 104.011413 -107.160855)
			(xy 103.984044 -107.16133) (xy 103.956791 -107.160826) (xy 103.902838 -107.153074) (xy 103.850538 -107.137723)
			(xy 103.800955 -107.115084) (xy 103.755099 -107.085619) (xy 103.713904 -107.049928) (xy 103.678207 -107.008736)
			(xy 103.648737 -106.962883) (xy 103.626092 -106.913303) (xy 103.610735 -106.861005) (xy 103.602977 -106.807053)
			(xy 91.131529 -106.807053) (xy 91.142032 -106.818669) (xy 91.174599 -106.866032) (xy 91.199691 -106.917744)
			(xy 91.216742 -106.972636) (xy 91.225365 -107.029465) (xy 91.225364 -107.086944) (xy 91.21674 -107.143772)
			(xy 91.199688 -107.198664) (xy 91.174594 -107.250376) (xy 91.142026 -107.297738) (xy 91.122754 -107.319064)
			(xy 91.11615 -107.325922) (xy 91.109038 -107.343956) (xy 91.109038 -107.432856) (xy 91.11615 -107.45089)
			(xy 91.122754 -107.457748) (xy 91.142032 -107.479069) (xy 91.174599 -107.526432) (xy 91.199691 -107.578144)
			(xy 91.216742 -107.633036) (xy 91.225365 -107.689865) (xy 91.225364 -107.740253) (xy 95.684273 -107.740253)
			(xy 95.684273 -107.685747) (xy 95.692031 -107.631795) (xy 95.707388 -107.579496) (xy 95.730033 -107.529916)
			(xy 95.759503 -107.484063) (xy 95.795199 -107.442871) (xy 95.836395 -107.407179) (xy 95.882251 -107.377714)
			(xy 95.931834 -107.355074) (xy 95.984134 -107.339723) (xy 96.038087 -107.331971) (xy 96.06534 -107.33151)
			(xy 96.092709 -107.332009) (xy 96.146887 -107.339818) (xy 96.19939 -107.3553) (xy 96.249137 -107.378134)
			(xy 96.295105 -107.407852) (xy 96.316038 -107.42549) (xy 96.316292 -107.425744) (xy 96.323373 -107.431339)
			(xy 96.340294 -107.437579) (xy 96.349312 -107.437936) (xy 96.416368 -107.437936) (xy 96.425382 -107.437556)
			(xy 96.442299 -107.431323) (xy 96.449388 -107.425744) (xy 96.449388 -107.42549) (xy 96.449642 -107.42549)
			(xy 96.470575 -107.407849) (xy 96.516543 -107.378125) (xy 96.566289 -107.355279) (xy 96.618791 -107.339783)
			(xy 96.672969 -107.331954) (xy 96.727711 -107.331954) (xy 96.781889 -107.339783) (xy 96.834391 -107.355279)
			(xy 96.884137 -107.378125) (xy 96.930105 -107.407849) (xy 96.951038 -107.42549) (xy 96.951292 -107.425744)
			(xy 96.958373 -107.431339) (xy 96.975294 -107.437579) (xy 96.984312 -107.437936) (xy 97.051368 -107.437936)
			(xy 97.060382 -107.437556) (xy 97.077299 -107.431323) (xy 97.084388 -107.425744) (xy 97.084388 -107.42549)
			(xy 97.084642 -107.42549) (xy 97.105575 -107.407849) (xy 97.151543 -107.378125) (xy 97.201289 -107.355279)
			(xy 97.253791 -107.339783) (xy 97.307969 -107.331954) (xy 97.362711 -107.331954) (xy 97.416889 -107.339783)
			(xy 97.469391 -107.355279) (xy 97.519137 -107.378125) (xy 97.565105 -107.407849) (xy 97.586038 -107.42549)
			(xy 97.586292 -107.425744) (xy 97.593373 -107.431339) (xy 97.610294 -107.437579) (xy 97.619312 -107.437936)
			(xy 97.686368 -107.437936) (xy 97.695382 -107.437556) (xy 97.712299 -107.431323) (xy 97.719388 -107.425744)
			(xy 97.719388 -107.42549) (xy 97.719642 -107.42549) (xy 97.740584 -107.407863) (xy 97.786554 -107.37815)
			(xy 97.836299 -107.355312) (xy 97.888798 -107.339818) (xy 97.942972 -107.331986) (xy 97.97034 -107.33151)
			(xy 97.997591 -107.331963) (xy 98.051537 -107.339724) (xy 98.103829 -107.355083) (xy 98.153404 -107.377728)
			(xy 98.199251 -107.407197) (xy 98.240438 -107.44289) (xy 98.276127 -107.484081) (xy 98.305591 -107.529932)
			(xy 98.328231 -107.579508) (xy 98.343584 -107.631803) (xy 98.35134 -107.685749) (xy 98.35134 -107.709052)
			(xy 99.652554 -107.709052) (xy 99.652554 -107.654548) (xy 99.66031 -107.600598) (xy 99.675666 -107.548302)
			(xy 99.698307 -107.498723) (xy 99.727773 -107.45287) (xy 99.763465 -107.411678) (xy 99.804656 -107.375984)
			(xy 99.850507 -107.346515) (xy 99.900085 -107.323872) (xy 99.952381 -107.308514) (xy 100.00633 -107.300755)
			(xy 100.033582 -107.300268) (xy 100.059895 -107.300758) (xy 100.112022 -107.307989) (xy 100.162664 -107.322305)
			(xy 100.210863 -107.343433) (xy 100.255707 -107.370975) (xy 100.296348 -107.404409) (xy 100.314506 -107.423458)
			(xy 100.322029 -107.430858) (xy 100.341308 -107.439385) (xy 100.351844 -107.439968) (xy 100.42652 -107.439968)
			(xy 100.437068 -107.439419) (xy 100.456364 -107.430899) (xy 100.463858 -107.423458) (xy 100.481984 -107.404373)
			(xy 100.522621 -107.37092) (xy 100.567468 -107.343366) (xy 100.615674 -107.322233) (xy 100.666326 -107.307922)
			(xy 100.718464 -107.300703) (xy 100.744782 -107.300268) (xy 100.772153 -107.300728) (xy 100.826333 -107.308545)
			(xy 100.878836 -107.324034) (xy 100.928583 -107.346878) (xy 100.974549 -107.376605) (xy 100.99548 -107.394248)
			(xy 100.995734 -107.394502) (xy 101.002835 -107.400067) (xy 101.019741 -107.406327) (xy 101.028754 -107.406694)
			(xy 101.09581 -107.406694) (xy 101.104828 -107.406343) (xy 101.121744 -107.400091) (xy 101.12883 -107.394502)
			(xy 101.12883 -107.394248) (xy 101.129084 -107.394248) (xy 101.150017 -107.376607) (xy 101.195985 -107.346883)
			(xy 101.245731 -107.324037) (xy 101.298233 -107.308541) (xy 101.352411 -107.300712) (xy 101.407153 -107.300712)
			(xy 101.461331 -107.308541) (xy 101.513833 -107.324037) (xy 101.563579 -107.346883) (xy 101.609547 -107.376607)
			(xy 101.63048 -107.394248) (xy 101.630734 -107.394502) (xy 101.637835 -107.400067) (xy 101.654741 -107.406327)
			(xy 101.663754 -107.406694) (xy 101.73081 -107.406694) (xy 101.739828 -107.406343) (xy 101.756744 -107.400091)
			(xy 101.76383 -107.394502) (xy 101.76383 -107.394248) (xy 101.764084 -107.394248) (xy 101.785017 -107.37661)
			(xy 101.830989 -107.346897) (xy 101.880736 -107.32406) (xy 101.933237 -107.308568) (xy 101.987413 -107.300741)
			(xy 102.014782 -107.300268) (xy 102.042034 -107.300778) (xy 102.095983 -107.308532) (xy 102.14828 -107.323886)
			(xy 102.197859 -107.346526) (xy 102.243712 -107.375992) (xy 102.284904 -107.411683) (xy 102.320598 -107.452874)
			(xy 102.350065 -107.498725) (xy 102.372708 -107.548303) (xy 102.388064 -107.600599) (xy 102.395821 -107.654548)
			(xy 102.395821 -107.709052) (xy 102.388064 -107.763001) (xy 102.372708 -107.815297) (xy 102.350065 -107.864875)
			(xy 102.320598 -107.910726) (xy 102.284904 -107.951917) (xy 102.243712 -107.987608) (xy 102.197859 -108.017074)
			(xy 102.14828 -108.039714) (xy 102.095983 -108.055068) (xy 102.042034 -108.062822) (xy 102.014782 -108.063284)
			(xy 101.987411 -108.062832) (xy 101.933231 -108.055012) (xy 101.880728 -108.039519) (xy 101.830981 -108.016674)
			(xy 101.785015 -107.986947) (xy 101.764084 -107.969304) (xy 101.76383 -107.96905) (xy 101.756743 -107.963464)
			(xy 101.739826 -107.957218) (xy 101.73081 -107.956858) (xy 101.663754 -107.956858) (xy 101.654738 -107.957228)
			(xy 101.63782 -107.963465) (xy 101.630734 -107.96905) (xy 101.63048 -107.969304) (xy 101.609547 -107.986945)
			(xy 101.563579 -108.016669) (xy 101.513833 -108.039515) (xy 101.461331 -108.055011) (xy 101.407153 -108.06284)
			(xy 101.352411 -108.06284) (xy 101.298233 -108.055011) (xy 101.245731 -108.039515) (xy 101.195985 -108.016669)
			(xy 101.150017 -107.986945) (xy 101.129084 -107.969304) (xy 101.12883 -107.96905) (xy 101.121743 -107.963464)
			(xy 101.104826 -107.957218) (xy 101.09581 -107.956858) (xy 101.028754 -107.956858) (xy 101.019738 -107.957228)
			(xy 101.00282 -107.963465) (xy 100.995734 -107.96905) (xy 100.995734 -107.969304) (xy 100.99548 -107.969304)
			(xy 100.974529 -107.98692) (xy 100.928561 -108.016635) (xy 100.878819 -108.039475) (xy 100.826322 -108.054972)
			(xy 100.77215 -108.062806) (xy 100.744782 -108.063284) (xy 100.718467 -108.062834) (xy 100.666338 -108.055596)
			(xy 100.615695 -108.041274) (xy 100.567496 -108.020138) (xy 100.522653 -107.992589) (xy 100.482014 -107.959147)
			(xy 100.463858 -107.940094) (xy 100.456355 -107.932671) (xy 100.437061 -107.924159) (xy 100.42652 -107.923584)
			(xy 100.351844 -107.923584) (xy 100.341296 -107.924128) (xy 100.322001 -107.932653) (xy 100.314506 -107.940094)
			(xy 100.296339 -107.959139) (xy 100.255712 -107.992597) (xy 100.210874 -108.020158) (xy 100.162676 -108.041298)
			(xy 100.11203 -108.055617) (xy 100.059898 -108.062844) (xy 100.033582 -108.063284) (xy 100.00633 -108.062845)
			(xy 99.952381 -108.055086) (xy 99.900085 -108.039728) (xy 99.850507 -108.017085) (xy 99.804656 -107.987616)
			(xy 99.763465 -107.951922) (xy 99.727773 -107.91073) (xy 99.698307 -107.864877) (xy 99.675666 -107.815298)
			(xy 99.66031 -107.763002) (xy 99.652554 -107.709052) (xy 98.35134 -107.709052) (xy 98.35134 -107.740251)
			(xy 98.343584 -107.794197) (xy 98.328231 -107.846492) (xy 98.305591 -107.896068) (xy 98.276127 -107.941919)
			(xy 98.240438 -107.98311) (xy 98.199251 -108.018803) (xy 98.153404 -108.048272) (xy 98.103829 -108.070917)
			(xy 98.051537 -108.086276) (xy 97.997591 -108.094037) (xy 97.97034 -108.094526) (xy 97.94297 -108.094055)
			(xy 97.88879 -108.086241) (xy 97.836286 -108.070754) (xy 97.786539 -108.047913) (xy 97.740573 -108.018188)
			(xy 97.719642 -108.000546) (xy 97.719388 -108.000292) (xy 97.71231 -107.994693) (xy 97.695387 -107.988454)
			(xy 97.686368 -107.9881) (xy 97.619312 -107.9881) (xy 97.610296 -107.988463) (xy 97.593379 -107.994706)
			(xy 97.586292 -108.000292) (xy 97.586038 -108.000546) (xy 97.565105 -108.018187) (xy 97.519137 -108.047911)
			(xy 97.469391 -108.070757) (xy 97.416889 -108.086253) (xy 97.362711 -108.094082) (xy 97.307969 -108.094082)
			(xy 97.253791 -108.086253) (xy 97.201289 -108.070757) (xy 97.151543 -108.047911) (xy 97.105575 -108.018187)
			(xy 97.084642 -108.000546) (xy 97.084388 -108.000292) (xy 97.07731 -107.994693) (xy 97.060387 -107.988454)
			(xy 97.051368 -107.9881) (xy 96.984312 -107.9881) (xy 96.975296 -107.988463) (xy 96.958379 -107.994706)
			(xy 96.951292 -108.000292) (xy 96.951292 -108.000546) (xy 96.951038 -108.000546) (xy 96.930105 -108.018187)
			(xy 96.884137 -108.047911) (xy 96.834391 -108.070757) (xy 96.781889 -108.086253) (xy 96.727711 -108.094082)
			(xy 96.672969 -108.094082) (xy 96.618791 -108.086253) (xy 96.566289 -108.070757) (xy 96.516543 -108.047911)
			(xy 96.470575 -108.018187) (xy 96.449642 -108.000546) (xy 96.449388 -108.000292) (xy 96.44231 -107.994693)
			(xy 96.425387 -107.988454) (xy 96.416368 -107.9881) (xy 96.349312 -107.9881) (xy 96.340296 -107.988463)
			(xy 96.323379 -107.994706) (xy 96.316292 -108.000292) (xy 96.316292 -108.000546) (xy 96.316038 -108.000546)
			(xy 96.295095 -108.018172) (xy 96.249126 -108.047888) (xy 96.199382 -108.070727) (xy 96.146883 -108.086221)
			(xy 96.092709 -108.094051) (xy 96.06534 -108.094526) (xy 96.038087 -108.094029) (xy 95.984134 -108.086277)
			(xy 95.931834 -108.070926) (xy 95.882251 -108.048286) (xy 95.836395 -108.018821) (xy 95.795199 -107.983129)
			(xy 95.759503 -107.941937) (xy 95.730033 -107.896084) (xy 95.707388 -107.846504) (xy 95.692031 -107.794205)
			(xy 95.684273 -107.740253) (xy 91.225364 -107.740253) (xy 91.225364 -107.747344) (xy 91.21674 -107.804172)
			(xy 91.199688 -107.859064) (xy 91.174594 -107.910776) (xy 91.142026 -107.958138) (xy 91.122754 -107.979464)
			(xy 91.11615 -107.986322) (xy 91.109038 -108.004356) (xy 91.109038 -108.093256) (xy 91.11615 -108.11129)
			(xy 91.122754 -108.118148) (xy 91.142026 -108.139474) (xy 91.174593 -108.186836) (xy 91.199685 -108.238548)
			(xy 91.216735 -108.293439) (xy 91.225357 -108.350267) (xy 91.225878 -108.379006) (xy 91.225647 -108.39196)
			(xy 104.22763 -108.39196) (xy 104.228124 -108.364591) (xy 104.235934 -108.310413) (xy 104.251416 -108.257909)
			(xy 104.274252 -108.208162) (xy 104.303971 -108.162194) (xy 104.32161 -108.141262) (xy 104.321864 -108.141008)
			(xy 104.327461 -108.133929) (xy 104.3337 -108.117006) (xy 104.334056 -108.107988) (xy 104.334056 -108.040932)
			(xy 104.333693 -108.031916) (xy 104.327451 -108.014998) (xy 104.321864 -108.007912) (xy 104.32161 -108.007912)
			(xy 104.32161 -108.007658) (xy 104.303986 -107.986714) (xy 104.274272 -107.940744) (xy 104.251433 -107.891)
			(xy 104.235938 -107.838502) (xy 104.228106 -107.784328) (xy 104.22763 -107.75696) (xy 104.228116 -107.729709)
			(xy 104.235872 -107.675761) (xy 104.251227 -107.623466) (xy 104.273869 -107.573889) (xy 104.303335 -107.528039)
			(xy 104.339026 -107.486848) (xy 104.380217 -107.451157) (xy 104.426067 -107.421691) (xy 104.475644 -107.399049)
			(xy 104.527939 -107.383694) (xy 104.581887 -107.375938) (xy 104.636389 -107.375938) (xy 104.690337 -107.383694)
			(xy 104.742632 -107.399049) (xy 104.792209 -107.421691) (xy 104.838059 -107.451157) (xy 104.87925 -107.486848)
			(xy 104.914941 -107.528039) (xy 104.944407 -107.573889) (xy 104.967049 -107.623466) (xy 104.982404 -107.675761)
			(xy 104.99016 -107.729709) (xy 104.990646 -107.75696) (xy 104.99017 -107.78433) (xy 104.982356 -107.838509)
			(xy 104.96687 -107.891013) (xy 104.944031 -107.94076) (xy 104.914307 -107.986727) (xy 104.896666 -108.007658)
			(xy 104.896412 -108.007912) (xy 104.890816 -108.014992) (xy 104.884574 -108.031914) (xy 104.88422 -108.040932)
			(xy 104.88422 -108.107988) (xy 104.884578 -108.117005) (xy 104.890824 -108.133922) (xy 104.896412 -108.141008)
			(xy 104.896666 -108.141008) (xy 104.896666 -108.141262) (xy 104.914295 -108.162202) (xy 104.94401 -108.208172)
			(xy 104.966848 -108.257917) (xy 104.982341 -108.310417) (xy 104.990171 -108.364591) (xy 104.990646 -108.39196)
			(xy 104.99016 -108.419211) (xy 104.982404 -108.473159) (xy 104.967049 -108.525454) (xy 104.94693 -108.569506)
			(xy 106.861102 -108.569506) (xy 106.861571 -108.542136) (xy 106.869388 -108.487957) (xy 106.884876 -108.435454)
			(xy 106.907718 -108.385707) (xy 106.937441 -108.33974) (xy 106.955082 -108.318808) (xy 106.955336 -108.318554)
			(xy 106.96091 -108.311459) (xy 106.967163 -108.294549) (xy 106.967528 -108.285534) (xy 106.967528 -108.218478)
			(xy 106.967176 -108.209461) (xy 106.960924 -108.192544) (xy 106.955336 -108.185458) (xy 106.955082 -108.185458)
			(xy 106.955082 -108.185204) (xy 106.937429 -108.164284) (xy 106.907719 -108.118307) (xy 106.884887 -108.068557)
			(xy 106.869399 -108.016054) (xy 106.861574 -107.961876) (xy 106.861102 -107.934506) (xy 106.861588 -107.907255)
			(xy 106.869344 -107.853307) (xy 106.884699 -107.801012) (xy 106.907341 -107.751435) (xy 106.936807 -107.705585)
			(xy 106.972498 -107.664394) (xy 107.013689 -107.628703) (xy 107.059539 -107.599237) (xy 107.109116 -107.576595)
			(xy 107.161411 -107.56124) (xy 107.215359 -107.553484) (xy 107.269861 -107.553484) (xy 107.323809 -107.56124)
			(xy 107.376104 -107.576595) (xy 107.425681 -107.599237) (xy 107.471531 -107.628703) (xy 107.512722 -107.664394)
			(xy 107.548413 -107.705585) (xy 107.577879 -107.751435) (xy 107.600521 -107.801012) (xy 107.615876 -107.853307)
			(xy 107.623632 -107.907255) (xy 107.624118 -107.934506) (xy 107.623675 -107.961877) (xy 107.615855 -108.016058)
			(xy 107.60057 -108.067856) (xy 123.681234 -108.067856) (xy 123.685305 -108.012234) (xy 123.697431 -107.957797)
			(xy 123.717354 -107.905706) (xy 123.74465 -107.857071) (xy 123.778736 -107.812928) (xy 123.818885 -107.774219)
			(xy 123.864243 -107.741768) (xy 123.913843 -107.716267) (xy 123.966627 -107.69826) (xy 124.02147 -107.68813)
			(xy 124.077204 -107.686093) (xy 124.132641 -107.692193) (xy 124.186598 -107.706299) (xy 124.237927 -107.728111)
			(xy 124.285533 -107.757165) (xy 124.328401 -107.79284) (xy 124.365618 -107.834377) (xy 124.396391 -107.88089)
			(xy 124.420063 -107.931387) (xy 124.436131 -107.984794) (xy 124.444251 -108.03997) (xy 124.44476 -108.067856)
			(xy 124.444251 -108.095742) (xy 124.436131 -108.150918) (xy 124.420063 -108.204325) (xy 124.396391 -108.254822)
			(xy 124.365618 -108.301335) (xy 124.328401 -108.342872) (xy 124.285533 -108.378547) (xy 124.237927 -108.407601)
			(xy 124.186598 -108.429413) (xy 124.132641 -108.443519) (xy 124.077204 -108.449619) (xy 124.02147 -108.447582)
			(xy 123.966627 -108.437452) (xy 123.913843 -108.419445) (xy 123.864243 -108.393944) (xy 123.818885 -108.361493)
			(xy 123.778736 -108.322784) (xy 123.74465 -108.278641) (xy 123.717354 -108.230006) (xy 123.697431 -108.177915)
			(xy 123.685305 -108.123478) (xy 123.681234 -108.067856) (xy 107.60057 -108.067856) (xy 107.600362 -108.068562)
			(xy 107.577514 -108.118309) (xy 107.547783 -108.164274) (xy 107.530138 -108.185204) (xy 107.529884 -108.185458)
			(xy 107.524307 -108.192551) (xy 107.518055 -108.209463) (xy 107.517692 -108.218478) (xy 107.517692 -108.285534)
			(xy 107.518035 -108.294552) (xy 107.524293 -108.311469) (xy 107.529884 -108.318554) (xy 107.530138 -108.318554)
			(xy 107.530138 -108.318808) (xy 107.547801 -108.339721) (xy 107.577508 -108.3857) (xy 107.600339 -108.435452)
			(xy 107.615824 -108.487957) (xy 107.623647 -108.542136) (xy 107.624118 -108.569506) (xy 107.623632 -108.596757)
			(xy 107.615876 -108.650705) (xy 107.600521 -108.703) (xy 107.577879 -108.752577) (xy 107.548413 -108.798427)
			(xy 107.512722 -108.839618) (xy 107.471531 -108.875309) (xy 107.425681 -108.904775) (xy 107.376104 -108.927417)
			(xy 107.323809 -108.942772) (xy 107.269861 -108.950528) (xy 107.215359 -108.950528) (xy 107.161411 -108.942772)
			(xy 107.109116 -108.927417) (xy 107.059539 -108.904775) (xy 107.013689 -108.875309) (xy 106.972498 -108.839618)
			(xy 106.936807 -108.798427) (xy 106.907341 -108.752577) (xy 106.884699 -108.703) (xy 106.869344 -108.650705)
			(xy 106.861588 -108.596757) (xy 106.861102 -108.569506) (xy 104.94693 -108.569506) (xy 104.944407 -108.575031)
			(xy 104.914941 -108.620881) (xy 104.87925 -108.662072) (xy 104.838059 -108.697763) (xy 104.792209 -108.727229)
			(xy 104.742632 -108.749871) (xy 104.690337 -108.765226) (xy 104.636389 -108.772982) (xy 104.581887 -108.772982)
			(xy 104.527939 -108.765226) (xy 104.475644 -108.749871) (xy 104.426067 -108.727229) (xy 104.380217 -108.697763)
			(xy 104.339026 -108.662072) (xy 104.303335 -108.620881) (xy 104.273869 -108.575031) (xy 104.251227 -108.525454)
			(xy 104.235872 -108.473159) (xy 104.228116 -108.419211) (xy 104.22763 -108.39196) (xy 91.225647 -108.39196)
			(xy 91.225392 -108.406257) (xy 91.217636 -108.460205) (xy 91.202281 -108.5125) (xy 91.179639 -108.562077)
			(xy 91.150173 -108.607927) (xy 91.114482 -108.649118) (xy 91.073291 -108.684809) (xy 91.027441 -108.714275)
			(xy 90.977864 -108.736917) (xy 90.925569 -108.752272) (xy 90.871621 -108.760028) (xy 90.817119 -108.760028)
			(xy 90.763171 -108.752272) (xy 90.710876 -108.736917) (xy 90.661299 -108.714275) (xy 90.615449 -108.684809)
			(xy 90.574258 -108.649118) (xy 90.538567 -108.607927) (xy 90.509101 -108.562077) (xy 90.486459 -108.5125)
			(xy 90.471104 -108.460205) (xy 90.463348 -108.406257) (xy 90.462862 -108.379006) (xy 67.311524 -108.379006)
			(xy 67.311524 -108.781596) (xy 67.312137 -108.793443) (xy 67.322736 -108.814635) (xy 67.331844 -108.822236)
			(xy 67.407028 -108.878116) (xy 67.43065 -108.882434) (xy 67.44208 -108.878878) (xy 67.468294 -108.871687)
			(xy 67.522091 -108.863906) (xy 67.549268 -108.863384) (xy 67.55003 -108.863384) (xy 67.577282 -108.86385)
			(xy 67.63123 -108.87161) (xy 67.683524 -108.886969) (xy 67.733101 -108.909613) (xy 67.778951 -108.939082)
			(xy 67.820141 -108.974775) (xy 67.855832 -109.015967) (xy 67.885298 -109.061818) (xy 67.907939 -109.111396)
			(xy 67.923294 -109.163692) (xy 67.931052 -109.21764) (xy 67.931538 -109.244892) (xy 67.931082 -109.272263)
			(xy 67.923264 -109.326443) (xy 67.907774 -109.378947) (xy 67.892117 -109.41304) (xy 71.829422 -109.41304)
			(xy 71.829908 -109.385789) (xy 71.837664 -109.331841) (xy 71.853019 -109.279546) (xy 71.875661 -109.229969)
			(xy 71.905127 -109.184119) (xy 71.940818 -109.142928) (xy 71.982009 -109.107237) (xy 72.027859 -109.077771)
			(xy 72.077436 -109.055129) (xy 72.129731 -109.039774) (xy 72.183679 -109.032018) (xy 72.238181 -109.032018)
			(xy 72.292129 -109.039774) (xy 72.344424 -109.055129) (xy 72.394001 -109.077771) (xy 72.439851 -109.107237)
			(xy 72.481042 -109.142928) (xy 72.516733 -109.184119) (xy 72.546199 -109.229969) (xy 72.568841 -109.279546)
			(xy 72.584196 -109.331841) (xy 72.591952 -109.385789) (xy 72.592438 -109.41304) (xy 72.591998 -109.439234)
			(xy 72.58483 -109.491131) (xy 72.570634 -109.54156) (xy 72.549678 -109.589575) (xy 72.522354 -109.634274)
			(xy 72.489175 -109.674817) (xy 72.470264 -109.692948) (xy 72.462903 -109.700559) (xy 72.454499 -109.719965)
			(xy 72.454008 -109.73054) (xy 72.454516 -109.816392) (xy 72.463152 -109.83595) (xy 72.47128 -109.843062)
			(xy 72.49085 -109.861194) (xy 72.525175 -109.902035) (xy 72.553473 -109.947263) (xy 72.575192 -109.995992)
			(xy 72.589907 -110.047273) (xy 72.597332 -110.100105) (xy 72.597772 -110.12678) (xy 72.597286 -110.154031)
			(xy 72.58953 -110.207979) (xy 72.574175 -110.260274) (xy 72.551533 -110.309851) (xy 72.522067 -110.355701)
			(xy 72.486376 -110.396892) (xy 72.445185 -110.432583) (xy 72.399335 -110.462049) (xy 72.349758 -110.484691)
			(xy 72.297463 -110.500046) (xy 72.243515 -110.507802) (xy 72.189013 -110.507802) (xy 72.135065 -110.500046)
			(xy 72.08277 -110.484691) (xy 72.033193 -110.462049) (xy 71.987343 -110.432583) (xy 71.946152 -110.396892)
			(xy 71.910461 -110.355701) (xy 71.880995 -110.309851) (xy 71.858353 -110.260274) (xy 71.842998 -110.207979)
			(xy 71.835242 -110.154031) (xy 71.834756 -110.12678) (xy 71.835212 -110.100586) (xy 71.842377 -110.04869)
			(xy 71.856569 -109.998262) (xy 71.877523 -109.950247) (xy 71.904844 -109.905547) (xy 71.93802 -109.865003)
			(xy 71.95693 -109.846872) (xy 71.964326 -109.83929) (xy 71.972711 -109.819862) (xy 71.973186 -109.80928)
			(xy 71.972678 -109.723428) (xy 71.964042 -109.70387) (xy 71.955914 -109.696758) (xy 71.936353 -109.678618)
			(xy 71.902027 -109.637778) (xy 71.873728 -109.592552) (xy 71.852008 -109.543824) (xy 71.83729 -109.492545)
			(xy 71.829864 -109.439715) (xy 71.829422 -109.41304) (xy 67.892117 -109.41304) (xy 67.884929 -109.428693)
			(xy 67.855201 -109.474659) (xy 67.837558 -109.49559) (xy 67.837304 -109.495844) (xy 67.831735 -109.502943)
			(xy 67.825478 -109.51985) (xy 67.825112 -109.528864) (xy 67.825112 -109.59592) (xy 67.825457 -109.604938)
			(xy 67.831713 -109.621855) (xy 67.837304 -109.62894) (xy 67.837558 -109.62894) (xy 67.837558 -109.629194)
			(xy 67.855191 -109.650133) (xy 67.884918 -109.696099) (xy 67.907764 -109.745844) (xy 67.923262 -109.798346)
			(xy 67.931092 -109.852524) (xy 67.931093 -109.907264) (xy 67.923265 -109.961443) (xy 67.907769 -110.013944)
			(xy 67.884924 -110.06369) (xy 67.855199 -110.109658) (xy 67.837558 -110.13059) (xy 67.837304 -110.130844)
			(xy 67.831735 -110.137943) (xy 67.825478 -110.15485) (xy 67.825112 -110.163864) (xy 67.825112 -110.23092)
			(xy 67.825457 -110.239938) (xy 67.831713 -110.256855) (xy 67.837304 -110.26394) (xy 67.837558 -110.26394)
			(xy 67.837558 -110.264194) (xy 67.855191 -110.285133) (xy 67.884918 -110.331099) (xy 67.907764 -110.380844)
			(xy 67.923262 -110.433346) (xy 67.931092 -110.487524) (xy 67.931093 -110.530132) (xy 70.429118 -110.530132)
			(xy 70.433189 -110.47451) (xy 70.445315 -110.420073) (xy 70.465238 -110.367982) (xy 70.492534 -110.319347)
			(xy 70.52662 -110.275204) (xy 70.566769 -110.236495) (xy 70.612127 -110.204044) (xy 70.661727 -110.178543)
			(xy 70.714511 -110.160536) (xy 70.769354 -110.150406) (xy 70.825088 -110.148369) (xy 70.880525 -110.154469)
			(xy 70.934482 -110.168575) (xy 70.985811 -110.190387) (xy 71.033417 -110.219441) (xy 71.076285 -110.255116)
			(xy 71.113502 -110.296653) (xy 71.144275 -110.343166) (xy 71.167947 -110.393663) (xy 71.184015 -110.44707)
			(xy 71.192135 -110.502246) (xy 71.192644 -110.530132) (xy 71.192135 -110.558018) (xy 71.184015 -110.613194)
			(xy 71.167947 -110.666601) (xy 71.144275 -110.717098) (xy 71.113502 -110.763611) (xy 71.076285 -110.805148)
			(xy 71.033417 -110.840823) (xy 70.985811 -110.869877) (xy 70.934482 -110.891689) (xy 70.880525 -110.905795)
			(xy 70.825088 -110.911895) (xy 70.769354 -110.909858) (xy 70.714511 -110.899728) (xy 70.661727 -110.881721)
			(xy 70.612127 -110.85622) (xy 70.566769 -110.823769) (xy 70.52662 -110.78506) (xy 70.492534 -110.740917)
			(xy 70.465238 -110.692282) (xy 70.445315 -110.640191) (xy 70.433189 -110.585754) (xy 70.429118 -110.530132)
			(xy 67.931093 -110.530132) (xy 67.931093 -110.542264) (xy 67.923265 -110.596443) (xy 67.907769 -110.648944)
			(xy 67.884924 -110.69869) (xy 67.855199 -110.744658) (xy 67.837558 -110.76559) (xy 67.837304 -110.765844)
			(xy 67.831735 -110.772943) (xy 67.825478 -110.78985) (xy 67.825112 -110.798864) (xy 67.825112 -110.86592)
			(xy 67.825457 -110.874938) (xy 67.831713 -110.891855) (xy 67.837304 -110.89894) (xy 67.837558 -110.89894)
			(xy 67.837558 -110.899194) (xy 67.855191 -110.920133) (xy 67.884918 -110.966099) (xy 67.907764 -111.015844)
			(xy 67.907895 -111.016288) (xy 71.78802 -111.016288) (xy 71.788506 -110.989037) (xy 71.796262 -110.935089)
			(xy 71.811617 -110.882794) (xy 71.834259 -110.833217) (xy 71.863725 -110.787367) (xy 71.899416 -110.746176)
			(xy 71.940607 -110.710485) (xy 71.986457 -110.681019) (xy 72.036034 -110.658377) (xy 72.088329 -110.643022)
			(xy 72.142277 -110.635266) (xy 72.196779 -110.635266) (xy 72.250727 -110.643022) (xy 72.303022 -110.658377)
			(xy 72.352599 -110.681019) (xy 72.398449 -110.710485) (xy 72.43964 -110.746176) (xy 72.475331 -110.787367)
			(xy 72.504797 -110.833217) (xy 72.527439 -110.882794) (xy 72.542794 -110.935089) (xy 72.55055 -110.989037)
			(xy 72.551036 -111.016288) (xy 72.550585 -111.043309) (xy 72.542972 -111.096812) (xy 72.527881 -111.148704)
			(xy 72.505615 -111.197945) (xy 72.476621 -111.24355) (xy 72.441479 -111.284606) (xy 72.421496 -111.3028)
			(xy 72.413541 -111.31046) (xy 72.404591 -111.330624) (xy 72.404224 -111.341662) (xy 72.405494 -111.418878)
			(xy 72.406146 -111.429892) (xy 72.415643 -111.449782) (xy 72.423782 -111.457232) (xy 72.444922 -111.475455)
			(xy 72.482198 -111.516992) (xy 72.513021 -111.563519) (xy 72.536734 -111.614042) (xy 72.552829 -111.667482)
			(xy 72.560964 -111.722697) (xy 72.56145 -111.750602) (xy 72.560845 -111.780395) (xy 72.551594 -111.839258)
			(xy 72.533302 -111.895966) (xy 72.506414 -111.949139) (xy 72.483658 -111.980726) (xy 73.901554 -111.980726)
			(xy 73.902106 -111.951988) (xy 73.910723 -111.895163) (xy 73.927768 -111.840273) (xy 73.952853 -111.788561)
			(xy 73.985411 -111.741196) (xy 74.004678 -111.719868) (xy 74.011282 -111.71301) (xy 74.018394 -111.694976)
			(xy 74.018394 -111.606076) (xy 74.011282 -111.588042) (xy 74.004678 -111.581184) (xy 73.985435 -111.559834)
			(xy 73.952873 -111.512474) (xy 73.927783 -111.460766) (xy 73.910733 -111.405879) (xy 73.902109 -111.349056)
			(xy 73.902106 -111.291582) (xy 73.910725 -111.234758) (xy 73.927769 -111.17987) (xy 73.952854 -111.128159)
			(xy 73.985411 -111.080796) (xy 74.004678 -111.059468) (xy 74.011282 -111.05261) (xy 74.018394 -111.034576)
			(xy 74.018394 -110.945676) (xy 74.011282 -110.927642) (xy 74.004678 -110.920784) (xy 73.985435 -110.899434)
			(xy 73.952873 -110.852074) (xy 73.927783 -110.800366) (xy 73.910733 -110.745479) (xy 73.902109 -110.688656)
			(xy 73.902106 -110.631182) (xy 73.910725 -110.574358) (xy 73.927769 -110.51947) (xy 73.952854 -110.467759)
			(xy 73.985411 -110.420396) (xy 74.004678 -110.399068) (xy 74.011282 -110.39221) (xy 74.018394 -110.374176)
			(xy 74.018394 -110.285276) (xy 74.011282 -110.267242) (xy 74.004678 -110.260384) (xy 73.985435 -110.239034)
			(xy 73.952873 -110.191674) (xy 73.927783 -110.139966) (xy 73.910733 -110.085079) (xy 73.902109 -110.028256)
			(xy 73.902106 -109.970782) (xy 73.910725 -109.913958) (xy 73.927769 -109.85907) (xy 73.952854 -109.807359)
			(xy 73.985411 -109.759996) (xy 74.004678 -109.738668) (xy 74.011282 -109.73181) (xy 74.018394 -109.713776)
			(xy 74.018394 -109.624876) (xy 74.011282 -109.606842) (xy 74.004678 -109.599984) (xy 73.985426 -109.57864)
			(xy 73.952856 -109.531284) (xy 73.927759 -109.479576) (xy 73.910704 -109.424689) (xy 73.902077 -109.367864)
			(xy 73.901554 -109.339126) (xy 73.902102 -109.311877) (xy 73.909854 -109.257934) (xy 73.925204 -109.205642)
			(xy 73.94784 -109.156068) (xy 73.9773 -109.110219) (xy 74.012984 -109.06903) (xy 74.054168 -109.033338)
			(xy 74.100012 -109.00387) (xy 74.149582 -108.981227) (xy 74.201871 -108.965868) (xy 74.255813 -108.958107)
			(xy 74.283062 -108.957618) (xy 74.309378 -108.958038) (xy 74.361508 -108.965282) (xy 74.412152 -108.97961)
			(xy 74.460351 -109.000751) (xy 74.505193 -109.028306) (xy 74.545831 -109.061753) (xy 74.563986 -109.080808)
			(xy 74.57151 -109.088206) (xy 74.590788 -109.096732) (xy 74.601324 -109.097318) (xy 74.676 -109.097318)
			(xy 74.686551 -109.096797) (xy 74.705845 -109.088256) (xy 74.713338 -109.080808) (xy 74.731484 -109.061743)
			(xy 74.772115 -109.028286) (xy 74.816958 -109.000728) (xy 74.86516 -108.979591) (xy 74.91581 -108.965276)
			(xy 74.967945 -108.958055) (xy 74.994262 -108.957618) (xy 75.021515 -108.958091) (xy 75.075467 -108.965843)
			(xy 75.127766 -108.981196) (xy 75.177348 -109.003836) (xy 75.223203 -109.033302) (xy 75.264396 -109.068995)
			(xy 75.300091 -109.110188) (xy 75.329559 -109.156041) (xy 75.3522 -109.205622) (xy 75.367554 -109.257921)
			(xy 75.375308 -109.311873) (xy 75.37577 -109.339126) (xy 75.375243 -109.367865) (xy 75.366619 -109.424691)
			(xy 75.349568 -109.479581) (xy 75.338473 -109.502448) (xy 109.415072 -109.502448) (xy 109.415558 -109.475197)
			(xy 109.423314 -109.421249) (xy 109.438669 -109.368954) (xy 109.461311 -109.319377) (xy 109.490777 -109.273527)
			(xy 109.526468 -109.232336) (xy 109.567659 -109.196645) (xy 109.613509 -109.167179) (xy 109.663086 -109.144537)
			(xy 109.715381 -109.129182) (xy 109.769329 -109.121426) (xy 109.823831 -109.121426) (xy 109.877779 -109.129182)
			(xy 109.930074 -109.144537) (xy 109.979651 -109.167179) (xy 110.025501 -109.196645) (xy 110.066692 -109.232336)
			(xy 110.102383 -109.273527) (xy 110.131849 -109.319377) (xy 110.154491 -109.368954) (xy 110.169846 -109.421249)
			(xy 110.177602 -109.475197) (xy 110.178088 -109.502448) (xy 110.17766 -109.527979) (xy 110.170855 -109.578587)
			(xy 110.15736 -109.627834) (xy 110.137415 -109.674841) (xy 110.124748 -109.697012) (xy 110.118894 -109.706918)
			(xy 121.915172 -109.706918) (xy 121.919243 -109.651296) (xy 121.931369 -109.596859) (xy 121.951292 -109.544768)
			(xy 121.978588 -109.496133) (xy 122.012674 -109.45199) (xy 122.052823 -109.413281) (xy 122.098181 -109.38083)
			(xy 122.147781 -109.355329) (xy 122.200565 -109.337322) (xy 122.255408 -109.327192) (xy 122.311142 -109.325155)
			(xy 122.366579 -109.331255) (xy 122.420536 -109.345361) (xy 122.471865 -109.367173) (xy 122.519471 -109.396227)
			(xy 122.562339 -109.431902) (xy 122.599556 -109.473439) (xy 122.630329 -109.519952) (xy 122.654001 -109.570449)
			(xy 122.65685 -109.579918) (xy 123.947172 -109.579918) (xy 123.951243 -109.524296) (xy 123.963369 -109.469859)
			(xy 123.983292 -109.417768) (xy 124.010588 -109.369133) (xy 124.044674 -109.32499) (xy 124.084823 -109.286281)
			(xy 124.130181 -109.25383) (xy 124.179781 -109.228329) (xy 124.232565 -109.210322) (xy 124.287408 -109.200192)
			(xy 124.343142 -109.198155) (xy 124.398579 -109.204255) (xy 124.452536 -109.218361) (xy 124.503865 -109.240173)
			(xy 124.551471 -109.269227) (xy 124.594339 -109.304902) (xy 124.631556 -109.346439) (xy 124.662329 -109.392952)
			(xy 124.679962 -109.430566) (xy 140.055852 -109.430566) (xy 140.059923 -109.374944) (xy 140.072049 -109.320507)
			(xy 140.091972 -109.268416) (xy 140.119268 -109.219781) (xy 140.153354 -109.175638) (xy 140.193503 -109.136929)
			(xy 140.238861 -109.104478) (xy 140.288461 -109.078977) (xy 140.341245 -109.06097) (xy 140.396088 -109.05084)
			(xy 140.451822 -109.048803) (xy 140.507259 -109.054903) (xy 140.561216 -109.069009) (xy 140.612545 -109.090821)
			(xy 140.660151 -109.119875) (xy 140.703019 -109.15555) (xy 140.740236 -109.197087) (xy 140.771009 -109.2436)
			(xy 140.794681 -109.294097) (xy 140.810749 -109.347504) (xy 140.818869 -109.40268) (xy 140.818991 -109.409357)
			(xy 150.210407 -109.409357) (xy 150.210407 -109.354843) (xy 150.218165 -109.300883) (xy 150.233524 -109.248577)
			(xy 150.256171 -109.198989) (xy 150.285645 -109.15313) (xy 150.321345 -109.111931) (xy 150.362546 -109.076233)
			(xy 150.408407 -109.046762) (xy 150.457996 -109.024117) (xy 150.510303 -109.008761) (xy 150.564263 -109.001006)
			(xy 150.59152 -109.000544) (xy 150.592028 -109.000544) (xy 150.606757 -109.000693) (xy 150.636127 -109.00298)
			(xy 150.650702 -109.005116) (xy 150.661677 -109.006231) (xy 150.682867 -109.000177) (xy 150.691596 -108.993432)
			(xy 150.750016 -108.943394) (xy 150.758042 -108.935825) (xy 150.767258 -108.915806) (xy 150.767796 -108.904786)
			(xy 150.767796 -108.600494) (xy 150.767263 -108.589474) (xy 150.75804 -108.569458) (xy 150.750016 -108.561886)
			(xy 150.68296 -108.504482) (xy 150.661878 -108.498386) (xy 150.650702 -108.500164) (xy 150.636127 -108.502293)
			(xy 150.606757 -108.504584) (xy 150.592028 -108.504736) (xy 150.59152 -108.504736) (xy 150.564268 -108.504218)
			(xy 150.510319 -108.496464) (xy 150.458023 -108.481111) (xy 150.408444 -108.458471) (xy 150.362591 -108.429006)
			(xy 150.321399 -108.393315) (xy 150.285706 -108.352125) (xy 150.256238 -108.306274) (xy 150.233596 -108.256696)
			(xy 150.21824 -108.2044) (xy 150.210483 -108.150452) (xy 150.210483 -108.095948) (xy 150.21824 -108.042)
			(xy 150.233596 -107.989704) (xy 150.256238 -107.940126) (xy 150.285706 -107.894275) (xy 150.321399 -107.853085)
			(xy 150.362591 -107.817394) (xy 150.408444 -107.787929) (xy 150.458023 -107.765289) (xy 150.510319 -107.749936)
			(xy 150.564268 -107.742182) (xy 150.59152 -107.74172) (xy 150.617458 -107.74212) (xy 150.668855 -107.749152)
			(xy 150.718826 -107.763084) (xy 150.766448 -107.783658) (xy 150.810843 -107.810495) (xy 150.851192 -107.8431)
			(xy 150.88675 -107.880872) (xy 150.902162 -107.90174) (xy 150.907989 -107.909068) (xy 150.923605 -107.919365)
			(xy 150.932642 -107.921806) (xy 150.962614 -107.928664) (xy 150.97191 -107.930359) (xy 150.990574 -107.927479)
			(xy 150.998936 -107.923076) (xy 151.024953 -107.908812) (xy 151.079884 -107.886381) (xy 151.137249 -107.871222)
			(xy 151.196091 -107.863589) (xy 151.225758 -107.863132) (xy 151.255386 -107.863557) (xy 151.314155 -107.871142)
			(xy 151.371455 -107.886241) (xy 151.426329 -107.908602) (xy 151.452326 -107.922822) (xy 151.46071 -107.927154)
			(xy 151.479348 -107.930014) (xy 151.488648 -107.92841) (xy 151.51862 -107.921552) (xy 151.527705 -107.919212)
			(xy 151.543367 -107.908911) (xy 151.5491 -107.901486) (xy 151.564488 -107.880634) (xy 151.600033 -107.842923)
			(xy 151.640359 -107.810373) (xy 151.684722 -107.783586) (xy 151.732304 -107.763054) (xy 151.782229 -107.749156)
			(xy 151.833576 -107.742149) (xy 151.859488 -107.74172) (xy 151.886743 -107.742126) (xy 151.9407 -107.749882)
			(xy 151.993003 -107.765238) (xy 152.042588 -107.787882) (xy 152.088446 -107.817352) (xy 152.129643 -107.853048)
			(xy 152.165341 -107.894244) (xy 152.194812 -107.940101) (xy 152.217457 -107.989686) (xy 152.232815 -108.041989)
			(xy 152.240573 -108.095945) (xy 152.240573 -108.150455) (xy 152.232815 -108.204411) (xy 152.217457 -108.256714)
			(xy 152.206847 -108.279946) (xy 163.111432 -108.279946) (xy 163.115503 -108.224324) (xy 163.127629 -108.169887)
			(xy 163.147552 -108.117796) (xy 163.174848 -108.069161) (xy 163.208934 -108.025018) (xy 163.249083 -107.986309)
			(xy 163.294441 -107.953858) (xy 163.344041 -107.928357) (xy 163.396825 -107.91035) (xy 163.451668 -107.90022)
			(xy 163.507402 -107.898183) (xy 163.562839 -107.904283) (xy 163.616796 -107.918389) (xy 163.668125 -107.940201)
			(xy 163.715731 -107.969255) (xy 163.758599 -108.00493) (xy 163.795816 -108.046467) (xy 163.826589 -108.09298)
			(xy 163.850261 -108.143477) (xy 163.866329 -108.196884) (xy 163.874449 -108.25206) (xy 163.874958 -108.279946)
			(xy 163.874449 -108.307832) (xy 163.866329 -108.363008) (xy 163.850261 -108.416415) (xy 163.826589 -108.466912)
			(xy 163.795816 -108.513425) (xy 163.758599 -108.554962) (xy 163.715731 -108.590637) (xy 163.668125 -108.619691)
			(xy 163.616796 -108.641503) (xy 163.562839 -108.655609) (xy 163.507402 -108.661709) (xy 163.451668 -108.659672)
			(xy 163.396825 -108.649542) (xy 163.344041 -108.631535) (xy 163.294441 -108.606034) (xy 163.249083 -108.573583)
			(xy 163.208934 -108.534874) (xy 163.174848 -108.490731) (xy 163.147552 -108.442096) (xy 163.127629 -108.390005)
			(xy 163.115503 -108.335568) (xy 163.111432 -108.279946) (xy 152.206847 -108.279946) (xy 152.194812 -108.306299)
			(xy 152.165341 -108.352156) (xy 152.129643 -108.393352) (xy 152.088446 -108.429048) (xy 152.042588 -108.458518)
			(xy 151.993003 -108.481162) (xy 151.9407 -108.496518) (xy 151.886743 -108.504274) (xy 151.859488 -108.504736)
			(xy 151.844759 -108.504586) (xy 151.815389 -108.502299) (xy 151.800814 -108.500164) (xy 151.789839 -108.499063)
			(xy 151.76865 -108.505108) (xy 151.75992 -108.511848) (xy 151.7015 -108.561886) (xy 151.693485 -108.569466)
			(xy 151.684262 -108.589477) (xy 151.68372 -108.600494) (xy 151.68372 -108.904786) (xy 151.684259 -108.915805)
			(xy 151.693477 -108.935822) (xy 151.7015 -108.943394) (xy 151.768556 -109.000798) (xy 151.789638 -109.006894)
			(xy 151.800814 -109.005116) (xy 151.815389 -109.002985) (xy 151.844759 -109.000696) (xy 151.859488 -109.000544)
			(xy 151.886738 -109.001102) (xy 151.940683 -109.008857) (xy 151.992976 -109.02421) (xy 152.042552 -109.046849)
			(xy 152.0884 -109.076313) (xy 152.129589 -109.112002) (xy 152.16528 -109.15319) (xy 152.180793 -109.177328)
			(xy 165.164768 -109.177328) (xy 165.168839 -109.121706) (xy 165.180965 -109.067269) (xy 165.200888 -109.015178)
			(xy 165.228184 -108.966543) (xy 165.26227 -108.9224) (xy 165.302419 -108.883691) (xy 165.347777 -108.85124)
			(xy 165.397377 -108.825739) (xy 165.450161 -108.807732) (xy 165.505004 -108.797602) (xy 165.560738 -108.795565)
			(xy 165.616175 -108.801665) (xy 165.670132 -108.815771) (xy 165.721461 -108.837583) (xy 165.769067 -108.866637)
			(xy 165.811935 -108.902312) (xy 165.849152 -108.943849) (xy 165.879925 -108.990362) (xy 165.903597 -109.040859)
			(xy 165.919665 -109.094266) (xy 165.927785 -109.149442) (xy 165.928294 -109.177328) (xy 165.927785 -109.205214)
			(xy 165.919665 -109.26039) (xy 165.903597 -109.313797) (xy 165.879925 -109.364294) (xy 165.849152 -109.410807)
			(xy 165.811935 -109.452344) (xy 165.769067 -109.488019) (xy 165.721461 -109.517073) (xy 165.670132 -109.538885)
			(xy 165.616175 -109.552991) (xy 165.560738 -109.559091) (xy 165.505004 -109.557054) (xy 165.450161 -109.546924)
			(xy 165.397377 -109.528917) (xy 165.347777 -109.503416) (xy 165.302419 -109.470965) (xy 165.26227 -109.432256)
			(xy 165.228184 -109.388113) (xy 165.200888 -109.339478) (xy 165.180965 -109.287387) (xy 165.168839 -109.23295)
			(xy 165.164768 -109.177328) (xy 152.180793 -109.177328) (xy 152.194745 -109.199038) (xy 152.217386 -109.248613)
			(xy 152.23274 -109.300905) (xy 152.240497 -109.35485) (xy 152.240497 -109.40935) (xy 152.23274 -109.463295)
			(xy 152.217386 -109.515587) (xy 152.194745 -109.565162) (xy 152.16528 -109.61101) (xy 152.129589 -109.652198)
			(xy 152.0884 -109.687887) (xy 152.042552 -109.717351) (xy 151.992976 -109.73999) (xy 151.940683 -109.755343)
			(xy 151.886738 -109.763098) (xy 151.859488 -109.76356) (xy 151.83358 -109.763097) (xy 151.782243 -109.756071)
			(xy 151.732329 -109.742164) (xy 151.684755 -109.721631) (xy 151.640397 -109.69485) (xy 151.60007 -109.662314)
			(xy 151.564516 -109.624621) (xy 151.5491 -109.603794) (xy 151.54328 -109.59646) (xy 151.52766 -109.586165)
			(xy 151.51862 -109.583728) (xy 151.488648 -109.57687) (xy 151.479347 -109.575216) (xy 151.46069 -109.57807)
			(xy 151.452326 -109.582458) (xy 151.426333 -109.596685) (xy 151.371458 -109.619046) (xy 151.314157 -109.63414)
			(xy 151.255387 -109.641715) (xy 151.225758 -109.642148) (xy 151.196088 -109.641717) (xy 151.137239 -109.634108)
			(xy 151.07987 -109.618945) (xy 151.024947 -109.596484) (xy 150.998936 -109.582204) (xy 150.990538 -109.577904)
			(xy 150.971912 -109.575023) (xy 150.962614 -109.576616) (xy 150.932642 -109.583474) (xy 150.923549 -109.58579)
			(xy 150.907891 -109.596108) (xy 150.902162 -109.60354) (xy 150.886745 -109.624402) (xy 150.851184 -109.662166)
			(xy 150.810833 -109.694764) (xy 150.766439 -109.721595) (xy 150.718818 -109.742165) (xy 150.668851 -109.756093)
			(xy 150.617456 -109.763123) (xy 150.59152 -109.76356) (xy 150.564263 -109.763194) (xy 150.510303 -109.755439)
			(xy 150.457996 -109.740083) (xy 150.408407 -109.717438) (xy 150.362546 -109.687967) (xy 150.321345 -109.652269)
			(xy 150.285645 -109.61107) (xy 150.256171 -109.565211) (xy 150.233524 -109.515623) (xy 150.218165 -109.463317)
			(xy 150.210407 -109.409357) (xy 140.818991 -109.409357) (xy 140.819378 -109.430566) (xy 140.818869 -109.458452)
			(xy 140.810749 -109.513628) (xy 140.794681 -109.567035) (xy 140.771009 -109.617532) (xy 140.740236 -109.664045)
			(xy 140.703019 -109.705582) (xy 140.660151 -109.741257) (xy 140.612545 -109.770311) (xy 140.561216 -109.792123)
			(xy 140.507259 -109.806229) (xy 140.451822 -109.812329) (xy 140.396088 -109.810292) (xy 140.341245 -109.800162)
			(xy 140.288461 -109.782155) (xy 140.238861 -109.756654) (xy 140.193503 -109.724203) (xy 140.153354 -109.685494)
			(xy 140.119268 -109.641351) (xy 140.091972 -109.592716) (xy 140.072049 -109.540625) (xy 140.059923 -109.486188)
			(xy 140.055852 -109.430566) (xy 124.679962 -109.430566) (xy 124.686001 -109.443449) (xy 124.702069 -109.496856)
			(xy 124.710189 -109.552032) (xy 124.710698 -109.579918) (xy 124.710189 -109.607804) (xy 124.702069 -109.66298)
			(xy 124.686001 -109.716387) (xy 124.662329 -109.766884) (xy 124.631556 -109.813397) (xy 124.594339 -109.854934)
			(xy 124.551471 -109.890609) (xy 124.503865 -109.919663) (xy 124.452536 -109.941475) (xy 124.443057 -109.943953)
			(xy 152.852577 -109.943953) (xy 152.852577 -109.889447) (xy 152.860335 -109.835497) (xy 152.875691 -109.7832)
			(xy 152.898334 -109.733621) (xy 152.927803 -109.687769) (xy 152.963498 -109.646578) (xy 153.004692 -109.610887)
			(xy 153.050546 -109.581421) (xy 153.100126 -109.558781) (xy 153.152425 -109.543429) (xy 153.206375 -109.535675)
			(xy 153.233628 -109.535214) (xy 153.259564 -109.535686) (xy 153.310958 -109.542705) (xy 153.360927 -109.556625)
			(xy 153.408548 -109.577187) (xy 153.452944 -109.604013) (xy 153.493295 -109.636608) (xy 153.528857 -109.674371)
			(xy 153.54427 -109.695234) (xy 153.550096 -109.702564) (xy 153.565712 -109.71286) (xy 153.57475 -109.7153)
			(xy 153.604722 -109.722158) (xy 153.614018 -109.723858) (xy 153.632682 -109.720975) (xy 153.641044 -109.71657)
			(xy 153.667049 -109.702267) (xy 153.721974 -109.679777) (xy 153.779341 -109.664557) (xy 153.838191 -109.656861)
			(xy 153.867866 -109.656372) (xy 153.897502 -109.656834) (xy 153.956278 -109.664483) (xy 154.013577 -109.679645)
			(xy 154.068444 -109.702068) (xy 154.094434 -109.716316) (xy 154.102816 -109.720652) (xy 154.121455 -109.72351)
			(xy 154.130756 -109.721904) (xy 154.160728 -109.715046) (xy 154.169815 -109.712711) (xy 154.185476 -109.702407)
			(xy 154.191208 -109.69498) (xy 154.206589 -109.674123) (xy 154.242136 -109.636412) (xy 154.282463 -109.603863)
			(xy 154.326827 -109.577077) (xy 154.37441 -109.556546) (xy 154.424336 -109.542649) (xy 154.475684 -109.535642)
			(xy 154.501596 -109.535214) (xy 154.528851 -109.535633) (xy 154.582805 -109.54339) (xy 154.635107 -109.558746)
			(xy 154.68469 -109.58139) (xy 154.730546 -109.610859) (xy 154.76988 -109.644942) (xy 160.769552 -109.644942)
			(xy 160.773623 -109.58932) (xy 160.785749 -109.534883) (xy 160.805672 -109.482792) (xy 160.832968 -109.434157)
			(xy 160.867054 -109.390014) (xy 160.907203 -109.351305) (xy 160.952561 -109.318854) (xy 161.002161 -109.293353)
			(xy 161.054945 -109.275346) (xy 161.109788 -109.265216) (xy 161.165522 -109.263179) (xy 161.220959 -109.269279)
			(xy 161.274916 -109.283385) (xy 161.326245 -109.305197) (xy 161.373851 -109.334251) (xy 161.416719 -109.369926)
			(xy 161.453936 -109.411463) (xy 161.484709 -109.457976) (xy 161.508381 -109.508473) (xy 161.524449 -109.56188)
			(xy 161.532569 -109.617056) (xy 161.533078 -109.644942) (xy 161.532569 -109.672828) (xy 161.524449 -109.728004)
			(xy 161.508381 -109.781411) (xy 161.484709 -109.831908) (xy 161.453936 -109.878421) (xy 161.416719 -109.919958)
			(xy 161.373851 -109.955633) (xy 161.326245 -109.984687) (xy 161.274916 -110.006499) (xy 161.220959 -110.020605)
			(xy 161.165522 -110.026705) (xy 161.109788 -110.024668) (xy 161.054945 -110.014538) (xy 161.002161 -109.996531)
			(xy 160.952561 -109.97103) (xy 160.907203 -109.938579) (xy 160.867054 -109.89987) (xy 160.832968 -109.855727)
			(xy 160.805672 -109.807092) (xy 160.785749 -109.755001) (xy 160.773623 -109.700564) (xy 160.769552 -109.644942)
			(xy 154.76988 -109.644942) (xy 154.771742 -109.646555) (xy 154.807438 -109.68775) (xy 154.836908 -109.733606)
			(xy 154.859552 -109.78319) (xy 154.87491 -109.835491) (xy 154.882667 -109.889445) (xy 154.882667 -109.943955)
			(xy 154.87491 -109.997909) (xy 154.859552 -110.05021) (xy 154.836908 -110.099794) (xy 154.807438 -110.14565)
			(xy 154.771742 -110.186845) (xy 154.730546 -110.222541) (xy 154.68469 -110.25201) (xy 154.635107 -110.274654)
			(xy 154.582805 -110.29001) (xy 154.528851 -110.297767) (xy 154.501596 -110.29823) (xy 154.486867 -110.298079)
			(xy 154.457497 -110.295793) (xy 154.442922 -110.293658) (xy 154.431947 -110.292563) (xy 154.410759 -110.298604)
			(xy 154.402028 -110.305342) (xy 154.343608 -110.35538) (xy 154.335597 -110.362963) (xy 154.326371 -110.382972)
			(xy 154.325828 -110.393988) (xy 154.325828 -110.69828) (xy 154.326368 -110.709299) (xy 154.335585 -110.729316)
			(xy 154.343608 -110.736888) (xy 154.410664 -110.794292) (xy 154.431746 -110.800388) (xy 154.442922 -110.79861)
			(xy 154.457497 -110.796479) (xy 154.486867 -110.794189) (xy 154.501596 -110.794038) (xy 154.528852 -110.794409)
			(xy 154.58281 -110.802166) (xy 154.635115 -110.817524) (xy 154.684702 -110.840169) (xy 154.711729 -110.857538)
			(xy 165.064438 -110.857538) (xy 165.068509 -110.801916) (xy 165.080635 -110.747479) (xy 165.100558 -110.695388)
			(xy 165.127854 -110.646753) (xy 165.16194 -110.60261) (xy 165.202089 -110.563901) (xy 165.247447 -110.53145)
			(xy 165.297047 -110.505949) (xy 165.349831 -110.487942) (xy 165.404674 -110.477812) (xy 165.460408 -110.475775)
			(xy 165.515845 -110.481875) (xy 165.569802 -110.495981) (xy 165.621131 -110.517793) (xy 165.668737 -110.546847)
			(xy 165.711605 -110.582522) (xy 165.748822 -110.624059) (xy 165.779595 -110.670572) (xy 165.803267 -110.721069)
			(xy 165.819335 -110.774476) (xy 165.827455 -110.829652) (xy 165.827964 -110.857538) (xy 165.827455 -110.885424)
			(xy 165.819335 -110.9406) (xy 165.803267 -110.994007) (xy 165.779595 -111.044504) (xy 165.748822 -111.091017)
			(xy 165.711605 -111.132554) (xy 165.668737 -111.168229) (xy 165.621131 -111.197283) (xy 165.569802 -111.219095)
			(xy 165.515845 -111.233201) (xy 165.460408 -111.239301) (xy 165.404674 -111.237264) (xy 165.349831 -111.227134)
			(xy 165.297047 -111.209127) (xy 165.247447 -111.183626) (xy 165.202089 -111.151175) (xy 165.16194 -111.112466)
			(xy 165.127854 -111.068323) (xy 165.100558 -111.019688) (xy 165.080635 -110.967597) (xy 165.068509 -110.91316)
			(xy 165.064438 -110.857538) (xy 154.711729 -110.857538) (xy 154.730561 -110.86964) (xy 154.771759 -110.905338)
			(xy 154.807457 -110.946536) (xy 154.836929 -110.992395) (xy 154.859575 -111.041981) (xy 154.874933 -111.094286)
			(xy 154.882691 -111.148244) (xy 154.882691 -111.202756) (xy 154.874933 -111.256714) (xy 154.859575 -111.309019)
			(xy 154.836929 -111.358605) (xy 154.807457 -111.404464) (xy 154.772298 -111.44504) (xy 160.769552 -111.44504)
			(xy 160.773623 -111.389418) (xy 160.785749 -111.334981) (xy 160.805672 -111.28289) (xy 160.832968 -111.234255)
			(xy 160.867054 -111.190112) (xy 160.907203 -111.151403) (xy 160.952561 -111.118952) (xy 161.002161 -111.093451)
			(xy 161.054945 -111.075444) (xy 161.109788 -111.065314) (xy 161.165522 -111.063277) (xy 161.220959 -111.069377)
			(xy 161.274916 -111.083483) (xy 161.326245 -111.105295) (xy 161.373851 -111.134349) (xy 161.416719 -111.170024)
			(xy 161.453936 -111.211561) (xy 161.484709 -111.258074) (xy 161.508381 -111.308571) (xy 161.524449 -111.361978)
			(xy 161.532569 -111.417154) (xy 161.533078 -111.44504) (xy 161.532569 -111.472926) (xy 161.524449 -111.528102)
			(xy 161.508381 -111.581509) (xy 161.484709 -111.632006) (xy 161.453936 -111.678519) (xy 161.416719 -111.720056)
			(xy 161.373851 -111.755731) (xy 161.326245 -111.784785) (xy 161.274916 -111.806597) (xy 161.220959 -111.820703)
			(xy 161.165522 -111.826803) (xy 161.109788 -111.824766) (xy 161.054945 -111.814636) (xy 161.002161 -111.796629)
			(xy 160.952561 -111.771128) (xy 160.907203 -111.738677) (xy 160.867054 -111.699968) (xy 160.832968 -111.655825)
			(xy 160.805672 -111.60719) (xy 160.785749 -111.555099) (xy 160.773623 -111.500662) (xy 160.769552 -111.44504)
			(xy 154.772298 -111.44504) (xy 154.771759 -111.445662) (xy 154.730561 -111.48136) (xy 154.684702 -111.510831)
			(xy 154.635115 -111.533476) (xy 154.58281 -111.548834) (xy 154.528852 -111.556591) (xy 154.501596 -111.557054)
			(xy 154.475688 -111.556587) (xy 154.424351 -111.549562) (xy 154.374437 -111.535656) (xy 154.326863 -111.515124)
			(xy 154.282505 -111.488343) (xy 154.242178 -111.455808) (xy 154.206624 -111.418115) (xy 154.191208 -111.397288)
			(xy 154.185386 -111.389955) (xy 154.169767 -111.37966) (xy 154.160728 -111.377222) (xy 154.130756 -111.370364)
			(xy 154.121456 -111.368703) (xy 154.102797 -111.37156) (xy 154.094434 -111.375952) (xy 154.068449 -111.390211)
			(xy 154.013582 -111.412633) (xy 153.95628 -111.427791) (xy 153.897502 -111.435431) (xy 153.867866 -111.435896)
			(xy 153.838189 -111.435425) (xy 153.779332 -111.427752) (xy 153.721964 -111.412528) (xy 153.667048 -111.390007)
			(xy 153.641044 -111.375698) (xy 153.632666 -111.371352) (xy 153.614023 -111.3685) (xy 153.604722 -111.37011)
			(xy 153.57475 -111.376968) (xy 153.565659 -111.379289) (xy 153.55 -111.389603) (xy 153.54427 -111.397034)
			(xy 153.528847 -111.417891) (xy 153.493286 -111.455655) (xy 153.452937 -111.488254) (xy 153.408544 -111.515086)
			(xy 153.360925 -111.535656) (xy 153.310957 -111.549585) (xy 153.259564 -111.556617) (xy 153.233628 -111.557054)
			(xy 153.206377 -111.556501) (xy 153.15243 -111.548748) (xy 153.100135 -111.533396) (xy 153.050557 -111.510758)
			(xy 153.004706 -111.481294) (xy 152.963515 -111.445605) (xy 152.927823 -111.404416) (xy 152.898355 -111.358568)
			(xy 152.875714 -111.308991) (xy 152.860358 -111.256698) (xy 152.852601 -111.202751) (xy 152.852601 -111.148249)
			(xy 152.860358 -111.094302) (xy 152.875714 -111.042008) (xy 152.898355 -110.992432) (xy 152.927823 -110.946584)
			(xy 152.963515 -110.905395) (xy 153.004706 -110.869706) (xy 153.050557 -110.840242) (xy 153.100135 -110.817604)
			(xy 153.15243 -110.802252) (xy 153.206377 -110.794499) (xy 153.233628 -110.794038) (xy 153.234136 -110.794038)
			(xy 153.248865 -110.794186) (xy 153.278235 -110.796474) (xy 153.29281 -110.79861) (xy 153.303785 -110.799731)
			(xy 153.324976 -110.793673) (xy 153.333704 -110.786926) (xy 153.392124 -110.736888) (xy 153.400154 -110.729323)
			(xy 153.409368 -110.7093) (xy 153.409904 -110.69828) (xy 153.409904 -110.393988) (xy 153.409372 -110.382968)
			(xy 153.400148 -110.362952) (xy 153.392124 -110.35538) (xy 153.325068 -110.297976) (xy 153.303986 -110.29188)
			(xy 153.29281 -110.293658) (xy 153.278234 -110.295786) (xy 153.248865 -110.298077) (xy 153.234136 -110.29823)
			(xy 153.233628 -110.29823) (xy 153.206375 -110.297725) (xy 153.152425 -110.289971) (xy 153.100126 -110.274619)
			(xy 153.050546 -110.251979) (xy 153.004692 -110.222513) (xy 152.963498 -110.186822) (xy 152.927803 -110.145631)
			(xy 152.898334 -110.099779) (xy 152.875691 -110.0502) (xy 152.860335 -109.997903) (xy 152.852577 -109.943953)
			(xy 124.443057 -109.943953) (xy 124.398579 -109.955581) (xy 124.343142 -109.961681) (xy 124.287408 -109.959644)
			(xy 124.232565 -109.949514) (xy 124.179781 -109.931507) (xy 124.130181 -109.906006) (xy 124.084823 -109.873555)
			(xy 124.044674 -109.834846) (xy 124.010588 -109.790703) (xy 123.983292 -109.742068) (xy 123.963369 -109.689977)
			(xy 123.951243 -109.63554) (xy 123.947172 -109.579918) (xy 122.65685 -109.579918) (xy 122.670069 -109.623856)
			(xy 122.678189 -109.679032) (xy 122.678698 -109.706918) (xy 122.678189 -109.734804) (xy 122.670069 -109.78998)
			(xy 122.654001 -109.843387) (xy 122.630329 -109.893884) (xy 122.599556 -109.940397) (xy 122.562339 -109.981934)
			(xy 122.519471 -110.017609) (xy 122.471865 -110.046663) (xy 122.420536 -110.068475) (xy 122.366579 -110.082581)
			(xy 122.311142 -110.088681) (xy 122.255408 -110.086644) (xy 122.200565 -110.076514) (xy 122.147781 -110.058507)
			(xy 122.098181 -110.033006) (xy 122.052823 -110.000555) (xy 122.012674 -109.961846) (xy 121.978588 -109.917703)
			(xy 121.951292 -109.869068) (xy 121.931369 -109.816977) (xy 121.919243 -109.76254) (xy 121.915172 -109.706918)
			(xy 110.118894 -109.706918) (xy 110.118144 -109.708188) (xy 110.117128 -109.734096) (xy 110.161832 -109.822234)
			(xy 110.165963 -109.829712) (xy 110.178262 -109.841559) (xy 110.193755 -109.84874) (xy 110.202218 -109.84992)
			(xy 110.202472 -109.84992) (xy 110.230448 -109.853053) (xy 110.285083 -109.866627) (xy 110.33713 -109.888083)
			(xy 110.385459 -109.916954) (xy 110.429021 -109.952614) (xy 110.466869 -109.994288) (xy 110.498182 -110.041072)
			(xy 110.522279 -110.09195) (xy 110.538639 -110.145816) (xy 110.546904 -110.201502) (xy 110.547404 -110.22965)
			(xy 110.546865 -110.257812) (xy 110.53859 -110.313524) (xy 110.522213 -110.367413) (xy 110.498091 -110.418309)
			(xy 110.466747 -110.465105) (xy 110.428862 -110.506783) (xy 110.418014 -110.515654) (xy 110.828072 -110.515654)
			(xy 110.832143 -110.460032) (xy 110.844269 -110.405595) (xy 110.864192 -110.353504) (xy 110.891488 -110.304869)
			(xy 110.925574 -110.260726) (xy 110.965723 -110.222017) (xy 111.011081 -110.189566) (xy 111.060681 -110.164065)
			(xy 111.113465 -110.146058) (xy 111.168308 -110.135928) (xy 111.224042 -110.133891) (xy 111.279479 -110.139991)
			(xy 111.333436 -110.154097) (xy 111.384765 -110.175909) (xy 111.432371 -110.204963) (xy 111.475239 -110.240638)
			(xy 111.512456 -110.282175) (xy 111.543229 -110.328688) (xy 111.560266 -110.365032) (xy 129.880612 -110.365032)
			(xy 129.884683 -110.30941) (xy 129.896809 -110.254973) (xy 129.916732 -110.202882) (xy 129.944028 -110.154247)
			(xy 129.978114 -110.110104) (xy 130.018263 -110.071395) (xy 130.063621 -110.038944) (xy 130.113221 -110.013443)
			(xy 130.166005 -109.995436) (xy 130.220848 -109.985306) (xy 130.276582 -109.983269) (xy 130.332019 -109.989369)
			(xy 130.385976 -110.003475) (xy 130.437305 -110.025287) (xy 130.484911 -110.054341) (xy 130.527779 -110.090016)
			(xy 130.564996 -110.131553) (xy 130.595769 -110.178066) (xy 130.619441 -110.228563) (xy 130.635509 -110.28197)
			(xy 130.643629 -110.337146) (xy 130.644138 -110.365032) (xy 130.896612 -110.365032) (xy 130.900683 -110.30941)
			(xy 130.912809 -110.254973) (xy 130.932732 -110.202882) (xy 130.960028 -110.154247) (xy 130.994114 -110.110104)
			(xy 131.034263 -110.071395) (xy 131.079621 -110.038944) (xy 131.129221 -110.013443) (xy 131.182005 -109.995436)
			(xy 131.236848 -109.985306) (xy 131.292582 -109.983269) (xy 131.348019 -109.989369) (xy 131.401976 -110.003475)
			(xy 131.453305 -110.025287) (xy 131.500911 -110.054341) (xy 131.543779 -110.090016) (xy 131.580996 -110.131553)
			(xy 131.611769 -110.178066) (xy 131.635441 -110.228563) (xy 131.651509 -110.28197) (xy 131.659629 -110.337146)
			(xy 131.660138 -110.365032) (xy 131.912612 -110.365032) (xy 131.916683 -110.30941) (xy 131.928809 -110.254973)
			(xy 131.948732 -110.202882) (xy 131.976028 -110.154247) (xy 132.010114 -110.110104) (xy 132.050263 -110.071395)
			(xy 132.095621 -110.038944) (xy 132.145221 -110.013443) (xy 132.198005 -109.995436) (xy 132.252848 -109.985306)
			(xy 132.308582 -109.983269) (xy 132.364019 -109.989369) (xy 132.417976 -110.003475) (xy 132.469305 -110.025287)
			(xy 132.516911 -110.054341) (xy 132.559779 -110.090016) (xy 132.596996 -110.131553) (xy 132.627769 -110.178066)
			(xy 132.651441 -110.228563) (xy 132.667509 -110.28197) (xy 132.675629 -110.337146) (xy 132.676138 -110.365032)
			(xy 132.675629 -110.392918) (xy 132.667509 -110.448094) (xy 132.651441 -110.501501) (xy 132.627769 -110.551998)
			(xy 132.596996 -110.598511) (xy 132.559779 -110.640048) (xy 132.516911 -110.675723) (xy 132.469305 -110.704777)
			(xy 132.417976 -110.726589) (xy 132.364019 -110.740695) (xy 132.308582 -110.746795) (xy 132.252848 -110.744758)
			(xy 132.198005 -110.734628) (xy 132.145221 -110.716621) (xy 132.095621 -110.69112) (xy 132.050263 -110.658669)
			(xy 132.010114 -110.61996) (xy 131.976028 -110.575817) (xy 131.948732 -110.527182) (xy 131.928809 -110.475091)
			(xy 131.916683 -110.420654) (xy 131.912612 -110.365032) (xy 131.660138 -110.365032) (xy 131.659629 -110.392918)
			(xy 131.651509 -110.448094) (xy 131.635441 -110.501501) (xy 131.611769 -110.551998) (xy 131.580996 -110.598511)
			(xy 131.543779 -110.640048) (xy 131.500911 -110.675723) (xy 131.453305 -110.704777) (xy 131.401976 -110.726589)
			(xy 131.348019 -110.740695) (xy 131.292582 -110.746795) (xy 131.236848 -110.744758) (xy 131.182005 -110.734628)
			(xy 131.129221 -110.716621) (xy 131.079621 -110.69112) (xy 131.034263 -110.658669) (xy 130.994114 -110.61996)
			(xy 130.960028 -110.575817) (xy 130.932732 -110.527182) (xy 130.912809 -110.475091) (xy 130.900683 -110.420654)
			(xy 130.896612 -110.365032) (xy 130.644138 -110.365032) (xy 130.643629 -110.392918) (xy 130.635509 -110.448094)
			(xy 130.619441 -110.501501) (xy 130.595769 -110.551998) (xy 130.564996 -110.598511) (xy 130.527779 -110.640048)
			(xy 130.484911 -110.675723) (xy 130.437305 -110.704777) (xy 130.385976 -110.726589) (xy 130.332019 -110.740695)
			(xy 130.276582 -110.746795) (xy 130.220848 -110.744758) (xy 130.166005 -110.734628) (xy 130.113221 -110.716621)
			(xy 130.063621 -110.69112) (xy 130.018263 -110.658669) (xy 129.978114 -110.61996) (xy 129.944028 -110.575817)
			(xy 129.916732 -110.527182) (xy 129.896809 -110.475091) (xy 129.884683 -110.420654) (xy 129.880612 -110.365032)
			(xy 111.560266 -110.365032) (xy 111.566901 -110.379185) (xy 111.582969 -110.432592) (xy 111.591089 -110.487768)
			(xy 111.591598 -110.515654) (xy 111.591089 -110.54354) (xy 111.582969 -110.598716) (xy 111.566901 -110.652123)
			(xy 111.543229 -110.70262) (xy 111.512456 -110.749133) (xy 111.475239 -110.79067) (xy 111.432371 -110.826345)
			(xy 111.384765 -110.855399) (xy 111.333436 -110.877211) (xy 111.279479 -110.891317) (xy 111.224042 -110.897417)
			(xy 111.168308 -110.89538) (xy 111.113465 -110.88525) (xy 111.060681 -110.867243) (xy 111.011081 -110.841742)
			(xy 110.965723 -110.809291) (xy 110.925574 -110.770582) (xy 110.891488 -110.726439) (xy 110.864192 -110.677804)
			(xy 110.844269 -110.625713) (xy 110.832143 -110.571276) (xy 110.828072 -110.515654) (xy 110.418014 -110.515654)
			(xy 110.385261 -110.542438) (xy 110.336892 -110.571293) (xy 110.284805 -110.592723) (xy 110.25759 -110.599982)
			(xy 110.248331 -110.602693) (xy 110.232669 -110.613939) (xy 110.22711 -110.621826) (xy 110.18393 -110.688374)
			(xy 110.18012 -110.706916) (xy 110.181898 -110.716822) (xy 110.184849 -110.733878) (xy 110.188029 -110.768348)
			(xy 110.188248 -110.785656) (xy 110.187762 -110.812907) (xy 110.180006 -110.866855) (xy 110.164651 -110.91915)
			(xy 110.142009 -110.968727) (xy 110.112543 -111.014577) (xy 110.076852 -111.055768) (xy 110.035661 -111.091459)
			(xy 109.989811 -111.120925) (xy 109.940234 -111.143567) (xy 109.887939 -111.158922) (xy 109.833991 -111.166678)
			(xy 109.779489 -111.166678) (xy 109.725541 -111.158922) (xy 109.673246 -111.143567) (xy 109.623669 -111.120925)
			(xy 109.577819 -111.091459) (xy 109.536628 -111.055768) (xy 109.500937 -111.014577) (xy 109.471471 -110.968727)
			(xy 109.448829 -110.91915) (xy 109.433474 -110.866855) (xy 109.425718 -110.812907) (xy 109.425232 -110.785656)
			(xy 109.42575 -110.757493) (xy 109.434024 -110.701779) (xy 109.450402 -110.647887) (xy 109.474526 -110.59699)
			(xy 109.505873 -110.550193) (xy 109.543761 -110.508515) (xy 109.587365 -110.472861) (xy 109.635739 -110.444007)
			(xy 109.68783 -110.422581) (xy 109.715046 -110.415324) (xy 109.724295 -110.412585) (xy 109.739962 -110.401359)
			(xy 109.745526 -110.39348) (xy 109.788706 -110.326932) (xy 109.792516 -110.30839) (xy 109.790738 -110.298484)
			(xy 109.787789 -110.281428) (xy 109.784607 -110.246958) (xy 109.784388 -110.22965) (xy 109.784818 -110.204119)
			(xy 109.791623 -110.153511) (xy 109.805118 -110.104264) (xy 109.825062 -110.057258) (xy 109.837728 -110.035086)
			(xy 109.844332 -110.02391) (xy 109.845348 -109.998002) (xy 109.800644 -109.909864) (xy 109.796528 -109.902376)
			(xy 109.784222 -109.890531) (xy 109.768723 -109.883354) (xy 109.760258 -109.882178) (xy 109.760004 -109.882178)
			(xy 109.732035 -109.878984) (xy 109.677401 -109.86542) (xy 109.625354 -109.843974) (xy 109.577024 -109.815112)
			(xy 109.533461 -109.779459) (xy 109.495611 -109.737791) (xy 109.464297 -109.691012) (xy 109.440198 -109.640139)
			(xy 109.423838 -109.586277) (xy 109.415572 -109.530594) (xy 109.415072 -109.502448) (xy 75.338473 -109.502448)
			(xy 75.324478 -109.531293) (xy 75.291915 -109.578656) (xy 75.272646 -109.599984) (xy 75.266042 -109.606842)
			(xy 75.25893 -109.624876) (xy 75.25893 -109.713776) (xy 75.266042 -109.73181) (xy 75.272646 -109.738668)
			(xy 75.291944 -109.759972) (xy 75.324511 -109.807337) (xy 75.349603 -109.859053) (xy 75.366653 -109.913947)
			(xy 75.375273 -109.970778) (xy 75.375271 -110.02826) (xy 75.366644 -110.08509) (xy 75.349589 -110.139983)
			(xy 75.324492 -110.191696) (xy 75.29192 -110.239058) (xy 75.272646 -110.260384) (xy 75.266042 -110.267242)
			(xy 75.25893 -110.285276) (xy 75.25893 -110.374176) (xy 75.266042 -110.39221) (xy 75.272646 -110.399068)
			(xy 75.291944 -110.420372) (xy 75.324511 -110.467737) (xy 75.349603 -110.519453) (xy 75.366653 -110.574347)
			(xy 75.373816 -110.621572) (xy 90.56116 -110.621572) (xy 90.56159 -110.595257) (xy 90.568829 -110.543126)
			(xy 90.583155 -110.492481) (xy 90.604294 -110.444282) (xy 90.631848 -110.39944) (xy 90.665294 -110.358803)
			(xy 90.68435 -110.340648) (xy 90.691769 -110.333141) (xy 90.700285 -110.31385) (xy 90.70086 -110.30331)
			(xy 90.70086 -110.228634) (xy 90.700338 -110.218083) (xy 90.691799 -110.198787) (xy 90.68435 -110.191296)
			(xy 90.66529 -110.173145) (xy 90.631835 -110.132513) (xy 90.604278 -110.087672) (xy 90.583141 -110.03947)
			(xy 90.568824 -109.988822) (xy 90.561599 -109.936688) (xy 90.56116 -109.910372) (xy 90.561646 -109.883121)
			(xy 90.569402 -109.829173) (xy 90.584757 -109.776878) (xy 90.607399 -109.727301) (xy 90.636865 -109.681451)
			(xy 90.672556 -109.64026) (xy 90.713747 -109.604569) (xy 90.759597 -109.575103) (xy 90.809174 -109.552461)
			(xy 90.861469 -109.537106) (xy 90.915417 -109.52935) (xy 90.969919 -109.52935) (xy 91.023867 -109.537106)
			(xy 91.076162 -109.552461) (xy 91.125739 -109.575103) (xy 91.171589 -109.604569) (xy 91.21278 -109.64026)
			(xy 91.248471 -109.681451) (xy 91.277937 -109.727301) (xy 91.300579 -109.776878) (xy 91.315934 -109.829173)
			(xy 91.32369 -109.883121) (xy 91.324176 -109.910372) (xy 91.323764 -109.936688) (xy 91.316519 -109.988819)
			(xy 91.30219 -110.039463) (xy 91.281047 -110.087662) (xy 91.253491 -110.132504) (xy 91.220042 -110.173141)
			(xy 91.200986 -110.191296) (xy 91.193582 -110.198815) (xy 91.185059 -110.218097) (xy 91.184476 -110.228634)
			(xy 91.184476 -110.30331) (xy 91.184993 -110.313861) (xy 91.193538 -110.333156) (xy 91.200986 -110.340648)
			(xy 91.220055 -110.35879) (xy 91.253512 -110.399422) (xy 91.281069 -110.444265) (xy 91.302205 -110.492469)
			(xy 91.316519 -110.543119) (xy 91.32374 -110.595255) (xy 91.324176 -110.621572) (xy 91.32369 -110.648823)
			(xy 91.315934 -110.702771) (xy 91.300579 -110.755066) (xy 91.277937 -110.804643) (xy 91.248471 -110.850493)
			(xy 91.21278 -110.891684) (xy 91.171589 -110.927375) (xy 91.125739 -110.956841) (xy 91.076162 -110.979483)
			(xy 91.023867 -110.994838) (xy 90.969919 -111.002594) (xy 90.915417 -111.002594) (xy 90.861469 -110.994838)
			(xy 90.809174 -110.979483) (xy 90.759597 -110.956841) (xy 90.713747 -110.927375) (xy 90.672556 -110.891684)
			(xy 90.636865 -110.850493) (xy 90.607399 -110.804643) (xy 90.584757 -110.755066) (xy 90.569402 -110.702771)
			(xy 90.561646 -110.648823) (xy 90.56116 -110.621572) (xy 75.373816 -110.621572) (xy 75.375273 -110.631178)
			(xy 75.375271 -110.68866) (xy 75.366644 -110.74549) (xy 75.349589 -110.800383) (xy 75.324492 -110.852096)
			(xy 75.29192 -110.899458) (xy 75.272646 -110.920784) (xy 75.266042 -110.927642) (xy 75.25893 -110.945676)
			(xy 75.25893 -111.034576) (xy 75.266042 -111.05261) (xy 75.272646 -111.059468) (xy 75.291944 -111.080772)
			(xy 75.324511 -111.128137) (xy 75.349603 -111.179853) (xy 75.366653 -111.234747) (xy 75.375273 -111.291578)
			(xy 75.375271 -111.34906) (xy 75.366644 -111.40589) (xy 75.349589 -111.460783) (xy 75.324492 -111.512496)
			(xy 75.29192 -111.559858) (xy 75.272646 -111.581184) (xy 75.266042 -111.588042) (xy 75.25893 -111.606076)
			(xy 75.25893 -111.694976) (xy 75.266042 -111.71301) (xy 75.272646 -111.719868) (xy 75.291926 -111.741187)
			(xy 75.324492 -111.788551) (xy 75.349583 -111.840264) (xy 75.366631 -111.895157) (xy 75.375251 -111.951986)
			(xy 75.37577 -111.980726) (xy 75.375369 -112.007981) (xy 75.367608 -112.061936) (xy 75.352246 -112.114238)
			(xy 75.329598 -112.163821) (xy 75.300124 -112.209676) (xy 75.264424 -112.250869) (xy 75.223224 -112.286562)
			(xy 75.177364 -112.316029) (xy 75.127778 -112.338669) (xy 75.075474 -112.354021) (xy 75.021517 -112.361774)
			(xy 74.994262 -112.362234) (xy 74.967948 -112.361781) (xy 74.915819 -112.354542) (xy 74.865176 -112.340219)
			(xy 74.816978 -112.319084) (xy 74.772135 -112.291536) (xy 74.731495 -112.258096) (xy 74.713338 -112.239044)
			(xy 74.705798 -112.231664) (xy 74.686532 -112.223126) (xy 74.676 -112.222534) (xy 74.601324 -112.222534)
			(xy 74.590773 -112.223052) (xy 74.571477 -112.231594) (xy 74.563986 -112.239044) (xy 74.545839 -112.258108)
			(xy 74.505206 -112.291562) (xy 74.460364 -112.319119) (xy 74.412162 -112.340256) (xy 74.361513 -112.354572)
			(xy 74.309378 -112.361796) (xy 74.283062 -112.362234) (xy 74.255811 -112.361758) (xy 74.201864 -112.353997)
			(xy 74.149571 -112.338638) (xy 74.099995 -112.315994) (xy 74.054146 -112.286526) (xy 74.012957 -112.250834)
			(xy 73.977266 -112.209644) (xy 73.9478 -112.163794) (xy 73.925158 -112.114218) (xy 73.909801 -112.061924)
			(xy 73.902042 -112.007977) (xy 73.901554 -111.980726) (xy 72.483658 -111.980726) (xy 72.471585 -111.997485)
			(xy 72.429661 -112.039826) (xy 72.406002 -112.057942) (xy 72.399232 -112.063312) (xy 72.389496 -112.077574)
			(xy 72.385073 -112.094266) (xy 72.385428 -112.1029) (xy 72.392032 -112.188752) (xy 72.392966 -112.197263)
			(xy 72.399735 -112.212977) (xy 72.411313 -112.225575) (xy 72.418702 -112.2299) (xy 72.418956 -112.2299)
			(xy 72.441759 -112.242299) (xy 72.484054 -112.27239) (xy 72.521876 -112.30794) (xy 72.554525 -112.348292)
			(xy 72.5814 -112.3927) (xy 72.584372 -112.399572) (xy 90.56116 -112.399572) (xy 90.56159 -112.373257)
			(xy 90.568829 -112.321126) (xy 90.583155 -112.270481) (xy 90.604294 -112.222282) (xy 90.631848 -112.17744)
			(xy 90.665294 -112.136803) (xy 90.68435 -112.118648) (xy 90.691769 -112.111141) (xy 90.700285 -112.09185)
			(xy 90.70086 -112.08131) (xy 90.70086 -112.006634) (xy 90.700338 -111.996083) (xy 90.691799 -111.976787)
			(xy 90.68435 -111.969296) (xy 90.66529 -111.951145) (xy 90.631835 -111.910513) (xy 90.604278 -111.865672)
			(xy 90.583141 -111.81747) (xy 90.568824 -111.766822) (xy 90.561599 -111.714688) (xy 90.56116 -111.688372)
			(xy 90.561646 -111.661121) (xy 90.569402 -111.607173) (xy 90.584757 -111.554878) (xy 90.607399 -111.505301)
			(xy 90.636865 -111.459451) (xy 90.672556 -111.41826) (xy 90.713747 -111.382569) (xy 90.759597 -111.353103)
			(xy 90.809174 -111.330461) (xy 90.861469 -111.315106) (xy 90.915417 -111.30735) (xy 90.969919 -111.30735)
			(xy 91.023867 -111.315106) (xy 91.076162 -111.330461) (xy 91.125739 -111.353103) (xy 91.171589 -111.382569)
			(xy 91.21278 -111.41826) (xy 91.248471 -111.459451) (xy 91.277937 -111.505301) (xy 91.300579 -111.554878)
			(xy 91.315934 -111.607173) (xy 91.32369 -111.661121) (xy 91.324176 -111.688372) (xy 91.323764 -111.714688)
			(xy 91.316519 -111.766819) (xy 91.30219 -111.817463) (xy 91.281047 -111.865662) (xy 91.253491 -111.910504)
			(xy 91.220042 -111.951141) (xy 91.200986 -111.969296) (xy 91.193582 -111.976815) (xy 91.185059 -111.996097)
			(xy 91.184476 -112.006634) (xy 91.184476 -112.08131) (xy 91.184993 -112.091861) (xy 91.193538 -112.111156)
			(xy 91.200986 -112.118648) (xy 91.220055 -112.13679) (xy 91.253512 -112.177422) (xy 91.281069 -112.222265)
			(xy 91.302205 -112.270469) (xy 91.309978 -112.297972) (xy 93.069918 -112.297972) (xy 93.070361 -112.271657)
			(xy 93.0776 -112.219527) (xy 93.091924 -112.168884) (xy 93.113061 -112.120685) (xy 93.140611 -112.075842)
			(xy 93.174054 -112.035204) (xy 93.193108 -112.017048) (xy 93.200536 -112.009549) (xy 93.209045 -111.990252)
			(xy 93.209618 -111.97971) (xy 93.209618 -111.905034) (xy 93.209079 -111.894486) (xy 93.20055 -111.875191)
			(xy 93.193108 -111.867696) (xy 93.174059 -111.849534) (xy 93.140601 -111.808906) (xy 93.113041 -111.764067)
			(xy 93.091901 -111.715867) (xy 93.077583 -111.665221) (xy 93.070357 -111.613088) (xy 93.069918 -111.586772)
			(xy 93.070404 -111.559521) (xy 93.07816 -111.505573) (xy 93.093515 -111.453278) (xy 93.116157 -111.403701)
			(xy 93.145623 -111.357851) (xy 93.181314 -111.31666) (xy 93.222505 -111.280969) (xy 93.268355 -111.251503)
			(xy 93.317932 -111.228861) (xy 93.370227 -111.213506) (xy 93.424175 -111.20575) (xy 93.478677 -111.20575)
			(xy 93.532625 -111.213506) (xy 93.58492 -111.228861) (xy 93.634497 -111.251503) (xy 93.680347 -111.280969)
			(xy 93.721538 -111.31666) (xy 93.757229 -111.357851) (xy 93.786695 -111.403701) (xy 93.809337 -111.453278)
			(xy 93.824692 -111.505573) (xy 93.832448 -111.559521) (xy 93.832934 -111.586772) (xy 93.832504 -111.613087)
			(xy 93.82526 -111.665217) (xy 93.810933 -111.71586) (xy 93.789793 -111.764058) (xy 93.762241 -111.808901)
			(xy 93.728798 -111.84954) (xy 93.709744 -111.867696) (xy 93.702349 -111.875223) (xy 93.693819 -111.894499)
			(xy 93.693234 -111.905034) (xy 93.693234 -111.97971) (xy 93.693734 -111.990263) (xy 93.702289 -112.009559)
			(xy 93.709744 -112.017048) (xy 93.728824 -112.035179) (xy 93.762277 -112.075815) (xy 93.789832 -112.12066)
			(xy 93.810966 -112.168866) (xy 93.825278 -112.219517) (xy 93.832498 -112.271655) (xy 93.832934 -112.297972)
			(xy 95.101918 -112.297972) (xy 95.102361 -112.271657) (xy 95.1096 -112.219527) (xy 95.123924 -112.168884)
			(xy 95.145061 -112.120685) (xy 95.172611 -112.075842) (xy 95.206054 -112.035204) (xy 95.225108 -112.017048)
			(xy 95.232536 -112.009549) (xy 95.241045 -111.990252) (xy 95.241618 -111.97971) (xy 95.241618 -111.905034)
			(xy 95.241079 -111.894486) (xy 95.23255 -111.875191) (xy 95.225108 -111.867696) (xy 95.206059 -111.849534)
			(xy 95.172601 -111.808906) (xy 95.145041 -111.764067) (xy 95.123901 -111.715867) (xy 95.109583 -111.665221)
			(xy 95.102357 -111.613088) (xy 95.101918 -111.586772) (xy 95.102404 -111.559521) (xy 95.11016 -111.505573)
			(xy 95.125515 -111.453278) (xy 95.148157 -111.403701) (xy 95.177623 -111.357851) (xy 95.213314 -111.31666)
			(xy 95.254505 -111.280969) (xy 95.300355 -111.251503) (xy 95.349932 -111.228861) (xy 95.402227 -111.213506)
			(xy 95.456175 -111.20575) (xy 95.510677 -111.20575) (xy 95.564625 -111.213506) (xy 95.61692 -111.228861)
			(xy 95.666497 -111.251503) (xy 95.712347 -111.280969) (xy 95.753538 -111.31666) (xy 95.789229 -111.357851)
			(xy 95.818695 -111.403701) (xy 95.841337 -111.453278) (xy 95.856692 -111.505573) (xy 95.864448 -111.559521)
			(xy 95.864934 -111.586772) (xy 95.864504 -111.613087) (xy 95.85726 -111.665217) (xy 95.842933 -111.71586)
			(xy 95.821793 -111.764058) (xy 95.794241 -111.808901) (xy 95.760798 -111.84954) (xy 95.741744 -111.867696)
			(xy 95.734349 -111.875223) (xy 95.725819 -111.894499) (xy 95.725234 -111.905034) (xy 95.725234 -111.97971)
			(xy 95.725734 -111.990263) (xy 95.734289 -112.009559) (xy 95.741744 -112.017048) (xy 95.760824 -112.035179)
			(xy 95.762829 -112.037615) (xy 97.556142 -112.037615) (xy 97.560456 -111.980343) (xy 97.573304 -111.924365)
			(xy 97.594396 -111.870944) (xy 97.623255 -111.821288) (xy 97.65923 -111.776517) (xy 97.680018 -111.756698)
			(xy 97.687425 -111.749182) (xy 97.695946 -111.729897) (xy 97.696528 -111.71936) (xy 97.696528 -111.644684)
			(xy 97.696013 -111.634133) (xy 97.687467 -111.614838) (xy 97.680018 -111.607346) (xy 97.660947 -111.589206)
			(xy 97.62749 -111.548573) (xy 97.599933 -111.50373) (xy 97.578797 -111.455526) (xy 97.564484 -111.404876)
			(xy 97.557264 -111.352739) (xy 97.556828 -111.326422) (xy 97.557314 -111.299171) (xy 97.56507 -111.245223)
			(xy 97.580425 -111.192928) (xy 97.603067 -111.143351) (xy 97.632533 -111.097501) (xy 97.668224 -111.05631)
			(xy 97.709415 -111.020619) (xy 97.755265 -110.991153) (xy 97.804842 -110.968511) (xy 97.857137 -110.953156)
			(xy 97.911085 -110.9454) (xy 97.965587 -110.9454) (xy 98.019535 -110.953156) (xy 98.07183 -110.968511)
			(xy 98.121407 -110.991153) (xy 98.167257 -111.020619) (xy 98.208448 -111.05631) (xy 98.244139 -111.097501)
			(xy 98.273605 -111.143351) (xy 98.296247 -111.192928) (xy 98.311602 -111.245223) (xy 98.319358 -111.299171)
			(xy 98.319844 -111.326422) (xy 98.319409 -111.352737) (xy 98.31217 -111.404868) (xy 98.297846 -111.455512)
			(xy 98.276707 -111.503711) (xy 98.249155 -111.548554) (xy 98.215709 -111.589191) (xy 98.196654 -111.607346)
			(xy 98.189238 -111.614856) (xy 98.18072 -111.634144) (xy 98.180144 -111.644684) (xy 98.180144 -111.71936)
			(xy 98.180668 -111.729911) (xy 98.189206 -111.749207) (xy 98.196654 -111.756698) (xy 98.217462 -111.776497)
			(xy 98.253434 -111.821274) (xy 98.28229 -111.870935) (xy 98.303379 -111.924359) (xy 98.316226 -111.980341)
			(xy 98.320539 -112.037615) (xy 100.09439 -112.037615) (xy 100.098702 -111.980346) (xy 100.111547 -111.924369)
			(xy 100.132634 -111.87095) (xy 100.161488 -111.821292) (xy 100.197456 -111.776519) (xy 100.21824 -111.756698)
			(xy 100.225636 -111.749171) (xy 100.234165 -111.729895) (xy 100.23475 -111.71936) (xy 100.23475 -111.644684)
			(xy 100.234228 -111.634134) (xy 100.225686 -111.614839) (xy 100.21824 -111.607346) (xy 100.199154 -111.589222)
			(xy 100.165702 -111.548584) (xy 100.138148 -111.503737) (xy 100.117016 -111.45553) (xy 100.102704 -111.404878)
			(xy 100.095486 -111.35274) (xy 100.09505 -111.326422) (xy 100.095536 -111.299171) (xy 100.103292 -111.245223)
			(xy 100.118647 -111.192928) (xy 100.141289 -111.143351) (xy 100.170755 -111.097501) (xy 100.206446 -111.05631)
			(xy 100.247637 -111.020619) (xy 100.293487 -110.991153) (xy 100.343064 -110.968511) (xy 100.395359 -110.953156)
			(xy 100.449307 -110.9454) (xy 100.503809 -110.9454) (xy 100.557757 -110.953156) (xy 100.610052 -110.968511)
			(xy 100.659629 -110.991153) (xy 100.705479 -111.020619) (xy 100.74667 -111.05631) (xy 100.782361 -111.097501)
			(xy 100.811827 -111.143351) (xy 100.834469 -111.192928) (xy 100.849824 -111.245223) (xy 100.85758 -111.299171)
			(xy 100.858066 -111.326422) (xy 100.857624 -111.352737) (xy 100.850386 -111.404867) (xy 100.836062 -111.455511)
			(xy 100.814925 -111.50371) (xy 100.787374 -111.548553) (xy 100.75393 -111.589191) (xy 100.734876 -111.607346)
			(xy 100.727463 -111.614859) (xy 100.718942 -111.634145) (xy 100.718366 -111.644684) (xy 100.718366 -111.71936)
			(xy 100.718913 -111.729907) (xy 100.727437 -111.749202) (xy 100.734876 -111.756698) (xy 100.755688 -111.776495)
			(xy 100.791667 -111.821269) (xy 100.820529 -111.87093) (xy 100.841623 -111.924355) (xy 100.854472 -111.980338)
			(xy 100.855495 -111.993923) (xy 104.297324 -111.993923) (xy 104.301636 -111.936654) (xy 104.314481 -111.880678)
			(xy 104.335569 -111.827258) (xy 104.364423 -111.777602) (xy 104.400393 -111.73283) (xy 104.421178 -111.71301)
			(xy 104.428574 -111.705484) (xy 104.437102 -111.686207) (xy 104.437688 -111.675672) (xy 104.437688 -111.600996)
			(xy 104.437178 -111.590444) (xy 104.42863 -111.571149) (xy 104.421178 -111.563658) (xy 104.400424 -111.543804)
			(xy 104.364449 -111.499036) (xy 104.335589 -111.449383) (xy 104.314494 -111.395966) (xy 104.301643 -111.339992)
			(xy 104.297324 -111.282723) (xy 104.301636 -111.225454) (xy 104.314481 -111.169478) (xy 104.335569 -111.116058)
			(xy 104.364423 -111.066402) (xy 104.400393 -111.02163) (xy 104.421178 -111.00181) (xy 104.428574 -110.994284)
			(xy 104.437102 -110.975007) (xy 104.437688 -110.964472) (xy 104.437688 -110.889796) (xy 104.437178 -110.879244)
			(xy 104.42863 -110.859949) (xy 104.421178 -110.852458) (xy 104.402105 -110.83432) (xy 104.36865 -110.793686)
			(xy 104.341094 -110.748842) (xy 104.319959 -110.700638) (xy 104.305645 -110.649987) (xy 104.298424 -110.597851)
			(xy 104.297988 -110.571534) (xy 104.298487 -110.544282) (xy 104.306239 -110.490333) (xy 104.321591 -110.438036)
			(xy 104.344229 -110.388456) (xy 104.373693 -110.342603) (xy 104.409383 -110.30141) (xy 104.450572 -110.265716)
			(xy 104.496423 -110.236247) (xy 104.546 -110.213604) (xy 104.598296 -110.198247) (xy 104.652244 -110.19049)
			(xy 104.679496 -110.190026) (xy 104.70581 -110.190488) (xy 104.757939 -110.197723) (xy 104.808583 -110.212042)
			(xy 104.856782 -110.233176) (xy 104.901625 -110.260723) (xy 104.942264 -110.294164) (xy 104.96042 -110.313216)
			(xy 104.96793 -110.320631) (xy 104.987219 -110.329147) (xy 104.997758 -110.329726) (xy 105.072434 -110.329726)
			(xy 105.08298 -110.329167) (xy 105.102275 -110.320652) (xy 105.109772 -110.313216) (xy 105.127951 -110.294184)
			(xy 105.168576 -110.260724) (xy 105.213411 -110.233162) (xy 105.261607 -110.212019) (xy 105.31225 -110.197697)
			(xy 105.364381 -110.190467) (xy 105.390696 -110.190026) (xy 105.41795 -110.190459) (xy 105.471904 -110.198216)
			(xy 105.524205 -110.213574) (xy 105.573787 -110.236218) (xy 105.613417 -110.261688) (xy 106.914421 -110.261688)
			(xy 106.914421 -110.209712) (xy 106.922553 -110.158377) (xy 106.938615 -110.108946) (xy 106.962213 -110.062636)
			(xy 106.992766 -110.020588) (xy 107.02952 -109.983839) (xy 107.071572 -109.953291) (xy 107.117884 -109.929699)
			(xy 107.167318 -109.913643) (xy 107.218654 -109.905518) (xy 107.244642 -109.905038) (xy 107.271287 -109.905526)
			(xy 107.323889 -109.914057) (xy 107.374439 -109.930922) (xy 107.421625 -109.955684) (xy 107.464224 -109.987701)
			(xy 107.50113 -110.026141) (xy 107.516676 -110.047786) (xy 107.52504 -110.059072) (xy 107.546713 -110.076927)
			(xy 107.572427 -110.08821) (xy 107.600242 -110.092068) (xy 107.628057 -110.08821) (xy 107.653771 -110.076927)
			(xy 107.675444 -110.059072) (xy 107.683808 -110.047786) (xy 107.699397 -110.026178) (xy 107.73631 -109.987761)
			(xy 107.778906 -109.95576) (xy 107.826082 -109.931002) (xy 107.876617 -109.914129) (xy 107.929203 -109.905578)
			(xy 107.955842 -109.905038) (xy 107.981831 -109.905459) (xy 108.033167 -109.913596) (xy 108.082599 -109.929663)
			(xy 108.128909 -109.953264) (xy 108.170957 -109.983819) (xy 108.207709 -110.020575) (xy 108.238258 -110.062627)
			(xy 108.261853 -110.10894) (xy 108.277914 -110.158374) (xy 108.286044 -110.209711) (xy 108.286044 -110.261689)
			(xy 108.277914 -110.313026) (xy 108.261853 -110.36246) (xy 108.238258 -110.408773) (xy 108.207709 -110.450825)
			(xy 108.170957 -110.487581) (xy 108.128909 -110.518136) (xy 108.082599 -110.541737) (xy 108.033167 -110.557804)
			(xy 107.981831 -110.565941) (xy 107.955842 -110.566454) (xy 107.929197 -110.565981) (xy 107.876594 -110.557448)
			(xy 107.826043 -110.54058) (xy 107.778857 -110.515815) (xy 107.736259 -110.483795) (xy 107.699354 -110.445352)
			(xy 107.683808 -110.423706) (xy 107.675444 -110.41242) (xy 107.653771 -110.394565) (xy 107.628057 -110.383282)
			(xy 107.600242 -110.379424) (xy 107.572427 -110.383282) (xy 107.546713 -110.394565) (xy 107.52504 -110.41242)
			(xy 107.516676 -110.423706) (xy 107.501095 -110.44532) (xy 107.46418 -110.483737) (xy 107.421583 -110.515738)
			(xy 107.374405 -110.540494) (xy 107.323869 -110.557366) (xy 107.271281 -110.565916) (xy 107.244642 -110.566454)
			(xy 107.218654 -110.565882) (xy 107.167318 -110.557757) (xy 107.117884 -110.541701) (xy 107.071572 -110.518109)
			(xy 107.02952 -110.487561) (xy 106.992766 -110.450812) (xy 106.962213 -110.408764) (xy 106.938615 -110.362454)
			(xy 106.922553 -110.313023) (xy 106.914421 -110.261688) (xy 105.613417 -110.261688) (xy 105.619642 -110.265689)
			(xy 105.660835 -110.301386) (xy 105.696529 -110.342582) (xy 105.725996 -110.388439) (xy 105.748637 -110.438024)
			(xy 105.76399 -110.490325) (xy 105.771743 -110.54428) (xy 105.772204 -110.571534) (xy 105.771758 -110.597849)
			(xy 105.764519 -110.649978) (xy 105.750195 -110.700621) (xy 105.729059 -110.74882) (xy 105.701509 -110.793663)
			(xy 105.668067 -110.834302) (xy 105.649014 -110.852458) (xy 105.641631 -110.859995) (xy 105.633095 -110.879263)
			(xy 105.632504 -110.889796) (xy 105.632504 -110.964472) (xy 105.633034 -110.975022) (xy 105.641568 -110.994317)
			(xy 105.649014 -111.00181) (xy 105.669836 -111.021596) (xy 105.705811 -111.066373) (xy 105.73467 -111.116036)
			(xy 105.752772 -111.16189) (xy 106.914397 -111.16189) (xy 106.914397 -111.10991) (xy 106.922529 -111.058571)
			(xy 106.938593 -111.009136) (xy 106.962193 -110.962823) (xy 106.992748 -110.920773) (xy 107.029505 -110.88402)
			(xy 107.071559 -110.853471) (xy 107.117875 -110.829877) (xy 107.167312 -110.813819) (xy 107.218652 -110.805694)
			(xy 107.244642 -110.805214) (xy 107.271286 -110.805713) (xy 107.323887 -110.814242) (xy 107.374436 -110.831106)
			(xy 107.421622 -110.855866) (xy 107.464222 -110.887881) (xy 107.501129 -110.926319) (xy 107.516676 -110.947962)
			(xy 107.52504 -110.959248) (xy 107.546713 -110.977103) (xy 107.572427 -110.988386) (xy 107.600242 -110.992244)
			(xy 107.628057 -110.988386) (xy 107.653771 -110.977103) (xy 107.675444 -110.959248) (xy 107.683808 -110.947962)
			(xy 107.69939 -110.926349) (xy 107.736306 -110.887933) (xy 107.778903 -110.855933) (xy 107.82608 -110.831177)
			(xy 107.876616 -110.814305) (xy 107.929203 -110.805754) (xy 107.955842 -110.805214) (xy 107.981829 -110.805683)
			(xy 108.033162 -110.813819) (xy 108.08259 -110.829885) (xy 108.128897 -110.853484) (xy 108.170942 -110.884037)
			(xy 108.20769 -110.92079) (xy 108.238238 -110.962839) (xy 108.261831 -111.009149) (xy 108.277891 -111.058579)
			(xy 108.286021 -111.109913) (xy 108.286021 -111.161887) (xy 108.277891 -111.213221) (xy 108.261831 -111.262651)
			(xy 108.238238 -111.308961) (xy 108.20769 -111.35101) (xy 108.170942 -111.387763) (xy 108.128897 -111.418316)
			(xy 108.08259 -111.441915) (xy 108.033162 -111.457981) (xy 107.981829 -111.466117) (xy 107.955842 -111.46663)
			(xy 107.929196 -111.466167) (xy 107.876592 -111.457633) (xy 107.826041 -111.440764) (xy 107.778855 -111.415997)
			(xy 107.736257 -111.383975) (xy 107.699353 -111.345529) (xy 107.683808 -111.323882) (xy 107.675444 -111.312596)
			(xy 107.653771 -111.294741) (xy 107.628057 -111.283458) (xy 107.600242 -111.2796) (xy 107.572427 -111.283458)
			(xy 107.546713 -111.294741) (xy 107.52504 -111.312596) (xy 107.516676 -111.323882) (xy 107.501117 -111.345512)
			(xy 107.464195 -111.383925) (xy 107.421592 -111.415922) (xy 107.374411 -111.440675) (xy 107.323872 -111.457543)
			(xy 107.271282 -111.466092) (xy 107.244642 -111.46663) (xy 107.218652 -111.466106) (xy 107.167312 -111.457981)
			(xy 107.117875 -111.441923) (xy 107.071559 -111.418329) (xy 107.029505 -111.38778) (xy 106.992748 -111.351027)
			(xy 106.962193 -111.308977) (xy 106.938593 -111.262664) (xy 106.922529 -111.213229) (xy 106.914397 -111.16189)
			(xy 105.752772 -111.16189) (xy 105.755761 -111.169462) (xy 105.768608 -111.225446) (xy 105.77292 -111.282723)
			(xy 105.768601 -111.339999) (xy 105.755748 -111.395982) (xy 105.73465 -111.449406) (xy 105.705785 -111.499065)
			(xy 105.669805 -111.543838) (xy 105.649014 -111.563658) (xy 105.641631 -111.571195) (xy 105.633095 -111.590463)
			(xy 105.632504 -111.600996) (xy 105.632504 -111.675672) (xy 105.633034 -111.686222) (xy 105.641568 -111.705517)
			(xy 105.649014 -111.71301) (xy 105.669836 -111.732796) (xy 105.705811 -111.777573) (xy 105.73467 -111.827236)
			(xy 105.755761 -111.880662) (xy 105.768608 -111.936646) (xy 105.77292 -111.993923) (xy 105.768601 -112.051199)
			(xy 105.76617 -112.061788) (xy 106.914419 -112.061788) (xy 106.914419 -112.009812) (xy 106.922551 -111.958476)
			(xy 106.938613 -111.909045) (xy 106.962212 -111.862735) (xy 106.992764 -111.820687) (xy 107.029519 -111.783937)
			(xy 107.071571 -111.75339) (xy 107.117884 -111.729797) (xy 107.167317 -111.713741) (xy 107.218654 -111.705616)
			(xy 107.244642 -111.705136) (xy 107.271287 -111.705625) (xy 107.323888 -111.714156) (xy 107.374438 -111.73102)
			(xy 107.421625 -111.755782) (xy 107.464224 -111.787799) (xy 107.501129 -111.826239) (xy 107.516676 -111.847884)
			(xy 107.52504 -111.85917) (xy 107.546713 -111.877025) (xy 107.572427 -111.888308) (xy 107.600242 -111.892166)
			(xy 107.628057 -111.888308) (xy 107.653771 -111.877025) (xy 107.675444 -111.85917) (xy 107.683808 -111.847884)
			(xy 107.699396 -111.826275) (xy 107.73631 -111.787859) (xy 107.778906 -111.755857) (xy 107.826082 -111.7311)
			(xy 107.876617 -111.714227) (xy 107.929203 -111.705676) (xy 107.955842 -111.705136) (xy 107.98183 -111.705561)
			(xy 108.033167 -111.713698) (xy 108.082598 -111.729765) (xy 108.128908 -111.753366) (xy 108.170956 -111.78392)
			(xy 108.17269 -111.785654) (xy 109.457742 -111.785654) (xy 109.461813 -111.730032) (xy 109.473939 -111.675595)
			(xy 109.493862 -111.623504) (xy 109.521158 -111.574869) (xy 109.555244 -111.530726) (xy 109.595393 -111.492017)
			(xy 109.640751 -111.459566) (xy 109.690351 -111.434065) (xy 109.743135 -111.416058) (xy 109.797978 -111.405928)
			(xy 109.853712 -111.403891) (xy 109.909149 -111.409991) (xy 109.963106 -111.424097) (xy 110.014435 -111.445909)
			(xy 110.062041 -111.474963) (xy 110.104909 -111.510638) (xy 110.142126 -111.552175) (xy 110.172899 -111.598688)
			(xy 110.196571 -111.649185) (xy 110.212639 -111.702592) (xy 110.217349 -111.7346) (xy 121.915172 -111.7346)
			(xy 121.919243 -111.678978) (xy 121.931369 -111.624541) (xy 121.951292 -111.57245) (xy 121.978588 -111.523815)
			(xy 122.012674 -111.479672) (xy 122.052823 -111.440963) (xy 122.098181 -111.408512) (xy 122.147781 -111.383011)
			(xy 122.200565 -111.365004) (xy 122.255408 -111.354874) (xy 122.311142 -111.352837) (xy 122.366579 -111.358937)
			(xy 122.420536 -111.373043) (xy 122.471865 -111.394855) (xy 122.519471 -111.423909) (xy 122.562339 -111.459584)
			(xy 122.599556 -111.501121) (xy 122.630329 -111.547634) (xy 122.654001 -111.598131) (xy 122.670069 -111.651538)
			(xy 122.678189 -111.706714) (xy 122.678698 -111.7346) (xy 122.678684 -111.735362) (xy 122.931172 -111.735362)
			(xy 122.935243 -111.67974) (xy 122.947369 -111.625303) (xy 122.967292 -111.573212) (xy 122.994588 -111.524577)
			(xy 123.028674 -111.480434) (xy 123.068823 -111.441725) (xy 123.114181 -111.409274) (xy 123.163781 -111.383773)
			(xy 123.216565 -111.365766) (xy 123.271408 -111.355636) (xy 123.327142 -111.353599) (xy 123.382579 -111.359699)
			(xy 123.436536 -111.373805) (xy 123.487865 -111.395617) (xy 123.535471 -111.424671) (xy 123.578339 -111.460346)
			(xy 123.615556 -111.501883) (xy 123.646329 -111.548396) (xy 123.670001 -111.598893) (xy 123.686069 -111.6523)
			(xy 123.694189 -111.707476) (xy 123.694698 -111.735362) (xy 123.947172 -111.735362) (xy 123.951243 -111.67974)
			(xy 123.963369 -111.625303) (xy 123.983292 -111.573212) (xy 124.010588 -111.524577) (xy 124.044674 -111.480434)
			(xy 124.084823 -111.441725) (xy 124.130181 -111.409274) (xy 124.179781 -111.383773) (xy 124.232565 -111.365766)
			(xy 124.287408 -111.355636) (xy 124.343142 -111.353599) (xy 124.398579 -111.359699) (xy 124.452536 -111.373805)
			(xy 124.503865 -111.395617) (xy 124.551471 -111.424671) (xy 124.594339 -111.460346) (xy 124.631556 -111.501883)
			(xy 124.662329 -111.548396) (xy 124.686001 -111.598893) (xy 124.702069 -111.6523) (xy 124.710189 -111.707476)
			(xy 124.710698 -111.735362) (xy 124.963172 -111.735362) (xy 124.967243 -111.67974) (xy 124.979369 -111.625303)
			(xy 124.999292 -111.573212) (xy 125.026588 -111.524577) (xy 125.060674 -111.480434) (xy 125.100823 -111.441725)
			(xy 125.146181 -111.409274) (xy 125.195781 -111.383773) (xy 125.248565 -111.365766) (xy 125.303408 -111.355636)
			(xy 125.359142 -111.353599) (xy 125.414579 -111.359699) (xy 125.468536 -111.373805) (xy 125.519865 -111.395617)
			(xy 125.567471 -111.424671) (xy 125.610339 -111.460346) (xy 125.647556 -111.501883) (xy 125.678329 -111.548396)
			(xy 125.702001 -111.598893) (xy 125.718069 -111.6523) (xy 125.726189 -111.707476) (xy 125.726698 -111.735362)
			(xy 125.726422 -111.750456) (xy 150.210425 -111.750456) (xy 150.210425 -111.695944) (xy 150.218183 -111.641987)
			(xy 150.233541 -111.589683) (xy 150.256187 -111.540098) (xy 150.285659 -111.49424) (xy 150.321358 -111.453044)
			(xy 150.362556 -111.417347) (xy 150.408416 -111.387878) (xy 150.458002 -111.365234) (xy 150.510307 -111.349879)
			(xy 150.564264 -111.342124) (xy 150.59152 -111.341662) (xy 150.617459 -111.342045) (xy 150.668858 -111.349078)
			(xy 150.718829 -111.363011) (xy 150.766452 -111.383587) (xy 150.810847 -111.410428) (xy 150.851195 -111.443037)
			(xy 150.886752 -111.480812) (xy 150.902162 -111.501682) (xy 150.907981 -111.509017) (xy 150.923603 -111.51931)
			(xy 150.932642 -111.521748) (xy 150.962614 -111.528606) (xy 150.971911 -111.530296) (xy 150.990573 -111.527418)
			(xy 150.998936 -111.523018) (xy 151.024945 -111.508723) (xy 151.079868 -111.48623) (xy 151.137234 -111.471007)
			(xy 151.196083 -111.46331) (xy 151.225758 -111.46282) (xy 151.255393 -111.463292) (xy 151.314169 -111.470939)
			(xy 151.371468 -111.486098) (xy 151.426336 -111.508517) (xy 151.452326 -111.522764) (xy 151.460711 -111.527094)
			(xy 151.479348 -111.529957) (xy 151.488648 -111.528352) (xy 151.51862 -111.521494) (xy 151.527711 -111.519173)
			(xy 151.543371 -111.508859) (xy 151.5491 -111.501428) (xy 151.5645 -111.480586) (xy 151.600042 -111.442872)
			(xy 151.640365 -111.41032) (xy 151.684726 -111.383531) (xy 151.732307 -111.362998) (xy 151.78223 -111.349099)
			(xy 151.833577 -111.342091) (xy 151.859488 -111.341662) (xy 151.886739 -111.342184) (xy 151.940687 -111.349939)
			(xy 151.992982 -111.365293) (xy 152.04256 -111.387933) (xy 152.088411 -111.417399) (xy 152.129602 -111.453089)
			(xy 152.165294 -111.494279) (xy 152.194761 -111.540129) (xy 152.217403 -111.589706) (xy 152.232758 -111.642001)
			(xy 152.240515 -111.695949) (xy 152.240515 -111.750451) (xy 152.232758 -111.804399) (xy 152.217403 -111.856694)
			(xy 152.194761 -111.906271) (xy 152.165294 -111.952121) (xy 152.129602 -111.993311) (xy 152.088411 -112.029001)
			(xy 152.04256 -112.058467) (xy 151.992982 -112.081107) (xy 151.940687 -112.096461) (xy 151.886739 -112.104216)
			(xy 151.859488 -112.104678) (xy 151.844759 -112.104527) (xy 151.815389 -112.102241) (xy 151.800814 -112.100106)
			(xy 151.789839 -112.098995) (xy 151.768649 -112.105045) (xy 151.75992 -112.11179) (xy 151.7015 -112.161828)
			(xy 151.693466 -112.169391) (xy 151.684254 -112.189415) (xy 151.68372 -112.200436) (xy 151.68372 -112.504728)
			(xy 151.684236 -112.51575) (xy 151.69347 -112.535766) (xy 151.7015 -112.543336) (xy 151.768556 -112.60074)
			(xy 151.789638 -112.606836) (xy 151.800814 -112.605058) (xy 151.815389 -112.602928) (xy 151.844759 -112.600638)
			(xy 151.859488 -112.600486) (xy 151.886741 -112.600961) (xy 151.940692 -112.608716) (xy 151.992991 -112.624071)
			(xy 152.042572 -112.646712) (xy 152.088426 -112.676179) (xy 152.129619 -112.711872) (xy 152.165313 -112.753065)
			(xy 152.194782 -112.798918) (xy 152.217425 -112.848498) (xy 152.232781 -112.900796) (xy 152.240539 -112.954747)
			(xy 152.240539 -113.009253) (xy 152.232781 -113.063204) (xy 152.217425 -113.115502) (xy 152.194782 -113.165082)
			(xy 152.165313 -113.210935) (xy 152.135676 -113.245138) (xy 160.769552 -113.245138) (xy 160.773623 -113.189516)
			(xy 160.785749 -113.135079) (xy 160.805672 -113.082988) (xy 160.832968 -113.034353) (xy 160.867054 -112.99021)
			(xy 160.907203 -112.951501) (xy 160.952561 -112.91905) (xy 161.002161 -112.893549) (xy 161.054945 -112.875542)
			(xy 161.109788 -112.865412) (xy 161.165522 -112.863375) (xy 161.220959 -112.869475) (xy 161.274916 -112.883581)
			(xy 161.326245 -112.905393) (xy 161.373851 -112.934447) (xy 161.416719 -112.970122) (xy 161.453936 -113.011659)
			(xy 161.484709 -113.058172) (xy 161.508381 -113.108669) (xy 161.524449 -113.162076) (xy 161.532569 -113.217252)
			(xy 161.533078 -113.245138) (xy 163.190426 -113.245138) (xy 163.194497 -113.189516) (xy 163.206623 -113.135079)
			(xy 163.226546 -113.082988) (xy 163.253842 -113.034353) (xy 163.287928 -112.99021) (xy 163.328077 -112.951501)
			(xy 163.373435 -112.91905) (xy 163.423035 -112.893549) (xy 163.475819 -112.875542) (xy 163.530662 -112.865412)
			(xy 163.586396 -112.863375) (xy 163.641833 -112.869475) (xy 163.69579 -112.883581) (xy 163.747119 -112.905393)
			(xy 163.794725 -112.934447) (xy 163.837593 -112.970122) (xy 163.87481 -113.011659) (xy 163.905583 -113.058172)
			(xy 163.929255 -113.108669) (xy 163.945323 -113.162076) (xy 163.953443 -113.217252) (xy 163.953952 -113.245138)
			(xy 163.953443 -113.273024) (xy 163.945323 -113.3282) (xy 163.929255 -113.381607) (xy 163.905583 -113.432104)
			(xy 163.87481 -113.478617) (xy 163.837593 -113.520154) (xy 163.794725 -113.555829) (xy 163.747119 -113.584883)
			(xy 163.69579 -113.606695) (xy 163.641833 -113.620801) (xy 163.586396 -113.626901) (xy 163.530662 -113.624864)
			(xy 163.475819 -113.614734) (xy 163.423035 -113.596727) (xy 163.373435 -113.571226) (xy 163.328077 -113.538775)
			(xy 163.287928 -113.500066) (xy 163.253842 -113.455923) (xy 163.226546 -113.407288) (xy 163.206623 -113.355197)
			(xy 163.194497 -113.30076) (xy 163.190426 -113.245138) (xy 161.533078 -113.245138) (xy 161.532569 -113.273024)
			(xy 161.524449 -113.3282) (xy 161.508381 -113.381607) (xy 161.484709 -113.432104) (xy 161.453936 -113.478617)
			(xy 161.416719 -113.520154) (xy 161.373851 -113.555829) (xy 161.326245 -113.584883) (xy 161.274916 -113.606695)
			(xy 161.220959 -113.620801) (xy 161.165522 -113.626901) (xy 161.109788 -113.624864) (xy 161.054945 -113.614734)
			(xy 161.002161 -113.596727) (xy 160.952561 -113.571226) (xy 160.907203 -113.538775) (xy 160.867054 -113.500066)
			(xy 160.832968 -113.455923) (xy 160.805672 -113.407288) (xy 160.785749 -113.355197) (xy 160.773623 -113.30076)
			(xy 160.769552 -113.245138) (xy 152.135676 -113.245138) (xy 152.129619 -113.252128) (xy 152.088426 -113.287821)
			(xy 152.042572 -113.317288) (xy 151.992991 -113.339929) (xy 151.940692 -113.355284) (xy 151.886741 -113.363039)
			(xy 151.859488 -113.363502) (xy 151.833581 -113.363021) (xy 151.782245 -113.355996) (xy 151.732332 -113.342091)
			(xy 151.684759 -113.32156) (xy 151.640401 -113.294783) (xy 151.600073 -113.26225) (xy 151.564517 -113.224561)
			(xy 151.5491 -113.203736) (xy 151.543291 -113.196392) (xy 151.527662 -113.186104) (xy 151.51862 -113.18367)
			(xy 151.488648 -113.176812) (xy 151.479348 -113.175153) (xy 151.46069 -113.17801) (xy 151.452326 -113.1824)
			(xy 151.42634 -113.196657) (xy 151.371473 -113.219081) (xy 151.314172 -113.234239) (xy 151.255394 -113.241879)
			(xy 151.225758 -113.242344) (xy 151.19608 -113.241883) (xy 151.137223 -113.234209) (xy 151.079855 -113.218981)
			(xy 151.02494 -113.196457) (xy 150.998936 -113.182146) (xy 150.990539 -113.177844) (xy 150.971912 -113.174966)
			(xy 150.962614 -113.176558) (xy 150.932642 -113.183416) (xy 150.923544 -113.185718) (xy 150.907887 -113.196045)
			(xy 150.902162 -113.203482) (xy 150.886758 -113.224353) (xy 150.851192 -113.262115) (xy 150.810839 -113.294711)
			(xy 150.766443 -113.321541) (xy 150.718821 -113.342108) (xy 150.668852 -113.356035) (xy 150.617457 -113.363065)
			(xy 150.59152 -113.363502) (xy 150.564266 -113.363052) (xy 150.510312 -113.355297) (xy 150.458011 -113.339943)
			(xy 150.408427 -113.317301) (xy 150.362571 -113.287833) (xy 150.321375 -113.252139) (xy 150.285679 -113.210945)
			(xy 150.256209 -113.16509) (xy 150.233564 -113.115508) (xy 150.218207 -113.063208) (xy 150.210449 -113.009254)
			(xy 150.210449 -112.954746) (xy 150.218207 -112.900792) (xy 150.233564 -112.848492) (xy 150.256209 -112.79891)
			(xy 150.285679 -112.753055) (xy 150.321375 -112.711861) (xy 150.362571 -112.676167) (xy 150.408427 -112.646699)
			(xy 150.458011 -112.624057) (xy 150.510312 -112.608703) (xy 150.564266 -112.600948) (xy 150.59152 -112.600486)
			(xy 150.592028 -112.600486) (xy 150.606757 -112.600634) (xy 150.636127 -112.602922) (xy 150.650702 -112.605058)
			(xy 150.661677 -112.606186) (xy 150.682869 -112.600125) (xy 150.691596 -112.593374) (xy 150.750016 -112.543336)
			(xy 150.758023 -112.53575) (xy 150.76725 -112.515743) (xy 150.767796 -112.504728) (xy 150.767796 -112.200436)
			(xy 150.76724 -112.189419) (xy 150.758033 -112.169402) (xy 150.750016 -112.161828) (xy 150.68296 -112.104424)
			(xy 150.661878 -112.098328) (xy 150.650702 -112.100106) (xy 150.636127 -112.102235) (xy 150.606757 -112.104526)
			(xy 150.592028 -112.104678) (xy 150.59152 -112.104678) (xy 150.564264 -112.104276) (xy 150.510307 -112.096521)
			(xy 150.458002 -112.081166) (xy 150.408416 -112.058522) (xy 150.362556 -112.029053) (xy 150.321358 -111.993356)
			(xy 150.285659 -111.95216) (xy 150.256187 -111.906302) (xy 150.233541 -111.856717) (xy 150.218183 -111.804413)
			(xy 150.210425 -111.750456) (xy 125.726422 -111.750456) (xy 125.726189 -111.763248) (xy 125.718069 -111.818424)
			(xy 125.702001 -111.871831) (xy 125.678329 -111.922328) (xy 125.647556 -111.968841) (xy 125.610339 -112.010378)
			(xy 125.567471 -112.046053) (xy 125.519865 -112.075107) (xy 125.468536 -112.096919) (xy 125.414579 -112.111025)
			(xy 125.359142 -112.117125) (xy 125.303408 -112.115088) (xy 125.248565 -112.104958) (xy 125.195781 -112.086951)
			(xy 125.146181 -112.06145) (xy 125.100823 -112.028999) (xy 125.060674 -111.99029) (xy 125.026588 -111.946147)
			(xy 124.999292 -111.897512) (xy 124.979369 -111.845421) (xy 124.967243 -111.790984) (xy 124.963172 -111.735362)
			(xy 124.710698 -111.735362) (xy 124.710189 -111.763248) (xy 124.702069 -111.818424) (xy 124.686001 -111.871831)
			(xy 124.662329 -111.922328) (xy 124.631556 -111.968841) (xy 124.594339 -112.010378) (xy 124.551471 -112.046053)
			(xy 124.503865 -112.075107) (xy 124.452536 -112.096919) (xy 124.398579 -112.111025) (xy 124.343142 -112.117125)
			(xy 124.287408 -112.115088) (xy 124.232565 -112.104958) (xy 124.179781 -112.086951) (xy 124.130181 -112.06145)
			(xy 124.084823 -112.028999) (xy 124.044674 -111.99029) (xy 124.010588 -111.946147) (xy 123.983292 -111.897512)
			(xy 123.963369 -111.845421) (xy 123.951243 -111.790984) (xy 123.947172 -111.735362) (xy 123.694698 -111.735362)
			(xy 123.694189 -111.763248) (xy 123.686069 -111.818424) (xy 123.670001 -111.871831) (xy 123.646329 -111.922328)
			(xy 123.615556 -111.968841) (xy 123.578339 -112.010378) (xy 123.535471 -112.046053) (xy 123.487865 -112.075107)
			(xy 123.436536 -112.096919) (xy 123.382579 -112.111025) (xy 123.327142 -112.117125) (xy 123.271408 -112.115088)
			(xy 123.216565 -112.104958) (xy 123.163781 -112.086951) (xy 123.114181 -112.06145) (xy 123.068823 -112.028999)
			(xy 123.028674 -111.99029) (xy 122.994588 -111.946147) (xy 122.967292 -111.897512) (xy 122.947369 -111.845421)
			(xy 122.935243 -111.790984) (xy 122.931172 -111.735362) (xy 122.678684 -111.735362) (xy 122.678189 -111.762486)
			(xy 122.670069 -111.817662) (xy 122.654001 -111.871069) (xy 122.630329 -111.921566) (xy 122.599556 -111.968079)
			(xy 122.562339 -112.009616) (xy 122.519471 -112.045291) (xy 122.471865 -112.074345) (xy 122.420536 -112.096157)
			(xy 122.366579 -112.110263) (xy 122.311142 -112.116363) (xy 122.255408 -112.114326) (xy 122.200565 -112.104196)
			(xy 122.147781 -112.086189) (xy 122.098181 -112.060688) (xy 122.052823 -112.028237) (xy 122.012674 -111.989528)
			(xy 121.978588 -111.945385) (xy 121.951292 -111.89675) (xy 121.931369 -111.844659) (xy 121.919243 -111.790222)
			(xy 121.915172 -111.7346) (xy 110.217349 -111.7346) (xy 110.220759 -111.757768) (xy 110.221268 -111.785654)
			(xy 110.220759 -111.81354) (xy 110.212639 -111.868716) (xy 110.196571 -111.922123) (xy 110.172899 -111.97262)
			(xy 110.142126 -112.019133) (xy 110.104909 -112.06067) (xy 110.062041 -112.096345) (xy 110.014435 -112.125399)
			(xy 109.963106 -112.147211) (xy 109.909149 -112.161317) (xy 109.853712 -112.167417) (xy 109.797978 -112.16538)
			(xy 109.743135 -112.15525) (xy 109.690351 -112.137243) (xy 109.640751 -112.111742) (xy 109.595393 -112.079291)
			(xy 109.555244 -112.040582) (xy 109.521158 -111.996439) (xy 109.493862 -111.947804) (xy 109.473939 -111.895713)
			(xy 109.461813 -111.841276) (xy 109.457742 -111.785654) (xy 108.17269 -111.785654) (xy 108.207707 -111.820676)
			(xy 108.238256 -111.862728) (xy 108.261852 -111.909041) (xy 108.277912 -111.958474) (xy 108.286042 -112.009811)
			(xy 108.286042 -112.061789) (xy 108.277912 -112.113126) (xy 108.261852 -112.162559) (xy 108.238256 -112.208872)
			(xy 108.207707 -112.250924) (xy 108.170956 -112.28768) (xy 108.15819 -112.296956) (xy 110.894874 -112.296956)
			(xy 110.898945 -112.241334) (xy 110.911071 -112.186897) (xy 110.930994 -112.134806) (xy 110.95829 -112.086171)
			(xy 110.992376 -112.042028) (xy 111.032525 -112.003319) (xy 111.077883 -111.970868) (xy 111.127483 -111.945367)
			(xy 111.180267 -111.92736) (xy 111.23511 -111.91723) (xy 111.290844 -111.915193) (xy 111.346281 -111.921293)
			(xy 111.400238 -111.935399) (xy 111.451567 -111.957211) (xy 111.499173 -111.986265) (xy 111.542041 -112.02194)
			(xy 111.579258 -112.063477) (xy 111.610031 -112.10999) (xy 111.633703 -112.160487) (xy 111.649771 -112.213894)
			(xy 111.657891 -112.26907) (xy 111.6584 -112.296956) (xy 111.657891 -112.324842) (xy 111.649771 -112.380018)
			(xy 111.633703 -112.433425) (xy 111.610031 -112.483922) (xy 111.579258 -112.530435) (xy 111.542041 -112.571972)
			(xy 111.499173 -112.607647) (xy 111.451567 -112.636701) (xy 111.400238 -112.658513) (xy 111.346281 -112.672619)
			(xy 111.290844 -112.678719) (xy 111.23511 -112.676682) (xy 111.180267 -112.666552) (xy 111.127483 -112.648545)
			(xy 111.077883 -112.623044) (xy 111.032525 -112.590593) (xy 110.992376 -112.551884) (xy 110.95829 -112.507741)
			(xy 110.930994 -112.459106) (xy 110.911071 -112.407015) (xy 110.898945 -112.352578) (xy 110.894874 -112.296956)
			(xy 108.15819 -112.296956) (xy 108.128908 -112.318234) (xy 108.082598 -112.341835) (xy 108.033167 -112.357902)
			(xy 107.98183 -112.366039) (xy 107.955842 -112.366552) (xy 107.929197 -112.36608) (xy 107.876594 -112.357547)
			(xy 107.826043 -112.340679) (xy 107.778857 -112.315913) (xy 107.736259 -112.283894) (xy 107.699354 -112.24545)
			(xy 107.683808 -112.223804) (xy 107.675444 -112.212518) (xy 107.653771 -112.194663) (xy 107.628057 -112.18338)
			(xy 107.600242 -112.179522) (xy 107.572427 -112.18338) (xy 107.546713 -112.194663) (xy 107.52504 -112.212518)
			(xy 107.516676 -112.223804) (xy 107.501094 -112.245417) (xy 107.46418 -112.283835) (xy 107.421582 -112.315836)
			(xy 107.374405 -112.340592) (xy 107.323869 -112.357464) (xy 107.271281 -112.366014) (xy 107.244642 -112.366552)
			(xy 107.218654 -112.365984) (xy 107.167317 -112.357859) (xy 107.117884 -112.341803) (xy 107.071571 -112.31821)
			(xy 107.029519 -112.287663) (xy 106.992764 -112.250913) (xy 106.962212 -112.208865) (xy 106.938613 -112.162555)
			(xy 106.922551 -112.113124) (xy 106.914419 -112.061788) (xy 105.76617 -112.061788) (xy 105.755748 -112.107182)
			(xy 105.73465 -112.160606) (xy 105.705785 -112.210265) (xy 105.669805 -112.255038) (xy 105.649014 -112.274858)
			(xy 105.641631 -112.282395) (xy 105.633095 -112.301663) (xy 105.632504 -112.312196) (xy 105.632504 -112.386872)
			(xy 105.633034 -112.397422) (xy 105.641568 -112.416717) (xy 105.649014 -112.42421) (xy 105.66807 -112.442365)
			(xy 105.701527 -112.482995) (xy 105.729085 -112.527836) (xy 105.750224 -112.576036) (xy 105.764541 -112.626684)
			(xy 105.771765 -112.678818) (xy 105.772204 -112.705134) (xy 105.771754 -112.732386) (xy 105.763993 -112.786335)
			(xy 105.748633 -112.838631) (xy 105.725988 -112.888209) (xy 105.696517 -112.934059) (xy 105.672482 -112.961794)
			(xy 106.914341 -112.961794) (xy 106.914341 -112.909806) (xy 106.922475 -112.858458) (xy 106.938541 -112.809015)
			(xy 106.962145 -112.762694) (xy 106.992705 -112.720636) (xy 107.029468 -112.683878) (xy 107.07153 -112.653323)
			(xy 107.117854 -112.629725) (xy 107.167299 -112.613665) (xy 107.218648 -112.605538) (xy 107.244642 -112.605058)
			(xy 107.271287 -112.605538) (xy 107.32389 -112.614069) (xy 107.37444 -112.630935) (xy 107.421627 -112.655699)
			(xy 107.464225 -112.687717) (xy 107.50113 -112.72616) (xy 107.516676 -112.747806) (xy 107.52504 -112.759092)
			(xy 107.546713 -112.776947) (xy 107.572427 -112.78823) (xy 107.600242 -112.792088) (xy 107.628057 -112.78823)
			(xy 107.653771 -112.776947) (xy 107.675444 -112.759092) (xy 107.683808 -112.747806) (xy 107.699373 -112.72618)
			(xy 107.736294 -112.687768) (xy 107.778896 -112.655771) (xy 107.826076 -112.631018) (xy 107.876614 -112.614148)
			(xy 107.929202 -112.605598) (xy 107.955842 -112.605058) (xy 107.981824 -112.605639) (xy 108.033148 -112.613774)
			(xy 108.082568 -112.629837) (xy 108.128867 -112.653432) (xy 108.170905 -112.68398) (xy 108.207648 -112.720727)
			(xy 108.23819 -112.762769) (xy 108.26178 -112.809071) (xy 108.277836 -112.858492) (xy 108.285569 -112.907318)
			(xy 122.168918 -112.907318) (xy 122.172989 -112.851696) (xy 122.185115 -112.797259) (xy 122.205038 -112.745168)
			(xy 122.232334 -112.696533) (xy 122.26642 -112.65239) (xy 122.306569 -112.613681) (xy 122.351927 -112.58123)
			(xy 122.401527 -112.555729) (xy 122.454311 -112.537722) (xy 122.509154 -112.527592) (xy 122.564888 -112.525555)
			(xy 122.620325 -112.531655) (xy 122.652376 -112.540034) (xy 129.906014 -112.540034) (xy 129.9065 -112.512783)
			(xy 129.914256 -112.458835) (xy 129.929611 -112.40654) (xy 129.952253 -112.356963) (xy 129.981719 -112.311113)
			(xy 130.01741 -112.269922) (xy 130.058601 -112.234231) (xy 130.104451 -112.204765) (xy 130.154028 -112.182123)
			(xy 130.206323 -112.166768) (xy 130.260271 -112.159012) (xy 130.314773 -112.159012) (xy 130.368721 -112.166768)
			(xy 130.421016 -112.182123) (xy 130.470593 -112.204765) (xy 130.516443 -112.234231) (xy 130.557634 -112.269922)
			(xy 130.593325 -112.311113) (xy 130.622791 -112.356963) (xy 130.639699 -112.393985) (xy 131.90791 -112.393985)
			(xy 131.915662 -112.340027) (xy 131.931014 -112.287721) (xy 131.953654 -112.238133) (xy 131.983121 -112.192272)
			(xy 132.018814 -112.151071) (xy 132.060008 -112.115369) (xy 132.105863 -112.085893) (xy 132.155446 -112.063242)
			(xy 132.207749 -112.047879) (xy 132.261705 -112.040116) (xy 132.316217 -112.04011) (xy 132.370174 -112.047862)
			(xy 132.42248 -112.063215) (xy 132.472068 -112.085855) (xy 132.517929 -112.115322) (xy 132.55913 -112.151015)
			(xy 132.594832 -112.192209) (xy 132.624308 -112.238064) (xy 132.646958 -112.287648) (xy 132.662321 -112.33995)
			(xy 132.670084 -112.393906) (xy 132.67055 -112.421162) (xy 132.67055 -112.428528) (xy 132.670296 -112.442244)
			(xy 132.683758 -112.466374) (xy 132.78485 -112.524794) (xy 132.812536 -112.52454) (xy 132.824474 -112.517428)
			(xy 132.846837 -112.504496) (xy 132.894284 -112.484066) (xy 132.944056 -112.470233) (xy 132.995241 -112.46325)
			(xy 133.02107 -112.462818) (xy 133.048323 -112.463283) (xy 133.102276 -112.471037) (xy 133.154575 -112.48639)
			(xy 133.204157 -112.509031) (xy 133.250011 -112.538499) (xy 133.291205 -112.574192) (xy 133.326899 -112.615386)
			(xy 133.356367 -112.66124) (xy 133.379008 -112.710821) (xy 133.394362 -112.763121) (xy 133.402116 -112.817073)
			(xy 133.402578 -112.844326) (xy 133.402018 -112.873663) (xy 133.393019 -112.931643) (xy 133.375253 -112.987564)
			(xy 133.349137 -113.040106) (xy 133.315288 -113.088033) (xy 133.274503 -113.130214) (xy 133.251448 -113.148364)
			(xy 133.242822 -113.155592) (xy 133.232408 -113.17551) (xy 133.231382 -113.186718) (xy 133.227572 -113.276634)
			(xy 133.236208 -113.297462) (xy 133.244844 -113.305082) (xy 133.264449 -113.32322) (xy 133.298839 -113.364086)
			(xy 133.327193 -113.409349) (xy 133.348957 -113.458124) (xy 133.363704 -113.509459) (xy 133.371146 -113.562349)
			(xy 133.37159 -113.589054) (xy 133.371104 -113.616305) (xy 133.363348 -113.670253) (xy 133.347993 -113.722548)
			(xy 133.325351 -113.772125) (xy 133.32025 -113.780062) (xy 165.581328 -113.780062) (xy 165.585399 -113.72444)
			(xy 165.597525 -113.670003) (xy 165.617448 -113.617912) (xy 165.644744 -113.569277) (xy 165.67883 -113.525134)
			(xy 165.718979 -113.486425) (xy 165.764337 -113.453974) (xy 165.813937 -113.428473) (xy 165.866721 -113.410466)
			(xy 165.921564 -113.400336) (xy 165.977298 -113.398299) (xy 166.032735 -113.404399) (xy 166.086692 -113.418505)
			(xy 166.138021 -113.440317) (xy 166.185627 -113.469371) (xy 166.228495 -113.505046) (xy 166.265712 -113.546583)
			(xy 166.296485 -113.593096) (xy 166.320157 -113.643593) (xy 166.336225 -113.697) (xy 166.344345 -113.752176)
			(xy 166.344854 -113.780062) (xy 166.344345 -113.807948) (xy 166.336225 -113.863124) (xy 166.320157 -113.916531)
			(xy 166.296485 -113.967028) (xy 166.265712 -114.013541) (xy 166.228495 -114.055078) (xy 166.185627 -114.090753)
			(xy 166.138021 -114.119807) (xy 166.086692 -114.141619) (xy 166.032735 -114.155725) (xy 165.977298 -114.161825)
			(xy 165.921564 -114.159788) (xy 165.866721 -114.149658) (xy 165.813937 -114.131651) (xy 165.764337 -114.10615)
			(xy 165.718979 -114.073699) (xy 165.67883 -114.03499) (xy 165.644744 -113.990847) (xy 165.617448 -113.942212)
			(xy 165.597525 -113.890121) (xy 165.585399 -113.835684) (xy 165.581328 -113.780062) (xy 133.32025 -113.780062)
			(xy 133.295885 -113.817975) (xy 133.260194 -113.859166) (xy 133.219003 -113.894857) (xy 133.173153 -113.924323)
			(xy 133.123576 -113.946965) (xy 133.071281 -113.96232) (xy 133.017333 -113.970076) (xy 132.962831 -113.970076)
			(xy 132.908883 -113.96232) (xy 132.856588 -113.946965) (xy 132.807011 -113.924323) (xy 132.761161 -113.894857)
			(xy 132.71997 -113.859166) (xy 132.684279 -113.817975) (xy 132.654813 -113.772125) (xy 132.632171 -113.722548)
			(xy 132.616816 -113.670253) (xy 132.60906 -113.616305) (xy 132.608574 -113.589054) (xy 132.609139 -113.559717)
			(xy 132.618139 -113.501738) (xy 132.635906 -113.445819) (xy 132.662021 -113.393277) (xy 132.695868 -113.34535)
			(xy 132.73665 -113.303167) (xy 132.759704 -113.285016) (xy 132.768348 -113.277807) (xy 132.77875 -113.257874)
			(xy 132.77977 -113.246662) (xy 132.78358 -113.156746) (xy 132.774944 -113.135918) (xy 132.766308 -113.128298)
			(xy 132.746752 -113.110109) (xy 132.712355 -113.069256) (xy 132.683994 -113.024004) (xy 132.662221 -112.975238)
			(xy 132.647465 -112.923912) (xy 132.640011 -112.871029) (xy 132.639562 -112.844326) (xy 132.639562 -112.83696)
			(xy 132.639816 -112.823244) (xy 132.626354 -112.799114) (xy 132.525262 -112.740694) (xy 132.497576 -112.740948)
			(xy 132.485638 -112.74806) (xy 132.463294 -112.761026) (xy 132.41584 -112.781448) (xy 132.366062 -112.795272)
			(xy 132.314873 -112.802243) (xy 132.289042 -112.80267) (xy 132.261786 -112.80229) (xy 132.207828 -112.794538)
			(xy 132.155523 -112.779186) (xy 132.105934 -112.756546) (xy 132.060073 -112.72708) (xy 132.018872 -112.691387)
			(xy 131.98317 -112.650193) (xy 131.953693 -112.604338) (xy 131.931043 -112.554755) (xy 131.915679 -112.502453)
			(xy 131.907916 -112.448497) (xy 131.90791 -112.393985) (xy 130.639699 -112.393985) (xy 130.645433 -112.40654)
			(xy 130.660788 -112.458835) (xy 130.668544 -112.512783) (xy 130.66903 -112.540034) (xy 130.66903 -112.540542)
			(xy 130.668372 -112.571872) (xy 130.658083 -112.633683) (xy 130.637837 -112.692984) (xy 130.623564 -112.720882)
			(xy 130.616917 -112.734303) (xy 130.610979 -112.763643) (xy 130.613808 -112.793444) (xy 130.625163 -112.821142)
			(xy 130.644065 -112.844355) (xy 130.668889 -112.861085) (xy 130.697499 -112.869893) (xy 130.712464 -112.870488)
			(xy 130.739621 -112.871092) (xy 130.793349 -112.879086) (xy 130.845399 -112.89462) (xy 130.894721 -112.917379)
			(xy 130.940316 -112.946904) (xy 130.981263 -112.982596) (xy 131.016733 -113.023735) (xy 131.046011 -113.069489)
			(xy 131.068503 -113.118932) (xy 131.083756 -113.171066) (xy 131.091461 -113.224836) (xy 131.09194 -113.251996)
			(xy 131.091454 -113.279247) (xy 131.083698 -113.333195) (xy 131.068343 -113.38549) (xy 131.045701 -113.435067)
			(xy 131.016235 -113.480917) (xy 130.980544 -113.522108) (xy 130.939353 -113.557799) (xy 130.893503 -113.587265)
			(xy 130.843926 -113.609907) (xy 130.791631 -113.625262) (xy 130.737683 -113.633018) (xy 130.683181 -113.633018)
			(xy 130.629233 -113.625262) (xy 130.576938 -113.609907) (xy 130.527361 -113.587265) (xy 130.481511 -113.557799)
			(xy 130.44032 -113.522108) (xy 130.404629 -113.480917) (xy 130.375163 -113.435067) (xy 130.352521 -113.38549)
			(xy 130.337166 -113.333195) (xy 130.32941 -113.279247) (xy 130.328924 -113.251996) (xy 130.328924 -113.251488)
			(xy 130.329587 -113.220158) (xy 130.339873 -113.158347) (xy 130.360117 -113.099046) (xy 130.37439 -113.071148)
			(xy 130.38104 -113.057726) (xy 130.38699 -113.028384) (xy 130.384166 -112.998578) (xy 130.372812 -112.970874)
			(xy 130.353906 -112.947659) (xy 130.329075 -112.930931) (xy 130.300458 -112.922131) (xy 130.28549 -112.921542)
			(xy 130.258336 -112.920858) (xy 130.204613 -112.912871) (xy 130.152566 -112.897346) (xy 130.103246 -112.874595)
			(xy 130.057652 -112.845079) (xy 130.016706 -112.809395) (xy 129.981234 -112.768264) (xy 129.951955 -112.722518)
			(xy 129.92946 -112.673082) (xy 129.914204 -112.620955) (xy 129.906496 -112.567191) (xy 129.906014 -112.540034)
			(xy 122.652376 -112.540034) (xy 122.674282 -112.545761) (xy 122.725611 -112.567573) (xy 122.773217 -112.596627)
			(xy 122.816085 -112.632302) (xy 122.853302 -112.673839) (xy 122.884075 -112.720352) (xy 122.907747 -112.770849)
			(xy 122.923815 -112.824256) (xy 122.931935 -112.879432) (xy 122.932444 -112.907318) (xy 122.931935 -112.935204)
			(xy 122.923815 -112.99038) (xy 122.907747 -113.043787) (xy 122.884075 -113.094284) (xy 122.853302 -113.140797)
			(xy 122.816085 -113.182334) (xy 122.773217 -113.218009) (xy 122.725611 -113.247063) (xy 122.674282 -113.268875)
			(xy 122.620325 -113.282981) (xy 122.564888 -113.289081) (xy 122.509154 -113.287044) (xy 122.454311 -113.276914)
			(xy 122.401527 -113.258907) (xy 122.351927 -113.233406) (xy 122.306569 -113.200955) (xy 122.26642 -113.162246)
			(xy 122.232334 -113.118103) (xy 122.205038 -113.069468) (xy 122.185115 -113.017377) (xy 122.172989 -112.96294)
			(xy 122.168918 -112.907318) (xy 108.285569 -112.907318) (xy 108.285965 -112.909818) (xy 108.285965 -112.961782)
			(xy 108.277836 -113.013108) (xy 108.26178 -113.062529) (xy 108.23819 -113.108831) (xy 108.207648 -113.150873)
			(xy 108.170905 -113.18762) (xy 108.128867 -113.218168) (xy 108.082568 -113.241763) (xy 108.033148 -113.257826)
			(xy 107.981824 -113.265961) (xy 107.955842 -113.266474) (xy 107.929197 -113.265992) (xy 107.876595 -113.25746)
			(xy 107.826045 -113.240593) (xy 107.778859 -113.21583) (xy 107.73626 -113.183812) (xy 107.699355 -113.145371)
			(xy 107.683808 -113.123726) (xy 107.675444 -113.11244) (xy 107.653771 -113.094585) (xy 107.628057 -113.083302)
			(xy 107.600242 -113.079444) (xy 107.572427 -113.083302) (xy 107.546713 -113.094585) (xy 107.52504 -113.11244)
			(xy 107.516676 -113.123726) (xy 107.501101 -113.145344) (xy 107.464184 -113.18376) (xy 107.421585 -113.21576)
			(xy 107.374407 -113.240516) (xy 107.32387 -113.257386) (xy 107.271281 -113.265936) (xy 107.244642 -113.266474)
			(xy 107.218648 -113.266062) (xy 107.167299 -113.257935) (xy 107.117854 -113.241875) (xy 107.07153 -113.218277)
			(xy 107.029468 -113.187722) (xy 106.992705 -113.150964) (xy 106.962145 -113.108906) (xy 106.938541 -113.062585)
			(xy 106.922475 -113.013142) (xy 106.914341 -112.961794) (xy 105.672482 -112.961794) (xy 105.660822 -112.975249)
			(xy 105.619629 -113.01094) (xy 105.573775 -113.040406) (xy 105.524195 -113.063046) (xy 105.471898 -113.078401)
			(xy 105.417948 -113.086157) (xy 105.390696 -113.086642) (xy 105.364381 -113.086196) (xy 105.312251 -113.078959)
			(xy 105.261607 -113.064637) (xy 105.213408 -113.043501) (xy 105.168565 -113.01595) (xy 105.127927 -112.982506)
			(xy 105.109772 -112.963452) (xy 105.102256 -112.956044) (xy 105.082972 -112.947521) (xy 105.072434 -112.946942)
			(xy 104.997758 -112.946942) (xy 104.987209 -112.947477) (xy 104.967912 -112.956007) (xy 104.96042 -112.963452)
			(xy 104.942258 -112.982501) (xy 104.901628 -113.015957) (xy 104.856789 -113.043515) (xy 104.80859 -113.064654)
			(xy 104.757944 -113.078974) (xy 104.705812 -113.086202) (xy 104.679496 -113.086642) (xy 104.652246 -113.086126)
			(xy 104.598301 -113.07837) (xy 104.546009 -113.063016) (xy 104.496434 -113.040377) (xy 104.450585 -113.010913)
			(xy 104.409396 -112.975225) (xy 104.373705 -112.934039) (xy 104.344238 -112.888192) (xy 104.321595 -112.838619)
			(xy 104.306237 -112.786328) (xy 104.298476 -112.732384) (xy 104.297988 -112.705134) (xy 104.298415 -112.678819)
			(xy 104.305659 -112.626689) (xy 104.319986 -112.576045) (xy 104.341126 -112.527847) (xy 104.368679 -112.483004)
			(xy 104.402124 -112.442366) (xy 104.421178 -112.42421) (xy 104.428574 -112.416684) (xy 104.437102 -112.397407)
			(xy 104.437688 -112.386872) (xy 104.437688 -112.312196) (xy 104.437178 -112.301644) (xy 104.42863 -112.282349)
			(xy 104.421178 -112.274858) (xy 104.400424 -112.255004) (xy 104.364449 -112.210236) (xy 104.335589 -112.160583)
			(xy 104.314494 -112.107166) (xy 104.301643 -112.051192) (xy 104.297324 -111.993923) (xy 100.855495 -111.993923)
			(xy 100.858786 -112.037615) (xy 100.854467 -112.094891) (xy 100.841614 -112.150873) (xy 100.820516 -112.204297)
			(xy 100.79165 -112.253956) (xy 100.755667 -112.298727) (xy 100.734876 -112.318546) (xy 100.727463 -112.326059)
			(xy 100.718942 -112.345345) (xy 100.718366 -112.355884) (xy 100.718366 -112.43056) (xy 100.718913 -112.441107)
			(xy 100.727437 -112.460402) (xy 100.734876 -112.467898) (xy 100.753919 -112.486066) (xy 100.787378 -112.526693)
			(xy 100.814939 -112.57153) (xy 100.83608 -112.619729) (xy 100.8504 -112.670374) (xy 100.857627 -112.722506)
			(xy 100.858066 -112.748822) (xy 100.85758 -112.776073) (xy 100.849824 -112.830021) (xy 100.834469 -112.882316)
			(xy 100.811827 -112.931893) (xy 100.782361 -112.977743) (xy 100.74667 -113.018934) (xy 100.705479 -113.054625)
			(xy 100.659629 -113.084091) (xy 100.610052 -113.106733) (xy 100.557757 -113.122088) (xy 100.503809 -113.129844)
			(xy 100.449307 -113.129844) (xy 100.395359 -113.122088) (xy 100.343064 -113.106733) (xy 100.293487 -113.084091)
			(xy 100.247637 -113.054625) (xy 100.206446 -113.018934) (xy 100.170755 -112.977743) (xy 100.141289 -112.931893)
			(xy 100.118647 -112.882316) (xy 100.103292 -112.830021) (xy 100.095536 -112.776073) (xy 100.09505 -112.748822)
			(xy 100.095516 -112.722508) (xy 100.102749 -112.670379) (xy 100.117067 -112.619735) (xy 100.1382 -112.571536)
			(xy 100.165747 -112.526693) (xy 100.199187 -112.486054) (xy 100.21824 -112.467898) (xy 100.225636 -112.460371)
			(xy 100.234165 -112.441095) (xy 100.23475 -112.43056) (xy 100.23475 -112.355884) (xy 100.234228 -112.345334)
			(xy 100.225686 -112.326039) (xy 100.21824 -112.318546) (xy 100.197476 -112.298703) (xy 100.161505 -112.253932)
			(xy 100.132647 -112.204277) (xy 100.111556 -112.150859) (xy 100.098707 -112.094884) (xy 100.09439 -112.037615)
			(xy 98.320539 -112.037615) (xy 98.316221 -112.094889) (xy 98.303371 -112.150869) (xy 98.282277 -112.204292)
			(xy 98.253417 -112.253951) (xy 98.217442 -112.298725) (xy 98.196654 -112.318546) (xy 98.189238 -112.326056)
			(xy 98.18072 -112.345344) (xy 98.180144 -112.355884) (xy 98.180144 -112.43056) (xy 98.180668 -112.441111)
			(xy 98.189206 -112.460407) (xy 98.196654 -112.467898) (xy 98.215712 -112.486051) (xy 98.249167 -112.526682)
			(xy 98.276724 -112.571524) (xy 98.297862 -112.619725) (xy 98.312179 -112.670372) (xy 98.319405 -112.722506)
			(xy 98.319844 -112.748822) (xy 98.319358 -112.776073) (xy 98.311602 -112.830021) (xy 98.296247 -112.882316)
			(xy 98.273605 -112.931893) (xy 98.244139 -112.977743) (xy 98.208448 -113.018934) (xy 98.167257 -113.054625)
			(xy 98.121407 -113.084091) (xy 98.07183 -113.106733) (xy 98.019535 -113.122088) (xy 97.965587 -113.129844)
			(xy 97.911085 -113.129844) (xy 97.857137 -113.122088) (xy 97.804842 -113.106733) (xy 97.755265 -113.084091)
			(xy 97.709415 -113.054625) (xy 97.668224 -113.018934) (xy 97.632533 -112.977743) (xy 97.603067 -112.931893)
			(xy 97.580425 -112.882316) (xy 97.56507 -112.830021) (xy 97.557314 -112.776073) (xy 97.556828 -112.748822)
			(xy 97.557301 -112.722508) (xy 97.564534 -112.67038) (xy 97.578851 -112.619737) (xy 97.599982 -112.571537)
			(xy 97.627528 -112.526694) (xy 97.660966 -112.486054) (xy 97.680018 -112.467898) (xy 97.687425 -112.460382)
			(xy 97.695946 -112.441097) (xy 97.696528 -112.43056) (xy 97.696528 -112.355884) (xy 97.696013 -112.345333)
			(xy 97.687467 -112.326038) (xy 97.680018 -112.318546) (xy 97.65925 -112.298705) (xy 97.623272 -112.253937)
			(xy 97.594409 -112.204283) (xy 97.573313 -112.150863) (xy 97.560461 -112.094886) (xy 97.556142 -112.037615)
			(xy 95.762829 -112.037615) (xy 95.794277 -112.075815) (xy 95.821832 -112.12066) (xy 95.842966 -112.168866)
			(xy 95.857278 -112.219517) (xy 95.864498 -112.271655) (xy 95.864934 -112.297972) (xy 95.864448 -112.325223)
			(xy 95.856692 -112.379171) (xy 95.841337 -112.431466) (xy 95.818695 -112.481043) (xy 95.789229 -112.526893)
			(xy 95.753538 -112.568084) (xy 95.712347 -112.603775) (xy 95.666497 -112.633241) (xy 95.61692 -112.655883)
			(xy 95.564625 -112.671238) (xy 95.510677 -112.678994) (xy 95.456175 -112.678994) (xy 95.402227 -112.671238)
			(xy 95.349932 -112.655883) (xy 95.300355 -112.633241) (xy 95.254505 -112.603775) (xy 95.213314 -112.568084)
			(xy 95.177623 -112.526893) (xy 95.148157 -112.481043) (xy 95.125515 -112.431466) (xy 95.11016 -112.379171)
			(xy 95.102404 -112.325223) (xy 95.101918 -112.297972) (xy 93.832934 -112.297972) (xy 93.832448 -112.325223)
			(xy 93.824692 -112.379171) (xy 93.809337 -112.431466) (xy 93.786695 -112.481043) (xy 93.757229 -112.526893)
			(xy 93.721538 -112.568084) (xy 93.680347 -112.603775) (xy 93.634497 -112.633241) (xy 93.58492 -112.655883)
			(xy 93.532625 -112.671238) (xy 93.478677 -112.678994) (xy 93.424175 -112.678994) (xy 93.370227 -112.671238)
			(xy 93.317932 -112.655883) (xy 93.268355 -112.633241) (xy 93.222505 -112.603775) (xy 93.181314 -112.568084)
			(xy 93.145623 -112.526893) (xy 93.116157 -112.481043) (xy 93.093515 -112.431466) (xy 93.07816 -112.379171)
			(xy 93.070404 -112.325223) (xy 93.069918 -112.297972) (xy 91.309978 -112.297972) (xy 91.316519 -112.321119)
			(xy 91.32374 -112.373255) (xy 91.324176 -112.399572) (xy 91.32369 -112.426823) (xy 91.315934 -112.480771)
			(xy 91.300579 -112.533066) (xy 91.277937 -112.582643) (xy 91.248471 -112.628493) (xy 91.21278 -112.669684)
			(xy 91.171589 -112.705375) (xy 91.125739 -112.734841) (xy 91.076162 -112.757483) (xy 91.023867 -112.772838)
			(xy 90.969919 -112.780594) (xy 90.915417 -112.780594) (xy 90.861469 -112.772838) (xy 90.809174 -112.757483)
			(xy 90.759597 -112.734841) (xy 90.713747 -112.705375) (xy 90.672556 -112.669684) (xy 90.636865 -112.628493)
			(xy 90.607399 -112.582643) (xy 90.584757 -112.533066) (xy 90.569402 -112.480771) (xy 90.561646 -112.426823)
			(xy 90.56116 -112.399572) (xy 72.584372 -112.399572) (xy 72.602002 -112.440343) (xy 72.615951 -112.49034)
			(xy 72.62299 -112.541767) (xy 72.623426 -112.56772) (xy 72.62294 -112.594971) (xy 72.615184 -112.648919)
			(xy 72.599829 -112.701214) (xy 72.577187 -112.750791) (xy 72.547721 -112.796641) (xy 72.51203 -112.837832)
			(xy 72.470839 -112.873523) (xy 72.424989 -112.902989) (xy 72.375412 -112.925631) (xy 72.323117 -112.940986)
			(xy 72.269169 -112.948742) (xy 72.214667 -112.948742) (xy 72.160719 -112.940986) (xy 72.108424 -112.925631)
			(xy 72.058847 -112.902989) (xy 72.012997 -112.873523) (xy 71.971806 -112.837832) (xy 71.936115 -112.796641)
			(xy 71.906649 -112.750791) (xy 71.884007 -112.701214) (xy 71.868652 -112.648919) (xy 71.860896 -112.594971)
			(xy 71.86041 -112.56772) (xy 71.860974 -112.537926) (xy 71.870236 -112.479062) (xy 71.888537 -112.422354)
			(xy 71.915432 -112.369181) (xy 71.950268 -112.320836) (xy 71.992197 -112.278495) (xy 72.015858 -112.26038)
			(xy 72.022627 -112.255011) (xy 72.032359 -112.240747) (xy 72.036784 -112.224056) (xy 72.036432 -112.215422)
			(xy 72.029828 -112.12957) (xy 72.028899 -112.121058) (xy 72.022131 -112.105341) (xy 72.010549 -112.092745)
			(xy 72.003158 -112.088422) (xy 72.002904 -112.088422) (xy 71.980101 -112.076023) (xy 71.937808 -112.04593)
			(xy 71.899988 -112.010379) (xy 71.867339 -111.970027) (xy 71.840465 -111.92562) (xy 71.819863 -111.877978)
			(xy 71.805912 -111.827981) (xy 71.798872 -111.776555) (xy 71.798434 -111.750602) (xy 71.798888 -111.723581)
			(xy 71.806502 -111.670079) (xy 71.821593 -111.618188) (xy 71.843858 -111.568946) (xy 71.872851 -111.523341)
			(xy 71.907992 -111.482285) (xy 71.927974 -111.46409) (xy 71.935944 -111.456444) (xy 71.944884 -111.436269)
			(xy 71.945246 -111.425228) (xy 71.943976 -111.348012) (xy 71.943307 -111.337001) (xy 71.93382 -111.317112)
			(xy 71.925688 -111.309658) (xy 71.904537 -111.291448) (xy 71.867263 -111.249907) (xy 71.836442 -111.203377)
			(xy 71.812732 -111.152852) (xy 71.796638 -111.09941) (xy 71.788506 -111.044194) (xy 71.78802 -111.016288)
			(xy 67.907895 -111.016288) (xy 67.923262 -111.068346) (xy 67.931092 -111.122524) (xy 67.931093 -111.177264)
			(xy 67.923265 -111.231443) (xy 67.907769 -111.283944) (xy 67.884924 -111.33369) (xy 67.855199 -111.379658)
			(xy 67.837558 -111.40059) (xy 67.837304 -111.400844) (xy 67.831735 -111.407943) (xy 67.825478 -111.42485)
			(xy 67.825112 -111.433864) (xy 67.825112 -111.50092) (xy 67.825457 -111.509938) (xy 67.831713 -111.526855)
			(xy 67.837304 -111.53394) (xy 67.837558 -111.53394) (xy 67.837558 -111.534194) (xy 67.855201 -111.555123)
			(xy 67.884914 -111.601096) (xy 67.90775 -111.650844) (xy 67.92324 -111.703346) (xy 67.931066 -111.757522)
			(xy 67.931538 -111.784892) (xy 67.931075 -111.81191) (xy 67.923482 -111.86541) (xy 67.918026 -111.884206)
			(xy 70.364348 -111.884206) (xy 70.368419 -111.828584) (xy 70.380545 -111.774147) (xy 70.400468 -111.722056)
			(xy 70.427764 -111.673421) (xy 70.46185 -111.629278) (xy 70.501999 -111.590569) (xy 70.547357 -111.558118)
			(xy 70.596957 -111.532617) (xy 70.649741 -111.51461) (xy 70.704584 -111.50448) (xy 70.760318 -111.502443)
			(xy 70.815755 -111.508543) (xy 70.869712 -111.522649) (xy 70.921041 -111.544461) (xy 70.968647 -111.573515)
			(xy 71.011515 -111.60919) (xy 71.048732 -111.650727) (xy 71.079505 -111.69724) (xy 71.103177 -111.747737)
			(xy 71.119245 -111.801144) (xy 71.127365 -111.85632) (xy 71.127874 -111.884206) (xy 71.127365 -111.912092)
			(xy 71.119245 -111.967268) (xy 71.103177 -112.020675) (xy 71.079505 -112.071172) (xy 71.048732 -112.117685)
			(xy 71.011515 -112.159222) (xy 70.968647 -112.194897) (xy 70.921041 -112.223951) (xy 70.869712 -112.245763)
			(xy 70.815755 -112.259869) (xy 70.760318 -112.265969) (xy 70.704584 -112.263932) (xy 70.649741 -112.253802)
			(xy 70.596957 -112.235795) (xy 70.547357 -112.210294) (xy 70.501999 -112.177843) (xy 70.46185 -112.139134)
			(xy 70.427764 -112.094991) (xy 70.400468 -112.046356) (xy 70.380545 -111.994265) (xy 70.368419 -111.939828)
			(xy 70.364348 -111.884206) (xy 67.918026 -111.884206) (xy 67.908418 -111.917304) (xy 67.886185 -111.966554)
			(xy 67.872102 -111.989616) (xy 67.867475 -111.997573) (xy 67.86374 -112.015586) (xy 67.866616 -112.033756)
			(xy 67.870832 -112.04194) (xy 67.889203 -112.075273) (xy 67.918108 -112.14568) (xy 67.937638 -112.219241)
			(xy 67.947462 -112.294715) (xy 67.948048 -112.33277) (xy 67.948048 -112.421924) (xy 69.455028 -112.421924)
			(xy 69.459099 -112.366302) (xy 69.471225 -112.311865) (xy 69.491148 -112.259774) (xy 69.518444 -112.211139)
			(xy 69.55253 -112.166996) (xy 69.592679 -112.128287) (xy 69.638037 -112.095836) (xy 69.687637 -112.070335)
			(xy 69.740421 -112.052328) (xy 69.795264 -112.042198) (xy 69.850998 -112.040161) (xy 69.906435 -112.046261)
			(xy 69.960392 -112.060367) (xy 70.011721 -112.082179) (xy 70.059327 -112.111233) (xy 70.102195 -112.146908)
			(xy 70.139412 -112.188445) (xy 70.170185 -112.234958) (xy 70.193857 -112.285455) (xy 70.209925 -112.338862)
			(xy 70.218045 -112.394038) (xy 70.218554 -112.421924) (xy 70.218045 -112.44981) (xy 70.209925 -112.504986)
			(xy 70.193857 -112.558393) (xy 70.170185 -112.60889) (xy 70.139412 -112.655403) (xy 70.102195 -112.69694)
			(xy 70.059327 -112.732615) (xy 70.011721 -112.761669) (xy 69.960392 -112.783481) (xy 69.906435 -112.797587)
			(xy 69.850998 -112.803687) (xy 69.795264 -112.80165) (xy 69.740421 -112.79152) (xy 69.687637 -112.773513)
			(xy 69.638037 -112.748012) (xy 69.592679 -112.715561) (xy 69.55253 -112.676852) (xy 69.518444 -112.632709)
			(xy 69.491148 -112.584074) (xy 69.471225 -112.531983) (xy 69.459099 -112.477546) (xy 69.455028 -112.421924)
			(xy 67.948048 -112.421924) (xy 67.948048 -112.989614) (xy 70.44004 -112.989614) (xy 70.444111 -112.933992)
			(xy 70.456237 -112.879555) (xy 70.47616 -112.827464) (xy 70.503456 -112.778829) (xy 70.537542 -112.734686)
			(xy 70.577691 -112.695977) (xy 70.623049 -112.663526) (xy 70.672649 -112.638025) (xy 70.725433 -112.620018)
			(xy 70.780276 -112.609888) (xy 70.83601 -112.607851) (xy 70.891447 -112.613951) (xy 70.945404 -112.628057)
			(xy 70.996733 -112.649869) (xy 71.044339 -112.678923) (xy 71.087207 -112.714598) (xy 71.124424 -112.756135)
			(xy 71.155197 -112.802648) (xy 71.178869 -112.853145) (xy 71.194937 -112.906552) (xy 71.203057 -112.961728)
			(xy 71.203566 -112.989614) (xy 71.203057 -113.0175) (xy 71.194937 -113.072676) (xy 71.178869 -113.126083)
			(xy 71.155197 -113.17658) (xy 71.124424 -113.223093) (xy 71.090789 -113.260632) (xy 75.43876 -113.260632)
			(xy 75.442831 -113.20501) (xy 75.454957 -113.150573) (xy 75.47488 -113.098482) (xy 75.502176 -113.049847)
			(xy 75.536262 -113.005704) (xy 75.576411 -112.966995) (xy 75.621769 -112.934544) (xy 75.671369 -112.909043)
			(xy 75.724153 -112.891036) (xy 75.778996 -112.880906) (xy 75.83473 -112.878869) (xy 75.890167 -112.884969)
			(xy 75.944124 -112.899075) (xy 75.995453 -112.920887) (xy 76.043059 -112.949941) (xy 76.085927 -112.985616)
			(xy 76.123144 -113.027153) (xy 76.153917 -113.073666) (xy 76.177589 -113.124163) (xy 76.193657 -113.17757)
			(xy 76.201358 -113.229898) (xy 76.44206 -113.229898) (xy 76.446131 -113.174276) (xy 76.458257 -113.119839)
			(xy 76.47818 -113.067748) (xy 76.505476 -113.019113) (xy 76.539562 -112.97497) (xy 76.579711 -112.936261)
			(xy 76.625069 -112.90381) (xy 76.674669 -112.878309) (xy 76.727453 -112.860302) (xy 76.782296 -112.850172)
			(xy 76.83803 -112.848135) (xy 76.893467 -112.854235) (xy 76.947424 -112.868341) (xy 76.998753 -112.890153)
			(xy 77.046359 -112.919207) (xy 77.089227 -112.954882) (xy 77.126444 -112.996419) (xy 77.157217 -113.042932)
			(xy 77.180889 -113.093429) (xy 77.196957 -113.146836) (xy 77.205077 -113.202012) (xy 77.205586 -113.229898)
			(xy 77.205077 -113.257784) (xy 77.196957 -113.31296) (xy 77.180889 -113.366367) (xy 77.157217 -113.416864)
			(xy 77.126444 -113.463377) (xy 77.089227 -113.504914) (xy 77.046359 -113.540589) (xy 76.998753 -113.569643)
			(xy 76.947424 -113.591455) (xy 76.893467 -113.605561) (xy 76.83803 -113.611661) (xy 76.782296 -113.609624)
			(xy 76.727453 -113.599494) (xy 76.674669 -113.581487) (xy 76.625069 -113.555986) (xy 76.579711 -113.523535)
			(xy 76.539562 -113.484826) (xy 76.505476 -113.440683) (xy 76.47818 -113.392048) (xy 76.458257 -113.339957)
			(xy 76.446131 -113.28552) (xy 76.44206 -113.229898) (xy 76.201358 -113.229898) (xy 76.201777 -113.232746)
			(xy 76.202286 -113.260632) (xy 76.201777 -113.288518) (xy 76.193657 -113.343694) (xy 76.177589 -113.397101)
			(xy 76.153917 -113.447598) (xy 76.123144 -113.494111) (xy 76.085927 -113.535648) (xy 76.043059 -113.571323)
			(xy 75.995453 -113.600377) (xy 75.944124 -113.622189) (xy 75.890167 -113.636295) (xy 75.83473 -113.642395)
			(xy 75.778996 -113.640358) (xy 75.724153 -113.630228) (xy 75.671369 -113.612221) (xy 75.621769 -113.58672)
			(xy 75.576411 -113.554269) (xy 75.536262 -113.51556) (xy 75.502176 -113.471417) (xy 75.47488 -113.422782)
			(xy 75.454957 -113.370691) (xy 75.442831 -113.316254) (xy 75.43876 -113.260632) (xy 71.090789 -113.260632)
			(xy 71.087207 -113.26463) (xy 71.044339 -113.300305) (xy 70.996733 -113.329359) (xy 70.945404 -113.351171)
			(xy 70.891447 -113.365277) (xy 70.83601 -113.371377) (xy 70.780276 -113.36934) (xy 70.725433 -113.35921)
			(xy 70.672649 -113.341203) (xy 70.623049 -113.315702) (xy 70.577691 -113.283251) (xy 70.537542 -113.244542)
			(xy 70.503456 -113.200399) (xy 70.47616 -113.151764) (xy 70.456237 -113.099673) (xy 70.444111 -113.045236)
			(xy 70.44004 -112.989614) (xy 67.948048 -112.989614) (xy 67.948048 -113.385854) (xy 67.947621 -113.418709)
			(xy 67.945452 -113.437924) (xy 69.433946 -113.437924) (xy 69.438017 -113.382302) (xy 69.450143 -113.327865)
			(xy 69.470066 -113.275774) (xy 69.497362 -113.227139) (xy 69.531448 -113.182996) (xy 69.571597 -113.144287)
			(xy 69.616955 -113.111836) (xy 69.666555 -113.086335) (xy 69.719339 -113.068328) (xy 69.774182 -113.058198)
			(xy 69.829916 -113.056161) (xy 69.885353 -113.062261) (xy 69.93931 -113.076367) (xy 69.990639 -113.098179)
			(xy 70.038245 -113.127233) (xy 70.081113 -113.162908) (xy 70.11833 -113.204445) (xy 70.149103 -113.250958)
			(xy 70.172775 -113.301455) (xy 70.188843 -113.354862) (xy 70.196963 -113.410038) (xy 70.197472 -113.437924)
			(xy 70.196963 -113.46581) (xy 70.188843 -113.520986) (xy 70.172775 -113.574393) (xy 70.149103 -113.62489)
			(xy 70.11833 -113.671403) (xy 70.081113 -113.71294) (xy 70.038245 -113.748615) (xy 69.990639 -113.777669)
			(xy 69.93931 -113.799481) (xy 69.885353 -113.813587) (xy 69.829916 -113.819687) (xy 69.774182 -113.81765)
			(xy 69.719339 -113.80752) (xy 69.666555 -113.789513) (xy 69.616955 -113.764012) (xy 69.571597 -113.731561)
			(xy 69.531448 -113.692852) (xy 69.497362 -113.648709) (xy 69.470066 -113.600074) (xy 69.450143 -113.547983)
			(xy 69.438017 -113.493546) (xy 69.433946 -113.437924) (xy 67.945452 -113.437924) (xy 67.940251 -113.484003)
			(xy 67.925622 -113.548063) (xy 67.903918 -113.610085) (xy 67.87541 -113.669288) (xy 67.840457 -113.72493)
			(xy 67.799498 -113.776311) (xy 67.776598 -113.799874) (xy 67.727068 -113.849404) (xy 67.70348 -113.87231)
			(xy 67.65207 -113.913305) (xy 67.645837 -113.917222) (xy 70.793862 -113.917222) (xy 70.797933 -113.8616)
			(xy 70.810059 -113.807163) (xy 70.829982 -113.755072) (xy 70.857278 -113.706437) (xy 70.891364 -113.662294)
			(xy 70.931513 -113.623585) (xy 70.976871 -113.591134) (xy 71.026471 -113.565633) (xy 71.079255 -113.547626)
			(xy 71.134098 -113.537496) (xy 71.189832 -113.535459) (xy 71.245269 -113.541559) (xy 71.299226 -113.555665)
			(xy 71.350555 -113.577477) (xy 71.398161 -113.606531) (xy 71.441029 -113.642206) (xy 71.478246 -113.683743)
			(xy 71.509019 -113.730256) (xy 71.532691 -113.780753) (xy 71.544863 -113.82121) (xy 81.291938 -113.82121)
			(xy 81.2924 -113.794896) (xy 81.299634 -113.742766) (xy 81.313954 -113.692123) (xy 81.335087 -113.643924)
			(xy 81.362635 -113.599081) (xy 81.396075 -113.558442) (xy 81.415128 -113.540286) (xy 81.422527 -113.532762)
			(xy 81.431056 -113.513484) (xy 81.431638 -113.502948) (xy 81.431638 -113.428272) (xy 81.431072 -113.417727)
			(xy 81.422562 -113.398432) (xy 81.415128 -113.390934) (xy 81.396053 -113.372798) (xy 81.362596 -113.332165)
			(xy 81.335039 -113.287321) (xy 81.313904 -113.239116) (xy 81.299591 -113.188465) (xy 81.292373 -113.136327)
			(xy 81.291938 -113.11001) (xy 81.292424 -113.082759) (xy 81.30018 -113.028811) (xy 81.315535 -112.976516)
			(xy 81.338177 -112.926939) (xy 81.367643 -112.881089) (xy 81.403334 -112.839898) (xy 81.444525 -112.804207)
			(xy 81.490375 -112.774741) (xy 81.539952 -112.752099) (xy 81.592247 -112.736744) (xy 81.646195 -112.728988)
			(xy 81.700697 -112.728988) (xy 81.754645 -112.736744) (xy 81.80694 -112.752099) (xy 81.856517 -112.774741)
			(xy 81.902367 -112.804207) (xy 81.943558 -112.839898) (xy 81.979249 -112.881089) (xy 82.008715 -112.926939)
			(xy 82.031357 -112.976516) (xy 82.046712 -113.028811) (xy 82.054468 -113.082759) (xy 82.054954 -113.11001)
			(xy 82.054508 -113.136325) (xy 82.047271 -113.188455) (xy 82.032949 -113.239099) (xy 82.011812 -113.287298)
			(xy 81.984262 -113.332141) (xy 81.950818 -113.372779) (xy 81.931764 -113.390934) (xy 81.924355 -113.39845)
			(xy 81.915833 -113.417734) (xy 81.915254 -113.428272) (xy 81.915254 -113.502948) (xy 81.915812 -113.513494)
			(xy 81.924328 -113.532789) (xy 81.931764 -113.540286) (xy 81.950818 -113.558443) (xy 81.984273 -113.599074)
			(xy 82.01183 -113.643914) (xy 82.019518 -113.661444) (xy 87.870282 -113.661444) (xy 87.874353 -113.605822)
			(xy 87.886479 -113.551385) (xy 87.906402 -113.499294) (xy 87.933698 -113.450659) (xy 87.967784 -113.406516)
			(xy 88.007933 -113.367807) (xy 88.053291 -113.335356) (xy 88.102891 -113.309855) (xy 88.155675 -113.291848)
			(xy 88.210518 -113.281718) (xy 88.266252 -113.279681) (xy 88.321689 -113.285781) (xy 88.375646 -113.299887)
			(xy 88.426975 -113.321699) (xy 88.474581 -113.350753) (xy 88.517449 -113.386428) (xy 88.554666 -113.427965)
			(xy 88.585439 -113.474478) (xy 88.609111 -113.524975) (xy 88.625179 -113.578382) (xy 88.633299 -113.633558)
			(xy 88.633808 -113.661444) (xy 88.633299 -113.68933) (xy 88.625179 -113.744506) (xy 88.609111 -113.797913)
			(xy 88.585439 -113.84841) (xy 88.554666 -113.894923) (xy 88.517449 -113.93646) (xy 88.474581 -113.972135)
			(xy 88.426975 -114.001189) (xy 88.375646 -114.023001) (xy 88.321689 -114.037107) (xy 88.266252 -114.043207)
			(xy 88.210518 -114.04117) (xy 88.155675 -114.03104) (xy 88.102891 -114.013033) (xy 88.053291 -113.987532)
			(xy 88.007933 -113.955081) (xy 87.967784 -113.916372) (xy 87.933698 -113.872229) (xy 87.906402 -113.823594)
			(xy 87.886479 -113.771503) (xy 87.874353 -113.717066) (xy 87.870282 -113.661444) (xy 82.019518 -113.661444)
			(xy 82.032969 -113.692114) (xy 82.047287 -113.742761) (xy 82.054514 -113.794894) (xy 82.054954 -113.82121)
			(xy 82.054468 -113.848461) (xy 82.046712 -113.902409) (xy 82.031357 -113.954704) (xy 82.008715 -114.004281)
			(xy 81.979249 -114.050131) (xy 81.94935 -114.084637) (xy 89.449407 -114.084637) (xy 89.449409 -114.03014)
			(xy 89.457166 -113.976198) (xy 89.472521 -113.923908) (xy 89.495161 -113.874336) (xy 89.524626 -113.828491)
			(xy 89.560315 -113.787305) (xy 89.601502 -113.751618) (xy 89.647348 -113.722155) (xy 89.696921 -113.699517)
			(xy 89.749211 -113.684163) (xy 89.803153 -113.676408) (xy 89.830402 -113.675922) (xy 89.83091 -113.675922)
			(xy 89.854668 -113.676301) (xy 89.901812 -113.682246) (xy 89.947855 -113.693991) (xy 89.970102 -113.702338)
			(xy 89.982802 -113.707418) (xy 90.009472 -113.703354) (xy 90.088974 -113.640108) (xy 90.095629 -113.634331)
			(xy 90.10491 -113.619367) (xy 90.108586 -113.602146) (xy 90.10777 -113.593372) (xy 90.10777 -113.592864)
			(xy 90.105906 -113.579288) (xy 90.103869 -113.551957) (xy 90.103706 -113.538254) (xy 90.104135 -113.511001)
			(xy 90.111898 -113.45705) (xy 90.12726 -113.404754) (xy 90.149907 -113.355176) (xy 90.17938 -113.309325)
			(xy 90.215077 -113.268135) (xy 90.256273 -113.232444) (xy 90.302128 -113.202979) (xy 90.35171 -113.180339)
			(xy 90.404009 -113.164985) (xy 90.457961 -113.157231) (xy 90.485214 -113.156746) (xy 90.514129 -113.157309)
			(xy 90.571299 -113.166026) (xy 90.626498 -113.183274) (xy 90.67846 -113.208657) (xy 90.725995 -113.241594)
			(xy 90.768013 -113.281329) (xy 90.786204 -113.303812) (xy 90.793817 -113.312613) (xy 90.814713 -113.322799)
			(xy 90.826336 -113.32337) (xy 90.906092 -113.32337) (xy 90.917723 -113.322822) (xy 90.938633 -113.312641)
			(xy 90.946224 -113.303812) (xy 90.964405 -113.28132) (xy 91.006426 -113.241584) (xy 91.053963 -113.208646)
			(xy 91.105926 -113.183259) (xy 91.161126 -113.166005) (xy 91.218297 -113.157279) (xy 91.247214 -113.156746)
			(xy 91.274464 -113.157265) (xy 91.328408 -113.165022) (xy 91.380699 -113.180376) (xy 91.430273 -113.203016)
			(xy 91.476121 -113.232479) (xy 91.51731 -113.268167) (xy 91.553001 -113.309353) (xy 91.582469 -113.355199)
			(xy 91.605112 -113.404771) (xy 91.620471 -113.457061) (xy 91.628233 -113.511005) (xy 91.628722 -113.538254)
			(xy 91.628284 -113.565013) (xy 91.620797 -113.618004) (xy 91.605979 -113.669429) (xy 91.58412 -113.718279)
			(xy 91.555649 -113.763594) (xy 91.521125 -113.804487) (xy 91.481225 -113.840153) (xy 91.436732 -113.869894)
			(xy 91.412822 -113.881916) (xy 91.412568 -113.881916) (xy 91.40182 -113.888029) (xy 91.387212 -113.907926)
			(xy 91.384628 -113.920016) (xy 91.369642 -114.015012) (xy 91.37777 -114.03838) (xy 91.38666 -114.047016)
			(xy 91.396783 -114.05681) (xy 91.415729 -114.077656) (xy 91.424506 -114.088672) (xy 91.432057 -114.097444)
			(xy 91.452825 -114.107619) (xy 91.464384 -114.10823) (xy 91.544394 -114.10823) (xy 91.556027 -114.107697)
			(xy 91.576938 -114.097506) (xy 91.584526 -114.088672) (xy 91.602695 -114.06617) (xy 91.64472 -114.026437)
			(xy 91.69226 -113.993501) (xy 91.744225 -113.968116) (xy 91.799426 -113.950864) (xy 91.856599 -113.942139)
			(xy 91.885516 -113.941606) (xy 91.91276 -113.942085) (xy 91.966693 -113.949844) (xy 92.018972 -113.965201)
			(xy 92.068532 -113.987844) (xy 92.114365 -114.017312) (xy 92.155536 -114.053003) (xy 92.191206 -114.094193)
			(xy 92.206318 -114.116866) (xy 92.211162 -114.123894) (xy 92.224572 -114.134438) (xy 92.240712 -114.139963)
			(xy 92.249244 -114.140234) (xy 92.334588 -114.140234) (xy 92.34311 -114.139944) (xy 92.359221 -114.13438)
			(xy 92.37263 -114.123857) (xy 92.377514 -114.116866) (xy 92.392627 -114.094192) (xy 92.428293 -114.052996)
			(xy 92.469461 -114.017299) (xy 92.515293 -113.987828) (xy 92.564855 -113.965182) (xy 92.617136 -113.949825)
			(xy 92.671071 -113.942068) (xy 92.698316 -113.941606) (xy 92.729098 -113.942194) (xy 92.789861 -113.952087)
			(xy 92.848246 -113.971614) (xy 92.902735 -114.000267) (xy 92.927678 -114.018314) (xy 92.937584 -114.02568)
			(xy 92.961968 -114.029744) (xy 93.065092 -113.995962) (xy 93.082364 -113.978182) (xy 93.08592 -113.966244)
			(xy 93.093681 -113.941884) (xy 93.114774 -113.895314) (xy 93.1419 -113.851978) (xy 93.174571 -113.812654)
			(xy 93.193108 -113.795048) (xy 93.200536 -113.787549) (xy 93.209045 -113.768252) (xy 93.209618 -113.75771)
			(xy 93.209618 -113.683034) (xy 93.209079 -113.672486) (xy 93.20055 -113.653191) (xy 93.193108 -113.645696)
			(xy 93.174059 -113.627534) (xy 93.140601 -113.586906) (xy 93.113041 -113.542067) (xy 93.091901 -113.493867)
			(xy 93.077583 -113.443221) (xy 93.070357 -113.391088) (xy 93.069918 -113.364772) (xy 93.070404 -113.337521)
			(xy 93.07816 -113.283573) (xy 93.093515 -113.231278) (xy 93.116157 -113.181701) (xy 93.145623 -113.135851)
			(xy 93.181314 -113.09466) (xy 93.222505 -113.058969) (xy 93.268355 -113.029503) (xy 93.317932 -113.006861)
			(xy 93.370227 -112.991506) (xy 93.424175 -112.98375) (xy 93.478677 -112.98375) (xy 93.532625 -112.991506)
			(xy 93.58492 -113.006861) (xy 93.634497 -113.029503) (xy 93.680347 -113.058969) (xy 93.721538 -113.09466)
			(xy 93.757229 -113.135851) (xy 93.786695 -113.181701) (xy 93.809337 -113.231278) (xy 93.824692 -113.283573)
			(xy 93.832448 -113.337521) (xy 93.832934 -113.364772) (xy 93.832504 -113.391087) (xy 93.82526 -113.443217)
			(xy 93.810933 -113.49386) (xy 93.789793 -113.542058) (xy 93.762241 -113.586901) (xy 93.728798 -113.62754)
			(xy 93.709744 -113.645696) (xy 93.702349 -113.653223) (xy 93.693819 -113.672499) (xy 93.693234 -113.683034)
			(xy 93.693234 -113.75771) (xy 93.693734 -113.768263) (xy 93.702289 -113.787559) (xy 93.709744 -113.795048)
			(xy 93.728824 -113.813179) (xy 93.762277 -113.853815) (xy 93.789832 -113.89866) (xy 93.810966 -113.946866)
			(xy 93.825278 -113.997517) (xy 93.832498 -114.049655) (xy 93.832934 -114.075972) (xy 95.101918 -114.075972)
			(xy 95.102361 -114.049657) (xy 95.1096 -113.997527) (xy 95.123924 -113.946884) (xy 95.145061 -113.898685)
			(xy 95.172611 -113.853842) (xy 95.206054 -113.813204) (xy 95.225108 -113.795048) (xy 95.232536 -113.787549)
			(xy 95.241045 -113.768252) (xy 95.241618 -113.75771) (xy 95.241618 -113.683034) (xy 95.241079 -113.672486)
			(xy 95.23255 -113.653191) (xy 95.225108 -113.645696) (xy 95.206059 -113.627534) (xy 95.172601 -113.586906)
			(xy 95.145041 -113.542067) (xy 95.123901 -113.493867) (xy 95.109583 -113.443221) (xy 95.102357 -113.391088)
			(xy 95.101918 -113.364772) (xy 95.102404 -113.337521) (xy 95.11016 -113.283573) (xy 95.125515 -113.231278)
			(xy 95.148157 -113.181701) (xy 95.177623 -113.135851) (xy 95.213314 -113.09466) (xy 95.254505 -113.058969)
			(xy 95.300355 -113.029503) (xy 95.349932 -113.006861) (xy 95.402227 -112.991506) (xy 95.456175 -112.98375)
			(xy 95.510677 -112.98375) (xy 95.564625 -112.991506) (xy 95.61692 -113.006861) (xy 95.666497 -113.029503)
			(xy 95.712347 -113.058969) (xy 95.753538 -113.09466) (xy 95.789229 -113.135851) (xy 95.818695 -113.181701)
			(xy 95.841337 -113.231278) (xy 95.856692 -113.283573) (xy 95.864448 -113.337521) (xy 95.864934 -113.364772)
			(xy 95.864504 -113.391087) (xy 95.85726 -113.443217) (xy 95.842933 -113.49386) (xy 95.821793 -113.542058)
			(xy 95.805403 -113.568734) (xy 110.889794 -113.568734) (xy 110.893865 -113.513112) (xy 110.905991 -113.458675)
			(xy 110.925914 -113.406584) (xy 110.95321 -113.357949) (xy 110.987296 -113.313806) (xy 111.027445 -113.275097)
			(xy 111.072803 -113.242646) (xy 111.122403 -113.217145) (xy 111.175187 -113.199138) (xy 111.23003 -113.189008)
			(xy 111.285764 -113.186971) (xy 111.341201 -113.193071) (xy 111.395158 -113.207177) (xy 111.446487 -113.228989)
			(xy 111.494093 -113.258043) (xy 111.536961 -113.293718) (xy 111.574178 -113.335255) (xy 111.604951 -113.381768)
			(xy 111.628623 -113.432265) (xy 111.644691 -113.485672) (xy 111.652811 -113.540848) (xy 111.653227 -113.563654)
			(xy 112.947448 -113.563654) (xy 112.951519 -113.508032) (xy 112.963645 -113.453595) (xy 112.983568 -113.401504)
			(xy 113.010864 -113.352869) (xy 113.04495 -113.308726) (xy 113.085099 -113.270017) (xy 113.130457 -113.237566)
			(xy 113.180057 -113.212065) (xy 113.232841 -113.194058) (xy 113.287684 -113.183928) (xy 113.343418 -113.181891)
			(xy 113.398855 -113.187991) (xy 113.452812 -113.202097) (xy 113.504141 -113.223909) (xy 113.551747 -113.252963)
			(xy 113.594615 -113.288638) (xy 113.631832 -113.330175) (xy 113.660435 -113.373408) (xy 129.16357 -113.373408)
			(xy 129.167641 -113.317786) (xy 129.179767 -113.263349) (xy 129.19969 -113.211258) (xy 129.226986 -113.162623)
			(xy 129.261072 -113.11848) (xy 129.301221 -113.079771) (xy 129.346579 -113.04732) (xy 129.396179 -113.021819)
			(xy 129.448963 -113.003812) (xy 129.503806 -112.993682) (xy 129.55954 -112.991645) (xy 129.614977 -112.997745)
			(xy 129.668934 -113.011851) (xy 129.720263 -113.033663) (xy 129.767869 -113.062717) (xy 129.810737 -113.098392)
			(xy 129.847954 -113.139929) (xy 129.878727 -113.186442) (xy 129.902399 -113.236939) (xy 129.918467 -113.290346)
			(xy 129.926587 -113.345522) (xy 129.927096 -113.373408) (xy 129.926587 -113.401294) (xy 129.918467 -113.45647)
			(xy 129.902399 -113.509877) (xy 129.878727 -113.560374) (xy 129.847954 -113.606887) (xy 129.810737 -113.648424)
			(xy 129.767869 -113.684099) (xy 129.720263 -113.713153) (xy 129.668934 -113.734965) (xy 129.614977 -113.749071)
			(xy 129.55954 -113.755171) (xy 129.503806 -113.753134) (xy 129.448963 -113.743004) (xy 129.396179 -113.724997)
			(xy 129.346579 -113.699496) (xy 129.301221 -113.667045) (xy 129.261072 -113.628336) (xy 129.226986 -113.584193)
			(xy 129.19969 -113.535558) (xy 129.179767 -113.483467) (xy 129.167641 -113.42903) (xy 129.16357 -113.373408)
			(xy 113.660435 -113.373408) (xy 113.662605 -113.376688) (xy 113.686277 -113.427185) (xy 113.702345 -113.480592)
			(xy 113.710465 -113.535768) (xy 113.710974 -113.563654) (xy 113.710465 -113.59154) (xy 113.702345 -113.646716)
			(xy 113.686277 -113.700123) (xy 113.662605 -113.75062) (xy 113.631832 -113.797133) (xy 113.594615 -113.83867)
			(xy 113.551747 -113.874345) (xy 113.504141 -113.903399) (xy 113.487751 -113.910364) (xy 126.053086 -113.910364)
			(xy 126.057157 -113.854742) (xy 126.069283 -113.800305) (xy 126.089206 -113.748214) (xy 126.116502 -113.699579)
			(xy 126.150588 -113.655436) (xy 126.190737 -113.616727) (xy 126.236095 -113.584276) (xy 126.285695 -113.558775)
			(xy 126.338479 -113.540768) (xy 126.393322 -113.530638) (xy 126.449056 -113.528601) (xy 126.504493 -113.534701)
			(xy 126.55845 -113.548807) (xy 126.609779 -113.570619) (xy 126.657385 -113.599673) (xy 126.700253 -113.635348)
			(xy 126.73747 -113.676885) (xy 126.768243 -113.723398) (xy 126.791915 -113.773895) (xy 126.807983 -113.827302)
			(xy 126.816103 -113.882478) (xy 126.816394 -113.898426) (xy 127.55321 -113.898426) (xy 127.557281 -113.842804)
			(xy 127.569407 -113.788367) (xy 127.58933 -113.736276) (xy 127.616626 -113.687641) (xy 127.650712 -113.643498)
			(xy 127.690861 -113.604789) (xy 127.736219 -113.572338) (xy 127.785819 -113.546837) (xy 127.838603 -113.52883)
			(xy 127.893446 -113.5187) (xy 127.94918 -113.516663) (xy 128.004617 -113.522763) (xy 128.058574 -113.536869)
			(xy 128.109903 -113.558681) (xy 128.157509 -113.587735) (xy 128.200377 -113.62341) (xy 128.237594 -113.664947)
			(xy 128.268367 -113.71146) (xy 128.292039 -113.761957) (xy 128.308107 -113.815364) (xy 128.316227 -113.87054)
			(xy 128.316736 -113.898426) (xy 128.316227 -113.926312) (xy 128.308107 -113.981488) (xy 128.292039 -114.034895)
			(xy 128.268367 -114.085392) (xy 128.237594 -114.131905) (xy 128.200377 -114.173442) (xy 128.157509 -114.209117)
			(xy 128.109903 -114.238171) (xy 128.058574 -114.259983) (xy 128.004617 -114.274089) (xy 127.94918 -114.280189)
			(xy 127.893446 -114.278152) (xy 127.838603 -114.268022) (xy 127.785819 -114.250015) (xy 127.736219 -114.224514)
			(xy 127.690861 -114.192063) (xy 127.650712 -114.153354) (xy 127.616626 -114.109211) (xy 127.58933 -114.060576)
			(xy 127.569407 -114.008485) (xy 127.557281 -113.954048) (xy 127.55321 -113.898426) (xy 126.816394 -113.898426)
			(xy 126.816612 -113.910364) (xy 126.816103 -113.93825) (xy 126.807983 -113.993426) (xy 126.791915 -114.046833)
			(xy 126.768243 -114.09733) (xy 126.73747 -114.143843) (xy 126.700253 -114.18538) (xy 126.657385 -114.221055)
			(xy 126.609779 -114.250109) (xy 126.55845 -114.271921) (xy 126.504493 -114.286027) (xy 126.449056 -114.292127)
			(xy 126.393322 -114.29009) (xy 126.338479 -114.27996) (xy 126.285695 -114.261953) (xy 126.236095 -114.236452)
			(xy 126.190737 -114.204001) (xy 126.150588 -114.165292) (xy 126.116502 -114.121149) (xy 126.089206 -114.072514)
			(xy 126.069283 -114.020423) (xy 126.057157 -113.965986) (xy 126.053086 -113.910364) (xy 113.487751 -113.910364)
			(xy 113.452812 -113.925211) (xy 113.398855 -113.939317) (xy 113.343418 -113.945417) (xy 113.287684 -113.94338)
			(xy 113.232841 -113.93325) (xy 113.180057 -113.915243) (xy 113.130457 -113.889742) (xy 113.085099 -113.857291)
			(xy 113.04495 -113.818582) (xy 113.010864 -113.774439) (xy 112.983568 -113.725804) (xy 112.963645 -113.673713)
			(xy 112.951519 -113.619276) (xy 112.947448 -113.563654) (xy 111.653227 -113.563654) (xy 111.65332 -113.568734)
			(xy 111.652811 -113.59662) (xy 111.644691 -113.651796) (xy 111.628623 -113.705203) (xy 111.604951 -113.7557)
			(xy 111.574178 -113.802213) (xy 111.536961 -113.84375) (xy 111.494093 -113.879425) (xy 111.446487 -113.908479)
			(xy 111.395158 -113.930291) (xy 111.341201 -113.944397) (xy 111.285764 -113.950497) (xy 111.23003 -113.94846)
			(xy 111.175187 -113.93833) (xy 111.122403 -113.920323) (xy 111.072803 -113.894822) (xy 111.027445 -113.862371)
			(xy 110.987296 -113.823662) (xy 110.95321 -113.779519) (xy 110.925914 -113.730884) (xy 110.905991 -113.678793)
			(xy 110.893865 -113.624356) (xy 110.889794 -113.568734) (xy 95.805403 -113.568734) (xy 95.794241 -113.586901)
			(xy 95.760798 -113.62754) (xy 95.741744 -113.645696) (xy 95.734349 -113.653223) (xy 95.725819 -113.672499)
			(xy 95.725234 -113.683034) (xy 95.725234 -113.75771) (xy 95.725734 -113.768263) (xy 95.734289 -113.787559)
			(xy 95.741744 -113.795048) (xy 95.760824 -113.813179) (xy 95.794277 -113.853815) (xy 95.821832 -113.89866)
			(xy 95.842966 -113.946866) (xy 95.857278 -113.997517) (xy 95.864498 -114.049655) (xy 95.864934 -114.075972)
			(xy 95.864448 -114.103223) (xy 95.856692 -114.157171) (xy 95.841337 -114.209466) (xy 95.818695 -114.259043)
			(xy 95.789229 -114.304893) (xy 95.753538 -114.346084) (xy 95.712347 -114.381775) (xy 95.666497 -114.411241)
			(xy 95.61692 -114.433883) (xy 95.564625 -114.449238) (xy 95.510677 -114.456994) (xy 95.456175 -114.456994)
			(xy 95.402227 -114.449238) (xy 95.349932 -114.433883) (xy 95.300355 -114.411241) (xy 95.254505 -114.381775)
			(xy 95.213314 -114.346084) (xy 95.177623 -114.304893) (xy 95.148157 -114.259043) (xy 95.125515 -114.209466)
			(xy 95.11016 -114.157171) (xy 95.102404 -114.103223) (xy 95.101918 -114.075972) (xy 93.832934 -114.075972)
			(xy 93.832419 -114.103223) (xy 93.824666 -114.157171) (xy 93.809315 -114.209466) (xy 93.786678 -114.259044)
			(xy 93.757215 -114.304896) (xy 93.721527 -114.346089) (xy 93.68034 -114.381783) (xy 93.634492 -114.411252)
			(xy 93.584917 -114.433896) (xy 93.532624 -114.449255) (xy 93.478677 -114.457015) (xy 93.451426 -114.45748)
			(xy 93.420645 -114.456873) (xy 93.359882 -114.446986) (xy 93.301498 -114.427465) (xy 93.247008 -114.398817)
			(xy 93.222064 -114.380772) (xy 93.212158 -114.373406) (xy 93.187774 -114.369342) (xy 93.08465 -114.403124)
			(xy 93.067378 -114.420904) (xy 93.063822 -114.432842) (xy 93.055602 -114.458699) (xy 93.032782 -114.507923)
			(xy 93.003219 -114.553419) (xy 92.96751 -114.59427) (xy 92.926376 -114.629651) (xy 92.880645 -114.658849)
			(xy 92.83124 -114.681275) (xy 92.779157 -114.696478) (xy 92.725445 -114.704151) (xy 92.698316 -114.704622)
			(xy 92.671073 -114.704106) (xy 92.617143 -114.696352) (xy 92.564865 -114.681) (xy 92.515305 -114.658363)
			(xy 92.469473 -114.628902) (xy 92.4283 -114.593216) (xy 92.392627 -114.552033) (xy 92.377514 -114.529362)
			(xy 92.372644 -114.522355) (xy 92.359246 -114.511804) (xy 92.343116 -114.506271) (xy 92.334588 -114.505994)
			(xy 92.249244 -114.505994) (xy 92.240722 -114.506293) (xy 92.224611 -114.511851) (xy 92.211202 -114.522371)
			(xy 92.206318 -114.529362) (xy 92.191194 -114.552028) (xy 92.155528 -114.593222) (xy 92.114361 -114.628919)
			(xy 92.068531 -114.658391) (xy 92.018972 -114.681037) (xy 91.966693 -114.696397) (xy 91.91276 -114.704157)
			(xy 91.885516 -114.704622) (xy 91.856598 -114.704122) (xy 91.799425 -114.695393) (xy 91.744224 -114.678134)
			(xy 91.692262 -114.652739) (xy 91.644729 -114.619791) (xy 91.602714 -114.580044) (xy 91.584526 -114.557556)
			(xy 91.576905 -114.548763) (xy 91.556015 -114.538574) (xy 91.544394 -114.537998) (xy 91.464638 -114.537998)
			(xy 91.453004 -114.538516) (xy 91.432094 -114.54872) (xy 91.424506 -114.557556) (xy 91.4063 -114.580027)
			(xy 91.364285 -114.619765) (xy 91.316754 -114.652707) (xy 91.264795 -114.678098) (xy 91.209599 -114.695356)
			(xy 91.152431 -114.704087) (xy 91.123516 -114.704622) (xy 91.096264 -114.70413) (xy 91.042315 -114.696375)
			(xy 90.990019 -114.681022) (xy 90.940439 -114.658383) (xy 90.894587 -114.628917) (xy 90.853394 -114.593227)
			(xy 90.817701 -114.552037) (xy 90.788232 -114.506187) (xy 90.765588 -114.45661) (xy 90.750231 -114.404314)
			(xy 90.742472 -114.350366) (xy 90.742008 -114.323114) (xy 90.742459 -114.296356) (xy 90.749948 -114.243367)
			(xy 90.764767 -114.191945) (xy 90.786626 -114.143097) (xy 90.815095 -114.097782) (xy 90.849616 -114.056889)
			(xy 90.889512 -114.021221) (xy 90.934 -113.991476) (xy 90.957908 -113.979452) (xy 90.958162 -113.979452)
			(xy 90.968927 -113.973364) (xy 90.983526 -113.953449) (xy 90.986102 -113.941352) (xy 91.001088 -113.846356)
			(xy 90.99296 -113.822988) (xy 90.98407 -113.814352) (xy 90.973942 -113.804563) (xy 90.954999 -113.783714)
			(xy 90.946224 -113.772696) (xy 90.938648 -113.763949) (xy 90.9179 -113.753757) (xy 90.906346 -113.753138)
			(xy 90.826336 -113.753138) (xy 90.814699 -113.753642) (xy 90.793789 -113.763854) (xy 90.786204 -113.772696)
			(xy 90.76801 -113.795177) (xy 90.725991 -113.834912) (xy 90.678457 -113.867852) (xy 90.626496 -113.893241)
			(xy 90.571299 -113.910497) (xy 90.51413 -113.919227) (xy 90.485214 -113.919762) (xy 90.484706 -113.919762)
			(xy 90.460948 -113.919379) (xy 90.413804 -113.913436) (xy 90.367761 -113.901692) (xy 90.345514 -113.893346)
			(xy 90.332814 -113.888266) (xy 90.306144 -113.89233) (xy 90.226642 -113.955576) (xy 90.219982 -113.961347)
			(xy 90.210709 -113.976316) (xy 90.207033 -113.993537) (xy 90.207846 -114.002312) (xy 90.207846 -114.00282)
			(xy 90.209719 -114.016395) (xy 90.21175 -114.043727) (xy 90.21191 -114.05743) (xy 90.21139 -114.084679)
			(xy 90.20363 -114.138621) (xy 90.188272 -114.190909) (xy 90.16563 -114.24048) (xy 90.136163 -114.286324)
			(xy 90.100472 -114.327508) (xy 90.059283 -114.363193) (xy 90.013436 -114.392654) (xy 89.963862 -114.41529)
			(xy 89.911571 -114.430641) (xy 89.857628 -114.438393) (xy 89.803131 -114.43839) (xy 89.749189 -114.430632)
			(xy 89.6969 -114.415276) (xy 89.647328 -114.392634) (xy 89.601483 -114.363169) (xy 89.560299 -114.327479)
			(xy 89.524612 -114.286291) (xy 89.49515 -114.240444) (xy 89.472513 -114.19087) (xy 89.457161 -114.13858)
			(xy 89.449407 -114.084637) (xy 81.94935 -114.084637) (xy 81.943558 -114.091322) (xy 81.902367 -114.127013)
			(xy 81.856517 -114.156479) (xy 81.80694 -114.179121) (xy 81.754645 -114.194476) (xy 81.700697 -114.202232)
			(xy 81.646195 -114.202232) (xy 81.592247 -114.194476) (xy 81.539952 -114.179121) (xy 81.490375 -114.156479)
			(xy 81.444525 -114.127013) (xy 81.403334 -114.091322) (xy 81.367643 -114.050131) (xy 81.338177 -114.004281)
			(xy 81.315535 -113.954704) (xy 81.30018 -113.902409) (xy 81.292424 -113.848461) (xy 81.291938 -113.82121)
			(xy 71.544863 -113.82121) (xy 71.548759 -113.83416) (xy 71.556879 -113.889336) (xy 71.557388 -113.917222)
			(xy 71.556879 -113.945108) (xy 71.548759 -114.000284) (xy 71.532691 -114.053691) (xy 71.509019 -114.104188)
			(xy 71.478246 -114.150701) (xy 71.441029 -114.192238) (xy 71.398161 -114.227913) (xy 71.350555 -114.256967)
			(xy 71.299226 -114.278779) (xy 71.245269 -114.292885) (xy 71.189832 -114.298985) (xy 71.134098 -114.296948)
			(xy 71.079255 -114.286818) (xy 71.026471 -114.268811) (xy 70.976871 -114.24331) (xy 70.931513 -114.210859)
			(xy 70.891364 -114.17215) (xy 70.857278 -114.128007) (xy 70.829982 -114.079372) (xy 70.810059 -114.027281)
			(xy 70.797933 -113.972844) (xy 70.793862 -113.917222) (xy 67.645837 -113.917222) (xy 67.596398 -113.948292)
			(xy 67.537161 -113.976833) (xy 67.475105 -113.998569) (xy 67.411006 -114.013228) (xy 67.34567 -114.020626)
			(xy 67.312794 -114.021108) (xy 67.277382 -114.020549) (xy 67.207075 -114.012012) (xy 67.13831 -113.995063)
			(xy 67.072088 -113.969949) (xy 67.009377 -113.937036) (xy 66.95109 -113.896804) (xy 66.898077 -113.84984)
			(xy 66.851111 -113.796829) (xy 66.810877 -113.738544) (xy 66.777961 -113.675834) (xy 66.752844 -113.609613)
			(xy 66.735892 -113.540849) (xy 66.727352 -113.470542) (xy 66.726816 -113.43513) (xy 66.727832 -113.401094)
			(xy 66.690793 -113.390604) (xy 66.619628 -113.361249) (xy 66.552923 -113.322823) (xy 66.491827 -113.275989)
			(xy 66.46418 -113.249202) (xy 65.828926 -112.613948) (xy 65.806006 -112.590404) (xy 65.765044 -112.539023)
			(xy 65.730092 -112.48338) (xy 65.701589 -112.424172) (xy 65.679895 -112.362146) (xy 65.665281 -112.298082)
			(xy 65.657932 -112.232783) (xy 65.657476 -112.199928) (xy 65.657476 -111.25835) (xy 65.640458 -111.232696)
			(xy 65.62598 -111.226854) (xy 65.61658 -111.22354) (xy 65.596674 -111.22353) (xy 65.578265 -111.231106)
			(xy 65.570862 -111.237776) (xy 65.060322 -111.748316) (xy 65.036739 -111.771229) (xy 64.98533 -111.812225)
			(xy 64.929657 -111.847213) (xy 64.87042 -111.875754) (xy 64.808362 -111.89749) (xy 64.744262 -111.912147)
			(xy 64.678925 -111.919541) (xy 64.646048 -111.92002) (xy 64.61064 -111.919465) (xy 64.540341 -111.910932)
			(xy 64.471584 -111.893985) (xy 64.405371 -111.868871) (xy 64.34267 -111.835957) (xy 64.284395 -111.795722)
			(xy 64.231397 -111.748755) (xy 64.184448 -111.695739) (xy 64.144234 -111.63745) (xy 64.111343 -111.574737)
			(xy 64.086252 -111.508516) (xy 64.06933 -111.439752) (xy 64.060822 -111.36945) (xy 64.060324 -111.334042)
			(xy 64.060774 -111.30117) (xy 64.068118 -111.235838) (xy 64.082729 -111.171739) (xy 64.104425 -111.109679)
			(xy 64.132932 -111.050438) (xy 64.167891 -110.99476) (xy 64.208864 -110.943346) (xy 64.231774 -110.919768)
			(xy 64.255396 -110.896146) (xy 64.262232 -110.888777) (xy 64.269977 -110.870246) (xy 64.269979 -110.850161)
			(xy 64.262236 -110.831629) (xy 64.255396 -110.824264) (xy 64.251586 -110.820454) (xy 64.247014 -110.81766)
			(xy 64.22451 -110.802459) (xy 64.183602 -110.766743) (xy 64.148168 -110.725592) (xy 64.11892 -110.679836)
			(xy 64.096449 -110.630397) (xy 64.081209 -110.578275) (xy 64.073506 -110.524519) (xy 64.073024 -110.497366)
			(xy 64.073446 -110.470112) (xy 64.081208 -110.416161) (xy 64.096569 -110.363863) (xy 64.119217 -110.314283)
			(xy 64.14869 -110.268432) (xy 64.184388 -110.227241) (xy 64.225585 -110.19155) (xy 64.271441 -110.162085)
			(xy 64.321025 -110.139446) (xy 64.373325 -110.124094) (xy 64.427278 -110.116342) (xy 64.454532 -110.115858)
			(xy 64.482137 -110.116358) (xy 64.536771 -110.124308) (xy 64.589689 -110.140052) (xy 64.639783 -110.16326)
			(xy 64.686008 -110.193449) (xy 64.727398 -110.229986) (xy 64.745616 -110.250732) (xy 64.752474 -110.25886)
			(xy 64.77127 -110.268004) (xy 64.856614 -110.27156) (xy 64.867176 -110.271498) (xy 64.886855 -110.263886)
			(xy 64.894714 -110.256828) (xy 65.128394 -110.023148) (xy 65.135205 -110.015725) (xy 65.142942 -109.997143)
			(xy 65.14338 -109.98708) (xy 65.14338 -109.814106) (xy 65.142968 -109.803996) (xy 65.135083 -109.785375)
			(xy 65.120616 -109.771245) (xy 65.111376 -109.767116) (xy 65.009522 -109.726222) (xy 64.979042 -109.73308)
			(xy 64.968374 -109.744256) (xy 64.950266 -109.762624) (xy 64.910006 -109.794865) (xy 64.865773 -109.821393)
			(xy 64.818372 -109.841726) (xy 64.768665 -109.855493) (xy 64.717557 -109.862445) (xy 64.691768 -109.862874)
			(xy 64.664516 -109.862454) (xy 64.610567 -109.854693) (xy 64.558271 -109.839334) (xy 64.508694 -109.816689)
			(xy 64.462843 -109.787219) (xy 64.421653 -109.751524) (xy 64.385962 -109.710331) (xy 64.356496 -109.664478)
			(xy 64.333855 -109.614899) (xy 64.3185 -109.562602) (xy 64.310744 -109.508652) (xy 64.310744 -109.454148)
			(xy 64.3185 -109.400198) (xy 64.333855 -109.347901) (xy 64.356496 -109.298322) (xy 64.385962 -109.252469)
			(xy 64.421653 -109.211276) (xy 64.462843 -109.175581) (xy 64.508694 -109.146111) (xy 64.558271 -109.123466)
			(xy 64.610567 -109.108107) (xy 64.664516 -109.100346) (xy 64.691768 -109.099858) (xy 64.71756 -109.10025)
			(xy 64.768675 -109.107193) (xy 64.818389 -109.120958) (xy 64.865796 -109.141293) (xy 64.910032 -109.167828)
			(xy 64.950291 -109.200079) (xy 64.968374 -109.218476) (xy 64.979042 -109.229652) (xy 65.009522 -109.23651)
			(xy 65.111376 -109.195616) (xy 65.120589 -109.19146) (xy 65.135008 -109.177318) (xy 65.142886 -109.158721)
			(xy 65.14338 -109.148626) (xy 65.14338 -108.861606) (xy 65.142981 -108.852439) (xy 65.1365 -108.835288)
			(xy 65.124375 -108.821537) (xy 65.116456 -108.816902) (xy 65.036954 -108.774738) (xy 65.028667 -108.77082)
			(xy 65.010503 -108.768489) (xy 64.992688 -108.772726) (xy 64.984884 -108.777532) (xy 64.984376 -108.777532)
			(xy 64.96053 -108.793118) (xy 64.909219 -108.817858) (xy 64.854799 -108.834695) (xy 64.798481 -108.843253)
			(xy 64.77 -108.843826) (xy 64.74275 -108.843304) (xy 64.688805 -108.835548) (xy 64.636513 -108.820193)
			(xy 64.586938 -108.797553) (xy 64.54109 -108.768088) (xy 64.499901 -108.732399) (xy 64.464212 -108.69121)
			(xy 64.434747 -108.645362) (xy 64.412107 -108.595787) (xy 64.396752 -108.543495) (xy 64.388996 -108.48955)
			(xy 64.388996 -108.43505) (xy 64.396752 -108.381105) (xy 64.412107 -108.328813) (xy 64.434747 -108.279238)
			(xy 64.464212 -108.23339) (xy 64.499901 -108.192201) (xy 64.54109 -108.156512) (xy 64.586938 -108.127047)
			(xy 64.636513 -108.104407) (xy 64.688805 -108.089052) (xy 64.74275 -108.081296) (xy 64.77 -108.08081)
			(xy 64.798513 -108.081386) (xy 64.8549 -108.089915) (xy 64.909389 -108.10674) (xy 64.960769 -108.131485)
			(xy 64.98463 -108.147104) (xy 64.984884 -108.147104) (xy 64.992712 -108.151857) (xy 65.010516 -108.15608)
			(xy 65.028673 -108.153805) (xy 65.036954 -108.149898) (xy 65.116456 -108.107734) (xy 65.124357 -108.103086)
			(xy 65.136437 -108.089312) (xy 65.142945 -108.072187) (xy 65.14338 -108.06303) (xy 65.14338 -107.620054)
			(xy 65.11798 -107.591352) (xy 65.09893 -107.589066) (xy 65.07149 -107.585354) (xy 65.018051 -107.570846)
			(xy 64.967271 -107.548764) (xy 64.920217 -107.519573) (xy 64.877877 -107.483886) (xy 64.841141 -107.442453)
			(xy 64.810781 -107.396144) (xy 64.787435 -107.345932) (xy 64.771593 -107.292873) (xy 64.763589 -107.238081)
			(xy 64.76359 -107.182707) (xy 64.771596 -107.127916) (xy 64.787439 -107.074857) (xy 64.810787 -107.024646)
			(xy 64.841148 -106.978338) (xy 64.877885 -106.936906) (xy 64.920226 -106.90122) (xy 64.967281 -106.872031)
			(xy 65.018062 -106.84995) (xy 65.071502 -106.835443) (xy 65.09893 -106.831638) (xy 65.11798 -106.829352)
			(xy 65.14338 -106.80065) (xy 65.14338 -101.285548) (xy 65.143828 -101.252667) (xy 65.151191 -101.187319)
			(xy 65.16583 -101.123207) (xy 65.18756 -101.061139) (xy 65.216108 -101.001896) (xy 65.251114 -100.946226)
			(xy 65.292137 -100.894828) (xy 65.315084 -100.871274) (xy 68.429632 -97.756726) (xy 68.453185 -97.733816)
			(xy 68.504564 -97.692853) (xy 68.560206 -97.657899) (xy 68.619412 -97.629396) (xy 68.681436 -97.6077)
			(xy 68.7455 -97.593084) (xy 68.810797 -97.585733) (xy 68.843652 -97.585276) (xy 73.88098 -97.585276)
			(xy 73.892243 -97.584708) (xy 73.912614 -97.575093) (xy 73.926925 -97.557697) (xy 73.930256 -97.546922)
			(xy 73.930256 -97.546668) (xy 73.937612 -97.519589) (xy 73.959183 -97.467789) (xy 73.98811 -97.419708)
			(xy 74.023768 -97.376384) (xy 74.065389 -97.338751) (xy 74.112073 -97.307621) (xy 74.162815 -97.283666)
			(xy 74.216518 -97.267403) (xy 74.272024 -97.259182) (xy 74.328136 -97.259182) (xy 74.383642 -97.267403)
			(xy 74.437345 -97.283666) (xy 74.488087 -97.307621) (xy 74.534771 -97.338751) (xy 74.576392 -97.376384)
			(xy 74.61205 -97.419708) (xy 74.640977 -97.467789) (xy 74.662548 -97.519589) (xy 74.669904 -97.546668)
			(xy 74.669904 -97.546922) (xy 74.673235 -97.557693) (xy 74.687557 -97.57507) (xy 74.707921 -97.58468)
			(xy 74.71918 -97.585276) (xy 74.759058 -97.585276) (xy 74.76908 -97.584845) (xy 74.7876 -97.577185)
			(xy 74.801775 -97.563015) (xy 74.809442 -97.544497) (xy 74.809858 -97.534476) (xy 74.809858 -97.295716)
			(xy 74.809598 -97.287603) (xy 74.80454 -97.272187) (xy 74.799952 -97.26549) (xy 74.784482 -97.243566)
			(xy 74.759113 -97.196287) (xy 74.740624 -97.145917) (xy 74.729381 -97.093453) (xy 74.725605 -97.039931)
			(xy 74.729372 -96.986408) (xy 74.740607 -96.933942) (xy 74.759088 -96.883569) (xy 74.78445 -96.836286)
			(xy 74.799952 -96.814386) (xy 74.804523 -96.807683) (xy 74.809564 -96.792269) (xy 74.809858 -96.78416)
			(xy 74.809858 -94.36608) (xy 74.809454 -94.356008) (xy 74.80172 -94.33741) (xy 74.794872 -94.330012)
			(xy 73.308718 -92.843858) (xy 73.301311 -92.837027) (xy 73.282717 -92.829303) (xy 73.27265 -92.828872)
			(xy 72.623426 -92.828872) (xy 72.613403 -92.829258) (xy 72.594862 -92.836871) (xy 72.580666 -92.851019)
			(xy 72.576436 -92.860114) (xy 72.534526 -92.961206) (xy 72.540622 -92.991432) (xy 72.55129 -93.0021)
			(xy 72.583348 -93.03509) (xy 72.641541 -93.106341) (xy 72.692495 -93.182937) (xy 72.735723 -93.264143)
			(xy 72.770812 -93.349184) (xy 72.797425 -93.437246) (xy 72.815309 -93.527486) (xy 72.824292 -93.619042)
			(xy 72.824848 -93.66504) (xy 72.824291 -93.710119) (xy 72.815647 -93.799862) (xy 72.798461 -93.888368)
			(xy 72.772891 -93.974824) (xy 72.756522 -94.01683) (xy 72.752204 -94.027752) (xy 72.753728 -94.051374)
			(xy 72.806814 -94.14129) (xy 72.826626 -94.154244) (xy 72.83831 -94.155768) (xy 72.884272 -94.162013)
			(xy 72.975 -94.181326) (xy 73.06371 -94.20844) (xy 73.149733 -94.24315) (xy 73.232419 -94.285194)
			(xy 73.311144 -94.334254) (xy 73.385315 -94.389962) (xy 73.454372 -94.451896) (xy 73.517794 -94.519588)
			(xy 73.575102 -94.59253) (xy 73.625864 -94.670169) (xy 73.669698 -94.751921) (xy 73.706271 -94.837168)
			(xy 73.735309 -94.925267) (xy 73.756592 -95.015553) (xy 73.769959 -95.107346) (xy 73.775311 -95.199953)
			(xy 73.772605 -95.292675) (xy 73.761864 -95.384812) (xy 73.743168 -95.47567) (xy 73.716657 -95.564562)
			(xy 73.682532 -95.650819) (xy 73.641051 -95.733788) (xy 73.592527 -95.812845) (xy 73.537324 -95.887393)
			(xy 73.475861 -95.956869) (xy 73.408601 -96.020749) (xy 73.33605 -96.078552) (xy 73.258758 -96.12984)
			(xy 73.177306 -96.174228) (xy 73.092309 -96.21138) (xy 73.00441 -96.241015) (xy 72.914269 -96.262911)
			(xy 72.822569 -96.276902) (xy 72.730001 -96.282882) (xy 72.637263 -96.280807) (xy 72.545055 -96.270692)
			(xy 72.454072 -96.252613) (xy 72.365002 -96.226707) (xy 72.278516 -96.19317) (xy 72.195266 -96.152253)
			(xy 72.115881 -96.104267) (xy 72.04096 -96.049572) (xy 71.971068 -95.988582) (xy 71.906732 -95.921757)
			(xy 71.848438 -95.849601) (xy 71.796626 -95.772659) (xy 71.751686 -95.691511) (xy 71.713958 -95.606769)
			(xy 71.683726 -95.519072) (xy 71.661218 -95.429083) (xy 71.646604 -95.33748) (xy 71.639995 -95.244954)
			(xy 71.64144 -95.152204) (xy 71.650929 -95.05993) (xy 71.668389 -94.968826) (xy 71.693689 -94.879582)
			(xy 71.726638 -94.79287) (xy 71.746364 -94.75089) (xy 71.751952 -94.739206) (xy 71.750682 -94.713044)
			(xy 71.69785 -94.629224) (xy 71.692996 -94.622108) (xy 71.679527 -94.611382) (xy 71.663278 -94.605689)
			(xy 71.65467 -94.605348) (xy 70.03034 -94.605348) (xy 69.986892 -94.604768) (xy 69.900366 -94.596754)
			(xy 69.814949 -94.58079) (xy 69.731369 -94.557014) (xy 69.65034 -94.525627) (xy 69.572552 -94.486897)
			(xy 69.49867 -94.441155) (xy 69.429323 -94.388792) (xy 69.365103 -94.330253) (xy 69.306559 -94.266039)
			(xy 69.25419 -94.196696) (xy 69.208442 -94.122818) (xy 69.169706 -94.045033) (xy 69.138312 -93.964007)
			(xy 69.114528 -93.880429) (xy 69.098557 -93.795013) (xy 69.090536 -93.708488) (xy 69.090032 -93.66504)
			(xy 69.090618 -93.619044) (xy 69.0996 -93.52749) (xy 69.117483 -93.437253) (xy 69.144095 -93.349193)
			(xy 69.179182 -93.264155) (xy 69.222408 -93.18295) (xy 69.27336 -93.106356) (xy 69.33155 -93.035106)
			(xy 69.36359 -93.0021) (xy 69.374258 -92.991432) (xy 69.380354 -92.961206) (xy 69.338444 -92.860114)
			(xy 69.334159 -92.851066) (xy 69.319951 -92.836984) (xy 69.301456 -92.82936) (xy 69.291454 -92.828872)
			(xy 58.258456 -92.828872) (xy 58.225602 -92.828431) (xy 58.160308 -92.821063) (xy 58.096248 -92.806436)
			(xy 58.034227 -92.784734) (xy 57.975024 -92.756228) (xy 57.919382 -92.721278) (xy 57.868 -92.680321)
			(xy 57.844436 -92.657422) (xy 57.563512 -92.376498) (xy 57.556102 -92.36967) (xy 57.53751 -92.361944)
			(xy 57.527444 -92.361512) (xy 33.356804 -92.361512) (xy 33.346735 -92.361937) (xy 33.328137 -92.369658)
			(xy 33.320736 -92.376498) (xy 32.355536 -93.341698) (xy 32.332002 -93.364628) (xy 32.280619 -93.405589)
			(xy 32.224973 -93.440539) (xy 32.165764 -93.46904) (xy 32.103737 -93.490733) (xy 32.039671 -93.505345)
			(xy 31.974372 -93.512692) (xy 31.941516 -93.513148) (xy 31.941262 -93.513148) (xy 31.905857 -93.51268)
			(xy 31.835563 -93.504142) (xy 31.766811 -93.487197) (xy 31.700601 -93.46209) (xy 31.6379 -93.429187)
			(xy 31.57962 -93.388969) (xy 31.526611 -93.34202) (xy 31.479646 -93.289027) (xy 31.439409 -93.230759)
			(xy 31.406487 -93.168068) (xy 31.381359 -93.101867) (xy 31.364391 -93.03312) (xy 31.355832 -92.962829)
			(xy 31.355284 -92.927424) (xy 31.355744 -92.894544) (xy 31.363109 -92.829196) (xy 31.377747 -92.765086)
			(xy 31.399476 -92.703018) (xy 31.428021 -92.643776) (xy 31.463024 -92.588105) (xy 31.504043 -92.536705)
			(xy 31.526988 -92.51315) (xy 31.545784 -92.494354) (xy 31.552866 -92.486512) (xy 31.560472 -92.466822)
			(xy 31.560516 -92.456254) (xy 31.55696 -92.38107) (xy 31.555949 -92.370575) (xy 31.546639 -92.351682)
			(xy 31.538926 -92.344494) (xy 31.538926 -92.34424) (xy 31.538418 -92.34424) (xy 31.517181 -92.32603)
			(xy 31.479744 -92.284462) (xy 31.448791 -92.237865) (xy 31.424987 -92.187241) (xy 31.408844 -92.13368)
			(xy 31.40071 -92.078333) (xy 31.400242 -92.050362) (xy 31.400669 -92.023555) (xy 31.408196 -91.970472)
			(xy 31.423084 -91.918967) (xy 31.445038 -91.870054) (xy 31.473626 -91.824698) (xy 31.508284 -91.783792)
			(xy 31.528004 -91.765628) (xy 31.528258 -91.765374) (xy 31.534647 -91.75916) (xy 31.542975 -91.743418)
			(xy 31.544514 -91.73464) (xy 31.554674 -91.65971) (xy 31.55061 -91.64193) (xy 31.54553 -91.63431)
			(xy 31.537309 -91.621393) (xy 31.522059 -91.594837) (xy 31.51505 -91.581224) (xy 31.509462 -91.570302)
			(xy 31.489904 -91.556078) (xy 31.396432 -91.541092) (xy 31.38443 -91.539894) (xy 31.361512 -91.547311)
			(xy 31.35249 -91.555316) (xy 29.242863 -93.66504) (xy 46.475396 -93.66504) (xy 46.475918 -93.622772)
			(xy 46.483713 -93.538596) (xy 46.499241 -93.455498) (xy 46.522368 -93.374187) (xy 46.552899 -93.295356)
			(xy 46.590571 -93.219678) (xy 46.635065 -93.147798) (xy 46.686 -93.08033) (xy 46.742943 -93.017848)
			(xy 46.805406 -92.960886) (xy 46.872859 -92.909929) (xy 46.944724 -92.865413) (xy 47.02039 -92.827716)
			(xy 47.099211 -92.797161) (xy 47.180515 -92.774007) (xy 47.263608 -92.758453) (xy 47.347782 -92.750631)
			(xy 47.39005 -92.750132) (xy 49.29505 -92.750132) (xy 49.337307 -92.750586) (xy 49.421461 -92.758387)
			(xy 49.504537 -92.773917) (xy 49.585826 -92.797046) (xy 49.664634 -92.827574) (xy 49.740291 -92.865242)
			(xy 49.81215 -92.909728) (xy 49.879598 -92.960654) (xy 49.942062 -93.017584) (xy 49.999007 -93.080034)
			(xy 50.049949 -93.147471) (xy 50.094452 -93.219319) (xy 50.132138 -93.294966) (xy 50.162685 -93.373768)
			(xy 50.185833 -93.455051) (xy 50.201383 -93.538123) (xy 50.209204 -93.622275) (xy 50.209704 -93.664532)
			(xy 50.209704 -93.66504) (xy 50.209246 -93.707535) (xy 50.201361 -93.792158) (xy 50.185661 -93.875684)
			(xy 50.162283 -93.957395) (xy 50.131427 -94.036586) (xy 50.093361 -94.112574) (xy 50.048411 -94.184704)
			(xy 49.996965 -94.252354) (xy 49.939468 -94.314942) (xy 49.876414 -94.371928) (xy 49.808346 -94.42282)
			(xy 49.735853 -94.467181) (xy 49.659557 -94.504627) (xy 49.580118 -94.534836) (xy 49.498219 -94.557548)
			(xy 49.414567 -94.572566) (xy 49.372266 -94.576646) (xy 49.359729 -94.578304) (xy 49.338538 -94.592054)
			(xy 49.33188 -94.602808) (xy 49.29124 -94.676722) (xy 49.285744 -94.687991) (xy 49.285352 -94.713032)
			(xy 49.290478 -94.724474) (xy 49.311424 -94.766034) (xy 49.346856 -94.852101) (xy 49.37466 -94.940926)
			(xy 49.394626 -95.031834) (xy 49.406602 -95.124135) (xy 49.410496 -95.217129) (xy 49.40628 -95.310108)
			(xy 49.393985 -95.402367) (xy 49.373704 -95.493206) (xy 49.345592 -95.581934) (xy 49.309862 -95.667877)
			(xy 49.266786 -95.750384) (xy 49.21669 -95.828827) (xy 49.159955 -95.902611) (xy 49.097012 -95.971176)
			(xy 49.028338 -96.034) (xy 48.954456 -96.090607) (xy 48.875926 -96.140567) (xy 48.793345 -96.183501)
			(xy 48.70734 -96.219082) (xy 48.618563 -96.24704) (xy 48.52769 -96.267163) (xy 48.435409 -96.279298)
			(xy 48.342423 -96.283354) (xy 48.249437 -96.279298) (xy 48.157156 -96.267163) (xy 48.066283 -96.24704)
			(xy 47.977506 -96.219082) (xy 47.891501 -96.183501) (xy 47.80892 -96.140567) (xy 47.73039 -96.090607)
			(xy 47.656508 -96.034) (xy 47.587834 -95.971176) (xy 47.524891 -95.902611) (xy 47.468156 -95.828827)
			(xy 47.41806 -95.750384) (xy 47.374984 -95.667877) (xy 47.339254 -95.581934) (xy 47.311142 -95.493206)
			(xy 47.290861 -95.402367) (xy 47.278566 -95.310108) (xy 47.27435 -95.217129) (xy 47.278244 -95.124135)
			(xy 47.29022 -95.031834) (xy 47.310186 -94.940926) (xy 47.33799 -94.852101) (xy 47.373422 -94.766034)
			(xy 47.394368 -94.724474) (xy 47.399507 -94.713034) (xy 47.399112 -94.687989) (xy 47.393606 -94.676722)
			(xy 47.352966 -94.602808) (xy 47.346277 -94.592081) (xy 47.325105 -94.578338) (xy 47.31258 -94.576646)
			(xy 47.270293 -94.572507) (xy 47.186663 -94.55747) (xy 47.104788 -94.534743) (xy 47.025372 -94.504523)
			(xy 46.949101 -94.467069) (xy 46.876631 -94.422704) (xy 46.808588 -94.371811) (xy 46.745556 -94.314828)
			(xy 46.688079 -94.252245) (xy 46.636653 -94.184603) (xy 46.591721 -94.112484) (xy 46.553669 -94.03651)
			(xy 46.522826 -93.957334) (xy 46.499457 -93.87564) (xy 46.483763 -93.79213) (xy 46.475881 -93.707526)
			(xy 46.475396 -93.66504) (xy 29.242863 -93.66504) (xy 26.743617 -96.1644) (xy 37.225476 -96.1644)
			(xy 37.229547 -96.108778) (xy 37.241673 -96.054341) (xy 37.261596 -96.00225) (xy 37.288892 -95.953615)
			(xy 37.322978 -95.909472) (xy 37.363127 -95.870763) (xy 37.408485 -95.838312) (xy 37.458085 -95.812811)
			(xy 37.510869 -95.794804) (xy 37.565712 -95.784674) (xy 37.621446 -95.782637) (xy 37.676883 -95.788737)
			(xy 37.73084 -95.802843) (xy 37.782169 -95.824655) (xy 37.829775 -95.853709) (xy 37.872643 -95.889384)
			(xy 37.90986 -95.930921) (xy 37.940633 -95.977434) (xy 37.964305 -96.027931) (xy 37.980373 -96.081338)
			(xy 37.988493 -96.136514) (xy 37.989002 -96.1644) (xy 37.988493 -96.192286) (xy 37.980373 -96.247462)
			(xy 37.964305 -96.300869) (xy 37.940633 -96.351366) (xy 37.90986 -96.397879) (xy 37.872643 -96.439416)
			(xy 37.829775 -96.475091) (xy 37.782169 -96.504145) (xy 37.73084 -96.525957) (xy 37.676883 -96.540063)
			(xy 37.621446 -96.546163) (xy 37.565712 -96.544126) (xy 37.510869 -96.533996) (xy 37.458085 -96.515989)
			(xy 37.408485 -96.490488) (xy 37.363127 -96.458037) (xy 37.322978 -96.419328) (xy 37.288892 -96.375185)
			(xy 37.261596 -96.32655) (xy 37.241673 -96.274459) (xy 37.229547 -96.220022) (xy 37.225476 -96.1644)
			(xy 26.743617 -96.1644) (xy 25.793446 -97.114614) (xy 25.789341 -97.119017) (xy 25.783049 -97.129274)
			(xy 25.781 -97.134934) (xy 25.781 -97.135442) (xy 25.772576 -97.160995) (xy 25.763365 -97.1804) (xy 37.225476 -97.1804)
			(xy 37.229547 -97.124778) (xy 37.241673 -97.070341) (xy 37.261596 -97.01825) (xy 37.288892 -96.969615)
			(xy 37.322978 -96.925472) (xy 37.363127 -96.886763) (xy 37.408485 -96.854312) (xy 37.458085 -96.828811)
			(xy 37.510869 -96.810804) (xy 37.565712 -96.800674) (xy 37.621446 -96.798637) (xy 37.676883 -96.804737)
			(xy 37.73084 -96.818843) (xy 37.782169 -96.840655) (xy 37.829775 -96.869709) (xy 37.872643 -96.905384)
			(xy 37.90986 -96.946921) (xy 37.940633 -96.993434) (xy 37.964305 -97.043931) (xy 37.967842 -97.055686)
			(xy 51.605432 -97.055686) (xy 51.609503 -97.000064) (xy 51.621629 -96.945627) (xy 51.641552 -96.893536)
			(xy 51.668848 -96.844901) (xy 51.702934 -96.800758) (xy 51.743083 -96.762049) (xy 51.788441 -96.729598)
			(xy 51.838041 -96.704097) (xy 51.890825 -96.68609) (xy 51.945668 -96.67596) (xy 52.001402 -96.673923)
			(xy 52.056839 -96.680023) (xy 52.110796 -96.694129) (xy 52.162125 -96.715941) (xy 52.209731 -96.744995)
			(xy 52.252599 -96.78067) (xy 52.289816 -96.822207) (xy 52.320589 -96.86872) (xy 52.335721 -96.901)
			(xy 69.321932 -96.901) (xy 69.326003 -96.845378) (xy 69.338129 -96.790941) (xy 69.358052 -96.73885)
			(xy 69.385348 -96.690215) (xy 69.419434 -96.646072) (xy 69.459583 -96.607363) (xy 69.504941 -96.574912)
			(xy 69.554541 -96.549411) (xy 69.607325 -96.531404) (xy 69.662168 -96.521274) (xy 69.717902 -96.519237)
			(xy 69.773339 -96.525337) (xy 69.827296 -96.539443) (xy 69.878625 -96.561255) (xy 69.926231 -96.590309)
			(xy 69.969099 -96.625984) (xy 70.006316 -96.667521) (xy 70.037089 -96.714034) (xy 70.060761 -96.764531)
			(xy 70.076829 -96.817938) (xy 70.084949 -96.873114) (xy 70.085458 -96.901) (xy 71.773032 -96.901)
			(xy 71.777103 -96.845378) (xy 71.789229 -96.790941) (xy 71.809152 -96.73885) (xy 71.836448 -96.690215)
			(xy 71.870534 -96.646072) (xy 71.910683 -96.607363) (xy 71.956041 -96.574912) (xy 72.005641 -96.549411)
			(xy 72.058425 -96.531404) (xy 72.113268 -96.521274) (xy 72.169002 -96.519237) (xy 72.224439 -96.525337)
			(xy 72.278396 -96.539443) (xy 72.329725 -96.561255) (xy 72.377331 -96.590309) (xy 72.420199 -96.625984)
			(xy 72.457416 -96.667521) (xy 72.488189 -96.714034) (xy 72.511861 -96.764531) (xy 72.527929 -96.817938)
			(xy 72.536049 -96.873114) (xy 72.536558 -96.901) (xy 72.536049 -96.928886) (xy 72.527929 -96.984062)
			(xy 72.511861 -97.037469) (xy 72.488189 -97.087966) (xy 72.457416 -97.134479) (xy 72.420199 -97.176016)
			(xy 72.377331 -97.211691) (xy 72.329725 -97.240745) (xy 72.278396 -97.262557) (xy 72.224439 -97.276663)
			(xy 72.169002 -97.282763) (xy 72.113268 -97.280726) (xy 72.058425 -97.270596) (xy 72.005641 -97.252589)
			(xy 71.956041 -97.227088) (xy 71.910683 -97.194637) (xy 71.870534 -97.155928) (xy 71.836448 -97.111785)
			(xy 71.809152 -97.06315) (xy 71.789229 -97.011059) (xy 71.777103 -96.956622) (xy 71.773032 -96.901)
			(xy 70.085458 -96.901) (xy 70.084949 -96.928886) (xy 70.076829 -96.984062) (xy 70.060761 -97.037469)
			(xy 70.037089 -97.087966) (xy 70.006316 -97.134479) (xy 69.969099 -97.176016) (xy 69.926231 -97.211691)
			(xy 69.878625 -97.240745) (xy 69.827296 -97.262557) (xy 69.773339 -97.276663) (xy 69.717902 -97.282763)
			(xy 69.662168 -97.280726) (xy 69.607325 -97.270596) (xy 69.554541 -97.252589) (xy 69.504941 -97.227088)
			(xy 69.459583 -97.194637) (xy 69.419434 -97.155928) (xy 69.385348 -97.111785) (xy 69.358052 -97.06315)
			(xy 69.338129 -97.011059) (xy 69.326003 -96.956622) (xy 69.321932 -96.901) (xy 52.335721 -96.901)
			(xy 52.344261 -96.919217) (xy 52.360329 -96.972624) (xy 52.368449 -97.0278) (xy 52.368958 -97.055686)
			(xy 52.368449 -97.083572) (xy 52.360329 -97.138748) (xy 52.344261 -97.192155) (xy 52.320589 -97.242652)
			(xy 52.289816 -97.289165) (xy 52.252599 -97.330702) (xy 52.209731 -97.366377) (xy 52.162125 -97.395431)
			(xy 52.110796 -97.417243) (xy 52.056839 -97.431349) (xy 52.001402 -97.437449) (xy 51.945668 -97.435412)
			(xy 51.890825 -97.425282) (xy 51.838041 -97.407275) (xy 51.788441 -97.381774) (xy 51.743083 -97.349323)
			(xy 51.702934 -97.310614) (xy 51.668848 -97.266471) (xy 51.641552 -97.217836) (xy 51.621629 -97.165745)
			(xy 51.609503 -97.111308) (xy 51.605432 -97.055686) (xy 37.967842 -97.055686) (xy 37.980373 -97.097338)
			(xy 37.988493 -97.152514) (xy 37.989002 -97.1804) (xy 37.988493 -97.208286) (xy 37.980373 -97.263462)
			(xy 37.964305 -97.316869) (xy 37.940633 -97.367366) (xy 37.90986 -97.413879) (xy 37.872643 -97.455416)
			(xy 37.829775 -97.491091) (xy 37.782169 -97.520145) (xy 37.73084 -97.541957) (xy 37.676883 -97.556063)
			(xy 37.621446 -97.562163) (xy 37.565712 -97.560126) (xy 37.510869 -97.549996) (xy 37.458085 -97.531989)
			(xy 37.408485 -97.506488) (xy 37.363127 -97.474037) (xy 37.322978 -97.435328) (xy 37.288892 -97.391185)
			(xy 37.261596 -97.34255) (xy 37.241673 -97.290459) (xy 37.229547 -97.236022) (xy 37.225476 -97.1804)
			(xy 25.763365 -97.1804) (xy 25.749504 -97.209601) (xy 25.719832 -97.254483) (xy 25.684149 -97.294752)
			(xy 25.643162 -97.329608) (xy 25.597684 -97.358359) (xy 25.548618 -97.380435) (xy 25.496937 -97.395399)
			(xy 25.443666 -97.402954) (xy 25.416764 -97.403412) (xy 25.389512 -97.402956) (xy 25.335563 -97.395194)
			(xy 25.283268 -97.379835) (xy 25.233691 -97.35719) (xy 25.187841 -97.32772) (xy 25.146652 -97.292026)
			(xy 25.110961 -97.250833) (xy 25.081495 -97.204981) (xy 25.058854 -97.155402) (xy 25.043499 -97.103105)
			(xy 25.035742 -97.049156) (xy 25.035256 -97.021904) (xy 25.03579 -96.994996) (xy 25.043365 -96.941716)
			(xy 25.05835 -96.890029) (xy 25.08045 -96.84096) (xy 25.109225 -96.795483) (xy 25.144104 -96.7545)
			(xy 25.184395 -96.718824) (xy 25.229299 -96.689164) (xy 25.277925 -96.666106) (xy 25.30348 -96.657668)
			(xy 25.303734 -96.657668) (xy 25.309425 -96.655683) (xy 25.319701 -96.64939) (xy 25.324054 -96.645222)
			(xy 25.341072 -96.628204) (xy 25.341072 -96.58604) (xy 25.32634 -96.571308) (xy 25.321132 -96.566393)
			(xy 25.308622 -96.559435) (xy 25.301702 -96.557592) (xy 25.301448 -96.557592) (xy 25.266735 -96.5492)
			(xy 25.199512 -96.525086) (xy 25.135716 -96.492984) (xy 25.076291 -96.453371) (xy 25.022119 -96.406832)
			(xy 24.974001 -96.354057) (xy 24.932651 -96.295828) (xy 24.89868 -96.233007) (xy 24.885142 -96.19996)
			(xy 24.879808 -96.18599) (xy 24.856186 -96.168718) (xy 24.74976 -96.161606) (xy 24.740183 -96.16129)
			(xy 24.721916 -96.167038) (xy 24.707052 -96.179111) (xy 24.702008 -96.18726) (xy 24.687394 -96.212137)
			(xy 24.651828 -96.257566) (xy 24.609829 -96.297125) (xy 24.562355 -96.329912) (xy 24.510487 -96.355179)
			(xy 24.455407 -96.372353) (xy 24.39837 -96.38104) (xy 24.369522 -96.38157) (xy 24.342268 -96.381124)
			(xy 24.288314 -96.373369) (xy 24.236014 -96.358014) (xy 24.186431 -96.335371) (xy 24.140576 -96.305902)
			(xy 24.099382 -96.270206) (xy 24.063688 -96.229011) (xy 24.034221 -96.183155) (xy 24.01158 -96.133571)
			(xy 23.996227 -96.08127) (xy 23.988475 -96.027316) (xy 23.988014 -96.000062) (xy 23.988442 -95.97282)
			(xy 23.996197 -95.918892) (xy 24.011546 -95.866615) (xy 24.034174 -95.817053) (xy 24.063623 -95.771214)
			(xy 24.099293 -95.73003) (xy 24.140458 -95.694339) (xy 24.186282 -95.664867) (xy 24.235833 -95.642213)
			(xy 24.288102 -95.626839) (xy 24.342027 -95.619056) (xy 24.369268 -95.618554) (xy 24.369776 -95.618554)
			(xy 24.387302 -95.619062) (xy 24.387556 -95.619062) (xy 24.396952 -95.619026) (xy 24.414717 -95.612954)
			(xy 24.429114 -95.600904) (xy 24.434038 -95.5929) (xy 24.485346 -95.500444) (xy 24.483822 -95.471488)
			(xy 24.47544 -95.45955) (xy 24.455601 -95.430039) (xy 24.422419 -95.367145) (xy 24.397086 -95.3007)
			(xy 24.379974 -95.231679) (xy 24.371333 -95.161095) (xy 24.370792 -95.12554) (xy 24.37126 -95.09266)
			(xy 24.378623 -95.027313) (xy 24.39326 -94.963202) (xy 24.414988 -94.901135) (xy 24.443532 -94.841893)
			(xy 24.478533 -94.786221) (xy 24.519551 -94.734821) (xy 24.542496 -94.711266) (xy 29.838396 -89.415366)
			(xy 29.861973 -89.39248) (xy 29.913347 -89.351514) (xy 29.968984 -89.316557) (xy 30.028186 -89.28805)
			(xy 30.090207 -89.26635) (xy 30.154267 -89.25173) (xy 30.219562 -89.244375) (xy 30.252416 -89.243916)
			(xy 37.002466 -89.243916) (xy 37.012536 -89.243495) (xy 37.031135 -89.235774) (xy 37.038534 -89.22893)
			(xy 38.40353 -87.863934) (xy 38.410352 -87.85652) (xy 38.418081 -87.837931) (xy 38.418516 -87.827866)
			(xy 38.418516 -70.97268) (xy 38.418029 -70.962673) (xy 38.410366 -70.944184) (xy 38.396213 -70.930032)
			(xy 38.377723 -70.92237) (xy 38.367716 -70.92188) (xy 22.22119 -70.92188) (xy 22.211972 -70.922309)
			(xy 22.194715 -70.928794) (xy 22.180864 -70.940961) (xy 22.172207 -70.957237) (xy 22.170644 -70.96633)
			(xy 22.170644 -70.966584) (xy 22.166716 -70.993889) (xy 22.152009 -71.047054) (xy 22.129796 -71.097547)
			(xy 22.100541 -71.144314) (xy 22.064855 -71.186379) (xy 22.023482 -71.222864) (xy 21.977285 -71.25301)
			(xy 21.927227 -71.276186) (xy 21.874353 -71.29191) (xy 21.819765 -71.299854) (xy 21.792184 -71.30034)
			(xy 21.764934 -71.299837) (xy 21.710988 -71.292079) (xy 21.658696 -71.276724) (xy 21.609121 -71.254083)
			(xy 21.563272 -71.224618) (xy 21.522083 -71.188929) (xy 21.486391 -71.147741) (xy 21.456925 -71.101893)
			(xy 21.434282 -71.052319) (xy 21.418924 -71.000027) (xy 21.411164 -70.946082) (xy 21.410676 -70.918832)
			(xy 21.411087 -70.892671) (xy 21.41823 -70.840839) (xy 21.432387 -70.790468) (xy 21.453293 -70.742504)
			(xy 21.466556 -70.71995) (xy 21.472038 -70.709916) (xy 21.474486 -70.687217) (xy 21.466849 -70.665701)
			(xy 21.45919 -70.657212) (xy 19.944588 -69.142864) (xy 19.917942 -69.115275) (xy 19.870251 -69.055201)
			(xy 19.829558 -68.990182) (xy 19.79637 -68.921031) (xy 19.771104 -68.848609) (xy 19.754072 -68.773821)
			(xy 19.745489 -68.697599) (xy 19.744944 -68.659248) (xy 19.744944 -68.019422) (xy 19.745379 -67.984488)
			(xy 19.752514 -67.914985) (xy 19.766673 -67.846566) (xy 19.787708 -67.779939) (xy 19.815403 -67.715794)
			(xy 19.84947 -67.654794) (xy 19.889557 -67.59757) (xy 19.912076 -67.570858) (xy 19.91777 -67.563748)
			(xy 19.92413 -67.54669) (xy 19.924126 -67.528486) (xy 19.917757 -67.511431) (xy 19.912076 -67.50431)
			(xy 19.889574 -67.477585) (xy 19.849477 -67.420368) (xy 19.815403 -67.359372) (xy 19.787705 -67.295229)
			(xy 19.766671 -67.228603) (xy 19.752517 -67.160183) (xy 19.74539 -67.09068) (xy 19.744944 -67.055746)
			(xy 19.744944 -65.57518) (xy 19.744718 -65.566591) (xy 19.739336 -65.55029) (xy 19.728848 -65.536699)
			(xy 19.72183 -65.531746) (xy 19.695668 -65.514982) (xy 19.684828 -65.508735) (xy 19.659923 -65.506623)
			(xy 19.64817 -65.510918) (xy 19.624468 -65.520571) (xy 19.575124 -65.534145) (xy 19.524407 -65.540989)
			(xy 19.498818 -65.541398) (xy 19.498564 -65.541398) (xy 19.471311 -65.540935) (xy 19.41736 -65.533178)
			(xy 19.365061 -65.517823) (xy 19.315481 -65.49518) (xy 19.269627 -65.465713) (xy 19.228434 -65.430019)
			(xy 19.19274 -65.388826) (xy 19.163271 -65.342973) (xy 19.140629 -65.293392) (xy 19.125272 -65.241094)
			(xy 19.117515 -65.187143) (xy 6.865268 -65.187143) (xy 6.862325 -65.207138) (xy 6.846257 -65.260545)
			(xy 6.822585 -65.311042) (xy 6.791812 -65.357555) (xy 6.754595 -65.399092) (xy 6.711727 -65.434767)
			(xy 6.664121 -65.463821) (xy 6.612792 -65.485633) (xy 6.558835 -65.499739) (xy 6.503398 -65.505839)
			(xy 6.447664 -65.503802) (xy 6.392821 -65.493672) (xy 6.340037 -65.475665) (xy 6.290437 -65.450164)
			(xy 6.245079 -65.417713) (xy 6.20493 -65.379004) (xy 6.170844 -65.334861) (xy 6.143548 -65.286226)
			(xy 6.123625 -65.234135) (xy 6.111499 -65.179698) (xy 6.107428 -65.124076) (xy 2.033192 -65.124076)
			(xy 2.00787 -65.14084) (xy 1.998638 -65.148449) (xy 1.987891 -65.169787) (xy 1.987296 -65.181734)
			(xy 1.987296 -65.882774) (xy 3.101592 -65.882774) (xy 3.105663 -65.827152) (xy 3.117789 -65.772715)
			(xy 3.137712 -65.720624) (xy 3.165008 -65.671989) (xy 3.199094 -65.627846) (xy 3.239243 -65.589137)
			(xy 3.284601 -65.556686) (xy 3.334201 -65.531185) (xy 3.386985 -65.513178) (xy 3.441828 -65.503048)
			(xy 3.497562 -65.501011) (xy 3.552999 -65.507111) (xy 3.606956 -65.521217) (xy 3.658285 -65.543029)
			(xy 3.705891 -65.572083) (xy 3.748759 -65.607758) (xy 3.785976 -65.649295) (xy 3.816749 -65.695808)
			(xy 3.840421 -65.746305) (xy 3.843193 -65.75552) (xy 14.34668 -65.75552) (xy 14.350751 -65.699898)
			(xy 14.362877 -65.645461) (xy 14.3828 -65.59337) (xy 14.410096 -65.544735) (xy 14.444182 -65.500592)
			(xy 14.484331 -65.461883) (xy 14.529689 -65.429432) (xy 14.579289 -65.403931) (xy 14.632073 -65.385924)
			(xy 14.686916 -65.375794) (xy 14.74265 -65.373757) (xy 14.798087 -65.379857) (xy 14.852044 -65.393963)
			(xy 14.903373 -65.415775) (xy 14.950979 -65.444829) (xy 14.993847 -65.480504) (xy 15.031064 -65.522041)
			(xy 15.061837 -65.568554) (xy 15.085509 -65.619051) (xy 15.101577 -65.672458) (xy 15.109697 -65.727634)
			(xy 15.110206 -65.75552) (xy 15.109697 -65.783406) (xy 15.101577 -65.838582) (xy 15.085509 -65.891989)
			(xy 15.061837 -65.942486) (xy 15.031064 -65.988999) (xy 14.993847 -66.030536) (xy 14.950979 -66.066211)
			(xy 14.903373 -66.095265) (xy 14.852044 -66.117077) (xy 14.798087 -66.131183) (xy 14.74265 -66.137283)
			(xy 14.686916 -66.135246) (xy 14.632073 -66.125116) (xy 14.579289 -66.107109) (xy 14.529689 -66.081608)
			(xy 14.484331 -66.049157) (xy 14.444182 -66.010448) (xy 14.410096 -65.966305) (xy 14.3828 -65.91767)
			(xy 14.362877 -65.865579) (xy 14.350751 -65.811142) (xy 14.34668 -65.75552) (xy 3.843193 -65.75552)
			(xy 3.856489 -65.799712) (xy 3.864609 -65.854888) (xy 3.865118 -65.882774) (xy 3.864609 -65.91066)
			(xy 3.856489 -65.965836) (xy 3.840421 -66.019243) (xy 3.816749 -66.06974) (xy 3.785976 -66.116253)
			(xy 3.748759 -66.15779) (xy 3.705891 -66.193465) (xy 3.658285 -66.222519) (xy 3.606956 -66.244331)
			(xy 3.552999 -66.258437) (xy 3.497562 -66.264537) (xy 3.441828 -66.2625) (xy 3.386985 -66.25237)
			(xy 3.334201 -66.234363) (xy 3.284601 -66.208862) (xy 3.239243 -66.176411) (xy 3.199094 -66.137702)
			(xy 3.165008 -66.093559) (xy 3.137712 -66.044924) (xy 3.117789 -65.992833) (xy 3.105663 -65.938396)
			(xy 3.101592 -65.882774) (xy 1.987296 -65.882774) (xy 1.987296 -66.396616) (xy 1.988312 -66.406268)
			(xy 1.989941 -66.413511) (xy 1.996783 -66.426679) (xy 2.001774 -66.432176) (xy 2.13741 -66.567812)
			(xy 6.304532 -66.567812) (xy 6.308603 -66.51219) (xy 6.320729 -66.457753) (xy 6.340652 -66.405662)
			(xy 6.367948 -66.357027) (xy 6.402034 -66.312884) (xy 6.442183 -66.274175) (xy 6.487541 -66.241724)
			(xy 6.537141 -66.216223) (xy 6.589925 -66.198216) (xy 6.644768 -66.188086) (xy 6.700502 -66.186049)
			(xy 6.755939 -66.192149) (xy 6.809896 -66.206255) (xy 6.861225 -66.228067) (xy 6.908831 -66.257121)
			(xy 6.951699 -66.292796) (xy 6.988916 -66.334333) (xy 7.019689 -66.380846) (xy 7.043361 -66.431343)
			(xy 7.059429 -66.48475) (xy 7.067549 -66.539926) (xy 7.068058 -66.567812) (xy 7.067549 -66.595698)
			(xy 7.059429 -66.650874) (xy 7.043361 -66.704281) (xy 7.019689 -66.754778) (xy 6.988916 -66.801291)
			(xy 6.951699 -66.842828) (xy 6.908831 -66.878503) (xy 6.861225 -66.907557) (xy 6.809896 -66.929369)
			(xy 6.755939 -66.943475) (xy 6.700502 -66.949575) (xy 6.644768 -66.947538) (xy 6.589925 -66.937408)
			(xy 6.537141 -66.919401) (xy 6.487541 -66.8939) (xy 6.442183 -66.861449) (xy 6.402034 -66.82274)
			(xy 6.367948 -66.778597) (xy 6.340652 -66.729962) (xy 6.320729 -66.677871) (xy 6.308603 -66.623434)
			(xy 6.304532 -66.567812) (xy 2.13741 -66.567812) (xy 2.770632 -67.201034) (xy 4.242306 -67.201034)
			(xy 4.246377 -67.145412) (xy 4.258503 -67.090975) (xy 4.278426 -67.038884) (xy 4.305722 -66.990249)
			(xy 4.339808 -66.946106) (xy 4.379957 -66.907397) (xy 4.425315 -66.874946) (xy 4.474915 -66.849445)
			(xy 4.527699 -66.831438) (xy 4.582542 -66.821308) (xy 4.638276 -66.819271) (xy 4.693713 -66.825371)
			(xy 4.74767 -66.839477) (xy 4.798999 -66.861289) (xy 4.846605 -66.890343) (xy 4.889473 -66.926018)
			(xy 4.92669 -66.967555) (xy 4.957463 -67.014068) (xy 4.981135 -67.064565) (xy 4.997203 -67.117972)
			(xy 4.998822 -67.128971) (xy 14.366728 -67.128971) (xy 14.366728 -67.074469) (xy 14.374484 -67.020521)
			(xy 14.389839 -66.968227) (xy 14.41248 -66.91865) (xy 14.441946 -66.872799) (xy 14.477638 -66.831609)
			(xy 14.518828 -66.795918) (xy 14.564678 -66.766451) (xy 14.614255 -66.74381) (xy 14.666549 -66.728455)
			(xy 14.720497 -66.720698) (xy 14.747748 -66.720212) (xy 14.775117 -66.720706) (xy 14.829295 -66.728516)
			(xy 14.881798 -66.743999) (xy 14.931546 -66.766834) (xy 14.977514 -66.796553) (xy 14.998446 -66.814192)
			(xy 14.9987 -66.814446) (xy 15.005778 -66.820044) (xy 15.022702 -66.826283) (xy 15.03172 -66.826638)
			(xy 15.098776 -66.826638) (xy 15.107791 -66.826261) (xy 15.124707 -66.820026) (xy 15.131796 -66.814446)
			(xy 15.131796 -66.814192) (xy 15.13205 -66.814192) (xy 15.152989 -66.796562) (xy 15.19896 -66.766849)
			(xy 15.248706 -66.744011) (xy 15.301205 -66.728518) (xy 15.355379 -66.720687) (xy 15.382748 -66.720212)
			(xy 15.410001 -66.720675) (xy 15.463952 -66.728432) (xy 15.51625 -66.743788) (xy 15.565831 -66.76643)
			(xy 15.611684 -66.795898) (xy 15.652877 -66.831592) (xy 15.688571 -66.872784) (xy 15.718039 -66.918638)
			(xy 15.740682 -66.968218) (xy 15.756038 -67.020516) (xy 15.763795 -67.074467) (xy 15.763795 -67.128973)
			(xy 15.756038 -67.182924) (xy 15.740682 -67.235222) (xy 15.718039 -67.284802) (xy 15.688571 -67.330656)
			(xy 15.652877 -67.371848) (xy 15.611684 -67.407542) (xy 15.565831 -67.43701) (xy 15.51625 -67.459652)
			(xy 15.463952 -67.475008) (xy 15.410001 -67.482765) (xy 15.382748 -67.483228) (xy 15.355378 -67.482751)
			(xy 15.301199 -67.474939) (xy 15.248695 -67.459453) (xy 15.198948 -67.436613) (xy 15.152981 -67.406889)
			(xy 15.13205 -67.389248) (xy 15.131796 -67.388994) (xy 15.124715 -67.383399) (xy 15.107794 -67.377158)
			(xy 15.098776 -67.376802) (xy 15.03172 -67.376802) (xy 15.022704 -67.377168) (xy 15.005787 -67.383409)
			(xy 14.9987 -67.388994) (xy 14.9987 -67.389248) (xy 14.998446 -67.389248) (xy 14.977501 -67.406871)
			(xy 14.931532 -67.436587) (xy 14.881788 -67.459427) (xy 14.82929 -67.474922) (xy 14.775116 -67.482753)
			(xy 14.747748 -67.483228) (xy 14.720497 -67.482742) (xy 14.666549 -67.474985) (xy 14.614255 -67.45963)
			(xy 14.564678 -67.436989) (xy 14.518828 -67.407522) (xy 14.477638 -67.371831) (xy 14.441946 -67.330641)
			(xy 14.41248 -67.28479) (xy 14.389839 -67.235213) (xy 14.374484 -67.182919) (xy 14.366728 -67.128971)
			(xy 4.998822 -67.128971) (xy 5.005323 -67.173148) (xy 5.005832 -67.201034) (xy 5.005323 -67.22892)
			(xy 4.997203 -67.284096) (xy 4.981135 -67.337503) (xy 4.957463 -67.388) (xy 4.92669 -67.434513) (xy 4.889473 -67.47605)
			(xy 4.875049 -67.488054) (xy 18.779234 -67.488054) (xy 18.783305 -67.432432) (xy 18.795431 -67.377995)
			(xy 18.815354 -67.325904) (xy 18.84265 -67.277269) (xy 18.876736 -67.233126) (xy 18.916885 -67.194417)
			(xy 18.962243 -67.161966) (xy 19.011843 -67.136465) (xy 19.064627 -67.118458) (xy 19.11947 -67.108328)
			(xy 19.175204 -67.106291) (xy 19.230641 -67.112391) (xy 19.284598 -67.126497) (xy 19.335927 -67.148309)
			(xy 19.383533 -67.177363) (xy 19.426401 -67.213038) (xy 19.463618 -67.254575) (xy 19.494391 -67.301088)
			(xy 19.518063 -67.351585) (xy 19.534131 -67.404992) (xy 19.542251 -67.460168) (xy 19.54276 -67.488054)
			(xy 19.542251 -67.51594) (xy 19.534131 -67.571116) (xy 19.518063 -67.624523) (xy 19.494391 -67.67502)
			(xy 19.463618 -67.721533) (xy 19.426401 -67.76307) (xy 19.383533 -67.798745) (xy 19.335927 -67.827799)
			(xy 19.284598 -67.849611) (xy 19.230641 -67.863717) (xy 19.175204 -67.869817) (xy 19.11947 -67.86778)
			(xy 19.064627 -67.85765) (xy 19.011843 -67.839643) (xy 18.962243 -67.814142) (xy 18.916885 -67.781691)
			(xy 18.876736 -67.742982) (xy 18.84265 -67.698839) (xy 18.815354 -67.650204) (xy 18.795431 -67.598113)
			(xy 18.783305 -67.543676) (xy 18.779234 -67.488054) (xy 4.875049 -67.488054) (xy 4.846605 -67.511725)
			(xy 4.798999 -67.540779) (xy 4.74767 -67.562591) (xy 4.693713 -67.576697) (xy 4.638276 -67.582797)
			(xy 4.582542 -67.58076) (xy 4.527699 -67.57063) (xy 4.474915 -67.552623) (xy 4.425315 -67.527122)
			(xy 4.379957 -67.494671) (xy 4.339808 -67.455962) (xy 4.305722 -67.411819) (xy 4.278426 -67.363184)
			(xy 4.258503 -67.311093) (xy 4.246377 -67.256656) (xy 4.242306 -67.201034) (xy 2.770632 -67.201034)
			(xy 3.024886 -67.455288) (xy 3.031736 -67.462685) (xy 3.039477 -67.481283) (xy 3.039872 -67.491356)
			(xy 3.039872 -67.892168) (xy 6.917942 -67.892168) (xy 6.922013 -67.836546) (xy 6.934139 -67.782109)
			(xy 6.954062 -67.730018) (xy 6.981358 -67.681383) (xy 7.015444 -67.63724) (xy 7.055593 -67.598531)
			(xy 7.100951 -67.56608) (xy 7.150551 -67.540579) (xy 7.203335 -67.522572) (xy 7.258178 -67.512442)
			(xy 7.313912 -67.510405) (xy 7.369349 -67.516505) (xy 7.423306 -67.530611) (xy 7.474635 -67.552423)
			(xy 7.522241 -67.581477) (xy 7.565109 -67.617152) (xy 7.602326 -67.658689) (xy 7.633099 -67.705202)
			(xy 7.656771 -67.755699) (xy 7.672839 -67.809106) (xy 7.680959 -67.864282) (xy 7.681468 -67.892168)
			(xy 7.680959 -67.920054) (xy 7.672839 -67.97523) (xy 7.656771 -68.028637) (xy 7.633099 -68.079134)
			(xy 7.602326 -68.125647) (xy 7.565109 -68.167184) (xy 7.522241 -68.202859) (xy 7.474635 -68.231913)
			(xy 7.423306 -68.253725) (xy 7.369349 -68.267831) (xy 7.313912 -68.273931) (xy 7.258178 -68.271894)
			(xy 7.203335 -68.261764) (xy 7.150551 -68.243757) (xy 7.100951 -68.218256) (xy 7.055593 -68.185805)
			(xy 7.015444 -68.147096) (xy 6.981358 -68.102953) (xy 6.954062 -68.054318) (xy 6.934139 -68.002227)
			(xy 6.922013 -67.94779) (xy 6.917942 -67.892168) (xy 3.039872 -67.892168) (xy 3.039872 -68.353432)
			(xy 3.576826 -68.353432) (xy 3.580897 -68.29781) (xy 3.593023 -68.243373) (xy 3.612946 -68.191282)
			(xy 3.640242 -68.142647) (xy 3.674328 -68.098504) (xy 3.714477 -68.059795) (xy 3.759835 -68.027344)
			(xy 3.809435 -68.001843) (xy 3.862219 -67.983836) (xy 3.917062 -67.973706) (xy 3.972796 -67.971669)
			(xy 4.028233 -67.977769) (xy 4.08219 -67.991875) (xy 4.133519 -68.013687) (xy 4.181125 -68.042741)
			(xy 4.223993 -68.078416) (xy 4.26121 -68.119953) (xy 4.291983 -68.166466) (xy 4.315655 -68.216963)
			(xy 4.331723 -68.27037) (xy 4.339843 -68.325546) (xy 4.340352 -68.353432) (xy 4.339843 -68.381318)
			(xy 4.331723 -68.436494) (xy 4.315655 -68.489901) (xy 4.291983 -68.540398) (xy 4.261413 -68.586604)
			(xy 16.625316 -68.586604) (xy 16.625781 -68.559234) (xy 16.633598 -68.505054) (xy 16.649087 -68.452551)
			(xy 16.67193 -68.402804) (xy 16.701655 -68.356838) (xy 16.719296 -68.335906) (xy 16.71955 -68.335652)
			(xy 16.725127 -68.328559) (xy 16.731378 -68.311647) (xy 16.731742 -68.302632) (xy 16.731742 -68.235576)
			(xy 16.731409 -68.226556) (xy 16.725146 -68.209639) (xy 16.71955 -68.202556) (xy 16.719296 -68.202556)
			(xy 16.719296 -68.202302) (xy 16.701644 -68.181381) (xy 16.671934 -68.135405) (xy 16.649101 -68.085655)
			(xy 16.633613 -68.033152) (xy 16.625788 -67.978974) (xy 16.625316 -67.951604) (xy 16.625759 -67.92435)
			(xy 16.633516 -67.870397) (xy 16.648873 -67.818098) (xy 16.671517 -67.768516) (xy 16.700987 -67.722662)
			(xy 16.736682 -67.681468) (xy 16.777878 -67.645775) (xy 16.823733 -67.616307) (xy 16.873316 -67.593666)
			(xy 16.925617 -67.578312) (xy 16.97957 -67.570558) (xy 17.006824 -67.570096) (xy 17.033138 -67.570549)
			(xy 17.085268 -67.577787) (xy 17.13591 -67.592109) (xy 17.184109 -67.613244) (xy 17.228953 -67.640793)
			(xy 17.269592 -67.674233) (xy 17.287748 -67.693286) (xy 17.295252 -67.700709) (xy 17.314545 -67.709221)
			(xy 17.325086 -67.709796) (xy 17.399762 -67.709796) (xy 17.410311 -67.709261) (xy 17.429607 -67.70073)
			(xy 17.4371 -67.693286) (xy 17.45526 -67.674235) (xy 17.495889 -67.640778) (xy 17.540728 -67.613219)
			(xy 17.588928 -67.592079) (xy 17.639575 -67.577761) (xy 17.691708 -67.570535) (xy 17.718024 -67.570096)
			(xy 17.745395 -67.570549) (xy 17.799574 -67.57837) (xy 17.852078 -67.593862) (xy 17.901824 -67.616707)
			(xy 17.947791 -67.646434) (xy 17.968722 -67.664076) (xy 17.968976 -67.66433) (xy 17.976063 -67.669916)
			(xy 17.99298 -67.676162) (xy 18.001996 -67.676522) (xy 18.069052 -67.676522) (xy 18.078066 -67.676137)
			(xy 18.094983 -67.669908) (xy 18.102072 -67.66433) (xy 18.102072 -67.664076) (xy 18.102326 -67.664076)
			(xy 18.123272 -67.646454) (xy 18.169241 -67.616741) (xy 18.218985 -67.593902) (xy 18.271483 -67.578407)
			(xy 18.325656 -67.570573) (xy 18.353024 -67.570096) (xy 18.380276 -67.570555) (xy 18.434225 -67.578315)
			(xy 18.48652 -67.593674) (xy 18.536098 -67.616318) (xy 18.581948 -67.645787) (xy 18.623138 -67.681481)
			(xy 18.65883 -67.722674) (xy 18.688295 -67.768527) (xy 18.710936 -67.818106) (xy 18.726291 -67.870402)
			(xy 18.734047 -67.924352) (xy 18.734532 -67.951604) (xy 18.734085 -67.978975) (xy 18.726265 -68.033156)
			(xy 18.710772 -68.08566) (xy 18.687926 -68.135406) (xy 18.658196 -68.181372) (xy 18.640552 -68.202302)
			(xy 18.640298 -68.202556) (xy 18.634723 -68.209651) (xy 18.62847 -68.226561) (xy 18.628106 -68.235576)
			(xy 18.628106 -68.302632) (xy 18.628447 -68.311651) (xy 18.634705 -68.328567) (xy 18.640298 -68.335652)
			(xy 18.640552 -68.335652) (xy 18.640552 -68.335906) (xy 18.6582 -68.356831) (xy 18.687912 -68.402805)
			(xy 18.710747 -68.452554) (xy 18.726236 -68.505057) (xy 18.73406 -68.559234) (xy 18.734532 -68.586604)
			(xy 18.734026 -68.613854) (xy 18.72627 -68.6678) (xy 18.710915 -68.720093) (xy 18.688275 -68.769669)
			(xy 18.658811 -68.815518) (xy 18.623122 -68.856707) (xy 18.581934 -68.892399) (xy 18.536086 -68.921866)
			(xy 18.486512 -68.944508) (xy 18.43422 -68.959865) (xy 18.380274 -68.967625) (xy 18.353024 -68.968112)
			(xy 18.325654 -68.967629) (xy 18.271476 -68.959815) (xy 18.218973 -68.944329) (xy 18.169226 -68.921492)
			(xy 18.123258 -68.891771) (xy 18.102326 -68.874132) (xy 18.102072 -68.873878) (xy 18.094971 -68.868313)
			(xy 18.078065 -68.862054) (xy 18.069052 -68.861686) (xy 18.001996 -68.861686) (xy 17.992979 -68.862044)
			(xy 17.976063 -68.868291) (xy 17.968976 -68.873878) (xy 17.968976 -68.874132) (xy 17.968722 -68.874132)
			(xy 17.947797 -68.891779) (xy 17.901821 -68.921489) (xy 17.852072 -68.944323) (xy 17.79957 -68.959812)
			(xy 17.745394 -68.967639) (xy 17.718024 -68.968112) (xy 17.691711 -68.967625) (xy 17.639583 -68.960393)
			(xy 17.588941 -68.946078) (xy 17.540742 -68.924949) (xy 17.495898 -68.897407) (xy 17.455257 -68.863972)
			(xy 17.4371 -68.844922) (xy 17.429577 -68.837522) (xy 17.410298 -68.828996) (xy 17.399762 -68.828412)
			(xy 17.325086 -68.828412) (xy 17.314533 -68.828916) (xy 17.295238 -68.837468) (xy 17.287748 -68.844922)
			(xy 17.269615 -68.864) (xy 17.22898 -68.897454) (xy 17.184135 -68.92501) (xy 17.13593 -68.946144)
			(xy 17.085278 -68.960457) (xy 17.033141 -68.967676) (xy 17.006824 -68.968112) (xy 16.979572 -68.967622)
			(xy 16.925622 -68.959869) (xy 16.873325 -68.944516) (xy 16.823745 -68.921877) (xy 16.777892 -68.892411)
			(xy 16.736699 -68.85672) (xy 16.701005 -68.81553) (xy 16.671537 -68.769679) (xy 16.648894 -68.720101)
			(xy 16.633537 -68.667805) (xy 16.62578 -68.613856) (xy 16.625316 -68.586604) (xy 4.261413 -68.586604)
			(xy 4.26121 -68.586911) (xy 4.223993 -68.628448) (xy 4.181125 -68.664123) (xy 4.133519 -68.693177)
			(xy 4.08219 -68.714989) (xy 4.028233 -68.729095) (xy 3.972796 -68.735195) (xy 3.917062 -68.733158)
			(xy 3.862219 -68.723028) (xy 3.809435 -68.705021) (xy 3.759835 -68.67952) (xy 3.714477 -68.647069)
			(xy 3.674328 -68.60836) (xy 3.640242 -68.564217) (xy 3.612946 -68.515582) (xy 3.593023 -68.463491)
			(xy 3.580897 -68.409054) (xy 3.576826 -68.353432) (xy 3.039872 -68.353432) (xy 3.039872 -69.392292)
			(xy 5.050026 -69.392292) (xy 5.054097 -69.33667) (xy 5.066223 -69.282233) (xy 5.086146 -69.230142)
			(xy 5.113442 -69.181507) (xy 5.147528 -69.137364) (xy 5.187677 -69.098655) (xy 5.233035 -69.066204)
			(xy 5.282635 -69.040703) (xy 5.335419 -69.022696) (xy 5.390262 -69.012566) (xy 5.445996 -69.010529)
			(xy 5.501433 -69.016629) (xy 5.55539 -69.030735) (xy 5.606719 -69.052547) (xy 5.654325 -69.081601)
			(xy 5.697193 -69.117276) (xy 5.73441 -69.158813) (xy 5.765183 -69.205326) (xy 5.788855 -69.255823)
			(xy 5.804923 -69.30923) (xy 5.813043 -69.364406) (xy 5.813552 -69.392292) (xy 5.813043 -69.420178)
			(xy 5.804923 -69.475354) (xy 5.788855 -69.528761) (xy 5.765183 -69.579258) (xy 5.73441 -69.625771)
			(xy 5.697193 -69.667308) (xy 5.654325 -69.702983) (xy 5.606719 -69.732037) (xy 5.55539 -69.753849)
			(xy 5.501433 -69.767955) (xy 5.445996 -69.774055) (xy 5.390262 -69.772018) (xy 5.335419 -69.761888)
			(xy 5.282635 -69.743881) (xy 5.233035 -69.71838) (xy 5.187677 -69.685929) (xy 5.147528 -69.64722)
			(xy 5.113442 -69.603077) (xy 5.086146 -69.554442) (xy 5.066223 -69.502351) (xy 5.054097 -69.447914)
			(xy 5.050026 -69.392292) (xy 3.039872 -69.392292) (xy 3.039872 -70.204076) (xy 6.107428 -70.204076)
			(xy 6.111499 -70.148454) (xy 6.123625 -70.094017) (xy 6.143548 -70.041926) (xy 6.170844 -69.993291)
			(xy 6.20493 -69.949148) (xy 6.245079 -69.910439) (xy 6.290437 -69.877988) (xy 6.340037 -69.852487)
			(xy 6.392821 -69.83448) (xy 6.447664 -69.82435) (xy 6.503398 -69.822313) (xy 6.558835 -69.828413)
			(xy 6.612792 -69.842519) (xy 6.664121 -69.864331) (xy 6.711727 -69.893385) (xy 6.754595 -69.92906)
			(xy 6.791812 -69.970597) (xy 6.822585 -70.01711) (xy 6.846257 -70.067607) (xy 6.862325 -70.121014)
			(xy 6.870445 -70.17619) (xy 6.870954 -70.204076) (xy 6.870445 -70.231962) (xy 6.862325 -70.287138)
			(xy 6.846257 -70.340545) (xy 6.822585 -70.391042) (xy 6.791812 -70.437555) (xy 6.754595 -70.479092)
			(xy 6.711727 -70.514767) (xy 6.664121 -70.543821) (xy 6.612792 -70.565633) (xy 6.558835 -70.579739)
			(xy 6.503398 -70.585839) (xy 6.447664 -70.583802) (xy 6.392821 -70.573672) (xy 6.340037 -70.555665)
			(xy 6.290437 -70.530164) (xy 6.245079 -70.497713) (xy 6.20493 -70.459004) (xy 6.170844 -70.414861)
			(xy 6.143548 -70.366226) (xy 6.123625 -70.314135) (xy 6.111499 -70.259698) (xy 6.107428 -70.204076)
			(xy 3.039872 -70.204076) (xy 3.039872 -70.720966) (xy 4.463032 -70.720966) (xy 4.467103 -70.665344)
			(xy 4.479229 -70.610907) (xy 4.499152 -70.558816) (xy 4.526448 -70.510181) (xy 4.560534 -70.466038)
			(xy 4.600683 -70.427329) (xy 4.646041 -70.394878) (xy 4.695641 -70.369377) (xy 4.748425 -70.35137)
			(xy 4.803268 -70.34124) (xy 4.859002 -70.339203) (xy 4.914439 -70.345303) (xy 4.968396 -70.359409)
			(xy 5.019725 -70.381221) (xy 5.067331 -70.410275) (xy 5.110199 -70.44595) (xy 5.147416 -70.487487)
			(xy 5.178189 -70.534) (xy 5.201861 -70.584497) (xy 5.217929 -70.637904) (xy 5.226049 -70.69308) (xy 5.226558 -70.720966)
			(xy 5.226049 -70.748852) (xy 5.217929 -70.804028) (xy 5.201861 -70.857435) (xy 5.178189 -70.907932)
			(xy 5.147416 -70.954445) (xy 5.110199 -70.995982) (xy 5.067331 -71.031657) (xy 5.019725 -71.060711)
			(xy 4.968396 -71.082523) (xy 4.914439 -71.096629) (xy 4.859002 -71.102729) (xy 4.803268 -71.100692)
			(xy 4.748425 -71.090562) (xy 4.695641 -71.072555) (xy 4.646041 -71.047054) (xy 4.600683 -71.014603)
			(xy 4.560534 -70.975894) (xy 4.526448 -70.931751) (xy 4.499152 -70.883116) (xy 4.479229 -70.831025)
			(xy 4.467103 -70.776588) (xy 4.463032 -70.720966) (xy 3.039872 -70.720966) (xy 3.039872 -71.673974)
			(xy 3.37896 -71.673974) (xy 3.383031 -71.618352) (xy 3.395157 -71.563915) (xy 3.41508 -71.511824)
			(xy 3.442376 -71.463189) (xy 3.476462 -71.419046) (xy 3.516611 -71.380337) (xy 3.561969 -71.347886)
			(xy 3.611569 -71.322385) (xy 3.664353 -71.304378) (xy 3.719196 -71.294248) (xy 3.77493 -71.292211)
			(xy 3.830367 -71.298311) (xy 3.884324 -71.312417) (xy 3.935653 -71.334229) (xy 3.983259 -71.363283)
			(xy 4.026127 -71.398958) (xy 4.033123 -71.406766) (xy 7.013446 -71.406766) (xy 7.017517 -71.351144)
			(xy 7.029643 -71.296707) (xy 7.049566 -71.244616) (xy 7.076862 -71.195981) (xy 7.110948 -71.151838)
			(xy 7.151097 -71.113129) (xy 7.196455 -71.080678) (xy 7.246055 -71.055177) (xy 7.298839 -71.03717)
			(xy 7.353682 -71.02704) (xy 7.409416 -71.025003) (xy 7.464853 -71.031103) (xy 7.51881 -71.045209)
			(xy 7.570139 -71.067021) (xy 7.617745 -71.096075) (xy 7.643747 -71.117714) (xy 9.0457 -71.117714)
			(xy 9.049771 -71.062092) (xy 9.061897 -71.007655) (xy 9.08182 -70.955564) (xy 9.109116 -70.906929)
			(xy 9.143202 -70.862786) (xy 9.183351 -70.824077) (xy 9.228709 -70.791626) (xy 9.278309 -70.766125)
			(xy 9.331093 -70.748118) (xy 9.385936 -70.737988) (xy 9.44167 -70.735951) (xy 9.497107 -70.742051)
			(xy 9.551064 -70.756157) (xy 9.602393 -70.777969) (xy 9.649999 -70.807023) (xy 9.692867 -70.842698)
			(xy 9.730084 -70.884235) (xy 9.760857 -70.930748) (xy 9.784529 -70.981245) (xy 9.800597 -71.034652)
			(xy 9.808717 -71.089828) (xy 9.809226 -71.117714) (xy 9.808717 -71.1456) (xy 9.800597 -71.200776)
			(xy 9.784529 -71.254183) (xy 9.760857 -71.30468) (xy 9.730084 -71.351193) (xy 9.692867 -71.39273)
			(xy 9.649999 -71.428405) (xy 9.602393 -71.457459) (xy 9.551064 -71.479271) (xy 9.497107 -71.493377)
			(xy 9.44167 -71.499477) (xy 9.385936 -71.49744) (xy 9.331093 -71.48731) (xy 9.278309 -71.469303)
			(xy 9.228709 -71.443802) (xy 9.183351 -71.411351) (xy 9.143202 -71.372642) (xy 9.109116 -71.328499)
			(xy 9.08182 -71.279864) (xy 9.061897 -71.227773) (xy 9.049771 -71.173336) (xy 9.0457 -71.117714)
			(xy 7.643747 -71.117714) (xy 7.660613 -71.13175) (xy 7.69783 -71.173287) (xy 7.728603 -71.2198) (xy 7.752275 -71.270297)
			(xy 7.768343 -71.323704) (xy 7.776463 -71.37888) (xy 7.776972 -71.406766) (xy 7.776463 -71.434652)
			(xy 7.768343 -71.489828) (xy 7.752275 -71.543235) (xy 7.746355 -71.555864) (xy 19.194524 -71.555864)
			(xy 19.198595 -71.500242) (xy 19.210721 -71.445805) (xy 19.230644 -71.393714) (xy 19.25794 -71.345079)
			(xy 19.292026 -71.300936) (xy 19.332175 -71.262227) (xy 19.377533 -71.229776) (xy 19.427133 -71.204275)
			(xy 19.479917 -71.186268) (xy 19.53476 -71.176138) (xy 19.590494 -71.174101) (xy 19.645931 -71.180201)
			(xy 19.699888 -71.194307) (xy 19.751217 -71.216119) (xy 19.798823 -71.245173) (xy 19.841691 -71.280848)
			(xy 19.878908 -71.322385) (xy 19.909681 -71.368898) (xy 19.933353 -71.419395) (xy 19.949421 -71.472802)
			(xy 19.957541 -71.527978) (xy 19.95805 -71.555864) (xy 19.957541 -71.58375) (xy 19.951702 -71.623428)
			(xy 20.703538 -71.623428) (xy 20.707609 -71.567806) (xy 20.719735 -71.513369) (xy 20.739658 -71.461278)
			(xy 20.766954 -71.412643) (xy 20.80104 -71.3685) (xy 20.841189 -71.329791) (xy 20.886547 -71.29734)
			(xy 20.936147 -71.271839) (xy 20.988931 -71.253832) (xy 21.043774 -71.243702) (xy 21.099508 -71.241665)
			(xy 21.154945 -71.247765) (xy 21.208902 -71.261871) (xy 21.260231 -71.283683) (xy 21.307837 -71.312737)
			(xy 21.350705 -71.348412) (xy 21.387922 -71.389949) (xy 21.418695 -71.436462) (xy 21.425969 -71.451978)
			(xy 22.452582 -71.451978) (xy 22.456653 -71.396356) (xy 22.468779 -71.341919) (xy 22.488702 -71.289828)
			(xy 22.515998 -71.241193) (xy 22.550084 -71.19705) (xy 22.590233 -71.158341) (xy 22.635591 -71.12589)
			(xy 22.685191 -71.100389) (xy 22.737975 -71.082382) (xy 22.792818 -71.072252) (xy 22.848552 -71.070215)
			(xy 22.903989 -71.076315) (xy 22.957946 -71.090421) (xy 23.009275 -71.112233) (xy 23.056881 -71.141287)
			(xy 23.099749 -71.176962) (xy 23.136966 -71.218499) (xy 23.167739 -71.265012) (xy 23.191411 -71.315509)
			(xy 23.207479 -71.368916) (xy 23.215599 -71.424092) (xy 23.216108 -71.451978) (xy 23.215599 -71.479864)
			(xy 23.207479 -71.53504) (xy 23.191411 -71.588447) (xy 23.167739 -71.638944) (xy 23.136966 -71.685457)
			(xy 23.099749 -71.726994) (xy 23.056881 -71.762669) (xy 23.009275 -71.791723) (xy 22.957946 -71.813535)
			(xy 22.903989 -71.827641) (xy 22.848552 -71.833741) (xy 22.792818 -71.831704) (xy 22.737975 -71.821574)
			(xy 22.685191 -71.803567) (xy 22.635591 -71.778066) (xy 22.590233 -71.745615) (xy 22.550084 -71.706906)
			(xy 22.515998 -71.662763) (xy 22.488702 -71.614128) (xy 22.468779 -71.562037) (xy 22.456653 -71.5076)
			(xy 22.452582 -71.451978) (xy 21.425969 -71.451978) (xy 21.442367 -71.486959) (xy 21.458435 -71.540366)
			(xy 21.466555 -71.595542) (xy 21.467064 -71.623428) (xy 21.466555 -71.651314) (xy 21.458435 -71.70649)
			(xy 21.442367 -71.759897) (xy 21.418695 -71.810394) (xy 21.387922 -71.856907) (xy 21.350705 -71.898444)
			(xy 21.307837 -71.934119) (xy 21.260231 -71.963173) (xy 21.208902 -71.984985) (xy 21.154945 -71.999091)
			(xy 21.099508 -72.005191) (xy 21.043774 -72.003154) (xy 20.988931 -71.993024) (xy 20.936147 -71.975017)
			(xy 20.886547 -71.949516) (xy 20.841189 -71.917065) (xy 20.80104 -71.878356) (xy 20.766954 -71.834213)
			(xy 20.739658 -71.785578) (xy 20.719735 -71.733487) (xy 20.707609 -71.67905) (xy 20.703538 -71.623428)
			(xy 19.951702 -71.623428) (xy 19.949421 -71.638926) (xy 19.933353 -71.692333) (xy 19.909681 -71.74283)
			(xy 19.878908 -71.789343) (xy 19.841691 -71.83088) (xy 19.798823 -71.866555) (xy 19.751217 -71.895609)
			(xy 19.699888 -71.917421) (xy 19.645931 -71.931527) (xy 19.590494 -71.937627) (xy 19.53476 -71.93559)
			(xy 19.479917 -71.92546) (xy 19.427133 -71.907453) (xy 19.377533 -71.881952) (xy 19.332175 -71.849501)
			(xy 19.292026 -71.810792) (xy 19.25794 -71.766649) (xy 19.230644 -71.718014) (xy 19.210721 -71.665923)
			(xy 19.198595 -71.611486) (xy 19.194524 -71.555864) (xy 7.746355 -71.555864) (xy 7.728603 -71.593732)
			(xy 7.69783 -71.640245) (xy 7.660613 -71.681782) (xy 7.617745 -71.717457) (xy 7.570139 -71.746511)
			(xy 7.51881 -71.768323) (xy 7.464853 -71.782429) (xy 7.409416 -71.788529) (xy 7.353682 -71.786492)
			(xy 7.298839 -71.776362) (xy 7.246055 -71.758355) (xy 7.196455 -71.732854) (xy 7.151097 -71.700403)
			(xy 7.110948 -71.661694) (xy 7.076862 -71.617551) (xy 7.049566 -71.568916) (xy 7.029643 -71.516825)
			(xy 7.017517 -71.462388) (xy 7.013446 -71.406766) (xy 4.033123 -71.406766) (xy 4.063344 -71.440495)
			(xy 4.094117 -71.487008) (xy 4.117789 -71.537505) (xy 4.133857 -71.590912) (xy 4.141977 -71.646088)
			(xy 4.142486 -71.673974) (xy 4.141977 -71.70186) (xy 4.133857 -71.757036) (xy 4.117789 -71.810443)
			(xy 4.094117 -71.86094) (xy 4.063344 -71.907453) (xy 4.026127 -71.94899) (xy 3.983259 -71.984665)
			(xy 3.935653 -72.013719) (xy 3.884324 -72.035531) (xy 3.830367 -72.049637) (xy 3.77493 -72.055737)
			(xy 3.719196 -72.0537) (xy 3.664353 -72.04357) (xy 3.611569 -72.025563) (xy 3.561969 -72.000062)
			(xy 3.516611 -71.967611) (xy 3.476462 -71.928902) (xy 3.442376 -71.884759) (xy 3.41508 -71.836124)
			(xy 3.395157 -71.784033) (xy 3.383031 -71.729596) (xy 3.37896 -71.673974) (xy 3.039872 -71.673974)
			(xy 3.039872 -72.459088) (xy 9.088118 -72.459088) (xy 9.092189 -72.403466) (xy 9.104315 -72.349029)
			(xy 9.124238 -72.296938) (xy 9.151534 -72.248303) (xy 9.18562 -72.20416) (xy 9.225769 -72.165451)
			(xy 9.271127 -72.133) (xy 9.320727 -72.107499) (xy 9.373511 -72.089492) (xy 9.428354 -72.079362)
			(xy 9.484088 -72.077325) (xy 9.539525 -72.083425) (xy 9.593482 -72.097531) (xy 9.644811 -72.119343)
			(xy 9.692417 -72.148397) (xy 9.735285 -72.184072) (xy 9.772502 -72.225609) (xy 9.803275 -72.272122)
			(xy 9.826947 -72.322619) (xy 9.843015 -72.376026) (xy 9.851135 -72.431202) (xy 9.851644 -72.459088)
			(xy 9.851135 -72.486974) (xy 9.843015 -72.54215) (xy 9.826947 -72.595557) (xy 9.803275 -72.646054)
			(xy 9.772502 -72.692567) (xy 9.735285 -72.734104) (xy 9.692417 -72.769779) (xy 9.644811 -72.798833)
			(xy 9.593482 -72.820645) (xy 9.539525 -72.834751) (xy 9.484088 -72.840851) (xy 9.428354 -72.838814)
			(xy 9.373511 -72.828684) (xy 9.320727 -72.810677) (xy 9.271127 -72.785176) (xy 9.225769 -72.752725)
			(xy 9.18562 -72.714016) (xy 9.151534 -72.669873) (xy 9.124238 -72.621238) (xy 9.104315 -72.569147)
			(xy 9.092189 -72.51471) (xy 9.088118 -72.459088) (xy 3.039872 -72.459088) (xy 3.039872 -73.289668)
			(xy 3.554728 -73.289668) (xy 3.558799 -73.234046) (xy 3.570925 -73.179609) (xy 3.590848 -73.127518)
			(xy 3.618144 -73.078883) (xy 3.65223 -73.03474) (xy 3.692379 -72.996031) (xy 3.737737 -72.96358)
			(xy 3.787337 -72.938079) (xy 3.840121 -72.920072) (xy 3.894964 -72.909942) (xy 3.950698 -72.907905)
			(xy 4.006135 -72.914005) (xy 4.060092 -72.928111) (xy 4.111421 -72.949923) (xy 4.159027 -72.978977)
			(xy 4.201895 -73.014652) (xy 4.239112 -73.056189) (xy 4.269885 -73.102702) (xy 4.293557 -73.153199)
			(xy 4.307716 -73.20026) (xy 16.456914 -73.20026) (xy 16.457412 -73.172891) (xy 16.465221 -73.118713)
			(xy 16.480703 -73.06621) (xy 16.503538 -73.016463) (xy 16.533256 -72.970495) (xy 16.550894 -72.949562)
			(xy 16.551148 -72.949308) (xy 16.556743 -72.942227) (xy 16.562984 -72.925306) (xy 16.56334 -72.916288)
			(xy 16.56334 -72.849232) (xy 16.562981 -72.840215) (xy 16.556736 -72.823297) (xy 16.551148 -72.816212)
			(xy 16.550894 -72.816212) (xy 16.550894 -72.815958) (xy 16.533268 -72.795016) (xy 16.503554 -72.749046)
			(xy 16.480716 -72.699301) (xy 16.465222 -72.646802) (xy 16.45739 -72.592628) (xy 16.456914 -72.56526)
			(xy 16.457341 -72.538007) (xy 16.465103 -72.484056) (xy 16.480465 -72.431759) (xy 16.503112 -72.38218)
			(xy 16.532584 -72.336328) (xy 16.568282 -72.295138) (xy 16.609478 -72.259447) (xy 16.655334 -72.229982)
			(xy 16.704917 -72.207343) (xy 16.757216 -72.19199) (xy 16.811169 -72.184236) (xy 16.838422 -72.183752)
			(xy 16.865793 -72.184192) (xy 16.919974 -72.192015) (xy 16.972478 -72.207509) (xy 17.022224 -72.230357)
			(xy 17.06819 -72.260088) (xy 17.08912 -72.277732) (xy 17.089374 -72.277986) (xy 17.096465 -72.283566)
			(xy 17.113378 -72.289817) (xy 17.122394 -72.290178) (xy 17.18945 -72.290178) (xy 17.198465 -72.289802)
			(xy 17.215382 -72.283568) (xy 17.22247 -72.277986) (xy 17.22247 -72.277732) (xy 17.222724 -72.277732)
			(xy 17.243678 -72.26012) (xy 17.289644 -72.230403) (xy 17.339386 -72.207561) (xy 17.391882 -72.192064)
			(xy 17.446054 -72.184229) (xy 17.473422 -72.183752) (xy 17.499737 -72.184188) (xy 17.551868 -72.191427)
			(xy 17.602512 -72.205751) (xy 17.650711 -72.226889) (xy 17.695554 -72.254442) (xy 17.736191 -72.287887)
			(xy 17.754346 -72.306942) (xy 17.761856 -72.314357) (xy 17.781145 -72.322876) (xy 17.791684 -72.323452)
			(xy 17.86636 -72.323452) (xy 17.876911 -72.322929) (xy 17.896207 -72.314391) (xy 17.903698 -72.306942)
			(xy 17.92185 -72.287883) (xy 17.962482 -72.254429) (xy 18.007323 -72.226872) (xy 18.055525 -72.205734)
			(xy 18.106172 -72.191417) (xy 18.158306 -72.184191) (xy 18.184622 -72.183752) (xy 18.211872 -72.184257)
			(xy 18.265817 -72.192016) (xy 18.318109 -72.207372) (xy 18.367683 -72.230012) (xy 18.413532 -72.259477)
			(xy 18.454721 -72.295166) (xy 18.490412 -72.336354) (xy 18.519879 -72.382201) (xy 18.542522 -72.431774)
			(xy 18.55788 -72.484065) (xy 18.565642 -72.53801) (xy 18.56613 -72.56526) (xy 18.565658 -72.59263)
			(xy 18.557844 -72.64681) (xy 18.542357 -72.699313) (xy 18.519516 -72.74906) (xy 18.489792 -72.795027)
			(xy 18.47215 -72.815958) (xy 18.471896 -72.816212) (xy 18.466298 -72.823291) (xy 18.460058 -72.840214)
			(xy 18.459704 -72.849232) (xy 18.459704 -72.916288) (xy 18.460066 -72.925304) (xy 18.46631 -72.942221)
			(xy 18.471896 -72.949308) (xy 18.47215 -72.949308) (xy 18.47215 -72.949562) (xy 18.489777 -72.970504)
			(xy 18.519492 -73.016473) (xy 18.542331 -73.066218) (xy 18.557825 -73.118717) (xy 18.565655 -73.172891)
			(xy 18.56613 -73.20026) (xy 18.565608 -73.227511) (xy 18.557857 -73.281459) (xy 18.542507 -73.333754)
			(xy 18.519871 -73.383332) (xy 18.490409 -73.429185) (xy 18.454721 -73.470377) (xy 18.413534 -73.506072)
			(xy 18.367687 -73.535541) (xy 18.318112 -73.558185) (xy 18.265819 -73.573543) (xy 18.211873 -73.581303)
			(xy 18.184622 -73.581768) (xy 18.158308 -73.581296) (xy 18.106179 -73.574064) (xy 18.055536 -73.559746)
			(xy 18.007337 -73.538615) (xy 17.962494 -73.511069) (xy 17.921854 -73.47763) (xy 17.903698 -73.458578)
			(xy 17.896182 -73.45117) (xy 17.876898 -73.44265) (xy 17.86636 -73.442068) (xy 17.791684 -73.442068)
			(xy 17.781133 -73.442585) (xy 17.761839 -73.45113) (xy 17.754346 -73.458578) (xy 17.736205 -73.477649)
			(xy 17.695573 -73.511105) (xy 17.65073 -73.538663) (xy 17.602526 -73.559799) (xy 17.551876 -73.574112)
			(xy 17.499739 -73.581332) (xy 17.473422 -73.581768) (xy 17.446052 -73.581297) (xy 17.391873 -73.573481)
			(xy 17.339369 -73.557994) (xy 17.289622 -73.535153) (xy 17.243656 -73.505429) (xy 17.222724 -73.487788)
			(xy 17.22247 -73.487534) (xy 17.215373 -73.481963) (xy 17.198464 -73.475709) (xy 17.18945 -73.475342)
			(xy 17.122394 -73.475342) (xy 17.113376 -73.475687) (xy 17.096459 -73.481942) (xy 17.089374 -73.487534)
			(xy 17.089374 -73.487788) (xy 17.08912 -73.487788) (xy 17.06819 -73.505429) (xy 17.022217 -73.535141)
			(xy 16.972469 -73.557977) (xy 16.919968 -73.573467) (xy 16.865791 -73.581295) (xy 16.838422 -73.581768)
			(xy 16.811168 -73.581324) (xy 16.757214 -73.573569) (xy 16.704914 -73.558214) (xy 16.655331 -73.535571)
			(xy 16.609476 -73.506102) (xy 16.568282 -73.470406) (xy 16.532588 -73.42921) (xy 16.50312 -73.383353)
			(xy 16.48048 -73.33377) (xy 16.465127 -73.281468) (xy 16.457375 -73.227514) (xy 16.456914 -73.20026)
			(xy 4.307716 -73.20026) (xy 4.309625 -73.206606) (xy 4.317745 -73.261782) (xy 4.318254 -73.289668)
			(xy 4.317745 -73.317554) (xy 4.309625 -73.37273) (xy 4.293557 -73.426137) (xy 4.269885 -73.476634)
			(xy 4.239112 -73.523147) (xy 4.201895 -73.564684) (xy 4.159027 -73.600359) (xy 4.111421 -73.629413)
			(xy 4.060092 -73.651225) (xy 4.006135 -73.665331) (xy 3.950698 -73.671431) (xy 3.894964 -73.669394)
			(xy 3.840121 -73.659264) (xy 3.787337 -73.641257) (xy 3.737737 -73.615756) (xy 3.692379 -73.583305)
			(xy 3.65223 -73.544596) (xy 3.618144 -73.500453) (xy 3.590848 -73.451818) (xy 3.570925 -73.399727)
			(xy 3.558799 -73.34529) (xy 3.554728 -73.289668) (xy 3.039872 -73.289668) (xy 3.039872 -74.106024)
			(xy 8.468612 -74.106024) (xy 8.472683 -74.050402) (xy 8.484809 -73.995965) (xy 8.504732 -73.943874)
			(xy 8.532028 -73.895239) (xy 8.566114 -73.851096) (xy 8.606263 -73.812387) (xy 8.651621 -73.779936)
			(xy 8.701221 -73.754435) (xy 8.754005 -73.736428) (xy 8.808848 -73.726298) (xy 8.864582 -73.724261)
			(xy 8.920019 -73.730361) (xy 8.973976 -73.744467) (xy 9.025305 -73.766279) (xy 9.072911 -73.795333)
			(xy 9.115779 -73.831008) (xy 9.134382 -73.85177) (xy 18.876008 -73.85177) (xy 18.880079 -73.796148)
			(xy 18.892205 -73.741711) (xy 18.912128 -73.68962) (xy 18.939424 -73.640985) (xy 18.97351 -73.596842)
			(xy 19.013659 -73.558133) (xy 19.059017 -73.525682) (xy 19.108617 -73.500181) (xy 19.161401 -73.482174)
			(xy 19.216244 -73.472044) (xy 19.271978 -73.470007) (xy 19.327415 -73.476107) (xy 19.381372 -73.490213)
			(xy 19.432701 -73.512025) (xy 19.480307 -73.541079) (xy 19.523175 -73.576754) (xy 19.560392 -73.618291)
			(xy 19.591165 -73.664804) (xy 19.614837 -73.715301) (xy 19.630905 -73.768708) (xy 19.639025 -73.823884)
			(xy 19.639534 -73.85177) (xy 19.892008 -73.85177) (xy 19.896079 -73.796148) (xy 19.908205 -73.741711)
			(xy 19.928128 -73.68962) (xy 19.955424 -73.640985) (xy 19.98951 -73.596842) (xy 20.029659 -73.558133)
			(xy 20.075017 -73.525682) (xy 20.124617 -73.500181) (xy 20.177401 -73.482174) (xy 20.232244 -73.472044)
			(xy 20.287978 -73.470007) (xy 20.343415 -73.476107) (xy 20.397372 -73.490213) (xy 20.448701 -73.512025)
			(xy 20.496307 -73.541079) (xy 20.539175 -73.576754) (xy 20.576392 -73.618291) (xy 20.607165 -73.664804)
			(xy 20.630837 -73.715301) (xy 20.646905 -73.768708) (xy 20.655025 -73.823884) (xy 20.655534 -73.85177)
			(xy 20.908008 -73.85177) (xy 20.912079 -73.796148) (xy 20.924205 -73.741711) (xy 20.944128 -73.68962)
			(xy 20.971424 -73.640985) (xy 21.00551 -73.596842) (xy 21.045659 -73.558133) (xy 21.091017 -73.525682)
			(xy 21.140617 -73.500181) (xy 21.193401 -73.482174) (xy 21.248244 -73.472044) (xy 21.303978 -73.470007)
			(xy 21.359415 -73.476107) (xy 21.413372 -73.490213) (xy 21.464701 -73.512025) (xy 21.512307 -73.541079)
			(xy 21.555175 -73.576754) (xy 21.592392 -73.618291) (xy 21.623165 -73.664804) (xy 21.646837 -73.715301)
			(xy 21.662905 -73.768708) (xy 21.671025 -73.823884) (xy 21.671534 -73.85177) (xy 21.671025 -73.879656)
			(xy 21.662905 -73.934832) (xy 21.646837 -73.988239) (xy 21.623165 -74.038736) (xy 21.592392 -74.085249)
			(xy 21.555175 -74.126786) (xy 21.512307 -74.162461) (xy 21.464701 -74.191515) (xy 21.413372 -74.213327)
			(xy 21.359415 -74.227433) (xy 21.303978 -74.233533) (xy 21.248244 -74.231496) (xy 21.193401 -74.221366)
			(xy 21.140617 -74.203359) (xy 21.091017 -74.177858) (xy 21.045659 -74.145407) (xy 21.00551 -74.106698)
			(xy 20.971424 -74.062555) (xy 20.944128 -74.01392) (xy 20.924205 -73.961829) (xy 20.912079 -73.907392)
			(xy 20.908008 -73.85177) (xy 20.655534 -73.85177) (xy 20.655025 -73.879656) (xy 20.646905 -73.934832)
			(xy 20.630837 -73.988239) (xy 20.607165 -74.038736) (xy 20.576392 -74.085249) (xy 20.539175 -74.126786)
			(xy 20.496307 -74.162461) (xy 20.448701 -74.191515) (xy 20.397372 -74.213327) (xy 20.343415 -74.227433)
			(xy 20.287978 -74.233533) (xy 20.232244 -74.231496) (xy 20.177401 -74.221366) (xy 20.124617 -74.203359)
			(xy 20.075017 -74.177858) (xy 20.029659 -74.145407) (xy 19.98951 -74.106698) (xy 19.955424 -74.062555)
			(xy 19.928128 -74.01392) (xy 19.908205 -73.961829) (xy 19.896079 -73.907392) (xy 19.892008 -73.85177)
			(xy 19.639534 -73.85177) (xy 19.639025 -73.879656) (xy 19.630905 -73.934832) (xy 19.614837 -73.988239)
			(xy 19.591165 -74.038736) (xy 19.560392 -74.085249) (xy 19.523175 -74.126786) (xy 19.480307 -74.162461)
			(xy 19.432701 -74.191515) (xy 19.381372 -74.213327) (xy 19.327415 -74.227433) (xy 19.271978 -74.233533)
			(xy 19.216244 -74.231496) (xy 19.161401 -74.221366) (xy 19.108617 -74.203359) (xy 19.059017 -74.177858)
			(xy 19.013659 -74.145407) (xy 18.97351 -74.106698) (xy 18.939424 -74.062555) (xy 18.912128 -74.01392)
			(xy 18.892205 -73.961829) (xy 18.880079 -73.907392) (xy 18.876008 -73.85177) (xy 9.134382 -73.85177)
			(xy 9.152996 -73.872545) (xy 9.183769 -73.919058) (xy 9.207441 -73.969555) (xy 9.223509 -74.022962)
			(xy 9.231629 -74.078138) (xy 9.232138 -74.106024) (xy 9.231629 -74.13391) (xy 9.223509 -74.189086)
			(xy 9.207441 -74.242493) (xy 9.183769 -74.29299) (xy 9.152996 -74.339503) (xy 9.115779 -74.38104)
			(xy 9.072911 -74.416715) (xy 9.025305 -74.445769) (xy 8.973976 -74.467581) (xy 8.920019 -74.481687)
			(xy 8.864582 -74.487787) (xy 8.808848 -74.48575) (xy 8.754005 -74.47562) (xy 8.701221 -74.457613)
			(xy 8.651621 -74.432112) (xy 8.606263 -74.399661) (xy 8.566114 -74.360952) (xy 8.532028 -74.316809)
			(xy 8.504732 -74.268174) (xy 8.484809 -74.216083) (xy 8.472683 -74.161646) (xy 8.468612 -74.106024)
			(xy 3.039872 -74.106024) (xy 3.039872 -74.651431) (xy 14.421852 -74.651431) (xy 14.421852 -74.596929)
			(xy 14.429608 -74.542982) (xy 14.444963 -74.490689) (xy 14.467603 -74.441112) (xy 14.497069 -74.395262)
			(xy 14.53276 -74.354073) (xy 14.573949 -74.318381) (xy 14.619799 -74.288915) (xy 14.669375 -74.266274)
			(xy 14.721668 -74.250919) (xy 14.775615 -74.243162) (xy 14.802866 -74.242676) (xy 14.830236 -74.243143)
			(xy 14.884416 -74.250958) (xy 14.93692 -74.266446) (xy 14.986667 -74.289288) (xy 15.032633 -74.319014)
			(xy 15.053564 -74.336656) (xy 15.053818 -74.33691) (xy 15.060894 -74.342511) (xy 15.077819 -74.348749)
			(xy 15.086838 -74.349102) (xy 15.153894 -74.349102) (xy 15.162911 -74.348742) (xy 15.179827 -74.342496)
			(xy 15.186914 -74.33691) (xy 15.186914 -74.336656) (xy 15.187168 -74.336656) (xy 15.208095 -74.319011)
			(xy 15.25407 -74.289302) (xy 15.303819 -74.266467) (xy 15.35632 -74.250977) (xy 15.410497 -74.24315)
			(xy 15.437866 -74.242676) (xy 15.465119 -74.243131) (xy 15.519071 -74.250888) (xy 15.57137 -74.266244)
			(xy 15.620951 -74.288886) (xy 15.666805 -74.318354) (xy 15.707999 -74.354048) (xy 15.743693 -74.395241)
			(xy 15.773162 -74.441095) (xy 15.795805 -74.490676) (xy 15.811161 -74.542975) (xy 15.817323 -74.58583)
			(xy 22.958552 -74.58583) (xy 22.958956 -74.559514) (xy 22.966202 -74.507382) (xy 22.980532 -74.456737)
			(xy 23.001676 -74.408538) (xy 23.029234 -74.363696) (xy 23.062685 -74.32306) (xy 23.081742 -74.304906)
			(xy 23.089134 -74.297376) (xy 23.097666 -74.278103) (xy 23.098252 -74.267568) (xy 23.098252 -74.192892)
			(xy 23.097755 -74.182338) (xy 23.089199 -74.163042) (xy 23.081742 -74.155554) (xy 23.06266 -74.137425)
			(xy 23.029208 -74.096788) (xy 23.001653 -74.051942) (xy 22.98052 -74.003736) (xy 22.966208 -73.953085)
			(xy 22.958988 -73.900947) (xy 22.958552 -73.87463) (xy 22.959023 -73.84726) (xy 22.966838 -73.79308)
			(xy 22.982325 -73.740577) (xy 23.005166 -73.69083) (xy 23.03489 -73.644863) (xy 23.052532 -73.623932)
			(xy 23.052786 -73.623678) (xy 23.058386 -73.616601) (xy 23.064625 -73.599677) (xy 23.064978 -73.590658)
			(xy 23.064978 -73.523602) (xy 23.064625 -73.514585) (xy 23.058375 -73.497667) (xy 23.052786 -73.490582)
			(xy 23.052532 -73.490582) (xy 23.052532 -73.490328) (xy 23.034898 -73.469392) (xy 23.005184 -73.423421)
			(xy 22.982347 -73.373674) (xy 22.966855 -73.321174) (xy 22.959026 -73.266999) (xy 22.958552 -73.23963)
			(xy 22.959106 -73.212381) (xy 22.966857 -73.158438) (xy 22.982207 -73.106147) (xy 23.004841 -73.056573)
			(xy 23.034301 -73.010724) (xy 23.069985 -72.969535) (xy 23.111168 -72.933843) (xy 23.157011 -72.904375)
			(xy 23.206582 -72.881731) (xy 23.25887 -72.866372) (xy 23.312811 -72.858611) (xy 23.34006 -72.858122)
			(xy 23.36743 -72.858606) (xy 23.421608 -72.866419) (xy 23.474111 -72.881903) (xy 23.523858 -72.904741)
			(xy 23.569826 -72.934462) (xy 23.590758 -72.952102) (xy 23.591012 -72.952356) (xy 23.598086 -72.95796)
			(xy 23.615013 -72.964195) (xy 23.624032 -72.964548) (xy 23.691088 -72.964548) (xy 23.700106 -72.964196)
			(xy 23.717023 -72.957946) (xy 23.724108 -72.952356) (xy 23.724108 -72.952102) (xy 23.724362 -72.952102)
			(xy 23.745298 -72.934468) (xy 23.79127 -72.904755) (xy 23.841016 -72.881918) (xy 23.893516 -72.866426)
			(xy 23.947691 -72.858597) (xy 23.97506 -72.858122) (xy 24.002313 -72.858593) (xy 24.056265 -72.866345)
			(xy 24.108565 -72.881697) (xy 24.158147 -72.904337) (xy 24.204002 -72.933804) (xy 24.245196 -72.969497)
			(xy 24.28089 -73.01069) (xy 24.310358 -73.056544) (xy 24.332999 -73.106126) (xy 24.348353 -73.158425)
			(xy 24.356107 -73.212377) (xy 24.356568 -73.23963) (xy 24.356127 -73.267001) (xy 24.348305 -73.321182)
			(xy 24.33281 -73.373685) (xy 24.309962 -73.423432) (xy 24.280232 -73.469397) (xy 24.262588 -73.490328)
			(xy 24.262334 -73.490582) (xy 24.256741 -73.497664) (xy 24.2505 -73.514585) (xy 24.250142 -73.523602)
			(xy 24.250142 -73.590658) (xy 24.25051 -73.599674) (xy 24.256749 -73.616591) (xy 24.262334 -73.623678)
			(xy 24.262588 -73.623678) (xy 24.262588 -73.623932) (xy 24.280207 -73.64488) (xy 24.309922 -73.690849)
			(xy 24.332762 -73.740592) (xy 24.348258 -73.793089) (xy 24.356091 -73.847262) (xy 24.356568 -73.87463)
			(xy 24.356131 -73.900945) (xy 24.348891 -73.953075) (xy 24.334567 -74.003719) (xy 24.313429 -74.051918)
			(xy 24.285877 -74.096761) (xy 24.252432 -74.137399) (xy 24.233378 -74.155554) (xy 24.225947 -74.163051)
			(xy 24.21744 -74.18235) (xy 24.216868 -74.192892) (xy 24.216868 -74.267568) (xy 24.217411 -74.278116)
			(xy 24.225937 -74.297411) (xy 24.233378 -74.304906) (xy 24.252425 -74.32307) (xy 24.285884 -74.363697)
			(xy 24.313445 -74.408536) (xy 24.334585 -74.456735) (xy 24.348903 -74.507381) (xy 24.356129 -74.559514)
			(xy 24.356568 -74.58583) (xy 24.356173 -74.613085) (xy 24.348411 -74.667041) (xy 24.333049 -74.719343)
			(xy 24.3104 -74.768926) (xy 24.280925 -74.81478) (xy 24.245224 -74.855974) (xy 24.204024 -74.891667)
			(xy 24.158164 -74.921134) (xy 24.108577 -74.943773) (xy 24.056272 -74.959126) (xy 24.002316 -74.966878)
			(xy 23.97506 -74.967338) (xy 23.94769 -74.966852) (xy 23.893511 -74.959041) (xy 23.841008 -74.943558)
			(xy 23.791261 -74.92072) (xy 23.745294 -74.890998) (xy 23.724362 -74.873358) (xy 23.724108 -74.873104)
			(xy 23.717023 -74.867515) (xy 23.700105 -74.86127) (xy 23.691088 -74.860912) (xy 23.624032 -74.860912)
			(xy 23.615016 -74.861282) (xy 23.598099 -74.86752) (xy 23.591012 -74.873104) (xy 23.591012 -74.873358)
			(xy 23.590758 -74.873358) (xy 23.569809 -74.890977) (xy 23.523842 -74.920693) (xy 23.474099 -74.943534)
			(xy 23.421601 -74.959029) (xy 23.367428 -74.966862) (xy 23.34006 -74.967338) (xy 23.312809 -74.966859)
			(xy 23.258863 -74.959098) (xy 23.20657 -74.94374) (xy 23.156994 -74.921096) (xy 23.111146 -74.891628)
			(xy 23.069957 -74.855936) (xy 23.034266 -74.814746) (xy 23.004799 -74.768897) (xy 22.982157 -74.719321)
			(xy 22.9668 -74.667027) (xy 22.95904 -74.613081) (xy 22.958552 -74.58583) (xy 15.817323 -74.58583)
			(xy 15.818919 -74.596927) (xy 15.818919 -74.651433) (xy 15.811161 -74.705385) (xy 15.795805 -74.757684)
			(xy 15.773162 -74.807265) (xy 15.743693 -74.853119) (xy 15.707999 -74.894312) (xy 15.666805 -74.930006)
			(xy 15.620951 -74.959474) (xy 15.57137 -74.982116) (xy 15.519071 -74.997472) (xy 15.465119 -75.005229)
			(xy 15.437866 -75.005692) (xy 15.410495 -75.005248) (xy 15.356315 -74.997425) (xy 15.303811 -74.981931)
			(xy 15.254065 -74.959084) (xy 15.208099 -74.929355) (xy 15.187168 -74.911712) (xy 15.186914 -74.911458)
			(xy 15.179831 -74.905866) (xy 15.162911 -74.899624) (xy 15.153894 -74.899266) (xy 15.086838 -74.899266)
			(xy 15.077824 -74.899649) (xy 15.060907 -74.905879) (xy 15.053818 -74.911458) (xy 15.053818 -74.911712)
			(xy 15.053564 -74.911712) (xy 15.03262 -74.929336) (xy 14.98665 -74.95905) (xy 14.936906 -74.981889)
			(xy 14.884408 -74.997383) (xy 14.830234 -75.005216) (xy 14.802866 -75.005692) (xy 14.775615 -75.005198)
			(xy 14.721668 -74.997441) (xy 14.669375 -74.982086) (xy 14.619799 -74.959445) (xy 14.573949 -74.929979)
			(xy 14.53276 -74.894287) (xy 14.497069 -74.853098) (xy 14.467603 -74.807248) (xy 14.444963 -74.757671)
			(xy 14.429608 -74.705378) (xy 14.421852 -74.651431) (xy 3.039872 -74.651431) (xy 3.039872 -75.114481)
			(xy 5.582644 -75.114481) (xy 5.582644 -75.059979) (xy 5.5904 -75.006031) (xy 5.605755 -74.953736)
			(xy 5.628396 -74.904158) (xy 5.657863 -74.858308) (xy 5.693554 -74.817117) (xy 5.734744 -74.781425)
			(xy 5.780595 -74.751958) (xy 5.830172 -74.729317) (xy 5.882467 -74.713961) (xy 5.936415 -74.706204)
			(xy 5.963666 -74.705718) (xy 5.990269 -74.706185) (xy 6.042962 -74.713562) (xy 6.094118 -74.728193)
			(xy 6.142743 -74.749792) (xy 6.187894 -74.777941) (xy 6.228693 -74.812093) (xy 6.264349 -74.851585)
			(xy 6.279642 -74.873358) (xy 6.287976 -74.884838) (xy 6.30972 -74.903042) (xy 6.335633 -74.91456)
			(xy 6.363716 -74.9185) (xy 6.391799 -74.91456) (xy 6.417712 -74.903042) (xy 6.439456 -74.884838)
			(xy 6.44779 -74.873358) (xy 6.463085 -74.851588) (xy 6.498751 -74.812108) (xy 6.539554 -74.777964)
			(xy 6.584704 -74.749818) (xy 6.633325 -74.728216) (xy 6.684476 -74.713575) (xy 6.737164 -74.706181)
			(xy 6.763766 -74.705718) (xy 6.791019 -74.706189) (xy 6.84497 -74.713945) (xy 6.897267 -74.729301)
			(xy 6.946847 -74.751943) (xy 6.992701 -74.781411) (xy 7.033893 -74.817104) (xy 7.069587 -74.858296)
			(xy 7.099055 -74.904149) (xy 7.121698 -74.953729) (xy 7.137054 -75.006027) (xy 7.144811 -75.059977)
			(xy 7.144811 -75.114483) (xy 7.137054 -75.168433) (xy 7.121698 -75.220731) (xy 7.099055 -75.270311)
			(xy 7.069587 -75.316164) (xy 7.033893 -75.357356) (xy 6.992701 -75.393049) (xy 6.946847 -75.422517)
			(xy 6.897267 -75.445159) (xy 6.84497 -75.460515) (xy 6.791019 -75.468271) (xy 6.763766 -75.468734)
			(xy 6.737162 -75.468264) (xy 6.684469 -75.46089) (xy 6.633313 -75.446261) (xy 6.584687 -75.424663)
			(xy 6.539536 -75.396514) (xy 6.498737 -75.362361) (xy 6.463082 -75.322868) (xy 6.44779 -75.301094)
			(xy 6.439456 -75.289614) (xy 6.417712 -75.27141) (xy 6.391799 -75.259892) (xy 6.363716 -75.255952)
			(xy 6.335633 -75.259892) (xy 6.30972 -75.27141) (xy 6.287976 -75.289614) (xy 6.279642 -75.301094)
			(xy 6.264343 -75.322861) (xy 6.228676 -75.362339) (xy 6.187873 -75.396481) (xy 6.142724 -75.424626)
			(xy 6.094103 -75.446229) (xy 6.042954 -75.460871) (xy 5.990268 -75.468269) (xy 5.963666 -75.468734)
			(xy 5.936415 -75.468256) (xy 5.882467 -75.460499) (xy 5.830172 -75.445143) (xy 5.780595 -75.422502)
			(xy 5.734744 -75.393035) (xy 5.693554 -75.357343) (xy 5.657863 -75.316152) (xy 5.628396 -75.270302)
			(xy 5.605755 -75.220724) (xy 5.5904 -75.168429) (xy 5.582644 -75.114481) (xy 3.039872 -75.114481)
			(xy 3.039872 -75.569572) (xy 3.039618 -75.569572) (xy 3.039618 -75.6666) (xy 3.039195 -75.676671)
			(xy 3.031483 -75.695277) (xy 3.024632 -75.702668) (xy 2.002028 -76.725272) (xy 1.999321 -76.728122)
			(xy 1.994726 -76.734499) (xy 1.992884 -76.737972) (xy 1.990305 -76.7434) (xy 1.987488 -76.755079)
			(xy 1.987296 -76.761086) (xy 1.987296 -82.360262) (xy 1.988312 -82.369914) (xy 1.989934 -82.377161)
			(xy 1.996767 -82.390339) (xy 2.001774 -82.395822) (xy 4.305808 -84.699856) (xy 13.297418 -84.699856)
			(xy 13.301407 -84.490366) (xy 13.313368 -84.28118) (xy 13.333285 -84.072602) (xy 13.361128 -83.864932)
			(xy 13.396857 -83.658473) (xy 13.440421 -83.453524) (xy 13.491755 -83.250382) (xy 13.550786 -83.049342)
			(xy 13.617427 -82.850695) (xy 13.691583 -82.654729) (xy 13.773146 -82.461728) (xy 13.861998 -82.271972)
			(xy 13.958009 -82.085737) (xy 14.06104 -81.903291) (xy 14.170943 -81.724901) (xy 14.287558 -81.550823)
			(xy 14.410715 -81.381312) (xy 14.540236 -81.216612) (xy 14.675934 -81.056963) (xy 14.817611 -80.902595)
			(xy 14.965063 -80.753733) (xy 15.118075 -80.610593) (xy 15.276425 -80.473381) (xy 15.439885 -80.342298)
			(xy 15.608216 -80.217532) (xy 15.781175 -80.099266) (xy 15.958511 -79.98767) (xy 16.139968 -79.882906)
			(xy 16.325281 -79.785126) (xy 16.514182 -79.694473) (xy 16.706398 -79.611076) (xy 16.901649 -79.535058)
			(xy 17.099653 -79.466528) (xy 17.300122 -79.405586) (xy 17.502766 -79.35232) (xy 17.707291 -79.306808)
			(xy 17.9134 -79.269115) (xy 18.120795 -79.239296) (xy 18.329175 -79.217395) (xy 18.538238 -79.203442)
			(xy 18.74768 -79.197459) (xy 18.957198 -79.199454) (xy 19.166488 -79.209423) (xy 19.375247 -79.227354)
			(xy 19.583172 -79.253219) (xy 19.789962 -79.286981) (xy 19.995316 -79.328591) (xy 20.198938 -79.377989)
			(xy 20.400531 -79.435103) (xy 20.599803 -79.499851) (xy 20.796467 -79.572138) (xy 20.990235 -79.651859)
			(xy 21.180828 -79.7389) (xy 21.367969 -79.833134) (xy 21.551387 -79.934424) (xy 21.730816 -80.042624)
			(xy 21.905996 -80.157576) (xy 22.076672 -80.279114) (xy 22.242597 -80.407062) (xy 22.403531 -80.541233)
			(xy 22.55924 -80.681435) (xy 22.709499 -80.827462) (xy 22.85409 -80.979105) (xy 22.992803 -81.136142)
			(xy 23.125436 -81.298346) (xy 23.251799 -81.465482) (xy 23.371706 -81.637307) (xy 23.484985 -81.813573)
			(xy 23.591472 -81.994024) (xy 23.691011 -82.178397) (xy 23.783459 -82.366427) (xy 23.868682 -82.55784)
			(xy 23.946555 -82.752359) (xy 24.016967 -82.949701) (xy 24.079815 -83.149581) (xy 24.135007 -83.351709)
			(xy 24.182464 -83.555791) (xy 24.222118 -83.761533) (xy 24.25391 -83.968634) (xy 24.277794 -84.176796)
			(xy 24.293736 -84.385716) (xy 24.301713 -84.595092) (xy 24.302212 -84.699856) (xy 24.301713 -84.80462)
			(xy 24.293736 -85.013996) (xy 24.277794 -85.222916) (xy 24.25391 -85.431078) (xy 24.222118 -85.638179)
			(xy 24.182464 -85.843921) (xy 24.135007 -86.048003) (xy 24.079815 -86.250131) (xy 24.016967 -86.450011)
			(xy 23.946555 -86.647353) (xy 23.868682 -86.841872) (xy 23.783459 -87.033285) (xy 23.691011 -87.221315)
			(xy 23.591472 -87.405688) (xy 23.484985 -87.586139) (xy 23.371706 -87.762405) (xy 23.251799 -87.93423)
			(xy 23.125436 -88.101366) (xy 22.992803 -88.26357) (xy 22.85409 -88.420607) (xy 22.709499 -88.57225)
			(xy 22.55924 -88.718277) (xy 22.403531 -88.858479) (xy 22.242597 -88.99265) (xy 22.076672 -89.120598)
			(xy 21.905996 -89.242136) (xy 21.730816 -89.357088) (xy 21.551387 -89.465288) (xy 21.367969 -89.566578)
			(xy 21.180828 -89.660812) (xy 20.990235 -89.747853) (xy 20.796467 -89.827574) (xy 20.599803 -89.899861)
			(xy 20.400531 -89.964609) (xy 20.198938 -90.021723) (xy 19.995316 -90.071121) (xy 19.789962 -90.112731)
			(xy 19.583172 -90.146493) (xy 19.375247 -90.172358) (xy 19.166488 -90.190289) (xy 18.957198 -90.200258)
			(xy 18.74768 -90.202253) (xy 18.538238 -90.19627) (xy 18.329175 -90.182317) (xy 18.120795 -90.160416)
			(xy 17.9134 -90.130597) (xy 17.707291 -90.092904) (xy 17.502766 -90.047392) (xy 17.300122 -89.994126)
			(xy 17.099653 -89.933184) (xy 16.901649 -89.864654) (xy 16.706398 -89.788636) (xy 16.514182 -89.705239)
			(xy 16.325281 -89.614586) (xy 16.139968 -89.516806) (xy 15.958511 -89.412042) (xy 15.781175 -89.300446)
			(xy 15.608216 -89.18218) (xy 15.439885 -89.057414) (xy 15.276425 -88.926331) (xy 15.118075 -88.789119)
			(xy 14.965063 -88.645979) (xy 14.817611 -88.497117) (xy 14.675934 -88.342749) (xy 14.540236 -88.1831)
			(xy 14.410715 -88.0184) (xy 14.287558 -87.848889) (xy 14.170943 -87.674811) (xy 14.06104 -87.496421)
			(xy 13.958009 -87.313975) (xy 13.861998 -87.12774) (xy 13.773146 -86.937984) (xy 13.691583 -86.744983)
			(xy 13.617427 -86.549017) (xy 13.550786 -86.35037) (xy 13.491755 -86.14933) (xy 13.440421 -85.946188)
			(xy 13.396857 -85.741239) (xy 13.361128 -85.53478) (xy 13.333285 -85.32711) (xy 13.313368 -85.118532)
			(xy 13.301407 -84.909346) (xy 13.297418 -84.699856) (xy 4.305808 -84.699856) (xy 5.080508 -85.474556)
			(xy 5.087345 -85.481958) (xy 5.095058 -85.500556) (xy 5.095494 -85.510624) (xy 5.095494 -89.055702)
			(xy 5.095136 -89.064957) (xy 5.088613 -89.082276) (xy 5.082794 -89.089484) (xy 5.077206 -89.09558)
			(xy 5.07365 -89.10447) (xy 5.071892 -89.109036) (xy 5.069967 -89.118629) (xy 5.06984 -89.12352) (xy 5.06984 -100.402753)
			(xy 36.752744 -100.402753) (xy 36.752744 -100.348247) (xy 36.760501 -100.294296) (xy 36.775856 -100.241998)
			(xy 36.798498 -100.192417) (xy 36.827966 -100.146563) (xy 36.863659 -100.10537) (xy 36.904851 -100.069675)
			(xy 36.950703 -100.040206) (xy 37.000283 -100.017562) (xy 37.05258 -100.002204) (xy 37.106531 -99.994445)
			(xy 37.133784 -99.993958) (xy 37.148577 -99.994093) (xy 37.178075 -99.996382) (xy 37.192712 -99.99853)
			(xy 37.203687 -99.999648) (xy 37.224877 -99.993592) (xy 37.233606 -99.986846) (xy 37.29228 -99.936808)
			(xy 37.30031 -99.929243) (xy 37.309521 -99.90922) (xy 37.31006 -99.8982) (xy 37.31006 -99.593908)
			(xy 37.309531 -99.582888) (xy 37.300307 -99.56287) (xy 37.29228 -99.5553) (xy 37.233606 -99.505262)
			(xy 37.224898 -99.49847) (xy 37.203692 -99.492403) (xy 37.192712 -99.493578) (xy 37.178073 -99.495712)
			(xy 37.148577 -99.498005) (xy 37.133784 -99.49815) (xy 37.106537 -99.497579) (xy 37.052597 -99.489821)
			(xy 37.00031 -99.474466) (xy 36.95074 -99.451827) (xy 36.904897 -99.422363) (xy 36.863713 -99.386676)
			(xy 36.828027 -99.345491) (xy 36.798565 -99.299646) (xy 36.775928 -99.250075) (xy 36.760575 -99.197788)
			(xy 36.75282 -99.143847) (xy 36.75282 -99.089353) (xy 36.760575 -99.035412) (xy 36.775928 -98.983125)
			(xy 36.798565 -98.933554) (xy 36.828027 -98.887709) (xy 36.863713 -98.846524) (xy 36.904897 -98.810837)
			(xy 36.95074 -98.781373) (xy 37.00031 -98.758734) (xy 37.052597 -98.743379) (xy 37.106537 -98.735621)
			(xy 37.133784 -98.735134) (xy 37.159693 -98.735546) (xy 37.211033 -98.742582) (xy 37.260948 -98.756498)
			(xy 37.308522 -98.777039) (xy 37.352879 -98.803827) (xy 37.393205 -98.836371) (xy 37.428757 -98.87407)
			(xy 37.444172 -98.8949) (xy 37.449909 -98.902233) (xy 37.465414 -98.912517) (xy 37.474398 -98.914966)
			(xy 37.504878 -98.921824) (xy 37.514153 -98.923589) (xy 37.532818 -98.920837) (xy 37.5412 -98.91649)
			(xy 37.567177 -98.902197) (xy 37.622029 -98.879686) (xy 37.679331 -98.864459) (xy 37.738122 -98.856772)
			(xy 37.767768 -98.856292) (xy 37.797411 -98.85679) (xy 37.856193 -98.864511) (xy 37.913491 -98.879737)
			(xy 37.968351 -98.902216) (xy 37.994336 -98.91649) (xy 38.002758 -98.920715) (xy 38.02138 -98.923461)
			(xy 38.030658 -98.921824) (xy 38.061138 -98.914966) (xy 38.070132 -98.912542) (xy 38.085637 -98.902247)
			(xy 38.091364 -98.8949) (xy 38.106778 -98.874068) (xy 38.142318 -98.836356) (xy 38.182639 -98.803804)
			(xy 38.226998 -98.777014) (xy 38.274576 -98.756479) (xy 38.324497 -98.742577) (xy 38.375842 -98.735565)
			(xy 38.401752 -98.735134) (xy 38.42901 -98.73551) (xy 38.482972 -98.743262) (xy 38.535282 -98.758616)
			(xy 38.584873 -98.781258) (xy 38.630738 -98.810728) (xy 38.67043 -98.845116) (xy 44.669708 -98.845116)
			(xy 44.673779 -98.789494) (xy 44.685905 -98.735057) (xy 44.705828 -98.682966) (xy 44.733124 -98.634331)
			(xy 44.76721 -98.590188) (xy 44.807359 -98.551479) (xy 44.852717 -98.519028) (xy 44.902317 -98.493527)
			(xy 44.955101 -98.47552) (xy 45.009944 -98.46539) (xy 45.065678 -98.463353) (xy 45.121115 -98.469453)
			(xy 45.175072 -98.483559) (xy 45.226401 -98.505371) (xy 45.274007 -98.534425) (xy 45.316875 -98.5701)
			(xy 45.354092 -98.611637) (xy 45.384865 -98.65815) (xy 45.408537 -98.708647) (xy 45.424605 -98.762054)
			(xy 45.432725 -98.81723) (xy 45.433234 -98.845116) (xy 46.650908 -98.845116) (xy 46.654979 -98.789494)
			(xy 46.667105 -98.735057) (xy 46.687028 -98.682966) (xy 46.714324 -98.634331) (xy 46.74841 -98.590188)
			(xy 46.788559 -98.551479) (xy 46.833917 -98.519028) (xy 46.883517 -98.493527) (xy 46.936301 -98.47552)
			(xy 46.991144 -98.46539) (xy 47.046878 -98.463353) (xy 47.102315 -98.469453) (xy 47.156272 -98.483559)
			(xy 47.207601 -98.505371) (xy 47.255207 -98.534425) (xy 47.298075 -98.5701) (xy 47.335292 -98.611637)
			(xy 47.366065 -98.65815) (xy 47.389737 -98.708647) (xy 47.405805 -98.762054) (xy 47.413925 -98.81723)
			(xy 47.414434 -98.845116) (xy 48.382934 -98.845116) (xy 48.387005 -98.789494) (xy 48.399131 -98.735057)
			(xy 48.419054 -98.682966) (xy 48.44635 -98.634331) (xy 48.480436 -98.590188) (xy 48.520585 -98.551479)
			(xy 48.565943 -98.519028) (xy 48.615543 -98.493527) (xy 48.668327 -98.47552) (xy 48.72317 -98.46539)
			(xy 48.778904 -98.463353) (xy 48.834341 -98.469453) (xy 48.888298 -98.483559) (xy 48.939627 -98.505371)
			(xy 48.987233 -98.534425) (xy 49.030101 -98.5701) (xy 49.067318 -98.611637) (xy 49.098091 -98.65815)
			(xy 49.121763 -98.708647) (xy 49.137831 -98.762054) (xy 49.145951 -98.81723) (xy 49.14646 -98.845116)
			(xy 51.251102 -98.845116) (xy 51.255173 -98.789494) (xy 51.267299 -98.735057) (xy 51.287222 -98.682966)
			(xy 51.314518 -98.634331) (xy 51.348604 -98.590188) (xy 51.388753 -98.551479) (xy 51.434111 -98.519028)
			(xy 51.483711 -98.493527) (xy 51.536495 -98.47552) (xy 51.591338 -98.46539) (xy 51.647072 -98.463353)
			(xy 51.702509 -98.469453) (xy 51.756466 -98.483559) (xy 51.807795 -98.505371) (xy 51.855401 -98.534425)
			(xy 51.898269 -98.5701) (xy 51.935486 -98.611637) (xy 51.966259 -98.65815) (xy 51.989931 -98.708647)
			(xy 52.005999 -98.762054) (xy 52.014119 -98.81723) (xy 52.014628 -98.845116) (xy 52.014119 -98.873002)
			(xy 52.005999 -98.928178) (xy 51.989931 -98.981585) (xy 51.966259 -99.032082) (xy 51.935486 -99.078595)
			(xy 51.898269 -99.120132) (xy 51.855401 -99.155807) (xy 51.807795 -99.184861) (xy 51.756466 -99.206673)
			(xy 51.702509 -99.220779) (xy 51.647072 -99.226879) (xy 51.591338 -99.224842) (xy 51.536495 -99.214712)
			(xy 51.483711 -99.196705) (xy 51.434111 -99.171204) (xy 51.388753 -99.138753) (xy 51.348604 -99.100044)
			(xy 51.314518 -99.055901) (xy 51.287222 -99.007266) (xy 51.267299 -98.955175) (xy 51.255173 -98.900738)
			(xy 51.251102 -98.845116) (xy 49.14646 -98.845116) (xy 49.145951 -98.873002) (xy 49.137831 -98.928178)
			(xy 49.121763 -98.981585) (xy 49.098091 -99.032082) (xy 49.067318 -99.078595) (xy 49.030101 -99.120132)
			(xy 48.987233 -99.155807) (xy 48.939627 -99.184861) (xy 48.888298 -99.206673) (xy 48.834341 -99.220779)
			(xy 48.778904 -99.226879) (xy 48.72317 -99.224842) (xy 48.668327 -99.214712) (xy 48.615543 -99.196705)
			(xy 48.565943 -99.171204) (xy 48.520585 -99.138753) (xy 48.480436 -99.100044) (xy 48.44635 -99.055901)
			(xy 48.419054 -99.007266) (xy 48.399131 -98.955175) (xy 48.387005 -98.900738) (xy 48.382934 -98.845116)
			(xy 47.414434 -98.845116) (xy 47.413925 -98.873002) (xy 47.405805 -98.928178) (xy 47.389737 -98.981585)
			(xy 47.366065 -99.032082) (xy 47.335292 -99.078595) (xy 47.298075 -99.120132) (xy 47.255207 -99.155807)
			(xy 47.207601 -99.184861) (xy 47.156272 -99.206673) (xy 47.102315 -99.220779) (xy 47.046878 -99.226879)
			(xy 46.991144 -99.224842) (xy 46.936301 -99.214712) (xy 46.883517 -99.196705) (xy 46.833917 -99.171204)
			(xy 46.788559 -99.138753) (xy 46.74841 -99.100044) (xy 46.714324 -99.055901) (xy 46.687028 -99.007266)
			(xy 46.667105 -98.955175) (xy 46.654979 -98.900738) (xy 46.650908 -98.845116) (xy 45.433234 -98.845116)
			(xy 45.432725 -98.873002) (xy 45.424605 -98.928178) (xy 45.408537 -98.981585) (xy 45.384865 -99.032082)
			(xy 45.354092 -99.078595) (xy 45.316875 -99.120132) (xy 45.274007 -99.155807) (xy 45.226401 -99.184861)
			(xy 45.175072 -99.206673) (xy 45.121115 -99.220779) (xy 45.065678 -99.226879) (xy 45.009944 -99.224842)
			(xy 44.955101 -99.214712) (xy 44.902317 -99.196705) (xy 44.852717 -99.171204) (xy 44.807359 -99.138753)
			(xy 44.76721 -99.100044) (xy 44.733124 -99.055901) (xy 44.705828 -99.007266) (xy 44.685905 -98.955175)
			(xy 44.673779 -98.900738) (xy 44.669708 -98.845116) (xy 38.67043 -98.845116) (xy 38.671941 -98.846425)
			(xy 38.707643 -98.887624) (xy 38.737119 -98.933484) (xy 38.759768 -98.983073) (xy 38.775128 -99.035381)
			(xy 38.782887 -99.089342) (xy 38.782887 -99.143858) (xy 38.775128 -99.197819) (xy 38.759768 -99.250127)
			(xy 38.737119 -99.299716) (xy 38.707643 -99.345576) (xy 38.671941 -99.386775) (xy 38.630738 -99.422472)
			(xy 38.584873 -99.451942) (xy 38.535282 -99.474584) (xy 38.482972 -99.489938) (xy 38.42901 -99.49769)
			(xy 38.401752 -99.49815) (xy 38.386959 -99.498011) (xy 38.357461 -99.495725) (xy 38.342824 -99.493578)
			(xy 38.331849 -99.492479) (xy 38.31066 -99.498522) (xy 38.30193 -99.505262) (xy 38.243256 -99.5553)
			(xy 38.235228 -99.562867) (xy 38.226014 -99.582888) (xy 38.225476 -99.593908) (xy 38.225476 -99.8982)
			(xy 38.226021 -99.909218) (xy 38.235236 -99.929234) (xy 38.243256 -99.936808) (xy 38.30193 -99.986846)
			(xy 38.310625 -99.993658) (xy 38.331841 -99.999713) (xy 38.342824 -99.99853) (xy 38.357462 -99.996392)
			(xy 38.386959 -99.994102) (xy 38.401752 -99.993958) (xy 38.429005 -99.994486) (xy 38.482956 -100.002237)
			(xy 38.535255 -100.017587) (xy 38.584837 -100.040225) (xy 38.630692 -100.069689) (xy 38.671886 -100.10538)
			(xy 38.707582 -100.14657) (xy 38.737052 -100.192421) (xy 38.759696 -100.242) (xy 38.775053 -100.294297)
			(xy 38.782811 -100.348247) (xy 38.782811 -100.402753) (xy 38.775053 -100.456703) (xy 38.759696 -100.509)
			(xy 38.737052 -100.558579) (xy 38.707582 -100.60443) (xy 38.672458 -100.64496) (xy 44.669708 -100.64496)
			(xy 44.673779 -100.589338) (xy 44.685905 -100.534901) (xy 44.705828 -100.48281) (xy 44.733124 -100.434175)
			(xy 44.76721 -100.390032) (xy 44.807359 -100.351323) (xy 44.852717 -100.318872) (xy 44.902317 -100.293371)
			(xy 44.955101 -100.275364) (xy 45.009944 -100.265234) (xy 45.065678 -100.263197) (xy 45.121115 -100.269297)
			(xy 45.175072 -100.283403) (xy 45.226401 -100.305215) (xy 45.274007 -100.334269) (xy 45.316875 -100.369944)
			(xy 45.354092 -100.411481) (xy 45.384865 -100.457994) (xy 45.408537 -100.508491) (xy 45.424605 -100.561898)
			(xy 45.432725 -100.617074) (xy 45.433234 -100.64496) (xy 46.650908 -100.64496) (xy 46.654979 -100.589338)
			(xy 46.667105 -100.534901) (xy 46.687028 -100.48281) (xy 46.714324 -100.434175) (xy 46.74841 -100.390032)
			(xy 46.788559 -100.351323) (xy 46.833917 -100.318872) (xy 46.883517 -100.293371) (xy 46.936301 -100.275364)
			(xy 46.991144 -100.265234) (xy 47.046878 -100.263197) (xy 47.102315 -100.269297) (xy 47.156272 -100.283403)
			(xy 47.207601 -100.305215) (xy 47.255207 -100.334269) (xy 47.298075 -100.369944) (xy 47.335292 -100.411481)
			(xy 47.366065 -100.457994) (xy 47.389737 -100.508491) (xy 47.405805 -100.561898) (xy 47.413925 -100.617074)
			(xy 47.414434 -100.64496) (xy 48.009554 -100.64496) (xy 48.013625 -100.589338) (xy 48.025751 -100.534901)
			(xy 48.045674 -100.48281) (xy 48.07297 -100.434175) (xy 48.107056 -100.390032) (xy 48.147205 -100.351323)
			(xy 48.192563 -100.318872) (xy 48.242163 -100.293371) (xy 48.294947 -100.275364) (xy 48.34979 -100.265234)
			(xy 48.405524 -100.263197) (xy 48.460961 -100.269297) (xy 48.514918 -100.283403) (xy 48.566247 -100.305215)
			(xy 48.613853 -100.334269) (xy 48.656721 -100.369944) (xy 48.693938 -100.411481) (xy 48.724711 -100.457994)
			(xy 48.748383 -100.508491) (xy 48.764451 -100.561898) (xy 48.772571 -100.617074) (xy 48.77308 -100.64496)
			(xy 48.772571 -100.672846) (xy 48.764451 -100.728022) (xy 48.748383 -100.781429) (xy 48.724711 -100.831926)
			(xy 48.693938 -100.878439) (xy 48.656721 -100.919976) (xy 48.613853 -100.955651) (xy 48.566247 -100.984705)
			(xy 48.514918 -101.006517) (xy 48.460961 -101.020623) (xy 48.405524 -101.026723) (xy 48.34979 -101.024686)
			(xy 48.294947 -101.014556) (xy 48.242163 -100.996549) (xy 48.192563 -100.971048) (xy 48.147205 -100.938597)
			(xy 48.107056 -100.899888) (xy 48.07297 -100.855745) (xy 48.045674 -100.80711) (xy 48.025751 -100.755019)
			(xy 48.013625 -100.700582) (xy 48.009554 -100.64496) (xy 47.414434 -100.64496) (xy 47.413925 -100.672846)
			(xy 47.405805 -100.728022) (xy 47.389737 -100.781429) (xy 47.366065 -100.831926) (xy 47.335292 -100.878439)
			(xy 47.298075 -100.919976) (xy 47.255207 -100.955651) (xy 47.207601 -100.984705) (xy 47.156272 -101.006517)
			(xy 47.102315 -101.020623) (xy 47.046878 -101.026723) (xy 46.991144 -101.024686) (xy 46.936301 -101.014556)
			(xy 46.883517 -100.996549) (xy 46.833917 -100.971048) (xy 46.788559 -100.938597) (xy 46.74841 -100.899888)
			(xy 46.714324 -100.855745) (xy 46.687028 -100.80711) (xy 46.667105 -100.755019) (xy 46.654979 -100.700582)
			(xy 46.650908 -100.64496) (xy 45.433234 -100.64496) (xy 45.432725 -100.672846) (xy 45.424605 -100.728022)
			(xy 45.408537 -100.781429) (xy 45.384865 -100.831926) (xy 45.354092 -100.878439) (xy 45.316875 -100.919976)
			(xy 45.274007 -100.955651) (xy 45.226401 -100.984705) (xy 45.175072 -101.006517) (xy 45.121115 -101.020623)
			(xy 45.065678 -101.026723) (xy 45.009944 -101.024686) (xy 44.955101 -101.014556) (xy 44.902317 -100.996549)
			(xy 44.852717 -100.971048) (xy 44.807359 -100.938597) (xy 44.76721 -100.899888) (xy 44.733124 -100.855745)
			(xy 44.705828 -100.80711) (xy 44.685905 -100.755019) (xy 44.673779 -100.700582) (xy 44.669708 -100.64496)
			(xy 38.672458 -100.64496) (xy 38.671886 -100.64562) (xy 38.630692 -100.681311) (xy 38.584837 -100.710775)
			(xy 38.535255 -100.733413) (xy 38.482956 -100.748763) (xy 38.429005 -100.756514) (xy 38.401752 -100.756974)
			(xy 38.375844 -100.756532) (xy 38.324506 -100.749501) (xy 38.274591 -100.73559) (xy 38.227018 -100.715054)
			(xy 38.18266 -100.68827) (xy 38.142333 -100.655731) (xy 38.10678 -100.618036) (xy 38.091364 -100.597208)
			(xy 38.085613 -100.589888) (xy 38.070118 -100.579597) (xy 38.061138 -100.577142) (xy 38.030658 -100.570284)
			(xy 38.021381 -100.568537) (xy 38.002718 -100.571277) (xy 37.994336 -100.575618) (xy 37.968372 -100.589936)
			(xy 37.913516 -100.612441) (xy 37.856209 -100.627661) (xy 37.797415 -100.63534) (xy 37.767768 -100.635816)
			(xy 37.738126 -100.635301) (xy 37.679344 -100.627585) (xy 37.622046 -100.612364) (xy 37.567185 -100.58989)
			(xy 37.5412 -100.575618) (xy 37.532792 -100.571361) (xy 37.514158 -100.568634) (xy 37.504878 -100.570284)
			(xy 37.474398 -100.577142) (xy 37.465394 -100.579538) (xy 37.449894 -100.589853) (xy 37.444172 -100.597208)
			(xy 37.428738 -100.618024) (xy 37.393201 -100.655737) (xy 37.352883 -100.68829) (xy 37.308528 -100.715082)
			(xy 37.260953 -100.735619) (xy 37.211035 -100.749524) (xy 37.159693 -100.75654) (xy 37.133784 -100.756974)
			(xy 37.106531 -100.756555) (xy 37.05258 -100.748796) (xy 37.000283 -100.733438) (xy 36.950703 -100.710794)
			(xy 36.904851 -100.681325) (xy 36.863659 -100.64563) (xy 36.827966 -100.604436) (xy 36.798498 -100.558583)
			(xy 36.775856 -100.509002) (xy 36.760501 -100.456704) (xy 36.752744 -100.402753) (xy 5.06984 -100.402753)
			(xy 5.06984 -100.950351) (xy 34.720268 -100.950351) (xy 34.720268 -100.895849) (xy 34.728024 -100.841902)
			(xy 34.743378 -100.789608) (xy 34.766018 -100.740031) (xy 34.795483 -100.694181) (xy 34.831173 -100.65299)
			(xy 34.872361 -100.617297) (xy 34.91821 -100.58783) (xy 34.967785 -100.565187) (xy 35.020079 -100.549829)
			(xy 35.074025 -100.542069) (xy 35.101276 -100.541582) (xy 35.127184 -100.542022) (xy 35.178521 -100.549055)
			(xy 35.228435 -100.562968) (xy 35.276008 -100.583505) (xy 35.320366 -100.610289) (xy 35.360693 -100.642827)
			(xy 35.396247 -100.680521) (xy 35.411664 -100.701348) (xy 35.417414 -100.70867) (xy 35.43291 -100.718961)
			(xy 35.44189 -100.721414) (xy 35.47237 -100.728272) (xy 35.481645 -100.730039) (xy 35.500311 -100.727287)
			(xy 35.508692 -100.722938) (xy 35.534673 -100.708653) (xy 35.589523 -100.686138) (xy 35.646825 -100.670909)
			(xy 35.705615 -100.663221) (xy 35.73526 -100.66274) (xy 35.764902 -100.663248) (xy 35.823684 -100.670967)
			(xy 35.880982 -100.686191) (xy 35.935843 -100.708666) (xy 35.961828 -100.722938) (xy 35.970252 -100.727158)
			(xy 35.988873 -100.729909) (xy 35.99815 -100.728272) (xy 36.02863 -100.721414) (xy 36.037618 -100.718971)
			(xy 36.053125 -100.708688) (xy 36.058856 -100.701348) (xy 36.07426 -100.680509) (xy 36.109804 -100.642798)
			(xy 36.150127 -100.610249) (xy 36.194487 -100.583461) (xy 36.242067 -100.562927) (xy 36.291989 -100.549026)
			(xy 36.343333 -100.542014) (xy 36.369244 -100.541582) (xy 36.396492 -100.542091) (xy 36.450434 -100.549853)
			(xy 36.502722 -100.565211) (xy 36.552292 -100.587854) (xy 36.598136 -100.617321) (xy 36.63932 -100.653011)
			(xy 36.675006 -100.694199) (xy 36.704467 -100.740046) (xy 36.727104 -100.789619) (xy 36.742457 -100.841909)
			(xy 36.750212 -100.895851) (xy 36.750212 -100.950348) (xy 36.742457 -101.004291) (xy 36.727104 -101.056581)
			(xy 36.704467 -101.106154) (xy 36.675006 -101.152001) (xy 36.63932 -101.193189) (xy 36.598136 -101.228879)
			(xy 36.552292 -101.258346) (xy 36.502722 -101.280989) (xy 36.450434 -101.296347) (xy 36.396492 -101.304109)
			(xy 36.369244 -101.304598) (xy 36.354451 -101.304459) (xy 36.324953 -101.302173) (xy 36.310316 -101.300026)
			(xy 36.299341 -101.298912) (xy 36.27815 -101.304964) (xy 36.269422 -101.31171) (xy 36.210748 -101.361748)
			(xy 36.202742 -101.369335) (xy 36.193516 -101.389341) (xy 36.192968 -101.400356) (xy 36.192968 -101.704648)
			(xy 36.193545 -101.715662) (xy 36.202738 -101.735678) (xy 36.210748 -101.743256) (xy 36.269422 -101.793294)
			(xy 36.278116 -101.800106) (xy 36.299333 -101.806159) (xy 36.310316 -101.804978) (xy 36.324954 -101.80284)
			(xy 36.354451 -101.80055) (xy 36.369244 -101.800406) (xy 36.396494 -101.800867) (xy 36.450439 -101.808629)
			(xy 36.502731 -101.823988) (xy 36.552304 -101.846633) (xy 36.598151 -101.876101) (xy 36.639337 -101.911794)
			(xy 36.675025 -101.952985) (xy 36.704488 -101.998835) (xy 36.727127 -102.048411) (xy 36.742481 -102.100704)
			(xy 36.750236 -102.15465) (xy 36.750236 -102.20915) (xy 36.742481 -102.263096) (xy 36.727127 -102.315389)
			(xy 36.704488 -102.364965) (xy 36.675025 -102.410815) (xy 36.639337 -102.452006) (xy 36.598151 -102.487699)
			(xy 36.552304 -102.517167) (xy 36.502731 -102.539812) (xy 36.450439 -102.555171) (xy 36.396494 -102.562933)
			(xy 36.369244 -102.563422) (xy 36.343336 -102.562966) (xy 36.292 -102.555935) (xy 36.242087 -102.542025)
			(xy 36.194514 -102.52149) (xy 36.150156 -102.494709) (xy 36.109829 -102.462173) (xy 36.074273 -102.424482)
			(xy 36.058856 -102.403656) (xy 36.053098 -102.396341) (xy 36.037608 -102.386046) (xy 36.02863 -102.38359)
			(xy 35.99815 -102.376732) (xy 35.988874 -102.374975) (xy 35.970209 -102.37772) (xy 35.961828 -102.382066)
			(xy 35.935843 -102.396344) (xy 35.880995 -102.41886) (xy 35.823694 -102.434091) (xy 35.764905 -102.441782)
			(xy 35.73526 -102.442264) (xy 35.705618 -102.441746) (xy 35.646837 -102.43403) (xy 35.589539 -102.418809)
			(xy 35.534677 -102.396337) (xy 35.508692 -102.382066) (xy 35.500285 -102.377807) (xy 35.48165 -102.37508)
			(xy 35.47237 -102.376732) (xy 35.44189 -102.38359) (xy 35.432905 -102.38604) (xy 35.417396 -102.396318)
			(xy 35.411664 -102.403656) (xy 35.396249 -102.424487) (xy 35.360707 -102.462197) (xy 35.320385 -102.494747)
			(xy 35.276027 -102.521536) (xy 35.22845 -102.542071) (xy 35.178529 -102.555974) (xy 35.127186 -102.562989)
			(xy 35.101276 -102.563422) (xy 35.074027 -102.562906) (xy 35.020084 -102.555147) (xy 34.967794 -102.539791)
			(xy 34.918222 -102.517149) (xy 34.872376 -102.487683) (xy 34.83119 -102.451993) (xy 34.795503 -102.410805)
			(xy 34.76604 -102.364957) (xy 34.743401 -102.315384) (xy 34.728048 -102.263093) (xy 34.720292 -102.209149)
			(xy 34.720292 -102.154651) (xy 34.728048 -102.100707) (xy 34.743401 -102.048416) (xy 34.76604 -101.998843)
			(xy 34.795503 -101.952995) (xy 34.83119 -101.911807) (xy 34.872376 -101.876117) (xy 34.918222 -101.846651)
			(xy 34.967794 -101.824009) (xy 35.020084 -101.808653) (xy 35.074027 -101.800894) (xy 35.101276 -101.800406)
			(xy 35.116069 -101.800542) (xy 35.145567 -101.802831) (xy 35.160204 -101.804978) (xy 35.171179 -101.806103)
			(xy 35.192371 -101.800044) (xy 35.201098 -101.793294) (xy 35.259772 -101.743256) (xy 35.267779 -101.73567)
			(xy 35.277004 -101.715663) (xy 35.277552 -101.704648) (xy 35.277552 -101.400356) (xy 35.276998 -101.389339)
			(xy 35.267792 -101.369321) (xy 35.259772 -101.361748) (xy 35.201098 -101.31171) (xy 35.192397 -101.304909)
			(xy 35.171185 -101.298849) (xy 35.160204 -101.300026) (xy 35.145565 -101.302161) (xy 35.116069 -101.304453)
			(xy 35.101276 -101.304598) (xy 35.074025 -101.304131) (xy 35.020079 -101.296371) (xy 34.967785 -101.281013)
			(xy 34.91821 -101.25837) (xy 34.872361 -101.228903) (xy 34.831173 -101.19321) (xy 34.795483 -101.152019)
			(xy 34.766018 -101.106169) (xy 34.743378 -101.056592) (xy 34.728024 -101.004298) (xy 34.720268 -100.950351)
			(xy 5.06984 -100.950351) (xy 5.06984 -102.743852) (xy 36.752762 -102.743852) (xy 36.752762 -102.689348)
			(xy 36.760518 -102.6354) (xy 36.775873 -102.583104) (xy 36.798514 -102.533526) (xy 36.82798 -102.487674)
			(xy 36.863671 -102.446483) (xy 36.904861 -102.41079) (xy 36.950712 -102.381322) (xy 37.000289 -102.358679)
			(xy 37.052584 -102.343322) (xy 37.106532 -102.335563) (xy 37.133784 -102.335076) (xy 37.159692 -102.335512)
			(xy 37.211029 -102.342546) (xy 37.260943 -102.35646) (xy 37.308516 -102.376998) (xy 37.352874 -102.403782)
			(xy 37.393201 -102.436321) (xy 37.428755 -102.474015) (xy 37.444172 -102.494842) (xy 37.449921 -102.502165)
			(xy 37.465417 -102.512456) (xy 37.474398 -102.514908) (xy 37.504878 -102.521766) (xy 37.514153 -102.523526)
			(xy 37.532818 -102.520776) (xy 37.5412 -102.516432) (xy 37.567187 -102.502177) (xy 37.622052 -102.479745)
			(xy 37.679353 -102.464578) (xy 37.738131 -102.456931) (xy 37.797405 -102.456931) (xy 37.856183 -102.464578)
			(xy 37.913484 -102.479745) (xy 37.968349 -102.502177) (xy 37.994336 -102.516432) (xy 38.002759 -102.520655)
			(xy 38.021381 -102.523405) (xy 38.030658 -102.521766) (xy 38.061138 -102.514908) (xy 38.070127 -102.51247)
			(xy 38.085634 -102.502184) (xy 38.091364 -102.494842) (xy 38.106761 -102.473998) (xy 38.142306 -102.436288)
			(xy 38.182631 -102.403739) (xy 38.226992 -102.376952) (xy 38.274573 -102.356419) (xy 38.324496 -102.342518)
			(xy 38.375841 -102.335507) (xy 38.401752 -102.335076) (xy 38.429006 -102.335568) (xy 38.48296 -102.343319)
			(xy 38.535261 -102.35867) (xy 38.584845 -102.381309) (xy 38.630703 -102.410775) (xy 38.670273 -102.445058)
			(xy 44.669708 -102.445058) (xy 44.673779 -102.389436) (xy 44.685905 -102.334999) (xy 44.705828 -102.282908)
			(xy 44.733124 -102.234273) (xy 44.76721 -102.19013) (xy 44.807359 -102.151421) (xy 44.852717 -102.11897)
			(xy 44.902317 -102.093469) (xy 44.955101 -102.075462) (xy 45.009944 -102.065332) (xy 45.065678 -102.063295)
			(xy 45.121115 -102.069395) (xy 45.175072 -102.083501) (xy 45.226401 -102.105313) (xy 45.274007 -102.134367)
			(xy 45.316875 -102.170042) (xy 45.354092 -102.211579) (xy 45.384865 -102.258092) (xy 45.408537 -102.308589)
			(xy 45.424605 -102.361996) (xy 45.432725 -102.417172) (xy 45.433234 -102.445058) (xy 45.432725 -102.472944)
			(xy 45.424605 -102.52812) (xy 45.408537 -102.581527) (xy 45.384865 -102.632024) (xy 45.354092 -102.678537)
			(xy 45.316875 -102.720074) (xy 45.274007 -102.755749) (xy 45.226401 -102.784803) (xy 45.175072 -102.806615)
			(xy 45.121115 -102.820721) (xy 45.065678 -102.826821) (xy 45.009944 -102.824784) (xy 44.955101 -102.814654)
			(xy 44.902317 -102.796647) (xy 44.852717 -102.771146) (xy 44.807359 -102.738695) (xy 44.76721 -102.699986)
			(xy 44.733124 -102.655843) (xy 44.705828 -102.607208) (xy 44.685905 -102.555117) (xy 44.673779 -102.50068)
			(xy 44.669708 -102.445058) (xy 38.670273 -102.445058) (xy 38.671899 -102.446467) (xy 38.707597 -102.487659)
			(xy 38.737068 -102.533513) (xy 38.759713 -102.583094) (xy 38.775071 -102.635393) (xy 38.782829 -102.689346)
			(xy 38.782829 -102.743854) (xy 38.775071 -102.797807) (xy 38.760509 -102.847394) (xy 46.975774 -102.847394)
			(xy 46.979845 -102.791772) (xy 46.991971 -102.737335) (xy 47.011894 -102.685244) (xy 47.03919 -102.636609)
			(xy 47.073276 -102.592466) (xy 47.113425 -102.553757) (xy 47.158783 -102.521306) (xy 47.208383 -102.495805)
			(xy 47.261167 -102.477798) (xy 47.31601 -102.467668) (xy 47.371744 -102.465631) (xy 47.427181 -102.471731)
			(xy 47.429576 -102.472357) (xy 51.252013 -102.472357) (xy 51.252013 -102.417843) (xy 51.259771 -102.363885)
			(xy 51.27513 -102.311579) (xy 51.297777 -102.261992) (xy 51.32725 -102.216133) (xy 51.36295 -102.174935)
			(xy 51.404149 -102.139238) (xy 51.45001 -102.109767) (xy 51.499598 -102.087123) (xy 51.551904 -102.071767)
			(xy 51.605863 -102.064012) (xy 51.63312 -102.06355) (xy 51.650168 -102.063752) (xy 51.684128 -102.066803)
			(xy 51.700938 -102.069646) (xy 51.712266 -102.071057) (xy 51.734281 -102.065138) (xy 51.743356 -102.058216)
			(xy 51.767994 -102.03688) (xy 51.776342 -102.029007) (xy 51.785458 -102.00797) (xy 51.78552 -101.996494)
			(xy 51.785012 -101.976428) (xy 51.785012 -101.112574) (xy 51.78552 -101.093778) (xy 51.785447 -101.082216)
			(xy 51.776168 -101.061057) (xy 51.76774 -101.053138) (xy 51.743356 -101.032056) (xy 51.734389 -101.02505)
			(xy 51.712487 -101.018987) (xy 51.701192 -101.020372) (xy 51.684321 -101.023245) (xy 51.650233 -101.026295)
			(xy 51.63312 -101.026468) (xy 51.605863 -101.026086) (xy 51.551905 -101.018331) (xy 51.499599 -101.002975)
			(xy 51.450011 -100.980331) (xy 51.40415 -100.950861) (xy 51.362951 -100.915163) (xy 51.327251 -100.873966)
			(xy 51.297778 -100.828107) (xy 51.275132 -100.77852) (xy 51.259773 -100.726215) (xy 51.252015 -100.672257)
			(xy 51.252015 -100.617743) (xy 51.259773 -100.563785) (xy 51.275132 -100.51148) (xy 51.297778 -100.461893)
			(xy 51.327251 -100.416034) (xy 51.362951 -100.374837) (xy 51.40415 -100.339139) (xy 51.450011 -100.309669)
			(xy 51.499599 -100.287025) (xy 51.551905 -100.271669) (xy 51.605863 -100.263914) (xy 51.63312 -100.263452)
			(xy 51.660098 -100.263907) (xy 51.713517 -100.271491) (xy 51.765334 -100.286532) (xy 51.814511 -100.308731)
			(xy 51.860066 -100.337643) (xy 51.901088 -100.372691) (xy 51.936758 -100.413173) (xy 51.966362 -100.458281)
			(xy 51.989309 -100.507114) (xy 52.005141 -100.558694) (xy 52.009802 -100.58527) (xy 52.011975 -100.595498)
			(xy 52.023248 -100.613078) (xy 52.031646 -100.619306) (xy 52.10302 -100.666804) (xy 52.124102 -100.670614)
			(xy 52.134262 -100.668074) (xy 52.160966 -100.66201) (xy 52.215339 -100.65551) (xy 52.24272 -100.65512)
			(xy 52.270102 -100.655495) (xy 52.324478 -100.66199) (xy 52.351178 -100.668074) (xy 52.361338 -100.670614)
			(xy 52.38242 -100.666804) (xy 52.462684 -100.613464) (xy 52.47386 -100.595938) (xy 52.475638 -100.58527)
			(xy 52.480319 -100.558702) (xy 52.496175 -100.507139) (xy 52.519138 -100.458324) (xy 52.548749 -100.413231)
			(xy 52.584418 -100.37276) (xy 52.625433 -100.337718) (xy 52.670977 -100.308805) (xy 52.720139 -100.286596)
			(xy 52.771941 -100.271536) (xy 52.825347 -100.263924) (xy 52.85232 -100.263452) (xy 52.879691 -100.263894)
			(xy 52.933872 -100.271715) (xy 52.986376 -100.28721) (xy 53.036122 -100.310057) (xy 53.082088 -100.339788)
			(xy 53.103018 -100.357432) (xy 53.103272 -100.357686) (xy 53.110364 -100.363265) (xy 53.127276 -100.369517)
			(xy 53.136292 -100.369878) (xy 53.203348 -100.369878) (xy 53.212363 -100.369501) (xy 53.22928 -100.363268)
			(xy 53.236368 -100.357686) (xy 53.236368 -100.357432) (xy 53.236622 -100.357432) (xy 53.257577 -100.339821)
			(xy 53.303543 -100.310104) (xy 53.353285 -100.287262) (xy 53.40578 -100.271764) (xy 53.459952 -100.263929)
			(xy 53.48732 -100.263452) (xy 53.504368 -100.263654) (xy 53.538328 -100.266705) (xy 53.555138 -100.269548)
			(xy 53.566466 -100.270959) (xy 53.58848 -100.26504) (xy 53.597556 -100.258118) (xy 53.622194 -100.236782)
			(xy 53.630541 -100.228908) (xy 53.639657 -100.207872) (xy 53.63972 -100.196396) (xy 53.639212 -100.17633)
			(xy 53.639212 -99.312476) (xy 53.63972 -99.29368) (xy 53.639645 -99.282118) (xy 53.630367 -99.260959)
			(xy 53.62194 -99.25304) (xy 53.597556 -99.231958) (xy 53.588589 -99.224952) (xy 53.566687 -99.218889)
			(xy 53.555392 -99.220274) (xy 53.538521 -99.223147) (xy 53.504433 -99.226197) (xy 53.48732 -99.22637)
			(xy 53.460063 -99.225984) (xy 53.406105 -99.218229) (xy 53.353799 -99.202873) (xy 53.304212 -99.18023)
			(xy 53.258352 -99.150759) (xy 53.217152 -99.115062) (xy 53.181453 -99.073864) (xy 53.15198 -99.028006)
			(xy 53.129334 -98.978419) (xy 53.113975 -98.926115) (xy 53.106217 -98.872157) (xy 53.106217 -98.817643)
			(xy 53.113975 -98.763685) (xy 53.129334 -98.711381) (xy 53.15198 -98.661794) (xy 53.181453 -98.615936)
			(xy 53.217152 -98.574738) (xy 53.258352 -98.539041) (xy 53.304212 -98.50957) (xy 53.353799 -98.486927)
			(xy 53.406105 -98.471571) (xy 53.460063 -98.463816) (xy 53.48732 -98.463354) (xy 53.514298 -98.463807)
			(xy 53.567718 -98.471391) (xy 53.619534 -98.486433) (xy 53.668711 -98.508632) (xy 53.714266 -98.537544)
			(xy 53.755289 -98.572592) (xy 53.790959 -98.613074) (xy 53.820563 -98.658183) (xy 53.84351 -98.707015)
			(xy 53.859341 -98.758596) (xy 53.864002 -98.785172) (xy 53.866174 -98.7954) (xy 53.877448 -98.812981)
			(xy 53.885846 -98.819208) (xy 53.95722 -98.866706) (xy 53.978302 -98.870516) (xy 53.988462 -98.867976)
			(xy 54.015156 -98.861834) (xy 54.069532 -98.855214) (xy 54.09692 -98.854768) (xy 54.124308 -98.855205)
			(xy 54.178684 -98.861831) (xy 54.205378 -98.867976) (xy 54.215538 -98.870516) (xy 54.23662 -98.866706)
			(xy 54.316884 -98.813366) (xy 54.32806 -98.79584) (xy 54.329838 -98.785172) (xy 54.334521 -98.758604)
			(xy 54.350376 -98.707041) (xy 54.373339 -98.658226) (xy 54.40295 -98.613133) (xy 54.438619 -98.572662)
			(xy 54.479634 -98.537621) (xy 54.525177 -98.508707) (xy 54.57434 -98.486498) (xy 54.626141 -98.471438)
			(xy 54.679547 -98.463826) (xy 54.70652 -98.463354) (xy 54.733768 -98.463918) (xy 54.787708 -98.471676)
			(xy 54.839995 -98.487031) (xy 54.889564 -98.509671) (xy 54.935408 -98.539135) (xy 54.976591 -98.574823)
			(xy 55.012277 -98.616008) (xy 55.041739 -98.661853) (xy 55.064376 -98.711424) (xy 55.079729 -98.763712)
			(xy 55.087484 -98.817652) (xy 55.087484 -98.872148) (xy 55.079729 -98.926088) (xy 55.064376 -98.978376)
			(xy 55.041739 -99.027947) (xy 55.012277 -99.073792) (xy 54.976591 -99.114977) (xy 54.935408 -99.150665)
			(xy 54.889564 -99.180129) (xy 54.839995 -99.202769) (xy 54.787708 -99.218124) (xy 54.733768 -99.225882)
			(xy 54.70652 -99.22637) (xy 54.689408 -99.226181) (xy 54.655321 -99.223127) (xy 54.638448 -99.220274)
			(xy 54.627157 -99.218896) (xy 54.605266 -99.224976) (xy 54.596284 -99.231958) (xy 54.5719 -99.25304)
			(xy 54.563463 -99.26095) (xy 54.554203 -99.282115) (xy 54.55412 -99.29368) (xy 54.554628 -99.312476)
			(xy 54.554628 -99.750372) (xy 57.5978 -99.750372) (xy 57.601871 -99.69475) (xy 57.613997 -99.640313)
			(xy 57.63392 -99.588222) (xy 57.661216 -99.539587) (xy 57.695302 -99.495444) (xy 57.735451 -99.456735)
			(xy 57.780809 -99.424284) (xy 57.830409 -99.398783) (xy 57.883193 -99.380776) (xy 57.938036 -99.370646)
			(xy 57.99377 -99.368609) (xy 58.049207 -99.374709) (xy 58.103164 -99.388815) (xy 58.154493 -99.410627)
			(xy 58.202099 -99.439681) (xy 58.244967 -99.475356) (xy 58.282184 -99.516893) (xy 58.312957 -99.563406)
			(xy 58.336629 -99.613903) (xy 58.352697 -99.66731) (xy 58.360817 -99.722486) (xy 58.361326 -99.750372)
			(xy 58.360817 -99.778258) (xy 58.352697 -99.833434) (xy 58.336629 -99.886841) (xy 58.312957 -99.937338)
			(xy 58.282184 -99.983851) (xy 58.244967 -100.025388) (xy 58.202099 -100.061063) (xy 58.154493 -100.090117)
			(xy 58.103164 -100.111929) (xy 58.049207 -100.126035) (xy 57.99377 -100.132135) (xy 57.938036 -100.130098)
			(xy 57.883193 -100.119968) (xy 57.830409 -100.101961) (xy 57.780809 -100.07646) (xy 57.735451 -100.044009)
			(xy 57.695302 -100.0053) (xy 57.661216 -99.961157) (xy 57.63392 -99.912522) (xy 57.613997 -99.860431)
			(xy 57.601871 -99.805994) (xy 57.5978 -99.750372) (xy 54.554628 -99.750372) (xy 54.554628 -100.17633)
			(xy 54.55412 -100.196396) (xy 54.554316 -100.207842) (xy 54.563427 -100.228812) (xy 54.571646 -100.236782)
			(xy 54.596284 -100.258118) (xy 54.605287 -100.265191) (xy 54.627367 -100.27115) (xy 54.638702 -100.269548)
			(xy 54.65551 -100.266685) (xy 54.689471 -100.263634) (xy 54.70652 -100.263452) (xy 54.733767 -100.26402)
			(xy 54.787707 -100.271778) (xy 54.839994 -100.287133) (xy 54.889564 -100.309773) (xy 54.935407 -100.339236)
			(xy 54.97659 -100.374924) (xy 55.012276 -100.416109) (xy 55.041737 -100.461954) (xy 55.064374 -100.511525)
			(xy 55.079727 -100.563812) (xy 55.087482 -100.617753) (xy 55.087482 -100.672247) (xy 55.079727 -100.726188)
			(xy 55.067928 -100.766372) (xy 57.5978 -100.766372) (xy 57.601871 -100.71075) (xy 57.613997 -100.656313)
			(xy 57.63392 -100.604222) (xy 57.661216 -100.555587) (xy 57.695302 -100.511444) (xy 57.735451 -100.472735)
			(xy 57.780809 -100.440284) (xy 57.830409 -100.414783) (xy 57.883193 -100.396776) (xy 57.938036 -100.386646)
			(xy 57.99377 -100.384609) (xy 58.049207 -100.390709) (xy 58.103164 -100.404815) (xy 58.154493 -100.426627)
			(xy 58.202099 -100.455681) (xy 58.244967 -100.491356) (xy 58.282184 -100.532893) (xy 58.312957 -100.579406)
			(xy 58.336629 -100.629903) (xy 58.352697 -100.68331) (xy 58.360817 -100.738486) (xy 58.361326 -100.766372)
			(xy 58.360817 -100.794258) (xy 58.352697 -100.849434) (xy 58.336629 -100.902841) (xy 58.312957 -100.953338)
			(xy 58.282184 -100.999851) (xy 58.244967 -101.041388) (xy 58.202099 -101.077063) (xy 58.154493 -101.106117)
			(xy 58.103164 -101.127929) (xy 58.049207 -101.142035) (xy 57.99377 -101.148135) (xy 57.938036 -101.146098)
			(xy 57.883193 -101.135968) (xy 57.830409 -101.117961) (xy 57.780809 -101.09246) (xy 57.735451 -101.060009)
			(xy 57.695302 -101.0213) (xy 57.661216 -100.977157) (xy 57.63392 -100.928522) (xy 57.613997 -100.876431)
			(xy 57.601871 -100.821994) (xy 57.5978 -100.766372) (xy 55.067928 -100.766372) (xy 55.064374 -100.778475)
			(xy 55.041737 -100.828046) (xy 55.012276 -100.873891) (xy 54.97659 -100.915076) (xy 54.935407 -100.950764)
			(xy 54.889564 -100.980227) (xy 54.839994 -101.002867) (xy 54.787707 -101.018222) (xy 54.733767 -101.02598)
			(xy 54.70652 -101.026468) (xy 54.679514 -101.025968) (xy 54.626039 -101.018366) (xy 54.574172 -101.003295)
			(xy 54.524949 -100.981059) (xy 54.479356 -100.9521) (xy 54.438303 -100.917) (xy 54.402613 -100.876459)
			(xy 54.372999 -100.831289) (xy 54.350053 -100.782393) (xy 54.334235 -100.730749) (xy 54.329584 -100.704142)
			(xy 54.32806 -100.693474) (xy 54.31663 -100.675694) (xy 54.245256 -100.628196) (xy 54.236328 -100.622845)
			(xy 54.215863 -100.61917) (xy 54.205632 -100.621084) (xy 54.20487 -100.621084) (xy 54.1783 -100.6272)
			(xy 54.12418 -100.633822) (xy 54.09692 -100.634292) (xy 54.069595 -100.633846) (xy 54.015347 -100.627219)
			(xy 53.988716 -100.621084) (xy 53.988208 -100.621084) (xy 53.977974 -100.619262) (xy 53.957533 -100.622911)
			(xy 53.948584 -100.628196) (xy 53.87721 -100.675694) (xy 53.86578 -100.693474) (xy 53.864256 -100.704142)
			(xy 53.859586 -100.730745) (xy 53.843761 -100.782385) (xy 53.820812 -100.831277) (xy 53.791197 -100.876445)
			(xy 53.755509 -100.916985) (xy 53.714461 -100.952087) (xy 53.668874 -100.981051) (xy 53.619657 -101.003296)
			(xy 53.567796 -101.018379) (xy 53.514325 -101.025998) (xy 53.48732 -101.026468) (xy 53.45995 -101.025998)
			(xy 53.405771 -101.018182) (xy 53.353267 -101.002695) (xy 53.30352 -100.979854) (xy 53.257554 -100.950129)
			(xy 53.236622 -100.932488) (xy 53.236368 -100.932234) (xy 53.229272 -100.926662) (xy 53.212362 -100.920408)
			(xy 53.203348 -100.920042) (xy 53.136292 -100.920042) (xy 53.127274 -100.920386) (xy 53.110356 -100.926641)
			(xy 53.103272 -100.932234) (xy 53.103272 -100.932488) (xy 53.103018 -100.932488) (xy 53.082088 -100.95013)
			(xy 53.036115 -100.979842) (xy 52.986367 -101.002678) (xy 52.933866 -101.018168) (xy 52.879689 -101.025995)
			(xy 52.85232 -101.026468) (xy 52.835208 -101.026279) (xy 52.801121 -101.023225) (xy 52.784248 -101.020372)
			(xy 52.772957 -101.018994) (xy 52.751066 -101.025074) (xy 52.742084 -101.032056) (xy 52.7177 -101.053138)
			(xy 52.709264 -101.061049) (xy 52.700003 -101.082214) (xy 52.69992 -101.093778) (xy 52.700428 -101.112574)
			(xy 52.700428 -101.782372) (xy 57.5978 -101.782372) (xy 57.601871 -101.72675) (xy 57.613997 -101.672313)
			(xy 57.63392 -101.620222) (xy 57.661216 -101.571587) (xy 57.695302 -101.527444) (xy 57.735451 -101.488735)
			(xy 57.780809 -101.456284) (xy 57.830409 -101.430783) (xy 57.883193 -101.412776) (xy 57.938036 -101.402646)
			(xy 57.99377 -101.400609) (xy 58.049207 -101.406709) (xy 58.103164 -101.420815) (xy 58.154493 -101.442627)
			(xy 58.202099 -101.471681) (xy 58.244967 -101.507356) (xy 58.282184 -101.548893) (xy 58.312957 -101.595406)
			(xy 58.336629 -101.645903) (xy 58.352697 -101.69931) (xy 58.360817 -101.754486) (xy 58.361326 -101.782372)
			(xy 58.360817 -101.810258) (xy 58.352697 -101.865434) (xy 58.336629 -101.918841) (xy 58.312957 -101.969338)
			(xy 58.282184 -102.015851) (xy 58.244967 -102.057388) (xy 58.202099 -102.093063) (xy 58.154493 -102.122117)
			(xy 58.103164 -102.143929) (xy 58.049207 -102.158035) (xy 57.99377 -102.164135) (xy 57.938036 -102.162098)
			(xy 57.883193 -102.151968) (xy 57.830409 -102.133961) (xy 57.780809 -102.10846) (xy 57.735451 -102.076009)
			(xy 57.695302 -102.0373) (xy 57.661216 -101.993157) (xy 57.63392 -101.944522) (xy 57.613997 -101.892431)
			(xy 57.601871 -101.837994) (xy 57.5978 -101.782372) (xy 52.700428 -101.782372) (xy 52.700428 -101.976428)
			(xy 52.69992 -101.996494) (xy 52.700117 -102.00794) (xy 52.709227 -102.02891) (xy 52.717446 -102.03688)
			(xy 52.742084 -102.058216) (xy 52.751087 -102.065289) (xy 52.773167 -102.071248) (xy 52.784502 -102.069646)
			(xy 52.80131 -102.066783) (xy 52.835271 -102.063732) (xy 52.85232 -102.06355) (xy 52.879691 -102.063992)
			(xy 52.933872 -102.071814) (xy 52.986376 -102.087308) (xy 53.036122 -102.110155) (xy 53.082088 -102.139886)
			(xy 53.103018 -102.15753) (xy 53.109876 -102.163626) (xy 53.126894 -102.169976) (xy 53.212238 -102.169976)
			(xy 53.22951 -102.163372) (xy 53.236368 -102.157276) (xy 53.257299 -102.139634) (xy 53.303268 -102.109914)
			(xy 53.353015 -102.087074) (xy 53.405518 -102.071584) (xy 53.459696 -102.063764) (xy 53.487066 -102.063296)
			(xy 53.48732 -102.063296) (xy 53.514296 -102.063798) (xy 53.567711 -102.071381) (xy 53.619524 -102.086419)
			(xy 53.668698 -102.108614) (xy 53.714251 -102.137521) (xy 53.755273 -102.172563) (xy 53.790943 -102.213039)
			(xy 53.82055 -102.258141) (xy 53.843501 -102.306967) (xy 53.859337 -102.358541) (xy 53.864002 -102.385114)
			(xy 53.866154 -102.395347) (xy 53.877442 -102.412925) (xy 53.885846 -102.41915) (xy 53.95722 -102.466648)
			(xy 53.978302 -102.470458) (xy 53.988462 -102.467918) (xy 54.015165 -102.461853) (xy 54.069539 -102.455354)
			(xy 54.09692 -102.454964) (xy 54.124302 -102.455338) (xy 54.178678 -102.461833) (xy 54.205378 -102.467918)
			(xy 54.215538 -102.470458) (xy 54.23662 -102.466648) (xy 54.316884 -102.413308) (xy 54.32806 -102.395782)
			(xy 54.329838 -102.385114) (xy 54.334553 -102.358552) (xy 54.350403 -102.306989) (xy 54.37336 -102.258174)
			(xy 54.402967 -102.21308) (xy 54.438632 -102.172608) (xy 54.479644 -102.137565) (xy 54.525184 -102.108651)
			(xy 54.574344 -102.086441) (xy 54.626144 -102.07138) (xy 54.679548 -102.063768) (xy 54.70652 -102.063296)
			(xy 54.733771 -102.063775) (xy 54.787717 -102.071534) (xy 54.84001 -102.086891) (xy 54.889585 -102.109534)
			(xy 54.935433 -102.139001) (xy 54.976622 -102.174693) (xy 55.012311 -102.215883) (xy 55.041776 -102.261733)
			(xy 55.064416 -102.311309) (xy 55.07977 -102.363603) (xy 55.087526 -102.417549) (xy 55.087526 -102.472051)
			(xy 55.07977 -102.525997) (xy 55.064416 -102.578291) (xy 55.041776 -102.627867) (xy 55.012311 -102.673717)
			(xy 54.976622 -102.714907) (xy 54.935433 -102.750599) (xy 54.889585 -102.780066) (xy 54.849506 -102.798372)
			(xy 57.5978 -102.798372) (xy 57.601871 -102.74275) (xy 57.613997 -102.688313) (xy 57.63392 -102.636222)
			(xy 57.661216 -102.587587) (xy 57.695302 -102.543444) (xy 57.735451 -102.504735) (xy 57.780809 -102.472284)
			(xy 57.830409 -102.446783) (xy 57.883193 -102.428776) (xy 57.938036 -102.418646) (xy 57.99377 -102.416609)
			(xy 58.049207 -102.422709) (xy 58.103164 -102.436815) (xy 58.154493 -102.458627) (xy 58.202099 -102.487681)
			(xy 58.244967 -102.523356) (xy 58.282184 -102.564893) (xy 58.312957 -102.611406) (xy 58.336629 -102.661903)
			(xy 58.352697 -102.71531) (xy 58.360817 -102.770486) (xy 58.361326 -102.798372) (xy 58.360817 -102.826258)
			(xy 58.352697 -102.881434) (xy 58.336629 -102.934841) (xy 58.312957 -102.985338) (xy 58.282184 -103.031851)
			(xy 58.244967 -103.073388) (xy 58.202099 -103.109063) (xy 58.154493 -103.138117) (xy 58.103164 -103.159929)
			(xy 58.049207 -103.174035) (xy 57.99377 -103.180135) (xy 57.938036 -103.178098) (xy 57.883193 -103.167968)
			(xy 57.830409 -103.149961) (xy 57.780809 -103.12446) (xy 57.735451 -103.092009) (xy 57.695302 -103.0533)
			(xy 57.661216 -103.009157) (xy 57.63392 -102.960522) (xy 57.613997 -102.908431) (xy 57.601871 -102.853994)
			(xy 57.5978 -102.798372) (xy 54.849506 -102.798372) (xy 54.84001 -102.802709) (xy 54.787717 -102.818066)
			(xy 54.733771 -102.825825) (xy 54.70652 -102.826312) (xy 54.689408 -102.826124) (xy 54.655321 -102.823069)
			(xy 54.638448 -102.820216) (xy 54.627157 -102.818851) (xy 54.605268 -102.824924) (xy 54.596284 -102.8319)
			(xy 54.5719 -102.852982) (xy 54.563491 -102.860916) (xy 54.554215 -102.882063) (xy 54.55412 -102.893622)
			(xy 54.554628 -102.912418) (xy 54.554628 -103.776272) (xy 54.55412 -103.796338) (xy 54.55435 -103.807781)
			(xy 54.557206 -103.814372) (xy 57.5978 -103.814372) (xy 57.601871 -103.75875) (xy 57.613997 -103.704313)
			(xy 57.63392 -103.652222) (xy 57.661216 -103.603587) (xy 57.695302 -103.559444) (xy 57.735451 -103.520735)
			(xy 57.780809 -103.488284) (xy 57.830409 -103.462783) (xy 57.883193 -103.444776) (xy 57.938036 -103.434646)
			(xy 57.99377 -103.432609) (xy 58.049207 -103.438709) (xy 58.103164 -103.452815) (xy 58.154493 -103.474627)
			(xy 58.202099 -103.503681) (xy 58.244967 -103.539356) (xy 58.282184 -103.580893) (xy 58.312957 -103.627406)
			(xy 58.336629 -103.677903) (xy 58.352697 -103.73131) (xy 58.360817 -103.786486) (xy 58.361326 -103.814372)
			(xy 58.360817 -103.842258) (xy 58.352697 -103.897434) (xy 58.336629 -103.950841) (xy 58.312957 -104.001338)
			(xy 58.282184 -104.047851) (xy 58.244967 -104.089388) (xy 58.202099 -104.125063) (xy 58.154493 -104.154117)
			(xy 58.103164 -104.175929) (xy 58.049207 -104.190035) (xy 57.99377 -104.196135) (xy 57.938036 -104.194098)
			(xy 57.883193 -104.183968) (xy 57.830409 -104.165961) (xy 57.780809 -104.14046) (xy 57.735451 -104.108009)
			(xy 57.695302 -104.0693) (xy 57.661216 -104.025157) (xy 57.63392 -103.976522) (xy 57.613997 -103.924431)
			(xy 57.601871 -103.869994) (xy 57.5978 -103.814372) (xy 54.557206 -103.814372) (xy 54.563437 -103.828751)
			(xy 54.571646 -103.836724) (xy 54.596284 -103.85806) (xy 54.605283 -103.865138) (xy 54.627366 -103.871093)
			(xy 54.638702 -103.86949) (xy 54.65551 -103.866628) (xy 54.689471 -103.863576) (xy 54.70652 -103.863394)
			(xy 54.73377 -103.863877) (xy 54.787716 -103.871636) (xy 54.840009 -103.886993) (xy 54.889584 -103.909635)
			(xy 54.935432 -103.939102) (xy 54.97662 -103.974794) (xy 55.01231 -104.015984) (xy 55.041774 -104.061834)
			(xy 55.064414 -104.11141) (xy 55.079768 -104.163703) (xy 55.087524 -104.21765) (xy 55.087524 -104.27215)
			(xy 55.079768 -104.326097) (xy 55.064414 -104.37839) (xy 55.041774 -104.427966) (xy 55.01231 -104.473816)
			(xy 54.97662 -104.515006) (xy 54.935432 -104.550698) (xy 54.889584 -104.580165) (xy 54.840009 -104.602807)
			(xy 54.787716 -104.618164) (xy 54.73377 -104.625923) (xy 54.70652 -104.62641) (xy 54.679511 -104.625959)
			(xy 54.626033 -104.618355) (xy 54.574161 -104.603282) (xy 54.524936 -104.581041) (xy 54.47934 -104.552078)
			(xy 54.438287 -104.516971) (xy 54.402598 -104.476424) (xy 54.372986 -104.431247) (xy 54.350044 -104.382344)
			(xy 54.334231 -104.330694) (xy 54.329584 -104.304084) (xy 54.32806 -104.293416) (xy 54.31663 -104.275636)
			(xy 54.245256 -104.228138) (xy 54.23633 -104.222783) (xy 54.215864 -104.219113) (xy 54.205632 -104.221026)
			(xy 54.20487 -104.221026) (xy 54.178294 -104.227079) (xy 54.124174 -104.233572) (xy 54.09692 -104.23398)
			(xy 54.069602 -104.233595) (xy 54.015353 -104.227099) (xy 53.988716 -104.221026) (xy 53.988208 -104.221026)
			(xy 53.977974 -104.219198) (xy 53.957532 -104.22285) (xy 53.948584 -104.228138) (xy 53.87721 -104.275636)
			(xy 53.86578 -104.293416) (xy 53.864256 -104.304084) (xy 53.859618 -104.330693) (xy 53.843787 -104.382333)
			(xy 53.820833 -104.431225) (xy 53.791214 -104.476392) (xy 53.755523 -104.516931) (xy 53.714471 -104.552032)
			(xy 53.668881 -104.580995) (xy 53.619662 -104.603239) (xy 53.567798 -104.618322) (xy 53.514326 -104.625941)
			(xy 53.48732 -104.62641) (xy 53.45995 -104.62593) (xy 53.405772 -104.618115) (xy 53.353269 -104.602629)
			(xy 53.303522 -104.579791) (xy 53.257554 -104.550069) (xy 53.236622 -104.53243) (xy 53.236368 -104.532176)
			(xy 53.229268 -104.526609) (xy 53.212361 -104.520351) (xy 53.203348 -104.519984) (xy 53.136292 -104.519984)
			(xy 53.127275 -104.520341) (xy 53.110358 -104.526589) (xy 53.103272 -104.532176) (xy 53.103272 -104.53243)
			(xy 53.103018 -104.53243) (xy 53.082094 -104.550079) (xy 53.036118 -104.579788) (xy 52.986369 -104.602622)
			(xy 52.933867 -104.618111) (xy 52.87969 -104.625937) (xy 52.85232 -104.62641) (xy 52.835208 -104.626222)
			(xy 52.801121 -104.623168) (xy 52.784248 -104.620314) (xy 52.772957 -104.61895) (xy 52.751068 -104.625023)
			(xy 52.742084 -104.631998) (xy 52.7177 -104.65308) (xy 52.709292 -104.661015) (xy 52.700015 -104.682161)
			(xy 52.69992 -104.69372) (xy 52.700428 -104.712516) (xy 52.700428 -104.830372) (xy 57.5978 -104.830372)
			(xy 57.601871 -104.77475) (xy 57.613997 -104.720313) (xy 57.63392 -104.668222) (xy 57.661216 -104.619587)
			(xy 57.695302 -104.575444) (xy 57.735451 -104.536735) (xy 57.780809 -104.504284) (xy 57.830409 -104.478783)
			(xy 57.883193 -104.460776) (xy 57.938036 -104.450646) (xy 57.99377 -104.448609) (xy 58.049207 -104.454709)
			(xy 58.103164 -104.468815) (xy 58.154493 -104.490627) (xy 58.202099 -104.519681) (xy 58.244967 -104.555356)
			(xy 58.282184 -104.596893) (xy 58.312957 -104.643406) (xy 58.336629 -104.693903) (xy 58.352697 -104.74731)
			(xy 58.360817 -104.802486) (xy 58.361326 -104.830372) (xy 58.360817 -104.858258) (xy 58.352697 -104.913434)
			(xy 58.336629 -104.966841) (xy 58.312957 -105.017338) (xy 58.282184 -105.063851) (xy 58.244967 -105.105388)
			(xy 58.202099 -105.141063) (xy 58.154493 -105.170117) (xy 58.103164 -105.191929) (xy 58.049207 -105.206035)
			(xy 57.99377 -105.212135) (xy 57.938036 -105.210098) (xy 57.883193 -105.199968) (xy 57.830409 -105.181961)
			(xy 57.780809 -105.15646) (xy 57.735451 -105.124009) (xy 57.695302 -105.0853) (xy 57.661216 -105.041157)
			(xy 57.63392 -104.992522) (xy 57.613997 -104.940431) (xy 57.601871 -104.885994) (xy 57.5978 -104.830372)
			(xy 52.700428 -104.830372) (xy 52.700428 -105.57637) (xy 52.69992 -105.596436) (xy 52.700151 -105.607879)
			(xy 52.709237 -105.628849) (xy 52.717446 -105.636822) (xy 52.742084 -105.658158) (xy 52.751084 -105.665235)
			(xy 52.773166 -105.671191) (xy 52.784502 -105.669588) (xy 52.80131 -105.666726) (xy 52.835271 -105.663674)
			(xy 52.85232 -105.663492) (xy 52.879691 -105.663948) (xy 52.93387 -105.671769) (xy 52.986373 -105.68726)
			(xy 53.03612 -105.710104) (xy 53.082086 -105.73983) (xy 53.103018 -105.757472) (xy 53.109876 -105.763568)
			(xy 53.126894 -105.769918) (xy 53.212238 -105.769918) (xy 53.22951 -105.763314) (xy 53.236368 -105.757218)
			(xy 53.257292 -105.739567) (xy 53.303263 -105.70985) (xy 53.353013 -105.687013) (xy 53.405516 -105.671525)
			(xy 53.459696 -105.663706) (xy 53.487066 -105.663238) (xy 53.48732 -105.663238) (xy 53.514297 -105.663705)
			(xy 53.567716 -105.671288) (xy 53.619531 -105.686329) (xy 53.668708 -105.708527) (xy 53.714262 -105.737438)
			(xy 53.755284 -105.772484) (xy 53.790954 -105.812965) (xy 53.820559 -105.858071) (xy 53.843507 -105.906902)
			(xy 53.85934 -105.958481) (xy 53.864002 -105.985056) (xy 53.866135 -105.995295) (xy 53.877437 -106.01287)
			(xy 53.885846 -106.019092) (xy 53.95722 -106.06659) (xy 53.978302 -106.0704) (xy 53.988462 -106.06786)
			(xy 54.015156 -106.061719) (xy 54.069532 -106.055098) (xy 54.09692 -106.054652) (xy 54.124308 -106.055089)
			(xy 54.178684 -106.061715) (xy 54.205378 -106.06786) (xy 54.215538 -106.0704) (xy 54.23662 -106.06659)
			(xy 54.316884 -106.01325) (xy 54.32806 -105.995724) (xy 54.329838 -105.985056) (xy 54.334508 -105.958486)
			(xy 54.350366 -105.906923) (xy 54.373331 -105.858108) (xy 54.402943 -105.813016) (xy 54.438614 -105.772545)
			(xy 54.47963 -105.737503) (xy 54.525174 -105.70859) (xy 54.574338 -105.686382) (xy 54.62614 -105.671322)
			(xy 54.679547 -105.66371) (xy 54.70652 -105.663238) (xy 54.733774 -105.663633) (xy 54.787726 -105.671393)
			(xy 54.840024 -105.686752) (xy 54.889605 -105.709397) (xy 54.935458 -105.738867) (xy 54.976651 -105.774563)
			(xy 55.012345 -105.815758) (xy 55.041813 -105.861613) (xy 55.064455 -105.911194) (xy 55.079811 -105.963494)
			(xy 55.087568 -106.017446) (xy 55.087568 -106.071954) (xy 55.079811 -106.125906) (xy 55.064455 -106.178206)
			(xy 55.041813 -106.227787) (xy 55.012345 -106.273642) (xy 54.976651 -106.314837) (xy 54.935458 -106.350533)
			(xy 54.889605 -106.380003) (xy 54.840024 -106.402648) (xy 54.787726 -106.418007) (xy 54.733774 -106.425767)
			(xy 54.70652 -106.426254) (xy 54.689408 -106.426065) (xy 54.655321 -106.423011) (xy 54.638448 -106.420158)
			(xy 54.627157 -106.418784) (xy 54.605266 -106.424862) (xy 54.596284 -106.431842) (xy 54.5719 -106.452924)
			(xy 54.563471 -106.460841) (xy 54.554206 -106.482001) (xy 54.55412 -106.493564) (xy 54.554628 -106.51236)
			(xy 54.554628 -107.376214) (xy 54.55412 -107.39628) (xy 54.554325 -107.407725) (xy 54.563429 -107.428695)
			(xy 54.571646 -107.436666) (xy 54.596284 -107.458002) (xy 54.605288 -107.465074) (xy 54.627367 -107.471035)
			(xy 54.638702 -107.469432) (xy 54.65551 -107.46657) (xy 54.689471 -107.463518) (xy 54.70652 -107.463336)
			(xy 54.733773 -107.463735) (xy 54.787725 -107.471495) (xy 54.840024 -107.486854) (xy 54.889604 -107.509499)
			(xy 54.935457 -107.538969) (xy 54.97665 -107.574664) (xy 55.012343 -107.615859) (xy 55.041811 -107.661714)
			(xy 55.064453 -107.711295) (xy 55.079809 -107.763594) (xy 55.087566 -107.817547) (xy 55.087566 -107.872053)
			(xy 55.079809 -107.926006) (xy 55.064453 -107.978305) (xy 55.041811 -108.027886) (xy 55.012343 -108.073741)
			(xy 54.97665 -108.114936) (xy 54.935457 -108.150631) (xy 54.889604 -108.180101) (xy 54.840024 -108.202746)
			(xy 54.787725 -108.218105) (xy 54.733773 -108.225865) (xy 54.70652 -108.226352) (xy 54.679513 -108.225866)
			(xy 54.626037 -108.218263) (xy 54.574169 -108.203192) (xy 54.524945 -108.180954) (xy 54.479351 -108.151994)
			(xy 54.438299 -108.116892) (xy 54.402609 -108.07635) (xy 54.372995 -108.031177) (xy 54.350051 -107.98228)
			(xy 54.334234 -107.930634) (xy 54.329584 -107.904026) (xy 54.32806 -107.893358) (xy 54.31663 -107.875578)
			(xy 54.245256 -107.82808) (xy 54.236329 -107.822728) (xy 54.215863 -107.819054) (xy 54.205632 -107.820968)
			(xy 54.20487 -107.820968) (xy 54.1783 -107.827083) (xy 54.12418 -107.833706) (xy 54.09692 -107.834176)
			(xy 54.069595 -107.83373) (xy 54.015347 -107.827103) (xy 53.988716 -107.820968) (xy 53.988208 -107.820968)
			(xy 53.977974 -107.819149) (xy 53.957533 -107.822797) (xy 53.948584 -107.82808) (xy 53.87721 -107.875578)
			(xy 53.86578 -107.893358) (xy 53.864256 -107.904026) (xy 53.85965 -107.930641) (xy 53.843814 -107.982281)
			(xy 53.820855 -108.031172) (xy 53.791231 -108.076338) (xy 53.755536 -108.116877) (xy 53.714481 -108.151977)
			(xy 53.668888 -108.180939) (xy 53.619667 -108.203182) (xy 53.567801 -108.218264) (xy 53.514327 -108.225883)
			(xy 53.48732 -108.226352) (xy 53.45995 -108.225886) (xy 53.40577 -108.21807) (xy 53.353267 -108.202581)
			(xy 53.30352 -108.179739) (xy 53.257553 -108.150014) (xy 53.236622 -108.132372) (xy 53.236368 -108.132118)
			(xy 53.229264 -108.126556) (xy 53.212361 -108.120294) (xy 53.203348 -108.119926) (xy 53.136292 -108.119926)
			(xy 53.127274 -108.120273) (xy 53.110357 -108.126527) (xy 53.103272 -108.132118) (xy 53.103272 -108.132372)
			(xy 53.103018 -108.132372) (xy 53.082086 -108.150012) (xy 53.036114 -108.179724) (xy 52.986366 -108.202561)
			(xy 52.933865 -108.218052) (xy 52.879689 -108.225879) (xy 52.85232 -108.226352) (xy 52.835208 -108.226163)
			(xy 52.801121 -108.223109) (xy 52.784248 -108.220256) (xy 52.772957 -108.218882) (xy 52.751066 -108.22496)
			(xy 52.742084 -108.23194) (xy 52.7177 -108.253022) (xy 52.709272 -108.260939) (xy 52.700007 -108.282099)
			(xy 52.69992 -108.293662) (xy 52.700428 -108.312458) (xy 52.700428 -109.176312) (xy 52.69992 -109.196378)
			(xy 52.700127 -109.207823) (xy 52.70923 -109.228793) (xy 52.717446 -109.236764) (xy 52.742084 -109.2581)
			(xy 52.751088 -109.265172) (xy 52.773167 -109.271133) (xy 52.784502 -109.26953) (xy 52.80131 -109.266668)
			(xy 52.835271 -109.263616) (xy 52.85232 -109.263434) (xy 52.879691 -109.26388) (xy 52.933871 -109.271701)
			(xy 52.986375 -109.287195) (xy 53.036122 -109.310041) (xy 53.082087 -109.33977) (xy 53.103018 -109.357414)
			(xy 53.103272 -109.357668) (xy 53.110357 -109.363257) (xy 53.127275 -109.3695) (xy 53.136292 -109.36986)
			(xy 53.203348 -109.36986) (xy 53.212363 -109.369487) (xy 53.229281 -109.363251) (xy 53.236368 -109.357668)
			(xy 53.236368 -109.357414) (xy 53.236622 -109.357414) (xy 53.257574 -109.3398) (xy 53.303541 -109.310084)
			(xy 53.353284 -109.287243) (xy 53.40578 -109.271746) (xy 53.459952 -109.263911) (xy 53.48732 -109.263434)
			(xy 53.514297 -109.263904) (xy 53.567715 -109.271488) (xy 53.61953 -109.286528) (xy 53.668707 -109.308726)
			(xy 53.714261 -109.337636) (xy 53.755283 -109.372682) (xy 53.790953 -109.413162) (xy 53.820558 -109.458268)
			(xy 53.843507 -109.507098) (xy 53.85934 -109.558677) (xy 53.864002 -109.585252) (xy 53.866136 -109.59549)
			(xy 53.877437 -109.613066) (xy 53.885846 -109.619288) (xy 53.95722 -109.666786) (xy 53.978302 -109.670596)
			(xy 53.988462 -109.668056) (xy 54.015156 -109.661915) (xy 54.069532 -109.655294) (xy 54.09692 -109.654848)
			(xy 54.124308 -109.655285) (xy 54.178684 -109.661911) (xy 54.205378 -109.668056) (xy 54.215538 -109.670596)
			(xy 54.23662 -109.666786) (xy 54.316884 -109.613446) (xy 54.32806 -109.59592) (xy 54.329838 -109.585252)
			(xy 54.334505 -109.558682) (xy 54.350364 -109.507118) (xy 54.373329 -109.458303) (xy 54.402942 -109.413211)
			(xy 54.438612 -109.37274) (xy 54.479629 -109.337699) (xy 54.525174 -109.308786) (xy 54.574337 -109.286578)
			(xy 54.626139 -109.271518) (xy 54.679547 -109.263906) (xy 54.70652 -109.263434) (xy 54.733773 -109.263837)
			(xy 54.787725 -109.271597) (xy 54.840023 -109.286955) (xy 54.889603 -109.3096) (xy 54.935456 -109.33907)
			(xy 54.976648 -109.374766) (xy 55.012342 -109.41596) (xy 55.041809 -109.461815) (xy 55.064452 -109.511396)
			(xy 55.079807 -109.563695) (xy 55.087564 -109.617647) (xy 55.087564 -109.672153) (xy 55.079807 -109.726105)
			(xy 55.064452 -109.778404) (xy 55.041809 -109.827985) (xy 55.012342 -109.87384) (xy 54.976648 -109.915034)
			(xy 54.935456 -109.95073) (xy 54.889603 -109.9802) (xy 54.840023 -110.002845) (xy 54.787725 -110.018203)
			(xy 54.733773 -110.025963) (xy 54.70652 -110.02645) (xy 54.689408 -110.026261) (xy 54.655321 -110.023207)
			(xy 54.638448 -110.020354) (xy 54.627157 -110.018981) (xy 54.605267 -110.025058) (xy 54.596284 -110.032038)
			(xy 54.5719 -110.05312) (xy 54.563473 -110.061038) (xy 54.554207 -110.082197) (xy 54.55412 -110.09376)
			(xy 54.554628 -110.112556) (xy 54.554628 -110.97641) (xy 54.55412 -110.996476) (xy 54.554328 -111.007921)
			(xy 54.56343 -111.028891) (xy 54.571646 -111.036862) (xy 54.596284 -111.058198) (xy 54.605288 -111.06527)
			(xy 54.627367 -111.071231) (xy 54.638702 -111.069628) (xy 54.65551 -111.066766) (xy 54.689471 -111.063714)
			(xy 54.70652 -111.063532) (xy 54.733773 -111.063939) (xy 54.787724 -111.071699) (xy 54.840022 -111.087057)
			(xy 54.889602 -111.109702) (xy 54.935455 -111.139172) (xy 54.976647 -111.174867) (xy 55.01234 -111.216061)
			(xy 55.041808 -111.261915) (xy 55.06445 -111.311497) (xy 55.079805 -111.363795) (xy 55.087562 -111.417747)
			(xy 55.087562 -111.472253) (xy 55.079805 -111.526205) (xy 55.06445 -111.578503) (xy 55.041808 -111.628085)
			(xy 55.01234 -111.673939) (xy 54.976647 -111.715133) (xy 54.935455 -111.750828) (xy 54.889602 -111.780298)
			(xy 54.840022 -111.802943) (xy 54.787724 -111.818301) (xy 54.733773 -111.826061) (xy 54.70652 -111.826548)
			(xy 54.679513 -111.826065) (xy 54.626037 -111.818462) (xy 54.574168 -111.803391) (xy 54.524944 -111.781153)
			(xy 54.47935 -111.752193) (xy 54.438298 -111.71709) (xy 54.402608 -111.676547) (xy 54.372994 -111.631375)
			(xy 54.35005 -111.582476) (xy 54.334234 -111.53083) (xy 54.329584 -111.504222) (xy 54.32806 -111.493554)
			(xy 54.31663 -111.475774) (xy 54.245256 -111.428276) (xy 54.236329 -111.422923) (xy 54.215863 -111.41925)
			(xy 54.205632 -111.421164) (xy 54.20487 -111.421164) (xy 54.1783 -111.427279) (xy 54.12418 -111.433902)
			(xy 54.09692 -111.434372) (xy 54.069595 -111.433924) (xy 54.015347 -111.427298) (xy 53.988716 -111.421164)
			(xy 53.988208 -111.421164) (xy 53.977974 -111.419345) (xy 53.957534 -111.422993) (xy 53.948584 -111.428276)
			(xy 53.87721 -111.475774) (xy 53.86578 -111.493554) (xy 53.864256 -111.504222) (xy 53.859647 -111.530836)
			(xy 53.843811 -111.582476) (xy 53.820852 -111.631368) (xy 53.79123 -111.676534) (xy 53.755535 -111.717072)
			(xy 53.71448 -111.752173) (xy 53.668887 -111.781134) (xy 53.619666 -111.803378) (xy 53.567801 -111.81846)
			(xy 53.514327 -111.826079) (xy 53.48732 -111.826548) (xy 53.45995 -111.826083) (xy 53.40577 -111.818267)
			(xy 53.353266 -111.802778) (xy 53.303519 -111.779936) (xy 53.257553 -111.75021) (xy 53.236622 -111.732568)
			(xy 53.236368 -111.732314) (xy 53.229265 -111.726751) (xy 53.212361 -111.72049) (xy 53.203348 -111.720122)
			(xy 53.136292 -111.720122) (xy 53.127274 -111.72047) (xy 53.110357 -111.726723) (xy 53.103272 -111.732314)
			(xy 53.103272 -111.732568) (xy 53.103018 -111.732568) (xy 53.082086 -111.750207) (xy 53.036114 -111.77992)
			(xy 52.986366 -111.802757) (xy 52.933865 -111.818247) (xy 52.879689 -111.826075) (xy 52.85232 -111.826548)
			(xy 52.835208 -111.826359) (xy 52.801121 -111.823305) (xy 52.784248 -111.820452) (xy 52.772957 -111.819079)
			(xy 52.751067 -111.825157) (xy 52.742084 -111.832136) (xy 52.7177 -111.853218) (xy 52.709274 -111.861137)
			(xy 52.700007 -111.882296) (xy 52.69992 -111.893858) (xy 52.700428 -111.912654) (xy 52.700428 -112.510824)
			(xy 63.802512 -112.510824) (xy 63.806583 -112.455202) (xy 63.818709 -112.400765) (xy 63.838632 -112.348674)
			(xy 63.865928 -112.300039) (xy 63.900014 -112.255896) (xy 63.940163 -112.217187) (xy 63.985521 -112.184736)
			(xy 64.035121 -112.159235) (xy 64.087905 -112.141228) (xy 64.142748 -112.131098) (xy 64.198482 -112.129061)
			(xy 64.253919 -112.135161) (xy 64.307876 -112.149267) (xy 64.359205 -112.171079) (xy 64.406811 -112.200133)
			(xy 64.449679 -112.235808) (xy 64.486896 -112.277345) (xy 64.517669 -112.323858) (xy 64.541341 -112.374355)
			(xy 64.557409 -112.427762) (xy 64.565529 -112.482938) (xy 64.566038 -112.510824) (xy 64.565529 -112.53871)
			(xy 64.557409 -112.593886) (xy 64.541341 -112.647293) (xy 64.517669 -112.69779) (xy 64.486896 -112.744303)
			(xy 64.449679 -112.78584) (xy 64.406811 -112.821515) (xy 64.359205 -112.850569) (xy 64.307876 -112.872381)
			(xy 64.253919 -112.886487) (xy 64.198482 -112.892587) (xy 64.142748 -112.89055) (xy 64.087905 -112.88042)
			(xy 64.035121 -112.862413) (xy 63.985521 -112.836912) (xy 63.940163 -112.804461) (xy 63.900014 -112.765752)
			(xy 63.865928 -112.721609) (xy 63.838632 -112.672974) (xy 63.818709 -112.620883) (xy 63.806583 -112.566446)
			(xy 63.802512 -112.510824) (xy 52.700428 -112.510824) (xy 52.700428 -112.776508) (xy 52.69992 -112.796574)
			(xy 52.700129 -112.808019) (xy 52.70923 -112.828989) (xy 52.717446 -112.83696) (xy 52.742084 -112.858296)
			(xy 52.751088 -112.865368) (xy 52.773167 -112.871329) (xy 52.784502 -112.869726) (xy 52.80131 -112.866864)
			(xy 52.835271 -112.863812) (xy 52.85232 -112.86363) (xy 52.879573 -112.864041) (xy 52.933524 -112.871801)
			(xy 52.985822 -112.887159) (xy 53.035401 -112.909804) (xy 53.081254 -112.939274) (xy 53.122446 -112.974969)
			(xy 53.158138 -113.016162) (xy 53.187606 -113.062016) (xy 53.210248 -113.111597) (xy 53.225603 -113.163896)
			(xy 53.23336 -113.217847) (xy 53.23336 -113.251742) (xy 64.306194 -113.251742) (xy 64.310265 -113.19612)
			(xy 64.322391 -113.141683) (xy 64.342314 -113.089592) (xy 64.36961 -113.040957) (xy 64.403696 -112.996814)
			(xy 64.443845 -112.958105) (xy 64.489203 -112.925654) (xy 64.538803 -112.900153) (xy 64.591587 -112.882146)
			(xy 64.64643 -112.872016) (xy 64.702164 -112.869979) (xy 64.757601 -112.876079) (xy 64.811558 -112.890185)
			(xy 64.862887 -112.911997) (xy 64.910493 -112.941051) (xy 64.953361 -112.976726) (xy 64.990578 -113.018263)
			(xy 65.021351 -113.064776) (xy 65.045023 -113.115273) (xy 65.061091 -113.16868) (xy 65.069211 -113.223856)
			(xy 65.06972 -113.251742) (xy 65.069211 -113.279628) (xy 65.061091 -113.334804) (xy 65.045023 -113.388211)
			(xy 65.021351 -113.438708) (xy 64.990578 -113.485221) (xy 64.953361 -113.526758) (xy 64.910493 -113.562433)
			(xy 64.862887 -113.591487) (xy 64.811558 -113.613299) (xy 64.757601 -113.627405) (xy 64.702164 -113.633505)
			(xy 64.64643 -113.631468) (xy 64.591587 -113.621338) (xy 64.538803 -113.603331) (xy 64.489203 -113.57783)
			(xy 64.443845 -113.545379) (xy 64.403696 -113.50667) (xy 64.36961 -113.462527) (xy 64.342314 -113.413892)
			(xy 64.322391 -113.361801) (xy 64.310265 -113.307364) (xy 64.306194 -113.251742) (xy 53.23336 -113.251742)
			(xy 53.23336 -113.272353) (xy 53.225603 -113.326304) (xy 53.210248 -113.378603) (xy 53.187606 -113.428184)
			(xy 53.158138 -113.474038) (xy 53.122446 -113.515231) (xy 53.081254 -113.550926) (xy 53.035401 -113.580396)
			(xy 52.985822 -113.603041) (xy 52.933524 -113.618399) (xy 52.879573 -113.626159) (xy 52.85232 -113.626646)
			(xy 52.825313 -113.626165) (xy 52.771837 -113.618562) (xy 52.719968 -113.60349) (xy 52.670744 -113.581252)
			(xy 52.62515 -113.552292) (xy 52.584097 -113.517189) (xy 52.548407 -113.476646) (xy 52.518794 -113.431473)
			(xy 52.49585 -113.382574) (xy 52.480033 -113.330928) (xy 52.475384 -113.30432) (xy 52.47386 -113.293652)
			(xy 52.46243 -113.275872) (xy 52.391056 -113.228374) (xy 52.382129 -113.223021) (xy 52.361663 -113.219349)
			(xy 52.351432 -113.221262) (xy 52.35067 -113.221262) (xy 52.324094 -113.227316) (xy 52.269974 -113.233808)
			(xy 52.24272 -113.234216) (xy 52.215402 -113.233832) (xy 52.161153 -113.227336) (xy 52.134516 -113.221262)
			(xy 52.134008 -113.221262) (xy 52.123774 -113.219444) (xy 52.103334 -113.223091) (xy 52.094384 -113.228374)
			(xy 52.02301 -113.275872) (xy 52.01158 -113.293652) (xy 52.010056 -113.30432) (xy 52.005446 -113.330934)
			(xy 51.98961 -113.382574) (xy 51.966651 -113.431466) (xy 51.937029 -113.476632) (xy 51.901334 -113.51717)
			(xy 51.86028 -113.552271) (xy 51.814687 -113.581232) (xy 51.765466 -113.603476) (xy 51.713601 -113.618558)
			(xy 51.660127 -113.626177) (xy 51.63312 -113.626646) (xy 51.605869 -113.626108) (xy 51.551921 -113.618354)
			(xy 51.499626 -113.603001) (xy 51.450048 -113.580362) (xy 51.404197 -113.550898) (xy 51.363006 -113.515208)
			(xy 51.327314 -113.474019) (xy 51.297847 -113.428169) (xy 51.275206 -113.378593) (xy 51.25985 -113.326298)
			(xy 51.252093 -113.272351) (xy 51.252093 -113.217849) (xy 51.25985 -113.163902) (xy 51.275206 -113.111607)
			(xy 51.297847 -113.062031) (xy 51.327314 -113.016181) (xy 51.363006 -112.974992) (xy 51.404197 -112.939302)
			(xy 51.450048 -112.909838) (xy 51.499626 -112.887199) (xy 51.551921 -112.871846) (xy 51.605869 -112.864092)
			(xy 51.63312 -112.86363) (xy 51.650168 -112.863833) (xy 51.684128 -112.866883) (xy 51.700938 -112.869726)
			(xy 51.712266 -112.871142) (xy 51.734281 -112.865221) (xy 51.743356 -112.858296) (xy 51.767994 -112.83696)
			(xy 51.776352 -112.829096) (xy 51.785462 -112.808052) (xy 51.78552 -112.796574) (xy 51.785012 -112.776508)
			(xy 51.785012 -111.912654) (xy 51.78552 -111.893858) (xy 51.7854 -111.8823) (xy 51.776154 -111.861142)
			(xy 51.76774 -111.853218) (xy 51.743356 -111.832136) (xy 51.734384 -111.825137) (xy 51.712486 -111.819066)
			(xy 51.701192 -111.820452) (xy 51.684321 -111.823325) (xy 51.650233 -111.826375) (xy 51.63312 -111.826548)
			(xy 51.605869 -111.826006) (xy 51.551922 -111.818252) (xy 51.499627 -111.8029) (xy 51.450049 -111.780261)
			(xy 51.404199 -111.750796) (xy 51.363008 -111.715106) (xy 51.327316 -111.673917) (xy 51.297849 -111.628068)
			(xy 51.275207 -111.578492) (xy 51.259852 -111.526198) (xy 51.252095 -111.472251) (xy 51.252095 -111.417749)
			(xy 51.259852 -111.363802) (xy 51.275207 -111.311508) (xy 51.297849 -111.261932) (xy 51.327316 -111.216083)
			(xy 51.363008 -111.174894) (xy 51.404199 -111.139204) (xy 51.450049 -111.109739) (xy 51.499627 -111.0871)
			(xy 51.551922 -111.071748) (xy 51.605869 -111.063994) (xy 51.63312 -111.063532) (xy 51.660097 -111.064004)
			(xy 51.713515 -111.071587) (xy 51.76533 -111.086628) (xy 51.814506 -111.108825) (xy 51.86006 -111.137735)
			(xy 51.901083 -111.172781) (xy 51.936753 -111.213261) (xy 51.966358 -111.258367) (xy 51.989306 -111.307197)
			(xy 52.005139 -111.358775) (xy 52.009802 -111.38535) (xy 52.011937 -111.395588) (xy 52.023238 -111.413164)
			(xy 52.031646 -111.419386) (xy 52.10302 -111.466884) (xy 52.124102 -111.470694) (xy 52.134262 -111.468154)
			(xy 52.160966 -111.46209) (xy 52.215339 -111.45559) (xy 52.24272 -111.4552) (xy 52.270102 -111.455576)
			(xy 52.324478 -111.46207) (xy 52.351178 -111.468154) (xy 52.361338 -111.470694) (xy 52.38242 -111.466884)
			(xy 52.462684 -111.413544) (xy 52.47386 -111.396018) (xy 52.475638 -111.38535) (xy 52.480304 -111.358779)
			(xy 52.496162 -111.307216) (xy 52.519128 -111.258401) (xy 52.548741 -111.213309) (xy 52.584412 -111.172838)
			(xy 52.625429 -111.137797) (xy 52.670973 -111.108884) (xy 52.720137 -111.086676) (xy 52.771939 -111.071616)
			(xy 52.825347 -111.064004) (xy 52.85232 -111.063532) (xy 52.879691 -111.063979) (xy 52.933871 -111.0718)
			(xy 52.986375 -111.087293) (xy 53.036121 -111.110139) (xy 53.082087 -111.139869) (xy 53.103018 -111.157512)
			(xy 53.103272 -111.157766) (xy 53.110357 -111.163355) (xy 53.127275 -111.169598) (xy 53.136292 -111.169958)
			(xy 53.203348 -111.169958) (xy 53.212363 -111.169585) (xy 53.229281 -111.16335) (xy 53.236368 -111.157766)
			(xy 53.236368 -111.157512) (xy 53.236622 -111.157512) (xy 53.257574 -111.139898) (xy 53.303541 -111.110182)
			(xy 53.353284 -111.087341) (xy 53.40578 -111.071844) (xy 53.459952 -111.064009) (xy 53.48732 -111.063532)
			(xy 53.504368 -111.063735) (xy 53.538328 -111.066785) (xy 53.555138 -111.069628) (xy 53.566466 -111.071043)
			(xy 53.588481 -111.065122) (xy 53.597556 -111.058198) (xy 53.622194 -111.036862) (xy 53.630551 -111.028997)
			(xy 53.639662 -111.007954) (xy 53.63972 -110.996476) (xy 53.639212 -110.97641) (xy 53.639212 -110.112556)
			(xy 53.63972 -110.09376) (xy 53.639598 -110.082202) (xy 53.630353 -110.061044) (xy 53.62194 -110.05312)
			(xy 53.597556 -110.032038) (xy 53.58859 -110.02503) (xy 53.566688 -110.018969) (xy 53.555392 -110.020354)
			(xy 53.538521 -110.023227) (xy 53.504433 -110.026277) (xy 53.48732 -110.02645) (xy 53.45995 -110.025984)
			(xy 53.40577 -110.018168) (xy 53.353266 -110.00268) (xy 53.30352 -109.979838) (xy 53.257553 -109.950112)
			(xy 53.236622 -109.93247) (xy 53.236368 -109.932216) (xy 53.229265 -109.926654) (xy 53.212361 -109.920392)
			(xy 53.203348 -109.920024) (xy 53.136292 -109.920024) (xy 53.127274 -109.920372) (xy 53.110357 -109.926625)
			(xy 53.103272 -109.932216) (xy 53.103272 -109.93247) (xy 53.103018 -109.93247) (xy 53.082086 -109.950109)
			(xy 53.036114 -109.979822) (xy 52.986366 -110.002659) (xy 52.933865 -110.018149) (xy 52.879689 -110.025977)
			(xy 52.85232 -110.02645) (xy 52.825313 -110.025966) (xy 52.771837 -110.018362) (xy 52.719968 -110.003291)
			(xy 52.670745 -109.981053) (xy 52.625151 -109.952093) (xy 52.584098 -109.916991) (xy 52.548408 -109.876448)
			(xy 52.518795 -109.831276) (xy 52.49585 -109.782378) (xy 52.480034 -109.730732) (xy 52.475384 -109.704124)
			(xy 52.47386 -109.693456) (xy 52.46243 -109.675676) (xy 52.391056 -109.628178) (xy 52.382129 -109.622825)
			(xy 52.361663 -109.619152) (xy 52.351432 -109.621066) (xy 52.35067 -109.621066) (xy 52.324094 -109.62712)
			(xy 52.269974 -109.633612) (xy 52.24272 -109.63402) (xy 52.215402 -109.633636) (xy 52.161153 -109.62714)
			(xy 52.134516 -109.621066) (xy 52.134008 -109.621066) (xy 52.123774 -109.619247) (xy 52.103333 -109.622895)
			(xy 52.094384 -109.628178) (xy 52.02301 -109.675676) (xy 52.01158 -109.693456) (xy 52.010056 -109.704124)
			(xy 52.005449 -109.730738) (xy 51.989613 -109.782379) (xy 51.966654 -109.83127) (xy 51.93703 -109.876436)
			(xy 51.901335 -109.916975) (xy 51.860281 -109.952075) (xy 51.814688 -109.981037) (xy 51.765467 -110.00328)
			(xy 51.713601 -110.018362) (xy 51.660127 -110.025981) (xy 51.63312 -110.02645) (xy 51.605869 -110.025904)
			(xy 51.551922 -110.01815) (xy 51.499628 -110.002798) (xy 51.45005 -109.980159) (xy 51.4042 -109.950695)
			(xy 51.363009 -109.915005) (xy 51.327317 -109.873816) (xy 51.297851 -109.827967) (xy 51.275209 -109.778391)
			(xy 51.259854 -109.726098) (xy 51.252097 -109.672151) (xy 51.252097 -109.617649) (xy 51.259854 -109.563702)
			(xy 51.275209 -109.511409) (xy 51.297851 -109.461833) (xy 51.327317 -109.415984) (xy 51.363009 -109.374795)
			(xy 51.4042 -109.339105) (xy 51.45005 -109.309641) (xy 51.499628 -109.287002) (xy 51.551922 -109.27165)
			(xy 51.605869 -109.263896) (xy 51.63312 -109.263434) (xy 51.650168 -109.263637) (xy 51.684128 -109.266687)
			(xy 51.700938 -109.26953) (xy 51.712266 -109.270945) (xy 51.734281 -109.265024) (xy 51.743356 -109.2581)
			(xy 51.767994 -109.236764) (xy 51.77635 -109.228898) (xy 51.785461 -109.207856) (xy 51.78552 -109.196378)
			(xy 51.785012 -109.176312) (xy 51.785012 -108.312458) (xy 51.78552 -108.293662) (xy 51.785397 -108.282104)
			(xy 51.776153 -108.260946) (xy 51.76774 -108.253022) (xy 51.743356 -108.23194) (xy 51.73439 -108.224932)
			(xy 51.712488 -108.218871) (xy 51.701192 -108.220256) (xy 51.684321 -108.223129) (xy 51.650233 -108.226179)
			(xy 51.63312 -108.226352) (xy 51.605869 -108.225802) (xy 51.551922 -108.218048) (xy 51.499628 -108.202696)
			(xy 51.450051 -108.180057) (xy 51.404201 -108.150593) (xy 51.363011 -108.114903) (xy 51.327319 -108.073715)
			(xy 51.297852 -108.027866) (xy 51.275211 -107.97829) (xy 51.259856 -107.925997) (xy 51.252099 -107.872051)
			(xy 51.252099 -107.817549) (xy 51.259856 -107.763603) (xy 51.275211 -107.71131) (xy 51.297852 -107.661734)
			(xy 51.327319 -107.615885) (xy 51.363011 -107.574697) (xy 51.404201 -107.539007) (xy 51.450051 -107.509543)
			(xy 51.499628 -107.486904) (xy 51.551922 -107.471552) (xy 51.605869 -107.463798) (xy 51.63312 -107.463336)
			(xy 51.660097 -107.463804) (xy 51.713516 -107.471388) (xy 51.765331 -107.486429) (xy 51.814507 -107.508626)
			(xy 51.860062 -107.537537) (xy 51.901084 -107.572583) (xy 51.936754 -107.613063) (xy 51.966359 -107.65817)
			(xy 51.989307 -107.707) (xy 52.00514 -107.758579) (xy 52.009802 -107.785154) (xy 52.011935 -107.795393)
			(xy 52.023237 -107.812968) (xy 52.031646 -107.81919) (xy 52.10302 -107.866688) (xy 52.124102 -107.870498)
			(xy 52.134262 -107.867958) (xy 52.160966 -107.861894) (xy 52.215339 -107.855394) (xy 52.24272 -107.855004)
			(xy 52.270102 -107.855379) (xy 52.324478 -107.861874) (xy 52.351178 -107.867958) (xy 52.361338 -107.870498)
			(xy 52.38242 -107.866688) (xy 52.462684 -107.813348) (xy 52.47386 -107.795822) (xy 52.475638 -107.785154)
			(xy 52.480307 -107.758584) (xy 52.496165 -107.707021) (xy 52.51913 -107.658206) (xy 52.548743 -107.613113)
			(xy 52.584413 -107.572643) (xy 52.62543 -107.537601) (xy 52.670974 -107.508688) (xy 52.720138 -107.48648)
			(xy 52.77194 -107.47142) (xy 52.825347 -107.463808) (xy 52.85232 -107.463336) (xy 52.879691 -107.463782)
			(xy 52.933871 -107.471603) (xy 52.986375 -107.487096) (xy 53.036122 -107.509943) (xy 53.082087 -107.539672)
			(xy 53.103018 -107.557316) (xy 53.103272 -107.55757) (xy 53.110356 -107.563159) (xy 53.127275 -107.569402)
			(xy 53.136292 -107.569762) (xy 53.203348 -107.569762) (xy 53.212363 -107.569388) (xy 53.229281 -107.563153)
			(xy 53.236368 -107.55757) (xy 53.236368 -107.557316) (xy 53.236622 -107.557316) (xy 53.257575 -107.539702)
			(xy 53.303542 -107.509986) (xy 53.353284 -107.487145) (xy 53.40578 -107.471648) (xy 53.459952 -107.463813)
			(xy 53.48732 -107.463336) (xy 53.504368 -107.463539) (xy 53.538328 -107.466589) (xy 53.555138 -107.469432)
			(xy 53.566466 -107.470846) (xy 53.588481 -107.464926) (xy 53.597556 -107.458002) (xy 53.622194 -107.436666)
			(xy 53.630549 -107.428799) (xy 53.639661 -107.407757) (xy 53.63972 -107.39628) (xy 53.639212 -107.376214)
			(xy 53.639212 -106.51236) (xy 53.63972 -106.493564) (xy 53.639596 -106.482006) (xy 53.630353 -106.460848)
			(xy 53.62194 -106.452924) (xy 53.597556 -106.431842) (xy 53.58859 -106.424835) (xy 53.566688 -106.418773)
			(xy 53.555392 -106.420158) (xy 53.538521 -106.423031) (xy 53.504433 -106.426081) (xy 53.48732 -106.426254)
			(xy 53.45995 -106.425787) (xy 53.40577 -106.417971) (xy 53.353267 -106.402483) (xy 53.30352 -106.379641)
			(xy 53.257553 -106.349916) (xy 53.236622 -106.332274) (xy 53.229764 -106.326178) (xy 53.212746 -106.319828)
			(xy 53.127402 -106.319828) (xy 53.11013 -106.326432) (xy 53.103272 -106.332528) (xy 53.082326 -106.350151)
			(xy 53.036362 -106.379875) (xy 52.986618 -106.402718) (xy 52.934119 -106.418212) (xy 52.879943 -106.426037)
			(xy 52.852574 -106.426508) (xy 52.85232 -106.426508) (xy 52.825315 -106.425975) (xy 52.771844 -106.418373)
			(xy 52.719979 -106.403305) (xy 52.670758 -106.381071) (xy 52.625166 -106.352116) (xy 52.584114 -106.31702)
			(xy 52.548424 -106.276483) (xy 52.518808 -106.231318) (xy 52.49586 -106.182427) (xy 52.480037 -106.130787)
			(xy 52.475384 -106.104182) (xy 52.47386 -106.093514) (xy 52.46243 -106.075734) (xy 52.391056 -106.028236)
			(xy 52.38213 -106.022881) (xy 52.361664 -106.019211) (xy 52.351432 -106.021124) (xy 52.35067 -106.021124)
			(xy 52.3241 -106.02724) (xy 52.26998 -106.033862) (xy 52.24272 -106.034332) (xy 52.215395 -106.033885)
			(xy 52.161147 -106.027258) (xy 52.134516 -106.021124) (xy 52.134008 -106.021124) (xy 52.123774 -106.019296)
			(xy 52.103332 -106.022948) (xy 52.094384 -106.028236) (xy 52.02301 -106.075734) (xy 52.01158 -106.093514)
			(xy 52.010056 -106.104182) (xy 52.005417 -106.13079) (xy 51.989586 -106.182431) (xy 51.966632 -106.231322)
			(xy 51.937013 -106.276489) (xy 51.901322 -106.317029) (xy 51.860271 -106.35213) (xy 51.81468 -106.381093)
			(xy 51.765462 -106.403337) (xy 51.713598 -106.41842) (xy 51.660126 -106.426039) (xy 51.63312 -106.426508)
			(xy 51.605866 -106.426046) (xy 51.551913 -106.418291) (xy 51.499613 -106.402937) (xy 51.45003 -106.380296)
			(xy 51.404175 -106.350828) (xy 51.36298 -106.315135) (xy 51.327284 -106.273941) (xy 51.297814 -106.228087)
			(xy 51.27517 -106.178506) (xy 51.259813 -106.126206) (xy 51.252055 -106.072254) (xy 51.252055 -106.017746)
			(xy 51.259813 -105.963794) (xy 51.27517 -105.911494) (xy 51.297814 -105.861913) (xy 51.327284 -105.816059)
			(xy 51.36298 -105.774865) (xy 51.404175 -105.739172) (xy 51.45003 -105.709704) (xy 51.499613 -105.687063)
			(xy 51.551913 -105.671709) (xy 51.605866 -105.663954) (xy 51.63312 -105.663492) (xy 51.650168 -105.663694)
			(xy 51.684128 -105.666745) (xy 51.700938 -105.669588) (xy 51.712266 -105.67099) (xy 51.734279 -105.665076)
			(xy 51.743356 -105.658158) (xy 51.767994 -105.636822) (xy 51.776322 -105.628932) (xy 51.785449 -105.607908)
			(xy 51.78552 -105.596436) (xy 51.785012 -105.57637) (xy 51.785012 -104.712516) (xy 51.78552 -104.69372)
			(xy 51.785422 -104.68216) (xy 51.77616 -104.661002) (xy 51.76774 -104.65308) (xy 51.743356 -104.631998)
			(xy 51.734386 -104.624996) (xy 51.712487 -104.618928) (xy 51.701192 -104.620314) (xy 51.684321 -104.623187)
			(xy 51.650233 -104.626237) (xy 51.63312 -104.62641) (xy 51.605866 -104.625944) (xy 51.551914 -104.618189)
			(xy 51.499614 -104.602835) (xy 51.450031 -104.580194) (xy 51.404176 -104.550727) (xy 51.362981 -104.515033)
			(xy 51.327285 -104.47384) (xy 51.297816 -104.427986) (xy 51.275172 -104.378405) (xy 51.259815 -104.326106)
			(xy 51.252057 -104.272154) (xy 51.252057 -104.217646) (xy 51.259815 -104.163694) (xy 51.275172 -104.111395)
			(xy 51.297816 -104.061814) (xy 51.327285 -104.01596) (xy 51.362981 -103.974767) (xy 51.404176 -103.939073)
			(xy 51.450031 -103.909606) (xy 51.499614 -103.886965) (xy 51.551914 -103.871611) (xy 51.605866 -103.863856)
			(xy 51.63312 -103.863394) (xy 51.660096 -103.863898) (xy 51.713511 -103.87148) (xy 51.765323 -103.886519)
			(xy 51.814497 -103.908714) (xy 51.86005 -103.93762) (xy 51.901072 -103.972662) (xy 51.936743 -104.013138)
			(xy 51.966349 -104.058239) (xy 51.9893 -104.107065) (xy 52.005137 -104.158639) (xy 52.009802 -104.185212)
			(xy 52.011955 -104.195445) (xy 52.023243 -104.213023) (xy 52.031646 -104.219248) (xy 52.10302 -104.266746)
			(xy 52.124102 -104.270556) (xy 52.134262 -104.268016) (xy 52.160956 -104.261875) (xy 52.215332 -104.255254)
			(xy 52.24272 -104.254808) (xy 52.270108 -104.255246) (xy 52.324484 -104.261871) (xy 52.351178 -104.268016)
			(xy 52.361338 -104.270556) (xy 52.38242 -104.266746) (xy 52.462684 -104.213406) (xy 52.47386 -104.19588)
			(xy 52.475638 -104.185212) (xy 52.480351 -104.15865) (xy 52.496202 -104.107087) (xy 52.519159 -104.058272)
			(xy 52.548766 -104.013178) (xy 52.584431 -103.972706) (xy 52.625443 -103.937663) (xy 52.670984 -103.908749)
			(xy 52.720144 -103.886539) (xy 52.771943 -103.871478) (xy 52.825348 -103.863866) (xy 52.85232 -103.863394)
			(xy 52.879691 -103.86385) (xy 52.93387 -103.87167) (xy 52.986373 -103.887162) (xy 53.03612 -103.910006)
			(xy 53.082086 -103.939732) (xy 53.103018 -103.957374) (xy 53.103272 -103.957628) (xy 53.11036 -103.963212)
			(xy 53.127276 -103.969459) (xy 53.136292 -103.96982) (xy 53.203348 -103.96982) (xy 53.212362 -103.969434)
			(xy 53.229279 -103.963206) (xy 53.236368 -103.957628) (xy 53.236368 -103.957374) (xy 53.236622 -103.957374)
			(xy 53.257569 -103.939754) (xy 53.303538 -103.91004) (xy 53.353282 -103.887201) (xy 53.405779 -103.871705)
			(xy 53.459952 -103.863871) (xy 53.48732 -103.863394) (xy 53.504368 -103.863596) (xy 53.538328 -103.866647)
			(xy 53.555138 -103.86949) (xy 53.566466 -103.870891) (xy 53.588479 -103.864978) (xy 53.597556 -103.85806)
			(xy 53.622194 -103.836724) (xy 53.630521 -103.828833) (xy 53.639648 -103.80781) (xy 53.63972 -103.796338)
			(xy 53.639212 -103.776272) (xy 53.639212 -102.912418) (xy 53.63972 -102.893622) (xy 53.639621 -102.882062)
			(xy 53.63036 -102.860904) (xy 53.62194 -102.852982) (xy 53.597556 -102.8319) (xy 53.588586 -102.824898)
			(xy 53.566687 -102.81883) (xy 53.555392 -102.820216) (xy 53.538521 -102.823089) (xy 53.504433 -102.826139)
			(xy 53.48732 -102.826312) (xy 53.45995 -102.825831) (xy 53.405772 -102.818017) (xy 53.353269 -102.802531)
			(xy 53.303522 -102.779692) (xy 53.257554 -102.749971) (xy 53.236622 -102.732332) (xy 53.229764 -102.726236)
			(xy 53.212746 -102.719886) (xy 53.127402 -102.719886) (xy 53.11013 -102.72649) (xy 53.103272 -102.732586)
			(xy 53.082334 -102.750218) (xy 53.036366 -102.779939) (xy 52.986621 -102.802779) (xy 52.93412 -102.818271)
			(xy 52.879943 -102.826096) (xy 52.852574 -102.826566) (xy 52.85232 -102.826566) (xy 52.825314 -102.826068)
			(xy 52.771839 -102.818465) (xy 52.719971 -102.803395) (xy 52.670749 -102.781158) (xy 52.625155 -102.7522)
			(xy 52.584103 -102.717099) (xy 52.548413 -102.676558) (xy 52.518799 -102.631388) (xy 52.495853 -102.582491)
			(xy 52.480035 -102.530847) (xy 52.475384 -102.50424) (xy 52.47386 -102.493572) (xy 52.46243 -102.475792)
			(xy 52.391056 -102.428294) (xy 52.382128 -102.422942) (xy 52.361663 -102.419268) (xy 52.351432 -102.421182)
			(xy 52.35067 -102.421182) (xy 52.324094 -102.427236) (xy 52.269974 -102.433728) (xy 52.24272 -102.434136)
			(xy 52.215402 -102.433752) (xy 52.161153 -102.427256) (xy 52.134516 -102.421182) (xy 52.134008 -102.421182)
			(xy 52.123774 -102.41936) (xy 52.103333 -102.42301) (xy 52.094384 -102.428294) (xy 52.02301 -102.475792)
			(xy 52.01158 -102.493572) (xy 52.010056 -102.50424) (xy 52.005385 -102.530843) (xy 51.98956 -102.582482)
			(xy 51.966611 -102.631375) (xy 51.936996 -102.676542) (xy 51.901309 -102.717083) (xy 51.860261 -102.752185)
			(xy 51.814673 -102.781149) (xy 51.765457 -102.803394) (xy 51.713595 -102.818477) (xy 51.660125 -102.826096)
			(xy 51.63312 -102.826566) (xy 51.605863 -102.826188) (xy 51.551904 -102.818433) (xy 51.499598 -102.803077)
			(xy 51.45001 -102.780433) (xy 51.404149 -102.750962) (xy 51.36295 -102.715265) (xy 51.32725 -102.674067)
			(xy 51.297777 -102.628208) (xy 51.27513 -102.578621) (xy 51.259771 -102.526315) (xy 51.252013 -102.472357)
			(xy 47.429576 -102.472357) (xy 47.481138 -102.485837) (xy 47.532467 -102.507649) (xy 47.580073 -102.536703)
			(xy 47.622941 -102.572378) (xy 47.660158 -102.613915) (xy 47.690931 -102.660428) (xy 47.714603 -102.710925)
			(xy 47.730671 -102.764332) (xy 47.738791 -102.819508) (xy 47.7393 -102.847394) (xy 47.738791 -102.87528)
			(xy 47.730671 -102.930456) (xy 47.714603 -102.983863) (xy 47.690931 -103.03436) (xy 47.660158 -103.080873)
			(xy 47.622941 -103.12241) (xy 47.580073 -103.158085) (xy 47.532467 -103.187139) (xy 47.481138 -103.208951)
			(xy 47.427181 -103.223057) (xy 47.371744 -103.229157) (xy 47.31601 -103.22712) (xy 47.261167 -103.21699)
			(xy 47.208383 -103.198983) (xy 47.158783 -103.173482) (xy 47.113425 -103.141031) (xy 47.073276 -103.102322)
			(xy 47.03919 -103.058179) (xy 47.011894 -103.009544) (xy 46.991971 -102.957453) (xy 46.979845 -102.903016)
			(xy 46.975774 -102.847394) (xy 38.760509 -102.847394) (xy 38.759713 -102.850106) (xy 38.737068 -102.899687)
			(xy 38.707597 -102.945541) (xy 38.671899 -102.986733) (xy 38.630703 -103.022425) (xy 38.584845 -103.051891)
			(xy 38.535261 -103.07453) (xy 38.48296 -103.089881) (xy 38.429006 -103.097632) (xy 38.401752 -103.098092)
			(xy 38.386959 -103.097952) (xy 38.357461 -103.095666) (xy 38.342824 -103.09352) (xy 38.331849 -103.092412)
			(xy 38.310659 -103.09846) (xy 38.30193 -103.105204) (xy 38.243256 -103.155242) (xy 38.235254 -103.162833)
			(xy 38.226026 -103.182836) (xy 38.225476 -103.19385) (xy 38.225476 -103.498142) (xy 38.225998 -103.509163)
			(xy 38.235229 -103.529179) (xy 38.243256 -103.53675) (xy 38.30193 -103.586788) (xy 38.310622 -103.593604)
			(xy 38.331841 -103.599655) (xy 38.342824 -103.598472) (xy 38.357462 -103.596333) (xy 38.386959 -103.594044)
			(xy 38.401752 -103.5939) (xy 38.429008 -103.594344) (xy 38.482965 -103.602096) (xy 38.53527 -103.617448)
			(xy 38.584857 -103.640088) (xy 38.630717 -103.669555) (xy 38.671916 -103.70525) (xy 38.707616 -103.746445)
			(xy 38.737089 -103.792301) (xy 38.759735 -103.841885) (xy 38.775094 -103.894188) (xy 38.782852 -103.948144)
			(xy 38.782852 -104.002656) (xy 38.775094 -104.056612) (xy 38.759735 -104.108915) (xy 38.737089 -104.158499)
			(xy 38.707616 -104.204355) (xy 38.672478 -104.244902) (xy 44.669708 -104.244902) (xy 44.673779 -104.18928)
			(xy 44.685905 -104.134843) (xy 44.705828 -104.082752) (xy 44.733124 -104.034117) (xy 44.76721 -103.989974)
			(xy 44.807359 -103.951265) (xy 44.852717 -103.918814) (xy 44.902317 -103.893313) (xy 44.955101 -103.875306)
			(xy 45.009944 -103.865176) (xy 45.065678 -103.863139) (xy 45.121115 -103.869239) (xy 45.175072 -103.883345)
			(xy 45.226401 -103.905157) (xy 45.274007 -103.934211) (xy 45.316875 -103.969886) (xy 45.354092 -104.011423)
			(xy 45.384865 -104.057936) (xy 45.408537 -104.108433) (xy 45.424605 -104.16184) (xy 45.432725 -104.217016)
			(xy 45.433234 -104.244902) (xy 45.432725 -104.272788) (xy 45.424605 -104.327964) (xy 45.408537 -104.381371)
			(xy 45.384865 -104.431868) (xy 45.354092 -104.478381) (xy 45.316875 -104.519918) (xy 45.274007 -104.555593)
			(xy 45.226401 -104.584647) (xy 45.175072 -104.606459) (xy 45.121115 -104.620565) (xy 45.065678 -104.626665)
			(xy 45.009944 -104.624628) (xy 44.955101 -104.614498) (xy 44.902317 -104.596491) (xy 44.852717 -104.57099)
			(xy 44.807359 -104.538539) (xy 44.76721 -104.49983) (xy 44.733124 -104.455687) (xy 44.705828 -104.407052)
			(xy 44.685905 -104.354961) (xy 44.673779 -104.300524) (xy 44.669708 -104.244902) (xy 38.672478 -104.244902)
			(xy 38.671916 -104.24555) (xy 38.630717 -104.281245) (xy 38.584857 -104.310712) (xy 38.53527 -104.333352)
			(xy 38.482965 -104.348704) (xy 38.429008 -104.356456) (xy 38.401752 -104.356916) (xy 38.375844 -104.356456)
			(xy 38.324508 -104.349427) (xy 38.274595 -104.335517) (xy 38.227022 -104.314983) (xy 38.182664 -104.288202)
			(xy 38.142336 -104.255667) (xy 38.106781 -104.217976) (xy 38.091364 -104.19715) (xy 38.085604 -104.189837)
			(xy 38.070116 -104.179541) (xy 38.061138 -104.177084) (xy 38.030658 -104.170226) (xy 38.021382 -104.168474)
			(xy 38.002718 -104.171216) (xy 37.994336 -104.17556) (xy 37.968349 -104.189815) (xy 37.913484 -104.212247)
			(xy 37.856183 -104.227414) (xy 37.797405 -104.235061) (xy 37.738131 -104.235061) (xy 37.679353 -104.227414)
			(xy 37.622052 -104.212247) (xy 37.567187 -104.189815) (xy 37.5412 -104.17556) (xy 37.532791 -104.171304)
			(xy 37.514158 -104.168576) (xy 37.504878 -104.170226) (xy 37.474398 -104.177084) (xy 37.465401 -104.179498)
			(xy 37.449899 -104.189802) (xy 37.444172 -104.19715) (xy 37.428751 -104.217976) (xy 37.39321 -104.255686)
			(xy 37.352889 -104.288237) (xy 37.308532 -104.315027) (xy 37.260956 -104.335563) (xy 37.211036 -104.349467)
			(xy 37.159694 -104.356482) (xy 37.133784 -104.356916) (xy 37.106534 -104.356413) (xy 37.052589 -104.348655)
			(xy 37.000297 -104.333299) (xy 36.950723 -104.310657) (xy 36.904876 -104.281191) (xy 36.863688 -104.2455)
			(xy 36.827999 -104.204311) (xy 36.798535 -104.158463) (xy 36.775896 -104.108888) (xy 36.760542 -104.056595)
			(xy 36.752786 -104.00265) (xy 36.752786 -103.94815) (xy 36.760542 -103.894205) (xy 36.775896 -103.841912)
			(xy 36.798535 -103.792337) (xy 36.827999 -103.746489) (xy 36.863688 -103.7053) (xy 36.904876 -103.669609)
			(xy 36.950723 -103.640143) (xy 37.000297 -103.617501) (xy 37.052589 -103.602145) (xy 37.106534 -103.594387)
			(xy 37.133784 -103.5939) (xy 37.148577 -103.594035) (xy 37.178075 -103.596324) (xy 37.192712 -103.598472)
			(xy 37.203687 -103.599603) (xy 37.224879 -103.59354) (xy 37.233606 -103.586788) (xy 37.29228 -103.53675)
			(xy 37.300291 -103.529168) (xy 37.309513 -103.509158) (xy 37.31006 -103.498142) (xy 37.31006 -103.19385)
			(xy 37.309507 -103.182833) (xy 37.3003 -103.162815) (xy 37.29228 -103.155242) (xy 37.233606 -103.105204)
			(xy 37.224902 -103.098407) (xy 37.203693 -103.092345) (xy 37.192712 -103.09352) (xy 37.178073 -103.095654)
			(xy 37.148577 -103.097947) (xy 37.133784 -103.098092) (xy 37.106532 -103.097637) (xy 37.052584 -103.089878)
			(xy 37.000289 -103.074521) (xy 36.950712 -103.051878) (xy 36.904861 -103.02241) (xy 36.863671 -102.986717)
			(xy 36.82798 -102.945526) (xy 36.798514 -102.899674) (xy 36.775873 -102.850096) (xy 36.760518 -102.7978)
			(xy 36.752762 -102.743852) (xy 5.06984 -102.743852) (xy 5.06984 -104.550551) (xy 34.110664 -104.550551)
			(xy 34.110664 -104.496049) (xy 34.11842 -104.442101) (xy 34.133774 -104.389806) (xy 34.156415 -104.340229)
			(xy 34.18588 -104.294378) (xy 34.22157 -104.253187) (xy 34.262759 -104.217494) (xy 34.308608 -104.188026)
			(xy 34.358184 -104.165383) (xy 34.410478 -104.150025) (xy 34.464425 -104.142265) (xy 34.491676 -104.141778)
			(xy 34.517584 -104.14222) (xy 34.568921 -104.149253) (xy 34.618835 -104.163165) (xy 34.666408 -104.183702)
			(xy 34.710766 -104.210486) (xy 34.751092 -104.243024) (xy 34.786647 -104.280717) (xy 34.802064 -104.301544)
			(xy 34.807815 -104.308865) (xy 34.82331 -104.319157) (xy 34.83229 -104.32161) (xy 34.86277 -104.328468)
			(xy 34.872044 -104.330235) (xy 34.890711 -104.327483) (xy 34.899092 -104.323134) (xy 34.925073 -104.308848)
			(xy 34.979923 -104.286334) (xy 35.037224 -104.271105) (xy 35.096015 -104.263417) (xy 35.12566 -104.262936)
			(xy 35.155302 -104.263445) (xy 35.214084 -104.271164) (xy 35.271382 -104.286387) (xy 35.326243 -104.308862)
			(xy 35.352228 -104.323134) (xy 35.360653 -104.327354) (xy 35.379273 -104.330105) (xy 35.38855 -104.328468)
			(xy 35.41903 -104.32161) (xy 35.428018 -104.319169) (xy 35.443525 -104.308885) (xy 35.449256 -104.301544)
			(xy 35.464658 -104.280704) (xy 35.500203 -104.242994) (xy 35.540527 -104.210445) (xy 35.584887 -104.183657)
			(xy 35.632467 -104.163123) (xy 35.682389 -104.149222) (xy 35.733733 -104.14221) (xy 35.759644 -104.141778)
			(xy 35.786892 -104.142295) (xy 35.840833 -104.150057) (xy 35.893121 -104.165415) (xy 35.94269 -104.188058)
			(xy 35.988534 -104.217524) (xy 36.029717 -104.253214) (xy 36.065402 -104.294402) (xy 36.094863 -104.340248)
			(xy 36.1175 -104.389821) (xy 36.132853 -104.44211) (xy 36.140608 -104.496052) (xy 36.140608 -104.550548)
			(xy 36.132853 -104.60449) (xy 36.1175 -104.656779) (xy 36.094863 -104.706352) (xy 36.065402 -104.752198)
			(xy 36.030022 -104.793034) (xy 46.71009 -104.793034) (xy 46.714161 -104.737412) (xy 46.726287 -104.682975)
			(xy 46.74621 -104.630884) (xy 46.773506 -104.582249) (xy 46.807592 -104.538106) (xy 46.847741 -104.499397)
			(xy 46.893099 -104.466946) (xy 46.942699 -104.441445) (xy 46.995483 -104.423438) (xy 47.050326 -104.413308)
			(xy 47.10606 -104.411271) (xy 47.161497 -104.417371) (xy 47.215454 -104.431477) (xy 47.266783 -104.453289)
			(xy 47.314389 -104.482343) (xy 47.357257 -104.518018) (xy 47.394474 -104.559555) (xy 47.425247 -104.606068)
			(xy 47.448919 -104.656565) (xy 47.464987 -104.709972) (xy 47.473107 -104.765148) (xy 47.473616 -104.793034)
			(xy 47.473107 -104.82092) (xy 47.464987 -104.876096) (xy 47.448919 -104.929503) (xy 47.425247 -104.98)
			(xy 47.394474 -105.026513) (xy 47.357257 -105.06805) (xy 47.314389 -105.103725) (xy 47.266783 -105.132779)
			(xy 47.215454 -105.154591) (xy 47.161497 -105.168697) (xy 47.10606 -105.174797) (xy 47.050326 -105.17276)
			(xy 46.995483 -105.16263) (xy 46.942699 -105.144623) (xy 46.893099 -105.119122) (xy 46.847741 -105.086671)
			(xy 46.807592 -105.047962) (xy 46.773506 -105.003819) (xy 46.74621 -104.955184) (xy 46.726287 -104.903093)
			(xy 46.714161 -104.848656) (xy 46.71009 -104.793034) (xy 36.030022 -104.793034) (xy 36.029717 -104.793386)
			(xy 35.988534 -104.829076) (xy 35.94269 -104.858542) (xy 35.893121 -104.881185) (xy 35.840833 -104.896543)
			(xy 35.786892 -104.904305) (xy 35.759644 -104.904794) (xy 35.744851 -104.904655) (xy 35.715353 -104.902369)
			(xy 35.700716 -104.900222) (xy 35.689741 -104.899109) (xy 35.66855 -104.90516) (xy 35.659822 -104.911906)
			(xy 35.601148 -104.961944) (xy 35.593144 -104.969533) (xy 35.583917 -104.989537) (xy 35.583368 -105.000552)
			(xy 35.583368 -105.304844) (xy 35.583947 -105.315858) (xy 35.593139 -105.335874) (xy 35.601148 -105.343452)
			(xy 35.626464 -105.365042) (xy 49.222912 -105.365042) (xy 49.226983 -105.30942) (xy 49.239109 -105.254983)
			(xy 49.259032 -105.202892) (xy 49.286328 -105.154257) (xy 49.320414 -105.110114) (xy 49.360563 -105.071405)
			(xy 49.405921 -105.038954) (xy 49.455521 -105.013453) (xy 49.508305 -104.995446) (xy 49.563148 -104.985316)
			(xy 49.618882 -104.983279) (xy 49.674319 -104.989379) (xy 49.728276 -105.003485) (xy 49.779605 -105.025297)
			(xy 49.827211 -105.054351) (xy 49.870079 -105.090026) (xy 49.907296 -105.131563) (xy 49.938069 -105.178076)
			(xy 49.961741 -105.228573) (xy 49.977809 -105.28198) (xy 49.985929 -105.337156) (xy 49.986438 -105.365042)
			(xy 49.985929 -105.392928) (xy 49.977809 -105.448104) (xy 49.961741 -105.501511) (xy 49.938069 -105.552008)
			(xy 49.907296 -105.598521) (xy 49.870079 -105.640058) (xy 49.827211 -105.675733) (xy 49.779605 -105.704787)
			(xy 49.728276 -105.726599) (xy 49.674319 -105.740705) (xy 49.618882 -105.746805) (xy 49.563148 -105.744768)
			(xy 49.508305 -105.734638) (xy 49.455521 -105.716631) (xy 49.405921 -105.69113) (xy 49.360563 -105.658679)
			(xy 49.320414 -105.61997) (xy 49.286328 -105.575827) (xy 49.259032 -105.527192) (xy 49.239109 -105.475101)
			(xy 49.226983 -105.420664) (xy 49.222912 -105.365042) (xy 35.626464 -105.365042) (xy 35.659822 -105.39349)
			(xy 35.668517 -105.400302) (xy 35.689733 -105.406355) (xy 35.700716 -105.405174) (xy 35.715354 -105.403036)
			(xy 35.744851 -105.400746) (xy 35.759644 -105.400602) (xy 35.786894 -105.401071) (xy 35.840838 -105.408833)
			(xy 35.893129 -105.424192) (xy 35.942702 -105.446836) (xy 35.988548 -105.476304) (xy 36.029734 -105.511997)
			(xy 36.065422 -105.553187) (xy 36.094885 -105.599037) (xy 36.117523 -105.648612) (xy 36.132877 -105.700905)
			(xy 36.140632 -105.75485) (xy 36.140632 -105.80935) (xy 36.132877 -105.863295) (xy 36.117523 -105.915588)
			(xy 36.094885 -105.965163) (xy 36.065422 -106.011013) (xy 36.029734 -106.052203) (xy 35.988548 -106.087896)
			(xy 35.942702 -106.117364) (xy 35.893129 -106.140008) (xy 35.840838 -106.155367) (xy 35.786894 -106.163129)
			(xy 35.759644 -106.163618) (xy 35.733736 -106.163163) (xy 35.6824 -106.156133) (xy 35.632486 -106.142222)
			(xy 35.584913 -106.121688) (xy 35.540555 -106.094906) (xy 35.500228 -106.06237) (xy 35.464673 -106.024678)
			(xy 35.449256 -106.003852) (xy 35.443498 -105.996537) (xy 35.428008 -105.986242) (xy 35.41903 -105.983786)
			(xy 35.38855 -105.976928) (xy 35.379274 -105.975172) (xy 35.360609 -105.977917) (xy 35.352228 -105.982262)
			(xy 35.326243 -105.99654) (xy 35.271394 -106.019056) (xy 35.214094 -106.034287) (xy 35.155305 -106.041978)
			(xy 35.12566 -106.04246) (xy 35.096018 -106.041943) (xy 35.037237 -106.034227) (xy 34.979939 -106.019006)
			(xy 34.925077 -105.996533) (xy 34.899092 -105.982262) (xy 34.890685 -105.978002) (xy 34.87205 -105.975276)
			(xy 34.86277 -105.976928) (xy 34.83229 -105.983786) (xy 34.823305 -105.986237) (xy 34.807797 -105.996514)
			(xy 34.802064 -106.003852) (xy 34.786648 -106.024682) (xy 34.751106 -106.062392) (xy 34.710785 -106.094942)
			(xy 34.666427 -106.121732) (xy 34.618849 -106.142267) (xy 34.568929 -106.15617) (xy 34.517586 -106.163185)
			(xy 34.491676 -106.163618) (xy 34.464427 -106.16311) (xy 34.410483 -106.155351) (xy 34.358193 -106.139994)
			(xy 34.30862 -106.117352) (xy 34.262774 -106.087886) (xy 34.221587 -106.052196) (xy 34.185899 -106.011007)
			(xy 34.156436 -105.965159) (xy 34.133797 -105.915585) (xy 34.118444 -105.863294) (xy 34.110688 -105.809349)
			(xy 34.110688 -105.754851) (xy 34.118444 -105.700906) (xy 34.133797 -105.648615) (xy 34.156436 -105.599041)
			(xy 34.185899 -105.553193) (xy 34.221587 -105.512004) (xy 34.262774 -105.476314) (xy 34.30862 -105.446848)
			(xy 34.358193 -105.424206) (xy 34.410483 -105.408849) (xy 34.464427 -105.40109) (xy 34.491676 -105.400602)
			(xy 34.506469 -105.400738) (xy 34.535967 -105.403027) (xy 34.550604 -105.405174) (xy 34.561579 -105.4063)
			(xy 34.582771 -105.40024) (xy 34.591498 -105.39349) (xy 34.650172 -105.343452) (xy 34.658181 -105.335868)
			(xy 34.667405 -105.31586) (xy 34.667952 -105.304844) (xy 34.667952 -105.000552) (xy 34.667401 -104.989534)
			(xy 34.658192 -104.969517) (xy 34.650172 -104.961944) (xy 34.591498 -104.911906) (xy 34.582797 -104.905105)
			(xy 34.561585 -104.899045) (xy 34.550604 -104.900222) (xy 34.535965 -104.902357) (xy 34.506469 -104.904649)
			(xy 34.491676 -104.904794) (xy 34.464425 -104.904335) (xy 34.410478 -104.896575) (xy 34.358184 -104.881217)
			(xy 34.308608 -104.858574) (xy 34.262759 -104.829106) (xy 34.22157 -104.793413) (xy 34.18588 -104.752222)
			(xy 34.156415 -104.706371) (xy 34.133774 -104.656794) (xy 34.11842 -104.604499) (xy 34.110664 -104.550551)
			(xy 5.06984 -104.550551) (xy 5.06984 -106.343749) (xy 36.752804 -106.343749) (xy 36.752804 -106.289251)
			(xy 36.76056 -106.235309) (xy 36.775913 -106.183019) (xy 36.798551 -106.133446) (xy 36.828014 -106.0876)
			(xy 36.863701 -106.046413) (xy 36.904887 -106.010724) (xy 36.950732 -105.981259) (xy 37.000304 -105.958619)
			(xy 37.052593 -105.943263) (xy 37.106535 -105.935505) (xy 37.133784 -105.935018) (xy 37.159693 -105.935437)
			(xy 37.211032 -105.942472) (xy 37.260947 -105.956387) (xy 37.30852 -105.976928) (xy 37.352878 -106.003715)
			(xy 37.393204 -106.036257) (xy 37.428756 -106.073955) (xy 37.444172 -106.094784) (xy 37.449913 -106.102114)
			(xy 37.465415 -106.1124) (xy 37.474398 -106.11485) (xy 37.504878 -106.121708) (xy 37.514152 -106.123475)
			(xy 37.532819 -106.120722) (xy 37.5412 -106.116374) (xy 37.567176 -106.10208) (xy 37.622028 -106.079569)
			(xy 37.679331 -106.064343) (xy 37.738122 -106.056656) (xy 37.767768 -106.056176) (xy 37.797411 -106.056676)
			(xy 37.856193 -106.064397) (xy 37.913491 -106.079623) (xy 37.968351 -106.1021) (xy 37.994336 -106.116374)
			(xy 38.002758 -106.120599) (xy 38.02138 -106.123346) (xy 38.030658 -106.121708) (xy 38.061138 -106.11485)
			(xy 38.070134 -106.112431) (xy 38.085638 -106.102132) (xy 38.091364 -106.094784) (xy 38.106773 -106.073949)
			(xy 38.142315 -106.036237) (xy 38.182637 -106.003686) (xy 38.226996 -105.976897) (xy 38.274575 -105.956362)
			(xy 38.324497 -105.942461) (xy 38.375841 -105.935449) (xy 38.401752 -105.935018) (xy 38.429009 -105.935426)
			(xy 38.482969 -105.943178) (xy 38.535276 -105.958531) (xy 38.584866 -105.981172) (xy 38.630728 -106.010641)
			(xy 38.670386 -106.045) (xy 44.669708 -106.045) (xy 44.673779 -105.989378) (xy 44.685905 -105.934941)
			(xy 44.705828 -105.88285) (xy 44.733124 -105.834215) (xy 44.76721 -105.790072) (xy 44.807359 -105.751363)
			(xy 44.852717 -105.718912) (xy 44.902317 -105.693411) (xy 44.955101 -105.675404) (xy 45.009944 -105.665274)
			(xy 45.065678 -105.663237) (xy 45.121115 -105.669337) (xy 45.175072 -105.683443) (xy 45.226401 -105.705255)
			(xy 45.274007 -105.734309) (xy 45.316875 -105.769984) (xy 45.354092 -105.811521) (xy 45.384865 -105.858034)
			(xy 45.408537 -105.908531) (xy 45.424605 -105.961938) (xy 45.432725 -106.017114) (xy 45.433234 -106.045)
			(xy 45.432725 -106.072886) (xy 45.424605 -106.128062) (xy 45.408537 -106.181469) (xy 45.384865 -106.231966)
			(xy 45.354092 -106.278479) (xy 45.316875 -106.320016) (xy 45.274007 -106.355691) (xy 45.226401 -106.384745)
			(xy 45.175072 -106.406557) (xy 45.121115 -106.420663) (xy 45.065678 -106.426763) (xy 45.009944 -106.424726)
			(xy 44.955101 -106.414596) (xy 44.902317 -106.396589) (xy 44.852717 -106.371088) (xy 44.807359 -106.338637)
			(xy 44.76721 -106.299928) (xy 44.733124 -106.255785) (xy 44.705828 -106.20715) (xy 44.685905 -106.155059)
			(xy 44.673779 -106.100622) (xy 44.669708 -106.045) (xy 38.670386 -106.045) (xy 38.671929 -106.046337)
			(xy 38.707631 -106.087534) (xy 38.737105 -106.133392) (xy 38.759753 -106.182979) (xy 38.775112 -106.235284)
			(xy 38.782871 -106.289243) (xy 38.782871 -106.343757) (xy 38.775112 -106.397716) (xy 38.759753 -106.450021)
			(xy 38.737105 -106.499608) (xy 38.707631 -106.545466) (xy 38.671929 -106.586663) (xy 38.630728 -106.622359)
			(xy 38.584866 -106.651828) (xy 38.535276 -106.674469) (xy 38.482969 -106.689822) (xy 38.429009 -106.697574)
			(xy 38.401752 -106.698034) (xy 38.386959 -106.697895) (xy 38.357461 -106.695609) (xy 38.342824 -106.693462)
			(xy 38.331849 -106.692367) (xy 38.310661 -106.698408) (xy 38.30193 -106.705146) (xy 38.243256 -106.755184)
			(xy 38.235235 -106.762758) (xy 38.226017 -106.782774) (xy 38.225476 -106.793792) (xy 38.225476 -107.098084)
			(xy 38.22603 -107.109101) (xy 38.235239 -107.129117) (xy 38.243256 -107.136692) (xy 38.30193 -107.18673)
			(xy 38.310626 -107.19354) (xy 38.331842 -107.199597) (xy 38.342824 -107.198414) (xy 38.357462 -107.196276)
			(xy 38.386959 -107.193986) (xy 38.401752 -107.193842) (xy 38.429011 -107.194202) (xy 38.482974 -107.201954)
			(xy 38.535284 -107.217308) (xy 38.584877 -107.239951) (xy 38.630742 -107.269421) (xy 38.671946 -107.30512)
			(xy 38.70765 -107.346319) (xy 38.737126 -107.392181) (xy 38.744102 -107.407456) (xy 49.047144 -107.407456)
			(xy 49.051215 -107.351834) (xy 49.063341 -107.297397) (xy 49.083264 -107.245306) (xy 49.11056 -107.196671)
			(xy 49.144646 -107.152528) (xy 49.184795 -107.113819) (xy 49.230153 -107.081368) (xy 49.279753 -107.055867)
			(xy 49.332537 -107.03786) (xy 49.38738 -107.02773) (xy 49.443114 -107.025693) (xy 49.498551 -107.031793)
			(xy 49.552508 -107.045899) (xy 49.603837 -107.067711) (xy 49.651443 -107.096765) (xy 49.694311 -107.13244)
			(xy 49.731528 -107.173977) (xy 49.762301 -107.22049) (xy 49.785973 -107.270987) (xy 49.802041 -107.324394)
			(xy 49.810161 -107.37957) (xy 49.81067 -107.407456) (xy 49.810161 -107.435342) (xy 49.802041 -107.490518)
			(xy 49.785973 -107.543925) (xy 49.762301 -107.594422) (xy 49.731528 -107.640935) (xy 49.694311 -107.682472)
			(xy 49.651443 -107.718147) (xy 49.603837 -107.747201) (xy 49.552508 -107.769013) (xy 49.498551 -107.783119)
			(xy 49.443114 -107.789219) (xy 49.38738 -107.787182) (xy 49.332537 -107.777052) (xy 49.279753 -107.759045)
			(xy 49.230153 -107.733544) (xy 49.184795 -107.701093) (xy 49.144646 -107.662384) (xy 49.11056 -107.618241)
			(xy 49.083264 -107.569606) (xy 49.063341 -107.517515) (xy 49.051215 -107.463078) (xy 49.047144 -107.407456)
			(xy 38.744102 -107.407456) (xy 38.759775 -107.441771) (xy 38.775136 -107.494079) (xy 38.782895 -107.548041)
			(xy 38.782895 -107.602559) (xy 38.775136 -107.656521) (xy 38.759775 -107.708829) (xy 38.737126 -107.758419)
			(xy 38.70765 -107.804281) (xy 38.672277 -107.845098) (xy 44.669708 -107.845098) (xy 44.673779 -107.789476)
			(xy 44.685905 -107.735039) (xy 44.705828 -107.682948) (xy 44.733124 -107.634313) (xy 44.76721 -107.59017)
			(xy 44.807359 -107.551461) (xy 44.852717 -107.51901) (xy 44.902317 -107.493509) (xy 44.955101 -107.475502)
			(xy 45.009944 -107.465372) (xy 45.065678 -107.463335) (xy 45.121115 -107.469435) (xy 45.175072 -107.483541)
			(xy 45.226401 -107.505353) (xy 45.274007 -107.534407) (xy 45.316875 -107.570082) (xy 45.354092 -107.611619)
			(xy 45.384865 -107.658132) (xy 45.408537 -107.708629) (xy 45.424605 -107.762036) (xy 45.432725 -107.817212)
			(xy 45.433234 -107.845098) (xy 45.432725 -107.872984) (xy 45.424605 -107.92816) (xy 45.408537 -107.981567)
			(xy 45.384865 -108.032064) (xy 45.354092 -108.078577) (xy 45.316875 -108.120114) (xy 45.274007 -108.155789)
			(xy 45.226401 -108.184843) (xy 45.175072 -108.206655) (xy 45.121115 -108.220761) (xy 45.065678 -108.226861)
			(xy 45.009944 -108.224824) (xy 44.955101 -108.214694) (xy 44.902317 -108.196687) (xy 44.852717 -108.171186)
			(xy 44.807359 -108.138735) (xy 44.76721 -108.100026) (xy 44.733124 -108.055883) (xy 44.705828 -108.007248)
			(xy 44.685905 -107.955157) (xy 44.673779 -107.90072) (xy 44.669708 -107.845098) (xy 38.672277 -107.845098)
			(xy 38.671946 -107.84548) (xy 38.630742 -107.881179) (xy 38.584877 -107.910649) (xy 38.535284 -107.933292)
			(xy 38.482974 -107.948646) (xy 38.429011 -107.956398) (xy 38.401752 -107.956858) (xy 38.375843 -107.956422)
			(xy 38.324505 -107.949392) (xy 38.27459 -107.93548) (xy 38.227016 -107.914942) (xy 38.182658 -107.888157)
			(xy 38.142332 -107.855617) (xy 38.106779 -107.81792) (xy 38.091364 -107.797092) (xy 38.085596 -107.789786)
			(xy 38.070114 -107.779485) (xy 38.061138 -107.777026) (xy 38.030658 -107.770168) (xy 38.021381 -107.768424)
			(xy 38.002718 -107.771162) (xy 37.994336 -107.775502) (xy 37.968372 -107.789819) (xy 37.913515 -107.812325)
			(xy 37.856209 -107.827545) (xy 37.797415 -107.835224) (xy 37.767768 -107.8357) (xy 37.738126 -107.835187)
			(xy 37.679344 -107.827471) (xy 37.622046 -107.812249) (xy 37.567185 -107.789774) (xy 37.5412 -107.775502)
			(xy 37.532792 -107.771244) (xy 37.514158 -107.768519) (xy 37.504878 -107.770168) (xy 37.474398 -107.777026)
			(xy 37.465396 -107.779427) (xy 37.449896 -107.789739) (xy 37.444172 -107.797092) (xy 37.428734 -107.817905)
			(xy 37.393198 -107.855619) (xy 37.352881 -107.888172) (xy 37.308527 -107.914964) (xy 37.260952 -107.935503)
			(xy 37.211034 -107.949408) (xy 37.159693 -107.956424) (xy 37.133784 -107.956858) (xy 37.106537 -107.956271)
			(xy 37.052598 -107.948513) (xy 37.000312 -107.933159) (xy 36.950744 -107.91052) (xy 36.904901 -107.881057)
			(xy 36.863718 -107.84537) (xy 36.828033 -107.804186) (xy 36.798572 -107.758342) (xy 36.775935 -107.708773)
			(xy 36.760583 -107.656486) (xy 36.752828 -107.602547) (xy 36.752828 -107.548053) (xy 36.760583 -107.494114)
			(xy 36.775935 -107.441827) (xy 36.798572 -107.392258) (xy 36.828033 -107.346414) (xy 36.863718 -107.30523)
			(xy 36.904901 -107.269543) (xy 36.950744 -107.24008) (xy 37.000312 -107.217441) (xy 37.052598 -107.202087)
			(xy 37.106537 -107.194329) (xy 37.133784 -107.193842) (xy 37.148577 -107.193977) (xy 37.178075 -107.196266)
			(xy 37.192712 -107.198414) (xy 37.203687 -107.199535) (xy 37.224878 -107.193477) (xy 37.233606 -107.18673)
			(xy 37.29228 -107.136692) (xy 37.300317 -107.129133) (xy 37.309525 -107.109106) (xy 37.31006 -107.098084)
			(xy 37.31006 -106.793792) (xy 37.309539 -106.782771) (xy 37.300309 -106.762754) (xy 37.29228 -106.755184)
			(xy 37.233606 -106.705146) (xy 37.224899 -106.698353) (xy 37.203692 -106.692287) (xy 37.192712 -106.693462)
			(xy 37.178073 -106.695597) (xy 37.148577 -106.697889) (xy 37.133784 -106.698034) (xy 37.106535 -106.697495)
			(xy 37.052593 -106.689737) (xy 37.000304 -106.674381) (xy 36.950732 -106.651741) (xy 36.904887 -106.622276)
			(xy 36.863701 -106.586587) (xy 36.828014 -106.5454) (xy 36.798551 -106.499554) (xy 36.775913 -106.449981)
			(xy 36.76056 -106.397691) (xy 36.752804 -106.343749) (xy 5.06984 -106.343749) (xy 5.06984 -109.409354)
			(xy 34.11063 -109.409354) (xy 34.11063 -109.354846) (xy 34.118387 -109.300894) (xy 34.133743 -109.248595)
			(xy 34.156385 -109.199013) (xy 34.185853 -109.153158) (xy 34.221546 -109.111963) (xy 34.262738 -109.076267)
			(xy 34.308592 -109.046796) (xy 34.358172 -109.024151) (xy 34.410471 -109.008792) (xy 34.464422 -109.001032)
			(xy 34.491676 -109.000544) (xy 34.506469 -109.00068) (xy 34.535967 -109.002968) (xy 34.550604 -109.005116)
			(xy 34.561579 -109.006232) (xy 34.582769 -109.000177) (xy 34.591498 -108.993432) (xy 34.650172 -108.943394)
			(xy 34.658207 -108.935833) (xy 34.667416 -108.915807) (xy 34.667952 -108.904786) (xy 34.667952 -108.600494)
			(xy 34.667433 -108.589472) (xy 34.658202 -108.569455) (xy 34.650172 -108.561886) (xy 34.591498 -108.511848)
			(xy 34.582794 -108.505051) (xy 34.561585 -108.498987) (xy 34.550604 -108.500164) (xy 34.535965 -108.502299)
			(xy 34.506469 -108.504591) (xy 34.491676 -108.504736) (xy 34.464428 -108.504192) (xy 34.410487 -108.496433)
			(xy 34.358199 -108.481077) (xy 34.308628 -108.458437) (xy 34.262784 -108.428972) (xy 34.2216 -108.393283)
			(xy 34.185914 -108.352096) (xy 34.156452 -108.306251) (xy 34.133814 -108.256679) (xy 34.118461 -108.20439)
			(xy 34.110706 -108.150448) (xy 34.110706 -108.095952) (xy 34.118461 -108.04201) (xy 34.133814 -107.989721)
			(xy 34.156452 -107.940149) (xy 34.185914 -107.894304) (xy 34.2216 -107.853117) (xy 34.262784 -107.817428)
			(xy 34.308628 -107.787963) (xy 34.358199 -107.765323) (xy 34.410487 -107.749967) (xy 34.464428 -107.742208)
			(xy 34.491676 -107.74172) (xy 34.517585 -107.742144) (xy 34.568923 -107.749178) (xy 34.618838 -107.763093)
			(xy 34.666412 -107.783632) (xy 34.71077 -107.810419) (xy 34.751096 -107.84296) (xy 34.786648 -107.880657)
			(xy 34.802064 -107.901486) (xy 34.807807 -107.908814) (xy 34.823308 -107.919101) (xy 34.83229 -107.921552)
			(xy 34.86277 -107.92841) (xy 34.872045 -107.930172) (xy 34.89071 -107.927422) (xy 34.899092 -107.923076)
			(xy 34.925079 -107.908821) (xy 34.979944 -107.886389) (xy 35.037245 -107.871222) (xy 35.096023 -107.863575)
			(xy 35.155297 -107.863575) (xy 35.214075 -107.871222) (xy 35.271376 -107.886389) (xy 35.326241 -107.908821)
			(xy 35.352228 -107.923076) (xy 35.360652 -107.927297) (xy 35.379273 -107.930046) (xy 35.38855 -107.92841)
			(xy 35.41903 -107.921552) (xy 35.428025 -107.919129) (xy 35.443529 -107.908833) (xy 35.449256 -107.901486)
			(xy 35.464671 -107.880655) (xy 35.500212 -107.842943) (xy 35.540533 -107.810392) (xy 35.584891 -107.783602)
			(xy 35.632469 -107.763067) (xy 35.68239 -107.749165) (xy 35.733734 -107.742152) (xy 35.759644 -107.74172)
			(xy 35.786895 -107.742153) (xy 35.840842 -107.749915) (xy 35.893135 -107.765275) (xy 35.942711 -107.78792)
			(xy 35.988559 -107.81739) (xy 36.029747 -107.853084) (xy 36.065436 -107.894276) (xy 36.094901 -107.940128)
			(xy 36.11754 -107.989706) (xy 36.132894 -108.042001) (xy 36.14065 -108.095949) (xy 36.14065 -108.150451)
			(xy 36.132894 -108.204399) (xy 36.11754 -108.256694) (xy 36.106922 -108.279946) (xy 47.011588 -108.279946)
			(xy 47.015659 -108.224324) (xy 47.027785 -108.169887) (xy 47.047708 -108.117796) (xy 47.075004 -108.069161)
			(xy 47.10909 -108.025018) (xy 47.149239 -107.986309) (xy 47.194597 -107.953858) (xy 47.244197 -107.928357)
			(xy 47.296981 -107.91035) (xy 47.351824 -107.90022) (xy 47.407558 -107.898183) (xy 47.462995 -107.904283)
			(xy 47.516952 -107.918389) (xy 47.568281 -107.940201) (xy 47.615887 -107.969255) (xy 47.658755 -108.00493)
			(xy 47.695972 -108.046467) (xy 47.726745 -108.09298) (xy 47.750417 -108.143477) (xy 47.766485 -108.196884)
			(xy 47.774605 -108.25206) (xy 47.775114 -108.279946) (xy 47.774605 -108.307832) (xy 47.766485 -108.363008)
			(xy 47.750417 -108.416415) (xy 47.726745 -108.466912) (xy 47.695972 -108.513425) (xy 47.658755 -108.554962)
			(xy 47.615887 -108.590637) (xy 47.568281 -108.619691) (xy 47.516952 -108.641503) (xy 47.462995 -108.655609)
			(xy 47.407558 -108.661709) (xy 47.351824 -108.659672) (xy 47.296981 -108.649542) (xy 47.244197 -108.631535)
			(xy 47.194597 -108.606034) (xy 47.149239 -108.573583) (xy 47.10909 -108.534874) (xy 47.075004 -108.490731)
			(xy 47.047708 -108.442096) (xy 47.027785 -108.390005) (xy 47.015659 -108.335568) (xy 47.011588 -108.279946)
			(xy 36.106922 -108.279946) (xy 36.094901 -108.306272) (xy 36.065436 -108.352124) (xy 36.029747 -108.393316)
			(xy 35.988559 -108.42901) (xy 35.942711 -108.45848) (xy 35.893135 -108.481125) (xy 35.840842 -108.496485)
			(xy 35.786895 -108.504247) (xy 35.759644 -108.504736) (xy 35.744851 -108.504598) (xy 35.715353 -108.502311)
			(xy 35.700716 -108.500164) (xy 35.689741 -108.499064) (xy 35.668552 -108.505108) (xy 35.659822 -108.511848)
			(xy 35.601148 -108.561886) (xy 35.593125 -108.569458) (xy 35.583909 -108.589475) (xy 35.583368 -108.600494)
			(xy 35.583368 -108.904786) (xy 35.583924 -108.915802) (xy 35.593132 -108.935819) (xy 35.601148 -108.943394)
			(xy 35.659822 -108.993432) (xy 35.668521 -109.000238) (xy 35.689734 -109.006298) (xy 35.700716 -109.005116)
			(xy 35.715354 -109.002979) (xy 35.744851 -109.000688) (xy 35.759644 -109.000544) (xy 35.78689 -109.001129)
			(xy 35.840826 -109.00889) (xy 35.893109 -109.024247) (xy 35.942674 -109.046888) (xy 35.988513 -109.076351)
			(xy 36.029693 -109.112038) (xy 36.065375 -109.153222) (xy 36.080866 -109.177328) (xy 49.064924 -109.177328)
			(xy 49.068995 -109.121706) (xy 49.081121 -109.067269) (xy 49.101044 -109.015178) (xy 49.12834 -108.966543)
			(xy 49.162426 -108.9224) (xy 49.202575 -108.883691) (xy 49.247933 -108.85124) (xy 49.297533 -108.825739)
			(xy 49.350317 -108.807732) (xy 49.40516 -108.797602) (xy 49.460894 -108.795565) (xy 49.516331 -108.801665)
			(xy 49.570288 -108.815771) (xy 49.621617 -108.837583) (xy 49.669223 -108.866637) (xy 49.712091 -108.902312)
			(xy 49.749308 -108.943849) (xy 49.780081 -108.990362) (xy 49.803753 -109.040859) (xy 49.819821 -109.094266)
			(xy 49.827941 -109.149442) (xy 49.82845 -109.177328) (xy 49.827941 -109.205214) (xy 49.819821 -109.26039)
			(xy 49.803753 -109.313797) (xy 49.780081 -109.364294) (xy 49.749308 -109.410807) (xy 49.712091 -109.452344)
			(xy 49.669223 -109.488019) (xy 49.621617 -109.517073) (xy 49.570288 -109.538885) (xy 49.516331 -109.552991)
			(xy 49.460894 -109.559091) (xy 49.40516 -109.557054) (xy 49.350317 -109.546924) (xy 49.297533 -109.528917)
			(xy 49.247933 -109.503416) (xy 49.202575 -109.470965) (xy 49.162426 -109.432256) (xy 49.12834 -109.388113)
			(xy 49.101044 -109.339478) (xy 49.081121 -109.287387) (xy 49.068995 -109.23295) (xy 49.064924 -109.177328)
			(xy 36.080866 -109.177328) (xy 36.094834 -109.199065) (xy 36.117469 -109.248633) (xy 36.13282 -109.300917)
			(xy 36.140574 -109.354854) (xy 36.140574 -109.409346) (xy 36.13282 -109.463283) (xy 36.117469 -109.515567)
			(xy 36.094834 -109.565135) (xy 36.065375 -109.610978) (xy 36.029693 -109.652162) (xy 35.988513 -109.687849)
			(xy 35.942674 -109.717312) (xy 35.893109 -109.739953) (xy 35.840826 -109.75531) (xy 35.78689 -109.763071)
			(xy 35.759644 -109.76356) (xy 35.733735 -109.763129) (xy 35.682397 -109.756098) (xy 35.632482 -109.742185)
			(xy 35.584908 -109.721647) (xy 35.54055 -109.694861) (xy 35.500224 -109.66232) (xy 35.464671 -109.624623)
			(xy 35.449256 -109.603794) (xy 35.44349 -109.596486) (xy 35.428006 -109.586186) (xy 35.41903 -109.583728)
			(xy 35.38855 -109.57687) (xy 35.379274 -109.575121) (xy 35.36061 -109.577863) (xy 35.352228 -109.582204)
			(xy 35.326241 -109.596459) (xy 35.271376 -109.618891) (xy 35.214075 -109.634058) (xy 35.155297 -109.641705)
			(xy 35.096023 -109.641705) (xy 35.037245 -109.634058) (xy 34.979944 -109.618891) (xy 34.925079 -109.596459)
			(xy 34.899092 -109.582204) (xy 34.890686 -109.577943) (xy 34.87205 -109.575219) (xy 34.86277 -109.57687)
			(xy 34.83229 -109.583728) (xy 34.8233 -109.586166) (xy 34.807793 -109.596451) (xy 34.802064 -109.603794)
			(xy 34.786631 -109.624611) (xy 34.751094 -109.662325) (xy 34.710776 -109.694877) (xy 34.666421 -109.721669)
			(xy 34.618846 -109.742207) (xy 34.568927 -109.756111) (xy 34.517585 -109.763127) (xy 34.491676 -109.76356)
			(xy 34.464422 -109.763168) (xy 34.410471 -109.755408) (xy 34.358172 -109.740049) (xy 34.308592 -109.717404)
			(xy 34.262738 -109.687933) (xy 34.221546 -109.652237) (xy 34.185853 -109.611042) (xy 34.156385 -109.565187)
			(xy 34.133743 -109.515605) (xy 34.118387 -109.463306) (xy 34.11063 -109.409354) (xy 5.06984 -109.409354)
			(xy 5.06984 -109.943949) (xy 36.7528 -109.943949) (xy 36.7528 -109.889451) (xy 36.760556 -109.835508)
			(xy 36.775909 -109.783218) (xy 36.798548 -109.733644) (xy 36.828011 -109.687797) (xy 36.863699 -109.64661)
			(xy 36.904885 -109.610921) (xy 36.95073 -109.581456) (xy 37.000303 -109.558815) (xy 37.052592 -109.543459)
			(xy 37.106535 -109.535701) (xy 37.133784 -109.535214) (xy 37.159693 -109.535635) (xy 37.211032 -109.542669)
			(xy 37.260946 -109.556585) (xy 37.30852 -109.577125) (xy 37.352878 -109.603912) (xy 37.393203 -109.636454)
			(xy 37.428756 -109.674151) (xy 37.444172 -109.69498) (xy 37.449913 -109.702309) (xy 37.465415 -109.712595)
			(xy 37.474398 -109.715046) (xy 37.504878 -109.721904) (xy 37.514152 -109.723671) (xy 37.532819 -109.720918)
			(xy 37.5412 -109.71657) (xy 37.567176 -109.702275) (xy 37.622028 -109.679765) (xy 37.679331 -109.664539)
			(xy 37.738122 -109.656852) (xy 37.767768 -109.656372) (xy 37.797411 -109.656873) (xy 37.856193 -109.664593)
			(xy 37.913491 -109.679819) (xy 37.968351 -109.702296) (xy 37.994336 -109.71657) (xy 38.002758 -109.720794)
			(xy 38.02138 -109.723542) (xy 38.030658 -109.721904) (xy 38.061138 -109.715046) (xy 38.070123 -109.712596)
			(xy 38.085631 -109.702318) (xy 38.091364 -109.69498) (xy 38.106772 -109.674144) (xy 38.142314 -109.636432)
			(xy 38.182637 -109.603882) (xy 38.226996 -109.577092) (xy 38.274575 -109.556558) (xy 38.324497 -109.542657)
			(xy 38.375841 -109.535645) (xy 38.401752 -109.535214) (xy 38.429009 -109.53563) (xy 38.482968 -109.543381)
			(xy 38.535275 -109.558734) (xy 38.584864 -109.581375) (xy 38.630726 -109.610844) (xy 38.670082 -109.644942)
			(xy 44.669708 -109.644942) (xy 44.673779 -109.58932) (xy 44.685905 -109.534883) (xy 44.705828 -109.482792)
			(xy 44.733124 -109.434157) (xy 44.76721 -109.390014) (xy 44.807359 -109.351305) (xy 44.852717 -109.318854)
			(xy 44.902317 -109.293353) (xy 44.955101 -109.275346) (xy 45.009944 -109.265216) (xy 45.065678 -109.263179)
			(xy 45.121115 -109.269279) (xy 45.175072 -109.283385) (xy 45.226401 -109.305197) (xy 45.274007 -109.334251)
			(xy 45.316875 -109.369926) (xy 45.354092 -109.411463) (xy 45.384865 -109.457976) (xy 45.408537 -109.508473)
			(xy 45.424605 -109.56188) (xy 45.432725 -109.617056) (xy 45.433234 -109.644942) (xy 45.432725 -109.672828)
			(xy 45.424605 -109.728004) (xy 45.408537 -109.781411) (xy 45.384865 -109.831908) (xy 45.354092 -109.878421)
			(xy 45.316875 -109.919958) (xy 45.274007 -109.955633) (xy 45.226401 -109.984687) (xy 45.175072 -110.006499)
			(xy 45.121115 -110.020605) (xy 45.065678 -110.026705) (xy 45.009944 -110.024668) (xy 44.955101 -110.014538)
			(xy 44.902317 -109.996531) (xy 44.852717 -109.97103) (xy 44.807359 -109.938579) (xy 44.76721 -109.89987)
			(xy 44.733124 -109.855727) (xy 44.705828 -109.807092) (xy 44.685905 -109.755001) (xy 44.673779 -109.700564)
			(xy 44.669708 -109.644942) (xy 38.670082 -109.644942) (xy 38.671926 -109.64654) (xy 38.707627 -109.687736)
			(xy 38.737102 -109.733594) (xy 38.759749 -109.78318) (xy 38.775108 -109.835485) (xy 38.782867 -109.889443)
			(xy 38.782867 -109.943957) (xy 38.775108 -109.997915) (xy 38.759749 -110.05022) (xy 38.737102 -110.099806)
			(xy 38.707627 -110.145664) (xy 38.671926 -110.18686) (xy 38.630726 -110.222556) (xy 38.584864 -110.252025)
			(xy 38.535275 -110.274666) (xy 38.482968 -110.290019) (xy 38.429009 -110.29777) (xy 38.401752 -110.29823)
			(xy 38.386959 -110.298091) (xy 38.357461 -110.295805) (xy 38.342824 -110.293658) (xy 38.331849 -110.292564)
			(xy 38.310661 -110.298605) (xy 38.30193 -110.305342) (xy 38.243256 -110.35538) (xy 38.235237 -110.362955)
			(xy 38.226018 -110.38297) (xy 38.225476 -110.393988) (xy 38.225476 -110.69828) (xy 38.226033 -110.709296)
			(xy 38.23524 -110.729313) (xy 38.243256 -110.736888) (xy 38.30193 -110.786926) (xy 38.310626 -110.793736)
			(xy 38.331842 -110.799793) (xy 38.342824 -110.79861) (xy 38.357462 -110.796472) (xy 38.386959 -110.794182)
			(xy 38.401752 -110.794038) (xy 38.42901 -110.794406) (xy 38.482973 -110.802158) (xy 38.535283 -110.817512)
			(xy 38.584875 -110.840154) (xy 38.611929 -110.857538) (xy 48.964594 -110.857538) (xy 48.968665 -110.801916)
			(xy 48.980791 -110.747479) (xy 49.000714 -110.695388) (xy 49.02801 -110.646753) (xy 49.062096 -110.60261)
			(xy 49.102245 -110.563901) (xy 49.147603 -110.53145) (xy 49.197203 -110.505949) (xy 49.249987 -110.487942)
			(xy 49.30483 -110.477812) (xy 49.360564 -110.475775) (xy 49.416001 -110.481875) (xy 49.469958 -110.495981)
			(xy 49.521287 -110.517793) (xy 49.568893 -110.546847) (xy 49.611761 -110.582522) (xy 49.648978 -110.624059)
			(xy 49.679751 -110.670572) (xy 49.703423 -110.721069) (xy 49.719491 -110.774476) (xy 49.727611 -110.829652)
			(xy 49.72812 -110.857538) (xy 49.727611 -110.885424) (xy 49.719491 -110.9406) (xy 49.703423 -110.994007)
			(xy 49.679751 -111.044504) (xy 49.648978 -111.091017) (xy 49.611761 -111.132554) (xy 49.568893 -111.168229)
			(xy 49.521287 -111.197283) (xy 49.469958 -111.219095) (xy 49.416001 -111.233201) (xy 49.360564 -111.239301)
			(xy 49.30483 -111.237264) (xy 49.249987 -111.227134) (xy 49.197203 -111.209127) (xy 49.147603 -111.183626)
			(xy 49.102245 -111.151175) (xy 49.062096 -111.112466) (xy 49.02801 -111.068323) (xy 49.000714 -111.019688)
			(xy 48.980791 -110.967597) (xy 48.968665 -110.91316) (xy 48.964594 -110.857538) (xy 38.611929 -110.857538)
			(xy 38.63074 -110.869625) (xy 38.671943 -110.905323) (xy 38.707647 -110.946522) (xy 38.737123 -110.992383)
			(xy 38.759771 -111.041972) (xy 38.775132 -111.09428) (xy 38.782891 -111.148242) (xy 38.782891 -111.202758)
			(xy 38.775132 -111.25672) (xy 38.759771 -111.309028) (xy 38.737123 -111.358617) (xy 38.707647 -111.404478)
			(xy 38.672495 -111.44504) (xy 44.669708 -111.44504) (xy 44.673779 -111.389418) (xy 44.685905 -111.334981)
			(xy 44.705828 -111.28289) (xy 44.733124 -111.234255) (xy 44.76721 -111.190112) (xy 44.807359 -111.151403)
			(xy 44.852717 -111.118952) (xy 44.902317 -111.093451) (xy 44.955101 -111.075444) (xy 45.009944 -111.065314)
			(xy 45.065678 -111.063277) (xy 45.121115 -111.069377) (xy 45.175072 -111.083483) (xy 45.226401 -111.105295)
			(xy 45.274007 -111.134349) (xy 45.316875 -111.170024) (xy 45.354092 -111.211561) (xy 45.384865 -111.258074)
			(xy 45.408537 -111.308571) (xy 45.424605 -111.361978) (xy 45.432725 -111.417154) (xy 45.433234 -111.44504)
			(xy 45.432725 -111.472926) (xy 45.424605 -111.528102) (xy 45.408537 -111.581509) (xy 45.384865 -111.632006)
			(xy 45.354092 -111.678519) (xy 45.316875 -111.720056) (xy 45.274007 -111.755731) (xy 45.226401 -111.784785)
			(xy 45.175072 -111.806597) (xy 45.121115 -111.820703) (xy 45.065678 -111.826803) (xy 45.009944 -111.824766)
			(xy 44.955101 -111.814636) (xy 44.902317 -111.796629) (xy 44.852717 -111.771128) (xy 44.807359 -111.738677)
			(xy 44.76721 -111.699968) (xy 44.733124 -111.655825) (xy 44.705828 -111.60719) (xy 44.685905 -111.555099)
			(xy 44.673779 -111.500662) (xy 44.669708 -111.44504) (xy 38.672495 -111.44504) (xy 38.671943 -111.445677)
			(xy 38.63074 -111.481375) (xy 38.584875 -111.510846) (xy 38.535283 -111.533488) (xy 38.482973 -111.548842)
			(xy 38.42901 -111.556594) (xy 38.401752 -111.557054) (xy 38.375843 -111.55662) (xy 38.324505 -111.549589)
			(xy 38.27459 -111.535677) (xy 38.227016 -111.51514) (xy 38.182658 -111.488354) (xy 38.142332 -111.455814)
			(xy 38.106779 -111.418116) (xy 38.091364 -111.397288) (xy 38.085596 -111.389982) (xy 38.070114 -111.379681)
			(xy 38.061138 -111.377222) (xy 38.030658 -111.370364) (xy 38.021381 -111.36862) (xy 38.002719 -111.371358)
			(xy 37.994336 -111.375698) (xy 37.968371 -111.390015) (xy 37.913515 -111.41252) (xy 37.856209 -111.427741)
			(xy 37.797415 -111.43542) (xy 37.767768 -111.435896) (xy 37.738126 -111.435371) (xy 37.679346 -111.427656)
			(xy 37.622047 -111.412438) (xy 37.567186 -111.389968) (xy 37.5412 -111.375698) (xy 37.53279 -111.371444)
			(xy 37.514158 -111.368714) (xy 37.504878 -111.370364) (xy 37.474398 -111.377222) (xy 37.465397 -111.379624)
			(xy 37.449896 -111.389935) (xy 37.444172 -111.397288) (xy 37.428733 -111.4181) (xy 37.393197 -111.455814)
			(xy 37.35288 -111.488367) (xy 37.308526 -111.51516) (xy 37.260952 -111.535698) (xy 37.211034 -111.549604)
			(xy 37.159693 -111.55662) (xy 37.133784 -111.557054) (xy 37.106537 -111.556475) (xy 37.052597 -111.548717)
			(xy 37.000311 -111.533363) (xy 36.950742 -111.510723) (xy 36.904899 -111.48126) (xy 36.863716 -111.445573)
			(xy 36.82803 -111.404388) (xy 36.798569 -111.358544) (xy 36.775932 -111.308974) (xy 36.760579 -111.256687)
			(xy 36.752824 -111.202747) (xy 36.752824 -111.148253) (xy 36.760579 -111.094313) (xy 36.775932 -111.042026)
			(xy 36.798569 -110.992456) (xy 36.82803 -110.946612) (xy 36.863716 -110.905427) (xy 36.904899 -110.86974)
			(xy 36.950742 -110.840277) (xy 37.000311 -110.817637) (xy 37.052597 -110.802283) (xy 37.106537 -110.794525)
			(xy 37.133784 -110.794038) (xy 37.148577 -110.794173) (xy 37.178075 -110.796462) (xy 37.192712 -110.79861)
			(xy 37.203687 -110.799732) (xy 37.224878 -110.793674) (xy 37.233606 -110.786926) (xy 37.29228 -110.736888)
			(xy 37.300319 -110.729331) (xy 37.309525 -110.709302) (xy 37.31006 -110.69828) (xy 37.31006 -110.393988)
			(xy 37.309541 -110.382966) (xy 37.30031 -110.362949) (xy 37.29228 -110.35538) (xy 37.233606 -110.305342)
			(xy 37.224899 -110.298548) (xy 37.203692 -110.292483) (xy 37.192712 -110.293658) (xy 37.178073 -110.295793)
			(xy 37.148577 -110.298085) (xy 37.133784 -110.29823) (xy 37.106535 -110.297699) (xy 37.052592 -110.289941)
			(xy 37.000303 -110.274585) (xy 36.95073 -110.251944) (xy 36.904885 -110.222479) (xy 36.863699 -110.18679)
			(xy 36.828011 -110.145603) (xy 36.798548 -110.099756) (xy 36.775909 -110.050182) (xy 36.760556 -109.997892)
			(xy 36.7528 -109.943949) (xy 5.06984 -109.943949) (xy 5.06984 -111.127032) (xy 14.288768 -111.127032)
			(xy 14.292839 -111.07141) (xy 14.304965 -111.016973) (xy 14.324888 -110.964882) (xy 14.352184 -110.916247)
			(xy 14.38627 -110.872104) (xy 14.426419 -110.833395) (xy 14.471777 -110.800944) (xy 14.521377 -110.775443)
			(xy 14.574161 -110.757436) (xy 14.629004 -110.747306) (xy 14.684738 -110.745269) (xy 14.740175 -110.751369)
			(xy 14.794132 -110.765475) (xy 14.845461 -110.787287) (xy 14.893067 -110.816341) (xy 14.935935 -110.852016)
			(xy 14.973152 -110.893553) (xy 15.003925 -110.940066) (xy 15.027597 -110.990563) (xy 15.043665 -111.04397)
			(xy 15.051785 -111.099146) (xy 15.052294 -111.127032) (xy 15.304768 -111.127032) (xy 15.308839 -111.07141)
			(xy 15.320965 -111.016973) (xy 15.340888 -110.964882) (xy 15.368184 -110.916247) (xy 15.40227 -110.872104)
			(xy 15.442419 -110.833395) (xy 15.487777 -110.800944) (xy 15.537377 -110.775443) (xy 15.590161 -110.757436)
			(xy 15.645004 -110.747306) (xy 15.700738 -110.745269) (xy 15.756175 -110.751369) (xy 15.810132 -110.765475)
			(xy 15.861461 -110.787287) (xy 15.909067 -110.816341) (xy 15.951935 -110.852016) (xy 15.989152 -110.893553)
			(xy 16.019925 -110.940066) (xy 16.043597 -110.990563) (xy 16.059665 -111.04397) (xy 16.067785 -111.099146)
			(xy 16.068294 -111.127032) (xy 16.320768 -111.127032) (xy 16.324839 -111.07141) (xy 16.336965 -111.016973)
			(xy 16.356888 -110.964882) (xy 16.384184 -110.916247) (xy 16.41827 -110.872104) (xy 16.458419 -110.833395)
			(xy 16.503777 -110.800944) (xy 16.553377 -110.775443) (xy 16.606161 -110.757436) (xy 16.661004 -110.747306)
			(xy 16.716738 -110.745269) (xy 16.772175 -110.751369) (xy 16.826132 -110.765475) (xy 16.877461 -110.787287)
			(xy 16.925067 -110.816341) (xy 16.967935 -110.852016) (xy 17.005152 -110.893553) (xy 17.035925 -110.940066)
			(xy 17.059597 -110.990563) (xy 17.075665 -111.04397) (xy 17.083785 -111.099146) (xy 17.084294 -111.127032)
			(xy 17.083785 -111.154918) (xy 17.075665 -111.210094) (xy 17.059597 -111.263501) (xy 17.035925 -111.313998)
			(xy 17.005152 -111.360511) (xy 16.967935 -111.402048) (xy 16.925067 -111.437723) (xy 16.877461 -111.466777)
			(xy 16.826132 -111.488589) (xy 16.772175 -111.502695) (xy 16.716738 -111.508795) (xy 16.661004 -111.506758)
			(xy 16.606161 -111.496628) (xy 16.553377 -111.478621) (xy 16.503777 -111.45312) (xy 16.458419 -111.420669)
			(xy 16.41827 -111.38196) (xy 16.384184 -111.337817) (xy 16.356888 -111.289182) (xy 16.336965 -111.237091)
			(xy 16.324839 -111.182654) (xy 16.320768 -111.127032) (xy 16.068294 -111.127032) (xy 16.067785 -111.154918)
			(xy 16.059665 -111.210094) (xy 16.043597 -111.263501) (xy 16.019925 -111.313998) (xy 15.989152 -111.360511)
			(xy 15.951935 -111.402048) (xy 15.909067 -111.437723) (xy 15.861461 -111.466777) (xy 15.810132 -111.488589)
			(xy 15.756175 -111.502695) (xy 15.700738 -111.508795) (xy 15.645004 -111.506758) (xy 15.590161 -111.496628)
			(xy 15.537377 -111.478621) (xy 15.487777 -111.45312) (xy 15.442419 -111.420669) (xy 15.40227 -111.38196)
			(xy 15.368184 -111.337817) (xy 15.340888 -111.289182) (xy 15.320965 -111.237091) (xy 15.308839 -111.182654)
			(xy 15.304768 -111.127032) (xy 15.052294 -111.127032) (xy 15.051785 -111.154918) (xy 15.043665 -111.210094)
			(xy 15.027597 -111.263501) (xy 15.003925 -111.313998) (xy 14.973152 -111.360511) (xy 14.935935 -111.402048)
			(xy 14.893067 -111.437723) (xy 14.845461 -111.466777) (xy 14.794132 -111.488589) (xy 14.740175 -111.502695)
			(xy 14.684738 -111.508795) (xy 14.629004 -111.506758) (xy 14.574161 -111.496628) (xy 14.521377 -111.478621)
			(xy 14.471777 -111.45312) (xy 14.426419 -111.420669) (xy 14.38627 -111.38196) (xy 14.352184 -111.337817)
			(xy 14.324888 -111.289182) (xy 14.304965 -111.237091) (xy 14.292839 -111.182654) (xy 14.288768 -111.127032)
			(xy 5.06984 -111.127032) (xy 5.06984 -111.750452) (xy 34.110648 -111.750452) (xy 34.110648 -111.695948)
			(xy 34.118404 -111.641998) (xy 34.133759 -111.589701) (xy 34.156401 -111.540121) (xy 34.185867 -111.494269)
			(xy 34.221559 -111.453076) (xy 34.262749 -111.417381) (xy 34.3086 -111.387912) (xy 34.358178 -111.365268)
			(xy 34.410474 -111.349909) (xy 34.464424 -111.342149) (xy 34.491676 -111.341662) (xy 34.517586 -111.342069)
			(xy 34.568926 -111.349103) (xy 34.618842 -111.36302) (xy 34.666416 -111.383562) (xy 34.710774 -111.410351)
			(xy 34.751099 -111.442896) (xy 34.78665 -111.480598) (xy 34.802064 -111.501428) (xy 34.807819 -111.508746)
			(xy 34.823311 -111.51904) (xy 34.83229 -111.521494) (xy 34.86277 -111.528352) (xy 34.872045 -111.530109)
			(xy 34.89071 -111.527362) (xy 34.899092 -111.523018) (xy 34.925072 -111.508731) (xy 34.979922 -111.486217)
			(xy 35.037224 -111.470989) (xy 35.096015 -111.463301) (xy 35.12566 -111.46282) (xy 35.155302 -111.463331)
			(xy 35.214084 -111.471049) (xy 35.271382 -111.486272) (xy 35.326243 -111.508746) (xy 35.352228 -111.523018)
			(xy 35.360653 -111.527237) (xy 35.379273 -111.529989) (xy 35.38855 -111.528352) (xy 35.41903 -111.521494)
			(xy 35.42802 -111.519057) (xy 35.443526 -111.50877) (xy 35.449256 -111.501428) (xy 35.464683 -111.480606)
			(xy 35.50022 -111.442892) (xy 35.540539 -111.410339) (xy 35.584895 -111.383547) (xy 35.632471 -111.36301)
			(xy 35.682391 -111.349107) (xy 35.733734 -111.342094) (xy 35.759644 -111.341662) (xy 35.786891 -111.342211)
			(xy 35.84083 -111.349972) (xy 35.893115 -111.36533) (xy 35.942683 -111.387972) (xy 35.988524 -111.417437)
			(xy 36.029706 -111.453126) (xy 36.06539 -111.494311) (xy 36.094849 -111.540156) (xy 36.117486 -111.589726)
			(xy 36.132837 -111.642013) (xy 36.140592 -111.695953) (xy 36.140592 -111.750447) (xy 36.132837 -111.804387)
			(xy 36.117486 -111.856674) (xy 36.094849 -111.906244) (xy 36.06539 -111.952089) (xy 36.029706 -111.993274)
			(xy 35.988524 -112.028963) (xy 35.942683 -112.058428) (xy 35.893115 -112.08107) (xy 35.84083 -112.096428)
			(xy 35.786891 -112.104189) (xy 35.759644 -112.104678) (xy 35.744851 -112.10454) (xy 35.715353 -112.102253)
			(xy 35.700716 -112.100106) (xy 35.689741 -112.098996) (xy 35.668551 -112.105046) (xy 35.659822 -112.11179)
			(xy 35.601148 -112.161828) (xy 35.593106 -112.169383) (xy 35.5839 -112.189413) (xy 35.583368 -112.200436)
			(xy 35.583368 -112.504728) (xy 35.5839 -112.515747) (xy 35.593125 -112.535763) (xy 35.601148 -112.543336)
			(xy 35.659822 -112.593374) (xy 35.668518 -112.600184) (xy 35.689734 -112.60624) (xy 35.700716 -112.605058)
			(xy 35.715354 -112.60292) (xy 35.744851 -112.60063) (xy 35.759644 -112.600486) (xy 35.786893 -112.600987)
			(xy 35.840835 -112.608748) (xy 35.893124 -112.624107) (xy 35.942694 -112.64675) (xy 35.988539 -112.676217)
			(xy 36.029723 -112.711908) (xy 36.065409 -112.753097) (xy 36.094871 -112.798944) (xy 36.117508 -112.848518)
			(xy 36.132861 -112.900808) (xy 36.140616 -112.954751) (xy 36.140616 -113.009249) (xy 36.132861 -113.063192)
			(xy 36.117508 -113.115482) (xy 36.094871 -113.165056) (xy 36.065409 -113.210903) (xy 36.035748 -113.245138)
			(xy 44.669708 -113.245138) (xy 44.673779 -113.189516) (xy 44.685905 -113.135079) (xy 44.705828 -113.082988)
			(xy 44.733124 -113.034353) (xy 44.76721 -112.99021) (xy 44.807359 -112.951501) (xy 44.852717 -112.91905)
			(xy 44.902317 -112.893549) (xy 44.955101 -112.875542) (xy 45.009944 -112.865412) (xy 45.065678 -112.863375)
			(xy 45.121115 -112.869475) (xy 45.175072 -112.883581) (xy 45.226401 -112.905393) (xy 45.274007 -112.934447)
			(xy 45.316875 -112.970122) (xy 45.354092 -113.011659) (xy 45.384865 -113.058172) (xy 45.408537 -113.108669)
			(xy 45.424605 -113.162076) (xy 45.432725 -113.217252) (xy 45.433234 -113.245138) (xy 47.090582 -113.245138)
			(xy 47.094653 -113.189516) (xy 47.106779 -113.135079) (xy 47.126702 -113.082988) (xy 47.153998 -113.034353)
			(xy 47.188084 -112.99021) (xy 47.228233 -112.951501) (xy 47.273591 -112.91905) (xy 47.323191 -112.893549)
			(xy 47.375975 -112.875542) (xy 47.430818 -112.865412) (xy 47.486552 -112.863375) (xy 47.541989 -112.869475)
			(xy 47.595946 -112.883581) (xy 47.647275 -112.905393) (xy 47.694881 -112.934447) (xy 47.737749 -112.970122)
			(xy 47.774966 -113.011659) (xy 47.805739 -113.058172) (xy 47.829411 -113.108669) (xy 47.845479 -113.162076)
			(xy 47.853599 -113.217252) (xy 47.854108 -113.245138) (xy 47.853599 -113.273024) (xy 47.845479 -113.3282)
			(xy 47.829411 -113.381607) (xy 47.805739 -113.432104) (xy 47.774966 -113.478617) (xy 47.737749 -113.520154)
			(xy 47.694881 -113.555829) (xy 47.647275 -113.584883) (xy 47.595946 -113.606695) (xy 47.541989 -113.620801)
			(xy 47.486552 -113.626901) (xy 47.430818 -113.624864) (xy 47.375975 -113.614734) (xy 47.323191 -113.596727)
			(xy 47.273591 -113.571226) (xy 47.228233 -113.538775) (xy 47.188084 -113.500066) (xy 47.153998 -113.455923)
			(xy 47.126702 -113.407288) (xy 47.106779 -113.355197) (xy 47.094653 -113.30076) (xy 47.090582 -113.245138)
			(xy 45.433234 -113.245138) (xy 45.432725 -113.273024) (xy 45.424605 -113.3282) (xy 45.408537 -113.381607)
			(xy 45.384865 -113.432104) (xy 45.354092 -113.478617) (xy 45.316875 -113.520154) (xy 45.274007 -113.555829)
			(xy 45.226401 -113.584883) (xy 45.175072 -113.606695) (xy 45.121115 -113.620801) (xy 45.065678 -113.626901)
			(xy 45.009944 -113.624864) (xy 44.955101 -113.614734) (xy 44.902317 -113.596727) (xy 44.852717 -113.571226)
			(xy 44.807359 -113.538775) (xy 44.76721 -113.500066) (xy 44.733124 -113.455923) (xy 44.705828 -113.407288)
			(xy 44.685905 -113.355197) (xy 44.673779 -113.30076) (xy 44.669708 -113.245138) (xy 36.035748 -113.245138)
			(xy 36.029723 -113.252092) (xy 35.988539 -113.287783) (xy 35.942694 -113.31725) (xy 35.893124 -113.339893)
			(xy 35.840835 -113.355252) (xy 35.786893 -113.363013) (xy 35.759644 -113.363502) (xy 35.733736 -113.363054)
			(xy 35.682399 -113.356023) (xy 35.632485 -113.342112) (xy 35.584912 -113.321576) (xy 35.540554 -113.294794)
			(xy 35.500227 -113.262256) (xy 35.464673 -113.224563) (xy 35.449256 -113.203736) (xy 35.443502 -113.196418)
			(xy 35.428009 -113.186125) (xy 35.41903 -113.18367) (xy 35.38855 -113.176812) (xy 35.379274 -113.175058)
			(xy 35.36061 -113.177802) (xy 35.352228 -113.182146) (xy 35.326247 -113.196431) (xy 35.271397 -113.218944)
			(xy 35.214095 -113.234173) (xy 35.155305 -113.241862) (xy 35.12566 -113.242344) (xy 35.096018 -113.241829)
			(xy 35.037237 -113.234113) (xy 34.979938 -113.218891) (xy 34.925077 -113.196418) (xy 34.899092 -113.182146)
			(xy 34.890685 -113.177886) (xy 34.87205 -113.175161) (xy 34.86277 -113.176812) (xy 34.83229 -113.18367)
			(xy 34.823307 -113.186126) (xy 34.807798 -113.1964) (xy 34.802064 -113.203736) (xy 34.786644 -113.224562)
			(xy 34.751103 -113.262274) (xy 34.710783 -113.294824) (xy 34.666425 -113.321615) (xy 34.618848 -113.342151)
			(xy 34.568929 -113.356054) (xy 34.517586 -113.363069) (xy 34.491676 -113.363502) (xy 34.464425 -113.363027)
			(xy 34.410479 -113.355267) (xy 34.358187 -113.33991) (xy 34.308612 -113.317267) (xy 34.262764 -113.287799)
			(xy 34.221576 -113.252107) (xy 34.185886 -113.210917) (xy 34.156422 -113.165067) (xy 34.133782 -113.115491)
			(xy 34.118428 -113.063197) (xy 34.110672 -113.009251) (xy 34.110672 -112.954749) (xy 34.118428 -112.900803)
			(xy 34.133782 -112.848509) (xy 34.156422 -112.798933) (xy 34.185886 -112.753083) (xy 34.221576 -112.711893)
			(xy 34.262764 -112.676201) (xy 34.308612 -112.646733) (xy 34.358187 -112.62409) (xy 34.410479 -112.608733)
			(xy 34.464425 -112.600973) (xy 34.491676 -112.600486) (xy 34.506469 -112.600623) (xy 34.535967 -112.602911)
			(xy 34.550604 -112.605058) (xy 34.561579 -112.606188) (xy 34.582771 -112.600126) (xy 34.591498 -112.593374)
			(xy 34.650172 -112.543336) (xy 34.658188 -112.535758) (xy 34.667408 -112.515745) (xy 34.667952 -112.504728)
			(xy 34.667952 -112.200436) (xy 34.667409 -112.189417) (xy 34.658195 -112.1694) (xy 34.650172 -112.161828)
			(xy 34.591498 -112.11179) (xy 34.582791 -112.104997) (xy 34.561584 -112.098929) (xy 34.550604 -112.100106)
			(xy 34.535965 -112.102241) (xy 34.506469 -112.104533) (xy 34.491676 -112.104678) (xy 34.464424 -112.104251)
			(xy 34.410474 -112.096491) (xy 34.358178 -112.081132) (xy 34.3086 -112.058488) (xy 34.262749 -112.029019)
			(xy 34.221559 -111.993324) (xy 34.185867 -111.952131) (xy 34.156401 -111.906279) (xy 34.133759 -111.856699)
			(xy 34.118404 -111.804402) (xy 34.110648 -111.750452) (xy 5.06984 -111.750452) (xy 5.06984 -113.302034)
			(xy 14.31417 -113.302034) (xy 14.314656 -113.274783) (xy 14.322412 -113.220835) (xy 14.337767 -113.16854)
			(xy 14.360409 -113.118963) (xy 14.389875 -113.073113) (xy 14.425566 -113.031922) (xy 14.466757 -112.996231)
			(xy 14.512607 -112.966765) (xy 14.562184 -112.944123) (xy 14.614479 -112.928768) (xy 14.668427 -112.921012)
			(xy 14.722929 -112.921012) (xy 14.776877 -112.928768) (xy 14.829172 -112.944123) (xy 14.878749 -112.966765)
			(xy 14.924599 -112.996231) (xy 14.96579 -113.031922) (xy 15.001481 -113.073113) (xy 15.030947 -113.118963)
			(xy 15.047844 -113.155961) (xy 16.316179 -113.155961) (xy 16.323933 -113.102014) (xy 16.339286 -113.04972)
			(xy 16.361925 -113.000144) (xy 16.391388 -112.954293) (xy 16.427077 -112.913103) (xy 16.468264 -112.87741)
			(xy 16.514112 -112.847942) (xy 16.563687 -112.825299) (xy 16.615979 -112.809941) (xy 16.669925 -112.802181)
			(xy 16.724426 -112.802178) (xy 16.778373 -112.809931) (xy 16.830667 -112.825282) (xy 16.880245 -112.847918)
			(xy 16.926096 -112.87738) (xy 16.967288 -112.913068) (xy 17.002982 -112.954254) (xy 17.032451 -113.0001)
			(xy 17.055096 -113.049674) (xy 17.070456 -113.101966) (xy 17.078218 -113.155912) (xy 17.078265 -113.158524)
			(xy 22.54326 -113.158524) (xy 22.547331 -113.102902) (xy 22.559457 -113.048465) (xy 22.57938 -112.996374)
			(xy 22.606676 -112.947739) (xy 22.640762 -112.903596) (xy 22.680911 -112.864887) (xy 22.726269 -112.832436)
			(xy 22.775869 -112.806935) (xy 22.828653 -112.788928) (xy 22.883496 -112.778798) (xy 22.93923 -112.776761)
			(xy 22.994667 -112.782861) (xy 23.048624 -112.796967) (xy 23.099953 -112.818779) (xy 23.147559 -112.847833)
			(xy 23.190427 -112.883508) (xy 23.227644 -112.925045) (xy 23.258417 -112.971558) (xy 23.282089 -113.022055)
			(xy 23.298157 -113.075462) (xy 23.306277 -113.130638) (xy 23.306786 -113.158524) (xy 23.306277 -113.18641)
			(xy 23.298157 -113.241586) (xy 23.282089 -113.294993) (xy 23.258417 -113.34549) (xy 23.227644 -113.392003)
			(xy 23.190427 -113.43354) (xy 23.147559 -113.469215) (xy 23.099953 -113.498269) (xy 23.048624 -113.520081)
			(xy 22.994667 -113.534187) (xy 22.93923 -113.540287) (xy 22.883496 -113.53825) (xy 22.828653 -113.52812)
			(xy 22.775869 -113.510113) (xy 22.726269 -113.484612) (xy 22.680911 -113.452161) (xy 22.640762 -113.413452)
			(xy 22.606676 -113.369309) (xy 22.57938 -113.320674) (xy 22.559457 -113.268583) (xy 22.547331 -113.214146)
			(xy 22.54326 -113.158524) (xy 17.078265 -113.158524) (xy 17.078706 -113.183162) (xy 17.078706 -113.190528)
			(xy 17.078452 -113.204244) (xy 17.091914 -113.228374) (xy 17.193006 -113.286794) (xy 17.220692 -113.28654)
			(xy 17.23263 -113.279428) (xy 17.254981 -113.266473) (xy 17.302432 -113.246049) (xy 17.352208 -113.232222)
			(xy 17.403396 -113.225247) (xy 17.429226 -113.224818) (xy 17.456479 -113.225254) (xy 17.51043 -113.233014)
			(xy 17.562727 -113.248374) (xy 17.612306 -113.27102) (xy 17.658158 -113.300492) (xy 17.699348 -113.336188)
			(xy 17.73504 -113.377384) (xy 17.764505 -113.423239) (xy 17.787144 -113.472822) (xy 17.802497 -113.525121)
			(xy 17.81025 -113.579073) (xy 17.810734 -113.606326) (xy 17.810191 -113.635664) (xy 17.801191 -113.693646)
			(xy 17.783422 -113.749567) (xy 17.768264 -113.780062) (xy 49.481484 -113.780062) (xy 49.485555 -113.72444)
			(xy 49.497681 -113.670003) (xy 49.517604 -113.617912) (xy 49.5449 -113.569277) (xy 49.578986 -113.525134)
			(xy 49.619135 -113.486425) (xy 49.664493 -113.453974) (xy 49.714093 -113.428473) (xy 49.766877 -113.410466)
			(xy 49.82172 -113.400336) (xy 49.877454 -113.398299) (xy 49.932891 -113.404399) (xy 49.986848 -113.418505)
			(xy 50.038177 -113.440317) (xy 50.085783 -113.469371) (xy 50.128651 -113.505046) (xy 50.165868 -113.546583)
			(xy 50.196641 -113.593096) (xy 50.220313 -113.643593) (xy 50.236381 -113.697) (xy 50.244501 -113.752176)
			(xy 50.24501 -113.780062) (xy 50.244501 -113.807948) (xy 50.236381 -113.863124) (xy 50.220313 -113.916531)
			(xy 50.196641 -113.967028) (xy 50.165868 -114.013541) (xy 50.128651 -114.055078) (xy 50.085783 -114.090753)
			(xy 50.038177 -114.119807) (xy 49.986848 -114.141619) (xy 49.932891 -114.155725) (xy 49.877454 -114.161825)
			(xy 49.82172 -114.159788) (xy 49.766877 -114.149658) (xy 49.714093 -114.131651) (xy 49.664493 -114.10615)
			(xy 49.619135 -114.073699) (xy 49.578986 -114.03499) (xy 49.5449 -113.990847) (xy 49.517604 -113.942212)
			(xy 49.497681 -113.890121) (xy 49.485555 -113.835684) (xy 49.481484 -113.780062) (xy 17.768264 -113.780062)
			(xy 17.757304 -113.80211) (xy 17.723451 -113.850036) (xy 17.682662 -113.892216) (xy 17.659604 -113.910364)
			(xy 17.65097 -113.917584) (xy 17.640562 -113.937509) (xy 17.639538 -113.948718) (xy 17.635728 -114.038634)
			(xy 17.644364 -114.059462) (xy 17.653 -114.067082) (xy 17.672597 -114.085229) (xy 17.706989 -114.126092)
			(xy 17.735345 -114.171353) (xy 17.757111 -114.220127) (xy 17.771859 -114.27146) (xy 17.779302 -114.324349)
			(xy 17.779746 -114.351054) (xy 17.77926 -114.378305) (xy 17.771504 -114.432253) (xy 17.756149 -114.484548)
			(xy 17.753431 -114.4905) (xy 34.315398 -114.4905) (xy 34.319469 -114.434878) (xy 34.331595 -114.380441)
			(xy 34.351518 -114.32835) (xy 34.378814 -114.279715) (xy 34.4129 -114.235572) (xy 34.453049 -114.196863)
			(xy 34.498407 -114.164412) (xy 34.548007 -114.138911) (xy 34.600791 -114.120904) (xy 34.655634 -114.110774)
			(xy 34.711368 -114.108737) (xy 34.766805 -114.114837) (xy 34.820762 -114.128943) (xy 34.872091 -114.150755)
			(xy 34.919697 -114.179809) (xy 34.962565 -114.215484) (xy 34.999782 -114.257021) (xy 35.006875 -114.267742)
			(xy 64.306194 -114.267742) (xy 64.310265 -114.21212) (xy 64.322391 -114.157683) (xy 64.342314 -114.105592)
			(xy 64.36961 -114.056957) (xy 64.403696 -114.012814) (xy 64.443845 -113.974105) (xy 64.489203 -113.941654)
			(xy 64.538803 -113.916153) (xy 64.591587 -113.898146) (xy 64.64643 -113.888016) (xy 64.702164 -113.885979)
			(xy 64.757601 -113.892079) (xy 64.811558 -113.906185) (xy 64.862887 -113.927997) (xy 64.910493 -113.957051)
			(xy 64.953361 -113.992726) (xy 64.990578 -114.034263) (xy 65.021351 -114.080776) (xy 65.045023 -114.131273)
			(xy 65.061091 -114.18468) (xy 65.069211 -114.239856) (xy 65.06972 -114.267742) (xy 65.069211 -114.295628)
			(xy 65.061091 -114.350804) (xy 65.045023 -114.404211) (xy 65.021351 -114.454708) (xy 64.990578 -114.501221)
			(xy 64.953361 -114.542758) (xy 64.910493 -114.578433) (xy 64.905579 -114.581432) (xy 66.299586 -114.581432)
			(xy 66.303657 -114.52581) (xy 66.315783 -114.471373) (xy 66.335706 -114.419282) (xy 66.363002 -114.370647)
			(xy 66.397088 -114.326504) (xy 66.437237 -114.287795) (xy 66.482595 -114.255344) (xy 66.532195 -114.229843)
			(xy 66.584979 -114.211836) (xy 66.639822 -114.201706) (xy 66.695556 -114.199669) (xy 66.750993 -114.205769)
			(xy 66.80495 -114.219875) (xy 66.856279 -114.241687) (xy 66.903885 -114.270741) (xy 66.946753 -114.306416)
			(xy 66.98397 -114.347953) (xy 67.014743 -114.394466) (xy 67.038415 -114.444963) (xy 67.054483 -114.49837)
			(xy 67.062603 -114.553546) (xy 67.063112 -114.581432) (xy 67.062603 -114.609318) (xy 67.054483 -114.664494)
			(xy 67.038415 -114.717901) (xy 67.014743 -114.768398) (xy 66.98397 -114.814911) (xy 66.946753 -114.856448)
			(xy 66.903885 -114.892123) (xy 66.856279 -114.921177) (xy 66.80495 -114.942989) (xy 66.750993 -114.957095)
			(xy 66.695556 -114.963195) (xy 66.639822 -114.961158) (xy 66.584979 -114.951028) (xy 66.532195 -114.933021)
			(xy 66.482595 -114.90752) (xy 66.437237 -114.875069) (xy 66.397088 -114.83636) (xy 66.363002 -114.792217)
			(xy 66.335706 -114.743582) (xy 66.315783 -114.691491) (xy 66.303657 -114.637054) (xy 66.299586 -114.581432)
			(xy 64.905579 -114.581432) (xy 64.862887 -114.607487) (xy 64.811558 -114.629299) (xy 64.757601 -114.643405)
			(xy 64.702164 -114.649505) (xy 64.64643 -114.647468) (xy 64.591587 -114.637338) (xy 64.538803 -114.619331)
			(xy 64.489203 -114.59383) (xy 64.443845 -114.561379) (xy 64.403696 -114.52267) (xy 64.36961 -114.478527)
			(xy 64.342314 -114.429892) (xy 64.322391 -114.377801) (xy 64.310265 -114.323364) (xy 64.306194 -114.267742)
			(xy 35.006875 -114.267742) (xy 35.030555 -114.303534) (xy 35.054227 -114.354031) (xy 35.070295 -114.407438)
			(xy 35.078415 -114.462614) (xy 35.078924 -114.4905) (xy 35.078415 -114.518386) (xy 35.070295 -114.573562)
			(xy 35.054227 -114.626969) (xy 35.030555 -114.677466) (xy 34.999782 -114.723979) (xy 34.962565 -114.765516)
			(xy 34.919697 -114.801191) (xy 34.872091 -114.830245) (xy 34.820762 -114.852057) (xy 34.766805 -114.866163)
			(xy 34.711368 -114.872263) (xy 34.655634 -114.870226) (xy 34.600791 -114.860096) (xy 34.548007 -114.842089)
			(xy 34.498407 -114.816588) (xy 34.453049 -114.784137) (xy 34.4129 -114.745428) (xy 34.378814 -114.701285)
			(xy 34.351518 -114.65265) (xy 34.331595 -114.600559) (xy 34.319469 -114.546122) (xy 34.315398 -114.4905)
			(xy 17.753431 -114.4905) (xy 17.733507 -114.534125) (xy 17.704041 -114.579975) (xy 17.66835 -114.621166)
			(xy 17.627159 -114.656857) (xy 17.581309 -114.686323) (xy 17.531732 -114.708965) (xy 17.479437 -114.72432)
			(xy 17.425489 -114.732076) (xy 17.370987 -114.732076) (xy 17.317039 -114.72432) (xy 17.264744 -114.708965)
			(xy 17.215167 -114.686323) (xy 17.169317 -114.656857) (xy 17.128126 -114.621166) (xy 17.092435 -114.579975)
			(xy 17.062969 -114.534125) (xy 17.040327 -114.484548) (xy 17.024972 -114.432253) (xy 17.017216 -114.378305)
			(xy 17.01673 -114.351054) (xy 17.017273 -114.321716) (xy 17.026275 -114.263735) (xy 17.044044 -114.207814)
			(xy 17.070163 -114.155272) (xy 17.104015 -114.107346) (xy 17.144803 -114.065165) (xy 17.16786 -114.047016)
			(xy 17.176496 -114.039798) (xy 17.186904 -114.019872) (xy 17.187926 -114.008662) (xy 17.191736 -113.918746)
			(xy 17.1831 -113.897918) (xy 17.174464 -113.890298) (xy 17.154899 -113.872118) (xy 17.120505 -113.831262)
			(xy 17.092146 -113.786007) (xy 17.070375 -113.73724) (xy 17.05562 -113.685913) (xy 17.048167 -113.633029)
			(xy 17.047718 -113.606326) (xy 17.047718 -113.59896) (xy 17.047972 -113.585244) (xy 17.03451 -113.561114)
			(xy 16.933418 -113.502694) (xy 16.905732 -113.502948) (xy 16.893794 -113.51006) (xy 16.871437 -113.523004)
			(xy 16.823988 -113.543431) (xy 16.774214 -113.557261) (xy 16.723028 -113.56424) (xy 16.697198 -113.56467)
			(xy 16.669948 -113.56422) (xy 16.616001 -113.556464) (xy 16.563708 -113.541109) (xy 16.514132 -113.518469)
			(xy 16.468283 -113.489004) (xy 16.427093 -113.453313) (xy 16.391402 -113.412125) (xy 16.361936 -113.366276)
			(xy 16.339294 -113.316701) (xy 16.323938 -113.264408) (xy 16.316181 -113.210462) (xy 16.316179 -113.155961)
			(xy 15.047844 -113.155961) (xy 15.053589 -113.16854) (xy 15.068944 -113.220835) (xy 15.0767 -113.274783)
			(xy 15.077186 -113.302034) (xy 15.077186 -113.302542) (xy 15.076533 -113.333873) (xy 15.066243 -113.395684)
			(xy 15.045995 -113.454984) (xy 15.03172 -113.482882) (xy 15.025111 -113.496318) (xy 15.019178 -113.52565)
			(xy 15.022008 -113.555442) (xy 15.033357 -113.583132) (xy 15.052249 -113.606341) (xy 15.077061 -113.623072)
			(xy 15.10566 -113.631887) (xy 15.12062 -113.632488) (xy 15.147775 -113.633133) (xy 15.201502 -113.641122)
			(xy 15.253552 -113.65665) (xy 15.302873 -113.679404) (xy 15.348468 -113.708924) (xy 15.389415 -113.744612)
			(xy 15.424887 -113.785747) (xy 15.454165 -113.831498) (xy 15.476658 -113.880938) (xy 15.491911 -113.93307)
			(xy 15.499616 -113.986838) (xy 15.500096 -114.013996) (xy 15.49961 -114.041247) (xy 15.491854 -114.095195)
			(xy 15.476499 -114.14749) (xy 15.453857 -114.197067) (xy 15.424391 -114.242917) (xy 15.3887 -114.284108)
			(xy 15.347509 -114.319799) (xy 15.301659 -114.349265) (xy 15.252082 -114.371907) (xy 15.199787 -114.387262)
			(xy 15.145839 -114.395018) (xy 15.091337 -114.395018) (xy 15.037389 -114.387262) (xy 14.985094 -114.371907)
			(xy 14.935517 -114.349265) (xy 14.889667 -114.319799) (xy 14.848476 -114.284108) (xy 14.812785 -114.242917)
			(xy 14.783319 -114.197067) (xy 14.760677 -114.14749) (xy 14.745322 -114.095195) (xy 14.737566 -114.041247)
			(xy 14.73708 -114.013996) (xy 14.73708 -114.013488) (xy 14.737748 -113.982158) (xy 14.748033 -113.920347)
			(xy 14.768275 -113.861046) (xy 14.782546 -113.833148) (xy 14.789148 -113.819707) (xy 14.79509 -113.790375)
			(xy 14.792267 -113.76058) (xy 14.78092 -113.732887) (xy 14.762025 -113.709677) (xy 14.73721 -113.692947)
			(xy 14.708608 -113.684138) (xy 14.693646 -113.683542) (xy 14.666491 -113.682899) (xy 14.612766 -113.674907)
			(xy 14.560718 -113.659375) (xy 14.511399 -113.63662) (xy 14.465805 -113.607099) (xy 14.424859 -113.571411)
			(xy 14.389388 -113.530277) (xy 14.360109 -113.484527) (xy 14.337615 -113.435088) (xy 14.32236 -113.382958)
			(xy 14.314651 -113.329192) (xy 14.31417 -113.302034) (xy 5.06984 -113.302034) (xy 5.06984 -114.135408)
			(xy 13.571726 -114.135408) (xy 13.575797 -114.079786) (xy 13.587923 -114.025349) (xy 13.607846 -113.973258)
			(xy 13.635142 -113.924623) (xy 13.669228 -113.88048) (xy 13.709377 -113.841771) (xy 13.754735 -113.80932)
			(xy 13.804335 -113.783819) (xy 13.857119 -113.765812) (xy 13.911962 -113.755682) (xy 13.967696 -113.753645)
			(xy 14.023133 -113.759745) (xy 14.07709 -113.773851) (xy 14.128419 -113.795663) (xy 14.176025 -113.824717)
			(xy 14.218893 -113.860392) (xy 14.25611 -113.901929) (xy 14.286883 -113.948442) (xy 14.310555 -113.998939)
			(xy 14.326623 -114.052346) (xy 14.334743 -114.107522) (xy 14.335252 -114.135408) (xy 14.334743 -114.163294)
			(xy 14.326623 -114.21847) (xy 14.310555 -114.271877) (xy 14.286883 -114.322374) (xy 14.25611 -114.368887)
			(xy 14.218893 -114.410424) (xy 14.176025 -114.446099) (xy 14.128419 -114.475153) (xy 14.07709 -114.496965)
			(xy 14.023133 -114.511071) (xy 13.967696 -114.517171) (xy 13.911962 -114.515134) (xy 13.857119 -114.505004)
			(xy 13.804335 -114.486997) (xy 13.754735 -114.461496) (xy 13.709377 -114.429045) (xy 13.669228 -114.390336)
			(xy 13.635142 -114.346193) (xy 13.607846 -114.297558) (xy 13.587923 -114.245467) (xy 13.575797 -114.19103)
			(xy 13.571726 -114.135408) (xy 5.06984 -114.135408) (xy 5.06984 -114.672364) (xy 10.461242 -114.672364)
			(xy 10.465313 -114.616742) (xy 10.477439 -114.562305) (xy 10.497362 -114.510214) (xy 10.524658 -114.461579)
			(xy 10.558744 -114.417436) (xy 10.598893 -114.378727) (xy 10.644251 -114.346276) (xy 10.693851 -114.320775)
			(xy 10.746635 -114.302768) (xy 10.801478 -114.292638) (xy 10.857212 -114.290601) (xy 10.912649 -114.296701)
			(xy 10.966606 -114.310807) (xy 11.017935 -114.332619) (xy 11.065541 -114.361673) (xy 11.108409 -114.397348)
			(xy 11.145626 -114.438885) (xy 11.176399 -114.485398) (xy 11.200071 -114.535895) (xy 11.216139 -114.589302)
			(xy 11.224259 -114.644478) (xy 11.22455 -114.660426) (xy 11.961366 -114.660426) (xy 11.965437 -114.604804)
			(xy 11.977563 -114.550367) (xy 11.997486 -114.498276) (xy 12.024782 -114.449641) (xy 12.058868 -114.405498)
			(xy 12.099017 -114.366789) (xy 12.144375 -114.334338) (xy 12.193975 -114.308837) (xy 12.246759 -114.29083)
			(xy 12.301602 -114.2807) (xy 12.357336 -114.278663) (xy 12.412773 -114.284763) (xy 12.46673 -114.298869)
			(xy 12.518059 -114.320681) (xy 12.565665 -114.349735) (xy 12.608533 -114.38541) (xy 12.64575 -114.426947)
			(xy 12.676523 -114.47346) (xy 12.700195 -114.523957) (xy 12.716263 -114.577364) (xy 12.724383 -114.63254)
			(xy 12.724892 -114.660426) (xy 12.724383 -114.688312) (xy 12.716263 -114.743488) (xy 12.700195 -114.796895)
			(xy 12.676523 -114.847392) (xy 12.64575 -114.893905) (xy 12.608533 -114.935442) (xy 12.565665 -114.971117)
			(xy 12.518059 -115.000171) (xy 12.46673 -115.021983) (xy 12.412773 -115.036089) (xy 12.357336 -115.042189)
			(xy 12.301602 -115.040152) (xy 12.246759 -115.030022) (xy 12.193975 -115.012015) (xy 12.144375 -114.986514)
			(xy 12.099017 -114.954063) (xy 12.058868 -114.915354) (xy 12.024782 -114.871211) (xy 11.997486 -114.822576)
			(xy 11.977563 -114.770485) (xy 11.965437 -114.716048) (xy 11.961366 -114.660426) (xy 11.22455 -114.660426)
			(xy 11.224768 -114.672364) (xy 11.224259 -114.70025) (xy 11.216139 -114.755426) (xy 11.200071 -114.808833)
			(xy 11.176399 -114.85933) (xy 11.145626 -114.905843) (xy 11.108409 -114.94738) (xy 11.065541 -114.983055)
			(xy 11.017935 -115.012109) (xy 10.966606 -115.033921) (xy 10.912649 -115.048027) (xy 10.857212 -115.054127)
			(xy 10.801478 -115.05209) (xy 10.746635 -115.04196) (xy 10.693851 -115.023953) (xy 10.644251 -114.998452)
			(xy 10.598893 -114.966001) (xy 10.558744 -114.927292) (xy 10.524658 -114.883149) (xy 10.497362 -114.834514)
			(xy 10.477439 -114.782423) (xy 10.465313 -114.727986) (xy 10.461242 -114.672364) (xy 5.06984 -114.672364)
			(xy 5.06984 -116.450364) (xy 11.961366 -116.450364) (xy 11.965437 -116.394742) (xy 11.977563 -116.340305)
			(xy 11.997486 -116.288214) (xy 12.024782 -116.239579) (xy 12.058868 -116.195436) (xy 12.099017 -116.156727)
			(xy 12.144375 -116.124276) (xy 12.193975 -116.098775) (xy 12.246759 -116.080768) (xy 12.301602 -116.070638)
			(xy 12.357336 -116.068601) (xy 12.412773 -116.074701) (xy 12.46673 -116.088807) (xy 12.518059 -116.110619)
			(xy 12.565665 -116.139673) (xy 12.608533 -116.175348) (xy 12.64575 -116.216885) (xy 12.676523 -116.263398)
			(xy 12.700195 -116.313895) (xy 12.716263 -116.367302) (xy 12.724383 -116.422478) (xy 12.724892 -116.450364)
			(xy 12.724383 -116.47825) (xy 12.716263 -116.533426) (xy 12.700195 -116.586833) (xy 12.676523 -116.63733)
			(xy 12.64575 -116.683843) (xy 12.608533 -116.72538) (xy 12.565665 -116.761055) (xy 12.518059 -116.790109)
			(xy 12.46673 -116.811921) (xy 12.412773 -116.826027) (xy 12.357336 -116.832127) (xy 12.301602 -116.83009)
			(xy 12.246759 -116.81996) (xy 12.193975 -116.801953) (xy 12.144375 -116.776452) (xy 12.099017 -116.744001)
			(xy 12.058868 -116.705292) (xy 12.024782 -116.661149) (xy 11.997486 -116.612514) (xy 11.977563 -116.560423)
			(xy 11.965437 -116.505986) (xy 11.961366 -116.450364) (xy 5.06984 -116.450364) (xy 5.06984 -117.434106)
			(xy 13.37691 -117.434106) (xy 13.377377 -117.406736) (xy 13.385194 -117.352557) (xy 13.400683 -117.300053)
			(xy 13.423525 -117.250307) (xy 13.453249 -117.20434) (xy 13.47089 -117.183408) (xy 13.471144 -117.183154)
			(xy 13.476719 -117.17606) (xy 13.482972 -117.159149) (xy 13.483336 -117.150134) (xy 13.483336 -117.083078)
			(xy 13.482982 -117.074061) (xy 13.476732 -117.057144) (xy 13.471144 -117.050058) (xy 13.47089 -117.050058)
			(xy 13.47089 -117.049804) (xy 13.453257 -117.028866) (xy 13.423535 -116.982898) (xy 13.400691 -116.933152)
			(xy 13.385196 -116.880652) (xy 13.377368 -116.826474) (xy 13.377367 -116.771735) (xy 13.385194 -116.717557)
			(xy 13.400688 -116.665056) (xy 13.42353 -116.61531) (xy 13.453251 -116.569341) (xy 13.47089 -116.548408)
			(xy 13.471144 -116.548154) (xy 13.476719 -116.54106) (xy 13.482972 -116.524149) (xy 13.483336 -116.515134)
			(xy 13.483336 -116.448078) (xy 13.482982 -116.439061) (xy 13.476732 -116.422144) (xy 13.471144 -116.415058)
			(xy 13.47089 -116.415058) (xy 13.47089 -116.414804) (xy 13.453238 -116.393883) (xy 13.423528 -116.347907)
			(xy 13.400695 -116.298156) (xy 13.385207 -116.245653) (xy 13.377382 -116.191476) (xy 13.37691 -116.164106)
			(xy 13.377361 -116.136852) (xy 13.385118 -116.0829) (xy 13.400474 -116.030601) (xy 13.423117 -115.98102)
			(xy 13.452586 -115.935166) (xy 13.488281 -115.893972) (xy 13.529475 -115.858279) (xy 13.57533 -115.828811)
			(xy 13.624912 -115.80617) (xy 13.677212 -115.790815) (xy 13.731164 -115.78306) (xy 13.758418 -115.782598)
			(xy 13.785789 -115.783054) (xy 13.839968 -115.790874) (xy 13.892471 -115.806366) (xy 13.942218 -115.82921)
			(xy 13.988184 -115.858936) (xy 14.009116 -115.876578) (xy 14.00937 -115.876832) (xy 14.016458 -115.882416)
			(xy 14.033374 -115.888663) (xy 14.04239 -115.889024) (xy 14.109446 -115.889024) (xy 14.11846 -115.888636)
			(xy 14.135377 -115.882409) (xy 14.142466 -115.876832) (xy 14.142466 -115.876578) (xy 14.14272 -115.876578)
			(xy 14.163669 -115.85896) (xy 14.209637 -115.829245) (xy 14.259381 -115.806406) (xy 14.311877 -115.79091)
			(xy 14.36605 -115.783075) (xy 14.393418 -115.782598) (xy 14.42067 -115.783061) (xy 14.474619 -115.79082)
			(xy 14.526914 -115.806178) (xy 14.576492 -115.828822) (xy 14.622343 -115.85829) (xy 14.663533 -115.893984)
			(xy 14.699224 -115.935177) (xy 14.72869 -115.981029) (xy 14.75133 -116.030608) (xy 14.766685 -116.082905)
			(xy 14.774441 -116.136854) (xy 14.774926 -116.164106) (xy 14.774481 -116.191477) (xy 14.766661 -116.245658)
			(xy 14.751168 -116.298162) (xy 14.728321 -116.347909) (xy 14.69859 -116.393874) (xy 14.680946 -116.414804)
			(xy 14.680692 -116.415058) (xy 14.675116 -116.422152) (xy 14.668863 -116.439063) (xy 14.6685 -116.448078)
			(xy 14.6685 -116.515134) (xy 14.668841 -116.524152) (xy 14.6751 -116.541069) (xy 14.680692 -116.548154)
			(xy 14.680946 -116.548154) (xy 14.680946 -116.548408) (xy 14.698594 -116.569335) (xy 14.72832 -116.615303)
			(xy 14.751167 -116.66505) (xy 14.766664 -116.717554) (xy 14.774493 -116.771733) (xy 14.774492 -116.826476)
			(xy 14.766662 -116.880655) (xy 14.751164 -116.933158) (xy 14.728316 -116.982904) (xy 14.698588 -117.028872)
			(xy 14.680946 -117.049804) (xy 14.680692 -117.050058) (xy 14.675116 -117.057152) (xy 14.668863 -117.074063)
			(xy 14.6685 -117.083078) (xy 14.6685 -117.150134) (xy 14.668841 -117.159152) (xy 14.6751 -117.176069)
			(xy 14.680692 -117.183154) (xy 14.680946 -117.183154) (xy 14.680946 -117.183408) (xy 14.698594 -117.204333)
			(xy 14.728306 -117.250307) (xy 14.751141 -117.300056) (xy 14.76663 -117.352559) (xy 14.774454 -117.406736)
			(xy 14.774926 -117.434106) (xy 14.774786 -117.442234) (xy 15.659098 -117.442234) (xy 15.663169 -117.386612)
			(xy 15.675295 -117.332175) (xy 15.695218 -117.280084) (xy 15.722514 -117.231449) (xy 15.7566 -117.187306)
			(xy 15.796749 -117.148597) (xy 15.842107 -117.116146) (xy 15.891707 -117.090645) (xy 15.944491 -117.072638)
			(xy 15.999334 -117.062508) (xy 16.055068 -117.060471) (xy 16.110505 -117.066571) (xy 16.164462 -117.080677)
			(xy 16.215791 -117.102489) (xy 16.263397 -117.131543) (xy 16.306265 -117.167218) (xy 16.343482 -117.208755)
			(xy 16.374255 -117.255268) (xy 16.397927 -117.305765) (xy 16.413995 -117.359172) (xy 16.422115 -117.414348)
			(xy 16.422624 -117.442234) (xy 16.422115 -117.47012) (xy 16.413995 -117.525296) (xy 16.397927 -117.578703)
			(xy 16.374255 -117.6292) (xy 16.343482 -117.675713) (xy 16.306265 -117.71725) (xy 16.263397 -117.752925)
			(xy 16.215791 -117.781979) (xy 16.164462 -117.803791) (xy 16.110505 -117.817897) (xy 16.055068 -117.823997)
			(xy 15.999334 -117.82196) (xy 15.944491 -117.81183) (xy 15.891707 -117.793823) (xy 15.842107 -117.768322)
			(xy 15.796749 -117.735871) (xy 15.7566 -117.697162) (xy 15.722514 -117.653019) (xy 15.695218 -117.604384)
			(xy 15.675295 -117.552293) (xy 15.663169 -117.497856) (xy 15.659098 -117.442234) (xy 14.774786 -117.442234)
			(xy 14.774469 -117.460662) (xy 14.767101 -117.513262) (xy 14.752509 -117.564331) (xy 14.74216 -117.588792)
			(xy 14.737815 -117.600161) (xy 14.739162 -117.624433) (xy 14.7447 -117.635274) (xy 14.786102 -117.706394)
			(xy 14.792839 -117.716462) (xy 14.813244 -117.729453) (xy 14.825218 -117.731286) (xy 14.853196 -117.734495)
			(xy 14.90786 -117.748027) (xy 14.959939 -117.769449) (xy 15.008302 -117.798296) (xy 15.051898 -117.833941)
			(xy 15.089779 -117.875609) (xy 15.121122 -117.922394) (xy 15.145244 -117.973279) (xy 15.161622 -118.027158)
			(xy 15.167063 -118.063772) (xy 16.806162 -118.063772) (xy 16.810233 -118.00815) (xy 16.822359 -117.953713)
			(xy 16.842282 -117.901622) (xy 16.869578 -117.852987) (xy 16.903664 -117.808844) (xy 16.943813 -117.770135)
			(xy 16.989171 -117.737684) (xy 17.038771 -117.712183) (xy 17.091555 -117.694176) (xy 17.146398 -117.684046)
			(xy 17.202132 -117.682009) (xy 17.257569 -117.688109) (xy 17.311526 -117.702215) (xy 17.362855 -117.724027)
			(xy 17.410461 -117.753081) (xy 17.453329 -117.788756) (xy 17.490546 -117.830293) (xy 17.521319 -117.876806)
			(xy 17.544991 -117.927303) (xy 17.561059 -117.98071) (xy 17.567078 -118.021608) (xy 17.685512 -118.021608)
			(xy 17.68598 -117.994238) (xy 17.693797 -117.940059) (xy 17.709285 -117.887555) (xy 17.732127 -117.837809)
			(xy 17.761851 -117.791842) (xy 17.779492 -117.77091) (xy 17.779746 -117.770656) (xy 17.785321 -117.763562)
			(xy 17.791573 -117.746651) (xy 17.791938 -117.737636) (xy 17.791938 -117.67058) (xy 17.791582 -117.661563)
			(xy 17.785333 -117.644647) (xy 17.779746 -117.63756) (xy 17.779492 -117.63756) (xy 17.779492 -117.637306)
			(xy 17.761861 -117.616366) (xy 17.732138 -117.570399) (xy 17.709294 -117.520653) (xy 17.693799 -117.468153)
			(xy 17.68597 -117.413976) (xy 17.68597 -117.359236) (xy 17.693796 -117.305059) (xy 17.70929 -117.252558)
			(xy 17.732132 -117.202812) (xy 17.761853 -117.156843) (xy 17.779492 -117.13591) (xy 17.779746 -117.135656)
			(xy 17.785321 -117.128562) (xy 17.791573 -117.111651) (xy 17.791938 -117.102636) (xy 17.791938 -117.03558)
			(xy 17.791582 -117.026563) (xy 17.785333 -117.009647) (xy 17.779746 -117.00256) (xy 17.779492 -117.00256)
			(xy 17.779492 -117.002306) (xy 17.761841 -116.981384) (xy 17.732131 -116.935408) (xy 17.709298 -116.885658)
			(xy 17.693809 -116.833155) (xy 17.685984 -116.778978) (xy 17.685512 -116.751608) (xy 17.685963 -116.724354)
			(xy 17.693719 -116.670402) (xy 17.709075 -116.618103) (xy 17.731718 -116.568521) (xy 17.761187 -116.522667)
			(xy 17.796882 -116.481474) (xy 17.838077 -116.44578) (xy 17.883932 -116.416313) (xy 17.933514 -116.393671)
			(xy 17.985814 -116.378317) (xy 18.039766 -116.370562) (xy 18.06702 -116.3701) (xy 18.094391 -116.370554)
			(xy 18.14857 -116.378375) (xy 18.201073 -116.393867) (xy 18.25082 -116.416711) (xy 18.296787 -116.446438)
			(xy 18.317718 -116.46408) (xy 18.317972 -116.464334) (xy 18.32506 -116.469919) (xy 18.341976 -116.476165)
			(xy 18.350992 -116.476526) (xy 18.418048 -116.476526) (xy 18.427062 -116.476139) (xy 18.443979 -116.469912)
			(xy 18.451068 -116.464334) (xy 18.451068 -116.46408) (xy 18.451322 -116.46408) (xy 18.47227 -116.446461)
			(xy 18.518239 -116.416747) (xy 18.567982 -116.393907) (xy 18.620479 -116.378411) (xy 18.674652 -116.370577)
			(xy 18.70202 -116.3701) (xy 18.729272 -116.370559) (xy 18.783221 -116.378319) (xy 18.835517 -116.393677)
			(xy 18.885095 -116.416321) (xy 18.930945 -116.44579) (xy 18.972136 -116.481484) (xy 19.007827 -116.522677)
			(xy 19.018865 -116.539853) (xy 36.544449 -116.539853) (xy 36.544449 -116.485347) (xy 36.552207 -116.431394)
			(xy 36.567563 -116.379095) (xy 36.590206 -116.329514) (xy 36.619675 -116.28366) (xy 36.65537 -116.242467)
			(xy 36.696563 -116.206773) (xy 36.742418 -116.177304) (xy 36.791999 -116.154662) (xy 36.844298 -116.139306)
			(xy 36.898251 -116.131549) (xy 36.925504 -116.131086) (xy 36.951818 -116.131555) (xy 37.003946 -116.13879)
			(xy 37.054589 -116.153109) (xy 37.102788 -116.174242) (xy 37.147631 -116.201787) (xy 37.188271 -116.235225)
			(xy 37.206428 -116.254276) (xy 37.21394 -116.261688) (xy 37.233227 -116.270208) (xy 37.243766 -116.270786)
			(xy 37.318442 -116.270786) (xy 37.32899 -116.270243) (xy 37.348286 -116.261718) (xy 37.35578 -116.254276)
			(xy 37.372776 -116.236393) (xy 37.410614 -116.204732) (xy 37.452222 -116.17822) (xy 37.474398 -116.167408)
			(xy 37.484558 -116.162582) (xy 37.498782 -116.145818) (xy 37.525198 -116.049044) (xy 37.521642 -116.027708)
			(xy 37.515292 -116.018564) (xy 37.515292 -116.01831) (xy 37.499726 -115.994464) (xy 37.475069 -115.943134)
			(xy 37.458304 -115.888713) (xy 37.449802 -115.832406) (xy 37.449252 -115.803934) (xy 37.449827 -115.775043)
			(xy 37.458508 -115.717917) (xy 37.475707 -115.662754) (xy 37.501031 -115.610817) (xy 37.5339 -115.563294)
			(xy 37.573561 -115.521273) (xy 37.619107 -115.485716) (xy 37.669495 -115.457436) (xy 37.723573 -115.437081)
			(xy 37.780103 -115.425117) (xy 37.808916 -115.422934) (xy 37.819838 -115.422426) (xy 37.839142 -115.412266)
			(xy 37.899848 -115.335304) (xy 37.905182 -115.314222) (xy 37.90315 -115.303554) (xy 37.900308 -115.286807)
			(xy 37.897252 -115.252975) (xy 37.897054 -115.23599) (xy 37.897054 -115.235228) (xy 37.89754 -115.207977)
			(xy 37.905296 -115.154029) (xy 37.920651 -115.101734) (xy 37.943293 -115.052157) (xy 37.972759 -115.006307)
			(xy 38.00845 -114.965116) (xy 38.049641 -114.929425) (xy 38.095491 -114.899959) (xy 38.145068 -114.877317)
			(xy 38.197363 -114.861962) (xy 38.251311 -114.854206) (xy 38.305813 -114.854206) (xy 38.359761 -114.861962)
			(xy 38.412056 -114.877317) (xy 38.461633 -114.899959) (xy 38.507483 -114.929425) (xy 38.548674 -114.965116)
			(xy 38.584365 -115.006307) (xy 38.613831 -115.052157) (xy 38.636473 -115.101734) (xy 38.651828 -115.154029)
			(xy 38.659584 -115.207977) (xy 38.66007 -115.235228) (xy 38.659626 -115.264125) (xy 38.650934 -115.32126)
			(xy 38.633722 -115.37643) (xy 38.608384 -115.428372) (xy 38.575501 -115.475897) (xy 38.535825 -115.517919)
			(xy 38.490263 -115.553474) (xy 38.43986 -115.581749) (xy 38.385768 -115.602096) (xy 38.329225 -115.614052)
			(xy 38.300406 -115.616228) (xy 38.289484 -115.616736) (xy 38.27018 -115.626896) (xy 38.209474 -115.703858)
			(xy 38.20414 -115.72494) (xy 38.206172 -115.735608) (xy 38.20665 -115.738418) (xy 43.21276 -115.738418)
			(xy 43.21276 -115.651518) (xy 43.220778 -115.564989) (xy 43.236746 -115.479569) (xy 43.260527 -115.395987)
			(xy 43.291919 -115.314955) (xy 43.330653 -115.237166) (xy 43.3764 -115.163282) (xy 43.428769 -115.093935)
			(xy 43.487313 -115.029715) (xy 43.551533 -114.971171) (xy 43.62088 -114.918802) (xy 43.694764 -114.873055)
			(xy 43.772553 -114.834321) (xy 43.853585 -114.802929) (xy 43.937167 -114.779148) (xy 44.022587 -114.76318)
			(xy 44.109116 -114.755162) (xy 44.196016 -114.755162) (xy 44.282545 -114.76318) (xy 44.367965 -114.779148)
			(xy 44.451547 -114.802929) (xy 44.532579 -114.834321) (xy 44.610368 -114.873055) (xy 44.684252 -114.918802)
			(xy 44.753599 -114.971171) (xy 44.817819 -115.029715) (xy 44.876363 -115.093935) (xy 44.928732 -115.163282)
			(xy 44.974479 -115.237166) (xy 45.013213 -115.314955) (xy 45.044605 -115.395987) (xy 45.068386 -115.479569)
			(xy 45.084354 -115.564989) (xy 45.092372 -115.651518) (xy 45.092874 -115.694968) (xy 45.092372 -115.738418)
			(xy 45.092372 -115.73842) (xy 46.475642 -115.73842) (xy 46.475642 -115.65152) (xy 46.48366 -115.564991)
			(xy 46.499628 -115.479571) (xy 46.523409 -115.395988) (xy 46.554801 -115.314956) (xy 46.593536 -115.237167)
			(xy 46.639282 -115.163283) (xy 46.691651 -115.093935) (xy 46.750195 -115.029715) (xy 46.814415 -114.971171)
			(xy 46.883763 -114.918802) (xy 46.957647 -114.873056) (xy 47.035436 -114.834321) (xy 47.116468 -114.802929)
			(xy 47.200051 -114.779148) (xy 47.285471 -114.76318) (xy 47.372 -114.755162) (xy 47.41545 -114.75466)
			(xy 49.26965 -114.75466) (xy 49.3131 -114.755166) (xy 49.399629 -114.763184) (xy 49.485049 -114.779152)
			(xy 49.568631 -114.802933) (xy 49.649662 -114.834325) (xy 49.727451 -114.873059) (xy 49.801335 -114.918806)
			(xy 49.870682 -114.971174) (xy 49.934902 -115.029718) (xy 49.993446 -115.093938) (xy 50.045814 -115.163285)
			(xy 50.091561 -115.237169) (xy 50.130295 -115.314958) (xy 50.161687 -115.395989) (xy 50.185468 -115.479571)
			(xy 50.201436 -115.564991) (xy 50.209454 -115.65152) (xy 50.209454 -115.738418) (xy 50.58257 -115.738418)
			(xy 50.58257 -115.651518) (xy 50.590588 -115.564989) (xy 50.606556 -115.479569) (xy 50.630337 -115.395987)
			(xy 50.661729 -115.314955) (xy 50.700463 -115.237166) (xy 50.74621 -115.163282) (xy 50.798579 -115.093935)
			(xy 50.857123 -115.029715) (xy 50.921343 -114.971171) (xy 50.99069 -114.918802) (xy 51.064574 -114.873055)
			(xy 51.142363 -114.834321) (xy 51.223395 -114.802929) (xy 51.306977 -114.779148) (xy 51.392397 -114.76318)
			(xy 51.478926 -114.755162) (xy 51.565826 -114.755162) (xy 51.652355 -114.76318) (xy 51.737775 -114.779148)
			(xy 51.821357 -114.802929) (xy 51.902389 -114.834321) (xy 51.980178 -114.873055) (xy 52.054062 -114.918802)
			(xy 52.123409 -114.971171) (xy 52.187629 -115.029715) (xy 52.246173 -115.093935) (xy 52.298542 -115.163282)
			(xy 52.344289 -115.237166) (xy 52.383023 -115.314955) (xy 52.414415 -115.395987) (xy 52.438196 -115.479569)
			(xy 52.454164 -115.564989) (xy 52.455193 -115.576096) (xy 55.847232 -115.576096) (xy 55.851303 -115.520474)
			(xy 55.863429 -115.466037) (xy 55.883352 -115.413946) (xy 55.910648 -115.365311) (xy 55.944734 -115.321168)
			(xy 55.984883 -115.282459) (xy 56.030241 -115.250008) (xy 56.079841 -115.224507) (xy 56.132625 -115.2065)
			(xy 56.187468 -115.19637) (xy 56.243202 -115.194333) (xy 56.298639 -115.200433) (xy 56.352596 -115.214539)
			(xy 56.403925 -115.236351) (xy 56.451531 -115.265405) (xy 56.476007 -115.285774) (xy 66.931286 -115.285774)
			(xy 66.931889 -115.256693) (xy 66.940735 -115.199208) (xy 66.958202 -115.143732) (xy 66.983887 -115.091548)
			(xy 67.017193 -115.043868) (xy 67.05735 -115.001794) (xy 67.103427 -114.966301) (xy 67.154357 -114.938213)
			(xy 67.208959 -114.918179) (xy 67.237356 -114.911886) (xy 67.23761 -114.911886) (xy 67.248343 -114.909129)
			(xy 67.266125 -114.895945) (xy 67.2719 -114.886486) (xy 67.314826 -114.807746) (xy 67.31635 -114.785648)
			(xy 67.312032 -114.77498) (xy 67.303608 -114.752618) (xy 67.291748 -114.706327) (xy 67.285751 -114.658919)
			(xy 67.285362 -114.635026) (xy 67.285848 -114.607775) (xy 67.293604 -114.553827) (xy 67.308959 -114.501532)
			(xy 67.331601 -114.451955) (xy 67.361067 -114.406105) (xy 67.396758 -114.364914) (xy 67.437949 -114.329223)
			(xy 67.483799 -114.299757) (xy 67.533376 -114.277115) (xy 67.585671 -114.26176) (xy 67.639619 -114.254004)
			(xy 67.694121 -114.254004) (xy 67.748069 -114.26176) (xy 67.800364 -114.277115) (xy 67.849941 -114.299757)
			(xy 67.895791 -114.329223) (xy 67.936982 -114.364914) (xy 67.972673 -114.406105) (xy 68.002139 -114.451955)
			(xy 68.024781 -114.501532) (xy 68.040136 -114.553827) (xy 68.047892 -114.607775) (xy 68.048378 -114.635026)
			(xy 68.047803 -114.664108) (xy 68.038957 -114.721596) (xy 68.021487 -114.777075) (xy 68.004014 -114.812572)
			(xy 71.850758 -114.812572) (xy 71.851244 -114.785321) (xy 71.859 -114.731373) (xy 71.874355 -114.679078)
			(xy 71.896997 -114.629501) (xy 71.926463 -114.583651) (xy 71.962154 -114.54246) (xy 72.003345 -114.506769)
			(xy 72.049195 -114.477303) (xy 72.098772 -114.454661) (xy 72.151067 -114.439306) (xy 72.205015 -114.43155)
			(xy 72.259517 -114.43155) (xy 72.313465 -114.439306) (xy 72.36576 -114.454661) (xy 72.415337 -114.477303)
			(xy 72.461187 -114.506769) (xy 72.502378 -114.54246) (xy 72.538069 -114.583651) (xy 72.567535 -114.629501)
			(xy 72.590177 -114.679078) (xy 72.605532 -114.731373) (xy 72.613288 -114.785321) (xy 72.613774 -114.812572)
			(xy 72.613219 -114.842264) (xy 72.604009 -114.900929) (xy 72.585822 -114.957459) (xy 72.559097 -115.010489)
			(xy 72.52448 -115.058739) (xy 72.504046 -115.080288) (xy 72.49668 -115.087654) (xy 72.489314 -115.10645)
			(xy 72.491092 -115.200176) (xy 72.499474 -115.218972) (xy 72.507094 -115.22583) (xy 72.525906 -115.243934)
			(xy 72.558883 -115.28441) (xy 72.586035 -115.329003) (xy 72.599932 -115.360958) (xy 74.11847 -115.360958)
			(xy 74.118953 -115.333588) (xy 74.126764 -115.279409) (xy 74.142248 -115.226906) (xy 74.165087 -115.177158)
			(xy 74.194809 -115.131191) (xy 74.21245 -115.11026) (xy 74.212704 -115.110006) (xy 74.218295 -115.102922)
			(xy 74.224539 -115.086003) (xy 74.224896 -115.076986) (xy 74.224896 -115.00993) (xy 74.224526 -115.000914)
			(xy 74.218288 -114.983997) (xy 74.212704 -114.97691) (xy 74.21245 -114.97691) (xy 74.21245 -114.976656)
			(xy 74.194831 -114.955707) (xy 74.165115 -114.90974) (xy 74.142274 -114.859997) (xy 74.126778 -114.807499)
			(xy 74.118946 -114.753326) (xy 74.11847 -114.725958) (xy 74.118939 -114.698707) (xy 74.1267 -114.64476)
			(xy 74.14206 -114.592466) (xy 74.164704 -114.54289) (xy 74.194173 -114.497041) (xy 74.229866 -114.455852)
			(xy 74.271057 -114.420161) (xy 74.316907 -114.390694) (xy 74.366485 -114.368053) (xy 74.418779 -114.352696)
			(xy 74.472727 -114.344937) (xy 74.499978 -114.34445) (xy 74.527348 -114.344917) (xy 74.581528 -114.352733)
			(xy 74.634031 -114.368221) (xy 74.683778 -114.391063) (xy 74.729745 -114.420788) (xy 74.750676 -114.43843)
			(xy 74.75093 -114.438684) (xy 74.758034 -114.444246) (xy 74.774937 -114.450508) (xy 74.78395 -114.450876)
			(xy 74.851006 -114.450876) (xy 74.860024 -114.450527) (xy 74.876941 -114.444275) (xy 74.884026 -114.438684)
			(xy 74.884026 -114.43843) (xy 74.88428 -114.43843) (xy 74.905213 -114.420791) (xy 74.951185 -114.391079)
			(xy 75.000932 -114.368242) (xy 75.053433 -114.352751) (xy 75.107609 -114.344923) (xy 75.134978 -114.34445)
			(xy 75.162227 -114.344999) (xy 75.21617 -114.352751) (xy 75.268461 -114.368101) (xy 75.318035 -114.390737)
			(xy 75.363884 -114.420197) (xy 75.405073 -114.455882) (xy 75.440765 -114.497065) (xy 75.470233 -114.542909)
			(xy 75.492876 -114.592479) (xy 75.508235 -114.644767) (xy 75.515997 -114.698709) (xy 75.516486 -114.725958)
			(xy 75.515999 -114.753328) (xy 75.508187 -114.807506) (xy 75.492703 -114.860009) (xy 75.469866 -114.909756)
			(xy 75.440145 -114.955724) (xy 75.422506 -114.976656) (xy 75.422252 -114.97691) (xy 75.416649 -114.983985)
			(xy 75.410413 -115.000911) (xy 75.41006 -115.00993) (xy 75.41006 -115.076986) (xy 75.410411 -115.086004)
			(xy 75.416661 -115.102921) (xy 75.422252 -115.110006) (xy 75.422506 -115.110006) (xy 75.422506 -115.11026)
			(xy 75.440141 -115.131196) (xy 75.469853 -115.177167) (xy 75.49269 -115.226914) (xy 75.508182 -115.279414)
			(xy 75.516011 -115.333589) (xy 75.516486 -115.360958) (xy 75.516006 -115.388211) (xy 75.514192 -115.400836)
			(xy 87.260682 -115.400836) (xy 87.264753 -115.345214) (xy 87.276879 -115.290777) (xy 87.296802 -115.238686)
			(xy 87.324098 -115.190051) (xy 87.358184 -115.145908) (xy 87.398333 -115.107199) (xy 87.443691 -115.074748)
			(xy 87.493291 -115.049247) (xy 87.546075 -115.03124) (xy 87.600918 -115.02111) (xy 87.656652 -115.019073)
			(xy 87.712089 -115.025173) (xy 87.766046 -115.039279) (xy 87.817375 -115.061091) (xy 87.864981 -115.090145)
			(xy 87.907849 -115.12582) (xy 87.945066 -115.167357) (xy 87.975839 -115.21387) (xy 87.999511 -115.264367)
			(xy 88.015579 -115.317774) (xy 88.023317 -115.370356) (xy 89.361262 -115.370356) (xy 89.365333 -115.314734)
			(xy 89.377459 -115.260297) (xy 89.397382 -115.208206) (xy 89.424678 -115.159571) (xy 89.458764 -115.115428)
			(xy 89.498913 -115.076719) (xy 89.544271 -115.044268) (xy 89.593871 -115.018767) (xy 89.646655 -115.00076)
			(xy 89.701498 -114.99063) (xy 89.757232 -114.988593) (xy 89.812669 -114.994693) (xy 89.866626 -115.008799)
			(xy 89.917955 -115.030611) (xy 89.965561 -115.059665) (xy 90.008429 -115.09534) (xy 90.045646 -115.136877)
			(xy 90.076419 -115.18339) (xy 90.100091 -115.233887) (xy 90.116159 -115.287294) (xy 90.124279 -115.34247)
			(xy 90.124788 -115.370356) (xy 90.124279 -115.398242) (xy 90.116159 -115.453418) (xy 90.100091 -115.506825)
			(xy 90.076419 -115.557322) (xy 90.045646 -115.603835) (xy 90.008429 -115.645372) (xy 89.965561 -115.681047)
			(xy 89.917955 -115.710101) (xy 89.866626 -115.731913) (xy 89.812669 -115.746019) (xy 89.757232 -115.752119)
			(xy 89.701498 -115.750082) (xy 89.646655 -115.739952) (xy 89.593871 -115.721945) (xy 89.544271 -115.696444)
			(xy 89.498913 -115.663993) (xy 89.458764 -115.625284) (xy 89.424678 -115.581141) (xy 89.397382 -115.532506)
			(xy 89.377459 -115.480415) (xy 89.365333 -115.425978) (xy 89.361262 -115.370356) (xy 88.023317 -115.370356)
			(xy 88.023699 -115.37295) (xy 88.024208 -115.400836) (xy 88.023699 -115.428722) (xy 88.015579 -115.483898)
			(xy 87.999511 -115.537305) (xy 87.975839 -115.587802) (xy 87.945066 -115.634315) (xy 87.907849 -115.675852)
			(xy 87.864981 -115.711527) (xy 87.817375 -115.740581) (xy 87.766046 -115.762393) (xy 87.712089 -115.776499)
			(xy 87.656652 -115.782599) (xy 87.600918 -115.780562) (xy 87.546075 -115.770432) (xy 87.493291 -115.752425)
			(xy 87.443691 -115.726924) (xy 87.398333 -115.694473) (xy 87.358184 -115.655764) (xy 87.324098 -115.611621)
			(xy 87.296802 -115.562986) (xy 87.276879 -115.510895) (xy 87.264753 -115.456458) (xy 87.260682 -115.400836)
			(xy 75.514192 -115.400836) (xy 75.508254 -115.442162) (xy 75.492902 -115.494461) (xy 75.470263 -115.544043)
			(xy 75.440797 -115.589897) (xy 75.405105 -115.631091) (xy 75.363913 -115.666785) (xy 75.31806 -115.696253)
			(xy 75.26848 -115.718895) (xy 75.216182 -115.734249) (xy 75.162231 -115.742004) (xy 75.134978 -115.742466)
			(xy 75.107607 -115.742021) (xy 75.053427 -115.734199) (xy 75.000923 -115.718706) (xy 74.951176 -115.695859)
			(xy 74.905211 -115.66613) (xy 74.88428 -115.648486) (xy 74.884026 -115.648232) (xy 74.876942 -115.642642)
			(xy 74.860023 -115.636399) (xy 74.851006 -115.63604) (xy 74.78395 -115.63604) (xy 74.774934 -115.636412)
			(xy 74.758017 -115.642648) (xy 74.75093 -115.648232) (xy 74.75093 -115.648486) (xy 74.750676 -115.648486)
			(xy 74.729724 -115.666101) (xy 74.683757 -115.695817) (xy 74.634015 -115.718658) (xy 74.581518 -115.734154)
			(xy 74.527346 -115.741989) (xy 74.499978 -115.742466) (xy 74.472723 -115.742065) (xy 74.418767 -115.734304)
			(xy 74.366466 -115.718943) (xy 74.316883 -115.696295) (xy 74.271027 -115.666821) (xy 74.229834 -115.631121)
			(xy 74.194141 -115.589921) (xy 74.164674 -115.544061) (xy 74.142034 -115.494474) (xy 74.126682 -115.44217)
			(xy 74.11893 -115.388213) (xy 74.11847 -115.360958) (xy 72.599932 -115.360958) (xy 72.606857 -115.376881)
			(xy 72.620959 -115.42715) (xy 72.628078 -115.478871) (xy 72.628506 -115.504976) (xy 72.62802 -115.532227)
			(xy 72.620264 -115.586175) (xy 72.604909 -115.63847) (xy 72.582267 -115.688047) (xy 72.552801 -115.733897)
			(xy 72.51711 -115.775088) (xy 72.475919 -115.810779) (xy 72.441909 -115.832636) (xy 92.979748 -115.832636)
			(xy 92.980235 -115.804078) (xy 92.988733 -115.747598) (xy 93.005558 -115.693017) (xy 93.030334 -115.641555)
			(xy 93.062508 -115.594364) (xy 93.10136 -115.552498) (xy 93.146021 -115.516895) (xy 93.170502 -115.502182)
			(xy 93.183387 -115.494085) (xy 93.204065 -115.471781) (xy 93.217255 -115.444375) (xy 93.221786 -115.414299)
			(xy 93.217255 -115.384223) (xy 93.204064 -115.356818) (xy 93.183385 -115.334514) (xy 93.170502 -115.326414)
			(xy 93.14606 -115.311646) (xy 93.101418 -115.276037) (xy 93.062581 -115.234174) (xy 93.030415 -115.186991)
			(xy 93.005638 -115.135543) (xy 92.988803 -115.080977) (xy 92.980285 -115.024512) (xy 92.979748 -114.99596)
			(xy 92.980234 -114.968709) (xy 92.98799 -114.914761) (xy 93.003345 -114.862466) (xy 93.025987 -114.812889)
			(xy 93.055453 -114.767039) (xy 93.091144 -114.725848) (xy 93.132335 -114.690157) (xy 93.178185 -114.660691)
			(xy 93.227762 -114.638049) (xy 93.280057 -114.622694) (xy 93.334005 -114.614938) (xy 93.388507 -114.614938)
			(xy 93.442455 -114.622694) (xy 93.49475 -114.638049) (xy 93.544327 -114.660691) (xy 93.590177 -114.690157)
			(xy 93.631368 -114.725848) (xy 93.667059 -114.767039) (xy 93.696525 -114.812889) (xy 93.719167 -114.862466)
			(xy 93.734522 -114.914761) (xy 93.742278 -114.968709) (xy 93.742764 -114.99596) (xy 93.742268 -115.024518)
			(xy 93.733771 -115.080997) (xy 93.716947 -115.135577) (xy 93.692172 -115.187039) (xy 93.66 -115.23423)
			(xy 93.62115 -115.276096) (xy 93.576491 -115.311701) (xy 93.55201 -115.326414) (xy 93.539128 -115.334516)
			(xy 93.518447 -115.356818) (xy 93.505255 -115.384223) (xy 93.503709 -115.394486) (xy 95.147128 -115.394486)
			(xy 95.151199 -115.338864) (xy 95.163325 -115.284427) (xy 95.183248 -115.232336) (xy 95.210544 -115.183701)
			(xy 95.24463 -115.139558) (xy 95.284779 -115.100849) (xy 95.330137 -115.068398) (xy 95.379737 -115.042897)
			(xy 95.432521 -115.02489) (xy 95.487364 -115.01476) (xy 95.543098 -115.012723) (xy 95.598535 -115.018823)
			(xy 95.609192 -115.021609) (xy 97.556137 -115.021609) (xy 97.560451 -114.964337) (xy 97.5733 -114.908358)
			(xy 97.594393 -114.854937) (xy 97.623253 -114.80528) (xy 97.659229 -114.760509) (xy 97.680018 -114.74069)
			(xy 97.687429 -114.733176) (xy 97.695947 -114.71389) (xy 97.696528 -114.703352) (xy 97.696528 -114.628676)
			(xy 97.695963 -114.618131) (xy 97.687452 -114.598835) (xy 97.680018 -114.591338) (xy 97.660943 -114.573202)
			(xy 97.627487 -114.532569) (xy 97.59993 -114.487724) (xy 97.578795 -114.43952) (xy 97.564482 -114.388868)
			(xy 97.557263 -114.336731) (xy 97.556828 -114.310414) (xy 97.557314 -114.283163) (xy 97.56507 -114.229215)
			(xy 97.580425 -114.17692) (xy 97.603067 -114.127343) (xy 97.632533 -114.081493) (xy 97.668224 -114.040302)
			(xy 97.709415 -114.004611) (xy 97.755265 -113.975145) (xy 97.804842 -113.952503) (xy 97.857137 -113.937148)
			(xy 97.911085 -113.929392) (xy 97.965587 -113.929392) (xy 98.019535 -113.937148) (xy 98.07183 -113.952503)
			(xy 98.121407 -113.975145) (xy 98.167257 -114.004611) (xy 98.208448 -114.040302) (xy 98.244139 -114.081493)
			(xy 98.273605 -114.127343) (xy 98.296247 -114.17692) (xy 98.311602 -114.229215) (xy 98.319358 -114.283163)
			(xy 98.319844 -114.310414) (xy 98.319404 -114.336729) (xy 98.312166 -114.388859) (xy 98.297843 -114.439503)
			(xy 98.276705 -114.487703) (xy 98.249153 -114.532545) (xy 98.215709 -114.573183) (xy 98.196654 -114.591338)
			(xy 98.189242 -114.598851) (xy 98.180722 -114.618137) (xy 98.180144 -114.628676) (xy 98.180144 -114.703352)
			(xy 98.180673 -114.713902) (xy 98.189207 -114.733198) (xy 98.196654 -114.74069) (xy 98.217454 -114.760497)
			(xy 98.253426 -114.805273) (xy 98.282282 -114.854933) (xy 98.303372 -114.908356) (xy 98.316219 -114.964336)
			(xy 98.320533 -115.021609) (xy 100.094384 -115.021609) (xy 100.098697 -114.96434) (xy 100.111543 -114.908362)
			(xy 100.132631 -114.854942) (xy 100.161486 -114.805285) (xy 100.197455 -114.760511) (xy 100.21824 -114.74069)
			(xy 100.225639 -114.733166) (xy 100.234167 -114.713888) (xy 100.23475 -114.703352) (xy 100.23475 -114.628676)
			(xy 100.234178 -114.618132) (xy 100.225671 -114.598837) (xy 100.21824 -114.591338) (xy 100.19915 -114.573217)
			(xy 100.165698 -114.532579) (xy 100.138145 -114.487731) (xy 100.117013 -114.439523) (xy 100.102703 -114.38887)
			(xy 100.095485 -114.336732) (xy 100.09505 -114.310414) (xy 100.095536 -114.283163) (xy 100.103292 -114.229215)
			(xy 100.118647 -114.17692) (xy 100.141289 -114.127343) (xy 100.170755 -114.081493) (xy 100.206446 -114.040302)
			(xy 100.247637 -114.004611) (xy 100.293487 -113.975145) (xy 100.343064 -113.952503) (xy 100.395359 -113.937148)
			(xy 100.449307 -113.929392) (xy 100.503809 -113.929392) (xy 100.557757 -113.937148) (xy 100.610052 -113.952503)
			(xy 100.659629 -113.975145) (xy 100.705479 -114.004611) (xy 100.733019 -114.028474) (xy 105.005122 -114.028474)
			(xy 105.009193 -113.972852) (xy 105.021319 -113.918415) (xy 105.041242 -113.866324) (xy 105.068538 -113.817689)
			(xy 105.102624 -113.773546) (xy 105.142773 -113.734837) (xy 105.188131 -113.702386) (xy 105.237731 -113.676885)
			(xy 105.290515 -113.658878) (xy 105.345358 -113.648748) (xy 105.401092 -113.646711) (xy 105.456529 -113.652811)
			(xy 105.510486 -113.666917) (xy 105.561815 -113.688729) (xy 105.609421 -113.717783) (xy 105.652289 -113.753458)
			(xy 105.689506 -113.794995) (xy 105.720279 -113.841508) (xy 105.743951 -113.892005) (xy 105.760019 -113.945412)
			(xy 105.768139 -114.000588) (xy 105.768648 -114.028474) (xy 105.768139 -114.05636) (xy 105.760019 -114.111536)
			(xy 105.743951 -114.164943) (xy 105.720279 -114.21544) (xy 105.689506 -114.261953) (xy 105.652289 -114.30349)
			(xy 105.609421 -114.339165) (xy 105.561815 -114.368219) (xy 105.510486 -114.390031) (xy 105.456529 -114.404137)
			(xy 105.401092 -114.410237) (xy 105.345358 -114.4082) (xy 105.290515 -114.39807) (xy 105.237731 -114.380063)
			(xy 105.188131 -114.354562) (xy 105.142773 -114.322111) (xy 105.102624 -114.283402) (xy 105.068538 -114.239259)
			(xy 105.041242 -114.190624) (xy 105.021319 -114.138533) (xy 105.009193 -114.084096) (xy 105.005122 -114.028474)
			(xy 100.733019 -114.028474) (xy 100.74667 -114.040302) (xy 100.782361 -114.081493) (xy 100.811827 -114.127343)
			(xy 100.834469 -114.17692) (xy 100.849824 -114.229215) (xy 100.85758 -114.283163) (xy 100.858066 -114.310414)
			(xy 100.857619 -114.336729) (xy 100.850381 -114.388859) (xy 100.836059 -114.439502) (xy 100.814923 -114.487701)
			(xy 100.813203 -114.4905) (xy 150.415242 -114.4905) (xy 150.419313 -114.434878) (xy 150.431439 -114.380441)
			(xy 150.451362 -114.32835) (xy 150.478658 -114.279715) (xy 150.512744 -114.235572) (xy 150.552893 -114.196863)
			(xy 150.598251 -114.164412) (xy 150.647851 -114.138911) (xy 150.700635 -114.120904) (xy 150.755478 -114.110774)
			(xy 150.811212 -114.108737) (xy 150.866649 -114.114837) (xy 150.920606 -114.128943) (xy 150.971935 -114.150755)
			(xy 151.019541 -114.179809) (xy 151.062409 -114.215484) (xy 151.099626 -114.257021) (xy 151.106719 -114.267742)
			(xy 180.406038 -114.267742) (xy 180.410109 -114.21212) (xy 180.422235 -114.157683) (xy 180.442158 -114.105592)
			(xy 180.469454 -114.056957) (xy 180.50354 -114.012814) (xy 180.543689 -113.974105) (xy 180.589047 -113.941654)
			(xy 180.638647 -113.916153) (xy 180.691431 -113.898146) (xy 180.746274 -113.888016) (xy 180.802008 -113.885979)
			(xy 180.857445 -113.892079) (xy 180.911402 -113.906185) (xy 180.962731 -113.927997) (xy 181.010337 -113.957051)
			(xy 181.053205 -113.992726) (xy 181.090422 -114.034263) (xy 181.121195 -114.080776) (xy 181.144867 -114.131273)
			(xy 181.160935 -114.18468) (xy 181.169055 -114.239856) (xy 181.169564 -114.267742) (xy 181.169055 -114.295628)
			(xy 181.160935 -114.350804) (xy 181.144867 -114.404211) (xy 181.121195 -114.454708) (xy 181.090422 -114.501221)
			(xy 181.053205 -114.542758) (xy 181.010337 -114.578433) (xy 180.962731 -114.607487) (xy 180.911402 -114.629299)
			(xy 180.857445 -114.643405) (xy 180.802008 -114.649505) (xy 180.746274 -114.647468) (xy 180.691431 -114.637338)
			(xy 180.638647 -114.619331) (xy 180.589047 -114.59383) (xy 180.543689 -114.561379) (xy 180.50354 -114.52267)
			(xy 180.469454 -114.478527) (xy 180.442158 -114.429892) (xy 180.422235 -114.377801) (xy 180.410109 -114.323364)
			(xy 180.406038 -114.267742) (xy 151.106719 -114.267742) (xy 151.130399 -114.303534) (xy 151.154071 -114.354031)
			(xy 151.170139 -114.407438) (xy 151.178259 -114.462614) (xy 151.178768 -114.4905) (xy 151.178259 -114.518386)
			(xy 151.170139 -114.573562) (xy 151.154071 -114.626969) (xy 151.130399 -114.677466) (xy 151.099626 -114.723979)
			(xy 151.062409 -114.765516) (xy 151.019541 -114.801191) (xy 150.971935 -114.830245) (xy 150.920606 -114.852057)
			(xy 150.866649 -114.866163) (xy 150.811212 -114.872263) (xy 150.755478 -114.870226) (xy 150.700635 -114.860096)
			(xy 150.647851 -114.842089) (xy 150.598251 -114.816588) (xy 150.552893 -114.784137) (xy 150.512744 -114.745428)
			(xy 150.478658 -114.701285) (xy 150.451362 -114.65265) (xy 150.431439 -114.600559) (xy 150.419313 -114.546122)
			(xy 150.415242 -114.4905) (xy 100.813203 -114.4905) (xy 100.787373 -114.532544) (xy 100.75393 -114.573182)
			(xy 100.734876 -114.591338) (xy 100.727467 -114.598854) (xy 100.718944 -114.618138) (xy 100.718366 -114.628676)
			(xy 100.718366 -114.703352) (xy 100.718918 -114.713899) (xy 100.727438 -114.733194) (xy 100.734876 -114.74069)
			(xy 100.75568 -114.760495) (xy 100.791659 -114.805268) (xy 100.820521 -114.854927) (xy 100.841616 -114.908352)
			(xy 100.854465 -114.964334) (xy 100.857977 -115.010946) (xy 106.6198 -115.010946) (xy 106.623871 -114.955324)
			(xy 106.635997 -114.900887) (xy 106.65592 -114.848796) (xy 106.683216 -114.800161) (xy 106.717302 -114.756018)
			(xy 106.757451 -114.717309) (xy 106.802809 -114.684858) (xy 106.852409 -114.659357) (xy 106.905193 -114.64135)
			(xy 106.960036 -114.63122) (xy 107.01577 -114.629183) (xy 107.071207 -114.635283) (xy 107.125164 -114.649389)
			(xy 107.176493 -114.671201) (xy 107.224099 -114.700255) (xy 107.266967 -114.73593) (xy 107.304184 -114.777467)
			(xy 107.334957 -114.82398) (xy 107.358629 -114.874477) (xy 107.374697 -114.927884) (xy 107.382817 -114.98306)
			(xy 107.383326 -115.010946) (xy 107.382817 -115.038832) (xy 107.379893 -115.058698) (xy 107.98632 -115.058698)
			(xy 107.990391 -115.003076) (xy 108.002517 -114.948639) (xy 108.02244 -114.896548) (xy 108.049736 -114.847913)
			(xy 108.083822 -114.80377) (xy 108.123971 -114.765061) (xy 108.169329 -114.73261) (xy 108.218929 -114.707109)
			(xy 108.271713 -114.689102) (xy 108.326556 -114.678972) (xy 108.38229 -114.676935) (xy 108.437727 -114.683035)
			(xy 108.491684 -114.697141) (xy 108.543013 -114.718953) (xy 108.590619 -114.748007) (xy 108.633487 -114.783682)
			(xy 108.670704 -114.825219) (xy 108.701477 -114.871732) (xy 108.725149 -114.922229) (xy 108.741217 -114.975636)
			(xy 108.743386 -114.990372) (xy 109.365032 -114.990372) (xy 109.369103 -114.93475) (xy 109.381229 -114.880313)
			(xy 109.401152 -114.828222) (xy 109.428448 -114.779587) (xy 109.462534 -114.735444) (xy 109.502683 -114.696735)
			(xy 109.548041 -114.664284) (xy 109.597641 -114.638783) (xy 109.650425 -114.620776) (xy 109.705268 -114.610646)
			(xy 109.761002 -114.608609) (xy 109.816439 -114.614709) (xy 109.870396 -114.628815) (xy 109.921725 -114.650627)
			(xy 109.969331 -114.679681) (xy 110.012199 -114.715356) (xy 110.049416 -114.756893) (xy 110.080189 -114.803406)
			(xy 110.103861 -114.853903) (xy 110.119929 -114.90731) (xy 110.127779 -114.960654) (xy 110.891826 -114.960654)
			(xy 110.895897 -114.905032) (xy 110.908023 -114.850595) (xy 110.927946 -114.798504) (xy 110.955242 -114.749869)
			(xy 110.989328 -114.705726) (xy 111.029477 -114.667017) (xy 111.074835 -114.634566) (xy 111.124435 -114.609065)
			(xy 111.177219 -114.591058) (xy 111.232062 -114.580928) (xy 111.287796 -114.578891) (xy 111.343233 -114.584991)
			(xy 111.39719 -114.599097) (xy 111.448519 -114.620909) (xy 111.496125 -114.649963) (xy 111.538993 -114.685638)
			(xy 111.57621 -114.727175) (xy 111.606983 -114.773688) (xy 111.630655 -114.824185) (xy 111.646723 -114.877592)
			(xy 111.654843 -114.932768) (xy 111.655352 -114.960654) (xy 111.654843 -114.98854) (xy 111.646723 -115.043716)
			(xy 111.630655 -115.097123) (xy 111.606983 -115.14762) (xy 111.57621 -115.194133) (xy 111.538993 -115.23567)
			(xy 111.496125 -115.271345) (xy 111.448519 -115.300399) (xy 111.39719 -115.322211) (xy 111.343233 -115.336317)
			(xy 111.287796 -115.342417) (xy 111.232062 -115.34038) (xy 111.177219 -115.33025) (xy 111.124435 -115.312243)
			(xy 111.074835 -115.286742) (xy 111.029477 -115.254291) (xy 110.989328 -115.215582) (xy 110.955242 -115.171439)
			(xy 110.927946 -115.122804) (xy 110.908023 -115.070713) (xy 110.895897 -115.016276) (xy 110.891826 -114.960654)
			(xy 110.127779 -114.960654) (xy 110.128049 -114.962486) (xy 110.128558 -114.990372) (xy 110.128049 -115.018258)
			(xy 110.119929 -115.073434) (xy 110.103861 -115.126841) (xy 110.080189 -115.177338) (xy 110.049416 -115.223851)
			(xy 110.012199 -115.265388) (xy 109.969331 -115.301063) (xy 109.921725 -115.330117) (xy 109.870396 -115.351929)
			(xy 109.816439 -115.366035) (xy 109.761002 -115.372135) (xy 109.705268 -115.370098) (xy 109.650425 -115.359968)
			(xy 109.597641 -115.341961) (xy 109.548041 -115.31646) (xy 109.502683 -115.284009) (xy 109.462534 -115.2453)
			(xy 109.428448 -115.201157) (xy 109.401152 -115.152522) (xy 109.381229 -115.100431) (xy 109.369103 -115.045994)
			(xy 109.365032 -114.990372) (xy 108.743386 -114.990372) (xy 108.749337 -115.030812) (xy 108.749846 -115.058698)
			(xy 108.749337 -115.086584) (xy 108.741217 -115.14176) (xy 108.725149 -115.195167) (xy 108.701477 -115.245664)
			(xy 108.670704 -115.292177) (xy 108.633487 -115.333714) (xy 108.590619 -115.369389) (xy 108.543013 -115.398443)
			(xy 108.491684 -115.420255) (xy 108.437727 -115.434361) (xy 108.38229 -115.440461) (xy 108.326556 -115.438424)
			(xy 108.271713 -115.428294) (xy 108.218929 -115.410287) (xy 108.169329 -115.384786) (xy 108.123971 -115.352335)
			(xy 108.083822 -115.313626) (xy 108.049736 -115.269483) (xy 108.02244 -115.220848) (xy 108.002517 -115.168757)
			(xy 107.990391 -115.11432) (xy 107.98632 -115.058698) (xy 107.379893 -115.058698) (xy 107.374697 -115.094008)
			(xy 107.358629 -115.147415) (xy 107.334957 -115.197912) (xy 107.304184 -115.244425) (xy 107.266967 -115.285962)
			(xy 107.224099 -115.321637) (xy 107.176493 -115.350691) (xy 107.125164 -115.372503) (xy 107.071207 -115.386609)
			(xy 107.01577 -115.392709) (xy 106.960036 -115.390672) (xy 106.905193 -115.380542) (xy 106.852409 -115.362535)
			(xy 106.802809 -115.337034) (xy 106.757451 -115.304583) (xy 106.717302 -115.265874) (xy 106.683216 -115.221731)
			(xy 106.65592 -115.173096) (xy 106.635997 -115.121005) (xy 106.623871 -115.066568) (xy 106.6198 -115.010946)
			(xy 100.857977 -115.010946) (xy 100.85878 -115.021609) (xy 100.854462 -115.078885) (xy 100.84161 -115.134866)
			(xy 100.820513 -115.18829) (xy 100.791648 -115.237948) (xy 100.755667 -115.282719) (xy 100.734876 -115.302538)
			(xy 100.727467 -115.310054) (xy 100.718944 -115.329338) (xy 100.718366 -115.339876) (xy 100.718366 -115.414552)
			(xy 100.718918 -115.425099) (xy 100.727438 -115.444394) (xy 100.734876 -115.45189) (xy 100.753915 -115.470062)
			(xy 100.787375 -115.510688) (xy 100.814936 -115.555524) (xy 100.825631 -115.579906) (xy 105.143044 -115.579906)
			(xy 105.147115 -115.524284) (xy 105.159241 -115.469847) (xy 105.179164 -115.417756) (xy 105.20646 -115.369121)
			(xy 105.240546 -115.324978) (xy 105.280695 -115.286269) (xy 105.326053 -115.253818) (xy 105.375653 -115.228317)
			(xy 105.428437 -115.21031) (xy 105.48328 -115.20018) (xy 105.539014 -115.198143) (xy 105.594451 -115.204243)
			(xy 105.648408 -115.218349) (xy 105.699737 -115.240161) (xy 105.747343 -115.269215) (xy 105.790211 -115.30489)
			(xy 105.827428 -115.346427) (xy 105.858201 -115.39294) (xy 105.881873 -115.443437) (xy 105.897941 -115.496844)
			(xy 105.906061 -115.55202) (xy 105.90657 -115.579906) (xy 105.906061 -115.607792) (xy 105.897941 -115.662968)
			(xy 105.881873 -115.716375) (xy 105.858201 -115.766872) (xy 105.827428 -115.813385) (xy 105.790211 -115.854922)
			(xy 105.747343 -115.890597) (xy 105.699737 -115.919651) (xy 105.648408 -115.941463) (xy 105.594451 -115.955569)
			(xy 105.539014 -115.961669) (xy 105.48328 -115.959632) (xy 105.428437 -115.949502) (xy 105.375653 -115.931495)
			(xy 105.326053 -115.905994) (xy 105.280695 -115.873543) (xy 105.240546 -115.834834) (xy 105.20646 -115.790691)
			(xy 105.179164 -115.742056) (xy 105.159241 -115.689965) (xy 105.147115 -115.635528) (xy 105.143044 -115.579906)
			(xy 100.825631 -115.579906) (xy 100.836078 -115.603722) (xy 100.850398 -115.654367) (xy 100.857626 -115.706499)
			(xy 100.858066 -115.732814) (xy 100.85758 -115.760065) (xy 100.849824 -115.814013) (xy 100.834469 -115.866308)
			(xy 100.811827 -115.915885) (xy 100.782361 -115.961735) (xy 100.74667 -116.002926) (xy 100.705479 -116.038617)
			(xy 100.659629 -116.068083) (xy 100.610052 -116.090725) (xy 100.557757 -116.10608) (xy 100.503809 -116.113836)
			(xy 100.449307 -116.113836) (xy 100.395359 -116.10608) (xy 100.343064 -116.090725) (xy 100.293487 -116.068083)
			(xy 100.247637 -116.038617) (xy 100.206446 -116.002926) (xy 100.170755 -115.961735) (xy 100.141289 -115.915885)
			(xy 100.118647 -115.866308) (xy 100.103292 -115.814013) (xy 100.095536 -115.760065) (xy 100.09505 -115.732814)
			(xy 100.095511 -115.7065) (xy 100.102745 -115.65437) (xy 100.117064 -115.603727) (xy 100.138198 -115.555527)
			(xy 100.165746 -115.510684) (xy 100.199187 -115.470046) (xy 100.21824 -115.45189) (xy 100.225639 -115.444366)
			(xy 100.234167 -115.425088) (xy 100.23475 -115.414552) (xy 100.23475 -115.339876) (xy 100.234178 -115.329332)
			(xy 100.225671 -115.310037) (xy 100.21824 -115.302538) (xy 100.197468 -115.282703) (xy 100.161497 -115.237931)
			(xy 100.13264 -115.188275) (xy 100.111549 -115.134856) (xy 100.0987 -115.078879) (xy 100.094384 -115.021609)
			(xy 98.320533 -115.021609) (xy 98.316216 -115.078882) (xy 98.303367 -115.134862) (xy 98.282274 -115.188284)
			(xy 98.253415 -115.237943) (xy 98.217441 -115.282717) (xy 98.196654 -115.302538) (xy 98.189242 -115.310051)
			(xy 98.180722 -115.329337) (xy 98.180144 -115.339876) (xy 98.180144 -115.414552) (xy 98.180673 -115.425102)
			(xy 98.189207 -115.444398) (xy 98.196654 -115.45189) (xy 98.215708 -115.470047) (xy 98.249163 -115.510678)
			(xy 98.276721 -115.555518) (xy 98.297859 -115.603718) (xy 98.312178 -115.654365) (xy 98.319404 -115.706498)
			(xy 98.319844 -115.732814) (xy 98.319358 -115.760065) (xy 98.311602 -115.814013) (xy 98.296247 -115.866308)
			(xy 98.273605 -115.915885) (xy 98.244139 -115.961735) (xy 98.208448 -116.002926) (xy 98.167257 -116.038617)
			(xy 98.121407 -116.068083) (xy 98.07183 -116.090725) (xy 98.019535 -116.10608) (xy 97.965587 -116.113836)
			(xy 97.911085 -116.113836) (xy 97.857137 -116.10608) (xy 97.804842 -116.090725) (xy 97.755265 -116.068083)
			(xy 97.709415 -116.038617) (xy 97.668224 -116.002926) (xy 97.632533 -115.961735) (xy 97.603067 -115.915885)
			(xy 97.580425 -115.866308) (xy 97.56507 -115.814013) (xy 97.557314 -115.760065) (xy 97.556828 -115.732814)
			(xy 97.557296 -115.7065) (xy 97.564529 -115.654371) (xy 97.578848 -115.603728) (xy 97.59998 -115.555529)
			(xy 97.627527 -115.510685) (xy 97.660966 -115.470046) (xy 97.680018 -115.45189) (xy 97.687429 -115.444376)
			(xy 97.695947 -115.42509) (xy 97.696528 -115.414552) (xy 97.696528 -115.339876) (xy 97.695963 -115.329331)
			(xy 97.687452 -115.310035) (xy 97.680018 -115.302538) (xy 97.659242 -115.282705) (xy 97.623264 -115.237936)
			(xy 97.594401 -115.18828) (xy 97.573305 -115.13486) (xy 97.560454 -115.078882) (xy 97.556137 -115.021609)
			(xy 95.609192 -115.021609) (xy 95.652492 -115.032929) (xy 95.703821 -115.054741) (xy 95.751427 -115.083795)
			(xy 95.794295 -115.11947) (xy 95.831512 -115.161007) (xy 95.862285 -115.20752) (xy 95.885957 -115.258017)
			(xy 95.902025 -115.311424) (xy 95.910145 -115.3666) (xy 95.910654 -115.394486) (xy 95.910145 -115.422372)
			(xy 95.902025 -115.477548) (xy 95.885957 -115.530955) (xy 95.862285 -115.581452) (xy 95.831512 -115.627965)
			(xy 95.794295 -115.669502) (xy 95.751427 -115.705177) (xy 95.703821 -115.734231) (xy 95.652492 -115.756043)
			(xy 95.598535 -115.770149) (xy 95.543098 -115.776249) (xy 95.487364 -115.774212) (xy 95.432521 -115.764082)
			(xy 95.379737 -115.746075) (xy 95.330137 -115.720574) (xy 95.284779 -115.688123) (xy 95.24463 -115.649414)
			(xy 95.210544 -115.605271) (xy 95.183248 -115.556636) (xy 95.163325 -115.504545) (xy 95.151199 -115.450108)
			(xy 95.147128 -115.394486) (xy 93.503709 -115.394486) (xy 93.500723 -115.414299) (xy 93.505254 -115.444375)
			(xy 93.518446 -115.47178) (xy 93.539126 -115.494083) (xy 93.55201 -115.502182) (xy 93.576453 -115.516949)
			(xy 93.621094 -115.552559) (xy 93.659931 -115.594422) (xy 93.692097 -115.641605) (xy 93.716874 -115.693053)
			(xy 93.733709 -115.747619) (xy 93.742226 -115.804084) (xy 93.742764 -115.832636) (xy 93.742278 -115.859887)
			(xy 93.734522 -115.913835) (xy 93.719167 -115.96613) (xy 93.696525 -116.015707) (xy 93.667059 -116.061557)
			(xy 93.631368 -116.102748) (xy 93.590177 -116.138439) (xy 93.544327 -116.167905) (xy 93.49475 -116.190547)
			(xy 93.442455 -116.205902) (xy 93.388507 -116.213658) (xy 93.334005 -116.213658) (xy 93.280057 -116.205902)
			(xy 93.227762 -116.190547) (xy 93.178185 -116.167905) (xy 93.132335 -116.138439) (xy 93.091144 -116.102748)
			(xy 93.055453 -116.061557) (xy 93.025987 -116.015707) (xy 93.003345 -115.96613) (xy 92.98799 -115.913835)
			(xy 92.980234 -115.859887) (xy 92.979748 -115.832636) (xy 72.441909 -115.832636) (xy 72.430069 -115.840245)
			(xy 72.380492 -115.862887) (xy 72.328197 -115.878242) (xy 72.274249 -115.885998) (xy 72.219747 -115.885998)
			(xy 72.165799 -115.878242) (xy 72.113504 -115.862887) (xy 72.063927 -115.840245) (xy 72.018077 -115.810779)
			(xy 71.976886 -115.775088) (xy 71.941195 -115.733897) (xy 71.911729 -115.688047) (xy 71.889087 -115.63847)
			(xy 71.873732 -115.586175) (xy 71.865976 -115.532227) (xy 71.86549 -115.504976) (xy 71.866085 -115.475286)
			(xy 71.875287 -115.416623) (xy 71.893465 -115.360094) (xy 71.920181 -115.307063) (xy 71.954788 -115.258811)
			(xy 71.975218 -115.23726) (xy 71.982584 -115.229894) (xy 71.98995 -115.211098) (xy 71.988172 -115.117372)
			(xy 71.97979 -115.098576) (xy 71.97217 -115.091718) (xy 71.953375 -115.073598) (xy 71.920398 -115.033124)
			(xy 71.893244 -114.988534) (xy 71.87242 -114.94066) (xy 71.858314 -114.890395) (xy 71.851189 -114.838676)
			(xy 71.850758 -114.812572) (xy 68.004014 -114.812572) (xy 67.9958 -114.82926) (xy 67.96249 -114.876942)
			(xy 67.922329 -114.919016) (xy 67.876248 -114.954507) (xy 67.825314 -114.982593) (xy 67.770707 -115.002623)
			(xy 67.742308 -115.008914) (xy 67.742054 -115.008914) (xy 67.731331 -115.0117) (xy 67.713544 -115.024863)
			(xy 67.707764 -115.034314) (xy 67.664838 -115.113054) (xy 67.663314 -115.135152) (xy 67.667632 -115.14582)
			(xy 67.676059 -115.168181) (xy 67.687917 -115.214472) (xy 67.693913 -115.261881) (xy 67.694302 -115.285774)
			(xy 67.693816 -115.313025) (xy 67.68606 -115.366973) (xy 67.670705 -115.419268) (xy 67.648063 -115.468845)
			(xy 67.618597 -115.514695) (xy 67.582906 -115.555886) (xy 67.541715 -115.591577) (xy 67.495865 -115.621043)
			(xy 67.446288 -115.643685) (xy 67.393993 -115.65904) (xy 67.340045 -115.666796) (xy 67.285543 -115.666796)
			(xy 67.231595 -115.65904) (xy 67.1793 -115.643685) (xy 67.129723 -115.621043) (xy 67.083873 -115.591577)
			(xy 67.042682 -115.555886) (xy 67.006991 -115.514695) (xy 66.977525 -115.468845) (xy 66.954883 -115.419268)
			(xy 66.939528 -115.366973) (xy 66.931772 -115.313025) (xy 66.931286 -115.285774) (xy 56.476007 -115.285774)
			(xy 56.494399 -115.30108) (xy 56.531616 -115.342617) (xy 56.562389 -115.38913) (xy 56.586061 -115.439627)
			(xy 56.602129 -115.493034) (xy 56.610249 -115.54821) (xy 56.610758 -115.576096) (xy 56.610249 -115.603982)
			(xy 56.602129 -115.659158) (xy 56.586061 -115.712565) (xy 56.562389 -115.763062) (xy 56.531616 -115.809575)
			(xy 56.494399 -115.851112) (xy 56.451531 -115.886787) (xy 56.403925 -115.915841) (xy 56.389328 -115.922044)
			(xy 63.203326 -115.922044) (xy 63.207397 -115.866422) (xy 63.219523 -115.811985) (xy 63.239446 -115.759894)
			(xy 63.266742 -115.711259) (xy 63.300828 -115.667116) (xy 63.340977 -115.628407) (xy 63.386335 -115.595956)
			(xy 63.435935 -115.570455) (xy 63.488719 -115.552448) (xy 63.543562 -115.542318) (xy 63.599296 -115.540281)
			(xy 63.654733 -115.546381) (xy 63.70869 -115.560487) (xy 63.760019 -115.582299) (xy 63.807625 -115.611353)
			(xy 63.850493 -115.647028) (xy 63.88771 -115.688565) (xy 63.918483 -115.735078) (xy 63.942155 -115.785575)
			(xy 63.958223 -115.838982) (xy 63.966343 -115.894158) (xy 63.966852 -115.922044) (xy 63.966343 -115.94993)
			(xy 63.958223 -116.005106) (xy 63.942155 -116.058513) (xy 63.918483 -116.10901) (xy 63.88771 -116.155523)
			(xy 63.850493 -116.19706) (xy 63.807625 -116.232735) (xy 63.760019 -116.261789) (xy 63.70869 -116.283601)
			(xy 63.654733 -116.297707) (xy 63.599296 -116.303807) (xy 63.543562 -116.30177) (xy 63.488719 -116.29164)
			(xy 63.435935 -116.273633) (xy 63.386335 -116.248132) (xy 63.340977 -116.215681) (xy 63.300828 -116.176972)
			(xy 63.266742 -116.132829) (xy 63.239446 -116.084194) (xy 63.219523 -116.032103) (xy 63.207397 -115.977666)
			(xy 63.203326 -115.922044) (xy 56.389328 -115.922044) (xy 56.352596 -115.937653) (xy 56.298639 -115.951759)
			(xy 56.243202 -115.957859) (xy 56.187468 -115.955822) (xy 56.132625 -115.945692) (xy 56.079841 -115.927685)
			(xy 56.030241 -115.902184) (xy 55.984883 -115.869733) (xy 55.944734 -115.831024) (xy 55.910648 -115.786881)
			(xy 55.883352 -115.738246) (xy 55.863429 -115.686155) (xy 55.851303 -115.631718) (xy 55.847232 -115.576096)
			(xy 52.455193 -115.576096) (xy 52.462182 -115.651518) (xy 52.462684 -115.694968) (xy 52.462182 -115.738418)
			(xy 52.454164 -115.824947) (xy 52.438196 -115.910367) (xy 52.414415 -115.993949) (xy 52.383023 -116.074981)
			(xy 52.344289 -116.15277) (xy 52.298542 -116.226654) (xy 52.246173 -116.296001) (xy 52.187629 -116.360221)
			(xy 52.123409 -116.418765) (xy 52.085265 -116.44757) (xy 66.157092 -116.44757) (xy 66.161163 -116.391948)
			(xy 66.173289 -116.337511) (xy 66.193212 -116.28542) (xy 66.220508 -116.236785) (xy 66.254594 -116.192642)
			(xy 66.294743 -116.153933) (xy 66.340101 -116.121482) (xy 66.389701 -116.095981) (xy 66.442485 -116.077974)
			(xy 66.497328 -116.067844) (xy 66.553062 -116.065807) (xy 66.608499 -116.071907) (xy 66.662456 -116.086013)
			(xy 66.713785 -116.107825) (xy 66.761391 -116.136879) (xy 66.804259 -116.172554) (xy 66.841476 -116.214091)
			(xy 66.872249 -116.260604) (xy 66.895921 -116.311101) (xy 66.911989 -116.364508) (xy 66.920109 -116.419684)
			(xy 66.920391 -116.435124) (xy 67.284852 -116.435124) (xy 67.288923 -116.379502) (xy 67.301049 -116.325065)
			(xy 67.320972 -116.272974) (xy 67.348268 -116.224339) (xy 67.382354 -116.180196) (xy 67.422503 -116.141487)
			(xy 67.467861 -116.109036) (xy 67.517461 -116.083535) (xy 67.570245 -116.065528) (xy 67.625088 -116.055398)
			(xy 67.680822 -116.053361) (xy 67.736259 -116.059461) (xy 67.790216 -116.073567) (xy 67.841545 -116.095379)
			(xy 67.889151 -116.124433) (xy 67.932019 -116.160108) (xy 67.969236 -116.201645) (xy 68.000009 -116.248158)
			(xy 68.023681 -116.298655) (xy 68.039749 -116.352062) (xy 68.047869 -116.407238) (xy 68.048378 -116.435124)
			(xy 68.047869 -116.46301) (xy 68.041755 -116.504555) (xy 71.305343 -116.504555) (xy 71.305343 -116.450045)
			(xy 71.313101 -116.396091) (xy 71.328458 -116.34379) (xy 71.351103 -116.294207) (xy 71.380574 -116.248351)
			(xy 71.416271 -116.207157) (xy 71.457467 -116.171462) (xy 71.503324 -116.141993) (xy 71.552909 -116.119351)
			(xy 71.60521 -116.103996) (xy 71.659165 -116.096242) (xy 71.68642 -116.09578) (xy 71.714492 -116.096226)
			(xy 71.770028 -116.104478) (xy 71.823756 -116.120773) (xy 71.874519 -116.14476) (xy 71.921224 -116.17592)
			(xy 71.962862 -116.213583) (xy 71.998537 -116.256937) (xy 72.02748 -116.305047) (xy 72.049067 -116.356876)
			(xy 72.062833 -116.411308) (xy 72.06615 -116.439188) (xy 72.067992 -116.453154) (xy 72.078338 -116.479344)
			(xy 72.095447 -116.501711) (xy 72.118015 -116.518552) (xy 72.144326 -116.528587) (xy 72.172378 -116.531051)
			(xy 72.186292 -116.52885) (xy 72.204092 -116.525659) (xy 72.240092 -116.52222) (xy 72.258174 -116.521992)
			(xy 72.258428 -116.521992) (xy 72.285678 -116.52248) (xy 72.339623 -116.530239) (xy 72.391914 -116.545597)
			(xy 72.441488 -116.56824) (xy 72.487335 -116.597707) (xy 72.528522 -116.633398) (xy 72.56421 -116.674588)
			(xy 72.593674 -116.720437) (xy 72.616313 -116.770012) (xy 72.631667 -116.822305) (xy 72.639422 -116.87625)
			(xy 72.639422 -116.93075) (xy 72.631667 -116.984695) (xy 72.616313 -117.036988) (xy 72.593674 -117.086563)
			(xy 72.56421 -117.132412) (xy 72.528522 -117.173602) (xy 72.487335 -117.209293) (xy 72.441488 -117.23876)
			(xy 72.391914 -117.261403) (xy 72.339623 -117.276761) (xy 72.285678 -117.28452) (xy 72.258428 -117.285008)
			(xy 72.230357 -117.284529) (xy 72.174822 -117.276283) (xy 72.121094 -117.259993) (xy 72.07033 -117.236012)
			(xy 72.023625 -117.204855) (xy 71.981986 -117.167196) (xy 71.94631 -117.123845) (xy 71.917366 -117.075737)
			(xy 71.89578 -117.023909) (xy 71.882015 -116.969479) (xy 71.878698 -116.9416) (xy 71.87681 -116.927643)
			(xy 71.866468 -116.901461) (xy 71.849367 -116.879099) (xy 71.826809 -116.862258) (xy 71.800509 -116.852218)
			(xy 71.772467 -116.849744) (xy 71.758556 -116.851938) (xy 71.740758 -116.855136) (xy 71.704756 -116.858571)
			(xy 71.686674 -116.858796) (xy 71.68642 -116.858796) (xy 71.659165 -116.858358) (xy 71.60521 -116.850604)
			(xy 71.552909 -116.835249) (xy 71.503324 -116.812607) (xy 71.457467 -116.783138) (xy 71.416271 -116.747443)
			(xy 71.380574 -116.706249) (xy 71.351103 -116.660393) (xy 71.328458 -116.61081) (xy 71.313101 -116.558509)
			(xy 71.305343 -116.504555) (xy 68.041755 -116.504555) (xy 68.039749 -116.518186) (xy 68.023681 -116.571593)
			(xy 68.000009 -116.62209) (xy 67.969236 -116.668603) (xy 67.932019 -116.71014) (xy 67.889151 -116.745815)
			(xy 67.841545 -116.774869) (xy 67.790216 -116.796681) (xy 67.736259 -116.810787) (xy 67.680822 -116.816887)
			(xy 67.625088 -116.81485) (xy 67.570245 -116.80472) (xy 67.517461 -116.786713) (xy 67.467861 -116.761212)
			(xy 67.422503 -116.728761) (xy 67.382354 -116.690052) (xy 67.348268 -116.645909) (xy 67.320972 -116.597274)
			(xy 67.301049 -116.545183) (xy 67.288923 -116.490746) (xy 67.284852 -116.435124) (xy 66.920391 -116.435124)
			(xy 66.920618 -116.44757) (xy 66.920109 -116.475456) (xy 66.911989 -116.530632) (xy 66.895921 -116.584039)
			(xy 66.872249 -116.634536) (xy 66.841476 -116.681049) (xy 66.804259 -116.722586) (xy 66.761391 -116.758261)
			(xy 66.713785 -116.787315) (xy 66.662456 -116.809127) (xy 66.608499 -116.823233) (xy 66.553062 -116.829333)
			(xy 66.497328 -116.827296) (xy 66.442485 -116.817166) (xy 66.389701 -116.799159) (xy 66.340101 -116.773658)
			(xy 66.294743 -116.741207) (xy 66.254594 -116.702498) (xy 66.220508 -116.658355) (xy 66.193212 -116.60972)
			(xy 66.173289 -116.557629) (xy 66.161163 -116.503192) (xy 66.157092 -116.44757) (xy 52.085265 -116.44757)
			(xy 52.054062 -116.471134) (xy 51.980178 -116.516881) (xy 51.902389 -116.555615) (xy 51.821357 -116.587007)
			(xy 51.737775 -116.610788) (xy 51.652355 -116.626756) (xy 51.565826 -116.634774) (xy 51.478926 -116.634774)
			(xy 51.392397 -116.626756) (xy 51.306977 -116.610788) (xy 51.223395 -116.587007) (xy 51.142363 -116.555615)
			(xy 51.064574 -116.516881) (xy 50.99069 -116.471134) (xy 50.921343 -116.418765) (xy 50.857123 -116.360221)
			(xy 50.798579 -116.296001) (xy 50.74621 -116.226654) (xy 50.700463 -116.15277) (xy 50.661729 -116.074981)
			(xy 50.630337 -115.993949) (xy 50.606556 -115.910367) (xy 50.590588 -115.824947) (xy 50.58257 -115.738418)
			(xy 50.209454 -115.738418) (xy 50.209454 -115.73842) (xy 50.201436 -115.824949) (xy 50.185468 -115.910369)
			(xy 50.161687 -115.993951) (xy 50.130295 -116.074982) (xy 50.091561 -116.152771) (xy 50.045814 -116.226655)
			(xy 49.993446 -116.296002) (xy 49.934902 -116.360222) (xy 49.870682 -116.418766) (xy 49.801335 -116.471134)
			(xy 49.727451 -116.516881) (xy 49.649662 -116.555615) (xy 49.568631 -116.587007) (xy 49.485049 -116.610788)
			(xy 49.399629 -116.626756) (xy 49.3131 -116.634774) (xy 49.26965 -116.635276) (xy 47.41545 -116.635276)
			(xy 47.372 -116.634778) (xy 47.285471 -116.62676) (xy 47.200051 -116.610792) (xy 47.116468 -116.587011)
			(xy 47.035436 -116.555619) (xy 46.957647 -116.516884) (xy 46.883763 -116.471138) (xy 46.814415 -116.418769)
			(xy 46.750195 -116.360225) (xy 46.691651 -116.296005) (xy 46.639282 -116.226657) (xy 46.593536 -116.152773)
			(xy 46.554801 -116.074984) (xy 46.523409 -115.993952) (xy 46.499628 -115.910369) (xy 46.48366 -115.824949)
			(xy 46.475642 -115.73842) (xy 45.092372 -115.73842) (xy 45.084354 -115.824947) (xy 45.068386 -115.910367)
			(xy 45.044605 -115.993949) (xy 45.013213 -116.074981) (xy 44.974479 -116.15277) (xy 44.928732 -116.226654)
			(xy 44.876363 -116.296001) (xy 44.817819 -116.360221) (xy 44.753599 -116.418765) (xy 44.684252 -116.471134)
			(xy 44.610368 -116.516881) (xy 44.532579 -116.555615) (xy 44.451547 -116.587007) (xy 44.367965 -116.610788)
			(xy 44.282545 -116.626756) (xy 44.196016 -116.634774) (xy 44.109116 -116.634774) (xy 44.022587 -116.626756)
			(xy 43.937167 -116.610788) (xy 43.853585 -116.587007) (xy 43.772553 -116.555615) (xy 43.694764 -116.516881)
			(xy 43.62088 -116.471134) (xy 43.551533 -116.418765) (xy 43.487313 -116.360221) (xy 43.428769 -116.296001)
			(xy 43.3764 -116.226654) (xy 43.330653 -116.15277) (xy 43.291919 -116.074981) (xy 43.260527 -115.993949)
			(xy 43.236746 -115.910367) (xy 43.220778 -115.824947) (xy 43.21276 -115.738418) (xy 38.20665 -115.738418)
			(xy 38.209022 -115.752353) (xy 38.212073 -115.786187) (xy 38.212268 -115.803172) (xy 38.212268 -115.803934)
			(xy 38.211754 -115.830915) (xy 38.204134 -115.884336) (xy 38.189064 -115.936152) (xy 38.166846 -115.985327)
			(xy 38.137922 -116.030883) (xy 38.102869 -116.07191) (xy 38.062387 -116.10759) (xy 38.017282 -116.137212)
			(xy 37.993066 -116.14912) (xy 37.982906 -116.153946) (xy 37.968682 -116.17071) (xy 37.942266 -116.267484)
			(xy 37.945822 -116.28882) (xy 37.952172 -116.297964) (xy 37.952172 -116.298218) (xy 37.967757 -116.322053)
			(xy 37.992408 -116.373387) (xy 38.009167 -116.427812) (xy 38.017664 -116.484121) (xy 38.018212 -116.512594)
			(xy 38.017739 -116.539847) (xy 38.009983 -116.593797) (xy 37.994628 -116.646094) (xy 37.971986 -116.695674)
			(xy 37.942519 -116.741527) (xy 37.906827 -116.78272) (xy 37.865635 -116.818413) (xy 37.819783 -116.847882)
			(xy 37.770204 -116.870524) (xy 37.717907 -116.885881) (xy 37.663957 -116.893638) (xy 37.636704 -116.894102)
			(xy 37.61039 -116.893631) (xy 37.558262 -116.886397) (xy 37.507619 -116.872079) (xy 37.45942 -116.850947)
			(xy 37.414577 -116.823401) (xy 37.373937 -116.789963) (xy 37.35578 -116.770912) (xy 37.348266 -116.763501)
			(xy 37.32898 -116.754982) (xy 37.318442 -116.754402) (xy 37.243766 -116.754402) (xy 37.233219 -116.754953)
			(xy 37.213923 -116.763473) (xy 37.206428 -116.770912) (xy 37.188254 -116.789949) (xy 37.147628 -116.823408)
			(xy 37.102792 -116.850969) (xy 37.054594 -116.87211) (xy 37.00395 -116.886431) (xy 36.951819 -116.893661)
			(xy 36.925504 -116.894102) (xy 36.898251 -116.893651) (xy 36.844298 -116.885894) (xy 36.791999 -116.870538)
			(xy 36.742418 -116.847896) (xy 36.696563 -116.818427) (xy 36.65537 -116.782733) (xy 36.619675 -116.74154)
			(xy 36.590206 -116.695686) (xy 36.567563 -116.646105) (xy 36.552207 -116.593806) (xy 36.544449 -116.539853)
			(xy 19.018865 -116.539853) (xy 19.037293 -116.56853) (xy 19.059933 -116.618109) (xy 19.075287 -116.670406)
			(xy 19.083043 -116.724356) (xy 19.083528 -116.751608) (xy 19.083084 -116.778979) (xy 19.075264 -116.83316)
			(xy 19.05977 -116.885664) (xy 19.036923 -116.935411) (xy 19.007192 -116.981376) (xy 18.989548 -117.002306)
			(xy 18.989294 -117.00256) (xy 18.983717 -117.009653) (xy 18.977465 -117.026565) (xy 18.977102 -117.03558)
			(xy 18.977102 -117.102636) (xy 18.977442 -117.111655) (xy 18.983701 -117.128571) (xy 18.989294 -117.135656)
			(xy 18.989548 -117.135656) (xy 18.989548 -117.13591) (xy 19.007198 -117.156836) (xy 19.036924 -117.202804)
			(xy 19.05977 -117.252551) (xy 19.075267 -117.305055) (xy 19.083095 -117.359235) (xy 19.083095 -117.413977)
			(xy 19.075265 -117.468157) (xy 19.059766 -117.52066) (xy 19.036918 -117.570406) (xy 19.00719 -117.616374)
			(xy 18.989548 -117.637306) (xy 18.989294 -117.63756) (xy 18.983717 -117.644653) (xy 18.977465 -117.661565)
			(xy 18.977102 -117.67058) (xy 18.977102 -117.737636) (xy 18.977442 -117.746655) (xy 18.980308 -117.7544)
			(xy 37.088062 -117.7544) (xy 37.092133 -117.698778) (xy 37.104259 -117.644341) (xy 37.124182 -117.59225)
			(xy 37.151478 -117.543615) (xy 37.185564 -117.499472) (xy 37.225713 -117.460763) (xy 37.271071 -117.428312)
			(xy 37.320671 -117.402811) (xy 37.373455 -117.384804) (xy 37.428298 -117.374674) (xy 37.484032 -117.372637)
			(xy 37.539469 -117.378737) (xy 37.593426 -117.392843) (xy 37.644755 -117.414655) (xy 37.692361 -117.443709)
			(xy 37.735229 -117.479384) (xy 37.772446 -117.520921) (xy 37.803219 -117.567434) (xy 37.826891 -117.617931)
			(xy 37.842959 -117.671338) (xy 37.851079 -117.726514) (xy 37.851588 -117.7544) (xy 37.851079 -117.782286)
			(xy 37.842959 -117.837462) (xy 37.826891 -117.890869) (xy 37.803219 -117.941366) (xy 37.772446 -117.987879)
			(xy 37.735229 -118.029416) (xy 37.692361 -118.065091) (xy 37.644755 -118.094145) (xy 37.593426 -118.115957)
			(xy 37.539469 -118.130063) (xy 37.484032 -118.136163) (xy 37.428298 -118.134126) (xy 37.373455 -118.123996)
			(xy 37.320671 -118.105989) (xy 37.271071 -118.080488) (xy 37.225713 -118.048037) (xy 37.185564 -118.009328)
			(xy 37.151478 -117.965185) (xy 37.124182 -117.91655) (xy 37.104259 -117.864459) (xy 37.092133 -117.810022)
			(xy 37.088062 -117.7544) (xy 18.980308 -117.7544) (xy 18.983701 -117.763571) (xy 18.989294 -117.770656)
			(xy 18.989548 -117.770656) (xy 18.989548 -117.77091) (xy 19.007197 -117.791834) (xy 19.036909 -117.837808)
			(xy 19.059744 -117.887558) (xy 19.075233 -117.94006) (xy 19.083057 -117.994238) (xy 19.083528 -118.021608)
			(xy 19.08303 -118.048859) (xy 19.075273 -118.102805) (xy 19.059918 -118.155098) (xy 19.037277 -118.204674)
			(xy 19.007812 -118.250523) (xy 18.992679 -118.267988) (xy 55.586628 -118.267988) (xy 55.590699 -118.212366)
			(xy 55.602825 -118.157929) (xy 55.622748 -118.105838) (xy 55.650044 -118.057203) (xy 55.68413 -118.01306)
			(xy 55.724279 -117.974351) (xy 55.769637 -117.9419) (xy 55.819237 -117.916399) (xy 55.872021 -117.898392)
			(xy 55.926864 -117.888262) (xy 55.982598 -117.886225) (xy 56.038035 -117.892325) (xy 56.091992 -117.906431)
			(xy 56.143321 -117.928243) (xy 56.190927 -117.957297) (xy 56.233795 -117.992972) (xy 56.271012 -118.034509)
			(xy 56.301785 -118.081022) (xy 56.325457 -118.131519) (xy 56.341525 -118.184926) (xy 56.349645 -118.240102)
			(xy 56.350154 -118.267988) (xy 56.349645 -118.295874) (xy 56.344329 -118.331996) (xy 62.895732 -118.331996)
			(xy 62.899803 -118.276374) (xy 62.911929 -118.221937) (xy 62.931852 -118.169846) (xy 62.959148 -118.121211)
			(xy 62.993234 -118.077068) (xy 63.033383 -118.038359) (xy 63.078741 -118.005908) (xy 63.128341 -117.980407)
			(xy 63.181125 -117.9624) (xy 63.235968 -117.95227) (xy 63.291702 -117.950233) (xy 63.347139 -117.956333)
			(xy 63.401096 -117.970439) (xy 63.452425 -117.992251) (xy 63.500031 -118.021305) (xy 63.542899 -118.05698)
			(xy 63.580116 -118.098517) (xy 63.610889 -118.14503) (xy 63.634561 -118.195527) (xy 63.650629 -118.248934)
			(xy 63.658749 -118.30411) (xy 63.659258 -118.331996) (xy 63.658749 -118.359882) (xy 63.650629 -118.415058)
			(xy 63.634561 -118.468465) (xy 63.610889 -118.518962) (xy 63.580116 -118.565475) (xy 63.542899 -118.607012)
			(xy 63.500031 -118.642687) (xy 63.452425 -118.671741) (xy 63.401096 -118.693553) (xy 63.347139 -118.707659)
			(xy 63.291702 -118.713759) (xy 63.235968 -118.711722) (xy 63.181125 -118.701592) (xy 63.128341 -118.683585)
			(xy 63.078741 -118.658084) (xy 63.033383 -118.625633) (xy 62.993234 -118.586924) (xy 62.959148 -118.542781)
			(xy 62.931852 -118.494146) (xy 62.911929 -118.442055) (xy 62.899803 -118.387618) (xy 62.895732 -118.331996)
			(xy 56.344329 -118.331996) (xy 56.341525 -118.35105) (xy 56.325457 -118.404457) (xy 56.301785 -118.454954)
			(xy 56.271012 -118.501467) (xy 56.233795 -118.543004) (xy 56.190927 -118.578679) (xy 56.143321 -118.607733)
			(xy 56.091992 -118.629545) (xy 56.038035 -118.643651) (xy 55.982598 -118.649751) (xy 55.926864 -118.647714)
			(xy 55.872021 -118.637584) (xy 55.819237 -118.619577) (xy 55.769637 -118.594076) (xy 55.724279 -118.561625)
			(xy 55.68413 -118.522916) (xy 55.650044 -118.478773) (xy 55.622748 -118.430138) (xy 55.602825 -118.378047)
			(xy 55.590699 -118.32361) (xy 55.586628 -118.267988) (xy 18.992679 -118.267988) (xy 18.972122 -118.291713)
			(xy 18.930933 -118.327404) (xy 18.885085 -118.356871) (xy 18.835509 -118.379513) (xy 18.783217 -118.39487)
			(xy 18.729271 -118.402629) (xy 18.70202 -118.403116) (xy 18.674649 -118.402659) (xy 18.620469 -118.394842)
			(xy 18.567965 -118.379352) (xy 18.518218 -118.356508) (xy 18.472252 -118.326779) (xy 18.451322 -118.309136)
			(xy 18.451068 -118.308882) (xy 18.443968 -118.303316) (xy 18.427061 -118.297057) (xy 18.418048 -118.29669)
			(xy 18.350992 -118.29669) (xy 18.341975 -118.297045) (xy 18.325058 -118.303294) (xy 18.317972 -118.308882)
			(xy 18.317972 -118.309136) (xy 18.317718 -118.309136) (xy 18.296795 -118.326786) (xy 18.250819 -118.356495)
			(xy 18.201069 -118.379328) (xy 18.148567 -118.394817) (xy 18.09439 -118.402643) (xy 18.06702 -118.403116)
			(xy 18.039768 -118.402626) (xy 17.985818 -118.394872) (xy 17.933522 -118.379519) (xy 17.883942 -118.356879)
			(xy 17.838089 -118.327414) (xy 17.796897 -118.291723) (xy 17.761203 -118.250533) (xy 17.731734 -118.204683)
			(xy 17.709091 -118.155105) (xy 17.693734 -118.102809) (xy 17.685976 -118.04886) (xy 17.685512 -118.021608)
			(xy 17.567078 -118.021608) (xy 17.569179 -118.035886) (xy 17.569688 -118.063772) (xy 17.569179 -118.091658)
			(xy 17.561059 -118.146834) (xy 17.544991 -118.200241) (xy 17.521319 -118.250738) (xy 17.490546 -118.297251)
			(xy 17.453329 -118.338788) (xy 17.410461 -118.374463) (xy 17.362855 -118.403517) (xy 17.311526 -118.425329)
			(xy 17.257569 -118.439435) (xy 17.202132 -118.445535) (xy 17.146398 -118.443498) (xy 17.091555 -118.433368)
			(xy 17.038771 -118.415361) (xy 16.989171 -118.38986) (xy 16.943813 -118.357409) (xy 16.903664 -118.3187)
			(xy 16.869578 -118.274557) (xy 16.842282 -118.225922) (xy 16.822359 -118.173831) (xy 16.810233 -118.119394)
			(xy 16.806162 -118.063772) (xy 15.167063 -118.063772) (xy 15.1699 -118.082859) (xy 15.170404 -118.111016)
			(xy 15.169918 -118.138267) (xy 15.162162 -118.192215) (xy 15.146807 -118.24451) (xy 15.124165 -118.294087)
			(xy 15.094699 -118.339937) (xy 15.059008 -118.381128) (xy 15.017817 -118.416819) (xy 14.971967 -118.446285)
			(xy 14.92239 -118.468927) (xy 14.870095 -118.484282) (xy 14.816147 -118.492038) (xy 14.761645 -118.492038)
			(xy 14.707697 -118.484282) (xy 14.655402 -118.468927) (xy 14.605825 -118.446285) (xy 14.559975 -118.416819)
			(xy 14.518784 -118.381128) (xy 14.483093 -118.339937) (xy 14.453627 -118.294087) (xy 14.430985 -118.24451)
			(xy 14.41563 -118.192215) (xy 14.407874 -118.138267) (xy 14.407388 -118.111016) (xy 14.407851 -118.08446)
			(xy 14.415217 -118.031861) (xy 14.429807 -117.980792) (xy 14.440154 -117.95633) (xy 14.444483 -117.944956)
			(xy 14.443146 -117.920689) (xy 14.437614 -117.909848) (xy 14.396212 -117.838728) (xy 14.389488 -117.828651)
			(xy 14.369072 -117.815667) (xy 14.357096 -117.813836) (xy 14.32762 -117.810473) (xy 14.270151 -117.79575)
			(xy 14.215655 -117.772305) (xy 14.165446 -117.740706) (xy 14.14272 -117.721634) (xy 14.142466 -117.72138)
			(xy 14.135366 -117.715813) (xy 14.11846 -117.709555) (xy 14.109446 -117.709188) (xy 14.04239 -117.709188)
			(xy 14.033373 -117.709543) (xy 14.016456 -117.715792) (xy 14.00937 -117.72138) (xy 14.00937 -117.721634)
			(xy 14.009116 -117.721634) (xy 13.988193 -117.739284) (xy 13.942217 -117.768993) (xy 13.892467 -117.791827)
			(xy 13.839965 -117.807315) (xy 13.785788 -117.815141) (xy 13.758418 -117.815614) (xy 13.731166 -117.815128)
			(xy 13.677216 -117.807374) (xy 13.624919 -117.79202) (xy 13.575339 -117.76938) (xy 13.529486 -117.739915)
			(xy 13.488294 -117.704223) (xy 13.4526 -117.663033) (xy 13.423131 -117.617182) (xy 13.400488 -117.567604)
			(xy 13.385132 -117.515307) (xy 13.377374 -117.461358) (xy 13.37691 -117.434106) (xy 5.06984 -117.434106)
			(xy 5.06984 -118.089426) (xy 10.195304 -118.089426) (xy 10.199375 -118.033804) (xy 10.211501 -117.979367)
			(xy 10.231424 -117.927276) (xy 10.25872 -117.878641) (xy 10.292806 -117.834498) (xy 10.332955 -117.795789)
			(xy 10.378313 -117.763338) (xy 10.427913 -117.737837) (xy 10.480697 -117.71983) (xy 10.53554 -117.7097)
			(xy 10.591274 -117.707663) (xy 10.646711 -117.713763) (xy 10.700668 -117.727869) (xy 10.751997 -117.749681)
			(xy 10.799603 -117.778735) (xy 10.842471 -117.81441) (xy 10.879688 -117.855947) (xy 10.910461 -117.90246)
			(xy 10.934133 -117.952957) (xy 10.936982 -117.962426) (xy 12.227304 -117.962426) (xy 12.231375 -117.906804)
			(xy 12.243501 -117.852367) (xy 12.263424 -117.800276) (xy 12.29072 -117.751641) (xy 12.324806 -117.707498)
			(xy 12.364955 -117.668789) (xy 12.410313 -117.636338) (xy 12.459913 -117.610837) (xy 12.512697 -117.59283)
			(xy 12.56754 -117.5827) (xy 12.623274 -117.580663) (xy 12.678711 -117.586763) (xy 12.732668 -117.600869)
			(xy 12.783997 -117.622681) (xy 12.831603 -117.651735) (xy 12.874471 -117.68741) (xy 12.911688 -117.728947)
			(xy 12.942461 -117.77546) (xy 12.966133 -117.825957) (xy 12.982201 -117.879364) (xy 12.990321 -117.93454)
			(xy 12.99083 -117.962426) (xy 12.990321 -117.990312) (xy 12.982201 -118.045488) (xy 12.966133 -118.098895)
			(xy 12.942461 -118.149392) (xy 12.911688 -118.195905) (xy 12.874471 -118.237442) (xy 12.831603 -118.273117)
			(xy 12.783997 -118.302171) (xy 12.732668 -118.323983) (xy 12.678711 -118.338089) (xy 12.623274 -118.344189)
			(xy 12.56754 -118.342152) (xy 12.512697 -118.332022) (xy 12.459913 -118.314015) (xy 12.410313 -118.288514)
			(xy 12.364955 -118.256063) (xy 12.324806 -118.217354) (xy 12.29072 -118.173211) (xy 12.263424 -118.124576)
			(xy 12.243501 -118.072485) (xy 12.231375 -118.018048) (xy 12.227304 -117.962426) (xy 10.936982 -117.962426)
			(xy 10.950201 -118.006364) (xy 10.958321 -118.06154) (xy 10.95883 -118.089426) (xy 10.958321 -118.117312)
			(xy 10.950201 -118.172488) (xy 10.934133 -118.225895) (xy 10.910461 -118.276392) (xy 10.879688 -118.322905)
			(xy 10.842471 -118.364442) (xy 10.799603 -118.400117) (xy 10.751997 -118.429171) (xy 10.700668 -118.450983)
			(xy 10.646711 -118.465089) (xy 10.591274 -118.471189) (xy 10.53554 -118.469152) (xy 10.480697 -118.459022)
			(xy 10.427913 -118.441015) (xy 10.378313 -118.415514) (xy 10.332955 -118.383063) (xy 10.292806 -118.344354)
			(xy 10.25872 -118.300211) (xy 10.231424 -118.251576) (xy 10.211501 -118.199485) (xy 10.199375 -118.145048)
			(xy 10.195304 -118.089426) (xy 5.06984 -118.089426) (xy 5.06984 -119.053951) (xy 34.110664 -119.053951)
			(xy 34.110664 -118.999449) (xy 34.11842 -118.945501) (xy 34.133774 -118.893206) (xy 34.156415 -118.843629)
			(xy 34.18588 -118.797778) (xy 34.22157 -118.756587) (xy 34.262759 -118.720894) (xy 34.308608 -118.691426)
			(xy 34.358184 -118.668783) (xy 34.410478 -118.653425) (xy 34.464425 -118.645665) (xy 34.491676 -118.645178)
			(xy 34.517584 -118.64562) (xy 34.568921 -118.652653) (xy 34.618835 -118.666565) (xy 34.666408 -118.687102)
			(xy 34.710766 -118.713886) (xy 34.751092 -118.746424) (xy 34.786647 -118.784117) (xy 34.802064 -118.804944)
			(xy 34.807815 -118.812265) (xy 34.82331 -118.822557) (xy 34.83229 -118.82501) (xy 34.86277 -118.831868)
			(xy 34.872044 -118.833635) (xy 34.890711 -118.830883) (xy 34.899092 -118.826534) (xy 34.925073 -118.812248)
			(xy 34.979923 -118.789734) (xy 35.037224 -118.774505) (xy 35.096015 -118.766817) (xy 35.12566 -118.766336)
			(xy 35.155302 -118.766845) (xy 35.214084 -118.774564) (xy 35.271382 -118.789787) (xy 35.326243 -118.812262)
			(xy 35.352228 -118.826534) (xy 35.360653 -118.830754) (xy 35.379273 -118.833505) (xy 35.38855 -118.831868)
			(xy 35.41903 -118.82501) (xy 35.428018 -118.822569) (xy 35.443525 -118.812285) (xy 35.449256 -118.804944)
			(xy 35.464658 -118.784104) (xy 35.500203 -118.746394) (xy 35.540527 -118.713845) (xy 35.584887 -118.687057)
			(xy 35.632467 -118.666523) (xy 35.682389 -118.652622) (xy 35.733733 -118.64561) (xy 35.759644 -118.645178)
			(xy 35.786892 -118.645695) (xy 35.840833 -118.653457) (xy 35.893121 -118.668815) (xy 35.94269 -118.691458)
			(xy 35.988534 -118.720924) (xy 36.027746 -118.754906) (xy 44.669708 -118.754906) (xy 44.673779 -118.699284)
			(xy 44.685905 -118.644847) (xy 44.705828 -118.592756) (xy 44.733124 -118.544121) (xy 44.76721 -118.499978)
			(xy 44.807359 -118.461269) (xy 44.852717 -118.428818) (xy 44.902317 -118.403317) (xy 44.955101 -118.38531)
			(xy 45.009944 -118.37518) (xy 45.065678 -118.373143) (xy 45.121115 -118.379243) (xy 45.175072 -118.393349)
			(xy 45.226401 -118.415161) (xy 45.274007 -118.444215) (xy 45.316875 -118.47989) (xy 45.354092 -118.521427)
			(xy 45.384865 -118.56794) (xy 45.408537 -118.618437) (xy 45.424605 -118.671844) (xy 45.432725 -118.72702)
			(xy 45.433234 -118.754906) (xy 46.650908 -118.754906) (xy 46.654979 -118.699284) (xy 46.667105 -118.644847)
			(xy 46.687028 -118.592756) (xy 46.714324 -118.544121) (xy 46.74841 -118.499978) (xy 46.788559 -118.461269)
			(xy 46.833917 -118.428818) (xy 46.883517 -118.403317) (xy 46.936301 -118.38531) (xy 46.991144 -118.37518)
			(xy 47.046878 -118.373143) (xy 47.102315 -118.379243) (xy 47.156272 -118.393349) (xy 47.207601 -118.415161)
			(xy 47.255207 -118.444215) (xy 47.298075 -118.47989) (xy 47.335292 -118.521427) (xy 47.366065 -118.56794)
			(xy 47.389737 -118.618437) (xy 47.405805 -118.671844) (xy 47.413925 -118.72702) (xy 47.414434 -118.754906)
			(xy 49.269902 -118.754906) (xy 49.273973 -118.699284) (xy 49.286099 -118.644847) (xy 49.306022 -118.592756)
			(xy 49.333318 -118.544121) (xy 49.367404 -118.499978) (xy 49.407553 -118.461269) (xy 49.452911 -118.428818)
			(xy 49.502511 -118.403317) (xy 49.555295 -118.38531) (xy 49.610138 -118.37518) (xy 49.665872 -118.373143)
			(xy 49.721309 -118.379243) (xy 49.775266 -118.393349) (xy 49.826595 -118.415161) (xy 49.874201 -118.444215)
			(xy 49.917069 -118.47989) (xy 49.954286 -118.521427) (xy 49.985059 -118.56794) (xy 50.008731 -118.618437)
			(xy 50.024799 -118.671844) (xy 50.032919 -118.72702) (xy 50.033428 -118.754906) (xy 51.251102 -118.754906)
			(xy 51.255173 -118.699284) (xy 51.267299 -118.644847) (xy 51.287222 -118.592756) (xy 51.314518 -118.544121)
			(xy 51.348604 -118.499978) (xy 51.388753 -118.461269) (xy 51.434111 -118.428818) (xy 51.483711 -118.403317)
			(xy 51.536495 -118.38531) (xy 51.591338 -118.37518) (xy 51.647072 -118.373143) (xy 51.702509 -118.379243)
			(xy 51.756466 -118.393349) (xy 51.807795 -118.415161) (xy 51.855401 -118.444215) (xy 51.898269 -118.47989)
			(xy 51.935486 -118.521427) (xy 51.966259 -118.56794) (xy 51.989931 -118.618437) (xy 52.005999 -118.671844)
			(xy 52.014119 -118.72702) (xy 52.014628 -118.754906) (xy 52.014119 -118.782792) (xy 52.005999 -118.837968)
			(xy 51.989931 -118.891375) (xy 51.966259 -118.941872) (xy 51.935486 -118.988385) (xy 51.898269 -119.029922)
			(xy 51.855401 -119.065597) (xy 51.807795 -119.094651) (xy 51.756466 -119.116463) (xy 51.702509 -119.130569)
			(xy 51.647072 -119.136669) (xy 51.591338 -119.134632) (xy 51.536495 -119.124502) (xy 51.483711 -119.106495)
			(xy 51.434111 -119.080994) (xy 51.388753 -119.048543) (xy 51.348604 -119.009834) (xy 51.314518 -118.965691)
			(xy 51.287222 -118.917056) (xy 51.267299 -118.864965) (xy 51.255173 -118.810528) (xy 51.251102 -118.754906)
			(xy 50.033428 -118.754906) (xy 50.032919 -118.782792) (xy 50.024799 -118.837968) (xy 50.008731 -118.891375)
			(xy 49.985059 -118.941872) (xy 49.954286 -118.988385) (xy 49.917069 -119.029922) (xy 49.874201 -119.065597)
			(xy 49.826595 -119.094651) (xy 49.775266 -119.116463) (xy 49.721309 -119.130569) (xy 49.665872 -119.136669)
			(xy 49.610138 -119.134632) (xy 49.555295 -119.124502) (xy 49.502511 -119.106495) (xy 49.452911 -119.080994)
			(xy 49.407553 -119.048543) (xy 49.367404 -119.009834) (xy 49.333318 -118.965691) (xy 49.306022 -118.917056)
			(xy 49.286099 -118.864965) (xy 49.273973 -118.810528) (xy 49.269902 -118.754906) (xy 47.414434 -118.754906)
			(xy 47.413925 -118.782792) (xy 47.405805 -118.837968) (xy 47.389737 -118.891375) (xy 47.366065 -118.941872)
			(xy 47.335292 -118.988385) (xy 47.298075 -119.029922) (xy 47.255207 -119.065597) (xy 47.207601 -119.094651)
			(xy 47.156272 -119.116463) (xy 47.102315 -119.130569) (xy 47.046878 -119.136669) (xy 46.991144 -119.134632)
			(xy 46.936301 -119.124502) (xy 46.883517 -119.106495) (xy 46.833917 -119.080994) (xy 46.788559 -119.048543)
			(xy 46.74841 -119.009834) (xy 46.714324 -118.965691) (xy 46.687028 -118.917056) (xy 46.667105 -118.864965)
			(xy 46.654979 -118.810528) (xy 46.650908 -118.754906) (xy 45.433234 -118.754906) (xy 45.432725 -118.782792)
			(xy 45.424605 -118.837968) (xy 45.408537 -118.891375) (xy 45.384865 -118.941872) (xy 45.354092 -118.988385)
			(xy 45.316875 -119.029922) (xy 45.274007 -119.065597) (xy 45.226401 -119.094651) (xy 45.175072 -119.116463)
			(xy 45.121115 -119.130569) (xy 45.065678 -119.136669) (xy 45.009944 -119.134632) (xy 44.955101 -119.124502)
			(xy 44.902317 -119.106495) (xy 44.852717 -119.080994) (xy 44.807359 -119.048543) (xy 44.76721 -119.009834)
			(xy 44.733124 -118.965691) (xy 44.705828 -118.917056) (xy 44.685905 -118.864965) (xy 44.673779 -118.810528)
			(xy 44.669708 -118.754906) (xy 36.027746 -118.754906) (xy 36.029717 -118.756614) (xy 36.065402 -118.797802)
			(xy 36.094863 -118.843648) (xy 36.1175 -118.893221) (xy 36.132853 -118.94551) (xy 36.140608 -118.999452)
			(xy 36.140608 -119.053948) (xy 36.132853 -119.10789) (xy 36.1175 -119.160179) (xy 36.094863 -119.209752)
			(xy 36.065402 -119.255598) (xy 36.029717 -119.296786) (xy 35.988534 -119.332476) (xy 35.94269 -119.361942)
			(xy 35.893121 -119.384585) (xy 35.840833 -119.399943) (xy 35.786892 -119.407705) (xy 35.759644 -119.408194)
			(xy 35.744851 -119.408055) (xy 35.715353 -119.405769) (xy 35.700716 -119.403622) (xy 35.689741 -119.402509)
			(xy 35.66855 -119.40856) (xy 35.659822 -119.415306) (xy 35.601148 -119.465344) (xy 35.593144 -119.472933)
			(xy 35.583917 -119.492937) (xy 35.583368 -119.503952) (xy 35.583368 -119.808244) (xy 35.583947 -119.819258)
			(xy 35.593139 -119.839274) (xy 35.601148 -119.846852) (xy 35.659822 -119.89689) (xy 35.668517 -119.903702)
			(xy 35.689733 -119.909755) (xy 35.700716 -119.908574) (xy 35.715354 -119.906436) (xy 35.744851 -119.904146)
			(xy 35.759644 -119.904002) (xy 35.786894 -119.904471) (xy 35.840838 -119.912233) (xy 35.893129 -119.927592)
			(xy 35.942702 -119.950236) (xy 35.988548 -119.979704) (xy 36.029734 -120.015397) (xy 36.065422 -120.056587)
			(xy 36.083094 -120.084088) (xy 48.95037 -120.084088) (xy 48.954441 -120.028466) (xy 48.966567 -119.974029)
			(xy 48.98649 -119.921938) (xy 49.013786 -119.873303) (xy 49.047872 -119.82916) (xy 49.088021 -119.790451)
			(xy 49.133379 -119.758) (xy 49.182979 -119.732499) (xy 49.235763 -119.714492) (xy 49.290606 -119.704362)
			(xy 49.34634 -119.702325) (xy 49.401777 -119.708425) (xy 49.455734 -119.722531) (xy 49.507063 -119.744343)
			(xy 49.554669 -119.773397) (xy 49.597537 -119.809072) (xy 49.634754 -119.850609) (xy 49.665527 -119.897122)
			(xy 49.689199 -119.947619) (xy 49.705267 -120.001026) (xy 49.713387 -120.056202) (xy 49.713896 -120.084088)
			(xy 49.713387 -120.111974) (xy 49.705267 -120.16715) (xy 49.689199 -120.220557) (xy 49.665527 -120.271054)
			(xy 49.634754 -120.317567) (xy 49.597537 -120.359104) (xy 49.554669 -120.394779) (xy 49.507063 -120.423833)
			(xy 49.455734 -120.445645) (xy 49.401777 -120.459751) (xy 49.34634 -120.465851) (xy 49.290606 -120.463814)
			(xy 49.235763 -120.453684) (xy 49.182979 -120.435677) (xy 49.133379 -120.410176) (xy 49.088021 -120.377725)
			(xy 49.047872 -120.339016) (xy 49.013786 -120.294873) (xy 48.98649 -120.246238) (xy 48.966567 -120.194147)
			(xy 48.954441 -120.13971) (xy 48.95037 -120.084088) (xy 36.083094 -120.084088) (xy 36.094885 -120.102437)
			(xy 36.117523 -120.152012) (xy 36.132877 -120.204305) (xy 36.140632 -120.25825) (xy 36.140632 -120.31275)
			(xy 36.132877 -120.366695) (xy 36.117523 -120.418988) (xy 36.094885 -120.468563) (xy 36.065422 -120.514413)
			(xy 36.029734 -120.555603) (xy 35.988548 -120.591296) (xy 35.942702 -120.620764) (xy 35.893129 -120.643408)
			(xy 35.840838 -120.658767) (xy 35.786894 -120.666529) (xy 35.759644 -120.667018) (xy 35.733736 -120.666563)
			(xy 35.6824 -120.659533) (xy 35.632486 -120.645622) (xy 35.584913 -120.625088) (xy 35.540555 -120.598306)
			(xy 35.500228 -120.56577) (xy 35.464673 -120.528078) (xy 35.449256 -120.507252) (xy 35.443498 -120.499937)
			(xy 35.428008 -120.489642) (xy 35.41903 -120.487186) (xy 35.38855 -120.480328) (xy 35.379274 -120.478572)
			(xy 35.360609 -120.481317) (xy 35.352228 -120.485662) (xy 35.326243 -120.49994) (xy 35.271394 -120.522456)
			(xy 35.214094 -120.537687) (xy 35.155305 -120.545378) (xy 35.12566 -120.54586) (xy 35.096018 -120.545343)
			(xy 35.037237 -120.537627) (xy 34.979939 -120.522406) (xy 34.925077 -120.499933) (xy 34.899092 -120.485662)
			(xy 34.890685 -120.481402) (xy 34.87205 -120.478676) (xy 34.86277 -120.480328) (xy 34.83229 -120.487186)
			(xy 34.823305 -120.489637) (xy 34.807797 -120.499914) (xy 34.802064 -120.507252) (xy 34.786648 -120.528082)
			(xy 34.751106 -120.565792) (xy 34.710785 -120.598342) (xy 34.666427 -120.625132) (xy 34.618849 -120.645667)
			(xy 34.568929 -120.65957) (xy 34.517586 -120.666585) (xy 34.491676 -120.667018) (xy 34.464427 -120.66651)
			(xy 34.410483 -120.658751) (xy 34.358193 -120.643394) (xy 34.30862 -120.620752) (xy 34.262774 -120.591286)
			(xy 34.221587 -120.555596) (xy 34.185899 -120.514407) (xy 34.156436 -120.468559) (xy 34.133797 -120.418985)
			(xy 34.118444 -120.366694) (xy 34.110688 -120.312749) (xy 34.110688 -120.258251) (xy 34.118444 -120.204306)
			(xy 34.133797 -120.152015) (xy 34.156436 -120.102441) (xy 34.185899 -120.056593) (xy 34.221587 -120.015404)
			(xy 34.262774 -119.979714) (xy 34.30862 -119.950248) (xy 34.358193 -119.927606) (xy 34.410483 -119.912249)
			(xy 34.464427 -119.90449) (xy 34.491676 -119.904002) (xy 34.506469 -119.904138) (xy 34.535967 -119.906427)
			(xy 34.550604 -119.908574) (xy 34.561579 -119.9097) (xy 34.582771 -119.90364) (xy 34.591498 -119.89689)
			(xy 34.650172 -119.846852) (xy 34.658181 -119.839268) (xy 34.667405 -119.81926) (xy 34.667952 -119.808244)
			(xy 34.667952 -119.503952) (xy 34.667401 -119.492934) (xy 34.658192 -119.472917) (xy 34.650172 -119.465344)
			(xy 34.591498 -119.415306) (xy 34.582797 -119.408505) (xy 34.561585 -119.402445) (xy 34.550604 -119.403622)
			(xy 34.535965 -119.405757) (xy 34.506469 -119.408049) (xy 34.491676 -119.408194) (xy 34.464425 -119.407735)
			(xy 34.410478 -119.399975) (xy 34.358184 -119.384617) (xy 34.308608 -119.361974) (xy 34.262759 -119.332506)
			(xy 34.22157 -119.296813) (xy 34.18588 -119.255622) (xy 34.156415 -119.209771) (xy 34.133774 -119.160194)
			(xy 34.11842 -119.107899) (xy 34.110664 -119.053951) (xy 5.06984 -119.053951) (xy 5.06984 -120.248426)
			(xy 10.195304 -120.248426) (xy 10.199375 -120.192804) (xy 10.211501 -120.138367) (xy 10.231424 -120.086276)
			(xy 10.25872 -120.037641) (xy 10.292806 -119.993498) (xy 10.332955 -119.954789) (xy 10.378313 -119.922338)
			(xy 10.427913 -119.896837) (xy 10.480697 -119.87883) (xy 10.53554 -119.8687) (xy 10.591274 -119.866663)
			(xy 10.646711 -119.872763) (xy 10.700668 -119.886869) (xy 10.751997 -119.908681) (xy 10.799603 -119.937735)
			(xy 10.842471 -119.97341) (xy 10.879688 -120.014947) (xy 10.910461 -120.06146) (xy 10.934133 -120.111957)
			(xy 10.935912 -120.11787) (xy 11.211304 -120.11787) (xy 11.215375 -120.062248) (xy 11.227501 -120.007811)
			(xy 11.247424 -119.95572) (xy 11.27472 -119.907085) (xy 11.308806 -119.862942) (xy 11.348955 -119.824233)
			(xy 11.394313 -119.791782) (xy 11.443913 -119.766281) (xy 11.496697 -119.748274) (xy 11.55154 -119.738144)
			(xy 11.607274 -119.736107) (xy 11.662711 -119.742207) (xy 11.716668 -119.756313) (xy 11.767997 -119.778125)
			(xy 11.815603 -119.807179) (xy 11.858471 -119.842854) (xy 11.895688 -119.884391) (xy 11.926461 -119.930904)
			(xy 11.950133 -119.981401) (xy 11.966201 -120.034808) (xy 11.974321 -120.089984) (xy 11.97483 -120.11787)
			(xy 12.227304 -120.11787) (xy 12.231375 -120.062248) (xy 12.243501 -120.007811) (xy 12.263424 -119.95572)
			(xy 12.29072 -119.907085) (xy 12.324806 -119.862942) (xy 12.364955 -119.824233) (xy 12.410313 -119.791782)
			(xy 12.459913 -119.766281) (xy 12.512697 -119.748274) (xy 12.56754 -119.738144) (xy 12.623274 -119.736107)
			(xy 12.678711 -119.742207) (xy 12.732668 -119.756313) (xy 12.783997 -119.778125) (xy 12.831603 -119.807179)
			(xy 12.874471 -119.842854) (xy 12.911688 -119.884391) (xy 12.942461 -119.930904) (xy 12.966133 -119.981401)
			(xy 12.982201 -120.034808) (xy 12.990321 -120.089984) (xy 12.99083 -120.11787) (xy 13.243814 -120.11787)
			(xy 13.2443 -120.090619) (xy 13.252056 -120.036671) (xy 13.267411 -119.984376) (xy 13.290053 -119.934799)
			(xy 13.319519 -119.888949) (xy 13.35521 -119.847758) (xy 13.396401 -119.812067) (xy 13.442251 -119.782601)
			(xy 13.491828 -119.759959) (xy 13.544123 -119.744604) (xy 13.598071 -119.736848) (xy 13.652573 -119.736848)
			(xy 13.706521 -119.744604) (xy 13.758816 -119.759959) (xy 13.808393 -119.782601) (xy 13.854243 -119.812067)
			(xy 13.895434 -119.847758) (xy 13.931125 -119.888949) (xy 13.960591 -119.934799) (xy 13.983233 -119.984376)
			(xy 13.998588 -120.036671) (xy 14.006344 -120.090619) (xy 14.00683 -120.11787) (xy 14.006355 -120.144929)
			(xy 14.005143 -120.15343) (xy 14.406878 -120.15343) (xy 14.410949 -120.097808) (xy 14.423075 -120.043371)
			(xy 14.442998 -119.99128) (xy 14.470294 -119.942645) (xy 14.50438 -119.898502) (xy 14.544529 -119.859793)
			(xy 14.589887 -119.827342) (xy 14.639487 -119.801841) (xy 14.692271 -119.783834) (xy 14.747114 -119.773704)
			(xy 14.802848 -119.771667) (xy 14.858285 -119.777767) (xy 14.912242 -119.791873) (xy 14.963571 -119.813685)
			(xy 15.011177 -119.842739) (xy 15.054045 -119.878414) (xy 15.091262 -119.919951) (xy 15.122035 -119.966464)
			(xy 15.145707 -120.016961) (xy 15.161775 -120.070368) (xy 15.169895 -120.125544) (xy 15.170404 -120.15343)
			(xy 15.422878 -120.15343) (xy 15.426949 -120.097808) (xy 15.439075 -120.043371) (xy 15.458998 -119.99128)
			(xy 15.486294 -119.942645) (xy 15.52038 -119.898502) (xy 15.560529 -119.859793) (xy 15.605887 -119.827342)
			(xy 15.655487 -119.801841) (xy 15.708271 -119.783834) (xy 15.763114 -119.773704) (xy 15.818848 -119.771667)
			(xy 15.874285 -119.777767) (xy 15.928242 -119.791873) (xy 15.979571 -119.813685) (xy 16.027177 -119.842739)
			(xy 16.070045 -119.878414) (xy 16.107262 -119.919951) (xy 16.138035 -119.966464) (xy 16.161707 -120.016961)
			(xy 16.177775 -120.070368) (xy 16.185895 -120.125544) (xy 16.186404 -120.15343) (xy 16.438878 -120.15343)
			(xy 16.442949 -120.097808) (xy 16.455075 -120.043371) (xy 16.474998 -119.99128) (xy 16.502294 -119.942645)
			(xy 16.53638 -119.898502) (xy 16.576529 -119.859793) (xy 16.621887 -119.827342) (xy 16.671487 -119.801841)
			(xy 16.724271 -119.783834) (xy 16.779114 -119.773704) (xy 16.834848 -119.771667) (xy 16.890285 -119.777767)
			(xy 16.944242 -119.791873) (xy 16.995571 -119.813685) (xy 17.043177 -119.842739) (xy 17.086045 -119.878414)
			(xy 17.123262 -119.919951) (xy 17.154035 -119.966464) (xy 17.177707 -120.016961) (xy 17.193775 -120.070368)
			(xy 17.201895 -120.125544) (xy 17.202404 -120.15343) (xy 17.201895 -120.181316) (xy 17.193775 -120.236492)
			(xy 17.177707 -120.289899) (xy 17.154035 -120.340396) (xy 17.123262 -120.386909) (xy 17.086045 -120.428446)
			(xy 17.043177 -120.464121) (xy 16.995571 -120.493175) (xy 16.944242 -120.514987) (xy 16.890285 -120.529093)
			(xy 16.834848 -120.535193) (xy 16.779114 -120.533156) (xy 16.724271 -120.523026) (xy 16.671487 -120.505019)
			(xy 16.621887 -120.479518) (xy 16.576529 -120.447067) (xy 16.53638 -120.408358) (xy 16.502294 -120.364215)
			(xy 16.474998 -120.31558) (xy 16.455075 -120.263489) (xy 16.442949 -120.209052) (xy 16.438878 -120.15343)
			(xy 16.186404 -120.15343) (xy 16.185895 -120.181316) (xy 16.177775 -120.236492) (xy 16.161707 -120.289899)
			(xy 16.138035 -120.340396) (xy 16.107262 -120.386909) (xy 16.070045 -120.428446) (xy 16.027177 -120.464121)
			(xy 15.979571 -120.493175) (xy 15.928242 -120.514987) (xy 15.874285 -120.529093) (xy 15.818848 -120.535193)
			(xy 15.763114 -120.533156) (xy 15.708271 -120.523026) (xy 15.655487 -120.505019) (xy 15.605887 -120.479518)
			(xy 15.560529 -120.447067) (xy 15.52038 -120.408358) (xy 15.486294 -120.364215) (xy 15.458998 -120.31558)
			(xy 15.439075 -120.263489) (xy 15.426949 -120.209052) (xy 15.422878 -120.15343) (xy 15.170404 -120.15343)
			(xy 15.169895 -120.181316) (xy 15.161775 -120.236492) (xy 15.145707 -120.289899) (xy 15.122035 -120.340396)
			(xy 15.091262 -120.386909) (xy 15.054045 -120.428446) (xy 15.011177 -120.464121) (xy 14.963571 -120.493175)
			(xy 14.912242 -120.514987) (xy 14.858285 -120.529093) (xy 14.802848 -120.535193) (xy 14.747114 -120.533156)
			(xy 14.692271 -120.523026) (xy 14.639487 -120.505019) (xy 14.589887 -120.479518) (xy 14.544529 -120.447067)
			(xy 14.50438 -120.408358) (xy 14.470294 -120.364215) (xy 14.442998 -120.31558) (xy 14.423075 -120.263489)
			(xy 14.410949 -120.209052) (xy 14.406878 -120.15343) (xy 14.005143 -120.15343) (xy 13.998716 -120.198505)
			(xy 13.983586 -120.250465) (xy 13.96127 -120.299767) (xy 13.94714 -120.322848) (xy 13.939774 -120.334278)
			(xy 13.938504 -120.360948) (xy 13.990066 -120.46331) (xy 14.012672 -120.478042) (xy 14.026134 -120.478804)
			(xy 14.054786 -120.481182) (xy 14.110949 -120.493472) (xy 14.164633 -120.514049) (xy 14.214623 -120.542446)
			(xy 14.259787 -120.578021) (xy 14.299103 -120.619968) (xy 14.331682 -120.667339) (xy 14.356786 -120.719061)
			(xy 14.373847 -120.773963) (xy 14.382479 -120.830804) (xy 14.383004 -120.85955) (xy 14.382569 -120.885865)
			(xy 14.375327 -120.937995) (xy 14.361002 -120.988638) (xy 14.339863 -121.036837) (xy 14.312311 -121.08168)
			(xy 14.278868 -121.122318) (xy 14.259814 -121.140474) (xy 14.252424 -121.148005) (xy 14.243892 -121.167278)
			(xy 14.243304 -121.177812) (xy 14.243304 -121.252488) (xy 14.243825 -121.263039) (xy 14.252366 -121.282334)
			(xy 14.259814 -121.289826) (xy 14.278878 -121.307973) (xy 14.312334 -121.348605) (xy 14.339891 -121.393447)
			(xy 14.361028 -121.44165) (xy 14.375344 -121.492298) (xy 14.379914 -121.525284) (xy 17.351756 -121.525284)
			(xy 17.352199 -121.497913) (xy 17.36002 -121.443732) (xy 17.375514 -121.391228) (xy 17.398361 -121.341482)
			(xy 17.428092 -121.295516) (xy 17.445736 -121.274586) (xy 17.44599 -121.274332) (xy 17.451568 -121.26724)
			(xy 17.45782 -121.250327) (xy 17.458182 -121.241312) (xy 17.458182 -121.174256) (xy 17.457802 -121.165241)
			(xy 17.451571 -121.148324) (xy 17.44599 -121.141236) (xy 17.445736 -121.141236) (xy 17.445736 -121.140982)
			(xy 17.428127 -121.120025) (xy 17.39841 -121.07406) (xy 17.375567 -121.024319) (xy 17.360069 -120.971823)
			(xy 17.352234 -120.917652) (xy 17.351756 -120.890284) (xy 17.352242 -120.863033) (xy 17.359998 -120.809085)
			(xy 17.375353 -120.75679) (xy 17.397995 -120.707213) (xy 17.427461 -120.661363) (xy 17.463152 -120.620172)
			(xy 17.504343 -120.584481) (xy 17.550193 -120.555015) (xy 17.59977 -120.532373) (xy 17.652065 -120.517018)
			(xy 17.706013 -120.509262) (xy 17.760515 -120.509262) (xy 17.814463 -120.517018) (xy 17.866758 -120.532373)
			(xy 17.916335 -120.555015) (xy 17.962185 -120.584481) (xy 18.003376 -120.620172) (xy 18.039067 -120.661363)
			(xy 18.068533 -120.707213) (xy 18.091175 -120.75679) (xy 18.10653 -120.809085) (xy 18.114286 -120.863033)
			(xy 18.114772 -120.890284) (xy 18.114303 -120.917654) (xy 18.106487 -120.971833) (xy 18.090999 -121.024337)
			(xy 18.068158 -121.074084) (xy 18.038433 -121.12005) (xy 18.020792 -121.140982) (xy 18.020538 -121.141236)
			(xy 18.014965 -121.148331) (xy 18.008712 -121.165242) (xy 18.008346 -121.174256) (xy 18.008346 -121.241312)
			(xy 18.008687 -121.250331) (xy 18.014944 -121.267248) (xy 18.020538 -121.274332) (xy 18.020792 -121.274332)
			(xy 18.020792 -121.274586) (xy 18.038437 -121.295514) (xy 18.068148 -121.341487) (xy 18.090983 -121.391236)
			(xy 18.106473 -121.443738) (xy 18.114299 -121.497914) (xy 18.114772 -121.525284) (xy 18.114524 -121.543563)
			(xy 18.110965 -121.579949) (xy 18.10766 -121.597928) (xy 18.10766 -121.598182) (xy 18.106133 -121.609697)
			(xy 18.112327 -121.632053) (xy 18.119598 -121.641108) (xy 18.18132 -121.710704) (xy 18.203418 -121.719594)
			(xy 18.215102 -121.718578) (xy 18.243804 -121.717562) (xy 18.271175 -121.718011) (xy 18.325355 -121.72583)
			(xy 18.377859 -121.741323) (xy 18.427606 -121.764169) (xy 18.473571 -121.793898) (xy 18.494502 -121.811542)
			(xy 18.494756 -121.811796) (xy 18.501851 -121.81737) (xy 18.518761 -121.823624) (xy 18.527776 -121.823988)
			(xy 18.594832 -121.823988) (xy 18.603851 -121.823649) (xy 18.620768 -121.817389) (xy 18.627852 -121.811796)
			(xy 18.627852 -121.811542) (xy 18.628106 -121.811542) (xy 18.64903 -121.793893) (xy 18.695005 -121.764181)
			(xy 18.744754 -121.741347) (xy 18.797257 -121.725858) (xy 18.851434 -121.718034) (xy 18.878804 -121.717562)
			(xy 18.906053 -121.718108) (xy 18.959996 -121.725865) (xy 19.012286 -121.741219) (xy 19.061859 -121.763859)
			(xy 19.107705 -121.793323) (xy 19.148891 -121.829011) (xy 19.18458 -121.870198) (xy 19.214043 -121.916045)
			(xy 19.236682 -121.965618) (xy 19.252036 -122.017908) (xy 19.259792 -122.071851) (xy 19.259792 -122.126349)
			(xy 19.252036 -122.180292) (xy 19.236682 -122.232582) (xy 19.214043 -122.282155) (xy 19.18458 -122.328002)
			(xy 19.148891 -122.369189) (xy 19.107705 -122.404877) (xy 19.061859 -122.434341) (xy 19.012286 -122.456981)
			(xy 18.959996 -122.472335) (xy 18.906053 -122.480092) (xy 18.878804 -122.480578) (xy 18.851434 -122.480115)
			(xy 18.797254 -122.472297) (xy 18.744751 -122.456808) (xy 18.695004 -122.433965) (xy 18.649037 -122.40424)
			(xy 18.628106 -122.386598) (xy 18.627852 -122.386344) (xy 18.62076 -122.380766) (xy 18.603847 -122.374516)
			(xy 18.594832 -122.374152) (xy 18.527776 -122.374152) (xy 18.518757 -122.374486) (xy 18.501839 -122.380748)
			(xy 18.494756 -122.386344) (xy 18.494756 -122.386598) (xy 18.494502 -122.386598) (xy 18.47358 -122.404249)
			(xy 18.427604 -122.433959) (xy 18.377854 -122.456793) (xy 18.325351 -122.472281) (xy 18.271174 -122.480106)
			(xy 18.243804 -122.480578) (xy 18.21655 -122.480141) (xy 18.162596 -122.472384) (xy 18.110296 -122.457027)
			(xy 18.060714 -122.434382) (xy 18.01486 -122.404912) (xy 17.973666 -122.369215) (xy 17.937972 -122.32802)
			(xy 17.908505 -122.282163) (xy 17.885864 -122.232579) (xy 17.870511 -122.180278) (xy 17.862757 -122.126324)
			(xy 17.862296 -122.09907) (xy 17.862536 -122.080791) (xy 17.8661 -122.044405) (xy 17.869408 -122.026426)
			(xy 17.869408 -122.026172) (xy 17.870972 -122.014659) (xy 17.864754 -121.992298) (xy 17.85747 -121.983246)
			(xy 17.795748 -121.91365) (xy 17.77365 -121.90476) (xy 17.761966 -121.905776) (xy 17.733264 -121.906792)
			(xy 17.706011 -121.906356) (xy 17.652061 -121.898594) (xy 17.599764 -121.883233) (xy 17.550186 -121.860587)
			(xy 17.504335 -121.831115) (xy 17.463145 -121.795419) (xy 17.427454 -121.754224) (xy 17.397988 -121.708369)
			(xy 17.375349 -121.658787) (xy 17.359995 -121.606488) (xy 17.352241 -121.552537) (xy 17.351756 -121.525284)
			(xy 14.379914 -121.525284) (xy 14.382567 -121.544433) (xy 14.383004 -121.57075) (xy 14.382518 -121.598001)
			(xy 14.374762 -121.651949) (xy 14.359407 -121.704244) (xy 14.336765 -121.753821) (xy 14.307299 -121.799671)
			(xy 14.271608 -121.840862) (xy 14.230417 -121.876553) (xy 14.184567 -121.906019) (xy 14.13499 -121.928661)
			(xy 14.082695 -121.944016) (xy 14.028747 -121.951772) (xy 13.974245 -121.951772) (xy 13.920297 -121.944016)
			(xy 13.868002 -121.928661) (xy 13.818425 -121.906019) (xy 13.772575 -121.876553) (xy 13.731384 -121.840862)
			(xy 13.695693 -121.799671) (xy 13.666227 -121.753821) (xy 13.643585 -121.704244) (xy 13.62823 -121.651949)
			(xy 13.620474 -121.598001) (xy 13.619988 -121.57075) (xy 13.620426 -121.544435) (xy 13.627667 -121.492305)
			(xy 13.641992 -121.441662) (xy 13.66313 -121.393464) (xy 13.690682 -121.348621) (xy 13.724125 -121.307982)
			(xy 13.743178 -121.289826) (xy 13.750567 -121.282294) (xy 13.759099 -121.263022) (xy 13.759688 -121.252488)
			(xy 13.759688 -121.177812) (xy 13.759169 -121.167261) (xy 13.750627 -121.147966) (xy 13.743178 -121.140474)
			(xy 13.724113 -121.122328) (xy 13.690657 -121.081696) (xy 13.6631 -121.036854) (xy 13.641963 -120.988651)
			(xy 13.627648 -120.938002) (xy 13.620425 -120.885867) (xy 13.619988 -120.85955) (xy 13.62047 -120.832491)
			(xy 13.628106 -120.778916) (xy 13.643234 -120.726956) (xy 13.665548 -120.677653) (xy 13.679678 -120.654572)
			(xy 13.687044 -120.643142) (xy 13.688314 -120.616472) (xy 13.636752 -120.51411) (xy 13.614146 -120.499378)
			(xy 13.600684 -120.498616) (xy 13.572035 -120.496203) (xy 13.515874 -120.483916) (xy 13.462192 -120.463343)
			(xy 13.412203 -120.43495) (xy 13.36704 -120.399379) (xy 13.327723 -120.357436) (xy 13.295143 -120.310069)
			(xy 13.270038 -120.258351) (xy 13.252975 -120.203452) (xy 13.24434 -120.146615) (xy 13.243814 -120.11787)
			(xy 12.99083 -120.11787) (xy 12.990321 -120.145756) (xy 12.982201 -120.200932) (xy 12.966133 -120.254339)
			(xy 12.942461 -120.304836) (xy 12.911688 -120.351349) (xy 12.874471 -120.392886) (xy 12.831603 -120.428561)
			(xy 12.783997 -120.457615) (xy 12.732668 -120.479427) (xy 12.678711 -120.493533) (xy 12.623274 -120.499633)
			(xy 12.56754 -120.497596) (xy 12.512697 -120.487466) (xy 12.459913 -120.469459) (xy 12.410313 -120.443958)
			(xy 12.364955 -120.411507) (xy 12.324806 -120.372798) (xy 12.29072 -120.328655) (xy 12.263424 -120.28002)
			(xy 12.243501 -120.227929) (xy 12.231375 -120.173492) (xy 12.227304 -120.11787) (xy 11.97483 -120.11787)
			(xy 11.974321 -120.145756) (xy 11.966201 -120.200932) (xy 11.950133 -120.254339) (xy 11.926461 -120.304836)
			(xy 11.895688 -120.351349) (xy 11.858471 -120.392886) (xy 11.815603 -120.428561) (xy 11.767997 -120.457615)
			(xy 11.716668 -120.479427) (xy 11.662711 -120.493533) (xy 11.607274 -120.499633) (xy 11.55154 -120.497596)
			(xy 11.496697 -120.487466) (xy 11.443913 -120.469459) (xy 11.394313 -120.443958) (xy 11.348955 -120.411507)
			(xy 11.308806 -120.372798) (xy 11.27472 -120.328655) (xy 11.247424 -120.28002) (xy 11.227501 -120.227929)
			(xy 11.215375 -120.173492) (xy 11.211304 -120.11787) (xy 10.935912 -120.11787) (xy 10.950201 -120.165364)
			(xy 10.958321 -120.22054) (xy 10.95883 -120.248426) (xy 10.958321 -120.276312) (xy 10.950201 -120.331488)
			(xy 10.934133 -120.384895) (xy 10.910461 -120.435392) (xy 10.879688 -120.481905) (xy 10.842471 -120.523442)
			(xy 10.799603 -120.559117) (xy 10.751997 -120.588171) (xy 10.700668 -120.609983) (xy 10.646711 -120.624089)
			(xy 10.591274 -120.630189) (xy 10.53554 -120.628152) (xy 10.480697 -120.618022) (xy 10.427913 -120.600015)
			(xy 10.378313 -120.574514) (xy 10.332955 -120.542063) (xy 10.292806 -120.503354) (xy 10.25872 -120.459211)
			(xy 10.231424 -120.410576) (xy 10.211501 -120.358485) (xy 10.199375 -120.304048) (xy 10.195304 -120.248426)
			(xy 5.06984 -120.248426) (xy 5.06984 -121.661428) (xy 8.673082 -121.661428) (xy 8.677153 -121.605806)
			(xy 8.689279 -121.551369) (xy 8.709202 -121.499278) (xy 8.736498 -121.450643) (xy 8.770584 -121.4065)
			(xy 8.810733 -121.367791) (xy 8.856091 -121.33534) (xy 8.905691 -121.309839) (xy 8.958475 -121.291832)
			(xy 9.013318 -121.281702) (xy 9.069052 -121.279665) (xy 9.124489 -121.285765) (xy 9.178446 -121.299871)
			(xy 9.229775 -121.321683) (xy 9.277381 -121.350737) (xy 9.320249 -121.386412) (xy 9.357466 -121.427949)
			(xy 9.388239 -121.474462) (xy 9.411911 -121.524959) (xy 9.427979 -121.578366) (xy 9.436099 -121.633542)
			(xy 9.436608 -121.661428) (xy 9.436099 -121.689314) (xy 9.427979 -121.74449) (xy 9.411911 -121.797897)
			(xy 9.388239 -121.848394) (xy 9.357466 -121.894907) (xy 9.320249 -121.936444) (xy 9.277381 -121.972119)
			(xy 9.229775 -122.001173) (xy 9.178446 -122.022985) (xy 9.124489 -122.037091) (xy 9.069052 -122.043191)
			(xy 9.013318 -122.041154) (xy 8.958475 -122.031024) (xy 8.905691 -122.013017) (xy 8.856091 -121.987516)
			(xy 8.810733 -121.955065) (xy 8.770584 -121.916356) (xy 8.736498 -121.872213) (xy 8.709202 -121.823578)
			(xy 8.689279 -121.771487) (xy 8.677153 -121.71705) (xy 8.673082 -121.661428) (xy 5.06984 -121.661428)
			(xy 5.06984 -122.46991) (xy 10.936984 -122.46991) (xy 10.941055 -122.414288) (xy 10.953181 -122.359851)
			(xy 10.973104 -122.30776) (xy 11.0004 -122.259125) (xy 11.034486 -122.214982) (xy 11.074635 -122.176273)
			(xy 11.119993 -122.143822) (xy 11.169593 -122.118321) (xy 11.222377 -122.100314) (xy 11.27722 -122.090184)
			(xy 11.332954 -122.088147) (xy 11.388391 -122.094247) (xy 11.442348 -122.108353) (xy 11.493677 -122.130165)
			(xy 11.541283 -122.159219) (xy 11.584151 -122.194894) (xy 11.621368 -122.236431) (xy 11.652141 -122.282944)
			(xy 11.675813 -122.333441) (xy 11.691881 -122.386848) (xy 11.700001 -122.442024) (xy 11.70051 -122.46991)
			(xy 11.700001 -122.497796) (xy 11.691881 -122.552972) (xy 11.675813 -122.606379) (xy 11.652141 -122.656876)
			(xy 11.621368 -122.703389) (xy 11.584151 -122.744926) (xy 11.541283 -122.780601) (xy 11.493677 -122.809655)
			(xy 11.442348 -122.831467) (xy 11.388391 -122.845573) (xy 11.332954 -122.851673) (xy 11.27722 -122.849636)
			(xy 11.222377 -122.839506) (xy 11.169593 -122.821499) (xy 11.119993 -122.795998) (xy 11.074635 -122.763547)
			(xy 11.034486 -122.724838) (xy 11.0004 -122.680695) (xy 10.973104 -122.63206) (xy 10.953181 -122.579969)
			(xy 10.941055 -122.525532) (xy 10.936984 -122.46991) (xy 5.06984 -122.46991) (xy 5.06984 -122.931428)
			(xy 8.673082 -122.931428) (xy 8.677153 -122.875806) (xy 8.689279 -122.821369) (xy 8.709202 -122.769278)
			(xy 8.736498 -122.720643) (xy 8.770584 -122.6765) (xy 8.810733 -122.637791) (xy 8.856091 -122.60534)
			(xy 8.905691 -122.579839) (xy 8.958475 -122.561832) (xy 9.013318 -122.551702) (xy 9.069052 -122.549665)
			(xy 9.124489 -122.555765) (xy 9.178446 -122.569871) (xy 9.229775 -122.591683) (xy 9.277381 -122.620737)
			(xy 9.320249 -122.656412) (xy 9.357466 -122.697949) (xy 9.388239 -122.744462) (xy 9.411911 -122.794959)
			(xy 9.427979 -122.848366) (xy 9.436099 -122.903542) (xy 9.436608 -122.931428) (xy 9.436099 -122.959314)
			(xy 9.427979 -123.01449) (xy 9.411911 -123.067897) (xy 9.388239 -123.118394) (xy 9.357466 -123.164907)
			(xy 9.320249 -123.206444) (xy 9.277381 -123.242119) (xy 9.264859 -123.249761) (xy 11.91004 -123.249761)
			(xy 11.91004 -123.195259) (xy 11.917796 -123.141311) (xy 11.933151 -123.089017) (xy 11.955792 -123.03944)
			(xy 11.985258 -122.99359) (xy 12.02095 -122.9524) (xy 12.06214 -122.916708) (xy 12.10799 -122.887242)
			(xy 12.157567 -122.864601) (xy 12.209861 -122.849246) (xy 12.263809 -122.84149) (xy 12.29106 -122.841004)
			(xy 12.318091 -122.841459) (xy 12.371611 -122.849105) (xy 12.423513 -122.864236) (xy 12.472757 -122.886548)
			(xy 12.518354 -122.915593) (xy 12.559391 -122.950789) (xy 12.577572 -122.970798) (xy 12.577826 -122.971052)
			(xy 12.585282 -122.978685) (xy 12.604757 -122.987361) (xy 12.615418 -122.987816) (xy 12.703048 -122.988324)
			(xy 12.722606 -122.979688) (xy 12.729972 -122.971306) (xy 12.748153 -122.951603) (xy 12.78905 -122.916937)
			(xy 12.834401 -122.888346) (xy 12.883312 -122.866393) (xy 12.934818 -122.851514) (xy 12.9879 -122.844)
			(xy 13.014706 -122.843544) (xy 13.042077 -122.843996) (xy 13.096257 -122.851815) (xy 13.148761 -122.867307)
			(xy 13.198507 -122.890152) (xy 13.244473 -122.919881) (xy 13.265404 -122.937524) (xy 13.265658 -122.937778)
			(xy 13.272746 -122.943362) (xy 13.289662 -122.949608) (xy 13.298678 -122.94997) (xy 13.365734 -122.94997)
			(xy 13.374753 -122.949636) (xy 13.39167 -122.943373) (xy 13.398754 -122.937778) (xy 13.398754 -122.937524)
			(xy 13.399008 -122.937524) (xy 13.419941 -122.919883) (xy 13.465909 -122.890159) (xy 13.515655 -122.867313)
			(xy 13.568157 -122.851817) (xy 13.622335 -122.843988) (xy 13.677077 -122.843988) (xy 13.731255 -122.851817)
			(xy 13.783757 -122.867313) (xy 13.833503 -122.890159) (xy 13.879471 -122.919883) (xy 13.900404 -122.937524)
			(xy 13.900658 -122.937778) (xy 13.907746 -122.943362) (xy 13.924662 -122.949608) (xy 13.933678 -122.94997)
			(xy 14.000734 -122.94997) (xy 14.009753 -122.949636) (xy 14.02667 -122.943373) (xy 14.033754 -122.937778)
			(xy 14.034262 -122.937524) (xy 14.046999 -122.926583) (xy 14.074088 -122.90674) (xy 14.088364 -122.8979)
			(xy 14.097254 -122.892566) (xy 14.109446 -122.875548) (xy 14.129766 -122.78233) (xy 14.125448 -122.761756)
			(xy 14.119606 -122.75312) (xy 14.103613 -122.729052) (xy 14.078269 -122.677122) (xy 14.061041 -122.621965)
			(xy 14.052324 -122.564842) (xy 14.051788 -122.53595) (xy 14.052274 -122.508699) (xy 14.06003 -122.454751)
			(xy 14.075385 -122.402456) (xy 14.098027 -122.352879) (xy 14.127493 -122.307029) (xy 14.163184 -122.265838)
			(xy 14.204375 -122.230147) (xy 14.250225 -122.200681) (xy 14.299802 -122.178039) (xy 14.352097 -122.162684)
			(xy 14.406045 -122.154928) (xy 14.460547 -122.154928) (xy 14.514495 -122.162684) (xy 14.56679 -122.178039)
			(xy 14.616367 -122.200681) (xy 14.662217 -122.230147) (xy 14.703408 -122.265838) (xy 14.739099 -122.307029)
			(xy 14.768565 -122.352879) (xy 14.791207 -122.402456) (xy 14.806562 -122.454751) (xy 14.814318 -122.508699)
			(xy 14.814804 -122.53595) (xy 14.814277 -122.56404) (xy 14.806056 -122.619616) (xy 14.789771 -122.673385)
			(xy 14.765774 -122.724183) (xy 14.734584 -122.77091) (xy 14.696876 -122.812556) (xy 14.653467 -122.848219)
			(xy 14.629638 -122.863102) (xy 14.620748 -122.868436) (xy 14.608556 -122.885454) (xy 14.588236 -122.978672)
			(xy 14.592554 -122.999246) (xy 14.598396 -123.007882) (xy 14.61439 -123.03195) (xy 14.639734 -123.08388)
			(xy 14.643843 -123.097036) (xy 16.476726 -123.097036) (xy 16.477207 -123.069666) (xy 16.48502 -123.015488)
			(xy 16.500505 -122.962984) (xy 16.523344 -122.913237) (xy 16.553066 -122.86727) (xy 16.570706 -122.846338)
			(xy 16.57096 -122.846084) (xy 16.576567 -122.839011) (xy 16.5828 -122.822084) (xy 16.583152 -122.813064)
			(xy 16.583152 -122.746008) (xy 16.582801 -122.73699) (xy 16.57655 -122.720073) (xy 16.57096 -122.712988)
			(xy 16.570706 -122.712988) (xy 16.570706 -122.712734) (xy 16.55307 -122.691799) (xy 16.523358 -122.645827)
			(xy 16.500521 -122.59608) (xy 16.485029 -122.54358) (xy 16.4772 -122.489405) (xy 16.476726 -122.462036)
			(xy 16.477212 -122.434785) (xy 16.484968 -122.380837) (xy 16.500323 -122.328542) (xy 16.522965 -122.278965)
			(xy 16.552431 -122.233115) (xy 16.588122 -122.191924) (xy 16.629313 -122.156233) (xy 16.675163 -122.126767)
			(xy 16.72474 -122.104125) (xy 16.777035 -122.08877) (xy 16.830983 -122.081014) (xy 16.885485 -122.081014)
			(xy 16.939433 -122.08877) (xy 16.991728 -122.104125) (xy 17.041305 -122.126767) (xy 17.087155 -122.156233)
			(xy 17.128346 -122.191924) (xy 17.164037 -122.233115) (xy 17.193503 -122.278965) (xy 17.216145 -122.328542)
			(xy 17.2315 -122.380837) (xy 17.239256 -122.434785) (xy 17.239742 -122.462036) (xy 17.239311 -122.489408)
			(xy 17.231487 -122.543589) (xy 17.21599 -122.596093) (xy 17.193141 -122.645839) (xy 17.163407 -122.691804)
			(xy 17.145762 -122.712734) (xy 17.145508 -122.712988) (xy 17.139921 -122.720074) (xy 17.133674 -122.736991)
			(xy 17.133316 -122.746008) (xy 17.133316 -122.813064) (xy 17.133687 -122.82208) (xy 17.136919 -122.830844)
			(xy 19.438874 -122.830844) (xy 19.439348 -122.803474) (xy 19.447161 -122.749294) (xy 19.462647 -122.696791)
			(xy 19.485488 -122.647044) (xy 19.515212 -122.601077) (xy 19.532854 -122.580146) (xy 19.533108 -122.579892)
			(xy 19.538705 -122.572813) (xy 19.544945 -122.55589) (xy 19.5453 -122.546872) (xy 19.5453 -122.479816)
			(xy 19.544935 -122.4708) (xy 19.538693 -122.453883) (xy 19.533108 -122.446796) (xy 19.532854 -122.446796)
			(xy 19.532854 -122.446542) (xy 19.515217 -122.425606) (xy 19.485493 -122.379639) (xy 19.462647 -122.329893)
			(xy 19.447151 -122.277391) (xy 19.439322 -122.223213) (xy 19.439321 -122.168473) (xy 19.447149 -122.114294)
			(xy 19.462645 -122.061793) (xy 19.48549 -122.012047) (xy 19.515214 -121.966079) (xy 19.532854 -121.945146)
			(xy 19.533108 -121.944892) (xy 19.538705 -121.937813) (xy 19.544945 -121.92089) (xy 19.5453 -121.911872)
			(xy 19.5453 -121.844816) (xy 19.544935 -121.8358) (xy 19.538693 -121.818883) (xy 19.533108 -121.811796)
			(xy 19.532854 -121.811796) (xy 19.532854 -121.811542) (xy 19.515217 -121.790606) (xy 19.485493 -121.744639)
			(xy 19.462647 -121.694893) (xy 19.447151 -121.642391) (xy 19.439322 -121.588213) (xy 19.439321 -121.533473)
			(xy 19.447149 -121.479294) (xy 19.462645 -121.426793) (xy 19.48549 -121.377047) (xy 19.515214 -121.331079)
			(xy 19.532854 -121.310146) (xy 19.533108 -121.309892) (xy 19.538705 -121.302813) (xy 19.544945 -121.28589)
			(xy 19.5453 -121.276872) (xy 19.5453 -121.209816) (xy 19.544935 -121.2008) (xy 19.538693 -121.183883)
			(xy 19.533108 -121.176796) (xy 19.532854 -121.176796) (xy 19.532854 -121.176542) (xy 19.51523 -121.155598)
			(xy 19.485514 -121.109629) (xy 19.462674 -121.059885) (xy 19.44718 -121.007387) (xy 19.439349 -120.953213)
			(xy 19.438874 -120.925844) (xy 19.43936 -120.898593) (xy 19.447116 -120.844645) (xy 19.462471 -120.79235)
			(xy 19.485113 -120.742773) (xy 19.514579 -120.696923) (xy 19.55027 -120.655732) (xy 19.591461 -120.620041)
			(xy 19.637311 -120.590575) (xy 19.686888 -120.567933) (xy 19.739183 -120.552578) (xy 19.793131 -120.544822)
			(xy 19.847633 -120.544822) (xy 19.901581 -120.552578) (xy 19.953876 -120.567933) (xy 20.003453 -120.590575)
			(xy 20.049303 -120.620041) (xy 20.090494 -120.655732) (xy 20.126185 -120.696923) (xy 20.155651 -120.742773)
			(xy 20.178293 -120.79235) (xy 20.193648 -120.844645) (xy 20.201404 -120.898593) (xy 20.20189 -120.925844)
			(xy 20.201394 -120.953213) (xy 20.193583 -121.007391) (xy 20.178102 -121.059894) (xy 20.155267 -121.109641)
			(xy 20.125548 -121.155609) (xy 20.10791 -121.176542) (xy 20.107656 -121.176796) (xy 20.10206 -121.183876)
			(xy 20.09582 -121.200798) (xy 20.095464 -121.209816) (xy 20.095464 -121.276872) (xy 20.095842 -121.285887)
			(xy 20.102076 -121.302803) (xy 20.107656 -121.309892) (xy 20.10791 -121.309892) (xy 20.10791 -121.310146)
			(xy 20.125555 -121.331076) (xy 20.15528 -121.377044) (xy 20.178125 -121.426791) (xy 20.193621 -121.479293)
			(xy 20.201449 -121.533472) (xy 20.201449 -121.588214) (xy 20.19362 -121.642393) (xy 20.178123 -121.694895)
			(xy 20.155277 -121.744642) (xy 20.125551 -121.790609) (xy 20.10791 -121.811542) (xy 20.107656 -121.811796)
			(xy 20.10206 -121.818876) (xy 20.09582 -121.835798) (xy 20.095464 -121.844816) (xy 20.095464 -121.911872)
			(xy 20.095842 -121.920887) (xy 20.102076 -121.937803) (xy 20.107656 -121.944892) (xy 20.10791 -121.944892)
			(xy 20.10791 -121.945146) (xy 20.125555 -121.966076) (xy 20.15528 -122.012044) (xy 20.178125 -122.061791)
			(xy 20.193621 -122.114293) (xy 20.194338 -122.119254) (xy 36.752736 -122.119254) (xy 36.752736 -122.064746)
			(xy 36.760493 -122.010794) (xy 36.775849 -121.958495) (xy 36.798491 -121.908913) (xy 36.827959 -121.863059)
			(xy 36.863653 -121.821864) (xy 36.904846 -121.786169) (xy 36.950699 -121.756699) (xy 37.00028 -121.734054)
			(xy 37.052579 -121.718696) (xy 37.106531 -121.710937) (xy 37.133784 -121.71045) (xy 37.148577 -121.710585)
			(xy 37.178075 -121.712874) (xy 37.192712 -121.715022) (xy 37.203687 -121.716142) (xy 37.224877 -121.710085)
			(xy 37.233606 -121.703338) (xy 37.29228 -121.6533) (xy 37.300314 -121.645738) (xy 37.309523 -121.625713)
			(xy 37.31006 -121.614692) (xy 37.31006 -121.3104) (xy 37.309535 -121.299379) (xy 37.300308 -121.279362)
			(xy 37.29228 -121.271792) (xy 37.233606 -121.221754) (xy 37.224898 -121.214961) (xy 37.203692 -121.208895)
			(xy 37.192712 -121.21007) (xy 37.178073 -121.212204) (xy 37.148577 -121.214497) (xy 37.133784 -121.214642)
			(xy 37.106536 -121.214087) (xy 37.052595 -121.206329) (xy 37.000307 -121.190974) (xy 36.950736 -121.168334)
			(xy 36.904892 -121.13887) (xy 36.863707 -121.103182) (xy 36.828021 -121.061995) (xy 36.798558 -121.01615)
			(xy 36.77592 -120.966578) (xy 36.760568 -120.91429) (xy 36.752812 -120.860348) (xy 36.752812 -120.805852)
			(xy 36.760568 -120.75191) (xy 36.77592 -120.699622) (xy 36.798558 -120.65005) (xy 36.828021 -120.604205)
			(xy 36.863707 -120.563018) (xy 36.904892 -120.52733) (xy 36.950736 -120.497866) (xy 37.000307 -120.475226)
			(xy 37.052595 -120.459871) (xy 37.106536 -120.452113) (xy 37.133784 -120.451626) (xy 37.159693 -120.452042)
			(xy 37.211032 -120.459077) (xy 37.260947 -120.472993) (xy 37.308521 -120.493533) (xy 37.352879 -120.520321)
			(xy 37.393204 -120.552864) (xy 37.428757 -120.590563) (xy 37.444172 -120.611392) (xy 37.449911 -120.618724)
			(xy 37.465415 -120.629008) (xy 37.474398 -120.631458) (xy 37.504878 -120.638316) (xy 37.514152 -120.640082)
			(xy 37.532818 -120.637329) (xy 37.5412 -120.632982) (xy 37.567177 -120.618689) (xy 37.622029 -120.596177)
			(xy 37.679331 -120.580951) (xy 37.738122 -120.573264) (xy 37.767768 -120.572784) (xy 37.797411 -120.573283)
			(xy 37.856193 -120.581004) (xy 37.913491 -120.59623) (xy 37.968351 -120.618708) (xy 37.994336 -120.632982)
			(xy 38.002758 -120.637207) (xy 38.02138 -120.639953) (xy 38.030658 -120.638316) (xy 38.061138 -120.631458)
			(xy 38.070133 -120.629036) (xy 38.085637 -120.618739) (xy 38.091364 -120.611392) (xy 38.106776 -120.590559)
			(xy 38.142317 -120.552846) (xy 38.182638 -120.520295) (xy 38.226997 -120.493505) (xy 38.274576 -120.472971)
			(xy 38.324497 -120.459069) (xy 38.375842 -120.452057) (xy 38.401752 -120.451626) (xy 38.42901 -120.452018)
			(xy 38.482971 -120.45977) (xy 38.535279 -120.475123) (xy 38.58487 -120.497765) (xy 38.630733 -120.527234)
			(xy 38.662786 -120.555004) (xy 44.669708 -120.555004) (xy 44.673779 -120.499382) (xy 44.685905 -120.444945)
			(xy 44.705828 -120.392854) (xy 44.733124 -120.344219) (xy 44.76721 -120.300076) (xy 44.807359 -120.261367)
			(xy 44.852717 -120.228916) (xy 44.902317 -120.203415) (xy 44.955101 -120.185408) (xy 45.009944 -120.175278)
			(xy 45.065678 -120.173241) (xy 45.121115 -120.179341) (xy 45.175072 -120.193447) (xy 45.226401 -120.215259)
			(xy 45.274007 -120.244313) (xy 45.316875 -120.279988) (xy 45.354092 -120.321525) (xy 45.384865 -120.368038)
			(xy 45.408537 -120.418535) (xy 45.424605 -120.471942) (xy 45.432725 -120.527118) (xy 45.433234 -120.555004)
			(xy 46.650908 -120.555004) (xy 46.654979 -120.499382) (xy 46.667105 -120.444945) (xy 46.687028 -120.392854)
			(xy 46.714324 -120.344219) (xy 46.74841 -120.300076) (xy 46.788559 -120.261367) (xy 46.833917 -120.228916)
			(xy 46.883517 -120.203415) (xy 46.936301 -120.185408) (xy 46.991144 -120.175278) (xy 47.046878 -120.173241)
			(xy 47.102315 -120.179341) (xy 47.156272 -120.193447) (xy 47.207601 -120.215259) (xy 47.255207 -120.244313)
			(xy 47.298075 -120.279988) (xy 47.335292 -120.321525) (xy 47.366065 -120.368038) (xy 47.389737 -120.418535)
			(xy 47.405805 -120.471942) (xy 47.413925 -120.527118) (xy 47.414434 -120.555004) (xy 47.413925 -120.58289)
			(xy 47.405805 -120.638066) (xy 47.389737 -120.691473) (xy 47.366065 -120.74197) (xy 47.335292 -120.788483)
			(xy 47.298075 -120.83002) (xy 47.255207 -120.865695) (xy 47.207601 -120.894749) (xy 47.156272 -120.916561)
			(xy 47.102315 -120.930667) (xy 47.046878 -120.936767) (xy 46.991144 -120.93473) (xy 46.936301 -120.9246)
			(xy 46.883517 -120.906593) (xy 46.833917 -120.881092) (xy 46.788559 -120.848641) (xy 46.74841 -120.809932)
			(xy 46.714324 -120.765789) (xy 46.687028 -120.717154) (xy 46.667105 -120.665063) (xy 46.654979 -120.610626)
			(xy 46.650908 -120.555004) (xy 45.433234 -120.555004) (xy 45.432725 -120.58289) (xy 45.424605 -120.638066)
			(xy 45.408537 -120.691473) (xy 45.384865 -120.74197) (xy 45.354092 -120.788483) (xy 45.316875 -120.83002)
			(xy 45.274007 -120.865695) (xy 45.226401 -120.894749) (xy 45.175072 -120.916561) (xy 45.121115 -120.930667)
			(xy 45.065678 -120.936767) (xy 45.009944 -120.93473) (xy 44.955101 -120.9246) (xy 44.902317 -120.906593)
			(xy 44.852717 -120.881092) (xy 44.807359 -120.848641) (xy 44.76721 -120.809932) (xy 44.733124 -120.765789)
			(xy 44.705828 -120.717154) (xy 44.685905 -120.665063) (xy 44.673779 -120.610626) (xy 44.669708 -120.555004)
			(xy 38.662786 -120.555004) (xy 38.671935 -120.562931) (xy 38.707637 -120.604129) (xy 38.737112 -120.649988)
			(xy 38.75976 -120.699576) (xy 38.77512 -120.751882) (xy 38.782879 -120.805843) (xy 38.782879 -120.860357)
			(xy 38.77512 -120.914318) (xy 38.75976 -120.966624) (xy 38.737112 -121.016212) (xy 38.707637 -121.062071)
			(xy 38.671935 -121.103269) (xy 38.630733 -121.138966) (xy 38.58487 -121.168435) (xy 38.535279 -121.191077)
			(xy 38.482971 -121.20643) (xy 38.42901 -121.214182) (xy 38.401752 -121.214642) (xy 38.386959 -121.214503)
			(xy 38.357461 -121.212217) (xy 38.342824 -121.21007) (xy 38.331849 -121.208973) (xy 38.31066 -121.215015)
			(xy 38.30193 -121.221754) (xy 38.243256 -121.271792) (xy 38.235232 -121.279363) (xy 38.226016 -121.299381)
			(xy 38.225476 -121.3104) (xy 38.225476 -121.614692) (xy 38.226026 -121.625709) (xy 38.235238 -121.645725)
			(xy 38.243256 -121.6533) (xy 38.289123 -121.692416) (xy 49.165508 -121.692416) (xy 49.169579 -121.636794)
			(xy 49.181705 -121.582357) (xy 49.201628 -121.530266) (xy 49.228924 -121.481631) (xy 49.26301 -121.437488)
			(xy 49.303159 -121.398779) (xy 49.348517 -121.366328) (xy 49.398117 -121.340827) (xy 49.450901 -121.32282)
			(xy 49.505744 -121.31269) (xy 49.561478 -121.310653) (xy 49.616915 -121.316753) (xy 49.670872 -121.330859)
			(xy 49.722201 -121.352671) (xy 49.769807 -121.381725) (xy 49.812675 -121.4174) (xy 49.849892 -121.458937)
			(xy 49.880665 -121.50545) (xy 49.904337 -121.555947) (xy 49.920405 -121.609354) (xy 49.928525 -121.66453)
			(xy 49.929034 -121.692416) (xy 49.928525 -121.720302) (xy 49.920405 -121.775478) (xy 49.904337 -121.828885)
			(xy 49.880665 -121.879382) (xy 49.849892 -121.925895) (xy 49.812675 -121.967432) (xy 49.769807 -122.003107)
			(xy 49.722201 -122.032161) (xy 49.670872 -122.053973) (xy 49.616915 -122.068079) (xy 49.561478 -122.074179)
			(xy 49.505744 -122.072142) (xy 49.450901 -122.062012) (xy 49.398117 -122.044005) (xy 49.348517 -122.018504)
			(xy 49.303159 -121.986053) (xy 49.26301 -121.947344) (xy 49.228924 -121.903201) (xy 49.201628 -121.854566)
			(xy 49.181705 -121.802475) (xy 49.169579 -121.748038) (xy 49.165508 -121.692416) (xy 38.289123 -121.692416)
			(xy 38.30193 -121.703338) (xy 38.310625 -121.710149) (xy 38.331842 -121.716205) (xy 38.342824 -121.715022)
			(xy 38.357462 -121.712884) (xy 38.386959 -121.710594) (xy 38.401752 -121.71045) (xy 38.429004 -121.710994)
			(xy 38.482954 -121.718745) (xy 38.535252 -121.734095) (xy 38.584833 -121.756732) (xy 38.630687 -121.786195)
			(xy 38.671881 -121.821885) (xy 38.707576 -121.863075) (xy 38.737045 -121.908925) (xy 38.759688 -121.958503)
			(xy 38.775045 -122.010799) (xy 38.782803 -122.064748) (xy 38.782803 -122.119252) (xy 38.775045 -122.173201)
			(xy 38.759688 -122.225497) (xy 38.737045 -122.275075) (xy 38.707576 -122.320925) (xy 38.677958 -122.355102)
			(xy 44.669708 -122.355102) (xy 44.673779 -122.29948) (xy 44.685905 -122.245043) (xy 44.705828 -122.192952)
			(xy 44.733124 -122.144317) (xy 44.76721 -122.100174) (xy 44.807359 -122.061465) (xy 44.852717 -122.029014)
			(xy 44.902317 -122.003513) (xy 44.955101 -121.985506) (xy 45.009944 -121.975376) (xy 45.065678 -121.973339)
			(xy 45.121115 -121.979439) (xy 45.175072 -121.993545) (xy 45.226401 -122.015357) (xy 45.274007 -122.044411)
			(xy 45.316875 -122.080086) (xy 45.354092 -122.121623) (xy 45.359841 -122.130312) (xy 46.717202 -122.130312)
			(xy 46.721273 -122.07469) (xy 46.733399 -122.020253) (xy 46.753322 -121.968162) (xy 46.780618 -121.919527)
			(xy 46.814704 -121.875384) (xy 46.854853 -121.836675) (xy 46.900211 -121.804224) (xy 46.949811 -121.778723)
			(xy 47.002595 -121.760716) (xy 47.057438 -121.750586) (xy 47.113172 -121.748549) (xy 47.168609 -121.754649)
			(xy 47.222566 -121.768755) (xy 47.273895 -121.790567) (xy 47.321501 -121.819621) (xy 47.364369 -121.855296)
			(xy 47.401586 -121.896833) (xy 47.432359 -121.943346) (xy 47.456031 -121.993843) (xy 47.472099 -122.04725)
			(xy 47.480219 -122.102426) (xy 47.480728 -122.130312) (xy 47.480219 -122.158198) (xy 47.472099 -122.213374)
			(xy 47.456031 -122.266781) (xy 47.432359 -122.317278) (xy 47.401586 -122.363791) (xy 47.384954 -122.382354)
			(xy 51.252057 -122.382354) (xy 51.252057 -122.327846) (xy 51.259815 -122.273894) (xy 51.275172 -122.221595)
			(xy 51.297816 -122.172014) (xy 51.327285 -122.12616) (xy 51.362981 -122.084967) (xy 51.404176 -122.049273)
			(xy 51.450031 -122.019806) (xy 51.499614 -121.997165) (xy 51.551914 -121.981811) (xy 51.605866 -121.974056)
			(xy 51.63312 -121.973594) (xy 51.650168 -121.973796) (xy 51.684128 -121.976847) (xy 51.700938 -121.97969)
			(xy 51.712266 -121.981091) (xy 51.734279 -121.975178) (xy 51.743356 -121.96826) (xy 51.767994 -121.946924)
			(xy 51.776321 -121.939033) (xy 51.785448 -121.91801) (xy 51.78552 -121.906538) (xy 51.785012 -121.886472)
			(xy 51.785012 -121.022618) (xy 51.78552 -121.003822) (xy 51.785421 -120.992262) (xy 51.77616 -120.971104)
			(xy 51.76774 -120.963182) (xy 51.743356 -120.9421) (xy 51.734386 -120.935098) (xy 51.712487 -120.92903)
			(xy 51.701192 -120.930416) (xy 51.684321 -120.933289) (xy 51.650233 -120.936339) (xy 51.63312 -120.936512)
			(xy 51.605867 -120.936042) (xy 51.551914 -120.928287) (xy 51.499614 -120.912933) (xy 51.450032 -120.890292)
			(xy 51.404177 -120.860825) (xy 51.362982 -120.825132) (xy 51.327287 -120.783939) (xy 51.297817 -120.738085)
			(xy 51.275174 -120.688504) (xy 51.259817 -120.636206) (xy 51.252059 -120.582253) (xy 51.252059 -120.527747)
			(xy 51.259817 -120.473794) (xy 51.275174 -120.421496) (xy 51.297817 -120.371915) (xy 51.327287 -120.326061)
			(xy 51.362982 -120.284868) (xy 51.404177 -120.249175) (xy 51.450032 -120.219708) (xy 51.499614 -120.197067)
			(xy 51.551914 -120.181713) (xy 51.605867 -120.173958) (xy 51.63312 -120.173496) (xy 51.660096 -120.173998)
			(xy 51.713511 -120.181581) (xy 51.765324 -120.196619) (xy 51.814498 -120.218814) (xy 51.860051 -120.247721)
			(xy 51.901073 -120.282763) (xy 51.936743 -120.323239) (xy 51.96635 -120.368341) (xy 51.989301 -120.417167)
			(xy 52.005137 -120.468741) (xy 52.009802 -120.495314) (xy 52.011954 -120.505547) (xy 52.023242 -120.523125)
			(xy 52.031646 -120.52935) (xy 52.10302 -120.576848) (xy 52.124102 -120.580658) (xy 52.134262 -120.578118)
			(xy 52.160965 -120.572053) (xy 52.215339 -120.565554) (xy 52.24272 -120.565164) (xy 52.270102 -120.565538)
			(xy 52.324478 -120.572033) (xy 52.351178 -120.578118) (xy 52.361338 -120.580658) (xy 52.38242 -120.576848)
			(xy 52.462684 -120.523508) (xy 52.47386 -120.505982) (xy 52.475638 -120.495314) (xy 52.480353 -120.468752)
			(xy 52.496203 -120.417189) (xy 52.51916 -120.368374) (xy 52.548767 -120.32328) (xy 52.584432 -120.282808)
			(xy 52.625444 -120.247765) (xy 52.670984 -120.218851) (xy 52.720144 -120.196641) (xy 52.771944 -120.18158)
			(xy 52.825348 -120.173968) (xy 52.85232 -120.173496) (xy 52.879691 -120.173951) (xy 52.93387 -120.181772)
			(xy 52.986373 -120.197264) (xy 53.03612 -120.220108) (xy 53.082086 -120.249834) (xy 53.103018 -120.267476)
			(xy 53.103272 -120.26773) (xy 53.11036 -120.273314) (xy 53.127276 -120.279561) (xy 53.136292 -120.279922)
			(xy 53.203348 -120.279922) (xy 53.212362 -120.279535) (xy 53.229279 -120.273308) (xy 53.236368 -120.26773)
			(xy 53.236368 -120.267476) (xy 53.236622 -120.267476) (xy 53.25757 -120.249856) (xy 53.303539 -120.220142)
			(xy 53.353282 -120.197303) (xy 53.405779 -120.181807) (xy 53.459952 -120.173973) (xy 53.48732 -120.173496)
			(xy 53.504368 -120.173698) (xy 53.538328 -120.176749) (xy 53.555138 -120.179592) (xy 53.566466 -120.180993)
			(xy 53.588479 -120.175079) (xy 53.597556 -120.168162) (xy 53.622194 -120.146826) (xy 53.63052 -120.138934)
			(xy 53.639648 -120.117912) (xy 53.63972 -120.10644) (xy 53.639212 -120.086374) (xy 53.639212 -119.22252)
			(xy 53.63972 -119.203724) (xy 53.63962 -119.192164) (xy 53.63036 -119.171006) (xy 53.62194 -119.163084)
			(xy 53.597556 -119.142002) (xy 53.588586 -119.135) (xy 53.566687 -119.128932) (xy 53.555392 -119.130318)
			(xy 53.538521 -119.133191) (xy 53.504433 -119.136241) (xy 53.48732 -119.136414) (xy 53.460067 -119.13594)
			(xy 53.406114 -119.128186) (xy 53.353815 -119.112831) (xy 53.304233 -119.09019) (xy 53.258378 -119.060723)
			(xy 53.217184 -119.02503) (xy 53.181489 -118.983838) (xy 53.152019 -118.937984) (xy 53.129376 -118.888404)
			(xy 53.114019 -118.836105) (xy 53.106261 -118.782153) (xy 53.106261 -118.727647) (xy 53.114019 -118.673695)
			(xy 53.129376 -118.621396) (xy 53.152019 -118.571816) (xy 53.181489 -118.525962) (xy 53.217184 -118.48477)
			(xy 53.258378 -118.449077) (xy 53.304233 -118.41961) (xy 53.353815 -118.396969) (xy 53.406114 -118.381614)
			(xy 53.460067 -118.37386) (xy 53.48732 -118.373398) (xy 53.514296 -118.373898) (xy 53.567711 -118.381481)
			(xy 53.619524 -118.39652) (xy 53.668698 -118.418715) (xy 53.714251 -118.447622) (xy 53.755273 -118.482664)
			(xy 53.790944 -118.52314) (xy 53.82055 -118.568242) (xy 53.843501 -118.617068) (xy 53.859337 -118.668643)
			(xy 53.864002 -118.695216) (xy 53.866153 -118.70545) (xy 53.877442 -118.723028) (xy 53.885846 -118.729252)
			(xy 53.95722 -118.77675) (xy 53.978302 -118.78056) (xy 53.988462 -118.77802) (xy 54.015156 -118.771879)
			(xy 54.069532 -118.765258) (xy 54.09692 -118.764812) (xy 54.124308 -118.76525) (xy 54.178684 -118.771875)
			(xy 54.205378 -118.77802) (xy 54.215538 -118.78056) (xy 54.23662 -118.77675) (xy 54.316884 -118.72341)
			(xy 54.32806 -118.705884) (xy 54.329838 -118.695216) (xy 54.334554 -118.668655) (xy 54.350404 -118.617091)
			(xy 54.373361 -118.568276) (xy 54.402968 -118.523183) (xy 54.438633 -118.482711) (xy 54.479644 -118.447668)
			(xy 54.525185 -118.418753) (xy 54.574345 -118.396543) (xy 54.626144 -118.381482) (xy 54.679548 -118.37387)
			(xy 54.70652 -118.373398) (xy 54.733771 -118.373873) (xy 54.787717 -118.381632) (xy 54.84001 -118.396989)
			(xy 54.889586 -118.419632) (xy 54.935434 -118.449099) (xy 54.976623 -118.484791) (xy 55.012313 -118.525982)
			(xy 55.041778 -118.571832) (xy 55.064418 -118.621408) (xy 55.079772 -118.673702) (xy 55.087528 -118.727649)
			(xy 55.087528 -118.782151) (xy 55.079772 -118.836098) (xy 55.064418 -118.888392) (xy 55.041778 -118.937968)
			(xy 55.012313 -118.983818) (xy 54.976623 -119.025009) (xy 54.935434 -119.060701) (xy 54.889586 -119.090168)
			(xy 54.84001 -119.112811) (xy 54.787717 -119.128168) (xy 54.733771 -119.135927) (xy 54.70652 -119.136414)
			(xy 54.689408 -119.136226) (xy 54.655321 -119.133171) (xy 54.638448 -119.130318) (xy 54.627157 -119.128953)
			(xy 54.605268 -119.135026) (xy 54.596284 -119.142002) (xy 54.5719 -119.163084) (xy 54.56349 -119.171018)
			(xy 54.554215 -119.192165) (xy 54.55412 -119.203724) (xy 54.554628 -119.22252) (xy 54.554628 -120.086374)
			(xy 54.55412 -120.10644) (xy 54.554349 -120.117883) (xy 54.563436 -120.138853) (xy 54.571646 -120.146826)
			(xy 54.596284 -120.168162) (xy 54.605283 -120.17524) (xy 54.627366 -120.181195) (xy 54.638702 -120.179592)
			(xy 54.65551 -120.17673) (xy 54.689471 -120.173678) (xy 54.70652 -120.173496) (xy 54.733771 -120.173975)
			(xy 54.787717 -120.181734) (xy 54.84001 -120.197091) (xy 54.889585 -120.219734) (xy 54.935433 -120.249201)
			(xy 54.976622 -120.284893) (xy 55.012311 -120.326083) (xy 55.041776 -120.371933) (xy 55.064416 -120.421509)
			(xy 55.07977 -120.473803) (xy 55.087526 -120.527749) (xy 55.087526 -120.582251) (xy 55.07977 -120.636197)
			(xy 55.064416 -120.688491) (xy 55.041776 -120.738067) (xy 55.012311 -120.783917) (xy 54.976622 -120.825107)
			(xy 54.935433 -120.860799) (xy 54.889585 -120.890266) (xy 54.84001 -120.912909) (xy 54.787717 -120.928266)
			(xy 54.733771 -120.936025) (xy 54.70652 -120.936512) (xy 54.679512 -120.93606) (xy 54.626033 -120.928455)
			(xy 54.574162 -120.913382) (xy 54.524936 -120.891142) (xy 54.479341 -120.862179) (xy 54.438288 -120.827072)
			(xy 54.402598 -120.786525) (xy 54.372986 -120.741349) (xy 54.350044 -120.692446) (xy 54.334231 -120.640796)
			(xy 54.329584 -120.614186) (xy 54.32806 -120.603518) (xy 54.31663 -120.585738) (xy 54.245256 -120.53824)
			(xy 54.23633 -120.532886) (xy 54.215864 -120.529215) (xy 54.205632 -120.531128) (xy 54.20487 -120.531128)
			(xy 54.1783 -120.537244) (xy 54.12418 -120.543866) (xy 54.09692 -120.544336) (xy 54.069595 -120.543889)
			(xy 54.015347 -120.537262) (xy 53.988716 -120.531128) (xy 53.988208 -120.531128) (xy 53.977975 -120.529299)
			(xy 53.957532 -120.532952) (xy 53.948584 -120.53824) (xy 53.87721 -120.585738) (xy 53.86578 -120.603518)
			(xy 53.864256 -120.614186) (xy 53.85962 -120.640795) (xy 53.843789 -120.692435) (xy 53.820834 -120.741327)
			(xy 53.791215 -120.786494) (xy 53.755523 -120.827033) (xy 53.714472 -120.862134) (xy 53.668881 -120.891097)
			(xy 53.619662 -120.913341) (xy 53.567798 -120.928424) (xy 53.514326 -120.936043) (xy 53.48732 -120.936512)
			(xy 53.45995 -120.936031) (xy 53.405772 -120.928217) (xy 53.353269 -120.912731) (xy 53.303522 -120.889892)
			(xy 53.257554 -120.860171) (xy 53.236622 -120.842532) (xy 53.236368 -120.842278) (xy 53.229268 -120.836711)
			(xy 53.212361 -120.830453) (xy 53.203348 -120.830086) (xy 53.136292 -120.830086) (xy 53.127275 -120.830442)
			(xy 53.110358 -120.836691) (xy 53.103272 -120.842278) (xy 53.103272 -120.842532) (xy 53.103018 -120.842532)
			(xy 53.082094 -120.860181) (xy 53.036119 -120.88989) (xy 52.986369 -120.912724) (xy 52.933867 -120.928213)
			(xy 52.87969 -120.936039) (xy 52.85232 -120.936512) (xy 52.835208 -120.936324) (xy 52.801121 -120.933269)
			(xy 52.784248 -120.930416) (xy 52.772957 -120.929051) (xy 52.751068 -120.935124) (xy 52.742084 -120.9421)
			(xy 52.7177 -120.963182) (xy 52.709291 -120.971116) (xy 52.700015 -120.992263) (xy 52.69992 -121.003822)
			(xy 52.700428 -121.022618) (xy 52.700428 -121.862452) (xy 64.212442 -121.862452) (xy 64.212442 -121.807948)
			(xy 64.220198 -121.753997) (xy 64.235553 -121.7017) (xy 64.258194 -121.65212) (xy 64.287661 -121.606267)
			(xy 64.323352 -121.565074) (xy 64.364543 -121.529379) (xy 64.410394 -121.499909) (xy 64.459972 -121.477264)
			(xy 64.512268 -121.461905) (xy 64.566218 -121.454144) (xy 64.59347 -121.453656) (xy 64.610582 -121.453846)
			(xy 64.644669 -121.456899) (xy 64.661542 -121.459752) (xy 64.672833 -121.461118) (xy 64.694723 -121.455045)
			(xy 64.703706 -121.448068) (xy 64.72809 -121.42724) (xy 64.736538 -121.41928) (xy 64.745653 -121.397955)
			(xy 64.745616 -121.386346) (xy 64.745108 -121.367296) (xy 64.745108 -120.503696) (xy 64.745616 -120.483884)
			(xy 64.745601 -120.47229) (xy 64.736472 -120.451001) (xy 64.72809 -120.44299) (xy 64.703706 -120.421908)
			(xy 64.694705 -120.414831) (xy 64.672624 -120.408873) (xy 64.661288 -120.410478) (xy 64.64448 -120.413341)
			(xy 64.610519 -120.416393) (xy 64.59347 -120.416574) (xy 64.566218 -120.416154) (xy 64.512268 -120.408393)
			(xy 64.459973 -120.393034) (xy 64.410395 -120.370389) (xy 64.364544 -120.34092) (xy 64.323354 -120.305225)
			(xy 64.287662 -120.264032) (xy 64.258196 -120.218179) (xy 64.235555 -120.168599) (xy 64.2202 -120.116302)
			(xy 64.212444 -120.062352) (xy 64.212444 -120.007848) (xy 64.2202 -119.953898) (xy 64.235555 -119.901601)
			(xy 64.258196 -119.852021) (xy 64.287662 -119.806168) (xy 64.323354 -119.764975) (xy 64.364544 -119.72928)
			(xy 64.410395 -119.699811) (xy 64.459973 -119.677166) (xy 64.512268 -119.661807) (xy 64.566218 -119.654046)
			(xy 64.59347 -119.653558) (xy 64.620477 -119.654045) (xy 64.673953 -119.661647) (xy 64.725822 -119.676717)
			(xy 64.775046 -119.698955) (xy 64.82064 -119.727914) (xy 64.861693 -119.763016) (xy 64.897383 -119.803559)
			(xy 64.926996 -119.848731) (xy 64.949941 -119.89763) (xy 64.965757 -119.949276) (xy 64.970406 -119.975884)
			(xy 64.97193 -119.986552) (xy 64.98336 -120.004332) (xy 65.054734 -120.05183) (xy 65.063664 -120.057177)
			(xy 65.084127 -120.060853) (xy 65.094358 -120.058942) (xy 65.09512 -120.058942) (xy 65.121696 -120.05289)
			(xy 65.175816 -120.046397) (xy 65.20307 -120.045988) (xy 65.230388 -120.046373) (xy 65.284637 -120.052869)
			(xy 65.311274 -120.058942) (xy 65.311782 -120.058942) (xy 65.322011 -120.060811) (xy 65.342458 -120.057129)
			(xy 65.351406 -120.05183) (xy 65.42278 -120.004332) (xy 65.43421 -119.986552) (xy 65.435734 -119.975884)
			(xy 65.440357 -119.949273) (xy 65.456191 -119.897633) (xy 65.479149 -119.848742) (xy 65.50877 -119.803576)
			(xy 65.544464 -119.763038) (xy 65.585516 -119.727937) (xy 65.631108 -119.698975) (xy 65.680327 -119.676731)
			(xy 65.732191 -119.661648) (xy 65.785664 -119.654028) (xy 65.81267 -119.653558) (xy 65.84004 -119.654028)
			(xy 65.89422 -119.661842) (xy 65.946723 -119.67733) (xy 65.99647 -119.700171) (xy 66.042437 -119.729896)
			(xy 66.063368 -119.747538) (xy 66.063622 -119.747792) (xy 66.070699 -119.753393) (xy 66.087623 -119.759631)
			(xy 66.096642 -119.759984) (xy 66.163698 -119.759984) (xy 66.172715 -119.75963) (xy 66.189632 -119.753381)
			(xy 66.196718 -119.747792) (xy 66.196718 -119.747538) (xy 66.196972 -119.747538) (xy 66.217909 -119.729904)
			(xy 66.26388 -119.700191) (xy 66.313626 -119.677353) (xy 66.366126 -119.661861) (xy 66.420301 -119.654032)
			(xy 66.44767 -119.653558) (xy 66.464782 -119.653748) (xy 66.498869 -119.656801) (xy 66.515742 -119.659654)
			(xy 66.527033 -119.661019) (xy 66.548923 -119.654947) (xy 66.557906 -119.64797) (xy 66.58229 -119.627142)
			(xy 66.590737 -119.619181) (xy 66.599852 -119.597857) (xy 66.599816 -119.586248) (xy 66.599308 -119.567198)
			(xy 66.599308 -118.703598) (xy 66.599816 -118.683786) (xy 66.5998 -118.672192) (xy 66.590672 -118.650903)
			(xy 66.58229 -118.642892) (xy 66.557906 -118.62181) (xy 66.548912 -118.614724) (xy 66.526825 -118.608775)
			(xy 66.515488 -118.61038) (xy 66.49868 -118.613243) (xy 66.464719 -118.616295) (xy 66.44767 -118.616476)
			(xy 66.420418 -118.616052) (xy 66.366469 -118.608291) (xy 66.314173 -118.592932) (xy 66.264596 -118.570288)
			(xy 66.218745 -118.540818) (xy 66.177555 -118.505124) (xy 66.141864 -118.463931) (xy 66.112398 -118.418078)
			(xy 66.089757 -118.368499) (xy 66.074402 -118.316202) (xy 66.066646 -118.262252) (xy 66.066646 -118.207748)
			(xy 66.074402 -118.153798) (xy 66.089757 -118.101501) (xy 66.112398 -118.051922) (xy 66.141864 -118.006069)
			(xy 66.177555 -117.964876) (xy 66.218745 -117.929182) (xy 66.264596 -117.899712) (xy 66.314173 -117.877068)
			(xy 66.366469 -117.861709) (xy 66.420418 -117.853948) (xy 66.44767 -117.85346) (xy 66.474677 -117.853945)
			(xy 66.528153 -117.861547) (xy 66.580022 -117.876618) (xy 66.629247 -117.898855) (xy 66.674841 -117.927815)
			(xy 66.715894 -117.962917) (xy 66.751584 -118.00346) (xy 66.781197 -118.048633) (xy 66.804141 -118.097531)
			(xy 66.819957 -118.149178) (xy 66.824606 -118.175786) (xy 66.82613 -118.186454) (xy 66.83756 -118.204234)
			(xy 66.908934 -118.251732) (xy 66.917864 -118.25708) (xy 66.938327 -118.260755) (xy 66.948558 -118.258844)
			(xy 66.94932 -118.258844) (xy 66.97589 -118.25273) (xy 67.03001 -118.246107) (xy 67.05727 -118.245636)
			(xy 67.084595 -118.246086) (xy 67.138843 -118.252711) (xy 67.165474 -118.258844) (xy 67.165982 -118.258844)
			(xy 67.17621 -118.260729) (xy 67.196661 -118.25704) (xy 67.205606 -118.251732) (xy 67.27698 -118.204234)
			(xy 67.28841 -118.186454) (xy 67.289934 -118.175786) (xy 67.294302 -118.150547) (xy 67.308968 -118.101468)
			(xy 67.330071 -118.054794) (xy 67.35723 -118.011364) (xy 67.389957 -117.97196) (xy 67.427663 -117.93729)
			(xy 67.44843 -117.922294) (xy 67.455282 -117.917048) (xy 67.465323 -117.903028) (xy 67.47015 -117.886472)
			(xy 67.47002 -117.877844) (xy 67.464686 -117.778276) (xy 67.450716 -117.756178) (xy 67.439032 -117.749828)
			(xy 67.413711 -117.735312) (xy 67.367377 -117.699825) (xy 67.326988 -117.657697) (xy 67.293486 -117.609909)
			(xy 67.267653 -117.557576) (xy 67.25009 -117.501919) (xy 67.241209 -117.444237) (xy 67.240658 -117.415056)
			(xy 67.241144 -117.387805) (xy 67.2489 -117.333857) (xy 67.264255 -117.281562) (xy 67.286897 -117.231985)
			(xy 67.316363 -117.186135) (xy 67.352054 -117.144944) (xy 67.393245 -117.109253) (xy 67.439095 -117.079787)
			(xy 67.488672 -117.057145) (xy 67.540967 -117.04179) (xy 67.594915 -117.034034) (xy 67.649417 -117.034034)
			(xy 67.703365 -117.04179) (xy 67.75566 -117.057145) (xy 67.805237 -117.079787) (xy 67.851087 -117.109253)
			(xy 67.892278 -117.144944) (xy 67.927969 -117.186135) (xy 67.957435 -117.231985) (xy 67.980077 -117.281562)
			(xy 67.995432 -117.333857) (xy 68.003188 -117.387805) (xy 68.003674 -117.415056) (xy 68.003261 -117.441254)
			(xy 67.99609 -117.493158) (xy 67.981879 -117.543591) (xy 67.960893 -117.591601) (xy 67.93353 -117.636286)
			(xy 67.900305 -117.676801) (xy 67.861843 -117.712384) (xy 67.840606 -117.72773) (xy 67.833748 -117.732971)
			(xy 67.823705 -117.746992) (xy 67.818882 -117.763551) (xy 67.819016 -117.77218) (xy 67.82435 -117.871748)
			(xy 67.83832 -117.893846) (xy 67.850004 -117.900196) (xy 67.875343 -117.914681) (xy 67.921676 -117.950174)
			(xy 67.962062 -117.992308) (xy 67.995562 -118.040102) (xy 68.021392 -118.092439) (xy 68.038951 -118.1481)
			(xy 68.047829 -118.205786) (xy 68.048378 -118.234968) (xy 68.047915 -118.262221) (xy 68.040161 -118.316174)
			(xy 68.024808 -118.368474) (xy 68.023719 -118.370858) (xy 69.266562 -118.370858) (xy 69.26709 -118.342075)
			(xy 69.275744 -118.285164) (xy 69.292849 -118.230199) (xy 69.318018 -118.178427) (xy 69.350679 -118.131024)
			(xy 69.390091 -118.089065) (xy 69.435358 -118.053503) (xy 69.485454 -118.025146) (xy 69.539242 -118.004635)
			(xy 69.595501 -117.992439) (xy 69.624194 -117.990112) (xy 69.636132 -117.98935) (xy 69.65696 -117.977412)
			(xy 69.714618 -117.88902) (xy 69.717412 -117.865144) (xy 69.713094 -117.853968) (xy 69.702473 -117.822573)
			(xy 69.69097 -117.757309) (xy 69.690234 -117.724174) (xy 69.690234 -117.723666) (xy 69.69072 -117.696415)
			(xy 69.698476 -117.642467) (xy 69.713831 -117.590172) (xy 69.736473 -117.540595) (xy 69.765939 -117.494745)
			(xy 69.80163 -117.453554) (xy 69.842821 -117.417863) (xy 69.888671 -117.388397) (xy 69.938248 -117.365755)
			(xy 69.990543 -117.3504) (xy 70.044491 -117.342644) (xy 70.098993 -117.342644) (xy 70.152941 -117.3504)
			(xy 70.205236 -117.365755) (xy 70.254813 -117.388397) (xy 70.300663 -117.417863) (xy 70.341854 -117.453554)
			(xy 70.377545 -117.494745) (xy 70.407011 -117.540595) (xy 70.429653 -117.590172) (xy 70.445008 -117.642467)
			(xy 70.452764 -117.696415) (xy 70.45325 -117.723666) (xy 70.452733 -117.752449) (xy 70.444076 -117.80936)
			(xy 70.426968 -117.864325) (xy 70.401797 -117.916096) (xy 70.369135 -117.963498) (xy 70.329722 -118.005457)
			(xy 70.284454 -118.041018) (xy 70.234358 -118.069376) (xy 70.18057 -118.089887) (xy 70.124311 -118.102085)
			(xy 70.095618 -118.104412) (xy 70.08368 -118.105174) (xy 70.062852 -118.117112) (xy 70.005194 -118.205504)
			(xy 70.0024 -118.22938) (xy 70.004559 -118.234968) (xy 71.885046 -118.234968) (xy 71.889117 -118.179346)
			(xy 71.901243 -118.124909) (xy 71.921166 -118.072818) (xy 71.948462 -118.024183) (xy 71.982548 -117.98004)
			(xy 72.022697 -117.941331) (xy 72.068055 -117.90888) (xy 72.117655 -117.883379) (xy 72.170439 -117.865372)
			(xy 72.225282 -117.855242) (xy 72.281016 -117.853205) (xy 72.336453 -117.859305) (xy 72.39041 -117.873411)
			(xy 72.441739 -117.895223) (xy 72.489345 -117.924277) (xy 72.532213 -117.959952) (xy 72.56943 -118.001489)
			(xy 72.600203 -118.048002) (xy 72.623875 -118.098499) (xy 72.639943 -118.151906) (xy 72.648063 -118.207082)
			(xy 72.648572 -118.234968) (xy 72.648074 -118.262252) (xy 73.867246 -118.262252) (xy 73.867246 -118.207748)
			(xy 73.875002 -118.153799) (xy 73.890357 -118.101503) (xy 73.912997 -118.051924) (xy 73.942462 -118.006071)
			(xy 73.978153 -117.964879) (xy 74.019342 -117.929184) (xy 74.065192 -117.899714) (xy 74.114769 -117.877069)
			(xy 74.167064 -117.86171) (xy 74.221012 -117.853948) (xy 74.248264 -117.85346) (xy 74.248772 -117.85346)
			(xy 74.273638 -117.85389) (xy 74.322944 -117.860381) (xy 74.34707 -117.866414) (xy 74.347324 -117.866414)
			(xy 74.358887 -117.868956) (xy 74.382073 -117.864313) (xy 74.391774 -117.857524) (xy 74.455528 -117.807486)
			(xy 74.464419 -117.799781) (xy 74.474606 -117.778602) (xy 74.475086 -117.766846) (xy 74.475086 -117.766592)
			(xy 74.474832 -117.758718) (xy 74.474832 -116.895118) (xy 74.476102 -116.862098) (xy 74.476451 -116.853507)
			(xy 74.471983 -116.836913) (xy 74.462264 -116.82274) (xy 74.455528 -116.817394) (xy 74.430636 -116.798852)
			(xy 74.423653 -116.794082) (xy 74.40753 -116.78902) (xy 74.390638 -116.789532) (xy 74.38263 -116.792248)
			(xy 74.350205 -116.803603) (xy 74.282612 -116.81586) (xy 74.248264 -116.816632) (xy 74.221016 -116.816095)
			(xy 74.167076 -116.808335) (xy 74.114789 -116.792978) (xy 74.065219 -116.770336) (xy 74.019376 -116.740871)
			(xy 73.978193 -116.705182) (xy 73.942508 -116.663995) (xy 73.913047 -116.618149) (xy 73.89041 -116.568578)
			(xy 73.875057 -116.516289) (xy 73.867302 -116.462348) (xy 73.867302 -116.407852) (xy 73.875057 -116.353911)
			(xy 73.89041 -116.301622) (xy 73.913047 -116.252051) (xy 73.942508 -116.206205) (xy 73.978193 -116.165018)
			(xy 74.019376 -116.129329) (xy 74.065219 -116.099864) (xy 74.114789 -116.077222) (xy 74.167076 -116.061865)
			(xy 74.221016 -116.054105) (xy 74.248264 -116.053616) (xy 74.275841 -116.054157) (xy 74.33042 -116.062108)
			(xy 74.383286 -116.077835) (xy 74.433336 -116.101011) (xy 74.479527 -116.131151) (xy 74.520897 -116.167629)
			(xy 74.556583 -116.209683) (xy 74.585842 -116.256438) (xy 74.608063 -116.306919) (xy 74.622785 -116.360073)
			(xy 74.626724 -116.387372) (xy 74.628248 -116.399056) (xy 74.639793 -116.416836) (xy 87.260682 -116.416836)
			(xy 87.264753 -116.361214) (xy 87.276879 -116.306777) (xy 87.296802 -116.254686) (xy 87.324098 -116.206051)
			(xy 87.358184 -116.161908) (xy 87.398333 -116.123199) (xy 87.443691 -116.090748) (xy 87.493291 -116.065247)
			(xy 87.546075 -116.04724) (xy 87.600918 -116.03711) (xy 87.656652 -116.035073) (xy 87.712089 -116.041173)
			(xy 87.766046 -116.055279) (xy 87.817375 -116.077091) (xy 87.864981 -116.106145) (xy 87.907849 -116.14182)
			(xy 87.945066 -116.183357) (xy 87.975839 -116.22987) (xy 87.999511 -116.280367) (xy 88.015579 -116.333774)
			(xy 88.023699 -116.38895) (xy 88.024208 -116.416836) (xy 88.023699 -116.444722) (xy 88.015579 -116.499898)
			(xy 87.999511 -116.553305) (xy 87.975839 -116.603802) (xy 87.945066 -116.650315) (xy 87.92759 -116.66982)
			(xy 89.3732 -116.66982) (xy 89.377271 -116.614198) (xy 89.389397 -116.559761) (xy 89.40932 -116.50767)
			(xy 89.436616 -116.459035) (xy 89.470702 -116.414892) (xy 89.510851 -116.376183) (xy 89.556209 -116.343732)
			(xy 89.605809 -116.318231) (xy 89.658593 -116.300224) (xy 89.713436 -116.290094) (xy 89.76917 -116.288057)
			(xy 89.824607 -116.294157) (xy 89.878564 -116.308263) (xy 89.929893 -116.330075) (xy 89.977499 -116.359129)
			(xy 90.020367 -116.394804) (xy 90.034418 -116.410486) (xy 95.147128 -116.410486) (xy 95.151199 -116.354864)
			(xy 95.163325 -116.300427) (xy 95.183248 -116.248336) (xy 95.210544 -116.199701) (xy 95.24463 -116.155558)
			(xy 95.284779 -116.116849) (xy 95.330137 -116.084398) (xy 95.379737 -116.058897) (xy 95.432521 -116.04089)
			(xy 95.487364 -116.03076) (xy 95.543098 -116.028723) (xy 95.598535 -116.034823) (xy 95.652492 -116.048929)
			(xy 95.703821 -116.070741) (xy 95.751427 -116.099795) (xy 95.794295 -116.13547) (xy 95.831512 -116.177007)
			(xy 95.862285 -116.22352) (xy 95.885957 -116.274017) (xy 95.902025 -116.327424) (xy 95.910145 -116.3826)
			(xy 95.910654 -116.410486) (xy 95.910145 -116.438372) (xy 95.902025 -116.493548) (xy 95.885957 -116.546955)
			(xy 95.862285 -116.597452) (xy 95.841294 -116.62918) (xy 105.137964 -116.62918) (xy 105.142035 -116.573558)
			(xy 105.154161 -116.519121) (xy 105.174084 -116.46703) (xy 105.20138 -116.418395) (xy 105.235466 -116.374252)
			(xy 105.275615 -116.335543) (xy 105.320973 -116.303092) (xy 105.370573 -116.277591) (xy 105.423357 -116.259584)
			(xy 105.4782 -116.249454) (xy 105.533934 -116.247417) (xy 105.589371 -116.253517) (xy 105.643328 -116.267623)
			(xy 105.694657 -116.289435) (xy 105.742263 -116.318489) (xy 105.785131 -116.354164) (xy 105.822348 -116.395701)
			(xy 105.853121 -116.442214) (xy 105.876793 -116.492711) (xy 105.892861 -116.546118) (xy 105.900981 -116.601294)
			(xy 105.90149 -116.62918) (xy 105.900981 -116.657066) (xy 105.892861 -116.712242) (xy 105.876793 -116.765649)
			(xy 105.853121 -116.816146) (xy 105.822348 -116.862659) (xy 105.785131 -116.904196) (xy 105.742263 -116.939871)
			(xy 105.694657 -116.968925) (xy 105.643328 -116.990737) (xy 105.589371 -117.004843) (xy 105.533934 -117.010943)
			(xy 105.4782 -117.008906) (xy 105.423357 -116.998776) (xy 105.370573 -116.980769) (xy 105.320973 -116.955268)
			(xy 105.275615 -116.922817) (xy 105.235466 -116.884108) (xy 105.20138 -116.839965) (xy 105.174084 -116.79133)
			(xy 105.154161 -116.739239) (xy 105.142035 -116.684802) (xy 105.137964 -116.62918) (xy 95.841294 -116.62918)
			(xy 95.831512 -116.643965) (xy 95.794295 -116.685502) (xy 95.751427 -116.721177) (xy 95.703821 -116.750231)
			(xy 95.652492 -116.772043) (xy 95.598535 -116.786149) (xy 95.543098 -116.792249) (xy 95.487364 -116.790212)
			(xy 95.432521 -116.780082) (xy 95.379737 -116.762075) (xy 95.330137 -116.736574) (xy 95.284779 -116.704123)
			(xy 95.24463 -116.665414) (xy 95.210544 -116.621271) (xy 95.183248 -116.572636) (xy 95.163325 -116.520545)
			(xy 95.151199 -116.466108) (xy 95.147128 -116.410486) (xy 90.034418 -116.410486) (xy 90.057584 -116.436341)
			(xy 90.088357 -116.482854) (xy 90.112029 -116.533351) (xy 90.128097 -116.586758) (xy 90.136217 -116.641934)
			(xy 90.136726 -116.66982) (xy 90.136217 -116.697706) (xy 90.128097 -116.752882) (xy 90.112029 -116.806289)
			(xy 90.088357 -116.856786) (xy 90.057584 -116.903299) (xy 90.020367 -116.944836) (xy 89.977499 -116.980511)
			(xy 89.929893 -117.009565) (xy 89.878564 -117.031377) (xy 89.824607 -117.045483) (xy 89.76917 -117.051583)
			(xy 89.713436 -117.049546) (xy 89.658593 -117.039416) (xy 89.605809 -117.021409) (xy 89.556209 -116.995908)
			(xy 89.510851 -116.963457) (xy 89.470702 -116.924748) (xy 89.436616 -116.880605) (xy 89.40932 -116.83197)
			(xy 89.389397 -116.779879) (xy 89.377271 -116.725442) (xy 89.3732 -116.66982) (xy 87.92759 -116.66982)
			(xy 87.907849 -116.691852) (xy 87.864981 -116.727527) (xy 87.817375 -116.756581) (xy 87.766046 -116.778393)
			(xy 87.712089 -116.792499) (xy 87.656652 -116.798599) (xy 87.600918 -116.796562) (xy 87.546075 -116.786432)
			(xy 87.493291 -116.768425) (xy 87.443691 -116.742924) (xy 87.398333 -116.710473) (xy 87.358184 -116.671764)
			(xy 87.324098 -116.627621) (xy 87.296802 -116.578986) (xy 87.276879 -116.526895) (xy 87.264753 -116.472458)
			(xy 87.260682 -116.416836) (xy 74.639793 -116.416836) (xy 74.640948 -116.418614) (xy 74.73061 -116.4717)
			(xy 74.753724 -116.473478) (xy 74.7649 -116.46916) (xy 74.791723 -116.459043) (xy 74.847255 -116.444804)
			(xy 74.90413 -116.437615) (xy 74.932794 -116.437156) (xy 74.96278 -116.437613) (xy 75.02224 -116.44544)
			(xy 75.080169 -116.460962) (xy 75.135576 -116.483913) (xy 75.187514 -116.513899) (xy 75.235093 -116.550408)
			(xy 75.277499 -116.592816) (xy 75.314008 -116.640396) (xy 75.343993 -116.692334) (xy 75.366942 -116.747742)
			(xy 75.382462 -116.805672) (xy 75.390288 -116.865132) (xy 75.390756 -116.895118) (xy 75.390756 -117.390451)
			(xy 90.742495 -117.390451) (xy 90.742495 -117.335949) (xy 90.750252 -117.282003) (xy 90.765607 -117.229709)
			(xy 90.788248 -117.180133) (xy 90.817715 -117.134284) (xy 90.853406 -117.093095) (xy 90.894597 -117.057405)
			(xy 90.940447 -117.027941) (xy 90.990024 -117.005301) (xy 91.042318 -116.989948) (xy 91.096265 -116.982194)
			(xy 91.123516 -116.981732) (xy 91.152431 -116.982299) (xy 91.209601 -116.991016) (xy 91.264799 -117.008264)
			(xy 91.316761 -117.033646) (xy 91.364296 -117.066582) (xy 91.406315 -117.106316) (xy 91.424506 -117.128798)
			(xy 91.432121 -117.137598) (xy 91.453016 -117.147786) (xy 91.464638 -117.148356) (xy 91.544394 -117.148356)
			(xy 91.556026 -117.147815) (xy 91.576937 -117.137629) (xy 91.584526 -117.128798) (xy 91.602702 -117.106302)
			(xy 91.644725 -117.066567) (xy 91.692263 -117.03363) (xy 91.744227 -117.008244) (xy 91.799427 -116.99099)
			(xy 91.856599 -116.982265) (xy 91.885516 -116.981732) (xy 91.912769 -116.982139) (xy 91.966721 -116.989898)
			(xy 92.019019 -117.005256) (xy 92.0686 -117.027901) (xy 92.114453 -117.057371) (xy 92.155646 -117.093066)
			(xy 92.163938 -117.102636) (xy 92.979238 -117.102636) (xy 92.983309 -117.047014) (xy 92.995435 -116.992577)
			(xy 93.015358 -116.940486) (xy 93.042654 -116.891851) (xy 93.07674 -116.847708) (xy 93.116889 -116.808999)
			(xy 93.162247 -116.776548) (xy 93.211847 -116.751047) (xy 93.264631 -116.73304) (xy 93.319474 -116.72291)
			(xy 93.375208 -116.720873) (xy 93.430645 -116.726973) (xy 93.484602 -116.741079) (xy 93.535931 -116.762891)
			(xy 93.583537 -116.791945) (xy 93.626405 -116.82762) (xy 93.663622 -116.869157) (xy 93.694395 -116.91567)
			(xy 93.718067 -116.966167) (xy 93.734135 -117.019574) (xy 93.742255 -117.07475) (xy 93.742764 -117.102636)
			(xy 93.742255 -117.130522) (xy 93.734135 -117.185698) (xy 93.718067 -117.239105) (xy 93.694395 -117.289602)
			(xy 93.663622 -117.336115) (xy 93.626405 -117.377652) (xy 93.583537 -117.413327) (xy 93.561976 -117.426486)
			(xy 95.147128 -117.426486) (xy 95.151199 -117.370864) (xy 95.163325 -117.316427) (xy 95.183248 -117.264336)
			(xy 95.210544 -117.215701) (xy 95.24463 -117.171558) (xy 95.284779 -117.132849) (xy 95.330137 -117.100398)
			(xy 95.379737 -117.074897) (xy 95.432521 -117.05689) (xy 95.487364 -117.04676) (xy 95.543098 -117.044723)
			(xy 95.598535 -117.050823) (xy 95.652492 -117.064929) (xy 95.703821 -117.086741) (xy 95.751427 -117.115795)
			(xy 95.794295 -117.15147) (xy 95.831512 -117.193007) (xy 95.850018 -117.220979) (xy 107.73981 -117.220979)
			(xy 107.747563 -117.167021) (xy 107.762917 -117.114715) (xy 107.785558 -117.065127) (xy 107.815025 -117.019266)
			(xy 107.85072 -116.978065) (xy 107.891915 -116.942364) (xy 107.937771 -116.912888) (xy 107.987355 -116.890239)
			(xy 108.039658 -116.874877) (xy 108.093615 -116.867115) (xy 108.148128 -116.867111) (xy 108.202086 -116.874865)
			(xy 108.254391 -116.890219) (xy 108.303979 -116.912861) (xy 108.34984 -116.942329) (xy 108.39104 -116.978024)
			(xy 108.42674 -117.01922) (xy 108.456215 -117.065077) (xy 108.478863 -117.114661) (xy 108.494224 -117.166965)
			(xy 108.501985 -117.220922) (xy 108.50245 -117.248178) (xy 108.50245 -117.24894) (xy 108.501954 -117.276119)
			(xy 108.494171 -117.329919) (xy 108.486956 -117.356128) (xy 108.483146 -117.368828) (xy 108.488734 -117.394228)
			(xy 108.562394 -117.478302) (xy 108.586524 -117.487446) (xy 108.599478 -117.485414) (xy 108.613615 -117.483393)
			(xy 108.642094 -117.481234) (xy 108.656374 -117.481096) (xy 108.656882 -117.481096) (xy 108.66882 -117.48135)
			(xy 108.669074 -117.48135) (xy 108.681031 -117.481012) (xy 108.702632 -117.470821) (xy 108.710476 -117.461792)
			(xy 108.761022 -117.397022) (xy 108.767826 -117.387258) (xy 108.772458 -117.363944) (xy 108.769912 -117.352318)
			(xy 108.769912 -117.35181) (xy 108.763178 -117.326431) (xy 108.755909 -117.27443) (xy 108.755434 -117.248178)
			(xy 108.75592 -117.220927) (xy 108.763676 -117.166979) (xy 108.779031 -117.114684) (xy 108.801673 -117.065107)
			(xy 108.831139 -117.019257) (xy 108.86683 -116.978066) (xy 108.908021 -116.942375) (xy 108.953871 -116.912909)
			(xy 109.003448 -116.890267) (xy 109.055743 -116.874912) (xy 109.109691 -116.867156) (xy 109.164193 -116.867156)
			(xy 109.218141 -116.874912) (xy 109.270436 -116.890267) (xy 109.320013 -116.912909) (xy 109.365863 -116.942375)
			(xy 109.407054 -116.978066) (xy 109.442745 -117.019257) (xy 109.472211 -117.065107) (xy 109.494853 -117.114684)
			(xy 109.510208 -117.166979) (xy 109.517964 -117.220927) (xy 109.51845 -117.248178) (xy 109.770924 -117.248178)
			(xy 109.774995 -117.192556) (xy 109.787121 -117.138119) (xy 109.807044 -117.086028) (xy 109.83434 -117.037393)
			(xy 109.868426 -116.99325) (xy 109.908575 -116.954541) (xy 109.953933 -116.92209) (xy 110.003533 -116.896589)
			(xy 110.056317 -116.878582) (xy 110.11116 -116.868452) (xy 110.166894 -116.866415) (xy 110.222331 -116.872515)
			(xy 110.276288 -116.886621) (xy 110.327617 -116.908433) (xy 110.375223 -116.937487) (xy 110.418091 -116.973162)
			(xy 110.455308 -117.014699) (xy 110.486081 -117.061212) (xy 110.509753 -117.111709) (xy 110.525821 -117.165116)
			(xy 110.533941 -117.220292) (xy 110.53445 -117.248178) (xy 110.533941 -117.276064) (xy 110.525821 -117.33124)
			(xy 110.523759 -117.338094) (xy 114.818158 -117.338094) (xy 114.822229 -117.282472) (xy 114.834355 -117.228035)
			(xy 114.854278 -117.175944) (xy 114.881574 -117.127309) (xy 114.91566 -117.083166) (xy 114.955809 -117.044457)
			(xy 115.001167 -117.012006) (xy 115.050767 -116.986505) (xy 115.103551 -116.968498) (xy 115.158394 -116.958368)
			(xy 115.214128 -116.956331) (xy 115.269565 -116.962431) (xy 115.323522 -116.976537) (xy 115.326386 -116.977754)
			(xy 116.998945 -116.977754) (xy 116.998945 -116.923246) (xy 117.006702 -116.869293) (xy 117.022059 -116.816994)
			(xy 117.044702 -116.767412) (xy 117.074171 -116.721558) (xy 117.109866 -116.680364) (xy 117.151061 -116.644669)
			(xy 117.196916 -116.6152) (xy 117.246498 -116.592557) (xy 117.298797 -116.577201) (xy 117.35275 -116.569445)
			(xy 117.380004 -116.568982) (xy 117.408923 -116.569466) (xy 117.466097 -116.578198) (xy 117.521298 -116.595461)
			(xy 117.57326 -116.620859) (xy 117.620793 -116.65381) (xy 117.662806 -116.693559) (xy 117.680994 -116.716048)
			(xy 117.688605 -116.72485) (xy 117.709503 -116.735035) (xy 117.721126 -116.735606) (xy 117.800882 -116.735606)
			(xy 117.81251 -116.73504) (xy 117.83342 -116.72487) (xy 117.841014 -116.716048) (xy 117.859184 -116.693547)
			(xy 117.90121 -116.653815) (xy 117.948749 -116.62088) (xy 118.000715 -116.595495) (xy 118.055915 -116.578242)
			(xy 118.113087 -116.569516) (xy 118.142004 -116.568982) (xy 118.169254 -116.569489) (xy 118.2232 -116.577245)
			(xy 118.275493 -116.5926) (xy 118.325068 -116.615241) (xy 118.370917 -116.644707) (xy 118.412106 -116.680397)
			(xy 118.447796 -116.721586) (xy 118.477261 -116.767435) (xy 118.499901 -116.817011) (xy 118.515256 -116.869304)
			(xy 118.523012 -116.92325) (xy 118.523012 -116.97775) (xy 118.515256 -117.031696) (xy 118.499901 -117.083989)
			(xy 118.477261 -117.133565) (xy 118.447796 -117.179414) (xy 118.412106 -117.220603) (xy 118.370917 -117.256293)
			(xy 118.325068 -117.285759) (xy 118.275493 -117.3084) (xy 118.2232 -117.323755) (xy 118.197667 -117.327426)
			(xy 125.787148 -117.327426) (xy 125.791219 -117.271804) (xy 125.803345 -117.217367) (xy 125.823268 -117.165276)
			(xy 125.850564 -117.116641) (xy 125.88465 -117.072498) (xy 125.924799 -117.033789) (xy 125.970157 -117.001338)
			(xy 126.019757 -116.975837) (xy 126.072541 -116.95783) (xy 126.127384 -116.9477) (xy 126.183118 -116.945663)
			(xy 126.238555 -116.951763) (xy 126.292512 -116.965869) (xy 126.343841 -116.987681) (xy 126.391447 -117.016735)
			(xy 126.434315 -117.05241) (xy 126.471532 -117.093947) (xy 126.502305 -117.14046) (xy 126.525977 -117.190957)
			(xy 126.542045 -117.244364) (xy 126.550165 -117.29954) (xy 126.550674 -117.327426) (xy 126.550165 -117.355312)
			(xy 126.542045 -117.410488) (xy 126.525977 -117.463895) (xy 126.502305 -117.514392) (xy 126.471532 -117.560905)
			(xy 126.434315 -117.602442) (xy 126.391447 -117.638117) (xy 126.343841 -117.667171) (xy 126.292512 -117.688983)
			(xy 126.238555 -117.703089) (xy 126.183118 -117.709189) (xy 126.127384 -117.707152) (xy 126.072541 -117.697022)
			(xy 126.019757 -117.679015) (xy 125.970157 -117.653514) (xy 125.924799 -117.621063) (xy 125.88465 -117.582354)
			(xy 125.850564 -117.538211) (xy 125.823268 -117.489576) (xy 125.803345 -117.437485) (xy 125.791219 -117.383048)
			(xy 125.787148 -117.327426) (xy 118.197667 -117.327426) (xy 118.169254 -117.331511) (xy 118.142004 -117.331998)
			(xy 118.113087 -117.331477) (xy 118.055916 -117.322749) (xy 118.000717 -117.305491) (xy 117.948756 -117.2801)
			(xy 117.901222 -117.247157) (xy 117.859204 -117.207417) (xy 117.841014 -117.184932) (xy 117.833403 -117.17613)
			(xy 117.812505 -117.165946) (xy 117.800882 -117.165374) (xy 117.721126 -117.165374) (xy 117.709494 -117.165916)
			(xy 117.688582 -117.1761) (xy 117.680994 -117.184932) (xy 117.662814 -117.207425) (xy 117.620791 -117.247158)
			(xy 117.573254 -117.280095) (xy 117.52129 -117.305482) (xy 117.466091 -117.322736) (xy 117.408921 -117.331464)
			(xy 117.380004 -117.331998) (xy 117.35275 -117.331555) (xy 117.298797 -117.323799) (xy 117.246498 -117.308443)
			(xy 117.196916 -117.2858) (xy 117.151061 -117.256331) (xy 117.109866 -117.220636) (xy 117.074171 -117.179442)
			(xy 117.044702 -117.133588) (xy 117.022059 -117.084006) (xy 117.006702 -117.031707) (xy 116.998945 -116.977754)
			(xy 115.326386 -116.977754) (xy 115.374851 -116.998349) (xy 115.422457 -117.027403) (xy 115.465325 -117.063078)
			(xy 115.502542 -117.104615) (xy 115.533315 -117.151128) (xy 115.556987 -117.201625) (xy 115.573055 -117.255032)
			(xy 115.581175 -117.310208) (xy 115.581684 -117.338094) (xy 115.581175 -117.36598) (xy 115.573055 -117.421156)
			(xy 115.556987 -117.474563) (xy 115.533315 -117.52506) (xy 115.502542 -117.571573) (xy 115.465325 -117.61311)
			(xy 115.422457 -117.648785) (xy 115.374851 -117.677839) (xy 115.323522 -117.699651) (xy 115.269565 -117.713757)
			(xy 115.214128 -117.719857) (xy 115.158394 -117.71782) (xy 115.103551 -117.70769) (xy 115.050767 -117.689683)
			(xy 115.001167 -117.664182) (xy 114.955809 -117.631731) (xy 114.91566 -117.593022) (xy 114.881574 -117.548879)
			(xy 114.854278 -117.500244) (xy 114.834355 -117.448153) (xy 114.822229 -117.393716) (xy 114.818158 -117.338094)
			(xy 110.523759 -117.338094) (xy 110.509753 -117.384647) (xy 110.486081 -117.435144) (xy 110.455308 -117.481657)
			(xy 110.418091 -117.523194) (xy 110.375223 -117.558869) (xy 110.327617 -117.587923) (xy 110.276288 -117.609735)
			(xy 110.222331 -117.623841) (xy 110.166894 -117.629941) (xy 110.11116 -117.627904) (xy 110.056317 -117.617774)
			(xy 110.003533 -117.599767) (xy 109.953933 -117.574266) (xy 109.908575 -117.541815) (xy 109.868426 -117.503106)
			(xy 109.83434 -117.458963) (xy 109.807044 -117.410328) (xy 109.787121 -117.358237) (xy 109.774995 -117.3038)
			(xy 109.770924 -117.248178) (xy 109.51845 -117.248178) (xy 109.517902 -117.275415) (xy 109.510156 -117.329336)
			(xy 109.494819 -117.381607) (xy 109.472202 -117.431164) (xy 109.442766 -117.477) (xy 109.407108 -117.518183)
			(xy 109.365955 -117.553875) (xy 109.320144 -117.58335) (xy 109.270605 -117.606008) (xy 109.218347 -117.621389)
			(xy 109.164433 -117.62918) (xy 109.137196 -117.629686) (xy 109.136688 -117.629686) (xy 109.12475 -117.629432)
			(xy 109.124496 -117.629432) (xy 109.112538 -117.629759) (xy 109.090937 -117.639959) (xy 109.083094 -117.64899)
			(xy 109.032548 -117.71376) (xy 109.025752 -117.723528) (xy 109.023654 -117.73408) (xy 116.39626 -117.73408)
			(xy 116.400331 -117.678458) (xy 116.412457 -117.624021) (xy 116.43238 -117.57193) (xy 116.459676 -117.523295)
			(xy 116.493762 -117.479152) (xy 116.533911 -117.440443) (xy 116.579269 -117.407992) (xy 116.628869 -117.382491)
			(xy 116.681653 -117.364484) (xy 116.736496 -117.354354) (xy 116.79223 -117.352317) (xy 116.847667 -117.358417)
			(xy 116.901624 -117.372523) (xy 116.952953 -117.394335) (xy 117.000559 -117.423389) (xy 117.043427 -117.459064)
			(xy 117.080644 -117.500601) (xy 117.111417 -117.547114) (xy 117.135089 -117.597611) (xy 117.151157 -117.651018)
			(xy 117.159277 -117.706194) (xy 117.159786 -117.73408) (xy 117.159277 -117.761966) (xy 117.151157 -117.817142)
			(xy 117.135089 -117.870549) (xy 117.111417 -117.921046) (xy 117.080644 -117.967559) (xy 117.043427 -118.009096)
			(xy 117.021849 -118.027053) (xy 117.690342 -118.027053) (xy 117.690342 -117.972547) (xy 117.698099 -117.918594)
			(xy 117.713455 -117.866295) (xy 117.736098 -117.816714) (xy 117.765566 -117.77086) (xy 117.80126 -117.729666)
			(xy 117.842453 -117.693971) (xy 117.888307 -117.664502) (xy 117.937888 -117.641858) (xy 117.990187 -117.626501)
			(xy 118.044139 -117.618742) (xy 118.071392 -117.618256) (xy 118.10031 -117.618759) (xy 118.157483 -117.627488)
			(xy 118.212683 -117.644748) (xy 118.264645 -117.670142) (xy 118.312178 -117.703089) (xy 118.354193 -117.742834)
			(xy 118.372382 -117.765322) (xy 118.380003 -117.774115) (xy 118.400893 -117.784306) (xy 118.412514 -117.78488)
			(xy 118.49227 -117.78488) (xy 118.503899 -117.784316) (xy 118.524809 -117.774146) (xy 118.532402 -117.765322)
			(xy 118.550597 -117.742842) (xy 118.592616 -117.703106) (xy 118.640149 -117.670166) (xy 118.69211 -117.644776)
			(xy 118.747307 -117.62752) (xy 118.804476 -117.618791) (xy 118.833392 -117.618256) (xy 118.860636 -117.61873)
			(xy 118.91457 -117.626487) (xy 118.966851 -117.641843) (xy 119.016412 -117.664487) (xy 119.062245 -117.693955)
			(xy 119.103415 -117.729649) (xy 119.139084 -117.770841) (xy 119.154194 -117.793516) (xy 119.159066 -117.800522)
			(xy 119.172461 -117.811075) (xy 119.188592 -117.816608) (xy 119.19712 -117.816884) (xy 119.282464 -117.816884)
			(xy 119.290987 -117.8166) (xy 119.307101 -117.811037) (xy 119.320508 -117.80051) (xy 119.32539 -117.793516)
			(xy 119.340502 -117.770842) (xy 119.37617 -117.729648) (xy 119.41734 -117.693953) (xy 119.463172 -117.664482)
			(xy 119.512733 -117.641837) (xy 119.565013 -117.626479) (xy 119.618947 -117.61872) (xy 119.646192 -117.618256)
			(xy 119.673443 -117.618791) (xy 119.727389 -117.626546) (xy 119.779683 -117.6419) (xy 119.82926 -117.66454)
			(xy 119.875109 -117.694005) (xy 119.916299 -117.729695) (xy 119.95199 -117.770884) (xy 119.981456 -117.816733)
			(xy 120.004097 -117.866309) (xy 120.019452 -117.918603) (xy 120.027209 -117.972549) (xy 120.027209 -118.027051)
			(xy 120.019452 -118.080997) (xy 120.004097 -118.133291) (xy 119.981456 -118.182867) (xy 119.95199 -118.228716)
			(xy 119.916299 -118.269905) (xy 119.875109 -118.305595) (xy 119.82926 -118.33506) (xy 119.779683 -118.3577)
			(xy 119.727389 -118.373054) (xy 119.673443 -118.380809) (xy 119.646192 -118.381272) (xy 119.618948 -118.380797)
			(xy 119.565014 -118.373039) (xy 119.512735 -118.357682) (xy 119.463174 -118.335038) (xy 119.417341 -118.30557)
			(xy 119.376171 -118.269877) (xy 119.340501 -118.228686) (xy 119.32539 -118.206012) (xy 119.320547 -118.198984)
			(xy 119.307136 -118.188441) (xy 119.290996 -118.182916) (xy 119.282464 -118.182644) (xy 119.19712 -118.182644)
			(xy 119.188599 -118.182949) (xy 119.17249 -118.188508) (xy 119.15908 -118.199024) (xy 119.154194 -118.206012)
			(xy 119.139069 -118.228678) (xy 119.103406 -118.269874) (xy 119.062239 -118.305573) (xy 119.01641 -118.335046)
			(xy 118.96685 -118.357692) (xy 118.91457 -118.373051) (xy 118.860636 -118.380809) (xy 118.833392 -118.381272)
			(xy 118.804477 -118.380698) (xy 118.747308 -118.371982) (xy 118.69211 -118.354736) (xy 118.640148 -118.329355)
			(xy 118.592612 -118.29642) (xy 118.550594 -118.256687) (xy 118.532402 -118.234206) (xy 118.524783 -118.225411)
			(xy 118.503891 -118.21522) (xy 118.49227 -118.214648) (xy 118.412514 -118.214648) (xy 118.400882 -118.215193)
			(xy 118.379972 -118.225376) (xy 118.372382 -118.234206) (xy 118.354203 -118.256699) (xy 118.31218 -118.296434)
			(xy 118.264643 -118.329371) (xy 118.212679 -118.354758) (xy 118.15748 -118.372012) (xy 118.100309 -118.380738)
			(xy 118.071392 -118.381272) (xy 118.044139 -118.380858) (xy 117.990187 -118.373099) (xy 117.937888 -118.357742)
			(xy 117.888307 -118.335098) (xy 117.842453 -118.305629) (xy 117.80126 -118.269934) (xy 117.765566 -118.22874)
			(xy 117.736098 -118.182886) (xy 117.713455 -118.133305) (xy 117.698099 -118.081006) (xy 117.690342 -118.027053)
			(xy 117.021849 -118.027053) (xy 117.000559 -118.044771) (xy 116.952953 -118.073825) (xy 116.901624 -118.095637)
			(xy 116.847667 -118.109743) (xy 116.79223 -118.115843) (xy 116.736496 -118.113806) (xy 116.681653 -118.103676)
			(xy 116.628869 -118.085669) (xy 116.579269 -118.060168) (xy 116.533911 -118.027717) (xy 116.493762 -117.989008)
			(xy 116.459676 -117.944865) (xy 116.43238 -117.89623) (xy 116.412457 -117.844139) (xy 116.400331 -117.789702)
			(xy 116.39626 -117.73408) (xy 109.023654 -117.73408) (xy 109.021117 -117.746839) (xy 109.023658 -117.758464)
			(xy 109.023658 -117.758972) (xy 109.030408 -117.784347) (xy 109.037666 -117.836351) (xy 109.038136 -117.862604)
			(xy 109.03765 -117.889855) (xy 109.029894 -117.943803) (xy 109.014539 -117.996098) (xy 108.991897 -118.045675)
			(xy 108.962431 -118.091525) (xy 108.92674 -118.132716) (xy 108.885549 -118.168407) (xy 108.839699 -118.197873)
			(xy 108.790122 -118.220515) (xy 108.737827 -118.23587) (xy 108.683879 -118.243626) (xy 108.629377 -118.243626)
			(xy 108.575429 -118.23587) (xy 108.523134 -118.220515) (xy 108.473557 -118.197873) (xy 108.427707 -118.168407)
			(xy 108.386516 -118.132716) (xy 108.350825 -118.091525) (xy 108.321359 -118.045675) (xy 108.298717 -117.996098)
			(xy 108.283362 -117.943803) (xy 108.275606 -117.889855) (xy 108.27512 -117.862604) (xy 108.27512 -117.861842)
			(xy 108.275608 -117.834662) (xy 108.283381 -117.780859) (xy 108.290614 -117.754654) (xy 108.294424 -117.741954)
			(xy 108.288836 -117.716554) (xy 108.215176 -117.63248) (xy 108.191046 -117.623336) (xy 108.178092 -117.625368)
			(xy 108.163891 -117.62739) (xy 108.135286 -117.629553) (xy 108.120942 -117.629686) (xy 108.093686 -117.62929)
			(xy 108.039727 -117.621538) (xy 107.987422 -117.606186) (xy 107.937833 -117.583546) (xy 107.891971 -117.554079)
			(xy 107.85077 -117.518385) (xy 107.815068 -117.477191) (xy 107.785592 -117.431335) (xy 107.762941 -117.381751)
			(xy 107.747578 -117.329448) (xy 107.739815 -117.275491) (xy 107.73981 -117.220979) (xy 95.850018 -117.220979)
			(xy 95.862285 -117.23952) (xy 95.885957 -117.290017) (xy 95.902025 -117.343424) (xy 95.910145 -117.3986)
			(xy 95.910654 -117.426486) (xy 95.910145 -117.454372) (xy 95.902025 -117.509548) (xy 95.885957 -117.562955)
			(xy 95.862285 -117.613452) (xy 95.831512 -117.659965) (xy 95.794295 -117.701502) (xy 95.751427 -117.737177)
			(xy 95.703821 -117.766231) (xy 95.652492 -117.788043) (xy 95.598535 -117.802149) (xy 95.543098 -117.808249)
			(xy 95.487364 -117.806212) (xy 95.432521 -117.796082) (xy 95.379737 -117.778075) (xy 95.330137 -117.752574)
			(xy 95.284779 -117.720123) (xy 95.24463 -117.681414) (xy 95.210544 -117.637271) (xy 95.183248 -117.588636)
			(xy 95.163325 -117.536545) (xy 95.151199 -117.482108) (xy 95.147128 -117.426486) (xy 93.561976 -117.426486)
			(xy 93.535931 -117.442381) (xy 93.484602 -117.464193) (xy 93.430645 -117.478299) (xy 93.375208 -117.484399)
			(xy 93.319474 -117.482362) (xy 93.264631 -117.472232) (xy 93.211847 -117.454225) (xy 93.162247 -117.428724)
			(xy 93.116889 -117.396273) (xy 93.07674 -117.357564) (xy 93.042654 -117.313421) (xy 93.015358 -117.264786)
			(xy 92.995435 -117.212695) (xy 92.983309 -117.158258) (xy 92.979238 -117.102636) (xy 92.163938 -117.102636)
			(xy 92.191339 -117.13426) (xy 92.220807 -117.180114) (xy 92.243449 -117.229696) (xy 92.258805 -117.281995)
			(xy 92.266562 -117.335947) (xy 92.266562 -117.390453) (xy 92.258805 -117.444405) (xy 92.243449 -117.496704)
			(xy 92.220807 -117.546286) (xy 92.191339 -117.59214) (xy 92.155646 -117.633334) (xy 92.114453 -117.66903)
			(xy 92.0686 -117.698499) (xy 92.019019 -117.721144) (xy 91.966721 -117.736502) (xy 91.912769 -117.744261)
			(xy 91.885516 -117.744748) (xy 91.856599 -117.744238) (xy 91.799426 -117.73551) (xy 91.744226 -117.718252)
			(xy 91.692264 -117.692859) (xy 91.644731 -117.659913) (xy 91.602715 -117.620169) (xy 91.584526 -117.597682)
			(xy 91.576901 -117.588893) (xy 91.556014 -117.5787) (xy 91.544394 -117.578124) (xy 91.464638 -117.578124)
			(xy 91.453002 -117.578633) (xy 91.432092 -117.588842) (xy 91.424506 -117.597682) (xy 91.406307 -117.620159)
			(xy 91.364289 -117.659895) (xy 91.316756 -117.692836) (xy 91.264797 -117.718225) (xy 91.2096 -117.735483)
			(xy 91.152432 -117.744213) (xy 91.123516 -117.744748) (xy 91.096265 -117.744206) (xy 91.042318 -117.736452)
			(xy 90.990024 -117.721099) (xy 90.940447 -117.698459) (xy 90.894597 -117.668995) (xy 90.853406 -117.633305)
			(xy 90.817715 -117.592116) (xy 90.788248 -117.546267) (xy 90.765607 -117.496691) (xy 90.750252 -117.444397)
			(xy 90.742495 -117.390451) (xy 75.390756 -117.390451) (xy 75.390756 -117.758718) (xy 75.390289 -117.788703)
			(xy 75.382459 -117.84816) (xy 75.366935 -117.906086) (xy 75.343984 -117.96149) (xy 75.313998 -118.013424)
			(xy 75.277489 -118.061001) (xy 75.235083 -118.103405) (xy 75.187504 -118.139911) (xy 75.135568 -118.169895)
			(xy 75.080163 -118.192843) (xy 75.022236 -118.208364) (xy 74.962779 -118.21619) (xy 74.932794 -118.21668)
			(xy 74.904358 -118.216227) (xy 74.847928 -118.209151) (xy 74.792808 -118.195144) (xy 74.76617 -118.185184)
			(xy 74.754923 -118.181451) (xy 74.731352 -118.183559) (xy 74.720958 -118.189248) (xy 74.64171 -118.23827)
			(xy 74.629264 -118.258336) (xy 74.628248 -118.270274) (xy 74.625097 -118.298314) (xy 74.61164 -118.353108)
			(xy 74.590263 -118.405324) (xy 74.561431 -118.453824) (xy 74.525774 -118.497551) (xy 74.49526 -118.525354)
			(xy 80.517167 -118.525354) (xy 80.517167 -118.470846) (xy 80.524925 -118.416894) (xy 80.540283 -118.364594)
			(xy 80.562927 -118.315013) (xy 80.592398 -118.26916) (xy 80.628094 -118.227968) (xy 80.66929 -118.192275)
			(xy 80.715147 -118.162809) (xy 80.76473 -118.140169) (xy 80.817031 -118.124817) (xy 80.870984 -118.117065)
			(xy 80.898238 -118.116604) (xy 80.924146 -118.117063) (xy 80.975482 -118.124092) (xy 81.025396 -118.138001)
			(xy 81.07297 -118.158534) (xy 81.117328 -118.185316) (xy 81.157655 -118.217851) (xy 81.193209 -118.255544)
			(xy 81.208626 -118.27637) (xy 81.214425 -118.283724) (xy 81.230061 -118.294006) (xy 81.239106 -118.296436)
			(xy 81.269078 -118.303294) (xy 81.278377 -118.304966) (xy 81.297037 -118.3021) (xy 81.3054 -118.297706)
			(xy 81.331416 -118.283424) (xy 81.386337 -118.260928) (xy 81.4437 -118.245702) (xy 81.502548 -118.238)
			(xy 81.532222 -118.237508) (xy 81.561899 -118.237984) (xy 81.620755 -118.245655) (xy 81.678124 -118.260878)
			(xy 81.73304 -118.283398) (xy 81.759044 -118.297706) (xy 81.767424 -118.302046) (xy 81.786065 -118.304902)
			(xy 81.795366 -118.303294) (xy 81.825338 -118.296436) (xy 81.834427 -118.294109) (xy 81.850087 -118.283799)
			(xy 81.855818 -118.27637) (xy 81.871251 -118.255554) (xy 81.906789 -118.217842) (xy 81.947108 -118.18529)
			(xy 81.991463 -118.158498) (xy 82.039038 -118.137961) (xy 82.088955 -118.124055) (xy 82.140297 -118.117038)
			(xy 82.166206 -118.116604) (xy 82.193458 -118.117066) (xy 82.247407 -118.124824) (xy 82.299702 -118.14018)
			(xy 82.34928 -118.162822) (xy 82.395131 -118.192289) (xy 82.436322 -118.227982) (xy 82.472014 -118.269173)
			(xy 82.501481 -118.315025) (xy 82.524122 -118.364603) (xy 82.539478 -118.416899) (xy 82.547234 -118.470848)
			(xy 82.547234 -118.525352) (xy 82.539478 -118.579301) (xy 82.524122 -118.631597) (xy 82.501481 -118.681175)
			(xy 82.472014 -118.727027) (xy 82.436322 -118.768218) (xy 82.395131 -118.803911) (xy 82.34928 -118.833378)
			(xy 82.299702 -118.85602) (xy 82.247407 -118.871376) (xy 82.193458 -118.879134) (xy 82.166206 -118.87962)
			(xy 82.151413 -118.879485) (xy 82.121915 -118.877196) (xy 82.107278 -118.875048) (xy 82.096303 -118.873906)
			(xy 82.07511 -118.879976) (xy 82.066384 -118.886732) (xy 82.057488 -118.894352) (xy 93.41612 -118.894352)
			(xy 93.416549 -118.868037) (xy 93.423791 -118.815906) (xy 93.438117 -118.765263) (xy 93.459257 -118.717064)
			(xy 93.48681 -118.672221) (xy 93.520255 -118.631583) (xy 93.53931 -118.613428) (xy 93.546703 -118.605899)
			(xy 93.555232 -118.586625) (xy 93.55582 -118.57609) (xy 93.55582 -118.501414) (xy 93.555291 -118.490864)
			(xy 93.546755 -118.471569) (xy 93.53931 -118.464076) (xy 93.520252 -118.445923) (xy 93.486794 -118.405293)
			(xy 93.459236 -118.360452) (xy 93.438097 -118.312251) (xy 93.423781 -118.261603) (xy 93.416558 -118.209468)
			(xy 93.41612 -118.183152) (xy 93.416606 -118.155901) (xy 93.424362 -118.101953) (xy 93.439717 -118.049658)
			(xy 93.462359 -118.000081) (xy 93.491825 -117.954231) (xy 93.527516 -117.91304) (xy 93.568707 -117.877349)
			(xy 93.614557 -117.847883) (xy 93.664134 -117.825241) (xy 93.716429 -117.809886) (xy 93.770377 -117.80213)
			(xy 93.824879 -117.80213) (xy 93.878827 -117.809886) (xy 93.931122 -117.825241) (xy 93.980699 -117.847883)
			(xy 94.026549 -117.877349) (xy 94.06774 -117.91304) (xy 94.103431 -117.954231) (xy 94.132897 -118.000081)
			(xy 94.155539 -118.049658) (xy 94.170894 -118.101953) (xy 94.17865 -118.155901) (xy 94.179136 -118.183152)
			(xy 94.178692 -118.209467) (xy 94.171451 -118.261596) (xy 94.157126 -118.312238) (xy 94.135989 -118.360437)
			(xy 94.10844 -118.40528) (xy 94.074999 -118.445919) (xy 94.055946 -118.464076) (xy 94.052211 -118.467886)
			(xy 97.482404 -118.467886) (xy 97.486475 -118.412264) (xy 97.498601 -118.357827) (xy 97.518524 -118.305736)
			(xy 97.54582 -118.257101) (xy 97.579906 -118.212958) (xy 97.620055 -118.174249) (xy 97.665413 -118.141798)
			(xy 97.715013 -118.116297) (xy 97.767797 -118.09829) (xy 97.82264 -118.08816) (xy 97.878374 -118.086123)
			(xy 97.933811 -118.092223) (xy 97.987768 -118.106329) (xy 98.039097 -118.128141) (xy 98.086703 -118.157195)
			(xy 98.129571 -118.19287) (xy 98.166788 -118.234407) (xy 98.197561 -118.28092) (xy 98.221233 -118.331417)
			(xy 98.237301 -118.384824) (xy 98.245421 -118.44) (xy 98.24593 -118.467886) (xy 99.65258 -118.467886)
			(xy 99.656651 -118.412264) (xy 99.668777 -118.357827) (xy 99.6887 -118.305736) (xy 99.715996 -118.257101)
			(xy 99.750082 -118.212958) (xy 99.790231 -118.174249) (xy 99.835589 -118.141798) (xy 99.885189 -118.116297)
			(xy 99.937973 -118.09829) (xy 99.992816 -118.08816) (xy 100.04855 -118.086123) (xy 100.103987 -118.092223)
			(xy 100.157944 -118.106329) (xy 100.209273 -118.128141) (xy 100.256879 -118.157195) (xy 100.299747 -118.19287)
			(xy 100.336964 -118.234407) (xy 100.367737 -118.28092) (xy 100.391409 -118.331417) (xy 100.407477 -118.384824)
			(xy 100.415597 -118.44) (xy 100.416106 -118.467886) (xy 100.415597 -118.495772) (xy 100.407477 -118.550948)
			(xy 100.391409 -118.604355) (xy 100.367737 -118.654852) (xy 100.336964 -118.701365) (xy 100.299747 -118.742902)
			(xy 100.278913 -118.76024) (xy 102.564436 -118.76024) (xy 102.568507 -118.704618) (xy 102.580633 -118.650181)
			(xy 102.600556 -118.59809) (xy 102.627852 -118.549455) (xy 102.661938 -118.505312) (xy 102.702087 -118.466603)
			(xy 102.747445 -118.434152) (xy 102.797045 -118.408651) (xy 102.849829 -118.390644) (xy 102.904672 -118.380514)
			(xy 102.960406 -118.378477) (xy 103.015843 -118.384577) (xy 103.0698 -118.398683) (xy 103.121129 -118.420495)
			(xy 103.168735 -118.449549) (xy 103.211603 -118.485224) (xy 103.24882 -118.526761) (xy 103.279593 -118.573274)
			(xy 103.303265 -118.623771) (xy 103.319333 -118.677178) (xy 103.327453 -118.732354) (xy 103.327962 -118.76024)
			(xy 103.327453 -118.788126) (xy 103.319333 -118.843302) (xy 103.303265 -118.896709) (xy 103.279593 -118.947206)
			(xy 103.24882 -118.993719) (xy 103.219737 -119.026178) (xy 105.981498 -119.026178) (xy 105.985569 -118.970556)
			(xy 105.997695 -118.916119) (xy 106.017618 -118.864028) (xy 106.044914 -118.815393) (xy 106.079 -118.77125)
			(xy 106.119149 -118.732541) (xy 106.164507 -118.70009) (xy 106.214107 -118.674589) (xy 106.266891 -118.656582)
			(xy 106.321734 -118.646452) (xy 106.377468 -118.644415) (xy 106.432905 -118.650515) (xy 106.486862 -118.664621)
			(xy 106.538191 -118.686433) (xy 106.585797 -118.715487) (xy 106.628665 -118.751162) (xy 106.665882 -118.792699)
			(xy 106.696655 -118.839212) (xy 106.720327 -118.889709) (xy 106.736395 -118.943116) (xy 106.744515 -118.998292)
			(xy 106.745024 -119.026178) (xy 106.744515 -119.054064) (xy 106.741068 -119.077486) (xy 114.208558 -119.077486)
			(xy 114.212629 -119.021864) (xy 114.224755 -118.967427) (xy 114.244678 -118.915336) (xy 114.271974 -118.866701)
			(xy 114.30606 -118.822558) (xy 114.346209 -118.783849) (xy 114.391567 -118.751398) (xy 114.441167 -118.725897)
			(xy 114.493951 -118.70789) (xy 114.548794 -118.69776) (xy 114.604528 -118.695723) (xy 114.659965 -118.701823)
			(xy 114.713922 -118.715929) (xy 114.765251 -118.737741) (xy 114.812857 -118.766795) (xy 114.855725 -118.80247)
			(xy 114.892942 -118.844007) (xy 114.923715 -118.89052) (xy 114.947387 -118.941017) (xy 114.963455 -118.994424)
			(xy 114.971193 -119.047006) (xy 116.309138 -119.047006) (xy 116.313209 -118.991384) (xy 116.325335 -118.936947)
			(xy 116.345258 -118.884856) (xy 116.372554 -118.836221) (xy 116.40664 -118.792078) (xy 116.446789 -118.753369)
			(xy 116.492147 -118.720918) (xy 116.541747 -118.695417) (xy 116.594531 -118.67741) (xy 116.649374 -118.66728)
			(xy 116.705108 -118.665243) (xy 116.760545 -118.671343) (xy 116.814502 -118.685449) (xy 116.865831 -118.707261)
			(xy 116.913437 -118.736315) (xy 116.956305 -118.77199) (xy 116.993522 -118.813527) (xy 117.024295 -118.86004)
			(xy 117.047967 -118.910537) (xy 117.064035 -118.963944) (xy 117.072155 -119.01912) (xy 117.072664 -119.047006)
			(xy 117.072155 -119.074892) (xy 117.064035 -119.130068) (xy 117.047967 -119.183475) (xy 117.024295 -119.233972)
			(xy 116.993522 -119.280485) (xy 116.956305 -119.322022) (xy 116.913437 -119.357697) (xy 116.865831 -119.386751)
			(xy 116.814502 -119.408563) (xy 116.760545 -119.422669) (xy 116.705108 -119.428769) (xy 116.649374 -119.426732)
			(xy 116.594531 -119.416602) (xy 116.541747 -119.398595) (xy 116.492147 -119.373094) (xy 116.446789 -119.340643)
			(xy 116.40664 -119.301934) (xy 116.372554 -119.257791) (xy 116.345258 -119.209156) (xy 116.325335 -119.157065)
			(xy 116.313209 -119.102628) (xy 116.309138 -119.047006) (xy 114.971193 -119.047006) (xy 114.971575 -119.0496)
			(xy 114.972084 -119.077486) (xy 114.971575 -119.105372) (xy 114.963455 -119.160548) (xy 114.947387 -119.213955)
			(xy 114.923715 -119.264452) (xy 114.892942 -119.310965) (xy 114.855725 -119.352502) (xy 114.812857 -119.388177)
			(xy 114.765251 -119.417231) (xy 114.713922 -119.439043) (xy 114.659965 -119.453149) (xy 114.604528 -119.459249)
			(xy 114.548794 -119.457212) (xy 114.493951 -119.447082) (xy 114.441167 -119.429075) (xy 114.391567 -119.403574)
			(xy 114.346209 -119.371123) (xy 114.30606 -119.332414) (xy 114.271974 -119.288271) (xy 114.244678 -119.239636)
			(xy 114.224755 -119.187545) (xy 114.212629 -119.133108) (xy 114.208558 -119.077486) (xy 106.741068 -119.077486)
			(xy 106.736395 -119.10924) (xy 106.720327 -119.162647) (xy 106.696655 -119.213144) (xy 106.665882 -119.259657)
			(xy 106.628665 -119.301194) (xy 106.585797 -119.336869) (xy 106.538191 -119.365923) (xy 106.486862 -119.387735)
			(xy 106.432905 -119.401841) (xy 106.377468 -119.407941) (xy 106.321734 -119.405904) (xy 106.266891 -119.395774)
			(xy 106.214107 -119.377767) (xy 106.164507 -119.352266) (xy 106.119149 -119.319815) (xy 106.079 -119.281106)
			(xy 106.044914 -119.236963) (xy 106.017618 -119.188328) (xy 105.997695 -119.136237) (xy 105.985569 -119.0818)
			(xy 105.981498 -119.026178) (xy 103.219737 -119.026178) (xy 103.211603 -119.035256) (xy 103.168735 -119.070931)
			(xy 103.121129 -119.099985) (xy 103.0698 -119.121797) (xy 103.015843 -119.135903) (xy 102.960406 -119.142003)
			(xy 102.904672 -119.139966) (xy 102.849829 -119.129836) (xy 102.797045 -119.111829) (xy 102.747445 -119.086328)
			(xy 102.702087 -119.053877) (xy 102.661938 -119.015168) (xy 102.627852 -118.971025) (xy 102.600556 -118.92239)
			(xy 102.580633 -118.870299) (xy 102.568507 -118.815862) (xy 102.564436 -118.76024) (xy 100.278913 -118.76024)
			(xy 100.256879 -118.778577) (xy 100.209273 -118.807631) (xy 100.157944 -118.829443) (xy 100.103987 -118.843549)
			(xy 100.04855 -118.849649) (xy 99.992816 -118.847612) (xy 99.937973 -118.837482) (xy 99.885189 -118.819475)
			(xy 99.835589 -118.793974) (xy 99.790231 -118.761523) (xy 99.750082 -118.722814) (xy 99.715996 -118.678671)
			(xy 99.6887 -118.630036) (xy 99.668777 -118.577945) (xy 99.656651 -118.523508) (xy 99.65258 -118.467886)
			(xy 98.24593 -118.467886) (xy 98.245421 -118.495772) (xy 98.237301 -118.550948) (xy 98.221233 -118.604355)
			(xy 98.197561 -118.654852) (xy 98.166788 -118.701365) (xy 98.129571 -118.742902) (xy 98.086703 -118.778577)
			(xy 98.039097 -118.807631) (xy 97.987768 -118.829443) (xy 97.933811 -118.843549) (xy 97.878374 -118.849649)
			(xy 97.82264 -118.847612) (xy 97.767797 -118.837482) (xy 97.715013 -118.819475) (xy 97.665413 -118.793974)
			(xy 97.620055 -118.761523) (xy 97.579906 -118.722814) (xy 97.54582 -118.678671) (xy 97.518524 -118.630036)
			(xy 97.498601 -118.577945) (xy 97.486475 -118.523508) (xy 97.482404 -118.467886) (xy 94.052211 -118.467886)
			(xy 94.04856 -118.471611) (xy 94.040025 -118.490881) (xy 94.039436 -118.501414) (xy 94.039436 -118.57609)
			(xy 94.039946 -118.586642) (xy 94.048494 -118.605938) (xy 94.055946 -118.613428) (xy 94.075017 -118.631568)
			(xy 94.108471 -118.672202) (xy 94.136027 -118.717046) (xy 94.157162 -118.76525) (xy 94.171477 -118.815899)
			(xy 94.178699 -118.868035) (xy 94.179136 -118.894352) (xy 94.17865 -118.921603) (xy 94.170894 -118.975551)
			(xy 94.155539 -119.027846) (xy 94.132897 -119.077423) (xy 94.103431 -119.123273) (xy 94.06774 -119.164464)
			(xy 94.026549 -119.200155) (xy 93.980699 -119.229621) (xy 93.931122 -119.252263) (xy 93.878827 -119.267618)
			(xy 93.824879 -119.275374) (xy 93.770377 -119.275374) (xy 93.716429 -119.267618) (xy 93.664134 -119.252263)
			(xy 93.614557 -119.229621) (xy 93.568707 -119.200155) (xy 93.527516 -119.164464) (xy 93.491825 -119.123273)
			(xy 93.462359 -119.077423) (xy 93.439717 -119.027846) (xy 93.424362 -118.975551) (xy 93.416606 -118.921603)
			(xy 93.41612 -118.894352) (xy 82.057488 -118.894352) (xy 82.007964 -118.93677) (xy 81.999951 -118.944351)
			(xy 81.990728 -118.964361) (xy 81.990184 -118.975378) (xy 81.990184 -119.27967) (xy 81.990744 -119.290686)
			(xy 81.999948 -119.310703) (xy 82.007964 -119.318278) (xy 82.07502 -119.375682) (xy 82.096102 -119.381778)
			(xy 82.107278 -119.38) (xy 82.121915 -119.377855) (xy 82.151413 -119.37557) (xy 82.166206 -119.375428)
			(xy 82.19346 -119.375842) (xy 82.247412 -119.3836) (xy 82.299711 -119.398957) (xy 82.318535 -119.407554)
			(xy 94.499632 -119.407554) (xy 94.499632 -119.353046) (xy 94.507389 -119.299093) (xy 94.522745 -119.246794)
			(xy 94.545388 -119.197211) (xy 94.574856 -119.151356) (xy 94.61055 -119.110162) (xy 94.651743 -119.074466)
			(xy 94.697597 -119.044995) (xy 94.747179 -119.022351) (xy 94.799478 -119.006992) (xy 94.85343 -118.999233)
			(xy 94.880684 -118.998746) (xy 94.908054 -118.99921) (xy 94.962234 -119.007027) (xy 95.014738 -119.022516)
			(xy 95.064484 -119.045358) (xy 95.110451 -119.075084) (xy 95.131382 -119.092726) (xy 95.131636 -119.09298)
			(xy 95.13873 -119.098555) (xy 95.155641 -119.104807) (xy 95.164656 -119.105172) (xy 95.231712 -119.105172)
			(xy 95.24073 -119.104827) (xy 95.257647 -119.098572) (xy 95.264732 -119.09298) (xy 95.264732 -119.092726)
			(xy 95.264986 -119.092726) (xy 95.285916 -119.075084) (xy 95.331889 -119.045372) (xy 95.381637 -119.022536)
			(xy 95.434138 -119.007046) (xy 95.488315 -118.999219) (xy 95.515684 -118.998746) (xy 95.542934 -118.9993)
			(xy 95.59688 -119.007054) (xy 95.649174 -119.022407) (xy 95.69875 -119.045046) (xy 95.7446 -119.07451)
			(xy 95.785789 -119.110199) (xy 95.82148 -119.151387) (xy 95.850946 -119.197236) (xy 95.873587 -119.246811)
			(xy 95.888942 -119.299104) (xy 95.896699 -119.35305) (xy 95.896699 -119.40755) (xy 95.888942 -119.461496)
			(xy 95.884381 -119.477028) (xy 99.60813 -119.477028) (xy 99.612201 -119.421406) (xy 99.624327 -119.366969)
			(xy 99.64425 -119.314878) (xy 99.671546 -119.266243) (xy 99.705632 -119.2221) (xy 99.745781 -119.183391)
			(xy 99.791139 -119.15094) (xy 99.840739 -119.125439) (xy 99.893523 -119.107432) (xy 99.948366 -119.097302)
			(xy 100.0041 -119.095265) (xy 100.059537 -119.101365) (xy 100.113494 -119.115471) (xy 100.164823 -119.137283)
			(xy 100.212429 -119.166337) (xy 100.255297 -119.202012) (xy 100.292514 -119.243549) (xy 100.323287 -119.290062)
			(xy 100.346959 -119.340559) (xy 100.363027 -119.393966) (xy 100.371147 -119.449142) (xy 100.371656 -119.477028)
			(xy 100.371147 -119.504914) (xy 100.363027 -119.56009) (xy 100.346959 -119.613497) (xy 100.323287 -119.663994)
			(xy 100.292514 -119.710507) (xy 100.255297 -119.752044) (xy 100.226222 -119.77624) (xy 100.535992 -119.77624)
			(xy 100.540063 -119.720618) (xy 100.552189 -119.666181) (xy 100.572112 -119.61409) (xy 100.599408 -119.565455)
			(xy 100.633494 -119.521312) (xy 100.673643 -119.482603) (xy 100.719001 -119.450152) (xy 100.768601 -119.424651)
			(xy 100.821385 -119.406644) (xy 100.876228 -119.396514) (xy 100.931962 -119.394477) (xy 100.987399 -119.400577)
			(xy 101.041356 -119.414683) (xy 101.092685 -119.436495) (xy 101.140291 -119.465549) (xy 101.183159 -119.501224)
			(xy 101.190383 -119.509286) (xy 119.927624 -119.509286) (xy 119.928163 -119.48073) (xy 119.936652 -119.424253)
			(xy 119.953469 -119.369674) (xy 119.978237 -119.318213) (xy 120.010403 -119.271021) (xy 120.049247 -119.229153)
			(xy 120.0939 -119.193547) (xy 120.118378 -119.178832) (xy 120.131218 -119.170668) (xy 120.151898 -119.14838)
			(xy 120.165093 -119.120988) (xy 120.16963 -119.090924) (xy 120.165107 -119.060858) (xy 120.151926 -119.03346)
			(xy 120.131256 -119.011162) (xy 120.118378 -119.003064) (xy 120.093908 -118.98834) (xy 120.049268 -118.952722)
			(xy 120.010433 -118.910851) (xy 119.97827 -118.863662) (xy 119.953498 -118.812206) (xy 119.936668 -118.757634)
			(xy 119.928158 -118.701164) (xy 119.927624 -118.67261) (xy 119.92811 -118.645359) (xy 119.935866 -118.591411)
			(xy 119.951221 -118.539116) (xy 119.973863 -118.489539) (xy 120.003329 -118.443689) (xy 120.03902 -118.402498)
			(xy 120.080211 -118.366807) (xy 120.126061 -118.337341) (xy 120.175638 -118.314699) (xy 120.227933 -118.299344)
			(xy 120.281881 -118.291588) (xy 120.336383 -118.291588) (xy 120.390331 -118.299344) (xy 120.442626 -118.314699)
			(xy 120.492203 -118.337341) (xy 120.538053 -118.366807) (xy 120.579244 -118.402498) (xy 120.614935 -118.443689)
			(xy 120.644401 -118.489539) (xy 120.667043 -118.539116) (xy 120.682398 -118.591411) (xy 120.690154 -118.645359)
			(xy 120.69064 -118.67261) (xy 120.690195 -118.70117) (xy 120.681691 -118.757652) (xy 120.664859 -118.812234)
			(xy 120.640075 -118.863696) (xy 120.607895 -118.910887) (xy 120.569037 -118.952751) (xy 120.52437 -118.988353)
			(xy 120.499886 -119.003064) (xy 120.48696 -119.0111) (xy 120.46628 -119.033418) (xy 120.453093 -119.060837)
			(xy 120.451544 -119.071136) (xy 122.095004 -119.071136) (xy 122.099075 -119.015514) (xy 122.111201 -118.961077)
			(xy 122.131124 -118.908986) (xy 122.15842 -118.860351) (xy 122.192506 -118.816208) (xy 122.232655 -118.777499)
			(xy 122.278013 -118.745048) (xy 122.327613 -118.719547) (xy 122.380397 -118.70154) (xy 122.43524 -118.69141)
			(xy 122.490974 -118.689373) (xy 122.546411 -118.695473) (xy 122.600368 -118.709579) (xy 122.651697 -118.731391)
			(xy 122.699303 -118.760445) (xy 122.742171 -118.79612) (xy 122.779388 -118.837657) (xy 122.810161 -118.88417)
			(xy 122.833833 -118.934667) (xy 122.849901 -118.988074) (xy 122.858021 -119.04325) (xy 122.85853 -119.071136)
			(xy 122.858021 -119.099022) (xy 122.849901 -119.154198) (xy 122.833833 -119.207605) (xy 122.810161 -119.258102)
			(xy 122.779388 -119.304615) (xy 122.742171 -119.346152) (xy 122.699303 -119.381827) (xy 122.651697 -119.410881)
			(xy 122.600368 -119.432693) (xy 122.546411 -119.446799) (xy 122.490974 -119.452899) (xy 122.43524 -119.450862)
			(xy 122.380397 -119.440732) (xy 122.327613 -119.422725) (xy 122.278013 -119.397224) (xy 122.232655 -119.364773)
			(xy 122.192506 -119.326064) (xy 122.15842 -119.281921) (xy 122.131124 -119.233286) (xy 122.111201 -119.181195)
			(xy 122.099075 -119.126758) (xy 122.095004 -119.071136) (xy 120.451544 -119.071136) (xy 120.448568 -119.090924)
			(xy 120.453107 -119.121009) (xy 120.466308 -119.148422) (xy 120.486997 -119.17073) (xy 120.499886 -119.178832)
			(xy 120.524369 -119.193535) (xy 120.569006 -119.229159) (xy 120.607838 -119.271034) (xy 120.639998 -119.318228)
			(xy 120.664768 -119.369686) (xy 120.681596 -119.42426) (xy 120.690106 -119.480731) (xy 120.690213 -119.486426)
			(xy 125.787148 -119.486426) (xy 125.791219 -119.430804) (xy 125.803345 -119.376367) (xy 125.823268 -119.324276)
			(xy 125.850564 -119.275641) (xy 125.88465 -119.231498) (xy 125.924799 -119.192789) (xy 125.970157 -119.160338)
			(xy 126.019757 -119.134837) (xy 126.072541 -119.11683) (xy 126.127384 -119.1067) (xy 126.183118 -119.104663)
			(xy 126.238555 -119.110763) (xy 126.292512 -119.124869) (xy 126.343841 -119.146681) (xy 126.391447 -119.175735)
			(xy 126.434315 -119.21141) (xy 126.471532 -119.252947) (xy 126.502305 -119.29946) (xy 126.525977 -119.349957)
			(xy 126.542045 -119.403364) (xy 126.550165 -119.45854) (xy 126.550674 -119.486426) (xy 126.550165 -119.514312)
			(xy 126.542045 -119.569488) (xy 126.525977 -119.622895) (xy 126.502305 -119.673392) (xy 126.471532 -119.719905)
			(xy 126.434315 -119.761442) (xy 126.391447 -119.797117) (xy 126.343841 -119.826171) (xy 126.292512 -119.847983)
			(xy 126.238555 -119.862089) (xy 126.183118 -119.868189) (xy 126.127384 -119.866152) (xy 126.072541 -119.856022)
			(xy 126.019757 -119.838015) (xy 125.970157 -119.812514) (xy 125.924799 -119.780063) (xy 125.88465 -119.741354)
			(xy 125.850564 -119.697211) (xy 125.823268 -119.648576) (xy 125.803345 -119.596485) (xy 125.791219 -119.542048)
			(xy 125.787148 -119.486426) (xy 120.690213 -119.486426) (xy 120.69064 -119.509286) (xy 120.690154 -119.536537)
			(xy 120.682398 -119.590485) (xy 120.667043 -119.64278) (xy 120.644401 -119.692357) (xy 120.614935 -119.738207)
			(xy 120.579244 -119.779398) (xy 120.538053 -119.815089) (xy 120.492203 -119.844555) (xy 120.442626 -119.867197)
			(xy 120.390331 -119.882552) (xy 120.336383 -119.890308) (xy 120.281881 -119.890308) (xy 120.227933 -119.882552)
			(xy 120.175638 -119.867197) (xy 120.126061 -119.844555) (xy 120.080211 -119.815089) (xy 120.03902 -119.779398)
			(xy 120.003329 -119.738207) (xy 119.973863 -119.692357) (xy 119.951221 -119.64278) (xy 119.935866 -119.590485)
			(xy 119.92811 -119.536537) (xy 119.927624 -119.509286) (xy 101.190383 -119.509286) (xy 101.220376 -119.542761)
			(xy 101.251149 -119.589274) (xy 101.274821 -119.639771) (xy 101.290889 -119.693178) (xy 101.299009 -119.748354)
			(xy 101.299518 -119.77624) (xy 101.299009 -119.804126) (xy 101.290889 -119.859302) (xy 101.274821 -119.912709)
			(xy 101.251149 -119.963206) (xy 101.220376 -120.009719) (xy 101.183159 -120.051256) (xy 101.140291 -120.086931)
			(xy 101.12955 -120.093486) (xy 114.208558 -120.093486) (xy 114.212629 -120.037864) (xy 114.224755 -119.983427)
			(xy 114.244678 -119.931336) (xy 114.271974 -119.882701) (xy 114.30606 -119.838558) (xy 114.346209 -119.799849)
			(xy 114.391567 -119.767398) (xy 114.441167 -119.741897) (xy 114.493951 -119.72389) (xy 114.548794 -119.71376)
			(xy 114.604528 -119.711723) (xy 114.659965 -119.717823) (xy 114.713922 -119.731929) (xy 114.765251 -119.753741)
			(xy 114.812857 -119.782795) (xy 114.855725 -119.81847) (xy 114.892942 -119.860007) (xy 114.923715 -119.90652)
			(xy 114.947387 -119.957017) (xy 114.963455 -120.010424) (xy 114.971575 -120.0656) (xy 114.972084 -120.093486)
			(xy 114.971575 -120.121372) (xy 114.963455 -120.176548) (xy 114.947387 -120.229955) (xy 114.923715 -120.280452)
			(xy 114.892942 -120.326965) (xy 114.875466 -120.34647) (xy 116.321076 -120.34647) (xy 116.325147 -120.290848)
			(xy 116.337273 -120.236411) (xy 116.357196 -120.18432) (xy 116.384492 -120.135685) (xy 116.418578 -120.091542)
			(xy 116.458727 -120.052833) (xy 116.504085 -120.020382) (xy 116.553685 -119.994881) (xy 116.606469 -119.976874)
			(xy 116.661312 -119.966744) (xy 116.717046 -119.964707) (xy 116.772483 -119.970807) (xy 116.82644 -119.984913)
			(xy 116.877769 -120.006725) (xy 116.925375 -120.035779) (xy 116.968243 -120.071454) (xy 116.982294 -120.087136)
			(xy 122.095004 -120.087136) (xy 122.099075 -120.031514) (xy 122.111201 -119.977077) (xy 122.131124 -119.924986)
			(xy 122.15842 -119.876351) (xy 122.192506 -119.832208) (xy 122.232655 -119.793499) (xy 122.278013 -119.761048)
			(xy 122.327613 -119.735547) (xy 122.380397 -119.71754) (xy 122.43524 -119.70741) (xy 122.490974 -119.705373)
			(xy 122.546411 -119.711473) (xy 122.600368 -119.725579) (xy 122.651697 -119.747391) (xy 122.699303 -119.776445)
			(xy 122.742171 -119.81212) (xy 122.779388 -119.853657) (xy 122.810161 -119.90017) (xy 122.833833 -119.950667)
			(xy 122.849901 -120.004074) (xy 122.858021 -120.05925) (xy 122.85853 -120.087136) (xy 122.858021 -120.115022)
			(xy 122.849901 -120.170198) (xy 122.833833 -120.223605) (xy 122.810161 -120.274102) (xy 122.779388 -120.320615)
			(xy 122.742171 -120.362152) (xy 122.699303 -120.397827) (xy 122.651697 -120.426881) (xy 122.600368 -120.448693)
			(xy 122.546411 -120.462799) (xy 122.490974 -120.468899) (xy 122.43524 -120.466862) (xy 122.380397 -120.456732)
			(xy 122.327613 -120.438725) (xy 122.278013 -120.413224) (xy 122.232655 -120.380773) (xy 122.192506 -120.342064)
			(xy 122.15842 -120.297921) (xy 122.131124 -120.249286) (xy 122.111201 -120.197195) (xy 122.099075 -120.142758)
			(xy 122.095004 -120.087136) (xy 116.982294 -120.087136) (xy 117.00546 -120.112991) (xy 117.036233 -120.159504)
			(xy 117.059905 -120.210001) (xy 117.075973 -120.263408) (xy 117.084093 -120.318584) (xy 117.084602 -120.34647)
			(xy 117.084093 -120.374356) (xy 117.075973 -120.429532) (xy 117.059905 -120.482939) (xy 117.036233 -120.533436)
			(xy 117.00546 -120.579949) (xy 116.968243 -120.621486) (xy 116.925375 -120.657161) (xy 116.877769 -120.686215)
			(xy 116.82644 -120.708027) (xy 116.772483 -120.722133) (xy 116.717046 -120.728233) (xy 116.661312 -120.726196)
			(xy 116.606469 -120.716066) (xy 116.553685 -120.698059) (xy 116.504085 -120.672558) (xy 116.458727 -120.640107)
			(xy 116.418578 -120.601398) (xy 116.384492 -120.557255) (xy 116.357196 -120.50862) (xy 116.337273 -120.456529)
			(xy 116.325147 -120.402092) (xy 116.321076 -120.34647) (xy 114.875466 -120.34647) (xy 114.855725 -120.368502)
			(xy 114.812857 -120.404177) (xy 114.765251 -120.433231) (xy 114.713922 -120.455043) (xy 114.659965 -120.469149)
			(xy 114.604528 -120.475249) (xy 114.548794 -120.473212) (xy 114.493951 -120.463082) (xy 114.441167 -120.445075)
			(xy 114.391567 -120.419574) (xy 114.346209 -120.387123) (xy 114.30606 -120.348414) (xy 114.271974 -120.304271)
			(xy 114.244678 -120.255636) (xy 114.224755 -120.203545) (xy 114.212629 -120.149108) (xy 114.208558 -120.093486)
			(xy 101.12955 -120.093486) (xy 101.092685 -120.115985) (xy 101.041356 -120.137797) (xy 100.987399 -120.151903)
			(xy 100.931962 -120.158003) (xy 100.876228 -120.155966) (xy 100.821385 -120.145836) (xy 100.768601 -120.127829)
			(xy 100.719001 -120.102328) (xy 100.673643 -120.069877) (xy 100.633494 -120.031168) (xy 100.599408 -119.987025)
			(xy 100.572112 -119.93839) (xy 100.552189 -119.886299) (xy 100.540063 -119.831862) (xy 100.535992 -119.77624)
			(xy 100.226222 -119.77624) (xy 100.212429 -119.787719) (xy 100.164823 -119.816773) (xy 100.113494 -119.838585)
			(xy 100.059537 -119.852691) (xy 100.0041 -119.858791) (xy 99.948366 -119.856754) (xy 99.893523 -119.846624)
			(xy 99.840739 -119.828617) (xy 99.791139 -119.803116) (xy 99.745781 -119.770665) (xy 99.705632 -119.731956)
			(xy 99.671546 -119.687813) (xy 99.64425 -119.639178) (xy 99.624327 -119.587087) (xy 99.612201 -119.53265)
			(xy 99.60813 -119.477028) (xy 95.884381 -119.477028) (xy 95.873587 -119.513789) (xy 95.850946 -119.563364)
			(xy 95.82148 -119.609213) (xy 95.785789 -119.650401) (xy 95.7446 -119.68609) (xy 95.69875 -119.715554)
			(xy 95.649174 -119.738193) (xy 95.59688 -119.753546) (xy 95.542934 -119.7613) (xy 95.515684 -119.761762)
			(xy 95.488313 -119.761315) (xy 95.434133 -119.753494) (xy 95.381629 -119.738001) (xy 95.331882 -119.715155)
			(xy 95.285917 -119.685426) (xy 95.264986 -119.667782) (xy 95.264732 -119.667528) (xy 95.257647 -119.66194)
			(xy 95.240729 -119.655696) (xy 95.231712 -119.655336) (xy 95.164656 -119.655336) (xy 95.155641 -119.655712)
			(xy 95.138723 -119.661946) (xy 95.131636 -119.667528) (xy 95.131636 -119.667782) (xy 95.131382 -119.667782)
			(xy 95.110428 -119.685393) (xy 95.064461 -119.71511) (xy 95.014719 -119.737952) (xy 94.962224 -119.753449)
			(xy 94.908052 -119.761284) (xy 94.880684 -119.761762) (xy 94.85343 -119.761367) (xy 94.799478 -119.753608)
			(xy 94.747179 -119.738249) (xy 94.697597 -119.715605) (xy 94.651743 -119.686134) (xy 94.61055 -119.650438)
			(xy 94.574856 -119.609244) (xy 94.545388 -119.563389) (xy 94.522745 -119.513806) (xy 94.507389 -119.461507)
			(xy 94.499632 -119.407554) (xy 82.318535 -119.407554) (xy 82.349292 -119.421601) (xy 82.395146 -119.45107)
			(xy 82.436339 -119.486765) (xy 82.472033 -119.527959) (xy 82.501502 -119.573813) (xy 82.524145 -119.623395)
			(xy 82.539501 -119.675694) (xy 82.547258 -119.729646) (xy 82.547258 -119.784154) (xy 82.539501 -119.838106)
			(xy 82.524145 -119.890405) (xy 82.501502 -119.939987) (xy 82.472033 -119.985841) (xy 82.436339 -120.027035)
			(xy 82.395146 -120.06273) (xy 82.349292 -120.092199) (xy 82.299711 -120.114843) (xy 82.247412 -120.1302)
			(xy 82.19346 -120.137958) (xy 82.166206 -120.138444) (xy 82.140268 -120.138039) (xy 82.08887 -120.13101)
			(xy 82.038899 -120.11708) (xy 81.991277 -120.096507) (xy 81.946882 -120.06967) (xy 81.906533 -120.037065)
			(xy 81.870975 -119.999292) (xy 81.855564 -119.978424) (xy 81.84977 -119.971066) (xy 81.83413 -119.960786)
			(xy 81.825084 -119.958358) (xy 81.795112 -119.9515) (xy 81.785814 -119.949823) (xy 81.767153 -119.952692)
			(xy 81.75879 -119.957088) (xy 81.732803 -119.971343) (xy 81.677938 -119.993775) (xy 81.620637 -120.008942)
			(xy 81.561859 -120.016589) (xy 81.502585 -120.016589) (xy 81.443807 -120.008942) (xy 81.386506 -119.993775)
			(xy 81.331641 -119.971343) (xy 81.305654 -119.957088) (xy 81.297274 -119.952747) (xy 81.278633 -119.949892)
			(xy 81.269332 -119.9515) (xy 81.23936 -119.958358) (xy 81.230271 -119.960686) (xy 81.214611 -119.970996)
			(xy 81.20888 -119.978424) (xy 81.193448 -119.999274) (xy 81.157889 -120.037039) (xy 81.117542 -120.069639)
			(xy 81.07315 -120.096472) (xy 81.025532 -120.117043) (xy 80.975566 -120.130973) (xy 80.924174 -120.138006)
			(xy 80.898238 -120.138444) (xy 80.870986 -120.137911) (xy 80.817036 -120.130159) (xy 80.764739 -120.114808)
			(xy 80.715158 -120.09217) (xy 80.669305 -120.062706) (xy 80.628111 -120.027016) (xy 80.592417 -119.985826)
			(xy 80.562948 -119.939975) (xy 80.540305 -119.890397) (xy 80.524949 -119.838101) (xy 80.517191 -119.784152)
			(xy 80.517191 -119.729648) (xy 80.524949 -119.675699) (xy 80.540305 -119.623403) (xy 80.562948 -119.573825)
			(xy 80.592417 -119.527974) (xy 80.628111 -119.486784) (xy 80.669305 -119.451094) (xy 80.715158 -119.42163)
			(xy 80.764739 -119.398992) (xy 80.817036 -119.38364) (xy 80.870986 -119.375889) (xy 80.898238 -119.375428)
			(xy 80.913031 -119.375568) (xy 80.942529 -119.377854) (xy 80.957166 -119.38) (xy 80.968141 -119.381097)
			(xy 80.98933 -119.375056) (xy 80.99806 -119.368316) (xy 81.05648 -119.318278) (xy 81.064524 -119.310725)
			(xy 81.073727 -119.290693) (xy 81.07426 -119.27967) (xy 81.07426 -118.975378) (xy 81.073747 -118.964356)
			(xy 81.064511 -118.944339) (xy 81.05648 -118.93677) (xy 80.989424 -118.879366) (xy 80.968342 -118.87327)
			(xy 80.957166 -118.875048) (xy 80.942528 -118.877188) (xy 80.913031 -118.879476) (xy 80.898238 -118.87962)
			(xy 80.870984 -118.879135) (xy 80.817031 -118.871383) (xy 80.76473 -118.856031) (xy 80.715147 -118.833391)
			(xy 80.66929 -118.803925) (xy 80.628094 -118.768232) (xy 80.592398 -118.72704) (xy 80.562927 -118.681187)
			(xy 80.540283 -118.631606) (xy 80.524925 -118.579306) (xy 80.517167 -118.525354) (xy 74.49526 -118.525354)
			(xy 74.484067 -118.535552) (xy 74.437221 -118.566999) (xy 74.386256 -118.591207) (xy 74.332282 -118.607648)
			(xy 74.276475 -118.615964) (xy 74.248264 -118.616476) (xy 74.221012 -118.616052) (xy 74.167064 -118.60829)
			(xy 74.114769 -118.592931) (xy 74.065192 -118.570286) (xy 74.019342 -118.540816) (xy 73.978153 -118.505121)
			(xy 73.942462 -118.463929) (xy 73.912997 -118.418076) (xy 73.890357 -118.368497) (xy 73.875002 -118.316201)
			(xy 73.867246 -118.262252) (xy 72.648074 -118.262252) (xy 72.648063 -118.262854) (xy 72.639943 -118.31803)
			(xy 72.623875 -118.371437) (xy 72.600203 -118.421934) (xy 72.56943 -118.468447) (xy 72.532213 -118.509984)
			(xy 72.489345 -118.545659) (xy 72.441739 -118.574713) (xy 72.39041 -118.596525) (xy 72.336453 -118.610631)
			(xy 72.281016 -118.616731) (xy 72.225282 -118.614694) (xy 72.170439 -118.604564) (xy 72.117655 -118.586557)
			(xy 72.068055 -118.561056) (xy 72.022697 -118.528605) (xy 71.982548 -118.489896) (xy 71.948462 -118.445753)
			(xy 71.921166 -118.397118) (xy 71.901243 -118.345027) (xy 71.889117 -118.29059) (xy 71.885046 -118.234968)
			(xy 70.004559 -118.234968) (xy 70.006718 -118.240556) (xy 70.014084 -118.263416) (xy 70.014084 -118.26367)
			(xy 70.017083 -118.272375) (xy 70.028301 -118.286958) (xy 70.035928 -118.292118) (xy 70.093078 -118.327932)
			(xy 70.101047 -118.332483) (xy 70.119018 -118.336131) (xy 70.12813 -118.335044) (xy 70.128638 -118.335044)
			(xy 70.144206 -118.332575) (xy 70.175615 -118.329901) (xy 70.191376 -118.32971) (xy 70.218631 -118.330135)
			(xy 70.272587 -118.33789) (xy 70.324891 -118.353245) (xy 70.374476 -118.375887) (xy 70.420335 -118.405356)
			(xy 70.461532 -118.441051) (xy 70.49723 -118.482246) (xy 70.526702 -118.528103) (xy 70.549347 -118.577687)
			(xy 70.564705 -118.629989) (xy 70.572463 -118.683945) (xy 70.572463 -118.738455) (xy 70.564705 -118.792411)
			(xy 70.549347 -118.844713) (xy 70.526702 -118.894297) (xy 70.49723 -118.940154) (xy 70.461532 -118.981349)
			(xy 70.420335 -119.017044) (xy 70.374476 -119.046513) (xy 70.324891 -119.069155) (xy 70.272587 -119.08451)
			(xy 70.218631 -119.092265) (xy 70.191376 -119.092726) (xy 70.164127 -119.092216) (xy 70.110186 -119.084445)
			(xy 70.0579 -119.06908) (xy 70.008331 -119.046432) (xy 69.962488 -119.016963) (xy 69.921304 -118.981271)
			(xy 69.885616 -118.940084) (xy 69.856151 -118.894238) (xy 69.833508 -118.844667) (xy 69.825362 -118.81866)
			(xy 69.825362 -118.818406) (xy 69.822319 -118.80972) (xy 69.811132 -118.795127) (xy 69.803518 -118.789958)
			(xy 69.746368 -118.754144) (xy 69.738389 -118.749614) (xy 69.720427 -118.745954) (xy 69.711316 -118.747032)
			(xy 69.710808 -118.747032) (xy 69.695241 -118.749507) (xy 69.663831 -118.752177) (xy 69.64807 -118.752366)
			(xy 69.620814 -118.751973) (xy 69.566859 -118.744211) (xy 69.514557 -118.728849) (xy 69.464974 -118.7062)
			(xy 69.419119 -118.676725) (xy 69.377925 -118.641024) (xy 69.342232 -118.599823) (xy 69.312766 -118.553963)
			(xy 69.290126 -118.504375) (xy 69.274774 -118.452071) (xy 69.267022 -118.398114) (xy 69.266562 -118.370858)
			(xy 68.023719 -118.370858) (xy 68.002167 -118.418056) (xy 67.9727 -118.46391) (xy 67.937006 -118.505104)
			(xy 67.895812 -118.540798) (xy 67.849957 -118.570266) (xy 67.800375 -118.592907) (xy 67.748076 -118.608261)
			(xy 67.694123 -118.616015) (xy 67.66687 -118.616476) (xy 67.649822 -118.616275) (xy 67.615862 -118.613223)
			(xy 67.599052 -118.61038) (xy 67.587724 -118.608957) (xy 67.565708 -118.614883) (xy 67.556634 -118.62181)
			(xy 67.53225 -118.642892) (xy 67.523841 -118.650887) (xy 67.514703 -118.672184) (xy 67.514724 -118.683786)
			(xy 67.515232 -118.703598) (xy 67.515232 -119.387254) (xy 71.309616 -119.387254) (xy 71.317373 -119.333295)
			(xy 71.332731 -119.280989) (xy 71.355376 -119.231402) (xy 71.384848 -119.185542) (xy 71.420547 -119.144343)
			(xy 71.461746 -119.108645) (xy 71.507607 -119.079173) (xy 71.557195 -119.056529) (xy 71.609501 -119.041172)
			(xy 71.66346 -119.033416) (xy 71.717973 -119.033418) (xy 71.771932 -119.041179) (xy 71.824237 -119.05654)
			(xy 71.873822 -119.079189) (xy 71.91968 -119.108665) (xy 71.960876 -119.144367) (xy 71.996572 -119.185568)
			(xy 72.02604 -119.231431) (xy 72.048681 -119.28102) (xy 72.064034 -119.333327) (xy 72.071786 -119.387287)
			(xy 72.072246 -119.414544) (xy 72.072246 -119.415052) (xy 72.071645 -119.445494) (xy 72.061946 -119.5056)
			(xy 72.052942 -119.534686) (xy 72.049136 -119.547716) (xy 72.047759 -119.574816) (xy 72.05357 -119.601321)
			(xy 72.066158 -119.625359) (xy 72.084634 -119.645232) (xy 72.107693 -119.659535) (xy 72.133705 -119.667259)
			(xy 72.160833 -119.667857) (xy 72.1741 -119.664988) (xy 72.196841 -119.659652) (xy 72.2432 -119.653924)
			(xy 72.266556 -119.653558) (xy 72.267064 -119.653558) (xy 72.294321 -119.654016) (xy 72.348279 -119.66177)
			(xy 72.400586 -119.677123) (xy 72.450174 -119.699765) (xy 72.496036 -119.729234) (xy 72.537236 -119.764929)
			(xy 72.572937 -119.806125) (xy 72.602412 -119.851983) (xy 72.62506 -119.901569) (xy 72.64042 -119.953873)
			(xy 72.64818 -120.007831) (xy 72.648181 -120.035066) (xy 73.866246 -120.035066) (xy 73.870317 -119.979444)
			(xy 73.882443 -119.925007) (xy 73.902366 -119.872916) (xy 73.929662 -119.824281) (xy 73.963748 -119.780138)
			(xy 74.003897 -119.741429) (xy 74.049255 -119.708978) (xy 74.098855 -119.683477) (xy 74.151639 -119.66547)
			(xy 74.206482 -119.65534) (xy 74.262216 -119.653303) (xy 74.317653 -119.659403) (xy 74.37161 -119.673509)
			(xy 74.422939 -119.695321) (xy 74.470545 -119.724375) (xy 74.513413 -119.76005) (xy 74.55063 -119.801587)
			(xy 74.581403 -119.8481) (xy 74.605075 -119.898597) (xy 74.621143 -119.952004) (xy 74.629263 -120.00718)
			(xy 74.629772 -120.035066) (xy 74.629263 -120.062952) (xy 74.621143 -120.118128) (xy 74.605075 -120.171535)
			(xy 74.581403 -120.222032) (xy 74.55063 -120.268545) (xy 74.513413 -120.310082) (xy 74.487246 -120.331858)
			(xy 83.159215 -120.331858) (xy 83.159215 -120.277342) (xy 83.166974 -120.223381) (xy 83.182334 -120.171074)
			(xy 83.204982 -120.121486) (xy 83.234458 -120.075626) (xy 83.27016 -120.034428) (xy 83.311363 -119.99873)
			(xy 83.357226 -119.96926) (xy 83.406818 -119.946618) (xy 83.459126 -119.931264) (xy 83.513088 -119.923512)
			(xy 83.540346 -119.923052) (xy 83.566255 -119.923485) (xy 83.617593 -119.930516) (xy 83.667509 -119.944428)
			(xy 83.715083 -119.964965) (xy 83.759441 -119.991751) (xy 83.799767 -120.024292) (xy 83.835319 -120.061989)
			(xy 83.850734 -120.082818) (xy 83.856501 -120.090125) (xy 83.871984 -120.100425) (xy 83.88096 -120.102884)
			(xy 83.91144 -120.109742) (xy 83.920717 -120.111484) (xy 83.939379 -120.108747) (xy 83.947762 -120.104408)
			(xy 83.973749 -120.090153) (xy 84.028614 -120.067721) (xy 84.085915 -120.052554) (xy 84.144693 -120.044907)
			(xy 84.203967 -120.044907) (xy 84.262745 -120.052554) (xy 84.320046 -120.067721) (xy 84.374911 -120.090153)
			(xy 84.400898 -120.104408) (xy 84.409308 -120.108661) (xy 84.427941 -120.111392) (xy 84.43722 -120.109742)
			(xy 84.4677 -120.102884) (xy 84.4767 -120.100479) (xy 84.492201 -120.09017) (xy 84.497926 -120.082818)
			(xy 84.513368 -120.062008) (xy 84.548903 -120.024294) (xy 84.589219 -119.99174) (xy 84.633573 -119.964947)
			(xy 84.681147 -119.944408) (xy 84.731064 -119.930503) (xy 84.782405 -119.923486) (xy 84.808314 -119.923052)
			(xy 84.835562 -119.923619) (xy 84.889502 -119.931376) (xy 84.94179 -119.946731) (xy 84.99136 -119.969371)
			(xy 85.037204 -119.998834) (xy 85.078388 -120.034522) (xy 85.114074 -120.075707) (xy 85.143536 -120.121552)
			(xy 85.166174 -120.171123) (xy 85.181527 -120.223411) (xy 85.189282 -120.277352) (xy 85.189282 -120.331848)
			(xy 85.181527 -120.385789) (xy 85.166174 -120.438077) (xy 85.143536 -120.487648) (xy 85.114074 -120.533493)
			(xy 85.078388 -120.574678) (xy 85.037204 -120.610366) (xy 84.99136 -120.639829) (xy 84.94179 -120.662469)
			(xy 84.889502 -120.677824) (xy 84.835562 -120.685581) (xy 84.808314 -120.686068) (xy 84.793521 -120.685933)
			(xy 84.764023 -120.683644) (xy 84.749386 -120.681496) (xy 84.738411 -120.680371) (xy 84.71722 -120.686431)
			(xy 84.708492 -120.69318) (xy 84.650072 -120.743218) (xy 84.642038 -120.75078) (xy 84.632827 -120.770805)
			(xy 84.632292 -120.781826) (xy 84.632292 -121.086118) (xy 84.632822 -121.097138) (xy 84.642047 -121.117154)
			(xy 84.650072 -121.124726) (xy 84.717128 -121.18213) (xy 84.73821 -121.188226) (xy 84.749386 -121.186448)
			(xy 84.764023 -121.184302) (xy 84.793521 -121.182017) (xy 84.808314 -121.181876) (xy 84.835563 -121.182395)
			(xy 84.889507 -121.190153) (xy 84.941798 -121.205509) (xy 84.991371 -121.22815) (xy 85.037218 -121.257615)
			(xy 85.078405 -121.293305) (xy 85.114093 -121.334493) (xy 85.143557 -121.380341) (xy 85.166196 -121.429915)
			(xy 85.18155 -121.482206) (xy 85.189306 -121.536151) (xy 85.189306 -121.590649) (xy 85.18155 -121.644594)
			(xy 85.166196 -121.696885) (xy 85.143557 -121.746459) (xy 85.114093 -121.792307) (xy 85.078405 -121.833495)
			(xy 85.037218 -121.869185) (xy 84.991371 -121.89865) (xy 84.941798 -121.921291) (xy 84.889507 -121.936647)
			(xy 84.835563 -121.944405) (xy 84.808314 -121.944892) (xy 84.782405 -121.94447) (xy 84.731067 -121.937435)
			(xy 84.681152 -121.92352) (xy 84.633578 -121.90298) (xy 84.589221 -121.876193) (xy 84.548895 -121.843652)
			(xy 84.513342 -121.805954) (xy 84.497926 -121.785126) (xy 84.492184 -121.777797) (xy 84.476683 -121.767511)
			(xy 84.4677 -121.76506) (xy 84.43722 -121.758202) (xy 84.427946 -121.756433) (xy 84.409279 -121.759187)
			(xy 84.400898 -121.763536) (xy 84.374911 -121.777791) (xy 84.320046 -121.800223) (xy 84.262745 -121.81539)
			(xy 84.203967 -121.823037) (xy 84.144693 -121.823037) (xy 84.085915 -121.81539) (xy 84.028614 -121.800223)
			(xy 83.973749 -121.777791) (xy 83.947762 -121.763536) (xy 83.93934 -121.759311) (xy 83.920718 -121.756564)
			(xy 83.91144 -121.758202) (xy 83.88096 -121.76506) (xy 83.871974 -121.767507) (xy 83.856467 -121.777788)
			(xy 83.850734 -121.785126) (xy 83.835329 -121.805964) (xy 83.799786 -121.843676) (xy 83.759463 -121.876226)
			(xy 83.715103 -121.903015) (xy 83.667524 -121.923549) (xy 83.617602 -121.937449) (xy 83.566257 -121.944461)
			(xy 83.540346 -121.944892) (xy 83.51309 -121.944464) (xy 83.459132 -121.936712) (xy 83.406826 -121.92136)
			(xy 83.357238 -121.898719) (xy 83.311377 -121.869251) (xy 83.270177 -121.833555) (xy 83.234477 -121.79236)
			(xy 83.205003 -121.746503) (xy 83.182357 -121.696917) (xy 83.166998 -121.644613) (xy 83.159239 -121.590656)
			(xy 83.159239 -121.536144) (xy 83.166998 -121.482187) (xy 83.182357 -121.429883) (xy 83.205003 -121.380297)
			(xy 83.234477 -121.33444) (xy 83.270177 -121.293245) (xy 83.311377 -121.257549) (xy 83.357238 -121.228081)
			(xy 83.406826 -121.20544) (xy 83.459132 -121.190088) (xy 83.51309 -121.182336) (xy 83.540346 -121.181876)
			(xy 83.555139 -121.182016) (xy 83.584637 -121.184302) (xy 83.599274 -121.186448) (xy 83.610249 -121.187539)
			(xy 83.631437 -121.1815) (xy 83.640168 -121.174764) (xy 83.698588 -121.124726) (xy 83.706596 -121.11714)
			(xy 83.715823 -121.097134) (xy 83.716368 -121.086118) (xy 83.716368 -120.781826) (xy 83.715826 -120.770807)
			(xy 83.70661 -120.75079) (xy 83.698588 -120.743218) (xy 83.631532 -120.685814) (xy 83.61045 -120.679718)
			(xy 83.599274 -120.681496) (xy 83.584636 -120.683635) (xy 83.555139 -120.685924) (xy 83.540346 -120.686068)
			(xy 83.513088 -120.685688) (xy 83.459127 -120.677936) (xy 83.406818 -120.662582) (xy 83.357226 -120.63994)
			(xy 83.311363 -120.61047) (xy 83.27016 -120.574772) (xy 83.234458 -120.533574) (xy 83.204982 -120.487714)
			(xy 83.182334 -120.438126) (xy 83.166974 -120.385819) (xy 83.159215 -120.331858) (xy 74.487246 -120.331858)
			(xy 74.470545 -120.345757) (xy 74.422939 -120.374811) (xy 74.37161 -120.396623) (xy 74.317653 -120.410729)
			(xy 74.262216 -120.416829) (xy 74.206482 -120.414792) (xy 74.151639 -120.404662) (xy 74.098855 -120.386655)
			(xy 74.049255 -120.361154) (xy 74.003897 -120.328703) (xy 73.963748 -120.289994) (xy 73.929662 -120.245851)
			(xy 73.902366 -120.197216) (xy 73.882443 -120.145125) (xy 73.870317 -120.090688) (xy 73.866246 -120.035066)
			(xy 72.648181 -120.035066) (xy 72.648182 -120.062344) (xy 72.640425 -120.116302) (xy 72.625068 -120.168607)
			(xy 72.602424 -120.218195) (xy 72.572952 -120.264054) (xy 72.537254 -120.305253) (xy 72.496056 -120.340951)
			(xy 72.450196 -120.370423) (xy 72.400609 -120.393068) (xy 72.348304 -120.408425) (xy 72.294346 -120.416182)
			(xy 72.239833 -120.41618) (xy 72.185875 -120.40842) (xy 72.133571 -120.39306) (xy 72.083985 -120.370413)
			(xy 72.038127 -120.340938) (xy 71.996931 -120.305238) (xy 71.961235 -120.264037) (xy 71.931766 -120.218176)
			(xy 71.909124 -120.168587) (xy 71.89377 -120.116281) (xy 71.886017 -120.062323) (xy 71.885556 -120.035066)
			(xy 71.885556 -120.034558) (xy 71.886159 -120.004116) (xy 71.895857 -119.94401) (xy 71.90486 -119.914924)
			(xy 71.908652 -119.90189) (xy 71.910031 -119.874792) (xy 71.904222 -119.848288) (xy 71.891636 -119.824251)
			(xy 71.873162 -119.804378) (xy 71.850105 -119.790075) (xy 71.824095 -119.782351) (xy 71.796969 -119.781753)
			(xy 71.783702 -119.784622) (xy 71.760961 -119.789958) (xy 71.714602 -119.795686) (xy 71.691246 -119.796052)
			(xy 71.690738 -119.796052) (xy 71.663481 -119.795586) (xy 71.609522 -119.787833) (xy 71.557215 -119.772479)
			(xy 71.507626 -119.749837) (xy 71.461764 -119.720368) (xy 71.420562 -119.684672) (xy 71.384861 -119.643475)
			(xy 71.355386 -119.597617) (xy 71.332738 -119.548031) (xy 71.317378 -119.495726) (xy 71.309618 -119.441767)
			(xy 71.309616 -119.387254) (xy 67.515232 -119.387254) (xy 67.515232 -119.567198) (xy 67.514724 -119.586248)
			(xy 67.514739 -119.597842) (xy 67.52387 -119.619129) (xy 67.53225 -119.627142) (xy 67.556634 -119.64797)
			(xy 67.56561 -119.654964) (xy 67.587504 -119.661037) (xy 67.598798 -119.659654) (xy 67.615669 -119.656782)
			(xy 67.649757 -119.653731) (xy 67.66687 -119.653558) (xy 67.694122 -119.654087) (xy 67.748071 -119.66184)
			(xy 67.800368 -119.677192) (xy 67.849947 -119.699831) (xy 67.8958 -119.729295) (xy 67.936993 -119.764986)
			(xy 67.972687 -119.806176) (xy 68.002155 -119.852026) (xy 68.024797 -119.901604) (xy 68.040154 -119.953899)
			(xy 68.047911 -120.007848) (xy 68.047911 -120.062352) (xy 68.040154 -120.116301) (xy 68.024797 -120.168596)
			(xy 68.002155 -120.218174) (xy 67.972687 -120.264024) (xy 67.936993 -120.305214) (xy 67.8958 -120.340905)
			(xy 67.849947 -120.370369) (xy 67.800368 -120.393008) (xy 67.748071 -120.40836) (xy 67.694122 -120.416113)
			(xy 67.66687 -120.416574) (xy 67.639893 -120.416106) (xy 67.586475 -120.408522) (xy 67.53466 -120.39348)
			(xy 67.485484 -120.371282) (xy 67.43993 -120.342371) (xy 67.398908 -120.307326) (xy 67.363238 -120.266845)
			(xy 67.333633 -120.221739) (xy 67.310684 -120.172909) (xy 67.294851 -120.121331) (xy 67.290188 -120.094756)
			(xy 67.288054 -120.084518) (xy 67.276753 -120.066942) (xy 67.268344 -120.06072) (xy 67.19697 -120.013222)
			(xy 67.175888 -120.009412) (xy 67.165728 -120.011952) (xy 67.139034 -120.018095) (xy 67.084658 -120.024715)
			(xy 67.05727 -120.02516) (xy 67.029882 -120.024724) (xy 66.975506 -120.018098) (xy 66.948812 -120.011952)
			(xy 66.938652 -120.009412) (xy 66.91757 -120.013222) (xy 66.837306 -120.066562) (xy 66.82613 -120.084088)
			(xy 66.824352 -120.094756) (xy 66.8197 -120.12133) (xy 66.80384 -120.172894) (xy 66.780874 -120.221709)
			(xy 66.751259 -120.266801) (xy 66.715586 -120.307272) (xy 66.674568 -120.342313) (xy 66.629021 -120.371226)
			(xy 66.579856 -120.393433) (xy 66.528053 -120.408492) (xy 66.474644 -120.416102) (xy 66.44767 -120.416574)
			(xy 66.420299 -120.416132) (xy 66.366118 -120.408309) (xy 66.313615 -120.392815) (xy 66.263868 -120.369968)
			(xy 66.217903 -120.340238) (xy 66.196972 -120.322594) (xy 66.196718 -120.32234) (xy 66.189636 -120.316748)
			(xy 66.172715 -120.310506) (xy 66.163698 -120.310148) (xy 66.096642 -120.310148) (xy 66.087626 -120.310515)
			(xy 66.070708 -120.316754) (xy 66.063622 -120.32234) (xy 66.063622 -120.322594) (xy 66.063368 -120.322594)
			(xy 66.04242 -120.340214) (xy 65.996452 -120.369929) (xy 65.946708 -120.392768) (xy 65.894211 -120.408264)
			(xy 65.840038 -120.416097) (xy 65.81267 -120.416574) (xy 65.795622 -120.416373) (xy 65.761662 -120.413321)
			(xy 65.744852 -120.410478) (xy 65.733524 -120.409055) (xy 65.711508 -120.414981) (xy 65.702434 -120.421908)
			(xy 65.67805 -120.44299) (xy 65.669642 -120.450986) (xy 65.660503 -120.472282) (xy 65.660524 -120.483884)
			(xy 65.661032 -120.503696) (xy 65.661032 -120.716548) (xy 69.30212 -120.716548) (xy 69.306191 -120.660926)
			(xy 69.318317 -120.606489) (xy 69.33824 -120.554398) (xy 69.365536 -120.505763) (xy 69.399622 -120.46162)
			(xy 69.439771 -120.422911) (xy 69.485129 -120.39046) (xy 69.534729 -120.364959) (xy 69.587513 -120.346952)
			(xy 69.642356 -120.336822) (xy 69.69809 -120.334785) (xy 69.753527 -120.340885) (xy 69.807484 -120.354991)
			(xy 69.858813 -120.376803) (xy 69.906419 -120.405857) (xy 69.949287 -120.441532) (xy 69.986504 -120.483069)
			(xy 70.017277 -120.529582) (xy 70.040949 -120.580079) (xy 70.057017 -120.633486) (xy 70.065137 -120.688662)
			(xy 70.065646 -120.716548) (xy 70.065137 -120.744434) (xy 70.057017 -120.79961) (xy 70.040949 -120.853017)
			(xy 70.017277 -120.903514) (xy 69.986504 -120.950027) (xy 69.949287 -120.991564) (xy 69.906419 -121.027239)
			(xy 69.858813 -121.056293) (xy 69.807484 -121.078105) (xy 69.753527 -121.092211) (xy 69.69809 -121.098311)
			(xy 69.642356 -121.096274) (xy 69.587513 -121.086144) (xy 69.534729 -121.068137) (xy 69.485129 -121.042636)
			(xy 69.439771 -121.010185) (xy 69.399622 -120.971476) (xy 69.365536 -120.927333) (xy 69.33824 -120.878698)
			(xy 69.318317 -120.826607) (xy 69.306191 -120.77217) (xy 69.30212 -120.716548) (xy 65.661032 -120.716548)
			(xy 65.661032 -121.367296) (xy 65.660524 -121.386346) (xy 65.660541 -121.397939) (xy 65.66967 -121.419227)
			(xy 65.67805 -121.42724) (xy 65.702434 -121.448068) (xy 65.71141 -121.455062) (xy 65.733304 -121.461135)
			(xy 65.744598 -121.459752) (xy 65.761469 -121.45688) (xy 65.795557 -121.453829) (xy 65.81267 -121.453656)
			(xy 65.84004 -121.454126) (xy 65.89422 -121.461941) (xy 65.946723 -121.477428) (xy 65.99647 -121.500269)
			(xy 66.042437 -121.529994) (xy 66.063368 -121.547636) (xy 66.063622 -121.54789) (xy 66.070699 -121.553491)
			(xy 66.087623 -121.559729) (xy 66.096642 -121.560082) (xy 66.163698 -121.560082) (xy 66.172715 -121.559728)
			(xy 66.189632 -121.553479) (xy 66.196718 -121.54789) (xy 66.196718 -121.547636) (xy 66.196972 -121.547636)
			(xy 66.217908 -121.530002) (xy 66.263879 -121.500288) (xy 66.313626 -121.477451) (xy 66.366126 -121.461959)
			(xy 66.420301 -121.45413) (xy 66.44767 -121.453656) (xy 66.474667 -121.454104) (xy 66.528125 -121.4617)
			(xy 66.579976 -121.476758) (xy 66.629187 -121.498977) (xy 66.674772 -121.527914) (xy 66.715822 -121.56299)
			(xy 66.751515 -121.603504) (xy 66.781138 -121.648646) (xy 66.8041 -121.697515) (xy 66.819941 -121.749133)
			(xy 66.824606 -121.775728) (xy 66.82613 -121.786396) (xy 66.83756 -121.804176) (xy 66.917824 -121.857516)
			(xy 66.938398 -121.861326) (xy 66.948558 -121.858786) (xy 66.949066 -121.858786) (xy 66.975707 -121.852733)
			(xy 67.029953 -121.846233) (xy 67.05727 -121.845832) (xy 67.084588 -121.846219) (xy 67.138837 -121.852713)
			(xy 67.165474 -121.858786) (xy 67.165982 -121.858786) (xy 67.17621 -121.860664) (xy 67.19666 -121.856978)
			(xy 67.205606 -121.851674) (xy 67.27698 -121.804176) (xy 67.28841 -121.786396) (xy 67.289934 -121.775728)
			(xy 67.29459 -121.749123) (xy 67.310419 -121.697484) (xy 67.333371 -121.648592) (xy 67.362988 -121.603425)
			(xy 67.398677 -121.562886) (xy 67.439727 -121.527784) (xy 67.485315 -121.498821) (xy 67.534532 -121.476576)
			(xy 67.586394 -121.461492) (xy 67.639865 -121.453872) (xy 67.66687 -121.453402) (xy 67.694125 -121.453843)
			(xy 67.748081 -121.461597) (xy 67.800384 -121.47695) (xy 67.849969 -121.499592) (xy 67.895827 -121.52906)
			(xy 67.937024 -121.564754) (xy 67.972722 -121.605949) (xy 68.002194 -121.651805) (xy 68.024839 -121.701388)
			(xy 68.040197 -121.75369) (xy 68.047955 -121.807645) (xy 68.047955 -121.83491) (xy 71.885046 -121.83491)
			(xy 71.889117 -121.779288) (xy 71.901243 -121.724851) (xy 71.921166 -121.67276) (xy 71.948462 -121.624125)
			(xy 71.982548 -121.579982) (xy 72.022697 -121.541273) (xy 72.068055 -121.508822) (xy 72.117655 -121.483321)
			(xy 72.170439 -121.465314) (xy 72.225282 -121.455184) (xy 72.281016 -121.453147) (xy 72.336453 -121.459247)
			(xy 72.39041 -121.473353) (xy 72.441739 -121.495165) (xy 72.489345 -121.524219) (xy 72.532213 -121.559894)
			(xy 72.56943 -121.601431) (xy 72.600203 -121.647944) (xy 72.623875 -121.698441) (xy 72.639943 -121.751848)
			(xy 72.648063 -121.807024) (xy 72.648572 -121.83491) (xy 73.866246 -121.83491) (xy 73.870317 -121.779288)
			(xy 73.882443 -121.724851) (xy 73.902366 -121.67276) (xy 73.929662 -121.624125) (xy 73.963748 -121.579982)
			(xy 74.003897 -121.541273) (xy 74.049255 -121.508822) (xy 74.098855 -121.483321) (xy 74.151639 -121.465314)
			(xy 74.206482 -121.455184) (xy 74.262216 -121.453147) (xy 74.317653 -121.459247) (xy 74.37161 -121.473353)
			(xy 74.422939 -121.495165) (xy 74.470545 -121.524219) (xy 74.513413 -121.559894) (xy 74.55063 -121.601431)
			(xy 74.581403 -121.647944) (xy 74.605075 -121.698441) (xy 74.621143 -121.751848) (xy 74.629263 -121.807024)
			(xy 74.629772 -121.83491) (xy 74.629263 -121.862796) (xy 74.621143 -121.917972) (xy 74.605075 -121.971379)
			(xy 74.581403 -122.021876) (xy 74.55063 -122.068389) (xy 74.513413 -122.109926) (xy 74.49487 -122.125358)
			(xy 80.517109 -122.125358) (xy 80.517109 -122.070842) (xy 80.524868 -122.016881) (xy 80.540228 -121.964574)
			(xy 80.562876 -121.914985) (xy 80.592351 -121.869125) (xy 80.628053 -121.827926) (xy 80.669255 -121.792228)
			(xy 80.715119 -121.762758) (xy 80.76471 -121.740114) (xy 80.817018 -121.72476) (xy 80.87098 -121.717006)
			(xy 80.898238 -121.716546) (xy 80.924146 -121.716988) (xy 80.975485 -121.724017) (xy 81.0254 -121.737928)
			(xy 81.072974 -121.758464) (xy 81.117332 -121.785248) (xy 81.157658 -121.817788) (xy 81.193211 -121.855484)
			(xy 81.208626 -121.876312) (xy 81.214397 -121.883615) (xy 81.229877 -121.893917) (xy 81.238852 -121.896378)
			(xy 81.269332 -121.903236) (xy 81.27861 -121.904975) (xy 81.297271 -121.90224) (xy 81.305654 -121.897902)
			(xy 81.331621 -121.883589) (xy 81.386476 -121.861083) (xy 81.443782 -121.845861) (xy 81.502576 -121.838181)
			(xy 81.532222 -121.837704) (xy 81.561864 -121.838233) (xy 81.620644 -121.845947) (xy 81.677942 -121.861164)
			(xy 81.732804 -121.883633) (xy 81.75879 -121.897902) (xy 81.767202 -121.902151) (xy 81.785833 -121.904885)
			(xy 81.795112 -121.903236) (xy 81.825592 -121.896378) (xy 81.834592 -121.893972) (xy 81.850093 -121.883663)
			(xy 81.855818 -121.876312) (xy 81.871264 -121.855505) (xy 81.906798 -121.817791) (xy 81.947114 -121.785237)
			(xy 81.991467 -121.758444) (xy 82.03904 -121.737904) (xy 82.088957 -121.723998) (xy 82.140297 -121.71698)
			(xy 82.166206 -121.716546) (xy 82.193454 -121.717125) (xy 82.247394 -121.724881) (xy 82.299682 -121.740235)
			(xy 82.349252 -121.762873) (xy 82.395096 -121.792336) (xy 82.436281 -121.828023) (xy 82.471967 -121.869208)
			(xy 82.50143 -121.915053) (xy 82.524067 -121.964624) (xy 82.53942 -122.016912) (xy 82.547176 -122.070852)
			(xy 82.547176 -122.125348) (xy 82.53942 -122.179288) (xy 82.535677 -122.192034) (xy 89.450672 -122.192034)
			(xy 89.45114 -122.164664) (xy 89.458955 -122.110484) (xy 89.474443 -122.05798) (xy 89.497284 -122.008233)
			(xy 89.52701 -121.962267) (xy 89.544652 -121.941336) (xy 89.544906 -121.941082) (xy 89.550507 -121.934005)
			(xy 89.556745 -121.917081) (xy 89.557098 -121.908062) (xy 89.557098 -121.841006) (xy 89.556739 -121.831989)
			(xy 89.550493 -121.815072) (xy 89.544906 -121.807986) (xy 89.544652 -121.807986) (xy 89.544652 -121.807732)
			(xy 89.527044 -121.786773) (xy 89.497316 -121.74081) (xy 89.474467 -121.691068) (xy 89.458967 -121.63857)
			(xy 89.451134 -121.584395) (xy 89.451131 -121.529656) (xy 89.458956 -121.47548) (xy 89.474449 -121.42298)
			(xy 89.497291 -121.373235) (xy 89.527013 -121.327268) (xy 89.544652 -121.306336) (xy 89.544906 -121.306082)
			(xy 89.550507 -121.299005) (xy 89.556745 -121.282081) (xy 89.557098 -121.273062) (xy 89.557098 -121.206006)
			(xy 89.556739 -121.196989) (xy 89.550493 -121.180072) (xy 89.544906 -121.172986) (xy 89.544652 -121.172986)
			(xy 89.544652 -121.172732) (xy 89.527044 -121.151773) (xy 89.497316 -121.10581) (xy 89.474467 -121.056068)
			(xy 89.458967 -121.00357) (xy 89.451134 -120.949395) (xy 89.451131 -120.894656) (xy 89.458956 -120.84048)
			(xy 89.474449 -120.78798) (xy 89.497291 -120.738235) (xy 89.527013 -120.692268) (xy 89.544652 -120.671336)
			(xy 89.544906 -120.671082) (xy 89.550507 -120.664005) (xy 89.556745 -120.647081) (xy 89.557098 -120.638062)
			(xy 89.557098 -120.571006) (xy 89.556739 -120.561989) (xy 89.550493 -120.545072) (xy 89.544906 -120.537986)
			(xy 89.544652 -120.537986) (xy 89.544652 -120.537732) (xy 89.527023 -120.516792) (xy 89.497307 -120.470822)
			(xy 89.474469 -120.421077) (xy 89.458976 -120.368578) (xy 89.451146 -120.314403) (xy 89.450672 -120.287034)
			(xy 89.451158 -120.259783) (xy 89.458914 -120.205835) (xy 89.474269 -120.15354) (xy 89.496911 -120.103963)
			(xy 89.526377 -120.058113) (xy 89.562068 -120.016922) (xy 89.603259 -119.981231) (xy 89.649109 -119.951765)
			(xy 89.698686 -119.929123) (xy 89.750981 -119.913768) (xy 89.804929 -119.906012) (xy 89.859431 -119.906012)
			(xy 89.913379 -119.913768) (xy 89.965674 -119.929123) (xy 89.980745 -119.936006) (xy 92.694504 -119.936006)
			(xy 92.698575 -119.880384) (xy 92.710701 -119.825947) (xy 92.730624 -119.773856) (xy 92.75792 -119.725221)
			(xy 92.792006 -119.681078) (xy 92.832155 -119.642369) (xy 92.877513 -119.609918) (xy 92.927113 -119.584417)
			(xy 92.979897 -119.56641) (xy 93.03474 -119.55628) (xy 93.090474 -119.554243) (xy 93.145911 -119.560343)
			(xy 93.199868 -119.574449) (xy 93.251197 -119.596261) (xy 93.298803 -119.625315) (xy 93.341671 -119.66099)
			(xy 93.378888 -119.702527) (xy 93.409661 -119.74904) (xy 93.433333 -119.799537) (xy 93.449401 -119.852944)
			(xy 93.455308 -119.89308) (xy 97.569018 -119.89308) (xy 97.573089 -119.837458) (xy 97.585215 -119.783021)
			(xy 97.605138 -119.73093) (xy 97.632434 -119.682295) (xy 97.66652 -119.638152) (xy 97.706669 -119.599443)
			(xy 97.752027 -119.566992) (xy 97.801627 -119.541491) (xy 97.854411 -119.523484) (xy 97.909254 -119.513354)
			(xy 97.964988 -119.511317) (xy 98.020425 -119.517417) (xy 98.074382 -119.531523) (xy 98.125711 -119.553335)
			(xy 98.173317 -119.582389) (xy 98.216185 -119.618064) (xy 98.253402 -119.659601) (xy 98.284175 -119.706114)
			(xy 98.307847 -119.756611) (xy 98.323915 -119.810018) (xy 98.332035 -119.865194) (xy 98.332544 -119.89308)
			(xy 98.332035 -119.920966) (xy 98.323915 -119.976142) (xy 98.307847 -120.029549) (xy 98.284175 -120.080046)
			(xy 98.253402 -120.126559) (xy 98.216185 -120.168096) (xy 98.173317 -120.203771) (xy 98.125711 -120.232825)
			(xy 98.074382 -120.254637) (xy 98.020425 -120.268743) (xy 97.964988 -120.274843) (xy 97.909254 -120.272806)
			(xy 97.854411 -120.262676) (xy 97.801627 -120.244669) (xy 97.752027 -120.219168) (xy 97.706669 -120.186717)
			(xy 97.66652 -120.148008) (xy 97.632434 -120.103865) (xy 97.605138 -120.05523) (xy 97.585215 -120.003139)
			(xy 97.573089 -119.948702) (xy 97.569018 -119.89308) (xy 93.455308 -119.89308) (xy 93.457521 -119.90812)
			(xy 93.45803 -119.936006) (xy 93.457521 -119.963892) (xy 93.449401 -120.019068) (xy 93.433333 -120.072475)
			(xy 93.409661 -120.122972) (xy 93.378888 -120.169485) (xy 93.341671 -120.211022) (xy 93.298803 -120.246697)
			(xy 93.251197 -120.275751) (xy 93.199868 -120.297563) (xy 93.145911 -120.311669) (xy 93.090474 -120.317769)
			(xy 93.03474 -120.315732) (xy 92.979897 -120.305602) (xy 92.927113 -120.287595) (xy 92.877513 -120.262094)
			(xy 92.832155 -120.229643) (xy 92.792006 -120.190934) (xy 92.75792 -120.146791) (xy 92.730624 -120.098156)
			(xy 92.710701 -120.046065) (xy 92.698575 -119.991628) (xy 92.694504 -119.936006) (xy 89.980745 -119.936006)
			(xy 90.015251 -119.951765) (xy 90.061101 -119.981231) (xy 90.102292 -120.016922) (xy 90.137983 -120.058113)
			(xy 90.167449 -120.103963) (xy 90.190091 -120.15354) (xy 90.205446 -120.205835) (xy 90.213202 -120.259783)
			(xy 90.213688 -120.287034) (xy 90.213245 -120.314405) (xy 90.205422 -120.368585) (xy 90.189928 -120.421089)
			(xy 90.167081 -120.470835) (xy 90.152727 -120.493028) (xy 99.604066 -120.493028) (xy 99.608137 -120.437406)
			(xy 99.620263 -120.382969) (xy 99.640186 -120.330878) (xy 99.667482 -120.282243) (xy 99.701568 -120.2381)
			(xy 99.741717 -120.199391) (xy 99.787075 -120.16694) (xy 99.836675 -120.141439) (xy 99.889459 -120.123432)
			(xy 99.944302 -120.113302) (xy 100.000036 -120.111265) (xy 100.055473 -120.117365) (xy 100.10943 -120.131471)
			(xy 100.160759 -120.153283) (xy 100.208365 -120.182337) (xy 100.251233 -120.218012) (xy 100.28845 -120.259549)
			(xy 100.319223 -120.306062) (xy 100.342895 -120.356559) (xy 100.358963 -120.409966) (xy 100.367083 -120.465142)
			(xy 100.367592 -120.493028) (xy 100.367083 -120.520914) (xy 100.358963 -120.57609) (xy 100.342895 -120.629497)
			(xy 100.319223 -120.679994) (xy 100.28845 -120.726507) (xy 100.251233 -120.768044) (xy 100.222158 -120.79224)
			(xy 100.535992 -120.79224) (xy 100.540063 -120.736618) (xy 100.552189 -120.682181) (xy 100.572112 -120.63009)
			(xy 100.599408 -120.581455) (xy 100.633494 -120.537312) (xy 100.673643 -120.498603) (xy 100.719001 -120.466152)
			(xy 100.768601 -120.440651) (xy 100.821385 -120.422644) (xy 100.876228 -120.412514) (xy 100.931962 -120.410477)
			(xy 100.987399 -120.416577) (xy 101.041356 -120.430683) (xy 101.092685 -120.452495) (xy 101.140291 -120.481549)
			(xy 101.183159 -120.517224) (xy 101.220376 -120.558761) (xy 101.251149 -120.605274) (xy 101.274821 -120.655771)
			(xy 101.290889 -120.709178) (xy 101.299009 -120.764354) (xy 101.299518 -120.79224) (xy 102.691436 -120.79224)
			(xy 102.695507 -120.736618) (xy 102.707633 -120.682181) (xy 102.727556 -120.63009) (xy 102.754852 -120.581455)
			(xy 102.788938 -120.537312) (xy 102.829087 -120.498603) (xy 102.874445 -120.466152) (xy 102.924045 -120.440651)
			(xy 102.976829 -120.422644) (xy 103.031672 -120.412514) (xy 103.087406 -120.410477) (xy 103.142843 -120.416577)
			(xy 103.1968 -120.430683) (xy 103.248129 -120.452495) (xy 103.295735 -120.481549) (xy 103.338603 -120.517224)
			(xy 103.346737 -120.526302) (xy 104.203498 -120.526302) (xy 104.207569 -120.47068) (xy 104.219695 -120.416243)
			(xy 104.239618 -120.364152) (xy 104.266914 -120.315517) (xy 104.301 -120.271374) (xy 104.341149 -120.232665)
			(xy 104.386507 -120.200214) (xy 104.436107 -120.174713) (xy 104.488891 -120.156706) (xy 104.543734 -120.146576)
			(xy 104.599468 -120.144539) (xy 104.654905 -120.150639) (xy 104.708862 -120.164745) (xy 104.760191 -120.186557)
			(xy 104.807797 -120.215611) (xy 104.850665 -120.251286) (xy 104.887882 -120.292823) (xy 104.918655 -120.339336)
			(xy 104.942327 -120.389833) (xy 104.958395 -120.44324) (xy 104.966515 -120.498416) (xy 104.967024 -120.526302)
			(xy 105.993436 -120.526302) (xy 105.997507 -120.47068) (xy 106.009633 -120.416243) (xy 106.029556 -120.364152)
			(xy 106.056852 -120.315517) (xy 106.090938 -120.271374) (xy 106.131087 -120.232665) (xy 106.176445 -120.200214)
			(xy 106.226045 -120.174713) (xy 106.278829 -120.156706) (xy 106.333672 -120.146576) (xy 106.389406 -120.144539)
			(xy 106.444843 -120.150639) (xy 106.4988 -120.164745) (xy 106.550129 -120.186557) (xy 106.597735 -120.215611)
			(xy 106.640603 -120.251286) (xy 106.67782 -120.292823) (xy 106.708593 -120.339336) (xy 106.732265 -120.389833)
			(xy 106.748333 -120.44324) (xy 106.756453 -120.498416) (xy 106.756962 -120.526302) (xy 106.756453 -120.554188)
			(xy 106.748333 -120.609364) (xy 106.732265 -120.662771) (xy 106.708593 -120.713268) (xy 106.67782 -120.759781)
			(xy 106.640603 -120.801318) (xy 106.597735 -120.836993) (xy 106.550129 -120.866047) (xy 106.4988 -120.887859)
			(xy 106.444843 -120.901965) (xy 106.389406 -120.908065) (xy 106.333672 -120.906028) (xy 106.278829 -120.895898)
			(xy 106.226045 -120.877891) (xy 106.176445 -120.85239) (xy 106.131087 -120.819939) (xy 106.090938 -120.78123)
			(xy 106.056852 -120.737087) (xy 106.029556 -120.688452) (xy 106.009633 -120.636361) (xy 105.997507 -120.581924)
			(xy 105.993436 -120.526302) (xy 104.967024 -120.526302) (xy 104.966515 -120.554188) (xy 104.958395 -120.609364)
			(xy 104.942327 -120.662771) (xy 104.918655 -120.713268) (xy 104.887882 -120.759781) (xy 104.850665 -120.801318)
			(xy 104.807797 -120.836993) (xy 104.760191 -120.866047) (xy 104.708862 -120.887859) (xy 104.654905 -120.901965)
			(xy 104.599468 -120.908065) (xy 104.543734 -120.906028) (xy 104.488891 -120.895898) (xy 104.436107 -120.877891)
			(xy 104.386507 -120.85239) (xy 104.341149 -120.819939) (xy 104.301 -120.78123) (xy 104.266914 -120.737087)
			(xy 104.239618 -120.688452) (xy 104.219695 -120.636361) (xy 104.207569 -120.581924) (xy 104.203498 -120.526302)
			(xy 103.346737 -120.526302) (xy 103.37582 -120.558761) (xy 103.406593 -120.605274) (xy 103.430265 -120.655771)
			(xy 103.446333 -120.709178) (xy 103.454453 -120.764354) (xy 103.454962 -120.79224) (xy 103.454453 -120.820126)
			(xy 103.446333 -120.875302) (xy 103.430265 -120.928709) (xy 103.406593 -120.979206) (xy 103.37582 -121.025719)
			(xy 103.338696 -121.067152) (xy 117.690368 -121.067152) (xy 117.690368 -121.012648) (xy 117.698124 -120.9587)
			(xy 117.713479 -120.906404) (xy 117.736121 -120.856826) (xy 117.765587 -120.810975) (xy 117.801278 -120.769784)
			(xy 117.842469 -120.734092) (xy 117.888319 -120.704624) (xy 117.937897 -120.681982) (xy 117.990192 -120.666626)
			(xy 118.04414 -120.658868) (xy 118.071392 -120.658382) (xy 118.10031 -120.658875) (xy 118.157484 -120.667605)
			(xy 118.212685 -120.684866) (xy 118.264647 -120.710262) (xy 118.31218 -120.743212) (xy 118.354194 -120.782959)
			(xy 118.372382 -120.805448) (xy 118.379999 -120.814245) (xy 118.400892 -120.824432) (xy 118.412514 -120.825006)
			(xy 118.49227 -120.825006) (xy 118.503898 -120.824433) (xy 118.524807 -120.814268) (xy 118.532402 -120.805448)
			(xy 118.550579 -120.782953) (xy 118.592603 -120.743221) (xy 118.640141 -120.710285) (xy 118.692105 -120.684899)
			(xy 118.747305 -120.667644) (xy 118.804475 -120.658917) (xy 118.833392 -120.658382) (xy 118.860645 -120.658865)
			(xy 118.914595 -120.666621) (xy 118.966892 -120.681976) (xy 119.016472 -120.704617) (xy 119.062325 -120.734084)
			(xy 119.103518 -120.769777) (xy 119.111758 -120.779286) (xy 119.927114 -120.779286) (xy 119.931185 -120.723664)
			(xy 119.943311 -120.669227) (xy 119.963234 -120.617136) (xy 119.99053 -120.568501) (xy 120.024616 -120.524358)
			(xy 120.064765 -120.485649) (xy 120.110123 -120.453198) (xy 120.159723 -120.427697) (xy 120.212507 -120.40969)
			(xy 120.26735 -120.39956) (xy 120.323084 -120.397523) (xy 120.378521 -120.403623) (xy 120.432478 -120.417729)
			(xy 120.483807 -120.439541) (xy 120.531413 -120.468595) (xy 120.574281 -120.50427) (xy 120.611498 -120.545807)
			(xy 120.642271 -120.59232) (xy 120.665943 -120.642817) (xy 120.682011 -120.696224) (xy 120.690131 -120.7514)
			(xy 120.69064 -120.779286) (xy 120.690131 -120.807172) (xy 120.682011 -120.862348) (xy 120.665943 -120.915755)
			(xy 120.642271 -120.966252) (xy 120.611498 -121.012765) (xy 120.574281 -121.054302) (xy 120.531413 -121.089977)
			(xy 120.509852 -121.103136) (xy 122.095004 -121.103136) (xy 122.099075 -121.047514) (xy 122.111201 -120.993077)
			(xy 122.131124 -120.940986) (xy 122.15842 -120.892351) (xy 122.192506 -120.848208) (xy 122.232655 -120.809499)
			(xy 122.278013 -120.777048) (xy 122.327613 -120.751547) (xy 122.380397 -120.73354) (xy 122.43524 -120.72341)
			(xy 122.490974 -120.721373) (xy 122.546411 -120.727473) (xy 122.600368 -120.741579) (xy 122.651697 -120.763391)
			(xy 122.699303 -120.792445) (xy 122.742171 -120.82812) (xy 122.779388 -120.869657) (xy 122.810161 -120.91617)
			(xy 122.833833 -120.966667) (xy 122.849901 -121.020074) (xy 122.858021 -121.07525) (xy 122.85853 -121.103136)
			(xy 122.858021 -121.131022) (xy 122.849901 -121.186198) (xy 122.833833 -121.239605) (xy 122.810161 -121.290102)
			(xy 122.779388 -121.336615) (xy 122.742171 -121.378152) (xy 122.699303 -121.413827) (xy 122.651697 -121.442881)
			(xy 122.600368 -121.464693) (xy 122.546411 -121.478799) (xy 122.490974 -121.484899) (xy 122.43524 -121.482862)
			(xy 122.380397 -121.472732) (xy 122.327613 -121.454725) (xy 122.278013 -121.429224) (xy 122.232655 -121.396773)
			(xy 122.192506 -121.358064) (xy 122.15842 -121.313921) (xy 122.131124 -121.265286) (xy 122.111201 -121.213195)
			(xy 122.099075 -121.158758) (xy 122.095004 -121.103136) (xy 120.509852 -121.103136) (xy 120.483807 -121.119031)
			(xy 120.432478 -121.140843) (xy 120.378521 -121.154949) (xy 120.323084 -121.161049) (xy 120.26735 -121.159012)
			(xy 120.212507 -121.148882) (xy 120.159723 -121.130875) (xy 120.110123 -121.105374) (xy 120.064765 -121.072923)
			(xy 120.024616 -121.034214) (xy 119.99053 -120.990071) (xy 119.963234 -120.941436) (xy 119.943311 -120.889345)
			(xy 119.931185 -120.834908) (xy 119.927114 -120.779286) (xy 119.111758 -120.779286) (xy 119.139211 -120.810969)
			(xy 119.168679 -120.856821) (xy 119.191322 -120.9064) (xy 119.206678 -120.958697) (xy 119.214435 -121.012647)
			(xy 119.214435 -121.067153) (xy 119.206678 -121.121103) (xy 119.191322 -121.1734) (xy 119.168679 -121.222979)
			(xy 119.139211 -121.268831) (xy 119.103518 -121.310023) (xy 119.062325 -121.345716) (xy 119.016472 -121.375183)
			(xy 118.966892 -121.397824) (xy 118.914595 -121.413179) (xy 118.860645 -121.420935) (xy 118.833392 -121.421398)
			(xy 118.804477 -121.420815) (xy 118.747309 -121.412099) (xy 118.692112 -121.394854) (xy 118.64015 -121.369475)
			(xy 118.592614 -121.336543) (xy 118.550594 -121.296812) (xy 118.532402 -121.274332) (xy 118.524796 -121.265524)
			(xy 118.503894 -121.255344) (xy 118.49227 -121.254774) (xy 118.412514 -121.254774) (xy 118.400881 -121.25531)
			(xy 118.37997 -121.265498) (xy 118.372382 -121.274332) (xy 118.354209 -121.296831) (xy 118.312185 -121.336564)
			(xy 118.264646 -121.3695) (xy 118.212681 -121.394885) (xy 118.157481 -121.412139) (xy 118.100309 -121.420865)
			(xy 118.071392 -121.421398) (xy 118.04414 -121.420932) (xy 117.990192 -121.413174) (xy 117.937897 -121.397818)
			(xy 117.888319 -121.375176) (xy 117.842469 -121.345708) (xy 117.801278 -121.310016) (xy 117.765587 -121.268825)
			(xy 117.736121 -121.222974) (xy 117.713479 -121.173396) (xy 117.698124 -121.1211) (xy 117.690368 -121.067152)
			(xy 103.338696 -121.067152) (xy 103.338603 -121.067256) (xy 103.295735 -121.102931) (xy 103.248129 -121.131985)
			(xy 103.1968 -121.153797) (xy 103.142843 -121.167903) (xy 103.087406 -121.174003) (xy 103.031672 -121.171966)
			(xy 102.976829 -121.161836) (xy 102.924045 -121.143829) (xy 102.874445 -121.118328) (xy 102.829087 -121.085877)
			(xy 102.788938 -121.047168) (xy 102.754852 -121.003025) (xy 102.727556 -120.95439) (xy 102.707633 -120.902299)
			(xy 102.695507 -120.847862) (xy 102.691436 -120.79224) (xy 101.299518 -120.79224) (xy 101.299009 -120.820126)
			(xy 101.290889 -120.875302) (xy 101.274821 -120.928709) (xy 101.251149 -120.979206) (xy 101.220376 -121.025719)
			(xy 101.183159 -121.067256) (xy 101.140291 -121.102931) (xy 101.092685 -121.131985) (xy 101.041356 -121.153797)
			(xy 100.987399 -121.167903) (xy 100.931962 -121.174003) (xy 100.876228 -121.171966) (xy 100.821385 -121.161836)
			(xy 100.768601 -121.143829) (xy 100.719001 -121.118328) (xy 100.673643 -121.085877) (xy 100.633494 -121.047168)
			(xy 100.599408 -121.003025) (xy 100.572112 -120.95439) (xy 100.552189 -120.902299) (xy 100.540063 -120.847862)
			(xy 100.535992 -120.79224) (xy 100.222158 -120.79224) (xy 100.208365 -120.803719) (xy 100.160759 -120.832773)
			(xy 100.10943 -120.854585) (xy 100.055473 -120.868691) (xy 100.000036 -120.874791) (xy 99.944302 -120.872754)
			(xy 99.889459 -120.862624) (xy 99.836675 -120.844617) (xy 99.787075 -120.819116) (xy 99.741717 -120.786665)
			(xy 99.701568 -120.747956) (xy 99.667482 -120.703813) (xy 99.640186 -120.655178) (xy 99.620263 -120.603087)
			(xy 99.608137 -120.54865) (xy 99.604066 -120.493028) (xy 90.152727 -120.493028) (xy 90.137351 -120.516801)
			(xy 90.119708 -120.537732) (xy 90.119454 -120.537986) (xy 90.113862 -120.545068) (xy 90.10762 -120.561989)
			(xy 90.107262 -120.571006) (xy 90.107262 -120.638062) (xy 90.107645 -120.647076) (xy 90.113876 -120.663993)
			(xy 90.119454 -120.671082) (xy 90.119708 -120.671082) (xy 90.119708 -120.671336) (xy 90.137381 -120.692242)
			(xy 90.167101 -120.738216) (xy 90.189943 -120.787966) (xy 90.205435 -120.840472) (xy 90.213259 -120.894654)
			(xy 90.213256 -120.949397) (xy 90.205424 -121.003578) (xy 90.189925 -121.056082) (xy 90.167077 -121.105829)
			(xy 90.13735 -121.151799) (xy 90.119708 -121.172732) (xy 90.119454 -121.172986) (xy 90.113862 -121.180068)
			(xy 90.10762 -121.196989) (xy 90.10755 -121.198753) (xy 90.48544 -121.198753) (xy 90.48544 -121.144247)
			(xy 90.493196 -121.090297) (xy 90.508551 -121.038) (xy 90.531192 -120.98842) (xy 90.560659 -120.942566)
			(xy 90.59635 -120.901373) (xy 90.637541 -120.865678) (xy 90.683392 -120.836208) (xy 90.73297 -120.813562)
			(xy 90.785266 -120.798203) (xy 90.839216 -120.790442) (xy 90.866468 -120.789954) (xy 90.893838 -120.790426)
			(xy 90.948018 -120.79824) (xy 91.000521 -120.813727) (xy 91.050268 -120.836568) (xy 91.096235 -120.866293)
			(xy 91.117166 -120.883934) (xy 91.11742 -120.884188) (xy 91.124498 -120.889788) (xy 91.141421 -120.896027)
			(xy 91.15044 -120.89638) (xy 91.217496 -120.89638) (xy 91.226513 -120.896026) (xy 91.24343 -120.889777)
			(xy 91.250516 -120.884188) (xy 91.250516 -120.883934) (xy 91.25077 -120.883934) (xy 91.271707 -120.866301)
			(xy 91.317678 -120.836587) (xy 91.367424 -120.813749) (xy 91.419924 -120.798257) (xy 91.474099 -120.790428)
			(xy 91.501468 -120.789954) (xy 91.52872 -120.790491) (xy 91.582669 -120.798244) (xy 91.634965 -120.813595)
			(xy 91.684544 -120.836234) (xy 91.730397 -120.865698) (xy 91.771589 -120.901388) (xy 91.807283 -120.942577)
			(xy 91.836751 -120.988428) (xy 91.859394 -121.038005) (xy 91.87475 -121.0903) (xy 91.882507 -121.144248)
			(xy 91.882507 -121.198752) (xy 91.87475 -121.2527) (xy 91.859394 -121.304995) (xy 91.836751 -121.354572)
			(xy 91.807283 -121.400423) (xy 91.771589 -121.441612) (xy 91.730397 -121.477302) (xy 91.684544 -121.506766)
			(xy 91.634965 -121.529405) (xy 91.582669 -121.544756) (xy 91.52872 -121.552509) (xy 91.501468 -121.55297)
			(xy 91.474097 -121.55253) (xy 91.419916 -121.544707) (xy 91.367413 -121.529212) (xy 91.317666 -121.506365)
			(xy 91.271701 -121.476634) (xy 91.25077 -121.45899) (xy 91.250516 -121.458736) (xy 91.243435 -121.453142)
			(xy 91.226514 -121.446902) (xy 91.217496 -121.446544) (xy 91.15044 -121.446544) (xy 91.141424 -121.446911)
			(xy 91.124506 -121.45315) (xy 91.11742 -121.458736) (xy 91.11742 -121.45899) (xy 91.117166 -121.45899)
			(xy 91.096219 -121.47661) (xy 91.05025 -121.506325) (xy 91.000507 -121.529165) (xy 90.948009 -121.54466)
			(xy 90.893836 -121.552493) (xy 90.866468 -121.55297) (xy 90.839216 -121.552558) (xy 90.785266 -121.544797)
			(xy 90.73297 -121.529438) (xy 90.683392 -121.506792) (xy 90.637541 -121.477322) (xy 90.59635 -121.441627)
			(xy 90.560659 -121.400434) (xy 90.531192 -121.35458) (xy 90.508551 -121.305) (xy 90.493196 -121.252703)
			(xy 90.48544 -121.198753) (xy 90.10755 -121.198753) (xy 90.107262 -121.206006) (xy 90.107262 -121.273062)
			(xy 90.107645 -121.282076) (xy 90.113876 -121.298993) (xy 90.119454 -121.306082) (xy 90.119708 -121.306082)
			(xy 90.119708 -121.306336) (xy 90.137381 -121.327242) (xy 90.167101 -121.373216) (xy 90.189943 -121.422966)
			(xy 90.205435 -121.475472) (xy 90.213259 -121.529654) (xy 90.213256 -121.581672) (xy 91.994736 -121.581672)
			(xy 91.995177 -121.554301) (xy 92.002999 -121.50012) (xy 92.018494 -121.447617) (xy 92.041341 -121.39787)
			(xy 92.071072 -121.351905) (xy 92.088716 -121.330974) (xy 92.08897 -121.33072) (xy 92.094563 -121.323638)
			(xy 92.100804 -121.306717) (xy 92.101162 -121.2977) (xy 92.101162 -121.230644) (xy 92.100792 -121.221628)
			(xy 92.094554 -121.204711) (xy 92.08897 -121.197624) (xy 92.088716 -121.197624) (xy 92.088716 -121.19737)
			(xy 92.071099 -121.17642) (xy 92.041383 -121.130453) (xy 92.018543 -121.08071) (xy 92.003047 -121.028213)
			(xy 91.995213 -120.97404) (xy 91.994736 -120.946672) (xy 91.995129 -120.919416) (xy 92.002891 -120.865461)
			(xy 92.018253 -120.813159) (xy 92.040902 -120.763576) (xy 92.070377 -120.71772) (xy 92.106078 -120.676527)
			(xy 92.147278 -120.640834) (xy 92.193139 -120.611367) (xy 92.242726 -120.588728) (xy 92.295031 -120.573376)
			(xy 92.348988 -120.565624) (xy 92.376244 -120.565164) (xy 92.405365 -120.565735) (xy 92.462934 -120.574566)
			(xy 92.518491 -120.592047) (xy 92.570744 -120.617772) (xy 92.618478 -120.651142) (xy 92.660584 -120.691381)
			(xy 92.696083 -120.737554) (xy 92.724149 -120.788588) (xy 92.74413 -120.843295) (xy 92.750386 -120.871742)
			(xy 92.752672 -120.883426) (xy 92.76715 -120.902222) (xy 92.851224 -120.942608) (xy 92.862036 -120.947177)
			(xy 92.885477 -120.946915) (xy 92.896182 -120.9421) (xy 92.89669 -120.9421) (xy 92.923744 -120.928808)
			(xy 92.981022 -120.910034) (xy 93.040542 -120.900519) (xy 93.07068 -120.899936) (xy 93.097934 -120.900374)
			(xy 93.151888 -120.908129) (xy 93.20419 -120.923485) (xy 93.253772 -120.946129) (xy 93.299628 -120.975599)
			(xy 93.340822 -121.011295) (xy 93.376516 -121.052491) (xy 93.405983 -121.098349) (xy 93.428623 -121.147933)
			(xy 93.443976 -121.200235) (xy 93.449513 -121.238772) (xy 97.584258 -121.238772) (xy 97.588329 -121.18315)
			(xy 97.600455 -121.128713) (xy 97.620378 -121.076622) (xy 97.647674 -121.027987) (xy 97.68176 -120.983844)
			(xy 97.721909 -120.945135) (xy 97.767267 -120.912684) (xy 97.816867 -120.887183) (xy 97.869651 -120.869176)
			(xy 97.924494 -120.859046) (xy 97.980228 -120.857009) (xy 98.035665 -120.863109) (xy 98.089622 -120.877215)
			(xy 98.140951 -120.899027) (xy 98.188557 -120.928081) (xy 98.231425 -120.963756) (xy 98.268642 -121.005293)
			(xy 98.299415 -121.051806) (xy 98.323087 -121.102303) (xy 98.339155 -121.15571) (xy 98.347275 -121.210886)
			(xy 98.347784 -121.238772) (xy 98.347275 -121.266658) (xy 98.339155 -121.321834) (xy 98.323087 -121.375241)
			(xy 98.299415 -121.425738) (xy 98.268642 -121.472251) (xy 98.23569 -121.509028) (xy 99.629466 -121.509028)
			(xy 99.633537 -121.453406) (xy 99.645663 -121.398969) (xy 99.665586 -121.346878) (xy 99.692882 -121.298243)
			(xy 99.726968 -121.2541) (xy 99.767117 -121.215391) (xy 99.812475 -121.18294) (xy 99.862075 -121.157439)
			(xy 99.914859 -121.139432) (xy 99.969702 -121.129302) (xy 100.025436 -121.127265) (xy 100.080873 -121.133365)
			(xy 100.13483 -121.147471) (xy 100.186159 -121.169283) (xy 100.233765 -121.198337) (xy 100.276633 -121.234012)
			(xy 100.31385 -121.275549) (xy 100.344623 -121.322062) (xy 100.368295 -121.372559) (xy 100.384363 -121.425966)
			(xy 100.392483 -121.481142) (xy 100.392992 -121.509028) (xy 100.392483 -121.536914) (xy 100.384363 -121.59209)
			(xy 100.368295 -121.645497) (xy 100.344623 -121.695994) (xy 100.31385 -121.742507) (xy 100.276633 -121.784044)
			(xy 100.247558 -121.80824) (xy 100.535992 -121.80824) (xy 100.540063 -121.752618) (xy 100.552189 -121.698181)
			(xy 100.572112 -121.64609) (xy 100.599408 -121.597455) (xy 100.633494 -121.553312) (xy 100.673643 -121.514603)
			(xy 100.719001 -121.482152) (xy 100.768601 -121.456651) (xy 100.821385 -121.438644) (xy 100.876228 -121.428514)
			(xy 100.931962 -121.426477) (xy 100.987399 -121.432577) (xy 101.041356 -121.446683) (xy 101.092685 -121.468495)
			(xy 101.140291 -121.497549) (xy 101.183159 -121.533224) (xy 101.220376 -121.574761) (xy 101.251149 -121.621274)
			(xy 101.269972 -121.661428) (xy 124.772926 -121.661428) (xy 124.776997 -121.605806) (xy 124.789123 -121.551369)
			(xy 124.809046 -121.499278) (xy 124.836342 -121.450643) (xy 124.870428 -121.4065) (xy 124.910577 -121.367791)
			(xy 124.955935 -121.33534) (xy 125.005535 -121.309839) (xy 125.058319 -121.291832) (xy 125.113162 -121.281702)
			(xy 125.168896 -121.279665) (xy 125.224333 -121.285765) (xy 125.27829 -121.299871) (xy 125.329619 -121.321683)
			(xy 125.377225 -121.350737) (xy 125.420093 -121.386412) (xy 125.45731 -121.427949) (xy 125.488083 -121.474462)
			(xy 125.511755 -121.524959) (xy 125.527823 -121.578366) (xy 125.535943 -121.633542) (xy 125.536452 -121.661428)
			(xy 125.535943 -121.689314) (xy 125.527823 -121.74449) (xy 125.511755 -121.797897) (xy 125.488083 -121.848394)
			(xy 125.45731 -121.894907) (xy 125.420093 -121.936444) (xy 125.377225 -121.972119) (xy 125.329619 -122.001173)
			(xy 125.27829 -122.022985) (xy 125.224333 -122.037091) (xy 125.168896 -122.043191) (xy 125.113162 -122.041154)
			(xy 125.058319 -122.031024) (xy 125.005535 -122.013017) (xy 124.955935 -121.987516) (xy 124.910577 -121.955065)
			(xy 124.870428 -121.916356) (xy 124.836342 -121.872213) (xy 124.809046 -121.823578) (xy 124.789123 -121.771487)
			(xy 124.776997 -121.71705) (xy 124.772926 -121.661428) (xy 101.269972 -121.661428) (xy 101.274821 -121.671771)
			(xy 101.290889 -121.725178) (xy 101.299009 -121.780354) (xy 101.299518 -121.80824) (xy 101.299009 -121.836126)
			(xy 101.290889 -121.891302) (xy 101.274821 -121.944709) (xy 101.251149 -121.995206) (xy 101.220376 -122.041719)
			(xy 101.183159 -122.083256) (xy 101.140291 -122.118931) (xy 101.092685 -122.147985) (xy 101.041356 -122.169797)
			(xy 100.987399 -122.183903) (xy 100.931962 -122.190003) (xy 100.876228 -122.187966) (xy 100.821385 -122.177836)
			(xy 100.768601 -122.159829) (xy 100.719001 -122.134328) (xy 100.673643 -122.101877) (xy 100.633494 -122.063168)
			(xy 100.599408 -122.019025) (xy 100.572112 -121.97039) (xy 100.552189 -121.918299) (xy 100.540063 -121.863862)
			(xy 100.535992 -121.80824) (xy 100.247558 -121.80824) (xy 100.233765 -121.819719) (xy 100.186159 -121.848773)
			(xy 100.13483 -121.870585) (xy 100.080873 -121.884691) (xy 100.025436 -121.890791) (xy 99.969702 -121.888754)
			(xy 99.914859 -121.878624) (xy 99.862075 -121.860617) (xy 99.812475 -121.835116) (xy 99.767117 -121.802665)
			(xy 99.726968 -121.763956) (xy 99.692882 -121.719813) (xy 99.665586 -121.671178) (xy 99.645663 -121.619087)
			(xy 99.633537 -121.56465) (xy 99.629466 -121.509028) (xy 98.23569 -121.509028) (xy 98.231425 -121.513788)
			(xy 98.188557 -121.549463) (xy 98.140951 -121.578517) (xy 98.089622 -121.600329) (xy 98.035665 -121.614435)
			(xy 97.980228 -121.620535) (xy 97.924494 -121.618498) (xy 97.869651 -121.608368) (xy 97.816867 -121.590361)
			(xy 97.767267 -121.56486) (xy 97.721909 -121.532409) (xy 97.68176 -121.4937) (xy 97.647674 -121.449557)
			(xy 97.620378 -121.400922) (xy 97.600455 -121.348831) (xy 97.588329 -121.294394) (xy 97.584258 -121.238772)
			(xy 93.449513 -121.238772) (xy 93.451728 -121.25419) (xy 93.452188 -121.281444) (xy 93.451692 -121.308813)
			(xy 93.443882 -121.362991) (xy 93.4284 -121.415494) (xy 93.405565 -121.465241) (xy 93.375846 -121.511209)
			(xy 93.358208 -121.532142) (xy 93.357954 -121.532396) (xy 93.352357 -121.539476) (xy 93.346118 -121.556398)
			(xy 93.345762 -121.565416) (xy 93.345762 -121.632472) (xy 93.346141 -121.641486) (xy 93.352374 -121.658403)
			(xy 93.357954 -121.665492) (xy 93.358208 -121.665492) (xy 93.358208 -121.665746) (xy 93.375836 -121.686687)
			(xy 93.40555 -121.732657) (xy 93.428387 -121.782403) (xy 93.443881 -121.834901) (xy 93.451712 -121.889075)
			(xy 93.452188 -121.916444) (xy 93.451763 -121.943697) (xy 93.444 -121.997648) (xy 93.428638 -122.049945)
			(xy 93.405991 -122.099524) (xy 93.376518 -122.145375) (xy 93.34082 -122.186565) (xy 93.299624 -122.222256)
			(xy 93.253768 -122.251721) (xy 93.204185 -122.274361) (xy 93.151886 -122.289714) (xy 93.097933 -122.297468)
			(xy 93.07068 -122.297952) (xy 93.041557 -122.297438) (xy 92.983987 -122.288596) (xy 92.928429 -122.271105)
			(xy 92.876177 -122.245372) (xy 92.828443 -122.211995) (xy 92.786338 -122.171749) (xy 92.75084 -122.125571)
			(xy 92.722774 -122.074533) (xy 92.702793 -122.019822) (xy 92.696538 -121.991374) (xy 92.694252 -121.97969)
			(xy 92.679774 -121.960894) (xy 92.5957 -121.920508) (xy 92.584883 -121.915953) (xy 92.561446 -121.916206)
			(xy 92.550742 -121.921016) (xy 92.550234 -121.921016) (xy 92.523177 -121.934301) (xy 92.4659 -121.953077)
			(xy 92.406381 -121.962596) (xy 92.376244 -121.96318) (xy 92.348991 -121.962704) (xy 92.295039 -121.954952)
			(xy 92.24274 -121.9396) (xy 92.193158 -121.916961) (xy 92.147303 -121.887495) (xy 92.106109 -121.851802)
			(xy 92.070415 -121.81061) (xy 92.040947 -121.764756) (xy 92.018305 -121.715175) (xy 92.002951 -121.662877)
			(xy 91.995197 -121.608925) (xy 91.994736 -121.581672) (xy 90.213256 -121.581672) (xy 90.213256 -121.584397)
			(xy 90.205424 -121.638578) (xy 90.189925 -121.691082) (xy 90.167077 -121.740829) (xy 90.13735 -121.786799)
			(xy 90.119708 -121.807732) (xy 90.119454 -121.807986) (xy 90.113862 -121.815068) (xy 90.10762 -121.831989)
			(xy 90.107262 -121.841006) (xy 90.107262 -121.908062) (xy 90.107645 -121.917076) (xy 90.113876 -121.933993)
			(xy 90.119454 -121.941082) (xy 90.119708 -121.941082) (xy 90.119708 -121.941336) (xy 90.137332 -121.96228)
			(xy 90.167046 -122.00825) (xy 90.189884 -122.057994) (xy 90.205379 -122.110492) (xy 90.213212 -122.164666)
			(xy 90.213688 -122.192034) (xy 90.213202 -122.219285) (xy 90.205446 -122.273233) (xy 90.190091 -122.325528)
			(xy 90.167449 -122.375105) (xy 90.137983 -122.420955) (xy 90.102292 -122.462146) (xy 90.061101 -122.497837)
			(xy 90.018791 -122.525028) (xy 99.60559 -122.525028) (xy 99.609661 -122.469406) (xy 99.621787 -122.414969)
			(xy 99.64171 -122.362878) (xy 99.669006 -122.314243) (xy 99.703092 -122.2701) (xy 99.743241 -122.231391)
			(xy 99.788599 -122.19894) (xy 99.838199 -122.173439) (xy 99.890983 -122.155432) (xy 99.945826 -122.145302)
			(xy 100.00156 -122.143265) (xy 100.056997 -122.149365) (xy 100.110954 -122.163471) (xy 100.162283 -122.185283)
			(xy 100.209889 -122.214337) (xy 100.252757 -122.250012) (xy 100.289974 -122.291549) (xy 100.320747 -122.338062)
			(xy 100.344419 -122.388559) (xy 100.360487 -122.441966) (xy 100.368607 -122.497142) (xy 100.369116 -122.525028)
			(xy 100.368607 -122.552914) (xy 100.360487 -122.60809) (xy 100.344419 -122.661497) (xy 100.320747 -122.711994)
			(xy 100.289974 -122.758507) (xy 100.252757 -122.800044) (xy 100.209889 -122.835719) (xy 100.162283 -122.864773)
			(xy 100.110954 -122.886585) (xy 100.056997 -122.900691) (xy 100.00156 -122.906791) (xy 99.945826 -122.904754)
			(xy 99.890983 -122.894624) (xy 99.838199 -122.876617) (xy 99.788599 -122.851116) (xy 99.743241 -122.818665)
			(xy 99.703092 -122.779956) (xy 99.669006 -122.735813) (xy 99.64171 -122.687178) (xy 99.621787 -122.635087)
			(xy 99.609661 -122.58065) (xy 99.60559 -122.525028) (xy 90.018791 -122.525028) (xy 90.015251 -122.527303)
			(xy 89.965674 -122.549945) (xy 89.913379 -122.5653) (xy 89.859431 -122.573056) (xy 89.804929 -122.573056)
			(xy 89.750981 -122.5653) (xy 89.698686 -122.549945) (xy 89.649109 -122.527303) (xy 89.603259 -122.497837)
			(xy 89.562068 -122.462146) (xy 89.526377 -122.420955) (xy 89.496911 -122.375105) (xy 89.474269 -122.325528)
			(xy 89.458914 -122.273233) (xy 89.451158 -122.219285) (xy 89.450672 -122.192034) (xy 82.535677 -122.192034)
			(xy 82.524067 -122.231576) (xy 82.50143 -122.281147) (xy 82.471967 -122.326992) (xy 82.436281 -122.368177)
			(xy 82.395096 -122.403864) (xy 82.349252 -122.433327) (xy 82.299682 -122.455965) (xy 82.247394 -122.471319)
			(xy 82.193454 -122.479075) (xy 82.166206 -122.479562) (xy 82.151413 -122.479428) (xy 82.121915 -122.477138)
			(xy 82.107278 -122.47499) (xy 82.096303 -122.473861) (xy 82.075112 -122.479924) (xy 82.066384 -122.486674)
			(xy 82.007964 -122.536712) (xy 81.999932 -122.544276) (xy 81.99072 -122.564299) (xy 81.990184 -122.57532)
			(xy 81.990184 -122.879612) (xy 81.99072 -122.890631) (xy 81.999941 -122.910647) (xy 82.007964 -122.91822)
			(xy 82.023393 -122.931428) (xy 124.772926 -122.931428) (xy 124.776997 -122.875806) (xy 124.789123 -122.821369)
			(xy 124.809046 -122.769278) (xy 124.836342 -122.720643) (xy 124.870428 -122.6765) (xy 124.910577 -122.637791)
			(xy 124.955935 -122.60534) (xy 125.005535 -122.579839) (xy 125.058319 -122.561832) (xy 125.113162 -122.551702)
			(xy 125.168896 -122.549665) (xy 125.224333 -122.555765) (xy 125.27829 -122.569871) (xy 125.329619 -122.591683)
			(xy 125.377225 -122.620737) (xy 125.420093 -122.656412) (xy 125.45731 -122.697949) (xy 125.488083 -122.744462)
			(xy 125.511755 -122.794959) (xy 125.527823 -122.848366) (xy 125.535943 -122.903542) (xy 125.536452 -122.931428)
			(xy 125.535943 -122.959314) (xy 125.527823 -123.01449) (xy 125.511755 -123.067897) (xy 125.488083 -123.118394)
			(xy 125.45731 -123.164907) (xy 125.420093 -123.206444) (xy 125.377225 -123.242119) (xy 125.329619 -123.271173)
			(xy 125.27829 -123.292985) (xy 125.224333 -123.307091) (xy 125.168896 -123.313191) (xy 125.113162 -123.311154)
			(xy 125.058319 -123.301024) (xy 125.005535 -123.283017) (xy 124.955935 -123.257516) (xy 124.910577 -123.225065)
			(xy 124.870428 -123.186356) (xy 124.836342 -123.142213) (xy 124.809046 -123.093578) (xy 124.789123 -123.041487)
			(xy 124.776997 -122.98705) (xy 124.772926 -122.931428) (xy 82.023393 -122.931428) (xy 82.07502 -122.975624)
			(xy 82.096102 -122.98172) (xy 82.107278 -122.979942) (xy 82.121915 -122.977797) (xy 82.151413 -122.975512)
			(xy 82.166206 -122.97537) (xy 82.193455 -122.975901) (xy 82.247399 -122.983657) (xy 82.29969 -122.999012)
			(xy 82.349264 -123.021652) (xy 82.395111 -123.051117) (xy 82.436298 -123.086806) (xy 82.471987 -123.127994)
			(xy 82.501451 -123.173842) (xy 82.52409 -123.223415) (xy 82.539444 -123.275707) (xy 82.5472 -123.329651)
			(xy 82.5472 -123.364553) (xy 94.064275 -123.364553) (xy 94.064275 -123.310047) (xy 94.072033 -123.256097)
			(xy 94.087389 -123.203799) (xy 94.110033 -123.15422) (xy 94.139502 -123.108368) (xy 94.175197 -123.067177)
			(xy 94.21639 -123.031485) (xy 94.262245 -123.002019) (xy 94.311826 -122.97938) (xy 94.364124 -122.964027)
			(xy 94.418075 -122.956273) (xy 94.445328 -122.955812) (xy 94.472699 -122.956259) (xy 94.526879 -122.964081)
			(xy 94.579382 -122.979574) (xy 94.629129 -123.00242) (xy 94.675095 -123.032149) (xy 94.696026 -123.049792)
			(xy 94.69628 -123.050046) (xy 94.703364 -123.055636) (xy 94.720283 -123.061879) (xy 94.7293 -123.062238)
			(xy 94.796356 -123.062238) (xy 94.80537 -123.061852) (xy 94.822286 -123.055624) (xy 94.829376 -123.050046)
			(xy 94.829376 -123.049792) (xy 94.82963 -123.049792) (xy 94.850563 -123.032151) (xy 94.896531 -123.002427)
			(xy 94.946277 -122.979581) (xy 94.998779 -122.964085) (xy 95.052957 -122.956256) (xy 95.107699 -122.956256)
			(xy 95.161877 -122.964085) (xy 95.214379 -122.979581) (xy 95.264125 -123.002427) (xy 95.310093 -123.032151)
			(xy 95.331026 -123.049792) (xy 95.33128 -123.050046) (xy 95.338364 -123.055636) (xy 95.355283 -123.061879)
			(xy 95.3643 -123.062238) (xy 95.431356 -123.062238) (xy 95.44037 -123.061852) (xy 95.457286 -123.055624)
			(xy 95.464376 -123.050046) (xy 95.464376 -123.049792) (xy 95.46463 -123.049792) (xy 95.485577 -123.032171)
			(xy 95.531546 -123.002457) (xy 95.581289 -122.979617) (xy 95.633787 -122.964122) (xy 95.68796 -122.956289)
			(xy 95.715328 -122.955812) (xy 95.742579 -122.95626) (xy 95.796527 -122.96402) (xy 95.848821 -122.979378)
			(xy 95.898397 -123.002022) (xy 95.944247 -123.031491) (xy 95.985436 -123.067184) (xy 96.021126 -123.108376)
			(xy 96.050591 -123.154227) (xy 96.073232 -123.203805) (xy 96.088586 -123.256101) (xy 96.096342 -123.310049)
			(xy 96.096342 -123.364551) (xy 96.088586 -123.4185) (xy 96.073232 -123.470795) (xy 96.050591 -123.520373)
			(xy 96.021126 -123.566224) (xy 95.985436 -123.607416) (xy 95.944247 -123.643109) (xy 95.898397 -123.672578)
			(xy 95.848821 -123.695222) (xy 95.796527 -123.71058) (xy 95.742579 -123.71834) (xy 95.715328 -123.718828)
			(xy 95.687958 -123.718363) (xy 95.633778 -123.710548) (xy 95.581274 -123.695059) (xy 95.531527 -123.672217)
			(xy 95.485561 -123.64249) (xy 95.46463 -123.624848) (xy 95.464376 -123.624594) (xy 95.457301 -123.618991)
			(xy 95.440375 -123.612754) (xy 95.431356 -123.612402) (xy 95.3643 -123.612402) (xy 95.355283 -123.612759)
			(xy 95.338366 -123.619006) (xy 95.33128 -123.624594) (xy 95.331026 -123.624848) (xy 95.310093 -123.642489)
			(xy 95.264125 -123.672213) (xy 95.214379 -123.695059) (xy 95.161877 -123.710555) (xy 95.107699 -123.718384)
			(xy 95.052957 -123.718384) (xy 94.998779 -123.710555) (xy 94.946277 -123.695059) (xy 94.896531 -123.672213)
			(xy 94.850563 -123.642489) (xy 94.82963 -123.624848) (xy 94.829376 -123.624594) (xy 94.822301 -123.618991)
			(xy 94.805375 -123.612754) (xy 94.796356 -123.612402) (xy 94.7293 -123.612402) (xy 94.720283 -123.612759)
			(xy 94.703366 -123.619006) (xy 94.69628 -123.624594) (xy 94.69628 -123.624848) (xy 94.696026 -123.624848)
			(xy 94.675088 -123.64248) (xy 94.629118 -123.672195) (xy 94.579372 -123.695033) (xy 94.526872 -123.710525)
			(xy 94.472697 -123.718354) (xy 94.445328 -123.718828) (xy 94.418075 -123.718327) (xy 94.364124 -123.710573)
			(xy 94.311826 -123.69522) (xy 94.262245 -123.672581) (xy 94.21639 -123.643115) (xy 94.175197 -123.607423)
			(xy 94.139502 -123.566232) (xy 94.110033 -123.52038) (xy 94.087389 -123.470801) (xy 94.072033 -123.418503)
			(xy 94.064275 -123.364553) (xy 82.5472 -123.364553) (xy 82.5472 -123.384149) (xy 82.539444 -123.438093)
			(xy 82.52409 -123.490385) (xy 82.501451 -123.539958) (xy 82.471987 -123.585806) (xy 82.436298 -123.626994)
			(xy 82.395111 -123.662683) (xy 82.349264 -123.692148) (xy 82.29969 -123.714788) (xy 82.247399 -123.730143)
			(xy 82.193455 -123.737899) (xy 82.166206 -123.738386) (xy 82.140297 -123.737973) (xy 82.088958 -123.730937)
			(xy 82.039043 -123.71702) (xy 81.991469 -123.696479) (xy 81.947112 -123.669691) (xy 81.906786 -123.637148)
			(xy 81.871233 -123.599449) (xy 81.855818 -123.57862) (xy 81.85008 -123.571287) (xy 81.834576 -123.561003)
			(xy 81.825592 -123.558554) (xy 81.795112 -123.551696) (xy 81.785838 -123.549923) (xy 81.767171 -123.55268)
			(xy 81.75879 -123.55703) (xy 81.732816 -123.571328) (xy 81.677963 -123.593838) (xy 81.620659 -123.609063)
			(xy 81.561868 -123.616748) (xy 81.532222 -123.617228) (xy 81.502579 -123.616731) (xy 81.443797 -123.60901)
			(xy 81.386499 -123.593783) (xy 81.331639 -123.571304) (xy 81.305654 -123.55703) (xy 81.297234 -123.552801)
			(xy 81.27861 -123.550056) (xy 81.269332 -123.551696) (xy 81.238852 -123.558554) (xy 81.229866 -123.561)
			(xy 81.214359 -123.571281) (xy 81.208626 -123.57862) (xy 81.193224 -123.599461) (xy 81.157681 -123.637172)
			(xy 81.117357 -123.669722) (xy 81.072997 -123.696511) (xy 81.025417 -123.717045) (xy 80.975494 -123.730945)
			(xy 80.924149 -123.737955) (xy 80.898238 -123.738386) (xy 80.870982 -123.73797) (xy 80.817024 -123.730217)
			(xy 80.764718 -123.714863) (xy 80.71513 -123.692221) (xy 80.66927 -123.662753) (xy 80.62807 -123.627057)
			(xy 80.59237 -123.585861) (xy 80.562897 -123.540003) (xy 80.54025 -123.490418) (xy 80.524891 -123.438114)
			(xy 80.517133 -123.384156) (xy 80.517133 -123.329644) (xy 80.524891 -123.275686) (xy 80.54025 -123.223382)
			(xy 80.562897 -123.173797) (xy 80.59237 -123.127939) (xy 80.62807 -123.086743) (xy 80.66927 -123.051047)
			(xy 80.71513 -123.021579) (xy 80.764718 -122.998937) (xy 80.817024 -122.983583) (xy 80.870982 -122.97583)
			(xy 80.898238 -122.97537) (xy 80.913031 -122.97551) (xy 80.942529 -122.977796) (xy 80.957166 -122.979942)
			(xy 80.968141 -122.98103) (xy 80.989329 -122.974994) (xy 80.99806 -122.968258) (xy 81.05648 -122.91822)
			(xy 81.064505 -122.91065) (xy 81.073719 -122.890631) (xy 81.07426 -122.879612) (xy 81.07426 -122.57532)
			(xy 81.073723 -122.564301) (xy 81.064504 -122.544283) (xy 81.05648 -122.536712) (xy 80.989424 -122.479308)
			(xy 80.968342 -122.473212) (xy 80.957166 -122.47499) (xy 80.942528 -122.477129) (xy 80.913031 -122.479418)
			(xy 80.898238 -122.479562) (xy 80.87098 -122.479194) (xy 80.817018 -122.47144) (xy 80.76471 -122.456086)
			(xy 80.715119 -122.433442) (xy 80.669255 -122.403972) (xy 80.628053 -122.368274) (xy 80.592351 -122.327075)
			(xy 80.562876 -122.281215) (xy 80.540228 -122.231626) (xy 80.524868 -122.179319) (xy 80.517109 -122.125358)
			(xy 74.49487 -122.125358) (xy 74.470545 -122.145601) (xy 74.422939 -122.174655) (xy 74.37161 -122.196467)
			(xy 74.317653 -122.210573) (xy 74.262216 -122.216673) (xy 74.206482 -122.214636) (xy 74.151639 -122.204506)
			(xy 74.098855 -122.186499) (xy 74.049255 -122.160998) (xy 74.003897 -122.128547) (xy 73.963748 -122.089838)
			(xy 73.929662 -122.045695) (xy 73.902366 -121.99706) (xy 73.882443 -121.944969) (xy 73.870317 -121.890532)
			(xy 73.866246 -121.83491) (xy 72.648572 -121.83491) (xy 72.648063 -121.862796) (xy 72.639943 -121.917972)
			(xy 72.623875 -121.971379) (xy 72.600203 -122.021876) (xy 72.56943 -122.068389) (xy 72.532213 -122.109926)
			(xy 72.489345 -122.145601) (xy 72.441739 -122.174655) (xy 72.39041 -122.196467) (xy 72.336453 -122.210573)
			(xy 72.281016 -122.216673) (xy 72.225282 -122.214636) (xy 72.170439 -122.204506) (xy 72.117655 -122.186499)
			(xy 72.068055 -122.160998) (xy 72.022697 -122.128547) (xy 71.982548 -122.089838) (xy 71.948462 -122.045695)
			(xy 71.921166 -121.99706) (xy 71.901243 -121.944969) (xy 71.889117 -121.890532) (xy 71.885046 -121.83491)
			(xy 68.047955 -121.83491) (xy 68.047955 -121.862155) (xy 68.040197 -121.91611) (xy 68.024839 -121.968412)
			(xy 68.002194 -122.017995) (xy 67.972722 -122.063851) (xy 67.937024 -122.105046) (xy 67.895827 -122.14074)
			(xy 67.849969 -122.170208) (xy 67.800384 -122.19285) (xy 67.748081 -122.208203) (xy 67.694125 -122.215957)
			(xy 67.66687 -122.216418) (xy 67.649822 -122.216217) (xy 67.615862 -122.213165) (xy 67.599052 -122.210322)
			(xy 67.587724 -122.208912) (xy 67.56571 -122.214831) (xy 67.556634 -122.221752) (xy 67.53225 -122.242834)
			(xy 67.523821 -122.250811) (xy 67.514694 -122.272122) (xy 67.514724 -122.283728) (xy 67.515232 -122.30354)
			(xy 67.515232 -122.597164) (xy 69.30212 -122.597164) (xy 69.306191 -122.541542) (xy 69.318317 -122.487105)
			(xy 69.33824 -122.435014) (xy 69.365536 -122.386379) (xy 69.399622 -122.342236) (xy 69.439771 -122.303527)
			(xy 69.485129 -122.271076) (xy 69.534729 -122.245575) (xy 69.587513 -122.227568) (xy 69.642356 -122.217438)
			(xy 69.69809 -122.215401) (xy 69.753527 -122.221501) (xy 69.807484 -122.235607) (xy 69.858813 -122.257419)
			(xy 69.906419 -122.286473) (xy 69.949287 -122.322148) (xy 69.986504 -122.363685) (xy 70.017277 -122.410198)
			(xy 70.040949 -122.460695) (xy 70.057017 -122.514102) (xy 70.065137 -122.569278) (xy 70.065646 -122.597164)
			(xy 70.065137 -122.62505) (xy 70.057017 -122.680226) (xy 70.040949 -122.733633) (xy 70.017277 -122.78413)
			(xy 69.986504 -122.830643) (xy 69.949287 -122.87218) (xy 69.906419 -122.907855) (xy 69.858813 -122.936909)
			(xy 69.807484 -122.958721) (xy 69.753527 -122.972827) (xy 69.69809 -122.978927) (xy 69.642356 -122.97689)
			(xy 69.587513 -122.96676) (xy 69.534729 -122.948753) (xy 69.485129 -122.923252) (xy 69.439771 -122.890801)
			(xy 69.399622 -122.852092) (xy 69.365536 -122.807949) (xy 69.33824 -122.759314) (xy 69.318317 -122.707223)
			(xy 69.306191 -122.652786) (xy 69.30212 -122.597164) (xy 67.515232 -122.597164) (xy 67.515232 -123.16714)
			(xy 67.514724 -123.18619) (xy 67.514773 -123.197781) (xy 67.52388 -123.219068) (xy 67.53225 -123.227084)
			(xy 67.556634 -123.247912) (xy 67.565607 -123.25491) (xy 67.587504 -123.260979) (xy 67.598798 -123.259596)
			(xy 67.615669 -123.256725) (xy 67.649757 -123.253673) (xy 67.66687 -123.2535) (xy 67.694125 -123.253945)
			(xy 67.74808 -123.261699) (xy 67.800383 -123.277053) (xy 67.849968 -123.299694) (xy 67.895825 -123.329162)
			(xy 67.937023 -123.364856) (xy 67.97272 -123.406051) (xy 68.002192 -123.451906) (xy 68.024837 -123.501489)
			(xy 68.040195 -123.553791) (xy 68.047953 -123.607745) (xy 68.047953 -123.635008) (xy 71.885046 -123.635008)
			(xy 71.889117 -123.579386) (xy 71.901243 -123.524949) (xy 71.921166 -123.472858) (xy 71.948462 -123.424223)
			(xy 71.982548 -123.38008) (xy 72.022697 -123.341371) (xy 72.068055 -123.30892) (xy 72.117655 -123.283419)
			(xy 72.170439 -123.265412) (xy 72.225282 -123.255282) (xy 72.281016 -123.253245) (xy 72.336453 -123.259345)
			(xy 72.39041 -123.273451) (xy 72.441739 -123.295263) (xy 72.489345 -123.324317) (xy 72.532213 -123.359992)
			(xy 72.56943 -123.401529) (xy 72.600203 -123.448042) (xy 72.623875 -123.498539) (xy 72.639943 -123.551946)
			(xy 72.648063 -123.607122) (xy 72.648572 -123.635008) (xy 73.866246 -123.635008) (xy 73.870317 -123.579386)
			(xy 73.882443 -123.524949) (xy 73.902366 -123.472858) (xy 73.929662 -123.424223) (xy 73.963748 -123.38008)
			(xy 74.003897 -123.341371) (xy 74.049255 -123.30892) (xy 74.098855 -123.283419) (xy 74.151639 -123.265412)
			(xy 74.206482 -123.255282) (xy 74.262216 -123.253245) (xy 74.317653 -123.259345) (xy 74.37161 -123.273451)
			(xy 74.422939 -123.295263) (xy 74.470545 -123.324317) (xy 74.513413 -123.359992) (xy 74.55063 -123.401529)
			(xy 74.581403 -123.448042) (xy 74.605075 -123.498539) (xy 74.621143 -123.551946) (xy 74.629263 -123.607122)
			(xy 74.629772 -123.635008) (xy 74.629263 -123.662894) (xy 74.621143 -123.71807) (xy 74.605075 -123.771477)
			(xy 74.581403 -123.821974) (xy 74.55063 -123.868487) (xy 74.513413 -123.910024) (xy 74.4873 -123.931755)
			(xy 83.159257 -123.931755) (xy 83.159257 -123.877245) (xy 83.167016 -123.823291) (xy 83.182374 -123.770989)
			(xy 83.20502 -123.721406) (xy 83.234492 -123.675551) (xy 83.27019 -123.634358) (xy 83.311388 -123.598664)
			(xy 83.357247 -123.569198) (xy 83.406832 -123.546558) (xy 83.459136 -123.531206) (xy 83.513091 -123.523454)
			(xy 83.540346 -123.522994) (xy 83.566254 -123.523451) (xy 83.61759 -123.530481) (xy 83.667504 -123.54439)
			(xy 83.715077 -123.564925) (xy 83.759435 -123.591706) (xy 83.799762 -123.624242) (xy 83.835317 -123.661934)
			(xy 83.850734 -123.68276) (xy 83.856493 -123.690074) (xy 83.871982 -123.700369) (xy 83.88096 -123.702826)
			(xy 83.91144 -123.709684) (xy 83.920717 -123.711433) (xy 83.93938 -123.708693) (xy 83.947762 -123.70435)
			(xy 83.973725 -123.69003) (xy 84.028582 -123.667526) (xy 84.085889 -123.652307) (xy 84.144683 -123.644628)
			(xy 84.17433 -123.644152) (xy 84.203972 -123.644672) (xy 84.262753 -123.652387) (xy 84.320051 -123.667607)
			(xy 84.374913 -123.690079) (xy 84.400898 -123.70435) (xy 84.409307 -123.708605) (xy 84.42794 -123.711334)
			(xy 84.43722 -123.709684) (xy 84.4677 -123.702826) (xy 84.476696 -123.700408) (xy 84.492198 -123.690107)
			(xy 84.497926 -123.68276) (xy 84.513351 -123.661938) (xy 84.548891 -123.624226) (xy 84.589211 -123.591675)
			(xy 84.633567 -123.564885) (xy 84.681143 -123.544348) (xy 84.731062 -123.530444) (xy 84.782404 -123.523428)
			(xy 84.808314 -123.522994) (xy 84.835565 -123.523477) (xy 84.889511 -123.531235) (xy 84.941805 -123.546591)
			(xy 84.99138 -123.569233) (xy 85.037229 -123.5987) (xy 85.078418 -123.634392) (xy 85.114108 -123.675582)
			(xy 85.143573 -123.721432) (xy 85.166214 -123.771009) (xy 85.181568 -123.823302) (xy 85.189324 -123.877249)
			(xy 85.189324 -123.931751) (xy 85.181568 -123.985698) (xy 85.166214 -124.037991) (xy 85.143573 -124.087568)
			(xy 85.114108 -124.133418) (xy 85.078418 -124.174608) (xy 85.037229 -124.2103) (xy 84.99138 -124.239767)
			(xy 84.941805 -124.262409) (xy 84.889511 -124.277765) (xy 84.835565 -124.285523) (xy 84.808314 -124.28601)
			(xy 84.793521 -124.285875) (xy 84.764023 -124.283586) (xy 84.749386 -124.281438) (xy 84.738411 -124.280304)
			(xy 84.717218 -124.286369) (xy 84.708492 -124.293122) (xy 84.650072 -124.34316) (xy 84.642064 -124.350746)
			(xy 84.632838 -124.370753) (xy 84.632292 -124.381768) (xy 84.632292 -124.68606) (xy 84.632854 -124.697076)
			(xy 84.642057 -124.717093) (xy 84.650072 -124.724668) (xy 84.717128 -124.782072) (xy 84.73821 -124.788168)
			(xy 84.749386 -124.78639) (xy 84.764023 -124.784244) (xy 84.793521 -124.78196) (xy 84.808314 -124.781818)
			(xy 84.835566 -124.782253) (xy 84.889516 -124.790011) (xy 84.941813 -124.805369) (xy 84.991392 -124.828012)
			(xy 85.037244 -124.857481) (xy 85.078435 -124.893175) (xy 85.114127 -124.934368) (xy 85.143594 -124.98022)
			(xy 85.166236 -125.0298) (xy 85.181592 -125.082097) (xy 85.189348 -125.136048) (xy 85.189348 -125.190552)
			(xy 85.181592 -125.244503) (xy 85.166236 -125.2968) (xy 85.143594 -125.34638) (xy 85.114127 -125.392232)
			(xy 85.078435 -125.433425) (xy 85.037244 -125.469119) (xy 84.991392 -125.498588) (xy 84.941813 -125.521231)
			(xy 84.889516 -125.536589) (xy 84.835566 -125.544347) (xy 84.808314 -125.544834) (xy 84.782404 -125.544437)
			(xy 84.731064 -125.5374) (xy 84.681147 -125.523483) (xy 84.633573 -125.502939) (xy 84.589215 -125.476148)
			(xy 84.548891 -125.443602) (xy 84.51334 -125.405899) (xy 84.497926 -125.385068) (xy 84.492176 -125.377746)
			(xy 84.476681 -125.367454) (xy 84.4677 -125.365002) (xy 84.43722 -125.358144) (xy 84.427945 -125.356382)
			(xy 84.40928 -125.359133) (xy 84.400898 -125.363478) (xy 84.37492 -125.377769) (xy 84.320069 -125.400281)
			(xy 84.262766 -125.415509) (xy 84.203975 -125.423196) (xy 84.17433 -125.423676) (xy 84.144688 -125.42317)
			(xy 84.085906 -125.41545) (xy 84.028608 -125.400226) (xy 83.973747 -125.37775) (xy 83.947762 -125.363478)
			(xy 83.939339 -125.359254) (xy 83.920717 -125.356505) (xy 83.91144 -125.358144) (xy 83.88096 -125.365002)
			(xy 83.871969 -125.367436) (xy 83.856463 -125.377725) (xy 83.850734 -125.385068) (xy 83.835341 -125.405915)
			(xy 83.799795 -125.443625) (xy 83.759469 -125.476173) (xy 83.715107 -125.50296) (xy 83.667526 -125.523492)
			(xy 83.617603 -125.537392) (xy 83.566257 -125.544403) (xy 83.540346 -125.544834) (xy 83.513093 -125.544322)
			(xy 83.459141 -125.536571) (xy 83.406841 -125.52122) (xy 83.357258 -125.498581) (xy 83.311403 -125.469117)
			(xy 83.270207 -125.433425) (xy 83.234511 -125.392234) (xy 83.205041 -125.346382) (xy 83.182396 -125.296802)
			(xy 83.167039 -125.244504) (xy 83.159281 -125.190553) (xy 83.159281 -125.136047) (xy 83.167039 -125.082096)
			(xy 83.182396 -125.029798) (xy 83.205041 -124.980218) (xy 83.234511 -124.934366) (xy 83.270207 -124.893175)
			(xy 83.311403 -124.857483) (xy 83.357258 -124.828019) (xy 83.406841 -124.80538) (xy 83.459141 -124.790029)
			(xy 83.513093 -124.782278) (xy 83.540346 -124.781818) (xy 83.555139 -124.781958) (xy 83.584637 -124.784244)
			(xy 83.599274 -124.78639) (xy 83.610249 -124.787494) (xy 83.631439 -124.781449) (xy 83.640168 -124.774706)
			(xy 83.698588 -124.724668) (xy 83.706622 -124.717105) (xy 83.715835 -124.697081) (xy 83.716368 -124.68606)
			(xy 83.716368 -124.381768) (xy 83.715858 -124.370745) (xy 83.70662 -124.350729) (xy 83.698588 -124.34316)
			(xy 83.631532 -124.285756) (xy 83.61045 -124.27966) (xy 83.599274 -124.281438) (xy 83.584636 -124.283577)
			(xy 83.555139 -124.285866) (xy 83.540346 -124.28601) (xy 83.513091 -124.285546) (xy 83.459136 -124.277794)
			(xy 83.406832 -124.262442) (xy 83.357247 -124.239802) (xy 83.311388 -124.210336) (xy 83.27019 -124.174642)
			(xy 83.234492 -124.133449) (xy 83.20502 -124.087594) (xy 83.182374 -124.038011) (xy 83.167016 -123.985709)
			(xy 83.159257 -123.931755) (xy 74.4873 -123.931755) (xy 74.470545 -123.945699) (xy 74.422939 -123.974753)
			(xy 74.37161 -123.996565) (xy 74.317653 -124.010671) (xy 74.262216 -124.016771) (xy 74.206482 -124.014734)
			(xy 74.151639 -124.004604) (xy 74.098855 -123.986597) (xy 74.049255 -123.961096) (xy 74.003897 -123.928645)
			(xy 73.963748 -123.889936) (xy 73.929662 -123.845793) (xy 73.902366 -123.797158) (xy 73.882443 -123.745067)
			(xy 73.870317 -123.69063) (xy 73.866246 -123.635008) (xy 72.648572 -123.635008) (xy 72.648063 -123.662894)
			(xy 72.639943 -123.71807) (xy 72.623875 -123.771477) (xy 72.600203 -123.821974) (xy 72.56943 -123.868487)
			(xy 72.532213 -123.910024) (xy 72.489345 -123.945699) (xy 72.441739 -123.974753) (xy 72.39041 -123.996565)
			(xy 72.336453 -124.010671) (xy 72.281016 -124.016771) (xy 72.225282 -124.014734) (xy 72.170439 -124.004604)
			(xy 72.117655 -123.986597) (xy 72.068055 -123.961096) (xy 72.022697 -123.928645) (xy 71.982548 -123.889936)
			(xy 71.948462 -123.845793) (xy 71.921166 -123.797158) (xy 71.901243 -123.745067) (xy 71.889117 -123.69063)
			(xy 71.885046 -123.635008) (xy 68.047953 -123.635008) (xy 68.047953 -123.662255) (xy 68.040195 -123.716209)
			(xy 68.024837 -123.768511) (xy 68.002192 -123.818094) (xy 67.97272 -123.863949) (xy 67.937023 -123.905144)
			(xy 67.895825 -123.940838) (xy 67.849968 -123.970306) (xy 67.800383 -123.992947) (xy 67.74808 -124.008301)
			(xy 67.694125 -124.016055) (xy 67.66687 -124.016516) (xy 67.639891 -124.016097) (xy 67.586468 -124.008511)
			(xy 67.53465 -123.993467) (xy 67.485471 -123.971265) (xy 67.439915 -123.942349) (xy 67.398892 -123.907297)
			(xy 67.363223 -123.86681) (xy 67.33362 -123.821697) (xy 67.310675 -123.77286) (xy 67.294847 -123.721276)
			(xy 67.290188 -123.694698) (xy 67.288034 -123.684465) (xy 67.276747 -123.666886) (xy 67.268344 -123.660662)
			(xy 67.19697 -123.613164) (xy 67.175888 -123.609354) (xy 67.165728 -123.611894) (xy 67.139025 -123.617961)
			(xy 67.084651 -123.624459) (xy 67.05727 -123.624848) (xy 67.029888 -123.624476) (xy 66.975512 -123.617979)
			(xy 66.948812 -123.611894) (xy 66.938652 -123.609354) (xy 66.91757 -123.613164) (xy 66.837306 -123.666504)
			(xy 66.82613 -123.68403) (xy 66.824352 -123.694698) (xy 66.819656 -123.721263) (xy 66.803804 -123.772827)
			(xy 66.780844 -123.821643) (xy 66.751235 -123.866737) (xy 66.715568 -123.907209) (xy 66.674554 -123.942251)
			(xy 66.629012 -123.971165) (xy 66.57985 -123.993374) (xy 66.528049 -124.008434) (xy 66.474643 -124.016044)
			(xy 66.44767 -124.016516) (xy 66.420298 -124.016088) (xy 66.366117 -124.008264) (xy 66.313612 -123.992767)
			(xy 66.263866 -123.969917) (xy 66.217902 -123.940182) (xy 66.196972 -123.922536) (xy 66.196718 -123.922282)
			(xy 66.189632 -123.916695) (xy 66.172715 -123.910449) (xy 66.163698 -123.91009) (xy 66.096642 -123.91009)
			(xy 66.087627 -123.910469) (xy 66.07071 -123.916702) (xy 66.063622 -123.922282) (xy 66.063622 -123.922536)
			(xy 66.063368 -123.922536) (xy 66.042426 -123.940162) (xy 65.996455 -123.969875) (xy 65.94671 -123.992713)
			(xy 65.894212 -124.008207) (xy 65.840038 -124.016039) (xy 65.81267 -124.016516) (xy 65.795622 -124.016315)
			(xy 65.761662 -124.013263) (xy 65.744852 -124.01042) (xy 65.733524 -124.00901) (xy 65.71151 -124.014929)
			(xy 65.702434 -124.02185) (xy 65.67805 -124.042932) (xy 65.669622 -124.05091) (xy 65.660494 -124.07222)
			(xy 65.660524 -124.083826) (xy 65.661032 -124.103638) (xy 65.661032 -124.31649) (xy 69.30212 -124.31649)
			(xy 69.306191 -124.260868) (xy 69.318317 -124.206431) (xy 69.33824 -124.15434) (xy 69.365536 -124.105705)
			(xy 69.399622 -124.061562) (xy 69.439771 -124.022853) (xy 69.485129 -123.990402) (xy 69.534729 -123.964901)
			(xy 69.587513 -123.946894) (xy 69.642356 -123.936764) (xy 69.69809 -123.934727) (xy 69.753527 -123.940827)
			(xy 69.807484 -123.954933) (xy 69.858813 -123.976745) (xy 69.906419 -124.005799) (xy 69.949287 -124.041474)
			(xy 69.986504 -124.083011) (xy 70.017277 -124.129524) (xy 70.040949 -124.180021) (xy 70.057017 -124.233428)
			(xy 70.065137 -124.288604) (xy 70.065646 -124.31649) (xy 70.065137 -124.344376) (xy 70.057017 -124.399552)
			(xy 70.040949 -124.452959) (xy 70.017277 -124.503456) (xy 69.986504 -124.549969) (xy 69.949287 -124.591506)
			(xy 69.906419 -124.627181) (xy 69.858813 -124.656235) (xy 69.807484 -124.678047) (xy 69.753527 -124.692153)
			(xy 69.69809 -124.698253) (xy 69.642356 -124.696216) (xy 69.587513 -124.686086) (xy 69.534729 -124.668079)
			(xy 69.485129 -124.642578) (xy 69.439771 -124.610127) (xy 69.399622 -124.571418) (xy 69.365536 -124.527275)
			(xy 69.33824 -124.47864) (xy 69.318317 -124.426549) (xy 69.306191 -124.372112) (xy 69.30212 -124.31649)
			(xy 65.661032 -124.31649) (xy 65.661032 -124.967238) (xy 65.660524 -124.986288) (xy 65.660574 -124.997879)
			(xy 65.66968 -125.019166) (xy 65.67805 -125.027182) (xy 65.702434 -125.04801) (xy 65.711407 -125.055008)
			(xy 65.733304 -125.061077) (xy 65.744598 -125.059694) (xy 65.761469 -125.056823) (xy 65.795557 -125.053771)
			(xy 65.81267 -125.053598) (xy 65.839925 -125.054047) (xy 65.89388 -125.061801) (xy 65.946182 -125.077155)
			(xy 65.995767 -125.099796) (xy 66.041624 -125.129263) (xy 66.082821 -125.164958) (xy 66.118519 -125.206152)
			(xy 66.14799 -125.252007) (xy 66.170635 -125.30159) (xy 66.185993 -125.353891) (xy 66.193751 -125.407845)
			(xy 66.193751 -125.435106) (xy 67.284852 -125.435106) (xy 67.288923 -125.379484) (xy 67.301049 -125.325047)
			(xy 67.320972 -125.272956) (xy 67.348268 -125.224321) (xy 67.382354 -125.180178) (xy 67.422503 -125.141469)
			(xy 67.467861 -125.109018) (xy 67.517461 -125.083517) (xy 67.570245 -125.06551) (xy 67.625088 -125.05538)
			(xy 67.680822 -125.053343) (xy 67.736259 -125.059443) (xy 67.790216 -125.073549) (xy 67.841545 -125.095361)
			(xy 67.889151 -125.124415) (xy 67.932019 -125.16009) (xy 67.969236 -125.201627) (xy 68.000009 -125.24814)
			(xy 68.023681 -125.298637) (xy 68.039749 -125.352044) (xy 68.047869 -125.40722) (xy 68.048378 -125.435106)
			(xy 68.047869 -125.462992) (xy 68.039749 -125.518168) (xy 68.023681 -125.571575) (xy 68.000009 -125.622072)
			(xy 67.969236 -125.668585) (xy 67.932019 -125.710122) (xy 67.889151 -125.745797) (xy 67.87841 -125.752352)
			(xy 69.255384 -125.752352) (xy 69.259455 -125.69673) (xy 69.271581 -125.642293) (xy 69.291504 -125.590202)
			(xy 69.3188 -125.541567) (xy 69.352886 -125.497424) (xy 69.393035 -125.458715) (xy 69.438393 -125.426264)
			(xy 69.487993 -125.400763) (xy 69.540777 -125.382756) (xy 69.59562 -125.372626) (xy 69.651354 -125.370589)
			(xy 69.706791 -125.376689) (xy 69.760748 -125.390795) (xy 69.812077 -125.412607) (xy 69.848942 -125.435106)
			(xy 71.885046 -125.435106) (xy 71.889117 -125.379484) (xy 71.901243 -125.325047) (xy 71.921166 -125.272956)
			(xy 71.948462 -125.224321) (xy 71.982548 -125.180178) (xy 72.022697 -125.141469) (xy 72.068055 -125.109018)
			(xy 72.117655 -125.083517) (xy 72.170439 -125.06551) (xy 72.225282 -125.05538) (xy 72.281016 -125.053343)
			(xy 72.336453 -125.059443) (xy 72.39041 -125.073549) (xy 72.441739 -125.095361) (xy 72.489345 -125.124415)
			(xy 72.532213 -125.16009) (xy 72.56943 -125.201627) (xy 72.600203 -125.24814) (xy 72.623875 -125.298637)
			(xy 72.639943 -125.352044) (xy 72.648063 -125.40722) (xy 72.648572 -125.435106) (xy 73.866246 -125.435106)
			(xy 73.870317 -125.379484) (xy 73.882443 -125.325047) (xy 73.902366 -125.272956) (xy 73.929662 -125.224321)
			(xy 73.963748 -125.180178) (xy 74.003897 -125.141469) (xy 74.049255 -125.109018) (xy 74.098855 -125.083517)
			(xy 74.151639 -125.06551) (xy 74.206482 -125.05538) (xy 74.262216 -125.053343) (xy 74.317653 -125.059443)
			(xy 74.37161 -125.073549) (xy 74.422939 -125.095361) (xy 74.470545 -125.124415) (xy 74.513413 -125.16009)
			(xy 74.55063 -125.201627) (xy 74.581403 -125.24814) (xy 74.605075 -125.298637) (xy 74.621143 -125.352044)
			(xy 74.629263 -125.40722) (xy 74.629772 -125.435106) (xy 74.629263 -125.462992) (xy 74.621143 -125.518168)
			(xy 74.605075 -125.571575) (xy 74.581403 -125.622072) (xy 74.55063 -125.668585) (xy 74.513413 -125.710122)
			(xy 74.470545 -125.745797) (xy 74.422939 -125.774851) (xy 74.37161 -125.796663) (xy 74.317653 -125.810769)
			(xy 74.262216 -125.816869) (xy 74.206482 -125.814832) (xy 74.151639 -125.804702) (xy 74.098855 -125.786695)
			(xy 74.049255 -125.761194) (xy 74.003897 -125.728743) (xy 73.963748 -125.690034) (xy 73.929662 -125.645891)
			(xy 73.902366 -125.597256) (xy 73.882443 -125.545165) (xy 73.870317 -125.490728) (xy 73.866246 -125.435106)
			(xy 72.648572 -125.435106) (xy 72.648063 -125.462992) (xy 72.639943 -125.518168) (xy 72.623875 -125.571575)
			(xy 72.600203 -125.622072) (xy 72.56943 -125.668585) (xy 72.532213 -125.710122) (xy 72.489345 -125.745797)
			(xy 72.441739 -125.774851) (xy 72.39041 -125.796663) (xy 72.336453 -125.810769) (xy 72.281016 -125.816869)
			(xy 72.225282 -125.814832) (xy 72.170439 -125.804702) (xy 72.117655 -125.786695) (xy 72.068055 -125.761194)
			(xy 72.022697 -125.728743) (xy 71.982548 -125.690034) (xy 71.948462 -125.645891) (xy 71.921166 -125.597256)
			(xy 71.901243 -125.545165) (xy 71.889117 -125.490728) (xy 71.885046 -125.435106) (xy 69.848942 -125.435106)
			(xy 69.859683 -125.441661) (xy 69.902551 -125.477336) (xy 69.939768 -125.518873) (xy 69.970541 -125.565386)
			(xy 69.994213 -125.615883) (xy 70.010281 -125.66929) (xy 70.018401 -125.724466) (xy 70.01891 -125.752352)
			(xy 70.018401 -125.780238) (xy 70.010281 -125.835414) (xy 69.994213 -125.888821) (xy 69.970541 -125.939318)
			(xy 69.939768 -125.985831) (xy 69.914554 -126.013972) (xy 89.450672 -126.013972) (xy 89.451104 -125.9866)
			(xy 89.458927 -125.932419) (xy 89.474423 -125.879915) (xy 89.497273 -125.830169) (xy 89.527006 -125.784204)
			(xy 89.544652 -125.763274) (xy 89.544906 -125.76302) (xy 89.550491 -125.755932) (xy 89.556738 -125.739016)
			(xy 89.557098 -125.73) (xy 89.557098 -125.662944) (xy 89.55672 -125.653929) (xy 89.550487 -125.637012)
			(xy 89.544906 -125.629924) (xy 89.544652 -125.629924) (xy 89.544652 -125.62967) (xy 89.526983 -125.60876)
			(xy 89.497257 -125.562789) (xy 89.474412 -125.513039) (xy 89.458917 -125.460533) (xy 89.45109 -125.406351)
			(xy 89.451093 -125.351607) (xy 89.458926 -125.297425) (xy 89.474427 -125.244921) (xy 89.497278 -125.195174)
			(xy 89.527008 -125.149206) (xy 89.544652 -125.128274) (xy 89.544906 -125.12802) (xy 89.550491 -125.120932)
			(xy 89.556738 -125.104016) (xy 89.557098 -125.095) (xy 89.557098 -125.027944) (xy 89.55672 -125.018929)
			(xy 89.550487 -125.002012) (xy 89.544906 -124.994924) (xy 89.544652 -124.994924) (xy 89.544652 -124.99467)
			(xy 89.526983 -124.97376) (xy 89.497257 -124.927789) (xy 89.474412 -124.878039) (xy 89.458917 -124.825533)
			(xy 89.45109 -124.771351) (xy 89.451093 -124.716607) (xy 89.458926 -124.662425) (xy 89.474427 -124.609921)
			(xy 89.497278 -124.560174) (xy 89.527008 -124.514206) (xy 89.544652 -124.493274) (xy 89.544906 -124.49302)
			(xy 89.550491 -124.485932) (xy 89.556738 -124.469016) (xy 89.557098 -124.46) (xy 89.557098 -124.392944)
			(xy 89.55672 -124.383929) (xy 89.550487 -124.367012) (xy 89.544906 -124.359924) (xy 89.544652 -124.359924)
			(xy 89.544652 -124.35967) (xy 89.52704 -124.338716) (xy 89.497323 -124.29275) (xy 89.474481 -124.243008)
			(xy 89.458983 -124.190512) (xy 89.451149 -124.13634) (xy 89.450672 -124.108972) (xy 89.451158 -124.081721)
			(xy 89.458914 -124.027773) (xy 89.474269 -123.975478) (xy 89.496911 -123.925901) (xy 89.526377 -123.880051)
			(xy 89.562068 -123.83886) (xy 89.603259 -123.803169) (xy 89.649109 -123.773703) (xy 89.698686 -123.751061)
			(xy 89.750981 -123.735706) (xy 89.804929 -123.72795) (xy 89.859431 -123.72795) (xy 89.913379 -123.735706)
			(xy 89.965674 -123.751061) (xy 90.015251 -123.773703) (xy 90.061101 -123.803169) (xy 90.102292 -123.83886)
			(xy 90.137983 -123.880051) (xy 90.167449 -123.925901) (xy 90.190091 -123.975478) (xy 90.205446 -124.027773)
			(xy 90.213202 -124.081721) (xy 90.213688 -124.108972) (xy 90.213208 -124.136342) (xy 90.205394 -124.19052)
			(xy 90.189909 -124.243023) (xy 90.16707 -124.292771) (xy 90.137348 -124.338738) (xy 90.119708 -124.35967)
			(xy 90.119454 -124.359924) (xy 90.113846 -124.366996) (xy 90.107613 -124.383924) (xy 90.107262 -124.392944)
			(xy 90.107262 -124.46) (xy 90.107627 -124.469016) (xy 90.110861 -124.47778) (xy 92.41282 -124.47778)
			(xy 92.413269 -124.450409) (xy 92.421091 -124.396229) (xy 92.436583 -124.343726) (xy 92.459429 -124.293979)
			(xy 92.489157 -124.248013) (xy 92.5068 -124.227082) (xy 92.507054 -124.226828) (xy 92.512641 -124.219742)
			(xy 92.518886 -124.202825) (xy 92.519246 -124.193808) (xy 92.519246 -124.126752) (xy 92.518876 -124.117736)
			(xy 92.512639 -124.100818) (xy 92.507054 -124.093732) (xy 92.5068 -124.093732) (xy 92.5068 -124.093478)
			(xy 92.489184 -124.072527) (xy 92.459469 -124.02656) (xy 92.436628 -123.976817) (xy 92.421132 -123.92432)
			(xy 92.413297 -123.870148) (xy 92.41282 -123.84278) (xy 92.413306 -123.815529) (xy 92.421062 -123.761581)
			(xy 92.436417 -123.709286) (xy 92.459059 -123.659709) (xy 92.488525 -123.613859) (xy 92.524216 -123.572668)
			(xy 92.565407 -123.536977) (xy 92.611257 -123.507511) (xy 92.660834 -123.484869) (xy 92.713129 -123.469514)
			(xy 92.767077 -123.461758) (xy 92.821579 -123.461758) (xy 92.875527 -123.469514) (xy 92.927822 -123.484869)
			(xy 92.977399 -123.507511) (xy 93.023249 -123.536977) (xy 93.06444 -123.572668) (xy 93.100131 -123.613859)
			(xy 93.129597 -123.659709) (xy 93.152239 -123.709286) (xy 93.167594 -123.761581) (xy 93.172403 -123.795028)
			(xy 97.441256 -123.795028) (xy 97.445327 -123.739406) (xy 97.457453 -123.684969) (xy 97.477376 -123.632878)
			(xy 97.504672 -123.584243) (xy 97.538758 -123.5401) (xy 97.578907 -123.501391) (xy 97.624265 -123.46894)
			(xy 97.673865 -123.443439) (xy 97.726649 -123.425432) (xy 97.781492 -123.415302) (xy 97.837226 -123.413265)
			(xy 97.892663 -123.419365) (xy 97.94662 -123.433471) (xy 97.997949 -123.455283) (xy 98.045555 -123.484337)
			(xy 98.088423 -123.520012) (xy 98.12564 -123.561549) (xy 98.156413 -123.608062) (xy 98.180085 -123.658559)
			(xy 98.196153 -123.711966) (xy 98.204273 -123.767142) (xy 98.204782 -123.795028) (xy 99.649024 -123.795028)
			(xy 99.653095 -123.739406) (xy 99.665221 -123.684969) (xy 99.685144 -123.632878) (xy 99.71244 -123.584243)
			(xy 99.746526 -123.5401) (xy 99.786675 -123.501391) (xy 99.832033 -123.46894) (xy 99.881633 -123.443439)
			(xy 99.934417 -123.425432) (xy 99.98926 -123.415302) (xy 100.044994 -123.413265) (xy 100.100431 -123.419365)
			(xy 100.154388 -123.433471) (xy 100.205717 -123.455283) (xy 100.253323 -123.484337) (xy 100.296191 -123.520012)
			(xy 100.333408 -123.561549) (xy 100.364181 -123.608062) (xy 100.387853 -123.658559) (xy 100.403921 -123.711966)
			(xy 100.412041 -123.767142) (xy 100.41255 -123.795028) (xy 100.412041 -123.822914) (xy 100.403921 -123.87809)
			(xy 100.387853 -123.931497) (xy 100.364181 -123.981994) (xy 100.333408 -124.028507) (xy 100.296191 -124.070044)
			(xy 100.253323 -124.105719) (xy 100.205717 -124.134773) (xy 100.154388 -124.156585) (xy 100.100431 -124.170691)
			(xy 100.044994 -124.176791) (xy 99.98926 -124.174754) (xy 99.934417 -124.164624) (xy 99.881633 -124.146617)
			(xy 99.832033 -124.121116) (xy 99.786675 -124.088665) (xy 99.746526 -124.049956) (xy 99.71244 -124.005813)
			(xy 99.685144 -123.957178) (xy 99.665221 -123.905087) (xy 99.653095 -123.85065) (xy 99.649024 -123.795028)
			(xy 98.204782 -123.795028) (xy 98.204273 -123.822914) (xy 98.196153 -123.87809) (xy 98.180085 -123.931497)
			(xy 98.156413 -123.981994) (xy 98.12564 -124.028507) (xy 98.088423 -124.070044) (xy 98.045555 -124.105719)
			(xy 97.997949 -124.134773) (xy 97.94662 -124.156585) (xy 97.892663 -124.170691) (xy 97.837226 -124.176791)
			(xy 97.781492 -124.174754) (xy 97.726649 -124.164624) (xy 97.673865 -124.146617) (xy 97.624265 -124.121116)
			(xy 97.578907 -124.088665) (xy 97.538758 -124.049956) (xy 97.504672 -124.005813) (xy 97.477376 -123.957178)
			(xy 97.457453 -123.905087) (xy 97.445327 -123.85065) (xy 97.441256 -123.795028) (xy 93.172403 -123.795028)
			(xy 93.17535 -123.815529) (xy 93.175836 -123.84278) (xy 93.175374 -123.870151) (xy 93.167557 -123.92433)
			(xy 93.152068 -123.976834) (xy 93.129225 -124.026581) (xy 93.099499 -124.072547) (xy 93.081856 -124.093478)
			(xy 93.081602 -124.093732) (xy 93.076038 -124.100834) (xy 93.069778 -124.117739) (xy 93.06941 -124.126752)
			(xy 93.06941 -124.193808) (xy 93.069761 -124.202826) (xy 93.074313 -124.215144) (xy 94.606616 -124.215144)
			(xy 94.610687 -124.159522) (xy 94.622813 -124.105085) (xy 94.642736 -124.052994) (xy 94.670032 -124.004359)
			(xy 94.704118 -123.960216) (xy 94.744267 -123.921507) (xy 94.789625 -123.889056) (xy 94.839225 -123.863555)
			(xy 94.892009 -123.845548) (xy 94.946852 -123.835418) (xy 95.002586 -123.833381) (xy 95.058023 -123.839481)
			(xy 95.11198 -123.853587) (xy 95.163309 -123.875399) (xy 95.210915 -123.904453) (xy 95.253783 -123.940128)
			(xy 95.291 -123.981665) (xy 95.321773 -124.028178) (xy 95.345445 -124.078675) (xy 95.361513 -124.132082)
			(xy 95.369633 -124.187258) (xy 95.370142 -124.215144) (xy 95.369633 -124.24303) (xy 95.361513 -124.298206)
			(xy 95.345445 -124.351613) (xy 95.321773 -124.40211) (xy 95.291 -124.448623) (xy 95.253783 -124.49016)
			(xy 95.210915 -124.525835) (xy 95.163309 -124.554889) (xy 95.11198 -124.576701) (xy 95.058023 -124.590807)
			(xy 95.002586 -124.596907) (xy 94.946852 -124.59487) (xy 94.892009 -124.58474) (xy 94.839225 -124.566733)
			(xy 94.789625 -124.541232) (xy 94.744267 -124.508781) (xy 94.704118 -124.470072) (xy 94.670032 -124.425929)
			(xy 94.642736 -124.377294) (xy 94.622813 -124.325203) (xy 94.610687 -124.270766) (xy 94.606616 -124.215144)
			(xy 93.074313 -124.215144) (xy 93.076012 -124.219743) (xy 93.081602 -124.226828) (xy 93.081856 -124.226828)
			(xy 93.081856 -124.227082) (xy 93.099493 -124.248016) (xy 93.129207 -124.293987) (xy 93.152044 -124.343734)
			(xy 93.167535 -124.396235) (xy 93.175363 -124.450411) (xy 93.175836 -124.47778) (xy 93.17535 -124.505031)
			(xy 93.167594 -124.558979) (xy 93.152239 -124.611274) (xy 93.129597 -124.660851) (xy 93.100131 -124.706701)
			(xy 93.06444 -124.747892) (xy 93.023249 -124.783583) (xy 92.977399 -124.813049) (xy 92.927822 -124.835691)
			(xy 92.875527 -124.851046) (xy 92.821579 -124.858802) (xy 92.767077 -124.858802) (xy 92.713129 -124.851046)
			(xy 92.660834 -124.835691) (xy 92.611257 -124.813049) (xy 92.565407 -124.783583) (xy 92.524216 -124.747892)
			(xy 92.488525 -124.706701) (xy 92.459059 -124.660851) (xy 92.436417 -124.611274) (xy 92.421062 -124.558979)
			(xy 92.413306 -124.505031) (xy 92.41282 -124.47778) (xy 90.110861 -124.47778) (xy 90.11387 -124.485932)
			(xy 90.119454 -124.49302) (xy 90.119708 -124.493528) (xy 90.135395 -124.512048) (xy 90.162467 -124.552332)
			(xy 90.184213 -124.595723) (xy 90.192606 -124.618496) (xy 90.19667 -124.630688) (xy 90.21572 -124.648214)
			(xy 90.324178 -124.674376) (xy 90.34907 -124.667772) (xy 90.358468 -124.658628) (xy 90.379869 -124.63898)
			(xy 90.42755 -124.605789) (xy 90.479707 -124.580203) (xy 90.535138 -124.56281) (xy 90.592564 -124.554014)
			(xy 90.621612 -124.553472) (xy 90.648983 -124.553913) (xy 90.703164 -124.561735) (xy 90.755668 -124.577228)
			(xy 90.805415 -124.600076) (xy 90.85138 -124.629807) (xy 90.87231 -124.647452) (xy 90.872564 -124.647706)
			(xy 90.879656 -124.653284) (xy 90.896569 -124.659536) (xy 90.905584 -124.659898) (xy 90.97264 -124.659898)
			(xy 90.981659 -124.65956) (xy 90.998576 -124.653299) (xy 91.00566 -124.647706) (xy 91.00566 -124.647452)
			(xy 91.005914 -124.647452) (xy 91.026874 -124.629848) (xy 91.072839 -124.600129) (xy 91.122579 -124.577285)
			(xy 91.175074 -124.561786) (xy 91.229245 -124.55395) (xy 91.256612 -124.553472) (xy 91.283863 -124.553967)
			(xy 91.337809 -124.561724) (xy 91.390102 -124.57708) (xy 91.439678 -124.599721) (xy 91.485528 -124.629187)
			(xy 91.526717 -124.664877) (xy 91.562409 -124.706066) (xy 91.591875 -124.751915) (xy 91.614517 -124.80149)
			(xy 91.629874 -124.853783) (xy 91.637633 -124.907729) (xy 91.63812 -124.93498) (xy 91.637358 -124.959872)
			(xy 91.636596 -124.97308) (xy 91.647518 -124.996448) (xy 91.738704 -125.062488) (xy 91.764358 -125.065536)
			(xy 91.77655 -125.06071) (xy 91.799316 -125.051944) (xy 91.846518 -125.039622) (xy 91.894906 -125.03341)
			(xy 91.919298 -125.033024) (xy 91.946552 -125.033457) (xy 92.000506 -125.041215) (xy 92.052806 -125.056572)
			(xy 92.102389 -125.079217) (xy 92.148243 -125.108688) (xy 92.189437 -125.144385) (xy 92.22513 -125.185581)
			(xy 92.254598 -125.231438) (xy 92.277238 -125.281022) (xy 92.292592 -125.333323) (xy 92.300345 -125.387278)
			(xy 92.300806 -125.414532) (xy 92.300357 -125.441903) (xy 92.292535 -125.496083) (xy 92.277042 -125.548586)
			(xy 92.254196 -125.598332) (xy 92.224469 -125.644299) (xy 92.206826 -125.66523) (xy 92.206572 -125.665484)
			(xy 92.200983 -125.672569) (xy 92.194739 -125.689487) (xy 92.19438 -125.698504) (xy 92.19438 -125.76556)
			(xy 92.19476 -125.774574) (xy 92.200992 -125.791491) (xy 92.206572 -125.79858) (xy 92.206826 -125.79858)
			(xy 92.206826 -125.798834) (xy 92.224452 -125.819777) (xy 92.254165 -125.865747) (xy 92.266008 -125.891544)
			(xy 95.17507 -125.891544) (xy 95.17551 -125.865229) (xy 95.182752 -125.8131) (xy 95.197077 -125.762457)
			(xy 95.218214 -125.714258) (xy 95.245765 -125.669415) (xy 95.279207 -125.628776) (xy 95.29826 -125.61062)
			(xy 95.305649 -125.603087) (xy 95.314182 -125.583816) (xy 95.31477 -125.573282) (xy 95.31477 -125.498606)
			(xy 95.31426 -125.488054) (xy 95.305712 -125.468758) (xy 95.29826 -125.461268) (xy 95.279188 -125.443129)
			(xy 95.245734 -125.402495) (xy 95.218178 -125.357651) (xy 95.197043 -125.309447) (xy 95.182729 -125.258797)
			(xy 95.175507 -125.206661) (xy 95.17507 -125.180344) (xy 95.175556 -125.153093) (xy 95.183312 -125.099145)
			(xy 95.198667 -125.04685) (xy 95.221309 -124.997273) (xy 95.250775 -124.951423) (xy 95.286466 -124.910232)
			(xy 95.327657 -124.874541) (xy 95.373507 -124.845075) (xy 95.423084 -124.822433) (xy 95.475379 -124.807078)
			(xy 95.529327 -124.799322) (xy 95.583829 -124.799322) (xy 95.637777 -124.807078) (xy 95.690072 -124.822433)
			(xy 95.739649 -124.845075) (xy 95.785499 -124.874541) (xy 95.82669 -124.910232) (xy 95.862381 -124.951423)
			(xy 95.891847 -124.997273) (xy 95.914489 -125.04685) (xy 95.929844 -125.099145) (xy 95.9376 -125.153093)
			(xy 95.938086 -125.180344) (xy 95.937652 -125.206659) (xy 95.930411 -125.258789) (xy 95.916086 -125.309433)
			(xy 95.894947 -125.357632) (xy 95.867395 -125.402474) (xy 95.83395 -125.443112) (xy 95.814896 -125.461268)
			(xy 95.807506 -125.468799) (xy 95.798975 -125.488072) (xy 95.798386 -125.498606) (xy 95.798386 -125.573282)
			(xy 95.798916 -125.583831) (xy 95.807451 -125.603127) (xy 95.814896 -125.61062) (xy 95.833953 -125.628774)
			(xy 95.867411 -125.669404) (xy 95.894969 -125.714244) (xy 95.916108 -125.762445) (xy 95.930424 -125.813093)
			(xy 95.937648 -125.865228) (xy 95.938086 -125.891544) (xy 95.9376 -125.918795) (xy 95.929844 -125.972743)
			(xy 95.914489 -126.025038) (xy 95.891847 -126.074615) (xy 95.862381 -126.120465) (xy 95.82669 -126.161656)
			(xy 95.785499 -126.197347) (xy 95.739649 -126.226813) (xy 95.690072 -126.249455) (xy 95.637777 -126.26481)
			(xy 95.583829 -126.272566) (xy 95.529327 -126.272566) (xy 95.475379 -126.26481) (xy 95.423084 -126.249455)
			(xy 95.373507 -126.226813) (xy 95.327657 -126.197347) (xy 95.286466 -126.161656) (xy 95.250775 -126.120465)
			(xy 95.221309 -126.074615) (xy 95.198667 -126.025038) (xy 95.183312 -125.972743) (xy 95.175556 -125.918795)
			(xy 95.17507 -125.891544) (xy 92.266008 -125.891544) (xy 92.277003 -125.915492) (xy 92.292497 -125.96799)
			(xy 92.300329 -126.022164) (xy 92.300806 -126.049532) (xy 92.30032 -126.076783) (xy 92.292564 -126.130731)
			(xy 92.277209 -126.183026) (xy 92.254567 -126.232603) (xy 92.225101 -126.278453) (xy 92.18941 -126.319644)
			(xy 92.148219 -126.355335) (xy 92.102369 -126.384801) (xy 92.052792 -126.407443) (xy 92.000497 -126.422798)
			(xy 91.946549 -126.430554) (xy 91.892047 -126.430554) (xy 91.838099 -126.422798) (xy 91.785804 -126.407443)
			(xy 91.736227 -126.384801) (xy 91.690377 -126.355335) (xy 91.649186 -126.319644) (xy 91.613495 -126.278453)
			(xy 91.584029 -126.232603) (xy 91.561387 -126.183026) (xy 91.546032 -126.130731) (xy 91.538276 -126.076783)
			(xy 91.53779 -126.049532) (xy 91.538277 -126.022163) (xy 91.54609 -125.967984) (xy 91.561575 -125.915482)
			(xy 91.584412 -125.865735) (xy 91.614131 -125.819767) (xy 91.63177 -125.798834) (xy 91.632024 -125.79858)
			(xy 91.637628 -125.791505) (xy 91.643863 -125.774579) (xy 91.644216 -125.76556) (xy 91.644216 -125.698504)
			(xy 91.643854 -125.689488) (xy 91.637609 -125.672571) (xy 91.632024 -125.665484) (xy 91.63177 -125.665484)
			(xy 91.63177 -125.66523) (xy 91.614127 -125.644301) (xy 91.584417 -125.598327) (xy 91.561582 -125.548579)
			(xy 91.546092 -125.496077) (xy 91.538264 -125.441901) (xy 91.53779 -125.414532) (xy 91.538552 -125.38964)
			(xy 91.539314 -125.376432) (xy 91.528392 -125.353064) (xy 91.437206 -125.287024) (xy 91.411552 -125.283976)
			(xy 91.39936 -125.288802) (xy 91.376593 -125.297566) (xy 91.329391 -125.309889) (xy 91.281004 -125.316101)
			(xy 91.256612 -125.316488) (xy 91.229242 -125.316018) (xy 91.175063 -125.308201) (xy 91.12256 -125.292713)
			(xy 91.072813 -125.269873) (xy 91.026846 -125.240149) (xy 91.005914 -125.222508) (xy 91.00566 -125.222254)
			(xy 90.998564 -125.216681) (xy 90.981654 -125.210427) (xy 90.97264 -125.210062) (xy 90.905584 -125.210062)
			(xy 90.896567 -125.210419) (xy 90.879651 -125.216668) (xy 90.872564 -125.222254) (xy 90.872564 -125.222508)
			(xy 90.87231 -125.222508) (xy 90.851386 -125.240157) (xy 90.805411 -125.269867) (xy 90.755661 -125.292701)
			(xy 90.703159 -125.30819) (xy 90.648982 -125.316015) (xy 90.621612 -125.316488) (xy 90.593788 -125.315955)
			(xy 90.538729 -125.307893) (xy 90.485426 -125.291911) (xy 90.435015 -125.268348) (xy 90.388565 -125.237704)
			(xy 90.347066 -125.200632) (xy 90.311398 -125.157919) (xy 90.282321 -125.110474) (xy 90.260452 -125.059304)
			(xy 90.246257 -125.005498) (xy 90.242644 -124.977906) (xy 90.241063 -124.967592) (xy 90.23077 -124.949461)
			(xy 90.214128 -124.936902) (xy 90.193868 -124.931979) (xy 90.173318 -124.935499) (xy 90.155853 -124.946885)
			(xy 90.14968 -124.9553) (xy 90.142754 -124.965562) (xy 90.127756 -124.985262) (xy 90.119708 -124.99467)
			(xy 90.119454 -124.994924) (xy 90.113846 -125.001996) (xy 90.107613 -125.018924) (xy 90.107262 -125.027944)
			(xy 90.107262 -125.095) (xy 90.107627 -125.104016) (xy 90.11387 -125.120932) (xy 90.119454 -125.12802)
			(xy 90.119708 -125.12802) (xy 90.119708 -125.128274) (xy 90.13732 -125.14923) (xy 90.167043 -125.195194)
			(xy 90.189888 -125.244937) (xy 90.205385 -125.297435) (xy 90.213215 -125.35161) (xy 90.213218 -125.406348)
			(xy 90.205394 -125.460523) (xy 90.189903 -125.513023) (xy 90.167063 -125.562769) (xy 90.137345 -125.608737)
			(xy 90.119708 -125.62967) (xy 90.119454 -125.629924) (xy 90.113846 -125.636996) (xy 90.107613 -125.653924)
			(xy 90.107262 -125.662944) (xy 90.107262 -125.73) (xy 90.107627 -125.739016) (xy 90.11387 -125.755932)
			(xy 90.119454 -125.76302) (xy 90.119708 -125.76302) (xy 90.119708 -125.763274) (xy 90.13735 -125.784204)
			(xy 90.167061 -125.830178) (xy 90.189896 -125.879926) (xy 90.205387 -125.932427) (xy 90.213214 -125.986603)
			(xy 90.213688 -126.013972) (xy 90.213202 -126.041223) (xy 90.205446 -126.095171) (xy 90.190091 -126.147466)
			(xy 90.167449 -126.197043) (xy 90.137983 -126.242893) (xy 90.102292 -126.284084) (xy 90.061101 -126.319775)
			(xy 90.015251 -126.349241) (xy 89.965674 -126.371883) (xy 89.913379 -126.387238) (xy 89.859431 -126.394994)
			(xy 89.804929 -126.394994) (xy 89.750981 -126.387238) (xy 89.698686 -126.371883) (xy 89.649109 -126.349241)
			(xy 89.603259 -126.319775) (xy 89.562068 -126.284084) (xy 89.526377 -126.242893) (xy 89.496911 -126.197043)
			(xy 89.474269 -126.147466) (xy 89.458914 -126.095171) (xy 89.451158 -126.041223) (xy 89.450672 -126.013972)
			(xy 69.914554 -126.013972) (xy 69.902551 -126.027368) (xy 69.859683 -126.063043) (xy 69.812077 -126.092097)
			(xy 69.760748 -126.113909) (xy 69.706791 -126.128015) (xy 69.651354 -126.134115) (xy 69.59562 -126.132078)
			(xy 69.540777 -126.121948) (xy 69.487993 -126.103941) (xy 69.438393 -126.07844) (xy 69.393035 -126.045989)
			(xy 69.352886 -126.00728) (xy 69.3188 -125.963137) (xy 69.291504 -125.914502) (xy 69.271581 -125.862411)
			(xy 69.259455 -125.807974) (xy 69.255384 -125.752352) (xy 67.87841 -125.752352) (xy 67.841545 -125.774851)
			(xy 67.790216 -125.796663) (xy 67.736259 -125.810769) (xy 67.680822 -125.816869) (xy 67.625088 -125.814832)
			(xy 67.570245 -125.804702) (xy 67.517461 -125.786695) (xy 67.467861 -125.761194) (xy 67.422503 -125.728743)
			(xy 67.382354 -125.690034) (xy 67.348268 -125.645891) (xy 67.320972 -125.597256) (xy 67.301049 -125.545165)
			(xy 67.288923 -125.490728) (xy 67.284852 -125.435106) (xy 66.193751 -125.435106) (xy 66.193751 -125.462355)
			(xy 66.185993 -125.516309) (xy 66.170635 -125.56861) (xy 66.14799 -125.618193) (xy 66.118519 -125.664048)
			(xy 66.082821 -125.705242) (xy 66.041624 -125.740937) (xy 65.995767 -125.770404) (xy 65.946182 -125.793045)
			(xy 65.89388 -125.808399) (xy 65.839925 -125.816153) (xy 65.81267 -125.816614) (xy 65.785691 -125.816197)
			(xy 65.732268 -125.808611) (xy 65.680449 -125.793566) (xy 65.631271 -125.771364) (xy 65.585714 -125.742448)
			(xy 65.544692 -125.707396) (xy 65.509022 -125.666909) (xy 65.479419 -125.621796) (xy 65.456475 -125.572959)
			(xy 65.440647 -125.521374) (xy 65.435988 -125.494796) (xy 65.433835 -125.484563) (xy 65.422548 -125.466984)
			(xy 65.414144 -125.46076) (xy 65.34277 -125.413262) (xy 65.321688 -125.409452) (xy 65.311528 -125.411992)
			(xy 65.284834 -125.418135) (xy 65.230458 -125.424755) (xy 65.20307 -125.4252) (xy 65.175682 -125.424763)
			(xy 65.121306 -125.418137) (xy 65.094612 -125.411992) (xy 65.084452 -125.409452) (xy 65.06337 -125.413262)
			(xy 64.983106 -125.466602) (xy 64.97193 -125.484128) (xy 64.970152 -125.494796) (xy 64.965455 -125.521361)
			(xy 64.949603 -125.572925) (xy 64.926643 -125.621741) (xy 64.897034 -125.666834) (xy 64.861367 -125.707306)
			(xy 64.820354 -125.742349) (xy 64.774811 -125.771263) (xy 64.725649 -125.793472) (xy 64.673849 -125.808531)
			(xy 64.620443 -125.816142) (xy 64.59347 -125.816614) (xy 64.566221 -125.816114) (xy 64.512277 -125.808354)
			(xy 64.459987 -125.792997) (xy 64.410414 -125.770354) (xy 64.364568 -125.740888) (xy 64.323382 -125.705197)
			(xy 64.287694 -125.664008) (xy 64.258231 -125.61816) (xy 64.235593 -125.568585) (xy 64.220239 -125.516294)
			(xy 64.212484 -125.462349) (xy 64.212484 -125.407851) (xy 64.220239 -125.353906) (xy 64.235593 -125.301615)
			(xy 64.258231 -125.25204) (xy 64.287694 -125.206192) (xy 64.323382 -125.165003) (xy 64.364568 -125.129312)
			(xy 64.410414 -125.099846) (xy 64.459987 -125.077203) (xy 64.512277 -125.061846) (xy 64.566221 -125.054086)
			(xy 64.59347 -125.053598) (xy 64.610582 -125.053789) (xy 64.644669 -125.056842) (xy 64.661542 -125.059694)
			(xy 64.672833 -125.06105) (xy 64.694721 -125.054982) (xy 64.703706 -125.04801) (xy 64.72809 -125.027182)
			(xy 64.736517 -125.019204) (xy 64.745644 -124.997893) (xy 64.745616 -124.986288) (xy 64.745108 -124.967238)
			(xy 64.745108 -124.103638) (xy 64.745616 -124.083826) (xy 64.745576 -124.072234) (xy 64.736465 -124.050945)
			(xy 64.72809 -124.042932) (xy 64.703706 -124.02185) (xy 64.694709 -124.014768) (xy 64.672624 -124.008816)
			(xy 64.661288 -124.01042) (xy 64.64448 -124.013284) (xy 64.610519 -124.016335) (xy 64.59347 -124.016516)
			(xy 64.566221 -124.016012) (xy 64.512277 -124.008252) (xy 64.459987 -123.992895) (xy 64.410415 -123.970253)
			(xy 64.364569 -123.940786) (xy 64.323383 -123.905095) (xy 64.287696 -123.863907) (xy 64.258233 -123.818059)
			(xy 64.235595 -123.768485) (xy 64.220241 -123.716193) (xy 64.212486 -123.662249) (xy 64.212486 -123.607751)
			(xy 64.220241 -123.553807) (xy 64.235595 -123.501515) (xy 64.258233 -123.451941) (xy 64.287696 -123.406093)
			(xy 64.323383 -123.364905) (xy 64.364569 -123.329214) (xy 64.410415 -123.299747) (xy 64.459987 -123.277105)
			(xy 64.512277 -123.261748) (xy 64.566221 -123.253988) (xy 64.59347 -123.2535) (xy 64.620475 -123.254036)
			(xy 64.673947 -123.261636) (xy 64.725812 -123.276704) (xy 64.775033 -123.298937) (xy 64.820625 -123.327891)
			(xy 64.861677 -123.362988) (xy 64.897368 -123.403524) (xy 64.926983 -123.448689) (xy 64.949931 -123.497581)
			(xy 64.965753 -123.549221) (xy 64.970406 -123.575826) (xy 64.97193 -123.586494) (xy 64.98336 -123.604274)
			(xy 65.054734 -123.651772) (xy 65.063665 -123.657117) (xy 65.084127 -123.660796) (xy 65.094358 -123.658884)
			(xy 65.09512 -123.658884) (xy 65.12169 -123.652769) (xy 65.17581 -123.646146) (xy 65.20307 -123.645676)
			(xy 65.230395 -123.646125) (xy 65.284643 -123.65275) (xy 65.311274 -123.658884) (xy 65.311782 -123.658884)
			(xy 65.32201 -123.660762) (xy 65.34246 -123.657076) (xy 65.351406 -123.651772) (xy 65.42278 -123.604274)
			(xy 65.43421 -123.586494) (xy 65.435734 -123.575826) (xy 65.440389 -123.549221) (xy 65.456218 -123.497581)
			(xy 65.47917 -123.44869) (xy 65.508787 -123.403523) (xy 65.544477 -123.362984) (xy 65.585526 -123.327882)
			(xy 65.631115 -123.298919) (xy 65.680332 -123.276674) (xy 65.732194 -123.26159) (xy 65.785665 -123.25397)
			(xy 65.81267 -123.2535) (xy 65.84004 -123.253984) (xy 65.894218 -123.261797) (xy 65.946721 -123.277282)
			(xy 65.996468 -123.30012) (xy 66.042436 -123.329841) (xy 66.063368 -123.34748) (xy 66.063622 -123.347734)
			(xy 66.070695 -123.35334) (xy 66.087622 -123.359574) (xy 66.096642 -123.359926) (xy 66.163698 -123.359926)
			(xy 66.172714 -123.359562) (xy 66.189631 -123.353319) (xy 66.196718 -123.347734) (xy 66.196718 -123.34748)
			(xy 66.196972 -123.34748) (xy 66.217901 -123.329837) (xy 66.263875 -123.300127) (xy 66.313623 -123.277292)
			(xy 66.366125 -123.261802) (xy 66.420301 -123.253974) (xy 66.44767 -123.2535) (xy 66.464782 -123.253691)
			(xy 66.498869 -123.256744) (xy 66.515742 -123.259596) (xy 66.527033 -123.260952) (xy 66.548921 -123.254884)
			(xy 66.557906 -123.247912) (xy 66.58229 -123.227084) (xy 66.590716 -123.219105) (xy 66.599843 -123.197795)
			(xy 66.599816 -123.18619) (xy 66.599308 -123.16714) (xy 66.599308 -122.30354) (xy 66.599816 -122.283982)
			(xy 66.599802 -122.272388) (xy 66.590673 -122.251098) (xy 66.58229 -122.243088) (xy 66.557906 -122.222006)
			(xy 66.548906 -122.214929) (xy 66.526824 -122.208971) (xy 66.515488 -122.210576) (xy 66.49868 -122.213439)
			(xy 66.464719 -122.216491) (xy 66.44767 -122.216672) (xy 66.420299 -122.21623) (xy 66.366118 -122.208408)
			(xy 66.313615 -122.192913) (xy 66.263868 -122.170066) (xy 66.217903 -122.140336) (xy 66.196972 -122.122692)
			(xy 66.196718 -122.122438) (xy 66.189636 -122.116845) (xy 66.172715 -122.110604) (xy 66.163698 -122.110246)
			(xy 66.096642 -122.110246) (xy 66.087626 -122.110613) (xy 66.070708 -122.116853) (xy 66.063622 -122.122438)
			(xy 66.063622 -122.122692) (xy 66.063368 -122.122692) (xy 66.04242 -122.140311) (xy 65.996452 -122.170026)
			(xy 65.946708 -122.192866) (xy 65.894211 -122.208362) (xy 65.840038 -122.216195) (xy 65.81267 -122.216672)
			(xy 65.785693 -122.216206) (xy 65.732275 -122.208621) (xy 65.68046 -122.19358) (xy 65.631284 -122.171382)
			(xy 65.58573 -122.142471) (xy 65.544708 -122.107425) (xy 65.509038 -122.066944) (xy 65.479433 -122.021838)
			(xy 65.456484 -121.973008) (xy 65.440651 -121.921429) (xy 65.435988 -121.894854) (xy 65.433854 -121.884615)
			(xy 65.422553 -121.867039) (xy 65.414144 -121.860818) (xy 65.34277 -121.81332) (xy 65.321688 -121.80951)
			(xy 65.311528 -121.81205) (xy 65.284825 -121.818116) (xy 65.230451 -121.824615) (xy 65.20307 -121.825004)
			(xy 65.175688 -121.82463) (xy 65.121312 -121.818134) (xy 65.094612 -121.81205) (xy 65.084452 -121.80951)
			(xy 65.06337 -121.81332) (xy 64.983106 -121.86666) (xy 64.97193 -121.884186) (xy 64.970152 -121.894854)
			(xy 64.965499 -121.921427) (xy 64.949639 -121.972991) (xy 64.926673 -122.021807) (xy 64.897058 -122.066899)
			(xy 64.861386 -122.10737) (xy 64.820367 -122.142411) (xy 64.774821 -122.171324) (xy 64.725656 -122.193531)
			(xy 64.673852 -122.20859) (xy 64.620444 -122.2162) (xy 64.59347 -122.216672) (xy 64.566218 -122.216256)
			(xy 64.512268 -122.208495) (xy 64.459972 -122.193136) (xy 64.410394 -122.170491) (xy 64.364543 -122.141021)
			(xy 64.323352 -122.105326) (xy 64.287661 -122.064133) (xy 64.258194 -122.01828) (xy 64.235553 -121.9687)
			(xy 64.220198 -121.916403) (xy 64.212442 -121.862452) (xy 52.700428 -121.862452) (xy 52.700428 -121.886472)
			(xy 52.69992 -121.906284) (xy 52.700123 -121.917729) (xy 52.709229 -121.9387) (xy 52.717446 -121.94667)
			(xy 52.742084 -121.968006) (xy 52.751087 -121.975078) (xy 52.773167 -121.981039) (xy 52.784502 -121.979436)
			(xy 52.80131 -121.976574) (xy 52.835271 -121.973522) (xy 52.85232 -121.97334) (xy 52.879691 -121.973785)
			(xy 52.933872 -121.981606) (xy 52.986375 -121.9971) (xy 53.036122 -122.019946) (xy 53.082087 -122.049676)
			(xy 53.103018 -122.06732) (xy 53.103272 -122.067574) (xy 53.110356 -122.073164) (xy 53.127275 -122.079407)
			(xy 53.136292 -122.079766) (xy 53.203348 -122.079766) (xy 53.212363 -122.079391) (xy 53.229281 -122.073157)
			(xy 53.236368 -122.067574) (xy 53.236368 -122.06732) (xy 53.236622 -122.06732) (xy 53.257575 -122.049707)
			(xy 53.303542 -122.019991) (xy 53.353284 -121.997149) (xy 53.40578 -121.981652) (xy 53.459952 -121.973817)
			(xy 53.48732 -121.97334) (xy 53.514297 -121.973805) (xy 53.567716 -121.981389) (xy 53.619531 -121.99643)
			(xy 53.668708 -122.018627) (xy 53.714263 -122.047538) (xy 53.755285 -122.082585) (xy 53.790955 -122.123066)
			(xy 53.82056 -122.168173) (xy 53.843508 -122.217003) (xy 53.85934 -122.268583) (xy 53.864002 -122.295158)
			(xy 53.866134 -122.305397) (xy 53.877437 -122.322972) (xy 53.885846 -122.329194) (xy 53.95722 -122.376692)
			(xy 53.978302 -122.380502) (xy 53.988462 -122.377962) (xy 54.015166 -122.371898) (xy 54.069539 -122.365398)
			(xy 54.09692 -122.365008) (xy 54.124302 -122.365383) (xy 54.178678 -122.371878) (xy 54.205378 -122.377962)
			(xy 54.215538 -122.380502) (xy 54.23662 -122.376692) (xy 54.316884 -122.323352) (xy 54.32806 -122.305826)
			(xy 54.329838 -122.295158) (xy 54.33451 -122.268588) (xy 54.350368 -122.217025) (xy 54.373332 -122.16821)
			(xy 54.402944 -122.123118) (xy 54.438614 -122.082647) (xy 54.479631 -122.047606) (xy 54.525175 -122.018692)
			(xy 54.574338 -121.996484) (xy 54.62614 -121.981424) (xy 54.679547 -121.973812) (xy 54.70652 -121.97334)
			(xy 54.733774 -121.973731) (xy 54.787726 -121.981491) (xy 54.840025 -121.99685) (xy 54.889606 -122.019495)
			(xy 54.93546 -122.048966) (xy 54.976653 -122.084662) (xy 55.012346 -122.125856) (xy 55.041815 -122.171712)
			(xy 55.064457 -122.221294) (xy 55.079813 -122.273593) (xy 55.08757 -122.327546) (xy 55.08757 -122.382054)
			(xy 55.079813 -122.436007) (xy 55.064457 -122.488306) (xy 55.041815 -122.537888) (xy 55.012346 -122.583744)
			(xy 54.976653 -122.624938) (xy 54.93546 -122.660634) (xy 54.889606 -122.690105) (xy 54.840025 -122.71275)
			(xy 54.787726 -122.728109) (xy 54.733774 -122.735869) (xy 54.70652 -122.736356) (xy 54.689408 -122.736167)
			(xy 54.655321 -122.733113) (xy 54.638448 -122.73026) (xy 54.627157 -122.728885) (xy 54.605266 -122.734964)
			(xy 54.596284 -122.741944) (xy 54.5719 -122.763026) (xy 54.56347 -122.770942) (xy 54.554206 -122.792103)
			(xy 54.55412 -122.803666) (xy 54.554628 -122.822462) (xy 54.554628 -123.686316) (xy 54.55412 -123.706382)
			(xy 54.554324 -123.717827) (xy 54.563429 -123.738798) (xy 54.571646 -123.746768) (xy 54.596284 -123.768104)
			(xy 54.605287 -123.775176) (xy 54.627367 -123.781137) (xy 54.638702 -123.779534) (xy 54.65551 -123.776672)
			(xy 54.689471 -123.77362) (xy 54.70652 -123.773438) (xy 54.733774 -123.773833) (xy 54.787726 -123.781593)
			(xy 54.840024 -123.796952) (xy 54.889605 -123.819597) (xy 54.935458 -123.849067) (xy 54.976651 -123.884763)
			(xy 55.012345 -123.925958) (xy 55.041813 -123.971813) (xy 55.064455 -124.021394) (xy 55.079811 -124.073694)
			(xy 55.087568 -124.127646) (xy 55.087568 -124.182154) (xy 55.079811 -124.236106) (xy 55.064455 -124.288406)
			(xy 55.041813 -124.337987) (xy 55.012345 -124.383842) (xy 54.976651 -124.425037) (xy 54.935458 -124.460733)
			(xy 54.889605 -124.490203) (xy 54.840024 -124.512848) (xy 54.787726 -124.528207) (xy 54.733774 -124.535967)
			(xy 54.70652 -124.536454) (xy 54.679513 -124.535966) (xy 54.626037 -124.528363) (xy 54.574169 -124.513292)
			(xy 54.524946 -124.491054) (xy 54.479352 -124.462095) (xy 54.438299 -124.426993) (xy 54.402609 -124.386451)
			(xy 54.372996 -124.341279) (xy 54.350051 -124.292381) (xy 54.334234 -124.240736) (xy 54.329584 -124.214128)
			(xy 54.32806 -124.20346) (xy 54.31663 -124.18568) (xy 54.245256 -124.138182) (xy 54.236329 -124.13283)
			(xy 54.215863 -124.129156) (xy 54.205632 -124.13107) (xy 54.20487 -124.13107) (xy 54.178294 -124.137124)
			(xy 54.124174 -124.143616) (xy 54.09692 -124.144024) (xy 54.069602 -124.14364) (xy 54.015353 -124.137144)
			(xy 53.988716 -124.13107) (xy 53.988208 -124.13107) (xy 53.977974 -124.12925) (xy 53.957533 -124.132899)
			(xy 53.948584 -124.138182) (xy 53.87721 -124.18568) (xy 53.86578 -124.20346) (xy 53.864256 -124.214128)
			(xy 53.859576 -124.240729) (xy 53.843752 -124.292369) (xy 53.820804 -124.341261) (xy 53.791191 -124.386429)
			(xy 53.755505 -124.426969) (xy 53.714458 -124.462072) (xy 53.668871 -124.491036) (xy 53.619656 -124.513282)
			(xy 53.567795 -124.528365) (xy 53.514325 -124.535984) (xy 53.48732 -124.536454) (xy 53.45995 -124.535987)
			(xy 53.40577 -124.528171) (xy 53.353267 -124.512683) (xy 53.30352 -124.489841) (xy 53.257553 -124.460116)
			(xy 53.236622 -124.442474) (xy 53.236368 -124.44222) (xy 53.229273 -124.436646) (xy 53.212362 -124.430394)
			(xy 53.203348 -124.430028) (xy 53.136292 -124.430028) (xy 53.127274 -124.430375) (xy 53.110357 -124.436629)
			(xy 53.103272 -124.44222) (xy 53.103272 -124.442474) (xy 53.103018 -124.442474) (xy 53.082087 -124.460114)
			(xy 53.036114 -124.489827) (xy 52.986366 -124.512663) (xy 52.933865 -124.528154) (xy 52.879689 -124.535981)
			(xy 52.85232 -124.536454) (xy 52.835208 -124.536265) (xy 52.801121 -124.533211) (xy 52.784248 -124.530358)
			(xy 52.772957 -124.528984) (xy 52.751066 -124.535062) (xy 52.742084 -124.542042) (xy 52.7177 -124.563124)
			(xy 52.709271 -124.571041) (xy 52.700006 -124.592201) (xy 52.69992 -124.603764) (xy 52.700428 -124.62256)
			(xy 52.700428 -125.486414) (xy 52.69992 -125.50648) (xy 52.700125 -125.517925) (xy 52.709229 -125.538895)
			(xy 52.717446 -125.546866) (xy 52.742084 -125.568202) (xy 52.751088 -125.575274) (xy 52.773167 -125.581235)
			(xy 52.784502 -125.579632) (xy 52.80131 -125.57677) (xy 52.835271 -125.573718) (xy 52.85232 -125.573536)
			(xy 52.879573 -125.573935) (xy 52.933525 -125.581695) (xy 52.985824 -125.597054) (xy 53.035404 -125.619699)
			(xy 53.081257 -125.649169) (xy 53.12245 -125.684864) (xy 53.158143 -125.726059) (xy 53.187611 -125.771914)
			(xy 53.210253 -125.821495) (xy 53.225609 -125.873794) (xy 53.233366 -125.927747) (xy 53.233366 -125.982253)
			(xy 53.225609 -126.036206) (xy 53.210253 -126.088505) (xy 53.187611 -126.138086) (xy 53.158143 -126.183941)
			(xy 53.12245 -126.225136) (xy 53.081257 -126.260831) (xy 53.035404 -126.290301) (xy 52.985824 -126.312946)
			(xy 52.933525 -126.328305) (xy 52.879573 -126.336065) (xy 52.85232 -126.336552) (xy 52.825313 -126.336066)
			(xy 52.771837 -126.328463) (xy 52.719969 -126.313392) (xy 52.670745 -126.291154) (xy 52.625151 -126.262194)
			(xy 52.584099 -126.227092) (xy 52.548409 -126.18655) (xy 52.518795 -126.141377) (xy 52.495851 -126.09248)
			(xy 52.480034 -126.040834) (xy 52.475384 -126.014226) (xy 52.47386 -126.003558) (xy 52.46243 -125.985778)
			(xy 52.391056 -125.93828) (xy 52.382129 -125.932928) (xy 52.361663 -125.929254) (xy 52.351432 -125.931168)
			(xy 52.35067 -125.931168) (xy 52.3241 -125.937283) (xy 52.26998 -125.943906) (xy 52.24272 -125.944376)
			(xy 52.215395 -125.94393) (xy 52.161147 -125.937303) (xy 52.134516 -125.931168) (xy 52.134008 -125.931168)
			(xy 52.123774 -125.929349) (xy 52.103333 -125.932997) (xy 52.094384 -125.93828) (xy 52.02301 -125.985778)
			(xy 52.01158 -126.003558) (xy 52.010056 -126.014226) (xy 52.00545 -126.040841) (xy 51.989614 -126.092481)
			(xy 51.966655 -126.141372) (xy 51.937031 -126.186538) (xy 51.901336 -126.227077) (xy 51.860281 -126.262177)
			(xy 51.814688 -126.291139) (xy 51.765467 -126.313382) (xy 51.713601 -126.328464) (xy 51.660127 -126.336083)
			(xy 51.63312 -126.336552) (xy 51.605869 -126.336002) (xy 51.551922 -126.328248) (xy 51.499628 -126.312896)
			(xy 51.450051 -126.290257) (xy 51.404201 -126.260793) (xy 51.363011 -126.225103) (xy 51.327319 -126.183915)
			(xy 51.297852 -126.138066) (xy 51.275211 -126.08849) (xy 51.259856 -126.036197) (xy 51.252099 -125.982251)
			(xy 51.252099 -125.927749) (xy 51.259856 -125.873803) (xy 51.275211 -125.82151) (xy 51.297852 -125.771934)
			(xy 51.327319 -125.726085) (xy 51.363011 -125.684897) (xy 51.404201 -125.649207) (xy 51.450051 -125.619743)
			(xy 51.499628 -125.597104) (xy 51.551922 -125.581752) (xy 51.605869 -125.573998) (xy 51.63312 -125.573536)
			(xy 51.650168 -125.573739) (xy 51.684128 -125.576789) (xy 51.700938 -125.579632) (xy 51.712266 -125.581046)
			(xy 51.734281 -125.575126) (xy 51.743356 -125.568202) (xy 51.767994 -125.546866) (xy 51.776349 -125.538999)
			(xy 51.785461 -125.517957) (xy 51.78552 -125.50648) (xy 51.785012 -125.486414) (xy 51.785012 -124.62256)
			(xy 51.78552 -124.603764) (xy 51.785396 -124.592206) (xy 51.776153 -124.571048) (xy 51.76774 -124.563124)
			(xy 51.743356 -124.542042) (xy 51.73439 -124.535035) (xy 51.712488 -124.528973) (xy 51.701192 -124.530358)
			(xy 51.684321 -124.533231) (xy 51.650233 -124.536281) (xy 51.63312 -124.536454) (xy 51.605869 -124.5359)
			(xy 51.551923 -124.528146) (xy 51.499629 -124.512794) (xy 51.450052 -124.490155) (xy 51.404202 -124.460691)
			(xy 51.363012 -124.425002) (xy 51.327321 -124.383814) (xy 51.297854 -124.337965) (xy 51.275213 -124.28839)
			(xy 51.259858 -124.236097) (xy 51.252101 -124.18215) (xy 51.252101 -124.12765) (xy 51.259858 -124.073703)
			(xy 51.275213 -124.02141) (xy 51.297854 -123.971835) (xy 51.327321 -123.925986) (xy 51.363012 -123.884798)
			(xy 51.404202 -123.849109) (xy 51.450052 -123.819645) (xy 51.499629 -123.797006) (xy 51.551923 -123.781654)
			(xy 51.605869 -123.7739) (xy 51.63312 -123.773438) (xy 51.660097 -123.773905) (xy 51.713516 -123.781488)
			(xy 51.765331 -123.796529) (xy 51.814508 -123.818727) (xy 51.860062 -123.847638) (xy 51.901084 -123.882684)
			(xy 51.936754 -123.923165) (xy 51.966359 -123.968271) (xy 51.989307 -124.017102) (xy 52.00514 -124.068681)
			(xy 52.009802 -124.095256) (xy 52.011935 -124.105495) (xy 52.023237 -124.12307) (xy 52.031646 -124.129292)
			(xy 52.10302 -124.17679) (xy 52.124102 -124.1806) (xy 52.134262 -124.17806) (xy 52.160956 -124.171919)
			(xy 52.215332 -124.165298) (xy 52.24272 -124.164852) (xy 52.270108 -124.165289) (xy 52.324484 -124.171915)
			(xy 52.351178 -124.17806) (xy 52.361338 -124.1806) (xy 52.38242 -124.17679) (xy 52.462684 -124.12345)
			(xy 52.47386 -124.105924) (xy 52.475638 -124.095256) (xy 52.480308 -124.068686) (xy 52.496166 -124.017123)
			(xy 52.519131 -123.968308) (xy 52.548743 -123.923216) (xy 52.584414 -123.882745) (xy 52.62543 -123.847703)
			(xy 52.670974 -123.81879) (xy 52.720138 -123.796582) (xy 52.77194 -123.781522) (xy 52.825347 -123.77391)
			(xy 52.85232 -123.773438) (xy 52.879691 -123.773883) (xy 52.933871 -123.781705) (xy 52.986375 -123.797198)
			(xy 53.036122 -123.820045) (xy 53.082087 -123.849774) (xy 53.103018 -123.867418) (xy 53.103272 -123.867672)
			(xy 53.110356 -123.873261) (xy 53.127275 -123.879504) (xy 53.136292 -123.879864) (xy 53.203348 -123.879864)
			(xy 53.212363 -123.87949) (xy 53.229281 -123.873255) (xy 53.236368 -123.867672) (xy 53.236368 -123.867418)
			(xy 53.236622 -123.867418) (xy 53.257575 -123.849805) (xy 53.303542 -123.820088) (xy 53.353284 -123.797247)
			(xy 53.40578 -123.78175) (xy 53.459952 -123.773915) (xy 53.48732 -123.773438) (xy 53.504368 -123.773641)
			(xy 53.538328 -123.776691) (xy 53.555138 -123.779534) (xy 53.566466 -123.780948) (xy 53.588481 -123.775028)
			(xy 53.597556 -123.768104) (xy 53.622194 -123.746768) (xy 53.630548 -123.7389) (xy 53.63966 -123.717859)
			(xy 53.63972 -123.706382) (xy 53.639212 -123.686316) (xy 53.639212 -122.822462) (xy 53.63972 -122.803666)
			(xy 53.639595 -122.792108) (xy 53.630352 -122.77095) (xy 53.62194 -122.763026) (xy 53.597556 -122.741944)
			(xy 53.58859 -122.734937) (xy 53.566687 -122.728875) (xy 53.555392 -122.73026) (xy 53.538521 -122.733133)
			(xy 53.504433 -122.736183) (xy 53.48732 -122.736356) (xy 53.45995 -122.735889) (xy 53.40577 -122.728073)
			(xy 53.353267 -122.712585) (xy 53.30352 -122.689743) (xy 53.257553 -122.660018) (xy 53.236622 -122.642376)
			(xy 53.236368 -122.642122) (xy 53.229273 -122.636549) (xy 53.212362 -122.630296) (xy 53.203348 -122.62993)
			(xy 53.136292 -122.62993) (xy 53.127274 -122.630277) (xy 53.110357 -122.636531) (xy 53.103272 -122.642122)
			(xy 53.103272 -122.642376) (xy 53.103018 -122.642376) (xy 53.082087 -122.660016) (xy 53.036114 -122.689729)
			(xy 52.986366 -122.712565) (xy 52.933865 -122.728056) (xy 52.879689 -122.735883) (xy 52.85232 -122.736356)
			(xy 52.825323 -122.735907) (xy 52.771866 -122.72831) (xy 52.720015 -122.713251) (xy 52.670805 -122.691031)
			(xy 52.62522 -122.662095) (xy 52.584171 -122.627019) (xy 52.548478 -122.586506) (xy 52.518854 -122.541364)
			(xy 52.495891 -122.492496) (xy 52.480049 -122.440879) (xy 52.475384 -122.414284) (xy 52.47386 -122.403616)
			(xy 52.46243 -122.385836) (xy 52.382166 -122.332496) (xy 52.361592 -122.328686) (xy 52.351432 -122.331226)
			(xy 52.350924 -122.331226) (xy 52.324283 -122.337281) (xy 52.270037 -122.34378) (xy 52.24272 -122.34418)
			(xy 52.215402 -122.343795) (xy 52.161153 -122.337299) (xy 52.134516 -122.331226) (xy 52.134008 -122.331226)
			(xy 52.123774 -122.329398) (xy 52.103332 -122.33305) (xy 52.094384 -122.338338) (xy 52.02301 -122.385836)
			(xy 52.01158 -122.403616) (xy 52.010056 -122.414284) (xy 52.005418 -122.440893) (xy 51.989587 -122.492533)
			(xy 51.966633 -122.541425) (xy 51.937014 -122.586592) (xy 51.901323 -122.627131) (xy 51.860271 -122.662232)
			(xy 51.814681 -122.691195) (xy 51.765462 -122.713439) (xy 51.713598 -122.728522) (xy 51.660126 -122.736141)
			(xy 51.63312 -122.73661) (xy 51.605866 -122.736144) (xy 51.551914 -122.728389) (xy 51.499614 -122.713035)
			(xy 51.450031 -122.690394) (xy 51.404176 -122.660927) (xy 51.362981 -122.625233) (xy 51.327285 -122.58404)
			(xy 51.297816 -122.538186) (xy 51.275172 -122.488605) (xy 51.259815 -122.436306) (xy 51.252057 -122.382354)
			(xy 47.384954 -122.382354) (xy 47.364369 -122.405328) (xy 47.321501 -122.441003) (xy 47.273895 -122.470057)
			(xy 47.222566 -122.491869) (xy 47.168609 -122.505975) (xy 47.113172 -122.512075) (xy 47.057438 -122.510038)
			(xy 47.002595 -122.499908) (xy 46.949811 -122.481901) (xy 46.900211 -122.4564) (xy 46.854853 -122.423949)
			(xy 46.814704 -122.38524) (xy 46.780618 -122.341097) (xy 46.753322 -122.292462) (xy 46.733399 -122.240371)
			(xy 46.721273 -122.185934) (xy 46.717202 -122.130312) (xy 45.359841 -122.130312) (xy 45.384865 -122.168136)
			(xy 45.408537 -122.218633) (xy 45.424605 -122.27204) (xy 45.432725 -122.327216) (xy 45.433234 -122.355102)
			(xy 45.432725 -122.382988) (xy 45.424605 -122.438164) (xy 45.408537 -122.491571) (xy 45.384865 -122.542068)
			(xy 45.354092 -122.588581) (xy 45.316875 -122.630118) (xy 45.274007 -122.665793) (xy 45.226401 -122.694847)
			(xy 45.175072 -122.716659) (xy 45.121115 -122.730765) (xy 45.065678 -122.736865) (xy 45.009944 -122.734828)
			(xy 44.955101 -122.724698) (xy 44.902317 -122.706691) (xy 44.852717 -122.68119) (xy 44.807359 -122.648739)
			(xy 44.76721 -122.61003) (xy 44.733124 -122.565887) (xy 44.705828 -122.517252) (xy 44.685905 -122.465161)
			(xy 44.673779 -122.410724) (xy 44.669708 -122.355102) (xy 38.677958 -122.355102) (xy 38.671881 -122.362115)
			(xy 38.630687 -122.397805) (xy 38.584833 -122.427268) (xy 38.535252 -122.449905) (xy 38.482954 -122.465255)
			(xy 38.429004 -122.473006) (xy 38.401752 -122.473466) (xy 38.375844 -122.473027) (xy 38.324505 -122.465996)
			(xy 38.274591 -122.452085) (xy 38.227017 -122.431548) (xy 38.182659 -122.404764) (xy 38.142333 -122.372224)
			(xy 38.10678 -122.334528) (xy 38.091364 -122.3137) (xy 38.085614 -122.306378) (xy 38.070118 -122.296088)
			(xy 38.061138 -122.293634) (xy 38.030658 -122.286776) (xy 38.021381 -122.28503) (xy 38.002718 -122.28777)
			(xy 37.994336 -122.29211) (xy 37.968372 -122.306428) (xy 37.913516 -122.328933) (xy 37.856209 -122.344153)
			(xy 37.797415 -122.351832) (xy 37.767768 -122.352308) (xy 37.738126 -122.351794) (xy 37.679344 -122.344078)
			(xy 37.622046 -122.328856) (xy 37.567185 -122.306382) (xy 37.5412 -122.29211) (xy 37.532792 -122.287853)
			(xy 37.514158 -122.285127) (xy 37.504878 -122.286776) (xy 37.474398 -122.293634) (xy 37.465395 -122.296032)
			(xy 37.449895 -122.306346) (xy 37.444172 -122.3137) (xy 37.428736 -122.334515) (xy 37.393199 -122.372228)
			(xy 37.352882 -122.404781) (xy 37.308527 -122.431573) (xy 37.260953 -122.452111) (xy 37.211035 -122.466016)
			(xy 37.159693 -122.473032) (xy 37.133784 -122.473466) (xy 37.106531 -122.473063) (xy 37.052579 -122.465304)
			(xy 37.00028 -122.449946) (xy 36.950699 -122.427301) (xy 36.904846 -122.397831) (xy 36.863653 -122.362136)
			(xy 36.827959 -122.320941) (xy 36.798491 -122.275087) (xy 36.775849 -122.225505) (xy 36.760493 -122.173206)
			(xy 36.752736 -122.119254) (xy 20.194338 -122.119254) (xy 20.201449 -122.168472) (xy 20.201449 -122.223214)
			(xy 20.19362 -122.277393) (xy 20.178123 -122.329895) (xy 20.155277 -122.379642) (xy 20.125551 -122.425609)
			(xy 20.10791 -122.446542) (xy 20.107656 -122.446796) (xy 20.10206 -122.453876) (xy 20.09582 -122.470798)
			(xy 20.095464 -122.479816) (xy 20.095464 -122.546872) (xy 20.095842 -122.555887) (xy 20.102076 -122.572803)
			(xy 20.107656 -122.579892) (xy 20.10791 -122.579892) (xy 20.10791 -122.580146) (xy 20.125539 -122.601086)
			(xy 20.155252 -122.647057) (xy 20.17809 -122.696802) (xy 20.193583 -122.749301) (xy 20.201414 -122.803475)
			(xy 20.20189 -122.830844) (xy 20.201404 -122.858095) (xy 20.193648 -122.912043) (xy 20.178293 -122.964338)
			(xy 20.155651 -123.013915) (xy 20.126185 -123.059765) (xy 20.090494 -123.100956) (xy 20.049303 -123.136647)
			(xy 20.003453 -123.166113) (xy 19.953876 -123.188755) (xy 19.901581 -123.20411) (xy 19.847633 -123.211866)
			(xy 19.793131 -123.211866) (xy 19.739183 -123.20411) (xy 19.686888 -123.188755) (xy 19.637311 -123.166113)
			(xy 19.591461 -123.136647) (xy 19.55027 -123.100956) (xy 19.514579 -123.059765) (xy 19.485113 -123.013915)
			(xy 19.462471 -122.964338) (xy 19.447116 -122.912043) (xy 19.43936 -122.858095) (xy 19.438874 -122.830844)
			(xy 17.136919 -122.830844) (xy 17.139925 -122.838997) (xy 17.145508 -122.846084) (xy 17.145762 -122.846084)
			(xy 17.145762 -122.846338) (xy 17.16338 -122.867288) (xy 17.193096 -122.913255) (xy 17.215937 -122.962998)
			(xy 17.231433 -123.015495) (xy 17.239266 -123.069668) (xy 17.239742 -123.097036) (xy 17.239256 -123.124287)
			(xy 17.2315 -123.178235) (xy 17.216145 -123.23053) (xy 17.193503 -123.280107) (xy 17.164037 -123.325957)
			(xy 17.128346 -123.367148) (xy 17.087155 -123.402839) (xy 17.041305 -123.432305) (xy 16.991728 -123.454947)
			(xy 16.939433 -123.470302) (xy 16.885485 -123.478058) (xy 16.830983 -123.478058) (xy 16.777035 -123.470302)
			(xy 16.72474 -123.454947) (xy 16.675163 -123.432305) (xy 16.629313 -123.402839) (xy 16.588122 -123.367148)
			(xy 16.552431 -123.325957) (xy 16.522965 -123.280107) (xy 16.500323 -123.23053) (xy 16.484968 -123.178235)
			(xy 16.477212 -123.124287) (xy 16.476726 -123.097036) (xy 14.643843 -123.097036) (xy 14.656962 -123.139036)
			(xy 14.665678 -123.19616) (xy 14.666214 -123.225052) (xy 14.6657 -123.252303) (xy 14.65795 -123.306252)
			(xy 14.6426 -123.358549) (xy 14.619964 -123.408128) (xy 14.590501 -123.453981) (xy 14.554813 -123.495174)
			(xy 14.513625 -123.530869) (xy 14.467776 -123.560338) (xy 14.418199 -123.582981) (xy 14.365905 -123.598338)
			(xy 14.311957 -123.606096) (xy 14.284706 -123.60656) (xy 14.257335 -123.6061) (xy 14.203156 -123.598282)
			(xy 14.150652 -123.582792) (xy 14.100905 -123.559949) (xy 14.054939 -123.530222) (xy 14.034008 -123.51258)
			(xy 14.033754 -123.512326) (xy 14.026662 -123.506747) (xy 14.009749 -123.500498) (xy 14.000734 -123.500134)
			(xy 13.933678 -123.500134) (xy 13.924659 -123.500473) (xy 13.907742 -123.506732) (xy 13.900658 -123.512326)
			(xy 13.900404 -123.51258) (xy 13.879471 -123.530221) (xy 13.833503 -123.559945) (xy 13.783757 -123.582791)
			(xy 13.731255 -123.598287) (xy 13.677077 -123.606116) (xy 13.622335 -123.606116) (xy 13.568157 -123.598287)
			(xy 13.515655 -123.582791) (xy 13.465909 -123.559945) (xy 13.419941 -123.530221) (xy 13.399008 -123.51258)
			(xy 13.398754 -123.512326) (xy 13.391662 -123.506747) (xy 13.374749 -123.500498) (xy 13.365734 -123.500134)
			(xy 13.298678 -123.500134) (xy 13.289659 -123.500473) (xy 13.272742 -123.506732) (xy 13.265658 -123.512326)
			(xy 13.265658 -123.51258) (xy 13.265404 -123.51258) (xy 13.244479 -123.530228) (xy 13.198504 -123.559939)
			(xy 13.148755 -123.582773) (xy 13.096253 -123.598262) (xy 13.042076 -123.606088) (xy 13.014706 -123.60656)
			(xy 12.987675 -123.606107) (xy 12.934156 -123.598457) (xy 12.882255 -123.583325) (xy 12.833012 -123.561012)
			(xy 12.787414 -123.531968) (xy 12.746376 -123.496774) (xy 12.728194 -123.476766) (xy 12.72794 -123.476512)
			(xy 12.720488 -123.468874) (xy 12.70101 -123.460199) (xy 12.690348 -123.459748) (xy 12.602718 -123.45924)
			(xy 12.58316 -123.467876) (xy 12.575794 -123.476258) (xy 12.557643 -123.495991) (xy 12.516739 -123.530651)
			(xy 12.471381 -123.559237) (xy 12.422464 -123.581184) (xy 12.370954 -123.596059) (xy 12.317867 -123.603567)
			(xy 12.29106 -123.60402) (xy 12.263809 -123.60353) (xy 12.209861 -123.595774) (xy 12.157567 -123.580419)
			(xy 12.10799 -123.557778) (xy 12.06214 -123.528312) (xy 12.02095 -123.49262) (xy 11.985258 -123.45143)
			(xy 11.955792 -123.40558) (xy 11.933151 -123.356003) (xy 11.917796 -123.303709) (xy 11.91004 -123.249761)
			(xy 9.264859 -123.249761) (xy 9.229775 -123.271173) (xy 9.178446 -123.292985) (xy 9.124489 -123.307091)
			(xy 9.069052 -123.313191) (xy 9.013318 -123.311154) (xy 8.958475 -123.301024) (xy 8.905691 -123.283017)
			(xy 8.856091 -123.257516) (xy 8.810733 -123.225065) (xy 8.770584 -123.186356) (xy 8.736498 -123.142213)
			(xy 8.709202 -123.093578) (xy 8.689279 -123.041487) (xy 8.677153 -122.98705) (xy 8.673082 -122.931428)
			(xy 5.06984 -122.931428) (xy 5.06984 -123.947428) (xy 8.673082 -123.947428) (xy 8.677153 -123.891806)
			(xy 8.689279 -123.837369) (xy 8.709202 -123.785278) (xy 8.736498 -123.736643) (xy 8.770584 -123.6925)
			(xy 8.810733 -123.653791) (xy 8.856091 -123.62134) (xy 8.905691 -123.595839) (xy 8.958475 -123.577832)
			(xy 9.013318 -123.567702) (xy 9.069052 -123.565665) (xy 9.124489 -123.571765) (xy 9.178446 -123.585871)
			(xy 9.229775 -123.607683) (xy 9.277381 -123.636737) (xy 9.320249 -123.672412) (xy 9.357466 -123.713949)
			(xy 9.388239 -123.760462) (xy 9.411911 -123.810959) (xy 9.427979 -123.864366) (xy 9.4351 -123.912754)
			(xy 34.11063 -123.912754) (xy 34.11063 -123.858246) (xy 34.118387 -123.804294) (xy 34.133743 -123.751995)
			(xy 34.156385 -123.702413) (xy 34.185853 -123.656558) (xy 34.221546 -123.615363) (xy 34.262738 -123.579667)
			(xy 34.308592 -123.550196) (xy 34.358172 -123.527551) (xy 34.410471 -123.512192) (xy 34.464422 -123.504432)
			(xy 34.491676 -123.503944) (xy 34.506469 -123.50408) (xy 34.535967 -123.506368) (xy 34.550604 -123.508516)
			(xy 34.561579 -123.509632) (xy 34.582769 -123.503577) (xy 34.591498 -123.496832) (xy 34.650172 -123.446794)
			(xy 34.658207 -123.439233) (xy 34.667416 -123.419207) (xy 34.667952 -123.408186) (xy 34.667952 -123.103894)
			(xy 34.667433 -123.092872) (xy 34.658202 -123.072855) (xy 34.650172 -123.065286) (xy 34.591498 -123.015248)
			(xy 34.582794 -123.008451) (xy 34.561585 -123.002387) (xy 34.550604 -123.003564) (xy 34.535965 -123.005699)
			(xy 34.506469 -123.007991) (xy 34.491676 -123.008136) (xy 34.464428 -123.007592) (xy 34.410487 -122.999833)
			(xy 34.358199 -122.984477) (xy 34.308628 -122.961837) (xy 34.262784 -122.932372) (xy 34.2216 -122.896683)
			(xy 34.185914 -122.855496) (xy 34.156452 -122.809651) (xy 34.133814 -122.760079) (xy 34.118461 -122.70779)
			(xy 34.110706 -122.653848) (xy 34.110706 -122.599352) (xy 34.118461 -122.54541) (xy 34.133814 -122.493121)
			(xy 34.156452 -122.443549) (xy 34.185914 -122.397704) (xy 34.2216 -122.356517) (xy 34.262784 -122.320828)
			(xy 34.308628 -122.291363) (xy 34.358199 -122.268723) (xy 34.410487 -122.253367) (xy 34.464428 -122.245608)
			(xy 34.491676 -122.24512) (xy 34.517585 -122.245544) (xy 34.568923 -122.252578) (xy 34.618838 -122.266493)
			(xy 34.666412 -122.287032) (xy 34.71077 -122.313819) (xy 34.751096 -122.34636) (xy 34.786648 -122.384057)
			(xy 34.802064 -122.404886) (xy 34.807807 -122.412214) (xy 34.823308 -122.422501) (xy 34.83229 -122.424952)
			(xy 34.86277 -122.43181) (xy 34.872045 -122.433572) (xy 34.89071 -122.430822) (xy 34.899092 -122.426476)
			(xy 34.925079 -122.412221) (xy 34.979944 -122.389789) (xy 35.037245 -122.374622) (xy 35.096023 -122.366975)
			(xy 35.155297 -122.366975) (xy 35.214075 -122.374622) (xy 35.271376 -122.389789) (xy 35.326241 -122.412221)
			(xy 35.352228 -122.426476) (xy 35.360652 -122.430697) (xy 35.379273 -122.433446) (xy 35.38855 -122.43181)
			(xy 35.41903 -122.424952) (xy 35.428025 -122.422529) (xy 35.443529 -122.412233) (xy 35.449256 -122.404886)
			(xy 35.464671 -122.384055) (xy 35.500212 -122.346343) (xy 35.540533 -122.313792) (xy 35.584891 -122.287002)
			(xy 35.632469 -122.266467) (xy 35.68239 -122.252565) (xy 35.733734 -122.245552) (xy 35.759644 -122.24512)
			(xy 35.786895 -122.245553) (xy 35.840842 -122.253315) (xy 35.893135 -122.268675) (xy 35.942711 -122.29132)
			(xy 35.988559 -122.32079) (xy 36.029747 -122.356484) (xy 36.065436 -122.397676) (xy 36.094901 -122.443528)
			(xy 36.11754 -122.493106) (xy 36.132894 -122.545401) (xy 36.14065 -122.599349) (xy 36.14065 -122.653851)
			(xy 36.132894 -122.707799) (xy 36.11754 -122.760094) (xy 36.094901 -122.809672) (xy 36.065436 -122.855524)
			(xy 36.029747 -122.896716) (xy 35.988559 -122.93241) (xy 35.942711 -122.96188) (xy 35.893135 -122.984525)
			(xy 35.840842 -122.999885) (xy 35.786895 -123.007647) (xy 35.759644 -123.008136) (xy 35.744851 -123.007998)
			(xy 35.715353 -123.005711) (xy 35.700716 -123.003564) (xy 35.689741 -123.002464) (xy 35.668552 -123.008508)
			(xy 35.659822 -123.015248) (xy 35.601148 -123.065286) (xy 35.593125 -123.072858) (xy 35.583909 -123.092875)
			(xy 35.583368 -123.103894) (xy 35.583368 -123.408186) (xy 35.583924 -123.419202) (xy 35.593132 -123.439219)
			(xy 35.601148 -123.446794) (xy 35.659822 -123.496832) (xy 35.668521 -123.503638) (xy 35.689734 -123.509698)
			(xy 35.700716 -123.508516) (xy 35.715354 -123.506379) (xy 35.744851 -123.504088) (xy 35.759644 -123.503944)
			(xy 35.78689 -123.504529) (xy 35.840826 -123.51229) (xy 35.893109 -123.527647) (xy 35.942674 -123.550288)
			(xy 35.988513 -123.579751) (xy 36.029693 -123.615438) (xy 36.065375 -123.656622) (xy 36.094834 -123.702465)
			(xy 36.117469 -123.752033) (xy 36.13282 -123.804317) (xy 36.140574 -123.858254) (xy 36.140574 -123.912746)
			(xy 36.13282 -123.966683) (xy 36.117469 -124.018967) (xy 36.094834 -124.068535) (xy 36.065375 -124.114378)
			(xy 36.029693 -124.155562) (xy 35.988513 -124.191249) (xy 35.942674 -124.220712) (xy 35.893109 -124.243353)
			(xy 35.840826 -124.25871) (xy 35.78689 -124.266471) (xy 35.759644 -124.26696) (xy 35.733735 -124.266529)
			(xy 35.682397 -124.259498) (xy 35.632482 -124.245585) (xy 35.584908 -124.225047) (xy 35.54055 -124.198261)
			(xy 35.500224 -124.16572) (xy 35.464671 -124.128023) (xy 35.449256 -124.107194) (xy 35.44349 -124.099886)
			(xy 35.428006 -124.089586) (xy 35.41903 -124.087128) (xy 35.38855 -124.08027) (xy 35.379274 -124.078521)
			(xy 35.36061 -124.081263) (xy 35.352228 -124.085604) (xy 35.326241 -124.099859) (xy 35.271376 -124.122291)
			(xy 35.214075 -124.137458) (xy 35.155297 -124.145105) (xy 35.096023 -124.145105) (xy 35.037245 -124.137458)
			(xy 34.979944 -124.122291) (xy 34.925079 -124.099859) (xy 34.899092 -124.085604) (xy 34.890686 -124.081343)
			(xy 34.87205 -124.078619) (xy 34.86277 -124.08027) (xy 34.83229 -124.087128) (xy 34.8233 -124.089566)
			(xy 34.807793 -124.099851) (xy 34.802064 -124.107194) (xy 34.786631 -124.128011) (xy 34.751094 -124.165725)
			(xy 34.710776 -124.198277) (xy 34.666421 -124.225069) (xy 34.618846 -124.245607) (xy 34.568927 -124.259511)
			(xy 34.517585 -124.266527) (xy 34.491676 -124.26696) (xy 34.464422 -124.266568) (xy 34.410471 -124.258808)
			(xy 34.358172 -124.243449) (xy 34.308592 -124.220804) (xy 34.262738 -124.191333) (xy 34.221546 -124.155637)
			(xy 34.185853 -124.114442) (xy 34.156385 -124.068587) (xy 34.133743 -124.019005) (xy 34.118387 -123.966706)
			(xy 34.11063 -123.912754) (xy 9.4351 -123.912754) (xy 9.436099 -123.919542) (xy 9.436608 -123.947428)
			(xy 9.436099 -123.975314) (xy 9.427979 -124.03049) (xy 9.411911 -124.083897) (xy 9.388239 -124.134394)
			(xy 9.357466 -124.180907) (xy 9.320249 -124.222444) (xy 9.277381 -124.258119) (xy 9.229775 -124.287173)
			(xy 9.178446 -124.308985) (xy 9.124489 -124.323091) (xy 9.069052 -124.329191) (xy 9.013318 -124.327154)
			(xy 8.958475 -124.317024) (xy 8.905691 -124.299017) (xy 8.856091 -124.273516) (xy 8.810733 -124.241065)
			(xy 8.770584 -124.202356) (xy 8.736498 -124.158213) (xy 8.709202 -124.109578) (xy 8.689279 -124.057487)
			(xy 8.677153 -124.00305) (xy 8.673082 -123.947428) (xy 5.06984 -123.947428) (xy 5.06984 -124.963428)
			(xy 8.673082 -124.963428) (xy 8.677153 -124.907806) (xy 8.689279 -124.853369) (xy 8.709202 -124.801278)
			(xy 8.736498 -124.752643) (xy 8.770584 -124.7085) (xy 8.810733 -124.669791) (xy 8.856091 -124.63734)
			(xy 8.905691 -124.611839) (xy 8.958475 -124.593832) (xy 9.013318 -124.583702) (xy 9.069052 -124.581665)
			(xy 9.124489 -124.587765) (xy 9.178446 -124.601871) (xy 9.229775 -124.623683) (xy 9.277381 -124.652737)
			(xy 9.320249 -124.688412) (xy 9.357466 -124.729949) (xy 9.388239 -124.776462) (xy 9.411911 -124.826959)
			(xy 9.427979 -124.880366) (xy 9.436099 -124.935542) (xy 9.436608 -124.963428) (xy 9.436099 -124.991314)
			(xy 9.435493 -124.995432) (xy 10.780774 -124.995432) (xy 10.784845 -124.93981) (xy 10.796971 -124.885373)
			(xy 10.816894 -124.833282) (xy 10.84419 -124.784647) (xy 10.878276 -124.740504) (xy 10.918425 -124.701795)
			(xy 10.963783 -124.669344) (xy 11.013383 -124.643843) (xy 11.066167 -124.625836) (xy 11.12101 -124.615706)
			(xy 11.176744 -124.613669) (xy 11.232181 -124.619769) (xy 11.286138 -124.633875) (xy 11.337467 -124.655687)
			(xy 11.385073 -124.684741) (xy 11.427941 -124.720416) (xy 11.465158 -124.761953) (xy 11.495931 -124.808466)
			(xy 11.519603 -124.858963) (xy 11.535671 -124.91237) (xy 11.543791 -124.967546) (xy 11.5443 -124.995432)
			(xy 11.543791 -125.023318) (xy 11.535671 -125.078494) (xy 11.519603 -125.131901) (xy 11.495931 -125.182398)
			(xy 11.465158 -125.228911) (xy 11.427941 -125.270448) (xy 11.385073 -125.306123) (xy 11.337467 -125.335177)
			(xy 11.286138 -125.356989) (xy 11.232181 -125.371095) (xy 11.176744 -125.377195) (xy 11.12101 -125.375158)
			(xy 11.066167 -125.365028) (xy 11.013383 -125.347021) (xy 10.963783 -125.32152) (xy 10.918425 -125.289069)
			(xy 10.878276 -125.25036) (xy 10.84419 -125.206217) (xy 10.816894 -125.157582) (xy 10.796971 -125.105491)
			(xy 10.784845 -125.051054) (xy 10.780774 -124.995432) (xy 9.435493 -124.995432) (xy 9.427979 -125.04649)
			(xy 9.411911 -125.099897) (xy 9.388239 -125.150394) (xy 9.357466 -125.196907) (xy 9.320249 -125.238444)
			(xy 9.277381 -125.274119) (xy 9.229775 -125.303173) (xy 9.178446 -125.324985) (xy 9.124489 -125.339091)
			(xy 9.069052 -125.345191) (xy 9.013318 -125.343154) (xy 8.958475 -125.333024) (xy 8.905691 -125.315017)
			(xy 8.856091 -125.289516) (xy 8.810733 -125.257065) (xy 8.770584 -125.218356) (xy 8.736498 -125.174213)
			(xy 8.709202 -125.125578) (xy 8.689279 -125.073487) (xy 8.677153 -125.01905) (xy 8.673082 -124.963428)
			(xy 5.06984 -124.963428) (xy 5.06984 -125.403356) (xy 15.544292 -125.403356) (xy 15.544793 -125.375987)
			(xy 15.552603 -125.32181) (xy 15.568084 -125.269307) (xy 15.590918 -125.219559) (xy 15.620634 -125.173591)
			(xy 15.638272 -125.152658) (xy 15.638526 -125.152404) (xy 15.64412 -125.145323) (xy 15.650361 -125.128402)
			(xy 15.650718 -125.119384) (xy 15.650718 -125.052328) (xy 15.650344 -125.043313) (xy 15.644108 -125.026396)
			(xy 15.638526 -125.019308) (xy 15.638272 -125.019308) (xy 15.638272 -125.019054) (xy 15.62064 -124.998116)
			(xy 15.590928 -124.952144) (xy 15.568091 -124.902398) (xy 15.552599 -124.849899) (xy 15.544768 -124.795725)
			(xy 15.544292 -124.768356) (xy 15.544778 -124.741105) (xy 15.552534 -124.687157) (xy 15.567889 -124.634862)
			(xy 15.590531 -124.585285) (xy 15.619997 -124.539435) (xy 15.655688 -124.498244) (xy 15.696879 -124.462553)
			(xy 15.742729 -124.433087) (xy 15.792306 -124.410445) (xy 15.844601 -124.39509) (xy 15.898549 -124.387334)
			(xy 15.953051 -124.387334) (xy 16.006999 -124.39509) (xy 16.059294 -124.410445) (xy 16.108871 -124.433087)
			(xy 16.154721 -124.462553) (xy 16.195912 -124.498244) (xy 16.231603 -124.539435) (xy 16.261069 -124.585285)
			(xy 16.283711 -124.634862) (xy 16.299066 -124.687157) (xy 16.306822 -124.741105) (xy 16.307308 -124.768356)
			(xy 16.306814 -124.795725) (xy 16.299003 -124.849903) (xy 16.28352 -124.902406) (xy 16.260685 -124.952153)
			(xy 16.230966 -124.998121) (xy 16.213328 -125.019054) (xy 16.213074 -125.019308) (xy 16.207475 -125.026386)
			(xy 16.201237 -125.043309) (xy 16.200882 -125.052328) (xy 16.200882 -125.119384) (xy 16.201251 -125.1284)
			(xy 16.207491 -125.145316) (xy 16.213074 -125.152404) (xy 16.213328 -125.152404) (xy 16.213328 -125.152658)
			(xy 16.230965 -125.173591) (xy 16.260676 -125.219564) (xy 16.283512 -125.269312) (xy 16.299004 -125.321812)
			(xy 16.306833 -125.375987) (xy 16.307308 -125.403356) (xy 16.306822 -125.430607) (xy 16.299066 -125.484555)
			(xy 16.283711 -125.53685) (xy 16.261069 -125.586427) (xy 16.231603 -125.632277) (xy 16.195912 -125.673468)
			(xy 16.154721 -125.709159) (xy 16.108871 -125.738625) (xy 16.059294 -125.761267) (xy 16.006999 -125.776622)
			(xy 15.953051 -125.784378) (xy 15.898549 -125.784378) (xy 15.844601 -125.776622) (xy 15.792306 -125.761267)
			(xy 15.742729 -125.738625) (xy 15.696879 -125.709159) (xy 15.655688 -125.673468) (xy 15.619997 -125.632277)
			(xy 15.590531 -125.586427) (xy 15.567889 -125.53685) (xy 15.552534 -125.484555) (xy 15.544778 -125.430607)
			(xy 15.544292 -125.403356) (xy 5.06984 -125.403356) (xy 5.06984 -125.979428) (xy 8.673082 -125.979428)
			(xy 8.677153 -125.923806) (xy 8.689279 -125.869369) (xy 8.709202 -125.817278) (xy 8.736498 -125.768643)
			(xy 8.770584 -125.7245) (xy 8.810733 -125.685791) (xy 8.856091 -125.65334) (xy 8.905691 -125.627839)
			(xy 8.958475 -125.609832) (xy 9.013318 -125.599702) (xy 9.069052 -125.597665) (xy 9.124489 -125.603765)
			(xy 9.178446 -125.617871) (xy 9.229775 -125.639683) (xy 9.277381 -125.668737) (xy 9.320249 -125.704412)
			(xy 9.357466 -125.745949) (xy 9.388239 -125.792462) (xy 9.411911 -125.842959) (xy 9.427979 -125.896366)
			(xy 9.436099 -125.951542) (xy 9.436608 -125.979428) (xy 9.436557 -125.982222) (xy 11.113006 -125.982222)
			(xy 11.117077 -125.9266) (xy 11.129203 -125.872163) (xy 11.149126 -125.820072) (xy 11.176422 -125.771437)
			(xy 11.210508 -125.727294) (xy 11.250657 -125.688585) (xy 11.296015 -125.656134) (xy 11.345615 -125.630633)
			(xy 11.398399 -125.612626) (xy 11.453242 -125.602496) (xy 11.508976 -125.600459) (xy 11.564413 -125.606559)
			(xy 11.61837 -125.620665) (xy 11.669699 -125.642477) (xy 11.717305 -125.671531) (xy 11.760173 -125.707206)
			(xy 11.79739 -125.748743) (xy 11.828163 -125.795256) (xy 11.851835 -125.845753) (xy 11.854225 -125.853698)
			(xy 16.484854 -125.853698) (xy 16.485306 -125.826327) (xy 16.493125 -125.772147) (xy 16.508617 -125.719643)
			(xy 16.531462 -125.669896) (xy 16.561191 -125.623931) (xy 16.578834 -125.603) (xy 16.579088 -125.602746)
			(xy 16.58466 -125.595649) (xy 16.590916 -125.57874) (xy 16.59128 -125.569726) (xy 16.59128 -125.50267)
			(xy 16.590942 -125.493651) (xy 16.584682 -125.476734) (xy 16.579088 -125.46965) (xy 16.578834 -125.46965)
			(xy 16.578834 -125.469396) (xy 16.561185 -125.448472) (xy 16.531473 -125.402497) (xy 16.508639 -125.352748)
			(xy 16.49315 -125.300245) (xy 16.485326 -125.246068) (xy 16.484854 -125.218698) (xy 16.48534 -125.191447)
			(xy 16.493096 -125.137499) (xy 16.508451 -125.085204) (xy 16.531093 -125.035627) (xy 16.560559 -124.989777)
			(xy 16.59625 -124.948586) (xy 16.637441 -124.912895) (xy 16.683291 -124.883429) (xy 16.732868 -124.860787)
			(xy 16.785163 -124.845432) (xy 16.839111 -124.837676) (xy 16.893613 -124.837676) (xy 16.947561 -124.845432)
			(xy 16.999856 -124.860787) (xy 17.049433 -124.883429) (xy 17.095283 -124.912895) (xy 17.136474 -124.948586)
			(xy 17.172165 -124.989777) (xy 17.201631 -125.035627) (xy 17.224273 -125.085204) (xy 17.239628 -125.137499)
			(xy 17.247384 -125.191447) (xy 17.24787 -125.218698) (xy 17.24741 -125.246069) (xy 17.239592 -125.300248)
			(xy 17.224102 -125.352752) (xy 17.201258 -125.402498) (xy 17.171532 -125.448465) (xy 17.15389 -125.469396)
			(xy 17.153636 -125.46965) (xy 17.148057 -125.476741) (xy 17.141807 -125.493655) (xy 17.141444 -125.50267)
			(xy 17.141444 -125.569726) (xy 17.141779 -125.578745) (xy 17.148041 -125.595663) (xy 17.153636 -125.602746)
			(xy 17.15389 -125.602746) (xy 17.15389 -125.603) (xy 17.171541 -125.623923) (xy 17.201251 -125.669898)
			(xy 17.224085 -125.719648) (xy 17.239573 -125.772151) (xy 17.247398 -125.826328) (xy 17.24787 -125.853698)
			(xy 17.247384 -125.880949) (xy 17.239628 -125.934897) (xy 17.224273 -125.987192) (xy 17.201631 -126.036769)
			(xy 17.172165 -126.082619) (xy 17.136474 -126.12381) (xy 17.095283 -126.159501) (xy 17.049433 -126.188967)
			(xy 16.999856 -126.211609) (xy 16.947561 -126.226964) (xy 16.893613 -126.23472) (xy 16.839111 -126.23472)
			(xy 16.785163 -126.226964) (xy 16.732868 -126.211609) (xy 16.683291 -126.188967) (xy 16.637441 -126.159501)
			(xy 16.59625 -126.12381) (xy 16.560559 -126.082619) (xy 16.531093 -126.036769) (xy 16.508451 -125.987192)
			(xy 16.493096 -125.934897) (xy 16.48534 -125.880949) (xy 16.484854 -125.853698) (xy 11.854225 -125.853698)
			(xy 11.867903 -125.89916) (xy 11.876023 -125.954336) (xy 11.876532 -125.982222) (xy 11.876023 -126.010108)
			(xy 11.867903 -126.065284) (xy 11.851835 -126.118691) (xy 11.828163 -126.169188) (xy 11.79739 -126.215701)
			(xy 11.760173 -126.257238) (xy 11.717305 -126.292913) (xy 11.669699 -126.321967) (xy 11.61837 -126.343779)
			(xy 11.564413 -126.357885) (xy 11.508976 -126.363985) (xy 11.453242 -126.361948) (xy 11.398399 -126.351818)
			(xy 11.345615 -126.333811) (xy 11.296015 -126.30831) (xy 11.250657 -126.275859) (xy 11.210508 -126.23715)
			(xy 11.176422 -126.193007) (xy 11.149126 -126.144372) (xy 11.129203 -126.092281) (xy 11.117077 -126.037844)
			(xy 11.113006 -125.982222) (xy 9.436557 -125.982222) (xy 9.436099 -126.007314) (xy 9.427979 -126.06249)
			(xy 9.411911 -126.115897) (xy 9.388239 -126.166394) (xy 9.357466 -126.212907) (xy 9.320249 -126.254444)
			(xy 9.277381 -126.290119) (xy 9.229775 -126.319173) (xy 9.178446 -126.340985) (xy 9.124489 -126.355091)
			(xy 9.069052 -126.361191) (xy 9.013318 -126.359154) (xy 8.958475 -126.349024) (xy 8.905691 -126.331017)
			(xy 8.856091 -126.305516) (xy 8.810733 -126.273065) (xy 8.770584 -126.234356) (xy 8.736498 -126.190213)
			(xy 8.709202 -126.141578) (xy 8.689279 -126.089487) (xy 8.677153 -126.03505) (xy 8.673082 -125.979428)
			(xy 5.06984 -125.979428) (xy 5.06984 -126.530354) (xy 17.769586 -126.530354) (xy 17.770111 -126.501437)
			(xy 17.778834 -126.444265) (xy 17.796088 -126.389065) (xy 17.821479 -126.337102) (xy 17.854423 -126.289568)
			(xy 17.894166 -126.247553) (xy 17.916652 -126.229364) (xy 17.925474 -126.221772) (xy 17.935648 -126.200859)
			(xy 17.93621 -126.189232) (xy 17.93621 -126.109476) (xy 17.935667 -126.097845) (xy 17.92548 -126.076936)
			(xy 17.916652 -126.069344) (xy 17.89418 -126.05114) (xy 17.854446 -126.009122) (xy 17.821507 -125.961589)
			(xy 17.796117 -125.90963) (xy 17.778858 -125.854436) (xy 17.770124 -125.797269) (xy 17.769586 -125.768354)
			(xy 17.770035 -125.741102) (xy 17.777798 -125.687153) (xy 17.793158 -125.634858) (xy 17.815804 -125.585281)
			(xy 17.845275 -125.539431) (xy 17.88097 -125.498242) (xy 17.922163 -125.462551) (xy 17.968016 -125.433085)
			(xy 18.017596 -125.410444) (xy 18.069892 -125.395089) (xy 18.123842 -125.387332) (xy 18.151094 -125.386846)
			(xy 18.178465 -125.387304) (xy 18.232645 -125.395122) (xy 18.285148 -125.410613) (xy 18.334895 -125.433456)
			(xy 18.380861 -125.463183) (xy 18.401792 -125.480826) (xy 18.402046 -125.48108) (xy 18.409137 -125.486659)
			(xy 18.426051 -125.492908) (xy 18.435066 -125.493272) (xy 18.502122 -125.493272) (xy 18.511141 -125.492932)
			(xy 18.528058 -125.486673) (xy 18.535142 -125.48108) (xy 18.535142 -125.480826) (xy 18.535396 -125.480826)
			(xy 18.556322 -125.463179) (xy 18.602296 -125.433468) (xy 18.652045 -125.410633) (xy 18.704547 -125.395144)
			(xy 18.758724 -125.387318) (xy 18.786094 -125.386846) (xy 18.813343 -125.387383) (xy 18.867287 -125.395138)
			(xy 18.919577 -125.41049) (xy 18.969152 -125.433127) (xy 19.015 -125.462588) (xy 19.056189 -125.498274)
			(xy 19.091881 -125.539458) (xy 19.121348 -125.585303) (xy 19.143992 -125.634874) (xy 19.159351 -125.687163)
			(xy 19.167113 -125.741105) (xy 19.167602 -125.768354) (xy 19.16705 -125.79727) (xy 19.158328 -125.854439)
			(xy 19.141076 -125.909637) (xy 19.115691 -125.961599) (xy 19.082754 -126.009134) (xy 19.043019 -126.051153)
			(xy 19.020536 -126.069344) (xy 19.011708 -126.076931) (xy 19.001538 -126.097847) (xy 19.000978 -126.109476)
			(xy 19.000978 -126.189232) (xy 19.001521 -126.200863) (xy 19.011708 -126.221772) (xy 19.020536 -126.229364)
			(xy 19.04301 -126.247566) (xy 19.082744 -126.289585) (xy 19.115683 -126.337118) (xy 19.141073 -126.389077)
			(xy 19.158332 -126.444272) (xy 19.167065 -126.501439) (xy 19.167602 -126.530354) (xy 19.167102 -126.557606)
			(xy 19.159351 -126.611556) (xy 19.147251 -126.652782) (xy 19.438874 -126.652782) (xy 19.439311 -126.625411)
			(xy 19.447133 -126.571229) (xy 19.462628 -126.518725) (xy 19.485477 -126.468979) (xy 19.515209 -126.423014)
			(xy 19.532854 -126.402084) (xy 19.533108 -126.40183) (xy 19.538689 -126.39474) (xy 19.544939 -126.377826)
			(xy 19.5453 -126.36881) (xy 19.5453 -126.301754) (xy 19.544917 -126.29274) (xy 19.538687 -126.275823)
			(xy 19.533108 -126.268734) (xy 19.532854 -126.268734) (xy 19.532854 -126.26848) (xy 19.515195 -126.247562)
			(xy 19.485468 -126.201592) (xy 19.462622 -126.151844) (xy 19.447126 -126.099339) (xy 19.439299 -126.045158)
			(xy 19.439301 -125.990415) (xy 19.447132 -125.936234) (xy 19.462632 -125.883731) (xy 19.485481 -125.833984)
			(xy 19.515211 -125.788016) (xy 19.532854 -125.767084) (xy 19.533108 -125.76683) (xy 19.538689 -125.75974)
			(xy 19.544939 -125.742826) (xy 19.5453 -125.73381) (xy 19.5453 -125.666754) (xy 19.544917 -125.65774)
			(xy 19.538687 -125.640823) (xy 19.533108 -125.633734) (xy 19.532854 -125.633734) (xy 19.532854 -125.63348)
			(xy 19.515195 -125.612562) (xy 19.485468 -125.566592) (xy 19.462622 -125.516844) (xy 19.447126 -125.464339)
			(xy 19.439299 -125.410158) (xy 19.439301 -125.355415) (xy 19.447132 -125.301234) (xy 19.462632 -125.248731)
			(xy 19.485481 -125.198984) (xy 19.515211 -125.153016) (xy 19.532854 -125.132084) (xy 19.533108 -125.13183)
			(xy 19.538689 -125.12474) (xy 19.544939 -125.107826) (xy 19.5453 -125.09881) (xy 19.5453 -125.031754)
			(xy 19.544917 -125.02274) (xy 19.538687 -125.005823) (xy 19.533108 -124.998734) (xy 19.532854 -124.998734)
			(xy 19.532854 -124.99848) (xy 19.515247 -124.977522) (xy 19.485529 -124.931557) (xy 19.462686 -124.881816)
			(xy 19.447187 -124.829321) (xy 19.439352 -124.77515) (xy 19.438874 -124.747782) (xy 19.43936 -124.720531)
			(xy 19.447116 -124.666583) (xy 19.462471 -124.614288) (xy 19.485113 -124.564711) (xy 19.514579 -124.518861)
			(xy 19.55027 -124.47767) (xy 19.591461 -124.441979) (xy 19.637311 -124.412513) (xy 19.686888 -124.389871)
			(xy 19.739183 -124.374516) (xy 19.793131 -124.36676) (xy 19.847633 -124.36676) (xy 19.901581 -124.374516)
			(xy 19.953876 -124.389871) (xy 20.003453 -124.412513) (xy 20.049303 -124.441979) (xy 20.090494 -124.47767)
			(xy 20.126185 -124.518861) (xy 20.155651 -124.564711) (xy 20.178293 -124.614288) (xy 20.193648 -124.666583)
			(xy 20.201404 -124.720531) (xy 20.20189 -124.747782) (xy 20.201416 -124.775152) (xy 20.1936 -124.829331)
			(xy 20.178113 -124.881834) (xy 20.155273 -124.931581) (xy 20.12555 -124.977548) (xy 20.10791 -124.99848)
			(xy 20.107656 -124.998734) (xy 20.102086 -125.005831) (xy 20.09583 -125.02274) (xy 20.095464 -125.031754)
			(xy 20.095464 -125.09881) (xy 20.095824 -125.107826) (xy 20.10207 -125.124743) (xy 20.107656 -125.13183)
			(xy 20.10791 -125.13183) (xy 20.10791 -125.132084) (xy 20.125532 -125.153032) (xy 20.155254 -125.198998)
			(xy 20.178098 -125.248742) (xy 20.193594 -125.301241) (xy 20.201424 -125.355417) (xy 20.201426 -125.410156)
			(xy 20.1936 -125.464332) (xy 20.178108 -125.516833) (xy 20.155267 -125.566578) (xy 20.125548 -125.612547)
			(xy 20.10791 -125.63348) (xy 20.107656 -125.633734) (xy 20.102086 -125.640831) (xy 20.09583 -125.65774)
			(xy 20.095464 -125.666754) (xy 20.095464 -125.719454) (xy 36.752732 -125.719454) (xy 36.752732 -125.664946)
			(xy 36.760489 -125.610993) (xy 36.775845 -125.558694) (xy 36.798488 -125.509111) (xy 36.827956 -125.463256)
			(xy 36.86365 -125.422062) (xy 36.904843 -125.386366) (xy 36.950697 -125.356895) (xy 37.000279 -125.334251)
			(xy 37.052578 -125.318892) (xy 37.10653 -125.311133) (xy 37.133784 -125.310646) (xy 37.148577 -125.310781)
			(xy 37.178075 -125.31307) (xy 37.192712 -125.315218) (xy 37.203687 -125.316339) (xy 37.224878 -125.310281)
			(xy 37.233606 -125.303534) (xy 37.29228 -125.253496) (xy 37.300315 -125.245936) (xy 37.309524 -125.225909)
			(xy 37.31006 -125.214888) (xy 37.31006 -124.910596) (xy 37.309537 -124.899575) (xy 37.300308 -124.879558)
			(xy 37.29228 -124.871988) (xy 37.233606 -124.82195) (xy 37.224899 -124.815157) (xy 37.203692 -124.809091)
			(xy 37.192712 -124.810266) (xy 37.178073 -124.8124) (xy 37.148577 -124.814693) (xy 37.133784 -124.814838)
			(xy 37.106536 -124.814291) (xy 37.052594 -124.806533) (xy 37.000305 -124.791178) (xy 36.950734 -124.768537)
			(xy 36.904889 -124.739073) (xy 36.863704 -124.703384) (xy 36.828017 -124.662198) (xy 36.798555 -124.616352)
			(xy 36.775917 -124.56678) (xy 36.760564 -124.51449) (xy 36.752808 -124.460548) (xy 36.752808 -124.406052)
			(xy 36.760564 -124.35211) (xy 36.775917 -124.29982) (xy 36.798555 -124.250248) (xy 36.828017 -124.204402)
			(xy 36.863704 -124.163216) (xy 36.904889 -124.127527) (xy 36.950734 -124.098063) (xy 37.000305 -124.075422)
			(xy 37.052594 -124.060067) (xy 37.106536 -124.052309) (xy 37.133784 -124.051822) (xy 37.159693 -124.052239)
			(xy 37.211032 -124.059274) (xy 37.260947 -124.07319) (xy 37.308521 -124.093731) (xy 37.352878 -124.120518)
			(xy 37.393204 -124.15306) (xy 37.428757 -124.190759) (xy 37.444172 -124.211588) (xy 37.449912 -124.218919)
			(xy 37.465415 -124.229204) (xy 37.474398 -124.231654) (xy 37.504878 -124.238512) (xy 37.514152 -124.240278)
			(xy 37.532818 -124.237526) (xy 37.5412 -124.233178) (xy 37.567177 -124.218884) (xy 37.622028 -124.196373)
			(xy 37.679331 -124.181147) (xy 37.738122 -124.17346) (xy 37.767768 -124.17298) (xy 37.797411 -124.17348)
			(xy 37.856193 -124.1812) (xy 37.913491 -124.196426) (xy 37.968351 -124.218904) (xy 37.994336 -124.233178)
			(xy 38.002758 -124.237403) (xy 38.02138 -124.24015) (xy 38.030658 -124.238512) (xy 38.061138 -124.231654)
			(xy 38.070133 -124.229233) (xy 38.085638 -124.218936) (xy 38.091364 -124.211588) (xy 38.106774 -124.190754)
			(xy 38.142316 -124.153042) (xy 38.182638 -124.120491) (xy 38.226997 -124.093701) (xy 38.274576 -124.073166)
			(xy 38.324497 -124.059265) (xy 38.375841 -124.052253) (xy 38.401752 -124.051822) (xy 38.429009 -124.052222)
			(xy 38.48297 -124.059974) (xy 38.535277 -124.075327) (xy 38.584868 -124.097968) (xy 38.63073 -124.127437)
			(xy 38.662481 -124.154946) (xy 44.669708 -124.154946) (xy 44.673779 -124.099324) (xy 44.685905 -124.044887)
			(xy 44.705828 -123.992796) (xy 44.733124 -123.944161) (xy 44.76721 -123.900018) (xy 44.807359 -123.861309)
			(xy 44.852717 -123.828858) (xy 44.902317 -123.803357) (xy 44.955101 -123.78535) (xy 45.009944 -123.77522)
			(xy 45.065678 -123.773183) (xy 45.121115 -123.779283) (xy 45.175072 -123.793389) (xy 45.226401 -123.815201)
			(xy 45.274007 -123.844255) (xy 45.31527 -123.878594) (xy 49.136806 -123.878594) (xy 49.140877 -123.822972)
			(xy 49.153003 -123.768535) (xy 49.172926 -123.716444) (xy 49.200222 -123.667809) (xy 49.234308 -123.623666)
			(xy 49.274457 -123.584957) (xy 49.319815 -123.552506) (xy 49.369415 -123.527005) (xy 49.422199 -123.508998)
			(xy 49.477042 -123.498868) (xy 49.532776 -123.496831) (xy 49.588213 -123.502931) (xy 49.64217 -123.517037)
			(xy 49.693499 -123.538849) (xy 49.741105 -123.567903) (xy 49.783973 -123.603578) (xy 49.82119 -123.645115)
			(xy 49.851963 -123.691628) (xy 49.875635 -123.742125) (xy 49.891703 -123.795532) (xy 49.899823 -123.850708)
			(xy 49.900332 -123.878594) (xy 49.899823 -123.90648) (xy 49.891703 -123.961656) (xy 49.875635 -124.015063)
			(xy 49.851963 -124.06556) (xy 49.82119 -124.112073) (xy 49.783973 -124.15361) (xy 49.741105 -124.189285)
			(xy 49.693499 -124.218339) (xy 49.64217 -124.240151) (xy 49.588213 -124.254257) (xy 49.532776 -124.260357)
			(xy 49.477042 -124.25832) (xy 49.422199 -124.24819) (xy 49.369415 -124.230183) (xy 49.319815 -124.204682)
			(xy 49.274457 -124.172231) (xy 49.234308 -124.133522) (xy 49.200222 -124.089379) (xy 49.172926 -124.040744)
			(xy 49.153003 -123.988653) (xy 49.140877 -123.934216) (xy 49.136806 -123.878594) (xy 45.31527 -123.878594)
			(xy 45.316875 -123.87993) (xy 45.354092 -123.921467) (xy 45.384865 -123.96798) (xy 45.408537 -124.018477)
			(xy 45.424605 -124.071884) (xy 45.432725 -124.12706) (xy 45.433234 -124.154946) (xy 45.432725 -124.182832)
			(xy 45.424605 -124.238008) (xy 45.408537 -124.291415) (xy 45.384865 -124.341912) (xy 45.354092 -124.388425)
			(xy 45.316875 -124.429962) (xy 45.274007 -124.465637) (xy 45.226401 -124.494691) (xy 45.175072 -124.516503)
			(xy 45.121115 -124.530609) (xy 45.065678 -124.536709) (xy 45.009944 -124.534672) (xy 44.955101 -124.524542)
			(xy 44.902317 -124.506535) (xy 44.852717 -124.481034) (xy 44.807359 -124.448583) (xy 44.76721 -124.409874)
			(xy 44.733124 -124.365731) (xy 44.705828 -124.317096) (xy 44.685905 -124.265005) (xy 44.673779 -124.210568)
			(xy 44.669708 -124.154946) (xy 38.662481 -124.154946) (xy 38.671932 -124.163134) (xy 38.707634 -124.204331)
			(xy 38.737109 -124.25019) (xy 38.759756 -124.299777) (xy 38.775116 -124.352083) (xy 38.782875 -124.406043)
			(xy 38.782875 -124.460557) (xy 38.775116 -124.514517) (xy 38.759756 -124.566822) (xy 38.737109 -124.61641)
			(xy 38.707634 -124.662269) (xy 38.671932 -124.703466) (xy 38.63073 -124.739163) (xy 38.584868 -124.768632)
			(xy 38.535277 -124.791273) (xy 38.48297 -124.806626) (xy 38.429009 -124.814378) (xy 38.401752 -124.814838)
			(xy 38.386959 -124.814699) (xy 38.357461 -124.812413) (xy 38.342824 -124.810266) (xy 38.331849 -124.80917)
			(xy 38.310661 -124.815212) (xy 38.30193 -124.82195) (xy 38.243256 -124.871988) (xy 38.235233 -124.87956)
			(xy 38.226016 -124.899577) (xy 38.225476 -124.910596) (xy 38.225476 -125.214888) (xy 38.226028 -125.225905)
			(xy 38.235238 -125.245921) (xy 38.243256 -125.253496) (xy 38.30193 -125.303534) (xy 38.310626 -125.310345)
			(xy 38.331842 -125.316401) (xy 38.342824 -125.315218) (xy 38.357462 -125.31308) (xy 38.386959 -125.31079)
			(xy 38.401752 -125.310646) (xy 38.429004 -125.311198) (xy 38.482953 -125.318948) (xy 38.535251 -125.334298)
			(xy 38.584831 -125.356935) (xy 38.630685 -125.386399) (xy 38.671878 -125.422088) (xy 38.707573 -125.463277)
			(xy 38.737041 -125.509127) (xy 38.759685 -125.558704) (xy 38.775041 -125.611) (xy 38.782799 -125.664948)
			(xy 38.782799 -125.719452) (xy 38.775041 -125.7734) (xy 38.759685 -125.825696) (xy 38.737041 -125.875273)
			(xy 38.707573 -125.921123) (xy 38.678177 -125.955044) (xy 44.669708 -125.955044) (xy 44.673779 -125.899422)
			(xy 44.685905 -125.844985) (xy 44.705828 -125.792894) (xy 44.733124 -125.744259) (xy 44.76721 -125.700116)
			(xy 44.807359 -125.661407) (xy 44.852717 -125.628956) (xy 44.902317 -125.603455) (xy 44.955101 -125.585448)
			(xy 45.009944 -125.575318) (xy 45.065678 -125.573281) (xy 45.121115 -125.579381) (xy 45.175072 -125.593487)
			(xy 45.226401 -125.615299) (xy 45.274007 -125.644353) (xy 45.316875 -125.680028) (xy 45.354092 -125.721565)
			(xy 45.384865 -125.768078) (xy 45.408537 -125.818575) (xy 45.424605 -125.871982) (xy 45.432725 -125.927158)
			(xy 45.433234 -125.955044) (xy 49.269902 -125.955044) (xy 49.273973 -125.899422) (xy 49.286099 -125.844985)
			(xy 49.306022 -125.792894) (xy 49.333318 -125.744259) (xy 49.367404 -125.700116) (xy 49.407553 -125.661407)
			(xy 49.452911 -125.628956) (xy 49.502511 -125.603455) (xy 49.555295 -125.585448) (xy 49.610138 -125.575318)
			(xy 49.665872 -125.573281) (xy 49.721309 -125.579381) (xy 49.775266 -125.593487) (xy 49.826595 -125.615299)
			(xy 49.874201 -125.644353) (xy 49.917069 -125.680028) (xy 49.954286 -125.721565) (xy 49.985059 -125.768078)
			(xy 50.008731 -125.818575) (xy 50.024799 -125.871982) (xy 50.032919 -125.927158) (xy 50.033428 -125.955044)
			(xy 50.032919 -125.98293) (xy 50.024799 -126.038106) (xy 50.008731 -126.091513) (xy 49.985059 -126.14201)
			(xy 49.954286 -126.188523) (xy 49.917069 -126.23006) (xy 49.874201 -126.265735) (xy 49.826595 -126.294789)
			(xy 49.775266 -126.316601) (xy 49.721309 -126.330707) (xy 49.665872 -126.336807) (xy 49.610138 -126.33477)
			(xy 49.555295 -126.32464) (xy 49.502511 -126.306633) (xy 49.452911 -126.281132) (xy 49.407553 -126.248681)
			(xy 49.367404 -126.209972) (xy 49.333318 -126.165829) (xy 49.306022 -126.117194) (xy 49.286099 -126.065103)
			(xy 49.273973 -126.010666) (xy 49.269902 -125.955044) (xy 45.433234 -125.955044) (xy 45.432725 -125.98293)
			(xy 45.424605 -126.038106) (xy 45.408537 -126.091513) (xy 45.384865 -126.14201) (xy 45.354092 -126.188523)
			(xy 45.316875 -126.23006) (xy 45.274007 -126.265735) (xy 45.226401 -126.294789) (xy 45.175072 -126.316601)
			(xy 45.121115 -126.330707) (xy 45.065678 -126.336807) (xy 45.009944 -126.33477) (xy 44.955101 -126.32464)
			(xy 44.902317 -126.306633) (xy 44.852717 -126.281132) (xy 44.807359 -126.248681) (xy 44.76721 -126.209972)
			(xy 44.733124 -126.165829) (xy 44.705828 -126.117194) (xy 44.685905 -126.065103) (xy 44.673779 -126.010666)
			(xy 44.669708 -125.955044) (xy 38.678177 -125.955044) (xy 38.671878 -125.962312) (xy 38.630685 -125.998001)
			(xy 38.584831 -126.027465) (xy 38.535251 -126.050102) (xy 38.482953 -126.065452) (xy 38.429004 -126.073202)
			(xy 38.401752 -126.073662) (xy 38.375843 -126.073225) (xy 38.324505 -126.066194) (xy 38.27459 -126.052282)
			(xy 38.227016 -126.031745) (xy 38.182659 -126.004961) (xy 38.142332 -125.972421) (xy 38.10678 -125.934724)
			(xy 38.091364 -125.913896) (xy 38.085595 -125.906591) (xy 38.070114 -125.89629) (xy 38.061138 -125.89383)
			(xy 38.030658 -125.886972) (xy 38.021381 -125.885227) (xy 38.002718 -125.887966) (xy 37.994336 -125.892306)
			(xy 37.968372 -125.906623) (xy 37.913515 -125.929129) (xy 37.856209 -125.944349) (xy 37.797415 -125.952028)
			(xy 37.767768 -125.952504) (xy 37.738126 -125.951991) (xy 37.679344 -125.944275) (xy 37.622046 -125.929053)
			(xy 37.567185 -125.906578) (xy 37.5412 -125.892306) (xy 37.532792 -125.888049) (xy 37.514158 -125.885323)
			(xy 37.504878 -125.886972) (xy 37.474398 -125.89383) (xy 37.465396 -125.896229) (xy 37.449895 -125.906543)
			(xy 37.444172 -125.913896) (xy 37.428735 -125.93471) (xy 37.393198 -125.972423) (xy 37.352881 -126.004976)
			(xy 37.308527 -126.031769) (xy 37.260952 -126.052307) (xy 37.211035 -126.066212) (xy 37.159693 -126.073228)
			(xy 37.133784 -126.073662) (xy 37.10653 -126.073267) (xy 37.052578 -126.065508) (xy 37.000279 -126.050149)
			(xy 36.950697 -126.027505) (xy 36.904843 -125.998034) (xy 36.86365 -125.962338) (xy 36.827956 -125.921144)
			(xy 36.798488 -125.875289) (xy 36.775845 -125.825706) (xy 36.760489 -125.773407) (xy 36.752732 -125.719454)
			(xy 20.095464 -125.719454) (xy 20.095464 -125.73381) (xy 20.095824 -125.742826) (xy 20.10207 -125.759743)
			(xy 20.107656 -125.76683) (xy 20.10791 -125.76683) (xy 20.10791 -125.767084) (xy 20.125532 -125.788032)
			(xy 20.155254 -125.833998) (xy 20.178098 -125.883742) (xy 20.193594 -125.936241) (xy 20.201424 -125.990417)
			(xy 20.201426 -126.045156) (xy 20.1936 -126.099332) (xy 20.178108 -126.151833) (xy 20.155267 -126.201578)
			(xy 20.125548 -126.247547) (xy 20.10791 -126.26848) (xy 20.107656 -126.268734) (xy 20.102086 -126.275831)
			(xy 20.09583 -126.29274) (xy 20.095464 -126.301754) (xy 20.095464 -126.36881) (xy 20.095824 -126.377826)
			(xy 20.10207 -126.394743) (xy 20.107656 -126.40183) (xy 20.10791 -126.40183) (xy 20.10791 -126.402084)
			(xy 20.125557 -126.42301) (xy 20.155267 -126.468985) (xy 20.178101 -126.518734) (xy 20.193591 -126.571236)
			(xy 20.201417 -126.625412) (xy 20.20189 -126.652782) (xy 20.201404 -126.680033) (xy 20.193648 -126.733981)
			(xy 20.178293 -126.786276) (xy 20.155651 -126.835853) (xy 20.126185 -126.881703) (xy 20.090494 -126.922894)
			(xy 20.049303 -126.958585) (xy 20.003453 -126.988051) (xy 19.953876 -127.010693) (xy 19.901581 -127.026048)
			(xy 19.847633 -127.033804) (xy 19.793131 -127.033804) (xy 19.739183 -127.026048) (xy 19.686888 -127.010693)
			(xy 19.637311 -126.988051) (xy 19.591461 -126.958585) (xy 19.55027 -126.922894) (xy 19.514579 -126.881703)
			(xy 19.485113 -126.835853) (xy 19.462471 -126.786276) (xy 19.447116 -126.733981) (xy 19.43936 -126.680033)
			(xy 19.438874 -126.652782) (xy 19.147251 -126.652782) (xy 19.144001 -126.663853) (xy 19.121363 -126.713434)
			(xy 19.091899 -126.759287) (xy 19.056209 -126.800481) (xy 19.01502 -126.836175) (xy 18.969169 -126.865644)
			(xy 18.919591 -126.888287) (xy 18.867295 -126.903643) (xy 18.813346 -126.911399) (xy 18.786094 -126.911862)
			(xy 18.758723 -126.911409) (xy 18.704543 -126.903589) (xy 18.65204 -126.888098) (xy 18.602293 -126.865253)
			(xy 18.556327 -126.835525) (xy 18.535396 -126.817882) (xy 18.535142 -126.817628) (xy 18.528054 -126.812044)
			(xy 18.511138 -126.805798) (xy 18.502122 -126.805436) (xy 18.435066 -126.805436) (xy 18.426047 -126.805769)
			(xy 18.409129 -126.812032) (xy 18.402046 -126.817628) (xy 18.402046 -126.817882) (xy 18.401792 -126.817882)
			(xy 18.380871 -126.835536) (xy 18.334896 -126.865246) (xy 18.285145 -126.888079) (xy 18.232642 -126.903567)
			(xy 18.178464 -126.911391) (xy 18.151094 -126.911862) (xy 18.123839 -126.91145) (xy 18.069884 -126.903691)
			(xy 18.017582 -126.888332) (xy 17.967999 -126.865685) (xy 17.922144 -126.836213) (xy 17.88095 -126.800513)
			(xy 17.845256 -126.759315) (xy 17.81579 -126.713455) (xy 17.79315 -126.663869) (xy 17.777798 -126.611565)
			(xy 17.770046 -126.557609) (xy 17.769586 -126.530354) (xy 5.06984 -126.530354) (xy 5.06984 -126.995428)
			(xy 8.673082 -126.995428) (xy 8.677153 -126.939806) (xy 8.689279 -126.885369) (xy 8.709202 -126.833278)
			(xy 8.736498 -126.784643) (xy 8.770584 -126.7405) (xy 8.810733 -126.701791) (xy 8.856091 -126.66934)
			(xy 8.905691 -126.643839) (xy 8.958475 -126.625832) (xy 9.013318 -126.615702) (xy 9.069052 -126.613665)
			(xy 9.124489 -126.619765) (xy 9.178446 -126.633871) (xy 9.229775 -126.655683) (xy 9.277381 -126.684737)
			(xy 9.320249 -126.720412) (xy 9.357466 -126.761949) (xy 9.388239 -126.808462) (xy 9.411911 -126.858959)
			(xy 9.427979 -126.912366) (xy 9.436099 -126.967542) (xy 9.436608 -126.995428) (xy 9.436099 -127.023314)
			(xy 9.431979 -127.051308) (xy 10.744198 -127.051308) (xy 10.748269 -126.995686) (xy 10.760395 -126.941249)
			(xy 10.780318 -126.889158) (xy 10.807614 -126.840523) (xy 10.8417 -126.79638) (xy 10.881849 -126.757671)
			(xy 10.927207 -126.72522) (xy 10.976807 -126.699719) (xy 11.029591 -126.681712) (xy 11.084434 -126.671582)
			(xy 11.140168 -126.669545) (xy 11.195605 -126.675645) (xy 11.249562 -126.689751) (xy 11.300891 -126.711563)
			(xy 11.348497 -126.740617) (xy 11.391365 -126.776292) (xy 11.428582 -126.817829) (xy 11.459355 -126.864342)
			(xy 11.483027 -126.914839) (xy 11.499095 -126.968246) (xy 11.506983 -127.021844) (xy 14.774162 -127.021844)
			(xy 14.778233 -126.966222) (xy 14.790359 -126.911785) (xy 14.810282 -126.859694) (xy 14.837578 -126.811059)
			(xy 14.871664 -126.766916) (xy 14.911813 -126.728207) (xy 14.957171 -126.695756) (xy 15.006771 -126.670255)
			(xy 15.059555 -126.652248) (xy 15.114398 -126.642118) (xy 15.170132 -126.640081) (xy 15.225569 -126.646181)
			(xy 15.279526 -126.660287) (xy 15.330855 -126.682099) (xy 15.378461 -126.711153) (xy 15.421329 -126.746828)
			(xy 15.458546 -126.788365) (xy 15.489319 -126.834878) (xy 15.512991 -126.885375) (xy 15.529059 -126.938782)
			(xy 15.537179 -126.993958) (xy 15.537688 -127.021844) (xy 15.537179 -127.04973) (xy 15.529059 -127.104906)
			(xy 15.512991 -127.158313) (xy 15.489319 -127.20881) (xy 15.458546 -127.255323) (xy 15.421329 -127.29686)
			(xy 15.378461 -127.332535) (xy 15.330855 -127.361589) (xy 15.279526 -127.383401) (xy 15.225569 -127.397507)
			(xy 15.170132 -127.403607) (xy 15.114398 -127.40157) (xy 15.059555 -127.39144) (xy 15.006771 -127.373433)
			(xy 14.957171 -127.347932) (xy 14.911813 -127.315481) (xy 14.871664 -127.276772) (xy 14.837578 -127.232629)
			(xy 14.810282 -127.183994) (xy 14.790359 -127.131903) (xy 14.778233 -127.077466) (xy 14.774162 -127.021844)
			(xy 11.506983 -127.021844) (xy 11.507215 -127.023422) (xy 11.507724 -127.051308) (xy 11.507215 -127.079194)
			(xy 11.499095 -127.13437) (xy 11.483027 -127.187777) (xy 11.459355 -127.238274) (xy 11.428582 -127.284787)
			(xy 11.391365 -127.326324) (xy 11.348497 -127.361999) (xy 11.300891 -127.391053) (xy 11.249562 -127.412865)
			(xy 11.195605 -127.426971) (xy 11.140168 -127.433071) (xy 11.084434 -127.431034) (xy 11.029591 -127.420904)
			(xy 10.976807 -127.402897) (xy 10.927207 -127.377396) (xy 10.881849 -127.344945) (xy 10.8417 -127.306236)
			(xy 10.807614 -127.262093) (xy 10.780318 -127.213458) (xy 10.760395 -127.161367) (xy 10.748269 -127.10693)
			(xy 10.744198 -127.051308) (xy 9.431979 -127.051308) (xy 9.427979 -127.07849) (xy 9.411911 -127.131897)
			(xy 9.388239 -127.182394) (xy 9.357466 -127.228907) (xy 9.320249 -127.270444) (xy 9.277381 -127.306119)
			(xy 9.229775 -127.335173) (xy 9.178446 -127.356985) (xy 9.124489 -127.371091) (xy 9.069052 -127.377191)
			(xy 9.013318 -127.375154) (xy 8.958475 -127.365024) (xy 8.905691 -127.347017) (xy 8.856091 -127.321516)
			(xy 8.810733 -127.289065) (xy 8.770584 -127.250356) (xy 8.736498 -127.206213) (xy 8.709202 -127.157578)
			(xy 8.689279 -127.105487) (xy 8.677153 -127.05105) (xy 8.673082 -126.995428) (xy 5.06984 -126.995428)
			(xy 5.06984 -128.252803) (xy 9.728405 -128.252803) (xy 9.728405 -128.198297) (xy 9.736162 -128.144346)
			(xy 9.751519 -128.092048) (xy 9.774161 -128.042467) (xy 9.80363 -127.996614) (xy 9.839324 -127.955421)
			(xy 9.880517 -127.919727) (xy 9.926371 -127.89026) (xy 9.975951 -127.867617) (xy 10.02825 -127.852262)
			(xy 10.082201 -127.844505) (xy 10.109454 -127.844042) (xy 10.136824 -127.844525) (xy 10.191003 -127.852337)
			(xy 10.243506 -127.867822) (xy 10.293253 -127.89066) (xy 10.33922 -127.920382) (xy 10.360152 -127.938022)
			(xy 10.360406 -127.938276) (xy 10.36748 -127.94388) (xy 10.384407 -127.950114) (xy 10.393426 -127.950468)
			(xy 10.460482 -127.950468) (xy 10.469499 -127.950109) (xy 10.486416 -127.943863) (xy 10.493502 -127.938276)
			(xy 10.493502 -127.938022) (xy 10.493756 -127.938022) (xy 10.514689 -127.920381) (xy 10.560657 -127.890657)
			(xy 10.610403 -127.867811) (xy 10.662905 -127.852315) (xy 10.717083 -127.844486) (xy 10.771825 -127.844486)
			(xy 10.826003 -127.852315) (xy 10.878505 -127.867811) (xy 10.928251 -127.890657) (xy 10.974219 -127.920381)
			(xy 10.995152 -127.938022) (xy 10.995406 -127.938276) (xy 11.00248 -127.94388) (xy 11.019407 -127.950114)
			(xy 11.028426 -127.950468) (xy 11.095482 -127.950468) (xy 11.104499 -127.950109) (xy 11.121416 -127.943863)
			(xy 11.128502 -127.938276) (xy 11.128502 -127.938022) (xy 11.128756 -127.938022) (xy 11.149697 -127.920393)
			(xy 11.195667 -127.890679) (xy 11.245412 -127.867841) (xy 11.297911 -127.852348) (xy 11.352085 -127.844517)
			(xy 11.379454 -127.844042) (xy 11.406705 -127.844528) (xy 11.460652 -127.852285) (xy 11.512947 -127.867641)
			(xy 11.562523 -127.890282) (xy 11.608373 -127.919748) (xy 11.649563 -127.95544) (xy 11.685254 -127.99663)
			(xy 11.71472 -128.04248) (xy 11.737361 -128.092057) (xy 11.752716 -128.144352) (xy 11.760472 -128.198299)
			(xy 11.760472 -128.220802) (xy 14.744674 -128.220802) (xy 14.744674 -128.166298) (xy 14.75243 -128.11235)
			(xy 14.767786 -128.060055) (xy 14.790427 -128.010477) (xy 14.819894 -127.964626) (xy 14.855586 -127.923436)
			(xy 14.896776 -127.887744) (xy 14.942627 -127.858277) (xy 14.992205 -127.835636) (xy 15.0445 -127.82028)
			(xy 15.098448 -127.812524) (xy 15.1257 -127.812038) (xy 15.153071 -127.812495) (xy 15.207251 -127.820313)
			(xy 15.259754 -127.835804) (xy 15.309501 -127.858648) (xy 15.355467 -127.888375) (xy 15.376398 -127.906018)
			(xy 15.376652 -127.906272) (xy 15.383742 -127.911853) (xy 15.400656 -127.918101) (xy 15.409672 -127.918464)
			(xy 15.476728 -127.918464) (xy 15.485747 -127.918128) (xy 15.502664 -127.911867) (xy 15.509748 -127.906272)
			(xy 15.509748 -127.906018) (xy 15.510002 -127.906018) (xy 15.530935 -127.888377) (xy 15.576903 -127.858653)
			(xy 15.626649 -127.835807) (xy 15.679151 -127.820311) (xy 15.733329 -127.812482) (xy 15.788071 -127.812482)
			(xy 15.842249 -127.820311) (xy 15.894751 -127.835807) (xy 15.944497 -127.858653) (xy 15.990465 -127.888377)
			(xy 16.011398 -127.906018) (xy 16.011652 -127.906272) (xy 16.018742 -127.911853) (xy 16.035656 -127.918101)
			(xy 16.044672 -127.918464) (xy 16.111728 -127.918464) (xy 16.120747 -127.918128) (xy 16.137664 -127.911867)
			(xy 16.144748 -127.906272) (xy 16.144748 -127.906018) (xy 16.145002 -127.906018) (xy 16.165925 -127.888367)
			(xy 16.2119 -127.858657) (xy 16.26165 -127.835823) (xy 16.314153 -127.820334) (xy 16.36833 -127.81251)
			(xy 16.3957 -127.812038) (xy 16.422951 -127.812532) (xy 16.476898 -127.820288) (xy 16.529192 -127.835643)
			(xy 16.578769 -127.858284) (xy 16.624619 -127.88775) (xy 16.665809 -127.923441) (xy 16.69363 -127.955548)
			(xy 46.475396 -127.955548) (xy 46.475396 -127.95504) (xy 46.475943 -127.910144) (xy 46.484499 -127.82076)
			(xy 46.501537 -127.732599) (xy 46.526902 -127.646464) (xy 46.560363 -127.563139) (xy 46.601615 -127.483384)
			(xy 46.650283 -127.407924) (xy 46.705922 -127.337448) (xy 46.768027 -127.272596) (xy 46.836031 -127.213961)
			(xy 46.909315 -127.162075) (xy 46.987211 -127.117412) (xy 47.069011 -127.080379) (xy 47.153968 -127.051312)
			(xy 47.197518 -127.040386) (xy 47.209202 -127.037592) (xy 47.22749 -127.022352) (xy 47.269654 -126.925832)
			(xy 47.268384 -126.90221) (xy 47.262542 -126.891542) (xy 47.250781 -126.869994) (xy 47.232266 -126.824529)
			(xy 47.219739 -126.777063) (xy 47.213408 -126.728381) (xy 47.213012 -126.703836) (xy 47.213498 -126.676585)
			(xy 47.221254 -126.622637) (xy 47.236609 -126.570342) (xy 47.259251 -126.520765) (xy 47.288717 -126.474915)
			(xy 47.324408 -126.433724) (xy 47.365599 -126.398033) (xy 47.411449 -126.368567) (xy 47.461026 -126.345925)
			(xy 47.513321 -126.33057) (xy 47.567269 -126.322814) (xy 47.621771 -126.322814) (xy 47.675719 -126.33057)
			(xy 47.728014 -126.345925) (xy 47.777591 -126.368567) (xy 47.823441 -126.398033) (xy 47.864632 -126.433724)
			(xy 47.900323 -126.474915) (xy 47.929789 -126.520765) (xy 47.952431 -126.570342) (xy 47.967786 -126.622637)
			(xy 47.975542 -126.676585) (xy 47.976028 -126.703836) (xy 47.976028 -126.704344) (xy 47.975471 -126.732772)
			(xy 47.966989 -126.788992) (xy 47.950264 -126.843334) (xy 47.938436 -126.86919) (xy 47.938436 -126.869444)
			(xy 47.935069 -126.877277) (xy 47.93319 -126.89421) (xy 47.936983 -126.91082) (xy 47.94123 -126.918212)
			(xy 47.986696 -126.990856) (xy 47.991588 -126.997944) (xy 48.005038 -127.008677) (xy 48.021273 -127.014382)
			(xy 48.029876 -127.014732) (xy 49.26965 -127.014732) (xy 49.3131 -127.015234) (xy 49.399629 -127.023252)
			(xy 49.485049 -127.03922) (xy 49.568631 -127.063001) (xy 49.649663 -127.094393) (xy 49.727452 -127.133127)
			(xy 49.801336 -127.178874) (xy 49.870683 -127.231243) (xy 49.934903 -127.289787) (xy 49.993447 -127.354007)
			(xy 50.045816 -127.423354) (xy 50.086122 -127.488451) (xy 69.090486 -127.488451) (xy 69.090486 -127.401549)
			(xy 69.098505 -127.315017) (xy 69.114474 -127.229594) (xy 69.138256 -127.146008) (xy 69.16965 -127.064974)
			(xy 69.208387 -126.987183) (xy 69.254137 -126.913297) (xy 69.306508 -126.843948) (xy 69.365056 -126.779727)
			(xy 69.429279 -126.721183) (xy 69.49863 -126.668814) (xy 69.572518 -126.623068) (xy 69.650311 -126.584334)
			(xy 69.731346 -126.552944) (xy 69.814933 -126.529165) (xy 69.900356 -126.513199) (xy 69.986889 -126.505185)
			(xy 70.03034 -126.5047) (xy 71.88454 -126.5047) (xy 71.927989 -126.505188) (xy 72.014516 -126.513209)
			(xy 72.099934 -126.52918) (xy 72.183514 -126.552963) (xy 72.264543 -126.584357) (xy 72.34233 -126.623094)
			(xy 72.416211 -126.668841) (xy 72.485556 -126.721211) (xy 72.549773 -126.779755) (xy 72.608315 -126.843975)
			(xy 72.660681 -126.913322) (xy 72.706426 -126.987205) (xy 72.708876 -126.992126) (xy 104.844342 -126.992126)
			(xy 104.844813 -126.964756) (xy 104.852628 -126.910577) (xy 104.868115 -126.858073) (xy 104.890956 -126.808326)
			(xy 104.920681 -126.762359) (xy 104.938322 -126.741428) (xy 104.938576 -126.741174) (xy 104.944147 -126.734077)
			(xy 104.950401 -126.717168) (xy 104.950768 -126.708154) (xy 104.950768 -126.641098) (xy 104.950419 -126.63208)
			(xy 104.944167 -126.615163) (xy 104.938576 -126.608078) (xy 104.938322 -126.608078) (xy 104.938322 -126.607824)
			(xy 104.920707 -126.586871) (xy 104.890982 -126.540906) (xy 104.868135 -126.491163) (xy 104.852637 -126.438664)
			(xy 104.844806 -126.384489) (xy 104.844803 -126.32975) (xy 104.852629 -126.275574) (xy 104.868121 -126.223073)
			(xy 104.890963 -126.173328) (xy 104.920683 -126.127361) (xy 104.938322 -126.106428) (xy 104.938576 -126.106174)
			(xy 104.944147 -126.099077) (xy 104.950401 -126.082168) (xy 104.950768 -126.073154) (xy 104.950768 -126.006098)
			(xy 104.950419 -125.99708) (xy 104.944167 -125.980163) (xy 104.938576 -125.973078) (xy 104.938322 -125.973078)
			(xy 104.938322 -125.972824) (xy 104.920707 -125.951871) (xy 104.890982 -125.905906) (xy 104.868135 -125.856163)
			(xy 104.852637 -125.803664) (xy 104.844806 -125.749489) (xy 104.844803 -125.69475) (xy 104.852629 -125.640574)
			(xy 104.868121 -125.588073) (xy 104.890963 -125.538328) (xy 104.920683 -125.492361) (xy 104.938322 -125.471428)
			(xy 104.938576 -125.471174) (xy 104.944147 -125.464077) (xy 104.950401 -125.447168) (xy 104.950768 -125.438154)
			(xy 104.950768 -125.371098) (xy 104.950419 -125.36208) (xy 104.944167 -125.345163) (xy 104.938576 -125.338078)
			(xy 104.938322 -125.338078) (xy 104.938322 -125.337824) (xy 104.920684 -125.316891) (xy 104.890971 -125.270919)
			(xy 104.868135 -125.221172) (xy 104.852644 -125.168671) (xy 104.844816 -125.114495) (xy 104.844342 -125.087126)
			(xy 104.844828 -125.059875) (xy 104.852584 -125.005927) (xy 104.867939 -124.953632) (xy 104.890581 -124.904055)
			(xy 104.920047 -124.858205) (xy 104.955738 -124.817014) (xy 104.996929 -124.781323) (xy 105.042779 -124.751857)
			(xy 105.092356 -124.729215) (xy 105.144651 -124.71386) (xy 105.198599 -124.706104) (xy 105.253101 -124.706104)
			(xy 105.307049 -124.71386) (xy 105.359344 -124.729215) (xy 105.408921 -124.751857) (xy 105.454771 -124.781323)
			(xy 105.495962 -124.817014) (xy 105.531653 -124.858205) (xy 105.561119 -124.904055) (xy 105.583761 -124.953632)
			(xy 105.599116 -125.005927) (xy 105.606872 -125.059875) (xy 105.607358 -125.087126) (xy 105.606917 -125.114497)
			(xy 105.599095 -125.168678) (xy 105.583601 -125.221182) (xy 105.560753 -125.270928) (xy 105.531022 -125.316893)
			(xy 105.513378 -125.337824) (xy 105.513124 -125.338078) (xy 105.507532 -125.34516) (xy 105.50129 -125.362081)
			(xy 105.500932 -125.371098) (xy 105.500932 -125.438154) (xy 105.501304 -125.447169) (xy 105.50754 -125.464087)
			(xy 105.513124 -125.471174) (xy 105.513378 -125.471174) (xy 105.513378 -125.471428) (xy 105.531044 -125.49234)
			(xy 105.560767 -125.538312) (xy 105.583611 -125.588061) (xy 105.599105 -125.640567) (xy 105.606931 -125.694748)
			(xy 105.606928 -125.749491) (xy 105.599097 -125.803672) (xy 105.583597 -125.856175) (xy 105.560748 -125.905923)
			(xy 105.53102 -125.951891) (xy 105.513378 -125.972824) (xy 105.513124 -125.973078) (xy 105.507532 -125.98016)
			(xy 105.50129 -125.997081) (xy 105.500932 -126.006098) (xy 105.500932 -126.073154) (xy 105.501304 -126.082169)
			(xy 105.50754 -126.099087) (xy 105.513124 -126.106174) (xy 105.513378 -126.106174) (xy 105.513378 -126.106428)
			(xy 105.531044 -126.12734) (xy 105.560767 -126.173312) (xy 105.583611 -126.223061) (xy 105.599105 -126.275567)
			(xy 105.606931 -126.329748) (xy 105.606928 -126.384491) (xy 105.599097 -126.438672) (xy 105.583597 -126.491175)
			(xy 105.560748 -126.540923) (xy 105.53102 -126.586891) (xy 105.513378 -126.607824) (xy 105.513124 -126.608078)
			(xy 105.507532 -126.61516) (xy 105.50129 -126.632081) (xy 105.500932 -126.641098) (xy 105.500932 -126.708154)
			(xy 105.501304 -126.717169) (xy 105.50754 -126.734087) (xy 105.513124 -126.741174) (xy 105.513378 -126.741174)
			(xy 105.513378 -126.741428) (xy 105.530993 -126.762379) (xy 105.56071 -126.808346) (xy 105.58355 -126.858089)
			(xy 105.599047 -126.910586) (xy 105.606881 -126.964758) (xy 105.607358 -126.992126) (xy 105.606872 -127.019377)
			(xy 105.602208 -127.051816) (xy 107.500166 -127.051816) (xy 107.500625 -127.024445) (xy 107.508442 -126.970265)
			(xy 107.523932 -126.917762) (xy 107.546776 -126.868015) (xy 107.576503 -126.822049) (xy 107.594146 -126.801118)
			(xy 107.5944 -126.800864) (xy 107.599966 -126.793763) (xy 107.606225 -126.776857) (xy 107.606592 -126.767844)
			(xy 107.606592 -126.700788) (xy 107.606242 -126.69177) (xy 107.59999 -126.674853) (xy 107.5944 -126.667768)
			(xy 107.594146 -126.667768) (xy 107.594146 -126.667514) (xy 107.57652 -126.646569) (xy 107.546793 -126.600604)
			(xy 107.523946 -126.55086) (xy 107.508448 -126.498359) (xy 107.500617 -126.444182) (xy 107.500615 -126.389442)
			(xy 107.508442 -126.335264) (xy 107.523937 -126.282763) (xy 107.546782 -126.233017) (xy 107.576506 -126.18705)
			(xy 107.594146 -126.166118) (xy 107.5944 -126.165864) (xy 107.599966 -126.158763) (xy 107.606225 -126.141857)
			(xy 107.606592 -126.132844) (xy 107.606592 -126.065788) (xy 107.606242 -126.05677) (xy 107.59999 -126.039853)
			(xy 107.5944 -126.032768) (xy 107.594146 -126.032768) (xy 107.594146 -126.032514) (xy 107.57652 -126.011569)
			(xy 107.546793 -125.965604) (xy 107.523946 -125.91586) (xy 107.508448 -125.863359) (xy 107.500617 -125.809182)
			(xy 107.500615 -125.754442) (xy 107.508442 -125.700264) (xy 107.523937 -125.647763) (xy 107.546782 -125.598017)
			(xy 107.576506 -125.55205) (xy 107.594146 -125.531118) (xy 107.5944 -125.530864) (xy 107.599966 -125.523763)
			(xy 107.606225 -125.506857) (xy 107.606592 -125.497844) (xy 107.606592 -125.430788) (xy 107.606242 -125.42177)
			(xy 107.59999 -125.404853) (xy 107.5944 -125.397768) (xy 107.594146 -125.397768) (xy 107.594146 -125.397514)
			(xy 107.576507 -125.376582) (xy 107.546794 -125.33061) (xy 107.523957 -125.280862) (xy 107.508466 -125.228361)
			(xy 107.500639 -125.174185) (xy 107.500166 -125.146816) (xy 107.500652 -125.119565) (xy 107.508408 -125.065617)
			(xy 107.523763 -125.013322) (xy 107.546405 -124.963745) (xy 107.575871 -124.917895) (xy 107.611562 -124.876704)
			(xy 107.652753 -124.841013) (xy 107.698603 -124.811547) (xy 107.74818 -124.788905) (xy 107.800475 -124.77355)
			(xy 107.854423 -124.765794) (xy 107.908925 -124.765794) (xy 107.962873 -124.77355) (xy 107.977191 -124.777754)
			(xy 112.163858 -124.777754) (xy 112.167929 -124.722132) (xy 112.180055 -124.667695) (xy 112.199978 -124.615604)
			(xy 112.227274 -124.566969) (xy 112.26136 -124.522826) (xy 112.301509 -124.484117) (xy 112.346867 -124.451666)
			(xy 112.396467 -124.426165) (xy 112.449251 -124.408158) (xy 112.504094 -124.398028) (xy 112.559828 -124.395991)
			(xy 112.615265 -124.402091) (xy 112.669222 -124.416197) (xy 112.720551 -124.438009) (xy 112.768157 -124.467063)
			(xy 112.811025 -124.502738) (xy 112.848242 -124.544275) (xy 112.879015 -124.590788) (xy 112.902687 -124.641285)
			(xy 112.918755 -124.694692) (xy 112.926875 -124.749868) (xy 112.927384 -124.777754) (xy 112.926875 -124.80564)
			(xy 112.918755 -124.860816) (xy 112.911802 -124.883926) (xy 116.439948 -124.883926) (xy 116.444019 -124.828304)
			(xy 116.456145 -124.773867) (xy 116.476068 -124.721776) (xy 116.503364 -124.673141) (xy 116.53745 -124.628998)
			(xy 116.577599 -124.590289) (xy 116.622957 -124.557838) (xy 116.672557 -124.532337) (xy 116.725341 -124.51433)
			(xy 116.780184 -124.5042) (xy 116.835918 -124.502163) (xy 116.891355 -124.508263) (xy 116.945312 -124.522369)
			(xy 116.996641 -124.544181) (xy 117.044247 -124.573235) (xy 117.087115 -124.60891) (xy 117.124332 -124.650447)
			(xy 117.155105 -124.69696) (xy 117.178777 -124.747457) (xy 117.194845 -124.800864) (xy 117.202965 -124.85604)
			(xy 117.203474 -124.883926) (xy 118.631714 -124.883926) (xy 118.635785 -124.828304) (xy 118.647911 -124.773867)
			(xy 118.667834 -124.721776) (xy 118.69513 -124.673141) (xy 118.729216 -124.628998) (xy 118.769365 -124.590289)
			(xy 118.814723 -124.557838) (xy 118.864323 -124.532337) (xy 118.917107 -124.51433) (xy 118.97195 -124.5042)
			(xy 119.027684 -124.502163) (xy 119.083121 -124.508263) (xy 119.137078 -124.522369) (xy 119.188407 -124.544181)
			(xy 119.236013 -124.573235) (xy 119.278881 -124.60891) (xy 119.316098 -124.650447) (xy 119.346871 -124.69696)
			(xy 119.370543 -124.747457) (xy 119.386611 -124.800864) (xy 119.394731 -124.85604) (xy 119.39524 -124.883926)
			(xy 119.394731 -124.911812) (xy 119.386611 -124.966988) (xy 119.370543 -125.020395) (xy 119.346871 -125.070892)
			(xy 119.316098 -125.117405) (xy 119.278881 -125.158942) (xy 119.236013 -125.194617) (xy 119.188407 -125.223671)
			(xy 119.137078 -125.245483) (xy 119.083121 -125.259589) (xy 119.027684 -125.265689) (xy 118.97195 -125.263652)
			(xy 118.917107 -125.253522) (xy 118.864323 -125.235515) (xy 118.814723 -125.210014) (xy 118.769365 -125.177563)
			(xy 118.729216 -125.138854) (xy 118.69513 -125.094711) (xy 118.667834 -125.046076) (xy 118.647911 -124.993985)
			(xy 118.635785 -124.939548) (xy 118.631714 -124.883926) (xy 117.203474 -124.883926) (xy 117.202965 -124.911812)
			(xy 117.194845 -124.966988) (xy 117.178777 -125.020395) (xy 117.155105 -125.070892) (xy 117.124332 -125.117405)
			(xy 117.087115 -125.158942) (xy 117.044247 -125.194617) (xy 116.996641 -125.223671) (xy 116.945312 -125.245483)
			(xy 116.891355 -125.259589) (xy 116.835918 -125.265689) (xy 116.780184 -125.263652) (xy 116.725341 -125.253522)
			(xy 116.672557 -125.235515) (xy 116.622957 -125.210014) (xy 116.577599 -125.177563) (xy 116.53745 -125.138854)
			(xy 116.503364 -125.094711) (xy 116.476068 -125.046076) (xy 116.456145 -124.993985) (xy 116.444019 -124.939548)
			(xy 116.439948 -124.883926) (xy 112.911802 -124.883926) (xy 112.902687 -124.914223) (xy 112.879015 -124.96472)
			(xy 112.848242 -125.011233) (xy 112.811025 -125.05277) (xy 112.768157 -125.088445) (xy 112.720551 -125.117499)
			(xy 112.669222 -125.139311) (xy 112.615265 -125.153417) (xy 112.559828 -125.159517) (xy 112.504094 -125.15748)
			(xy 112.449251 -125.14735) (xy 112.396467 -125.129343) (xy 112.346867 -125.103842) (xy 112.301509 -125.071391)
			(xy 112.26136 -125.032682) (xy 112.227274 -124.988539) (xy 112.199978 -124.939904) (xy 112.180055 -124.887813)
			(xy 112.167929 -124.833376) (xy 112.163858 -124.777754) (xy 107.977191 -124.777754) (xy 108.015168 -124.788905)
			(xy 108.064745 -124.811547) (xy 108.110595 -124.841013) (xy 108.151786 -124.876704) (xy 108.187477 -124.917895)
			(xy 108.216943 -124.963745) (xy 108.239585 -125.013322) (xy 108.25494 -125.065617) (xy 108.262696 -125.119565)
			(xy 108.263182 -125.146816) (xy 108.26273 -125.174187) (xy 108.254909 -125.228367) (xy 108.239417 -125.28087)
			(xy 108.216572 -125.330617) (xy 108.186845 -125.376583) (xy 108.169202 -125.397514) (xy 108.168948 -125.397768)
			(xy 108.163362 -125.404855) (xy 108.157116 -125.421772) (xy 108.156756 -125.430788) (xy 108.156756 -125.497844)
			(xy 108.157128 -125.50686) (xy 108.163364 -125.523777) (xy 108.168948 -125.530864) (xy 108.169202 -125.530864)
			(xy 108.169202 -125.531118) (xy 108.186857 -125.552039) (xy 108.216579 -125.598009) (xy 108.239422 -125.647758)
			(xy 108.254916 -125.700261) (xy 108.262742 -125.754441) (xy 108.26274 -125.809183) (xy 108.25491 -125.863362)
			(xy 108.239413 -125.915865) (xy 108.216567 -125.965612) (xy 108.186843 -126.011581) (xy 108.169202 -126.032514)
			(xy 108.168948 -126.032768) (xy 108.163362 -126.039855) (xy 108.157116 -126.056772) (xy 108.156756 -126.065788)
			(xy 108.156756 -126.132844) (xy 108.157128 -126.14186) (xy 108.163364 -126.158777) (xy 108.168948 -126.165864)
			(xy 108.169202 -126.166118) (xy 108.186022 -126.186075) (xy 108.193742 -126.197868) (xy 116.44579 -126.197868)
			(xy 116.449861 -126.142246) (xy 116.461987 -126.087809) (xy 116.48191 -126.035718) (xy 116.509206 -125.987083)
			(xy 116.543292 -125.94294) (xy 116.583441 -125.904231) (xy 116.628799 -125.87178) (xy 116.678399 -125.846279)
			(xy 116.731183 -125.828272) (xy 116.786026 -125.818142) (xy 116.84176 -125.816105) (xy 116.897197 -125.822205)
			(xy 116.951154 -125.836311) (xy 117.002483 -125.858123) (xy 117.050089 -125.887177) (xy 117.065409 -125.899926)
			(xy 118.631714 -125.899926) (xy 118.635785 -125.844304) (xy 118.647911 -125.789867) (xy 118.667834 -125.737776)
			(xy 118.69513 -125.689141) (xy 118.729216 -125.644998) (xy 118.769365 -125.606289) (xy 118.814723 -125.573838)
			(xy 118.864323 -125.548337) (xy 118.917107 -125.53033) (xy 118.97195 -125.5202) (xy 119.027684 -125.518163)
			(xy 119.083121 -125.524263) (xy 119.137078 -125.538369) (xy 119.188407 -125.560181) (xy 119.236013 -125.589235)
			(xy 119.278881 -125.62491) (xy 119.316098 -125.666447) (xy 119.346871 -125.71296) (xy 119.370543 -125.763457)
			(xy 119.386611 -125.816864) (xy 119.394731 -125.87204) (xy 119.39524 -125.899926) (xy 119.394731 -125.927812)
			(xy 119.386611 -125.982988) (xy 119.370543 -126.036395) (xy 119.346871 -126.086892) (xy 119.316098 -126.133405)
			(xy 119.278881 -126.174942) (xy 119.236013 -126.210617) (xy 119.188407 -126.239671) (xy 119.137078 -126.261483)
			(xy 119.083121 -126.275589) (xy 119.027684 -126.281689) (xy 118.97195 -126.279652) (xy 118.917107 -126.269522)
			(xy 118.864323 -126.251515) (xy 118.814723 -126.226014) (xy 118.769365 -126.193563) (xy 118.729216 -126.154854)
			(xy 118.69513 -126.110711) (xy 118.667834 -126.062076) (xy 118.647911 -126.009985) (xy 118.635785 -125.955548)
			(xy 118.631714 -125.899926) (xy 117.065409 -125.899926) (xy 117.092957 -125.922852) (xy 117.130174 -125.964389)
			(xy 117.160947 -126.010902) (xy 117.184619 -126.061399) (xy 117.200687 -126.114806) (xy 117.208807 -126.169982)
			(xy 117.209316 -126.197868) (xy 117.208807 -126.225754) (xy 117.200687 -126.28093) (xy 117.184619 -126.334337)
			(xy 117.160947 -126.384834) (xy 117.130174 -126.431347) (xy 117.092957 -126.472884) (xy 117.050089 -126.508559)
			(xy 117.002483 -126.537613) (xy 116.951154 -126.559425) (xy 116.897197 -126.573531) (xy 116.84176 -126.579631)
			(xy 116.786026 -126.577594) (xy 116.731183 -126.567464) (xy 116.678399 -126.549457) (xy 116.628799 -126.523956)
			(xy 116.583441 -126.491505) (xy 116.543292 -126.452796) (xy 116.509206 -126.408653) (xy 116.48191 -126.360018)
			(xy 116.461987 -126.307927) (xy 116.449861 -126.25349) (xy 116.44579 -126.197868) (xy 108.193742 -126.197868)
			(xy 108.214608 -126.229744) (xy 108.236986 -126.276896) (xy 108.252738 -126.326655) (xy 108.257594 -126.3523)
			(xy 108.257594 -126.352554) (xy 108.259428 -126.360829) (xy 108.267719 -126.375599) (xy 108.280376 -126.386856)
			(xy 108.288074 -126.3904) (xy 108.379514 -126.429008) (xy 108.405168 -126.426214) (xy 108.415836 -126.418594)
			(xy 108.439986 -126.402441) (xy 108.492126 -126.376812) (xy 108.547549 -126.359386) (xy 108.604973 -126.350564)
			(xy 108.634022 -126.350014) (xy 108.661275 -126.350457) (xy 108.715225 -126.358217) (xy 108.767522 -126.373577)
			(xy 108.817101 -126.396222) (xy 108.862952 -126.425692) (xy 108.904143 -126.461388) (xy 108.939834 -126.502583)
			(xy 108.969299 -126.548438) (xy 108.991939 -126.598019) (xy 109.007292 -126.650318) (xy 109.015046 -126.704269)
			(xy 109.01553 -126.731522) (xy 109.015096 -126.758152) (xy 109.00769 -126.810896) (xy 108.993024 -126.862097)
			(xy 108.971382 -126.910763) (xy 108.943187 -126.955948) (xy 108.908984 -126.996776) (xy 108.869437 -127.032452)
			(xy 108.847636 -127.047752) (xy 108.837476 -127.05461) (xy 108.825792 -127.075438) (xy 108.821474 -127.18161)
			(xy 108.83138 -127.203454) (xy 108.841032 -127.211074) (xy 108.862881 -127.229325) (xy 108.901486 -127.27116)
			(xy 108.933453 -127.318263) (xy 108.95807 -127.369591) (xy 108.963528 -127.38735) (xy 110.308898 -127.38735)
			(xy 110.309418 -127.357979) (xy 110.318417 -127.29993) (xy 110.336209 -127.243946) (xy 110.362374 -127.191353)
			(xy 110.396293 -127.143393) (xy 110.41634 -127.12192) (xy 110.42272 -127.114735) (xy 110.430017 -127.096971)
			(xy 110.430564 -127.087376) (xy 110.431834 -127.008128) (xy 110.424976 -126.990094) (xy 110.418626 -126.982982)
			(xy 110.400068 -126.961814) (xy 110.368766 -126.915023) (xy 110.344678 -126.864142) (xy 110.328326 -126.810275)
			(xy 110.320065 -126.754589) (xy 110.319566 -126.726442) (xy 110.320094 -126.699191) (xy 110.327845 -126.645244)
			(xy 110.343194 -126.592949) (xy 110.36583 -126.543371) (xy 110.395291 -126.497519) (xy 110.430978 -126.456326)
			(xy 110.472164 -126.420632) (xy 110.518011 -126.391163) (xy 110.567585 -126.368518) (xy 110.619878 -126.353159)
			(xy 110.673823 -126.345399) (xy 110.701074 -126.344934) (xy 110.729754 -126.345504) (xy 110.786466 -126.35411)
			(xy 110.841253 -126.371103) (xy 110.892881 -126.3961) (xy 110.940189 -126.428538) (xy 110.982113 -126.467688)
			(xy 111.017708 -126.512669) (xy 111.046175 -126.562468) (xy 111.066872 -126.615966) (xy 111.079333 -126.671957)
			(xy 111.08182 -126.700534) (xy 111.082582 -126.713488) (xy 111.096552 -126.735332) (xy 111.194596 -126.788926)
			(xy 111.220504 -126.788926) (xy 111.231934 -126.782576) (xy 111.260181 -126.767818) (xy 111.320372 -126.746883)
			(xy 111.383205 -126.736248) (xy 111.415068 -126.735586) (xy 111.415576 -126.735586) (xy 111.44283 -126.73606)
			(xy 111.496782 -126.743814) (xy 111.549082 -126.759167) (xy 111.598664 -126.781808) (xy 111.64452 -126.811275)
			(xy 111.685715 -126.846968) (xy 111.72141 -126.888161) (xy 111.739255 -126.915926) (xy 118.631714 -126.915926)
			(xy 118.635785 -126.860304) (xy 118.647911 -126.805867) (xy 118.667834 -126.753776) (xy 118.69513 -126.705141)
			(xy 118.729216 -126.660998) (xy 118.769365 -126.622289) (xy 118.814723 -126.589838) (xy 118.864323 -126.564337)
			(xy 118.917107 -126.54633) (xy 118.97195 -126.5362) (xy 119.027684 -126.534163) (xy 119.083121 -126.540263)
			(xy 119.137078 -126.554369) (xy 119.188407 -126.576181) (xy 119.236013 -126.605235) (xy 119.278881 -126.64091)
			(xy 119.316098 -126.682447) (xy 119.346871 -126.72896) (xy 119.370543 -126.779457) (xy 119.386611 -126.832864)
			(xy 119.394731 -126.88804) (xy 119.39524 -126.915926) (xy 119.394731 -126.943812) (xy 119.386611 -126.998988)
			(xy 119.370543 -127.052395) (xy 119.346871 -127.102892) (xy 119.316098 -127.149405) (xy 119.278881 -127.190942)
			(xy 119.236013 -127.226617) (xy 119.188407 -127.255671) (xy 119.137078 -127.277483) (xy 119.083121 -127.291589)
			(xy 119.027684 -127.297689) (xy 118.97195 -127.295652) (xy 118.917107 -127.285522) (xy 118.864323 -127.267515)
			(xy 118.814723 -127.242014) (xy 118.769365 -127.209563) (xy 118.729216 -127.170854) (xy 118.69513 -127.126711)
			(xy 118.667834 -127.078076) (xy 118.647911 -127.025985) (xy 118.635785 -126.971548) (xy 118.631714 -126.915926)
			(xy 111.739255 -126.915926) (xy 111.75088 -126.934014) (xy 111.773524 -126.983595) (xy 111.788881 -127.035894)
			(xy 111.796639 -127.089846) (xy 111.796639 -127.144354) (xy 111.788881 -127.198306) (xy 111.773524 -127.250605)
			(xy 111.75088 -127.300186) (xy 111.72141 -127.346039) (xy 111.685715 -127.387232) (xy 111.64452 -127.422925)
			(xy 111.598664 -127.452392) (xy 111.549082 -127.475033) (xy 111.518979 -127.48387) (xy 116.59438 -127.48387)
			(xy 116.598451 -127.428248) (xy 116.610577 -127.373811) (xy 116.6305 -127.32172) (xy 116.657796 -127.273085)
			(xy 116.691882 -127.228942) (xy 116.732031 -127.190233) (xy 116.777389 -127.157782) (xy 116.826989 -127.132281)
			(xy 116.879773 -127.114274) (xy 116.934616 -127.104144) (xy 116.99035 -127.102107) (xy 117.045787 -127.108207)
			(xy 117.099744 -127.122313) (xy 117.151073 -127.144125) (xy 117.198679 -127.173179) (xy 117.241547 -127.208854)
			(xy 117.278764 -127.250391) (xy 117.309537 -127.296904) (xy 117.333209 -127.347401) (xy 117.349277 -127.400808)
			(xy 117.357397 -127.455984) (xy 117.357906 -127.48387) (xy 117.357397 -127.511756) (xy 117.349277 -127.566932)
			(xy 117.333209 -127.620339) (xy 117.309537 -127.670836) (xy 117.278764 -127.717349) (xy 117.241547 -127.758886)
			(xy 117.198679 -127.794561) (xy 117.151073 -127.823615) (xy 117.099744 -127.845427) (xy 117.045787 -127.859533)
			(xy 116.99035 -127.865633) (xy 116.934616 -127.863596) (xy 116.879773 -127.853466) (xy 116.826989 -127.835459)
			(xy 116.777389 -127.809958) (xy 116.732031 -127.777507) (xy 116.691882 -127.738798) (xy 116.657796 -127.694655)
			(xy 116.6305 -127.64602) (xy 116.610577 -127.593929) (xy 116.598451 -127.539492) (xy 116.59438 -127.48387)
			(xy 111.518979 -127.48387) (xy 111.496782 -127.490386) (xy 111.44283 -127.49814) (xy 111.415576 -127.498602)
			(xy 111.388288 -127.498128) (xy 111.334267 -127.49036) (xy 111.281905 -127.47497) (xy 111.232272 -127.452274)
			(xy 111.209074 -127.437896) (xy 111.20882 -127.437642) (xy 111.198527 -127.431896) (xy 111.175101 -127.429514)
			(xy 111.163862 -127.43307) (xy 111.087408 -127.461264) (xy 111.076556 -127.465943) (xy 111.060406 -127.483158)
			(xy 111.05642 -127.494284) (xy 111.05642 -127.494792) (xy 111.048249 -127.520795) (xy 111.025627 -127.570382)
			(xy 110.996177 -127.616243) (xy 110.960498 -127.657445) (xy 110.919317 -127.693147) (xy 110.873472 -127.722623)
			(xy 110.823899 -127.745273) (xy 110.771605 -127.760634) (xy 110.717657 -127.768394) (xy 110.690406 -127.768858)
			(xy 110.663151 -127.768439) (xy 110.609196 -127.760681) (xy 110.556894 -127.745324) (xy 110.507311 -127.722678)
			(xy 110.461455 -127.693206) (xy 110.420261 -127.657508) (xy 110.384567 -127.61631) (xy 110.355101 -127.570451)
			(xy 110.332461 -127.520865) (xy 110.317109 -127.468561) (xy 110.309358 -127.414605) (xy 110.308898 -127.38735)
			(xy 108.963528 -127.38735) (xy 108.974793 -127.424005) (xy 108.983252 -127.480299) (xy 108.98378 -127.508762)
			(xy 108.983294 -127.536013) (xy 108.975538 -127.589961) (xy 108.960183 -127.642256) (xy 108.937541 -127.691833)
			(xy 108.908075 -127.737683) (xy 108.872384 -127.778874) (xy 108.831193 -127.814565) (xy 108.785343 -127.844031)
			(xy 108.735766 -127.866673) (xy 108.683471 -127.882028) (xy 108.629523 -127.889784) (xy 108.575021 -127.889784)
			(xy 108.521073 -127.882028) (xy 108.468778 -127.866673) (xy 108.419201 -127.844031) (xy 108.373351 -127.814565)
			(xy 108.33216 -127.778874) (xy 108.296469 -127.737683) (xy 108.267003 -127.691833) (xy 108.244361 -127.642256)
			(xy 108.229006 -127.589961) (xy 108.22125 -127.536013) (xy 108.220764 -127.508762) (xy 108.22178 -127.479552)
			(xy 108.22305 -127.465582) (xy 108.21035 -127.440182) (xy 108.110528 -127.376936) (xy 108.082588 -127.376428)
			(xy 108.070396 -127.383286) (xy 108.048743 -127.395152) (xy 108.003045 -127.413849) (xy 107.955319 -127.426507)
			(xy 107.906361 -127.432913) (xy 107.881674 -127.433324) (xy 107.854423 -127.432846) (xy 107.800476 -127.425087)
			(xy 107.748182 -127.409729) (xy 107.698605 -127.387086) (xy 107.652756 -127.357619) (xy 107.611566 -127.321926)
			(xy 107.575875 -127.280736) (xy 107.546409 -127.234886) (xy 107.523767 -127.185309) (xy 107.508411 -127.133015)
			(xy 107.500653 -127.079067) (xy 107.500166 -127.051816) (xy 105.602208 -127.051816) (xy 105.599116 -127.073325)
			(xy 105.583761 -127.12562) (xy 105.561119 -127.175197) (xy 105.531653 -127.221047) (xy 105.495962 -127.262238)
			(xy 105.454771 -127.297929) (xy 105.408921 -127.327395) (xy 105.359344 -127.350037) (xy 105.307049 -127.365392)
			(xy 105.253101 -127.373148) (xy 105.198599 -127.373148) (xy 105.144651 -127.365392) (xy 105.092356 -127.350037)
			(xy 105.042779 -127.327395) (xy 104.996929 -127.297929) (xy 104.955738 -127.262238) (xy 104.920047 -127.221047)
			(xy 104.890581 -127.175197) (xy 104.867939 -127.12562) (xy 104.852584 -127.073325) (xy 104.844828 -127.019377)
			(xy 104.844342 -126.992126) (xy 72.708876 -126.992126) (xy 72.745159 -127.064994) (xy 72.776549 -127.146024)
			(xy 72.800329 -127.229605) (xy 72.816296 -127.315024) (xy 72.824314 -127.401551) (xy 72.824314 -127.488449)
			(xy 72.816296 -127.574976) (xy 72.800329 -127.660395) (xy 72.776549 -127.743976) (xy 72.745159 -127.825006)
			(xy 72.706426 -127.902795) (xy 72.688389 -127.931926) (xy 118.631714 -127.931926) (xy 118.635785 -127.876304)
			(xy 118.647911 -127.821867) (xy 118.667834 -127.769776) (xy 118.69513 -127.721141) (xy 118.729216 -127.676998)
			(xy 118.769365 -127.638289) (xy 118.814723 -127.605838) (xy 118.864323 -127.580337) (xy 118.917107 -127.56233)
			(xy 118.97195 -127.5522) (xy 119.027684 -127.550163) (xy 119.083121 -127.556263) (xy 119.137078 -127.570369)
			(xy 119.188407 -127.592181) (xy 119.236013 -127.621235) (xy 119.278881 -127.65691) (xy 119.316098 -127.698447)
			(xy 119.346871 -127.74496) (xy 119.370543 -127.795457) (xy 119.386611 -127.848864) (xy 119.394731 -127.90404)
			(xy 119.39524 -127.931926) (xy 119.394731 -127.959812) (xy 119.386611 -128.014988) (xy 119.370543 -128.068395)
			(xy 119.346871 -128.118892) (xy 119.316098 -128.165405) (xy 119.278881 -128.206942) (xy 119.236013 -128.242617)
			(xy 119.188407 -128.271671) (xy 119.137078 -128.293483) (xy 119.083121 -128.307589) (xy 119.027684 -128.313689)
			(xy 118.97195 -128.311652) (xy 118.917107 -128.301522) (xy 118.864323 -128.283515) (xy 118.814723 -128.258014)
			(xy 118.769365 -128.225563) (xy 118.729216 -128.186854) (xy 118.69513 -128.142711) (xy 118.667834 -128.094076)
			(xy 118.647911 -128.041985) (xy 118.635785 -127.987548) (xy 118.631714 -127.931926) (xy 72.688389 -127.931926)
			(xy 72.660681 -127.976678) (xy 72.608315 -128.046025) (xy 72.549773 -128.110245) (xy 72.485556 -128.168789)
			(xy 72.416211 -128.221159) (xy 72.34233 -128.266906) (xy 72.264543 -128.305643) (xy 72.183514 -128.337037)
			(xy 72.099934 -128.36082) (xy 72.014516 -128.376791) (xy 71.927989 -128.384812) (xy 71.88454 -128.385316)
			(xy 70.03034 -128.385316) (xy 69.986889 -128.384815) (xy 69.900356 -128.376801) (xy 69.814933 -128.360835)
			(xy 69.731346 -128.337056) (xy 69.650311 -128.305666) (xy 69.572518 -128.266932) (xy 69.49863 -128.221186)
			(xy 69.429279 -128.168817) (xy 69.365056 -128.110273) (xy 69.306508 -128.046052) (xy 69.254137 -127.976703)
			(xy 69.208387 -127.902817) (xy 69.16965 -127.825026) (xy 69.138256 -127.743992) (xy 69.114474 -127.660406)
			(xy 69.098505 -127.574983) (xy 69.090486 -127.488451) (xy 50.086122 -127.488451) (xy 50.091563 -127.497238)
			(xy 50.130297 -127.575027) (xy 50.161689 -127.656059) (xy 50.18547 -127.739641) (xy 50.201438 -127.825061)
			(xy 50.209456 -127.91159) (xy 50.209456 -127.99849) (xy 50.201438 -128.085019) (xy 50.18547 -128.170439)
			(xy 50.161689 -128.254021) (xy 50.130297 -128.335053) (xy 50.091563 -128.412842) (xy 50.045816 -128.486726)
			(xy 49.993447 -128.556073) (xy 49.934903 -128.620293) (xy 49.870683 -128.678837) (xy 49.801336 -128.731206)
			(xy 49.727452 -128.776953) (xy 49.649663 -128.815687) (xy 49.568631 -128.847079) (xy 49.485049 -128.87086)
			(xy 49.399629 -128.886828) (xy 49.3131 -128.894846) (xy 49.26965 -128.895348) (xy 47.41545 -128.895348)
			(xy 47.372018 -128.8949) (xy 47.285526 -128.886883) (xy 47.200142 -128.87092) (xy 47.116594 -128.847149)
			(xy 47.035596 -128.815772) (xy 46.957837 -128.777057) (xy 46.883982 -128.731334) (xy 46.81466 -128.678992)
			(xy 46.750461 -128.620479) (xy 46.691934 -128.556293) (xy 46.639578 -128.486981) (xy 46.593839 -128.413136)
			(xy 46.555108 -128.335385) (xy 46.523714 -128.254394) (xy 46.499925 -128.170851) (xy 46.483945 -128.08547)
			(xy 46.475909 -127.99898) (xy 46.475396 -127.955548) (xy 16.69363 -127.955548) (xy 16.7015 -127.964631)
			(xy 16.730966 -128.010481) (xy 16.753607 -128.060058) (xy 16.768962 -128.112352) (xy 16.776718 -128.166299)
			(xy 16.776718 -128.220801) (xy 16.768962 -128.274748) (xy 16.753607 -128.327042) (xy 16.730966 -128.376619)
			(xy 16.7015 -128.422469) (xy 16.665809 -128.463659) (xy 16.624619 -128.49935) (xy 16.578769 -128.528816)
			(xy 16.529192 -128.551457) (xy 16.476898 -128.566812) (xy 16.422951 -128.574568) (xy 16.3957 -128.575054)
			(xy 16.368329 -128.574599) (xy 16.314149 -128.56678) (xy 16.261646 -128.551289) (xy 16.211899 -128.528445)
			(xy 16.165933 -128.498717) (xy 16.145002 -128.481074) (xy 16.144748 -128.48082) (xy 16.137659 -128.475238)
			(xy 16.120744 -128.468991) (xy 16.111728 -128.468628) (xy 16.044672 -128.468628) (xy 16.035653 -128.468966)
			(xy 16.018736 -128.475226) (xy 16.011652 -128.48082) (xy 16.011398 -128.481074) (xy 15.990465 -128.498715)
			(xy 15.944497 -128.528439) (xy 15.894751 -128.551285) (xy 15.842249 -128.566781) (xy 15.788071 -128.57461)
			(xy 15.733329 -128.57461) (xy 15.679151 -128.566781) (xy 15.626649 -128.551285) (xy 15.576903 -128.528439)
			(xy 15.530935 -128.498715) (xy 15.510002 -128.481074) (xy 15.509748 -128.48082) (xy 15.502659 -128.475238)
			(xy 15.485744 -128.468991) (xy 15.476728 -128.468628) (xy 15.409672 -128.468628) (xy 15.400653 -128.468966)
			(xy 15.383736 -128.475226) (xy 15.376652 -128.48082) (xy 15.376652 -128.481074) (xy 15.376398 -128.481074)
			(xy 15.355474 -128.498723) (xy 15.3095 -128.528435) (xy 15.25975 -128.551269) (xy 15.207247 -128.566758)
			(xy 15.15307 -128.574582) (xy 15.1257 -128.575054) (xy 15.098448 -128.574576) (xy 15.0445 -128.56682)
			(xy 14.992205 -128.551464) (xy 14.942627 -128.528823) (xy 14.896776 -128.499356) (xy 14.855586 -128.463664)
			(xy 14.819894 -128.422474) (xy 14.790427 -128.376623) (xy 14.767786 -128.327045) (xy 14.75243 -128.27475)
			(xy 14.744674 -128.220802) (xy 11.760472 -128.220802) (xy 11.760472 -128.252801) (xy 11.752716 -128.306748)
			(xy 11.737361 -128.359043) (xy 11.71472 -128.40862) (xy 11.685254 -128.45447) (xy 11.649563 -128.49566)
			(xy 11.608373 -128.531352) (xy 11.562523 -128.560818) (xy 11.512947 -128.583459) (xy 11.460652 -128.598815)
			(xy 11.406705 -128.606572) (xy 11.379454 -128.607058) (xy 11.352084 -128.606571) (xy 11.297906 -128.598759)
			(xy 11.245403 -128.583276) (xy 11.195655 -128.560439) (xy 11.149688 -128.530718) (xy 11.128756 -128.513078)
			(xy 11.128502 -128.512824) (xy 11.121425 -128.507223) (xy 11.104501 -128.500987) (xy 11.095482 -128.500632)
			(xy 11.028426 -128.500632) (xy 11.01941 -128.500995) (xy 11.002492 -128.507238) (xy 10.995406 -128.512824)
			(xy 10.995152 -128.513078) (xy 10.974219 -128.530719) (xy 10.928251 -128.560443) (xy 10.878505 -128.583289)
			(xy 10.826003 -128.598785) (xy 10.771825 -128.606614) (xy 10.717083 -128.606614) (xy 10.662905 -128.598785)
			(xy 10.610403 -128.583289) (xy 10.560657 -128.560443) (xy 10.514689 -128.530719) (xy 10.493756 -128.513078)
			(xy 10.493502 -128.512824) (xy 10.486425 -128.507223) (xy 10.469501 -128.500987) (xy 10.460482 -128.500632)
			(xy 10.393426 -128.500632) (xy 10.38441 -128.500995) (xy 10.367492 -128.507238) (xy 10.360406 -128.512824)
			(xy 10.360406 -128.513078) (xy 10.360152 -128.513078) (xy 10.339208 -128.530703) (xy 10.293239 -128.560418)
			(xy 10.243495 -128.583257) (xy 10.190996 -128.598751) (xy 10.136822 -128.606582) (xy 10.109454 -128.607058)
			(xy 10.082201 -128.606595) (xy 10.02825 -128.598838) (xy 9.975951 -128.583483) (xy 9.926371 -128.56084)
			(xy 9.880517 -128.531373) (xy 9.839324 -128.495679) (xy 9.80363 -128.454486) (xy 9.774161 -128.408633)
			(xy 9.751519 -128.359052) (xy 9.736162 -128.306754) (xy 9.728405 -128.252803) (xy 5.06984 -128.252803)
			(xy 5.06984 -130.263949) (xy 34.1107 -130.263949) (xy 34.1107 -130.209451) (xy 34.118456 -130.155509)
			(xy 34.133809 -130.103219) (xy 34.156447 -130.053647) (xy 34.185909 -130.0078) (xy 34.221596 -129.966613)
			(xy 34.262781 -129.930923) (xy 34.308625 -129.901458) (xy 34.358197 -129.878817) (xy 34.410486 -129.863461)
			(xy 34.464427 -129.855702) (xy 34.491676 -129.855214) (xy 34.517585 -129.855641) (xy 34.568923 -129.862674)
			(xy 34.618838 -129.876589) (xy 34.666411 -129.897128) (xy 34.710769 -129.923914) (xy 34.751095 -129.956455)
			(xy 34.786648 -129.994152) (xy 34.802064 -130.01498) (xy 34.807808 -130.022307) (xy 34.823308 -130.032594)
			(xy 34.83229 -130.035046) (xy 34.86277 -130.041904) (xy 34.872045 -130.043667) (xy 34.89071 -130.040917)
			(xy 34.899092 -130.03657) (xy 34.92507 -130.022279) (xy 34.979921 -129.999767) (xy 35.037224 -129.98454)
			(xy 35.096015 -129.976853) (xy 35.12566 -129.976372) (xy 35.155303 -129.976876) (xy 35.214084 -129.984596)
			(xy 35.271383 -129.99982) (xy 35.326243 -130.022297) (xy 35.352228 -130.03657) (xy 35.360652 -130.04079)
			(xy 35.379273 -130.04354) (xy 35.38855 -130.041904) (xy 35.41903 -130.035046) (xy 35.428014 -130.032593)
			(xy 35.443522 -130.022317) (xy 35.449256 -130.01498) (xy 35.464669 -129.994148) (xy 35.50021 -129.956436)
			(xy 35.540532 -129.923885) (xy 35.58489 -129.897095) (xy 35.632469 -129.87656) (xy 35.68239 -129.862658)
			(xy 35.733734 -129.855646) (xy 35.759644 -129.855214) (xy 35.786895 -129.855659) (xy 35.840841 -129.863421)
			(xy 35.893133 -129.878781) (xy 35.942708 -129.901426) (xy 35.988555 -129.930895) (xy 36.027844 -129.964942)
			(xy 44.669708 -129.964942) (xy 44.673779 -129.90932) (xy 44.685905 -129.854883) (xy 44.705828 -129.802792)
			(xy 44.733124 -129.754157) (xy 44.76721 -129.710014) (xy 44.807359 -129.671305) (xy 44.852717 -129.638854)
			(xy 44.902317 -129.613353) (xy 44.955101 -129.595346) (xy 45.009944 -129.585216) (xy 45.065678 -129.583179)
			(xy 45.121115 -129.589279) (xy 45.175072 -129.603385) (xy 45.226401 -129.625197) (xy 45.274007 -129.654251)
			(xy 45.316875 -129.689926) (xy 45.354092 -129.731463) (xy 45.384865 -129.777976) (xy 45.408537 -129.828473)
			(xy 45.424605 -129.88188) (xy 45.432725 -129.937056) (xy 45.433234 -129.964942) (xy 46.650908 -129.964942)
			(xy 46.654979 -129.90932) (xy 46.667105 -129.854883) (xy 46.687028 -129.802792) (xy 46.714324 -129.754157)
			(xy 46.74841 -129.710014) (xy 46.788559 -129.671305) (xy 46.833917 -129.638854) (xy 46.883517 -129.613353)
			(xy 46.936301 -129.595346) (xy 46.991144 -129.585216) (xy 47.046878 -129.583179) (xy 47.102315 -129.589279)
			(xy 47.156272 -129.603385) (xy 47.207601 -129.625197) (xy 47.255207 -129.654251) (xy 47.290365 -129.68351)
			(xy 48.914302 -129.68351) (xy 48.918373 -129.627888) (xy 48.930499 -129.573451) (xy 48.950422 -129.52136)
			(xy 48.977718 -129.472725) (xy 49.011804 -129.428582) (xy 49.051953 -129.389873) (xy 49.097311 -129.357422)
			(xy 49.146911 -129.331921) (xy 49.199695 -129.313914) (xy 49.254538 -129.303784) (xy 49.310272 -129.301747)
			(xy 49.365709 -129.307847) (xy 49.419666 -129.321953) (xy 49.470995 -129.343765) (xy 49.518601 -129.372819)
			(xy 49.561469 -129.408494) (xy 49.598686 -129.450031) (xy 49.629459 -129.496544) (xy 49.653131 -129.547041)
			(xy 49.669199 -129.600448) (xy 49.677319 -129.655624) (xy 49.677828 -129.68351) (xy 49.677319 -129.711396)
			(xy 49.669199 -129.766572) (xy 49.653131 -129.819979) (xy 49.629459 -129.870476) (xy 49.598686 -129.916989)
			(xy 49.561469 -129.958526) (xy 49.553759 -129.964942) (xy 51.251102 -129.964942) (xy 51.255173 -129.90932)
			(xy 51.267299 -129.854883) (xy 51.287222 -129.802792) (xy 51.314518 -129.754157) (xy 51.348604 -129.710014)
			(xy 51.388753 -129.671305) (xy 51.434111 -129.638854) (xy 51.483711 -129.613353) (xy 51.536495 -129.595346)
			(xy 51.591338 -129.585216) (xy 51.647072 -129.583179) (xy 51.702509 -129.589279) (xy 51.756466 -129.603385)
			(xy 51.807795 -129.625197) (xy 51.855401 -129.654251) (xy 51.898269 -129.689926) (xy 51.935486 -129.731463)
			(xy 51.966259 -129.777976) (xy 51.989931 -129.828473) (xy 52.005999 -129.88188) (xy 52.014119 -129.937056)
			(xy 52.014628 -129.964942) (xy 52.014119 -129.992828) (xy 52.005999 -130.048004) (xy 51.989931 -130.101411)
			(xy 51.966259 -130.151908) (xy 51.935486 -130.198421) (xy 51.898269 -130.239958) (xy 51.855401 -130.275633)
			(xy 51.807795 -130.304687) (xy 51.756466 -130.326499) (xy 51.702509 -130.340605) (xy 51.647072 -130.346705)
			(xy 51.591338 -130.344668) (xy 51.536495 -130.334538) (xy 51.483711 -130.316531) (xy 51.434111 -130.29103)
			(xy 51.388753 -130.258579) (xy 51.348604 -130.21987) (xy 51.314518 -130.175727) (xy 51.287222 -130.127092)
			(xy 51.267299 -130.075001) (xy 51.255173 -130.020564) (xy 51.251102 -129.964942) (xy 49.553759 -129.964942)
			(xy 49.518601 -129.994201) (xy 49.470995 -130.023255) (xy 49.419666 -130.045067) (xy 49.365709 -130.059173)
			(xy 49.310272 -130.065273) (xy 49.254538 -130.063236) (xy 49.199695 -130.053106) (xy 49.146911 -130.035099)
			(xy 49.097311 -130.009598) (xy 49.051953 -129.977147) (xy 49.011804 -129.938438) (xy 48.977718 -129.894295)
			(xy 48.950422 -129.84566) (xy 48.930499 -129.793569) (xy 48.918373 -129.739132) (xy 48.914302 -129.68351)
			(xy 47.290365 -129.68351) (xy 47.298075 -129.689926) (xy 47.335292 -129.731463) (xy 47.366065 -129.777976)
			(xy 47.389737 -129.828473) (xy 47.405805 -129.88188) (xy 47.413925 -129.937056) (xy 47.414434 -129.964942)
			(xy 47.413925 -129.992828) (xy 47.405805 -130.048004) (xy 47.389737 -130.101411) (xy 47.366065 -130.151908)
			(xy 47.335292 -130.198421) (xy 47.298075 -130.239958) (xy 47.255207 -130.275633) (xy 47.207601 -130.304687)
			(xy 47.156272 -130.326499) (xy 47.102315 -130.340605) (xy 47.046878 -130.346705) (xy 46.991144 -130.344668)
			(xy 46.936301 -130.334538) (xy 46.883517 -130.316531) (xy 46.833917 -130.29103) (xy 46.788559 -130.258579)
			(xy 46.74841 -130.21987) (xy 46.714324 -130.175727) (xy 46.687028 -130.127092) (xy 46.667105 -130.075001)
			(xy 46.654979 -130.020564) (xy 46.650908 -129.964942) (xy 45.433234 -129.964942) (xy 45.432725 -129.992828)
			(xy 45.424605 -130.048004) (xy 45.408537 -130.101411) (xy 45.384865 -130.151908) (xy 45.354092 -130.198421)
			(xy 45.316875 -130.239958) (xy 45.274007 -130.275633) (xy 45.226401 -130.304687) (xy 45.175072 -130.326499)
			(xy 45.121115 -130.340605) (xy 45.065678 -130.346705) (xy 45.009944 -130.344668) (xy 44.955101 -130.334538)
			(xy 44.902317 -130.316531) (xy 44.852717 -130.29103) (xy 44.807359 -130.258579) (xy 44.76721 -130.21987)
			(xy 44.733124 -130.175727) (xy 44.705828 -130.127092) (xy 44.685905 -130.075001) (xy 44.673779 -130.020564)
			(xy 44.669708 -129.964942) (xy 36.027844 -129.964942) (xy 36.029743 -129.966588) (xy 36.065432 -130.00778)
			(xy 36.094895 -130.053631) (xy 36.117535 -130.103208) (xy 36.132888 -130.155502) (xy 36.140644 -130.209449)
			(xy 36.140644 -130.263951) (xy 36.132888 -130.317898) (xy 36.117535 -130.370192) (xy 36.094895 -130.419769)
			(xy 36.065432 -130.46562) (xy 36.029743 -130.506812) (xy 35.988555 -130.542505) (xy 35.942708 -130.571974)
			(xy 35.893133 -130.594619) (xy 35.840841 -130.609979) (xy 35.786895 -130.617741) (xy 35.759644 -130.61823)
			(xy 35.744851 -130.618092) (xy 35.715353 -130.615805) (xy 35.700716 -130.613658) (xy 35.689741 -130.612559)
			(xy 35.668552 -130.618603) (xy 35.659822 -130.625342) (xy 35.601148 -130.67538) (xy 35.593128 -130.682954)
			(xy 35.58391 -130.70297) (xy 35.583368 -130.713988) (xy 35.583368 -131.01828) (xy 35.583927 -131.029296)
			(xy 35.593133 -131.049312) (xy 35.601148 -131.056888) (xy 35.659822 -131.106926) (xy 35.668521 -131.113731)
			(xy 35.689734 -131.119791) (xy 35.700716 -131.11861) (xy 35.715354 -131.116473) (xy 35.744851 -131.114182)
			(xy 35.759644 -131.114038) (xy 35.786896 -131.114435) (xy 35.840846 -131.122197) (xy 35.893142 -131.137558)
			(xy 35.942719 -131.160205) (xy 35.98857 -131.189676) (xy 36.02976 -131.225371) (xy 36.065451 -131.266565)
			(xy 36.072551 -131.277614) (xy 48.088548 -131.277614) (xy 48.092619 -131.221992) (xy 48.104745 -131.167555)
			(xy 48.124668 -131.115464) (xy 48.151964 -131.066829) (xy 48.18605 -131.022686) (xy 48.226199 -130.983977)
			(xy 48.271557 -130.951526) (xy 48.321157 -130.926025) (xy 48.373941 -130.908018) (xy 48.428784 -130.897888)
			(xy 48.484518 -130.895851) (xy 48.539955 -130.901951) (xy 48.593912 -130.916057) (xy 48.645241 -130.937869)
			(xy 48.692847 -130.966923) (xy 48.735715 -131.002598) (xy 48.772932 -131.044135) (xy 48.803705 -131.090648)
			(xy 48.827377 -131.141145) (xy 48.843445 -131.194552) (xy 48.851565 -131.249728) (xy 48.852074 -131.277614)
			(xy 48.851565 -131.3055) (xy 48.843445 -131.360676) (xy 48.827377 -131.414083) (xy 48.803705 -131.46458)
			(xy 48.772932 -131.511093) (xy 48.735715 -131.55263) (xy 48.692847 -131.588305) (xy 48.645241 -131.617359)
			(xy 48.593912 -131.639171) (xy 48.539955 -131.653277) (xy 48.484518 -131.659377) (xy 48.428784 -131.65734)
			(xy 48.373941 -131.64721) (xy 48.321157 -131.629203) (xy 48.271557 -131.603702) (xy 48.226199 -131.571251)
			(xy 48.18605 -131.532542) (xy 48.151964 -131.488399) (xy 48.124668 -131.439764) (xy 48.104745 -131.387673)
			(xy 48.092619 -131.333236) (xy 48.088548 -131.277614) (xy 36.072551 -131.277614) (xy 36.094917 -131.312419)
			(xy 36.117557 -131.362) (xy 36.132912 -131.414297) (xy 36.140668 -131.468247) (xy 36.140668 -131.522753)
			(xy 36.132912 -131.576703) (xy 36.117557 -131.629) (xy 36.094917 -131.678581) (xy 36.065451 -131.724435)
			(xy 36.02976 -131.765629) (xy 35.98857 -131.801324) (xy 35.942719 -131.830795) (xy 35.893142 -131.853442)
			(xy 35.840846 -131.868803) (xy 35.786896 -131.876565) (xy 35.759644 -131.877054) (xy 35.733735 -131.876626)
			(xy 35.682396 -131.869594) (xy 35.632481 -131.855681) (xy 35.584907 -131.835143) (xy 35.540549 -131.808356)
			(xy 35.500223 -131.775815) (xy 35.464671 -131.738117) (xy 35.449256 -131.717288) (xy 35.443491 -131.709979)
			(xy 35.428007 -131.69968) (xy 35.41903 -131.697222) (xy 35.38855 -131.690364) (xy 35.379274 -131.688616)
			(xy 35.36061 -131.691357) (xy 35.352228 -131.695698) (xy 35.326245 -131.709979) (xy 35.271395 -131.732493)
			(xy 35.214095 -131.747724) (xy 35.155305 -131.755414) (xy 35.12566 -131.755896) (xy 35.096018 -131.755374)
			(xy 35.037237 -131.747659) (xy 34.979939 -131.732439) (xy 34.925078 -131.709968) (xy 34.899092 -131.695698)
			(xy 34.890684 -131.69144) (xy 34.87205 -131.688712) (xy 34.86277 -131.690364) (xy 34.83229 -131.697222)
			(xy 34.823301 -131.699662) (xy 34.807794 -131.709946) (xy 34.802064 -131.717288) (xy 34.786629 -131.738104)
			(xy 34.751093 -131.775818) (xy 34.710776 -131.808371) (xy 34.666421 -131.835163) (xy 34.618846 -131.855701)
			(xy 34.568927 -131.869605) (xy 34.517585 -131.876621) (xy 34.491676 -131.877054) (xy 34.464429 -131.876474)
			(xy 34.410491 -131.868716) (xy 34.358205 -131.853361) (xy 34.308637 -131.830721) (xy 34.262795 -131.801257)
			(xy 34.221613 -131.76557) (xy 34.185928 -131.724386) (xy 34.156468 -131.678542) (xy 34.133831 -131.628972)
			(xy 34.118479 -131.576686) (xy 34.110724 -131.522747) (xy 34.110724 -131.468253) (xy 34.118479 -131.414314)
			(xy 34.133831 -131.362028) (xy 34.156468 -131.312458) (xy 34.185928 -131.266614) (xy 34.221613 -131.22543)
			(xy 34.262795 -131.189743) (xy 34.308637 -131.160279) (xy 34.358205 -131.137639) (xy 34.410491 -131.122284)
			(xy 34.464429 -131.114526) (xy 34.491676 -131.114038) (xy 34.506469 -131.114174) (xy 34.535967 -131.116462)
			(xy 34.550604 -131.11861) (xy 34.561579 -131.119728) (xy 34.582769 -131.113672) (xy 34.591498 -131.106926)
			(xy 34.650172 -131.056888) (xy 34.65821 -131.04933) (xy 34.667417 -131.029302) (xy 34.667952 -131.01828)
			(xy 34.667952 -130.713988) (xy 34.667436 -130.702966) (xy 34.658203 -130.682949) (xy 34.650172 -130.67538)
			(xy 34.591498 -130.625342) (xy 34.582794 -130.618544) (xy 34.561585 -130.612481) (xy 34.550604 -130.613658)
			(xy 34.535965 -130.615794) (xy 34.506469 -130.618085) (xy 34.491676 -130.61823) (xy 34.464427 -130.617698)
			(xy 34.410486 -130.609939) (xy 34.358197 -130.594583) (xy 34.308625 -130.571942) (xy 34.262781 -130.542477)
			(xy 34.221596 -130.506787) (xy 34.185909 -130.4656) (xy 34.156447 -130.419753) (xy 34.133809 -130.370181)
			(xy 34.118456 -130.317891) (xy 34.1107 -130.263949) (xy 5.06984 -130.263949) (xy 5.06984 -131.447101)
			(xy 9.713452 -131.447101) (xy 9.713452 -131.392599) (xy 9.721208 -131.338652) (xy 9.736563 -131.286358)
			(xy 9.759204 -131.236782) (xy 9.78867 -131.190932) (xy 9.824361 -131.149742) (xy 9.86555 -131.114051)
			(xy 9.9114 -131.084585) (xy 9.960976 -131.061944) (xy 10.01327 -131.046589) (xy 10.067217 -131.038832)
			(xy 10.094468 -131.038346) (xy 10.121838 -131.03882) (xy 10.176017 -131.046634) (xy 10.228521 -131.062121)
			(xy 10.278268 -131.084961) (xy 10.324235 -131.114685) (xy 10.345166 -131.132326) (xy 10.34542 -131.13258)
			(xy 10.35249 -131.13819) (xy 10.36942 -131.144421) (xy 10.37844 -131.144772) (xy 10.445496 -131.144772)
			(xy 10.454513 -131.144419) (xy 10.471431 -131.13817) (xy 10.478516 -131.13258) (xy 10.478516 -131.132326)
			(xy 10.47877 -131.132326) (xy 10.499703 -131.114685) (xy 10.545671 -131.084961) (xy 10.595417 -131.062115)
			(xy 10.647919 -131.046619) (xy 10.702097 -131.03879) (xy 10.756839 -131.03879) (xy 10.811017 -131.046619)
			(xy 10.863519 -131.062115) (xy 10.913265 -131.084961) (xy 10.959233 -131.114685) (xy 10.980166 -131.132326)
			(xy 10.98042 -131.13258) (xy 10.98749 -131.13819) (xy 11.00442 -131.144421) (xy 11.01344 -131.144772)
			(xy 11.080496 -131.144772) (xy 11.089513 -131.144419) (xy 11.106431 -131.13817) (xy 11.113516 -131.13258)
			(xy 11.113516 -131.132326) (xy 11.11377 -131.132326) (xy 11.134706 -131.114692) (xy 11.180677 -131.084978)
			(xy 11.230424 -131.062141) (xy 11.282924 -131.046649) (xy 11.337099 -131.03882) (xy 11.364468 -131.038346)
			(xy 11.391721 -131.038801) (xy 11.445673 -131.046558) (xy 11.497972 -131.061914) (xy 11.547552 -131.084557)
			(xy 11.593406 -131.114025) (xy 11.6346 -131.149719) (xy 11.670294 -131.190912) (xy 11.699762 -131.236766)
			(xy 11.722405 -131.286347) (xy 11.737762 -131.338645) (xy 11.737945 -131.339921) (xy 14.668984 -131.339921)
			(xy 14.668984 -131.285419) (xy 14.67674 -131.23147) (xy 14.692096 -131.179175) (xy 14.714737 -131.129598)
			(xy 14.744203 -131.083747) (xy 14.779895 -131.042556) (xy 14.821085 -131.006864) (xy 14.866936 -130.977398)
			(xy 14.916513 -130.954756) (xy 14.968808 -130.939401) (xy 15.022757 -130.931644) (xy 15.050008 -130.931158)
			(xy 15.077379 -130.931605) (xy 15.13156 -130.939425) (xy 15.184063 -130.954918) (xy 15.23381 -130.977764)
			(xy 15.279775 -131.007494) (xy 15.300706 -131.025138) (xy 15.30096 -131.025392) (xy 15.308055 -131.030967)
			(xy 15.324965 -131.037221) (xy 15.33398 -131.037584) (xy 15.401036 -131.037584) (xy 15.410055 -131.037248)
			(xy 15.426972 -131.030986) (xy 15.434056 -131.025392) (xy 15.434056 -131.025138) (xy 15.43431 -131.025138)
			(xy 15.455243 -131.007497) (xy 15.501211 -130.977773) (xy 15.550957 -130.954927) (xy 15.603459 -130.939431)
			(xy 15.657637 -130.931602) (xy 15.712379 -130.931602) (xy 15.766557 -130.939431) (xy 15.819059 -130.954927)
			(xy 15.868805 -130.977773) (xy 15.914773 -131.007497) (xy 15.935706 -131.025138) (xy 15.93596 -131.025392)
			(xy 15.943055 -131.030967) (xy 15.959965 -131.037221) (xy 15.96898 -131.037584) (xy 16.036036 -131.037584)
			(xy 16.045055 -131.037248) (xy 16.061972 -131.030986) (xy 16.069056 -131.025392) (xy 16.069056 -131.025138)
			(xy 16.06931 -131.025138) (xy 16.090232 -131.007487) (xy 16.136207 -130.977775) (xy 16.185957 -130.954941)
			(xy 16.23846 -130.939453) (xy 16.292638 -130.931629) (xy 16.320008 -130.931158) (xy 16.347261 -130.931629)
			(xy 16.401211 -130.939386) (xy 16.453509 -130.954742) (xy 16.503089 -130.977384) (xy 16.548942 -131.006851)
			(xy 16.590134 -131.042545) (xy 16.625827 -131.083737) (xy 16.655295 -131.12959) (xy 16.677938 -131.179169)
			(xy 16.693294 -131.231467) (xy 16.701051 -131.285417) (xy 16.701051 -131.339923) (xy 16.693294 -131.393873)
			(xy 16.677938 -131.446171) (xy 16.655295 -131.49575) (xy 16.625827 -131.541603) (xy 16.590134 -131.582795)
			(xy 16.548942 -131.618489) (xy 16.503089 -131.647956) (xy 16.453509 -131.670598) (xy 16.401211 -131.685954)
			(xy 16.347261 -131.693711) (xy 16.320008 -131.694174) (xy 16.292638 -131.69371) (xy 16.238458 -131.685892)
			(xy 16.185955 -131.670403) (xy 16.136208 -131.647561) (xy 16.090241 -131.617836) (xy 16.06931 -131.600194)
			(xy 16.069056 -131.59994) (xy 16.061963 -131.594364) (xy 16.045051 -131.588112) (xy 16.036036 -131.587748)
			(xy 15.96898 -131.587748) (xy 15.959961 -131.588085) (xy 15.943043 -131.594345) (xy 15.93596 -131.59994)
			(xy 15.935706 -131.600194) (xy 15.914773 -131.617835) (xy 15.868805 -131.647559) (xy 15.819059 -131.670405)
			(xy 15.766557 -131.685901) (xy 15.712379 -131.69373) (xy 15.657637 -131.69373) (xy 15.603459 -131.685901)
			(xy 15.550957 -131.670405) (xy 15.501211 -131.647559) (xy 15.455243 -131.617835) (xy 15.43431 -131.600194)
			(xy 15.434056 -131.59994) (xy 15.426963 -131.594364) (xy 15.410051 -131.588112) (xy 15.401036 -131.587748)
			(xy 15.33398 -131.587748) (xy 15.324961 -131.588085) (xy 15.308043 -131.594345) (xy 15.30096 -131.59994)
			(xy 15.30096 -131.600194) (xy 15.300706 -131.600194) (xy 15.279782 -131.617843) (xy 15.233807 -131.647553)
			(xy 15.184057 -131.670388) (xy 15.131555 -131.685876) (xy 15.077378 -131.693702) (xy 15.050008 -131.694174)
			(xy 15.022757 -131.693696) (xy 14.968808 -131.685939) (xy 14.916513 -131.670584) (xy 14.866936 -131.647942)
			(xy 14.821085 -131.618476) (xy 14.779895 -131.582784) (xy 14.744203 -131.541593) (xy 14.714737 -131.495742)
			(xy 14.692096 -131.446165) (xy 14.67674 -131.39387) (xy 14.668984 -131.339921) (xy 11.737945 -131.339921)
			(xy 11.745519 -131.392597) (xy 11.745519 -131.447103) (xy 11.737762 -131.501055) (xy 11.722405 -131.553353)
			(xy 11.699762 -131.602934) (xy 11.670294 -131.648788) (xy 11.6346 -131.689981) (xy 11.593406 -131.725675)
			(xy 11.547552 -131.755143) (xy 11.497972 -131.777786) (xy 11.445673 -131.793142) (xy 11.391721 -131.800899)
			(xy 11.364468 -131.801362) (xy 11.337097 -131.800924) (xy 11.282916 -131.793101) (xy 11.230412 -131.777606)
			(xy 11.180666 -131.754757) (xy 11.1347 -131.725026) (xy 11.11377 -131.707382) (xy 11.113516 -131.707128)
			(xy 11.106435 -131.701534) (xy 11.089514 -131.695294) (xy 11.080496 -131.694936) (xy 11.01344 -131.694936)
			(xy 11.004424 -131.695304) (xy 10.987507 -131.701543) (xy 10.98042 -131.707128) (xy 10.980166 -131.707382)
			(xy 10.959233 -131.725023) (xy 10.913265 -131.754747) (xy 10.863519 -131.777593) (xy 10.811017 -131.793089)
			(xy 10.756839 -131.800918) (xy 10.702097 -131.800918) (xy 10.647919 -131.793089) (xy 10.595417 -131.777593)
			(xy 10.545671 -131.754747) (xy 10.499703 -131.725023) (xy 10.47877 -131.707382) (xy 10.478516 -131.707128)
			(xy 10.471435 -131.701534) (xy 10.454514 -131.695294) (xy 10.445496 -131.694936) (xy 10.37844 -131.694936)
			(xy 10.369424 -131.695304) (xy 10.352507 -131.701543) (xy 10.34542 -131.707128) (xy 10.34542 -131.707382)
			(xy 10.345166 -131.707382) (xy 10.324218 -131.725001) (xy 10.27825 -131.754716) (xy 10.228506 -131.777556)
			(xy 10.176009 -131.793052) (xy 10.121836 -131.800885) (xy 10.094468 -131.801362) (xy 10.067217 -131.800868)
			(xy 10.01327 -131.793111) (xy 9.960976 -131.777756) (xy 9.9114 -131.755115) (xy 9.86555 -131.725649)
			(xy 9.824361 -131.689958) (xy 9.78867 -131.648768) (xy 9.759204 -131.602918) (xy 9.736563 -131.553342)
			(xy 9.721208 -131.501048) (xy 9.713452 -131.447101) (xy 5.06984 -131.447101) (xy 5.06984 -133.443726)
			(xy 11.122914 -133.443726) (xy 11.123394 -133.417412) (xy 11.130626 -133.365284) (xy 11.144942 -133.314642)
			(xy 11.166072 -133.266442) (xy 11.193616 -133.221599) (xy 11.227053 -133.180959) (xy 11.246104 -133.162802)
			(xy 11.253507 -133.155282) (xy 11.26203 -133.136001) (xy 11.262614 -133.125464) (xy 11.262614 -133.050788)
			(xy 11.262101 -133.040237) (xy 11.253554 -133.020942) (xy 11.246104 -133.01345) (xy 11.227032 -132.995311)
			(xy 11.193576 -132.954678) (xy 11.166019 -132.909834) (xy 11.144884 -132.86163) (xy 11.13057 -132.81098)
			(xy 11.12335 -132.758843) (xy 11.122914 -132.732526) (xy 11.1234 -132.705275) (xy 11.131156 -132.651327)
			(xy 11.146511 -132.599032) (xy 11.169153 -132.549455) (xy 11.198619 -132.503605) (xy 11.23431 -132.462414)
			(xy 11.275501 -132.426723) (xy 11.321351 -132.397257) (xy 11.370928 -132.374615) (xy 11.423223 -132.35926)
			(xy 11.477171 -132.351504) (xy 11.531673 -132.351504) (xy 11.585621 -132.35926) (xy 11.637916 -132.374615)
			(xy 11.687493 -132.397257) (xy 11.733343 -132.426723) (xy 11.774534 -132.462414) (xy 11.810225 -132.503605)
			(xy 11.839691 -132.549455) (xy 11.862333 -132.599032) (xy 11.877688 -132.651327) (xy 11.885444 -132.705275)
			(xy 11.88593 -132.732526) (xy 11.88547 -132.75884) (xy 11.878233 -132.810969) (xy 11.863911 -132.861611)
			(xy 11.842777 -132.90981) (xy 11.81523 -132.954653) (xy 11.781791 -132.995293) (xy 11.76274 -133.01345)
			(xy 11.75532 -133.020957) (xy 11.746805 -133.040248) (xy 11.74623 -133.050788) (xy 11.74623 -133.125464)
			(xy 11.746756 -133.136014) (xy 11.755293 -133.15531) (xy 11.76274 -133.162802) (xy 11.773672 -133.173216)
			(xy 14.917674 -133.173216) (xy 14.918131 -133.145845) (xy 14.925949 -133.091665) (xy 14.941439 -133.039161)
			(xy 14.964283 -132.989414) (xy 14.994011 -132.943449) (xy 15.011654 -132.922518) (xy 15.011908 -132.922264)
			(xy 15.017475 -132.915164) (xy 15.023733 -132.898257) (xy 15.0241 -132.889244) (xy 15.0241 -132.822188)
			(xy 15.023749 -132.813171) (xy 15.017497 -132.796254) (xy 15.011908 -132.789168) (xy 15.011654 -132.789168)
			(xy 15.011654 -132.788914) (xy 14.994016 -132.767981) (xy 14.964302 -132.722009) (xy 14.941465 -132.672262)
			(xy 14.925974 -132.619761) (xy 14.918147 -132.565585) (xy 14.917674 -132.538216) (xy 14.91816 -132.510965)
			(xy 14.925916 -132.457017) (xy 14.941271 -132.404722) (xy 14.963913 -132.355145) (xy 14.993379 -132.309295)
			(xy 15.02907 -132.268104) (xy 15.070261 -132.232413) (xy 15.116111 -132.202947) (xy 15.165688 -132.180305)
			(xy 15.217983 -132.16495) (xy 15.271931 -132.157194) (xy 15.326433 -132.157194) (xy 15.380381 -132.16495)
			(xy 15.432676 -132.180305) (xy 15.482253 -132.202947) (xy 15.528103 -132.232413) (xy 15.569294 -132.268104)
			(xy 15.604985 -132.309295) (xy 15.634451 -132.355145) (xy 15.657093 -132.404722) (xy 15.672448 -132.457017)
			(xy 15.680204 -132.510965) (xy 15.68069 -132.538216) (xy 15.680236 -132.565587) (xy 15.672415 -132.619766)
			(xy 15.656924 -132.67227) (xy 15.634079 -132.722016) (xy 15.604352 -132.767983) (xy 15.58671 -132.788914)
			(xy 15.586456 -132.789168) (xy 15.580871 -132.796256) (xy 15.574625 -132.813172) (xy 15.574264 -132.822188)
			(xy 15.574264 -132.889244) (xy 15.574656 -132.898257) (xy 15.58088 -132.915174) (xy 15.586456 -132.922264)
			(xy 15.58671 -132.922264) (xy 15.58671 -132.922518) (xy 15.604326 -132.943469) (xy 15.634041 -132.989437)
			(xy 15.656881 -133.039179) (xy 15.672378 -133.091676) (xy 15.680212 -133.145848) (xy 15.68069 -133.173216)
			(xy 15.680204 -133.200467) (xy 15.672448 -133.254415) (xy 15.657093 -133.30671) (xy 15.634451 -133.356287)
			(xy 15.604985 -133.402137) (xy 15.569294 -133.443328) (xy 15.528103 -133.479019) (xy 15.482253 -133.508485)
			(xy 15.432676 -133.531127) (xy 15.380381 -133.546482) (xy 15.326433 -133.554238) (xy 15.271931 -133.554238)
			(xy 15.217983 -133.546482) (xy 15.165688 -133.531127) (xy 15.116111 -133.508485) (xy 15.070261 -133.479019)
			(xy 15.02907 -133.443328) (xy 14.993379 -133.402137) (xy 14.963913 -133.356287) (xy 14.941271 -133.30671)
			(xy 14.925916 -133.254415) (xy 14.91816 -133.200467) (xy 14.917674 -133.173216) (xy 11.773672 -133.173216)
			(xy 11.781797 -133.180956) (xy 11.815253 -133.221587) (xy 11.84281 -133.266428) (xy 11.863948 -133.314629)
			(xy 11.878266 -133.365276) (xy 11.885491 -133.41741) (xy 11.88593 -133.443726) (xy 11.885444 -133.470977)
			(xy 11.877688 -133.524925) (xy 11.862333 -133.57722) (xy 11.839691 -133.626797) (xy 11.810225 -133.672647)
			(xy 11.774534 -133.713838) (xy 11.733343 -133.749529) (xy 11.687493 -133.778995) (xy 11.637916 -133.801637)
			(xy 11.585621 -133.816992) (xy 11.531673 -133.824748) (xy 11.477171 -133.824748) (xy 11.423223 -133.816992)
			(xy 11.370928 -133.801637) (xy 11.321351 -133.778995) (xy 11.275501 -133.749529) (xy 11.23431 -133.713838)
			(xy 11.198619 -133.672647) (xy 11.169153 -133.626797) (xy 11.146511 -133.57722) (xy 11.131156 -133.524925)
			(xy 11.1234 -133.470977) (xy 11.122914 -133.443726) (xy 5.06984 -133.443726) (xy 5.06984 -134.042404)
			(xy 6.176008 -134.042404) (xy 6.180079 -133.986782) (xy 6.192205 -133.932345) (xy 6.212128 -133.880254)
			(xy 6.239424 -133.831619) (xy 6.27351 -133.787476) (xy 6.313659 -133.748767) (xy 6.359017 -133.716316)
			(xy 6.408617 -133.690815) (xy 6.461401 -133.672808) (xy 6.516244 -133.662678) (xy 6.571978 -133.660641)
			(xy 6.627415 -133.666741) (xy 6.681372 -133.680847) (xy 6.732701 -133.702659) (xy 6.780307 -133.731713)
			(xy 6.823175 -133.767388) (xy 6.860392 -133.808925) (xy 6.891165 -133.855438) (xy 6.914837 -133.905935)
			(xy 6.930905 -133.959342) (xy 6.939025 -134.014518) (xy 6.939534 -134.042404) (xy 6.939025 -134.07029)
			(xy 6.930905 -134.125466) (xy 6.914837 -134.178873) (xy 6.891165 -134.22937) (xy 6.860392 -134.275883)
			(xy 6.823175 -134.31742) (xy 6.780307 -134.353095) (xy 6.732701 -134.382149) (xy 6.681372 -134.403961)
			(xy 6.627415 -134.418067) (xy 6.571978 -134.424167) (xy 6.516244 -134.42213) (xy 6.461401 -134.412)
			(xy 6.408617 -134.393993) (xy 6.359017 -134.368492) (xy 6.313659 -134.336041) (xy 6.27351 -134.297332)
			(xy 6.239424 -134.253189) (xy 6.212128 -134.204554) (xy 6.192205 -134.152463) (xy 6.180079 -134.098026)
			(xy 6.176008 -134.042404) (xy 5.06984 -134.042404) (xy 5.06984 -135.058404) (xy 6.176008 -135.058404)
			(xy 6.180079 -135.002782) (xy 6.192205 -134.948345) (xy 6.212128 -134.896254) (xy 6.239424 -134.847619)
			(xy 6.27351 -134.803476) (xy 6.313659 -134.764767) (xy 6.359017 -134.732316) (xy 6.408617 -134.706815)
			(xy 6.461401 -134.688808) (xy 6.516244 -134.678678) (xy 6.571978 -134.676641) (xy 6.627415 -134.682741)
			(xy 6.681372 -134.696847) (xy 6.732701 -134.718659) (xy 6.780307 -134.747713) (xy 6.823175 -134.783388)
			(xy 6.860392 -134.824925) (xy 6.891165 -134.871438) (xy 6.914837 -134.921935) (xy 6.930905 -134.975342)
			(xy 6.939025 -135.030518) (xy 6.939534 -135.058404) (xy 6.939025 -135.08629) (xy 6.930905 -135.141466)
			(xy 6.930731 -135.142043) (xy 9.361887 -135.142043) (xy 9.361887 -135.087537) (xy 9.369644 -135.033586)
			(xy 9.385 -134.981289) (xy 9.407643 -134.931709) (xy 9.437111 -134.885856) (xy 9.472805 -134.844663)
			(xy 9.513997 -134.80897) (xy 9.55985 -134.779502) (xy 9.609431 -134.75686) (xy 9.661728 -134.741504)
			(xy 9.715679 -134.733747) (xy 9.742932 -134.733284) (xy 9.771849 -134.733819) (xy 9.82902 -134.74254)
			(xy 9.88422 -134.759793) (xy 9.936183 -134.785181) (xy 9.983717 -134.818123) (xy 10.025733 -134.857864)
			(xy 10.043922 -134.88035) (xy 10.051733 -134.889318) (xy 10.073184 -134.899517) (xy 10.08507 -134.899908)
			(xy 10.178542 -134.897876) (xy 10.199878 -134.8867) (xy 10.206736 -134.876794) (xy 10.22216 -134.855904)
			(xy 10.257734 -134.818076) (xy 10.298108 -134.785422) (xy 10.342538 -134.758545) (xy 10.390203 -134.737942)
			(xy 10.440221 -134.723993) (xy 10.491669 -134.716955) (xy 10.517632 -134.71652) (xy 10.545003 -134.716962)
			(xy 10.599183 -134.724785) (xy 10.651687 -134.74028) (xy 10.701433 -134.763127) (xy 10.747399 -134.792856)
			(xy 10.76833 -134.8105) (xy 10.768584 -134.810754) (xy 10.775666 -134.816346) (xy 10.792587 -134.822588)
			(xy 10.801604 -134.822946) (xy 10.86866 -134.822946) (xy 10.877676 -134.822582) (xy 10.894594 -134.81634)
			(xy 10.90168 -134.810754) (xy 10.90168 -134.8105) (xy 10.901934 -134.8105) (xy 10.922867 -134.792859)
			(xy 10.968835 -134.763135) (xy 11.018581 -134.740289) (xy 11.071083 -134.724793) (xy 11.125261 -134.716964)
			(xy 11.180003 -134.716964) (xy 11.234181 -134.724793) (xy 11.286683 -134.740289) (xy 11.336429 -134.763135)
			(xy 11.382397 -134.792859) (xy 11.40333 -134.8105) (xy 11.403584 -134.810754) (xy 11.410666 -134.816346)
			(xy 11.427587 -134.822588) (xy 11.436604 -134.822946) (xy 11.50366 -134.822946) (xy 11.512676 -134.822582)
			(xy 11.529594 -134.81634) (xy 11.53668 -134.810754) (xy 11.537188 -134.8105) (xy 11.549922 -134.799555)
			(xy 11.577013 -134.779714) (xy 11.59129 -134.770876) (xy 11.60018 -134.765542) (xy 11.612372 -134.748524)
			(xy 11.632692 -134.655306) (xy 11.628374 -134.634732) (xy 11.622532 -134.626096) (xy 11.606532 -134.602032)
			(xy 11.581188 -134.550101) (xy 11.563962 -134.494943) (xy 11.555248 -134.437819) (xy 11.554714 -134.408926)
			(xy 11.5552 -134.381675) (xy 11.562956 -134.327727) (xy 11.578311 -134.275432) (xy 11.600953 -134.225855)
			(xy 11.630419 -134.180005) (xy 11.66611 -134.138814) (xy 11.707301 -134.103123) (xy 11.753151 -134.073657)
			(xy 11.802728 -134.051015) (xy 11.855023 -134.03566) (xy 11.908971 -134.027904) (xy 11.963473 -134.027904)
			(xy 12.017421 -134.03566) (xy 12.069716 -134.051015) (xy 12.119293 -134.073657) (xy 12.165143 -134.103123)
			(xy 12.206334 -134.138814) (xy 12.242025 -134.180005) (xy 12.271491 -134.225855) (xy 12.294133 -134.275432)
			(xy 12.309488 -134.327727) (xy 12.317244 -134.381675) (xy 12.31773 -134.408926) (xy 12.31725 -134.437018)
			(xy 12.309019 -134.492596) (xy 12.292725 -134.546365) (xy 12.26872 -134.597162) (xy 12.237523 -134.643889)
			(xy 12.19981 -134.685533) (xy 12.156395 -134.721196) (xy 12.132564 -134.736078) (xy 12.123674 -134.741412)
			(xy 12.111482 -134.75843) (xy 12.091162 -134.851648) (xy 12.09548 -134.872222) (xy 12.101322 -134.880858)
			(xy 12.117309 -134.90493) (xy 12.142654 -134.956859) (xy 12.146763 -134.970012) (xy 13.979652 -134.970012)
			(xy 13.980112 -134.942641) (xy 13.98793 -134.888462) (xy 14.003419 -134.835958) (xy 14.026263 -134.786211)
			(xy 14.055989 -134.740245) (xy 14.073632 -134.719314) (xy 14.073886 -134.71906) (xy 14.079452 -134.711959)
			(xy 14.085712 -134.695053) (xy 14.086078 -134.68604) (xy 14.086078 -134.618984) (xy 14.085733 -134.609966)
			(xy 14.079478 -134.593049) (xy 14.073886 -134.585964) (xy 14.073632 -134.585964) (xy 14.073632 -134.58571)
			(xy 14.055989 -134.564781) (xy 14.026277 -134.518808) (xy 14.003441 -134.46906) (xy 13.987951 -134.416558)
			(xy 13.980125 -134.362381) (xy 13.979652 -134.335012) (xy 13.980138 -134.307761) (xy 13.987894 -134.253813)
			(xy 14.003249 -134.201518) (xy 14.025891 -134.151941) (xy 14.055357 -134.106091) (xy 14.091048 -134.0649)
			(xy 14.132239 -134.029209) (xy 14.178089 -133.999743) (xy 14.227666 -133.977101) (xy 14.279961 -133.961746)
			(xy 14.333909 -133.95399) (xy 14.388411 -133.95399) (xy 14.442359 -133.961746) (xy 14.494654 -133.977101)
			(xy 14.543265 -133.999302) (xy 15.289504 -133.999302) (xy 15.289504 -133.944798) (xy 15.29726 -133.89085)
			(xy 15.312616 -133.838555) (xy 15.335257 -133.788977) (xy 15.364724 -133.743126) (xy 15.400416 -133.701936)
			(xy 15.441606 -133.666244) (xy 15.487457 -133.636777) (xy 15.537035 -133.614136) (xy 15.58933 -133.59878)
			(xy 15.643278 -133.591024) (xy 15.67053 -133.590538) (xy 15.696845 -133.590973) (xy 15.748976 -133.598213)
			(xy 15.799619 -133.612538) (xy 15.847819 -133.633676) (xy 15.892661 -133.661228) (xy 15.933299 -133.694673)
			(xy 15.951454 -133.713728) (xy 15.958963 -133.721145) (xy 15.978252 -133.729663) (xy 15.988792 -133.730238)
			(xy 16.063468 -133.730238) (xy 16.074016 -133.729694) (xy 16.093311 -133.721168) (xy 16.100806 -133.713728)
			(xy 16.118971 -133.694682) (xy 16.159598 -133.661223) (xy 16.204436 -133.633662) (xy 16.252635 -133.612522)
			(xy 16.303281 -133.598203) (xy 16.355414 -133.590977) (xy 16.38173 -133.590538) (xy 16.408981 -133.591032)
			(xy 16.462928 -133.598788) (xy 16.515222 -133.614143) (xy 16.564799 -133.636784) (xy 16.610649 -133.66625)
			(xy 16.651839 -133.701941) (xy 16.68753 -133.743131) (xy 16.716996 -133.788981) (xy 16.739637 -133.838558)
			(xy 16.754992 -133.890852) (xy 16.762748 -133.944799) (xy 16.762748 -133.999301) (xy 16.754992 -134.053248)
			(xy 16.739637 -134.105542) (xy 16.716996 -134.155119) (xy 16.68753 -134.200969) (xy 16.651839 -134.242159)
			(xy 16.610649 -134.27785) (xy 16.564799 -134.307316) (xy 16.515222 -134.329957) (xy 16.462928 -134.345312)
			(xy 16.408981 -134.353068) (xy 16.38173 -134.353554) (xy 16.355414 -134.353148) (xy 16.303282 -134.345903)
			(xy 16.252638 -134.331572) (xy 16.204438 -134.310429) (xy 16.159597 -134.282871) (xy 16.11896 -134.249421)
			(xy 16.100806 -134.230364) (xy 16.093276 -134.222972) (xy 16.074003 -134.21444) (xy 16.063468 -134.213854)
			(xy 15.988792 -134.213854) (xy 15.978242 -134.214379) (xy 15.958948 -134.222919) (xy 15.951454 -134.230364)
			(xy 15.933326 -134.249447) (xy 15.892689 -134.282899) (xy 15.847843 -134.310453) (xy 15.799637 -134.331586)
			(xy 15.748985 -134.345898) (xy 15.696848 -134.353118) (xy 15.67053 -134.353554) (xy 15.643278 -134.353076)
			(xy 15.58933 -134.34532) (xy 15.537035 -134.329964) (xy 15.487457 -134.307323) (xy 15.441606 -134.277856)
			(xy 15.400416 -134.242164) (xy 15.364724 -134.200974) (xy 15.335257 -134.155123) (xy 15.312616 -134.105545)
			(xy 15.29726 -134.05325) (xy 15.289504 -133.999302) (xy 14.543265 -133.999302) (xy 14.544231 -133.999743)
			(xy 14.590081 -134.029209) (xy 14.631272 -134.0649) (xy 14.666963 -134.106091) (xy 14.696429 -134.151941)
			(xy 14.719071 -134.201518) (xy 14.734426 -134.253813) (xy 14.742182 -134.307761) (xy 14.742668 -134.335012)
			(xy 14.742217 -134.362383) (xy 14.734397 -134.416563) (xy 14.718904 -134.469066) (xy 14.696059 -134.518813)
			(xy 14.691562 -134.525766) (xy 16.9418 -134.525766) (xy 16.942246 -134.498395) (xy 16.950069 -134.444215)
			(xy 16.965563 -134.391712) (xy 16.988409 -134.341965) (xy 17.018137 -134.295999) (xy 17.03578 -134.275068)
			(xy 17.036034 -134.274814) (xy 17.041625 -134.26773) (xy 17.047868 -134.250811) (xy 17.048226 -134.241794)
			(xy 17.048226 -134.174738) (xy 17.047845 -134.165724) (xy 17.041614 -134.148807) (xy 17.036034 -134.141718)
			(xy 17.03578 -134.141718) (xy 17.03578 -134.141464) (xy 17.018108 -134.120557) (xy 16.988388 -134.074584)
			(xy 16.965548 -134.024833) (xy 16.950056 -133.972327) (xy 16.942232 -133.918146) (xy 16.942235 -133.863403)
			(xy 16.950067 -133.809223) (xy 16.965566 -133.756719) (xy 16.988413 -133.706971) (xy 17.018139 -133.661002)
			(xy 17.03578 -133.640068) (xy 17.036034 -133.639814) (xy 17.041625 -133.63273) (xy 17.047868 -133.615811)
			(xy 17.048226 -133.606794) (xy 17.048226 -133.539738) (xy 17.047845 -133.530724) (xy 17.041614 -133.513807)
			(xy 17.036034 -133.506718) (xy 17.03578 -133.506718) (xy 17.03578 -133.506464) (xy 17.018108 -133.485557)
			(xy 16.988388 -133.439584) (xy 16.965548 -133.389833) (xy 16.950056 -133.337327) (xy 16.942232 -133.283146)
			(xy 16.942235 -133.228403) (xy 16.950067 -133.174223) (xy 16.965566 -133.121719) (xy 16.988413 -133.071971)
			(xy 17.018139 -133.026002) (xy 17.03578 -133.005068) (xy 17.036034 -133.004814) (xy 17.041625 -132.99773)
			(xy 17.047868 -132.980811) (xy 17.048226 -132.971794) (xy 17.048226 -132.904738) (xy 17.047845 -132.895724)
			(xy 17.041614 -132.878807) (xy 17.036034 -132.871718) (xy 17.03578 -132.871718) (xy 17.03578 -132.871464)
			(xy 17.018154 -132.850521) (xy 16.988441 -132.804551) (xy 16.965603 -132.754806) (xy 16.950109 -132.702308)
			(xy 16.942276 -132.648134) (xy 16.9418 -132.620766) (xy 16.942401 -132.590572) (xy 16.951918 -132.530937)
			(xy 16.970709 -132.473546) (xy 16.998306 -132.419832) (xy 17.034019 -132.371134) (xy 17.055084 -132.349494)
			(xy 17.055338 -132.34924) (xy 17.061908 -132.341986) (xy 17.069481 -132.323958) (xy 17.07007 -132.314188)
			(xy 17.071086 -132.2324) (xy 17.063974 -132.214112) (xy 17.056862 -132.206746) (xy 17.037005 -132.185295)
			(xy 17.003411 -132.137461) (xy 16.977505 -132.085064) (xy 16.959893 -132.029328) (xy 16.950989 -131.971558)
			(xy 16.950436 -131.942332) (xy 16.950885 -131.915078) (xy 16.958639 -131.861124) (xy 16.973993 -131.808823)
			(xy 16.996635 -131.75924) (xy 17.026104 -131.713385) (xy 17.061799 -131.672191) (xy 17.102995 -131.636497)
			(xy 17.148851 -131.607029) (xy 17.198435 -131.584389) (xy 17.250736 -131.569036) (xy 17.30469 -131.561284)
			(xy 17.331944 -131.560824) (xy 17.359313 -131.561317) (xy 17.413491 -131.569127) (xy 17.465995 -131.58461)
			(xy 17.515742 -131.607446) (xy 17.56171 -131.637165) (xy 17.582642 -131.654804) (xy 17.582896 -131.655058)
			(xy 17.589975 -131.660656) (xy 17.606898 -131.666894) (xy 17.615916 -131.66725) (xy 17.682972 -131.66725)
			(xy 17.691989 -131.66689) (xy 17.708906 -131.660646) (xy 17.715992 -131.655058) (xy 17.715992 -131.654804)
			(xy 17.716246 -131.654804) (xy 17.737179 -131.637163) (xy 17.783147 -131.607439) (xy 17.832893 -131.584593)
			(xy 17.885395 -131.569097) (xy 17.939573 -131.561268) (xy 17.994315 -131.561268) (xy 18.048493 -131.569097)
			(xy 18.100995 -131.584593) (xy 18.150741 -131.607439) (xy 18.196709 -131.637163) (xy 18.217642 -131.654804)
			(xy 18.217896 -131.655058) (xy 18.224975 -131.660656) (xy 18.241898 -131.666894) (xy 18.250916 -131.66725)
			(xy 18.317972 -131.66725) (xy 18.326989 -131.66689) (xy 18.343906 -131.660646) (xy 18.350992 -131.655058)
			(xy 18.350992 -131.654804) (xy 18.351246 -131.654804) (xy 18.372179 -131.637163) (xy 18.418147 -131.607439)
			(xy 18.467893 -131.584593) (xy 18.520395 -131.569097) (xy 18.574573 -131.561268) (xy 18.629315 -131.561268)
			(xy 18.683493 -131.569097) (xy 18.735995 -131.584593) (xy 18.785741 -131.607439) (xy 18.831709 -131.637163)
			(xy 18.852642 -131.654804) (xy 18.852896 -131.655058) (xy 18.859975 -131.660656) (xy 18.876898 -131.666894)
			(xy 18.885916 -131.66725) (xy 18.952972 -131.66725) (xy 18.961989 -131.66689) (xy 18.978906 -131.660646)
			(xy 18.985992 -131.655058) (xy 18.985992 -131.654804) (xy 18.986246 -131.654804) (xy 19.007188 -131.637177)
			(xy 19.053158 -131.607464) (xy 19.102903 -131.584625) (xy 19.155402 -131.569131) (xy 19.209576 -131.5613)
			(xy 19.236944 -131.560824) (xy 19.264195 -131.561306) (xy 19.318143 -131.569063) (xy 19.370437 -131.584419)
			(xy 19.420014 -131.60706) (xy 19.465864 -131.636527) (xy 19.507054 -131.672218) (xy 19.542746 -131.713409)
			(xy 19.572212 -131.759259) (xy 19.594853 -131.808836) (xy 19.610208 -131.861131) (xy 19.617964 -131.915079)
			(xy 19.617964 -131.969581) (xy 19.610208 -132.023529) (xy 19.594853 -132.075824) (xy 19.572212 -132.125401)
			(xy 19.542746 -132.171251) (xy 19.507054 -132.212442) (xy 19.465864 -132.248133) (xy 19.420014 -132.2776)
			(xy 19.370437 -132.300241) (xy 19.318143 -132.315597) (xy 19.264195 -132.323354) (xy 19.236944 -132.32384)
			(xy 19.209574 -132.323363) (xy 19.155395 -132.31555) (xy 19.102891 -132.300064) (xy 19.053144 -132.277225)
			(xy 19.007177 -132.247501) (xy 18.986246 -132.22986) (xy 18.985992 -132.229606) (xy 18.978911 -132.224011)
			(xy 18.96199 -132.217769) (xy 18.952972 -132.217414) (xy 18.885916 -132.217414) (xy 18.8769 -132.217775)
			(xy 18.859982 -132.22402) (xy 18.852896 -132.229606) (xy 18.852896 -132.22986) (xy 18.852642 -132.22986)
			(xy 18.831709 -132.247501) (xy 18.785741 -132.277225) (xy 18.735995 -132.300071) (xy 18.683493 -132.315567)
			(xy 18.629315 -132.323396) (xy 18.574573 -132.323396) (xy 18.520395 -132.315567) (xy 18.467893 -132.300071)
			(xy 18.418147 -132.277225) (xy 18.372179 -132.247501) (xy 18.351246 -132.22986) (xy 18.350992 -132.229606)
			(xy 18.343911 -132.224011) (xy 18.32699 -132.217769) (xy 18.317972 -132.217414) (xy 18.250916 -132.217414)
			(xy 18.2419 -132.217775) (xy 18.224982 -132.22402) (xy 18.217896 -132.229606) (xy 18.217896 -132.22986)
			(xy 18.217642 -132.22986) (xy 18.1967 -132.247487) (xy 18.15073 -132.277202) (xy 18.100986 -132.300041)
			(xy 18.048487 -132.315535) (xy 17.994313 -132.323365) (xy 17.966944 -132.32384) (xy 17.937467 -132.323289)
			(xy 17.879213 -132.314225) (xy 17.823048 -132.296306) (xy 17.770309 -132.269958) (xy 17.722251 -132.23581)
			(xy 17.700752 -132.215636) (xy 17.693435 -132.209079) (xy 17.675261 -132.201649) (xy 17.665446 -132.201158)
			(xy 17.612106 -132.201158) (xy 17.600168 -132.213604) (xy 17.599914 -132.213858) (xy 17.593352 -132.221118)
			(xy 17.585772 -132.239142) (xy 17.585182 -132.24891) (xy 17.584166 -132.330698) (xy 17.591278 -132.348986)
			(xy 17.59839 -132.356352) (xy 17.618255 -132.377796) (xy 17.651846 -132.425633) (xy 17.67775 -132.478032)
			(xy 17.695359 -132.533769) (xy 17.704263 -132.59154) (xy 17.704816 -132.620766) (xy 17.70435 -132.648136)
			(xy 17.696536 -132.702316) (xy 17.681048 -132.75482) (xy 17.658205 -132.804567) (xy 17.628479 -132.850533)
			(xy 17.610836 -132.871464) (xy 17.610582 -132.871718) (xy 17.60498 -132.878794) (xy 17.598743 -132.895719)
			(xy 17.59839 -132.904738) (xy 17.59839 -132.971794) (xy 17.598752 -132.98081) (xy 17.604996 -132.997727)
			(xy 17.610582 -133.004814) (xy 17.610836 -133.004814) (xy 17.610836 -133.005068) (xy 17.628445 -133.026027)
			(xy 17.658174 -133.071989) (xy 17.681024 -133.121731) (xy 17.696524 -133.174229) (xy 17.704357 -133.228405)
			(xy 17.70436 -133.283144) (xy 17.696535 -133.337321) (xy 17.681042 -133.389821) (xy 17.658199 -133.439566)
			(xy 17.628476 -133.485532) (xy 17.610836 -133.506464) (xy 17.610582 -133.506718) (xy 17.60498 -133.513794)
			(xy 17.598743 -133.530719) (xy 17.59839 -133.539738) (xy 17.59839 -133.606794) (xy 17.598752 -133.61581)
			(xy 17.604996 -133.632727) (xy 17.610582 -133.639814) (xy 17.610836 -133.639814) (xy 17.610836 -133.640068)
			(xy 17.628445 -133.661027) (xy 17.658174 -133.706989) (xy 17.681024 -133.756731) (xy 17.696524 -133.809229)
			(xy 17.704357 -133.863405) (xy 17.70436 -133.918144) (xy 17.696535 -133.972321) (xy 17.681042 -134.024821)
			(xy 17.658199 -134.074566) (xy 17.628476 -134.120532) (xy 17.610836 -134.141464) (xy 17.610582 -134.141718)
			(xy 17.60498 -134.148794) (xy 17.598743 -134.165719) (xy 17.59839 -134.174738) (xy 17.59839 -134.241794)
			(xy 17.598752 -134.25081) (xy 17.604996 -134.267727) (xy 17.610582 -134.274814) (xy 17.610836 -134.274814)
			(xy 17.610836 -134.275068) (xy 17.628479 -134.295997) (xy 17.658189 -134.341971) (xy 17.681024 -134.391719)
			(xy 17.696514 -134.444221) (xy 17.704342 -134.498397) (xy 17.704816 -134.525766) (xy 17.70433 -134.553017)
			(xy 17.696574 -134.606965) (xy 17.681219 -134.65926) (xy 17.658577 -134.708837) (xy 17.629111 -134.754687)
			(xy 17.59342 -134.795878) (xy 17.552229 -134.831569) (xy 17.506379 -134.861035) (xy 17.456802 -134.883677)
			(xy 17.404507 -134.899032) (xy 17.350559 -134.906788) (xy 17.296057 -134.906788) (xy 17.242109 -134.899032)
			(xy 17.189814 -134.883677) (xy 17.140237 -134.861035) (xy 17.094387 -134.831569) (xy 17.053196 -134.795878)
			(xy 17.017505 -134.754687) (xy 16.988039 -134.708837) (xy 16.965397 -134.65926) (xy 16.950042 -134.606965)
			(xy 16.942286 -134.553017) (xy 16.9418 -134.525766) (xy 14.691562 -134.525766) (xy 14.666331 -134.564779)
			(xy 14.648688 -134.58571) (xy 14.648434 -134.585964) (xy 14.642849 -134.593051) (xy 14.636603 -134.609968)
			(xy 14.636242 -134.618984) (xy 14.636242 -134.68604) (xy 14.636571 -134.69506) (xy 14.642837 -134.711977)
			(xy 14.648434 -134.71906) (xy 14.648688 -134.71906) (xy 14.648688 -134.719314) (xy 14.666298 -134.740269)
			(xy 14.696015 -134.786235) (xy 14.718857 -134.835977) (xy 14.734354 -134.888473) (xy 14.74219 -134.942644)
			(xy 14.742668 -134.970012) (xy 14.742182 -134.997263) (xy 14.734426 -135.051211) (xy 14.719071 -135.103506)
			(xy 14.696429 -135.153083) (xy 14.666963 -135.198933) (xy 14.631272 -135.240124) (xy 14.590081 -135.275815)
			(xy 14.544231 -135.305281) (xy 14.494654 -135.327923) (xy 14.442359 -135.343278) (xy 14.42689 -135.345502)
			(xy 17.905704 -135.345502) (xy 17.905704 -135.290998) (xy 17.91346 -135.23705) (xy 17.928816 -135.184755)
			(xy 17.951457 -135.135177) (xy 17.980924 -135.089326) (xy 18.016616 -135.048136) (xy 18.057806 -135.012444)
			(xy 18.103657 -134.982977) (xy 18.153235 -134.960336) (xy 18.20553 -134.94498) (xy 18.259478 -134.937224)
			(xy 18.28673 -134.936738) (xy 18.313045 -134.937173) (xy 18.365176 -134.944413) (xy 18.415819 -134.958738)
			(xy 18.464019 -134.979876) (xy 18.508861 -135.007428) (xy 18.549499 -135.040873) (xy 18.567654 -135.059928)
			(xy 18.575163 -135.067345) (xy 18.594452 -135.075863) (xy 18.604992 -135.076438) (xy 18.679668 -135.076438)
			(xy 18.690216 -135.075894) (xy 18.709511 -135.067368) (xy 18.717006 -135.059928) (xy 18.735171 -135.040882)
			(xy 18.775798 -135.007423) (xy 18.820636 -134.979862) (xy 18.868835 -134.958722) (xy 18.919481 -134.944403)
			(xy 18.971614 -134.937177) (xy 18.99793 -134.936738) (xy 19.025181 -134.937232) (xy 19.079128 -134.944988)
			(xy 19.131422 -134.960343) (xy 19.180999 -134.982984) (xy 19.226849 -135.01245) (xy 19.268039 -135.048141)
			(xy 19.30373 -135.089331) (xy 19.333196 -135.135181) (xy 19.355837 -135.184758) (xy 19.371192 -135.237052)
			(xy 19.378948 -135.290999) (xy 19.378948 -135.345501) (xy 19.371192 -135.399448) (xy 19.355837 -135.451742)
			(xy 19.333196 -135.501319) (xy 19.30373 -135.547169) (xy 19.268039 -135.588359) (xy 19.226849 -135.62405)
			(xy 19.180999 -135.653516) (xy 19.131422 -135.676157) (xy 19.079128 -135.691512) (xy 19.025181 -135.699268)
			(xy 18.99793 -135.699754) (xy 18.971614 -135.699348) (xy 18.919482 -135.692103) (xy 18.868838 -135.677772)
			(xy 18.820638 -135.656629) (xy 18.775797 -135.629071) (xy 18.73516 -135.595621) (xy 18.717006 -135.576564)
			(xy 18.709476 -135.569172) (xy 18.690203 -135.56064) (xy 18.679668 -135.560054) (xy 18.604992 -135.560054)
			(xy 18.594442 -135.560579) (xy 18.575148 -135.569119) (xy 18.567654 -135.576564) (xy 18.549526 -135.595647)
			(xy 18.508889 -135.629099) (xy 18.464043 -135.656653) (xy 18.415837 -135.677786) (xy 18.365185 -135.692098)
			(xy 18.313048 -135.699318) (xy 18.28673 -135.699754) (xy 18.259478 -135.699276) (xy 18.20553 -135.69152)
			(xy 18.153235 -135.676164) (xy 18.103657 -135.653523) (xy 18.057806 -135.624056) (xy 18.016616 -135.588364)
			(xy 17.980924 -135.547174) (xy 17.951457 -135.501323) (xy 17.928816 -135.451745) (xy 17.91346 -135.39945)
			(xy 17.905704 -135.345502) (xy 14.42689 -135.345502) (xy 14.388411 -135.351034) (xy 14.333909 -135.351034)
			(xy 14.279961 -135.343278) (xy 14.227666 -135.327923) (xy 14.178089 -135.305281) (xy 14.132239 -135.275815)
			(xy 14.091048 -135.240124) (xy 14.055357 -135.198933) (xy 14.025891 -135.153083) (xy 14.003249 -135.103506)
			(xy 13.987894 -135.051211) (xy 13.980138 -134.997263) (xy 13.979652 -134.970012) (xy 12.146763 -134.970012)
			(xy 12.159883 -135.012014) (xy 12.168603 -135.069136) (xy 12.16914 -135.098028) (xy 12.168648 -135.125278)
			(xy 12.160889 -135.179224) (xy 12.145532 -135.231517) (xy 12.12289 -135.281092) (xy 12.093423 -135.326941)
			(xy 12.057733 -135.36813) (xy 12.016544 -135.403821) (xy 11.970696 -135.433288) (xy 11.921121 -135.45593)
			(xy 11.868828 -135.471288) (xy 11.814882 -135.479048) (xy 11.787632 -135.479536) (xy 11.760262 -135.479067)
			(xy 11.706082 -135.471252) (xy 11.653578 -135.455765) (xy 11.603831 -135.432923) (xy 11.557865 -135.403198)
			(xy 11.536934 -135.385556) (xy 11.53668 -135.385302) (xy 11.529603 -135.379701) (xy 11.512679 -135.373463)
			(xy 11.50366 -135.37311) (xy 11.436604 -135.37311) (xy 11.427587 -135.373467) (xy 11.41067 -135.379714)
			(xy 11.403584 -135.385302) (xy 11.403584 -135.385556) (xy 11.40333 -135.385556) (xy 11.382397 -135.403197)
			(xy 11.336429 -135.432921) (xy 11.286683 -135.455767) (xy 11.234181 -135.471263) (xy 11.180003 -135.479092)
			(xy 11.125261 -135.479092) (xy 11.071083 -135.471263) (xy 11.018581 -135.455767) (xy 10.968835 -135.432921)
			(xy 10.922867 -135.403197) (xy 10.901934 -135.385556) (xy 10.90168 -135.385302) (xy 10.894603 -135.379701)
			(xy 10.877679 -135.373463) (xy 10.86866 -135.37311) (xy 10.801604 -135.37311) (xy 10.792587 -135.373467)
			(xy 10.77567 -135.379714) (xy 10.768584 -135.385302) (xy 10.768584 -135.385556) (xy 10.76833 -135.385556)
			(xy 10.747392 -135.403188) (xy 10.701421 -135.432902) (xy 10.651676 -135.45574) (xy 10.599176 -135.471233)
			(xy 10.545001 -135.479062) (xy 10.517632 -135.479536) (xy 10.488715 -135.479019) (xy 10.431542 -135.470293)
			(xy 10.376342 -135.453037) (xy 10.32438 -135.427645) (xy 10.276847 -135.3947) (xy 10.234831 -135.354957)
			(xy 10.216642 -135.33247) (xy 10.208844 -135.323489) (xy 10.187383 -135.313296) (xy 10.175494 -135.312912)
			(xy 10.082022 -135.314944) (xy 10.060686 -135.32612) (xy 10.053828 -135.336026) (xy 10.038432 -135.356938)
			(xy 10.002853 -135.394764) (xy 9.962473 -135.427415) (xy 9.918038 -135.454289) (xy 9.87037 -135.474889)
			(xy 9.820348 -135.488834) (xy 9.768897 -135.495867) (xy 9.742932 -135.4963) (xy 9.715679 -135.495833)
			(xy 9.661728 -135.488076) (xy 9.609431 -135.47272) (xy 9.55985 -135.450078) (xy 9.513997 -135.42061)
			(xy 9.472805 -135.384917) (xy 9.437111 -135.343724) (xy 9.407643 -135.297871) (xy 9.385 -135.248291)
			(xy 9.369644 -135.195994) (xy 9.361887 -135.142043) (xy 6.930731 -135.142043) (xy 6.914837 -135.194873)
			(xy 6.891165 -135.24537) (xy 6.860392 -135.291883) (xy 6.823175 -135.33342) (xy 6.780307 -135.369095)
			(xy 6.732701 -135.398149) (xy 6.681372 -135.419961) (xy 6.627415 -135.434067) (xy 6.571978 -135.440167)
			(xy 6.516244 -135.43813) (xy 6.461401 -135.428) (xy 6.408617 -135.409993) (xy 6.359017 -135.384492)
			(xy 6.313659 -135.352041) (xy 6.27351 -135.313332) (xy 6.239424 -135.269189) (xy 6.212128 -135.220554)
			(xy 6.192205 -135.168463) (xy 6.180079 -135.114026) (xy 6.176008 -135.058404) (xy 5.06984 -135.058404)
			(xy 5.06984 -135.866886) (xy 8.43991 -135.866886) (xy 8.443981 -135.811264) (xy 8.456107 -135.756827)
			(xy 8.47603 -135.704736) (xy 8.503326 -135.656101) (xy 8.537412 -135.611958) (xy 8.577561 -135.573249)
			(xy 8.622919 -135.540798) (xy 8.672519 -135.515297) (xy 8.725303 -135.49729) (xy 8.780146 -135.48716)
			(xy 8.83588 -135.485123) (xy 8.891317 -135.491223) (xy 8.945274 -135.505329) (xy 8.996603 -135.527141)
			(xy 9.044209 -135.556195) (xy 9.087077 -135.59187) (xy 9.124294 -135.633407) (xy 9.155067 -135.67992)
			(xy 9.178739 -135.730417) (xy 9.194807 -135.783824) (xy 9.202927 -135.839) (xy 9.203436 -135.866886)
			(xy 9.202927 -135.894772) (xy 9.194807 -135.949948) (xy 9.178739 -136.003355) (xy 9.155067 -136.053852)
			(xy 9.124294 -136.100365) (xy 9.087077 -136.141902) (xy 9.044209 -136.177577) (xy 8.996603 -136.206631)
			(xy 8.945274 -136.228443) (xy 8.891317 -136.242549) (xy 8.83588 -136.248649) (xy 8.780146 -136.246612)
			(xy 8.725303 -136.236482) (xy 8.672519 -136.218475) (xy 8.622919 -136.192974) (xy 8.577561 -136.160523)
			(xy 8.537412 -136.121814) (xy 8.503326 -136.077671) (xy 8.47603 -136.029036) (xy 8.456107 -135.976945)
			(xy 8.443981 -135.922508) (xy 8.43991 -135.866886) (xy 5.06984 -135.866886) (xy 5.06984 -136.328404)
			(xy 6.176008 -136.328404) (xy 6.180079 -136.272782) (xy 6.192205 -136.218345) (xy 6.212128 -136.166254)
			(xy 6.239424 -136.117619) (xy 6.27351 -136.073476) (xy 6.313659 -136.034767) (xy 6.359017 -136.002316)
			(xy 6.408617 -135.976815) (xy 6.461401 -135.958808) (xy 6.516244 -135.948678) (xy 6.571978 -135.946641)
			(xy 6.627415 -135.952741) (xy 6.681372 -135.966847) (xy 6.732701 -135.988659) (xy 6.780307 -136.017713)
			(xy 6.823175 -136.053388) (xy 6.860392 -136.094925) (xy 6.891165 -136.141438) (xy 6.914837 -136.191935)
			(xy 6.930905 -136.245342) (xy 6.939025 -136.300518) (xy 6.939534 -136.328404) (xy 6.939025 -136.35629)
			(xy 6.930905 -136.411466) (xy 6.914837 -136.464873) (xy 6.891165 -136.51537) (xy 6.860392 -136.561883)
			(xy 6.823175 -136.60342) (xy 6.780307 -136.639095) (xy 6.732701 -136.668149) (xy 6.681372 -136.689961)
			(xy 6.627415 -136.704067) (xy 6.571978 -136.710167) (xy 6.516244 -136.70813) (xy 6.461401 -136.698)
			(xy 6.408617 -136.679993) (xy 6.359017 -136.654492) (xy 6.313659 -136.622041) (xy 6.27351 -136.583332)
			(xy 6.239424 -136.539189) (xy 6.212128 -136.490554) (xy 6.192205 -136.438463) (xy 6.180079 -136.384026)
			(xy 6.176008 -136.328404) (xy 5.06984 -136.328404) (xy 5.06984 -137.344404) (xy 6.176008 -137.344404)
			(xy 6.180079 -137.288782) (xy 6.192205 -137.234345) (xy 6.212128 -137.182254) (xy 6.239424 -137.133619)
			(xy 6.27351 -137.089476) (xy 6.313659 -137.050767) (xy 6.359017 -137.018316) (xy 6.408617 -136.992815)
			(xy 6.461401 -136.974808) (xy 6.516244 -136.964678) (xy 6.571978 -136.962641) (xy 6.627415 -136.968741)
			(xy 6.681372 -136.982847) (xy 6.732701 -137.004659) (xy 6.780307 -137.033713) (xy 6.823175 -137.069388)
			(xy 6.860392 -137.110925) (xy 6.891165 -137.157438) (xy 6.914837 -137.207935) (xy 6.930905 -137.261342)
			(xy 6.939025 -137.316518) (xy 6.939534 -137.344404) (xy 6.939025 -137.37229) (xy 6.930905 -137.427466)
			(xy 6.92464 -137.44829) (xy 8.345168 -137.44829) (xy 8.349239 -137.392668) (xy 8.361365 -137.338231)
			(xy 8.381288 -137.28614) (xy 8.408584 -137.237505) (xy 8.44267 -137.193362) (xy 8.482819 -137.154653)
			(xy 8.528177 -137.122202) (xy 8.577777 -137.096701) (xy 8.630561 -137.078694) (xy 8.685404 -137.068564)
			(xy 8.741138 -137.066527) (xy 8.796575 -137.072627) (xy 8.850532 -137.086733) (xy 8.901861 -137.108545)
			(xy 8.949467 -137.137599) (xy 8.992335 -137.173274) (xy 9.029552 -137.214811) (xy 9.060325 -137.261324)
			(xy 9.06736 -137.276332) (xy 13.047218 -137.276332) (xy 13.047698 -137.248962) (xy 13.055512 -137.194784)
			(xy 13.070998 -137.14228) (xy 13.093836 -137.092533) (xy 13.123558 -137.046566) (xy 13.141198 -137.025634)
			(xy 13.141452 -137.02538) (xy 13.147059 -137.018308) (xy 13.153292 -137.00138) (xy 13.153644 -136.99236)
			(xy 13.153644 -136.925304) (xy 13.153297 -136.916286) (xy 13.147044 -136.899368) (xy 13.141452 -136.892284)
			(xy 13.141198 -136.892284) (xy 13.141198 -136.89203) (xy 13.123559 -136.871098) (xy 13.093847 -136.825125)
			(xy 13.071011 -136.775377) (xy 13.05552 -136.722877) (xy 13.047692 -136.668701) (xy 13.047218 -136.641332)
			(xy 13.047704 -136.614081) (xy 13.05546 -136.560133) (xy 13.070815 -136.507838) (xy 13.093457 -136.458261)
			(xy 13.122923 -136.412411) (xy 13.158614 -136.37122) (xy 13.199805 -136.335529) (xy 13.245655 -136.306063)
			(xy 13.295232 -136.283421) (xy 13.347527 -136.268066) (xy 13.401475 -136.26031) (xy 13.455977 -136.26031)
			(xy 13.509925 -136.268066) (xy 13.56222 -136.283421) (xy 13.611797 -136.306063) (xy 13.657647 -136.335529)
			(xy 13.698838 -136.37122) (xy 13.734529 -136.412411) (xy 13.763995 -136.458261) (xy 13.786637 -136.507838)
			(xy 13.801992 -136.560133) (xy 13.809748 -136.614081) (xy 13.810234 -136.641332) (xy 13.809803 -136.668704)
			(xy 13.801979 -136.722885) (xy 13.786483 -136.775389) (xy 13.763633 -136.825135) (xy 13.7339 -136.8711)
			(xy 13.716254 -136.89203) (xy 13.716 -136.892284) (xy 13.710414 -136.899371) (xy 13.704167 -136.916287)
			(xy 13.703808 -136.925304) (xy 13.703808 -136.99236) (xy 13.704183 -137.001375) (xy 13.710418 -137.018292)
			(xy 13.716 -137.02538) (xy 13.716254 -137.02538) (xy 13.716254 -137.025634) (xy 13.733868 -137.046586)
			(xy 13.763586 -137.092553) (xy 13.786427 -137.142295) (xy 13.801924 -137.194792) (xy 13.809757 -137.248964)
			(xy 13.810234 -137.276332) (xy 13.809748 -137.303583) (xy 13.801992 -137.357531) (xy 13.786637 -137.409826)
			(xy 13.763995 -137.459403) (xy 13.734529 -137.505253) (xy 13.698838 -137.546444) (xy 13.657647 -137.582135)
			(xy 13.611797 -137.611601) (xy 13.56222 -137.634243) (xy 13.509925 -137.649598) (xy 13.455977 -137.657354)
			(xy 13.401475 -137.657354) (xy 13.347527 -137.649598) (xy 13.295232 -137.634243) (xy 13.245655 -137.611601)
			(xy 13.199805 -137.582135) (xy 13.158614 -137.546444) (xy 13.122923 -137.505253) (xy 13.093457 -137.459403)
			(xy 13.070815 -137.409826) (xy 13.05546 -137.357531) (xy 13.047704 -137.303583) (xy 13.047218 -137.276332)
			(xy 9.06736 -137.276332) (xy 9.083997 -137.311821) (xy 9.100065 -137.365228) (xy 9.108185 -137.420404)
			(xy 9.108694 -137.44829) (xy 9.108185 -137.476176) (xy 9.100065 -137.531352) (xy 9.083997 -137.584759)
			(xy 9.060325 -137.635256) (xy 9.029552 -137.681769) (xy 8.992335 -137.723306) (xy 8.988288 -137.726674)
			(xy 13.98778 -137.726674) (xy 13.988211 -137.699302) (xy 13.996035 -137.645121) (xy 14.011531 -137.592617)
			(xy 14.034381 -137.54287) (xy 14.064114 -137.496906) (xy 14.08176 -137.475976) (xy 14.082014 -137.475722)
			(xy 14.087599 -137.468634) (xy 14.093846 -137.451718) (xy 14.094206 -137.442702) (xy 14.094206 -137.375646)
			(xy 14.093826 -137.366631) (xy 14.087594 -137.349714) (xy 14.082014 -137.342626) (xy 14.08176 -137.342626)
			(xy 14.08176 -137.342372) (xy 14.064135 -137.321429) (xy 14.034422 -137.275459) (xy 14.011584 -137.225714)
			(xy 13.996089 -137.173216) (xy 13.988256 -137.119042) (xy 13.98778 -137.091674) (xy 13.988266 -137.064423)
			(xy 13.996022 -137.010475) (xy 14.011377 -136.95818) (xy 14.034019 -136.908603) (xy 14.063485 -136.862753)
			(xy 14.099176 -136.821562) (xy 14.140367 -136.785871) (xy 14.186217 -136.756405) (xy 14.235794 -136.733763)
			(xy 14.288089 -136.718408) (xy 14.342037 -136.710652) (xy 14.396539 -136.710652) (xy 14.450487 -136.718408)
			(xy 14.502782 -136.733763) (xy 14.552359 -136.756405) (xy 14.598209 -136.785871) (xy 14.6394 -136.821562)
			(xy 14.675091 -136.862753) (xy 14.704557 -136.908603) (xy 14.727199 -136.95818) (xy 14.742554 -137.010475)
			(xy 14.75031 -137.064423) (xy 14.750796 -137.091674) (xy 14.750316 -137.119044) (xy 14.742501 -137.173222)
			(xy 14.727016 -137.225725) (xy 14.704177 -137.275472) (xy 14.674456 -137.32144) (xy 14.656816 -137.342372)
			(xy 14.656562 -137.342626) (xy 14.650996 -137.349726) (xy 14.644738 -137.366633) (xy 14.64437 -137.375646)
			(xy 14.64437 -137.442702) (xy 14.644733 -137.451718) (xy 14.650977 -137.468635) (xy 14.656562 -137.475722)
			(xy 14.656816 -137.475722) (xy 14.656816 -137.475976) (xy 14.67446 -137.496904) (xy 14.70417 -137.542878)
			(xy 14.727005 -137.592627) (xy 14.742495 -137.645128) (xy 14.750322 -137.699305) (xy 14.750796 -137.726674)
			(xy 14.75031 -137.753925) (xy 14.742554 -137.807873) (xy 14.727199 -137.860168) (xy 14.704557 -137.909745)
			(xy 14.675091 -137.955595) (xy 14.6394 -137.996786) (xy 14.598209 -138.032477) (xy 14.552359 -138.061943)
			(xy 14.502782 -138.084585) (xy 14.450487 -138.09994) (xy 14.396539 -138.107696) (xy 14.342037 -138.107696)
			(xy 14.288089 -138.09994) (xy 14.235794 -138.084585) (xy 14.186217 -138.061943) (xy 14.140367 -138.032477)
			(xy 14.099176 -137.996786) (xy 14.063485 -137.955595) (xy 14.034019 -137.909745) (xy 14.011377 -137.860168)
			(xy 13.996022 -137.807873) (xy 13.988266 -137.753925) (xy 13.98778 -137.726674) (xy 8.988288 -137.726674)
			(xy 8.949467 -137.758981) (xy 8.901861 -137.788035) (xy 8.850532 -137.809847) (xy 8.796575 -137.823953)
			(xy 8.741138 -137.830053) (xy 8.685404 -137.828016) (xy 8.630561 -137.817886) (xy 8.577777 -137.799879)
			(xy 8.528177 -137.774378) (xy 8.482819 -137.741927) (xy 8.44267 -137.703218) (xy 8.408584 -137.659075)
			(xy 8.381288 -137.61044) (xy 8.361365 -137.558349) (xy 8.349239 -137.503912) (xy 8.345168 -137.44829)
			(xy 6.92464 -137.44829) (xy 6.914837 -137.480873) (xy 6.891165 -137.53137) (xy 6.860392 -137.577883)
			(xy 6.823175 -137.61942) (xy 6.780307 -137.655095) (xy 6.732701 -137.684149) (xy 6.681372 -137.705961)
			(xy 6.627415 -137.720067) (xy 6.571978 -137.726167) (xy 6.516244 -137.72413) (xy 6.461401 -137.714)
			(xy 6.408617 -137.695993) (xy 6.359017 -137.670492) (xy 6.313659 -137.638041) (xy 6.27351 -137.599332)
			(xy 6.239424 -137.555189) (xy 6.212128 -137.506554) (xy 6.192205 -137.454463) (xy 6.180079 -137.400026)
			(xy 6.176008 -137.344404) (xy 5.06984 -137.344404) (xy 5.06984 -138.360404) (xy 6.176008 -138.360404)
			(xy 6.180079 -138.304782) (xy 6.192205 -138.250345) (xy 6.212128 -138.198254) (xy 6.239424 -138.149619)
			(xy 6.27351 -138.105476) (xy 6.313659 -138.066767) (xy 6.359017 -138.034316) (xy 6.408617 -138.008815)
			(xy 6.461401 -137.990808) (xy 6.516244 -137.980678) (xy 6.571978 -137.978641) (xy 6.627415 -137.984741)
			(xy 6.681372 -137.998847) (xy 6.732701 -138.020659) (xy 6.780307 -138.049713) (xy 6.823175 -138.085388)
			(xy 6.860392 -138.126925) (xy 6.891165 -138.173438) (xy 6.914837 -138.223935) (xy 6.930905 -138.277342)
			(xy 6.939025 -138.332518) (xy 6.939534 -138.360404) (xy 6.939025 -138.38829) (xy 6.936812 -138.40333)
			(xy 15.196312 -138.40333) (xy 15.196842 -138.375665) (xy 15.204838 -138.320917) (xy 15.220651 -138.267895)
			(xy 15.243951 -138.217711) (xy 15.274249 -138.171415) (xy 15.310912 -138.129977) (xy 15.353172 -138.094264)
			(xy 15.376398 -138.079226) (xy 15.386055 -138.072565) (xy 15.398512 -138.052722) (xy 15.400274 -138.041126)
			(xy 15.408148 -137.961116) (xy 15.408763 -137.949478) (xy 15.400695 -137.927642) (xy 15.392654 -137.919206)
			(xy 15.3924 -137.918952) (xy 15.373813 -137.900876) (xy 15.341235 -137.860543) (xy 15.314423 -137.816168)
			(xy 15.293871 -137.768568) (xy 15.279959 -137.718623) (xy 15.272943 -137.667253) (xy 15.272512 -137.64133)
			(xy 15.272983 -137.614077) (xy 15.280737 -137.560125) (xy 15.29609 -137.507826) (xy 15.31873 -137.458245)
			(xy 15.348197 -137.412391) (xy 15.38389 -137.371197) (xy 15.425083 -137.335503) (xy 15.470936 -137.306035)
			(xy 15.520517 -137.283393) (xy 15.572816 -137.268039) (xy 15.626767 -137.260284) (xy 15.65402 -137.259822)
			(xy 15.681391 -137.260271) (xy 15.735571 -137.268092) (xy 15.788074 -137.283585) (xy 15.837821 -137.306431)
			(xy 15.883787 -137.336159) (xy 15.904718 -137.353802) (xy 15.904972 -137.354056) (xy 15.912058 -137.359644)
			(xy 15.928975 -137.365888) (xy 15.937992 -137.366248) (xy 16.005048 -137.366248) (xy 16.014064 -137.365877)
			(xy 16.030981 -137.359641) (xy 16.038068 -137.354056) (xy 16.038068 -137.353802) (xy 16.038322 -137.353802)
			(xy 16.059273 -137.336186) (xy 16.105241 -137.306471) (xy 16.154983 -137.28363) (xy 16.20748 -137.268134)
			(xy 16.261652 -137.260299) (xy 16.28902 -137.259822) (xy 16.316275 -137.260236) (xy 16.370229 -137.267997)
			(xy 16.42253 -137.283357) (xy 16.472112 -137.306004) (xy 16.517966 -137.335477) (xy 16.55916 -137.371176)
			(xy 16.594853 -137.412374) (xy 16.62432 -137.458232) (xy 16.646961 -137.507817) (xy 16.662314 -137.56012)
			(xy 16.670067 -137.614075) (xy 16.670528 -137.64133) (xy 16.669987 -137.670246) (xy 16.661266 -137.727418)
			(xy 16.644015 -137.782617) (xy 16.618627 -137.83458) (xy 16.585686 -137.882114) (xy 16.545947 -137.92413)
			(xy 16.523462 -137.94232) (xy 16.514649 -137.949922) (xy 16.50447 -137.970827) (xy 16.503904 -137.982452)
			(xy 16.503904 -138.062208) (xy 16.504451 -138.073839) (xy 16.514634 -138.094749) (xy 16.523462 -138.10234)
			(xy 16.545957 -138.120518) (xy 16.585693 -138.162539) (xy 16.618632 -138.210077) (xy 16.644019 -138.262041)
			(xy 16.661272 -138.317241) (xy 16.669996 -138.374413) (xy 16.670528 -138.40333) (xy 16.67005 -138.430581)
			(xy 16.66229 -138.484528) (xy 16.646932 -138.536822) (xy 16.624289 -138.586398) (xy 16.594821 -138.632247)
			(xy 16.559129 -138.673436) (xy 16.517939 -138.709127) (xy 16.472089 -138.738594) (xy 16.422512 -138.761236)
			(xy 16.370218 -138.776592) (xy 16.316271 -138.784351) (xy 16.28902 -138.784838) (xy 16.262706 -138.784377)
			(xy 16.210576 -138.777144) (xy 16.159932 -138.762825) (xy 16.111733 -138.741691) (xy 16.06689 -138.714143)
			(xy 16.026251 -138.680701) (xy 16.008096 -138.661648) (xy 16.000571 -138.65425) (xy 15.981294 -138.645722)
			(xy 15.970758 -138.645138) (xy 15.896082 -138.645138) (xy 15.885534 -138.645687) (xy 15.866238 -138.654207)
			(xy 15.858744 -138.661648) (xy 15.840618 -138.680733) (xy 15.799981 -138.714185) (xy 15.755134 -138.741739)
			(xy 15.706928 -138.762872) (xy 15.656276 -138.777184) (xy 15.604138 -138.784403) (xy 15.57782 -138.784838)
			(xy 15.550571 -138.784303) (xy 15.496626 -138.77655) (xy 15.444334 -138.761199) (xy 15.394759 -138.738563)
			(xy 15.34891 -138.709101) (xy 15.307721 -138.673415) (xy 15.272029 -138.63223) (xy 15.242561 -138.586385)
			(xy 15.219918 -138.536813) (xy 15.20456 -138.484523) (xy 15.1968 -138.430579) (xy 15.196312 -138.40333)
			(xy 6.936812 -138.40333) (xy 6.930905 -138.443466) (xy 6.914837 -138.496873) (xy 6.891165 -138.54737)
			(xy 6.860392 -138.593883) (xy 6.823175 -138.63542) (xy 6.780307 -138.671095) (xy 6.732701 -138.700149)
			(xy 6.681372 -138.721961) (xy 6.627415 -138.736067) (xy 6.571978 -138.742167) (xy 6.516244 -138.74013)
			(xy 6.461401 -138.73) (xy 6.408617 -138.711993) (xy 6.359017 -138.686492) (xy 6.313659 -138.654041)
			(xy 6.27351 -138.615332) (xy 6.239424 -138.571189) (xy 6.212128 -138.522554) (xy 6.192205 -138.470463)
			(xy 6.180079 -138.416026) (xy 6.176008 -138.360404) (xy 5.06984 -138.360404) (xy 5.06984 -138.824462)
			(xy 8.361932 -138.824462) (xy 8.366003 -138.76884) (xy 8.378129 -138.714403) (xy 8.398052 -138.662312)
			(xy 8.425348 -138.613677) (xy 8.459434 -138.569534) (xy 8.499583 -138.530825) (xy 8.544941 -138.498374)
			(xy 8.594541 -138.472873) (xy 8.647325 -138.454866) (xy 8.702168 -138.444736) (xy 8.757902 -138.442699)
			(xy 8.813339 -138.448799) (xy 8.867296 -138.462905) (xy 8.918625 -138.484717) (xy 8.966231 -138.513771)
			(xy 9.009099 -138.549446) (xy 9.046316 -138.590983) (xy 9.077089 -138.637496) (xy 9.100761 -138.687993)
			(xy 9.116829 -138.7414) (xy 9.124949 -138.796576) (xy 9.125458 -138.824462) (xy 9.124949 -138.852348)
			(xy 9.118699 -138.89482) (xy 12.277088 -138.89482) (xy 12.281159 -138.839198) (xy 12.293285 -138.784761)
			(xy 12.313208 -138.73267) (xy 12.340504 -138.684035) (xy 12.37459 -138.639892) (xy 12.414739 -138.601183)
			(xy 12.460097 -138.568732) (xy 12.509697 -138.543231) (xy 12.562481 -138.525224) (xy 12.617324 -138.515094)
			(xy 12.673058 -138.513057) (xy 12.728495 -138.519157) (xy 12.782452 -138.533263) (xy 12.833781 -138.555075)
			(xy 12.881387 -138.584129) (xy 12.924255 -138.619804) (xy 12.961472 -138.661341) (xy 12.992245 -138.707854)
			(xy 13.015917 -138.758351) (xy 13.031985 -138.811758) (xy 13.040105 -138.866934) (xy 13.040614 -138.89482)
			(xy 13.040105 -138.922706) (xy 13.031985 -138.977882) (xy 13.015917 -139.031289) (xy 12.992245 -139.081786)
			(xy 12.961472 -139.128299) (xy 12.924255 -139.169836) (xy 12.881387 -139.205511) (xy 12.833781 -139.234565)
			(xy 12.782452 -139.256377) (xy 12.728495 -139.270483) (xy 12.673058 -139.276583) (xy 12.617324 -139.274546)
			(xy 12.562481 -139.264416) (xy 12.509697 -139.246409) (xy 12.460097 -139.220908) (xy 12.414739 -139.188457)
			(xy 12.37459 -139.149748) (xy 12.340504 -139.105605) (xy 12.313208 -139.05697) (xy 12.293285 -139.004879)
			(xy 12.281159 -138.950442) (xy 12.277088 -138.89482) (xy 9.118699 -138.89482) (xy 9.116829 -138.907524)
			(xy 9.100761 -138.960931) (xy 9.077089 -139.011428) (xy 9.046316 -139.057941) (xy 9.009099 -139.099478)
			(xy 8.966231 -139.135153) (xy 8.918625 -139.164207) (xy 8.867296 -139.186019) (xy 8.813339 -139.200125)
			(xy 8.757902 -139.206225) (xy 8.702168 -139.204188) (xy 8.647325 -139.194058) (xy 8.594541 -139.176051)
			(xy 8.544941 -139.15055) (xy 8.499583 -139.118099) (xy 8.459434 -139.07939) (xy 8.425348 -139.035247)
			(xy 8.398052 -138.986612) (xy 8.378129 -138.934521) (xy 8.366003 -138.880084) (xy 8.361932 -138.824462)
			(xy 5.06984 -138.824462) (xy 5.06984 -139.376404) (xy 6.176008 -139.376404) (xy 6.180079 -139.320782)
			(xy 6.192205 -139.266345) (xy 6.212128 -139.214254) (xy 6.239424 -139.165619) (xy 6.27351 -139.121476)
			(xy 6.313659 -139.082767) (xy 6.359017 -139.050316) (xy 6.408617 -139.024815) (xy 6.461401 -139.006808)
			(xy 6.516244 -138.996678) (xy 6.571978 -138.994641) (xy 6.627415 -139.000741) (xy 6.681372 -139.014847)
			(xy 6.732701 -139.036659) (xy 6.780307 -139.065713) (xy 6.823175 -139.101388) (xy 6.860392 -139.142925)
			(xy 6.891165 -139.189438) (xy 6.914837 -139.239935) (xy 6.927773 -139.282932) (xy 16.938244 -139.282932)
			(xy 16.938754 -139.25414) (xy 16.947436 -139.197214) (xy 16.964578 -139.14224) (xy 16.989789 -139.090467)
			(xy 17.022498 -139.043074) (xy 17.061959 -139.001136) (xy 17.084294 -138.982958) (xy 17.092898 -138.975378)
			(xy 17.102912 -138.954782) (xy 17.103598 -138.943334) (xy 17.104106 -138.851894) (xy 17.093946 -138.830812)
			(xy 17.084802 -138.8237) (xy 17.062892 -138.805501) (xy 17.024216 -138.763691) (xy 16.992191 -138.716591)
			(xy 16.967531 -138.665251) (xy 16.950784 -138.610813) (xy 16.942323 -138.55449) (xy 16.9418 -138.526012)
			(xy 16.9418 -138.525758) (xy 16.9423 -138.498389) (xy 16.95011 -138.444211) (xy 16.965591 -138.391709)
			(xy 16.988425 -138.341961) (xy 17.018142 -138.295993) (xy 17.03578 -138.27506) (xy 17.036034 -138.274806)
			(xy 17.041628 -138.267725) (xy 17.047869 -138.250804) (xy 17.048226 -138.241786) (xy 17.048226 -138.17473)
			(xy 17.047849 -138.165715) (xy 17.041615 -138.148798) (xy 17.036034 -138.14171) (xy 17.03578 -138.14171)
			(xy 17.03578 -138.141456) (xy 17.018137 -138.120525) (xy 16.988412 -138.074557) (xy 16.965567 -138.02481)
			(xy 16.950071 -137.972308) (xy 16.942242 -137.918129) (xy 16.942242 -137.863388) (xy 16.950071 -137.809209)
			(xy 16.965568 -137.756707) (xy 16.988414 -137.70696) (xy 17.018139 -137.660993) (xy 17.03578 -137.64006)
			(xy 17.036034 -137.639806) (xy 17.041628 -137.632725) (xy 17.047869 -137.615804) (xy 17.048226 -137.606786)
			(xy 17.048226 -137.53973) (xy 17.047849 -137.530715) (xy 17.041615 -137.513798) (xy 17.036034 -137.50671)
			(xy 17.03578 -137.50671) (xy 17.03578 -137.506456) (xy 17.018137 -137.485525) (xy 16.988412 -137.439557)
			(xy 16.965567 -137.38981) (xy 16.950071 -137.337308) (xy 16.942242 -137.283129) (xy 16.942242 -137.228388)
			(xy 16.950071 -137.174209) (xy 16.965568 -137.121707) (xy 16.988414 -137.07196) (xy 17.018139 -137.025993)
			(xy 17.03578 -137.00506) (xy 17.036034 -137.004806) (xy 17.041628 -136.997725) (xy 17.047869 -136.980804)
			(xy 17.048226 -136.971786) (xy 17.048226 -136.90473) (xy 17.047849 -136.895715) (xy 17.041615 -136.878798)
			(xy 17.036034 -136.87171) (xy 17.03578 -136.87171) (xy 17.03578 -136.871456) (xy 17.018151 -136.850516)
			(xy 16.988438 -136.804545) (xy 16.9656 -136.7548) (xy 16.950107 -136.702301) (xy 16.942276 -136.648127)
			(xy 16.9418 -136.620758) (xy 16.942286 -136.593507) (xy 16.950042 -136.539559) (xy 16.965397 -136.487264)
			(xy 16.988039 -136.437687) (xy 17.017505 -136.391837) (xy 17.053196 -136.350646) (xy 17.094387 -136.314955)
			(xy 17.140237 -136.285489) (xy 17.189814 -136.262847) (xy 17.242109 -136.247492) (xy 17.296057 -136.239736)
			(xy 17.350559 -136.239736) (xy 17.404507 -136.247492) (xy 17.456802 -136.262847) (xy 17.506379 -136.285489)
			(xy 17.552229 -136.314955) (xy 17.59342 -136.350646) (xy 17.629111 -136.391837) (xy 17.658577 -136.437687)
			(xy 17.681219 -136.487264) (xy 17.696574 -136.539559) (xy 17.70433 -136.593507) (xy 17.704816 -136.620758)
			(xy 17.704346 -136.648128) (xy 17.696532 -136.702308) (xy 17.681045 -136.754812) (xy 17.658204 -136.804559)
			(xy 17.628478 -136.850525) (xy 17.610836 -136.871456) (xy 17.610582 -136.87171) (xy 17.604983 -136.878788)
			(xy 17.598744 -136.895711) (xy 17.59839 -136.90473) (xy 17.59839 -136.971786) (xy 17.598756 -136.980802)
			(xy 17.604998 -136.997719) (xy 17.610582 -137.004806) (xy 17.610836 -137.004806) (xy 17.610836 -137.00506)
			(xy 17.628475 -137.025994) (xy 17.658199 -137.071962) (xy 17.681045 -137.121708) (xy 17.696541 -137.17421)
			(xy 17.70437 -137.228388) (xy 17.70437 -137.283129) (xy 17.696541 -137.337307) (xy 17.681046 -137.389809)
			(xy 17.658201 -137.439555) (xy 17.628476 -137.485523) (xy 17.610836 -137.506456) (xy 17.610582 -137.50671)
			(xy 17.604983 -137.513788) (xy 17.598744 -137.530711) (xy 17.59839 -137.53973) (xy 17.59839 -137.606786)
			(xy 17.598756 -137.615802) (xy 17.604998 -137.632719) (xy 17.610582 -137.639806) (xy 17.610836 -137.639806)
			(xy 17.610836 -137.64006) (xy 17.628475 -137.660994) (xy 17.658199 -137.706962) (xy 17.681045 -137.756708)
			(xy 17.696541 -137.80921) (xy 17.70437 -137.863388) (xy 17.70437 -137.918129) (xy 17.696541 -137.972307)
			(xy 17.681046 -138.024809) (xy 17.658201 -138.074555) (xy 17.628476 -138.120523) (xy 17.610836 -138.141456)
			(xy 17.610582 -138.14171) (xy 17.604983 -138.148788) (xy 17.598744 -138.165711) (xy 17.59839 -138.17473)
			(xy 17.59839 -138.241786) (xy 17.598756 -138.250802) (xy 17.604998 -138.267719) (xy 17.610582 -138.274806)
			(xy 17.610836 -138.274806) (xy 17.610836 -138.27506) (xy 17.628475 -138.295992) (xy 17.658186 -138.341965)
			(xy 17.681021 -138.391713) (xy 17.696512 -138.444213) (xy 17.704341 -138.498389) (xy 17.704816 -138.525758)
			(xy 17.704314 -138.554551) (xy 17.695632 -138.611478) (xy 17.67849 -138.666453) (xy 17.653277 -138.718225)
			(xy 17.620567 -138.765619) (xy 17.581102 -138.807555) (xy 17.558766 -138.825732) (xy 17.550177 -138.833327)
			(xy 17.540152 -138.853911) (xy 17.539462 -138.865356) (xy 17.538954 -138.956796) (xy 17.549114 -138.977878)
			(xy 17.558258 -138.98499) (xy 17.57045 -138.995404) (xy 17.570704 -138.995658) (xy 17.57778 -139.001259)
			(xy 17.594705 -139.007496) (xy 17.603724 -139.00785) (xy 17.67078 -139.00785) (xy 17.679797 -139.007494)
			(xy 17.696715 -139.001247) (xy 17.7038 -138.995658) (xy 17.7038 -138.995404) (xy 17.704054 -138.995404)
			(xy 17.724987 -138.977763) (xy 17.770955 -138.948039) (xy 17.820701 -138.925193) (xy 17.873203 -138.909697)
			(xy 17.927381 -138.901868) (xy 17.982123 -138.901868) (xy 18.036301 -138.909697) (xy 18.088803 -138.925193)
			(xy 18.138549 -138.948039) (xy 18.184517 -138.977763) (xy 18.20545 -138.995404) (xy 18.205704 -138.995658)
			(xy 18.21278 -139.001259) (xy 18.229705 -139.007496) (xy 18.238724 -139.00785) (xy 18.30578 -139.00785)
			(xy 18.314797 -139.007494) (xy 18.331715 -139.001247) (xy 18.3388 -138.995658) (xy 18.3388 -138.995404)
			(xy 18.339054 -138.995404) (xy 18.359987 -138.977763) (xy 18.405955 -138.948039) (xy 18.455701 -138.925193)
			(xy 18.508203 -138.909697) (xy 18.562381 -138.901868) (xy 18.617123 -138.901868) (xy 18.671301 -138.909697)
			(xy 18.723803 -138.925193) (xy 18.773549 -138.948039) (xy 18.819517 -138.977763) (xy 18.84045 -138.995404)
			(xy 18.840704 -138.995658) (xy 18.84778 -139.001259) (xy 18.864705 -139.007496) (xy 18.873724 -139.00785)
			(xy 18.94078 -139.00785) (xy 18.949797 -139.007494) (xy 18.966715 -139.001247) (xy 18.9738 -138.995658)
			(xy 18.9738 -138.995404) (xy 18.974054 -138.995404) (xy 18.994993 -138.977774) (xy 19.040964 -138.94806)
			(xy 19.09071 -138.925223) (xy 19.143209 -138.90973) (xy 19.197383 -138.901899) (xy 19.224752 -138.901424)
			(xy 19.252003 -138.901906) (xy 19.305951 -138.909663) (xy 19.358246 -138.925018) (xy 19.407823 -138.947659)
			(xy 19.453674 -138.977126) (xy 19.494864 -139.012818) (xy 19.530555 -139.054008) (xy 19.560021 -139.099859)
			(xy 19.582663 -139.149436) (xy 19.598018 -139.201731) (xy 19.605774 -139.255679) (xy 19.605774 -139.310181)
			(xy 19.598018 -139.364129) (xy 19.582663 -139.416424) (xy 19.560021 -139.466001) (xy 19.530555 -139.511852)
			(xy 19.494864 -139.553042) (xy 19.453674 -139.588734) (xy 19.407823 -139.618201) (xy 19.358246 -139.640842)
			(xy 19.305951 -139.656197) (xy 19.252003 -139.663954) (xy 19.224752 -139.66444) (xy 19.197382 -139.663958)
			(xy 19.143203 -139.656146) (xy 19.0907 -139.640662) (xy 19.040952 -139.617823) (xy 18.994986 -139.588101)
			(xy 18.974054 -139.57046) (xy 18.9738 -139.570206) (xy 18.966717 -139.564614) (xy 18.949798 -139.55837)
			(xy 18.94078 -139.558014) (xy 18.873724 -139.558014) (xy 18.864708 -139.558379) (xy 18.847791 -139.564621)
			(xy 18.840704 -139.570206) (xy 18.84045 -139.57046) (xy 18.819517 -139.588101) (xy 18.773549 -139.617825)
			(xy 18.723803 -139.640671) (xy 18.671301 -139.656167) (xy 18.617123 -139.663996) (xy 18.562381 -139.663996)
			(xy 18.508203 -139.656167) (xy 18.455701 -139.640671) (xy 18.405955 -139.617825) (xy 18.359987 -139.588101)
			(xy 18.339054 -139.57046) (xy 18.3388 -139.570206) (xy 18.331717 -139.564614) (xy 18.314798 -139.55837)
			(xy 18.30578 -139.558014) (xy 18.238724 -139.558014) (xy 18.229708 -139.558379) (xy 18.212791 -139.564621)
			(xy 18.205704 -139.570206) (xy 18.205704 -139.57046) (xy 18.20545 -139.57046) (xy 18.184517 -139.588101)
			(xy 18.138549 -139.617825) (xy 18.088803 -139.640671) (xy 18.036301 -139.656167) (xy 17.982123 -139.663996)
			(xy 17.927381 -139.663996) (xy 17.873203 -139.656167) (xy 17.820701 -139.640671) (xy 17.770955 -139.617825)
			(xy 17.724987 -139.588101) (xy 17.704054 -139.57046) (xy 17.7038 -139.570206) (xy 17.696717 -139.564614)
			(xy 17.679798 -139.55837) (xy 17.67078 -139.558014) (xy 17.603724 -139.558014) (xy 17.594708 -139.558379)
			(xy 17.577791 -139.564621) (xy 17.570704 -139.570206) (xy 17.570704 -139.57046) (xy 17.57045 -139.57046)
			(xy 17.549505 -139.588083) (xy 17.503536 -139.617799) (xy 17.453792 -139.640638) (xy 17.401294 -139.656133)
			(xy 17.34712 -139.663964) (xy 17.319752 -139.66444) (xy 17.292501 -139.663967) (xy 17.238555 -139.656205)
			(xy 17.186262 -139.640845) (xy 17.136686 -139.618201) (xy 17.090838 -139.588732) (xy 17.049649 -139.55304)
			(xy 17.013958 -139.51185) (xy 16.984492 -139.466) (xy 16.961849 -139.416423) (xy 16.946492 -139.36413)
			(xy 16.938732 -139.310183) (xy 16.938244 -139.282932) (xy 6.927773 -139.282932) (xy 6.930905 -139.293342)
			(xy 6.939025 -139.348518) (xy 6.939534 -139.376404) (xy 6.939025 -139.40429) (xy 6.930905 -139.459466)
			(xy 6.914837 -139.512873) (xy 6.891165 -139.56337) (xy 6.860392 -139.609883) (xy 6.823175 -139.65142)
			(xy 6.780307 -139.687095) (xy 6.732701 -139.716149) (xy 6.681372 -139.737961) (xy 6.627415 -139.752067)
			(xy 6.571978 -139.758167) (xy 6.516244 -139.75613) (xy 6.461401 -139.746) (xy 6.408617 -139.727993)
			(xy 6.359017 -139.702492) (xy 6.313659 -139.670041) (xy 6.27351 -139.631332) (xy 6.239424 -139.587189)
			(xy 6.212128 -139.538554) (xy 6.192205 -139.486463) (xy 6.180079 -139.432026) (xy 6.176008 -139.376404)
			(xy 5.06984 -139.376404) (xy 5.06984 -140.392404) (xy 6.176008 -140.392404) (xy 6.180079 -140.336782)
			(xy 6.192205 -140.282345) (xy 6.212128 -140.230254) (xy 6.239424 -140.181619) (xy 6.27351 -140.137476)
			(xy 6.313659 -140.098767) (xy 6.359017 -140.066316) (xy 6.408617 -140.040815) (xy 6.461401 -140.022808)
			(xy 6.516244 -140.012678) (xy 6.571978 -140.010641) (xy 6.627415 -140.016741) (xy 6.681372 -140.030847)
			(xy 6.732701 -140.052659) (xy 6.780307 -140.081713) (xy 6.823175 -140.117388) (xy 6.860392 -140.158925)
			(xy 6.891165 -140.205438) (xy 6.914837 -140.255935) (xy 6.930905 -140.309342) (xy 6.939025 -140.364518)
			(xy 6.939534 -140.392404) (xy 8.367774 -140.392404) (xy 8.371845 -140.336782) (xy 8.383971 -140.282345)
			(xy 8.403894 -140.230254) (xy 8.43119 -140.181619) (xy 8.465276 -140.137476) (xy 8.505425 -140.098767)
			(xy 8.550783 -140.066316) (xy 8.600383 -140.040815) (xy 8.653167 -140.022808) (xy 8.70801 -140.012678)
			(xy 8.763744 -140.010641) (xy 8.819181 -140.016741) (xy 8.873138 -140.030847) (xy 8.924467 -140.052659)
			(xy 8.972073 -140.081713) (xy 9.014941 -140.117388) (xy 9.052158 -140.158925) (xy 9.082931 -140.205438)
			(xy 9.106603 -140.255935) (xy 9.122671 -140.309342) (xy 9.130791 -140.364518) (xy 9.1313 -140.392404)
			(xy 9.130791 -140.42029) (xy 9.122671 -140.475466) (xy 9.106603 -140.528873) (xy 9.082931 -140.57937)
			(xy 9.052158 -140.625883) (xy 9.014941 -140.66742) (xy 8.972073 -140.703095) (xy 8.924467 -140.732149)
			(xy 8.873138 -140.753961) (xy 8.819181 -140.768067) (xy 8.763744 -140.774167) (xy 8.70801 -140.77213)
			(xy 8.653167 -140.762) (xy 8.600383 -140.743993) (xy 8.550783 -140.718492) (xy 8.505425 -140.686041)
			(xy 8.465276 -140.647332) (xy 8.43119 -140.603189) (xy 8.403894 -140.554554) (xy 8.383971 -140.502463)
			(xy 8.371845 -140.448026) (xy 8.367774 -140.392404) (xy 6.939534 -140.392404) (xy 6.939025 -140.42029)
			(xy 6.930905 -140.475466) (xy 6.914837 -140.528873) (xy 6.891165 -140.57937) (xy 6.860392 -140.625883)
			(xy 6.823175 -140.66742) (xy 6.780307 -140.703095) (xy 6.732701 -140.732149) (xy 6.681372 -140.753961)
			(xy 6.627415 -140.768067) (xy 6.571978 -140.774167) (xy 6.516244 -140.77213) (xy 6.461401 -140.762)
			(xy 6.408617 -140.743993) (xy 6.359017 -140.718492) (xy 6.313659 -140.686041) (xy 6.27351 -140.647332)
			(xy 6.239424 -140.603189) (xy 6.212128 -140.554554) (xy 6.192205 -140.502463) (xy 6.180079 -140.448026)
			(xy 6.176008 -140.392404) (xy 5.06984 -140.392404) (xy 5.06984 -141.046533) (xy 8.977071 -141.046533)
			(xy 8.977071 -140.992027) (xy 8.984828 -140.938075) (xy 9.000185 -140.885777) (xy 9.022828 -140.836196)
			(xy 9.052296 -140.790342) (xy 9.08799 -140.749149) (xy 9.129184 -140.713455) (xy 9.175038 -140.683987)
			(xy 9.224618 -140.661344) (xy 9.276917 -140.645988) (xy 9.330869 -140.638231) (xy 9.358122 -140.637768)
			(xy 9.384436 -140.638231) (xy 9.436564 -140.645468) (xy 9.487207 -140.659789) (xy 9.535405 -140.680922)
			(xy 9.580249 -140.708469) (xy 9.620889 -140.741907) (xy 9.639046 -140.760958) (xy 9.646554 -140.768376)
			(xy 9.665844 -140.776892) (xy 9.676384 -140.777468) (xy 9.75106 -140.777468) (xy 9.76161 -140.77694)
			(xy 9.780906 -140.768405) (xy 9.788398 -140.760958) (xy 9.806553 -140.741902) (xy 9.847184 -140.708447)
			(xy 9.892025 -140.680889) (xy 9.940225 -140.659751) (xy 9.990872 -140.645433) (xy 10.043006 -140.638207)
			(xy 10.069322 -140.637768) (xy 10.096573 -140.638262) (xy 10.15052 -140.646019) (xy 10.202814 -140.661374)
			(xy 10.25239 -140.684015) (xy 10.29824 -140.713481) (xy 10.339429 -140.749172) (xy 10.37512 -140.790362)
			(xy 10.404586 -140.836212) (xy 10.427227 -140.885788) (xy 10.442582 -140.938082) (xy 10.450338 -140.992029)
			(xy 10.450338 -141.046531) (xy 10.450338 -141.046533) (xy 10.755071 -141.046533) (xy 10.755071 -140.992027)
			(xy 10.762828 -140.938075) (xy 10.778185 -140.885777) (xy 10.800828 -140.836196) (xy 10.830296 -140.790342)
			(xy 10.86599 -140.749149) (xy 10.907184 -140.713455) (xy 10.953038 -140.683987) (xy 11.002618 -140.661344)
			(xy 11.054917 -140.645988) (xy 11.108869 -140.638231) (xy 11.136122 -140.637768) (xy 11.162436 -140.638231)
			(xy 11.214564 -140.645468) (xy 11.265207 -140.659789) (xy 11.313405 -140.680922) (xy 11.358249 -140.708469)
			(xy 11.398889 -140.741907) (xy 11.417046 -140.760958) (xy 11.424554 -140.768376) (xy 11.443844 -140.776892)
			(xy 11.454384 -140.777468) (xy 11.52906 -140.777468) (xy 11.53961 -140.77694) (xy 11.558906 -140.768405)
			(xy 11.566398 -140.760958) (xy 11.584553 -140.741902) (xy 11.625184 -140.708447) (xy 11.670025 -140.680889)
			(xy 11.718225 -140.659751) (xy 11.768872 -140.645433) (xy 11.821006 -140.638207) (xy 11.847322 -140.637768)
			(xy 11.874573 -140.638262) (xy 11.92852 -140.646019) (xy 11.980814 -140.661374) (xy 12.03039 -140.684015)
			(xy 12.07624 -140.713481) (xy 12.117429 -140.749172) (xy 12.15312 -140.790362) (xy 12.182586 -140.836212)
			(xy 12.205227 -140.885788) (xy 12.220582 -140.938082) (xy 12.228338 -140.992029) (xy 12.228338 -141.046531)
			(xy 12.220582 -141.100478) (xy 12.205227 -141.152772) (xy 12.182586 -141.202348) (xy 12.15312 -141.248198)
			(xy 12.117429 -141.289388) (xy 12.07624 -141.325079) (xy 12.03039 -141.354545) (xy 11.980814 -141.377186)
			(xy 11.92852 -141.392541) (xy 11.874573 -141.400298) (xy 11.847322 -141.400784) (xy 11.821008 -141.400307)
			(xy 11.76888 -141.393075) (xy 11.718237 -141.378758) (xy 11.670038 -141.357627) (xy 11.625194 -141.330083)
			(xy 11.584555 -141.296645) (xy 11.566398 -141.277594) (xy 11.55888 -141.270189) (xy 11.539597 -141.261667)
			(xy 11.52906 -141.261084) (xy 11.454384 -141.261084) (xy 11.443832 -141.261596) (xy 11.424538 -141.270144)
			(xy 11.417046 -141.277594) (xy 11.398909 -141.296668) (xy 11.358275 -141.330123) (xy 11.313431 -141.35768)
			(xy 11.265227 -141.378815) (xy 11.214576 -141.393129) (xy 11.162439 -141.400348) (xy 11.136122 -141.400784)
			(xy 11.108869 -141.400329) (xy 11.054917 -141.392572) (xy 11.002618 -141.377216) (xy 10.953038 -141.354573)
			(xy 10.907184 -141.325105) (xy 10.86599 -141.289411) (xy 10.830296 -141.248218) (xy 10.800828 -141.202364)
			(xy 10.778185 -141.152783) (xy 10.762828 -141.100485) (xy 10.755071 -141.046533) (xy 10.450338 -141.046533)
			(xy 10.442582 -141.100478) (xy 10.427227 -141.152772) (xy 10.404586 -141.202348) (xy 10.37512 -141.248198)
			(xy 10.339429 -141.289388) (xy 10.29824 -141.325079) (xy 10.25239 -141.354545) (xy 10.202814 -141.377186)
			(xy 10.15052 -141.392541) (xy 10.096573 -141.400298) (xy 10.069322 -141.400784) (xy 10.043008 -141.400307)
			(xy 9.99088 -141.393075) (xy 9.940237 -141.378758) (xy 9.892038 -141.357627) (xy 9.847194 -141.330083)
			(xy 9.806555 -141.296645) (xy 9.788398 -141.277594) (xy 9.78088 -141.270189) (xy 9.761597 -141.261667)
			(xy 9.75106 -141.261084) (xy 9.676384 -141.261084) (xy 9.665832 -141.261596) (xy 9.646538 -141.270144)
			(xy 9.639046 -141.277594) (xy 9.620909 -141.296668) (xy 9.580275 -141.330123) (xy 9.535431 -141.35768)
			(xy 9.487227 -141.378815) (xy 9.436576 -141.393129) (xy 9.384439 -141.400348) (xy 9.358122 -141.400784)
			(xy 9.330869 -141.400329) (xy 9.276917 -141.392572) (xy 9.224618 -141.377216) (xy 9.175038 -141.354573)
			(xy 9.129184 -141.325105) (xy 9.08799 -141.289411) (xy 9.052296 -141.248218) (xy 9.022828 -141.202364)
			(xy 9.000185 -141.152783) (xy 8.984828 -141.100485) (xy 8.977071 -141.046533) (xy 5.06984 -141.046533)
			(xy 5.06984 -143.078533) (xy 8.977071 -143.078533) (xy 8.977071 -143.024027) (xy 8.984828 -142.970075)
			(xy 9.000185 -142.917777) (xy 9.022828 -142.868196) (xy 9.052296 -142.822342) (xy 9.08799 -142.781149)
			(xy 9.129184 -142.745455) (xy 9.175038 -142.715987) (xy 9.224618 -142.693344) (xy 9.276917 -142.677988)
			(xy 9.330869 -142.670231) (xy 9.358122 -142.669768) (xy 9.384436 -142.670231) (xy 9.436564 -142.677468)
			(xy 9.487207 -142.691789) (xy 9.535405 -142.712922) (xy 9.580249 -142.740469) (xy 9.620889 -142.773907)
			(xy 9.639046 -142.792958) (xy 9.646554 -142.800376) (xy 9.665844 -142.808892) (xy 9.676384 -142.809468)
			(xy 9.75106 -142.809468) (xy 9.76161 -142.80894) (xy 9.780906 -142.800405) (xy 9.788398 -142.792958)
			(xy 9.806553 -142.773902) (xy 9.847184 -142.740447) (xy 9.892025 -142.712889) (xy 9.940225 -142.691751)
			(xy 9.990872 -142.677433) (xy 10.043006 -142.670207) (xy 10.069322 -142.669768) (xy 10.096573 -142.670262)
			(xy 10.15052 -142.678019) (xy 10.202814 -142.693374) (xy 10.25239 -142.716015) (xy 10.29824 -142.745481)
			(xy 10.339429 -142.781172) (xy 10.37512 -142.822362) (xy 10.404586 -142.868212) (xy 10.427227 -142.917788)
			(xy 10.442582 -142.970082) (xy 10.450338 -143.024029) (xy 10.450338 -143.078531) (xy 10.450338 -143.078533)
			(xy 10.755071 -143.078533) (xy 10.755071 -143.024027) (xy 10.762828 -142.970075) (xy 10.778185 -142.917777)
			(xy 10.800828 -142.868196) (xy 10.830296 -142.822342) (xy 10.86599 -142.781149) (xy 10.907184 -142.745455)
			(xy 10.953038 -142.715987) (xy 11.002618 -142.693344) (xy 11.054917 -142.677988) (xy 11.108869 -142.670231)
			(xy 11.136122 -142.669768) (xy 11.162436 -142.670231) (xy 11.214564 -142.677468) (xy 11.265207 -142.691789)
			(xy 11.313405 -142.712922) (xy 11.358249 -142.740469) (xy 11.398889 -142.773907) (xy 11.417046 -142.792958)
			(xy 11.424554 -142.800376) (xy 11.443844 -142.808892) (xy 11.454384 -142.809468) (xy 11.52906 -142.809468)
			(xy 11.53961 -142.80894) (xy 11.558906 -142.800405) (xy 11.566398 -142.792958) (xy 11.584553 -142.773902)
			(xy 11.625184 -142.740447) (xy 11.670025 -142.712889) (xy 11.718225 -142.691751) (xy 11.768872 -142.677433)
			(xy 11.821006 -142.670207) (xy 11.847322 -142.669768) (xy 11.874573 -142.670262) (xy 11.92852 -142.678019)
			(xy 11.980814 -142.693374) (xy 12.03039 -142.716015) (xy 12.07624 -142.745481) (xy 12.117429 -142.781172)
			(xy 12.15312 -142.822362) (xy 12.182586 -142.868212) (xy 12.205227 -142.917788) (xy 12.220582 -142.970082)
			(xy 12.228338 -143.024029) (xy 12.228338 -143.078531) (xy 12.220582 -143.132478) (xy 12.205227 -143.184772)
			(xy 12.182586 -143.234348) (xy 12.15312 -143.280198) (xy 12.117429 -143.321388) (xy 12.07624 -143.357079)
			(xy 12.03039 -143.386545) (xy 11.980814 -143.409186) (xy 11.92852 -143.424541) (xy 11.874573 -143.432298)
			(xy 11.847322 -143.432784) (xy 11.821008 -143.432307) (xy 11.76888 -143.425075) (xy 11.718237 -143.410758)
			(xy 11.670038 -143.389627) (xy 11.625194 -143.362083) (xy 11.584555 -143.328645) (xy 11.566398 -143.309594)
			(xy 11.55888 -143.302189) (xy 11.539597 -143.293667) (xy 11.52906 -143.293084) (xy 11.454384 -143.293084)
			(xy 11.443832 -143.293596) (xy 11.424538 -143.302144) (xy 11.417046 -143.309594) (xy 11.398909 -143.328668)
			(xy 11.358275 -143.362123) (xy 11.313431 -143.38968) (xy 11.265227 -143.410815) (xy 11.214576 -143.425129)
			(xy 11.162439 -143.432348) (xy 11.136122 -143.432784) (xy 11.108869 -143.432329) (xy 11.054917 -143.424572)
			(xy 11.002618 -143.409216) (xy 10.953038 -143.386573) (xy 10.907184 -143.357105) (xy 10.86599 -143.321411)
			(xy 10.830296 -143.280218) (xy 10.800828 -143.234364) (xy 10.778185 -143.184783) (xy 10.762828 -143.132485)
			(xy 10.755071 -143.078533) (xy 10.450338 -143.078533) (xy 10.442582 -143.132478) (xy 10.427227 -143.184772)
			(xy 10.404586 -143.234348) (xy 10.37512 -143.280198) (xy 10.339429 -143.321388) (xy 10.29824 -143.357079)
			(xy 10.25239 -143.386545) (xy 10.202814 -143.409186) (xy 10.15052 -143.424541) (xy 10.096573 -143.432298)
			(xy 10.069322 -143.432784) (xy 10.043008 -143.432307) (xy 9.99088 -143.425075) (xy 9.940237 -143.410758)
			(xy 9.892038 -143.389627) (xy 9.847194 -143.362083) (xy 9.806555 -143.328645) (xy 9.788398 -143.309594)
			(xy 9.78088 -143.302189) (xy 9.761597 -143.293667) (xy 9.75106 -143.293084) (xy 9.676384 -143.293084)
			(xy 9.665832 -143.293596) (xy 9.646538 -143.302144) (xy 9.639046 -143.309594) (xy 9.620909 -143.328668)
			(xy 9.580275 -143.362123) (xy 9.535431 -143.38968) (xy 9.487227 -143.410815) (xy 9.436576 -143.425129)
			(xy 9.384439 -143.432348) (xy 9.358122 -143.432784) (xy 9.330869 -143.432329) (xy 9.276917 -143.424572)
			(xy 9.224618 -143.409216) (xy 9.175038 -143.386573) (xy 9.129184 -143.357105) (xy 9.08799 -143.321411)
			(xy 9.052296 -143.280218) (xy 9.022828 -143.234364) (xy 9.000185 -143.184783) (xy 8.984828 -143.132485)
			(xy 8.977071 -143.078533) (xy 5.06984 -143.078533) (xy 5.06984 -143.915638) (xy 19.464274 -143.915638)
			(xy 19.464775 -143.888065) (xy 19.472722 -143.833494) (xy 19.48844 -143.780635) (xy 19.511604 -143.730589)
			(xy 19.541729 -143.684399) (xy 19.57819 -143.643025) (xy 19.598894 -143.624808) (xy 19.606965 -143.617249)
			(xy 19.616322 -143.597241) (xy 19.616928 -143.5862) (xy 19.616928 -143.508476) (xy 19.616341 -143.497428)
			(xy 19.606991 -143.477406) (xy 19.598894 -143.469868) (xy 19.578163 -143.451679) (xy 19.541694 -143.410305)
			(xy 19.511565 -143.364111) (xy 19.488403 -143.314058) (xy 19.472691 -143.261192) (xy 19.464756 -143.206614)
			(xy 19.464274 -143.179038) (xy 19.464767 -143.150298) (xy 19.473398 -143.09347) (xy 19.490456 -143.038579)
			(xy 19.515554 -142.986868) (xy 19.548125 -142.939506) (xy 19.567398 -142.91818) (xy 19.574002 -142.911322)
			(xy 19.581114 -142.893288) (xy 19.581114 -142.804388) (xy 19.574002 -142.786354) (xy 19.567398 -142.779496)
			(xy 19.548166 -142.758136) (xy 19.515602 -142.710778) (xy 19.49051 -142.659072) (xy 19.473458 -142.604187)
			(xy 19.464833 -142.547364) (xy 19.464829 -142.489891) (xy 19.473446 -142.433068) (xy 19.490489 -142.37818)
			(xy 19.515574 -142.32647) (xy 19.548131 -142.279107) (xy 19.567398 -142.25778) (xy 19.574002 -142.250922)
			(xy 19.581114 -142.232888) (xy 19.581114 -142.143988) (xy 19.574002 -142.125954) (xy 19.567398 -142.119096)
			(xy 19.548166 -142.097736) (xy 19.515602 -142.050378) (xy 19.49051 -141.998672) (xy 19.473458 -141.943787)
			(xy 19.464833 -141.886964) (xy 19.464829 -141.829491) (xy 19.473446 -141.772668) (xy 19.490489 -141.71778)
			(xy 19.515574 -141.66607) (xy 19.548131 -141.618707) (xy 19.567398 -141.59738) (xy 19.574002 -141.590522)
			(xy 19.581114 -141.572488) (xy 19.581114 -141.483588) (xy 19.574002 -141.465554) (xy 19.567398 -141.458696)
			(xy 19.548166 -141.437336) (xy 19.515602 -141.389978) (xy 19.49051 -141.338272) (xy 19.473458 -141.283387)
			(xy 19.464833 -141.226564) (xy 19.464829 -141.169091) (xy 19.473446 -141.112268) (xy 19.490489 -141.05738)
			(xy 19.515574 -141.00567) (xy 19.548131 -140.958307) (xy 19.567398 -140.93698) (xy 19.574002 -140.930122)
			(xy 19.581114 -140.912088) (xy 19.581114 -140.823188) (xy 19.574002 -140.805154) (xy 19.567398 -140.798296)
			(xy 19.548156 -140.776944) (xy 19.515583 -140.72959) (xy 19.490484 -140.677885) (xy 19.473427 -140.622999)
			(xy 19.464798 -140.566175) (xy 19.464274 -140.537438) (xy 19.46476 -140.510187) (xy 19.472516 -140.456239)
			(xy 19.487871 -140.403944) (xy 19.510513 -140.354367) (xy 19.539979 -140.308517) (xy 19.57567 -140.267326)
			(xy 19.616861 -140.231635) (xy 19.662711 -140.202169) (xy 19.712288 -140.179527) (xy 19.764583 -140.164172)
			(xy 19.818531 -140.156416) (xy 19.873033 -140.156416) (xy 19.926981 -140.164172) (xy 19.979276 -140.179527)
			(xy 20.028853 -140.202169) (xy 20.074703 -140.231635) (xy 20.115894 -140.267326) (xy 20.151585 -140.308517)
			(xy 20.181051 -140.354367) (xy 20.203693 -140.403944) (xy 20.219048 -140.456239) (xy 20.226804 -140.510187)
			(xy 20.22729 -140.537438) (xy 20.226792 -140.566178) (xy 20.218164 -140.623007) (xy 20.201108 -140.677898)
			(xy 20.17601 -140.729609) (xy 20.143439 -140.77697) (xy 20.124166 -140.798296) (xy 20.117562 -140.805154)
			(xy 20.11045 -140.823188) (xy 20.11045 -140.912088) (xy 20.117562 -140.930122) (xy 20.124166 -140.93698)
			(xy 20.143475 -140.958274) (xy 20.17604 -141.005642) (xy 20.20113 -141.057359) (xy 20.218178 -141.112255)
			(xy 20.226797 -141.169087) (xy 20.226793 -141.226569) (xy 20.218165 -141.283399) (xy 20.20111 -141.338293)
			(xy 20.176012 -141.390006) (xy 20.14344 -141.437369) (xy 20.124166 -141.458696) (xy 20.117562 -141.465554)
			(xy 20.11045 -141.483588) (xy 20.11045 -141.572488) (xy 20.117562 -141.590522) (xy 20.124166 -141.59738)
			(xy 20.143475 -141.618674) (xy 20.17604 -141.666042) (xy 20.20113 -141.717759) (xy 20.218178 -141.772655)
			(xy 20.226797 -141.829487) (xy 20.226793 -141.886969) (xy 20.218165 -141.943799) (xy 20.20111 -141.998693)
			(xy 20.176012 -142.050406) (xy 20.14344 -142.097769) (xy 20.124166 -142.119096) (xy 20.117562 -142.125954)
			(xy 20.11045 -142.143988) (xy 20.11045 -142.232888) (xy 20.117562 -142.250922) (xy 20.124166 -142.25778)
			(xy 20.143475 -142.279074) (xy 20.17604 -142.326442) (xy 20.20113 -142.378159) (xy 20.218178 -142.433055)
			(xy 20.226797 -142.489887) (xy 20.226793 -142.547369) (xy 20.218165 -142.604199) (xy 20.20111 -142.659093)
			(xy 20.176012 -142.710806) (xy 20.14344 -142.758169) (xy 20.124166 -142.779496) (xy 20.117562 -142.786354)
			(xy 20.11045 -142.804388) (xy 20.11045 -142.893288) (xy 20.117562 -142.911322) (xy 20.124166 -142.91818)
			(xy 20.143455 -142.939491) (xy 20.176019 -142.986857) (xy 20.201108 -143.038573) (xy 20.218154 -143.093467)
			(xy 20.226772 -143.150298) (xy 20.22729 -143.179038) (xy 20.226785 -143.206611) (xy 20.218841 -143.261182)
			(xy 20.203124 -143.314042) (xy 20.179961 -143.364088) (xy 20.149836 -143.410279) (xy 20.113374 -143.451651)
			(xy 20.09267 -143.469868) (xy 20.084604 -143.477431) (xy 20.075246 -143.497437) (xy 20.074636 -143.508476)
			(xy 20.074636 -143.5862) (xy 20.075248 -143.597244) (xy 20.084581 -143.617266) (xy 20.09267 -143.624808)
			(xy 20.113382 -143.643018) (xy 20.149854 -143.684386) (xy 20.179987 -143.730576) (xy 20.203152 -143.780625)
			(xy 20.218868 -143.833488) (xy 20.226806 -143.888063) (xy 20.22729 -143.915638) (xy 20.226804 -143.942889)
			(xy 20.219048 -143.996837) (xy 20.203693 -144.049132) (xy 20.181051 -144.098709) (xy 20.151585 -144.144559)
			(xy 20.115894 -144.18575) (xy 20.074703 -144.221441) (xy 20.028853 -144.250907) (xy 19.979276 -144.273549)
			(xy 19.926981 -144.288904) (xy 19.873033 -144.29666) (xy 19.818531 -144.29666) (xy 19.764583 -144.288904)
			(xy 19.712288 -144.273549) (xy 19.662711 -144.250907) (xy 19.616861 -144.221441) (xy 19.57567 -144.18575)
			(xy 19.539979 -144.144559) (xy 19.510513 -144.098709) (xy 19.487871 -144.049132) (xy 19.472516 -143.996837)
			(xy 19.46476 -143.942889) (xy 19.464274 -143.915638) (xy 5.06984 -143.915638) (xy 5.06984 -145.110533)
			(xy 8.977071 -145.110533) (xy 8.977071 -145.056027) (xy 8.984828 -145.002075) (xy 9.000185 -144.949777)
			(xy 9.022828 -144.900196) (xy 9.052296 -144.854342) (xy 9.08799 -144.813149) (xy 9.129184 -144.777455)
			(xy 9.175038 -144.747987) (xy 9.224618 -144.725344) (xy 9.276917 -144.709988) (xy 9.330869 -144.702231)
			(xy 9.358122 -144.701768) (xy 9.384436 -144.702231) (xy 9.436564 -144.709468) (xy 9.487207 -144.723789)
			(xy 9.535405 -144.744922) (xy 9.580249 -144.772469) (xy 9.620889 -144.805907) (xy 9.639046 -144.824958)
			(xy 9.646554 -144.832376) (xy 9.665844 -144.840892) (xy 9.676384 -144.841468) (xy 9.75106 -144.841468)
			(xy 9.76161 -144.84094) (xy 9.780906 -144.832405) (xy 9.788398 -144.824958) (xy 9.806553 -144.805902)
			(xy 9.847184 -144.772447) (xy 9.892025 -144.744889) (xy 9.940225 -144.723751) (xy 9.990872 -144.709433)
			(xy 10.043006 -144.702207) (xy 10.069322 -144.701768) (xy 10.096573 -144.702262) (xy 10.15052 -144.710019)
			(xy 10.202814 -144.725374) (xy 10.25239 -144.748015) (xy 10.29824 -144.777481) (xy 10.339429 -144.813172)
			(xy 10.37512 -144.854362) (xy 10.404586 -144.900212) (xy 10.427227 -144.949788) (xy 10.442582 -145.002082)
			(xy 10.450338 -145.056029) (xy 10.450338 -145.110531) (xy 10.450338 -145.110533) (xy 10.755071 -145.110533)
			(xy 10.755071 -145.056027) (xy 10.762828 -145.002075) (xy 10.778185 -144.949777) (xy 10.800828 -144.900196)
			(xy 10.830296 -144.854342) (xy 10.86599 -144.813149) (xy 10.907184 -144.777455) (xy 10.953038 -144.747987)
			(xy 11.002618 -144.725344) (xy 11.054917 -144.709988) (xy 11.108869 -144.702231) (xy 11.136122 -144.701768)
			(xy 11.162436 -144.702231) (xy 11.214564 -144.709468) (xy 11.265207 -144.723789) (xy 11.313405 -144.744922)
			(xy 11.358249 -144.772469) (xy 11.398889 -144.805907) (xy 11.417046 -144.824958) (xy 11.424554 -144.832376)
			(xy 11.443844 -144.840892) (xy 11.454384 -144.841468) (xy 11.52906 -144.841468) (xy 11.53961 -144.84094)
			(xy 11.558906 -144.832405) (xy 11.566398 -144.824958) (xy 11.584553 -144.805902) (xy 11.625184 -144.772447)
			(xy 11.670025 -144.744889) (xy 11.718225 -144.723751) (xy 11.768872 -144.709433) (xy 11.821006 -144.702207)
			(xy 11.847322 -144.701768) (xy 11.874573 -144.702262) (xy 11.92852 -144.710019) (xy 11.980814 -144.725374)
			(xy 12.03039 -144.748015) (xy 12.07624 -144.777481) (xy 12.117429 -144.813172) (xy 12.15312 -144.854362)
			(xy 12.182586 -144.900212) (xy 12.205227 -144.949788) (xy 12.206535 -144.954244) (xy 17.939004 -144.954244)
			(xy 17.939496 -144.926992) (xy 17.947248 -144.873041) (xy 17.962599 -144.820743) (xy 17.985237 -144.771162)
			(xy 18.014701 -144.725308) (xy 18.050392 -144.684115) (xy 18.091583 -144.648421) (xy 18.137434 -144.618952)
			(xy 18.187013 -144.59631) (xy 18.23931 -144.580954) (xy 18.29326 -144.573199) (xy 18.320512 -144.572736)
			(xy 18.349288 -144.573223) (xy 18.406184 -144.581882) (xy 18.461135 -144.598986) (xy 18.512895 -144.624148)
			(xy 18.560289 -144.656798) (xy 18.581624 -144.676114) (xy 18.589498 -144.68348) (xy 18.60931 -144.690592)
			(xy 18.705576 -144.683226) (xy 18.724372 -144.67332) (xy 18.730976 -144.664938) (xy 18.749179 -144.642735)
			(xy 18.791119 -144.603525) (xy 18.838459 -144.571041) (xy 18.890131 -144.546016) (xy 18.944969 -144.529014)
			(xy 19.001735 -144.520419) (xy 19.030442 -144.519904) (xy 19.057695 -144.520339) (xy 19.111645 -144.528101)
			(xy 19.163941 -144.543462) (xy 19.21352 -144.566109) (xy 19.25937 -144.595581) (xy 19.30056 -144.631278)
			(xy 19.336251 -144.672473) (xy 19.365717 -144.718328) (xy 19.388357 -144.767909) (xy 19.40371 -144.820208)
			(xy 19.411465 -144.874159) (xy 19.41195 -144.901412) (xy 19.411476 -144.928314) (xy 19.403904 -144.981583)
			(xy 19.388925 -145.03326) (xy 19.366836 -145.082321) (xy 19.338076 -145.127793) (xy 19.303214 -145.168775)
			(xy 19.262942 -145.204455) (xy 19.240754 -145.219674) (xy 19.229832 -145.226786) (xy 19.217894 -145.249646)
			(xy 19.219926 -145.361914) (xy 19.23288 -145.384266) (xy 19.244056 -145.391124) (xy 19.267647 -145.406062)
			(xy 19.310602 -145.441736) (xy 19.347897 -145.483291) (xy 19.378737 -145.529838) (xy 19.402462 -145.580383)
			(xy 19.418566 -145.633847) (xy 19.426704 -145.689088) (xy 19.42719 -145.717006) (xy 19.426721 -145.743999)
			(xy 19.419116 -145.797446) (xy 19.404057 -145.849289) (xy 19.381845 -145.898494) (xy 19.352923 -145.944079)
			(xy 19.33575 -145.96491) (xy 19.328638 -145.973038) (xy 19.322542 -145.993612) (xy 19.333464 -146.078956)
			(xy 19.335269 -146.089493) (xy 19.346303 -146.107777) (xy 19.3548 -146.114262) (xy 19.376018 -146.129632)
			(xy 19.414469 -146.165218) (xy 19.447687 -146.205732) (xy 19.475047 -146.250413) (xy 19.496032 -146.298418)
			(xy 19.510249 -146.348843) (xy 19.517429 -146.40074) (xy 19.517868 -146.426936) (xy 19.517382 -146.454187)
			(xy 19.509626 -146.508135) (xy 19.494271 -146.56043) (xy 19.471629 -146.610007) (xy 19.442163 -146.655857)
			(xy 19.406472 -146.697048) (xy 19.365281 -146.732739) (xy 19.319431 -146.762205) (xy 19.269854 -146.784847)
			(xy 19.217559 -146.800202) (xy 19.163611 -146.807958) (xy 19.109109 -146.807958) (xy 19.055161 -146.800202)
			(xy 19.002866 -146.784847) (xy 18.953289 -146.762205) (xy 18.907439 -146.732739) (xy 18.866248 -146.697048)
			(xy 18.830557 -146.655857) (xy 18.801091 -146.610007) (xy 18.778449 -146.56043) (xy 18.763094 -146.508135)
			(xy 18.755338 -146.454187) (xy 18.754852 -146.426936) (xy 18.755335 -146.399943) (xy 18.762936 -146.346496)
			(xy 18.777991 -146.294653) (xy 18.8002 -146.245448) (xy 18.82912 -146.199863) (xy 18.846292 -146.179032)
			(xy 18.853404 -146.170904) (xy 18.8595 -146.15033) (xy 18.848578 -146.064986) (xy 18.846822 -146.054437)
			(xy 18.835755 -146.036156) (xy 18.827242 -146.02968) (xy 18.802936 -146.012074) (xy 18.75968 -145.970474)
			(xy 18.741136 -145.946876) (xy 18.735294 -145.939002) (xy 18.717768 -145.928588) (xy 18.627344 -145.91538)
			(xy 18.60804 -145.920206) (xy 18.600166 -145.926048) (xy 18.599912 -145.926048) (xy 18.575181 -145.943571)
			(xy 18.521324 -145.97137) (xy 18.463748 -145.990301) (xy 18.403902 -145.999887) (xy 18.373598 -146.00047)
			(xy 18.346343 -146.000046) (xy 18.292389 -145.992288) (xy 18.240088 -145.97693) (xy 18.190505 -145.954284)
			(xy 18.144651 -145.924813) (xy 18.103457 -145.889115) (xy 18.067763 -145.847917) (xy 18.038296 -145.802059)
			(xy 18.015656 -145.752474) (xy 18.000303 -145.700172) (xy 17.992551 -145.646217) (xy 17.99209 -145.618962)
			(xy 17.992513 -145.592928) (xy 17.999606 -145.541344) (xy 18.01364 -145.491201) (xy 18.034357 -145.443431)
			(xy 18.061371 -145.398917) (xy 18.077434 -145.378424) (xy 18.08318 -145.37067) (xy 18.088917 -145.352257)
			(xy 18.08861 -145.34261) (xy 18.08226 -145.262854) (xy 18.073624 -145.245074) (xy 18.066258 -145.238724)
			(xy 18.046611 -145.220544) (xy 18.012087 -145.179638) (xy 17.983617 -145.134309) (xy 17.961759 -145.085447)
			(xy 17.946943 -145.03401) (xy 17.939458 -144.981008) (xy 17.939004 -144.954244) (xy 12.206535 -144.954244)
			(xy 12.220582 -145.002082) (xy 12.228338 -145.056029) (xy 12.228338 -145.110531) (xy 12.220582 -145.164478)
			(xy 12.205227 -145.216772) (xy 12.182586 -145.266348) (xy 12.15312 -145.312198) (xy 12.117429 -145.353388)
			(xy 12.07624 -145.389079) (xy 12.03039 -145.418545) (xy 11.980814 -145.441186) (xy 11.92852 -145.456541)
			(xy 11.874573 -145.464298) (xy 11.847322 -145.464784) (xy 11.821008 -145.464307) (xy 11.76888 -145.457075)
			(xy 11.718237 -145.442758) (xy 11.670038 -145.421627) (xy 11.625194 -145.394083) (xy 11.584555 -145.360645)
			(xy 11.566398 -145.341594) (xy 11.55888 -145.334189) (xy 11.539597 -145.325667) (xy 11.52906 -145.325084)
			(xy 11.454384 -145.325084) (xy 11.443832 -145.325596) (xy 11.424538 -145.334144) (xy 11.417046 -145.341594)
			(xy 11.398909 -145.360668) (xy 11.358275 -145.394123) (xy 11.313431 -145.42168) (xy 11.265227 -145.442815)
			(xy 11.214576 -145.457129) (xy 11.162439 -145.464348) (xy 11.136122 -145.464784) (xy 11.108869 -145.464329)
			(xy 11.054917 -145.456572) (xy 11.002618 -145.441216) (xy 10.953038 -145.418573) (xy 10.907184 -145.389105)
			(xy 10.86599 -145.353411) (xy 10.830296 -145.312218) (xy 10.800828 -145.266364) (xy 10.778185 -145.216783)
			(xy 10.762828 -145.164485) (xy 10.755071 -145.110533) (xy 10.450338 -145.110533) (xy 10.442582 -145.164478)
			(xy 10.427227 -145.216772) (xy 10.404586 -145.266348) (xy 10.37512 -145.312198) (xy 10.339429 -145.353388)
			(xy 10.29824 -145.389079) (xy 10.25239 -145.418545) (xy 10.202814 -145.441186) (xy 10.15052 -145.456541)
			(xy 10.096573 -145.464298) (xy 10.069322 -145.464784) (xy 10.043008 -145.464307) (xy 9.99088 -145.457075)
			(xy 9.940237 -145.442758) (xy 9.892038 -145.421627) (xy 9.847194 -145.394083) (xy 9.806555 -145.360645)
			(xy 9.788398 -145.341594) (xy 9.78088 -145.334189) (xy 9.761597 -145.325667) (xy 9.75106 -145.325084)
			(xy 9.676384 -145.325084) (xy 9.665832 -145.325596) (xy 9.646538 -145.334144) (xy 9.639046 -145.341594)
			(xy 9.620909 -145.360668) (xy 9.580275 -145.394123) (xy 9.535431 -145.42168) (xy 9.487227 -145.442815)
			(xy 9.436576 -145.457129) (xy 9.384439 -145.464348) (xy 9.358122 -145.464784) (xy 9.330869 -145.464329)
			(xy 9.276917 -145.456572) (xy 9.224618 -145.441216) (xy 9.175038 -145.418573) (xy 9.129184 -145.389105)
			(xy 9.08799 -145.353411) (xy 9.052296 -145.312218) (xy 9.022828 -145.266364) (xy 9.000185 -145.216783)
			(xy 8.984828 -145.164485) (xy 8.977071 -145.110533) (xy 5.06984 -145.110533) (xy 5.06984 -145.562903)
			(xy 15.978585 -145.562903) (xy 15.978585 -145.508397) (xy 15.986342 -145.454446) (xy 16.001698 -145.402148)
			(xy 16.024341 -145.352568) (xy 16.053809 -145.306714) (xy 16.089503 -145.265522) (xy 16.130696 -145.229828)
			(xy 16.176549 -145.20036) (xy 16.22613 -145.177718) (xy 16.278428 -145.162362) (xy 16.332379 -145.154605)
			(xy 16.359632 -145.154142) (xy 16.385972 -145.154626) (xy 16.438151 -145.161873) (xy 16.488839 -145.176224)
			(xy 16.537072 -145.197407) (xy 16.581935 -145.22502) (xy 16.622577 -145.258539) (xy 16.658224 -145.297326)
			(xy 16.673576 -145.318734) (xy 16.682302 -145.330535) (xy 16.705118 -145.348976) (xy 16.732238 -145.360165)
			(xy 16.76142 -145.363177) (xy 16.790253 -145.357764) (xy 16.816355 -145.344373) (xy 16.83757 -145.32411)
			(xy 16.84528 -145.311622) (xy 16.859992 -145.287097) (xy 16.895591 -145.242338) (xy 16.937471 -145.203394)
			(xy 16.984695 -145.171137) (xy 17.036204 -145.14629) (xy 17.090845 -145.129408) (xy 17.147393 -145.120871)
			(xy 17.175988 -145.12036) (xy 17.203239 -145.120886) (xy 17.257187 -145.128641) (xy 17.309482 -145.143995)
			(xy 17.359059 -145.166635) (xy 17.40491 -145.1961) (xy 17.446101 -145.231791) (xy 17.481793 -145.27298)
			(xy 17.511259 -145.31883) (xy 17.533901 -145.368407) (xy 17.549256 -145.420701) (xy 17.557013 -145.474649)
			(xy 17.557013 -145.529151) (xy 17.549256 -145.583099) (xy 17.533901 -145.635393) (xy 17.511259 -145.68497)
			(xy 17.481793 -145.73082) (xy 17.446101 -145.772009) (xy 17.40491 -145.8077) (xy 17.359059 -145.837165)
			(xy 17.309482 -145.859805) (xy 17.257187 -145.875159) (xy 17.203239 -145.882914) (xy 17.175988 -145.883376)
			(xy 17.149646 -145.882945) (xy 17.097465 -145.875688) (xy 17.046776 -145.861327) (xy 16.998543 -145.840135)
			(xy 16.953681 -145.812514) (xy 16.913041 -145.778989) (xy 16.877395 -145.740195) (xy 16.862044 -145.718784)
			(xy 16.853284 -145.707014) (xy 16.830471 -145.68859) (xy 16.803361 -145.67741) (xy 16.774192 -145.674399)
			(xy 16.74537 -145.679803) (xy 16.719273 -145.693177) (xy 16.698055 -145.713418) (xy 16.69034 -145.725896)
			(xy 16.675621 -145.750416) (xy 16.640022 -145.795174) (xy 16.598143 -145.834117) (xy 16.55092 -145.866375)
			(xy 16.499412 -145.891223) (xy 16.444773 -145.908106) (xy 16.388226 -145.916646) (xy 16.359632 -145.917158)
			(xy 16.332379 -145.916695) (xy 16.278428 -145.908938) (xy 16.22613 -145.893582) (xy 16.176549 -145.87094)
			(xy 16.130696 -145.841472) (xy 16.089503 -145.805778) (xy 16.053809 -145.764586) (xy 16.024341 -145.718732)
			(xy 16.001698 -145.669152) (xy 15.986342 -145.616854) (xy 15.978585 -145.562903) (xy 5.06984 -145.562903)
			(xy 5.06984 -147.18665) (xy 17.837402 -147.18665) (xy 17.841473 -147.131028) (xy 17.853599 -147.076591)
			(xy 17.873522 -147.0245) (xy 17.900818 -146.975865) (xy 17.934904 -146.931722) (xy 17.975053 -146.893013)
			(xy 18.020411 -146.860562) (xy 18.070011 -146.835061) (xy 18.122795 -146.817054) (xy 18.177638 -146.806924)
			(xy 18.233372 -146.804887) (xy 18.288809 -146.810987) (xy 18.342766 -146.825093) (xy 18.394095 -146.846905)
			(xy 18.441701 -146.875959) (xy 18.484569 -146.911634) (xy 18.487468 -146.91487) (xy 19.616164 -146.91487)
			(xy 19.620235 -146.859248) (xy 19.632361 -146.804811) (xy 19.652284 -146.75272) (xy 19.67958 -146.704085)
			(xy 19.713666 -146.659942) (xy 19.753815 -146.621233) (xy 19.799173 -146.588782) (xy 19.848773 -146.563281)
			(xy 19.901557 -146.545274) (xy 19.9564 -146.535144) (xy 20.012134 -146.533107) (xy 20.067571 -146.539207)
			(xy 20.121528 -146.553313) (xy 20.172857 -146.575125) (xy 20.220463 -146.604179) (xy 20.263331 -146.639854)
			(xy 20.300548 -146.681391) (xy 20.331321 -146.727904) (xy 20.354993 -146.778401) (xy 20.371061 -146.831808)
			(xy 20.379181 -146.886984) (xy 20.37969 -146.91487) (xy 20.379181 -146.942756) (xy 20.371061 -146.997932)
			(xy 20.354993 -147.051339) (xy 20.349787 -147.062444) (xy 20.994368 -147.062444) (xy 20.998439 -147.006822)
			(xy 21.010565 -146.952385) (xy 21.030488 -146.900294) (xy 21.057784 -146.851659) (xy 21.09187 -146.807516)
			(xy 21.132019 -146.768807) (xy 21.177377 -146.736356) (xy 21.226977 -146.710855) (xy 21.279761 -146.692848)
			(xy 21.334604 -146.682718) (xy 21.390338 -146.680681) (xy 21.445775 -146.686781) (xy 21.499732 -146.700887)
			(xy 21.551061 -146.722699) (xy 21.598667 -146.751753) (xy 21.641535 -146.787428) (xy 21.678752 -146.828965)
			(xy 21.709525 -146.875478) (xy 21.733197 -146.925975) (xy 21.749265 -146.979382) (xy 21.757385 -147.034558)
			(xy 21.757894 -147.062444) (xy 21.757385 -147.09033) (xy 21.749265 -147.145506) (xy 21.733197 -147.198913)
			(xy 21.709525 -147.24941) (xy 21.678752 -147.295923) (xy 21.641535 -147.33746) (xy 21.598667 -147.373135)
			(xy 21.551061 -147.402189) (xy 21.499732 -147.424001) (xy 21.445775 -147.438107) (xy 21.390338 -147.444207)
			(xy 21.334604 -147.44217) (xy 21.279761 -147.43204) (xy 21.226977 -147.414033) (xy 21.177377 -147.388532)
			(xy 21.132019 -147.356081) (xy 21.09187 -147.317372) (xy 21.057784 -147.273229) (xy 21.030488 -147.224594)
			(xy 21.010565 -147.172503) (xy 20.998439 -147.118066) (xy 20.994368 -147.062444) (xy 20.349787 -147.062444)
			(xy 20.331321 -147.101836) (xy 20.300548 -147.148349) (xy 20.263331 -147.189886) (xy 20.220463 -147.225561)
			(xy 20.172857 -147.254615) (xy 20.121528 -147.276427) (xy 20.067571 -147.290533) (xy 20.012134 -147.296633)
			(xy 19.9564 -147.294596) (xy 19.901557 -147.284466) (xy 19.848773 -147.266459) (xy 19.799173 -147.240958)
			(xy 19.753815 -147.208507) (xy 19.713666 -147.169798) (xy 19.67958 -147.125655) (xy 19.652284 -147.07702)
			(xy 19.632361 -147.024929) (xy 19.620235 -146.970492) (xy 19.616164 -146.91487) (xy 18.487468 -146.91487)
			(xy 18.521786 -146.953171) (xy 18.552559 -146.999684) (xy 18.576231 -147.050181) (xy 18.592299 -147.103588)
			(xy 18.600419 -147.158764) (xy 18.600928 -147.18665) (xy 18.600419 -147.214536) (xy 18.592299 -147.269712)
			(xy 18.576231 -147.323119) (xy 18.552559 -147.373616) (xy 18.521786 -147.420129) (xy 18.484569 -147.461666)
			(xy 18.441701 -147.497341) (xy 18.394095 -147.526395) (xy 18.342766 -147.548207) (xy 18.288809 -147.562313)
			(xy 18.233372 -147.568413) (xy 18.177638 -147.566376) (xy 18.122795 -147.556246) (xy 18.070011 -147.538239)
			(xy 18.020411 -147.512738) (xy 17.975053 -147.480287) (xy 17.934904 -147.441578) (xy 17.900818 -147.397435)
			(xy 17.873522 -147.3488) (xy 17.853599 -147.296709) (xy 17.841473 -147.242272) (xy 17.837402 -147.18665)
			(xy 5.06984 -147.18665) (xy 5.06984 -147.657654) (xy 7.150543 -147.657654) (xy 7.150543 -147.603146)
			(xy 7.1583 -147.549193) (xy 7.173657 -147.496892) (xy 7.196301 -147.44731) (xy 7.225771 -147.401455)
			(xy 7.261466 -147.360261) (xy 7.302661 -147.324566) (xy 7.348517 -147.295097) (xy 7.3981 -147.272454)
			(xy 7.4504 -147.257099) (xy 7.504354 -147.249342) (xy 7.531608 -147.24888) (xy 7.557922 -147.249348)
			(xy 7.61005 -147.256584) (xy 7.660693 -147.270903) (xy 7.708891 -147.292036) (xy 7.753735 -147.319581)
			(xy 7.794375 -147.353019) (xy 7.812532 -147.37207) (xy 7.820044 -147.379483) (xy 7.839331 -147.388002)
			(xy 7.84987 -147.38858) (xy 7.924546 -147.38858) (xy 7.935095 -147.388041) (xy 7.95439 -147.379513)
			(xy 7.961884 -147.37207) (xy 7.981704 -147.351282) (xy 8.026476 -147.315307) (xy 8.076134 -147.286447)
			(xy 8.129556 -147.265354) (xy 8.185535 -147.252505) (xy 8.242808 -147.24819) (xy 8.300081 -147.252505)
			(xy 8.35606 -147.265354) (xy 8.409482 -147.286447) (xy 8.45914 -147.315307) (xy 8.503912 -147.351282)
			(xy 8.523732 -147.37207) (xy 8.531244 -147.379483) (xy 8.550531 -147.388002) (xy 8.56107 -147.38858)
			(xy 8.635746 -147.38858) (xy 8.646295 -147.388041) (xy 8.66559 -147.379513) (xy 8.673084 -147.37207)
			(xy 8.691249 -147.353023) (xy 8.731877 -147.319567) (xy 8.776716 -147.292007) (xy 8.824914 -147.270867)
			(xy 8.87556 -147.256548) (xy 8.927692 -147.24932) (xy 8.954008 -147.24888) (xy 8.981258 -147.249391)
			(xy 9.035203 -147.257148) (xy 9.087495 -147.272503) (xy 9.13707 -147.295144) (xy 9.182918 -147.32461)
			(xy 9.224106 -147.3603) (xy 9.259795 -147.401489) (xy 9.28926 -147.447337) (xy 9.3119 -147.496912)
			(xy 9.327254 -147.549205) (xy 9.33501 -147.60315) (xy 9.33501 -147.65765) (xy 9.33501 -147.657652)
			(xy 11.150566 -147.657652) (xy 11.150566 -147.603148) (xy 11.158323 -147.549198) (xy 11.173678 -147.496902)
			(xy 11.19632 -147.447323) (xy 11.225787 -147.401471) (xy 11.26148 -147.36028) (xy 11.302671 -147.324587)
			(xy 11.348523 -147.29512) (xy 11.398102 -147.272478) (xy 11.450398 -147.257123) (xy 11.504348 -147.249366)
			(xy 11.5316 -147.24888) (xy 11.557914 -147.249354) (xy 11.610042 -147.256588) (xy 11.660684 -147.270907)
			(xy 11.708883 -147.292038) (xy 11.753727 -147.319582) (xy 11.794367 -147.353019) (xy 11.812524 -147.37207)
			(xy 11.820039 -147.37948) (xy 11.839324 -147.388001) (xy 11.849862 -147.38858) (xy 11.924538 -147.38858)
			(xy 11.935086 -147.388037) (xy 11.954382 -147.379512) (xy 11.961876 -147.37207) (xy 11.981696 -147.351282)
			(xy 12.026468 -147.315307) (xy 12.076126 -147.286447) (xy 12.129548 -147.265354) (xy 12.185527 -147.252505)
			(xy 12.2428 -147.24819) (xy 12.300073 -147.252505) (xy 12.356052 -147.265354) (xy 12.409474 -147.286447)
			(xy 12.459132 -147.315307) (xy 12.503904 -147.351282) (xy 12.523724 -147.37207) (xy 12.531239 -147.37948)
			(xy 12.550524 -147.388001) (xy 12.561062 -147.38858) (xy 12.635738 -147.38858) (xy 12.646286 -147.388037)
			(xy 12.665582 -147.379512) (xy 12.673076 -147.37207) (xy 12.691244 -147.353027) (xy 12.731872 -147.31957)
			(xy 12.77671 -147.29201) (xy 12.824908 -147.27087) (xy 12.875553 -147.256549) (xy 12.927685 -147.249321)
			(xy 12.954 -147.24888) (xy 12.98125 -147.24939) (xy 13.035196 -147.257147) (xy 13.087489 -147.272501)
			(xy 13.137065 -147.295142) (xy 13.182914 -147.324607) (xy 13.224103 -147.360297) (xy 13.259793 -147.401486)
			(xy 13.289258 -147.447335) (xy 13.311899 -147.496911) (xy 13.327253 -147.549204) (xy 13.33501 -147.60315)
			(xy 13.33501 -147.65765) (xy 13.327253 -147.711596) (xy 13.311899 -147.763889) (xy 13.289258 -147.813465)
			(xy 13.259793 -147.859314) (xy 13.224103 -147.900503) (xy 13.182914 -147.936193) (xy 13.137065 -147.965658)
			(xy 13.087489 -147.988299) (xy 13.035196 -148.003653) (xy 12.98125 -148.01141) (xy 12.954 -148.011896)
			(xy 12.927686 -148.01143) (xy 12.875557 -148.004195) (xy 12.824915 -147.989876) (xy 12.776716 -147.968743)
			(xy 12.731872 -147.941197) (xy 12.691233 -147.907758) (xy 12.673076 -147.888706) (xy 12.665564 -147.881293)
			(xy 12.646277 -147.872775) (xy 12.635738 -147.872196) (xy 12.561062 -147.872196) (xy 12.550515 -147.872746)
			(xy 12.531219 -147.881267) (xy 12.523724 -147.888706) (xy 12.503904 -147.909494) (xy 12.459132 -147.945469)
			(xy 12.409474 -147.974329) (xy 12.356052 -147.995422) (xy 12.300073 -148.008271) (xy 12.2428 -148.012586)
			(xy 12.185527 -148.008271) (xy 12.129548 -147.995422) (xy 12.076126 -147.974329) (xy 12.026468 -147.945469)
			(xy 11.981696 -147.909494) (xy 11.961876 -147.888706) (xy 11.954364 -147.881293) (xy 11.935077 -147.872775)
			(xy 11.924538 -147.872196) (xy 11.849862 -147.872196) (xy 11.839315 -147.872746) (xy 11.820019 -147.881267)
			(xy 11.812524 -147.888706) (xy 11.794351 -147.907744) (xy 11.753725 -147.941203) (xy 11.708888 -147.968764)
			(xy 11.660691 -147.989905) (xy 11.610047 -148.004226) (xy 11.557915 -148.011455) (xy 11.5316 -148.011896)
			(xy 11.504348 -148.011434) (xy 11.450398 -148.003677) (xy 11.398102 -147.988322) (xy 11.348523 -147.96568)
			(xy 11.302671 -147.936213) (xy 11.26148 -147.90052) (xy 11.225787 -147.859329) (xy 11.19632 -147.813477)
			(xy 11.173678 -147.763898) (xy 11.158323 -147.711602) (xy 11.150566 -147.657652) (xy 9.33501 -147.657652)
			(xy 9.327254 -147.711595) (xy 9.3119 -147.763888) (xy 9.28926 -147.813463) (xy 9.259795 -147.859311)
			(xy 9.224106 -147.9005) (xy 9.182918 -147.93619) (xy 9.13707 -147.965656) (xy 9.087495 -147.988297)
			(xy 9.035203 -148.003652) (xy 8.981258 -148.011409) (xy 8.954008 -148.011896) (xy 8.927694 -148.011425)
			(xy 8.875566 -148.004191) (xy 8.824923 -147.989872) (xy 8.776724 -147.968741) (xy 8.73188 -147.941195)
			(xy 8.691241 -147.907757) (xy 8.673084 -147.888706) (xy 8.665569 -147.881296) (xy 8.646284 -147.872776)
			(xy 8.635746 -147.872196) (xy 8.56107 -147.872196) (xy 8.550523 -147.872751) (xy 8.531228 -147.881268)
			(xy 8.523732 -147.888706) (xy 8.503912 -147.909494) (xy 8.45914 -147.945469) (xy 8.409482 -147.974329)
			(xy 8.35606 -147.995422) (xy 8.300081 -148.008271) (xy 8.242808 -148.012586) (xy 8.185535 -148.008271)
			(xy 8.129556 -147.995422) (xy 8.076134 -147.974329) (xy 8.026476 -147.945469) (xy 7.981704 -147.909494)
			(xy 7.961884 -147.888706) (xy 7.954369 -147.881296) (xy 7.935084 -147.872776) (xy 7.924546 -147.872196)
			(xy 7.84987 -147.872196) (xy 7.839323 -147.872751) (xy 7.820028 -147.881268) (xy 7.812532 -147.888706)
			(xy 7.794404 -147.907789) (xy 7.753768 -147.941243) (xy 7.708922 -147.968798) (xy 7.660716 -147.989932)
			(xy 7.610064 -148.004244) (xy 7.557926 -148.011461) (xy 7.531608 -148.011896) (xy 7.504354 -148.011458)
			(xy 7.4504 -148.003701) (xy 7.3981 -147.988346) (xy 7.348517 -147.965703) (xy 7.302661 -147.936234)
			(xy 7.261466 -147.900539) (xy 7.225771 -147.859345) (xy 7.196301 -147.81349) (xy 7.173657 -147.763908)
			(xy 7.1583 -147.711607) (xy 7.150543 -147.657654) (xy 5.06984 -147.657654) (xy 5.06984 -148.017738)
			(xy 15.977614 -148.017738) (xy 15.981685 -147.962116) (xy 15.993811 -147.907679) (xy 16.013734 -147.855588)
			(xy 16.04103 -147.806953) (xy 16.075116 -147.76281) (xy 16.115265 -147.724101) (xy 16.160623 -147.69165)
			(xy 16.210223 -147.666149) (xy 16.263007 -147.648142) (xy 16.31785 -147.638012) (xy 16.373584 -147.635975)
			(xy 16.429021 -147.642075) (xy 16.482978 -147.656181) (xy 16.534307 -147.677993) (xy 16.581913 -147.707047)
			(xy 16.623176 -147.741386) (xy 21.662134 -147.741386) (xy 21.666205 -147.685764) (xy 21.678331 -147.631327)
			(xy 21.698254 -147.579236) (xy 21.72555 -147.530601) (xy 21.759636 -147.486458) (xy 21.799785 -147.447749)
			(xy 21.845143 -147.415298) (xy 21.894743 -147.389797) (xy 21.947527 -147.37179) (xy 22.00237 -147.36166)
			(xy 22.058104 -147.359623) (xy 22.113541 -147.365723) (xy 22.167498 -147.379829) (xy 22.218827 -147.401641)
			(xy 22.266433 -147.430695) (xy 22.309301 -147.46637) (xy 22.346518 -147.507907) (xy 22.377291 -147.55442)
			(xy 22.400963 -147.604917) (xy 22.417031 -147.658324) (xy 22.425151 -147.7135) (xy 22.42566 -147.741386)
			(xy 22.425151 -147.769272) (xy 22.417031 -147.824448) (xy 22.400963 -147.877855) (xy 22.377291 -147.928352)
			(xy 22.346518 -147.974865) (xy 22.309301 -148.016402) (xy 22.266433 -148.052077) (xy 22.218827 -148.081131)
			(xy 22.167498 -148.102943) (xy 22.113541 -148.117049) (xy 22.058104 -148.123149) (xy 22.00237 -148.121112)
			(xy 21.947527 -148.110982) (xy 21.894743 -148.092975) (xy 21.845143 -148.067474) (xy 21.799785 -148.035023)
			(xy 21.759636 -147.996314) (xy 21.72555 -147.952171) (xy 21.698254 -147.903536) (xy 21.678331 -147.851445)
			(xy 21.666205 -147.797008) (xy 21.662134 -147.741386) (xy 16.623176 -147.741386) (xy 16.624781 -147.742722)
			(xy 16.661998 -147.784259) (xy 16.692771 -147.830772) (xy 16.716443 -147.881269) (xy 16.732511 -147.934676)
			(xy 16.740631 -147.989852) (xy 16.74114 -148.017738) (xy 16.740631 -148.045624) (xy 16.732511 -148.1008)
			(xy 16.716443 -148.154207) (xy 16.692771 -148.204704) (xy 16.661998 -148.251217) (xy 16.624781 -148.292754)
			(xy 16.581913 -148.328429) (xy 16.534307 -148.357483) (xy 16.482978 -148.379295) (xy 16.429021 -148.393401)
			(xy 16.373584 -148.399501) (xy 16.31785 -148.397464) (xy 16.263007 -148.387334) (xy 16.210223 -148.369327)
			(xy 16.160623 -148.343826) (xy 16.115265 -148.311375) (xy 16.075116 -148.272666) (xy 16.04103 -148.228523)
			(xy 16.013734 -148.179888) (xy 15.993811 -148.127797) (xy 15.981685 -148.07336) (xy 15.977614 -148.017738)
			(xy 5.06984 -148.017738) (xy 5.06984 -148.718778) (xy 17.698718 -148.718778) (xy 17.702789 -148.663156)
			(xy 17.714915 -148.608719) (xy 17.734838 -148.556628) (xy 17.762134 -148.507993) (xy 17.79622 -148.46385)
			(xy 17.836369 -148.425141) (xy 17.881727 -148.39269) (xy 17.931327 -148.367189) (xy 17.984111 -148.349182)
			(xy 18.038954 -148.339052) (xy 18.094688 -148.337015) (xy 18.150125 -148.343115) (xy 18.204082 -148.357221)
			(xy 18.255411 -148.379033) (xy 18.303017 -148.408087) (xy 18.345885 -148.443762) (xy 18.383102 -148.485299)
			(xy 18.413875 -148.531812) (xy 18.437547 -148.582309) (xy 18.453615 -148.635716) (xy 18.461735 -148.690892)
			(xy 18.462244 -148.718778) (xy 18.86534 -148.718778) (xy 18.869411 -148.663156) (xy 18.881537 -148.608719)
			(xy 18.90146 -148.556628) (xy 18.928756 -148.507993) (xy 18.962842 -148.46385) (xy 19.002991 -148.425141)
			(xy 19.048349 -148.39269) (xy 19.097949 -148.367189) (xy 19.150733 -148.349182) (xy 19.205576 -148.339052)
			(xy 19.26131 -148.337015) (xy 19.316747 -148.343115) (xy 19.370704 -148.357221) (xy 19.422033 -148.379033)
			(xy 19.469639 -148.408087) (xy 19.512507 -148.443762) (xy 19.549724 -148.485299) (xy 19.580497 -148.531812)
			(xy 19.604169 -148.582309) (xy 19.620237 -148.635716) (xy 19.628357 -148.690892) (xy 19.628866 -148.718778)
			(xy 19.628357 -148.746664) (xy 19.620237 -148.80184) (xy 19.604169 -148.855247) (xy 19.580497 -148.905744)
			(xy 19.549724 -148.952257) (xy 19.512507 -148.993794) (xy 19.469639 -149.029469) (xy 19.422033 -149.058523)
			(xy 19.370704 -149.080335) (xy 19.316747 -149.094441) (xy 19.26131 -149.100541) (xy 19.205576 -149.098504)
			(xy 19.150733 -149.088374) (xy 19.097949 -149.070367) (xy 19.048349 -149.044866) (xy 19.002991 -149.012415)
			(xy 18.962842 -148.973706) (xy 18.928756 -148.929563) (xy 18.90146 -148.880928) (xy 18.881537 -148.828837)
			(xy 18.869411 -148.7744) (xy 18.86534 -148.718778) (xy 18.462244 -148.718778) (xy 18.461735 -148.746664)
			(xy 18.453615 -148.80184) (xy 18.437547 -148.855247) (xy 18.413875 -148.905744) (xy 18.383102 -148.952257)
			(xy 18.345885 -148.993794) (xy 18.303017 -149.029469) (xy 18.255411 -149.058523) (xy 18.204082 -149.080335)
			(xy 18.150125 -149.094441) (xy 18.094688 -149.100541) (xy 18.038954 -149.098504) (xy 17.984111 -149.088374)
			(xy 17.931327 -149.070367) (xy 17.881727 -149.044866) (xy 17.836369 -149.012415) (xy 17.79622 -148.973706)
			(xy 17.762134 -148.929563) (xy 17.734838 -148.880928) (xy 17.714915 -148.828837) (xy 17.702789 -148.7744)
			(xy 17.698718 -148.718778) (xy 5.06984 -148.718778) (xy 5.06984 -150.195853) (xy 7.150565 -150.195853)
			(xy 7.150565 -150.141347) (xy 7.158322 -150.087397) (xy 7.173678 -150.0351) (xy 7.196321 -149.985521)
			(xy 7.225789 -149.939669) (xy 7.261482 -149.898477) (xy 7.302675 -149.862784) (xy 7.348528 -149.833317)
			(xy 7.398108 -149.810676) (xy 7.450405 -149.795321) (xy 7.504355 -149.787565) (xy 7.531608 -149.787102)
			(xy 7.557922 -149.787563) (xy 7.610051 -149.794799) (xy 7.660694 -149.80912) (xy 7.708893 -149.830253)
			(xy 7.753736 -149.8578) (xy 7.794376 -149.89124) (xy 7.812532 -149.910292) (xy 7.820041 -149.917708)
			(xy 7.839331 -149.926225) (xy 7.84987 -149.926802) (xy 7.924546 -149.926802) (xy 7.935094 -149.926257)
			(xy 7.954389 -149.917733) (xy 7.961884 -149.910292) (xy 7.981704 -149.889504) (xy 8.026476 -149.853529)
			(xy 8.076134 -149.824669) (xy 8.129556 -149.803576) (xy 8.185535 -149.790727) (xy 8.242808 -149.786412)
			(xy 8.300081 -149.790727) (xy 8.35606 -149.803576) (xy 8.409482 -149.824669) (xy 8.45914 -149.853529)
			(xy 8.503912 -149.889504) (xy 8.523732 -149.910292) (xy 8.531241 -149.917708) (xy 8.550531 -149.926225)
			(xy 8.56107 -149.926802) (xy 8.635746 -149.926802) (xy 8.646294 -149.926257) (xy 8.665589 -149.917733)
			(xy 8.673084 -149.910292) (xy 8.691253 -149.89125) (xy 8.73188 -149.857792) (xy 8.776717 -149.830231)
			(xy 8.824916 -149.80909) (xy 8.875561 -149.79477) (xy 8.927693 -149.787542) (xy 8.954008 -149.787102)
			(xy 8.98126 -149.787568) (xy 9.035208 -149.795326) (xy 9.087503 -149.810682) (xy 9.137081 -149.833324)
			(xy 9.182931 -149.862792) (xy 9.224122 -149.898484) (xy 9.259813 -149.939675) (xy 9.289279 -149.985526)
			(xy 9.311921 -150.035104) (xy 9.327276 -150.0874) (xy 9.335032 -150.141348) (xy 9.335032 -150.19585)
			(xy 11.150588 -150.19585) (xy 11.150588 -150.14135) (xy 11.158345 -150.087403) (xy 11.173699 -150.03511)
			(xy 11.19634 -149.985534) (xy 11.225805 -149.939685) (xy 11.261496 -149.898496) (xy 11.302685 -149.862805)
			(xy 11.348534 -149.83334) (xy 11.39811 -149.810699) (xy 11.450403 -149.795345) (xy 11.50435 -149.787588)
			(xy 11.5316 -149.787102) (xy 11.557914 -149.787569) (xy 11.610043 -149.794804) (xy 11.660685 -149.809123)
			(xy 11.708884 -149.830255) (xy 11.753728 -149.857802) (xy 11.794367 -149.89124) (xy 11.812524 -149.910292)
			(xy 11.820036 -149.917705) (xy 11.839323 -149.926223) (xy 11.849862 -149.926802) (xy 11.924538 -149.926802)
			(xy 11.935085 -149.926252) (xy 11.954381 -149.917732) (xy 11.961876 -149.910292) (xy 11.981696 -149.889504)
			(xy 12.026468 -149.853529) (xy 12.076126 -149.824669) (xy 12.129548 -149.803576) (xy 12.185527 -149.790727)
			(xy 12.2428 -149.786412) (xy 12.300073 -149.790727) (xy 12.356052 -149.803576) (xy 12.409474 -149.824669)
			(xy 12.459132 -149.853529) (xy 12.503904 -149.889504) (xy 12.523724 -149.910292) (xy 12.531236 -149.917705)
			(xy 12.550523 -149.926223) (xy 12.561062 -149.926802) (xy 12.635738 -149.926802) (xy 12.646285 -149.926252)
			(xy 12.665581 -149.917732) (xy 12.673076 -149.910292) (xy 12.691249 -149.891254) (xy 12.731875 -149.857795)
			(xy 12.776712 -149.830234) (xy 12.824909 -149.809093) (xy 12.875553 -149.794772) (xy 12.927685 -149.787543)
			(xy 12.954 -149.787102) (xy 12.981252 -149.787568) (xy 13.035201 -149.795325) (xy 13.087497 -149.81068)
			(xy 13.137076 -149.833322) (xy 13.182927 -149.862789) (xy 13.224119 -149.898481) (xy 13.259811 -149.939673)
			(xy 13.289278 -149.985524) (xy 13.31192 -150.035103) (xy 13.320244 -150.063454) (xy 15.838168 -150.063454)
			(xy 15.842239 -150.007832) (xy 15.854365 -149.953395) (xy 15.874288 -149.901304) (xy 15.901584 -149.852669)
			(xy 15.93567 -149.808526) (xy 15.975819 -149.769817) (xy 16.021177 -149.737366) (xy 16.070777 -149.711865)
			(xy 16.123561 -149.693858) (xy 16.178404 -149.683728) (xy 16.234138 -149.681691) (xy 16.289575 -149.687791)
			(xy 16.343532 -149.701897) (xy 16.394861 -149.723709) (xy 16.442467 -149.752763) (xy 16.485335 -149.788438)
			(xy 16.522552 -149.829975) (xy 16.553325 -149.876488) (xy 16.562861 -149.89683) (xy 17.709894 -149.89683)
			(xy 17.713965 -149.841208) (xy 17.726091 -149.786771) (xy 17.746014 -149.73468) (xy 17.77331 -149.686045)
			(xy 17.807396 -149.641902) (xy 17.847545 -149.603193) (xy 17.892903 -149.570742) (xy 17.942503 -149.545241)
			(xy 17.995287 -149.527234) (xy 18.05013 -149.517104) (xy 18.105864 -149.515067) (xy 18.161301 -149.521167)
			(xy 18.215258 -149.535273) (xy 18.266587 -149.557085) (xy 18.314193 -149.586139) (xy 18.357061 -149.621814)
			(xy 18.394278 -149.663351) (xy 18.425051 -149.709864) (xy 18.448723 -149.760361) (xy 18.464791 -149.813768)
			(xy 18.472911 -149.868944) (xy 18.47342 -149.89683) (xy 18.473211 -149.90826) (xy 18.87677 -149.90826)
			(xy 18.880841 -149.852638) (xy 18.892967 -149.798201) (xy 18.91289 -149.74611) (xy 18.940186 -149.697475)
			(xy 18.974272 -149.653332) (xy 19.014421 -149.614623) (xy 19.059779 -149.582172) (xy 19.109379 -149.556671)
			(xy 19.162163 -149.538664) (xy 19.217006 -149.528534) (xy 19.27274 -149.526497) (xy 19.328177 -149.532597)
			(xy 19.382134 -149.546703) (xy 19.433463 -149.568515) (xy 19.481069 -149.597569) (xy 19.523937 -149.633244)
			(xy 19.561154 -149.674781) (xy 19.591927 -149.721294) (xy 19.615599 -149.771791) (xy 19.631667 -149.825198)
			(xy 19.639787 -149.880374) (xy 19.640296 -149.90826) (xy 19.639787 -149.936146) (xy 19.631667 -149.991322)
			(xy 19.615599 -150.044729) (xy 19.591927 -150.095226) (xy 19.561154 -150.141739) (xy 19.523937 -150.183276)
			(xy 19.481069 -150.218951) (xy 19.433463 -150.248005) (xy 19.382134 -150.269817) (xy 19.328177 -150.283923)
			(xy 19.27274 -150.290023) (xy 19.217006 -150.287986) (xy 19.162163 -150.277856) (xy 19.109379 -150.259849)
			(xy 19.059779 -150.234348) (xy 19.014421 -150.201897) (xy 18.974272 -150.163188) (xy 18.940186 -150.119045)
			(xy 18.91289 -150.07041) (xy 18.892967 -150.018319) (xy 18.880841 -149.963882) (xy 18.87677 -149.90826)
			(xy 18.473211 -149.90826) (xy 18.472911 -149.924716) (xy 18.464791 -149.979892) (xy 18.448723 -150.033299)
			(xy 18.425051 -150.083796) (xy 18.394278 -150.130309) (xy 18.357061 -150.171846) (xy 18.314193 -150.207521)
			(xy 18.266587 -150.236575) (xy 18.215258 -150.258387) (xy 18.161301 -150.272493) (xy 18.105864 -150.278593)
			(xy 18.05013 -150.276556) (xy 17.995287 -150.266426) (xy 17.942503 -150.248419) (xy 17.892903 -150.222918)
			(xy 17.847545 -150.190467) (xy 17.807396 -150.151758) (xy 17.77331 -150.107615) (xy 17.746014 -150.05898)
			(xy 17.726091 -150.006889) (xy 17.713965 -149.952452) (xy 17.709894 -149.89683) (xy 16.562861 -149.89683)
			(xy 16.576997 -149.926985) (xy 16.593065 -149.980392) (xy 16.601185 -150.035568) (xy 16.601694 -150.063454)
			(xy 16.601185 -150.09134) (xy 16.593065 -150.146516) (xy 16.576997 -150.199923) (xy 16.553325 -150.25042)
			(xy 16.522552 -150.296933) (xy 16.485335 -150.33847) (xy 16.442467 -150.374145) (xy 16.394861 -150.403199)
			(xy 16.343532 -150.425011) (xy 16.289575 -150.439117) (xy 16.234138 -150.445217) (xy 16.178404 -150.44318)
			(xy 16.123561 -150.43305) (xy 16.070777 -150.415043) (xy 16.021177 -150.389542) (xy 15.975819 -150.357091)
			(xy 15.93567 -150.318382) (xy 15.901584 -150.274239) (xy 15.874288 -150.225604) (xy 15.854365 -150.173513)
			(xy 15.842239 -150.119076) (xy 15.838168 -150.063454) (xy 13.320244 -150.063454) (xy 13.327275 -150.087399)
			(xy 13.335032 -150.141348) (xy 13.335032 -150.195852) (xy 13.327275 -150.249801) (xy 13.31192 -150.302097)
			(xy 13.289278 -150.351676) (xy 13.259811 -150.397527) (xy 13.224119 -150.438719) (xy 13.182927 -150.474411)
			(xy 13.137076 -150.503878) (xy 13.087497 -150.52652) (xy 13.035201 -150.541875) (xy 12.981252 -150.549632)
			(xy 12.954 -150.550118) (xy 12.927686 -150.549645) (xy 12.875558 -150.54241) (xy 12.824916 -150.528092)
			(xy 12.776717 -150.506961) (xy 12.731873 -150.479416) (xy 12.691233 -150.445979) (xy 12.673076 -150.426928)
			(xy 12.665562 -150.419518) (xy 12.646276 -150.410997) (xy 12.635738 -150.410418) (xy 12.561062 -150.410418)
			(xy 12.550514 -150.410962) (xy 12.531218 -150.419486) (xy 12.523724 -150.426928) (xy 12.503904 -150.447716)
			(xy 12.459132 -150.483691) (xy 12.409474 -150.512551) (xy 12.356052 -150.533644) (xy 12.300073 -150.546493)
			(xy 12.2428 -150.550808) (xy 12.185527 -150.546493) (xy 12.129548 -150.533644) (xy 12.076126 -150.512551)
			(xy 12.026468 -150.483691) (xy 11.981696 -150.447716) (xy 11.961876 -150.426928) (xy 11.954362 -150.419518)
			(xy 11.935076 -150.410997) (xy 11.924538 -150.410418) (xy 11.849862 -150.410418) (xy 11.839314 -150.410962)
			(xy 11.820018 -150.419486) (xy 11.812524 -150.426928) (xy 11.794355 -150.44597) (xy 11.753728 -150.479428)
			(xy 11.70889 -150.506988) (xy 11.660692 -150.528128) (xy 11.610047 -150.542449) (xy 11.557915 -150.549677)
			(xy 11.5316 -150.550118) (xy 11.50435 -150.549612) (xy 11.450403 -150.541855) (xy 11.39811 -150.526501)
			(xy 11.348534 -150.50386) (xy 11.302685 -150.474395) (xy 11.261496 -150.438704) (xy 11.225805 -150.397515)
			(xy 11.19634 -150.351666) (xy 11.173699 -150.30209) (xy 11.158345 -150.249797) (xy 11.150588 -150.19585)
			(xy 9.335032 -150.19585) (xy 9.335032 -150.195852) (xy 9.327276 -150.2498) (xy 9.311921 -150.302096)
			(xy 9.289279 -150.351674) (xy 9.259813 -150.397525) (xy 9.224122 -150.438716) (xy 9.182931 -150.474408)
			(xy 9.137081 -150.503876) (xy 9.087503 -150.526518) (xy 9.035208 -150.541874) (xy 8.98126 -150.549632)
			(xy 8.954008 -150.550118) (xy 8.927694 -150.549639) (xy 8.875567 -150.542406) (xy 8.824924 -150.528089)
			(xy 8.776725 -150.506958) (xy 8.731882 -150.479415) (xy 8.691241 -150.445978) (xy 8.673084 -150.426928)
			(xy 8.665567 -150.419521) (xy 8.646284 -150.410999) (xy 8.635746 -150.410418) (xy 8.56107 -150.410418)
			(xy 8.550522 -150.410966) (xy 8.531226 -150.419487) (xy 8.523732 -150.426928) (xy 8.503912 -150.447716)
			(xy 8.45914 -150.483691) (xy 8.409482 -150.512551) (xy 8.35606 -150.533644) (xy 8.300081 -150.546493)
			(xy 8.242808 -150.550808) (xy 8.185535 -150.546493) (xy 8.129556 -150.533644) (xy 8.076134 -150.512551)
			(xy 8.026476 -150.483691) (xy 7.981704 -150.447716) (xy 7.961884 -150.426928) (xy 7.954367 -150.419521)
			(xy 7.935084 -150.410999) (xy 7.924546 -150.410418) (xy 7.84987 -150.410418) (xy 7.839322 -150.410966)
			(xy 7.820026 -150.419487) (xy 7.812532 -150.426928) (xy 7.794408 -150.446015) (xy 7.753771 -150.479468)
			(xy 7.708924 -150.507022) (xy 7.660717 -150.528155) (xy 7.610064 -150.542466) (xy 7.557926 -150.549683)
			(xy 7.531608 -150.550118) (xy 7.504355 -150.549635) (xy 7.450405 -150.541879) (xy 7.398108 -150.526524)
			(xy 7.348528 -150.503883) (xy 7.302675 -150.474416) (xy 7.261482 -150.438723) (xy 7.225789 -150.397531)
			(xy 7.196321 -150.351679) (xy 7.173678 -150.3021) (xy 7.158322 -150.249803) (xy 7.150565 -150.195853)
			(xy 5.06984 -150.195853) (xy 5.06984 -151.67102) (xy 15.793718 -151.67102) (xy 15.797789 -151.615398)
			(xy 15.809915 -151.560961) (xy 15.829838 -151.50887) (xy 15.857134 -151.460235) (xy 15.89122 -151.416092)
			(xy 15.931369 -151.377383) (xy 15.976727 -151.344932) (xy 16.026327 -151.319431) (xy 16.079111 -151.301424)
			(xy 16.133954 -151.291294) (xy 16.189688 -151.289257) (xy 16.245125 -151.295357) (xy 16.299082 -151.309463)
			(xy 16.350411 -151.331275) (xy 16.398017 -151.360329) (xy 16.440885 -151.396004) (xy 16.478102 -151.437541)
			(xy 16.508875 -151.484054) (xy 16.532547 -151.534551) (xy 16.548615 -151.587958) (xy 16.556735 -151.643134)
			(xy 16.557244 -151.67102) (xy 16.556771 -151.696928) (xy 16.809718 -151.696928) (xy 16.813789 -151.641306)
			(xy 16.825915 -151.586869) (xy 16.845838 -151.534778) (xy 16.873134 -151.486143) (xy 16.90722 -151.442)
			(xy 16.947369 -151.403291) (xy 16.992727 -151.37084) (xy 17.042327 -151.345339) (xy 17.095111 -151.327332)
			(xy 17.149954 -151.317202) (xy 17.205688 -151.315165) (xy 17.261125 -151.321265) (xy 17.315082 -151.335371)
			(xy 17.366411 -151.357183) (xy 17.414017 -151.386237) (xy 17.438493 -151.406606) (xy 18.036792 -151.406606)
			(xy 18.040863 -151.350984) (xy 18.052989 -151.296547) (xy 18.072912 -151.244456) (xy 18.100208 -151.195821)
			(xy 18.134294 -151.151678) (xy 18.174443 -151.112969) (xy 18.219801 -151.080518) (xy 18.269401 -151.055017)
			(xy 18.322185 -151.03701) (xy 18.377028 -151.02688) (xy 18.432762 -151.024843) (xy 18.488199 -151.030943)
			(xy 18.542156 -151.045049) (xy 18.593485 -151.066861) (xy 18.641091 -151.095915) (xy 18.683959 -151.13159)
			(xy 18.721176 -151.173127) (xy 18.751949 -151.21964) (xy 18.775621 -151.270137) (xy 18.791689 -151.323544)
			(xy 18.799809 -151.37872) (xy 18.800318 -151.406606) (xy 18.799809 -151.434492) (xy 18.791689 -151.489668)
			(xy 18.775621 -151.543075) (xy 18.757079 -151.582628) (xy 19.362418 -151.582628) (xy 19.366489 -151.527006)
			(xy 19.378615 -151.472569) (xy 19.398538 -151.420478) (xy 19.425834 -151.371843) (xy 19.45992 -151.3277)
			(xy 19.500069 -151.288991) (xy 19.545427 -151.25654) (xy 19.595027 -151.231039) (xy 19.647811 -151.213032)
			(xy 19.702654 -151.202902) (xy 19.758388 -151.200865) (xy 19.813825 -151.206965) (xy 19.867782 -151.221071)
			(xy 19.919111 -151.242883) (xy 19.966717 -151.271937) (xy 20.009585 -151.307612) (xy 20.046802 -151.349149)
			(xy 20.077575 -151.395662) (xy 20.101247 -151.446159) (xy 20.117315 -151.499566) (xy 20.125435 -151.554742)
			(xy 20.125698 -151.569166) (xy 20.873718 -151.569166) (xy 20.877789 -151.513544) (xy 20.889915 -151.459107)
			(xy 20.909838 -151.407016) (xy 20.937134 -151.358381) (xy 20.97122 -151.314238) (xy 21.011369 -151.275529)
			(xy 21.056727 -151.243078) (xy 21.106327 -151.217577) (xy 21.159111 -151.19957) (xy 21.213954 -151.18944)
			(xy 21.269688 -151.187403) (xy 21.325125 -151.193503) (xy 21.379082 -151.207609) (xy 21.430411 -151.229421)
			(xy 21.478017 -151.258475) (xy 21.520885 -151.29415) (xy 21.558102 -151.335687) (xy 21.588875 -151.3822)
			(xy 21.612547 -151.432697) (xy 21.628615 -151.486104) (xy 21.636735 -151.54128) (xy 21.637244 -151.569166)
			(xy 21.636735 -151.597052) (xy 21.628615 -151.652228) (xy 21.612547 -151.705635) (xy 21.588875 -151.756132)
			(xy 21.558102 -151.802645) (xy 21.520885 -151.844182) (xy 21.478017 -151.879857) (xy 21.430411 -151.908911)
			(xy 21.379082 -151.930723) (xy 21.325125 -151.944829) (xy 21.269688 -151.950929) (xy 21.213954 -151.948892)
			(xy 21.159111 -151.938762) (xy 21.106327 -151.920755) (xy 21.056727 -151.895254) (xy 21.011369 -151.862803)
			(xy 20.97122 -151.824094) (xy 20.937134 -151.779951) (xy 20.909838 -151.731316) (xy 20.889915 -151.679225)
			(xy 20.877789 -151.624788) (xy 20.873718 -151.569166) (xy 20.125698 -151.569166) (xy 20.125944 -151.582628)
			(xy 20.125435 -151.610514) (xy 20.117315 -151.66569) (xy 20.101247 -151.719097) (xy 20.077575 -151.769594)
			(xy 20.046802 -151.816107) (xy 20.009585 -151.857644) (xy 19.966717 -151.893319) (xy 19.919111 -151.922373)
			(xy 19.867782 -151.944185) (xy 19.813825 -151.958291) (xy 19.758388 -151.964391) (xy 19.702654 -151.962354)
			(xy 19.647811 -151.952224) (xy 19.595027 -151.934217) (xy 19.545427 -151.908716) (xy 19.500069 -151.876265)
			(xy 19.45992 -151.837556) (xy 19.425834 -151.793413) (xy 19.398538 -151.744778) (xy 19.378615 -151.692687)
			(xy 19.366489 -151.63825) (xy 19.362418 -151.582628) (xy 18.757079 -151.582628) (xy 18.751949 -151.593572)
			(xy 18.721176 -151.640085) (xy 18.683959 -151.681622) (xy 18.641091 -151.717297) (xy 18.593485 -151.746351)
			(xy 18.542156 -151.768163) (xy 18.488199 -151.782269) (xy 18.432762 -151.788369) (xy 18.377028 -151.786332)
			(xy 18.322185 -151.776202) (xy 18.269401 -151.758195) (xy 18.219801 -151.732694) (xy 18.174443 -151.700243)
			(xy 18.134294 -151.661534) (xy 18.100208 -151.617391) (xy 18.072912 -151.568756) (xy 18.052989 -151.516665)
			(xy 18.040863 -151.462228) (xy 18.036792 -151.406606) (xy 17.438493 -151.406606) (xy 17.456885 -151.421912)
			(xy 17.494102 -151.463449) (xy 17.524875 -151.509962) (xy 17.548547 -151.560459) (xy 17.564615 -151.613866)
			(xy 17.572735 -151.669042) (xy 17.573244 -151.696928) (xy 17.572735 -151.724814) (xy 17.564615 -151.77999)
			(xy 17.548547 -151.833397) (xy 17.524875 -151.883894) (xy 17.494102 -151.930407) (xy 17.456885 -151.971944)
			(xy 17.414017 -152.007619) (xy 17.366411 -152.036673) (xy 17.315082 -152.058485) (xy 17.261125 -152.072591)
			(xy 17.205688 -152.078691) (xy 17.149954 -152.076654) (xy 17.095111 -152.066524) (xy 17.042327 -152.048517)
			(xy 16.992727 -152.023016) (xy 16.947369 -151.990565) (xy 16.90722 -151.951856) (xy 16.873134 -151.907713)
			(xy 16.845838 -151.859078) (xy 16.825915 -151.806987) (xy 16.813789 -151.75255) (xy 16.809718 -151.696928)
			(xy 16.556771 -151.696928) (xy 16.556735 -151.698906) (xy 16.548615 -151.754082) (xy 16.532547 -151.807489)
			(xy 16.508875 -151.857986) (xy 16.478102 -151.904499) (xy 16.440885 -151.946036) (xy 16.398017 -151.981711)
			(xy 16.350411 -152.010765) (xy 16.299082 -152.032577) (xy 16.245125 -152.046683) (xy 16.189688 -152.052783)
			(xy 16.133954 -152.050746) (xy 16.079111 -152.040616) (xy 16.026327 -152.022609) (xy 15.976727 -151.997108)
			(xy 15.931369 -151.964657) (xy 15.89122 -151.925948) (xy 15.857134 -151.881805) (xy 15.829838 -151.83317)
			(xy 15.809915 -151.781079) (xy 15.797789 -151.726642) (xy 15.793718 -151.67102) (xy 5.06984 -151.67102)
			(xy 5.06984 -153.782522) (xy 14.777718 -153.782522) (xy 14.781789 -153.7269) (xy 14.793915 -153.672463)
			(xy 14.813838 -153.620372) (xy 14.841134 -153.571737) (xy 14.87522 -153.527594) (xy 14.915369 -153.488885)
			(xy 14.960727 -153.456434) (xy 15.010327 -153.430933) (xy 15.063111 -153.412926) (xy 15.117954 -153.402796)
			(xy 15.173688 -153.400759) (xy 15.229125 -153.406859) (xy 15.283082 -153.420965) (xy 15.334411 -153.442777)
			(xy 15.382017 -153.471831) (xy 15.424885 -153.507506) (xy 15.462102 -153.549043) (xy 15.492875 -153.595556)
			(xy 15.516547 -153.646053) (xy 15.532615 -153.69946) (xy 15.540735 -153.754636) (xy 15.541244 -153.782522)
			(xy 15.540735 -153.810408) (xy 15.532615 -153.865584) (xy 15.516547 -153.918991) (xy 15.492875 -153.969488)
			(xy 15.462102 -154.016001) (xy 15.424885 -154.057538) (xy 15.382017 -154.093213) (xy 15.334411 -154.122267)
			(xy 15.283082 -154.144079) (xy 15.229125 -154.158185) (xy 15.173688 -154.164285) (xy 15.117954 -154.162248)
			(xy 15.063111 -154.152118) (xy 15.010327 -154.134111) (xy 14.960727 -154.10861) (xy 14.915369 -154.076159)
			(xy 14.87522 -154.03745) (xy 14.841134 -153.993307) (xy 14.813838 -153.944672) (xy 14.793915 -153.892581)
			(xy 14.781789 -153.838144) (xy 14.777718 -153.782522) (xy 5.06984 -153.782522) (xy 5.06984 -155.212034)
			(xy 7.269224 -155.212034) (xy 7.273295 -155.156412) (xy 7.285421 -155.101975) (xy 7.305344 -155.049884)
			(xy 7.33264 -155.001249) (xy 7.366726 -154.957106) (xy 7.406875 -154.918397) (xy 7.452233 -154.885946)
			(xy 7.501833 -154.860445) (xy 7.554617 -154.842438) (xy 7.60946 -154.832308) (xy 7.665194 -154.830271)
			(xy 7.720631 -154.836371) (xy 7.774588 -154.850477) (xy 7.825917 -154.872289) (xy 7.873523 -154.901343)
			(xy 7.916391 -154.937018) (xy 7.953608 -154.978555) (xy 7.984381 -155.025068) (xy 8.008053 -155.075565)
			(xy 8.024121 -155.128972) (xy 8.032241 -155.184148) (xy 8.03275 -155.212034) (xy 8.032657 -155.217114)
			(xy 8.318498 -155.217114) (xy 8.322569 -155.161492) (xy 8.334695 -155.107055) (xy 8.354618 -155.054964)
			(xy 8.381914 -155.006329) (xy 8.416 -154.962186) (xy 8.456149 -154.923477) (xy 8.501507 -154.891026)
			(xy 8.551107 -154.865525) (xy 8.603891 -154.847518) (xy 8.658734 -154.837388) (xy 8.714468 -154.835351)
			(xy 8.769905 -154.841451) (xy 8.823862 -154.855557) (xy 8.875191 -154.877369) (xy 8.922797 -154.906423)
			(xy 8.965665 -154.942098) (xy 9.002882 -154.983635) (xy 9.033655 -155.030148) (xy 9.056646 -155.079192)
			(xy 9.86993 -155.079192) (xy 9.874001 -155.02357) (xy 9.886127 -154.969133) (xy 9.90605 -154.917042)
			(xy 9.933346 -154.868407) (xy 9.967432 -154.824264) (xy 10.007581 -154.785555) (xy 10.052939 -154.753104)
			(xy 10.102539 -154.727603) (xy 10.155323 -154.709596) (xy 10.210166 -154.699466) (xy 10.2659 -154.697429)
			(xy 10.321337 -154.703529) (xy 10.375294 -154.717635) (xy 10.426623 -154.739447) (xy 10.474229 -154.768501)
			(xy 10.517097 -154.804176) (xy 10.554314 -154.845713) (xy 10.585087 -154.892226) (xy 10.608759 -154.942723)
			(xy 10.624827 -154.99613) (xy 10.632947 -155.051306) (xy 10.633456 -155.079192) (xy 10.633391 -155.082748)
			(xy 11.19378 -155.082748) (xy 11.194219 -155.056433) (xy 11.201461 -155.004304) (xy 11.215786 -154.953661)
			(xy 11.236924 -154.905462) (xy 11.264474 -154.860619) (xy 11.297917 -154.81998) (xy 11.31697 -154.801824)
			(xy 11.324359 -154.794291) (xy 11.332892 -154.77502) (xy 11.33348 -154.764486) (xy 11.33348 -154.68981)
			(xy 11.332965 -154.679259) (xy 11.32442 -154.659963) (xy 11.31697 -154.652472) (xy 11.297902 -154.634329)
			(xy 11.264447 -154.593696) (xy 11.236891 -154.548853) (xy 11.215755 -154.50065) (xy 11.20144 -154.45)
			(xy 11.194217 -154.397865) (xy 11.19378 -154.371548) (xy 11.1943 -154.344297) (xy 11.20205 -154.290349)
			(xy 11.217399 -154.238053) (xy 11.240035 -154.188473) (xy 11.269497 -154.142621) (xy 11.305185 -154.101428)
			(xy 11.346372 -154.065733) (xy 11.392221 -154.036264) (xy 11.441796 -154.01362) (xy 11.49409 -153.998263)
			(xy 11.548037 -153.990504) (xy 11.575288 -153.99004) (xy 11.601602 -153.990503) (xy 11.653731 -153.997737)
			(xy 11.704375 -154.012056) (xy 11.752574 -154.033189) (xy 11.797417 -154.060737) (xy 11.838056 -154.094177)
			(xy 11.856212 -154.11323) (xy 11.863737 -154.120629) (xy 11.883014 -154.129157) (xy 11.89355 -154.12974)
			(xy 11.968226 -154.12974) (xy 11.978771 -154.129173) (xy 11.998066 -154.120663) (xy 12.005564 -154.11323)
			(xy 12.025384 -154.092442) (xy 12.070156 -154.056467) (xy 12.119814 -154.027607) (xy 12.173236 -154.006514)
			(xy 12.229215 -153.993665) (xy 12.286488 -153.98935) (xy 12.343761 -153.993665) (xy 12.39974 -154.006514)
			(xy 12.453162 -154.027607) (xy 12.50282 -154.056467) (xy 12.547592 -154.092442) (xy 12.567412 -154.11323)
			(xy 12.574937 -154.120629) (xy 12.594214 -154.129157) (xy 12.60475 -154.12974) (xy 12.679426 -154.12974)
			(xy 12.689971 -154.129173) (xy 12.709266 -154.120663) (xy 12.716764 -154.11323) (xy 12.736584 -154.092442)
			(xy 12.781356 -154.056467) (xy 12.831014 -154.027607) (xy 12.884436 -154.006514) (xy 12.940415 -153.993665)
			(xy 12.997688 -153.98935) (xy 13.054961 -153.993665) (xy 13.11094 -154.006514) (xy 13.164362 -154.027607)
			(xy 13.21402 -154.056467) (xy 13.258792 -154.092442) (xy 13.278612 -154.11323) (xy 13.286137 -154.120629)
			(xy 13.305414 -154.129157) (xy 13.31595 -154.12974) (xy 13.390626 -154.12974) (xy 13.401171 -154.129173)
			(xy 13.420466 -154.120663) (xy 13.427964 -154.11323) (xy 13.446101 -154.094156) (xy 13.486734 -154.060699)
			(xy 13.531578 -154.033142) (xy 13.579783 -154.012007) (xy 13.630434 -153.997694) (xy 13.682571 -153.990475)
			(xy 13.708888 -153.99004) (xy 13.736143 -153.990467) (xy 13.790097 -153.998223) (xy 13.842399 -154.01358)
			(xy 13.891982 -154.036225) (xy 13.937838 -154.065696) (xy 13.979032 -154.101394) (xy 14.014726 -154.142591)
			(xy 14.044193 -154.188449) (xy 14.066832 -154.238035) (xy 14.082184 -154.290338) (xy 14.089936 -154.344293)
			(xy 14.090396 -154.371548) (xy 14.089962 -154.397863) (xy 14.08272 -154.449993) (xy 14.068395 -154.500637)
			(xy 14.063853 -154.510994) (xy 15.566898 -154.510994) (xy 15.567484 -154.482056) (xy 15.576213 -154.424841)
			(xy 15.593486 -154.369602) (xy 15.618905 -154.317607) (xy 15.651888 -154.270048) (xy 15.691677 -154.228018)
			(xy 15.737359 -154.192481) (xy 15.787885 -154.164254) (xy 15.814802 -154.153616) (xy 15.829058 -154.147671)
			(xy 15.853387 -154.128662) (xy 15.870945 -154.103266) (xy 15.880134 -154.073791) (xy 15.88012 -154.042916)
			(xy 15.870903 -154.01345) (xy 15.862554 -154.000454) (xy 15.846452 -153.97632) (xy 15.820914 -153.92423)
			(xy 15.803553 -153.868874) (xy 15.79477 -153.811529) (xy 15.794228 -153.782522) (xy 15.794714 -153.755271)
			(xy 15.80247 -153.701323) (xy 15.817825 -153.649028) (xy 15.840467 -153.599451) (xy 15.869933 -153.553601)
			(xy 15.905624 -153.51241) (xy 15.946815 -153.476719) (xy 15.992665 -153.447253) (xy 16.042242 -153.424611)
			(xy 16.094537 -153.409256) (xy 16.148485 -153.4015) (xy 16.202987 -153.4015) (xy 16.256935 -153.409256)
			(xy 16.30923 -153.424611) (xy 16.358807 -153.447253) (xy 16.404657 -153.476719) (xy 16.445848 -153.51241)
			(xy 16.481539 -153.553601) (xy 16.511005 -153.599451) (xy 16.533647 -153.649028) (xy 16.549002 -153.701323)
			(xy 16.556758 -153.755271) (xy 16.557244 -153.782522) (xy 16.556709 -153.811463) (xy 16.553605 -153.831798)
			(xy 16.809718 -153.831798) (xy 16.813789 -153.776176) (xy 16.825915 -153.721739) (xy 16.845838 -153.669648)
			(xy 16.873134 -153.621013) (xy 16.90722 -153.57687) (xy 16.947369 -153.538161) (xy 16.992727 -153.50571)
			(xy 17.042327 -153.480209) (xy 17.095111 -153.462202) (xy 17.149954 -153.452072) (xy 17.205688 -153.450035)
			(xy 17.261125 -153.456135) (xy 17.315082 -153.470241) (xy 17.366411 -153.492053) (xy 17.414017 -153.521107)
			(xy 17.456885 -153.556782) (xy 17.494102 -153.598319) (xy 17.524875 -153.644832) (xy 17.548547 -153.695329)
			(xy 17.564615 -153.748736) (xy 17.569587 -153.782522) (xy 18.841718 -153.782522) (xy 18.845789 -153.7269)
			(xy 18.857915 -153.672463) (xy 18.877838 -153.620372) (xy 18.905134 -153.571737) (xy 18.93922 -153.527594)
			(xy 18.979369 -153.488885) (xy 19.024727 -153.456434) (xy 19.074327 -153.430933) (xy 19.127111 -153.412926)
			(xy 19.181954 -153.402796) (xy 19.237688 -153.400759) (xy 19.293125 -153.406859) (xy 19.347082 -153.420965)
			(xy 19.398411 -153.442777) (xy 19.446017 -153.471831) (xy 19.488885 -153.507506) (xy 19.526102 -153.549043)
			(xy 19.556875 -153.595556) (xy 19.580547 -153.646053) (xy 19.596615 -153.69946) (xy 19.604735 -153.754636)
			(xy 19.605244 -153.782522) (xy 19.857718 -153.782522) (xy 19.861789 -153.7269) (xy 19.873915 -153.672463)
			(xy 19.893838 -153.620372) (xy 19.921134 -153.571737) (xy 19.95522 -153.527594) (xy 19.995369 -153.488885)
			(xy 20.040727 -153.456434) (xy 20.090327 -153.430933) (xy 20.143111 -153.412926) (xy 20.197954 -153.402796)
			(xy 20.253688 -153.400759) (xy 20.309125 -153.406859) (xy 20.363082 -153.420965) (xy 20.414411 -153.442777)
			(xy 20.462017 -153.471831) (xy 20.504885 -153.507506) (xy 20.542102 -153.549043) (xy 20.572875 -153.595556)
			(xy 20.596547 -153.646053) (xy 20.612615 -153.69946) (xy 20.620735 -153.754636) (xy 20.621244 -153.782522)
			(xy 20.873718 -153.782522) (xy 20.877789 -153.7269) (xy 20.889915 -153.672463) (xy 20.909838 -153.620372)
			(xy 20.937134 -153.571737) (xy 20.97122 -153.527594) (xy 21.011369 -153.488885) (xy 21.056727 -153.456434)
			(xy 21.106327 -153.430933) (xy 21.159111 -153.412926) (xy 21.213954 -153.402796) (xy 21.269688 -153.400759)
			(xy 21.325125 -153.406859) (xy 21.379082 -153.420965) (xy 21.430411 -153.442777) (xy 21.478017 -153.471831)
			(xy 21.520885 -153.507506) (xy 21.558102 -153.549043) (xy 21.588875 -153.595556) (xy 21.612547 -153.646053)
			(xy 21.628615 -153.69946) (xy 21.636735 -153.754636) (xy 21.637244 -153.782522) (xy 21.889718 -153.782522)
			(xy 21.893789 -153.7269) (xy 21.905915 -153.672463) (xy 21.925838 -153.620372) (xy 21.953134 -153.571737)
			(xy 21.98722 -153.527594) (xy 22.027369 -153.488885) (xy 22.072727 -153.456434) (xy 22.122327 -153.430933)
			(xy 22.175111 -153.412926) (xy 22.229954 -153.402796) (xy 22.285688 -153.400759) (xy 22.341125 -153.406859)
			(xy 22.395082 -153.420965) (xy 22.446411 -153.442777) (xy 22.494017 -153.471831) (xy 22.536885 -153.507506)
			(xy 22.574102 -153.549043) (xy 22.604875 -153.595556) (xy 22.628547 -153.646053) (xy 22.644615 -153.69946)
			(xy 22.652735 -153.754636) (xy 22.653244 -153.782522) (xy 22.652735 -153.810408) (xy 22.644615 -153.865584)
			(xy 22.628547 -153.918991) (xy 22.604875 -153.969488) (xy 22.574102 -154.016001) (xy 22.536885 -154.057538)
			(xy 22.494017 -154.093213) (xy 22.446411 -154.122267) (xy 22.395082 -154.144079) (xy 22.341125 -154.158185)
			(xy 22.285688 -154.164285) (xy 22.229954 -154.162248) (xy 22.175111 -154.152118) (xy 22.122327 -154.134111)
			(xy 22.072727 -154.10861) (xy 22.027369 -154.076159) (xy 21.98722 -154.03745) (xy 21.953134 -153.993307)
			(xy 21.925838 -153.944672) (xy 21.905915 -153.892581) (xy 21.893789 -153.838144) (xy 21.889718 -153.782522)
			(xy 21.637244 -153.782522) (xy 21.636735 -153.810408) (xy 21.628615 -153.865584) (xy 21.612547 -153.918991)
			(xy 21.588875 -153.969488) (xy 21.558102 -154.016001) (xy 21.520885 -154.057538) (xy 21.478017 -154.093213)
			(xy 21.430411 -154.122267) (xy 21.379082 -154.144079) (xy 21.325125 -154.158185) (xy 21.269688 -154.164285)
			(xy 21.213954 -154.162248) (xy 21.159111 -154.152118) (xy 21.106327 -154.134111) (xy 21.056727 -154.10861)
			(xy 21.011369 -154.076159) (xy 20.97122 -154.03745) (xy 20.937134 -153.993307) (xy 20.909838 -153.944672)
			(xy 20.889915 -153.892581) (xy 20.877789 -153.838144) (xy 20.873718 -153.782522) (xy 20.621244 -153.782522)
			(xy 20.620735 -153.810408) (xy 20.612615 -153.865584) (xy 20.596547 -153.918991) (xy 20.572875 -153.969488)
			(xy 20.542102 -154.016001) (xy 20.504885 -154.057538) (xy 20.462017 -154.093213) (xy 20.414411 -154.122267)
			(xy 20.363082 -154.144079) (xy 20.309125 -154.158185) (xy 20.253688 -154.164285) (xy 20.197954 -154.162248)
			(xy 20.143111 -154.152118) (xy 20.090327 -154.134111) (xy 20.040727 -154.10861) (xy 19.995369 -154.076159)
			(xy 19.95522 -154.03745) (xy 19.921134 -153.993307) (xy 19.893838 -153.944672) (xy 19.873915 -153.892581)
			(xy 19.861789 -153.838144) (xy 19.857718 -153.782522) (xy 19.605244 -153.782522) (xy 19.604735 -153.810408)
			(xy 19.596615 -153.865584) (xy 19.580547 -153.918991) (xy 19.556875 -153.969488) (xy 19.526102 -154.016001)
			(xy 19.488885 -154.057538) (xy 19.446017 -154.093213) (xy 19.398411 -154.122267) (xy 19.347082 -154.144079)
			(xy 19.293125 -154.158185) (xy 19.237688 -154.164285) (xy 19.181954 -154.162248) (xy 19.127111 -154.152118)
			(xy 19.074327 -154.134111) (xy 19.024727 -154.10861) (xy 18.979369 -154.076159) (xy 18.93922 -154.03745)
			(xy 18.905134 -153.993307) (xy 18.877838 -153.944672) (xy 18.857915 -153.892581) (xy 18.845789 -153.838144)
			(xy 18.841718 -153.782522) (xy 17.569587 -153.782522) (xy 17.572735 -153.803912) (xy 17.573244 -153.831798)
			(xy 17.572735 -153.859684) (xy 17.564615 -153.91486) (xy 17.548547 -153.968267) (xy 17.524875 -154.018764)
			(xy 17.494102 -154.065277) (xy 17.456885 -154.106814) (xy 17.414017 -154.142489) (xy 17.366411 -154.171543)
			(xy 17.315082 -154.193355) (xy 17.261125 -154.207461) (xy 17.205688 -154.213561) (xy 17.149954 -154.211524)
			(xy 17.095111 -154.201394) (xy 17.042327 -154.183387) (xy 16.992727 -154.157886) (xy 16.947369 -154.125435)
			(xy 16.90722 -154.086726) (xy 16.873134 -154.042583) (xy 16.845838 -153.993948) (xy 16.825915 -153.941857)
			(xy 16.813789 -153.88742) (xy 16.809718 -153.831798) (xy 16.553605 -153.831798) (xy 16.547976 -153.868681)
			(xy 16.530698 -153.923923) (xy 16.505272 -153.975921) (xy 16.472282 -154.02348) (xy 16.432485 -154.065509)
			(xy 16.386795 -154.101043) (xy 16.336261 -154.129266) (xy 16.30934 -154.1399) (xy 16.295078 -154.145838)
			(xy 16.270742 -154.164843) (xy 16.25318 -154.190241) (xy 16.24399 -154.219721) (xy 16.244008 -154.250599)
			(xy 16.253233 -154.280068) (xy 16.261588 -154.293062) (xy 16.277702 -154.317188) (xy 16.303236 -154.369282)
			(xy 16.320593 -154.42464) (xy 16.329373 -154.481986) (xy 16.329914 -154.510994) (xy 16.329428 -154.538245)
			(xy 16.321672 -154.592193) (xy 16.306317 -154.644488) (xy 16.283675 -154.694065) (xy 16.254209 -154.739915)
			(xy 16.218518 -154.781106) (xy 16.177327 -154.816797) (xy 16.131477 -154.846263) (xy 16.0819 -154.868905)
			(xy 16.029605 -154.88426) (xy 15.975657 -154.892016) (xy 15.921155 -154.892016) (xy 15.867207 -154.88426)
			(xy 15.814912 -154.868905) (xy 15.765335 -154.846263) (xy 15.719485 -154.816797) (xy 15.678294 -154.781106)
			(xy 15.642603 -154.739915) (xy 15.613137 -154.694065) (xy 15.590495 -154.644488) (xy 15.57514 -154.592193)
			(xy 15.567384 -154.538245) (xy 15.566898 -154.510994) (xy 14.063853 -154.510994) (xy 14.047256 -154.548835)
			(xy 14.019704 -154.593678) (xy 13.98626 -154.634316) (xy 13.967206 -154.652472) (xy 13.959816 -154.660003)
			(xy 13.951285 -154.679276) (xy 13.950696 -154.68981) (xy 13.950696 -154.764486) (xy 13.951221 -154.775036)
			(xy 13.959759 -154.794331) (xy 13.967206 -154.801824) (xy 13.986267 -154.819974) (xy 14.019724 -154.860605)
			(xy 14.047282 -154.905446) (xy 14.068419 -154.953648) (xy 14.082735 -155.004297) (xy 14.089958 -155.056432)
			(xy 14.090396 -155.082748) (xy 14.089967 -155.110001) (xy 14.082203 -155.163951) (xy 14.066842 -155.216248)
			(xy 14.044194 -155.265826) (xy 14.014722 -155.311677) (xy 13.979024 -155.352867) (xy 13.937829 -155.388558)
			(xy 13.891973 -155.418023) (xy 13.842392 -155.440663) (xy 13.790093 -155.456016) (xy 13.736141 -155.463771)
			(xy 13.708888 -155.464256) (xy 13.682573 -155.463811) (xy 13.630443 -155.456573) (xy 13.579799 -155.442251)
			(xy 13.5316 -155.421114) (xy 13.486757 -155.393564) (xy 13.446119 -155.36012) (xy 13.427964 -155.341066)
			(xy 13.420449 -155.333656) (xy 13.401164 -155.325134) (xy 13.390626 -155.324556) (xy 13.31595 -155.324556)
			(xy 13.305404 -155.325112) (xy 13.286109 -155.33363) (xy 13.278612 -155.341066) (xy 13.258792 -155.361854)
			(xy 13.21402 -155.397829) (xy 13.164362 -155.426689) (xy 13.11094 -155.447782) (xy 13.054961 -155.460631)
			(xy 12.997688 -155.464946) (xy 12.940415 -155.460631) (xy 12.884436 -155.447782) (xy 12.831014 -155.426689)
			(xy 12.781356 -155.397829) (xy 12.736584 -155.361854) (xy 12.716764 -155.341066) (xy 12.709249 -155.333656)
			(xy 12.689964 -155.325134) (xy 12.679426 -155.324556) (xy 12.60475 -155.324556) (xy 12.594204 -155.325112)
			(xy 12.574909 -155.33363) (xy 12.567412 -155.341066) (xy 12.547592 -155.361854) (xy 12.50282 -155.397829)
			(xy 12.453162 -155.426689) (xy 12.39974 -155.447782) (xy 12.343761 -155.460631) (xy 12.286488 -155.464946)
			(xy 12.229215 -155.460631) (xy 12.173236 -155.447782) (xy 12.119814 -155.426689) (xy 12.070156 -155.397829)
			(xy 12.025384 -155.361854) (xy 12.005564 -155.341066) (xy 11.998049 -155.333656) (xy 11.978764 -155.325134)
			(xy 11.968226 -155.324556) (xy 11.89355 -155.324556) (xy 11.883004 -155.325112) (xy 11.863709 -155.33363)
			(xy 11.856212 -155.341066) (xy 11.838057 -155.360121) (xy 11.797425 -155.393576) (xy 11.752585 -155.421133)
			(xy 11.704384 -155.442271) (xy 11.653737 -155.456589) (xy 11.601604 -155.463816) (xy 11.575288 -155.464256)
			(xy 11.548037 -155.463774) (xy 11.494089 -155.456017) (xy 11.441794 -155.440662) (xy 11.392216 -155.41802)
			(xy 11.346366 -155.388554) (xy 11.305176 -155.352862) (xy 11.269484 -155.311671) (xy 11.240018 -155.26582)
			(xy 11.217377 -155.216243) (xy 11.202022 -155.163947) (xy 11.194266 -155.109999) (xy 11.19378 -155.082748)
			(xy 10.633391 -155.082748) (xy 10.632947 -155.107078) (xy 10.624827 -155.162254) (xy 10.608759 -155.215661)
			(xy 10.585087 -155.266158) (xy 10.554314 -155.312671) (xy 10.517097 -155.354208) (xy 10.474229 -155.389883)
			(xy 10.426623 -155.418937) (xy 10.375294 -155.440749) (xy 10.321337 -155.454855) (xy 10.2659 -155.460955)
			(xy 10.210166 -155.458918) (xy 10.155323 -155.448788) (xy 10.102539 -155.430781) (xy 10.052939 -155.40528)
			(xy 10.007581 -155.372829) (xy 9.967432 -155.33412) (xy 9.933346 -155.289977) (xy 9.90605 -155.241342)
			(xy 9.886127 -155.189251) (xy 9.874001 -155.134814) (xy 9.86993 -155.079192) (xy 9.056646 -155.079192)
			(xy 9.057327 -155.080645) (xy 9.073395 -155.134052) (xy 9.081515 -155.189228) (xy 9.082024 -155.217114)
			(xy 9.081515 -155.245) (xy 9.073395 -155.300176) (xy 9.057327 -155.353583) (xy 9.033655 -155.40408)
			(xy 9.002882 -155.450593) (xy 8.965665 -155.49213) (xy 8.922797 -155.527805) (xy 8.875191 -155.556859)
			(xy 8.823862 -155.578671) (xy 8.769905 -155.592777) (xy 8.714468 -155.598877) (xy 8.658734 -155.59684)
			(xy 8.603891 -155.58671) (xy 8.551107 -155.568703) (xy 8.501507 -155.543202) (xy 8.456149 -155.510751)
			(xy 8.416 -155.472042) (xy 8.381914 -155.427899) (xy 8.354618 -155.379264) (xy 8.334695 -155.327173)
			(xy 8.322569 -155.272736) (xy 8.318498 -155.217114) (xy 8.032657 -155.217114) (xy 8.032241 -155.23992)
			(xy 8.024121 -155.295096) (xy 8.008053 -155.348503) (xy 7.984381 -155.399) (xy 7.953608 -155.445513)
			(xy 7.916391 -155.48705) (xy 7.873523 -155.522725) (xy 7.825917 -155.551779) (xy 7.774588 -155.573591)
			(xy 7.720631 -155.587697) (xy 7.665194 -155.593797) (xy 7.60946 -155.59176) (xy 7.554617 -155.58163)
			(xy 7.501833 -155.563623) (xy 7.452233 -155.538122) (xy 7.406875 -155.505671) (xy 7.366726 -155.466962)
			(xy 7.33264 -155.422819) (xy 7.305344 -155.374184) (xy 7.285421 -155.322093) (xy 7.273295 -155.267656)
			(xy 7.269224 -155.212034) (xy 5.06984 -155.212034) (xy 5.06984 -156.69387) (xy 8.887458 -156.69387)
			(xy 8.891529 -156.638248) (xy 8.903655 -156.583811) (xy 8.923578 -156.53172) (xy 8.950874 -156.483085)
			(xy 8.98496 -156.438942) (xy 9.025109 -156.400233) (xy 9.070467 -156.367782) (xy 9.120067 -156.342281)
			(xy 9.172851 -156.324274) (xy 9.227694 -156.314144) (xy 9.283428 -156.312107) (xy 9.338865 -156.318207)
			(xy 9.392822 -156.332313) (xy 9.444151 -156.354125) (xy 9.491757 -156.383179) (xy 9.534625 -156.418854)
			(xy 9.571842 -156.460391) (xy 9.602615 -156.506904) (xy 9.626287 -156.557401) (xy 9.642355 -156.610808)
			(xy 9.650475 -156.665984) (xy 9.650984 -156.69387) (xy 9.650475 -156.721756) (xy 9.642355 -156.776932)
			(xy 9.626287 -156.830339) (xy 9.602615 -156.880836) (xy 9.571842 -156.927349) (xy 9.534625 -156.968886)
			(xy 9.491757 -157.004561) (xy 9.444151 -157.033615) (xy 9.392822 -157.055427) (xy 9.338865 -157.069533)
			(xy 9.283428 -157.075633) (xy 9.227694 -157.073596) (xy 9.172851 -157.063466) (xy 9.120067 -157.045459)
			(xy 9.070467 -157.019958) (xy 9.025109 -156.987507) (xy 8.98496 -156.948798) (xy 8.950874 -156.904655)
			(xy 8.923578 -156.85602) (xy 8.903655 -156.803929) (xy 8.891529 -156.749492) (xy 8.887458 -156.69387)
			(xy 5.06984 -156.69387) (xy 5.06984 -157.812994) (xy 6.650226 -157.812994) (xy 6.654297 -157.757372)
			(xy 6.666423 -157.702935) (xy 6.686346 -157.650844) (xy 6.713642 -157.602209) (xy 6.747728 -157.558066)
			(xy 6.787877 -157.519357) (xy 6.833235 -157.486906) (xy 6.882835 -157.461405) (xy 6.935619 -157.443398)
			(xy 6.990462 -157.433268) (xy 7.046196 -157.431231) (xy 7.101633 -157.437331) (xy 7.15559 -157.451437)
			(xy 7.206919 -157.473249) (xy 7.254525 -157.502303) (xy 7.297393 -157.537978) (xy 7.33461 -157.579515)
			(xy 7.365383 -157.626028) (xy 7.375633 -157.647894) (xy 11.013948 -157.647894) (xy 11.014459 -157.62125)
			(xy 11.022984 -157.568649) (xy 11.039844 -157.518099) (xy 11.064602 -157.470913) (xy 11.096615 -157.428313)
			(xy 11.135053 -157.391407) (xy 11.156696 -157.37586) (xy 11.167989 -157.367504) (xy 11.185848 -157.34583)
			(xy 11.197132 -157.320114) (xy 11.20099 -157.292297) (xy 11.19713 -157.26448) (xy 11.185844 -157.238764)
			(xy 11.167984 -157.217092) (xy 11.156696 -157.208728) (xy 11.135107 -157.193114) (xy 11.096689 -157.156206)
			(xy 11.064685 -157.113615) (xy 11.039924 -157.066445) (xy 11.023047 -157.015914) (xy 11.014491 -156.963331)
			(xy 11.013948 -156.936694) (xy 11.014458 -156.910707) (xy 11.022588 -156.859372) (xy 11.038649 -156.809942)
			(xy 11.062245 -156.763632) (xy 11.092795 -156.721584) (xy 11.129546 -156.684833) (xy 11.171594 -156.654283)
			(xy 11.217904 -156.630687) (xy 11.267334 -156.614626) (xy 11.318669 -156.606496) (xy 11.370643 -156.606496)
			(xy 11.421978 -156.614626) (xy 11.471408 -156.630687) (xy 11.517718 -156.654283) (xy 11.559766 -156.684833)
			(xy 11.596517 -156.721584) (xy 11.627067 -156.763632) (xy 11.650663 -156.809942) (xy 11.666724 -156.859372)
			(xy 11.674854 -156.910707) (xy 11.675364 -156.936694) (xy 11.674839 -156.963337) (xy 11.666316 -157.015937)
			(xy 11.649459 -157.066487) (xy 11.624703 -157.113673) (xy 11.592693 -157.156273) (xy 11.554258 -157.193181)
			(xy 11.532616 -157.208728) (xy 11.521334 -157.217098) (xy 11.503473 -157.238768) (xy 11.492187 -157.264482)
			(xy 11.488327 -157.292297) (xy 11.492185 -157.320112) (xy 11.50347 -157.345826) (xy 11.521328 -157.367497)
			(xy 11.532616 -157.37586) (xy 11.554202 -157.391478) (xy 11.59262 -157.428386) (xy 11.624623 -157.470975)
			(xy 11.649384 -157.518145) (xy 11.666262 -157.568675) (xy 11.674821 -157.621257) (xy 11.675364 -157.647894)
			(xy 11.91387 -157.647894) (xy 11.914371 -157.62125) (xy 11.922897 -157.568648) (xy 11.939758 -157.518097)
			(xy 11.964518 -157.47091) (xy 11.996533 -157.428311) (xy 12.034973 -157.391406) (xy 12.056618 -157.37586)
			(xy 12.067909 -157.367503) (xy 12.085764 -157.345828) (xy 12.097046 -157.320112) (xy 12.100903 -157.292297)
			(xy 12.097044 -157.264481) (xy 12.08576 -157.238766) (xy 12.067904 -157.217092) (xy 12.056618 -157.208728)
			(xy 12.035012 -157.193137) (xy 11.996598 -157.156222) (xy 11.964599 -157.113625) (xy 11.939842 -157.066451)
			(xy 11.922968 -157.015917) (xy 11.914412 -156.963332) (xy 11.91387 -156.936694) (xy 11.91438 -156.910707)
			(xy 11.92251 -156.859372) (xy 11.938571 -156.809942) (xy 11.962167 -156.763632) (xy 11.992717 -156.721584)
			(xy 12.029468 -156.684833) (xy 12.071516 -156.654283) (xy 12.117826 -156.630687) (xy 12.167256 -156.614626)
			(xy 12.218591 -156.606496) (xy 12.270565 -156.606496) (xy 12.3219 -156.614626) (xy 12.37133 -156.630687)
			(xy 12.41764 -156.654283) (xy 12.459688 -156.684833) (xy 12.496439 -156.721584) (xy 12.526989 -156.763632)
			(xy 12.550585 -156.809942) (xy 12.566646 -156.859372) (xy 12.574776 -156.910707) (xy 12.575286 -156.936694)
			(xy 12.574752 -156.963337) (xy 12.56623 -157.015936) (xy 12.549373 -157.066485) (xy 12.52462 -157.113671)
			(xy 12.492611 -157.156271) (xy 12.454179 -157.19318) (xy 12.432538 -157.208728) (xy 12.421262 -157.217102)
			(xy 12.403416 -157.238776) (xy 12.392139 -157.264487) (xy 12.388282 -157.292297) (xy 12.392137 -157.320106)
			(xy 12.403412 -157.345818) (xy 12.421257 -157.367493) (xy 12.432538 -157.37586) (xy 12.454129 -157.391471)
			(xy 12.492545 -157.428381) (xy 12.524548 -157.470973) (xy 12.549308 -157.518144) (xy 12.566185 -157.568674)
			(xy 12.574743 -157.621257) (xy 12.575286 -157.647894) (xy 12.813792 -157.647894) (xy 12.814327 -157.621251)
			(xy 12.82285 -157.568653) (xy 12.839707 -157.518105) (xy 12.864461 -157.470918) (xy 12.896468 -157.428318)
			(xy 12.9349 -157.391409) (xy 12.95654 -157.37586) (xy 12.967829 -157.367502) (xy 12.98568 -157.345826)
			(xy 12.996959 -157.320111) (xy 13.000815 -157.292297) (xy 12.996957 -157.264483) (xy 12.985677 -157.238768)
			(xy 12.967824 -157.217094) (xy 12.95654 -157.208728) (xy 12.934939 -157.193131) (xy 12.896524 -157.156217)
			(xy 12.864523 -157.113623) (xy 12.839765 -157.066449) (xy 12.82289 -157.015916) (xy 12.814334 -156.963332)
			(xy 12.813792 -156.936694) (xy 12.814302 -156.910707) (xy 12.822432 -156.859372) (xy 12.838493 -156.809942)
			(xy 12.862089 -156.763632) (xy 12.892639 -156.721584) (xy 12.92939 -156.684833) (xy 12.971438 -156.654283)
			(xy 13.017748 -156.630687) (xy 13.067178 -156.614626) (xy 13.118513 -156.606496) (xy 13.170487 -156.606496)
			(xy 13.221822 -156.614626) (xy 13.271252 -156.630687) (xy 13.317562 -156.654283) (xy 13.35961 -156.684833)
			(xy 13.396361 -156.721584) (xy 13.426911 -156.763632) (xy 13.450507 -156.809942) (xy 13.466568 -156.859372)
			(xy 13.474698 -156.910707) (xy 13.475208 -156.936694) (xy 13.474664 -156.963336) (xy 13.466143 -157.015935)
			(xy 13.449288 -157.066482) (xy 13.424536 -157.113669) (xy 13.39253 -157.156269) (xy 13.3541 -157.193179)
			(xy 13.33246 -157.208728) (xy 13.321182 -157.217101) (xy 13.303332 -157.238773) (xy 13.292052 -157.264485)
			(xy 13.288195 -157.292297) (xy 13.29205 -157.320108) (xy 13.303328 -157.345821) (xy 13.321177 -157.367494)
			(xy 13.33246 -157.37586) (xy 13.354056 -157.391465) (xy 13.392471 -157.428377) (xy 13.424472 -157.47097)
			(xy 13.449231 -157.518142) (xy 13.466107 -157.568673) (xy 13.474665 -157.621257) (xy 13.475208 -157.647894)
			(xy 13.713968 -157.647894) (xy 13.71447 -157.62125) (xy 13.722996 -157.568648) (xy 13.739857 -157.518098)
			(xy 13.764617 -157.470911) (xy 13.796632 -157.428312) (xy 13.835071 -157.391406) (xy 13.856716 -157.37586)
			(xy 13.868008 -157.367503) (xy 13.885863 -157.345828) (xy 13.897145 -157.320112) (xy 13.901002 -157.292297)
			(xy 13.897143 -157.264481) (xy 13.885859 -157.238766) (xy 13.868002 -157.217092) (xy 13.856716 -157.208728)
			(xy 13.83511 -157.193138) (xy 13.796696 -157.156222) (xy 13.764697 -157.113626) (xy 13.73994 -157.066451)
			(xy 13.723066 -157.015917) (xy 13.71451 -156.963332) (xy 13.713968 -156.936694) (xy 13.714478 -156.910707)
			(xy 13.722608 -156.859372) (xy 13.738669 -156.809942) (xy 13.762265 -156.763632) (xy 13.792815 -156.721584)
			(xy 13.829566 -156.684833) (xy 13.871614 -156.654283) (xy 13.917924 -156.630687) (xy 13.967354 -156.614626)
			(xy 14.018689 -156.606496) (xy 14.070663 -156.606496) (xy 14.121998 -156.614626) (xy 14.171428 -156.630687)
			(xy 14.217738 -156.654283) (xy 14.259786 -156.684833) (xy 14.296537 -156.721584) (xy 14.327087 -156.763632)
			(xy 14.350683 -156.809942) (xy 14.366744 -156.859372) (xy 14.374874 -156.910707) (xy 14.375384 -156.936694)
			(xy 14.374851 -156.963337) (xy 14.366328 -157.015936) (xy 14.349472 -157.066485) (xy 14.324718 -157.113671)
			(xy 14.29271 -157.156271) (xy 14.254277 -157.19318) (xy 14.232636 -157.208728) (xy 14.221352 -157.217097)
			(xy 14.203488 -157.238766) (xy 14.192199 -157.26448) (xy 14.188338 -157.292297) (xy 14.192197 -157.320113)
			(xy 14.203484 -157.345828) (xy 14.221347 -157.367498) (xy 14.232636 -157.37586) (xy 14.254226 -157.391472)
			(xy 14.292643 -157.428382) (xy 14.324645 -157.470973) (xy 14.349405 -157.518144) (xy 14.366283 -157.568674)
			(xy 14.374841 -157.621257) (xy 14.375343 -157.645862) (xy 15.329408 -157.645862) (xy 15.329848 -157.619547)
			(xy 15.337088 -157.567417) (xy 15.351412 -157.516774) (xy 15.37255 -157.468575) (xy 15.400101 -157.423732)
			(xy 15.433544 -157.383094) (xy 15.452598 -157.364938) (xy 15.459984 -157.357404) (xy 15.468517 -157.338133)
			(xy 15.469108 -157.3276) (xy 15.469108 -157.252924) (xy 15.468577 -157.242375) (xy 15.460043 -157.223079)
			(xy 15.452598 -157.215586) (xy 15.433542 -157.197431) (xy 15.400085 -157.156801) (xy 15.372526 -157.111961)
			(xy 15.351388 -157.06376) (xy 15.337071 -157.013112) (xy 15.329846 -156.960978) (xy 15.329408 -156.934662)
			(xy 15.329894 -156.907411) (xy 15.33765 -156.853463) (xy 15.353005 -156.801168) (xy 15.375647 -156.751591)
			(xy 15.405113 -156.705741) (xy 15.440804 -156.66455) (xy 15.481995 -156.628859) (xy 15.527845 -156.599393)
			(xy 15.577422 -156.576751) (xy 15.629717 -156.561396) (xy 15.683665 -156.55364) (xy 15.738167 -156.55364)
			(xy 15.792115 -156.561396) (xy 15.84441 -156.576751) (xy 15.893987 -156.599393) (xy 15.939837 -156.628859)
			(xy 15.958582 -156.645101) (xy 17.31399 -156.645101) (xy 17.318305 -156.587829) (xy 17.331153 -156.531851)
			(xy 17.352244 -156.478429) (xy 17.381102 -156.428772) (xy 17.417075 -156.383999) (xy 17.437862 -156.364178)
			(xy 17.445269 -156.356661) (xy 17.453792 -156.337378) (xy 17.454372 -156.32684) (xy 17.454372 -156.252164)
			(xy 17.45383 -156.241616) (xy 17.445305 -156.22232) (xy 17.437862 -156.214826) (xy 17.418819 -156.196658)
			(xy 17.385362 -156.15603) (xy 17.357802 -156.111192) (xy 17.336662 -156.062994) (xy 17.322342 -156.012349)
			(xy 17.315113 -155.960217) (xy 17.314672 -155.933902) (xy 17.315158 -155.906651) (xy 17.322914 -155.852703)
			(xy 17.338269 -155.800408) (xy 17.360911 -155.750831) (xy 17.390377 -155.704981) (xy 17.426068 -155.66379)
			(xy 17.467259 -155.628099) (xy 17.513109 -155.598633) (xy 17.562686 -155.575991) (xy 17.614981 -155.560636)
			(xy 17.668929 -155.55288) (xy 17.723431 -155.55288) (xy 17.777379 -155.560636) (xy 17.829674 -155.575991)
			(xy 17.879251 -155.598633) (xy 17.925101 -155.628099) (xy 17.966292 -155.66379) (xy 18.001983 -155.704981)
			(xy 18.031449 -155.750831) (xy 18.054091 -155.800408) (xy 18.069446 -155.852703) (xy 18.077202 -155.906651)
			(xy 18.077688 -155.933902) (xy 18.077226 -155.960216) (xy 18.06999 -156.012345) (xy 18.055671 -156.062988)
			(xy 18.034537 -156.111187) (xy 18.00699 -156.15603) (xy 17.97355 -156.19667) (xy 17.954498 -156.214826)
			(xy 17.947083 -156.222336) (xy 17.938566 -156.241625) (xy 17.937988 -156.252164) (xy 17.937988 -156.32684)
			(xy 17.938539 -156.337387) (xy 17.947059 -156.356682) (xy 17.954498 -156.364178) (xy 17.975289 -156.383995)
			(xy 18.011266 -156.428768) (xy 18.040127 -156.478425) (xy 18.061221 -156.531848) (xy 18.07407 -156.587828)
			(xy 18.078386 -156.645101) (xy 18.07407 -156.702375) (xy 18.072934 -156.707322) (xy 20.379798 -156.707322)
			(xy 20.38411 -156.650054) (xy 20.396954 -156.594078) (xy 20.41804 -156.540659) (xy 20.446892 -156.491002)
			(xy 20.482858 -156.446229) (xy 20.503642 -156.426408) (xy 20.511034 -156.418878) (xy 20.519566 -156.399605)
			(xy 20.520152 -156.38907) (xy 20.520152 -156.314394) (xy 20.519654 -156.30384) (xy 20.511098 -156.284544)
			(xy 20.503642 -156.277056) (xy 20.484561 -156.258926) (xy 20.451108 -156.21829) (xy 20.423554 -156.173444)
			(xy 20.402421 -156.125238) (xy 20.388108 -156.074587) (xy 20.380888 -156.022449) (xy 20.380452 -155.996132)
			(xy 20.380938 -155.968881) (xy 20.388694 -155.914933) (xy 20.404049 -155.862638) (xy 20.426691 -155.813061)
			(xy 20.456157 -155.767211) (xy 20.491848 -155.72602) (xy 20.533039 -155.690329) (xy 20.578889 -155.660863)
			(xy 20.628466 -155.638221) (xy 20.680761 -155.622866) (xy 20.734709 -155.61511) (xy 20.789211 -155.61511)
			(xy 20.843159 -155.622866) (xy 20.895454 -155.638221) (xy 20.945031 -155.660863) (xy 20.990881 -155.690329)
			(xy 21.032072 -155.72602) (xy 21.067763 -155.767211) (xy 21.097229 -155.813061) (xy 21.119871 -155.862638)
			(xy 21.135226 -155.914933) (xy 21.142982 -155.968881) (xy 21.143468 -155.996132) (xy 21.143032 -156.022447)
			(xy 21.135792 -156.074577) (xy 21.121468 -156.125221) (xy 21.100329 -156.17342) (xy 21.072777 -156.218263)
			(xy 21.039333 -156.258901) (xy 21.020278 -156.277056) (xy 21.01289 -156.284589) (xy 21.004359 -156.303861)
			(xy 21.003768 -156.314394) (xy 21.003768 -156.38907) (xy 21.004309 -156.399618) (xy 21.012837 -156.418913)
			(xy 21.020278 -156.426408) (xy 21.0411 -156.446195) (xy 21.077078 -156.490971) (xy 21.10594 -156.540633)
			(xy 21.127033 -156.59406) (xy 21.139882 -156.650044) (xy 21.144195 -156.707322) (xy 21.139875 -156.764599)
			(xy 21.12702 -156.820582) (xy 21.105921 -156.874006) (xy 21.077054 -156.923665) (xy 21.04107 -156.968437)
			(xy 21.020278 -156.988256) (xy 21.01289 -156.995789) (xy 21.004359 -157.015061) (xy 21.003768 -157.025594)
			(xy 21.003768 -157.10027) (xy 21.004309 -157.110818) (xy 21.012837 -157.130113) (xy 21.020278 -157.137608)
			(xy 21.039326 -157.155771) (xy 21.072785 -157.196399) (xy 21.100345 -157.241237) (xy 21.121485 -157.289437)
			(xy 21.135804 -157.340083) (xy 21.143029 -157.392216) (xy 21.143468 -157.418532) (xy 21.142982 -157.445783)
			(xy 21.135226 -157.499731) (xy 21.119871 -157.552026) (xy 21.097229 -157.601603) (xy 21.067763 -157.647453)
			(xy 21.032072 -157.688644) (xy 20.990881 -157.724335) (xy 20.945031 -157.753801) (xy 20.895454 -157.776443)
			(xy 20.843159 -157.791798) (xy 20.789211 -157.799554) (xy 20.734709 -157.799554) (xy 20.680761 -157.791798)
			(xy 20.628466 -157.776443) (xy 20.578889 -157.753801) (xy 20.533039 -157.724335) (xy 20.491848 -157.688644)
			(xy 20.456157 -157.647453) (xy 20.426691 -157.601603) (xy 20.404049 -157.552026) (xy 20.388694 -157.499731)
			(xy 20.380938 -157.445783) (xy 20.380452 -157.418532) (xy 20.380857 -157.392216) (xy 20.388103 -157.340084)
			(xy 20.402433 -157.289439) (xy 20.423577 -157.24124) (xy 20.451135 -157.196398) (xy 20.484585 -157.155762)
			(xy 20.503642 -157.137608) (xy 20.511034 -157.130078) (xy 20.519566 -157.110805) (xy 20.520152 -157.10027)
			(xy 20.520152 -157.025594) (xy 20.519654 -157.01504) (xy 20.511098 -156.995744) (xy 20.503642 -156.988256)
			(xy 20.482888 -156.968403) (xy 20.446916 -156.923634) (xy 20.418059 -156.87398) (xy 20.396967 -156.820564)
			(xy 20.384116 -156.764589) (xy 20.379798 -156.707322) (xy 18.072934 -156.707322) (xy 18.06122 -156.758355)
			(xy 18.040126 -156.811777) (xy 18.011264 -156.861435) (xy 17.975287 -156.906207) (xy 17.954498 -156.926026)
			(xy 17.947083 -156.933536) (xy 17.938566 -156.952825) (xy 17.937988 -156.963364) (xy 17.937988 -157.03804)
			(xy 17.938539 -157.048587) (xy 17.947059 -157.067882) (xy 17.954498 -157.075378) (xy 17.973536 -157.093552)
			(xy 18.006994 -157.134177) (xy 18.034556 -157.179014) (xy 18.055697 -157.227211) (xy 18.070018 -157.277855)
			(xy 18.077247 -157.329987) (xy 18.077688 -157.356302) (xy 18.077202 -157.383553) (xy 18.069446 -157.437501)
			(xy 18.054091 -157.489796) (xy 18.031449 -157.539373) (xy 18.001983 -157.585223) (xy 17.966292 -157.626414)
			(xy 17.925101 -157.662105) (xy 17.879251 -157.691571) (xy 17.829674 -157.714213) (xy 17.777379 -157.729568)
			(xy 17.723431 -157.737324) (xy 17.668929 -157.737324) (xy 17.614981 -157.729568) (xy 17.562686 -157.714213)
			(xy 17.513109 -157.691571) (xy 17.467259 -157.662105) (xy 17.426068 -157.626414) (xy 17.390377 -157.585223)
			(xy 17.360911 -157.539373) (xy 17.338269 -157.489796) (xy 17.322914 -157.437501) (xy 17.315158 -157.383553)
			(xy 17.314672 -157.356302) (xy 17.31515 -157.329988) (xy 17.322384 -157.277861) (xy 17.336701 -157.227219)
			(xy 17.357832 -157.17902) (xy 17.385376 -157.134176) (xy 17.418812 -157.093535) (xy 17.437862 -157.075378)
			(xy 17.445269 -157.067861) (xy 17.453792 -157.048578) (xy 17.454372 -157.03804) (xy 17.454372 -156.963364)
			(xy 17.45383 -156.952816) (xy 17.445305 -156.93352) (xy 17.437862 -156.926026) (xy 17.417077 -156.906203)
			(xy 17.381104 -156.861431) (xy 17.352245 -156.811773) (xy 17.331154 -156.758352) (xy 17.318305 -156.702373)
			(xy 17.31399 -156.645101) (xy 15.958582 -156.645101) (xy 15.981028 -156.66455) (xy 16.016719 -156.705741)
			(xy 16.046185 -156.751591) (xy 16.068827 -156.801168) (xy 16.084182 -156.853463) (xy 16.091938 -156.907411)
			(xy 16.092424 -156.934662) (xy 16.09199 -156.960977) (xy 16.084747 -157.013107) (xy 16.070421 -157.06375)
			(xy 16.049282 -157.111948) (xy 16.021731 -157.156791) (xy 15.988288 -157.19743) (xy 15.969234 -157.215586)
			(xy 15.961841 -157.223115) (xy 15.953311 -157.242389) (xy 15.952724 -157.252924) (xy 15.952724 -157.3276)
			(xy 15.953233 -157.338152) (xy 15.961781 -157.357448) (xy 15.969234 -157.364938) (xy 15.988307 -157.383075)
			(xy 16.021762 -157.42371) (xy 16.049317 -157.468554) (xy 16.070453 -157.516758) (xy 16.084766 -157.567409)
			(xy 16.091987 -157.619545) (xy 16.092424 -157.645862) (xy 16.091938 -157.673113) (xy 16.084182 -157.727061)
			(xy 16.068827 -157.779356) (xy 16.046185 -157.828933) (xy 16.016719 -157.874783) (xy 15.981028 -157.915974)
			(xy 15.939837 -157.951665) (xy 15.893987 -157.981131) (xy 15.84441 -158.003773) (xy 15.792115 -158.019128)
			(xy 15.738167 -158.026884) (xy 15.683665 -158.026884) (xy 15.629717 -158.019128) (xy 15.577422 -158.003773)
			(xy 15.527845 -157.981131) (xy 15.481995 -157.951665) (xy 15.440804 -157.915974) (xy 15.405113 -157.874783)
			(xy 15.375647 -157.828933) (xy 15.353005 -157.779356) (xy 15.33765 -157.727061) (xy 15.329894 -157.673113)
			(xy 15.329408 -157.645862) (xy 14.375343 -157.645862) (xy 14.375384 -157.647894) (xy 14.374874 -157.673881)
			(xy 14.366744 -157.725216) (xy 14.350683 -157.774646) (xy 14.327087 -157.820956) (xy 14.296537 -157.863004)
			(xy 14.259786 -157.899755) (xy 14.217738 -157.930305) (xy 14.171428 -157.953901) (xy 14.121998 -157.969962)
			(xy 14.070663 -157.978092) (xy 14.018689 -157.978092) (xy 13.967354 -157.969962) (xy 13.917924 -157.953901)
			(xy 13.871614 -157.930305) (xy 13.829566 -157.899755) (xy 13.792815 -157.863004) (xy 13.762265 -157.820956)
			(xy 13.738669 -157.774646) (xy 13.722608 -157.725216) (xy 13.714478 -157.673881) (xy 13.713968 -157.647894)
			(xy 13.475208 -157.647894) (xy 13.474698 -157.673881) (xy 13.466568 -157.725216) (xy 13.450507 -157.774646)
			(xy 13.426911 -157.820956) (xy 13.396361 -157.863004) (xy 13.35961 -157.899755) (xy 13.317562 -157.930305)
			(xy 13.271252 -157.953901) (xy 13.221822 -157.969962) (xy 13.170487 -157.978092) (xy 13.118513 -157.978092)
			(xy 13.067178 -157.969962) (xy 13.017748 -157.953901) (xy 12.971438 -157.930305) (xy 12.92939 -157.899755)
			(xy 12.892639 -157.863004) (xy 12.862089 -157.820956) (xy 12.838493 -157.774646) (xy 12.822432 -157.725216)
			(xy 12.814302 -157.673881) (xy 12.813792 -157.647894) (xy 12.575286 -157.647894) (xy 12.574776 -157.673881)
			(xy 12.566646 -157.725216) (xy 12.550585 -157.774646) (xy 12.526989 -157.820956) (xy 12.496439 -157.863004)
			(xy 12.459688 -157.899755) (xy 12.41764 -157.930305) (xy 12.37133 -157.953901) (xy 12.3219 -157.969962)
			(xy 12.270565 -157.978092) (xy 12.218591 -157.978092) (xy 12.167256 -157.969962) (xy 12.117826 -157.953901)
			(xy 12.071516 -157.930305) (xy 12.029468 -157.899755) (xy 11.992717 -157.863004) (xy 11.962167 -157.820956)
			(xy 11.938571 -157.774646) (xy 11.92251 -157.725216) (xy 11.91438 -157.673881) (xy 11.91387 -157.647894)
			(xy 11.675364 -157.647894) (xy 11.674854 -157.673881) (xy 11.666724 -157.725216) (xy 11.650663 -157.774646)
			(xy 11.627067 -157.820956) (xy 11.596517 -157.863004) (xy 11.559766 -157.899755) (xy 11.517718 -157.930305)
			(xy 11.471408 -157.953901) (xy 11.421978 -157.969962) (xy 11.370643 -157.978092) (xy 11.318669 -157.978092)
			(xy 11.267334 -157.969962) (xy 11.217904 -157.953901) (xy 11.171594 -157.930305) (xy 11.129546 -157.899755)
			(xy 11.092795 -157.863004) (xy 11.062245 -157.820956) (xy 11.038649 -157.774646) (xy 11.022588 -157.725216)
			(xy 11.014458 -157.673881) (xy 11.013948 -157.647894) (xy 7.375633 -157.647894) (xy 7.389055 -157.676525)
			(xy 7.405123 -157.729932) (xy 7.413243 -157.785108) (xy 7.413752 -157.812994) (xy 7.413243 -157.84088)
			(xy 7.405123 -157.896056) (xy 7.389055 -157.949463) (xy 7.365383 -157.99996) (xy 7.33461 -158.046473)
			(xy 7.32214 -158.06039) (xy 8.839706 -158.06039) (xy 8.843777 -158.004768) (xy 8.855903 -157.950331)
			(xy 8.875826 -157.89824) (xy 8.903122 -157.849605) (xy 8.937208 -157.805462) (xy 8.977357 -157.766753)
			(xy 9.022715 -157.734302) (xy 9.072315 -157.708801) (xy 9.125099 -157.690794) (xy 9.179942 -157.680664)
			(xy 9.235676 -157.678627) (xy 9.291113 -157.684727) (xy 9.34507 -157.698833) (xy 9.396399 -157.720645)
			(xy 9.444005 -157.749699) (xy 9.486873 -157.785374) (xy 9.52409 -157.826911) (xy 9.554863 -157.873424)
			(xy 9.578535 -157.923921) (xy 9.594603 -157.977328) (xy 9.602723 -158.032504) (xy 9.603232 -158.06039)
			(xy 9.602723 -158.088276) (xy 9.594603 -158.143452) (xy 9.578535 -158.196859) (xy 9.554863 -158.247356)
			(xy 9.52409 -158.293869) (xy 9.486873 -158.335406) (xy 9.444005 -158.371081) (xy 9.396399 -158.400135)
			(xy 9.34507 -158.421947) (xy 9.291113 -158.436053) (xy 9.235676 -158.442153) (xy 9.179942 -158.440116)
			(xy 9.125099 -158.429986) (xy 9.072315 -158.411979) (xy 9.022715 -158.386478) (xy 8.977357 -158.354027)
			(xy 8.937208 -158.315318) (xy 8.903122 -158.271175) (xy 8.875826 -158.22254) (xy 8.855903 -158.170449)
			(xy 8.843777 -158.116012) (xy 8.839706 -158.06039) (xy 7.32214 -158.06039) (xy 7.297393 -158.08801)
			(xy 7.254525 -158.123685) (xy 7.206919 -158.152739) (xy 7.15559 -158.174551) (xy 7.101633 -158.188657)
			(xy 7.046196 -158.194757) (xy 6.990462 -158.19272) (xy 6.935619 -158.18259) (xy 6.882835 -158.164583)
			(xy 6.833235 -158.139082) (xy 6.787877 -158.106631) (xy 6.747728 -158.067922) (xy 6.713642 -158.023779)
			(xy 6.686346 -157.975144) (xy 6.666423 -157.923053) (xy 6.654297 -157.868616) (xy 6.650226 -157.812994)
			(xy 5.06984 -157.812994) (xy 5.06984 -159.14751) (xy 5.070371 -159.157464) (xy 5.07803 -159.175847)
			(xy 5.092084 -159.189957) (xy 5.101082 -159.194246) (xy 5.110528 -159.197802) (xy 5.130694 -159.197919)
			(xy 5.149326 -159.190205) (xy 5.156708 -159.183324) (xy 5.74548 -158.594298) (xy 5.764261 -158.576187)
			(xy 5.806459 -158.545508) (xy 5.852941 -158.521813) (xy 5.902559 -158.505689) (xy 5.95409 -158.497532)
			(xy 5.980176 -158.497016) (xy 6.831584 -158.497016) (xy 6.837451 -158.496861) (xy 6.848868 -158.494157)
			(xy 6.85419 -158.491682) (xy 6.854698 -158.491428) (xy 6.882226 -158.477592) (xy 6.940639 -158.458013)
			(xy 7.001441 -158.448081) (xy 7.032244 -158.447486) (xy 7.059495 -158.447972) (xy 7.113442 -158.455729)
			(xy 7.165735 -158.471084) (xy 7.215311 -158.493725) (xy 7.261161 -158.523191) (xy 7.30235 -158.558883)
			(xy 7.338041 -158.600072) (xy 7.367507 -158.645922) (xy 7.390147 -158.695499) (xy 7.405502 -158.747792)
			(xy 7.413258 -158.801739) (xy 7.413258 -158.856241) (xy 7.405502 -158.910188) (xy 7.390147 -158.962481)
			(xy 7.367507 -159.012058) (xy 7.338041 -159.057908) (xy 7.30235 -159.099097) (xy 7.261161 -159.134789)
			(xy 7.215311 -159.164255) (xy 7.165735 -159.186896) (xy 7.113442 -159.202251) (xy 7.059495 -159.210008)
			(xy 7.032244 -159.210502) (xy 7.001539 -159.209867) (xy 6.940928 -159.199991) (xy 6.882681 -159.180537)
			(xy 6.855206 -159.166814) (xy 6.85419 -159.166306) (xy 6.848856 -159.163512) (xy 6.83768 -159.160972)
			(xy 6.138672 -159.160972) (xy 6.128603 -159.161399) (xy 6.110004 -159.169118) (xy 6.102604 -159.175958)
			(xy 5.83946 -159.439102) (xy 8.908032 -159.439102) (xy 8.912103 -159.38348) (xy 8.924229 -159.329043)
			(xy 8.944152 -159.276952) (xy 8.971448 -159.228317) (xy 9.005534 -159.184174) (xy 9.045683 -159.145465)
			(xy 9.091041 -159.113014) (xy 9.140641 -159.087513) (xy 9.193425 -159.069506) (xy 9.248268 -159.059376)
			(xy 9.304002 -159.057339) (xy 9.359439 -159.063439) (xy 9.413396 -159.077545) (xy 9.464725 -159.099357)
			(xy 9.512331 -159.128411) (xy 9.555199 -159.164086) (xy 9.592416 -159.205623) (xy 9.623189 -159.252136)
			(xy 9.646861 -159.302633) (xy 9.662929 -159.35604) (xy 9.671049 -159.411216) (xy 9.671558 -159.439102)
			(xy 9.671049 -159.466988) (xy 9.662929 -159.522164) (xy 9.660026 -159.531812) (xy 12.11275 -159.531812)
			(xy 12.116821 -159.47619) (xy 12.128947 -159.421753) (xy 12.14887 -159.369662) (xy 12.176166 -159.321027)
			(xy 12.210252 -159.276884) (xy 12.250401 -159.238175) (xy 12.295759 -159.205724) (xy 12.345359 -159.180223)
			(xy 12.398143 -159.162216) (xy 12.452986 -159.152086) (xy 12.50872 -159.150049) (xy 12.564157 -159.156149)
			(xy 12.618114 -159.170255) (xy 12.669443 -159.192067) (xy 12.717049 -159.221121) (xy 12.759917 -159.256796)
			(xy 12.797134 -159.298333) (xy 12.827907 -159.344846) (xy 12.851579 -159.395343) (xy 12.867647 -159.44875)
			(xy 12.875767 -159.503926) (xy 12.876171 -159.526041) (xy 13.11375 -159.526041) (xy 13.11375 -159.471539)
			(xy 13.121506 -159.417592) (xy 13.136861 -159.365298) (xy 13.159502 -159.315721) (xy 13.188967 -159.269871)
			(xy 13.224658 -159.228681) (xy 13.265848 -159.19299) (xy 13.311698 -159.163524) (xy 13.361274 -159.140882)
			(xy 13.413568 -159.125527) (xy 13.467515 -159.11777) (xy 13.494766 -159.117284) (xy 13.522928 -159.117818)
			(xy 13.578639 -159.126095) (xy 13.632529 -159.142473) (xy 13.683424 -159.166596) (xy 13.73022 -159.197941)
			(xy 13.771897 -159.235826) (xy 13.807552 -159.279427) (xy 13.836408 -159.327797) (xy 13.857839 -159.379883)
			(xy 13.865098 -159.407098) (xy 13.867809 -159.416357) (xy 13.879054 -159.432019) (xy 13.886942 -159.437578)
			(xy 13.95349 -159.480758) (xy 13.972032 -159.484568) (xy 13.981938 -159.48279) (xy 13.998994 -159.479837)
			(xy 14.033464 -159.476658) (xy 14.050772 -159.47644) (xy 14.076304 -159.476853) (xy 14.126912 -159.483662)
			(xy 14.176159 -159.497162) (xy 14.223165 -159.517111) (xy 14.245336 -159.52978) (xy 14.256512 -159.536384)
			(xy 14.28242 -159.5374) (xy 14.370558 -159.492696) (xy 14.378009 -159.488522) (xy 14.389865 -159.476244)
			(xy 14.397058 -159.460767) (xy 14.398244 -159.45231) (xy 14.398244 -159.452056) (xy 14.401475 -159.424093)
			(xy 14.415041 -159.369465) (xy 14.436488 -159.317423) (xy 14.465348 -159.269097) (xy 14.500997 -159.225537)
			(xy 14.54266 -159.187689) (xy 14.589432 -159.156373) (xy 14.640298 -159.132271) (xy 14.694154 -159.115904)
			(xy 14.74983 -159.107629) (xy 14.777974 -159.107124) (xy 14.805225 -159.107606) (xy 14.859173 -159.115363)
			(xy 14.911467 -159.130719) (xy 14.961044 -159.15336) (xy 15.006894 -159.182827) (xy 15.048084 -159.218518)
			(xy 15.083776 -159.259709) (xy 15.113242 -159.305559) (xy 15.135883 -159.355136) (xy 15.151238 -159.407431)
			(xy 15.158994 -159.461379) (xy 15.158994 -159.515881) (xy 15.151238 -159.569829) (xy 15.15017 -159.573468)
			(xy 16.512032 -159.573468) (xy 16.512554 -159.545657) (xy 16.520622 -159.490623) (xy 16.536598 -159.437345)
			(xy 16.560143 -159.386952) (xy 16.590757 -159.340512) (xy 16.627791 -159.299012) (xy 16.67046 -159.26333)
			(xy 16.693896 -159.248348) (xy 16.706199 -159.240207) (xy 16.725866 -159.218232) (xy 16.738436 -159.191556)
			(xy 16.742864 -159.162401) (xy 16.73878 -159.133196) (xy 16.726524 -159.106374) (xy 16.707117 -159.084169)
			(xy 16.694912 -159.075882) (xy 16.671929 -159.060829) (xy 16.63017 -159.025129) (xy 16.593962 -158.983808)
			(xy 16.564054 -158.937722) (xy 16.541065 -158.887824) (xy 16.52547 -158.835144) (xy 16.51759 -158.780772)
			(xy 16.517112 -158.753302) (xy 16.517598 -158.726051) (xy 16.525354 -158.672103) (xy 16.540709 -158.619808)
			(xy 16.563351 -158.570231) (xy 16.592817 -158.524381) (xy 16.628508 -158.48319) (xy 16.669699 -158.447499)
			(xy 16.715549 -158.418033) (xy 16.765126 -158.395391) (xy 16.817421 -158.380036) (xy 16.871369 -158.37228)
			(xy 16.925871 -158.37228) (xy 16.979819 -158.380036) (xy 17.032114 -158.395391) (xy 17.081691 -158.418033)
			(xy 17.127541 -158.447499) (xy 17.168732 -158.48319) (xy 17.204423 -158.524381) (xy 17.233889 -158.570231)
			(xy 17.256531 -158.619808) (xy 17.271886 -158.672103) (xy 17.279642 -158.726051) (xy 17.280128 -158.753302)
			(xy 17.27968 -158.781116) (xy 17.2716 -158.836154) (xy 17.255613 -158.889435) (xy 17.232056 -158.939829)
			(xy 17.201431 -158.986267) (xy 17.164385 -159.027765) (xy 17.121705 -159.063442) (xy 17.098264 -159.078422)
			(xy 17.085993 -159.086605) (xy 17.066336 -159.108573) (xy 17.05377 -159.135239) (xy 17.049341 -159.164383)
			(xy 17.053418 -159.193578) (xy 17.065661 -159.220394) (xy 17.085051 -159.242598) (xy 17.097248 -159.250888)
			(xy 17.120208 -159.265974) (xy 17.16197 -159.301668) (xy 17.19818 -159.342982) (xy 17.228091 -159.389062)
			(xy 17.251084 -159.438956) (xy 17.266684 -159.491631) (xy 17.274567 -159.546) (xy 17.275048 -159.573468)
			(xy 17.274562 -159.600719) (xy 17.266806 -159.654667) (xy 17.251451 -159.706962) (xy 17.228809 -159.756539)
			(xy 17.199343 -159.802389) (xy 17.163652 -159.84358) (xy 17.122461 -159.879271) (xy 17.076611 -159.908737)
			(xy 17.027034 -159.931379) (xy 16.974739 -159.946734) (xy 16.920791 -159.95449) (xy 16.866289 -159.95449)
			(xy 16.812341 -159.946734) (xy 16.760046 -159.931379) (xy 16.710469 -159.908737) (xy 16.664619 -159.879271)
			(xy 16.623428 -159.84358) (xy 16.587737 -159.802389) (xy 16.558271 -159.756539) (xy 16.535629 -159.706962)
			(xy 16.520274 -159.654667) (xy 16.512518 -159.600719) (xy 16.512032 -159.573468) (xy 15.15017 -159.573468)
			(xy 15.135883 -159.622124) (xy 15.113242 -159.671701) (xy 15.083776 -159.717551) (xy 15.048084 -159.758742)
			(xy 15.006894 -159.794433) (xy 14.961044 -159.8239) (xy 14.911467 -159.846541) (xy 14.859173 -159.861897)
			(xy 14.805225 -159.869654) (xy 14.777974 -159.87014) (xy 14.752442 -159.86974) (xy 14.701833 -159.862926)
			(xy 14.652586 -159.849422) (xy 14.605581 -159.82947) (xy 14.58341 -159.8168) (xy 14.572234 -159.810196)
			(xy 14.546326 -159.80918) (xy 14.458188 -159.853884) (xy 14.450733 -159.858051) (xy 14.438881 -159.870334)
			(xy 14.431689 -159.885813) (xy 14.430502 -159.89427) (xy 14.430502 -159.894524) (xy 14.427307 -159.922492)
			(xy 14.413741 -159.977125) (xy 14.392294 -160.02917) (xy 14.36343 -160.077499) (xy 14.327777 -160.121061)
			(xy 14.286109 -160.15891) (xy 14.239332 -160.190224) (xy 14.18846 -160.214324) (xy 14.134599 -160.230686)
			(xy 14.078918 -160.238955) (xy 14.050772 -160.239456) (xy 14.022606 -160.239023) (xy 13.966888 -160.230736)
			(xy 13.912994 -160.214346) (xy 13.862095 -160.190211) (xy 13.815299 -160.158853) (xy 13.773622 -160.120956)
			(xy 13.73797 -160.077342) (xy 13.709119 -160.02896) (xy 13.687695 -159.976862) (xy 13.68044 -159.949642)
			(xy 13.6777 -159.940394) (xy 13.666474 -159.924727) (xy 13.658596 -159.919162) (xy 13.592048 -159.875982)
			(xy 13.573506 -159.872172) (xy 13.5636 -159.87395) (xy 13.546544 -159.876898) (xy 13.512074 -159.88008)
			(xy 13.494766 -159.8803) (xy 13.467515 -159.87981) (xy 13.413568 -159.872053) (xy 13.361274 -159.856698)
			(xy 13.311698 -159.834056) (xy 13.265848 -159.80459) (xy 13.224658 -159.768899) (xy 13.188967 -159.727709)
			(xy 13.159502 -159.681859) (xy 13.136861 -159.632282) (xy 13.121506 -159.579988) (xy 13.11375 -159.526041)
			(xy 12.876171 -159.526041) (xy 12.876276 -159.531812) (xy 12.875767 -159.559698) (xy 12.867647 -159.614874)
			(xy 12.851579 -159.668281) (xy 12.827907 -159.718778) (xy 12.797134 -159.765291) (xy 12.759917 -159.806828)
			(xy 12.717049 -159.842503) (xy 12.669443 -159.871557) (xy 12.618114 -159.893369) (xy 12.564157 -159.907475)
			(xy 12.50872 -159.913575) (xy 12.452986 -159.911538) (xy 12.398143 -159.901408) (xy 12.345359 -159.883401)
			(xy 12.295759 -159.8579) (xy 12.250401 -159.825449) (xy 12.210252 -159.78674) (xy 12.176166 -159.742597)
			(xy 12.14887 -159.693962) (xy 12.128947 -159.641871) (xy 12.116821 -159.587434) (xy 12.11275 -159.531812)
			(xy 9.660026 -159.531812) (xy 9.646861 -159.575571) (xy 9.623189 -159.626068) (xy 9.592416 -159.672581)
			(xy 9.555199 -159.714118) (xy 9.512331 -159.749793) (xy 9.464725 -159.778847) (xy 9.413396 -159.800659)
			(xy 9.359439 -159.814765) (xy 9.304002 -159.820865) (xy 9.248268 -159.818828) (xy 9.193425 -159.808698)
			(xy 9.140641 -159.790691) (xy 9.091041 -159.76519) (xy 9.045683 -159.732739) (xy 9.005534 -159.69403)
			(xy 8.971448 -159.649887) (xy 8.944152 -159.601252) (xy 8.924229 -159.549161) (xy 8.912103 -159.494724)
			(xy 8.908032 -159.439102) (xy 5.83946 -159.439102) (xy 5.630418 -159.648144) (xy 5.623576 -159.655544)
			(xy 5.615855 -159.674142) (xy 5.615432 -159.684212) (xy 5.615432 -159.844994) (xy 6.650226 -159.844994)
			(xy 6.654297 -159.789372) (xy 6.666423 -159.734935) (xy 6.686346 -159.682844) (xy 6.713642 -159.634209)
			(xy 6.747728 -159.590066) (xy 6.787877 -159.551357) (xy 6.833235 -159.518906) (xy 6.882835 -159.493405)
			(xy 6.935619 -159.475398) (xy 6.990462 -159.465268) (xy 7.046196 -159.463231) (xy 7.101633 -159.469331)
			(xy 7.15559 -159.483437) (xy 7.206919 -159.505249) (xy 7.254525 -159.534303) (xy 7.297393 -159.569978)
			(xy 7.33461 -159.611515) (xy 7.365383 -159.658028) (xy 7.389055 -159.708525) (xy 7.405123 -159.761932)
			(xy 7.413243 -159.817108) (xy 7.413752 -159.844994) (xy 7.413243 -159.87288) (xy 7.405123 -159.928056)
			(xy 7.389055 -159.981463) (xy 7.365383 -160.03196) (xy 7.33461 -160.078473) (xy 7.297393 -160.12001)
			(xy 7.254525 -160.155685) (xy 7.206919 -160.184739) (xy 7.15559 -160.206551) (xy 7.101633 -160.220657)
			(xy 7.046196 -160.226757) (xy 6.990462 -160.22472) (xy 6.935619 -160.21459) (xy 6.882835 -160.196583)
			(xy 6.833235 -160.171082) (xy 6.787877 -160.138631) (xy 6.747728 -160.099922) (xy 6.713642 -160.055779)
			(xy 6.686346 -160.007144) (xy 6.666423 -159.955053) (xy 6.654297 -159.900616) (xy 6.650226 -159.844994)
			(xy 5.615432 -159.844994) (xy 5.615432 -160.92424) (xy 7.098536 -160.92424) (xy 7.102607 -160.868618)
			(xy 7.114733 -160.814181) (xy 7.134656 -160.76209) (xy 7.161952 -160.713455) (xy 7.196038 -160.669312)
			(xy 7.236187 -160.630603) (xy 7.281545 -160.598152) (xy 7.331145 -160.572651) (xy 7.383929 -160.554644)
			(xy 7.438772 -160.544514) (xy 7.494506 -160.542477) (xy 7.549943 -160.548577) (xy 7.6039 -160.562683)
			(xy 7.655229 -160.584495) (xy 7.702835 -160.613549) (xy 7.745703 -160.649224) (xy 7.78292 -160.690761)
			(xy 7.813693 -160.737274) (xy 7.837365 -160.787771) (xy 7.853433 -160.841178) (xy 7.861553 -160.896354)
			(xy 7.862062 -160.92424) (xy 7.861553 -160.952126) (xy 7.859527 -160.965896) (xy 8.93775 -160.965896)
			(xy 8.941821 -160.910274) (xy 8.953947 -160.855837) (xy 8.97387 -160.803746) (xy 9.001166 -160.755111)
			(xy 9.035252 -160.710968) (xy 9.075401 -160.672259) (xy 9.120759 -160.639808) (xy 9.170359 -160.614307)
			(xy 9.223143 -160.5963) (xy 9.277986 -160.58617) (xy 9.33372 -160.584133) (xy 9.389157 -160.590233)
			(xy 9.443114 -160.604339) (xy 9.494443 -160.626151) (xy 9.542049 -160.655205) (xy 9.584917 -160.69088)
			(xy 9.622134 -160.732417) (xy 9.652907 -160.77893) (xy 9.676579 -160.829427) (xy 9.692647 -160.882834)
			(xy 9.700767 -160.93801) (xy 9.701239 -160.963864) (xy 10.32967 -160.963864) (xy 10.333741 -160.908242)
			(xy 10.345867 -160.853805) (xy 10.36579 -160.801714) (xy 10.393086 -160.753079) (xy 10.427172 -160.708936)
			(xy 10.467321 -160.670227) (xy 10.512679 -160.637776) (xy 10.562279 -160.612275) (xy 10.615063 -160.594268)
			(xy 10.669906 -160.584138) (xy 10.72564 -160.582101) (xy 10.781077 -160.588201) (xy 10.835034 -160.602307)
			(xy 10.886363 -160.624119) (xy 10.933969 -160.653173) (xy 10.976837 -160.688848) (xy 11.014054 -160.730385)
			(xy 11.044827 -160.776898) (xy 11.068499 -160.827395) (xy 11.084567 -160.880802) (xy 11.092687 -160.935978)
			(xy 11.093196 -160.963864) (xy 11.093103 -160.968944) (xy 11.601448 -160.968944) (xy 11.605519 -160.913322)
			(xy 11.617645 -160.858885) (xy 11.637568 -160.806794) (xy 11.664864 -160.758159) (xy 11.69895 -160.714016)
			(xy 11.739099 -160.675307) (xy 11.784457 -160.642856) (xy 11.834057 -160.617355) (xy 11.886841 -160.599348)
			(xy 11.941684 -160.589218) (xy 11.997418 -160.587181) (xy 12.052855 -160.593281) (xy 12.106812 -160.607387)
			(xy 12.158141 -160.629199) (xy 12.205747 -160.658253) (xy 12.248615 -160.693928) (xy 12.285832 -160.735465)
			(xy 12.316605 -160.781978) (xy 12.340277 -160.832475) (xy 12.356345 -160.885882) (xy 12.358738 -160.902142)
			(xy 13.38275 -160.902142) (xy 13.386821 -160.84652) (xy 13.398947 -160.792083) (xy 13.41887 -160.739992)
			(xy 13.446166 -160.691357) (xy 13.480252 -160.647214) (xy 13.520401 -160.608505) (xy 13.565759 -160.576054)
			(xy 13.615359 -160.550553) (xy 13.668143 -160.532546) (xy 13.722986 -160.522416) (xy 13.77872 -160.520379)
			(xy 13.834157 -160.526479) (xy 13.888114 -160.540585) (xy 13.939443 -160.562397) (xy 13.987049 -160.591451)
			(xy 14.029917 -160.627126) (xy 14.067134 -160.668663) (xy 14.097907 -160.715176) (xy 14.121579 -160.765673)
			(xy 14.137647 -160.81908) (xy 14.145767 -160.874256) (xy 14.146276 -160.902142) (xy 14.145767 -160.930028)
			(xy 14.137647 -160.985204) (xy 14.121579 -161.038611) (xy 14.097907 -161.089108) (xy 14.067134 -161.135621)
			(xy 14.029917 -161.177158) (xy 13.987049 -161.212833) (xy 13.939443 -161.241887) (xy 13.888114 -161.263699)
			(xy 13.834157 -161.277805) (xy 13.77872 -161.283905) (xy 13.722986 -161.281868) (xy 13.668143 -161.271738)
			(xy 13.615359 -161.253731) (xy 13.565759 -161.22823) (xy 13.520401 -161.195779) (xy 13.480252 -161.15707)
			(xy 13.446166 -161.112927) (xy 13.41887 -161.064292) (xy 13.398947 -161.012201) (xy 13.386821 -160.957764)
			(xy 13.38275 -160.902142) (xy 12.358738 -160.902142) (xy 12.364465 -160.941058) (xy 12.364974 -160.968944)
			(xy 12.364465 -160.99683) (xy 12.356345 -161.052006) (xy 12.340277 -161.105413) (xy 12.316605 -161.15591)
			(xy 12.285832 -161.202423) (xy 12.248615 -161.24396) (xy 12.205747 -161.279635) (xy 12.158141 -161.308689)
			(xy 12.106812 -161.330501) (xy 12.052855 -161.344607) (xy 11.997418 -161.350707) (xy 11.941684 -161.34867)
			(xy 11.886841 -161.33854) (xy 11.834057 -161.320533) (xy 11.784457 -161.295032) (xy 11.739099 -161.262581)
			(xy 11.69895 -161.223872) (xy 11.664864 -161.179729) (xy 11.637568 -161.131094) (xy 11.617645 -161.079003)
			(xy 11.605519 -161.024566) (xy 11.601448 -160.968944) (xy 11.093103 -160.968944) (xy 11.092687 -160.99175)
			(xy 11.084567 -161.046926) (xy 11.068499 -161.100333) (xy 11.044827 -161.15083) (xy 11.014054 -161.197343)
			(xy 10.976837 -161.23888) (xy 10.933969 -161.274555) (xy 10.886363 -161.303609) (xy 10.835034 -161.325421)
			(xy 10.781077 -161.339527) (xy 10.72564 -161.345627) (xy 10.669906 -161.34359) (xy 10.615063 -161.33346)
			(xy 10.562279 -161.315453) (xy 10.512679 -161.289952) (xy 10.467321 -161.257501) (xy 10.427172 -161.218792)
			(xy 10.393086 -161.174649) (xy 10.36579 -161.126014) (xy 10.345867 -161.073923) (xy 10.333741 -161.019486)
			(xy 10.32967 -160.963864) (xy 9.701239 -160.963864) (xy 9.701276 -160.965896) (xy 9.700767 -160.993782)
			(xy 9.692647 -161.048958) (xy 9.676579 -161.102365) (xy 9.652907 -161.152862) (xy 9.622134 -161.199375)
			(xy 9.584917 -161.240912) (xy 9.542049 -161.276587) (xy 9.494443 -161.305641) (xy 9.443114 -161.327453)
			(xy 9.389157 -161.341559) (xy 9.33372 -161.347659) (xy 9.277986 -161.345622) (xy 9.223143 -161.335492)
			(xy 9.170359 -161.317485) (xy 9.120759 -161.291984) (xy 9.075401 -161.259533) (xy 9.035252 -161.220824)
			(xy 9.001166 -161.176681) (xy 8.97387 -161.128046) (xy 8.953947 -161.075955) (xy 8.941821 -161.021518)
			(xy 8.93775 -160.965896) (xy 7.859527 -160.965896) (xy 7.853433 -161.007302) (xy 7.837365 -161.060709)
			(xy 7.813693 -161.111206) (xy 7.78292 -161.157719) (xy 7.745703 -161.199256) (xy 7.702835 -161.234931)
			(xy 7.655229 -161.263985) (xy 7.6039 -161.285797) (xy 7.549943 -161.299903) (xy 7.494506 -161.306003)
			(xy 7.438772 -161.303966) (xy 7.383929 -161.293836) (xy 7.331145 -161.275829) (xy 7.281545 -161.250328)
			(xy 7.236187 -161.217877) (xy 7.196038 -161.179168) (xy 7.161952 -161.135025) (xy 7.134656 -161.08639)
			(xy 7.114733 -161.034299) (xy 7.102607 -160.979862) (xy 7.098536 -160.92424) (xy 5.615432 -160.92424)
			(xy 5.615432 -161.54528) (xy 17.313966 -161.54528) (xy 17.318285 -161.488005) (xy 17.331137 -161.432023)
			(xy 17.352233 -161.3786) (xy 17.381095 -161.32894) (xy 17.417073 -161.284167) (xy 17.437862 -161.264346)
			(xy 17.445284 -161.256841) (xy 17.453798 -161.237549) (xy 17.454372 -161.227008) (xy 17.454372 -161.152332)
			(xy 17.453848 -161.141782) (xy 17.44531 -161.122486) (xy 17.437862 -161.114994) (xy 17.418803 -161.096842)
			(xy 17.385348 -161.056211) (xy 17.35779 -161.011369) (xy 17.336653 -160.963168) (xy 17.322336 -160.91252)
			(xy 17.315111 -160.860386) (xy 17.314672 -160.83407) (xy 17.315158 -160.806819) (xy 17.322914 -160.752871)
			(xy 17.338269 -160.700576) (xy 17.360911 -160.650999) (xy 17.390377 -160.605149) (xy 17.426068 -160.563958)
			(xy 17.467259 -160.528267) (xy 17.513109 -160.498801) (xy 17.562686 -160.476159) (xy 17.614981 -160.460804)
			(xy 17.668929 -160.453048) (xy 17.723431 -160.453048) (xy 17.777379 -160.460804) (xy 17.829674 -160.476159)
			(xy 17.879251 -160.498801) (xy 17.925101 -160.528267) (xy 17.966292 -160.563958) (xy 18.001983 -160.605149)
			(xy 18.031449 -160.650999) (xy 18.054091 -160.700576) (xy 18.069446 -160.752871) (xy 18.077202 -160.806819)
			(xy 18.077688 -160.83407) (xy 18.077271 -160.860386) (xy 18.070026 -160.912517) (xy 18.055698 -160.96316)
			(xy 18.034556 -161.011359) (xy 18.007001 -161.056202) (xy 17.973554 -161.096839) (xy 17.954498 -161.114994)
			(xy 17.947097 -161.122516) (xy 17.938572 -161.141796) (xy 17.937988 -161.152332) (xy 17.937988 -161.227008)
			(xy 17.938503 -161.237559) (xy 17.947048 -161.256854) (xy 17.954498 -161.264346) (xy 17.975257 -161.284196)
			(xy 18.011234 -161.328963) (xy 18.040096 -161.378616) (xy 18.061192 -161.432034) (xy 18.074044 -161.48801)
			(xy 18.078362 -161.54528) (xy 18.07405 -161.60255) (xy 18.072914 -161.6075) (xy 20.379775 -161.6075)
			(xy 20.38409 -161.550229) (xy 20.396938 -161.49425) (xy 20.418028 -161.440829) (xy 20.446885 -161.391171)
			(xy 20.482856 -161.346397) (xy 20.503642 -161.326576) (xy 20.511048 -161.319057) (xy 20.519572 -161.299775)
			(xy 20.520152 -161.289238) (xy 20.520152 -161.214562) (xy 20.519617 -161.204013) (xy 20.511088 -161.184716)
			(xy 20.503642 -161.177224) (xy 20.484594 -161.159061) (xy 20.451138 -161.118432) (xy 20.42358 -161.073593)
			(xy 20.40244 -161.025393) (xy 20.388121 -160.974748) (xy 20.380893 -160.922616) (xy 20.380452 -160.8963)
			(xy 20.380938 -160.869049) (xy 20.388694 -160.815101) (xy 20.404049 -160.762806) (xy 20.426691 -160.713229)
			(xy 20.456157 -160.667379) (xy 20.491848 -160.626188) (xy 20.533039 -160.590497) (xy 20.578889 -160.561031)
			(xy 20.628466 -160.538389) (xy 20.680761 -160.523034) (xy 20.734709 -160.515278) (xy 20.789211 -160.515278)
			(xy 20.843159 -160.523034) (xy 20.895454 -160.538389) (xy 20.945031 -160.561031) (xy 20.990881 -160.590497)
			(xy 21.032072 -160.626188) (xy 21.067763 -160.667379) (xy 21.097229 -160.713229) (xy 21.119871 -160.762806)
			(xy 21.135226 -160.815101) (xy 21.142982 -160.869049) (xy 21.143468 -160.8963) (xy 21.143011 -160.922614)
			(xy 21.135775 -160.974744) (xy 21.121455 -161.025387) (xy 21.100321 -161.073586) (xy 21.072772 -161.118429)
			(xy 21.039331 -161.159068) (xy 21.020278 -161.177224) (xy 21.01286 -161.184732) (xy 21.004346 -161.204022)
			(xy 21.003768 -161.214562) (xy 21.003768 -161.289238) (xy 21.004327 -161.299784) (xy 21.012842 -161.319079)
			(xy 21.020278 -161.326576) (xy 21.041068 -161.346395) (xy 21.077047 -161.391166) (xy 21.105909 -161.440824)
			(xy 21.127004 -161.494246) (xy 21.139855 -161.550226) (xy 21.144171 -161.6075) (xy 21.139855 -161.664774)
			(xy 21.127004 -161.720754) (xy 21.105909 -161.774176) (xy 21.077047 -161.823834) (xy 21.041068 -161.868605)
			(xy 21.020278 -161.888424) (xy 21.01286 -161.895932) (xy 21.004346 -161.915222) (xy 21.003768 -161.925762)
			(xy 21.003768 -162.000438) (xy 21.004327 -162.010984) (xy 21.012842 -162.030279) (xy 21.020278 -162.037776)
			(xy 21.039311 -162.055955) (xy 21.072771 -162.096579) (xy 21.100333 -162.141414) (xy 21.121476 -162.18961)
			(xy 21.135798 -162.240254) (xy 21.143027 -162.292385) (xy 21.143468 -162.3187) (xy 21.142982 -162.345951)
			(xy 21.135226 -162.399899) (xy 21.119871 -162.452194) (xy 21.097229 -162.501771) (xy 21.067763 -162.547621)
			(xy 21.032072 -162.588812) (xy 20.990881 -162.624503) (xy 20.945031 -162.653969) (xy 20.895454 -162.676611)
			(xy 20.843159 -162.691966) (xy 20.789211 -162.699722) (xy 20.734709 -162.699722) (xy 20.680761 -162.691966)
			(xy 20.628466 -162.676611) (xy 20.578889 -162.653969) (xy 20.533039 -162.624503) (xy 20.491848 -162.588812)
			(xy 20.456157 -162.547621) (xy 20.426691 -162.501771) (xy 20.404049 -162.452194) (xy 20.388694 -162.399899)
			(xy 20.380938 -162.345951) (xy 20.380452 -162.3187) (xy 20.380903 -162.292385) (xy 20.388139 -162.240255)
			(xy 20.40246 -162.189612) (xy 20.423595 -162.141412) (xy 20.451145 -162.096569) (xy 20.484588 -162.055931)
			(xy 20.503642 -162.037776) (xy 20.511048 -162.030257) (xy 20.519572 -162.010975) (xy 20.520152 -162.000438)
			(xy 20.520152 -161.925762) (xy 20.519617 -161.915213) (xy 20.511088 -161.895916) (xy 20.503642 -161.888424)
			(xy 20.482856 -161.868603) (xy 20.446885 -161.823829) (xy 20.418028 -161.774171) (xy 20.396938 -161.72075)
			(xy 20.38409 -161.664771) (xy 20.379775 -161.6075) (xy 18.072914 -161.6075) (xy 18.061204 -161.658527)
			(xy 18.040114 -161.711947) (xy 18.011257 -161.761603) (xy 17.975285 -161.806375) (xy 17.954498 -161.826194)
			(xy 17.947097 -161.833716) (xy 17.938572 -161.852996) (xy 17.937988 -161.863532) (xy 17.937988 -161.938208)
			(xy 17.938503 -161.948759) (xy 17.947048 -161.968054) (xy 17.954498 -161.975546) (xy 17.973568 -161.993687)
			(xy 18.007024 -162.034319) (xy 18.034581 -162.079163) (xy 18.055717 -162.127367) (xy 18.070031 -162.178017)
			(xy 18.077252 -162.230153) (xy 18.077688 -162.25647) (xy 18.077202 -162.283721) (xy 18.069446 -162.337669)
			(xy 18.054091 -162.389964) (xy 18.031449 -162.439541) (xy 18.001983 -162.485391) (xy 17.966292 -162.526582)
			(xy 17.925101 -162.562273) (xy 17.879251 -162.591739) (xy 17.829674 -162.614381) (xy 17.777379 -162.629736)
			(xy 17.723431 -162.637492) (xy 17.668929 -162.637492) (xy 17.614981 -162.629736) (xy 17.562686 -162.614381)
			(xy 17.513109 -162.591739) (xy 17.467259 -162.562273) (xy 17.426068 -162.526582) (xy 17.390377 -162.485391)
			(xy 17.360911 -162.439541) (xy 17.338269 -162.389964) (xy 17.322914 -162.337669) (xy 17.315158 -162.283721)
			(xy 17.314672 -162.25647) (xy 17.315128 -162.230156) (xy 17.322367 -162.178027) (xy 17.336689 -162.127385)
			(xy 17.357823 -162.079186) (xy 17.385371 -162.034343) (xy 17.41881 -161.993703) (xy 17.437862 -161.975546)
			(xy 17.445284 -161.968041) (xy 17.453798 -161.948749) (xy 17.454372 -161.938208) (xy 17.454372 -161.863532)
			(xy 17.453848 -161.852982) (xy 17.44531 -161.833686) (xy 17.437862 -161.826194) (xy 17.417045 -161.806404)
			(xy 17.381072 -161.761626) (xy 17.352215 -161.711964) (xy 17.331125 -161.658538) (xy 17.318279 -161.602555)
			(xy 17.313966 -161.54528) (xy 5.615432 -161.54528) (xy 5.615432 -163.021518) (xy 8.93775 -163.021518)
			(xy 8.941821 -162.965896) (xy 8.953947 -162.911459) (xy 8.97387 -162.859368) (xy 9.001166 -162.810733)
			(xy 9.035252 -162.76659) (xy 9.075401 -162.727881) (xy 9.120759 -162.69543) (xy 9.170359 -162.669929)
			(xy 9.223143 -162.651922) (xy 9.277986 -162.641792) (xy 9.33372 -162.639755) (xy 9.389157 -162.645855)
			(xy 9.443114 -162.659961) (xy 9.494443 -162.681773) (xy 9.542049 -162.710827) (xy 9.584917 -162.746502)
			(xy 9.622134 -162.788039) (xy 9.652907 -162.834552) (xy 9.676579 -162.885049) (xy 9.692647 -162.938456)
			(xy 9.700767 -162.993632) (xy 9.701276 -163.021518) (xy 10.33475 -163.021518) (xy 10.338821 -162.965896)
			(xy 10.350947 -162.911459) (xy 10.37087 -162.859368) (xy 10.398166 -162.810733) (xy 10.432252 -162.76659)
			(xy 10.472401 -162.727881) (xy 10.517759 -162.69543) (xy 10.567359 -162.669929) (xy 10.620143 -162.651922)
			(xy 10.674986 -162.641792) (xy 10.73072 -162.639755) (xy 10.786157 -162.645855) (xy 10.840114 -162.659961)
			(xy 10.891443 -162.681773) (xy 10.939049 -162.710827) (xy 10.981917 -162.746502) (xy 11.019134 -162.788039)
			(xy 11.049907 -162.834552) (xy 11.073579 -162.885049) (xy 11.089647 -162.938456) (xy 11.097767 -162.993632)
			(xy 11.098276 -163.021518) (xy 11.097767 -163.049404) (xy 11.089647 -163.10458) (xy 11.086591 -163.114736)
			(xy 16.04975 -163.114736) (xy 16.053821 -163.059114) (xy 16.065947 -163.004677) (xy 16.08587 -162.952586)
			(xy 16.113166 -162.903951) (xy 16.147252 -162.859808) (xy 16.187401 -162.821099) (xy 16.232759 -162.788648)
			(xy 16.282359 -162.763147) (xy 16.335143 -162.74514) (xy 16.389986 -162.73501) (xy 16.44572 -162.732973)
			(xy 16.501157 -162.739073) (xy 16.555114 -162.753179) (xy 16.606443 -162.774991) (xy 16.654049 -162.804045)
			(xy 16.696917 -162.83972) (xy 16.734134 -162.881257) (xy 16.764907 -162.92777) (xy 16.788579 -162.978267)
			(xy 16.804647 -163.031674) (xy 16.812767 -163.08685) (xy 16.813276 -163.114736) (xy 16.812767 -163.142622)
			(xy 16.804647 -163.197798) (xy 16.788579 -163.251205) (xy 16.764907 -163.301702) (xy 16.734134 -163.348215)
			(xy 16.696917 -163.389752) (xy 16.654049 -163.425427) (xy 16.606443 -163.454481) (xy 16.555114 -163.476293)
			(xy 16.501157 -163.490399) (xy 16.44572 -163.496499) (xy 16.389986 -163.494462) (xy 16.335143 -163.484332)
			(xy 16.282359 -163.466325) (xy 16.232759 -163.440824) (xy 16.187401 -163.408373) (xy 16.147252 -163.369664)
			(xy 16.113166 -163.325521) (xy 16.08587 -163.276886) (xy 16.065947 -163.224795) (xy 16.053821 -163.170358)
			(xy 16.04975 -163.114736) (xy 11.086591 -163.114736) (xy 11.073579 -163.157987) (xy 11.049907 -163.208484)
			(xy 11.019134 -163.254997) (xy 10.981917 -163.296534) (xy 10.939049 -163.332209) (xy 10.891443 -163.361263)
			(xy 10.840114 -163.383075) (xy 10.786157 -163.397181) (xy 10.73072 -163.403281) (xy 10.674986 -163.401244)
			(xy 10.620143 -163.391114) (xy 10.567359 -163.373107) (xy 10.517759 -163.347606) (xy 10.472401 -163.315155)
			(xy 10.432252 -163.276446) (xy 10.398166 -163.232303) (xy 10.37087 -163.183668) (xy 10.350947 -163.131577)
			(xy 10.338821 -163.07714) (xy 10.33475 -163.021518) (xy 9.701276 -163.021518) (xy 9.700767 -163.049404)
			(xy 9.692647 -163.10458) (xy 9.676579 -163.157987) (xy 9.652907 -163.208484) (xy 9.622134 -163.254997)
			(xy 9.584917 -163.296534) (xy 9.542049 -163.332209) (xy 9.494443 -163.361263) (xy 9.443114 -163.383075)
			(xy 9.389157 -163.397181) (xy 9.33372 -163.403281) (xy 9.277986 -163.401244) (xy 9.223143 -163.391114)
			(xy 9.170359 -163.373107) (xy 9.120759 -163.347606) (xy 9.075401 -163.315155) (xy 9.035252 -163.276446)
			(xy 9.001166 -163.232303) (xy 8.97387 -163.183668) (xy 8.953947 -163.131577) (xy 8.941821 -163.07714)
			(xy 8.93775 -163.021518) (xy 5.615432 -163.021518) (xy 5.615432 -165.058852) (xy 23.355806 -165.058852)
			(xy 23.359877 -165.00323) (xy 23.372003 -164.948793) (xy 23.391926 -164.896702) (xy 23.419222 -164.848067)
			(xy 23.453308 -164.803924) (xy 23.493457 -164.765215) (xy 23.538815 -164.732764) (xy 23.588415 -164.707263)
			(xy 23.641199 -164.689256) (xy 23.696042 -164.679126) (xy 23.751776 -164.677089) (xy 23.807213 -164.683189)
			(xy 23.86117 -164.697295) (xy 23.912499 -164.719107) (xy 23.960105 -164.748161) (xy 24.002973 -164.783836)
			(xy 24.04019 -164.825373) (xy 24.070963 -164.871886) (xy 24.094635 -164.922383) (xy 24.110703 -164.97579)
			(xy 24.118823 -165.030966) (xy 24.119332 -165.058852) (xy 24.118823 -165.086738) (xy 24.110703 -165.141914)
			(xy 24.094635 -165.195321) (xy 24.070963 -165.245818) (xy 24.04019 -165.292331) (xy 24.002973 -165.333868)
			(xy 23.960105 -165.369543) (xy 23.912499 -165.398597) (xy 23.86117 -165.420409) (xy 23.807213 -165.434515)
			(xy 23.751776 -165.440615) (xy 23.696042 -165.438578) (xy 23.641199 -165.428448) (xy 23.588415 -165.410441)
			(xy 23.538815 -165.38494) (xy 23.493457 -165.352489) (xy 23.453308 -165.31378) (xy 23.419222 -165.269637)
			(xy 23.391926 -165.221002) (xy 23.372003 -165.168911) (xy 23.359877 -165.114474) (xy 23.355806 -165.058852)
			(xy 5.615432 -165.058852) (xy 5.615432 -166.8526) (xy 19.462748 -166.8526) (xy 19.466819 -166.796978)
			(xy 19.478945 -166.742541) (xy 19.498868 -166.69045) (xy 19.526164 -166.641815) (xy 19.56025 -166.597672)
			(xy 19.600399 -166.558963) (xy 19.645757 -166.526512) (xy 19.695357 -166.501011) (xy 19.748141 -166.483004)
			(xy 19.802984 -166.472874) (xy 19.858718 -166.470837) (xy 19.914155 -166.476937) (xy 19.968112 -166.491043)
			(xy 20.019441 -166.512855) (xy 20.067047 -166.541909) (xy 20.109915 -166.577584) (xy 20.147132 -166.619121)
			(xy 20.177905 -166.665634) (xy 20.201577 -166.716131) (xy 20.217645 -166.769538) (xy 20.225765 -166.824714)
			(xy 20.226274 -166.8526) (xy 20.225765 -166.880486) (xy 20.217645 -166.935662) (xy 20.201577 -166.989069)
			(xy 20.177905 -167.039566) (xy 20.147132 -167.086079) (xy 20.109915 -167.127616) (xy 20.067047 -167.163291)
			(xy 20.019441 -167.192345) (xy 19.968112 -167.214157) (xy 19.914155 -167.228263) (xy 19.858718 -167.234363)
			(xy 19.802984 -167.232326) (xy 19.748141 -167.222196) (xy 19.695357 -167.204189) (xy 19.645757 -167.178688)
			(xy 19.600399 -167.146237) (xy 19.56025 -167.107528) (xy 19.526164 -167.063385) (xy 19.498868 -167.01475)
			(xy 19.478945 -166.962659) (xy 19.466819 -166.908222) (xy 19.462748 -166.8526) (xy 5.615432 -166.8526)
			(xy 5.615432 -167.667178) (xy 18.392138 -167.667178) (xy 18.396209 -167.611556) (xy 18.408335 -167.557119)
			(xy 18.428258 -167.505028) (xy 18.455554 -167.456393) (xy 18.48964 -167.41225) (xy 18.529789 -167.373541)
			(xy 18.575147 -167.34109) (xy 18.624747 -167.315589) (xy 18.677531 -167.297582) (xy 18.732374 -167.287452)
			(xy 18.788108 -167.285415) (xy 18.843545 -167.291515) (xy 18.897502 -167.305621) (xy 18.948831 -167.327433)
			(xy 18.996437 -167.356487) (xy 19.039305 -167.392162) (xy 19.076522 -167.433699) (xy 19.107295 -167.480212)
			(xy 19.130967 -167.530709) (xy 19.147035 -167.584116) (xy 19.149914 -167.603678) (xy 21.168612 -167.603678)
			(xy 21.172683 -167.548056) (xy 21.184809 -167.493619) (xy 21.204732 -167.441528) (xy 21.232028 -167.392893)
			(xy 21.266114 -167.34875) (xy 21.306263 -167.310041) (xy 21.351621 -167.27759) (xy 21.401221 -167.252089)
			(xy 21.454005 -167.234082) (xy 21.508848 -167.223952) (xy 21.564582 -167.221915) (xy 21.620019 -167.228015)
			(xy 21.673976 -167.242121) (xy 21.69359 -167.250456) (xy 23.214741 -167.250456) (xy 23.214741 -167.195944)
			(xy 23.222499 -167.141988) (xy 23.237858 -167.089685) (xy 23.260504 -167.040101) (xy 23.289977 -166.994244)
			(xy 23.325676 -166.953049) (xy 23.366874 -166.917354) (xy 23.412734 -166.887886) (xy 23.462321 -166.865244)
			(xy 23.514625 -166.849891) (xy 23.568582 -166.842138) (xy 23.595838 -166.841678) (xy 23.625175 -166.842247)
			(xy 23.683154 -166.851246) (xy 23.739073 -166.869012) (xy 23.791615 -166.895126) (xy 23.839542 -166.928972)
			(xy 23.881725 -166.969754) (xy 23.899876 -166.992808) (xy 23.899876 -166.993062) (xy 23.907479 -167.001907)
			(xy 23.928364 -167.012232) (xy 23.940008 -167.012874) (xy 24.032718 -167.013382) (xy 24.054054 -167.002968)
			(xy 24.061166 -166.99357) (xy 24.070432 -166.981847) (xy 24.090519 -166.959723) (xy 24.101298 -166.949374)
			(xy 24.101552 -166.94912) (xy 24.108437 -166.941841) (xy 24.116552 -166.923549) (xy 24.1173 -166.91356)
			(xy 24.119078 -166.830502) (xy 24.111712 -166.811706) (xy 24.104346 -166.80434) (xy 24.08411 -166.782802)
			(xy 24.049802 -166.734686) (xy 24.023324 -166.681855) (xy 24.005311 -166.625574) (xy 23.996191 -166.567187)
			(xy 23.995634 -166.53764) (xy 23.99612 -166.510389) (xy 24.003876 -166.456441) (xy 24.019231 -166.404146)
			(xy 24.041873 -166.354569) (xy 24.071339 -166.308719) (xy 24.10703 -166.267528) (xy 24.148221 -166.231837)
			(xy 24.194071 -166.202371) (xy 24.243648 -166.179729) (xy 24.295943 -166.164374) (xy 24.349891 -166.156618)
			(xy 24.404393 -166.156618) (xy 24.458341 -166.164374) (xy 24.510636 -166.179729) (xy 24.560213 -166.202371)
			(xy 24.606063 -166.231837) (xy 24.647254 -166.267528) (xy 24.682945 -166.308719) (xy 24.712411 -166.354569)
			(xy 24.735053 -166.404146) (xy 24.750408 -166.456441) (xy 24.758164 -166.510389) (xy 24.75865 -166.53764)
			(xy 24.758194 -166.56356) (xy 24.751159 -166.614922) (xy 24.737239 -166.664858) (xy 24.716688 -166.712452)
			(xy 24.689886 -166.756826) (xy 24.657325 -166.797165) (xy 24.638762 -166.815262) (xy 24.638508 -166.815516)
			(xy 24.631617 -166.82279) (xy 24.623503 -166.841085) (xy 24.62276 -166.851076) (xy 24.620982 -166.934134)
			(xy 24.628348 -166.95293) (xy 24.635714 -166.960296) (xy 24.655977 -166.981809) (xy 24.690279 -167.029933)
			(xy 24.716751 -167.08277) (xy 24.734758 -167.139057) (xy 24.743871 -167.197447) (xy 24.744426 -167.226996)
			(xy 24.743919 -167.254246) (xy 24.736163 -167.308192) (xy 24.720809 -167.360486) (xy 24.69817 -167.410062)
			(xy 24.668706 -167.455911) (xy 24.633017 -167.497101) (xy 24.591829 -167.532793) (xy 24.545981 -167.562259)
			(xy 24.496406 -167.584902) (xy 24.444114 -167.600258) (xy 24.390168 -167.608017) (xy 24.362918 -167.608504)
			(xy 24.33358 -167.607974) (xy 24.275599 -167.598967) (xy 24.219678 -167.581194) (xy 24.167136 -167.555073)
			(xy 24.119211 -167.52122) (xy 24.07703 -167.480431) (xy 24.05888 -167.457374) (xy 24.05888 -167.45712)
			(xy 24.0513 -167.448252) (xy 24.030398 -167.437941) (xy 24.018748 -167.437308) (xy 23.926038 -167.4368)
			(xy 23.904702 -167.447214) (xy 23.89759 -167.456612) (xy 23.879385 -167.479219) (xy 23.837332 -167.519221)
			(xy 23.789705 -167.552392) (xy 23.737602 -167.577965) (xy 23.682228 -167.595351) (xy 23.624858 -167.604149)
			(xy 23.595838 -167.604694) (xy 23.568582 -167.604262) (xy 23.514625 -167.596509) (xy 23.462321 -167.581156)
			(xy 23.412734 -167.558514) (xy 23.366874 -167.529046) (xy 23.325676 -167.493351) (xy 23.289977 -167.452156)
			(xy 23.260504 -167.406299) (xy 23.237858 -167.356715) (xy 23.222499 -167.304412) (xy 23.214741 -167.250456)
			(xy 21.69359 -167.250456) (xy 21.725305 -167.263933) (xy 21.772911 -167.292987) (xy 21.815779 -167.328662)
			(xy 21.852996 -167.370199) (xy 21.883769 -167.416712) (xy 21.907441 -167.467209) (xy 21.923509 -167.520616)
			(xy 21.931629 -167.575792) (xy 21.932138 -167.603678) (xy 21.931629 -167.631564) (xy 21.923509 -167.68674)
			(xy 21.907441 -167.740147) (xy 21.883769 -167.790644) (xy 21.852996 -167.837157) (xy 21.815779 -167.878694)
			(xy 21.772911 -167.914369) (xy 21.725305 -167.943423) (xy 21.673976 -167.965235) (xy 21.620019 -167.979341)
			(xy 21.564582 -167.985441) (xy 21.508848 -167.983404) (xy 21.454005 -167.973274) (xy 21.401221 -167.955267)
			(xy 21.351621 -167.929766) (xy 21.306263 -167.897315) (xy 21.266114 -167.858606) (xy 21.232028 -167.814463)
			(xy 21.204732 -167.765828) (xy 21.184809 -167.713737) (xy 21.172683 -167.6593) (xy 21.168612 -167.603678)
			(xy 19.149914 -167.603678) (xy 19.155155 -167.639292) (xy 19.155664 -167.667178) (xy 19.155155 -167.695064)
			(xy 19.147035 -167.75024) (xy 19.130967 -167.803647) (xy 19.107295 -167.854144) (xy 19.076522 -167.900657)
			(xy 19.039305 -167.942194) (xy 18.996437 -167.977869) (xy 18.948831 -168.006923) (xy 18.897502 -168.028735)
			(xy 18.843545 -168.042841) (xy 18.788108 -168.048941) (xy 18.732374 -168.046904) (xy 18.677531 -168.036774)
			(xy 18.624747 -168.018767) (xy 18.575147 -167.993266) (xy 18.529789 -167.960815) (xy 18.48964 -167.922106)
			(xy 18.455554 -167.877963) (xy 18.428258 -167.829328) (xy 18.408335 -167.777237) (xy 18.396209 -167.7228)
			(xy 18.392138 -167.667178) (xy 5.615432 -167.667178) (xy 5.615432 -168.453132) (xy 6.635724 -168.453132)
			(xy 6.635724 -168.398628) (xy 6.64348 -168.34468) (xy 6.658836 -168.292385) (xy 6.681477 -168.242807)
			(xy 6.710944 -168.196956) (xy 6.746636 -168.155766) (xy 6.787826 -168.120074) (xy 6.833677 -168.090607)
			(xy 6.883255 -168.067966) (xy 6.93555 -168.05261) (xy 6.989498 -168.044854) (xy 7.01675 -168.044368)
			(xy 7.046872 -168.044965) (xy 7.106368 -168.054439) (xy 7.163636 -168.073144) (xy 7.217253 -168.100614)
			(xy 7.265888 -168.136167) (xy 7.287514 -168.157144) (xy 7.295079 -168.164086) (xy 7.314081 -168.171817)
			(xy 7.324344 -168.17213) (xy 7.408164 -168.17086) (xy 7.42696 -168.162478) (xy 7.434072 -168.154604)
			(xy 7.452196 -168.135728) (xy 7.492713 -168.102609) (xy 7.537375 -168.075337) (xy 7.585344 -168.054423)
			(xy 7.635721 -168.04026) (xy 7.687561 -168.033113) (xy 7.713726 -168.032684) (xy 7.740979 -168.033143)
			(xy 7.794931 -168.0409) (xy 7.847229 -168.056255) (xy 7.89681 -168.078898) (xy 7.942664 -168.108366)
			(xy 7.983858 -168.14406) (xy 8.019552 -168.185253) (xy 8.04902 -168.231106) (xy 8.071663 -168.280687)
			(xy 8.08702 -168.332985) (xy 8.094777 -168.386937) (xy 8.094777 -168.441443) (xy 8.08702 -168.495395)
			(xy 8.071663 -168.547693) (xy 8.04902 -168.597274) (xy 8.019552 -168.643127) (xy 7.983858 -168.68432)
			(xy 7.942664 -168.720014) (xy 7.89681 -168.749482) (xy 7.855118 -168.768522) (xy 23.884888 -168.768522)
			(xy 23.888959 -168.7129) (xy 23.901085 -168.658463) (xy 23.921008 -168.606372) (xy 23.948304 -168.557737)
			(xy 23.98239 -168.513594) (xy 24.022539 -168.474885) (xy 24.067897 -168.442434) (xy 24.117497 -168.416933)
			(xy 24.170281 -168.398926) (xy 24.225124 -168.388796) (xy 24.280858 -168.386759) (xy 24.336295 -168.392859)
			(xy 24.390252 -168.406965) (xy 24.441581 -168.428777) (xy 24.489187 -168.457831) (xy 24.532055 -168.493506)
			(xy 24.569272 -168.535043) (xy 24.600045 -168.581556) (xy 24.623717 -168.632053) (xy 24.639785 -168.68546)
			(xy 24.647905 -168.740636) (xy 24.648414 -168.768522) (xy 24.647905 -168.796408) (xy 24.639785 -168.851584)
			(xy 24.623717 -168.904991) (xy 24.600045 -168.955488) (xy 24.569272 -169.002001) (xy 24.532055 -169.043538)
			(xy 24.489187 -169.079213) (xy 24.441581 -169.108267) (xy 24.390252 -169.130079) (xy 24.336295 -169.144185)
			(xy 24.280858 -169.150285) (xy 24.225124 -169.148248) (xy 24.170281 -169.138118) (xy 24.117497 -169.120111)
			(xy 24.067897 -169.09461) (xy 24.022539 -169.062159) (xy 23.98239 -169.02345) (xy 23.948304 -168.979307)
			(xy 23.921008 -168.930672) (xy 23.901085 -168.878581) (xy 23.888959 -168.824144) (xy 23.884888 -168.768522)
			(xy 7.855118 -168.768522) (xy 7.847229 -168.772125) (xy 7.794931 -168.78748) (xy 7.740979 -168.795237)
			(xy 7.713726 -168.7957) (xy 7.683603 -168.795127) (xy 7.624106 -168.785649) (xy 7.566837 -168.766939)
			(xy 7.51322 -168.739463) (xy 7.464586 -168.703904) (xy 7.442962 -168.682924) (xy 7.435409 -168.675966)
			(xy 7.416398 -168.668245) (xy 7.406132 -168.667938) (xy 7.322312 -168.669208) (xy 7.303516 -168.67759)
			(xy 7.296404 -168.685464) (xy 7.278285 -168.704346) (xy 7.237768 -168.737465) (xy 7.193105 -168.764737)
			(xy 7.145135 -168.78565) (xy 7.094757 -168.799812) (xy 7.042916 -168.806956) (xy 7.01675 -168.807384)
			(xy 6.989498 -168.806906) (xy 6.93555 -168.79915) (xy 6.883255 -168.783794) (xy 6.833677 -168.761153)
			(xy 6.787826 -168.731686) (xy 6.746636 -168.695994) (xy 6.710944 -168.654804) (xy 6.681477 -168.608953)
			(xy 6.658836 -168.559375) (xy 6.64348 -168.50708) (xy 6.635724 -168.453132) (xy 5.615432 -168.453132)
			(xy 5.615432 -169.517314) (xy 19.694904 -169.517314) (xy 19.698975 -169.461692) (xy 19.711101 -169.407255)
			(xy 19.731024 -169.355164) (xy 19.75832 -169.306529) (xy 19.792406 -169.262386) (xy 19.832555 -169.223677)
			(xy 19.877913 -169.191226) (xy 19.927513 -169.165725) (xy 19.980297 -169.147718) (xy 20.03514 -169.137588)
			(xy 20.090874 -169.135551) (xy 20.146311 -169.141651) (xy 20.200268 -169.155757) (xy 20.251597 -169.177569)
			(xy 20.299203 -169.206623) (xy 20.342071 -169.242298) (xy 20.379288 -169.283835) (xy 20.410061 -169.330348)
			(xy 20.433733 -169.380845) (xy 20.449801 -169.434252) (xy 20.457921 -169.489428) (xy 20.45843 -169.517314)
			(xy 20.457921 -169.5452) (xy 20.449801 -169.600376) (xy 20.433733 -169.653783) (xy 20.410061 -169.70428)
			(xy 20.379288 -169.750793) (xy 20.358806 -169.773653) (xy 22.334677 -169.773653) (xy 22.334677 -169.719147)
			(xy 22.342435 -169.665197) (xy 22.357791 -169.6129) (xy 22.380434 -169.563321) (xy 22.409903 -169.517469)
			(xy 22.445598 -169.476278) (xy 22.486792 -169.440587) (xy 22.532646 -169.411121) (xy 22.582226 -169.388481)
			(xy 22.634525 -169.373129) (xy 22.688475 -169.365375) (xy 22.715728 -169.364914) (xy 22.745889 -169.36545)
			(xy 22.805457 -169.374959) (xy 22.862788 -169.393722) (xy 22.916453 -169.421269) (xy 22.965116 -169.456916)
			(xy 22.986746 -169.477944) (xy 22.994204 -169.484701) (xy 23.012764 -169.492423) (xy 23.022814 -169.49293)
			(xy 23.09495 -169.49293) (xy 23.105019 -169.492497) (xy 23.123618 -169.484783) (xy 23.131018 -169.477944)
			(xy 23.152639 -169.456908) (xy 23.201302 -169.421262) (xy 23.25497 -169.393722) (xy 23.312304 -169.374973)
			(xy 23.371875 -169.365483) (xy 23.402036 -169.364914) (xy 23.429287 -169.365358) (xy 23.483234 -169.373119)
			(xy 23.535528 -169.388479) (xy 23.585103 -169.411123) (xy 23.630952 -169.440592) (xy 23.67214 -169.476286)
			(xy 23.70783 -169.517477) (xy 23.737294 -169.563329) (xy 23.759934 -169.612906) (xy 23.775288 -169.665201)
			(xy 23.783044 -169.719149) (xy 23.783044 -169.773651) (xy 23.775288 -169.827599) (xy 23.759934 -169.879894)
			(xy 23.737294 -169.929471) (xy 23.70783 -169.975323) (xy 23.67214 -170.016514) (xy 23.630952 -170.052208)
			(xy 23.585103 -170.081677) (xy 23.535528 -170.104321) (xy 23.483234 -170.119681) (xy 23.429287 -170.127442)
			(xy 23.402036 -170.12793) (xy 23.371877 -170.127341) (xy 23.312312 -170.117842) (xy 23.254983 -170.099092)
			(xy 23.201317 -170.071556) (xy 23.152651 -170.035921) (xy 23.131018 -170.0149) (xy 23.123606 -170.008075)
			(xy 23.105016 -170.000347) (xy 23.09495 -169.999914) (xy 23.022814 -169.999914) (xy 23.012745 -170.000343)
			(xy 22.994147 -170.008061) (xy 22.986746 -170.0149) (xy 22.965132 -170.035944) (xy 22.916468 -170.07159)
			(xy 22.862798 -170.09913) (xy 22.805462 -170.117877) (xy 22.74589 -170.127363) (xy 22.715728 -170.12793)
			(xy 22.688475 -170.127425) (xy 22.634525 -170.119671) (xy 22.582226 -170.104319) (xy 22.532646 -170.081679)
			(xy 22.486792 -170.052213) (xy 22.445598 -170.016522) (xy 22.409903 -169.975331) (xy 22.380434 -169.929479)
			(xy 22.357791 -169.8799) (xy 22.342435 -169.827603) (xy 22.334677 -169.773653) (xy 20.358806 -169.773653)
			(xy 20.342071 -169.79233) (xy 20.299203 -169.828005) (xy 20.251597 -169.857059) (xy 20.200268 -169.878871)
			(xy 20.146311 -169.892977) (xy 20.090874 -169.899077) (xy 20.03514 -169.89704) (xy 19.980297 -169.88691)
			(xy 19.927513 -169.868903) (xy 19.877913 -169.843402) (xy 19.832555 -169.810951) (xy 19.792406 -169.772242)
			(xy 19.75832 -169.728099) (xy 19.731024 -169.679464) (xy 19.711101 -169.627373) (xy 19.698975 -169.572936)
			(xy 19.694904 -169.517314) (xy 5.615432 -169.517314) (xy 5.615432 -170.601711) (xy 6.6939 -170.601711)
			(xy 6.6939 -170.547209) (xy 6.701656 -170.493262) (xy 6.717011 -170.440968) (xy 6.739652 -170.391391)
			(xy 6.769117 -170.345541) (xy 6.804808 -170.304351) (xy 6.845998 -170.26866) (xy 6.891848 -170.239194)
			(xy 6.941424 -170.216552) (xy 6.993718 -170.201197) (xy 7.047665 -170.19344) (xy 7.074916 -170.192954)
			(xy 7.102426 -170.193433) (xy 7.156871 -170.201358) (xy 7.209612 -170.217027) (xy 7.259553 -170.240115)
			(xy 7.305657 -170.270141) (xy 7.32663 -170.28795) (xy 7.333742 -170.2943) (xy 7.351522 -170.30065)
			(xy 7.429754 -170.299126) (xy 7.439011 -170.298556) (xy 7.456208 -170.29166) (xy 7.463282 -170.285664)
			(xy 7.463536 -170.28541) (xy 7.484889 -170.26601) (xy 7.532349 -170.233211) (xy 7.584206 -170.207932)
			(xy 7.639279 -170.19075) (xy 7.696311 -170.182056) (xy 7.725156 -170.181524) (xy 7.752409 -170.181983)
			(xy 7.806361 -170.18974) (xy 7.858659 -170.205095) (xy 7.90824 -170.227738) (xy 7.954094 -170.257206)
			(xy 7.995288 -170.2929) (xy 8.030982 -170.334093) (xy 8.04279 -170.352466) (xy 20.610574 -170.352466)
			(xy 20.614645 -170.296844) (xy 20.626771 -170.242407) (xy 20.646694 -170.190316) (xy 20.67399 -170.141681)
			(xy 20.708076 -170.097538) (xy 20.748225 -170.058829) (xy 20.793583 -170.026378) (xy 20.843183 -170.000877)
			(xy 20.895967 -169.98287) (xy 20.95081 -169.97274) (xy 21.006544 -169.970703) (xy 21.061981 -169.976803)
			(xy 21.115938 -169.990909) (xy 21.167267 -170.012721) (xy 21.214873 -170.041775) (xy 21.257741 -170.07745)
			(xy 21.294958 -170.118987) (xy 21.325731 -170.1655) (xy 21.349403 -170.215997) (xy 21.365471 -170.269404)
			(xy 21.373591 -170.32458) (xy 21.3741 -170.352466) (xy 21.373591 -170.380352) (xy 21.365471 -170.435528)
			(xy 21.349403 -170.488935) (xy 21.325731 -170.539432) (xy 21.294958 -170.585945) (xy 21.257741 -170.627482)
			(xy 21.214873 -170.663157) (xy 21.167267 -170.692211) (xy 21.115938 -170.714023) (xy 21.061981 -170.728129)
			(xy 21.006544 -170.734229) (xy 20.95081 -170.732192) (xy 20.895967 -170.722062) (xy 20.843183 -170.704055)
			(xy 20.793583 -170.678554) (xy 20.748225 -170.646103) (xy 20.708076 -170.607394) (xy 20.67399 -170.563251)
			(xy 20.646694 -170.514616) (xy 20.626771 -170.462525) (xy 20.614645 -170.408088) (xy 20.610574 -170.352466)
			(xy 8.04279 -170.352466) (xy 8.06045 -170.379946) (xy 8.083093 -170.429527) (xy 8.09845 -170.481825)
			(xy 8.106207 -170.535777) (xy 8.106207 -170.590283) (xy 8.09845 -170.644235) (xy 8.083093 -170.696533)
			(xy 8.06045 -170.746114) (xy 8.030982 -170.791967) (xy 7.995288 -170.83316) (xy 7.954094 -170.868854)
			(xy 7.90824 -170.898322) (xy 7.858659 -170.920965) (xy 7.806361 -170.93632) (xy 7.752409 -170.944077)
			(xy 7.725156 -170.94454) (xy 7.697646 -170.944079) (xy 7.643199 -170.936149) (xy 7.590458 -170.920476)
			(xy 7.540517 -170.897385) (xy 7.494414 -170.867354) (xy 7.473442 -170.849544) (xy 7.46633 -170.843194)
			(xy 7.44855 -170.836844) (xy 7.370318 -170.838368) (xy 7.36106 -170.838926) (xy 7.343863 -170.84583)
			(xy 7.33679 -170.85183) (xy 7.336536 -170.852084) (xy 7.315194 -170.871497) (xy 7.267731 -170.904294)
			(xy 7.215871 -170.929571) (xy 7.160796 -170.94675) (xy 7.103762 -170.95544) (xy 7.074916 -170.95597)
			(xy 7.047665 -170.95548) (xy 6.993718 -170.947723) (xy 6.941424 -170.932368) (xy 6.891848 -170.909726)
			(xy 6.845998 -170.88026) (xy 6.804808 -170.844569) (xy 6.769117 -170.803379) (xy 6.739652 -170.757529)
			(xy 6.717011 -170.707952) (xy 6.701656 -170.655658) (xy 6.6939 -170.601711) (xy 5.615432 -170.601711)
			(xy 5.615432 -171.402831) (xy 20.628336 -171.402831) (xy 20.628336 -171.348329) (xy 20.636092 -171.294381)
			(xy 20.651447 -171.242086) (xy 20.674088 -171.192509) (xy 20.703554 -171.146659) (xy 20.739246 -171.105468)
			(xy 20.780436 -171.069777) (xy 20.826286 -171.04031) (xy 20.875863 -171.017669) (xy 20.928157 -171.002313)
			(xy 20.982105 -170.994556) (xy 21.009356 -170.99407) (xy 21.036929 -170.994576) (xy 21.0915 -171.002522)
			(xy 21.144358 -171.01824) (xy 21.194404 -171.041402) (xy 21.240595 -171.071527) (xy 21.281968 -171.107987)
			(xy 21.300186 -171.12869) (xy 21.307748 -171.136758) (xy 21.327754 -171.146117) (xy 21.338794 -171.146724)
			(xy 21.416518 -171.146724) (xy 21.427565 -171.146135) (xy 21.447588 -171.136787) (xy 21.455126 -171.12869)
			(xy 21.473318 -171.107961) (xy 21.514691 -171.071493) (xy 21.560885 -171.041363) (xy 21.610937 -171.0182)
			(xy 21.663803 -171.002488) (xy 21.71838 -170.994553) (xy 21.745956 -170.99407) (xy 21.773209 -170.994537)
			(xy 21.82716 -171.002294) (xy 21.879458 -171.017649) (xy 21.929038 -171.040291) (xy 21.974892 -171.069759)
			(xy 22.016085 -171.105452) (xy 22.051779 -171.146645) (xy 22.081247 -171.192498) (xy 22.103889 -171.242078)
			(xy 22.119246 -171.294376) (xy 22.127003 -171.348327) (xy 22.127003 -171.402833) (xy 22.119246 -171.456784)
			(xy 22.103889 -171.509082) (xy 22.081247 -171.558662) (xy 22.051779 -171.604515) (xy 22.016085 -171.645708)
			(xy 21.974892 -171.681401) (xy 21.929038 -171.710869) (xy 21.879458 -171.733511) (xy 21.82716 -171.748866)
			(xy 21.773209 -171.756623) (xy 21.745956 -171.757086) (xy 21.718383 -171.756587) (xy 21.663811 -171.748642)
			(xy 21.610952 -171.732924) (xy 21.560905 -171.70976) (xy 21.514715 -171.679633) (xy 21.473343 -171.643171)
			(xy 21.455126 -171.622466) (xy 21.447566 -171.614397) (xy 21.427558 -171.60504) (xy 21.416518 -171.604432)
			(xy 21.338794 -171.604432) (xy 21.32775 -171.605042) (xy 21.307728 -171.614377) (xy 21.300186 -171.622466)
			(xy 21.281978 -171.64318) (xy 21.24061 -171.679652) (xy 21.194419 -171.709784) (xy 21.14437 -171.73295)
			(xy 21.091507 -171.748665) (xy 21.036931 -171.756602) (xy 21.009356 -171.757086) (xy 20.982105 -171.756604)
			(xy 20.928157 -171.748847) (xy 20.875863 -171.733491) (xy 20.826286 -171.71085) (xy 20.780436 -171.681383)
			(xy 20.739246 -171.645692) (xy 20.703554 -171.604501) (xy 20.674088 -171.558651) (xy 20.651447 -171.509074)
			(xy 20.636092 -171.456779) (xy 20.628336 -171.402831) (xy 5.615432 -171.402831) (xy 5.615432 -173.290563)
			(xy 6.176721 -173.290563) (xy 6.176721 -173.236057) (xy 6.184478 -173.182105) (xy 6.199835 -173.129807)
			(xy 6.222478 -173.080226) (xy 6.251946 -173.034372) (xy 6.28764 -172.993179) (xy 6.328834 -172.957485)
			(xy 6.374688 -172.928017) (xy 6.424268 -172.905374) (xy 6.476567 -172.890018) (xy 6.530519 -172.882261)
			(xy 6.557772 -172.881798) (xy 6.586688 -172.882337) (xy 6.643858 -172.891062) (xy 6.699057 -172.908316)
			(xy 6.751018 -172.933704) (xy 6.798553 -172.966643) (xy 6.840571 -173.00638) (xy 6.858762 -173.028864)
			(xy 6.866385 -173.037655) (xy 6.887274 -173.047845) (xy 6.898894 -173.048422) (xy 6.97865 -173.048422)
			(xy 6.990282 -173.04789) (xy 7.011191 -173.037695) (xy 7.018782 -173.028864) (xy 7.036974 -173.006382)
			(xy 7.078995 -172.966648) (xy 7.12653 -172.93371) (xy 7.178491 -172.908322) (xy 7.233687 -172.891065)
			(xy 7.290856 -172.882334) (xy 7.319772 -172.881798) (xy 7.347023 -172.882292) (xy 7.40097 -172.890049)
			(xy 7.453264 -172.905404) (xy 7.50284 -172.928045) (xy 7.54869 -172.957511) (xy 7.589879 -172.993202)
			(xy 7.62557 -173.034392) (xy 7.655036 -173.080242) (xy 7.677677 -173.129818) (xy 7.693032 -173.182112)
			(xy 7.700788 -173.236059) (xy 7.700788 -173.290561) (xy 7.693032 -173.344508) (xy 7.677677 -173.396802)
			(xy 7.655036 -173.446378) (xy 7.62557 -173.492228) (xy 7.589879 -173.533418) (xy 7.54869 -173.569109)
			(xy 7.523375 -173.585378) (xy 17.986248 -173.585378) (xy 17.986703 -173.558133) (xy 17.994464 -173.504198)
			(xy 18.009824 -173.451918) (xy 18.03247 -173.402357) (xy 18.061942 -173.356524) (xy 18.097638 -173.315355)
			(xy 18.138832 -173.279686) (xy 18.161508 -173.264576) (xy 18.168527 -173.25972) (xy 18.179078 -173.246317)
			(xy 18.184605 -173.230181) (xy 18.184876 -173.22165) (xy 18.184876 -173.136306) (xy 18.184616 -173.12778)
			(xy 18.179042 -173.111666) (xy 18.168506 -173.09826) (xy 18.161508 -173.09338) (xy 18.138818 -173.078291)
			(xy 18.097625 -173.042618) (xy 18.061931 -173.001445) (xy 18.032463 -172.955609) (xy 18.00982 -172.906044)
			(xy 17.994465 -172.853761) (xy 17.98671 -172.799824) (xy 17.986248 -172.772578) (xy 17.986757 -172.745328)
			(xy 17.994516 -172.691384) (xy 18.009871 -172.639092) (xy 18.032512 -172.589518) (xy 18.061976 -172.543669)
			(xy 18.097665 -172.502481) (xy 18.138852 -172.466789) (xy 18.184698 -172.437322) (xy 18.234271 -172.414679)
			(xy 18.286562 -172.39932) (xy 18.340506 -172.391559) (xy 18.367756 -172.39107) (xy 18.395804 -172.39163)
			(xy 18.451292 -172.399866) (xy 18.504977 -172.416137) (xy 18.555701 -172.440093) (xy 18.602371 -172.471217)
			(xy 18.643981 -172.508839) (xy 18.679635 -172.552147) (xy 18.708564 -172.600209) (xy 18.730144 -172.651988)
			(xy 18.743911 -172.706369) (xy 18.746657 -172.729398) (xy 20.58873 -172.729398) (xy 20.592801 -172.673776)
			(xy 20.604927 -172.619339) (xy 20.62485 -172.567248) (xy 20.652146 -172.518613) (xy 20.686232 -172.47447)
			(xy 20.726381 -172.435761) (xy 20.771739 -172.40331) (xy 20.821339 -172.377809) (xy 20.874123 -172.359802)
			(xy 20.928966 -172.349672) (xy 20.9847 -172.347635) (xy 21.040137 -172.353735) (xy 21.094094 -172.367841)
			(xy 21.145423 -172.389653) (xy 21.193029 -172.418707) (xy 21.235897 -172.454382) (xy 21.273114 -172.495919)
			(xy 21.303887 -172.542432) (xy 21.327559 -172.592929) (xy 21.343627 -172.646336) (xy 21.351747 -172.701512)
			(xy 21.352256 -172.729398) (xy 21.351747 -172.757284) (xy 21.343627 -172.81246) (xy 21.327559 -172.865867)
			(xy 21.303887 -172.916364) (xy 21.273114 -172.962877) (xy 21.235897 -173.004414) (xy 21.193029 -173.040089)
			(xy 21.145423 -173.069143) (xy 21.094094 -173.090955) (xy 21.040137 -173.105061) (xy 20.9847 -173.111161)
			(xy 20.928966 -173.109124) (xy 20.874123 -173.098994) (xy 20.821339 -173.080987) (xy 20.771739 -173.055486)
			(xy 20.726381 -173.023035) (xy 20.686232 -172.984326) (xy 20.652146 -172.940183) (xy 20.62485 -172.891548)
			(xy 20.604927 -172.839457) (xy 20.592801 -172.78502) (xy 20.58873 -172.729398) (xy 18.746657 -172.729398)
			(xy 18.747232 -172.734224) (xy 18.747232 -172.734478) (xy 18.748843 -172.744326) (xy 18.758358 -172.76184)
			(xy 18.765774 -172.768514) (xy 18.830036 -172.820584) (xy 18.84934 -172.826172) (xy 18.8595 -172.825156)
			(xy 18.86988 -172.824082) (xy 18.89072 -172.82294) (xy 18.901156 -172.82287) (xy 18.928409 -172.823337)
			(xy 18.98236 -172.831094) (xy 19.034658 -172.846449) (xy 19.084238 -172.869091) (xy 19.130092 -172.898559)
			(xy 19.171285 -172.934252) (xy 19.206979 -172.975445) (xy 19.236447 -173.021298) (xy 19.259089 -173.070878)
			(xy 19.274446 -173.123176) (xy 19.282203 -173.177127) (xy 19.282203 -173.231633) (xy 19.274446 -173.285584)
			(xy 19.259089 -173.337882) (xy 19.236447 -173.387462) (xy 19.206979 -173.433315) (xy 19.171285 -173.474508)
			(xy 19.130092 -173.510201) (xy 19.084238 -173.539669) (xy 19.034658 -173.562311) (xy 18.98236 -173.577666)
			(xy 18.928409 -173.585423) (xy 18.901156 -173.585886) (xy 18.889185 -173.585776) (xy 18.865292 -173.584249)
			(xy 18.853404 -173.582838) (xy 18.844006 -173.581568) (xy 18.825464 -173.58614) (xy 18.81977 -173.590204)
			(xy 19.616672 -173.590204) (xy 19.620743 -173.534582) (xy 19.632869 -173.480145) (xy 19.652792 -173.428054)
			(xy 19.680088 -173.379419) (xy 19.714174 -173.335276) (xy 19.754323 -173.296567) (xy 19.799681 -173.264116)
			(xy 19.849281 -173.238615) (xy 19.902065 -173.220608) (xy 19.956908 -173.210478) (xy 20.012642 -173.208441)
			(xy 20.068079 -173.214541) (xy 20.122036 -173.228647) (xy 20.173365 -173.250459) (xy 20.220971 -173.279513)
			(xy 20.263839 -173.315188) (xy 20.301056 -173.356725) (xy 20.331829 -173.403238) (xy 20.355501 -173.453735)
			(xy 20.371569 -173.507142) (xy 20.379689 -173.562318) (xy 20.380198 -173.590204) (xy 20.379689 -173.61809)
			(xy 20.371569 -173.673266) (xy 20.355501 -173.726673) (xy 20.331829 -173.77717) (xy 20.301056 -173.823683)
			(xy 20.263839 -173.86522) (xy 20.233849 -173.890178) (xy 21.897338 -173.890178) (xy 21.901409 -173.834556)
			(xy 21.913535 -173.780119) (xy 21.933458 -173.728028) (xy 21.960754 -173.679393) (xy 21.99484 -173.63525)
			(xy 22.034989 -173.596541) (xy 22.080347 -173.56409) (xy 22.129947 -173.538589) (xy 22.182731 -173.520582)
			(xy 22.237574 -173.510452) (xy 22.293308 -173.508415) (xy 22.348745 -173.514515) (xy 22.402702 -173.528621)
			(xy 22.454031 -173.550433) (xy 22.501637 -173.579487) (xy 22.544505 -173.615162) (xy 22.581722 -173.656699)
			(xy 22.612495 -173.703212) (xy 22.636167 -173.753709) (xy 22.652235 -173.807116) (xy 22.660355 -173.862292)
			(xy 22.660864 -173.890178) (xy 22.660355 -173.918064) (xy 22.652235 -173.97324) (xy 22.636167 -174.026647)
			(xy 22.612495 -174.077144) (xy 22.581722 -174.123657) (xy 22.544505 -174.165194) (xy 22.501637 -174.200869)
			(xy 22.454031 -174.229923) (xy 22.402702 -174.251735) (xy 22.348745 -174.265841) (xy 22.293308 -174.271941)
			(xy 22.237574 -174.269904) (xy 22.182731 -174.259774) (xy 22.129947 -174.241767) (xy 22.080347 -174.216266)
			(xy 22.034989 -174.183815) (xy 21.99484 -174.145106) (xy 21.960754 -174.100963) (xy 21.933458 -174.052328)
			(xy 21.913535 -174.000237) (xy 21.901409 -173.9458) (xy 21.897338 -173.890178) (xy 20.233849 -173.890178)
			(xy 20.220971 -173.900895) (xy 20.173365 -173.929949) (xy 20.122036 -173.951761) (xy 20.068079 -173.965867)
			(xy 20.012642 -173.971967) (xy 19.956908 -173.96993) (xy 19.902065 -173.9598) (xy 19.849281 -173.941793)
			(xy 19.799681 -173.916292) (xy 19.754323 -173.883841) (xy 19.714174 -173.845132) (xy 19.680088 -173.800989)
			(xy 19.652792 -173.752354) (xy 19.632869 -173.700263) (xy 19.620743 -173.645826) (xy 19.616672 -173.590204)
			(xy 18.81977 -173.590204) (xy 18.753582 -173.637448) (xy 18.743168 -173.653704) (xy 18.74139 -173.663102)
			(xy 18.734939 -173.691344) (xy 18.714693 -173.745619) (xy 18.686475 -173.79621) (xy 18.650934 -173.841955)
			(xy 18.608887 -173.881802) (xy 18.561301 -173.914836) (xy 18.509268 -173.940298) (xy 18.453984 -173.957602)
			(xy 18.39672 -173.966352) (xy 18.367756 -173.966886) (xy 18.340503 -173.966463) (xy 18.286552 -173.9587)
			(xy 18.234254 -173.943338) (xy 18.184675 -173.92069) (xy 18.138824 -173.891217) (xy 18.097634 -173.855519)
			(xy 18.061943 -173.814323) (xy 18.032478 -173.768467) (xy 18.009839 -173.718884) (xy 17.994486 -173.666584)
			(xy 17.986732 -173.612631) (xy 17.986248 -173.585378) (xy 7.523375 -173.585378) (xy 7.50284 -173.598575)
			(xy 7.453264 -173.621216) (xy 7.40097 -173.636571) (xy 7.347023 -173.644328) (xy 7.319772 -173.644814)
			(xy 7.290855 -173.644276) (xy 7.233684 -173.635556) (xy 7.178484 -173.618304) (xy 7.126521 -173.592916)
			(xy 7.078987 -173.559974) (xy 7.036971 -173.520233) (xy 7.018782 -173.497748) (xy 7.011182 -173.488934)
			(xy 6.990276 -173.478756) (xy 6.97865 -173.47819) (xy 6.898894 -173.47819) (xy 6.887264 -173.478743)
			(xy 6.866355 -173.488923) (xy 6.858762 -173.497748) (xy 6.840605 -173.52026) (xy 6.798576 -173.559991)
			(xy 6.751034 -173.592925) (xy 6.699066 -173.618308) (xy 6.643864 -173.635559) (xy 6.58669 -173.644282)
			(xy 6.557772 -173.644814) (xy 6.530519 -173.644359) (xy 6.476567 -173.636602) (xy 6.424268 -173.621246)
			(xy 6.374688 -173.598603) (xy 6.328834 -173.569135) (xy 6.28764 -173.533441) (xy 6.251946 -173.492248)
			(xy 6.222478 -173.446394) (xy 6.199835 -173.396813) (xy 6.184478 -173.344515) (xy 6.176721 -173.290563)
			(xy 5.615432 -173.290563) (xy 5.615432 -174.872142) (xy 13.66596 -174.872142) (xy 13.670031 -174.81652)
			(xy 13.682157 -174.762083) (xy 13.70208 -174.709992) (xy 13.729376 -174.661357) (xy 13.763462 -174.617214)
			(xy 13.803611 -174.578505) (xy 13.848969 -174.546054) (xy 13.898569 -174.520553) (xy 13.951353 -174.502546)
			(xy 14.006196 -174.492416) (xy 14.06193 -174.490379) (xy 14.117367 -174.496479) (xy 14.171324 -174.510585)
			(xy 14.222653 -174.532397) (xy 14.270259 -174.561451) (xy 14.313127 -174.597126) (xy 14.350344 -174.638663)
			(xy 14.381117 -174.685176) (xy 14.404789 -174.735673) (xy 14.420857 -174.78908) (xy 14.428977 -174.844256)
			(xy 14.429486 -174.872142) (xy 14.428977 -174.900028) (xy 14.420857 -174.955204) (xy 14.404789 -175.008611)
			(xy 14.381117 -175.059108) (xy 14.350344 -175.105621) (xy 14.313127 -175.147158) (xy 14.270259 -175.182833)
			(xy 14.222653 -175.211887) (xy 14.171324 -175.233699) (xy 14.117367 -175.247805) (xy 14.06193 -175.253905)
			(xy 14.006196 -175.251868) (xy 13.951353 -175.241738) (xy 13.898569 -175.223731) (xy 13.848969 -175.19823)
			(xy 13.803611 -175.165779) (xy 13.763462 -175.12707) (xy 13.729376 -175.082927) (xy 13.70208 -175.034292)
			(xy 13.682157 -174.982201) (xy 13.670031 -174.927764) (xy 13.66596 -174.872142) (xy 5.615432 -174.872142)
			(xy 5.615432 -184.682892) (xy 5.615878 -184.69292) (xy 5.623465 -184.711483) (xy 5.630164 -184.71896)
			(xy 5.664454 -184.75325) (xy 5.671853 -184.760093) (xy 5.690452 -184.767816) (xy 5.700522 -184.768236)
		)
		(stroke
			(width 0)
			(type solid)
		)
		(fill yes)
		(layer "In15.Cu")
		(net "P5V_AUX")
	)
	(gr_poly
		(pts
			(xy 268.746986 -301.55642) (xy 268.750796 -301.538386) (xy 268.756228 -301.514415) (xy 268.773713 -301.468481)
			(xy 268.798332 -301.425944) (xy 268.829451 -301.387901) (xy 268.866263 -301.355337) (xy 268.907818 -301.329093)
			(xy 268.953041 -301.309847) (xy 269.000765 -301.298097) (xy 269.049754 -301.294146) (xy 269.098743 -301.298097)
			(xy 269.146467 -301.309847) (xy 269.19169 -301.329093) (xy 269.233245 -301.355337) (xy 269.270057 -301.387901)
			(xy 269.301176 -301.425944) (xy 269.325795 -301.468481) (xy 269.34328 -301.514415) (xy 269.348712 -301.538386)
			(xy 269.352522 -301.55642) (xy 269.380208 -301.579026) (xy 269.66926 -301.579026) (xy 269.696946 -301.55642)
			(xy 269.700756 -301.538386) (xy 269.706188 -301.514415) (xy 269.723673 -301.468481) (xy 269.748292 -301.425944)
			(xy 269.779411 -301.387901) (xy 269.816223 -301.355337) (xy 269.857778 -301.329093) (xy 269.903001 -301.309847)
			(xy 269.950725 -301.298097) (xy 269.999714 -301.294146) (xy 270.048703 -301.298097) (xy 270.096427 -301.309847)
			(xy 270.14165 -301.329093) (xy 270.183205 -301.355337) (xy 270.220017 -301.387901) (xy 270.251136 -301.425944)
			(xy 270.275755 -301.468481) (xy 270.29324 -301.514415) (xy 270.298672 -301.538386) (xy 270.302482 -301.55642)
			(xy 270.330168 -301.579026) (xy 270.597376 -301.579026) (xy 270.625316 -301.555912) (xy 270.628872 -301.537878)
			(xy 270.634075 -301.513334) (xy 270.650997 -301.466105) (xy 270.674934 -301.422014) (xy 270.705325 -301.382097)
			(xy 270.741456 -301.347291) (xy 270.78248 -301.318411) (xy 270.827434 -301.296137) (xy 270.875262 -301.280991)
			(xy 270.924843 -301.273327) (xy 270.975013 -301.273327) (xy 271.024594 -301.280991) (xy 271.072422 -301.296137)
			(xy 271.117376 -301.318411) (xy 271.1584 -301.347291) (xy 271.194531 -301.382097) (xy 271.224922 -301.422014)
			(xy 271.248859 -301.466105) (xy 271.265781 -301.513334) (xy 271.270984 -301.537878) (xy 271.27454 -301.555912)
			(xy 271.30248 -301.579026) (xy 271.547336 -301.579026) (xy 271.575276 -301.555912) (xy 271.578832 -301.537878)
			(xy 271.584035 -301.513334) (xy 271.600957 -301.466105) (xy 271.624894 -301.422014) (xy 271.655285 -301.382097)
			(xy 271.691416 -301.347291) (xy 271.73244 -301.318411) (xy 271.777394 -301.296137) (xy 271.825222 -301.280991)
			(xy 271.874803 -301.273327) (xy 271.924973 -301.273327) (xy 271.974554 -301.280991) (xy 272.022382 -301.296137)
			(xy 272.067336 -301.318411) (xy 272.10836 -301.347291) (xy 272.144491 -301.382097) (xy 272.174882 -301.422014)
			(xy 272.198819 -301.466105) (xy 272.215741 -301.513334) (xy 272.220944 -301.537878) (xy 272.2245 -301.555912)
			(xy 272.25244 -301.579026) (xy 272.519394 -301.579026) (xy 272.54708 -301.55642) (xy 272.55089 -301.538386)
			(xy 272.556322 -301.514415) (xy 272.573807 -301.468481) (xy 272.598426 -301.425944) (xy 272.629545 -301.387901)
			(xy 272.666357 -301.355337) (xy 272.707912 -301.329093) (xy 272.753135 -301.309847) (xy 272.800859 -301.298097)
			(xy 272.849848 -301.294146) (xy 272.898837 -301.298097) (xy 272.946561 -301.309847) (xy 272.991784 -301.329093)
			(xy 273.033339 -301.355337) (xy 273.070151 -301.387901) (xy 273.10127 -301.425944) (xy 273.125889 -301.468481)
			(xy 273.143374 -301.514415) (xy 273.148806 -301.538386) (xy 273.152616 -301.55642) (xy 273.180302 -301.579026)
			(xy 273.447256 -301.579026) (xy 273.475196 -301.555912) (xy 273.478752 -301.537878) (xy 273.483955 -301.513334)
			(xy 273.500877 -301.466105) (xy 273.524814 -301.422014) (xy 273.555205 -301.382097) (xy 273.591336 -301.347291)
			(xy 273.63236 -301.318411) (xy 273.677314 -301.296137) (xy 273.725142 -301.280991) (xy 273.774723 -301.273327)
			(xy 273.824893 -301.273327) (xy 273.874474 -301.280991) (xy 273.922302 -301.296137) (xy 273.967256 -301.318411)
			(xy 274.00828 -301.347291) (xy 274.044411 -301.382097) (xy 274.074802 -301.422014) (xy 274.098739 -301.466105)
			(xy 274.115661 -301.513334) (xy 274.120864 -301.537878) (xy 274.12442 -301.555912) (xy 274.15236 -301.579026)
			(xy 274.397216 -301.579026) (xy 274.425156 -301.555912) (xy 274.428712 -301.537878) (xy 274.433915 -301.513334)
			(xy 274.450837 -301.466105) (xy 274.474774 -301.422014) (xy 274.505165 -301.382097) (xy 274.541296 -301.347291)
			(xy 274.58232 -301.318411) (xy 274.627274 -301.296137) (xy 274.675102 -301.280991) (xy 274.724683 -301.273327)
			(xy 274.774853 -301.273327) (xy 274.824434 -301.280991) (xy 274.872262 -301.296137) (xy 274.917216 -301.318411)
			(xy 274.95824 -301.347291) (xy 274.994371 -301.382097) (xy 275.024762 -301.422014) (xy 275.048699 -301.466105)
			(xy 275.065621 -301.513334) (xy 275.070824 -301.537878) (xy 275.07438 -301.555912) (xy 275.10232 -301.579026)
			(xy 275.369274 -301.579026) (xy 275.39696 -301.55642) (xy 275.40077 -301.538386) (xy 275.406202 -301.514415)
			(xy 275.423687 -301.468481) (xy 275.448306 -301.425944) (xy 275.479425 -301.387901) (xy 275.516237 -301.355337)
			(xy 275.557792 -301.329093) (xy 275.603015 -301.309847) (xy 275.650739 -301.298097) (xy 275.699728 -301.294146)
			(xy 275.748717 -301.298097) (xy 275.796441 -301.309847) (xy 275.841664 -301.329093) (xy 275.883219 -301.355337)
			(xy 275.920031 -301.387901) (xy 275.95115 -301.425944) (xy 275.975769 -301.468481) (xy 275.993254 -301.514415)
			(xy 275.998686 -301.538386) (xy 276.002496 -301.55642) (xy 276.030182 -301.579026) (xy 276.319234 -301.579026)
			(xy 276.34692 -301.55642) (xy 276.35073 -301.538386) (xy 276.35652 -301.512916) (xy 276.3756 -301.464296)
			(xy 276.402671 -301.41963) (xy 276.436942 -301.380217) (xy 276.477416 -301.347205) (xy 276.522914 -301.321557)
			(xy 276.572111 -301.304019) (xy 276.623574 -301.295102) (xy 276.649688 -301.294546) (xy 276.663934 -301.294721)
			(xy 276.692302 -301.297388) (xy 276.70633 -301.29988) (xy 276.718522 -301.302166) (xy 276.742652 -301.2948)
			(xy 276.819868 -301.217584) (xy 276.827234 -301.193708) (xy 276.824948 -301.181262) (xy 276.822464 -301.167297)
			(xy 276.819794 -301.139057) (xy 276.819614 -301.124874) (xy 276.820136 -301.099619) (xy 276.828449 -301.049797)
			(xy 276.84485 -301.002023) (xy 276.868891 -300.9576) (xy 276.899915 -300.91774) (xy 276.937077 -300.88353)
			(xy 276.979363 -300.855904) (xy 277.025619 -300.835614) (xy 277.074584 -300.823214) (xy 277.124922 -300.819043)
			(xy 277.17526 -300.823214) (xy 277.224225 -300.835614) (xy 277.270481 -300.855904) (xy 277.312767 -300.88353)
			(xy 277.349929 -300.91774) (xy 277.380953 -300.9576) (xy 277.404994 -301.002023) (xy 277.421395 -301.049797)
			(xy 277.429708 -301.099619) (xy 277.43023 -301.124874) (xy 277.430045 -301.139057) (xy 277.427374 -301.167296)
			(xy 277.424896 -301.181262) (xy 277.42261 -301.193708) (xy 277.429976 -301.21733) (xy 277.507446 -301.2948)
			(xy 277.531068 -301.302166) (xy 277.543514 -301.29988) (xy 277.557479 -301.297395) (xy 277.585719 -301.294724)
			(xy 277.599902 -301.294546) (xy 277.626023 -301.295073) (xy 277.677504 -301.303954) (xy 277.726721 -301.321472)
			(xy 277.772236 -301.347115) (xy 277.812718 -301.380136) (xy 277.846986 -301.419568) (xy 277.874038 -301.46426)
			(xy 277.893083 -301.512906) (xy 277.89886 -301.538386) (xy 277.90267 -301.55642) (xy 277.930356 -301.579026)
			(xy 279.037288 -301.579026) (xy 279.04736 -301.578606) (xy 279.06597 -301.570897) (xy 279.073356 -301.56404)
			(xy 279.083008 -301.554388) (xy 279.089852 -301.546988) (xy 279.097581 -301.528391) (xy 279.097994 -301.51832)
			(xy 279.097994 -299.630846) (xy 279.097541 -299.621303) (xy 279.090489 -299.603562) (xy 279.084278 -299.596302)
			(xy 279.03043 -299.53839) (xy 279.013412 -299.530262) (xy 279.003506 -299.5295) (xy 278.979468 -299.527361)
			(xy 278.932459 -299.516462) (xy 278.88775 -299.498303) (xy 278.846455 -299.473335) (xy 278.809603 -299.44218)
			(xy 278.778112 -299.405615) (xy 278.752766 -299.364551) (xy 278.734197 -299.32001) (xy 278.722868 -299.273103)
			(xy 278.71906 -299.224997) (xy 278.722869 -299.176891) (xy 278.734199 -299.129984) (xy 278.752769 -299.085443)
			(xy 278.778115 -299.04438) (xy 278.809607 -299.007815) (xy 278.84646 -298.976662) (xy 278.887756 -298.951695)
			(xy 278.932465 -298.933536) (xy 278.979475 -298.922638) (xy 279.003506 -298.920408) (xy 279.013412 -298.919646)
			(xy 279.03043 -298.911518) (xy 279.084278 -298.853606) (xy 279.090527 -298.846369) (xy 279.09758 -298.828614)
			(xy 279.097994 -298.819062) (xy 279.097994 -297.730672) (xy 279.097545 -297.721127) (xy 279.0905 -297.70338)
			(xy 279.084278 -297.696128) (xy 279.03043 -297.638216) (xy 279.013412 -297.630088) (xy 279.003506 -297.629326)
			(xy 278.979466 -297.627187) (xy 278.932453 -297.616287) (xy 278.88774 -297.598127) (xy 278.846441 -297.573157)
			(xy 278.809586 -297.542) (xy 278.778092 -297.505432) (xy 278.752744 -297.464364) (xy 278.734173 -297.41982)
			(xy 278.722842 -297.372909) (xy 278.719034 -297.324799) (xy 278.722843 -297.276689) (xy 278.734174 -297.229777)
			(xy 278.752745 -297.185233) (xy 278.778093 -297.144166) (xy 278.809588 -297.107598) (xy 278.846443 -297.076442)
			(xy 278.887742 -297.051472) (xy 278.932456 -297.033312) (xy 278.979469 -297.022413) (xy 279.003506 -297.020234)
			(xy 279.013412 -297.019472) (xy 279.03043 -297.011344) (xy 279.084278 -296.953432) (xy 279.090531 -296.946197)
			(xy 279.097593 -296.928441) (xy 279.097994 -296.918888) (xy 279.097994 -294.880792) (xy 279.097549 -294.871246)
			(xy 279.090508 -294.853494) (xy 279.084278 -294.846248) (xy 279.03043 -294.788336) (xy 279.013412 -294.780208)
			(xy 279.003506 -294.779446) (xy 278.979465 -294.777307) (xy 278.932448 -294.766407) (xy 278.887732 -294.748245)
			(xy 278.846431 -294.723274) (xy 278.809573 -294.692115) (xy 278.778076 -294.655545) (xy 278.752727 -294.614475)
			(xy 278.734154 -294.569928) (xy 278.722823 -294.523013) (xy 278.719014 -294.4749) (xy 278.722823 -294.426787)
			(xy 278.734154 -294.379872) (xy 278.752727 -294.335325) (xy 278.778076 -294.294255) (xy 278.809573 -294.257685)
			(xy 278.846431 -294.226526) (xy 278.887732 -294.201555) (xy 278.932448 -294.183393) (xy 278.979465 -294.172493)
			(xy 279.003506 -294.170354) (xy 279.013412 -294.169592) (xy 279.03043 -294.161464) (xy 279.084278 -294.103552)
			(xy 279.090519 -294.096313) (xy 279.097553 -294.078557) (xy 279.097994 -294.069008) (xy 279.097994 -292.980872)
			(xy 279.097545 -292.971327) (xy 279.0905 -292.95358) (xy 279.084278 -292.946328) (xy 279.03043 -292.888416)
			(xy 279.013412 -292.880288) (xy 279.003506 -292.879526) (xy 278.979466 -292.877387) (xy 278.932453 -292.866487)
			(xy 278.88774 -292.848327) (xy 278.846441 -292.823357) (xy 278.809586 -292.7922) (xy 278.778092 -292.755632)
			(xy 278.752744 -292.714564) (xy 278.734173 -292.67002) (xy 278.722842 -292.623109) (xy 278.719034 -292.574999)
			(xy 278.722843 -292.526889) (xy 278.734174 -292.479977) (xy 278.752745 -292.435433) (xy 278.778093 -292.394366)
			(xy 278.809588 -292.357798) (xy 278.846443 -292.326642) (xy 278.887742 -292.301672) (xy 278.932456 -292.283512)
			(xy 278.979469 -292.272613) (xy 279.003506 -292.270434) (xy 279.013412 -292.269672) (xy 279.03043 -292.261544)
			(xy 279.084278 -292.203632) (xy 279.090531 -292.196397) (xy 279.097593 -292.178641) (xy 279.097994 -292.169088)
			(xy 279.097994 -290.130738) (xy 279.097539 -290.121196) (xy 279.090485 -290.103457) (xy 279.084278 -290.096194)
			(xy 279.03043 -290.038282) (xy 279.013412 -290.030154) (xy 279.003506 -290.029392) (xy 278.979461 -290.027253)
			(xy 278.932437 -290.016352) (xy 278.887714 -289.998187) (xy 278.846407 -289.973213) (xy 278.809543 -289.94205)
			(xy 278.778041 -289.905475) (xy 278.752687 -289.864399) (xy 278.734112 -289.819845) (xy 278.722778 -289.772923)
			(xy 278.718968 -289.724803) (xy 278.722777 -289.676683) (xy 278.73411 -289.629761) (xy 278.752684 -289.585207)
			(xy 278.778038 -289.544131) (xy 278.809538 -289.507555) (xy 278.846401 -289.476391) (xy 278.887709 -289.451415)
			(xy 278.932431 -289.43325) (xy 278.979455 -289.422348) (xy 279.003506 -289.4203) (xy 279.013412 -289.419538)
			(xy 279.03043 -289.41141) (xy 279.084278 -289.353498) (xy 279.090526 -289.346261) (xy 279.097576 -289.328506)
			(xy 279.097994 -289.318954) (xy 279.097994 -289.180778) (xy 279.097546 -289.171233) (xy 279.090502 -289.153484)
			(xy 279.084278 -289.146234) (xy 279.03043 -289.088322) (xy 279.013412 -289.080194) (xy 279.003506 -289.079432)
			(xy 278.979466 -289.077293) (xy 278.932451 -289.066393) (xy 278.887738 -289.048232) (xy 278.846438 -289.023262)
			(xy 278.809582 -288.992104) (xy 278.778087 -288.955536) (xy 278.752739 -288.914468) (xy 278.734167 -288.869922)
			(xy 278.722836 -288.82301) (xy 278.719028 -288.774899) (xy 278.722837 -288.726788) (xy 278.734168 -288.679876)
			(xy 278.752739 -288.635331) (xy 278.778088 -288.594263) (xy 278.809583 -288.557694) (xy 278.84644 -288.526537)
			(xy 278.887739 -288.501567) (xy 278.932453 -288.483406) (xy 278.979468 -288.472507) (xy 279.003506 -288.47034)
			(xy 279.013412 -288.469578) (xy 279.03043 -288.46145) (xy 279.084278 -288.403538) (xy 279.090532 -288.396303)
			(xy 279.097596 -288.378548) (xy 279.097994 -288.368994) (xy 279.097994 -288.230818) (xy 279.097553 -288.22127)
			(xy 279.090519 -288.203511) (xy 279.084278 -288.196274) (xy 279.03043 -288.138362) (xy 279.013412 -288.130234)
			(xy 279.003506 -288.129472) (xy 278.979463 -288.127333) (xy 278.932442 -288.116432) (xy 278.887722 -288.098269)
			(xy 278.846417 -288.073296) (xy 278.809556 -288.042135) (xy 278.778057 -288.005562) (xy 278.752704 -287.964488)
			(xy 278.73413 -287.919937) (xy 278.722797 -287.873019) (xy 278.718988 -287.824902) (xy 278.722797 -287.776785)
			(xy 278.734129 -287.729866) (xy 278.752703 -287.685315) (xy 278.778054 -287.644241) (xy 278.809553 -287.607668)
			(xy 278.846414 -287.576506) (xy 278.887719 -287.551533) (xy 278.932439 -287.533369) (xy 278.979459 -287.522468)
			(xy 279.003506 -287.52038) (xy 279.013412 -287.519618) (xy 279.03043 -287.51149) (xy 279.084278 -287.453578)
			(xy 279.090523 -287.44634) (xy 279.097566 -287.428584) (xy 279.097994 -287.419034) (xy 279.097994 -287.280858)
			(xy 279.097543 -287.271314) (xy 279.090494 -287.25357) (xy 279.084278 -287.246314) (xy 279.03043 -287.188402)
			(xy 279.013412 -287.180274) (xy 279.003506 -287.179512) (xy 278.979468 -287.177373) (xy 278.932456 -287.166474)
			(xy 278.887745 -287.148314) (xy 278.846449 -287.123345) (xy 278.809595 -287.092189) (xy 278.778102 -287.055623)
			(xy 278.752756 -287.014557) (xy 278.734186 -286.970015) (xy 278.722856 -286.923105) (xy 278.719048 -286.874998)
			(xy 278.722857 -286.82689) (xy 278.734187 -286.779981) (xy 278.752758 -286.735439) (xy 278.778105 -286.694373)
			(xy 278.809598 -286.657808) (xy 278.846452 -286.626652) (xy 278.887749 -286.601684) (xy 278.932461 -286.583525)
			(xy 278.979472 -286.572626) (xy 279.003506 -286.57042) (xy 279.013412 -286.569658) (xy 279.03043 -286.56153)
			(xy 279.084278 -286.503618) (xy 279.090529 -286.496382) (xy 279.097585 -286.478627) (xy 279.097994 -286.469074)
			(xy 279.097994 -286.330644) (xy 279.09754 -286.321101) (xy 279.090488 -286.303361) (xy 279.084278 -286.2961)
			(xy 279.03043 -286.238188) (xy 279.013412 -286.23006) (xy 279.003506 -286.229298) (xy 278.978134 -286.227004)
			(xy 278.928614 -286.215052) (xy 278.881765 -286.195047) (xy 278.838885 -286.167545) (xy 278.801164 -286.133308)
			(xy 278.769648 -286.093286) (xy 278.74521 -286.048589) (xy 278.728529 -286.000456) (xy 278.720066 -285.950223)
			(xy 278.719534 -285.924752) (xy 278.720008 -285.900764) (xy 278.727521 -285.853381) (xy 278.742353 -285.807756)
			(xy 278.76414 -285.765013) (xy 278.792344 -285.726205) (xy 278.826273 -285.692286) (xy 278.86509 -285.664092)
			(xy 278.907839 -285.642318) (xy 278.953469 -285.6275) (xy 279.000854 -285.620001) (xy 279.024842 -285.619444)
			(xy 279.048394 -285.619876) (xy 279.09494 -285.6271) (xy 279.139824 -285.641386) (xy 279.181982 -285.662396)
			(xy 279.220414 -285.68963) (xy 279.254208 -285.722443) (xy 279.282563 -285.760056) (xy 279.304805 -285.801577)
			(xy 279.320407 -285.846021) (xy 279.329 -285.892334) (xy 279.33015 -285.915862) (xy 279.330404 -285.925768)
			(xy 279.334214 -285.934912) (xy 279.336307 -285.93936) (xy 279.341932 -285.94742) (xy 279.34539 -285.950914)
			(xy 279.396444 -286.000444) (xy 279.403795 -286.006926) (xy 279.421958 -286.014242) (xy 279.43175 -286.014668)
			(xy 279.567894 -286.014668) (xy 279.577677 -286.014213) (xy 279.595824 -286.006889) (xy 279.6032 -286.000444)
			(xy 279.661366 -285.944056) (xy 279.66924 -285.926022) (xy 279.669494 -285.916116) (xy 279.67068 -285.891328)
			(xy 279.680083 -285.842604) (xy 279.697239 -285.796041) (xy 279.721697 -285.752864) (xy 279.752814 -285.714208)
			(xy 279.789769 -285.681091) (xy 279.831593 -285.654384) (xy 279.877184 -285.634789) (xy 279.925342 -285.622823)
			(xy 279.974802 -285.618798) (xy 280.024262 -285.622823) (xy 280.07242 -285.634789) (xy 280.118011 -285.654384)
			(xy 280.159835 -285.681091) (xy 280.19679 -285.714208) (xy 280.227907 -285.752864) (xy 280.252365 -285.796041)
			(xy 280.269521 -285.842604) (xy 280.278924 -285.891328) (xy 280.28011 -285.916116) (xy 280.280364 -285.926022)
			(xy 280.288238 -285.944056) (xy 280.346404 -286.000444) (xy 280.353753 -286.006932) (xy 280.371916 -286.014262)
			(xy 280.38171 -286.014668) (xy 280.517854 -286.014668) (xy 280.527641 -286.01422) (xy 280.545797 -286.006906)
			(xy 280.55316 -286.000444) (xy 280.611326 -285.944056) (xy 280.6192 -285.926022) (xy 280.619454 -285.916116)
			(xy 280.62064 -285.891328) (xy 280.630043 -285.842604) (xy 280.647199 -285.796041) (xy 280.671657 -285.752864)
			(xy 280.702774 -285.714208) (xy 280.739729 -285.681091) (xy 280.781553 -285.654384) (xy 280.827144 -285.634789)
			(xy 280.875302 -285.622823) (xy 280.924762 -285.618798) (xy 280.974222 -285.622823) (xy 281.02238 -285.634789)
			(xy 281.067971 -285.654384) (xy 281.109795 -285.681091) (xy 281.14675 -285.714208) (xy 281.177867 -285.752864)
			(xy 281.202325 -285.796041) (xy 281.219481 -285.842604) (xy 281.228884 -285.891328) (xy 281.23007 -285.916116)
			(xy 281.230324 -285.926022) (xy 281.238198 -285.944056) (xy 281.296364 -286.000444) (xy 281.303716 -286.006923)
			(xy 281.321879 -286.014231) (xy 281.33167 -286.014668) (xy 281.467814 -286.014668) (xy 281.477604 -286.014228)
			(xy 281.49577 -286.006924) (xy 281.50312 -286.000444) (xy 281.561286 -285.944056) (xy 281.56916 -285.926022)
			(xy 281.569414 -285.916116) (xy 281.5706 -285.891328) (xy 281.580003 -285.842604) (xy 281.597159 -285.796041)
			(xy 281.621617 -285.752864) (xy 281.652734 -285.714208) (xy 281.689689 -285.681091) (xy 281.731513 -285.654384)
			(xy 281.777104 -285.634789) (xy 281.825262 -285.622823) (xy 281.874722 -285.618798) (xy 281.924182 -285.622823)
			(xy 281.97234 -285.634789) (xy 282.017931 -285.654384) (xy 282.059755 -285.681091) (xy 282.09671 -285.714208)
			(xy 282.127827 -285.752864) (xy 282.152285 -285.796041) (xy 282.169441 -285.842604) (xy 282.178844 -285.891328)
			(xy 282.18003 -285.916116) (xy 282.180284 -285.926022) (xy 282.188158 -285.944056) (xy 282.246324 -286.000444)
			(xy 282.253674 -286.006929) (xy 282.271837 -286.014252) (xy 282.28163 -286.014668) (xy 282.418028 -286.014668)
			(xy 282.427817 -286.014225) (xy 282.445979 -286.006918) (xy 282.453334 -286.000444) (xy 282.5115 -285.944056)
			(xy 282.519374 -285.926022) (xy 282.519628 -285.916116) (xy 282.520814 -285.891328) (xy 282.530217 -285.842604)
			(xy 282.547373 -285.796041) (xy 282.571831 -285.752864) (xy 282.602948 -285.714208) (xy 282.639903 -285.681091)
			(xy 282.681727 -285.654384) (xy 282.727318 -285.634789) (xy 282.775476 -285.622823) (xy 282.824936 -285.618798)
			(xy 282.874396 -285.622823) (xy 282.922554 -285.634789) (xy 282.968145 -285.654384) (xy 283.009969 -285.681091)
			(xy 283.046924 -285.714208) (xy 283.078041 -285.752864) (xy 283.102499 -285.796041) (xy 283.119655 -285.842604)
			(xy 283.129058 -285.891328) (xy 283.130244 -285.916116) (xy 283.130498 -285.926022) (xy 283.138372 -285.944056)
			(xy 283.196538 -286.000444) (xy 283.203889 -286.006927) (xy 283.222052 -286.014245) (xy 283.231844 -286.014668)
			(xy 283.367988 -286.014668) (xy 283.377772 -286.014214) (xy 283.39592 -286.006892) (xy 283.403294 -286.000444)
			(xy 283.46146 -285.944056) (xy 283.469334 -285.926022) (xy 283.469588 -285.916116) (xy 283.470774 -285.891328)
			(xy 283.480177 -285.842604) (xy 283.497333 -285.796041) (xy 283.521791 -285.752864) (xy 283.552908 -285.714208)
			(xy 283.589863 -285.681091) (xy 283.631687 -285.654384) (xy 283.677278 -285.634789) (xy 283.725436 -285.622823)
			(xy 283.774896 -285.618798) (xy 283.824356 -285.622823) (xy 283.872514 -285.634789) (xy 283.918105 -285.654384)
			(xy 283.959929 -285.681091) (xy 283.996884 -285.714208) (xy 284.028001 -285.752864) (xy 284.052459 -285.796041)
			(xy 284.069615 -285.842604) (xy 284.079018 -285.891328) (xy 284.080204 -285.916116) (xy 284.080458 -285.926022)
			(xy 284.088332 -285.944056) (xy 284.146498 -286.000444) (xy 284.153847 -286.006933) (xy 284.17201 -286.014265)
			(xy 284.181804 -286.014668) (xy 284.317948 -286.014668) (xy 284.327735 -286.014221) (xy 284.345893 -286.006909)
			(xy 284.353254 -286.000444) (xy 284.41142 -285.944056) (xy 284.419294 -285.926022) (xy 284.419548 -285.916116)
			(xy 284.420734 -285.891328) (xy 284.430137 -285.842604) (xy 284.447293 -285.796041) (xy 284.471751 -285.752864)
			(xy 284.502868 -285.714208) (xy 284.539823 -285.681091) (xy 284.581647 -285.654384) (xy 284.627238 -285.634789)
			(xy 284.675396 -285.622823) (xy 284.724856 -285.618798) (xy 284.774316 -285.622823) (xy 284.822474 -285.634789)
			(xy 284.868065 -285.654384) (xy 284.909889 -285.681091) (xy 284.946844 -285.714208) (xy 284.977961 -285.752864)
			(xy 285.002419 -285.796041) (xy 285.019575 -285.842604) (xy 285.028978 -285.891328) (xy 285.030164 -285.916116)
			(xy 285.030418 -285.926022) (xy 285.038292 -285.944056) (xy 285.096458 -286.000444) (xy 285.10381 -286.006924)
			(xy 285.121973 -286.014234) (xy 285.131764 -286.014668) (xy 285.267908 -286.014668) (xy 285.277698 -286.014229)
			(xy 285.295866 -286.006926) (xy 285.303214 -286.000444) (xy 285.36138 -285.944056) (xy 285.369254 -285.926022)
			(xy 285.369508 -285.916116) (xy 285.370694 -285.891328) (xy 285.380097 -285.842604) (xy 285.397253 -285.796041)
			(xy 285.421711 -285.752864) (xy 285.452828 -285.714208) (xy 285.489783 -285.681091) (xy 285.531607 -285.654384)
			(xy 285.577198 -285.634789) (xy 285.625356 -285.622823) (xy 285.674816 -285.618798) (xy 285.724276 -285.622823)
			(xy 285.772434 -285.634789) (xy 285.818025 -285.654384) (xy 285.859849 -285.681091) (xy 285.896804 -285.714208)
			(xy 285.927921 -285.752864) (xy 285.952379 -285.796041) (xy 285.969535 -285.842604) (xy 285.978938 -285.891328)
			(xy 285.980124 -285.916116) (xy 285.980378 -285.926022) (xy 285.988252 -285.944056) (xy 286.046418 -286.000444)
			(xy 286.053768 -286.00693) (xy 286.071931 -286.014255) (xy 286.081724 -286.014668) (xy 286.217868 -286.014668)
			(xy 286.227654 -286.014218) (xy 286.245806 -286.0069) (xy 286.253174 -286.000444) (xy 286.31134 -285.944056)
			(xy 286.319214 -285.926022) (xy 286.319468 -285.916116) (xy 286.320654 -285.891328) (xy 286.330057 -285.842604)
			(xy 286.347213 -285.796041) (xy 286.371671 -285.752864) (xy 286.402788 -285.714208) (xy 286.439743 -285.681091)
			(xy 286.481567 -285.654384) (xy 286.527158 -285.634789) (xy 286.575316 -285.622823) (xy 286.624776 -285.618798)
			(xy 286.674236 -285.622823) (xy 286.722394 -285.634789) (xy 286.767985 -285.654384) (xy 286.809809 -285.681091)
			(xy 286.846764 -285.714208) (xy 286.877881 -285.752864) (xy 286.902339 -285.796041) (xy 286.919495 -285.842604)
			(xy 286.928898 -285.891328) (xy 286.930084 -285.916116) (xy 286.930338 -285.926022) (xy 286.938212 -285.944056)
			(xy 286.996378 -286.000444) (xy 287.003731 -286.006921) (xy 287.021894 -286.014224) (xy 287.031684 -286.014668)
			(xy 287.167828 -286.014668) (xy 287.177617 -286.014225) (xy 287.195779 -286.006918) (xy 287.203134 -286.000444)
			(xy 287.2613 -285.944056) (xy 287.269174 -285.926022) (xy 287.269428 -285.916116) (xy 287.270614 -285.891328)
			(xy 287.280017 -285.842604) (xy 287.297173 -285.796041) (xy 287.321631 -285.752864) (xy 287.352748 -285.714208)
			(xy 287.389703 -285.681091) (xy 287.431527 -285.654384) (xy 287.477118 -285.634789) (xy 287.525276 -285.622823)
			(xy 287.574736 -285.618798) (xy 287.624196 -285.622823) (xy 287.672354 -285.634789) (xy 287.717945 -285.654384)
			(xy 287.759769 -285.681091) (xy 287.796724 -285.714208) (xy 287.827841 -285.752864) (xy 287.852299 -285.796041)
			(xy 287.869455 -285.842604) (xy 287.878858 -285.891328) (xy 287.880044 -285.916116) (xy 287.880298 -285.926022)
			(xy 287.888172 -285.944056) (xy 287.946338 -286.000444) (xy 287.953689 -286.006927) (xy 287.971852 -286.014245)
			(xy 287.981644 -286.014668) (xy 288.117788 -286.014668) (xy 288.127572 -286.014214) (xy 288.14572 -286.006892)
			(xy 288.153094 -286.000444) (xy 288.21126 -285.944056) (xy 288.219134 -285.926022) (xy 288.219388 -285.916116)
			(xy 288.220574 -285.891328) (xy 288.229977 -285.842604) (xy 288.247133 -285.796041) (xy 288.271591 -285.752864)
			(xy 288.302708 -285.714208) (xy 288.339663 -285.681091) (xy 288.381487 -285.654384) (xy 288.427078 -285.634789)
			(xy 288.475236 -285.622823) (xy 288.524696 -285.618798) (xy 288.574156 -285.622823) (xy 288.622314 -285.634789)
			(xy 288.667905 -285.654384) (xy 288.709729 -285.681091) (xy 288.746684 -285.714208) (xy 288.777801 -285.752864)
			(xy 288.802259 -285.796041) (xy 288.819415 -285.842604) (xy 288.828818 -285.891328) (xy 288.830004 -285.916116)
			(xy 288.830258 -285.926022) (xy 288.838132 -285.944056) (xy 288.896298 -286.000444) (xy 288.903647 -286.006933)
			(xy 288.92181 -286.014265) (xy 288.931604 -286.014668) (xy 289.068002 -286.014668) (xy 289.077793 -286.01423)
			(xy 289.095962 -286.006929) (xy 289.103308 -286.000444) (xy 289.161474 -285.944056) (xy 289.169348 -285.926022)
			(xy 289.169602 -285.916116) (xy 289.170788 -285.891328) (xy 289.180191 -285.842604) (xy 289.197347 -285.796041)
			(xy 289.221805 -285.752864) (xy 289.252922 -285.714208) (xy 289.289877 -285.681091) (xy 289.331701 -285.654384)
			(xy 289.377292 -285.634789) (xy 289.42545 -285.622823) (xy 289.47491 -285.618798) (xy 289.52437 -285.622823)
			(xy 289.572528 -285.634789) (xy 289.618119 -285.654384) (xy 289.659943 -285.681091) (xy 289.696898 -285.714208)
			(xy 289.728015 -285.752864) (xy 289.752473 -285.796041) (xy 289.769629 -285.842604) (xy 289.779032 -285.891328)
			(xy 289.780218 -285.916116) (xy 289.780472 -285.926022) (xy 289.788346 -285.944056) (xy 289.846512 -286.000444)
			(xy 289.853862 -286.006931) (xy 289.872024 -286.014258) (xy 289.881818 -286.014668) (xy 290.017962 -286.014668)
			(xy 290.027748 -286.014219) (xy 290.045902 -286.006903) (xy 290.053268 -286.000444) (xy 290.111434 -285.944056)
			(xy 290.119308 -285.926022) (xy 290.119562 -285.916116) (xy 290.120748 -285.891328) (xy 290.130151 -285.842604)
			(xy 290.147307 -285.796041) (xy 290.171765 -285.752864) (xy 290.202882 -285.714208) (xy 290.239837 -285.681091)
			(xy 290.281661 -285.654384) (xy 290.327252 -285.634789) (xy 290.37541 -285.622823) (xy 290.42487 -285.618798)
			(xy 290.47433 -285.622823) (xy 290.522488 -285.634789) (xy 290.568079 -285.654384) (xy 290.609903 -285.681091)
			(xy 290.646858 -285.714208) (xy 290.677975 -285.752864) (xy 290.702433 -285.796041) (xy 290.719589 -285.842604)
			(xy 290.728992 -285.891328) (xy 290.730178 -285.916116) (xy 290.730432 -285.926022) (xy 290.738306 -285.944056)
			(xy 290.796472 -286.000444) (xy 290.803825 -286.006922) (xy 290.821988 -286.014227) (xy 290.831778 -286.014668)
			(xy 291.917882 -286.014668) (xy 291.927666 -286.014215) (xy 291.945816 -286.006894) (xy 291.953188 -286.000444)
			(xy 292.011354 -285.944056) (xy 292.019228 -285.926022) (xy 292.019482 -285.916116) (xy 292.020668 -285.891328)
			(xy 292.030071 -285.842604) (xy 292.047227 -285.796041) (xy 292.071685 -285.752864) (xy 292.102802 -285.714208)
			(xy 292.139757 -285.681091) (xy 292.181581 -285.654384) (xy 292.227172 -285.634789) (xy 292.27533 -285.622823)
			(xy 292.32479 -285.618798) (xy 292.37425 -285.622823) (xy 292.422408 -285.634789) (xy 292.467999 -285.654384)
			(xy 292.509823 -285.681091) (xy 292.546778 -285.714208) (xy 292.577895 -285.752864) (xy 292.602353 -285.796041)
			(xy 292.619509 -285.842604) (xy 292.628912 -285.891328) (xy 292.630098 -285.916116) (xy 292.630352 -285.926022)
			(xy 292.638226 -285.944056) (xy 292.696392 -286.000444) (xy 292.703741 -286.006934) (xy 292.721903 -286.014268)
			(xy 292.731698 -286.014668) (xy 292.867842 -286.014668) (xy 292.87763 -286.014223) (xy 292.895789 -286.006911)
			(xy 292.903148 -286.000444) (xy 292.961314 -285.944056) (xy 292.969188 -285.926022) (xy 292.969442 -285.916116)
			(xy 292.970628 -285.891328) (xy 292.980031 -285.842604) (xy 292.997187 -285.796041) (xy 293.021645 -285.752864)
			(xy 293.052762 -285.714208) (xy 293.089717 -285.681091) (xy 293.131541 -285.654384) (xy 293.177132 -285.634789)
			(xy 293.22529 -285.622823) (xy 293.27475 -285.618798) (xy 293.32421 -285.622823) (xy 293.372368 -285.634789)
			(xy 293.417959 -285.654384) (xy 293.459783 -285.681091) (xy 293.496738 -285.714208) (xy 293.527855 -285.752864)
			(xy 293.552313 -285.796041) (xy 293.569469 -285.842604) (xy 293.578872 -285.891328) (xy 293.580058 -285.916116)
			(xy 293.580312 -285.926022) (xy 293.588186 -285.944056) (xy 293.646352 -286.000444) (xy 293.653704 -286.006925)
			(xy 293.671867 -286.014238) (xy 293.681658 -286.014668) (xy 293.817802 -286.014668) (xy 293.827593 -286.01423)
			(xy 293.845762 -286.006929) (xy 293.853108 -286.000444) (xy 293.911274 -285.944056) (xy 293.919148 -285.926022)
			(xy 293.919402 -285.916116) (xy 293.920588 -285.891328) (xy 293.929991 -285.842604) (xy 293.947147 -285.796041)
			(xy 293.971605 -285.752864) (xy 294.002722 -285.714208) (xy 294.039677 -285.681091) (xy 294.081501 -285.654384)
			(xy 294.127092 -285.634789) (xy 294.17525 -285.622823) (xy 294.22471 -285.618798) (xy 294.27417 -285.622823)
			(xy 294.322328 -285.634789) (xy 294.367919 -285.654384) (xy 294.409743 -285.681091) (xy 294.446698 -285.714208)
			(xy 294.477815 -285.752864) (xy 294.502273 -285.796041) (xy 294.519429 -285.842604) (xy 294.528832 -285.891328)
			(xy 294.530018 -285.916116) (xy 294.530272 -285.926022) (xy 294.538146 -285.944056) (xy 294.596312 -286.000444)
			(xy 294.603662 -286.006931) (xy 294.621824 -286.014258) (xy 294.631618 -286.014668) (xy 294.768016 -286.014668)
			(xy 294.777806 -286.014227) (xy 294.795971 -286.006923) (xy 294.803322 -286.000444) (xy 294.861488 -285.944056)
			(xy 294.869362 -285.926022) (xy 294.869616 -285.916116) (xy 294.870802 -285.891328) (xy 294.880205 -285.842604)
			(xy 294.897361 -285.796041) (xy 294.921819 -285.752864) (xy 294.952936 -285.714208) (xy 294.989891 -285.681091)
			(xy 295.031715 -285.654384) (xy 295.077306 -285.634789) (xy 295.125464 -285.622823) (xy 295.174924 -285.618798)
			(xy 295.224384 -285.622823) (xy 295.272542 -285.634789) (xy 295.318133 -285.654384) (xy 295.359957 -285.681091)
			(xy 295.396912 -285.714208) (xy 295.428029 -285.752864) (xy 295.452487 -285.796041) (xy 295.469643 -285.842604)
			(xy 295.479046 -285.891328) (xy 295.480232 -285.916116) (xy 295.480486 -285.926022) (xy 295.48836 -285.944056)
			(xy 295.546526 -286.000444) (xy 295.553876 -286.006929) (xy 295.572039 -286.014251) (xy 295.581832 -286.014668)
			(xy 295.717976 -286.014668) (xy 295.727761 -286.014216) (xy 295.745912 -286.006897) (xy 295.753282 -286.000444)
			(xy 295.811448 -285.944056) (xy 295.819322 -285.926022) (xy 295.819576 -285.916116) (xy 295.820762 -285.891328)
			(xy 295.830165 -285.842604) (xy 295.847321 -285.796041) (xy 295.871779 -285.752864) (xy 295.902896 -285.714208)
			(xy 295.939851 -285.681091) (xy 295.981675 -285.654384) (xy 296.027266 -285.634789) (xy 296.075424 -285.622823)
			(xy 296.124884 -285.618798) (xy 296.174344 -285.622823) (xy 296.222502 -285.634789) (xy 296.268093 -285.654384)
			(xy 296.309917 -285.681091) (xy 296.346872 -285.714208) (xy 296.377989 -285.752864) (xy 296.402447 -285.796041)
			(xy 296.419603 -285.842604) (xy 296.429006 -285.891328) (xy 296.430192 -285.916116) (xy 296.430446 -285.926022)
			(xy 296.43832 -285.944056) (xy 296.496486 -286.000444) (xy 296.503834 -286.006935) (xy 296.521997 -286.014271)
			(xy 296.531792 -286.014668) (xy 296.667936 -286.014668) (xy 296.677724 -286.014224) (xy 296.695885 -286.006914)
			(xy 296.703242 -286.000444) (xy 296.761408 -285.944056) (xy 296.769282 -285.926022) (xy 296.769536 -285.916116)
			(xy 296.770722 -285.891328) (xy 296.780125 -285.842604) (xy 296.797281 -285.796041) (xy 296.821739 -285.752864)
			(xy 296.852856 -285.714208) (xy 296.889811 -285.681091) (xy 296.931635 -285.654384) (xy 296.977226 -285.634789)
			(xy 297.025384 -285.622823) (xy 297.074844 -285.618798) (xy 297.124304 -285.622823) (xy 297.172462 -285.634789)
			(xy 297.218053 -285.654384) (xy 297.259877 -285.681091) (xy 297.296832 -285.714208) (xy 297.327949 -285.752864)
			(xy 297.352407 -285.796041) (xy 297.369563 -285.842604) (xy 297.378966 -285.891328) (xy 297.380152 -285.916116)
			(xy 297.380406 -285.926022) (xy 297.38828 -285.944056) (xy 297.446446 -286.000444) (xy 297.453797 -286.006926)
			(xy 297.47196 -286.014241) (xy 297.481752 -286.014668) (xy 297.617896 -286.014668) (xy 297.627679 -286.014213)
			(xy 297.645825 -286.006888) (xy 297.653202 -286.000444) (xy 297.711368 -285.944056) (xy 297.719242 -285.926022)
			(xy 297.719496 -285.916116) (xy 297.720682 -285.891328) (xy 297.730085 -285.842604) (xy 297.747241 -285.796041)
			(xy 297.771699 -285.752864) (xy 297.802816 -285.714208) (xy 297.839771 -285.681091) (xy 297.881595 -285.654384)
			(xy 297.927186 -285.634789) (xy 297.975344 -285.622823) (xy 298.024804 -285.618798) (xy 298.074264 -285.622823)
			(xy 298.122422 -285.634789) (xy 298.168013 -285.654384) (xy 298.209837 -285.681091) (xy 298.246792 -285.714208)
			(xy 298.277909 -285.752864) (xy 298.302367 -285.796041) (xy 298.319523 -285.842604) (xy 298.328926 -285.891328)
			(xy 298.330112 -285.916116) (xy 298.330366 -285.926022) (xy 298.33824 -285.944056) (xy 298.396406 -286.000444)
			(xy 298.403755 -286.006932) (xy 298.421918 -286.014261) (xy 298.431712 -286.014668) (xy 298.567856 -286.014668)
			(xy 298.577642 -286.01422) (xy 298.595798 -286.006905) (xy 298.603162 -286.000444) (xy 298.661328 -285.944056)
			(xy 298.669202 -285.926022) (xy 298.669456 -285.916116) (xy 298.670642 -285.891328) (xy 298.680045 -285.842604)
			(xy 298.697201 -285.796041) (xy 298.721659 -285.752864) (xy 298.752776 -285.714208) (xy 298.789731 -285.681091)
			(xy 298.831555 -285.654384) (xy 298.877146 -285.634789) (xy 298.925304 -285.622823) (xy 298.974764 -285.618798)
			(xy 299.024224 -285.622823) (xy 299.072382 -285.634789) (xy 299.117973 -285.654384) (xy 299.159797 -285.681091)
			(xy 299.196752 -285.714208) (xy 299.227869 -285.752864) (xy 299.252327 -285.796041) (xy 299.269483 -285.842604)
			(xy 299.278886 -285.891328) (xy 299.280072 -285.916116) (xy 299.280326 -285.926022) (xy 299.2882 -285.944056)
			(xy 299.346366 -286.000444) (xy 299.353718 -286.006922) (xy 299.371881 -286.01423) (xy 299.381672 -286.014668)
			(xy 299.517816 -286.014668) (xy 299.527606 -286.014227) (xy 299.545771 -286.006923) (xy 299.553122 -286.000444)
			(xy 299.611288 -285.944056) (xy 299.619162 -285.926022) (xy 299.619416 -285.916116) (xy 299.620602 -285.891328)
			(xy 299.630005 -285.842604) (xy 299.647161 -285.796041) (xy 299.671619 -285.752864) (xy 299.702736 -285.714208)
			(xy 299.739691 -285.681091) (xy 299.781515 -285.654384) (xy 299.827106 -285.634789) (xy 299.875264 -285.622823)
			(xy 299.924724 -285.618798) (xy 299.974184 -285.622823) (xy 300.022342 -285.634789) (xy 300.067933 -285.654384)
			(xy 300.109757 -285.681091) (xy 300.146712 -285.714208) (xy 300.177829 -285.752864) (xy 300.202287 -285.796041)
			(xy 300.219443 -285.842604) (xy 300.228846 -285.891328) (xy 300.230032 -285.916116) (xy 300.230286 -285.926022)
			(xy 300.23816 -285.944056) (xy 300.296326 -286.000444) (xy 300.303676 -286.006929) (xy 300.321839 -286.014251)
			(xy 300.331632 -286.014668) (xy 300.467776 -286.014668) (xy 300.477561 -286.014216) (xy 300.495712 -286.006897)
			(xy 300.503082 -286.000444) (xy 300.561248 -285.944056) (xy 300.569122 -285.926022) (xy 300.569376 -285.916116)
			(xy 300.570562 -285.891328) (xy 300.579965 -285.842604) (xy 300.597121 -285.796041) (xy 300.621579 -285.752864)
			(xy 300.652696 -285.714208) (xy 300.689651 -285.681091) (xy 300.731475 -285.654384) (xy 300.777066 -285.634789)
			(xy 300.825224 -285.622823) (xy 300.874684 -285.618798) (xy 300.924144 -285.622823) (xy 300.972302 -285.634789)
			(xy 301.017893 -285.654384) (xy 301.059717 -285.681091) (xy 301.096672 -285.714208) (xy 301.127789 -285.752864)
			(xy 301.152247 -285.796041) (xy 301.169403 -285.842604) (xy 301.178806 -285.891328) (xy 301.179992 -285.916116)
			(xy 301.180246 -285.926022) (xy 301.18812 -285.944056) (xy 301.246286 -286.000444) (xy 301.253634 -286.006935)
			(xy 301.271797 -286.014271) (xy 301.281592 -286.014668) (xy 301.41799 -286.014668) (xy 301.427774 -286.014214)
			(xy 301.445921 -286.006891) (xy 301.453296 -286.000444) (xy 301.511462 -285.944056) (xy 301.519336 -285.926022)
			(xy 301.51959 -285.916116) (xy 301.520776 -285.891328) (xy 301.530179 -285.842604) (xy 301.547335 -285.796041)
			(xy 301.571793 -285.752864) (xy 301.60291 -285.714208) (xy 301.639865 -285.681091) (xy 301.681689 -285.654384)
			(xy 301.72728 -285.634789) (xy 301.775438 -285.622823) (xy 301.824898 -285.618798) (xy 301.874358 -285.622823)
			(xy 301.922516 -285.634789) (xy 301.968107 -285.654384) (xy 302.009931 -285.681091) (xy 302.046886 -285.714208)
			(xy 302.078003 -285.752864) (xy 302.102461 -285.796041) (xy 302.119617 -285.842604) (xy 302.12902 -285.891328)
			(xy 302.130206 -285.916116) (xy 302.13046 -285.926022) (xy 302.138334 -285.944056) (xy 302.1965 -286.000444)
			(xy 302.203849 -286.006933) (xy 302.222012 -286.014264) (xy 302.231806 -286.014668) (xy 302.36795 -286.014668)
			(xy 302.377737 -286.014221) (xy 302.395894 -286.006908) (xy 302.403256 -286.000444) (xy 302.461422 -285.944056)
			(xy 302.469296 -285.926022) (xy 302.46955 -285.916116) (xy 302.470736 -285.891328) (xy 302.480139 -285.842604)
			(xy 302.497295 -285.796041) (xy 302.521753 -285.752864) (xy 302.55287 -285.714208) (xy 302.589825 -285.681091)
			(xy 302.631649 -285.654384) (xy 302.67724 -285.634789) (xy 302.725398 -285.622823) (xy 302.774858 -285.618798)
			(xy 302.824318 -285.622823) (xy 302.872476 -285.634789) (xy 302.918067 -285.654384) (xy 302.959891 -285.681091)
			(xy 302.996846 -285.714208) (xy 303.027963 -285.752864) (xy 303.052421 -285.796041) (xy 303.069577 -285.842604)
			(xy 303.07898 -285.891328) (xy 303.080166 -285.916116) (xy 303.08042 -285.926022) (xy 303.088294 -285.944056)
			(xy 303.14646 -286.000444) (xy 303.153812 -286.006923) (xy 303.171975 -286.014233) (xy 303.181766 -286.014668)
			(xy 305.21783 -286.014668) (xy 305.227618 -286.014225) (xy 305.245781 -286.006917) (xy 305.253136 -286.000444)
			(xy 305.311302 -285.944056) (xy 305.319176 -285.926022) (xy 305.31943 -285.916116) (xy 305.320598 -285.892143)
			(xy 305.329478 -285.844979) (xy 305.345623 -285.799784) (xy 305.368638 -285.757669) (xy 305.397955 -285.719671)
			(xy 305.432853 -285.686725) (xy 305.472474 -285.659641) (xy 305.515842 -285.639086) (xy 305.561891 -285.625565)
			(xy 305.609488 -285.619412) (xy 305.657462 -285.620777) (xy 305.681126 -285.624778) (xy 305.693572 -285.627064)
			(xy 305.717194 -285.619698) (xy 305.794664 -285.542228) (xy 305.80203 -285.518606) (xy 305.799744 -285.50616)
			(xy 305.79726 -285.492195) (xy 305.79459 -285.463955) (xy 305.79441 -285.449772) (xy 305.794932 -285.424517)
			(xy 305.803245 -285.374695) (xy 305.819646 -285.326921) (xy 305.843687 -285.282498) (xy 305.874711 -285.242638)
			(xy 305.911873 -285.208428) (xy 305.954159 -285.180802) (xy 306.000415 -285.160512) (xy 306.04938 -285.148112)
			(xy 306.099718 -285.143941) (xy 306.150056 -285.148112) (xy 306.199021 -285.160512) (xy 306.245277 -285.180802)
			(xy 306.287563 -285.208428) (xy 306.324725 -285.242638) (xy 306.355749 -285.282498) (xy 306.37979 -285.326921)
			(xy 306.396191 -285.374695) (xy 306.404504 -285.424517) (xy 306.405026 -285.449772) (xy 306.404927 -285.458876)
			(xy 306.403782 -285.477049) (xy 306.40274 -285.486094) (xy 306.40147 -285.498286) (xy 306.409344 -285.520638)
			(xy 306.485798 -285.593536) (xy 306.508404 -285.600648) (xy 306.520342 -285.598616) (xy 306.53383 -285.596485)
			(xy 306.561043 -285.594198) (xy 306.574698 -285.594044) (xy 306.623212 -285.594044) (xy 306.633868 -285.593581)
			(xy 306.653326 -285.584888) (xy 306.660804 -285.57728) (xy 306.718716 -285.513526) (xy 306.72532 -285.493206)
			(xy 306.724304 -285.482284) (xy 306.72278 -285.449772) (xy 306.723284 -285.424084) (xy 306.731321 -285.373341)
			(xy 306.747197 -285.32448) (xy 306.770521 -285.278704) (xy 306.800718 -285.23714) (xy 306.837046 -285.200812)
			(xy 306.87861 -285.170615) (xy 306.924386 -285.147291) (xy 306.973247 -285.131415) (xy 307.02399 -285.123378)
			(xy 307.075366 -285.123378) (xy 307.126109 -285.131415) (xy 307.17497 -285.147291) (xy 307.220746 -285.170615)
			(xy 307.26231 -285.200812) (xy 307.298638 -285.23714) (xy 307.328835 -285.278704) (xy 307.352159 -285.32448)
			(xy 307.368035 -285.373341) (xy 307.376072 -285.424084) (xy 307.376576 -285.449772) (xy 307.375052 -285.482284)
			(xy 307.374036 -285.493206) (xy 307.38064 -285.513526) (xy 307.438552 -285.57728) (xy 307.446095 -285.584794)
			(xy 307.465514 -285.593468) (xy 307.476144 -285.594044) (xy 307.524658 -285.594044) (xy 307.534076 -285.59408)
			(xy 307.552883 -285.595098) (xy 307.56225 -285.596076) (xy 307.57368 -285.5976) (xy 307.595524 -285.58998)
			(xy 307.668168 -285.51759) (xy 307.676042 -285.496) (xy 307.674772 -285.48457) (xy 307.67274 -285.449772)
			(xy 307.673244 -285.424064) (xy 307.681287 -285.373282) (xy 307.697175 -285.324383) (xy 307.720518 -285.278571)
			(xy 307.750739 -285.236975) (xy 307.787095 -285.200619) (xy 307.828691 -285.170398) (xy 307.874503 -285.147055)
			(xy 307.923402 -285.131167) (xy 307.974184 -285.123124) (xy 308.0256 -285.123124) (xy 308.076382 -285.131167)
			(xy 308.125281 -285.147055) (xy 308.171093 -285.170398) (xy 308.212689 -285.200619) (xy 308.249045 -285.236975)
			(xy 308.279266 -285.278571) (xy 308.302609 -285.324383) (xy 308.318497 -285.373282) (xy 308.32654 -285.424064)
			(xy 308.327044 -285.449772) (xy 308.32685 -285.463495) (xy 308.324431 -285.490837) (xy 308.322218 -285.504382)
			(xy 308.32044 -285.51632) (xy 308.327298 -285.53918) (xy 308.400958 -285.615634) (xy 308.423564 -285.623508)
			(xy 308.435502 -285.621984) (xy 308.459425 -285.619349) (xy 308.507532 -285.620752) (xy 308.53126 -285.624778)
			(xy 308.543706 -285.627064) (xy 308.567328 -285.619698) (xy 308.644798 -285.542228) (xy 308.652164 -285.518606)
			(xy 308.649878 -285.50616) (xy 308.647394 -285.492195) (xy 308.644724 -285.463955) (xy 308.644544 -285.449772)
			(xy 308.645066 -285.424517) (xy 308.653379 -285.374695) (xy 308.66978 -285.326921) (xy 308.693821 -285.282498)
			(xy 308.724845 -285.242638) (xy 308.762007 -285.208428) (xy 308.804293 -285.180802) (xy 308.850549 -285.160512)
			(xy 308.899514 -285.148112) (xy 308.949852 -285.143941) (xy 309.00019 -285.148112) (xy 309.049155 -285.160512)
			(xy 309.095411 -285.180802) (xy 309.137697 -285.208428) (xy 309.174859 -285.242638) (xy 309.205883 -285.282498)
			(xy 309.229924 -285.326921) (xy 309.246325 -285.374695) (xy 309.254638 -285.424517) (xy 309.25516 -285.449772)
			(xy 309.254975 -285.463955) (xy 309.252304 -285.492194) (xy 309.249826 -285.50616) (xy 309.24754 -285.518606)
			(xy 309.254906 -285.542228) (xy 309.332376 -285.619698) (xy 309.355998 -285.627064) (xy 309.368444 -285.624778)
			(xy 309.396451 -285.620149) (xy 309.453213 -285.620149) (xy 309.48122 -285.624778) (xy 309.493666 -285.627064)
			(xy 309.517288 -285.619698) (xy 309.594758 -285.542228) (xy 309.602124 -285.518606) (xy 309.599838 -285.50616)
			(xy 309.597354 -285.492195) (xy 309.594684 -285.463955) (xy 309.594504 -285.449772) (xy 309.595026 -285.424517)
			(xy 309.603339 -285.374695) (xy 309.61974 -285.326921) (xy 309.643781 -285.282498) (xy 309.674805 -285.242638)
			(xy 309.711967 -285.208428) (xy 309.754253 -285.180802) (xy 309.800509 -285.160512) (xy 309.849474 -285.148112)
			(xy 309.899812 -285.143941) (xy 309.95015 -285.148112) (xy 309.999115 -285.160512) (xy 310.045371 -285.180802)
			(xy 310.087657 -285.208428) (xy 310.124819 -285.242638) (xy 310.155843 -285.282498) (xy 310.179884 -285.326921)
			(xy 310.196285 -285.374695) (xy 310.204598 -285.424517) (xy 310.20512 -285.449772) (xy 310.204935 -285.463955)
			(xy 310.202264 -285.492194) (xy 310.199786 -285.50616) (xy 310.1975 -285.518606) (xy 310.204866 -285.542228)
			(xy 310.282336 -285.619698) (xy 310.305958 -285.627064) (xy 310.318404 -285.624778) (xy 310.346411 -285.620149)
			(xy 310.403173 -285.620149) (xy 310.43118 -285.624778) (xy 310.443626 -285.627064) (xy 310.467248 -285.619698)
			(xy 310.544718 -285.542228) (xy 310.552084 -285.518606) (xy 310.549798 -285.50616) (xy 310.547314 -285.492195)
			(xy 310.544645 -285.463955) (xy 310.544464 -285.449772) (xy 310.544986 -285.424517) (xy 310.553299 -285.374695)
			(xy 310.5697 -285.326921) (xy 310.593741 -285.282498) (xy 310.624765 -285.242638) (xy 310.661927 -285.208428)
			(xy 310.704213 -285.180802) (xy 310.750469 -285.160512) (xy 310.799434 -285.148112) (xy 310.849772 -285.143941)
			(xy 310.90011 -285.148112) (xy 310.949075 -285.160512) (xy 310.995331 -285.180802) (xy 311.037617 -285.208428)
			(xy 311.074779 -285.242638) (xy 311.105803 -285.282498) (xy 311.129844 -285.326921) (xy 311.146245 -285.374695)
			(xy 311.154558 -285.424517) (xy 311.15508 -285.449772) (xy 311.154895 -285.463955) (xy 311.152224 -285.492194)
			(xy 311.149746 -285.50616) (xy 311.14746 -285.518606) (xy 311.154826 -285.542228) (xy 311.232296 -285.619698)
			(xy 311.255918 -285.627064) (xy 311.268364 -285.624778) (xy 311.296371 -285.620149) (xy 311.353133 -285.620149)
			(xy 311.38114 -285.624778) (xy 311.393586 -285.627064) (xy 311.417208 -285.619698) (xy 311.494678 -285.542228)
			(xy 311.502044 -285.518606) (xy 311.499758 -285.50616) (xy 311.497274 -285.492195) (xy 311.494604 -285.463955)
			(xy 311.494424 -285.449772) (xy 311.494946 -285.424517) (xy 311.503259 -285.374695) (xy 311.51966 -285.326921)
			(xy 311.543701 -285.282498) (xy 311.574725 -285.242638) (xy 311.611887 -285.208428) (xy 311.654173 -285.180802)
			(xy 311.700429 -285.160512) (xy 311.749394 -285.148112) (xy 311.799732 -285.143941) (xy 311.85007 -285.148112)
			(xy 311.899035 -285.160512) (xy 311.945291 -285.180802) (xy 311.987577 -285.208428) (xy 312.024739 -285.242638)
			(xy 312.055763 -285.282498) (xy 312.079804 -285.326921) (xy 312.096205 -285.374695) (xy 312.104518 -285.424517)
			(xy 312.10504 -285.449772) (xy 312.104941 -285.458876) (xy 312.103796 -285.477049) (xy 312.102754 -285.486094)
			(xy 312.101484 -285.498286) (xy 312.109358 -285.520638) (xy 312.185812 -285.593536) (xy 312.208418 -285.600648)
			(xy 312.220356 -285.598616) (xy 312.233844 -285.596486) (xy 312.261058 -285.594199) (xy 312.274712 -285.594044)
			(xy 312.34507 -285.594044) (xy 312.355756 -285.59347) (xy 312.375292 -285.584793) (xy 312.382916 -285.57728)
			(xy 312.440574 -285.513018) (xy 312.447178 -285.492698) (xy 312.446162 -285.481776) (xy 312.444384 -285.449772)
			(xy 312.444906 -285.424517) (xy 312.453219 -285.374695) (xy 312.46962 -285.326921) (xy 312.493661 -285.282498)
			(xy 312.524685 -285.242638) (xy 312.561847 -285.208428) (xy 312.604133 -285.180802) (xy 312.650389 -285.160512)
			(xy 312.699354 -285.148112) (xy 312.749692 -285.143941) (xy 312.80003 -285.148112) (xy 312.848995 -285.160512)
			(xy 312.895251 -285.180802) (xy 312.937537 -285.208428) (xy 312.974699 -285.242638) (xy 313.005723 -285.282498)
			(xy 313.029764 -285.326921) (xy 313.046165 -285.374695) (xy 313.054478 -285.424517) (xy 313.055 -285.449772)
			(xy 313.053222 -285.481776) (xy 313.052206 -285.492698) (xy 313.05881 -285.513018) (xy 313.116468 -285.57728)
			(xy 313.123984 -285.584943) (xy 313.143589 -285.593635) (xy 313.154314 -285.594044) (xy 313.224672 -285.594044)
			(xy 313.23409 -285.594081) (xy 313.252897 -285.5951) (xy 313.262264 -285.596076) (xy 313.273694 -285.5976)
			(xy 313.295538 -285.58998) (xy 313.368182 -285.51759) (xy 313.376056 -285.496) (xy 313.374786 -285.48457)
			(xy 313.373008 -285.449772) (xy 313.373512 -285.424084) (xy 313.381549 -285.373341) (xy 313.397425 -285.32448)
			(xy 313.420749 -285.278704) (xy 313.450946 -285.23714) (xy 313.487274 -285.200812) (xy 313.528838 -285.170615)
			(xy 313.574614 -285.147291) (xy 313.623475 -285.131415) (xy 313.674218 -285.123378) (xy 313.725594 -285.123378)
			(xy 313.776337 -285.131415) (xy 313.825198 -285.147291) (xy 313.870974 -285.170615) (xy 313.912538 -285.200812)
			(xy 313.948866 -285.23714) (xy 313.979063 -285.278704) (xy 314.002387 -285.32448) (xy 314.018263 -285.373341)
			(xy 314.0263 -285.424084) (xy 314.026804 -285.449772) (xy 314.026678 -285.463491) (xy 314.024393 -285.490834)
			(xy 314.022232 -285.504382) (xy 314.020454 -285.51632) (xy 314.027312 -285.53918) (xy 314.100972 -285.615634)
			(xy 314.123578 -285.623508) (xy 314.135516 -285.621984) (xy 314.155139 -285.619746) (xy 314.194633 -285.619746)
			(xy 314.214256 -285.621984) (xy 314.226194 -285.623508) (xy 314.2488 -285.615634) (xy 314.32246 -285.53918)
			(xy 314.329318 -285.51632) (xy 314.32754 -285.504382) (xy 314.325404 -285.490831) (xy 314.323119 -285.46349)
			(xy 314.322968 -285.449772) (xy 314.323472 -285.424084) (xy 314.331509 -285.373341) (xy 314.347385 -285.32448)
			(xy 314.370709 -285.278704) (xy 314.400906 -285.23714) (xy 314.437234 -285.200812) (xy 314.478798 -285.170615)
			(xy 314.524574 -285.147291) (xy 314.573435 -285.131415) (xy 314.624178 -285.123378) (xy 314.675554 -285.123378)
			(xy 314.726297 -285.131415) (xy 314.775158 -285.147291) (xy 314.820934 -285.170615) (xy 314.862498 -285.200812)
			(xy 314.898826 -285.23714) (xy 314.929023 -285.278704) (xy 314.952347 -285.32448) (xy 314.968223 -285.373341)
			(xy 314.97626 -285.424084) (xy 314.976764 -285.449772) (xy 314.976638 -285.463491) (xy 314.974352 -285.490834)
			(xy 314.972192 -285.504382) (xy 314.970414 -285.51632) (xy 314.977272 -285.53918) (xy 315.050932 -285.615634)
			(xy 315.073538 -285.623508) (xy 315.085476 -285.621984) (xy 315.109399 -285.619347) (xy 315.157506 -285.620746)
			(xy 315.181234 -285.624778) (xy 315.193934 -285.627064) (xy 315.217556 -285.619698) (xy 315.295026 -285.542482)
			(xy 315.302392 -285.51886) (xy 315.300106 -285.50616) (xy 315.297631 -285.492258) (xy 315.294962 -285.464145)
			(xy 315.294772 -285.450026) (xy 315.295256 -285.425203) (xy 315.303284 -285.37621) (xy 315.319133 -285.329161)
			(xy 315.342384 -285.285296) (xy 315.372427 -285.245771) (xy 315.408468 -285.211626) (xy 315.449558 -285.183763)
			(xy 315.494615 -285.162915) (xy 315.542451 -285.149631) (xy 315.591807 -285.144261) (xy 315.641381 -285.146948)
			(xy 315.689867 -285.157619) (xy 315.735988 -285.175994) (xy 315.778528 -285.201589) (xy 315.816367 -285.233729)
			(xy 315.848508 -285.271567) (xy 315.874104 -285.314107) (xy 315.892479 -285.360228) (xy 315.903152 -285.408713)
			(xy 315.905839 -285.458287) (xy 315.90047 -285.507643) (xy 315.897496 -285.518352) (xy 323.668134 -285.518352)
			(xy 323.672205 -285.46273) (xy 323.684331 -285.408293) (xy 323.704254 -285.356202) (xy 323.73155 -285.307567)
			(xy 323.765636 -285.263424) (xy 323.805785 -285.224715) (xy 323.851143 -285.192264) (xy 323.900743 -285.166763)
			(xy 323.953527 -285.148756) (xy 324.00837 -285.138626) (xy 324.064104 -285.136589) (xy 324.119541 -285.142689)
			(xy 324.173498 -285.156795) (xy 324.224827 -285.178607) (xy 324.272433 -285.207661) (xy 324.315301 -285.243336)
			(xy 324.352518 -285.284873) (xy 324.383291 -285.331386) (xy 324.406963 -285.381883) (xy 324.423031 -285.43529)
			(xy 324.431151 -285.490466) (xy 324.43166 -285.518352) (xy 324.431151 -285.546238) (xy 324.423031 -285.601414)
			(xy 324.406963 -285.654821) (xy 324.383291 -285.705318) (xy 324.352518 -285.751831) (xy 324.315301 -285.793368)
			(xy 324.272433 -285.829043) (xy 324.224827 -285.858097) (xy 324.173498 -285.879909) (xy 324.119541 -285.894015)
			(xy 324.064104 -285.900115) (xy 324.00837 -285.898078) (xy 323.953527 -285.887948) (xy 323.900743 -285.869941)
			(xy 323.851143 -285.84444) (xy 323.805785 -285.811989) (xy 323.765636 -285.77328) (xy 323.73155 -285.729137)
			(xy 323.704254 -285.680502) (xy 323.684331 -285.628411) (xy 323.672205 -285.573974) (xy 323.668134 -285.518352)
			(xy 315.897496 -285.518352) (xy 315.887187 -285.555479) (xy 315.86634 -285.600537) (xy 315.838477 -285.641628)
			(xy 315.804334 -285.677669) (xy 315.764809 -285.707712) (xy 315.720945 -285.730965) (xy 315.673896 -285.746815)
			(xy 315.624903 -285.754844) (xy 315.60008 -285.755334) (xy 315.585898 -285.755147) (xy 315.557659 -285.752471)
			(xy 315.543692 -285.75) (xy 315.530992 -285.747714) (xy 315.50737 -285.75508) (xy 315.4299 -285.832296)
			(xy 315.422788 -285.855918) (xy 315.425074 -285.868618) (xy 315.427159 -285.880392) (xy 315.429705 -285.904168)
			(xy 315.430154 -285.916116) (xy 315.430408 -285.926022) (xy 315.438282 -285.944056) (xy 315.496448 -286.000444)
			(xy 315.503799 -286.006926) (xy 315.521962 -286.01424) (xy 315.531754 -286.014668) (xy 331.52207 -286.014668)
			(xy 331.532093 -286.014253) (xy 331.550615 -286.006587) (xy 331.564788 -285.992413) (xy 331.572453 -285.973891)
			(xy 331.57287 -285.963868) (xy 331.57287 -271.033748) (xy 331.573302 -271.023681) (xy 331.581026 -271.005088)
			(xy 331.587856 -270.99768) (xy 336.00898 -266.576556) (xy 336.01638 -266.569716) (xy 336.034979 -266.562002)
			(xy 336.045048 -266.56157) (xy 375.941336 -266.56157) (xy 375.946841 -266.561452) (xy 375.957605 -266.559151)
			(xy 375.962672 -266.556998) (xy 376.050927 -266.517149) (xy 376.230154 -266.443776) (xy 376.412209 -266.377728)
			(xy 376.596791 -266.319115) (xy 376.783598 -266.268033) (xy 376.972321 -266.224565) (xy 377.162652 -266.188783)
			(xy 377.354277 -266.160747) (xy 377.546881 -266.140501) (xy 377.740147 -266.12808) (xy 377.933758 -266.123503)
			(xy 378.127396 -266.126779) (xy 378.320741 -266.137902) (xy 378.513477 -266.156853) (xy 378.705285 -266.183602)
			(xy 378.895852 -266.218105) (xy 379.084864 -266.260304) (xy 379.272009 -266.31013) (xy 379.456981 -266.367502)
			(xy 379.639475 -266.432326) (xy 379.819192 -266.504494) (xy 379.995835 -266.583887) (xy 380.169114 -266.670377)
			(xy 380.338745 -266.763819) (xy 380.504449 -266.864061) (xy 380.654558 -266.963398) (xy 386.956044 -266.963398)
			(xy 386.960115 -266.907776) (xy 386.972241 -266.853339) (xy 386.992164 -266.801248) (xy 387.01946 -266.752613)
			(xy 387.053546 -266.70847) (xy 387.093695 -266.669761) (xy 387.139053 -266.63731) (xy 387.188653 -266.611809)
			(xy 387.241437 -266.593802) (xy 387.29628 -266.583672) (xy 387.352014 -266.581635) (xy 387.407451 -266.587735)
			(xy 387.461408 -266.601841) (xy 387.512737 -266.623653) (xy 387.560343 -266.652707) (xy 387.603211 -266.688382)
			(xy 387.640428 -266.729919) (xy 387.671201 -266.776432) (xy 387.694873 -266.826929) (xy 387.710941 -266.880336)
			(xy 387.716137 -266.915646) (xy 388.736076 -266.915646) (xy 388.740147 -266.860024) (xy 388.752273 -266.805587)
			(xy 388.772196 -266.753496) (xy 388.799492 -266.704861) (xy 388.833578 -266.660718) (xy 388.873727 -266.622009)
			(xy 388.919085 -266.589558) (xy 388.968685 -266.564057) (xy 389.021469 -266.54605) (xy 389.076312 -266.53592)
			(xy 389.132046 -266.533883) (xy 389.187483 -266.539983) (xy 389.24144 -266.554089) (xy 389.292769 -266.575901)
			(xy 389.340375 -266.604955) (xy 389.383243 -266.64063) (xy 389.42046 -266.682167) (xy 389.451233 -266.72868)
			(xy 389.474905 -266.779177) (xy 389.490973 -266.832584) (xy 389.499093 -266.88776) (xy 389.499602 -266.915646)
			(xy 389.499093 -266.943532) (xy 389.490973 -266.998708) (xy 389.474905 -267.052115) (xy 389.451233 -267.102612)
			(xy 389.42046 -267.149125) (xy 389.383243 -267.190662) (xy 389.340375 -267.226337) (xy 389.292769 -267.255391)
			(xy 389.24144 -267.277203) (xy 389.187483 -267.291309) (xy 389.132046 -267.297409) (xy 389.076312 -267.295372)
			(xy 389.021469 -267.285242) (xy 388.968685 -267.267235) (xy 388.919085 -267.241734) (xy 388.873727 -267.209283)
			(xy 388.833578 -267.170574) (xy 388.799492 -267.126431) (xy 388.772196 -267.077796) (xy 388.752273 -267.025705)
			(xy 388.740147 -266.971268) (xy 388.736076 -266.915646) (xy 387.716137 -266.915646) (xy 387.719061 -266.935512)
			(xy 387.71957 -266.963398) (xy 387.719061 -266.991284) (xy 387.710941 -267.04646) (xy 387.694873 -267.099867)
			(xy 387.671201 -267.150364) (xy 387.640428 -267.196877) (xy 387.603211 -267.238414) (xy 387.560343 -267.274089)
			(xy 387.512737 -267.303143) (xy 387.461408 -267.324955) (xy 387.407451 -267.339061) (xy 387.352014 -267.345161)
			(xy 387.29628 -267.343124) (xy 387.241437 -267.332994) (xy 387.188653 -267.314987) (xy 387.139053 -267.289486)
			(xy 387.093695 -267.257035) (xy 387.053546 -267.218326) (xy 387.01946 -267.174183) (xy 386.992164 -267.125548)
			(xy 386.972241 -267.073457) (xy 386.960115 -267.01902) (xy 386.956044 -266.963398) (xy 380.654558 -266.963398)
			(xy 380.665952 -266.970938) (xy 380.822991 -267.084275) (xy 380.899416 -267.143738) (xy 380.89967 -267.143992)
			(xy 380.906516 -267.148924) (xy 380.922479 -267.154354) (xy 380.930912 -267.15466) (xy 382.537462 -267.15466)
			(xy 382.547526 -267.155096) (xy 382.566108 -267.162833) (xy 382.57353 -267.169646) (xy 382.981962 -267.578078)
			(xy 385.153152 -267.578078) (xy 385.157223 -267.522456) (xy 385.169349 -267.468019) (xy 385.189272 -267.415928)
			(xy 385.216568 -267.367293) (xy 385.250654 -267.32315) (xy 385.290803 -267.284441) (xy 385.336161 -267.25199)
			(xy 385.385761 -267.226489) (xy 385.438545 -267.208482) (xy 385.493388 -267.198352) (xy 385.549122 -267.196315)
			(xy 385.604559 -267.202415) (xy 385.658516 -267.216521) (xy 385.709845 -267.238333) (xy 385.757451 -267.267387)
			(xy 385.800319 -267.303062) (xy 385.837536 -267.344599) (xy 385.868309 -267.391112) (xy 385.891981 -267.441609)
			(xy 385.908049 -267.495016) (xy 385.916169 -267.550192) (xy 385.916678 -267.578078) (xy 385.916169 -267.605964)
			(xy 385.908049 -267.66114) (xy 385.891981 -267.714547) (xy 385.868309 -267.765044) (xy 385.837536 -267.811557)
			(xy 385.800319 -267.853094) (xy 385.757451 -267.888769) (xy 385.709845 -267.917823) (xy 385.658516 -267.939635)
			(xy 385.604559 -267.953741) (xy 385.549122 -267.959841) (xy 385.493388 -267.957804) (xy 385.438545 -267.947674)
			(xy 385.385761 -267.929667) (xy 385.336161 -267.904166) (xy 385.290803 -267.871715) (xy 385.250654 -267.833006)
			(xy 385.216568 -267.788863) (xy 385.189272 -267.740228) (xy 385.169349 -267.688137) (xy 385.157223 -267.6337)
			(xy 385.153152 -267.578078) (xy 382.981962 -267.578078) (xy 383.742946 -268.339062) (xy 388.744204 -268.339062)
			(xy 388.748275 -268.28344) (xy 388.760401 -268.229003) (xy 388.780324 -268.176912) (xy 388.80762 -268.128277)
			(xy 388.841706 -268.084134) (xy 388.881855 -268.045425) (xy 388.927213 -268.012974) (xy 388.976813 -267.987473)
			(xy 389.029597 -267.969466) (xy 389.08444 -267.959336) (xy 389.140174 -267.957299) (xy 389.195611 -267.963399)
			(xy 389.249568 -267.977505) (xy 389.300897 -267.999317) (xy 389.348503 -268.028371) (xy 389.391371 -268.064046)
			(xy 389.428588 -268.105583) (xy 389.459361 -268.152096) (xy 389.483033 -268.202593) (xy 389.499101 -268.256)
			(xy 389.507221 -268.311176) (xy 389.50773 -268.339062) (xy 389.507221 -268.366948) (xy 389.499101 -268.422124)
			(xy 389.483033 -268.475531) (xy 389.459361 -268.526028) (xy 389.428588 -268.572541) (xy 389.391371 -268.614078)
			(xy 389.348503 -268.649753) (xy 389.300897 -268.678807) (xy 389.249568 -268.700619) (xy 389.195611 -268.714725)
			(xy 389.140174 -268.720825) (xy 389.08444 -268.718788) (xy 389.029597 -268.708658) (xy 388.976813 -268.690651)
			(xy 388.927213 -268.66515) (xy 388.881855 -268.632699) (xy 388.841706 -268.59399) (xy 388.80762 -268.549847)
			(xy 388.780324 -268.501212) (xy 388.760401 -268.449121) (xy 388.748275 -268.394684) (xy 388.744204 -268.339062)
			(xy 383.742946 -268.339062) (xy 383.771394 -268.36751) (xy 383.778239 -268.374909) (xy 383.785971 -268.393507)
			(xy 383.78638 -268.403578) (xy 383.78638 -269.943326) (xy 388.630666 -269.943326) (xy 388.634737 -269.887704)
			(xy 388.646863 -269.833267) (xy 388.666786 -269.781176) (xy 388.694082 -269.732541) (xy 388.728168 -269.688398)
			(xy 388.768317 -269.649689) (xy 388.813675 -269.617238) (xy 388.863275 -269.591737) (xy 388.916059 -269.57373)
			(xy 388.970902 -269.5636) (xy 389.026636 -269.561563) (xy 389.082073 -269.567663) (xy 389.13603 -269.581769)
			(xy 389.187359 -269.603581) (xy 389.234965 -269.632635) (xy 389.277833 -269.66831) (xy 389.31505 -269.709847)
			(xy 389.345823 -269.75636) (xy 389.369495 -269.806857) (xy 389.385563 -269.860264) (xy 389.393683 -269.91544)
			(xy 389.394192 -269.943326) (xy 389.393683 -269.971212) (xy 389.385563 -270.026388) (xy 389.369495 -270.079795)
			(xy 389.345823 -270.130292) (xy 389.31505 -270.176805) (xy 389.277833 -270.218342) (xy 389.234965 -270.254017)
			(xy 389.187359 -270.283071) (xy 389.13603 -270.304883) (xy 389.082073 -270.318989) (xy 389.026636 -270.325089)
			(xy 388.970902 -270.323052) (xy 388.916059 -270.312922) (xy 388.863275 -270.294915) (xy 388.813675 -270.269414)
			(xy 388.768317 -270.236963) (xy 388.728168 -270.198254) (xy 388.694082 -270.154111) (xy 388.666786 -270.105476)
			(xy 388.646863 -270.053385) (xy 388.634737 -269.998948) (xy 388.630666 -269.943326) (xy 383.78638 -269.943326)
			(xy 383.78638 -272.14957) (xy 392.443728 -272.14957) (xy 392.447688 -272.100516) (xy 392.459465 -272.052732)
			(xy 392.478756 -272.007456) (xy 392.505059 -271.96586) (xy 392.537694 -271.929023) (xy 392.575815 -271.897898)
			(xy 392.618436 -271.873291) (xy 392.664452 -271.855839) (xy 392.712671 -271.845995) (xy 392.761846 -271.844014)
			(xy 392.810701 -271.849946) (xy 392.857972 -271.863638) (xy 392.902434 -271.884736) (xy 392.942937 -271.912692)
			(xy 392.97843 -271.946784) (xy 393.007995 -271.986128) (xy 393.030866 -272.029705) (xy 393.04645 -272.076386)
			(xy 393.054345 -272.124963) (xy 393.05484 -272.14957) (xy 394.343902 -272.14957) (xy 394.347862 -272.100516)
			(xy 394.359639 -272.052732) (xy 394.37893 -272.007456) (xy 394.405233 -271.96586) (xy 394.437868 -271.929023)
			(xy 394.475989 -271.897898) (xy 394.51861 -271.873291) (xy 394.564626 -271.855839) (xy 394.612845 -271.845995)
			(xy 394.66202 -271.844014) (xy 394.710875 -271.849946) (xy 394.758146 -271.863638) (xy 394.802608 -271.884736)
			(xy 394.843111 -271.912692) (xy 394.878604 -271.946784) (xy 394.908169 -271.986128) (xy 394.93104 -272.029705)
			(xy 394.946624 -272.076386) (xy 394.954519 -272.124963) (xy 394.955014 -272.14957) (xy 396.243822 -272.14957)
			(xy 396.247782 -272.100516) (xy 396.259559 -272.052732) (xy 396.27885 -272.007456) (xy 396.305153 -271.96586)
			(xy 396.337788 -271.929023) (xy 396.375909 -271.897898) (xy 396.41853 -271.873291) (xy 396.464546 -271.855839)
			(xy 396.512765 -271.845995) (xy 396.56194 -271.844014) (xy 396.610795 -271.849946) (xy 396.658066 -271.863638)
			(xy 396.702528 -271.884736) (xy 396.743031 -271.912692) (xy 396.778524 -271.946784) (xy 396.808089 -271.986128)
			(xy 396.83096 -272.029705) (xy 396.846544 -272.076386) (xy 396.854439 -272.124963) (xy 396.854934 -272.14957)
			(xy 398.143742 -272.14957) (xy 398.147702 -272.100516) (xy 398.159479 -272.052732) (xy 398.17877 -272.007456)
			(xy 398.205073 -271.96586) (xy 398.237708 -271.929023) (xy 398.275829 -271.897898) (xy 398.31845 -271.873291)
			(xy 398.364466 -271.855839) (xy 398.412685 -271.845995) (xy 398.46186 -271.844014) (xy 398.510715 -271.849946)
			(xy 398.557986 -271.863638) (xy 398.602448 -271.884736) (xy 398.642951 -271.912692) (xy 398.678444 -271.946784)
			(xy 398.708009 -271.986128) (xy 398.73088 -272.029705) (xy 398.746464 -272.076386) (xy 398.754359 -272.124963)
			(xy 398.754854 -272.14957) (xy 400.043916 -272.14957) (xy 400.047876 -272.100516) (xy 400.059653 -272.052732)
			(xy 400.078944 -272.007456) (xy 400.105247 -271.96586) (xy 400.137882 -271.929023) (xy 400.176003 -271.897898)
			(xy 400.218624 -271.873291) (xy 400.26464 -271.855839) (xy 400.312859 -271.845995) (xy 400.362034 -271.844014)
			(xy 400.410889 -271.849946) (xy 400.45816 -271.863638) (xy 400.502622 -271.884736) (xy 400.543125 -271.912692)
			(xy 400.578618 -271.946784) (xy 400.608183 -271.986128) (xy 400.631054 -272.029705) (xy 400.646638 -272.076386)
			(xy 400.654533 -272.124963) (xy 400.655028 -272.14957) (xy 401.943836 -272.14957) (xy 401.947796 -272.100516)
			(xy 401.959573 -272.052732) (xy 401.978864 -272.007456) (xy 402.005167 -271.96586) (xy 402.037802 -271.929023)
			(xy 402.075923 -271.897898) (xy 402.118544 -271.873291) (xy 402.16456 -271.855839) (xy 402.212779 -271.845995)
			(xy 402.261954 -271.844014) (xy 402.310809 -271.849946) (xy 402.35808 -271.863638) (xy 402.402542 -271.884736)
			(xy 402.443045 -271.912692) (xy 402.478538 -271.946784) (xy 402.508103 -271.986128) (xy 402.530974 -272.029705)
			(xy 402.546558 -272.076386) (xy 402.554453 -272.124963) (xy 402.554948 -272.14957) (xy 403.843756 -272.14957)
			(xy 403.847716 -272.100516) (xy 403.859493 -272.052732) (xy 403.878784 -272.007456) (xy 403.905087 -271.96586)
			(xy 403.937722 -271.929023) (xy 403.975843 -271.897898) (xy 404.018464 -271.873291) (xy 404.06448 -271.855839)
			(xy 404.112699 -271.845995) (xy 404.161874 -271.844014) (xy 404.210729 -271.849946) (xy 404.258 -271.863638)
			(xy 404.302462 -271.884736) (xy 404.342965 -271.912692) (xy 404.378458 -271.946784) (xy 404.408023 -271.986128)
			(xy 404.430894 -272.029705) (xy 404.446478 -272.076386) (xy 404.454373 -272.124963) (xy 404.454868 -272.14957)
			(xy 405.74393 -272.14957) (xy 405.74789 -272.100516) (xy 405.759667 -272.052732) (xy 405.778958 -272.007456)
			(xy 405.805261 -271.96586) (xy 405.837896 -271.929023) (xy 405.876017 -271.897898) (xy 405.918638 -271.873291)
			(xy 405.964654 -271.855839) (xy 406.012873 -271.845995) (xy 406.062048 -271.844014) (xy 406.110903 -271.849946)
			(xy 406.158174 -271.863638) (xy 406.202636 -271.884736) (xy 406.243139 -271.912692) (xy 406.278632 -271.946784)
			(xy 406.308197 -271.986128) (xy 406.331068 -272.029705) (xy 406.346652 -272.076386) (xy 406.354547 -272.124963)
			(xy 406.355037 -272.149316) (xy 407.64385 -272.149316) (xy 407.64781 -272.100262) (xy 407.659587 -272.052478)
			(xy 407.678878 -272.007202) (xy 407.705181 -271.965606) (xy 407.737816 -271.928769) (xy 407.775937 -271.897644)
			(xy 407.818558 -271.873037) (xy 407.864574 -271.855585) (xy 407.912793 -271.845741) (xy 407.961968 -271.84376)
			(xy 408.010823 -271.849692) (xy 408.058094 -271.863384) (xy 408.102556 -271.884482) (xy 408.143059 -271.912438)
			(xy 408.178552 -271.94653) (xy 408.208117 -271.985874) (xy 408.230988 -272.029451) (xy 408.246572 -272.076132)
			(xy 408.254467 -272.124709) (xy 408.254962 -272.149316) (xy 408.254957 -272.14957) (xy 409.54377 -272.14957)
			(xy 409.54773 -272.100516) (xy 409.559507 -272.052732) (xy 409.578798 -272.007456) (xy 409.605101 -271.96586)
			(xy 409.637736 -271.929023) (xy 409.675857 -271.897898) (xy 409.718478 -271.873291) (xy 409.764494 -271.855839)
			(xy 409.812713 -271.845995) (xy 409.861888 -271.844014) (xy 409.910743 -271.849946) (xy 409.958014 -271.863638)
			(xy 410.002476 -271.884736) (xy 410.042979 -271.912692) (xy 410.078472 -271.946784) (xy 410.108037 -271.986128)
			(xy 410.130908 -272.029705) (xy 410.146492 -272.076386) (xy 410.154387 -272.124963) (xy 410.154882 -272.14957)
			(xy 411.443944 -272.14957) (xy 411.447904 -272.100516) (xy 411.459681 -272.052732) (xy 411.478972 -272.007456)
			(xy 411.505275 -271.96586) (xy 411.53791 -271.929023) (xy 411.576031 -271.897898) (xy 411.618652 -271.873291)
			(xy 411.664668 -271.855839) (xy 411.712887 -271.845995) (xy 411.762062 -271.844014) (xy 411.810917 -271.849946)
			(xy 411.858188 -271.863638) (xy 411.90265 -271.884736) (xy 411.943153 -271.912692) (xy 411.978646 -271.946784)
			(xy 412.008211 -271.986128) (xy 412.031082 -272.029705) (xy 412.046666 -272.076386) (xy 412.054561 -272.124963)
			(xy 412.055056 -272.14957) (xy 413.343864 -272.14957) (xy 413.347824 -272.100516) (xy 413.359601 -272.052732)
			(xy 413.378892 -272.007456) (xy 413.405195 -271.96586) (xy 413.43783 -271.929023) (xy 413.475951 -271.897898)
			(xy 413.518572 -271.873291) (xy 413.564588 -271.855839) (xy 413.612807 -271.845995) (xy 413.661982 -271.844014)
			(xy 413.710837 -271.849946) (xy 413.758108 -271.863638) (xy 413.80257 -271.884736) (xy 413.843073 -271.912692)
			(xy 413.878566 -271.946784) (xy 413.908131 -271.986128) (xy 413.931002 -272.029705) (xy 413.946586 -272.076386)
			(xy 413.954481 -272.124963) (xy 413.954976 -272.14957) (xy 415.243784 -272.14957) (xy 415.247744 -272.100516)
			(xy 415.259521 -272.052732) (xy 415.278812 -272.007456) (xy 415.305115 -271.96586) (xy 415.33775 -271.929023)
			(xy 415.375871 -271.897898) (xy 415.418492 -271.873291) (xy 415.464508 -271.855839) (xy 415.512727 -271.845995)
			(xy 415.561902 -271.844014) (xy 415.610757 -271.849946) (xy 415.658028 -271.863638) (xy 415.70249 -271.884736)
			(xy 415.742993 -271.912692) (xy 415.778486 -271.946784) (xy 415.808051 -271.986128) (xy 415.830922 -272.029705)
			(xy 415.846506 -272.076386) (xy 415.854401 -272.124963) (xy 415.854896 -272.14957) (xy 417.143958 -272.14957)
			(xy 417.147918 -272.100516) (xy 417.159695 -272.052732) (xy 417.178986 -272.007456) (xy 417.205289 -271.96586)
			(xy 417.237924 -271.929023) (xy 417.276045 -271.897898) (xy 417.318666 -271.873291) (xy 417.364682 -271.855839)
			(xy 417.412901 -271.845995) (xy 417.462076 -271.844014) (xy 417.510931 -271.849946) (xy 417.558202 -271.863638)
			(xy 417.602664 -271.884736) (xy 417.643167 -271.912692) (xy 417.67866 -271.946784) (xy 417.708225 -271.986128)
			(xy 417.731096 -272.029705) (xy 417.74668 -272.076386) (xy 417.754575 -272.124963) (xy 417.75507 -272.14957)
			(xy 419.043878 -272.14957) (xy 419.047838 -272.100516) (xy 419.059615 -272.052732) (xy 419.078906 -272.007456)
			(xy 419.105209 -271.96586) (xy 419.137844 -271.929023) (xy 419.175965 -271.897898) (xy 419.218586 -271.873291)
			(xy 419.264602 -271.855839) (xy 419.312821 -271.845995) (xy 419.361996 -271.844014) (xy 419.410851 -271.849946)
			(xy 419.458122 -271.863638) (xy 419.502584 -271.884736) (xy 419.543087 -271.912692) (xy 419.57858 -271.946784)
			(xy 419.608145 -271.986128) (xy 419.631016 -272.029705) (xy 419.6466 -272.076386) (xy 419.654495 -272.124963)
			(xy 419.65499 -272.14957) (xy 420.943798 -272.14957) (xy 420.947758 -272.100516) (xy 420.959535 -272.052732)
			(xy 420.978826 -272.007456) (xy 421.005129 -271.96586) (xy 421.037764 -271.929023) (xy 421.075885 -271.897898)
			(xy 421.118506 -271.873291) (xy 421.164522 -271.855839) (xy 421.212741 -271.845995) (xy 421.261916 -271.844014)
			(xy 421.310771 -271.849946) (xy 421.358042 -271.863638) (xy 421.402504 -271.884736) (xy 421.443007 -271.912692)
			(xy 421.4785 -271.946784) (xy 421.508065 -271.986128) (xy 421.530936 -272.029705) (xy 421.54652 -272.076386)
			(xy 421.554415 -272.124963) (xy 421.55491 -272.14957) (xy 421.554415 -272.174177) (xy 421.54652 -272.222754)
			(xy 421.530936 -272.269435) (xy 421.508065 -272.313012) (xy 421.4785 -272.352356) (xy 421.443007 -272.386448)
			(xy 421.402504 -272.414404) (xy 421.358042 -272.435502) (xy 421.310771 -272.449194) (xy 421.261916 -272.455126)
			(xy 421.212741 -272.453145) (xy 421.164522 -272.443301) (xy 421.118506 -272.425849) (xy 421.075885 -272.401242)
			(xy 421.037764 -272.370117) (xy 421.005129 -272.33328) (xy 420.978826 -272.291684) (xy 420.959535 -272.246408)
			(xy 420.947758 -272.198624) (xy 420.943798 -272.14957) (xy 419.65499 -272.14957) (xy 419.654495 -272.174177)
			(xy 419.6466 -272.222754) (xy 419.631016 -272.269435) (xy 419.608145 -272.313012) (xy 419.57858 -272.352356)
			(xy 419.543087 -272.386448) (xy 419.502584 -272.414404) (xy 419.458122 -272.435502) (xy 419.410851 -272.449194)
			(xy 419.361996 -272.455126) (xy 419.312821 -272.453145) (xy 419.264602 -272.443301) (xy 419.218586 -272.425849)
			(xy 419.175965 -272.401242) (xy 419.137844 -272.370117) (xy 419.105209 -272.33328) (xy 419.078906 -272.291684)
			(xy 419.059615 -272.246408) (xy 419.047838 -272.198624) (xy 419.043878 -272.14957) (xy 417.75507 -272.14957)
			(xy 417.754575 -272.174177) (xy 417.74668 -272.222754) (xy 417.731096 -272.269435) (xy 417.708225 -272.313012)
			(xy 417.67866 -272.352356) (xy 417.643167 -272.386448) (xy 417.602664 -272.414404) (xy 417.558202 -272.435502)
			(xy 417.510931 -272.449194) (xy 417.462076 -272.455126) (xy 417.412901 -272.453145) (xy 417.364682 -272.443301)
			(xy 417.318666 -272.425849) (xy 417.276045 -272.401242) (xy 417.237924 -272.370117) (xy 417.205289 -272.33328)
			(xy 417.178986 -272.291684) (xy 417.159695 -272.246408) (xy 417.147918 -272.198624) (xy 417.143958 -272.14957)
			(xy 415.854896 -272.14957) (xy 415.854401 -272.174177) (xy 415.846506 -272.222754) (xy 415.830922 -272.269435)
			(xy 415.808051 -272.313012) (xy 415.778486 -272.352356) (xy 415.742993 -272.386448) (xy 415.70249 -272.414404)
			(xy 415.658028 -272.435502) (xy 415.610757 -272.449194) (xy 415.561902 -272.455126) (xy 415.512727 -272.453145)
			(xy 415.464508 -272.443301) (xy 415.418492 -272.425849) (xy 415.375871 -272.401242) (xy 415.33775 -272.370117)
			(xy 415.305115 -272.33328) (xy 415.278812 -272.291684) (xy 415.259521 -272.246408) (xy 415.247744 -272.198624)
			(xy 415.243784 -272.14957) (xy 413.954976 -272.14957) (xy 413.954481 -272.174177) (xy 413.946586 -272.222754)
			(xy 413.931002 -272.269435) (xy 413.908131 -272.313012) (xy 413.878566 -272.352356) (xy 413.843073 -272.386448)
			(xy 413.80257 -272.414404) (xy 413.758108 -272.435502) (xy 413.710837 -272.449194) (xy 413.661982 -272.455126)
			(xy 413.612807 -272.453145) (xy 413.564588 -272.443301) (xy 413.518572 -272.425849) (xy 413.475951 -272.401242)
			(xy 413.43783 -272.370117) (xy 413.405195 -272.33328) (xy 413.378892 -272.291684) (xy 413.359601 -272.246408)
			(xy 413.347824 -272.198624) (xy 413.343864 -272.14957) (xy 412.055056 -272.14957) (xy 412.054561 -272.174177)
			(xy 412.046666 -272.222754) (xy 412.031082 -272.269435) (xy 412.008211 -272.313012) (xy 411.978646 -272.352356)
			(xy 411.943153 -272.386448) (xy 411.90265 -272.414404) (xy 411.858188 -272.435502) (xy 411.810917 -272.449194)
			(xy 411.762062 -272.455126) (xy 411.712887 -272.453145) (xy 411.664668 -272.443301) (xy 411.618652 -272.425849)
			(xy 411.576031 -272.401242) (xy 411.53791 -272.370117) (xy 411.505275 -272.33328) (xy 411.478972 -272.291684)
			(xy 411.459681 -272.246408) (xy 411.447904 -272.198624) (xy 411.443944 -272.14957) (xy 410.154882 -272.14957)
			(xy 410.154387 -272.174177) (xy 410.146492 -272.222754) (xy 410.130908 -272.269435) (xy 410.108037 -272.313012)
			(xy 410.078472 -272.352356) (xy 410.042979 -272.386448) (xy 410.002476 -272.414404) (xy 409.958014 -272.435502)
			(xy 409.910743 -272.449194) (xy 409.861888 -272.455126) (xy 409.812713 -272.453145) (xy 409.764494 -272.443301)
			(xy 409.718478 -272.425849) (xy 409.675857 -272.401242) (xy 409.637736 -272.370117) (xy 409.605101 -272.33328)
			(xy 409.578798 -272.291684) (xy 409.559507 -272.246408) (xy 409.54773 -272.198624) (xy 409.54377 -272.14957)
			(xy 408.254957 -272.14957) (xy 408.254467 -272.173923) (xy 408.246572 -272.2225) (xy 408.230988 -272.269181)
			(xy 408.208117 -272.312758) (xy 408.178552 -272.352102) (xy 408.143059 -272.386194) (xy 408.102556 -272.41415)
			(xy 408.058094 -272.435248) (xy 408.010823 -272.44894) (xy 407.961968 -272.454872) (xy 407.912793 -272.452891)
			(xy 407.864574 -272.443047) (xy 407.818558 -272.425595) (xy 407.775937 -272.400988) (xy 407.737816 -272.369863)
			(xy 407.705181 -272.333026) (xy 407.678878 -272.29143) (xy 407.659587 -272.246154) (xy 407.64781 -272.19837)
			(xy 407.64385 -272.149316) (xy 406.355037 -272.149316) (xy 406.355042 -272.14957) (xy 406.354547 -272.174177)
			(xy 406.346652 -272.222754) (xy 406.331068 -272.269435) (xy 406.308197 -272.313012) (xy 406.278632 -272.352356)
			(xy 406.243139 -272.386448) (xy 406.202636 -272.414404) (xy 406.158174 -272.435502) (xy 406.110903 -272.449194)
			(xy 406.062048 -272.455126) (xy 406.012873 -272.453145) (xy 405.964654 -272.443301) (xy 405.918638 -272.425849)
			(xy 405.876017 -272.401242) (xy 405.837896 -272.370117) (xy 405.805261 -272.33328) (xy 405.778958 -272.291684)
			(xy 405.759667 -272.246408) (xy 405.74789 -272.198624) (xy 405.74393 -272.14957) (xy 404.454868 -272.14957)
			(xy 404.454373 -272.174177) (xy 404.446478 -272.222754) (xy 404.430894 -272.269435) (xy 404.408023 -272.313012)
			(xy 404.378458 -272.352356) (xy 404.342965 -272.386448) (xy 404.302462 -272.414404) (xy 404.258 -272.435502)
			(xy 404.210729 -272.449194) (xy 404.161874 -272.455126) (xy 404.112699 -272.453145) (xy 404.06448 -272.443301)
			(xy 404.018464 -272.425849) (xy 403.975843 -272.401242) (xy 403.937722 -272.370117) (xy 403.905087 -272.33328)
			(xy 403.878784 -272.291684) (xy 403.859493 -272.246408) (xy 403.847716 -272.198624) (xy 403.843756 -272.14957)
			(xy 402.554948 -272.14957) (xy 402.554453 -272.174177) (xy 402.546558 -272.222754) (xy 402.530974 -272.269435)
			(xy 402.508103 -272.313012) (xy 402.478538 -272.352356) (xy 402.443045 -272.386448) (xy 402.402542 -272.414404)
			(xy 402.35808 -272.435502) (xy 402.310809 -272.449194) (xy 402.261954 -272.455126) (xy 402.212779 -272.453145)
			(xy 402.16456 -272.443301) (xy 402.118544 -272.425849) (xy 402.075923 -272.401242) (xy 402.037802 -272.370117)
			(xy 402.005167 -272.33328) (xy 401.978864 -272.291684) (xy 401.959573 -272.246408) (xy 401.947796 -272.198624)
			(xy 401.943836 -272.14957) (xy 400.655028 -272.14957) (xy 400.654533 -272.174177) (xy 400.646638 -272.222754)
			(xy 400.631054 -272.269435) (xy 400.608183 -272.313012) (xy 400.578618 -272.352356) (xy 400.543125 -272.386448)
			(xy 400.502622 -272.414404) (xy 400.45816 -272.435502) (xy 400.410889 -272.449194) (xy 400.362034 -272.455126)
			(xy 400.312859 -272.453145) (xy 400.26464 -272.443301) (xy 400.218624 -272.425849) (xy 400.176003 -272.401242)
			(xy 400.137882 -272.370117) (xy 400.105247 -272.33328) (xy 400.078944 -272.291684) (xy 400.059653 -272.246408)
			(xy 400.047876 -272.198624) (xy 400.043916 -272.14957) (xy 398.754854 -272.14957) (xy 398.754359 -272.174177)
			(xy 398.746464 -272.222754) (xy 398.73088 -272.269435) (xy 398.708009 -272.313012) (xy 398.678444 -272.352356)
			(xy 398.642951 -272.386448) (xy 398.602448 -272.414404) (xy 398.557986 -272.435502) (xy 398.510715 -272.449194)
			(xy 398.46186 -272.455126) (xy 398.412685 -272.453145) (xy 398.364466 -272.443301) (xy 398.31845 -272.425849)
			(xy 398.275829 -272.401242) (xy 398.237708 -272.370117) (xy 398.205073 -272.33328) (xy 398.17877 -272.291684)
			(xy 398.159479 -272.246408) (xy 398.147702 -272.198624) (xy 398.143742 -272.14957) (xy 396.854934 -272.14957)
			(xy 396.854439 -272.174177) (xy 396.846544 -272.222754) (xy 396.83096 -272.269435) (xy 396.808089 -272.313012)
			(xy 396.778524 -272.352356) (xy 396.743031 -272.386448) (xy 396.702528 -272.414404) (xy 396.658066 -272.435502)
			(xy 396.610795 -272.449194) (xy 396.56194 -272.455126) (xy 396.512765 -272.453145) (xy 396.464546 -272.443301)
			(xy 396.41853 -272.425849) (xy 396.375909 -272.401242) (xy 396.337788 -272.370117) (xy 396.305153 -272.33328)
			(xy 396.27885 -272.291684) (xy 396.259559 -272.246408) (xy 396.247782 -272.198624) (xy 396.243822 -272.14957)
			(xy 394.955014 -272.14957) (xy 394.954519 -272.174177) (xy 394.946624 -272.222754) (xy 394.93104 -272.269435)
			(xy 394.908169 -272.313012) (xy 394.878604 -272.352356) (xy 394.843111 -272.386448) (xy 394.802608 -272.414404)
			(xy 394.758146 -272.435502) (xy 394.710875 -272.449194) (xy 394.66202 -272.455126) (xy 394.612845 -272.453145)
			(xy 394.564626 -272.443301) (xy 394.51861 -272.425849) (xy 394.475989 -272.401242) (xy 394.437868 -272.370117)
			(xy 394.405233 -272.33328) (xy 394.37893 -272.291684) (xy 394.359639 -272.246408) (xy 394.347862 -272.198624)
			(xy 394.343902 -272.14957) (xy 393.05484 -272.14957) (xy 393.054345 -272.174177) (xy 393.04645 -272.222754)
			(xy 393.030866 -272.269435) (xy 393.007995 -272.313012) (xy 392.97843 -272.352356) (xy 392.942937 -272.386448)
			(xy 392.902434 -272.414404) (xy 392.857972 -272.435502) (xy 392.810701 -272.449194) (xy 392.761846 -272.455126)
			(xy 392.712671 -272.453145) (xy 392.664452 -272.443301) (xy 392.618436 -272.425849) (xy 392.575815 -272.401242)
			(xy 392.537694 -272.370117) (xy 392.505059 -272.33328) (xy 392.478756 -272.291684) (xy 392.459465 -272.246408)
			(xy 392.447688 -272.198624) (xy 392.443728 -272.14957) (xy 383.78638 -272.14957) (xy 383.78638 -272.624804)
			(xy 386.269242 -272.624804) (xy 386.273202 -272.57575) (xy 386.284979 -272.527966) (xy 386.30427 -272.48269)
			(xy 386.330573 -272.441094) (xy 386.363208 -272.404257) (xy 386.401329 -272.373132) (xy 386.44395 -272.348525)
			(xy 386.489966 -272.331073) (xy 386.538185 -272.321229) (xy 386.58736 -272.319248) (xy 386.636215 -272.32518)
			(xy 386.683486 -272.338872) (xy 386.727948 -272.35997) (xy 386.768451 -272.387926) (xy 386.803944 -272.422018)
			(xy 386.833509 -272.461362) (xy 386.85638 -272.504939) (xy 386.871964 -272.55162) (xy 386.879859 -272.600197)
			(xy 386.880354 -272.624804) (xy 387.219202 -272.624804) (xy 387.223162 -272.57575) (xy 387.234939 -272.527966)
			(xy 387.25423 -272.48269) (xy 387.280533 -272.441094) (xy 387.313168 -272.404257) (xy 387.351289 -272.373132)
			(xy 387.39391 -272.348525) (xy 387.439926 -272.331073) (xy 387.488145 -272.321229) (xy 387.53732 -272.319248)
			(xy 387.586175 -272.32518) (xy 387.633446 -272.338872) (xy 387.677908 -272.35997) (xy 387.718411 -272.387926)
			(xy 387.753904 -272.422018) (xy 387.783469 -272.461362) (xy 387.80634 -272.504939) (xy 387.821924 -272.55162)
			(xy 387.829819 -272.600197) (xy 387.830314 -272.624804) (xy 388.169162 -272.624804) (xy 388.173122 -272.57575)
			(xy 388.184899 -272.527966) (xy 388.20419 -272.48269) (xy 388.230493 -272.441094) (xy 388.263128 -272.404257)
			(xy 388.301249 -272.373132) (xy 388.34387 -272.348525) (xy 388.389886 -272.331073) (xy 388.438105 -272.321229)
			(xy 388.48728 -272.319248) (xy 388.536135 -272.32518) (xy 388.583406 -272.338872) (xy 388.627868 -272.35997)
			(xy 388.668371 -272.387926) (xy 388.703864 -272.422018) (xy 388.733429 -272.461362) (xy 388.7563 -272.504939)
			(xy 388.771884 -272.55162) (xy 388.779779 -272.600197) (xy 388.780274 -272.624804) (xy 389.119122 -272.624804)
			(xy 389.123082 -272.57575) (xy 389.134859 -272.527966) (xy 389.15415 -272.48269) (xy 389.180453 -272.441094)
			(xy 389.213088 -272.404257) (xy 389.251209 -272.373132) (xy 389.29383 -272.348525) (xy 389.339846 -272.331073)
			(xy 389.388065 -272.321229) (xy 389.43724 -272.319248) (xy 389.486095 -272.32518) (xy 389.533366 -272.338872)
			(xy 389.577828 -272.35997) (xy 389.618331 -272.387926) (xy 389.653824 -272.422018) (xy 389.683389 -272.461362)
			(xy 389.70626 -272.504939) (xy 389.721844 -272.55162) (xy 389.729739 -272.600197) (xy 389.730234 -272.624804)
			(xy 390.069082 -272.624804) (xy 390.073042 -272.57575) (xy 390.084819 -272.527966) (xy 390.10411 -272.48269)
			(xy 390.130413 -272.441094) (xy 390.163048 -272.404257) (xy 390.201169 -272.373132) (xy 390.24379 -272.348525)
			(xy 390.289806 -272.331073) (xy 390.338025 -272.321229) (xy 390.3872 -272.319248) (xy 390.436055 -272.32518)
			(xy 390.483326 -272.338872) (xy 390.527788 -272.35997) (xy 390.568291 -272.387926) (xy 390.603784 -272.422018)
			(xy 390.633349 -272.461362) (xy 390.65622 -272.504939) (xy 390.671804 -272.55162) (xy 390.679699 -272.600197)
			(xy 390.680194 -272.624804) (xy 391.019042 -272.624804) (xy 391.023002 -272.57575) (xy 391.034779 -272.527966)
			(xy 391.05407 -272.48269) (xy 391.080373 -272.441094) (xy 391.113008 -272.404257) (xy 391.151129 -272.373132)
			(xy 391.19375 -272.348525) (xy 391.239766 -272.331073) (xy 391.287985 -272.321229) (xy 391.33716 -272.319248)
			(xy 391.386015 -272.32518) (xy 391.433286 -272.338872) (xy 391.477748 -272.35997) (xy 391.518251 -272.387926)
			(xy 391.553744 -272.422018) (xy 391.583309 -272.461362) (xy 391.60618 -272.504939) (xy 391.621764 -272.55162)
			(xy 391.629659 -272.600197) (xy 391.630154 -272.624804) (xy 391.629659 -272.649411) (xy 391.621764 -272.697988)
			(xy 391.60618 -272.744669) (xy 391.583309 -272.788246) (xy 391.553744 -272.82759) (xy 391.518251 -272.861682)
			(xy 391.477748 -272.889638) (xy 391.433286 -272.910736) (xy 391.386015 -272.924428) (xy 391.33716 -272.93036)
			(xy 391.287985 -272.928379) (xy 391.239766 -272.918535) (xy 391.19375 -272.901083) (xy 391.151129 -272.876476)
			(xy 391.113008 -272.845351) (xy 391.080373 -272.808514) (xy 391.05407 -272.766918) (xy 391.034779 -272.721642)
			(xy 391.023002 -272.673858) (xy 391.019042 -272.624804) (xy 390.680194 -272.624804) (xy 390.679699 -272.649411)
			(xy 390.671804 -272.697988) (xy 390.65622 -272.744669) (xy 390.633349 -272.788246) (xy 390.603784 -272.82759)
			(xy 390.568291 -272.861682) (xy 390.527788 -272.889638) (xy 390.483326 -272.910736) (xy 390.436055 -272.924428)
			(xy 390.3872 -272.93036) (xy 390.338025 -272.928379) (xy 390.289806 -272.918535) (xy 390.24379 -272.901083)
			(xy 390.201169 -272.876476) (xy 390.163048 -272.845351) (xy 390.130413 -272.808514) (xy 390.10411 -272.766918)
			(xy 390.084819 -272.721642) (xy 390.073042 -272.673858) (xy 390.069082 -272.624804) (xy 389.730234 -272.624804)
			(xy 389.729739 -272.649411) (xy 389.721844 -272.697988) (xy 389.70626 -272.744669) (xy 389.683389 -272.788246)
			(xy 389.653824 -272.82759) (xy 389.618331 -272.861682) (xy 389.577828 -272.889638) (xy 389.533366 -272.910736)
			(xy 389.486095 -272.924428) (xy 389.43724 -272.93036) (xy 389.388065 -272.928379) (xy 389.339846 -272.918535)
			(xy 389.29383 -272.901083) (xy 389.251209 -272.876476) (xy 389.213088 -272.845351) (xy 389.180453 -272.808514)
			(xy 389.15415 -272.766918) (xy 389.134859 -272.721642) (xy 389.123082 -272.673858) (xy 389.119122 -272.624804)
			(xy 388.780274 -272.624804) (xy 388.779779 -272.649411) (xy 388.771884 -272.697988) (xy 388.7563 -272.744669)
			(xy 388.733429 -272.788246) (xy 388.703864 -272.82759) (xy 388.668371 -272.861682) (xy 388.627868 -272.889638)
			(xy 388.583406 -272.910736) (xy 388.536135 -272.924428) (xy 388.48728 -272.93036) (xy 388.438105 -272.928379)
			(xy 388.389886 -272.918535) (xy 388.34387 -272.901083) (xy 388.301249 -272.876476) (xy 388.263128 -272.845351)
			(xy 388.230493 -272.808514) (xy 388.20419 -272.766918) (xy 388.184899 -272.721642) (xy 388.173122 -272.673858)
			(xy 388.169162 -272.624804) (xy 387.830314 -272.624804) (xy 387.829819 -272.649411) (xy 387.821924 -272.697988)
			(xy 387.80634 -272.744669) (xy 387.783469 -272.788246) (xy 387.753904 -272.82759) (xy 387.718411 -272.861682)
			(xy 387.677908 -272.889638) (xy 387.633446 -272.910736) (xy 387.586175 -272.924428) (xy 387.53732 -272.93036)
			(xy 387.488145 -272.928379) (xy 387.439926 -272.918535) (xy 387.39391 -272.901083) (xy 387.351289 -272.876476)
			(xy 387.313168 -272.845351) (xy 387.280533 -272.808514) (xy 387.25423 -272.766918) (xy 387.234939 -272.721642)
			(xy 387.223162 -272.673858) (xy 387.219202 -272.624804) (xy 386.880354 -272.624804) (xy 386.879859 -272.649411)
			(xy 386.871964 -272.697988) (xy 386.85638 -272.744669) (xy 386.833509 -272.788246) (xy 386.803944 -272.82759)
			(xy 386.768451 -272.861682) (xy 386.727948 -272.889638) (xy 386.683486 -272.910736) (xy 386.636215 -272.924428)
			(xy 386.58736 -272.93036) (xy 386.538185 -272.928379) (xy 386.489966 -272.918535) (xy 386.44395 -272.901083)
			(xy 386.401329 -272.876476) (xy 386.363208 -272.845351) (xy 386.330573 -272.808514) (xy 386.30427 -272.766918)
			(xy 386.284979 -272.721642) (xy 386.273202 -272.673858) (xy 386.269242 -272.624804) (xy 383.78638 -272.624804)
			(xy 383.78638 -273.125492) (xy 392.423138 -273.125492) (xy 392.423138 -273.074076) (xy 392.431181 -273.023294)
			(xy 392.447069 -272.974395) (xy 392.470412 -272.928583) (xy 392.500633 -272.886987) (xy 392.536989 -272.850631)
			(xy 392.578585 -272.82041) (xy 392.624397 -272.797067) (xy 392.673296 -272.781179) (xy 392.724078 -272.773136)
			(xy 392.775494 -272.773136) (xy 392.826276 -272.781179) (xy 392.875175 -272.797067) (xy 392.920987 -272.82041)
			(xy 392.962583 -272.850631) (xy 392.998939 -272.886987) (xy 393.02916 -272.928583) (xy 393.052503 -272.974395)
			(xy 393.068391 -273.023294) (xy 393.076434 -273.074076) (xy 393.076938 -273.099784) (xy 393.394196 -273.099784)
			(xy 393.398156 -273.05073) (xy 393.409933 -273.002946) (xy 393.429224 -272.95767) (xy 393.455527 -272.916074)
			(xy 393.488162 -272.879237) (xy 393.526283 -272.848112) (xy 393.568904 -272.823505) (xy 393.61492 -272.806053)
			(xy 393.663139 -272.796209) (xy 393.712314 -272.794228) (xy 393.761169 -272.80016) (xy 393.80844 -272.813852)
			(xy 393.852902 -272.83495) (xy 393.893405 -272.862906) (xy 393.928898 -272.896998) (xy 393.958463 -272.936342)
			(xy 393.981334 -272.979919) (xy 393.996918 -273.0266) (xy 394.004813 -273.075177) (xy 394.005308 -273.099784)
			(xy 394.004813 -273.124391) (xy 394.004634 -273.125492) (xy 394.323312 -273.125492) (xy 394.323312 -273.074076)
			(xy 394.331355 -273.023294) (xy 394.347243 -272.974395) (xy 394.370586 -272.928583) (xy 394.400807 -272.886987)
			(xy 394.437163 -272.850631) (xy 394.478759 -272.82041) (xy 394.524571 -272.797067) (xy 394.57347 -272.781179)
			(xy 394.624252 -272.773136) (xy 394.675668 -272.773136) (xy 394.72645 -272.781179) (xy 394.775349 -272.797067)
			(xy 394.821161 -272.82041) (xy 394.862757 -272.850631) (xy 394.899113 -272.886987) (xy 394.929334 -272.928583)
			(xy 394.952677 -272.974395) (xy 394.968565 -273.023294) (xy 394.976608 -273.074076) (xy 394.977112 -273.099784)
			(xy 395.294116 -273.099784) (xy 395.298076 -273.05073) (xy 395.309853 -273.002946) (xy 395.329144 -272.95767)
			(xy 395.355447 -272.916074) (xy 395.388082 -272.879237) (xy 395.426203 -272.848112) (xy 395.468824 -272.823505)
			(xy 395.51484 -272.806053) (xy 395.563059 -272.796209) (xy 395.612234 -272.794228) (xy 395.661089 -272.80016)
			(xy 395.70836 -272.813852) (xy 395.752822 -272.83495) (xy 395.793325 -272.862906) (xy 395.828818 -272.896998)
			(xy 395.858383 -272.936342) (xy 395.881254 -272.979919) (xy 395.896838 -273.0266) (xy 395.904733 -273.075177)
			(xy 395.905228 -273.099784) (xy 395.904733 -273.124391) (xy 395.904554 -273.125492) (xy 396.223232 -273.125492)
			(xy 396.223232 -273.074076) (xy 396.231275 -273.023294) (xy 396.247163 -272.974395) (xy 396.270506 -272.928583)
			(xy 396.300727 -272.886987) (xy 396.337083 -272.850631) (xy 396.378679 -272.82041) (xy 396.424491 -272.797067)
			(xy 396.47339 -272.781179) (xy 396.524172 -272.773136) (xy 396.575588 -272.773136) (xy 396.62637 -272.781179)
			(xy 396.675269 -272.797067) (xy 396.721081 -272.82041) (xy 396.762677 -272.850631) (xy 396.799033 -272.886987)
			(xy 396.829254 -272.928583) (xy 396.852597 -272.974395) (xy 396.868485 -273.023294) (xy 396.876528 -273.074076)
			(xy 396.877032 -273.099784) (xy 397.194036 -273.099784) (xy 397.197996 -273.05073) (xy 397.209773 -273.002946)
			(xy 397.229064 -272.95767) (xy 397.255367 -272.916074) (xy 397.288002 -272.879237) (xy 397.326123 -272.848112)
			(xy 397.368744 -272.823505) (xy 397.41476 -272.806053) (xy 397.462979 -272.796209) (xy 397.512154 -272.794228)
			(xy 397.561009 -272.80016) (xy 397.60828 -272.813852) (xy 397.652742 -272.83495) (xy 397.693245 -272.862906)
			(xy 397.728738 -272.896998) (xy 397.758303 -272.936342) (xy 397.781174 -272.979919) (xy 397.796758 -273.0266)
			(xy 397.804653 -273.075177) (xy 397.805148 -273.099784) (xy 397.804653 -273.124391) (xy 397.804474 -273.125492)
			(xy 398.123152 -273.125492) (xy 398.123152 -273.074076) (xy 398.131195 -273.023294) (xy 398.147083 -272.974395)
			(xy 398.170426 -272.928583) (xy 398.200647 -272.886987) (xy 398.237003 -272.850631) (xy 398.278599 -272.82041)
			(xy 398.324411 -272.797067) (xy 398.37331 -272.781179) (xy 398.424092 -272.773136) (xy 398.475508 -272.773136)
			(xy 398.52629 -272.781179) (xy 398.575189 -272.797067) (xy 398.621001 -272.82041) (xy 398.662597 -272.850631)
			(xy 398.698953 -272.886987) (xy 398.729174 -272.928583) (xy 398.752517 -272.974395) (xy 398.768405 -273.023294)
			(xy 398.776448 -273.074076) (xy 398.776952 -273.099784) (xy 399.09421 -273.099784) (xy 399.09817 -273.05073)
			(xy 399.109947 -273.002946) (xy 399.129238 -272.95767) (xy 399.155541 -272.916074) (xy 399.188176 -272.879237)
			(xy 399.226297 -272.848112) (xy 399.268918 -272.823505) (xy 399.314934 -272.806053) (xy 399.363153 -272.796209)
			(xy 399.412328 -272.794228) (xy 399.461183 -272.80016) (xy 399.508454 -272.813852) (xy 399.552916 -272.83495)
			(xy 399.593419 -272.862906) (xy 399.628912 -272.896998) (xy 399.658477 -272.936342) (xy 399.681348 -272.979919)
			(xy 399.696932 -273.0266) (xy 399.704827 -273.075177) (xy 399.705322 -273.099784) (xy 399.704827 -273.124391)
			(xy 399.704648 -273.125492) (xy 400.023326 -273.125492) (xy 400.023326 -273.074076) (xy 400.031369 -273.023294)
			(xy 400.047257 -272.974395) (xy 400.0706 -272.928583) (xy 400.100821 -272.886987) (xy 400.137177 -272.850631)
			(xy 400.178773 -272.82041) (xy 400.224585 -272.797067) (xy 400.273484 -272.781179) (xy 400.324266 -272.773136)
			(xy 400.375682 -272.773136) (xy 400.426464 -272.781179) (xy 400.475363 -272.797067) (xy 400.521175 -272.82041)
			(xy 400.562771 -272.850631) (xy 400.599127 -272.886987) (xy 400.629348 -272.928583) (xy 400.652691 -272.974395)
			(xy 400.668579 -273.023294) (xy 400.676622 -273.074076) (xy 400.677126 -273.099784) (xy 400.99413 -273.099784)
			(xy 400.99809 -273.05073) (xy 401.009867 -273.002946) (xy 401.029158 -272.95767) (xy 401.055461 -272.916074)
			(xy 401.088096 -272.879237) (xy 401.126217 -272.848112) (xy 401.168838 -272.823505) (xy 401.214854 -272.806053)
			(xy 401.263073 -272.796209) (xy 401.312248 -272.794228) (xy 401.361103 -272.80016) (xy 401.408374 -272.813852)
			(xy 401.452836 -272.83495) (xy 401.493339 -272.862906) (xy 401.528832 -272.896998) (xy 401.558397 -272.936342)
			(xy 401.581268 -272.979919) (xy 401.596852 -273.0266) (xy 401.604747 -273.075177) (xy 401.605242 -273.099784)
			(xy 401.604747 -273.124391) (xy 401.604568 -273.125492) (xy 401.923246 -273.125492) (xy 401.923246 -273.074076)
			(xy 401.931289 -273.023294) (xy 401.947177 -272.974395) (xy 401.97052 -272.928583) (xy 402.000741 -272.886987)
			(xy 402.037097 -272.850631) (xy 402.078693 -272.82041) (xy 402.124505 -272.797067) (xy 402.173404 -272.781179)
			(xy 402.224186 -272.773136) (xy 402.275602 -272.773136) (xy 402.326384 -272.781179) (xy 402.375283 -272.797067)
			(xy 402.421095 -272.82041) (xy 402.462691 -272.850631) (xy 402.499047 -272.886987) (xy 402.529268 -272.928583)
			(xy 402.552611 -272.974395) (xy 402.568499 -273.023294) (xy 402.576542 -273.074076) (xy 402.577046 -273.099784)
			(xy 402.89405 -273.099784) (xy 402.89801 -273.05073) (xy 402.909787 -273.002946) (xy 402.929078 -272.95767)
			(xy 402.955381 -272.916074) (xy 402.988016 -272.879237) (xy 403.026137 -272.848112) (xy 403.068758 -272.823505)
			(xy 403.114774 -272.806053) (xy 403.162993 -272.796209) (xy 403.212168 -272.794228) (xy 403.261023 -272.80016)
			(xy 403.308294 -272.813852) (xy 403.352756 -272.83495) (xy 403.393259 -272.862906) (xy 403.428752 -272.896998)
			(xy 403.458317 -272.936342) (xy 403.481188 -272.979919) (xy 403.496772 -273.0266) (xy 403.504667 -273.075177)
			(xy 403.505162 -273.099784) (xy 403.504667 -273.124391) (xy 403.504488 -273.125492) (xy 403.823166 -273.125492)
			(xy 403.823166 -273.074076) (xy 403.831209 -273.023294) (xy 403.847097 -272.974395) (xy 403.87044 -272.928583)
			(xy 403.900661 -272.886987) (xy 403.937017 -272.850631) (xy 403.978613 -272.82041) (xy 404.024425 -272.797067)
			(xy 404.073324 -272.781179) (xy 404.124106 -272.773136) (xy 404.175522 -272.773136) (xy 404.226304 -272.781179)
			(xy 404.275203 -272.797067) (xy 404.321015 -272.82041) (xy 404.362611 -272.850631) (xy 404.398967 -272.886987)
			(xy 404.429188 -272.928583) (xy 404.452531 -272.974395) (xy 404.468419 -273.023294) (xy 404.476462 -273.074076)
			(xy 404.476966 -273.099784) (xy 404.794224 -273.099784) (xy 404.798184 -273.05073) (xy 404.809961 -273.002946)
			(xy 404.829252 -272.95767) (xy 404.855555 -272.916074) (xy 404.88819 -272.879237) (xy 404.926311 -272.848112)
			(xy 404.968932 -272.823505) (xy 405.014948 -272.806053) (xy 405.063167 -272.796209) (xy 405.112342 -272.794228)
			(xy 405.161197 -272.80016) (xy 405.208468 -272.813852) (xy 405.25293 -272.83495) (xy 405.293433 -272.862906)
			(xy 405.328926 -272.896998) (xy 405.358491 -272.936342) (xy 405.381362 -272.979919) (xy 405.396946 -273.0266)
			(xy 405.404841 -273.075177) (xy 405.405336 -273.099784) (xy 405.404841 -273.124391) (xy 405.404662 -273.125492)
			(xy 405.72334 -273.125492) (xy 405.72334 -273.074076) (xy 405.731383 -273.023294) (xy 405.747271 -272.974395)
			(xy 405.770614 -272.928583) (xy 405.800835 -272.886987) (xy 405.837191 -272.850631) (xy 405.878787 -272.82041)
			(xy 405.924599 -272.797067) (xy 405.973498 -272.781179) (xy 406.02428 -272.773136) (xy 406.075696 -272.773136)
			(xy 406.126478 -272.781179) (xy 406.175377 -272.797067) (xy 406.221189 -272.82041) (xy 406.262785 -272.850631)
			(xy 406.299141 -272.886987) (xy 406.329362 -272.928583) (xy 406.352705 -272.974395) (xy 406.368593 -273.023294)
			(xy 406.376636 -273.074076) (xy 406.37714 -273.099784) (xy 406.694144 -273.099784) (xy 406.698104 -273.05073)
			(xy 406.709881 -273.002946) (xy 406.729172 -272.95767) (xy 406.755475 -272.916074) (xy 406.78811 -272.879237)
			(xy 406.826231 -272.848112) (xy 406.868852 -272.823505) (xy 406.914868 -272.806053) (xy 406.963087 -272.796209)
			(xy 407.012262 -272.794228) (xy 407.061117 -272.80016) (xy 407.108388 -272.813852) (xy 407.15285 -272.83495)
			(xy 407.193353 -272.862906) (xy 407.228846 -272.896998) (xy 407.258411 -272.936342) (xy 407.281282 -272.979919)
			(xy 407.296866 -273.0266) (xy 407.304761 -273.075177) (xy 407.305256 -273.099784) (xy 407.304761 -273.124391)
			(xy 407.304623 -273.125238) (xy 407.623006 -273.125238) (xy 407.623006 -273.073822) (xy 407.631049 -273.02304)
			(xy 407.646937 -272.974141) (xy 407.67028 -272.928329) (xy 407.700501 -272.886733) (xy 407.736857 -272.850377)
			(xy 407.778453 -272.820156) (xy 407.824265 -272.796813) (xy 407.873164 -272.780925) (xy 407.923946 -272.772882)
			(xy 407.975362 -272.772882) (xy 408.026144 -272.780925) (xy 408.075043 -272.796813) (xy 408.120855 -272.820156)
			(xy 408.162451 -272.850377) (xy 408.198807 -272.886733) (xy 408.229028 -272.928329) (xy 408.252371 -272.974141)
			(xy 408.268259 -273.02304) (xy 408.276302 -273.073822) (xy 408.276806 -273.09953) (xy 408.276801 -273.099784)
			(xy 408.594064 -273.099784) (xy 408.598024 -273.05073) (xy 408.609801 -273.002946) (xy 408.629092 -272.95767)
			(xy 408.655395 -272.916074) (xy 408.68803 -272.879237) (xy 408.726151 -272.848112) (xy 408.768772 -272.823505)
			(xy 408.814788 -272.806053) (xy 408.863007 -272.796209) (xy 408.912182 -272.794228) (xy 408.961037 -272.80016)
			(xy 409.008308 -272.813852) (xy 409.05277 -272.83495) (xy 409.093273 -272.862906) (xy 409.128766 -272.896998)
			(xy 409.158331 -272.936342) (xy 409.181202 -272.979919) (xy 409.196786 -273.0266) (xy 409.204681 -273.075177)
			(xy 409.205176 -273.099784) (xy 409.204681 -273.124391) (xy 409.204502 -273.125492) (xy 409.522926 -273.125492)
			(xy 409.522926 -273.074076) (xy 409.530969 -273.023294) (xy 409.546857 -272.974395) (xy 409.5702 -272.928583)
			(xy 409.600421 -272.886987) (xy 409.636777 -272.850631) (xy 409.678373 -272.82041) (xy 409.724185 -272.797067)
			(xy 409.773084 -272.781179) (xy 409.823866 -272.773136) (xy 409.875282 -272.773136) (xy 409.926064 -272.781179)
			(xy 409.974963 -272.797067) (xy 410.020775 -272.82041) (xy 410.062371 -272.850631) (xy 410.098727 -272.886987)
			(xy 410.128948 -272.928583) (xy 410.152291 -272.974395) (xy 410.168179 -273.023294) (xy 410.176222 -273.074076)
			(xy 410.176726 -273.099784) (xy 410.493984 -273.099784) (xy 410.497944 -273.05073) (xy 410.509721 -273.002946)
			(xy 410.529012 -272.95767) (xy 410.555315 -272.916074) (xy 410.58795 -272.879237) (xy 410.626071 -272.848112)
			(xy 410.668692 -272.823505) (xy 410.714708 -272.806053) (xy 410.762927 -272.796209) (xy 410.812102 -272.794228)
			(xy 410.860957 -272.80016) (xy 410.908228 -272.813852) (xy 410.95269 -272.83495) (xy 410.993193 -272.862906)
			(xy 411.028686 -272.896998) (xy 411.058251 -272.936342) (xy 411.081122 -272.979919) (xy 411.096706 -273.0266)
			(xy 411.104601 -273.075177) (xy 411.105096 -273.099784) (xy 411.104601 -273.124391) (xy 411.104422 -273.125492)
			(xy 411.4231 -273.125492) (xy 411.4231 -273.074076) (xy 411.431143 -273.023294) (xy 411.447031 -272.974395)
			(xy 411.470374 -272.928583) (xy 411.500595 -272.886987) (xy 411.536951 -272.850631) (xy 411.578547 -272.82041)
			(xy 411.624359 -272.797067) (xy 411.673258 -272.781179) (xy 411.72404 -272.773136) (xy 411.775456 -272.773136)
			(xy 411.826238 -272.781179) (xy 411.875137 -272.797067) (xy 411.920949 -272.82041) (xy 411.962545 -272.850631)
			(xy 411.998901 -272.886987) (xy 412.029122 -272.928583) (xy 412.052465 -272.974395) (xy 412.068353 -273.023294)
			(xy 412.076396 -273.074076) (xy 412.0769 -273.099784) (xy 412.394158 -273.099784) (xy 412.398118 -273.05073)
			(xy 412.409895 -273.002946) (xy 412.429186 -272.95767) (xy 412.455489 -272.916074) (xy 412.488124 -272.879237)
			(xy 412.526245 -272.848112) (xy 412.568866 -272.823505) (xy 412.614882 -272.806053) (xy 412.663101 -272.796209)
			(xy 412.712276 -272.794228) (xy 412.761131 -272.80016) (xy 412.808402 -272.813852) (xy 412.852864 -272.83495)
			(xy 412.893367 -272.862906) (xy 412.92886 -272.896998) (xy 412.958425 -272.936342) (xy 412.981296 -272.979919)
			(xy 412.99688 -273.0266) (xy 413.004775 -273.075177) (xy 413.00527 -273.099784) (xy 413.004775 -273.124391)
			(xy 413.004596 -273.125492) (xy 413.32302 -273.125492) (xy 413.32302 -273.074076) (xy 413.331063 -273.023294)
			(xy 413.346951 -272.974395) (xy 413.370294 -272.928583) (xy 413.400515 -272.886987) (xy 413.436871 -272.850631)
			(xy 413.478467 -272.82041) (xy 413.524279 -272.797067) (xy 413.573178 -272.781179) (xy 413.62396 -272.773136)
			(xy 413.675376 -272.773136) (xy 413.726158 -272.781179) (xy 413.775057 -272.797067) (xy 413.820869 -272.82041)
			(xy 413.862465 -272.850631) (xy 413.898821 -272.886987) (xy 413.929042 -272.928583) (xy 413.952385 -272.974395)
			(xy 413.968273 -273.023294) (xy 413.976316 -273.074076) (xy 413.97682 -273.099784) (xy 414.294078 -273.099784)
			(xy 414.298038 -273.05073) (xy 414.309815 -273.002946) (xy 414.329106 -272.95767) (xy 414.355409 -272.916074)
			(xy 414.388044 -272.879237) (xy 414.426165 -272.848112) (xy 414.468786 -272.823505) (xy 414.514802 -272.806053)
			(xy 414.563021 -272.796209) (xy 414.612196 -272.794228) (xy 414.661051 -272.80016) (xy 414.708322 -272.813852)
			(xy 414.752784 -272.83495) (xy 414.793287 -272.862906) (xy 414.82878 -272.896998) (xy 414.858345 -272.936342)
			(xy 414.881216 -272.979919) (xy 414.8968 -273.0266) (xy 414.904695 -273.075177) (xy 414.90519 -273.099784)
			(xy 414.904695 -273.124391) (xy 414.904516 -273.125492) (xy 415.22294 -273.125492) (xy 415.22294 -273.074076)
			(xy 415.230983 -273.023294) (xy 415.246871 -272.974395) (xy 415.270214 -272.928583) (xy 415.300435 -272.886987)
			(xy 415.336791 -272.850631) (xy 415.378387 -272.82041) (xy 415.424199 -272.797067) (xy 415.473098 -272.781179)
			(xy 415.52388 -272.773136) (xy 415.575296 -272.773136) (xy 415.626078 -272.781179) (xy 415.674977 -272.797067)
			(xy 415.720789 -272.82041) (xy 415.762385 -272.850631) (xy 415.798741 -272.886987) (xy 415.828962 -272.928583)
			(xy 415.852305 -272.974395) (xy 415.868193 -273.023294) (xy 415.876236 -273.074076) (xy 415.87674 -273.099784)
			(xy 416.193998 -273.099784) (xy 416.197958 -273.05073) (xy 416.209735 -273.002946) (xy 416.229026 -272.95767)
			(xy 416.255329 -272.916074) (xy 416.287964 -272.879237) (xy 416.326085 -272.848112) (xy 416.368706 -272.823505)
			(xy 416.414722 -272.806053) (xy 416.462941 -272.796209) (xy 416.512116 -272.794228) (xy 416.560971 -272.80016)
			(xy 416.608242 -272.813852) (xy 416.652704 -272.83495) (xy 416.693207 -272.862906) (xy 416.7287 -272.896998)
			(xy 416.758265 -272.936342) (xy 416.781136 -272.979919) (xy 416.79672 -273.0266) (xy 416.804615 -273.075177)
			(xy 416.80511 -273.099784) (xy 416.804615 -273.124391) (xy 416.804436 -273.125492) (xy 417.123114 -273.125492)
			(xy 417.123114 -273.074076) (xy 417.131157 -273.023294) (xy 417.147045 -272.974395) (xy 417.170388 -272.928583)
			(xy 417.200609 -272.886987) (xy 417.236965 -272.850631) (xy 417.278561 -272.82041) (xy 417.324373 -272.797067)
			(xy 417.373272 -272.781179) (xy 417.424054 -272.773136) (xy 417.47547 -272.773136) (xy 417.526252 -272.781179)
			(xy 417.575151 -272.797067) (xy 417.620963 -272.82041) (xy 417.662559 -272.850631) (xy 417.698915 -272.886987)
			(xy 417.729136 -272.928583) (xy 417.752479 -272.974395) (xy 417.768367 -273.023294) (xy 417.77641 -273.074076)
			(xy 417.776914 -273.099784) (xy 418.094172 -273.099784) (xy 418.098132 -273.05073) (xy 418.109909 -273.002946)
			(xy 418.1292 -272.95767) (xy 418.155503 -272.916074) (xy 418.188138 -272.879237) (xy 418.226259 -272.848112)
			(xy 418.26888 -272.823505) (xy 418.314896 -272.806053) (xy 418.363115 -272.796209) (xy 418.41229 -272.794228)
			(xy 418.461145 -272.80016) (xy 418.508416 -272.813852) (xy 418.552878 -272.83495) (xy 418.593381 -272.862906)
			(xy 418.628874 -272.896998) (xy 418.658439 -272.936342) (xy 418.68131 -272.979919) (xy 418.696894 -273.0266)
			(xy 418.704789 -273.075177) (xy 418.705284 -273.099784) (xy 418.704789 -273.124391) (xy 418.70461 -273.125492)
			(xy 419.023034 -273.125492) (xy 419.023034 -273.074076) (xy 419.031077 -273.023294) (xy 419.046965 -272.974395)
			(xy 419.070308 -272.928583) (xy 419.100529 -272.886987) (xy 419.136885 -272.850631) (xy 419.178481 -272.82041)
			(xy 419.224293 -272.797067) (xy 419.273192 -272.781179) (xy 419.323974 -272.773136) (xy 419.37539 -272.773136)
			(xy 419.426172 -272.781179) (xy 419.475071 -272.797067) (xy 419.520883 -272.82041) (xy 419.562479 -272.850631)
			(xy 419.598835 -272.886987) (xy 419.629056 -272.928583) (xy 419.652399 -272.974395) (xy 419.668287 -273.023294)
			(xy 419.67633 -273.074076) (xy 419.676834 -273.099784) (xy 419.994092 -273.099784) (xy 419.998052 -273.05073)
			(xy 420.009829 -273.002946) (xy 420.02912 -272.95767) (xy 420.055423 -272.916074) (xy 420.088058 -272.879237)
			(xy 420.126179 -272.848112) (xy 420.1688 -272.823505) (xy 420.214816 -272.806053) (xy 420.263035 -272.796209)
			(xy 420.31221 -272.794228) (xy 420.361065 -272.80016) (xy 420.408336 -272.813852) (xy 420.452798 -272.83495)
			(xy 420.493301 -272.862906) (xy 420.528794 -272.896998) (xy 420.558359 -272.936342) (xy 420.58123 -272.979919)
			(xy 420.596814 -273.0266) (xy 420.604709 -273.075177) (xy 420.605204 -273.099784) (xy 420.604709 -273.124391)
			(xy 420.60453 -273.125492) (xy 420.922954 -273.125492) (xy 420.922954 -273.074076) (xy 420.930997 -273.023294)
			(xy 420.946885 -272.974395) (xy 420.970228 -272.928583) (xy 421.000449 -272.886987) (xy 421.036805 -272.850631)
			(xy 421.078401 -272.82041) (xy 421.124213 -272.797067) (xy 421.173112 -272.781179) (xy 421.223894 -272.773136)
			(xy 421.27531 -272.773136) (xy 421.326092 -272.781179) (xy 421.374991 -272.797067) (xy 421.420803 -272.82041)
			(xy 421.462399 -272.850631) (xy 421.498755 -272.886987) (xy 421.528976 -272.928583) (xy 421.552319 -272.974395)
			(xy 421.568207 -273.023294) (xy 421.57625 -273.074076) (xy 421.576754 -273.099784) (xy 421.57625 -273.125492)
			(xy 421.568207 -273.176274) (xy 421.552319 -273.225173) (xy 421.528976 -273.270985) (xy 421.498755 -273.312581)
			(xy 421.462399 -273.348937) (xy 421.420803 -273.379158) (xy 421.374991 -273.402501) (xy 421.326092 -273.418389)
			(xy 421.27531 -273.426432) (xy 421.223894 -273.426432) (xy 421.173112 -273.418389) (xy 421.124213 -273.402501)
			(xy 421.078401 -273.379158) (xy 421.036805 -273.348937) (xy 421.000449 -273.312581) (xy 420.970228 -273.270985)
			(xy 420.946885 -273.225173) (xy 420.930997 -273.176274) (xy 420.922954 -273.125492) (xy 420.60453 -273.125492)
			(xy 420.596814 -273.172968) (xy 420.58123 -273.219649) (xy 420.558359 -273.263226) (xy 420.528794 -273.30257)
			(xy 420.493301 -273.336662) (xy 420.452798 -273.364618) (xy 420.408336 -273.385716) (xy 420.361065 -273.399408)
			(xy 420.31221 -273.40534) (xy 420.263035 -273.403359) (xy 420.214816 -273.393515) (xy 420.1688 -273.376063)
			(xy 420.126179 -273.351456) (xy 420.088058 -273.320331) (xy 420.055423 -273.283494) (xy 420.02912 -273.241898)
			(xy 420.009829 -273.196622) (xy 419.998052 -273.148838) (xy 419.994092 -273.099784) (xy 419.676834 -273.099784)
			(xy 419.67633 -273.125492) (xy 419.668287 -273.176274) (xy 419.652399 -273.225173) (xy 419.629056 -273.270985)
			(xy 419.598835 -273.312581) (xy 419.562479 -273.348937) (xy 419.520883 -273.379158) (xy 419.475071 -273.402501)
			(xy 419.426172 -273.418389) (xy 419.37539 -273.426432) (xy 419.323974 -273.426432) (xy 419.273192 -273.418389)
			(xy 419.224293 -273.402501) (xy 419.178481 -273.379158) (xy 419.136885 -273.348937) (xy 419.100529 -273.312581)
			(xy 419.070308 -273.270985) (xy 419.046965 -273.225173) (xy 419.031077 -273.176274) (xy 419.023034 -273.125492)
			(xy 418.70461 -273.125492) (xy 418.696894 -273.172968) (xy 418.68131 -273.219649) (xy 418.658439 -273.263226)
			(xy 418.628874 -273.30257) (xy 418.593381 -273.336662) (xy 418.552878 -273.364618) (xy 418.508416 -273.385716)
			(xy 418.461145 -273.399408) (xy 418.41229 -273.40534) (xy 418.363115 -273.403359) (xy 418.314896 -273.393515)
			(xy 418.26888 -273.376063) (xy 418.226259 -273.351456) (xy 418.188138 -273.320331) (xy 418.155503 -273.283494)
			(xy 418.1292 -273.241898) (xy 418.109909 -273.196622) (xy 418.098132 -273.148838) (xy 418.094172 -273.099784)
			(xy 417.776914 -273.099784) (xy 417.77641 -273.125492) (xy 417.768367 -273.176274) (xy 417.752479 -273.225173)
			(xy 417.729136 -273.270985) (xy 417.698915 -273.312581) (xy 417.662559 -273.348937) (xy 417.620963 -273.379158)
			(xy 417.575151 -273.402501) (xy 417.526252 -273.418389) (xy 417.47547 -273.426432) (xy 417.424054 -273.426432)
			(xy 417.373272 -273.418389) (xy 417.324373 -273.402501) (xy 417.278561 -273.379158) (xy 417.236965 -273.348937)
			(xy 417.200609 -273.312581) (xy 417.170388 -273.270985) (xy 417.147045 -273.225173) (xy 417.131157 -273.176274)
			(xy 417.123114 -273.125492) (xy 416.804436 -273.125492) (xy 416.79672 -273.172968) (xy 416.781136 -273.219649)
			(xy 416.758265 -273.263226) (xy 416.7287 -273.30257) (xy 416.693207 -273.336662) (xy 416.652704 -273.364618)
			(xy 416.608242 -273.385716) (xy 416.560971 -273.399408) (xy 416.512116 -273.40534) (xy 416.462941 -273.403359)
			(xy 416.414722 -273.393515) (xy 416.368706 -273.376063) (xy 416.326085 -273.351456) (xy 416.287964 -273.320331)
			(xy 416.255329 -273.283494) (xy 416.229026 -273.241898) (xy 416.209735 -273.196622) (xy 416.197958 -273.148838)
			(xy 416.193998 -273.099784) (xy 415.87674 -273.099784) (xy 415.876236 -273.125492) (xy 415.868193 -273.176274)
			(xy 415.852305 -273.225173) (xy 415.828962 -273.270985) (xy 415.798741 -273.312581) (xy 415.762385 -273.348937)
			(xy 415.720789 -273.379158) (xy 415.674977 -273.402501) (xy 415.626078 -273.418389) (xy 415.575296 -273.426432)
			(xy 415.52388 -273.426432) (xy 415.473098 -273.418389) (xy 415.424199 -273.402501) (xy 415.378387 -273.379158)
			(xy 415.336791 -273.348937) (xy 415.300435 -273.312581) (xy 415.270214 -273.270985) (xy 415.246871 -273.225173)
			(xy 415.230983 -273.176274) (xy 415.22294 -273.125492) (xy 414.904516 -273.125492) (xy 414.8968 -273.172968)
			(xy 414.881216 -273.219649) (xy 414.858345 -273.263226) (xy 414.82878 -273.30257) (xy 414.793287 -273.336662)
			(xy 414.752784 -273.364618) (xy 414.708322 -273.385716) (xy 414.661051 -273.399408) (xy 414.612196 -273.40534)
			(xy 414.563021 -273.403359) (xy 414.514802 -273.393515) (xy 414.468786 -273.376063) (xy 414.426165 -273.351456)
			(xy 414.388044 -273.320331) (xy 414.355409 -273.283494) (xy 414.329106 -273.241898) (xy 414.309815 -273.196622)
			(xy 414.298038 -273.148838) (xy 414.294078 -273.099784) (xy 413.97682 -273.099784) (xy 413.976316 -273.125492)
			(xy 413.968273 -273.176274) (xy 413.952385 -273.225173) (xy 413.929042 -273.270985) (xy 413.898821 -273.312581)
			(xy 413.862465 -273.348937) (xy 413.820869 -273.379158) (xy 413.775057 -273.402501) (xy 413.726158 -273.418389)
			(xy 413.675376 -273.426432) (xy 413.62396 -273.426432) (xy 413.573178 -273.418389) (xy 413.524279 -273.402501)
			(xy 413.478467 -273.379158) (xy 413.436871 -273.348937) (xy 413.400515 -273.312581) (xy 413.370294 -273.270985)
			(xy 413.346951 -273.225173) (xy 413.331063 -273.176274) (xy 413.32302 -273.125492) (xy 413.004596 -273.125492)
			(xy 412.99688 -273.172968) (xy 412.981296 -273.219649) (xy 412.958425 -273.263226) (xy 412.92886 -273.30257)
			(xy 412.893367 -273.336662) (xy 412.852864 -273.364618) (xy 412.808402 -273.385716) (xy 412.761131 -273.399408)
			(xy 412.712276 -273.40534) (xy 412.663101 -273.403359) (xy 412.614882 -273.393515) (xy 412.568866 -273.376063)
			(xy 412.526245 -273.351456) (xy 412.488124 -273.320331) (xy 412.455489 -273.283494) (xy 412.429186 -273.241898)
			(xy 412.409895 -273.196622) (xy 412.398118 -273.148838) (xy 412.394158 -273.099784) (xy 412.0769 -273.099784)
			(xy 412.076396 -273.125492) (xy 412.068353 -273.176274) (xy 412.052465 -273.225173) (xy 412.029122 -273.270985)
			(xy 411.998901 -273.312581) (xy 411.962545 -273.348937) (xy 411.920949 -273.379158) (xy 411.875137 -273.402501)
			(xy 411.826238 -273.418389) (xy 411.775456 -273.426432) (xy 411.72404 -273.426432) (xy 411.673258 -273.418389)
			(xy 411.624359 -273.402501) (xy 411.578547 -273.379158) (xy 411.536951 -273.348937) (xy 411.500595 -273.312581)
			(xy 411.470374 -273.270985) (xy 411.447031 -273.225173) (xy 411.431143 -273.176274) (xy 411.4231 -273.125492)
			(xy 411.104422 -273.125492) (xy 411.096706 -273.172968) (xy 411.081122 -273.219649) (xy 411.058251 -273.263226)
			(xy 411.028686 -273.30257) (xy 410.993193 -273.336662) (xy 410.95269 -273.364618) (xy 410.908228 -273.385716)
			(xy 410.860957 -273.399408) (xy 410.812102 -273.40534) (xy 410.762927 -273.403359) (xy 410.714708 -273.393515)
			(xy 410.668692 -273.376063) (xy 410.626071 -273.351456) (xy 410.58795 -273.320331) (xy 410.555315 -273.283494)
			(xy 410.529012 -273.241898) (xy 410.509721 -273.196622) (xy 410.497944 -273.148838) (xy 410.493984 -273.099784)
			(xy 410.176726 -273.099784) (xy 410.176222 -273.125492) (xy 410.168179 -273.176274) (xy 410.152291 -273.225173)
			(xy 410.128948 -273.270985) (xy 410.098727 -273.312581) (xy 410.062371 -273.348937) (xy 410.020775 -273.379158)
			(xy 409.974963 -273.402501) (xy 409.926064 -273.418389) (xy 409.875282 -273.426432) (xy 409.823866 -273.426432)
			(xy 409.773084 -273.418389) (xy 409.724185 -273.402501) (xy 409.678373 -273.379158) (xy 409.636777 -273.348937)
			(xy 409.600421 -273.312581) (xy 409.5702 -273.270985) (xy 409.546857 -273.225173) (xy 409.530969 -273.176274)
			(xy 409.522926 -273.125492) (xy 409.204502 -273.125492) (xy 409.196786 -273.172968) (xy 409.181202 -273.219649)
			(xy 409.158331 -273.263226) (xy 409.128766 -273.30257) (xy 409.093273 -273.336662) (xy 409.05277 -273.364618)
			(xy 409.008308 -273.385716) (xy 408.961037 -273.399408) (xy 408.912182 -273.40534) (xy 408.863007 -273.403359)
			(xy 408.814788 -273.393515) (xy 408.768772 -273.376063) (xy 408.726151 -273.351456) (xy 408.68803 -273.320331)
			(xy 408.655395 -273.283494) (xy 408.629092 -273.241898) (xy 408.609801 -273.196622) (xy 408.598024 -273.148838)
			(xy 408.594064 -273.099784) (xy 408.276801 -273.099784) (xy 408.276302 -273.125238) (xy 408.268259 -273.17602)
			(xy 408.252371 -273.224919) (xy 408.229028 -273.270731) (xy 408.198807 -273.312327) (xy 408.162451 -273.348683)
			(xy 408.120855 -273.378904) (xy 408.075043 -273.402247) (xy 408.026144 -273.418135) (xy 407.975362 -273.426178)
			(xy 407.923946 -273.426178) (xy 407.873164 -273.418135) (xy 407.824265 -273.402247) (xy 407.778453 -273.378904)
			(xy 407.736857 -273.348683) (xy 407.700501 -273.312327) (xy 407.67028 -273.270731) (xy 407.646937 -273.224919)
			(xy 407.631049 -273.17602) (xy 407.623006 -273.125238) (xy 407.304623 -273.125238) (xy 407.296866 -273.172968)
			(xy 407.281282 -273.219649) (xy 407.258411 -273.263226) (xy 407.228846 -273.30257) (xy 407.193353 -273.336662)
			(xy 407.15285 -273.364618) (xy 407.108388 -273.385716) (xy 407.061117 -273.399408) (xy 407.012262 -273.40534)
			(xy 406.963087 -273.403359) (xy 406.914868 -273.393515) (xy 406.868852 -273.376063) (xy 406.826231 -273.351456)
			(xy 406.78811 -273.320331) (xy 406.755475 -273.283494) (xy 406.729172 -273.241898) (xy 406.709881 -273.196622)
			(xy 406.698104 -273.148838) (xy 406.694144 -273.099784) (xy 406.37714 -273.099784) (xy 406.376636 -273.125492)
			(xy 406.368593 -273.176274) (xy 406.352705 -273.225173) (xy 406.329362 -273.270985) (xy 406.299141 -273.312581)
			(xy 406.262785 -273.348937) (xy 406.221189 -273.379158) (xy 406.175377 -273.402501) (xy 406.126478 -273.418389)
			(xy 406.075696 -273.426432) (xy 406.02428 -273.426432) (xy 405.973498 -273.418389) (xy 405.924599 -273.402501)
			(xy 405.878787 -273.379158) (xy 405.837191 -273.348937) (xy 405.800835 -273.312581) (xy 405.770614 -273.270985)
			(xy 405.747271 -273.225173) (xy 405.731383 -273.176274) (xy 405.72334 -273.125492) (xy 405.404662 -273.125492)
			(xy 405.396946 -273.172968) (xy 405.381362 -273.219649) (xy 405.358491 -273.263226) (xy 405.328926 -273.30257)
			(xy 405.293433 -273.336662) (xy 405.25293 -273.364618) (xy 405.208468 -273.385716) (xy 405.161197 -273.399408)
			(xy 405.112342 -273.40534) (xy 405.063167 -273.403359) (xy 405.014948 -273.393515) (xy 404.968932 -273.376063)
			(xy 404.926311 -273.351456) (xy 404.88819 -273.320331) (xy 404.855555 -273.283494) (xy 404.829252 -273.241898)
			(xy 404.809961 -273.196622) (xy 404.798184 -273.148838) (xy 404.794224 -273.099784) (xy 404.476966 -273.099784)
			(xy 404.476462 -273.125492) (xy 404.468419 -273.176274) (xy 404.452531 -273.225173) (xy 404.429188 -273.270985)
			(xy 404.398967 -273.312581) (xy 404.362611 -273.348937) (xy 404.321015 -273.379158) (xy 404.275203 -273.402501)
			(xy 404.226304 -273.418389) (xy 404.175522 -273.426432) (xy 404.124106 -273.426432) (xy 404.073324 -273.418389)
			(xy 404.024425 -273.402501) (xy 403.978613 -273.379158) (xy 403.937017 -273.348937) (xy 403.900661 -273.312581)
			(xy 403.87044 -273.270985) (xy 403.847097 -273.225173) (xy 403.831209 -273.176274) (xy 403.823166 -273.125492)
			(xy 403.504488 -273.125492) (xy 403.496772 -273.172968) (xy 403.481188 -273.219649) (xy 403.458317 -273.263226)
			(xy 403.428752 -273.30257) (xy 403.393259 -273.336662) (xy 403.352756 -273.364618) (xy 403.308294 -273.385716)
			(xy 403.261023 -273.399408) (xy 403.212168 -273.40534) (xy 403.162993 -273.403359) (xy 403.114774 -273.393515)
			(xy 403.068758 -273.376063) (xy 403.026137 -273.351456) (xy 402.988016 -273.320331) (xy 402.955381 -273.283494)
			(xy 402.929078 -273.241898) (xy 402.909787 -273.196622) (xy 402.89801 -273.148838) (xy 402.89405 -273.099784)
			(xy 402.577046 -273.099784) (xy 402.576542 -273.125492) (xy 402.568499 -273.176274) (xy 402.552611 -273.225173)
			(xy 402.529268 -273.270985) (xy 402.499047 -273.312581) (xy 402.462691 -273.348937) (xy 402.421095 -273.379158)
			(xy 402.375283 -273.402501) (xy 402.326384 -273.418389) (xy 402.275602 -273.426432) (xy 402.224186 -273.426432)
			(xy 402.173404 -273.418389) (xy 402.124505 -273.402501) (xy 402.078693 -273.379158) (xy 402.037097 -273.348937)
			(xy 402.000741 -273.312581) (xy 401.97052 -273.270985) (xy 401.947177 -273.225173) (xy 401.931289 -273.176274)
			(xy 401.923246 -273.125492) (xy 401.604568 -273.125492) (xy 401.596852 -273.172968) (xy 401.581268 -273.219649)
			(xy 401.558397 -273.263226) (xy 401.528832 -273.30257) (xy 401.493339 -273.336662) (xy 401.452836 -273.364618)
			(xy 401.408374 -273.385716) (xy 401.361103 -273.399408) (xy 401.312248 -273.40534) (xy 401.263073 -273.403359)
			(xy 401.214854 -273.393515) (xy 401.168838 -273.376063) (xy 401.126217 -273.351456) (xy 401.088096 -273.320331)
			(xy 401.055461 -273.283494) (xy 401.029158 -273.241898) (xy 401.009867 -273.196622) (xy 400.99809 -273.148838)
			(xy 400.99413 -273.099784) (xy 400.677126 -273.099784) (xy 400.676622 -273.125492) (xy 400.668579 -273.176274)
			(xy 400.652691 -273.225173) (xy 400.629348 -273.270985) (xy 400.599127 -273.312581) (xy 400.562771 -273.348937)
			(xy 400.521175 -273.379158) (xy 400.475363 -273.402501) (xy 400.426464 -273.418389) (xy 400.375682 -273.426432)
			(xy 400.324266 -273.426432) (xy 400.273484 -273.418389) (xy 400.224585 -273.402501) (xy 400.178773 -273.379158)
			(xy 400.137177 -273.348937) (xy 400.100821 -273.312581) (xy 400.0706 -273.270985) (xy 400.047257 -273.225173)
			(xy 400.031369 -273.176274) (xy 400.023326 -273.125492) (xy 399.704648 -273.125492) (xy 399.696932 -273.172968)
			(xy 399.681348 -273.219649) (xy 399.658477 -273.263226) (xy 399.628912 -273.30257) (xy 399.593419 -273.336662)
			(xy 399.552916 -273.364618) (xy 399.508454 -273.385716) (xy 399.461183 -273.399408) (xy 399.412328 -273.40534)
			(xy 399.363153 -273.403359) (xy 399.314934 -273.393515) (xy 399.268918 -273.376063) (xy 399.226297 -273.351456)
			(xy 399.188176 -273.320331) (xy 399.155541 -273.283494) (xy 399.129238 -273.241898) (xy 399.109947 -273.196622)
			(xy 399.09817 -273.148838) (xy 399.09421 -273.099784) (xy 398.776952 -273.099784) (xy 398.776448 -273.125492)
			(xy 398.768405 -273.176274) (xy 398.752517 -273.225173) (xy 398.729174 -273.270985) (xy 398.698953 -273.312581)
			(xy 398.662597 -273.348937) (xy 398.621001 -273.379158) (xy 398.575189 -273.402501) (xy 398.52629 -273.418389)
			(xy 398.475508 -273.426432) (xy 398.424092 -273.426432) (xy 398.37331 -273.418389) (xy 398.324411 -273.402501)
			(xy 398.278599 -273.379158) (xy 398.237003 -273.348937) (xy 398.200647 -273.312581) (xy 398.170426 -273.270985)
			(xy 398.147083 -273.225173) (xy 398.131195 -273.176274) (xy 398.123152 -273.125492) (xy 397.804474 -273.125492)
			(xy 397.796758 -273.172968) (xy 397.781174 -273.219649) (xy 397.758303 -273.263226) (xy 397.728738 -273.30257)
			(xy 397.693245 -273.336662) (xy 397.652742 -273.364618) (xy 397.60828 -273.385716) (xy 397.561009 -273.399408)
			(xy 397.512154 -273.40534) (xy 397.462979 -273.403359) (xy 397.41476 -273.393515) (xy 397.368744 -273.376063)
			(xy 397.326123 -273.351456) (xy 397.288002 -273.320331) (xy 397.255367 -273.283494) (xy 397.229064 -273.241898)
			(xy 397.209773 -273.196622) (xy 397.197996 -273.148838) (xy 397.194036 -273.099784) (xy 396.877032 -273.099784)
			(xy 396.876528 -273.125492) (xy 396.868485 -273.176274) (xy 396.852597 -273.225173) (xy 396.829254 -273.270985)
			(xy 396.799033 -273.312581) (xy 396.762677 -273.348937) (xy 396.721081 -273.379158) (xy 396.675269 -273.402501)
			(xy 396.62637 -273.418389) (xy 396.575588 -273.426432) (xy 396.524172 -273.426432) (xy 396.47339 -273.418389)
			(xy 396.424491 -273.402501) (xy 396.378679 -273.379158) (xy 396.337083 -273.348937) (xy 396.300727 -273.312581)
			(xy 396.270506 -273.270985) (xy 396.247163 -273.225173) (xy 396.231275 -273.176274) (xy 396.223232 -273.125492)
			(xy 395.904554 -273.125492) (xy 395.896838 -273.172968) (xy 395.881254 -273.219649) (xy 395.858383 -273.263226)
			(xy 395.828818 -273.30257) (xy 395.793325 -273.336662) (xy 395.752822 -273.364618) (xy 395.70836 -273.385716)
			(xy 395.661089 -273.399408) (xy 395.612234 -273.40534) (xy 395.563059 -273.403359) (xy 395.51484 -273.393515)
			(xy 395.468824 -273.376063) (xy 395.426203 -273.351456) (xy 395.388082 -273.320331) (xy 395.355447 -273.283494)
			(xy 395.329144 -273.241898) (xy 395.309853 -273.196622) (xy 395.298076 -273.148838) (xy 395.294116 -273.099784)
			(xy 394.977112 -273.099784) (xy 394.976608 -273.125492) (xy 394.968565 -273.176274) (xy 394.952677 -273.225173)
			(xy 394.929334 -273.270985) (xy 394.899113 -273.312581) (xy 394.862757 -273.348937) (xy 394.821161 -273.379158)
			(xy 394.775349 -273.402501) (xy 394.72645 -273.418389) (xy 394.675668 -273.426432) (xy 394.624252 -273.426432)
			(xy 394.57347 -273.418389) (xy 394.524571 -273.402501) (xy 394.478759 -273.379158) (xy 394.437163 -273.348937)
			(xy 394.400807 -273.312581) (xy 394.370586 -273.270985) (xy 394.347243 -273.225173) (xy 394.331355 -273.176274)
			(xy 394.323312 -273.125492) (xy 394.004634 -273.125492) (xy 393.996918 -273.172968) (xy 393.981334 -273.219649)
			(xy 393.958463 -273.263226) (xy 393.928898 -273.30257) (xy 393.893405 -273.336662) (xy 393.852902 -273.364618)
			(xy 393.80844 -273.385716) (xy 393.761169 -273.399408) (xy 393.712314 -273.40534) (xy 393.663139 -273.403359)
			(xy 393.61492 -273.393515) (xy 393.568904 -273.376063) (xy 393.526283 -273.351456) (xy 393.488162 -273.320331)
			(xy 393.455527 -273.283494) (xy 393.429224 -273.241898) (xy 393.409933 -273.196622) (xy 393.398156 -273.148838)
			(xy 393.394196 -273.099784) (xy 393.076938 -273.099784) (xy 393.076434 -273.125492) (xy 393.068391 -273.176274)
			(xy 393.052503 -273.225173) (xy 393.02916 -273.270985) (xy 392.998939 -273.312581) (xy 392.962583 -273.348937)
			(xy 392.920987 -273.379158) (xy 392.875175 -273.402501) (xy 392.826276 -273.418389) (xy 392.775494 -273.426432)
			(xy 392.724078 -273.426432) (xy 392.673296 -273.418389) (xy 392.624397 -273.402501) (xy 392.578585 -273.379158)
			(xy 392.536989 -273.348937) (xy 392.500633 -273.312581) (xy 392.470412 -273.270985) (xy 392.447069 -273.225173)
			(xy 392.431181 -273.176274) (xy 392.423138 -273.125492) (xy 383.78638 -273.125492) (xy 383.78638 -273.574764)
			(xy 385.319028 -273.574764) (xy 385.322988 -273.52571) (xy 385.334765 -273.477926) (xy 385.354056 -273.43265)
			(xy 385.380359 -273.391054) (xy 385.412994 -273.354217) (xy 385.451115 -273.323092) (xy 385.493736 -273.298485)
			(xy 385.539752 -273.281033) (xy 385.587971 -273.271189) (xy 385.637146 -273.269208) (xy 385.686001 -273.27514)
			(xy 385.733272 -273.288832) (xy 385.777734 -273.30993) (xy 385.818237 -273.337886) (xy 385.85373 -273.371978)
			(xy 385.883295 -273.411322) (xy 385.906166 -273.454899) (xy 385.92175 -273.50158) (xy 385.929645 -273.550157)
			(xy 385.93014 -273.574764) (xy 386.268988 -273.574764) (xy 386.272948 -273.52571) (xy 386.284725 -273.477926)
			(xy 386.304016 -273.43265) (xy 386.330319 -273.391054) (xy 386.362954 -273.354217) (xy 386.401075 -273.323092)
			(xy 386.443696 -273.298485) (xy 386.489712 -273.281033) (xy 386.537931 -273.271189) (xy 386.587106 -273.269208)
			(xy 386.635961 -273.27514) (xy 386.683232 -273.288832) (xy 386.727694 -273.30993) (xy 386.768197 -273.337886)
			(xy 386.80369 -273.371978) (xy 386.833255 -273.411322) (xy 386.856126 -273.454899) (xy 386.87171 -273.50158)
			(xy 386.879605 -273.550157) (xy 386.8801 -273.574764) (xy 387.219202 -273.574764) (xy 387.223162 -273.52571)
			(xy 387.234939 -273.477926) (xy 387.25423 -273.43265) (xy 387.280533 -273.391054) (xy 387.313168 -273.354217)
			(xy 387.351289 -273.323092) (xy 387.39391 -273.298485) (xy 387.439926 -273.281033) (xy 387.488145 -273.271189)
			(xy 387.53732 -273.269208) (xy 387.586175 -273.27514) (xy 387.633446 -273.288832) (xy 387.677908 -273.30993)
			(xy 387.718411 -273.337886) (xy 387.753904 -273.371978) (xy 387.783469 -273.411322) (xy 387.80634 -273.454899)
			(xy 387.821924 -273.50158) (xy 387.829819 -273.550157) (xy 387.830314 -273.574764) (xy 388.169162 -273.574764)
			(xy 388.173122 -273.52571) (xy 388.184899 -273.477926) (xy 388.20419 -273.43265) (xy 388.230493 -273.391054)
			(xy 388.263128 -273.354217) (xy 388.301249 -273.323092) (xy 388.34387 -273.298485) (xy 388.389886 -273.281033)
			(xy 388.438105 -273.271189) (xy 388.48728 -273.269208) (xy 388.536135 -273.27514) (xy 388.583406 -273.288832)
			(xy 388.627868 -273.30993) (xy 388.668371 -273.337886) (xy 388.703864 -273.371978) (xy 388.733429 -273.411322)
			(xy 388.7563 -273.454899) (xy 388.771884 -273.50158) (xy 388.779779 -273.550157) (xy 388.780274 -273.574764)
			(xy 389.119122 -273.574764) (xy 389.123082 -273.52571) (xy 389.134859 -273.477926) (xy 389.15415 -273.43265)
			(xy 389.180453 -273.391054) (xy 389.213088 -273.354217) (xy 389.251209 -273.323092) (xy 389.29383 -273.298485)
			(xy 389.339846 -273.281033) (xy 389.388065 -273.271189) (xy 389.43724 -273.269208) (xy 389.486095 -273.27514)
			(xy 389.533366 -273.288832) (xy 389.577828 -273.30993) (xy 389.618331 -273.337886) (xy 389.653824 -273.371978)
			(xy 389.683389 -273.411322) (xy 389.70626 -273.454899) (xy 389.721844 -273.50158) (xy 389.729739 -273.550157)
			(xy 389.730234 -273.574764) (xy 390.069082 -273.574764) (xy 390.073042 -273.52571) (xy 390.084819 -273.477926)
			(xy 390.10411 -273.43265) (xy 390.130413 -273.391054) (xy 390.163048 -273.354217) (xy 390.201169 -273.323092)
			(xy 390.24379 -273.298485) (xy 390.289806 -273.281033) (xy 390.338025 -273.271189) (xy 390.3872 -273.269208)
			(xy 390.436055 -273.27514) (xy 390.483326 -273.288832) (xy 390.527788 -273.30993) (xy 390.568291 -273.337886)
			(xy 390.603784 -273.371978) (xy 390.633349 -273.411322) (xy 390.65622 -273.454899) (xy 390.671804 -273.50158)
			(xy 390.679699 -273.550157) (xy 390.680194 -273.574764) (xy 391.019042 -273.574764) (xy 391.023002 -273.52571)
			(xy 391.034779 -273.477926) (xy 391.05407 -273.43265) (xy 391.080373 -273.391054) (xy 391.113008 -273.354217)
			(xy 391.151129 -273.323092) (xy 391.19375 -273.298485) (xy 391.239766 -273.281033) (xy 391.287985 -273.271189)
			(xy 391.33716 -273.269208) (xy 391.386015 -273.27514) (xy 391.433286 -273.288832) (xy 391.477748 -273.30993)
			(xy 391.518251 -273.337886) (xy 391.553744 -273.371978) (xy 391.583309 -273.411322) (xy 391.60618 -273.454899)
			(xy 391.621764 -273.50158) (xy 391.629659 -273.550157) (xy 391.630154 -273.574764) (xy 391.629659 -273.599371)
			(xy 391.621764 -273.647948) (xy 391.60618 -273.694629) (xy 391.583309 -273.738206) (xy 391.553744 -273.77755)
			(xy 391.518251 -273.811642) (xy 391.477748 -273.839598) (xy 391.433286 -273.860696) (xy 391.386015 -273.874388)
			(xy 391.33716 -273.88032) (xy 391.287985 -273.878339) (xy 391.239766 -273.868495) (xy 391.19375 -273.851043)
			(xy 391.151129 -273.826436) (xy 391.113008 -273.795311) (xy 391.080373 -273.758474) (xy 391.05407 -273.716878)
			(xy 391.034779 -273.671602) (xy 391.023002 -273.623818) (xy 391.019042 -273.574764) (xy 390.680194 -273.574764)
			(xy 390.679699 -273.599371) (xy 390.671804 -273.647948) (xy 390.65622 -273.694629) (xy 390.633349 -273.738206)
			(xy 390.603784 -273.77755) (xy 390.568291 -273.811642) (xy 390.527788 -273.839598) (xy 390.483326 -273.860696)
			(xy 390.436055 -273.874388) (xy 390.3872 -273.88032) (xy 390.338025 -273.878339) (xy 390.289806 -273.868495)
			(xy 390.24379 -273.851043) (xy 390.201169 -273.826436) (xy 390.163048 -273.795311) (xy 390.130413 -273.758474)
			(xy 390.10411 -273.716878) (xy 390.084819 -273.671602) (xy 390.073042 -273.623818) (xy 390.069082 -273.574764)
			(xy 389.730234 -273.574764) (xy 389.729739 -273.599371) (xy 389.721844 -273.647948) (xy 389.70626 -273.694629)
			(xy 389.683389 -273.738206) (xy 389.653824 -273.77755) (xy 389.618331 -273.811642) (xy 389.577828 -273.839598)
			(xy 389.533366 -273.860696) (xy 389.486095 -273.874388) (xy 389.43724 -273.88032) (xy 389.388065 -273.878339)
			(xy 389.339846 -273.868495) (xy 389.29383 -273.851043) (xy 389.251209 -273.826436) (xy 389.213088 -273.795311)
			(xy 389.180453 -273.758474) (xy 389.15415 -273.716878) (xy 389.134859 -273.671602) (xy 389.123082 -273.623818)
			(xy 389.119122 -273.574764) (xy 388.780274 -273.574764) (xy 388.779779 -273.599371) (xy 388.771884 -273.647948)
			(xy 388.7563 -273.694629) (xy 388.733429 -273.738206) (xy 388.703864 -273.77755) (xy 388.668371 -273.811642)
			(xy 388.627868 -273.839598) (xy 388.583406 -273.860696) (xy 388.536135 -273.874388) (xy 388.48728 -273.88032)
			(xy 388.438105 -273.878339) (xy 388.389886 -273.868495) (xy 388.34387 -273.851043) (xy 388.301249 -273.826436)
			(xy 388.263128 -273.795311) (xy 388.230493 -273.758474) (xy 388.20419 -273.716878) (xy 388.184899 -273.671602)
			(xy 388.173122 -273.623818) (xy 388.169162 -273.574764) (xy 387.830314 -273.574764) (xy 387.829819 -273.599371)
			(xy 387.821924 -273.647948) (xy 387.80634 -273.694629) (xy 387.783469 -273.738206) (xy 387.753904 -273.77755)
			(xy 387.718411 -273.811642) (xy 387.677908 -273.839598) (xy 387.633446 -273.860696) (xy 387.586175 -273.874388)
			(xy 387.53732 -273.88032) (xy 387.488145 -273.878339) (xy 387.439926 -273.868495) (xy 387.39391 -273.851043)
			(xy 387.351289 -273.826436) (xy 387.313168 -273.795311) (xy 387.280533 -273.758474) (xy 387.25423 -273.716878)
			(xy 387.234939 -273.671602) (xy 387.223162 -273.623818) (xy 387.219202 -273.574764) (xy 386.8801 -273.574764)
			(xy 386.879605 -273.599371) (xy 386.87171 -273.647948) (xy 386.856126 -273.694629) (xy 386.833255 -273.738206)
			(xy 386.80369 -273.77755) (xy 386.768197 -273.811642) (xy 386.727694 -273.839598) (xy 386.683232 -273.860696)
			(xy 386.635961 -273.874388) (xy 386.587106 -273.88032) (xy 386.537931 -273.878339) (xy 386.489712 -273.868495)
			(xy 386.443696 -273.851043) (xy 386.401075 -273.826436) (xy 386.362954 -273.795311) (xy 386.330319 -273.758474)
			(xy 386.304016 -273.716878) (xy 386.284725 -273.671602) (xy 386.272948 -273.623818) (xy 386.268988 -273.574764)
			(xy 385.93014 -273.574764) (xy 385.929645 -273.599371) (xy 385.92175 -273.647948) (xy 385.906166 -273.694629)
			(xy 385.883295 -273.738206) (xy 385.85373 -273.77755) (xy 385.818237 -273.811642) (xy 385.777734 -273.839598)
			(xy 385.733272 -273.860696) (xy 385.686001 -273.874388) (xy 385.637146 -273.88032) (xy 385.587971 -273.878339)
			(xy 385.539752 -273.868495) (xy 385.493736 -273.851043) (xy 385.451115 -273.826436) (xy 385.412994 -273.795311)
			(xy 385.380359 -273.758474) (xy 385.354056 -273.716878) (xy 385.334765 -273.671602) (xy 385.322988 -273.623818)
			(xy 385.319028 -273.574764) (xy 383.78638 -273.574764) (xy 383.78638 -274.075452) (xy 392.423138 -274.075452)
			(xy 392.423138 -274.024036) (xy 392.431181 -273.973254) (xy 392.447069 -273.924355) (xy 392.470412 -273.878543)
			(xy 392.500633 -273.836947) (xy 392.536989 -273.800591) (xy 392.578585 -273.77037) (xy 392.624397 -273.747027)
			(xy 392.673296 -273.731139) (xy 392.724078 -273.723096) (xy 392.775494 -273.723096) (xy 392.826276 -273.731139)
			(xy 392.875175 -273.747027) (xy 392.920987 -273.77037) (xy 392.962583 -273.800591) (xy 392.998939 -273.836947)
			(xy 393.02916 -273.878543) (xy 393.052503 -273.924355) (xy 393.068391 -273.973254) (xy 393.076434 -274.024036)
			(xy 393.076938 -274.049744) (xy 393.394196 -274.049744) (xy 393.398156 -274.00069) (xy 393.409933 -273.952906)
			(xy 393.429224 -273.90763) (xy 393.455527 -273.866034) (xy 393.488162 -273.829197) (xy 393.526283 -273.798072)
			(xy 393.568904 -273.773465) (xy 393.61492 -273.756013) (xy 393.663139 -273.746169) (xy 393.712314 -273.744188)
			(xy 393.761169 -273.75012) (xy 393.80844 -273.763812) (xy 393.852902 -273.78491) (xy 393.893405 -273.812866)
			(xy 393.928898 -273.846958) (xy 393.958463 -273.886302) (xy 393.981334 -273.929879) (xy 393.996918 -273.97656)
			(xy 394.004813 -274.025137) (xy 394.005308 -274.049744) (xy 394.004813 -274.074351) (xy 394.004634 -274.075452)
			(xy 394.323312 -274.075452) (xy 394.323312 -274.024036) (xy 394.331355 -273.973254) (xy 394.347243 -273.924355)
			(xy 394.370586 -273.878543) (xy 394.400807 -273.836947) (xy 394.437163 -273.800591) (xy 394.478759 -273.77037)
			(xy 394.524571 -273.747027) (xy 394.57347 -273.731139) (xy 394.624252 -273.723096) (xy 394.675668 -273.723096)
			(xy 394.72645 -273.731139) (xy 394.775349 -273.747027) (xy 394.821161 -273.77037) (xy 394.862757 -273.800591)
			(xy 394.899113 -273.836947) (xy 394.929334 -273.878543) (xy 394.952677 -273.924355) (xy 394.968565 -273.973254)
			(xy 394.976608 -274.024036) (xy 394.977112 -274.049744) (xy 395.294116 -274.049744) (xy 395.298076 -274.00069)
			(xy 395.309853 -273.952906) (xy 395.329144 -273.90763) (xy 395.355447 -273.866034) (xy 395.388082 -273.829197)
			(xy 395.426203 -273.798072) (xy 395.468824 -273.773465) (xy 395.51484 -273.756013) (xy 395.563059 -273.746169)
			(xy 395.612234 -273.744188) (xy 395.661089 -273.75012) (xy 395.70836 -273.763812) (xy 395.752822 -273.78491)
			(xy 395.793325 -273.812866) (xy 395.828818 -273.846958) (xy 395.858383 -273.886302) (xy 395.881254 -273.929879)
			(xy 395.896838 -273.97656) (xy 395.904733 -274.025137) (xy 395.905228 -274.049744) (xy 395.904733 -274.074351)
			(xy 395.904554 -274.075452) (xy 396.223232 -274.075452) (xy 396.223232 -274.024036) (xy 396.231275 -273.973254)
			(xy 396.247163 -273.924355) (xy 396.270506 -273.878543) (xy 396.300727 -273.836947) (xy 396.337083 -273.800591)
			(xy 396.378679 -273.77037) (xy 396.424491 -273.747027) (xy 396.47339 -273.731139) (xy 396.524172 -273.723096)
			(xy 396.575588 -273.723096) (xy 396.62637 -273.731139) (xy 396.675269 -273.747027) (xy 396.721081 -273.77037)
			(xy 396.762677 -273.800591) (xy 396.799033 -273.836947) (xy 396.829254 -273.878543) (xy 396.852597 -273.924355)
			(xy 396.868485 -273.973254) (xy 396.876528 -274.024036) (xy 396.877032 -274.049744) (xy 397.194036 -274.049744)
			(xy 397.197996 -274.00069) (xy 397.209773 -273.952906) (xy 397.229064 -273.90763) (xy 397.255367 -273.866034)
			(xy 397.288002 -273.829197) (xy 397.326123 -273.798072) (xy 397.368744 -273.773465) (xy 397.41476 -273.756013)
			(xy 397.462979 -273.746169) (xy 397.512154 -273.744188) (xy 397.561009 -273.75012) (xy 397.60828 -273.763812)
			(xy 397.652742 -273.78491) (xy 397.693245 -273.812866) (xy 397.728738 -273.846958) (xy 397.758303 -273.886302)
			(xy 397.781174 -273.929879) (xy 397.796758 -273.97656) (xy 397.804653 -274.025137) (xy 397.805148 -274.049744)
			(xy 397.804653 -274.074351) (xy 397.804474 -274.075452) (xy 398.123152 -274.075452) (xy 398.123152 -274.024036)
			(xy 398.131195 -273.973254) (xy 398.147083 -273.924355) (xy 398.170426 -273.878543) (xy 398.200647 -273.836947)
			(xy 398.237003 -273.800591) (xy 398.278599 -273.77037) (xy 398.324411 -273.747027) (xy 398.37331 -273.731139)
			(xy 398.424092 -273.723096) (xy 398.475508 -273.723096) (xy 398.52629 -273.731139) (xy 398.575189 -273.747027)
			(xy 398.621001 -273.77037) (xy 398.662597 -273.800591) (xy 398.698953 -273.836947) (xy 398.729174 -273.878543)
			(xy 398.752517 -273.924355) (xy 398.768405 -273.973254) (xy 398.776448 -274.024036) (xy 398.776952 -274.049744)
			(xy 399.09421 -274.049744) (xy 399.09817 -274.00069) (xy 399.109947 -273.952906) (xy 399.129238 -273.90763)
			(xy 399.155541 -273.866034) (xy 399.188176 -273.829197) (xy 399.226297 -273.798072) (xy 399.268918 -273.773465)
			(xy 399.314934 -273.756013) (xy 399.363153 -273.746169) (xy 399.412328 -273.744188) (xy 399.461183 -273.75012)
			(xy 399.508454 -273.763812) (xy 399.552916 -273.78491) (xy 399.593419 -273.812866) (xy 399.628912 -273.846958)
			(xy 399.658477 -273.886302) (xy 399.681348 -273.929879) (xy 399.696932 -273.97656) (xy 399.704827 -274.025137)
			(xy 399.705322 -274.049744) (xy 399.704827 -274.074351) (xy 399.704648 -274.075452) (xy 400.023326 -274.075452)
			(xy 400.023326 -274.024036) (xy 400.031369 -273.973254) (xy 400.047257 -273.924355) (xy 400.0706 -273.878543)
			(xy 400.100821 -273.836947) (xy 400.137177 -273.800591) (xy 400.178773 -273.77037) (xy 400.224585 -273.747027)
			(xy 400.273484 -273.731139) (xy 400.324266 -273.723096) (xy 400.375682 -273.723096) (xy 400.426464 -273.731139)
			(xy 400.475363 -273.747027) (xy 400.521175 -273.77037) (xy 400.562771 -273.800591) (xy 400.599127 -273.836947)
			(xy 400.629348 -273.878543) (xy 400.652691 -273.924355) (xy 400.668579 -273.973254) (xy 400.676622 -274.024036)
			(xy 400.677126 -274.049744) (xy 400.99413 -274.049744) (xy 400.99809 -274.00069) (xy 401.009867 -273.952906)
			(xy 401.029158 -273.90763) (xy 401.055461 -273.866034) (xy 401.088096 -273.829197) (xy 401.126217 -273.798072)
			(xy 401.168838 -273.773465) (xy 401.214854 -273.756013) (xy 401.263073 -273.746169) (xy 401.312248 -273.744188)
			(xy 401.361103 -273.75012) (xy 401.408374 -273.763812) (xy 401.452836 -273.78491) (xy 401.493339 -273.812866)
			(xy 401.528832 -273.846958) (xy 401.558397 -273.886302) (xy 401.581268 -273.929879) (xy 401.596852 -273.97656)
			(xy 401.604747 -274.025137) (xy 401.605242 -274.049744) (xy 401.604747 -274.074351) (xy 401.604568 -274.075452)
			(xy 401.923246 -274.075452) (xy 401.923246 -274.024036) (xy 401.931289 -273.973254) (xy 401.947177 -273.924355)
			(xy 401.97052 -273.878543) (xy 402.000741 -273.836947) (xy 402.037097 -273.800591) (xy 402.078693 -273.77037)
			(xy 402.124505 -273.747027) (xy 402.173404 -273.731139) (xy 402.224186 -273.723096) (xy 402.275602 -273.723096)
			(xy 402.326384 -273.731139) (xy 402.375283 -273.747027) (xy 402.421095 -273.77037) (xy 402.462691 -273.800591)
			(xy 402.499047 -273.836947) (xy 402.529268 -273.878543) (xy 402.552611 -273.924355) (xy 402.568499 -273.973254)
			(xy 402.576542 -274.024036) (xy 402.577046 -274.049744) (xy 402.89405 -274.049744) (xy 402.89801 -274.00069)
			(xy 402.909787 -273.952906) (xy 402.929078 -273.90763) (xy 402.955381 -273.866034) (xy 402.988016 -273.829197)
			(xy 403.026137 -273.798072) (xy 403.068758 -273.773465) (xy 403.114774 -273.756013) (xy 403.162993 -273.746169)
			(xy 403.212168 -273.744188) (xy 403.261023 -273.75012) (xy 403.308294 -273.763812) (xy 403.352756 -273.78491)
			(xy 403.393259 -273.812866) (xy 403.428752 -273.846958) (xy 403.458317 -273.886302) (xy 403.481188 -273.929879)
			(xy 403.496772 -273.97656) (xy 403.504667 -274.025137) (xy 403.505162 -274.049744) (xy 403.504667 -274.074351)
			(xy 403.504488 -274.075452) (xy 403.823166 -274.075452) (xy 403.823166 -274.024036) (xy 403.831209 -273.973254)
			(xy 403.847097 -273.924355) (xy 403.87044 -273.878543) (xy 403.900661 -273.836947) (xy 403.937017 -273.800591)
			(xy 403.978613 -273.77037) (xy 404.024425 -273.747027) (xy 404.073324 -273.731139) (xy 404.124106 -273.723096)
			(xy 404.175522 -273.723096) (xy 404.226304 -273.731139) (xy 404.275203 -273.747027) (xy 404.321015 -273.77037)
			(xy 404.362611 -273.800591) (xy 404.398967 -273.836947) (xy 404.429188 -273.878543) (xy 404.452531 -273.924355)
			(xy 404.468419 -273.973254) (xy 404.476462 -274.024036) (xy 404.476966 -274.049744) (xy 404.794224 -274.049744)
			(xy 404.798184 -274.00069) (xy 404.809961 -273.952906) (xy 404.829252 -273.90763) (xy 404.855555 -273.866034)
			(xy 404.88819 -273.829197) (xy 404.926311 -273.798072) (xy 404.968932 -273.773465) (xy 405.014948 -273.756013)
			(xy 405.063167 -273.746169) (xy 405.112342 -273.744188) (xy 405.161197 -273.75012) (xy 405.208468 -273.763812)
			(xy 405.25293 -273.78491) (xy 405.293433 -273.812866) (xy 405.328926 -273.846958) (xy 405.358491 -273.886302)
			(xy 405.381362 -273.929879) (xy 405.396946 -273.97656) (xy 405.404841 -274.025137) (xy 405.405336 -274.049744)
			(xy 405.404841 -274.074351) (xy 405.404662 -274.075452) (xy 405.72334 -274.075452) (xy 405.72334 -274.024036)
			(xy 405.731383 -273.973254) (xy 405.747271 -273.924355) (xy 405.770614 -273.878543) (xy 405.800835 -273.836947)
			(xy 405.837191 -273.800591) (xy 405.878787 -273.77037) (xy 405.924599 -273.747027) (xy 405.973498 -273.731139)
			(xy 406.02428 -273.723096) (xy 406.075696 -273.723096) (xy 406.126478 -273.731139) (xy 406.175377 -273.747027)
			(xy 406.221189 -273.77037) (xy 406.262785 -273.800591) (xy 406.299141 -273.836947) (xy 406.329362 -273.878543)
			(xy 406.352705 -273.924355) (xy 406.368593 -273.973254) (xy 406.376636 -274.024036) (xy 406.37714 -274.049744)
			(xy 406.694144 -274.049744) (xy 406.698104 -274.00069) (xy 406.709881 -273.952906) (xy 406.729172 -273.90763)
			(xy 406.755475 -273.866034) (xy 406.78811 -273.829197) (xy 406.826231 -273.798072) (xy 406.868852 -273.773465)
			(xy 406.914868 -273.756013) (xy 406.963087 -273.746169) (xy 407.012262 -273.744188) (xy 407.061117 -273.75012)
			(xy 407.108388 -273.763812) (xy 407.15285 -273.78491) (xy 407.193353 -273.812866) (xy 407.228846 -273.846958)
			(xy 407.258411 -273.886302) (xy 407.281282 -273.929879) (xy 407.296866 -273.97656) (xy 407.304761 -274.025137)
			(xy 407.305256 -274.049744) (xy 407.304761 -274.074351) (xy 407.304623 -274.075198) (xy 407.623006 -274.075198)
			(xy 407.623006 -274.023782) (xy 407.631049 -273.973) (xy 407.646937 -273.924101) (xy 407.67028 -273.878289)
			(xy 407.700501 -273.836693) (xy 407.736857 -273.800337) (xy 407.778453 -273.770116) (xy 407.824265 -273.746773)
			(xy 407.873164 -273.730885) (xy 407.923946 -273.722842) (xy 407.975362 -273.722842) (xy 408.026144 -273.730885)
			(xy 408.075043 -273.746773) (xy 408.120855 -273.770116) (xy 408.162451 -273.800337) (xy 408.198807 -273.836693)
			(xy 408.229028 -273.878289) (xy 408.252371 -273.924101) (xy 408.268259 -273.973) (xy 408.276302 -274.023782)
			(xy 408.276806 -274.04949) (xy 408.276801 -274.049744) (xy 408.594064 -274.049744) (xy 408.598024 -274.00069)
			(xy 408.609801 -273.952906) (xy 408.629092 -273.90763) (xy 408.655395 -273.866034) (xy 408.68803 -273.829197)
			(xy 408.726151 -273.798072) (xy 408.768772 -273.773465) (xy 408.814788 -273.756013) (xy 408.863007 -273.746169)
			(xy 408.912182 -273.744188) (xy 408.961037 -273.75012) (xy 409.008308 -273.763812) (xy 409.05277 -273.78491)
			(xy 409.093273 -273.812866) (xy 409.128766 -273.846958) (xy 409.158331 -273.886302) (xy 409.181202 -273.929879)
			(xy 409.196786 -273.97656) (xy 409.204681 -274.025137) (xy 409.205176 -274.049744) (xy 409.204681 -274.074351)
			(xy 409.204502 -274.075452) (xy 409.522926 -274.075452) (xy 409.522926 -274.024036) (xy 409.530969 -273.973254)
			(xy 409.546857 -273.924355) (xy 409.5702 -273.878543) (xy 409.600421 -273.836947) (xy 409.636777 -273.800591)
			(xy 409.678373 -273.77037) (xy 409.724185 -273.747027) (xy 409.773084 -273.731139) (xy 409.823866 -273.723096)
			(xy 409.875282 -273.723096) (xy 409.926064 -273.731139) (xy 409.974963 -273.747027) (xy 410.020775 -273.77037)
			(xy 410.062371 -273.800591) (xy 410.098727 -273.836947) (xy 410.128948 -273.878543) (xy 410.152291 -273.924355)
			(xy 410.168179 -273.973254) (xy 410.176222 -274.024036) (xy 410.176726 -274.049744) (xy 410.493984 -274.049744)
			(xy 410.497944 -274.00069) (xy 410.509721 -273.952906) (xy 410.529012 -273.90763) (xy 410.555315 -273.866034)
			(xy 410.58795 -273.829197) (xy 410.626071 -273.798072) (xy 410.668692 -273.773465) (xy 410.714708 -273.756013)
			(xy 410.762927 -273.746169) (xy 410.812102 -273.744188) (xy 410.860957 -273.75012) (xy 410.908228 -273.763812)
			(xy 410.95269 -273.78491) (xy 410.993193 -273.812866) (xy 411.028686 -273.846958) (xy 411.058251 -273.886302)
			(xy 411.081122 -273.929879) (xy 411.096706 -273.97656) (xy 411.104601 -274.025137) (xy 411.105096 -274.049744)
			(xy 411.104601 -274.074351) (xy 411.104422 -274.075452) (xy 411.4231 -274.075452) (xy 411.4231 -274.024036)
			(xy 411.431143 -273.973254) (xy 411.447031 -273.924355) (xy 411.470374 -273.878543) (xy 411.500595 -273.836947)
			(xy 411.536951 -273.800591) (xy 411.578547 -273.77037) (xy 411.624359 -273.747027) (xy 411.673258 -273.731139)
			(xy 411.72404 -273.723096) (xy 411.775456 -273.723096) (xy 411.826238 -273.731139) (xy 411.875137 -273.747027)
			(xy 411.920949 -273.77037) (xy 411.962545 -273.800591) (xy 411.998901 -273.836947) (xy 412.029122 -273.878543)
			(xy 412.052465 -273.924355) (xy 412.068353 -273.973254) (xy 412.076396 -274.024036) (xy 412.0769 -274.049744)
			(xy 412.394158 -274.049744) (xy 412.398118 -274.00069) (xy 412.409895 -273.952906) (xy 412.429186 -273.90763)
			(xy 412.455489 -273.866034) (xy 412.488124 -273.829197) (xy 412.526245 -273.798072) (xy 412.568866 -273.773465)
			(xy 412.614882 -273.756013) (xy 412.663101 -273.746169) (xy 412.712276 -273.744188) (xy 412.761131 -273.75012)
			(xy 412.808402 -273.763812) (xy 412.852864 -273.78491) (xy 412.893367 -273.812866) (xy 412.92886 -273.846958)
			(xy 412.958425 -273.886302) (xy 412.981296 -273.929879) (xy 412.99688 -273.97656) (xy 413.004775 -274.025137)
			(xy 413.00527 -274.049744) (xy 413.004775 -274.074351) (xy 413.004596 -274.075452) (xy 413.32302 -274.075452)
			(xy 413.32302 -274.024036) (xy 413.331063 -273.973254) (xy 413.346951 -273.924355) (xy 413.370294 -273.878543)
			(xy 413.400515 -273.836947) (xy 413.436871 -273.800591) (xy 413.478467 -273.77037) (xy 413.524279 -273.747027)
			(xy 413.573178 -273.731139) (xy 413.62396 -273.723096) (xy 413.675376 -273.723096) (xy 413.726158 -273.731139)
			(xy 413.775057 -273.747027) (xy 413.820869 -273.77037) (xy 413.862465 -273.800591) (xy 413.898821 -273.836947)
			(xy 413.929042 -273.878543) (xy 413.952385 -273.924355) (xy 413.968273 -273.973254) (xy 413.976316 -274.024036)
			(xy 413.97682 -274.049744) (xy 414.294078 -274.049744) (xy 414.298038 -274.00069) (xy 414.309815 -273.952906)
			(xy 414.329106 -273.90763) (xy 414.355409 -273.866034) (xy 414.388044 -273.829197) (xy 414.426165 -273.798072)
			(xy 414.468786 -273.773465) (xy 414.514802 -273.756013) (xy 414.563021 -273.746169) (xy 414.612196 -273.744188)
			(xy 414.661051 -273.75012) (xy 414.708322 -273.763812) (xy 414.752784 -273.78491) (xy 414.793287 -273.812866)
			(xy 414.82878 -273.846958) (xy 414.858345 -273.886302) (xy 414.881216 -273.929879) (xy 414.8968 -273.97656)
			(xy 414.904695 -274.025137) (xy 414.90519 -274.049744) (xy 414.904695 -274.074351) (xy 414.904516 -274.075452)
			(xy 415.22294 -274.075452) (xy 415.22294 -274.024036) (xy 415.230983 -273.973254) (xy 415.246871 -273.924355)
			(xy 415.270214 -273.878543) (xy 415.300435 -273.836947) (xy 415.336791 -273.800591) (xy 415.378387 -273.77037)
			(xy 415.424199 -273.747027) (xy 415.473098 -273.731139) (xy 415.52388 -273.723096) (xy 415.575296 -273.723096)
			(xy 415.626078 -273.731139) (xy 415.674977 -273.747027) (xy 415.720789 -273.77037) (xy 415.762385 -273.800591)
			(xy 415.798741 -273.836947) (xy 415.828962 -273.878543) (xy 415.852305 -273.924355) (xy 415.868193 -273.973254)
			(xy 415.876236 -274.024036) (xy 415.87674 -274.049744) (xy 416.193998 -274.049744) (xy 416.197958 -274.00069)
			(xy 416.209735 -273.952906) (xy 416.229026 -273.90763) (xy 416.255329 -273.866034) (xy 416.287964 -273.829197)
			(xy 416.326085 -273.798072) (xy 416.368706 -273.773465) (xy 416.414722 -273.756013) (xy 416.462941 -273.746169)
			(xy 416.512116 -273.744188) (xy 416.560971 -273.75012) (xy 416.608242 -273.763812) (xy 416.652704 -273.78491)
			(xy 416.693207 -273.812866) (xy 416.7287 -273.846958) (xy 416.758265 -273.886302) (xy 416.781136 -273.929879)
			(xy 416.79672 -273.97656) (xy 416.804615 -274.025137) (xy 416.80511 -274.049744) (xy 416.804615 -274.074351)
			(xy 416.804436 -274.075452) (xy 417.123114 -274.075452) (xy 417.123114 -274.024036) (xy 417.131157 -273.973254)
			(xy 417.147045 -273.924355) (xy 417.170388 -273.878543) (xy 417.200609 -273.836947) (xy 417.236965 -273.800591)
			(xy 417.278561 -273.77037) (xy 417.324373 -273.747027) (xy 417.373272 -273.731139) (xy 417.424054 -273.723096)
			(xy 417.47547 -273.723096) (xy 417.526252 -273.731139) (xy 417.575151 -273.747027) (xy 417.620963 -273.77037)
			(xy 417.662559 -273.800591) (xy 417.698915 -273.836947) (xy 417.729136 -273.878543) (xy 417.752479 -273.924355)
			(xy 417.768367 -273.973254) (xy 417.77641 -274.024036) (xy 417.776914 -274.049744) (xy 418.094172 -274.049744)
			(xy 418.098132 -274.00069) (xy 418.109909 -273.952906) (xy 418.1292 -273.90763) (xy 418.155503 -273.866034)
			(xy 418.188138 -273.829197) (xy 418.226259 -273.798072) (xy 418.26888 -273.773465) (xy 418.314896 -273.756013)
			(xy 418.363115 -273.746169) (xy 418.41229 -273.744188) (xy 418.461145 -273.75012) (xy 418.508416 -273.763812)
			(xy 418.552878 -273.78491) (xy 418.593381 -273.812866) (xy 418.628874 -273.846958) (xy 418.658439 -273.886302)
			(xy 418.68131 -273.929879) (xy 418.696894 -273.97656) (xy 418.704789 -274.025137) (xy 418.705284 -274.049744)
			(xy 418.704789 -274.074351) (xy 418.70461 -274.075452) (xy 419.023034 -274.075452) (xy 419.023034 -274.024036)
			(xy 419.031077 -273.973254) (xy 419.046965 -273.924355) (xy 419.070308 -273.878543) (xy 419.100529 -273.836947)
			(xy 419.136885 -273.800591) (xy 419.178481 -273.77037) (xy 419.224293 -273.747027) (xy 419.273192 -273.731139)
			(xy 419.323974 -273.723096) (xy 419.37539 -273.723096) (xy 419.426172 -273.731139) (xy 419.475071 -273.747027)
			(xy 419.520883 -273.77037) (xy 419.562479 -273.800591) (xy 419.598835 -273.836947) (xy 419.629056 -273.878543)
			(xy 419.652399 -273.924355) (xy 419.668287 -273.973254) (xy 419.67633 -274.024036) (xy 419.676834 -274.049744)
			(xy 419.994092 -274.049744) (xy 419.998052 -274.00069) (xy 420.009829 -273.952906) (xy 420.02912 -273.90763)
			(xy 420.055423 -273.866034) (xy 420.088058 -273.829197) (xy 420.126179 -273.798072) (xy 420.1688 -273.773465)
			(xy 420.214816 -273.756013) (xy 420.263035 -273.746169) (xy 420.31221 -273.744188) (xy 420.361065 -273.75012)
			(xy 420.408336 -273.763812) (xy 420.452798 -273.78491) (xy 420.493301 -273.812866) (xy 420.528794 -273.846958)
			(xy 420.558359 -273.886302) (xy 420.58123 -273.929879) (xy 420.596814 -273.97656) (xy 420.604709 -274.025137)
			(xy 420.605204 -274.049744) (xy 420.604709 -274.074351) (xy 420.60453 -274.075452) (xy 420.922954 -274.075452)
			(xy 420.922954 -274.024036) (xy 420.930997 -273.973254) (xy 420.946885 -273.924355) (xy 420.970228 -273.878543)
			(xy 421.000449 -273.836947) (xy 421.036805 -273.800591) (xy 421.078401 -273.77037) (xy 421.124213 -273.747027)
			(xy 421.173112 -273.731139) (xy 421.223894 -273.723096) (xy 421.27531 -273.723096) (xy 421.326092 -273.731139)
			(xy 421.374991 -273.747027) (xy 421.420803 -273.77037) (xy 421.462399 -273.800591) (xy 421.498755 -273.836947)
			(xy 421.528976 -273.878543) (xy 421.552319 -273.924355) (xy 421.568207 -273.973254) (xy 421.57625 -274.024036)
			(xy 421.576754 -274.049744) (xy 421.57625 -274.075452) (xy 421.568207 -274.126234) (xy 421.552319 -274.175133)
			(xy 421.528976 -274.220945) (xy 421.498755 -274.262541) (xy 421.462399 -274.298897) (xy 421.420803 -274.329118)
			(xy 421.374991 -274.352461) (xy 421.326092 -274.368349) (xy 421.27531 -274.376392) (xy 421.223894 -274.376392)
			(xy 421.173112 -274.368349) (xy 421.124213 -274.352461) (xy 421.078401 -274.329118) (xy 421.036805 -274.298897)
			(xy 421.000449 -274.262541) (xy 420.970228 -274.220945) (xy 420.946885 -274.175133) (xy 420.930997 -274.126234)
			(xy 420.922954 -274.075452) (xy 420.60453 -274.075452) (xy 420.596814 -274.122928) (xy 420.58123 -274.169609)
			(xy 420.558359 -274.213186) (xy 420.528794 -274.25253) (xy 420.493301 -274.286622) (xy 420.452798 -274.314578)
			(xy 420.408336 -274.335676) (xy 420.361065 -274.349368) (xy 420.31221 -274.3553) (xy 420.263035 -274.353319)
			(xy 420.214816 -274.343475) (xy 420.1688 -274.326023) (xy 420.126179 -274.301416) (xy 420.088058 -274.270291)
			(xy 420.055423 -274.233454) (xy 420.02912 -274.191858) (xy 420.009829 -274.146582) (xy 419.998052 -274.098798)
			(xy 419.994092 -274.049744) (xy 419.676834 -274.049744) (xy 419.67633 -274.075452) (xy 419.668287 -274.126234)
			(xy 419.652399 -274.175133) (xy 419.629056 -274.220945) (xy 419.598835 -274.262541) (xy 419.562479 -274.298897)
			(xy 419.520883 -274.329118) (xy 419.475071 -274.352461) (xy 419.426172 -274.368349) (xy 419.37539 -274.376392)
			(xy 419.323974 -274.376392) (xy 419.273192 -274.368349) (xy 419.224293 -274.352461) (xy 419.178481 -274.329118)
			(xy 419.136885 -274.298897) (xy 419.100529 -274.262541) (xy 419.070308 -274.220945) (xy 419.046965 -274.175133)
			(xy 419.031077 -274.126234) (xy 419.023034 -274.075452) (xy 418.70461 -274.075452) (xy 418.696894 -274.122928)
			(xy 418.68131 -274.169609) (xy 418.658439 -274.213186) (xy 418.628874 -274.25253) (xy 418.593381 -274.286622)
			(xy 418.552878 -274.314578) (xy 418.508416 -274.335676) (xy 418.461145 -274.349368) (xy 418.41229 -274.3553)
			(xy 418.363115 -274.353319) (xy 418.314896 -274.343475) (xy 418.26888 -274.326023) (xy 418.226259 -274.301416)
			(xy 418.188138 -274.270291) (xy 418.155503 -274.233454) (xy 418.1292 -274.191858) (xy 418.109909 -274.146582)
			(xy 418.098132 -274.098798) (xy 418.094172 -274.049744) (xy 417.776914 -274.049744) (xy 417.77641 -274.075452)
			(xy 417.768367 -274.126234) (xy 417.752479 -274.175133) (xy 417.729136 -274.220945) (xy 417.698915 -274.262541)
			(xy 417.662559 -274.298897) (xy 417.620963 -274.329118) (xy 417.575151 -274.352461) (xy 417.526252 -274.368349)
			(xy 417.47547 -274.376392) (xy 417.424054 -274.376392) (xy 417.373272 -274.368349) (xy 417.324373 -274.352461)
			(xy 417.278561 -274.329118) (xy 417.236965 -274.298897) (xy 417.200609 -274.262541) (xy 417.170388 -274.220945)
			(xy 417.147045 -274.175133) (xy 417.131157 -274.126234) (xy 417.123114 -274.075452) (xy 416.804436 -274.075452)
			(xy 416.79672 -274.122928) (xy 416.781136 -274.169609) (xy 416.758265 -274.213186) (xy 416.7287 -274.25253)
			(xy 416.693207 -274.286622) (xy 416.652704 -274.314578) (xy 416.608242 -274.335676) (xy 416.560971 -274.349368)
			(xy 416.512116 -274.3553) (xy 416.462941 -274.353319) (xy 416.414722 -274.343475) (xy 416.368706 -274.326023)
			(xy 416.326085 -274.301416) (xy 416.287964 -274.270291) (xy 416.255329 -274.233454) (xy 416.229026 -274.191858)
			(xy 416.209735 -274.146582) (xy 416.197958 -274.098798) (xy 416.193998 -274.049744) (xy 415.87674 -274.049744)
			(xy 415.876236 -274.075452) (xy 415.868193 -274.126234) (xy 415.852305 -274.175133) (xy 415.828962 -274.220945)
			(xy 415.798741 -274.262541) (xy 415.762385 -274.298897) (xy 415.720789 -274.329118) (xy 415.674977 -274.352461)
			(xy 415.626078 -274.368349) (xy 415.575296 -274.376392) (xy 415.52388 -274.376392) (xy 415.473098 -274.368349)
			(xy 415.424199 -274.352461) (xy 415.378387 -274.329118) (xy 415.336791 -274.298897) (xy 415.300435 -274.262541)
			(xy 415.270214 -274.220945) (xy 415.246871 -274.175133) (xy 415.230983 -274.126234) (xy 415.22294 -274.075452)
			(xy 414.904516 -274.075452) (xy 414.8968 -274.122928) (xy 414.881216 -274.169609) (xy 414.858345 -274.213186)
			(xy 414.82878 -274.25253) (xy 414.793287 -274.286622) (xy 414.752784 -274.314578) (xy 414.708322 -274.335676)
			(xy 414.661051 -274.349368) (xy 414.612196 -274.3553) (xy 414.563021 -274.353319) (xy 414.514802 -274.343475)
			(xy 414.468786 -274.326023) (xy 414.426165 -274.301416) (xy 414.388044 -274.270291) (xy 414.355409 -274.233454)
			(xy 414.329106 -274.191858) (xy 414.309815 -274.146582) (xy 414.298038 -274.098798) (xy 414.294078 -274.049744)
			(xy 413.97682 -274.049744) (xy 413.976316 -274.075452) (xy 413.968273 -274.126234) (xy 413.952385 -274.175133)
			(xy 413.929042 -274.220945) (xy 413.898821 -274.262541) (xy 413.862465 -274.298897) (xy 413.820869 -274.329118)
			(xy 413.775057 -274.352461) (xy 413.726158 -274.368349) (xy 413.675376 -274.376392) (xy 413.62396 -274.376392)
			(xy 413.573178 -274.368349) (xy 413.524279 -274.352461) (xy 413.478467 -274.329118) (xy 413.436871 -274.298897)
			(xy 413.400515 -274.262541) (xy 413.370294 -274.220945) (xy 413.346951 -274.175133) (xy 413.331063 -274.126234)
			(xy 413.32302 -274.075452) (xy 413.004596 -274.075452) (xy 412.99688 -274.122928) (xy 412.981296 -274.169609)
			(xy 412.958425 -274.213186) (xy 412.92886 -274.25253) (xy 412.893367 -274.286622) (xy 412.852864 -274.314578)
			(xy 412.808402 -274.335676) (xy 412.761131 -274.349368) (xy 412.712276 -274.3553) (xy 412.663101 -274.353319)
			(xy 412.614882 -274.343475) (xy 412.568866 -274.326023) (xy 412.526245 -274.301416) (xy 412.488124 -274.270291)
			(xy 412.455489 -274.233454) (xy 412.429186 -274.191858) (xy 412.409895 -274.146582) (xy 412.398118 -274.098798)
			(xy 412.394158 -274.049744) (xy 412.0769 -274.049744) (xy 412.076396 -274.075452) (xy 412.068353 -274.126234)
			(xy 412.052465 -274.175133) (xy 412.029122 -274.220945) (xy 411.998901 -274.262541) (xy 411.962545 -274.298897)
			(xy 411.920949 -274.329118) (xy 411.875137 -274.352461) (xy 411.826238 -274.368349) (xy 411.775456 -274.376392)
			(xy 411.72404 -274.376392) (xy 411.673258 -274.368349) (xy 411.624359 -274.352461) (xy 411.578547 -274.329118)
			(xy 411.536951 -274.298897) (xy 411.500595 -274.262541) (xy 411.470374 -274.220945) (xy 411.447031 -274.175133)
			(xy 411.431143 -274.126234) (xy 411.4231 -274.075452) (xy 411.104422 -274.075452) (xy 411.096706 -274.122928)
			(xy 411.081122 -274.169609) (xy 411.058251 -274.213186) (xy 411.028686 -274.25253) (xy 410.993193 -274.286622)
			(xy 410.95269 -274.314578) (xy 410.908228 -274.335676) (xy 410.860957 -274.349368) (xy 410.812102 -274.3553)
			(xy 410.762927 -274.353319) (xy 410.714708 -274.343475) (xy 410.668692 -274.326023) (xy 410.626071 -274.301416)
			(xy 410.58795 -274.270291) (xy 410.555315 -274.233454) (xy 410.529012 -274.191858) (xy 410.509721 -274.146582)
			(xy 410.497944 -274.098798) (xy 410.493984 -274.049744) (xy 410.176726 -274.049744) (xy 410.176222 -274.075452)
			(xy 410.168179 -274.126234) (xy 410.152291 -274.175133) (xy 410.128948 -274.220945) (xy 410.098727 -274.262541)
			(xy 410.062371 -274.298897) (xy 410.020775 -274.329118) (xy 409.974963 -274.352461) (xy 409.926064 -274.368349)
			(xy 409.875282 -274.376392) (xy 409.823866 -274.376392) (xy 409.773084 -274.368349) (xy 409.724185 -274.352461)
			(xy 409.678373 -274.329118) (xy 409.636777 -274.298897) (xy 409.600421 -274.262541) (xy 409.5702 -274.220945)
			(xy 409.546857 -274.175133) (xy 409.530969 -274.126234) (xy 409.522926 -274.075452) (xy 409.204502 -274.075452)
			(xy 409.196786 -274.122928) (xy 409.181202 -274.169609) (xy 409.158331 -274.213186) (xy 409.128766 -274.25253)
			(xy 409.093273 -274.286622) (xy 409.05277 -274.314578) (xy 409.008308 -274.335676) (xy 408.961037 -274.349368)
			(xy 408.912182 -274.3553) (xy 408.863007 -274.353319) (xy 408.814788 -274.343475) (xy 408.768772 -274.326023)
			(xy 408.726151 -274.301416) (xy 408.68803 -274.270291) (xy 408.655395 -274.233454) (xy 408.629092 -274.191858)
			(xy 408.609801 -274.146582) (xy 408.598024 -274.098798) (xy 408.594064 -274.049744) (xy 408.276801 -274.049744)
			(xy 408.276302 -274.075198) (xy 408.268259 -274.12598) (xy 408.252371 -274.174879) (xy 408.229028 -274.220691)
			(xy 408.198807 -274.262287) (xy 408.162451 -274.298643) (xy 408.120855 -274.328864) (xy 408.075043 -274.352207)
			(xy 408.026144 -274.368095) (xy 407.975362 -274.376138) (xy 407.923946 -274.376138) (xy 407.873164 -274.368095)
			(xy 407.824265 -274.352207) (xy 407.778453 -274.328864) (xy 407.736857 -274.298643) (xy 407.700501 -274.262287)
			(xy 407.67028 -274.220691) (xy 407.646937 -274.174879) (xy 407.631049 -274.12598) (xy 407.623006 -274.075198)
			(xy 407.304623 -274.075198) (xy 407.296866 -274.122928) (xy 407.281282 -274.169609) (xy 407.258411 -274.213186)
			(xy 407.228846 -274.25253) (xy 407.193353 -274.286622) (xy 407.15285 -274.314578) (xy 407.108388 -274.335676)
			(xy 407.061117 -274.349368) (xy 407.012262 -274.3553) (xy 406.963087 -274.353319) (xy 406.914868 -274.343475)
			(xy 406.868852 -274.326023) (xy 406.826231 -274.301416) (xy 406.78811 -274.270291) (xy 406.755475 -274.233454)
			(xy 406.729172 -274.191858) (xy 406.709881 -274.146582) (xy 406.698104 -274.098798) (xy 406.694144 -274.049744)
			(xy 406.37714 -274.049744) (xy 406.376636 -274.075452) (xy 406.368593 -274.126234) (xy 406.352705 -274.175133)
			(xy 406.329362 -274.220945) (xy 406.299141 -274.262541) (xy 406.262785 -274.298897) (xy 406.221189 -274.329118)
			(xy 406.175377 -274.352461) (xy 406.126478 -274.368349) (xy 406.075696 -274.376392) (xy 406.02428 -274.376392)
			(xy 405.973498 -274.368349) (xy 405.924599 -274.352461) (xy 405.878787 -274.329118) (xy 405.837191 -274.298897)
			(xy 405.800835 -274.262541) (xy 405.770614 -274.220945) (xy 405.747271 -274.175133) (xy 405.731383 -274.126234)
			(xy 405.72334 -274.075452) (xy 405.404662 -274.075452) (xy 405.396946 -274.122928) (xy 405.381362 -274.169609)
			(xy 405.358491 -274.213186) (xy 405.328926 -274.25253) (xy 405.293433 -274.286622) (xy 405.25293 -274.314578)
			(xy 405.208468 -274.335676) (xy 405.161197 -274.349368) (xy 405.112342 -274.3553) (xy 405.063167 -274.353319)
			(xy 405.014948 -274.343475) (xy 404.968932 -274.326023) (xy 404.926311 -274.301416) (xy 404.88819 -274.270291)
			(xy 404.855555 -274.233454) (xy 404.829252 -274.191858) (xy 404.809961 -274.146582) (xy 404.798184 -274.098798)
			(xy 404.794224 -274.049744) (xy 404.476966 -274.049744) (xy 404.476462 -274.075452) (xy 404.468419 -274.126234)
			(xy 404.452531 -274.175133) (xy 404.429188 -274.220945) (xy 404.398967 -274.262541) (xy 404.362611 -274.298897)
			(xy 404.321015 -274.329118) (xy 404.275203 -274.352461) (xy 404.226304 -274.368349) (xy 404.175522 -274.376392)
			(xy 404.124106 -274.376392) (xy 404.073324 -274.368349) (xy 404.024425 -274.352461) (xy 403.978613 -274.329118)
			(xy 403.937017 -274.298897) (xy 403.900661 -274.262541) (xy 403.87044 -274.220945) (xy 403.847097 -274.175133)
			(xy 403.831209 -274.126234) (xy 403.823166 -274.075452) (xy 403.504488 -274.075452) (xy 403.496772 -274.122928)
			(xy 403.481188 -274.169609) (xy 403.458317 -274.213186) (xy 403.428752 -274.25253) (xy 403.393259 -274.286622)
			(xy 403.352756 -274.314578) (xy 403.308294 -274.335676) (xy 403.261023 -274.349368) (xy 403.212168 -274.3553)
			(xy 403.162993 -274.353319) (xy 403.114774 -274.343475) (xy 403.068758 -274.326023) (xy 403.026137 -274.301416)
			(xy 402.988016 -274.270291) (xy 402.955381 -274.233454) (xy 402.929078 -274.191858) (xy 402.909787 -274.146582)
			(xy 402.89801 -274.098798) (xy 402.89405 -274.049744) (xy 402.577046 -274.049744) (xy 402.576542 -274.075452)
			(xy 402.568499 -274.126234) (xy 402.552611 -274.175133) (xy 402.529268 -274.220945) (xy 402.499047 -274.262541)
			(xy 402.462691 -274.298897) (xy 402.421095 -274.329118) (xy 402.375283 -274.352461) (xy 402.326384 -274.368349)
			(xy 402.275602 -274.376392) (xy 402.224186 -274.376392) (xy 402.173404 -274.368349) (xy 402.124505 -274.352461)
			(xy 402.078693 -274.329118) (xy 402.037097 -274.298897) (xy 402.000741 -274.262541) (xy 401.97052 -274.220945)
			(xy 401.947177 -274.175133) (xy 401.931289 -274.126234) (xy 401.923246 -274.075452) (xy 401.604568 -274.075452)
			(xy 401.596852 -274.122928) (xy 401.581268 -274.169609) (xy 401.558397 -274.213186) (xy 401.528832 -274.25253)
			(xy 401.493339 -274.286622) (xy 401.452836 -274.314578) (xy 401.408374 -274.335676) (xy 401.361103 -274.349368)
			(xy 401.312248 -274.3553) (xy 401.263073 -274.353319) (xy 401.214854 -274.343475) (xy 401.168838 -274.326023)
			(xy 401.126217 -274.301416) (xy 401.088096 -274.270291) (xy 401.055461 -274.233454) (xy 401.029158 -274.191858)
			(xy 401.009867 -274.146582) (xy 400.99809 -274.098798) (xy 400.99413 -274.049744) (xy 400.677126 -274.049744)
			(xy 400.676622 -274.075452) (xy 400.668579 -274.126234) (xy 400.652691 -274.175133) (xy 400.629348 -274.220945)
			(xy 400.599127 -274.262541) (xy 400.562771 -274.298897) (xy 400.521175 -274.329118) (xy 400.475363 -274.352461)
			(xy 400.426464 -274.368349) (xy 400.375682 -274.376392) (xy 400.324266 -274.376392) (xy 400.273484 -274.368349)
			(xy 400.224585 -274.352461) (xy 400.178773 -274.329118) (xy 400.137177 -274.298897) (xy 400.100821 -274.262541)
			(xy 400.0706 -274.220945) (xy 400.047257 -274.175133) (xy 400.031369 -274.126234) (xy 400.023326 -274.075452)
			(xy 399.704648 -274.075452) (xy 399.696932 -274.122928) (xy 399.681348 -274.169609) (xy 399.658477 -274.213186)
			(xy 399.628912 -274.25253) (xy 399.593419 -274.286622) (xy 399.552916 -274.314578) (xy 399.508454 -274.335676)
			(xy 399.461183 -274.349368) (xy 399.412328 -274.3553) (xy 399.363153 -274.353319) (xy 399.314934 -274.343475)
			(xy 399.268918 -274.326023) (xy 399.226297 -274.301416) (xy 399.188176 -274.270291) (xy 399.155541 -274.233454)
			(xy 399.129238 -274.191858) (xy 399.109947 -274.146582) (xy 399.09817 -274.098798) (xy 399.09421 -274.049744)
			(xy 398.776952 -274.049744) (xy 398.776448 -274.075452) (xy 398.768405 -274.126234) (xy 398.752517 -274.175133)
			(xy 398.729174 -274.220945) (xy 398.698953 -274.262541) (xy 398.662597 -274.298897) (xy 398.621001 -274.329118)
			(xy 398.575189 -274.352461) (xy 398.52629 -274.368349) (xy 398.475508 -274.376392) (xy 398.424092 -274.376392)
			(xy 398.37331 -274.368349) (xy 398.324411 -274.352461) (xy 398.278599 -274.329118) (xy 398.237003 -274.298897)
			(xy 398.200647 -274.262541) (xy 398.170426 -274.220945) (xy 398.147083 -274.175133) (xy 398.131195 -274.126234)
			(xy 398.123152 -274.075452) (xy 397.804474 -274.075452) (xy 397.796758 -274.122928) (xy 397.781174 -274.169609)
			(xy 397.758303 -274.213186) (xy 397.728738 -274.25253) (xy 397.693245 -274.286622) (xy 397.652742 -274.314578)
			(xy 397.60828 -274.335676) (xy 397.561009 -274.349368) (xy 397.512154 -274.3553) (xy 397.462979 -274.353319)
			(xy 397.41476 -274.343475) (xy 397.368744 -274.326023) (xy 397.326123 -274.301416) (xy 397.288002 -274.270291)
			(xy 397.255367 -274.233454) (xy 397.229064 -274.191858) (xy 397.209773 -274.146582) (xy 397.197996 -274.098798)
			(xy 397.194036 -274.049744) (xy 396.877032 -274.049744) (xy 396.876528 -274.075452) (xy 396.868485 -274.126234)
			(xy 396.852597 -274.175133) (xy 396.829254 -274.220945) (xy 396.799033 -274.262541) (xy 396.762677 -274.298897)
			(xy 396.721081 -274.329118) (xy 396.675269 -274.352461) (xy 396.62637 -274.368349) (xy 396.575588 -274.376392)
			(xy 396.524172 -274.376392) (xy 396.47339 -274.368349) (xy 396.424491 -274.352461) (xy 396.378679 -274.329118)
			(xy 396.337083 -274.298897) (xy 396.300727 -274.262541) (xy 396.270506 -274.220945) (xy 396.247163 -274.175133)
			(xy 396.231275 -274.126234) (xy 396.223232 -274.075452) (xy 395.904554 -274.075452) (xy 395.896838 -274.122928)
			(xy 395.881254 -274.169609) (xy 395.858383 -274.213186) (xy 395.828818 -274.25253) (xy 395.793325 -274.286622)
			(xy 395.752822 -274.314578) (xy 395.70836 -274.335676) (xy 395.661089 -274.349368) (xy 395.612234 -274.3553)
			(xy 395.563059 -274.353319) (xy 395.51484 -274.343475) (xy 395.468824 -274.326023) (xy 395.426203 -274.301416)
			(xy 395.388082 -274.270291) (xy 395.355447 -274.233454) (xy 395.329144 -274.191858) (xy 395.309853 -274.146582)
			(xy 395.298076 -274.098798) (xy 395.294116 -274.049744) (xy 394.977112 -274.049744) (xy 394.976608 -274.075452)
			(xy 394.968565 -274.126234) (xy 394.952677 -274.175133) (xy 394.929334 -274.220945) (xy 394.899113 -274.262541)
			(xy 394.862757 -274.298897) (xy 394.821161 -274.329118) (xy 394.775349 -274.352461) (xy 394.72645 -274.368349)
			(xy 394.675668 -274.376392) (xy 394.624252 -274.376392) (xy 394.57347 -274.368349) (xy 394.524571 -274.352461)
			(xy 394.478759 -274.329118) (xy 394.437163 -274.298897) (xy 394.400807 -274.262541) (xy 394.370586 -274.220945)
			(xy 394.347243 -274.175133) (xy 394.331355 -274.126234) (xy 394.323312 -274.075452) (xy 394.004634 -274.075452)
			(xy 393.996918 -274.122928) (xy 393.981334 -274.169609) (xy 393.958463 -274.213186) (xy 393.928898 -274.25253)
			(xy 393.893405 -274.286622) (xy 393.852902 -274.314578) (xy 393.80844 -274.335676) (xy 393.761169 -274.349368)
			(xy 393.712314 -274.3553) (xy 393.663139 -274.353319) (xy 393.61492 -274.343475) (xy 393.568904 -274.326023)
			(xy 393.526283 -274.301416) (xy 393.488162 -274.270291) (xy 393.455527 -274.233454) (xy 393.429224 -274.191858)
			(xy 393.409933 -274.146582) (xy 393.398156 -274.098798) (xy 393.394196 -274.049744) (xy 393.076938 -274.049744)
			(xy 393.076434 -274.075452) (xy 393.068391 -274.126234) (xy 393.052503 -274.175133) (xy 393.02916 -274.220945)
			(xy 392.998939 -274.262541) (xy 392.962583 -274.298897) (xy 392.920987 -274.329118) (xy 392.875175 -274.352461)
			(xy 392.826276 -274.368349) (xy 392.775494 -274.376392) (xy 392.724078 -274.376392) (xy 392.673296 -274.368349)
			(xy 392.624397 -274.352461) (xy 392.578585 -274.329118) (xy 392.536989 -274.298897) (xy 392.500633 -274.262541)
			(xy 392.470412 -274.220945) (xy 392.447069 -274.175133) (xy 392.431181 -274.126234) (xy 392.423138 -274.075452)
			(xy 383.78638 -274.075452) (xy 383.78638 -274.524724) (xy 385.319028 -274.524724) (xy 385.322988 -274.47567)
			(xy 385.334765 -274.427886) (xy 385.354056 -274.38261) (xy 385.380359 -274.341014) (xy 385.412994 -274.304177)
			(xy 385.451115 -274.273052) (xy 385.493736 -274.248445) (xy 385.539752 -274.230993) (xy 385.587971 -274.221149)
			(xy 385.637146 -274.219168) (xy 385.686001 -274.2251) (xy 385.733272 -274.238792) (xy 385.777734 -274.25989)
			(xy 385.818237 -274.287846) (xy 385.85373 -274.321938) (xy 385.883295 -274.361282) (xy 385.906166 -274.404859)
			(xy 385.92175 -274.45154) (xy 385.929645 -274.500117) (xy 385.93014 -274.524724) (xy 385.930135 -274.524978)
			(xy 386.269242 -274.524978) (xy 386.273202 -274.475924) (xy 386.284979 -274.42814) (xy 386.30427 -274.382864)
			(xy 386.330573 -274.341268) (xy 386.363208 -274.304431) (xy 386.401329 -274.273306) (xy 386.44395 -274.248699)
			(xy 386.489966 -274.231247) (xy 386.538185 -274.221403) (xy 386.58736 -274.219422) (xy 386.636215 -274.225354)
			(xy 386.683486 -274.239046) (xy 386.727948 -274.260144) (xy 386.768451 -274.2881) (xy 386.803944 -274.322192)
			(xy 386.833509 -274.361536) (xy 386.85638 -274.405113) (xy 386.871964 -274.451794) (xy 386.879859 -274.500371)
			(xy 386.880354 -274.524978) (xy 387.219202 -274.524978) (xy 387.223162 -274.475924) (xy 387.234939 -274.42814)
			(xy 387.25423 -274.382864) (xy 387.280533 -274.341268) (xy 387.313168 -274.304431) (xy 387.351289 -274.273306)
			(xy 387.39391 -274.248699) (xy 387.439926 -274.231247) (xy 387.488145 -274.221403) (xy 387.53732 -274.219422)
			(xy 387.586175 -274.225354) (xy 387.633446 -274.239046) (xy 387.677908 -274.260144) (xy 387.718411 -274.2881)
			(xy 387.753904 -274.322192) (xy 387.783469 -274.361536) (xy 387.80634 -274.405113) (xy 387.821924 -274.451794)
			(xy 387.829819 -274.500371) (xy 387.830314 -274.524978) (xy 388.169162 -274.524978) (xy 388.173122 -274.475924)
			(xy 388.184899 -274.42814) (xy 388.20419 -274.382864) (xy 388.230493 -274.341268) (xy 388.263128 -274.304431)
			(xy 388.301249 -274.273306) (xy 388.34387 -274.248699) (xy 388.389886 -274.231247) (xy 388.438105 -274.221403)
			(xy 388.48728 -274.219422) (xy 388.536135 -274.225354) (xy 388.583406 -274.239046) (xy 388.627868 -274.260144)
			(xy 388.668371 -274.2881) (xy 388.703864 -274.322192) (xy 388.733429 -274.361536) (xy 388.7563 -274.405113)
			(xy 388.771884 -274.451794) (xy 388.779779 -274.500371) (xy 388.780274 -274.524978) (xy 389.119122 -274.524978)
			(xy 389.123082 -274.475924) (xy 389.134859 -274.42814) (xy 389.15415 -274.382864) (xy 389.180453 -274.341268)
			(xy 389.213088 -274.304431) (xy 389.251209 -274.273306) (xy 389.29383 -274.248699) (xy 389.339846 -274.231247)
			(xy 389.388065 -274.221403) (xy 389.43724 -274.219422) (xy 389.486095 -274.225354) (xy 389.533366 -274.239046)
			(xy 389.577828 -274.260144) (xy 389.618331 -274.2881) (xy 389.653824 -274.322192) (xy 389.683389 -274.361536)
			(xy 389.70626 -274.405113) (xy 389.721844 -274.451794) (xy 389.729739 -274.500371) (xy 389.730234 -274.524978)
			(xy 390.069082 -274.524978) (xy 390.073042 -274.475924) (xy 390.084819 -274.42814) (xy 390.10411 -274.382864)
			(xy 390.130413 -274.341268) (xy 390.163048 -274.304431) (xy 390.201169 -274.273306) (xy 390.24379 -274.248699)
			(xy 390.289806 -274.231247) (xy 390.338025 -274.221403) (xy 390.3872 -274.219422) (xy 390.436055 -274.225354)
			(xy 390.483326 -274.239046) (xy 390.527788 -274.260144) (xy 390.568291 -274.2881) (xy 390.603784 -274.322192)
			(xy 390.633349 -274.361536) (xy 390.65622 -274.405113) (xy 390.671804 -274.451794) (xy 390.679699 -274.500371)
			(xy 390.680194 -274.524978) (xy 391.019042 -274.524978) (xy 391.023002 -274.475924) (xy 391.034779 -274.42814)
			(xy 391.05407 -274.382864) (xy 391.080373 -274.341268) (xy 391.113008 -274.304431) (xy 391.151129 -274.273306)
			(xy 391.19375 -274.248699) (xy 391.239766 -274.231247) (xy 391.287985 -274.221403) (xy 391.33716 -274.219422)
			(xy 391.386015 -274.225354) (xy 391.433286 -274.239046) (xy 391.477748 -274.260144) (xy 391.518251 -274.2881)
			(xy 391.553744 -274.322192) (xy 391.583309 -274.361536) (xy 391.60618 -274.405113) (xy 391.621764 -274.451794)
			(xy 391.629659 -274.500371) (xy 391.630154 -274.524978) (xy 391.629659 -274.549585) (xy 391.621764 -274.598162)
			(xy 391.60618 -274.644843) (xy 391.583309 -274.68842) (xy 391.553744 -274.727764) (xy 391.518251 -274.761856)
			(xy 391.477748 -274.789812) (xy 391.433286 -274.81091) (xy 391.386015 -274.824602) (xy 391.33716 -274.830534)
			(xy 391.287985 -274.828553) (xy 391.239766 -274.818709) (xy 391.19375 -274.801257) (xy 391.151129 -274.77665)
			(xy 391.113008 -274.745525) (xy 391.080373 -274.708688) (xy 391.05407 -274.667092) (xy 391.034779 -274.621816)
			(xy 391.023002 -274.574032) (xy 391.019042 -274.524978) (xy 390.680194 -274.524978) (xy 390.679699 -274.549585)
			(xy 390.671804 -274.598162) (xy 390.65622 -274.644843) (xy 390.633349 -274.68842) (xy 390.603784 -274.727764)
			(xy 390.568291 -274.761856) (xy 390.527788 -274.789812) (xy 390.483326 -274.81091) (xy 390.436055 -274.824602)
			(xy 390.3872 -274.830534) (xy 390.338025 -274.828553) (xy 390.289806 -274.818709) (xy 390.24379 -274.801257)
			(xy 390.201169 -274.77665) (xy 390.163048 -274.745525) (xy 390.130413 -274.708688) (xy 390.10411 -274.667092)
			(xy 390.084819 -274.621816) (xy 390.073042 -274.574032) (xy 390.069082 -274.524978) (xy 389.730234 -274.524978)
			(xy 389.729739 -274.549585) (xy 389.721844 -274.598162) (xy 389.70626 -274.644843) (xy 389.683389 -274.68842)
			(xy 389.653824 -274.727764) (xy 389.618331 -274.761856) (xy 389.577828 -274.789812) (xy 389.533366 -274.81091)
			(xy 389.486095 -274.824602) (xy 389.43724 -274.830534) (xy 389.388065 -274.828553) (xy 389.339846 -274.818709)
			(xy 389.29383 -274.801257) (xy 389.251209 -274.77665) (xy 389.213088 -274.745525) (xy 389.180453 -274.708688)
			(xy 389.15415 -274.667092) (xy 389.134859 -274.621816) (xy 389.123082 -274.574032) (xy 389.119122 -274.524978)
			(xy 388.780274 -274.524978) (xy 388.779779 -274.549585) (xy 388.771884 -274.598162) (xy 388.7563 -274.644843)
			(xy 388.733429 -274.68842) (xy 388.703864 -274.727764) (xy 388.668371 -274.761856) (xy 388.627868 -274.789812)
			(xy 388.583406 -274.81091) (xy 388.536135 -274.824602) (xy 388.48728 -274.830534) (xy 388.438105 -274.828553)
			(xy 388.389886 -274.818709) (xy 388.34387 -274.801257) (xy 388.301249 -274.77665) (xy 388.263128 -274.745525)
			(xy 388.230493 -274.708688) (xy 388.20419 -274.667092) (xy 388.184899 -274.621816) (xy 388.173122 -274.574032)
			(xy 388.169162 -274.524978) (xy 387.830314 -274.524978) (xy 387.829819 -274.549585) (xy 387.821924 -274.598162)
			(xy 387.80634 -274.644843) (xy 387.783469 -274.68842) (xy 387.753904 -274.727764) (xy 387.718411 -274.761856)
			(xy 387.677908 -274.789812) (xy 387.633446 -274.81091) (xy 387.586175 -274.824602) (xy 387.53732 -274.830534)
			(xy 387.488145 -274.828553) (xy 387.439926 -274.818709) (xy 387.39391 -274.801257) (xy 387.351289 -274.77665)
			(xy 387.313168 -274.745525) (xy 387.280533 -274.708688) (xy 387.25423 -274.667092) (xy 387.234939 -274.621816)
			(xy 387.223162 -274.574032) (xy 387.219202 -274.524978) (xy 386.880354 -274.524978) (xy 386.879859 -274.549585)
			(xy 386.871964 -274.598162) (xy 386.85638 -274.644843) (xy 386.833509 -274.68842) (xy 386.803944 -274.727764)
			(xy 386.768451 -274.761856) (xy 386.727948 -274.789812) (xy 386.683486 -274.81091) (xy 386.636215 -274.824602)
			(xy 386.58736 -274.830534) (xy 386.538185 -274.828553) (xy 386.489966 -274.818709) (xy 386.44395 -274.801257)
			(xy 386.401329 -274.77665) (xy 386.363208 -274.745525) (xy 386.330573 -274.708688) (xy 386.30427 -274.667092)
			(xy 386.284979 -274.621816) (xy 386.273202 -274.574032) (xy 386.269242 -274.524978) (xy 385.930135 -274.524978)
			(xy 385.929645 -274.549331) (xy 385.92175 -274.597908) (xy 385.906166 -274.644589) (xy 385.883295 -274.688166)
			(xy 385.85373 -274.72751) (xy 385.818237 -274.761602) (xy 385.777734 -274.789558) (xy 385.733272 -274.810656)
			(xy 385.686001 -274.824348) (xy 385.637146 -274.83028) (xy 385.587971 -274.828299) (xy 385.539752 -274.818455)
			(xy 385.493736 -274.801003) (xy 385.451115 -274.776396) (xy 385.412994 -274.745271) (xy 385.380359 -274.708434)
			(xy 385.354056 -274.666838) (xy 385.334765 -274.621562) (xy 385.322988 -274.573778) (xy 385.319028 -274.524724)
			(xy 383.78638 -274.524724) (xy 383.78638 -274.999958) (xy 392.443982 -274.999958) (xy 392.447942 -274.950904)
			(xy 392.459719 -274.90312) (xy 392.47901 -274.857844) (xy 392.505313 -274.816248) (xy 392.537948 -274.779411)
			(xy 392.576069 -274.748286) (xy 392.61869 -274.723679) (xy 392.664706 -274.706227) (xy 392.712925 -274.696383)
			(xy 392.7621 -274.694402) (xy 392.810955 -274.700334) (xy 392.858226 -274.714026) (xy 392.902688 -274.735124)
			(xy 392.943191 -274.76308) (xy 392.978684 -274.797172) (xy 393.008249 -274.836516) (xy 393.03112 -274.880093)
			(xy 393.046704 -274.926774) (xy 393.054599 -274.975351) (xy 393.055094 -274.999958) (xy 393.054599 -275.024565)
			(xy 393.05442 -275.025666) (xy 393.373352 -275.025666) (xy 393.373352 -274.97425) (xy 393.381395 -274.923468)
			(xy 393.397283 -274.874569) (xy 393.420626 -274.828757) (xy 393.450847 -274.787161) (xy 393.487203 -274.750805)
			(xy 393.528799 -274.720584) (xy 393.574611 -274.697241) (xy 393.62351 -274.681353) (xy 393.674292 -274.67331)
			(xy 393.725708 -274.67331) (xy 393.77649 -274.681353) (xy 393.825389 -274.697241) (xy 393.871201 -274.720584)
			(xy 393.912797 -274.750805) (xy 393.949153 -274.787161) (xy 393.979374 -274.828757) (xy 394.002717 -274.874569)
			(xy 394.018605 -274.923468) (xy 394.026648 -274.97425) (xy 394.027152 -274.999958) (xy 394.344156 -274.999958)
			(xy 394.348116 -274.950904) (xy 394.359893 -274.90312) (xy 394.379184 -274.857844) (xy 394.405487 -274.816248)
			(xy 394.438122 -274.779411) (xy 394.476243 -274.748286) (xy 394.518864 -274.723679) (xy 394.56488 -274.706227)
			(xy 394.613099 -274.696383) (xy 394.662274 -274.694402) (xy 394.711129 -274.700334) (xy 394.7584 -274.714026)
			(xy 394.802862 -274.735124) (xy 394.843365 -274.76308) (xy 394.878858 -274.797172) (xy 394.908423 -274.836516)
			(xy 394.931294 -274.880093) (xy 394.946878 -274.926774) (xy 394.954773 -274.975351) (xy 394.955268 -274.999958)
			(xy 394.954773 -275.024565) (xy 394.954594 -275.025666) (xy 395.273272 -275.025666) (xy 395.273272 -274.97425)
			(xy 395.281315 -274.923468) (xy 395.297203 -274.874569) (xy 395.320546 -274.828757) (xy 395.350767 -274.787161)
			(xy 395.387123 -274.750805) (xy 395.428719 -274.720584) (xy 395.474531 -274.697241) (xy 395.52343 -274.681353)
			(xy 395.574212 -274.67331) (xy 395.625628 -274.67331) (xy 395.67641 -274.681353) (xy 395.725309 -274.697241)
			(xy 395.771121 -274.720584) (xy 395.812717 -274.750805) (xy 395.849073 -274.787161) (xy 395.879294 -274.828757)
			(xy 395.902637 -274.874569) (xy 395.918525 -274.923468) (xy 395.926568 -274.97425) (xy 395.927072 -274.999958)
			(xy 396.244076 -274.999958) (xy 396.248036 -274.950904) (xy 396.259813 -274.90312) (xy 396.279104 -274.857844)
			(xy 396.305407 -274.816248) (xy 396.338042 -274.779411) (xy 396.376163 -274.748286) (xy 396.418784 -274.723679)
			(xy 396.4648 -274.706227) (xy 396.513019 -274.696383) (xy 396.562194 -274.694402) (xy 396.611049 -274.700334)
			(xy 396.65832 -274.714026) (xy 396.702782 -274.735124) (xy 396.743285 -274.76308) (xy 396.778778 -274.797172)
			(xy 396.808343 -274.836516) (xy 396.831214 -274.880093) (xy 396.846798 -274.926774) (xy 396.854693 -274.975351)
			(xy 396.855188 -274.999958) (xy 396.854693 -275.024565) (xy 396.854514 -275.025666) (xy 397.173192 -275.025666)
			(xy 397.173192 -274.97425) (xy 397.181235 -274.923468) (xy 397.197123 -274.874569) (xy 397.220466 -274.828757)
			(xy 397.250687 -274.787161) (xy 397.287043 -274.750805) (xy 397.328639 -274.720584) (xy 397.374451 -274.697241)
			(xy 397.42335 -274.681353) (xy 397.474132 -274.67331) (xy 397.525548 -274.67331) (xy 397.57633 -274.681353)
			(xy 397.625229 -274.697241) (xy 397.671041 -274.720584) (xy 397.712637 -274.750805) (xy 397.748993 -274.787161)
			(xy 397.779214 -274.828757) (xy 397.802557 -274.874569) (xy 397.818445 -274.923468) (xy 397.826488 -274.97425)
			(xy 397.826992 -274.999958) (xy 398.143996 -274.999958) (xy 398.147956 -274.950904) (xy 398.159733 -274.90312)
			(xy 398.179024 -274.857844) (xy 398.205327 -274.816248) (xy 398.237962 -274.779411) (xy 398.276083 -274.748286)
			(xy 398.318704 -274.723679) (xy 398.36472 -274.706227) (xy 398.412939 -274.696383) (xy 398.462114 -274.694402)
			(xy 398.510969 -274.700334) (xy 398.55824 -274.714026) (xy 398.602702 -274.735124) (xy 398.643205 -274.76308)
			(xy 398.678698 -274.797172) (xy 398.708263 -274.836516) (xy 398.731134 -274.880093) (xy 398.746718 -274.926774)
			(xy 398.754613 -274.975351) (xy 398.755108 -274.999958) (xy 398.754613 -275.024565) (xy 398.754434 -275.025666)
			(xy 399.073366 -275.025666) (xy 399.073366 -274.97425) (xy 399.081409 -274.923468) (xy 399.097297 -274.874569)
			(xy 399.12064 -274.828757) (xy 399.150861 -274.787161) (xy 399.187217 -274.750805) (xy 399.228813 -274.720584)
			(xy 399.274625 -274.697241) (xy 399.323524 -274.681353) (xy 399.374306 -274.67331) (xy 399.425722 -274.67331)
			(xy 399.476504 -274.681353) (xy 399.525403 -274.697241) (xy 399.571215 -274.720584) (xy 399.612811 -274.750805)
			(xy 399.649167 -274.787161) (xy 399.679388 -274.828757) (xy 399.702731 -274.874569) (xy 399.718619 -274.923468)
			(xy 399.726662 -274.97425) (xy 399.727166 -274.999958) (xy 400.04417 -274.999958) (xy 400.04813 -274.950904)
			(xy 400.059907 -274.90312) (xy 400.079198 -274.857844) (xy 400.105501 -274.816248) (xy 400.138136 -274.779411)
			(xy 400.176257 -274.748286) (xy 400.218878 -274.723679) (xy 400.264894 -274.706227) (xy 400.313113 -274.696383)
			(xy 400.362288 -274.694402) (xy 400.411143 -274.700334) (xy 400.458414 -274.714026) (xy 400.502876 -274.735124)
			(xy 400.543379 -274.76308) (xy 400.578872 -274.797172) (xy 400.608437 -274.836516) (xy 400.631308 -274.880093)
			(xy 400.646892 -274.926774) (xy 400.654787 -274.975351) (xy 400.655282 -274.999958) (xy 400.654787 -275.024565)
			(xy 400.654608 -275.025666) (xy 400.973286 -275.025666) (xy 400.973286 -274.97425) (xy 400.981329 -274.923468)
			(xy 400.997217 -274.874569) (xy 401.02056 -274.828757) (xy 401.050781 -274.787161) (xy 401.087137 -274.750805)
			(xy 401.128733 -274.720584) (xy 401.174545 -274.697241) (xy 401.223444 -274.681353) (xy 401.274226 -274.67331)
			(xy 401.325642 -274.67331) (xy 401.376424 -274.681353) (xy 401.425323 -274.697241) (xy 401.471135 -274.720584)
			(xy 401.512731 -274.750805) (xy 401.549087 -274.787161) (xy 401.579308 -274.828757) (xy 401.602651 -274.874569)
			(xy 401.618539 -274.923468) (xy 401.626582 -274.97425) (xy 401.627086 -274.999958) (xy 401.94409 -274.999958)
			(xy 401.94805 -274.950904) (xy 401.959827 -274.90312) (xy 401.979118 -274.857844) (xy 402.005421 -274.816248)
			(xy 402.038056 -274.779411) (xy 402.076177 -274.748286) (xy 402.118798 -274.723679) (xy 402.164814 -274.706227)
			(xy 402.213033 -274.696383) (xy 402.262208 -274.694402) (xy 402.311063 -274.700334) (xy 402.358334 -274.714026)
			(xy 402.402796 -274.735124) (xy 402.443299 -274.76308) (xy 402.478792 -274.797172) (xy 402.508357 -274.836516)
			(xy 402.531228 -274.880093) (xy 402.546812 -274.926774) (xy 402.554707 -274.975351) (xy 402.555202 -274.999958)
			(xy 402.554707 -275.024565) (xy 402.554528 -275.025666) (xy 402.873206 -275.025666) (xy 402.873206 -274.97425)
			(xy 402.881249 -274.923468) (xy 402.897137 -274.874569) (xy 402.92048 -274.828757) (xy 402.950701 -274.787161)
			(xy 402.987057 -274.750805) (xy 403.028653 -274.720584) (xy 403.074465 -274.697241) (xy 403.123364 -274.681353)
			(xy 403.174146 -274.67331) (xy 403.225562 -274.67331) (xy 403.276344 -274.681353) (xy 403.325243 -274.697241)
			(xy 403.371055 -274.720584) (xy 403.412651 -274.750805) (xy 403.449007 -274.787161) (xy 403.479228 -274.828757)
			(xy 403.502571 -274.874569) (xy 403.518459 -274.923468) (xy 403.526502 -274.97425) (xy 403.527006 -274.999958)
			(xy 403.84401 -274.999958) (xy 403.84797 -274.950904) (xy 403.859747 -274.90312) (xy 403.879038 -274.857844)
			(xy 403.905341 -274.816248) (xy 403.937976 -274.779411) (xy 403.976097 -274.748286) (xy 404.018718 -274.723679)
			(xy 404.064734 -274.706227) (xy 404.112953 -274.696383) (xy 404.162128 -274.694402) (xy 404.210983 -274.700334)
			(xy 404.258254 -274.714026) (xy 404.302716 -274.735124) (xy 404.343219 -274.76308) (xy 404.378712 -274.797172)
			(xy 404.408277 -274.836516) (xy 404.431148 -274.880093) (xy 404.446732 -274.926774) (xy 404.454627 -274.975351)
			(xy 404.455122 -274.999958) (xy 404.454627 -275.024565) (xy 404.454448 -275.025666) (xy 404.77338 -275.025666)
			(xy 404.77338 -274.97425) (xy 404.781423 -274.923468) (xy 404.797311 -274.874569) (xy 404.820654 -274.828757)
			(xy 404.850875 -274.787161) (xy 404.887231 -274.750805) (xy 404.928827 -274.720584) (xy 404.974639 -274.697241)
			(xy 405.023538 -274.681353) (xy 405.07432 -274.67331) (xy 405.125736 -274.67331) (xy 405.176518 -274.681353)
			(xy 405.225417 -274.697241) (xy 405.271229 -274.720584) (xy 405.312825 -274.750805) (xy 405.349181 -274.787161)
			(xy 405.379402 -274.828757) (xy 405.402745 -274.874569) (xy 405.418633 -274.923468) (xy 405.426676 -274.97425)
			(xy 405.42718 -274.999958) (xy 405.744184 -274.999958) (xy 405.748144 -274.950904) (xy 405.759921 -274.90312)
			(xy 405.779212 -274.857844) (xy 405.805515 -274.816248) (xy 405.83815 -274.779411) (xy 405.876271 -274.748286)
			(xy 405.918892 -274.723679) (xy 405.964908 -274.706227) (xy 406.013127 -274.696383) (xy 406.062302 -274.694402)
			(xy 406.111157 -274.700334) (xy 406.158428 -274.714026) (xy 406.20289 -274.735124) (xy 406.243393 -274.76308)
			(xy 406.278886 -274.797172) (xy 406.308451 -274.836516) (xy 406.331322 -274.880093) (xy 406.346906 -274.926774)
			(xy 406.354801 -274.975351) (xy 406.355296 -274.999958) (xy 406.354801 -275.024565) (xy 406.354622 -275.025666)
			(xy 406.6733 -275.025666) (xy 406.6733 -274.97425) (xy 406.681343 -274.923468) (xy 406.697231 -274.874569)
			(xy 406.720574 -274.828757) (xy 406.750795 -274.787161) (xy 406.787151 -274.750805) (xy 406.828747 -274.720584)
			(xy 406.874559 -274.697241) (xy 406.923458 -274.681353) (xy 406.97424 -274.67331) (xy 407.025656 -274.67331)
			(xy 407.076438 -274.681353) (xy 407.125337 -274.697241) (xy 407.171149 -274.720584) (xy 407.212745 -274.750805)
			(xy 407.249101 -274.787161) (xy 407.279322 -274.828757) (xy 407.302665 -274.874569) (xy 407.318553 -274.923468)
			(xy 407.326596 -274.97425) (xy 407.3271 -274.999958) (xy 407.644104 -274.999958) (xy 407.648064 -274.950904)
			(xy 407.659841 -274.90312) (xy 407.679132 -274.857844) (xy 407.705435 -274.816248) (xy 407.73807 -274.779411)
			(xy 407.776191 -274.748286) (xy 407.818812 -274.723679) (xy 407.864828 -274.706227) (xy 407.913047 -274.696383)
			(xy 407.962222 -274.694402) (xy 408.011077 -274.700334) (xy 408.058348 -274.714026) (xy 408.10281 -274.735124)
			(xy 408.143313 -274.76308) (xy 408.178806 -274.797172) (xy 408.208371 -274.836516) (xy 408.231242 -274.880093)
			(xy 408.246826 -274.926774) (xy 408.254721 -274.975351) (xy 408.255216 -274.999958) (xy 408.254721 -275.024565)
			(xy 408.254583 -275.025412) (xy 408.572966 -275.025412) (xy 408.572966 -274.973996) (xy 408.581009 -274.923214)
			(xy 408.596897 -274.874315) (xy 408.62024 -274.828503) (xy 408.650461 -274.786907) (xy 408.686817 -274.750551)
			(xy 408.728413 -274.72033) (xy 408.774225 -274.696987) (xy 408.823124 -274.681099) (xy 408.873906 -274.673056)
			(xy 408.925322 -274.673056) (xy 408.976104 -274.681099) (xy 409.025003 -274.696987) (xy 409.070815 -274.72033)
			(xy 409.112411 -274.750551) (xy 409.148767 -274.786907) (xy 409.178988 -274.828503) (xy 409.202331 -274.874315)
			(xy 409.218219 -274.923214) (xy 409.226262 -274.973996) (xy 409.226766 -274.999704) (xy 409.226761 -274.999958)
			(xy 409.544024 -274.999958) (xy 409.547984 -274.950904) (xy 409.559761 -274.90312) (xy 409.579052 -274.857844)
			(xy 409.605355 -274.816248) (xy 409.63799 -274.779411) (xy 409.676111 -274.748286) (xy 409.718732 -274.723679)
			(xy 409.764748 -274.706227) (xy 409.812967 -274.696383) (xy 409.862142 -274.694402) (xy 409.910997 -274.700334)
			(xy 409.958268 -274.714026) (xy 410.00273 -274.735124) (xy 410.043233 -274.76308) (xy 410.078726 -274.797172)
			(xy 410.108291 -274.836516) (xy 410.131162 -274.880093) (xy 410.146746 -274.926774) (xy 410.154641 -274.975351)
			(xy 410.155136 -274.999958) (xy 410.154641 -275.024565) (xy 410.154462 -275.025666) (xy 410.472886 -275.025666)
			(xy 410.472886 -274.97425) (xy 410.480929 -274.923468) (xy 410.496817 -274.874569) (xy 410.52016 -274.828757)
			(xy 410.550381 -274.787161) (xy 410.586737 -274.750805) (xy 410.628333 -274.720584) (xy 410.674145 -274.697241)
			(xy 410.723044 -274.681353) (xy 410.773826 -274.67331) (xy 410.825242 -274.67331) (xy 410.876024 -274.681353)
			(xy 410.924923 -274.697241) (xy 410.970735 -274.720584) (xy 411.012331 -274.750805) (xy 411.048687 -274.787161)
			(xy 411.078908 -274.828757) (xy 411.102251 -274.874569) (xy 411.118139 -274.923468) (xy 411.126182 -274.97425)
			(xy 411.126686 -274.999958) (xy 411.444198 -274.999958) (xy 411.448158 -274.950904) (xy 411.459935 -274.90312)
			(xy 411.479226 -274.857844) (xy 411.505529 -274.816248) (xy 411.538164 -274.779411) (xy 411.576285 -274.748286)
			(xy 411.618906 -274.723679) (xy 411.664922 -274.706227) (xy 411.713141 -274.696383) (xy 411.762316 -274.694402)
			(xy 411.811171 -274.700334) (xy 411.858442 -274.714026) (xy 411.902904 -274.735124) (xy 411.943407 -274.76308)
			(xy 411.9789 -274.797172) (xy 412.008465 -274.836516) (xy 412.031336 -274.880093) (xy 412.04692 -274.926774)
			(xy 412.054815 -274.975351) (xy 412.05531 -274.999958) (xy 412.054815 -275.024565) (xy 412.054677 -275.025412)
			(xy 412.37306 -275.025412) (xy 412.37306 -274.973996) (xy 412.381103 -274.923214) (xy 412.396991 -274.874315)
			(xy 412.420334 -274.828503) (xy 412.450555 -274.786907) (xy 412.486911 -274.750551) (xy 412.528507 -274.72033)
			(xy 412.574319 -274.696987) (xy 412.623218 -274.681099) (xy 412.674 -274.673056) (xy 412.725416 -274.673056)
			(xy 412.776198 -274.681099) (xy 412.825097 -274.696987) (xy 412.870909 -274.72033) (xy 412.912505 -274.750551)
			(xy 412.948861 -274.786907) (xy 412.979082 -274.828503) (xy 413.002425 -274.874315) (xy 413.018313 -274.923214)
			(xy 413.026356 -274.973996) (xy 413.02686 -274.999704) (xy 413.026855 -274.999958) (xy 413.344118 -274.999958)
			(xy 413.348078 -274.950904) (xy 413.359855 -274.90312) (xy 413.379146 -274.857844) (xy 413.405449 -274.816248)
			(xy 413.438084 -274.779411) (xy 413.476205 -274.748286) (xy 413.518826 -274.723679) (xy 413.564842 -274.706227)
			(xy 413.613061 -274.696383) (xy 413.662236 -274.694402) (xy 413.711091 -274.700334) (xy 413.758362 -274.714026)
			(xy 413.802824 -274.735124) (xy 413.843327 -274.76308) (xy 413.87882 -274.797172) (xy 413.908385 -274.836516)
			(xy 413.931256 -274.880093) (xy 413.94684 -274.926774) (xy 413.954735 -274.975351) (xy 413.95523 -274.999958)
			(xy 413.954735 -275.024565) (xy 413.954556 -275.025666) (xy 414.27298 -275.025666) (xy 414.27298 -274.97425)
			(xy 414.281023 -274.923468) (xy 414.296911 -274.874569) (xy 414.320254 -274.828757) (xy 414.350475 -274.787161)
			(xy 414.386831 -274.750805) (xy 414.428427 -274.720584) (xy 414.474239 -274.697241) (xy 414.523138 -274.681353)
			(xy 414.57392 -274.67331) (xy 414.625336 -274.67331) (xy 414.676118 -274.681353) (xy 414.725017 -274.697241)
			(xy 414.770829 -274.720584) (xy 414.812425 -274.750805) (xy 414.848781 -274.787161) (xy 414.879002 -274.828757)
			(xy 414.902345 -274.874569) (xy 414.918233 -274.923468) (xy 414.926276 -274.97425) (xy 414.92678 -274.999958)
			(xy 415.244038 -274.999958) (xy 415.247998 -274.950904) (xy 415.259775 -274.90312) (xy 415.279066 -274.857844)
			(xy 415.305369 -274.816248) (xy 415.338004 -274.779411) (xy 415.376125 -274.748286) (xy 415.418746 -274.723679)
			(xy 415.464762 -274.706227) (xy 415.512981 -274.696383) (xy 415.562156 -274.694402) (xy 415.611011 -274.700334)
			(xy 415.658282 -274.714026) (xy 415.702744 -274.735124) (xy 415.743247 -274.76308) (xy 415.77874 -274.797172)
			(xy 415.808305 -274.836516) (xy 415.831176 -274.880093) (xy 415.84676 -274.926774) (xy 415.854655 -274.975351)
			(xy 415.85515 -274.999958) (xy 415.854655 -275.024565) (xy 415.854517 -275.025412) (xy 416.1729 -275.025412)
			(xy 416.1729 -274.973996) (xy 416.180943 -274.923214) (xy 416.196831 -274.874315) (xy 416.220174 -274.828503)
			(xy 416.250395 -274.786907) (xy 416.286751 -274.750551) (xy 416.328347 -274.72033) (xy 416.374159 -274.696987)
			(xy 416.423058 -274.681099) (xy 416.47384 -274.673056) (xy 416.525256 -274.673056) (xy 416.576038 -274.681099)
			(xy 416.624937 -274.696987) (xy 416.670749 -274.72033) (xy 416.712345 -274.750551) (xy 416.748701 -274.786907)
			(xy 416.778922 -274.828503) (xy 416.802265 -274.874315) (xy 416.818153 -274.923214) (xy 416.826196 -274.973996)
			(xy 416.8267 -274.999704) (xy 416.826695 -274.999958) (xy 417.144212 -274.999958) (xy 417.148172 -274.950904)
			(xy 417.159949 -274.90312) (xy 417.17924 -274.857844) (xy 417.205543 -274.816248) (xy 417.238178 -274.779411)
			(xy 417.276299 -274.748286) (xy 417.31892 -274.723679) (xy 417.364936 -274.706227) (xy 417.413155 -274.696383)
			(xy 417.46233 -274.694402) (xy 417.511185 -274.700334) (xy 417.558456 -274.714026) (xy 417.602918 -274.735124)
			(xy 417.643421 -274.76308) (xy 417.678914 -274.797172) (xy 417.708479 -274.836516) (xy 417.73135 -274.880093)
			(xy 417.746934 -274.926774) (xy 417.754829 -274.975351) (xy 417.755324 -274.999958) (xy 417.754829 -275.024565)
			(xy 417.75465 -275.025666) (xy 418.07282 -275.025666) (xy 418.07282 -274.97425) (xy 418.080863 -274.923468)
			(xy 418.096751 -274.874569) (xy 418.120094 -274.828757) (xy 418.150315 -274.787161) (xy 418.186671 -274.750805)
			(xy 418.228267 -274.720584) (xy 418.274079 -274.697241) (xy 418.322978 -274.681353) (xy 418.37376 -274.67331)
			(xy 418.425176 -274.67331) (xy 418.475958 -274.681353) (xy 418.524857 -274.697241) (xy 418.570669 -274.720584)
			(xy 418.612265 -274.750805) (xy 418.648621 -274.787161) (xy 418.678842 -274.828757) (xy 418.702185 -274.874569)
			(xy 418.718073 -274.923468) (xy 418.726116 -274.97425) (xy 418.72662 -274.999958) (xy 419.044132 -274.999958)
			(xy 419.048092 -274.950904) (xy 419.059869 -274.90312) (xy 419.07916 -274.857844) (xy 419.105463 -274.816248)
			(xy 419.138098 -274.779411) (xy 419.176219 -274.748286) (xy 419.21884 -274.723679) (xy 419.264856 -274.706227)
			(xy 419.313075 -274.696383) (xy 419.36225 -274.694402) (xy 419.411105 -274.700334) (xy 419.458376 -274.714026)
			(xy 419.502838 -274.735124) (xy 419.543341 -274.76308) (xy 419.578834 -274.797172) (xy 419.608399 -274.836516)
			(xy 419.63127 -274.880093) (xy 419.646854 -274.926774) (xy 419.654749 -274.975351) (xy 419.655244 -274.999958)
			(xy 419.654749 -275.024565) (xy 419.654611 -275.025412) (xy 419.972994 -275.025412) (xy 419.972994 -274.973996)
			(xy 419.981037 -274.923214) (xy 419.996925 -274.874315) (xy 420.020268 -274.828503) (xy 420.050489 -274.786907)
			(xy 420.086845 -274.750551) (xy 420.128441 -274.72033) (xy 420.174253 -274.696987) (xy 420.223152 -274.681099)
			(xy 420.273934 -274.673056) (xy 420.32535 -274.673056) (xy 420.376132 -274.681099) (xy 420.425031 -274.696987)
			(xy 420.470843 -274.72033) (xy 420.512439 -274.750551) (xy 420.548795 -274.786907) (xy 420.579016 -274.828503)
			(xy 420.602359 -274.874315) (xy 420.618247 -274.923214) (xy 420.62629 -274.973996) (xy 420.626794 -274.999704)
			(xy 420.626789 -274.999958) (xy 420.944052 -274.999958) (xy 420.948012 -274.950904) (xy 420.959789 -274.90312)
			(xy 420.97908 -274.857844) (xy 421.005383 -274.816248) (xy 421.038018 -274.779411) (xy 421.076139 -274.748286)
			(xy 421.11876 -274.723679) (xy 421.164776 -274.706227) (xy 421.212995 -274.696383) (xy 421.26217 -274.694402)
			(xy 421.311025 -274.700334) (xy 421.358296 -274.714026) (xy 421.402758 -274.735124) (xy 421.443261 -274.76308)
			(xy 421.478754 -274.797172) (xy 421.508319 -274.836516) (xy 421.53119 -274.880093) (xy 421.546774 -274.926774)
			(xy 421.554669 -274.975351) (xy 421.555164 -274.999958) (xy 421.554669 -275.024565) (xy 421.546774 -275.073142)
			(xy 421.53119 -275.119823) (xy 421.508319 -275.1634) (xy 421.478754 -275.202744) (xy 421.443261 -275.236836)
			(xy 421.402758 -275.264792) (xy 421.358296 -275.28589) (xy 421.311025 -275.299582) (xy 421.26217 -275.305514)
			(xy 421.212995 -275.303533) (xy 421.164776 -275.293689) (xy 421.11876 -275.276237) (xy 421.076139 -275.25163)
			(xy 421.038018 -275.220505) (xy 421.005383 -275.183668) (xy 420.97908 -275.142072) (xy 420.959789 -275.096796)
			(xy 420.948012 -275.049012) (xy 420.944052 -274.999958) (xy 420.626789 -274.999958) (xy 420.62629 -275.025412)
			(xy 420.618247 -275.076194) (xy 420.602359 -275.125093) (xy 420.579016 -275.170905) (xy 420.548795 -275.212501)
			(xy 420.512439 -275.248857) (xy 420.470843 -275.279078) (xy 420.425031 -275.302421) (xy 420.376132 -275.318309)
			(xy 420.32535 -275.326352) (xy 420.273934 -275.326352) (xy 420.223152 -275.318309) (xy 420.174253 -275.302421)
			(xy 420.128441 -275.279078) (xy 420.086845 -275.248857) (xy 420.050489 -275.212501) (xy 420.020268 -275.170905)
			(xy 419.996925 -275.125093) (xy 419.981037 -275.076194) (xy 419.972994 -275.025412) (xy 419.654611 -275.025412)
			(xy 419.646854 -275.073142) (xy 419.63127 -275.119823) (xy 419.608399 -275.1634) (xy 419.578834 -275.202744)
			(xy 419.543341 -275.236836) (xy 419.502838 -275.264792) (xy 419.458376 -275.28589) (xy 419.411105 -275.299582)
			(xy 419.36225 -275.305514) (xy 419.313075 -275.303533) (xy 419.264856 -275.293689) (xy 419.21884 -275.276237)
			(xy 419.176219 -275.25163) (xy 419.138098 -275.220505) (xy 419.105463 -275.183668) (xy 419.07916 -275.142072)
			(xy 419.059869 -275.096796) (xy 419.048092 -275.049012) (xy 419.044132 -274.999958) (xy 418.72662 -274.999958)
			(xy 418.726116 -275.025666) (xy 418.718073 -275.076448) (xy 418.702185 -275.125347) (xy 418.678842 -275.171159)
			(xy 418.648621 -275.212755) (xy 418.612265 -275.249111) (xy 418.570669 -275.279332) (xy 418.524857 -275.302675)
			(xy 418.475958 -275.318563) (xy 418.425176 -275.326606) (xy 418.37376 -275.326606) (xy 418.322978 -275.318563)
			(xy 418.274079 -275.302675) (xy 418.228267 -275.279332) (xy 418.186671 -275.249111) (xy 418.150315 -275.212755)
			(xy 418.120094 -275.171159) (xy 418.096751 -275.125347) (xy 418.080863 -275.076448) (xy 418.07282 -275.025666)
			(xy 417.75465 -275.025666) (xy 417.746934 -275.073142) (xy 417.73135 -275.119823) (xy 417.708479 -275.1634)
			(xy 417.678914 -275.202744) (xy 417.643421 -275.236836) (xy 417.602918 -275.264792) (xy 417.558456 -275.28589)
			(xy 417.511185 -275.299582) (xy 417.46233 -275.305514) (xy 417.413155 -275.303533) (xy 417.364936 -275.293689)
			(xy 417.31892 -275.276237) (xy 417.276299 -275.25163) (xy 417.238178 -275.220505) (xy 417.205543 -275.183668)
			(xy 417.17924 -275.142072) (xy 417.159949 -275.096796) (xy 417.148172 -275.049012) (xy 417.144212 -274.999958)
			(xy 416.826695 -274.999958) (xy 416.826196 -275.025412) (xy 416.818153 -275.076194) (xy 416.802265 -275.125093)
			(xy 416.778922 -275.170905) (xy 416.748701 -275.212501) (xy 416.712345 -275.248857) (xy 416.670749 -275.279078)
			(xy 416.624937 -275.302421) (xy 416.576038 -275.318309) (xy 416.525256 -275.326352) (xy 416.47384 -275.326352)
			(xy 416.423058 -275.318309) (xy 416.374159 -275.302421) (xy 416.328347 -275.279078) (xy 416.286751 -275.248857)
			(xy 416.250395 -275.212501) (xy 416.220174 -275.170905) (xy 416.196831 -275.125093) (xy 416.180943 -275.076194)
			(xy 416.1729 -275.025412) (xy 415.854517 -275.025412) (xy 415.84676 -275.073142) (xy 415.831176 -275.119823)
			(xy 415.808305 -275.1634) (xy 415.77874 -275.202744) (xy 415.743247 -275.236836) (xy 415.702744 -275.264792)
			(xy 415.658282 -275.28589) (xy 415.611011 -275.299582) (xy 415.562156 -275.305514) (xy 415.512981 -275.303533)
			(xy 415.464762 -275.293689) (xy 415.418746 -275.276237) (xy 415.376125 -275.25163) (xy 415.338004 -275.220505)
			(xy 415.305369 -275.183668) (xy 415.279066 -275.142072) (xy 415.259775 -275.096796) (xy 415.247998 -275.049012)
			(xy 415.244038 -274.999958) (xy 414.92678 -274.999958) (xy 414.926276 -275.025666) (xy 414.918233 -275.076448)
			(xy 414.902345 -275.125347) (xy 414.879002 -275.171159) (xy 414.848781 -275.212755) (xy 414.812425 -275.249111)
			(xy 414.770829 -275.279332) (xy 414.725017 -275.302675) (xy 414.676118 -275.318563) (xy 414.625336 -275.326606)
			(xy 414.57392 -275.326606) (xy 414.523138 -275.318563) (xy 414.474239 -275.302675) (xy 414.428427 -275.279332)
			(xy 414.386831 -275.249111) (xy 414.350475 -275.212755) (xy 414.320254 -275.171159) (xy 414.296911 -275.125347)
			(xy 414.281023 -275.076448) (xy 414.27298 -275.025666) (xy 413.954556 -275.025666) (xy 413.94684 -275.073142)
			(xy 413.931256 -275.119823) (xy 413.908385 -275.1634) (xy 413.87882 -275.202744) (xy 413.843327 -275.236836)
			(xy 413.802824 -275.264792) (xy 413.758362 -275.28589) (xy 413.711091 -275.299582) (xy 413.662236 -275.305514)
			(xy 413.613061 -275.303533) (xy 413.564842 -275.293689) (xy 413.518826 -275.276237) (xy 413.476205 -275.25163)
			(xy 413.438084 -275.220505) (xy 413.405449 -275.183668) (xy 413.379146 -275.142072) (xy 413.359855 -275.096796)
			(xy 413.348078 -275.049012) (xy 413.344118 -274.999958) (xy 413.026855 -274.999958) (xy 413.026356 -275.025412)
			(xy 413.018313 -275.076194) (xy 413.002425 -275.125093) (xy 412.979082 -275.170905) (xy 412.948861 -275.212501)
			(xy 412.912505 -275.248857) (xy 412.870909 -275.279078) (xy 412.825097 -275.302421) (xy 412.776198 -275.318309)
			(xy 412.725416 -275.326352) (xy 412.674 -275.326352) (xy 412.623218 -275.318309) (xy 412.574319 -275.302421)
			(xy 412.528507 -275.279078) (xy 412.486911 -275.248857) (xy 412.450555 -275.212501) (xy 412.420334 -275.170905)
			(xy 412.396991 -275.125093) (xy 412.381103 -275.076194) (xy 412.37306 -275.025412) (xy 412.054677 -275.025412)
			(xy 412.04692 -275.073142) (xy 412.031336 -275.119823) (xy 412.008465 -275.1634) (xy 411.9789 -275.202744)
			(xy 411.943407 -275.236836) (xy 411.902904 -275.264792) (xy 411.858442 -275.28589) (xy 411.811171 -275.299582)
			(xy 411.762316 -275.305514) (xy 411.713141 -275.303533) (xy 411.664922 -275.293689) (xy 411.618906 -275.276237)
			(xy 411.576285 -275.25163) (xy 411.538164 -275.220505) (xy 411.505529 -275.183668) (xy 411.479226 -275.142072)
			(xy 411.459935 -275.096796) (xy 411.448158 -275.049012) (xy 411.444198 -274.999958) (xy 411.126686 -274.999958)
			(xy 411.126182 -275.025666) (xy 411.118139 -275.076448) (xy 411.102251 -275.125347) (xy 411.078908 -275.171159)
			(xy 411.048687 -275.212755) (xy 411.012331 -275.249111) (xy 410.970735 -275.279332) (xy 410.924923 -275.302675)
			(xy 410.876024 -275.318563) (xy 410.825242 -275.326606) (xy 410.773826 -275.326606) (xy 410.723044 -275.318563)
			(xy 410.674145 -275.302675) (xy 410.628333 -275.279332) (xy 410.586737 -275.249111) (xy 410.550381 -275.212755)
			(xy 410.52016 -275.171159) (xy 410.496817 -275.125347) (xy 410.480929 -275.076448) (xy 410.472886 -275.025666)
			(xy 410.154462 -275.025666) (xy 410.146746 -275.073142) (xy 410.131162 -275.119823) (xy 410.108291 -275.1634)
			(xy 410.078726 -275.202744) (xy 410.043233 -275.236836) (xy 410.00273 -275.264792) (xy 409.958268 -275.28589)
			(xy 409.910997 -275.299582) (xy 409.862142 -275.305514) (xy 409.812967 -275.303533) (xy 409.764748 -275.293689)
			(xy 409.718732 -275.276237) (xy 409.676111 -275.25163) (xy 409.63799 -275.220505) (xy 409.605355 -275.183668)
			(xy 409.579052 -275.142072) (xy 409.559761 -275.096796) (xy 409.547984 -275.049012) (xy 409.544024 -274.999958)
			(xy 409.226761 -274.999958) (xy 409.226262 -275.025412) (xy 409.218219 -275.076194) (xy 409.202331 -275.125093)
			(xy 409.178988 -275.170905) (xy 409.148767 -275.212501) (xy 409.112411 -275.248857) (xy 409.070815 -275.279078)
			(xy 409.025003 -275.302421) (xy 408.976104 -275.318309) (xy 408.925322 -275.326352) (xy 408.873906 -275.326352)
			(xy 408.823124 -275.318309) (xy 408.774225 -275.302421) (xy 408.728413 -275.279078) (xy 408.686817 -275.248857)
			(xy 408.650461 -275.212501) (xy 408.62024 -275.170905) (xy 408.596897 -275.125093) (xy 408.581009 -275.076194)
			(xy 408.572966 -275.025412) (xy 408.254583 -275.025412) (xy 408.246826 -275.073142) (xy 408.231242 -275.119823)
			(xy 408.208371 -275.1634) (xy 408.178806 -275.202744) (xy 408.143313 -275.236836) (xy 408.10281 -275.264792)
			(xy 408.058348 -275.28589) (xy 408.011077 -275.299582) (xy 407.962222 -275.305514) (xy 407.913047 -275.303533)
			(xy 407.864828 -275.293689) (xy 407.818812 -275.276237) (xy 407.776191 -275.25163) (xy 407.73807 -275.220505)
			(xy 407.705435 -275.183668) (xy 407.679132 -275.142072) (xy 407.659841 -275.096796) (xy 407.648064 -275.049012)
			(xy 407.644104 -274.999958) (xy 407.3271 -274.999958) (xy 407.326596 -275.025666) (xy 407.318553 -275.076448)
			(xy 407.302665 -275.125347) (xy 407.279322 -275.171159) (xy 407.249101 -275.212755) (xy 407.212745 -275.249111)
			(xy 407.171149 -275.279332) (xy 407.125337 -275.302675) (xy 407.076438 -275.318563) (xy 407.025656 -275.326606)
			(xy 406.97424 -275.326606) (xy 406.923458 -275.318563) (xy 406.874559 -275.302675) (xy 406.828747 -275.279332)
			(xy 406.787151 -275.249111) (xy 406.750795 -275.212755) (xy 406.720574 -275.171159) (xy 406.697231 -275.125347)
			(xy 406.681343 -275.076448) (xy 406.6733 -275.025666) (xy 406.354622 -275.025666) (xy 406.346906 -275.073142)
			(xy 406.331322 -275.119823) (xy 406.308451 -275.1634) (xy 406.278886 -275.202744) (xy 406.243393 -275.236836)
			(xy 406.20289 -275.264792) (xy 406.158428 -275.28589) (xy 406.111157 -275.299582) (xy 406.062302 -275.305514)
			(xy 406.013127 -275.303533) (xy 405.964908 -275.293689) (xy 405.918892 -275.276237) (xy 405.876271 -275.25163)
			(xy 405.83815 -275.220505) (xy 405.805515 -275.183668) (xy 405.779212 -275.142072) (xy 405.759921 -275.096796)
			(xy 405.748144 -275.049012) (xy 405.744184 -274.999958) (xy 405.42718 -274.999958) (xy 405.426676 -275.025666)
			(xy 405.418633 -275.076448) (xy 405.402745 -275.125347) (xy 405.379402 -275.171159) (xy 405.349181 -275.212755)
			(xy 405.312825 -275.249111) (xy 405.271229 -275.279332) (xy 405.225417 -275.302675) (xy 405.176518 -275.318563)
			(xy 405.125736 -275.326606) (xy 405.07432 -275.326606) (xy 405.023538 -275.318563) (xy 404.974639 -275.302675)
			(xy 404.928827 -275.279332) (xy 404.887231 -275.249111) (xy 404.850875 -275.212755) (xy 404.820654 -275.171159)
			(xy 404.797311 -275.125347) (xy 404.781423 -275.076448) (xy 404.77338 -275.025666) (xy 404.454448 -275.025666)
			(xy 404.446732 -275.073142) (xy 404.431148 -275.119823) (xy 404.408277 -275.1634) (xy 404.378712 -275.202744)
			(xy 404.343219 -275.236836) (xy 404.302716 -275.264792) (xy 404.258254 -275.28589) (xy 404.210983 -275.299582)
			(xy 404.162128 -275.305514) (xy 404.112953 -275.303533) (xy 404.064734 -275.293689) (xy 404.018718 -275.276237)
			(xy 403.976097 -275.25163) (xy 403.937976 -275.220505) (xy 403.905341 -275.183668) (xy 403.879038 -275.142072)
			(xy 403.859747 -275.096796) (xy 403.84797 -275.049012) (xy 403.84401 -274.999958) (xy 403.527006 -274.999958)
			(xy 403.526502 -275.025666) (xy 403.518459 -275.076448) (xy 403.502571 -275.125347) (xy 403.479228 -275.171159)
			(xy 403.449007 -275.212755) (xy 403.412651 -275.249111) (xy 403.371055 -275.279332) (xy 403.325243 -275.302675)
			(xy 403.276344 -275.318563) (xy 403.225562 -275.326606) (xy 403.174146 -275.326606) (xy 403.123364 -275.318563)
			(xy 403.074465 -275.302675) (xy 403.028653 -275.279332) (xy 402.987057 -275.249111) (xy 402.950701 -275.212755)
			(xy 402.92048 -275.171159) (xy 402.897137 -275.125347) (xy 402.881249 -275.076448) (xy 402.873206 -275.025666)
			(xy 402.554528 -275.025666) (xy 402.546812 -275.073142) (xy 402.531228 -275.119823) (xy 402.508357 -275.1634)
			(xy 402.478792 -275.202744) (xy 402.443299 -275.236836) (xy 402.402796 -275.264792) (xy 402.358334 -275.28589)
			(xy 402.311063 -275.299582) (xy 402.262208 -275.305514) (xy 402.213033 -275.303533) (xy 402.164814 -275.293689)
			(xy 402.118798 -275.276237) (xy 402.076177 -275.25163) (xy 402.038056 -275.220505) (xy 402.005421 -275.183668)
			(xy 401.979118 -275.142072) (xy 401.959827 -275.096796) (xy 401.94805 -275.049012) (xy 401.94409 -274.999958)
			(xy 401.627086 -274.999958) (xy 401.626582 -275.025666) (xy 401.618539 -275.076448) (xy 401.602651 -275.125347)
			(xy 401.579308 -275.171159) (xy 401.549087 -275.212755) (xy 401.512731 -275.249111) (xy 401.471135 -275.279332)
			(xy 401.425323 -275.302675) (xy 401.376424 -275.318563) (xy 401.325642 -275.326606) (xy 401.274226 -275.326606)
			(xy 401.223444 -275.318563) (xy 401.174545 -275.302675) (xy 401.128733 -275.279332) (xy 401.087137 -275.249111)
			(xy 401.050781 -275.212755) (xy 401.02056 -275.171159) (xy 400.997217 -275.125347) (xy 400.981329 -275.076448)
			(xy 400.973286 -275.025666) (xy 400.654608 -275.025666) (xy 400.646892 -275.073142) (xy 400.631308 -275.119823)
			(xy 400.608437 -275.1634) (xy 400.578872 -275.202744) (xy 400.543379 -275.236836) (xy 400.502876 -275.264792)
			(xy 400.458414 -275.28589) (xy 400.411143 -275.299582) (xy 400.362288 -275.305514) (xy 400.313113 -275.303533)
			(xy 400.264894 -275.293689) (xy 400.218878 -275.276237) (xy 400.176257 -275.25163) (xy 400.138136 -275.220505)
			(xy 400.105501 -275.183668) (xy 400.079198 -275.142072) (xy 400.059907 -275.096796) (xy 400.04813 -275.049012)
			(xy 400.04417 -274.999958) (xy 399.727166 -274.999958) (xy 399.726662 -275.025666) (xy 399.718619 -275.076448)
			(xy 399.702731 -275.125347) (xy 399.679388 -275.171159) (xy 399.649167 -275.212755) (xy 399.612811 -275.249111)
			(xy 399.571215 -275.279332) (xy 399.525403 -275.302675) (xy 399.476504 -275.318563) (xy 399.425722 -275.326606)
			(xy 399.374306 -275.326606) (xy 399.323524 -275.318563) (xy 399.274625 -275.302675) (xy 399.228813 -275.279332)
			(xy 399.187217 -275.249111) (xy 399.150861 -275.212755) (xy 399.12064 -275.171159) (xy 399.097297 -275.125347)
			(xy 399.081409 -275.076448) (xy 399.073366 -275.025666) (xy 398.754434 -275.025666) (xy 398.746718 -275.073142)
			(xy 398.731134 -275.119823) (xy 398.708263 -275.1634) (xy 398.678698 -275.202744) (xy 398.643205 -275.236836)
			(xy 398.602702 -275.264792) (xy 398.55824 -275.28589) (xy 398.510969 -275.299582) (xy 398.462114 -275.305514)
			(xy 398.412939 -275.303533) (xy 398.36472 -275.293689) (xy 398.318704 -275.276237) (xy 398.276083 -275.25163)
			(xy 398.237962 -275.220505) (xy 398.205327 -275.183668) (xy 398.179024 -275.142072) (xy 398.159733 -275.096796)
			(xy 398.147956 -275.049012) (xy 398.143996 -274.999958) (xy 397.826992 -274.999958) (xy 397.826488 -275.025666)
			(xy 397.818445 -275.076448) (xy 397.802557 -275.125347) (xy 397.779214 -275.171159) (xy 397.748993 -275.212755)
			(xy 397.712637 -275.249111) (xy 397.671041 -275.279332) (xy 397.625229 -275.302675) (xy 397.57633 -275.318563)
			(xy 397.525548 -275.326606) (xy 397.474132 -275.326606) (xy 397.42335 -275.318563) (xy 397.374451 -275.302675)
			(xy 397.328639 -275.279332) (xy 397.287043 -275.249111) (xy 397.250687 -275.212755) (xy 397.220466 -275.171159)
			(xy 397.197123 -275.125347) (xy 397.181235 -275.076448) (xy 397.173192 -275.025666) (xy 396.854514 -275.025666)
			(xy 396.846798 -275.073142) (xy 396.831214 -275.119823) (xy 396.808343 -275.1634) (xy 396.778778 -275.202744)
			(xy 396.743285 -275.236836) (xy 396.702782 -275.264792) (xy 396.65832 -275.28589) (xy 396.611049 -275.299582)
			(xy 396.562194 -275.305514) (xy 396.513019 -275.303533) (xy 396.4648 -275.293689) (xy 396.418784 -275.276237)
			(xy 396.376163 -275.25163) (xy 396.338042 -275.220505) (xy 396.305407 -275.183668) (xy 396.279104 -275.142072)
			(xy 396.259813 -275.096796) (xy 396.248036 -275.049012) (xy 396.244076 -274.999958) (xy 395.927072 -274.999958)
			(xy 395.926568 -275.025666) (xy 395.918525 -275.076448) (xy 395.902637 -275.125347) (xy 395.879294 -275.171159)
			(xy 395.849073 -275.212755) (xy 395.812717 -275.249111) (xy 395.771121 -275.279332) (xy 395.725309 -275.302675)
			(xy 395.67641 -275.318563) (xy 395.625628 -275.326606) (xy 395.574212 -275.326606) (xy 395.52343 -275.318563)
			(xy 395.474531 -275.302675) (xy 395.428719 -275.279332) (xy 395.387123 -275.249111) (xy 395.350767 -275.212755)
			(xy 395.320546 -275.171159) (xy 395.297203 -275.125347) (xy 395.281315 -275.076448) (xy 395.273272 -275.025666)
			(xy 394.954594 -275.025666) (xy 394.946878 -275.073142) (xy 394.931294 -275.119823) (xy 394.908423 -275.1634)
			(xy 394.878858 -275.202744) (xy 394.843365 -275.236836) (xy 394.802862 -275.264792) (xy 394.7584 -275.28589)
			(xy 394.711129 -275.299582) (xy 394.662274 -275.305514) (xy 394.613099 -275.303533) (xy 394.56488 -275.293689)
			(xy 394.518864 -275.276237) (xy 394.476243 -275.25163) (xy 394.438122 -275.220505) (xy 394.405487 -275.183668)
			(xy 394.379184 -275.142072) (xy 394.359893 -275.096796) (xy 394.348116 -275.049012) (xy 394.344156 -274.999958)
			(xy 394.027152 -274.999958) (xy 394.026648 -275.025666) (xy 394.018605 -275.076448) (xy 394.002717 -275.125347)
			(xy 393.979374 -275.171159) (xy 393.949153 -275.212755) (xy 393.912797 -275.249111) (xy 393.871201 -275.279332)
			(xy 393.825389 -275.302675) (xy 393.77649 -275.318563) (xy 393.725708 -275.326606) (xy 393.674292 -275.326606)
			(xy 393.62351 -275.318563) (xy 393.574611 -275.302675) (xy 393.528799 -275.279332) (xy 393.487203 -275.249111)
			(xy 393.450847 -275.212755) (xy 393.420626 -275.171159) (xy 393.397283 -275.125347) (xy 393.381395 -275.076448)
			(xy 393.373352 -275.025666) (xy 393.05442 -275.025666) (xy 393.046704 -275.073142) (xy 393.03112 -275.119823)
			(xy 393.008249 -275.1634) (xy 392.978684 -275.202744) (xy 392.943191 -275.236836) (xy 392.902688 -275.264792)
			(xy 392.858226 -275.28589) (xy 392.810955 -275.299582) (xy 392.7621 -275.305514) (xy 392.712925 -275.303533)
			(xy 392.664706 -275.293689) (xy 392.61869 -275.276237) (xy 392.576069 -275.25163) (xy 392.537948 -275.220505)
			(xy 392.505313 -275.183668) (xy 392.47901 -275.142072) (xy 392.459719 -275.096796) (xy 392.447942 -275.049012)
			(xy 392.443982 -274.999958) (xy 383.78638 -274.999958) (xy 383.78638 -275.474938) (xy 384.369068 -275.474938)
			(xy 384.373028 -275.425884) (xy 384.384805 -275.3781) (xy 384.404096 -275.332824) (xy 384.430399 -275.291228)
			(xy 384.463034 -275.254391) (xy 384.501155 -275.223266) (xy 384.543776 -275.198659) (xy 384.589792 -275.181207)
			(xy 384.638011 -275.171363) (xy 384.687186 -275.169382) (xy 384.736041 -275.175314) (xy 384.783312 -275.189006)
			(xy 384.827774 -275.210104) (xy 384.868277 -275.23806) (xy 384.90377 -275.272152) (xy 384.933335 -275.311496)
			(xy 384.956206 -275.355073) (xy 384.97179 -275.401754) (xy 384.979685 -275.450331) (xy 384.98018 -275.474938)
			(xy 385.319028 -275.474938) (xy 385.322988 -275.425884) (xy 385.334765 -275.3781) (xy 385.354056 -275.332824)
			(xy 385.380359 -275.291228) (xy 385.412994 -275.254391) (xy 385.451115 -275.223266) (xy 385.493736 -275.198659)
			(xy 385.539752 -275.181207) (xy 385.587971 -275.171363) (xy 385.637146 -275.169382) (xy 385.686001 -275.175314)
			(xy 385.733272 -275.189006) (xy 385.777734 -275.210104) (xy 385.818237 -275.23806) (xy 385.85373 -275.272152)
			(xy 385.883295 -275.311496) (xy 385.906166 -275.355073) (xy 385.92175 -275.401754) (xy 385.929645 -275.450331)
			(xy 385.93014 -275.474938) (xy 386.269242 -275.474938) (xy 386.273202 -275.425884) (xy 386.284979 -275.3781)
			(xy 386.30427 -275.332824) (xy 386.330573 -275.291228) (xy 386.363208 -275.254391) (xy 386.401329 -275.223266)
			(xy 386.44395 -275.198659) (xy 386.489966 -275.181207) (xy 386.538185 -275.171363) (xy 386.58736 -275.169382)
			(xy 386.636215 -275.175314) (xy 386.683486 -275.189006) (xy 386.727948 -275.210104) (xy 386.768451 -275.23806)
			(xy 386.803944 -275.272152) (xy 386.833509 -275.311496) (xy 386.85638 -275.355073) (xy 386.871964 -275.401754)
			(xy 386.879859 -275.450331) (xy 386.880354 -275.474938) (xy 387.219202 -275.474938) (xy 387.223162 -275.425884)
			(xy 387.234939 -275.3781) (xy 387.25423 -275.332824) (xy 387.280533 -275.291228) (xy 387.313168 -275.254391)
			(xy 387.351289 -275.223266) (xy 387.39391 -275.198659) (xy 387.439926 -275.181207) (xy 387.488145 -275.171363)
			(xy 387.53732 -275.169382) (xy 387.586175 -275.175314) (xy 387.633446 -275.189006) (xy 387.677908 -275.210104)
			(xy 387.718411 -275.23806) (xy 387.753904 -275.272152) (xy 387.783469 -275.311496) (xy 387.80634 -275.355073)
			(xy 387.821924 -275.401754) (xy 387.829819 -275.450331) (xy 387.830314 -275.474938) (xy 388.169162 -275.474938)
			(xy 388.173122 -275.425884) (xy 388.184899 -275.3781) (xy 388.20419 -275.332824) (xy 388.230493 -275.291228)
			(xy 388.263128 -275.254391) (xy 388.301249 -275.223266) (xy 388.34387 -275.198659) (xy 388.389886 -275.181207)
			(xy 388.438105 -275.171363) (xy 388.48728 -275.169382) (xy 388.536135 -275.175314) (xy 388.583406 -275.189006)
			(xy 388.627868 -275.210104) (xy 388.668371 -275.23806) (xy 388.703864 -275.272152) (xy 388.733429 -275.311496)
			(xy 388.7563 -275.355073) (xy 388.771884 -275.401754) (xy 388.779779 -275.450331) (xy 388.780274 -275.474938)
			(xy 389.119122 -275.474938) (xy 389.123082 -275.425884) (xy 389.134859 -275.3781) (xy 389.15415 -275.332824)
			(xy 389.180453 -275.291228) (xy 389.213088 -275.254391) (xy 389.251209 -275.223266) (xy 389.29383 -275.198659)
			(xy 389.339846 -275.181207) (xy 389.388065 -275.171363) (xy 389.43724 -275.169382) (xy 389.486095 -275.175314)
			(xy 389.533366 -275.189006) (xy 389.577828 -275.210104) (xy 389.618331 -275.23806) (xy 389.653824 -275.272152)
			(xy 389.683389 -275.311496) (xy 389.70626 -275.355073) (xy 389.721844 -275.401754) (xy 389.729739 -275.450331)
			(xy 389.730234 -275.474938) (xy 390.069082 -275.474938) (xy 390.073042 -275.425884) (xy 390.084819 -275.3781)
			(xy 390.10411 -275.332824) (xy 390.130413 -275.291228) (xy 390.163048 -275.254391) (xy 390.201169 -275.223266)
			(xy 390.24379 -275.198659) (xy 390.289806 -275.181207) (xy 390.338025 -275.171363) (xy 390.3872 -275.169382)
			(xy 390.436055 -275.175314) (xy 390.483326 -275.189006) (xy 390.527788 -275.210104) (xy 390.568291 -275.23806)
			(xy 390.603784 -275.272152) (xy 390.633349 -275.311496) (xy 390.65622 -275.355073) (xy 390.671804 -275.401754)
			(xy 390.679699 -275.450331) (xy 390.680194 -275.474938) (xy 391.019042 -275.474938) (xy 391.023002 -275.425884)
			(xy 391.034779 -275.3781) (xy 391.05407 -275.332824) (xy 391.080373 -275.291228) (xy 391.113008 -275.254391)
			(xy 391.151129 -275.223266) (xy 391.19375 -275.198659) (xy 391.239766 -275.181207) (xy 391.287985 -275.171363)
			(xy 391.33716 -275.169382) (xy 391.386015 -275.175314) (xy 391.433286 -275.189006) (xy 391.477748 -275.210104)
			(xy 391.518251 -275.23806) (xy 391.553744 -275.272152) (xy 391.583309 -275.311496) (xy 391.60618 -275.355073)
			(xy 391.621764 -275.401754) (xy 391.629659 -275.450331) (xy 391.630154 -275.474938) (xy 391.629659 -275.499545)
			(xy 391.621764 -275.548122) (xy 391.60618 -275.594803) (xy 391.583309 -275.63838) (xy 391.553744 -275.677724)
			(xy 391.518251 -275.711816) (xy 391.477748 -275.739772) (xy 391.433286 -275.76087) (xy 391.386015 -275.774562)
			(xy 391.33716 -275.780494) (xy 391.287985 -275.778513) (xy 391.239766 -275.768669) (xy 391.19375 -275.751217)
			(xy 391.151129 -275.72661) (xy 391.113008 -275.695485) (xy 391.080373 -275.658648) (xy 391.05407 -275.617052)
			(xy 391.034779 -275.571776) (xy 391.023002 -275.523992) (xy 391.019042 -275.474938) (xy 390.680194 -275.474938)
			(xy 390.679699 -275.499545) (xy 390.671804 -275.548122) (xy 390.65622 -275.594803) (xy 390.633349 -275.63838)
			(xy 390.603784 -275.677724) (xy 390.568291 -275.711816) (xy 390.527788 -275.739772) (xy 390.483326 -275.76087)
			(xy 390.436055 -275.774562) (xy 390.3872 -275.780494) (xy 390.338025 -275.778513) (xy 390.289806 -275.768669)
			(xy 390.24379 -275.751217) (xy 390.201169 -275.72661) (xy 390.163048 -275.695485) (xy 390.130413 -275.658648)
			(xy 390.10411 -275.617052) (xy 390.084819 -275.571776) (xy 390.073042 -275.523992) (xy 390.069082 -275.474938)
			(xy 389.730234 -275.474938) (xy 389.729739 -275.499545) (xy 389.721844 -275.548122) (xy 389.70626 -275.594803)
			(xy 389.683389 -275.63838) (xy 389.653824 -275.677724) (xy 389.618331 -275.711816) (xy 389.577828 -275.739772)
			(xy 389.533366 -275.76087) (xy 389.486095 -275.774562) (xy 389.43724 -275.780494) (xy 389.388065 -275.778513)
			(xy 389.339846 -275.768669) (xy 389.29383 -275.751217) (xy 389.251209 -275.72661) (xy 389.213088 -275.695485)
			(xy 389.180453 -275.658648) (xy 389.15415 -275.617052) (xy 389.134859 -275.571776) (xy 389.123082 -275.523992)
			(xy 389.119122 -275.474938) (xy 388.780274 -275.474938) (xy 388.779779 -275.499545) (xy 388.771884 -275.548122)
			(xy 388.7563 -275.594803) (xy 388.733429 -275.63838) (xy 388.703864 -275.677724) (xy 388.668371 -275.711816)
			(xy 388.627868 -275.739772) (xy 388.583406 -275.76087) (xy 388.536135 -275.774562) (xy 388.48728 -275.780494)
			(xy 388.438105 -275.778513) (xy 388.389886 -275.768669) (xy 388.34387 -275.751217) (xy 388.301249 -275.72661)
			(xy 388.263128 -275.695485) (xy 388.230493 -275.658648) (xy 388.20419 -275.617052) (xy 388.184899 -275.571776)
			(xy 388.173122 -275.523992) (xy 388.169162 -275.474938) (xy 387.830314 -275.474938) (xy 387.829819 -275.499545)
			(xy 387.821924 -275.548122) (xy 387.80634 -275.594803) (xy 387.783469 -275.63838) (xy 387.753904 -275.677724)
			(xy 387.718411 -275.711816) (xy 387.677908 -275.739772) (xy 387.633446 -275.76087) (xy 387.586175 -275.774562)
			(xy 387.53732 -275.780494) (xy 387.488145 -275.778513) (xy 387.439926 -275.768669) (xy 387.39391 -275.751217)
			(xy 387.351289 -275.72661) (xy 387.313168 -275.695485) (xy 387.280533 -275.658648) (xy 387.25423 -275.617052)
			(xy 387.234939 -275.571776) (xy 387.223162 -275.523992) (xy 387.219202 -275.474938) (xy 386.880354 -275.474938)
			(xy 386.879859 -275.499545) (xy 386.871964 -275.548122) (xy 386.85638 -275.594803) (xy 386.833509 -275.63838)
			(xy 386.803944 -275.677724) (xy 386.768451 -275.711816) (xy 386.727948 -275.739772) (xy 386.683486 -275.76087)
			(xy 386.636215 -275.774562) (xy 386.58736 -275.780494) (xy 386.538185 -275.778513) (xy 386.489966 -275.768669)
			(xy 386.44395 -275.751217) (xy 386.401329 -275.72661) (xy 386.363208 -275.695485) (xy 386.330573 -275.658648)
			(xy 386.30427 -275.617052) (xy 386.284979 -275.571776) (xy 386.273202 -275.523992) (xy 386.269242 -275.474938)
			(xy 385.93014 -275.474938) (xy 385.929645 -275.499545) (xy 385.92175 -275.548122) (xy 385.906166 -275.594803)
			(xy 385.883295 -275.63838) (xy 385.85373 -275.677724) (xy 385.818237 -275.711816) (xy 385.777734 -275.739772)
			(xy 385.733272 -275.76087) (xy 385.686001 -275.774562) (xy 385.637146 -275.780494) (xy 385.587971 -275.778513)
			(xy 385.539752 -275.768669) (xy 385.493736 -275.751217) (xy 385.451115 -275.72661) (xy 385.412994 -275.695485)
			(xy 385.380359 -275.658648) (xy 385.354056 -275.617052) (xy 385.334765 -275.571776) (xy 385.322988 -275.523992)
			(xy 385.319028 -275.474938) (xy 384.98018 -275.474938) (xy 384.979685 -275.499545) (xy 384.97179 -275.548122)
			(xy 384.956206 -275.594803) (xy 384.933335 -275.63838) (xy 384.90377 -275.677724) (xy 384.868277 -275.711816)
			(xy 384.827774 -275.739772) (xy 384.783312 -275.76087) (xy 384.736041 -275.774562) (xy 384.687186 -275.780494)
			(xy 384.638011 -275.778513) (xy 384.589792 -275.768669) (xy 384.543776 -275.751217) (xy 384.501155 -275.72661)
			(xy 384.463034 -275.695485) (xy 384.430399 -275.658648) (xy 384.404096 -275.617052) (xy 384.384805 -275.571776)
			(xy 384.373028 -275.523992) (xy 384.369068 -275.474938) (xy 383.78638 -275.474938) (xy 383.78638 -275.949918)
			(xy 392.443982 -275.949918) (xy 392.447942 -275.900864) (xy 392.459719 -275.85308) (xy 392.47901 -275.807804)
			(xy 392.505313 -275.766208) (xy 392.537948 -275.729371) (xy 392.576069 -275.698246) (xy 392.61869 -275.673639)
			(xy 392.664706 -275.656187) (xy 392.712925 -275.646343) (xy 392.7621 -275.644362) (xy 392.810955 -275.650294)
			(xy 392.858226 -275.663986) (xy 392.902688 -275.685084) (xy 392.943191 -275.71304) (xy 392.978684 -275.747132)
			(xy 393.008249 -275.786476) (xy 393.03112 -275.830053) (xy 393.046704 -275.876734) (xy 393.054599 -275.925311)
			(xy 393.055094 -275.949918) (xy 393.054599 -275.974525) (xy 393.05442 -275.975626) (xy 393.373352 -275.975626)
			(xy 393.373352 -275.92421) (xy 393.381395 -275.873428) (xy 393.397283 -275.824529) (xy 393.420626 -275.778717)
			(xy 393.450847 -275.737121) (xy 393.487203 -275.700765) (xy 393.528799 -275.670544) (xy 393.574611 -275.647201)
			(xy 393.62351 -275.631313) (xy 393.674292 -275.62327) (xy 393.725708 -275.62327) (xy 393.77649 -275.631313)
			(xy 393.825389 -275.647201) (xy 393.871201 -275.670544) (xy 393.912797 -275.700765) (xy 393.949153 -275.737121)
			(xy 393.979374 -275.778717) (xy 394.002717 -275.824529) (xy 394.018605 -275.873428) (xy 394.026648 -275.92421)
			(xy 394.027152 -275.949918) (xy 394.344156 -275.949918) (xy 394.348116 -275.900864) (xy 394.359893 -275.85308)
			(xy 394.379184 -275.807804) (xy 394.405487 -275.766208) (xy 394.438122 -275.729371) (xy 394.476243 -275.698246)
			(xy 394.518864 -275.673639) (xy 394.56488 -275.656187) (xy 394.613099 -275.646343) (xy 394.662274 -275.644362)
			(xy 394.711129 -275.650294) (xy 394.7584 -275.663986) (xy 394.802862 -275.685084) (xy 394.843365 -275.71304)
			(xy 394.878858 -275.747132) (xy 394.908423 -275.786476) (xy 394.931294 -275.830053) (xy 394.946878 -275.876734)
			(xy 394.954773 -275.925311) (xy 394.955268 -275.949918) (xy 394.954773 -275.974525) (xy 394.954594 -275.975626)
			(xy 395.273272 -275.975626) (xy 395.273272 -275.92421) (xy 395.281315 -275.873428) (xy 395.297203 -275.824529)
			(xy 395.320546 -275.778717) (xy 395.350767 -275.737121) (xy 395.387123 -275.700765) (xy 395.428719 -275.670544)
			(xy 395.474531 -275.647201) (xy 395.52343 -275.631313) (xy 395.574212 -275.62327) (xy 395.625628 -275.62327)
			(xy 395.67641 -275.631313) (xy 395.725309 -275.647201) (xy 395.771121 -275.670544) (xy 395.812717 -275.700765)
			(xy 395.849073 -275.737121) (xy 395.879294 -275.778717) (xy 395.902637 -275.824529) (xy 395.918525 -275.873428)
			(xy 395.926568 -275.92421) (xy 395.927072 -275.949918) (xy 396.244076 -275.949918) (xy 396.248036 -275.900864)
			(xy 396.259813 -275.85308) (xy 396.279104 -275.807804) (xy 396.305407 -275.766208) (xy 396.338042 -275.729371)
			(xy 396.376163 -275.698246) (xy 396.418784 -275.673639) (xy 396.4648 -275.656187) (xy 396.513019 -275.646343)
			(xy 396.562194 -275.644362) (xy 396.611049 -275.650294) (xy 396.65832 -275.663986) (xy 396.702782 -275.685084)
			(xy 396.743285 -275.71304) (xy 396.778778 -275.747132) (xy 396.808343 -275.786476) (xy 396.831214 -275.830053)
			(xy 396.846798 -275.876734) (xy 396.854693 -275.925311) (xy 396.855188 -275.949918) (xy 396.854693 -275.974525)
			(xy 396.854514 -275.975626) (xy 397.173192 -275.975626) (xy 397.173192 -275.92421) (xy 397.181235 -275.873428)
			(xy 397.197123 -275.824529) (xy 397.220466 -275.778717) (xy 397.250687 -275.737121) (xy 397.287043 -275.700765)
			(xy 397.328639 -275.670544) (xy 397.374451 -275.647201) (xy 397.42335 -275.631313) (xy 397.474132 -275.62327)
			(xy 397.525548 -275.62327) (xy 397.57633 -275.631313) (xy 397.625229 -275.647201) (xy 397.671041 -275.670544)
			(xy 397.712637 -275.700765) (xy 397.748993 -275.737121) (xy 397.779214 -275.778717) (xy 397.802557 -275.824529)
			(xy 397.818445 -275.873428) (xy 397.826488 -275.92421) (xy 397.826992 -275.949918) (xy 398.143996 -275.949918)
			(xy 398.147956 -275.900864) (xy 398.159733 -275.85308) (xy 398.179024 -275.807804) (xy 398.205327 -275.766208)
			(xy 398.237962 -275.729371) (xy 398.276083 -275.698246) (xy 398.318704 -275.673639) (xy 398.36472 -275.656187)
			(xy 398.412939 -275.646343) (xy 398.462114 -275.644362) (xy 398.510969 -275.650294) (xy 398.55824 -275.663986)
			(xy 398.602702 -275.685084) (xy 398.643205 -275.71304) (xy 398.678698 -275.747132) (xy 398.708263 -275.786476)
			(xy 398.731134 -275.830053) (xy 398.746718 -275.876734) (xy 398.754613 -275.925311) (xy 398.755108 -275.949918)
			(xy 398.754613 -275.974525) (xy 398.754434 -275.975626) (xy 399.073366 -275.975626) (xy 399.073366 -275.92421)
			(xy 399.081409 -275.873428) (xy 399.097297 -275.824529) (xy 399.12064 -275.778717) (xy 399.150861 -275.737121)
			(xy 399.187217 -275.700765) (xy 399.228813 -275.670544) (xy 399.274625 -275.647201) (xy 399.323524 -275.631313)
			(xy 399.374306 -275.62327) (xy 399.425722 -275.62327) (xy 399.476504 -275.631313) (xy 399.525403 -275.647201)
			(xy 399.571215 -275.670544) (xy 399.612811 -275.700765) (xy 399.649167 -275.737121) (xy 399.679388 -275.778717)
			(xy 399.702731 -275.824529) (xy 399.718619 -275.873428) (xy 399.726662 -275.92421) (xy 399.727166 -275.949918)
			(xy 400.04417 -275.949918) (xy 400.04813 -275.900864) (xy 400.059907 -275.85308) (xy 400.079198 -275.807804)
			(xy 400.105501 -275.766208) (xy 400.138136 -275.729371) (xy 400.176257 -275.698246) (xy 400.218878 -275.673639)
			(xy 400.264894 -275.656187) (xy 400.313113 -275.646343) (xy 400.362288 -275.644362) (xy 400.411143 -275.650294)
			(xy 400.458414 -275.663986) (xy 400.502876 -275.685084) (xy 400.543379 -275.71304) (xy 400.578872 -275.747132)
			(xy 400.608437 -275.786476) (xy 400.631308 -275.830053) (xy 400.646892 -275.876734) (xy 400.654787 -275.925311)
			(xy 400.655282 -275.949918) (xy 400.654787 -275.974525) (xy 400.654608 -275.975626) (xy 400.973286 -275.975626)
			(xy 400.973286 -275.92421) (xy 400.981329 -275.873428) (xy 400.997217 -275.824529) (xy 401.02056 -275.778717)
			(xy 401.050781 -275.737121) (xy 401.087137 -275.700765) (xy 401.128733 -275.670544) (xy 401.174545 -275.647201)
			(xy 401.223444 -275.631313) (xy 401.274226 -275.62327) (xy 401.325642 -275.62327) (xy 401.376424 -275.631313)
			(xy 401.425323 -275.647201) (xy 401.471135 -275.670544) (xy 401.512731 -275.700765) (xy 401.549087 -275.737121)
			(xy 401.579308 -275.778717) (xy 401.602651 -275.824529) (xy 401.618539 -275.873428) (xy 401.626582 -275.92421)
			(xy 401.627086 -275.949918) (xy 401.94409 -275.949918) (xy 401.94805 -275.900864) (xy 401.959827 -275.85308)
			(xy 401.979118 -275.807804) (xy 402.005421 -275.766208) (xy 402.038056 -275.729371) (xy 402.076177 -275.698246)
			(xy 402.118798 -275.673639) (xy 402.164814 -275.656187) (xy 402.213033 -275.646343) (xy 402.262208 -275.644362)
			(xy 402.311063 -275.650294) (xy 402.358334 -275.663986) (xy 402.402796 -275.685084) (xy 402.443299 -275.71304)
			(xy 402.478792 -275.747132) (xy 402.508357 -275.786476) (xy 402.531228 -275.830053) (xy 402.546812 -275.876734)
			(xy 402.554707 -275.925311) (xy 402.555202 -275.949918) (xy 402.554707 -275.974525) (xy 402.554528 -275.975626)
			(xy 402.873206 -275.975626) (xy 402.873206 -275.92421) (xy 402.881249 -275.873428) (xy 402.897137 -275.824529)
			(xy 402.92048 -275.778717) (xy 402.950701 -275.737121) (xy 402.987057 -275.700765) (xy 403.028653 -275.670544)
			(xy 403.074465 -275.647201) (xy 403.123364 -275.631313) (xy 403.174146 -275.62327) (xy 403.225562 -275.62327)
			(xy 403.276344 -275.631313) (xy 403.325243 -275.647201) (xy 403.371055 -275.670544) (xy 403.412651 -275.700765)
			(xy 403.449007 -275.737121) (xy 403.479228 -275.778717) (xy 403.502571 -275.824529) (xy 403.518459 -275.873428)
			(xy 403.526502 -275.92421) (xy 403.527006 -275.949918) (xy 403.84401 -275.949918) (xy 403.84797 -275.900864)
			(xy 403.859747 -275.85308) (xy 403.879038 -275.807804) (xy 403.905341 -275.766208) (xy 403.937976 -275.729371)
			(xy 403.976097 -275.698246) (xy 404.018718 -275.673639) (xy 404.064734 -275.656187) (xy 404.112953 -275.646343)
			(xy 404.162128 -275.644362) (xy 404.210983 -275.650294) (xy 404.258254 -275.663986) (xy 404.302716 -275.685084)
			(xy 404.343219 -275.71304) (xy 404.378712 -275.747132) (xy 404.408277 -275.786476) (xy 404.431148 -275.830053)
			(xy 404.446732 -275.876734) (xy 404.454627 -275.925311) (xy 404.455122 -275.949918) (xy 404.454627 -275.974525)
			(xy 404.454448 -275.975626) (xy 404.77338 -275.975626) (xy 404.77338 -275.92421) (xy 404.781423 -275.873428)
			(xy 404.797311 -275.824529) (xy 404.820654 -275.778717) (xy 404.850875 -275.737121) (xy 404.887231 -275.700765)
			(xy 404.928827 -275.670544) (xy 404.974639 -275.647201) (xy 405.023538 -275.631313) (xy 405.07432 -275.62327)
			(xy 405.125736 -275.62327) (xy 405.176518 -275.631313) (xy 405.225417 -275.647201) (xy 405.271229 -275.670544)
			(xy 405.312825 -275.700765) (xy 405.349181 -275.737121) (xy 405.379402 -275.778717) (xy 405.402745 -275.824529)
			(xy 405.418633 -275.873428) (xy 405.426676 -275.92421) (xy 405.42718 -275.949918) (xy 405.744184 -275.949918)
			(xy 405.748144 -275.900864) (xy 405.759921 -275.85308) (xy 405.779212 -275.807804) (xy 405.805515 -275.766208)
			(xy 405.83815 -275.729371) (xy 405.876271 -275.698246) (xy 405.918892 -275.673639) (xy 405.964908 -275.656187)
			(xy 406.013127 -275.646343) (xy 406.062302 -275.644362) (xy 406.111157 -275.650294) (xy 406.158428 -275.663986)
			(xy 406.20289 -275.685084) (xy 406.243393 -275.71304) (xy 406.278886 -275.747132) (xy 406.308451 -275.786476)
			(xy 406.331322 -275.830053) (xy 406.346906 -275.876734) (xy 406.354801 -275.925311) (xy 406.355296 -275.949918)
			(xy 406.354801 -275.974525) (xy 406.354622 -275.975626) (xy 406.6733 -275.975626) (xy 406.6733 -275.92421)
			(xy 406.681343 -275.873428) (xy 406.697231 -275.824529) (xy 406.720574 -275.778717) (xy 406.750795 -275.737121)
			(xy 406.787151 -275.700765) (xy 406.828747 -275.670544) (xy 406.874559 -275.647201) (xy 406.923458 -275.631313)
			(xy 406.97424 -275.62327) (xy 407.025656 -275.62327) (xy 407.076438 -275.631313) (xy 407.125337 -275.647201)
			(xy 407.171149 -275.670544) (xy 407.212745 -275.700765) (xy 407.249101 -275.737121) (xy 407.279322 -275.778717)
			(xy 407.302665 -275.824529) (xy 407.318553 -275.873428) (xy 407.326596 -275.92421) (xy 407.3271 -275.949918)
			(xy 407.644104 -275.949918) (xy 407.648064 -275.900864) (xy 407.659841 -275.85308) (xy 407.679132 -275.807804)
			(xy 407.705435 -275.766208) (xy 407.73807 -275.729371) (xy 407.776191 -275.698246) (xy 407.818812 -275.673639)
			(xy 407.864828 -275.656187) (xy 407.913047 -275.646343) (xy 407.962222 -275.644362) (xy 408.011077 -275.650294)
			(xy 408.058348 -275.663986) (xy 408.10281 -275.685084) (xy 408.143313 -275.71304) (xy 408.178806 -275.747132)
			(xy 408.208371 -275.786476) (xy 408.231242 -275.830053) (xy 408.246826 -275.876734) (xy 408.254721 -275.925311)
			(xy 408.255216 -275.949918) (xy 408.254721 -275.974525) (xy 408.254583 -275.975372) (xy 408.572966 -275.975372)
			(xy 408.572966 -275.923956) (xy 408.581009 -275.873174) (xy 408.596897 -275.824275) (xy 408.62024 -275.778463)
			(xy 408.650461 -275.736867) (xy 408.686817 -275.700511) (xy 408.728413 -275.67029) (xy 408.774225 -275.646947)
			(xy 408.823124 -275.631059) (xy 408.873906 -275.623016) (xy 408.925322 -275.623016) (xy 408.976104 -275.631059)
			(xy 409.025003 -275.646947) (xy 409.070815 -275.67029) (xy 409.112411 -275.700511) (xy 409.148767 -275.736867)
			(xy 409.178988 -275.778463) (xy 409.202331 -275.824275) (xy 409.218219 -275.873174) (xy 409.226262 -275.923956)
			(xy 409.226766 -275.949664) (xy 409.226761 -275.949918) (xy 409.544024 -275.949918) (xy 409.547984 -275.900864)
			(xy 409.559761 -275.85308) (xy 409.579052 -275.807804) (xy 409.605355 -275.766208) (xy 409.63799 -275.729371)
			(xy 409.676111 -275.698246) (xy 409.718732 -275.673639) (xy 409.764748 -275.656187) (xy 409.812967 -275.646343)
			(xy 409.862142 -275.644362) (xy 409.910997 -275.650294) (xy 409.958268 -275.663986) (xy 410.00273 -275.685084)
			(xy 410.043233 -275.71304) (xy 410.078726 -275.747132) (xy 410.108291 -275.786476) (xy 410.131162 -275.830053)
			(xy 410.146746 -275.876734) (xy 410.154641 -275.925311) (xy 410.155136 -275.949918) (xy 410.154641 -275.974525)
			(xy 410.154462 -275.975626) (xy 410.472886 -275.975626) (xy 410.472886 -275.92421) (xy 410.480929 -275.873428)
			(xy 410.496817 -275.824529) (xy 410.52016 -275.778717) (xy 410.550381 -275.737121) (xy 410.586737 -275.700765)
			(xy 410.628333 -275.670544) (xy 410.674145 -275.647201) (xy 410.723044 -275.631313) (xy 410.773826 -275.62327)
			(xy 410.825242 -275.62327) (xy 410.876024 -275.631313) (xy 410.924923 -275.647201) (xy 410.970735 -275.670544)
			(xy 411.012331 -275.700765) (xy 411.048687 -275.737121) (xy 411.078908 -275.778717) (xy 411.102251 -275.824529)
			(xy 411.118139 -275.873428) (xy 411.126182 -275.92421) (xy 411.126686 -275.949918) (xy 411.444198 -275.949918)
			(xy 411.448158 -275.900864) (xy 411.459935 -275.85308) (xy 411.479226 -275.807804) (xy 411.505529 -275.766208)
			(xy 411.538164 -275.729371) (xy 411.576285 -275.698246) (xy 411.618906 -275.673639) (xy 411.664922 -275.656187)
			(xy 411.713141 -275.646343) (xy 411.762316 -275.644362) (xy 411.811171 -275.650294) (xy 411.858442 -275.663986)
			(xy 411.902904 -275.685084) (xy 411.943407 -275.71304) (xy 411.9789 -275.747132) (xy 412.008465 -275.786476)
			(xy 412.031336 -275.830053) (xy 412.04692 -275.876734) (xy 412.054815 -275.925311) (xy 412.05531 -275.949918)
			(xy 412.054815 -275.974525) (xy 412.054677 -275.975372) (xy 412.37306 -275.975372) (xy 412.37306 -275.923956)
			(xy 412.381103 -275.873174) (xy 412.396991 -275.824275) (xy 412.420334 -275.778463) (xy 412.450555 -275.736867)
			(xy 412.486911 -275.700511) (xy 412.528507 -275.67029) (xy 412.574319 -275.646947) (xy 412.623218 -275.631059)
			(xy 412.674 -275.623016) (xy 412.725416 -275.623016) (xy 412.776198 -275.631059) (xy 412.825097 -275.646947)
			(xy 412.870909 -275.67029) (xy 412.912505 -275.700511) (xy 412.948861 -275.736867) (xy 412.979082 -275.778463)
			(xy 413.002425 -275.824275) (xy 413.018313 -275.873174) (xy 413.026356 -275.923956) (xy 413.02686 -275.949664)
			(xy 413.026855 -275.949918) (xy 413.344118 -275.949918) (xy 413.348078 -275.900864) (xy 413.359855 -275.85308)
			(xy 413.379146 -275.807804) (xy 413.405449 -275.766208) (xy 413.438084 -275.729371) (xy 413.476205 -275.698246)
			(xy 413.518826 -275.673639) (xy 413.564842 -275.656187) (xy 413.613061 -275.646343) (xy 413.662236 -275.644362)
			(xy 413.711091 -275.650294) (xy 413.758362 -275.663986) (xy 413.802824 -275.685084) (xy 413.843327 -275.71304)
			(xy 413.87882 -275.747132) (xy 413.908385 -275.786476) (xy 413.931256 -275.830053) (xy 413.94684 -275.876734)
			(xy 413.954735 -275.925311) (xy 413.95523 -275.949918) (xy 413.954735 -275.974525) (xy 413.954556 -275.975626)
			(xy 414.27298 -275.975626) (xy 414.27298 -275.92421) (xy 414.281023 -275.873428) (xy 414.296911 -275.824529)
			(xy 414.320254 -275.778717) (xy 414.350475 -275.737121) (xy 414.386831 -275.700765) (xy 414.428427 -275.670544)
			(xy 414.474239 -275.647201) (xy 414.523138 -275.631313) (xy 414.57392 -275.62327) (xy 414.625336 -275.62327)
			(xy 414.676118 -275.631313) (xy 414.725017 -275.647201) (xy 414.770829 -275.670544) (xy 414.812425 -275.700765)
			(xy 414.848781 -275.737121) (xy 414.879002 -275.778717) (xy 414.902345 -275.824529) (xy 414.918233 -275.873428)
			(xy 414.926276 -275.92421) (xy 414.92678 -275.949918) (xy 415.244038 -275.949918) (xy 415.247998 -275.900864)
			(xy 415.259775 -275.85308) (xy 415.279066 -275.807804) (xy 415.305369 -275.766208) (xy 415.338004 -275.729371)
			(xy 415.376125 -275.698246) (xy 415.418746 -275.673639) (xy 415.464762 -275.656187) (xy 415.512981 -275.646343)
			(xy 415.562156 -275.644362) (xy 415.611011 -275.650294) (xy 415.658282 -275.663986) (xy 415.702744 -275.685084)
			(xy 415.743247 -275.71304) (xy 415.77874 -275.747132) (xy 415.808305 -275.786476) (xy 415.831176 -275.830053)
			(xy 415.84676 -275.876734) (xy 415.854655 -275.925311) (xy 415.85515 -275.949918) (xy 415.854655 -275.974525)
			(xy 415.854517 -275.975372) (xy 416.1729 -275.975372) (xy 416.1729 -275.923956) (xy 416.180943 -275.873174)
			(xy 416.196831 -275.824275) (xy 416.220174 -275.778463) (xy 416.250395 -275.736867) (xy 416.286751 -275.700511)
			(xy 416.328347 -275.67029) (xy 416.374159 -275.646947) (xy 416.423058 -275.631059) (xy 416.47384 -275.623016)
			(xy 416.525256 -275.623016) (xy 416.576038 -275.631059) (xy 416.624937 -275.646947) (xy 416.670749 -275.67029)
			(xy 416.712345 -275.700511) (xy 416.748701 -275.736867) (xy 416.778922 -275.778463) (xy 416.802265 -275.824275)
			(xy 416.818153 -275.873174) (xy 416.826196 -275.923956) (xy 416.8267 -275.949664) (xy 416.826695 -275.949918)
			(xy 417.144212 -275.949918) (xy 417.148172 -275.900864) (xy 417.159949 -275.85308) (xy 417.17924 -275.807804)
			(xy 417.205543 -275.766208) (xy 417.238178 -275.729371) (xy 417.276299 -275.698246) (xy 417.31892 -275.673639)
			(xy 417.364936 -275.656187) (xy 417.413155 -275.646343) (xy 417.46233 -275.644362) (xy 417.511185 -275.650294)
			(xy 417.558456 -275.663986) (xy 417.602918 -275.685084) (xy 417.643421 -275.71304) (xy 417.678914 -275.747132)
			(xy 417.708479 -275.786476) (xy 417.73135 -275.830053) (xy 417.746934 -275.876734) (xy 417.754829 -275.925311)
			(xy 417.755324 -275.949918) (xy 417.754829 -275.974525) (xy 417.75465 -275.975626) (xy 418.07282 -275.975626)
			(xy 418.07282 -275.92421) (xy 418.080863 -275.873428) (xy 418.096751 -275.824529) (xy 418.120094 -275.778717)
			(xy 418.150315 -275.737121) (xy 418.186671 -275.700765) (xy 418.228267 -275.670544) (xy 418.274079 -275.647201)
			(xy 418.322978 -275.631313) (xy 418.37376 -275.62327) (xy 418.425176 -275.62327) (xy 418.475958 -275.631313)
			(xy 418.524857 -275.647201) (xy 418.570669 -275.670544) (xy 418.612265 -275.700765) (xy 418.648621 -275.737121)
			(xy 418.678842 -275.778717) (xy 418.702185 -275.824529) (xy 418.718073 -275.873428) (xy 418.726116 -275.92421)
			(xy 418.72662 -275.949918) (xy 419.044132 -275.949918) (xy 419.048092 -275.900864) (xy 419.059869 -275.85308)
			(xy 419.07916 -275.807804) (xy 419.105463 -275.766208) (xy 419.138098 -275.729371) (xy 419.176219 -275.698246)
			(xy 419.21884 -275.673639) (xy 419.264856 -275.656187) (xy 419.313075 -275.646343) (xy 419.36225 -275.644362)
			(xy 419.411105 -275.650294) (xy 419.458376 -275.663986) (xy 419.502838 -275.685084) (xy 419.543341 -275.71304)
			(xy 419.578834 -275.747132) (xy 419.608399 -275.786476) (xy 419.63127 -275.830053) (xy 419.646854 -275.876734)
			(xy 419.654749 -275.925311) (xy 419.655244 -275.949918) (xy 419.654749 -275.974525) (xy 419.654611 -275.975372)
			(xy 419.972994 -275.975372) (xy 419.972994 -275.923956) (xy 419.981037 -275.873174) (xy 419.996925 -275.824275)
			(xy 420.020268 -275.778463) (xy 420.050489 -275.736867) (xy 420.086845 -275.700511) (xy 420.128441 -275.67029)
			(xy 420.174253 -275.646947) (xy 420.223152 -275.631059) (xy 420.273934 -275.623016) (xy 420.32535 -275.623016)
			(xy 420.376132 -275.631059) (xy 420.425031 -275.646947) (xy 420.470843 -275.67029) (xy 420.512439 -275.700511)
			(xy 420.548795 -275.736867) (xy 420.579016 -275.778463) (xy 420.602359 -275.824275) (xy 420.618247 -275.873174)
			(xy 420.62629 -275.923956) (xy 420.626794 -275.949664) (xy 420.626789 -275.949918) (xy 420.944052 -275.949918)
			(xy 420.948012 -275.900864) (xy 420.959789 -275.85308) (xy 420.97908 -275.807804) (xy 421.005383 -275.766208)
			(xy 421.038018 -275.729371) (xy 421.076139 -275.698246) (xy 421.11876 -275.673639) (xy 421.164776 -275.656187)
			(xy 421.212995 -275.646343) (xy 421.26217 -275.644362) (xy 421.311025 -275.650294) (xy 421.358296 -275.663986)
			(xy 421.402758 -275.685084) (xy 421.443261 -275.71304) (xy 421.478754 -275.747132) (xy 421.508319 -275.786476)
			(xy 421.53119 -275.830053) (xy 421.546774 -275.876734) (xy 421.554669 -275.925311) (xy 421.555164 -275.949918)
			(xy 421.554669 -275.974525) (xy 421.546774 -276.023102) (xy 421.53119 -276.069783) (xy 421.508319 -276.11336)
			(xy 421.478754 -276.152704) (xy 421.443261 -276.186796) (xy 421.402758 -276.214752) (xy 421.358296 -276.23585)
			(xy 421.311025 -276.249542) (xy 421.26217 -276.255474) (xy 421.212995 -276.253493) (xy 421.164776 -276.243649)
			(xy 421.11876 -276.226197) (xy 421.076139 -276.20159) (xy 421.038018 -276.170465) (xy 421.005383 -276.133628)
			(xy 420.97908 -276.092032) (xy 420.959789 -276.046756) (xy 420.948012 -275.998972) (xy 420.944052 -275.949918)
			(xy 420.626789 -275.949918) (xy 420.62629 -275.975372) (xy 420.618247 -276.026154) (xy 420.602359 -276.075053)
			(xy 420.579016 -276.120865) (xy 420.548795 -276.162461) (xy 420.512439 -276.198817) (xy 420.470843 -276.229038)
			(xy 420.425031 -276.252381) (xy 420.376132 -276.268269) (xy 420.32535 -276.276312) (xy 420.273934 -276.276312)
			(xy 420.223152 -276.268269) (xy 420.174253 -276.252381) (xy 420.128441 -276.229038) (xy 420.086845 -276.198817)
			(xy 420.050489 -276.162461) (xy 420.020268 -276.120865) (xy 419.996925 -276.075053) (xy 419.981037 -276.026154)
			(xy 419.972994 -275.975372) (xy 419.654611 -275.975372) (xy 419.646854 -276.023102) (xy 419.63127 -276.069783)
			(xy 419.608399 -276.11336) (xy 419.578834 -276.152704) (xy 419.543341 -276.186796) (xy 419.502838 -276.214752)
			(xy 419.458376 -276.23585) (xy 419.411105 -276.249542) (xy 419.36225 -276.255474) (xy 419.313075 -276.253493)
			(xy 419.264856 -276.243649) (xy 419.21884 -276.226197) (xy 419.176219 -276.20159) (xy 419.138098 -276.170465)
			(xy 419.105463 -276.133628) (xy 419.07916 -276.092032) (xy 419.059869 -276.046756) (xy 419.048092 -275.998972)
			(xy 419.044132 -275.949918) (xy 418.72662 -275.949918) (xy 418.726116 -275.975626) (xy 418.718073 -276.026408)
			(xy 418.702185 -276.075307) (xy 418.678842 -276.121119) (xy 418.648621 -276.162715) (xy 418.612265 -276.199071)
			(xy 418.570669 -276.229292) (xy 418.524857 -276.252635) (xy 418.475958 -276.268523) (xy 418.425176 -276.276566)
			(xy 418.37376 -276.276566) (xy 418.322978 -276.268523) (xy 418.274079 -276.252635) (xy 418.228267 -276.229292)
			(xy 418.186671 -276.199071) (xy 418.150315 -276.162715) (xy 418.120094 -276.121119) (xy 418.096751 -276.075307)
			(xy 418.080863 -276.026408) (xy 418.07282 -275.975626) (xy 417.75465 -275.975626) (xy 417.746934 -276.023102)
			(xy 417.73135 -276.069783) (xy 417.708479 -276.11336) (xy 417.678914 -276.152704) (xy 417.643421 -276.186796)
			(xy 417.602918 -276.214752) (xy 417.558456 -276.23585) (xy 417.511185 -276.249542) (xy 417.46233 -276.255474)
			(xy 417.413155 -276.253493) (xy 417.364936 -276.243649) (xy 417.31892 -276.226197) (xy 417.276299 -276.20159)
			(xy 417.238178 -276.170465) (xy 417.205543 -276.133628) (xy 417.17924 -276.092032) (xy 417.159949 -276.046756)
			(xy 417.148172 -275.998972) (xy 417.144212 -275.949918) (xy 416.826695 -275.949918) (xy 416.826196 -275.975372)
			(xy 416.818153 -276.026154) (xy 416.802265 -276.075053) (xy 416.778922 -276.120865) (xy 416.748701 -276.162461)
			(xy 416.712345 -276.198817) (xy 416.670749 -276.229038) (xy 416.624937 -276.252381) (xy 416.576038 -276.268269)
			(xy 416.525256 -276.276312) (xy 416.47384 -276.276312) (xy 416.423058 -276.268269) (xy 416.374159 -276.252381)
			(xy 416.328347 -276.229038) (xy 416.286751 -276.198817) (xy 416.250395 -276.162461) (xy 416.220174 -276.120865)
			(xy 416.196831 -276.075053) (xy 416.180943 -276.026154) (xy 416.1729 -275.975372) (xy 415.854517 -275.975372)
			(xy 415.84676 -276.023102) (xy 415.831176 -276.069783) (xy 415.808305 -276.11336) (xy 415.77874 -276.152704)
			(xy 415.743247 -276.186796) (xy 415.702744 -276.214752) (xy 415.658282 -276.23585) (xy 415.611011 -276.249542)
			(xy 415.562156 -276.255474) (xy 415.512981 -276.253493) (xy 415.464762 -276.243649) (xy 415.418746 -276.226197)
			(xy 415.376125 -276.20159) (xy 415.338004 -276.170465) (xy 415.305369 -276.133628) (xy 415.279066 -276.092032)
			(xy 415.259775 -276.046756) (xy 415.247998 -275.998972) (xy 415.244038 -275.949918) (xy 414.92678 -275.949918)
			(xy 414.926276 -275.975626) (xy 414.918233 -276.026408) (xy 414.902345 -276.075307) (xy 414.879002 -276.121119)
			(xy 414.848781 -276.162715) (xy 414.812425 -276.199071) (xy 414.770829 -276.229292) (xy 414.725017 -276.252635)
			(xy 414.676118 -276.268523) (xy 414.625336 -276.276566) (xy 414.57392 -276.276566) (xy 414.523138 -276.268523)
			(xy 414.474239 -276.252635) (xy 414.428427 -276.229292) (xy 414.386831 -276.199071) (xy 414.350475 -276.162715)
			(xy 414.320254 -276.121119) (xy 414.296911 -276.075307) (xy 414.281023 -276.026408) (xy 414.27298 -275.975626)
			(xy 413.954556 -275.975626) (xy 413.94684 -276.023102) (xy 413.931256 -276.069783) (xy 413.908385 -276.11336)
			(xy 413.87882 -276.152704) (xy 413.843327 -276.186796) (xy 413.802824 -276.214752) (xy 413.758362 -276.23585)
			(xy 413.711091 -276.249542) (xy 413.662236 -276.255474) (xy 413.613061 -276.253493) (xy 413.564842 -276.243649)
			(xy 413.518826 -276.226197) (xy 413.476205 -276.20159) (xy 413.438084 -276.170465) (xy 413.405449 -276.133628)
			(xy 413.379146 -276.092032) (xy 413.359855 -276.046756) (xy 413.348078 -275.998972) (xy 413.344118 -275.949918)
			(xy 413.026855 -275.949918) (xy 413.026356 -275.975372) (xy 413.018313 -276.026154) (xy 413.002425 -276.075053)
			(xy 412.979082 -276.120865) (xy 412.948861 -276.162461) (xy 412.912505 -276.198817) (xy 412.870909 -276.229038)
			(xy 412.825097 -276.252381) (xy 412.776198 -276.268269) (xy 412.725416 -276.276312) (xy 412.674 -276.276312)
			(xy 412.623218 -276.268269) (xy 412.574319 -276.252381) (xy 412.528507 -276.229038) (xy 412.486911 -276.198817)
			(xy 412.450555 -276.162461) (xy 412.420334 -276.120865) (xy 412.396991 -276.075053) (xy 412.381103 -276.026154)
			(xy 412.37306 -275.975372) (xy 412.054677 -275.975372) (xy 412.04692 -276.023102) (xy 412.031336 -276.069783)
			(xy 412.008465 -276.11336) (xy 411.9789 -276.152704) (xy 411.943407 -276.186796) (xy 411.902904 -276.214752)
			(xy 411.858442 -276.23585) (xy 411.811171 -276.249542) (xy 411.762316 -276.255474) (xy 411.713141 -276.253493)
			(xy 411.664922 -276.243649) (xy 411.618906 -276.226197) (xy 411.576285 -276.20159) (xy 411.538164 -276.170465)
			(xy 411.505529 -276.133628) (xy 411.479226 -276.092032) (xy 411.459935 -276.046756) (xy 411.448158 -275.998972)
			(xy 411.444198 -275.949918) (xy 411.126686 -275.949918) (xy 411.126182 -275.975626) (xy 411.118139 -276.026408)
			(xy 411.102251 -276.075307) (xy 411.078908 -276.121119) (xy 411.048687 -276.162715) (xy 411.012331 -276.199071)
			(xy 410.970735 -276.229292) (xy 410.924923 -276.252635) (xy 410.876024 -276.268523) (xy 410.825242 -276.276566)
			(xy 410.773826 -276.276566) (xy 410.723044 -276.268523) (xy 410.674145 -276.252635) (xy 410.628333 -276.229292)
			(xy 410.586737 -276.199071) (xy 410.550381 -276.162715) (xy 410.52016 -276.121119) (xy 410.496817 -276.075307)
			(xy 410.480929 -276.026408) (xy 410.472886 -275.975626) (xy 410.154462 -275.975626) (xy 410.146746 -276.023102)
			(xy 410.131162 -276.069783) (xy 410.108291 -276.11336) (xy 410.078726 -276.152704) (xy 410.043233 -276.186796)
			(xy 410.00273 -276.214752) (xy 409.958268 -276.23585) (xy 409.910997 -276.249542) (xy 409.862142 -276.255474)
			(xy 409.812967 -276.253493) (xy 409.764748 -276.243649) (xy 409.718732 -276.226197) (xy 409.676111 -276.20159)
			(xy 409.63799 -276.170465) (xy 409.605355 -276.133628) (xy 409.579052 -276.092032) (xy 409.559761 -276.046756)
			(xy 409.547984 -275.998972) (xy 409.544024 -275.949918) (xy 409.226761 -275.949918) (xy 409.226262 -275.975372)
			(xy 409.218219 -276.026154) (xy 409.202331 -276.075053) (xy 409.178988 -276.120865) (xy 409.148767 -276.162461)
			(xy 409.112411 -276.198817) (xy 409.070815 -276.229038) (xy 409.025003 -276.252381) (xy 408.976104 -276.268269)
			(xy 408.925322 -276.276312) (xy 408.873906 -276.276312) (xy 408.823124 -276.268269) (xy 408.774225 -276.252381)
			(xy 408.728413 -276.229038) (xy 408.686817 -276.198817) (xy 408.650461 -276.162461) (xy 408.62024 -276.120865)
			(xy 408.596897 -276.075053) (xy 408.581009 -276.026154) (xy 408.572966 -275.975372) (xy 408.254583 -275.975372)
			(xy 408.246826 -276.023102) (xy 408.231242 -276.069783) (xy 408.208371 -276.11336) (xy 408.178806 -276.152704)
			(xy 408.143313 -276.186796) (xy 408.10281 -276.214752) (xy 408.058348 -276.23585) (xy 408.011077 -276.249542)
			(xy 407.962222 -276.255474) (xy 407.913047 -276.253493) (xy 407.864828 -276.243649) (xy 407.818812 -276.226197)
			(xy 407.776191 -276.20159) (xy 407.73807 -276.170465) (xy 407.705435 -276.133628) (xy 407.679132 -276.092032)
			(xy 407.659841 -276.046756) (xy 407.648064 -275.998972) (xy 407.644104 -275.949918) (xy 407.3271 -275.949918)
			(xy 407.326596 -275.975626) (xy 407.318553 -276.026408) (xy 407.302665 -276.075307) (xy 407.279322 -276.121119)
			(xy 407.249101 -276.162715) (xy 407.212745 -276.199071) (xy 407.171149 -276.229292) (xy 407.125337 -276.252635)
			(xy 407.076438 -276.268523) (xy 407.025656 -276.276566) (xy 406.97424 -276.276566) (xy 406.923458 -276.268523)
			(xy 406.874559 -276.252635) (xy 406.828747 -276.229292) (xy 406.787151 -276.199071) (xy 406.750795 -276.162715)
			(xy 406.720574 -276.121119) (xy 406.697231 -276.075307) (xy 406.681343 -276.026408) (xy 406.6733 -275.975626)
			(xy 406.354622 -275.975626) (xy 406.346906 -276.023102) (xy 406.331322 -276.069783) (xy 406.308451 -276.11336)
			(xy 406.278886 -276.152704) (xy 406.243393 -276.186796) (xy 406.20289 -276.214752) (xy 406.158428 -276.23585)
			(xy 406.111157 -276.249542) (xy 406.062302 -276.255474) (xy 406.013127 -276.253493) (xy 405.964908 -276.243649)
			(xy 405.918892 -276.226197) (xy 405.876271 -276.20159) (xy 405.83815 -276.170465) (xy 405.805515 -276.133628)
			(xy 405.779212 -276.092032) (xy 405.759921 -276.046756) (xy 405.748144 -275.998972) (xy 405.744184 -275.949918)
			(xy 405.42718 -275.949918) (xy 405.426676 -275.975626) (xy 405.418633 -276.026408) (xy 405.402745 -276.075307)
			(xy 405.379402 -276.121119) (xy 405.349181 -276.162715) (xy 405.312825 -276.199071) (xy 405.271229 -276.229292)
			(xy 405.225417 -276.252635) (xy 405.176518 -276.268523) (xy 405.125736 -276.276566) (xy 405.07432 -276.276566)
			(xy 405.023538 -276.268523) (xy 404.974639 -276.252635) (xy 404.928827 -276.229292) (xy 404.887231 -276.199071)
			(xy 404.850875 -276.162715) (xy 404.820654 -276.121119) (xy 404.797311 -276.075307) (xy 404.781423 -276.026408)
			(xy 404.77338 -275.975626) (xy 404.454448 -275.975626) (xy 404.446732 -276.023102) (xy 404.431148 -276.069783)
			(xy 404.408277 -276.11336) (xy 404.378712 -276.152704) (xy 404.343219 -276.186796) (xy 404.302716 -276.214752)
			(xy 404.258254 -276.23585) (xy 404.210983 -276.249542) (xy 404.162128 -276.255474) (xy 404.112953 -276.253493)
			(xy 404.064734 -276.243649) (xy 404.018718 -276.226197) (xy 403.976097 -276.20159) (xy 403.937976 -276.170465)
			(xy 403.905341 -276.133628) (xy 403.879038 -276.092032) (xy 403.859747 -276.046756) (xy 403.84797 -275.998972)
			(xy 403.84401 -275.949918) (xy 403.527006 -275.949918) (xy 403.526502 -275.975626) (xy 403.518459 -276.026408)
			(xy 403.502571 -276.075307) (xy 403.479228 -276.121119) (xy 403.449007 -276.162715) (xy 403.412651 -276.199071)
			(xy 403.371055 -276.229292) (xy 403.325243 -276.252635) (xy 403.276344 -276.268523) (xy 403.225562 -276.276566)
			(xy 403.174146 -276.276566) (xy 403.123364 -276.268523) (xy 403.074465 -276.252635) (xy 403.028653 -276.229292)
			(xy 402.987057 -276.199071) (xy 402.950701 -276.162715) (xy 402.92048 -276.121119) (xy 402.897137 -276.075307)
			(xy 402.881249 -276.026408) (xy 402.873206 -275.975626) (xy 402.554528 -275.975626) (xy 402.546812 -276.023102)
			(xy 402.531228 -276.069783) (xy 402.508357 -276.11336) (xy 402.478792 -276.152704) (xy 402.443299 -276.186796)
			(xy 402.402796 -276.214752) (xy 402.358334 -276.23585) (xy 402.311063 -276.249542) (xy 402.262208 -276.255474)
			(xy 402.213033 -276.253493) (xy 402.164814 -276.243649) (xy 402.118798 -276.226197) (xy 402.076177 -276.20159)
			(xy 402.038056 -276.170465) (xy 402.005421 -276.133628) (xy 401.979118 -276.092032) (xy 401.959827 -276.046756)
			(xy 401.94805 -275.998972) (xy 401.94409 -275.949918) (xy 401.627086 -275.949918) (xy 401.626582 -275.975626)
			(xy 401.618539 -276.026408) (xy 401.602651 -276.075307) (xy 401.579308 -276.121119) (xy 401.549087 -276.162715)
			(xy 401.512731 -276.199071) (xy 401.471135 -276.229292) (xy 401.425323 -276.252635) (xy 401.376424 -276.268523)
			(xy 401.325642 -276.276566) (xy 401.274226 -276.276566) (xy 401.223444 -276.268523) (xy 401.174545 -276.252635)
			(xy 401.128733 -276.229292) (xy 401.087137 -276.199071) (xy 401.050781 -276.162715) (xy 401.02056 -276.121119)
			(xy 400.997217 -276.075307) (xy 400.981329 -276.026408) (xy 400.973286 -275.975626) (xy 400.654608 -275.975626)
			(xy 400.646892 -276.023102) (xy 400.631308 -276.069783) (xy 400.608437 -276.11336) (xy 400.578872 -276.152704)
			(xy 400.543379 -276.186796) (xy 400.502876 -276.214752) (xy 400.458414 -276.23585) (xy 400.411143 -276.249542)
			(xy 400.362288 -276.255474) (xy 400.313113 -276.253493) (xy 400.264894 -276.243649) (xy 400.218878 -276.226197)
			(xy 400.176257 -276.20159) (xy 400.138136 -276.170465) (xy 400.105501 -276.133628) (xy 400.079198 -276.092032)
			(xy 400.059907 -276.046756) (xy 400.04813 -275.998972) (xy 400.04417 -275.949918) (xy 399.727166 -275.949918)
			(xy 399.726662 -275.975626) (xy 399.718619 -276.026408) (xy 399.702731 -276.075307) (xy 399.679388 -276.121119)
			(xy 399.649167 -276.162715) (xy 399.612811 -276.199071) (xy 399.571215 -276.229292) (xy 399.525403 -276.252635)
			(xy 399.476504 -276.268523) (xy 399.425722 -276.276566) (xy 399.374306 -276.276566) (xy 399.323524 -276.268523)
			(xy 399.274625 -276.252635) (xy 399.228813 -276.229292) (xy 399.187217 -276.199071) (xy 399.150861 -276.162715)
			(xy 399.12064 -276.121119) (xy 399.097297 -276.075307) (xy 399.081409 -276.026408) (xy 399.073366 -275.975626)
			(xy 398.754434 -275.975626) (xy 398.746718 -276.023102) (xy 398.731134 -276.069783) (xy 398.708263 -276.11336)
			(xy 398.678698 -276.152704) (xy 398.643205 -276.186796) (xy 398.602702 -276.214752) (xy 398.55824 -276.23585)
			(xy 398.510969 -276.249542) (xy 398.462114 -276.255474) (xy 398.412939 -276.253493) (xy 398.36472 -276.243649)
			(xy 398.318704 -276.226197) (xy 398.276083 -276.20159) (xy 398.237962 -276.170465) (xy 398.205327 -276.133628)
			(xy 398.179024 -276.092032) (xy 398.159733 -276.046756) (xy 398.147956 -275.998972) (xy 398.143996 -275.949918)
			(xy 397.826992 -275.949918) (xy 397.826488 -275.975626) (xy 397.818445 -276.026408) (xy 397.802557 -276.075307)
			(xy 397.779214 -276.121119) (xy 397.748993 -276.162715) (xy 397.712637 -276.199071) (xy 397.671041 -276.229292)
			(xy 397.625229 -276.252635) (xy 397.57633 -276.268523) (xy 397.525548 -276.276566) (xy 397.474132 -276.276566)
			(xy 397.42335 -276.268523) (xy 397.374451 -276.252635) (xy 397.328639 -276.229292) (xy 397.287043 -276.199071)
			(xy 397.250687 -276.162715) (xy 397.220466 -276.121119) (xy 397.197123 -276.075307) (xy 397.181235 -276.026408)
			(xy 397.173192 -275.975626) (xy 396.854514 -275.975626) (xy 396.846798 -276.023102) (xy 396.831214 -276.069783)
			(xy 396.808343 -276.11336) (xy 396.778778 -276.152704) (xy 396.743285 -276.186796) (xy 396.702782 -276.214752)
			(xy 396.65832 -276.23585) (xy 396.611049 -276.249542) (xy 396.562194 -276.255474) (xy 396.513019 -276.253493)
			(xy 396.4648 -276.243649) (xy 396.418784 -276.226197) (xy 396.376163 -276.20159) (xy 396.338042 -276.170465)
			(xy 396.305407 -276.133628) (xy 396.279104 -276.092032) (xy 396.259813 -276.046756) (xy 396.248036 -275.998972)
			(xy 396.244076 -275.949918) (xy 395.927072 -275.949918) (xy 395.926568 -275.975626) (xy 395.918525 -276.026408)
			(xy 395.902637 -276.075307) (xy 395.879294 -276.121119) (xy 395.849073 -276.162715) (xy 395.812717 -276.199071)
			(xy 395.771121 -276.229292) (xy 395.725309 -276.252635) (xy 395.67641 -276.268523) (xy 395.625628 -276.276566)
			(xy 395.574212 -276.276566) (xy 395.52343 -276.268523) (xy 395.474531 -276.252635) (xy 395.428719 -276.229292)
			(xy 395.387123 -276.199071) (xy 395.350767 -276.162715) (xy 395.320546 -276.121119) (xy 395.297203 -276.075307)
			(xy 395.281315 -276.026408) (xy 395.273272 -275.975626) (xy 394.954594 -275.975626) (xy 394.946878 -276.023102)
			(xy 394.931294 -276.069783) (xy 394.908423 -276.11336) (xy 394.878858 -276.152704) (xy 394.843365 -276.186796)
			(xy 394.802862 -276.214752) (xy 394.7584 -276.23585) (xy 394.711129 -276.249542) (xy 394.662274 -276.255474)
			(xy 394.613099 -276.253493) (xy 394.56488 -276.243649) (xy 394.518864 -276.226197) (xy 394.476243 -276.20159)
			(xy 394.438122 -276.170465) (xy 394.405487 -276.133628) (xy 394.379184 -276.092032) (xy 394.359893 -276.046756)
			(xy 394.348116 -275.998972) (xy 394.344156 -275.949918) (xy 394.027152 -275.949918) (xy 394.026648 -275.975626)
			(xy 394.018605 -276.026408) (xy 394.002717 -276.075307) (xy 393.979374 -276.121119) (xy 393.949153 -276.162715)
			(xy 393.912797 -276.199071) (xy 393.871201 -276.229292) (xy 393.825389 -276.252635) (xy 393.77649 -276.268523)
			(xy 393.725708 -276.276566) (xy 393.674292 -276.276566) (xy 393.62351 -276.268523) (xy 393.574611 -276.252635)
			(xy 393.528799 -276.229292) (xy 393.487203 -276.199071) (xy 393.450847 -276.162715) (xy 393.420626 -276.121119)
			(xy 393.397283 -276.075307) (xy 393.381395 -276.026408) (xy 393.373352 -275.975626) (xy 393.05442 -275.975626)
			(xy 393.046704 -276.023102) (xy 393.03112 -276.069783) (xy 393.008249 -276.11336) (xy 392.978684 -276.152704)
			(xy 392.943191 -276.186796) (xy 392.902688 -276.214752) (xy 392.858226 -276.23585) (xy 392.810955 -276.249542)
			(xy 392.7621 -276.255474) (xy 392.712925 -276.253493) (xy 392.664706 -276.243649) (xy 392.61869 -276.226197)
			(xy 392.576069 -276.20159) (xy 392.537948 -276.170465) (xy 392.505313 -276.133628) (xy 392.47901 -276.092032)
			(xy 392.459719 -276.046756) (xy 392.447942 -275.998972) (xy 392.443982 -275.949918) (xy 383.78638 -275.949918)
			(xy 383.78638 -276.424898) (xy 384.369068 -276.424898) (xy 384.373028 -276.375844) (xy 384.384805 -276.32806)
			(xy 384.404096 -276.282784) (xy 384.430399 -276.241188) (xy 384.463034 -276.204351) (xy 384.501155 -276.173226)
			(xy 384.543776 -276.148619) (xy 384.589792 -276.131167) (xy 384.638011 -276.121323) (xy 384.687186 -276.119342)
			(xy 384.736041 -276.125274) (xy 384.783312 -276.138966) (xy 384.827774 -276.160064) (xy 384.868277 -276.18802)
			(xy 384.90377 -276.222112) (xy 384.933335 -276.261456) (xy 384.956206 -276.305033) (xy 384.97179 -276.351714)
			(xy 384.979685 -276.400291) (xy 384.98018 -276.424898) (xy 385.319028 -276.424898) (xy 385.322988 -276.375844)
			(xy 385.334765 -276.32806) (xy 385.354056 -276.282784) (xy 385.380359 -276.241188) (xy 385.412994 -276.204351)
			(xy 385.451115 -276.173226) (xy 385.493736 -276.148619) (xy 385.539752 -276.131167) (xy 385.587971 -276.121323)
			(xy 385.637146 -276.119342) (xy 385.686001 -276.125274) (xy 385.733272 -276.138966) (xy 385.777734 -276.160064)
			(xy 385.818237 -276.18802) (xy 385.85373 -276.222112) (xy 385.883295 -276.261456) (xy 385.906166 -276.305033)
			(xy 385.92175 -276.351714) (xy 385.929645 -276.400291) (xy 385.93014 -276.424898) (xy 386.269242 -276.424898)
			(xy 386.273202 -276.375844) (xy 386.284979 -276.32806) (xy 386.30427 -276.282784) (xy 386.330573 -276.241188)
			(xy 386.363208 -276.204351) (xy 386.401329 -276.173226) (xy 386.44395 -276.148619) (xy 386.489966 -276.131167)
			(xy 386.538185 -276.121323) (xy 386.58736 -276.119342) (xy 386.636215 -276.125274) (xy 386.683486 -276.138966)
			(xy 386.727948 -276.160064) (xy 386.768451 -276.18802) (xy 386.803944 -276.222112) (xy 386.833509 -276.261456)
			(xy 386.85638 -276.305033) (xy 386.871964 -276.351714) (xy 386.879859 -276.400291) (xy 386.880354 -276.424898)
			(xy 387.219202 -276.424898) (xy 387.223162 -276.375844) (xy 387.234939 -276.32806) (xy 387.25423 -276.282784)
			(xy 387.280533 -276.241188) (xy 387.313168 -276.204351) (xy 387.351289 -276.173226) (xy 387.39391 -276.148619)
			(xy 387.439926 -276.131167) (xy 387.488145 -276.121323) (xy 387.53732 -276.119342) (xy 387.586175 -276.125274)
			(xy 387.633446 -276.138966) (xy 387.677908 -276.160064) (xy 387.718411 -276.18802) (xy 387.753904 -276.222112)
			(xy 387.783469 -276.261456) (xy 387.80634 -276.305033) (xy 387.821924 -276.351714) (xy 387.829819 -276.400291)
			(xy 387.830314 -276.424898) (xy 388.169162 -276.424898) (xy 388.173122 -276.375844) (xy 388.184899 -276.32806)
			(xy 388.20419 -276.282784) (xy 388.230493 -276.241188) (xy 388.263128 -276.204351) (xy 388.301249 -276.173226)
			(xy 388.34387 -276.148619) (xy 388.389886 -276.131167) (xy 388.438105 -276.121323) (xy 388.48728 -276.119342)
			(xy 388.536135 -276.125274) (xy 388.583406 -276.138966) (xy 388.627868 -276.160064) (xy 388.668371 -276.18802)
			(xy 388.703864 -276.222112) (xy 388.733429 -276.261456) (xy 388.7563 -276.305033) (xy 388.771884 -276.351714)
			(xy 388.779779 -276.400291) (xy 388.780274 -276.424898) (xy 389.119122 -276.424898) (xy 389.123082 -276.375844)
			(xy 389.134859 -276.32806) (xy 389.15415 -276.282784) (xy 389.180453 -276.241188) (xy 389.213088 -276.204351)
			(xy 389.251209 -276.173226) (xy 389.29383 -276.148619) (xy 389.339846 -276.131167) (xy 389.388065 -276.121323)
			(xy 389.43724 -276.119342) (xy 389.486095 -276.125274) (xy 389.533366 -276.138966) (xy 389.577828 -276.160064)
			(xy 389.618331 -276.18802) (xy 389.653824 -276.222112) (xy 389.683389 -276.261456) (xy 389.70626 -276.305033)
			(xy 389.721844 -276.351714) (xy 389.729739 -276.400291) (xy 389.730234 -276.424898) (xy 390.069082 -276.424898)
			(xy 390.073042 -276.375844) (xy 390.084819 -276.32806) (xy 390.10411 -276.282784) (xy 390.130413 -276.241188)
			(xy 390.163048 -276.204351) (xy 390.201169 -276.173226) (xy 390.24379 -276.148619) (xy 390.289806 -276.131167)
			(xy 390.338025 -276.121323) (xy 390.3872 -276.119342) (xy 390.436055 -276.125274) (xy 390.483326 -276.138966)
			(xy 390.527788 -276.160064) (xy 390.568291 -276.18802) (xy 390.603784 -276.222112) (xy 390.633349 -276.261456)
			(xy 390.65622 -276.305033) (xy 390.671804 -276.351714) (xy 390.679699 -276.400291) (xy 390.680194 -276.424898)
			(xy 391.019042 -276.424898) (xy 391.023002 -276.375844) (xy 391.034779 -276.32806) (xy 391.05407 -276.282784)
			(xy 391.080373 -276.241188) (xy 391.113008 -276.204351) (xy 391.151129 -276.173226) (xy 391.19375 -276.148619)
			(xy 391.239766 -276.131167) (xy 391.287985 -276.121323) (xy 391.33716 -276.119342) (xy 391.386015 -276.125274)
			(xy 391.433286 -276.138966) (xy 391.477748 -276.160064) (xy 391.518251 -276.18802) (xy 391.553744 -276.222112)
			(xy 391.583309 -276.261456) (xy 391.60618 -276.305033) (xy 391.621764 -276.351714) (xy 391.629659 -276.400291)
			(xy 391.630154 -276.424898) (xy 391.629659 -276.449505) (xy 391.621764 -276.498082) (xy 391.60618 -276.544763)
			(xy 391.583309 -276.58834) (xy 391.553744 -276.627684) (xy 391.518251 -276.661776) (xy 391.477748 -276.689732)
			(xy 391.433286 -276.71083) (xy 391.386015 -276.724522) (xy 391.33716 -276.730454) (xy 391.287985 -276.728473)
			(xy 391.239766 -276.718629) (xy 391.19375 -276.701177) (xy 391.151129 -276.67657) (xy 391.113008 -276.645445)
			(xy 391.080373 -276.608608) (xy 391.05407 -276.567012) (xy 391.034779 -276.521736) (xy 391.023002 -276.473952)
			(xy 391.019042 -276.424898) (xy 390.680194 -276.424898) (xy 390.679699 -276.449505) (xy 390.671804 -276.498082)
			(xy 390.65622 -276.544763) (xy 390.633349 -276.58834) (xy 390.603784 -276.627684) (xy 390.568291 -276.661776)
			(xy 390.527788 -276.689732) (xy 390.483326 -276.71083) (xy 390.436055 -276.724522) (xy 390.3872 -276.730454)
			(xy 390.338025 -276.728473) (xy 390.289806 -276.718629) (xy 390.24379 -276.701177) (xy 390.201169 -276.67657)
			(xy 390.163048 -276.645445) (xy 390.130413 -276.608608) (xy 390.10411 -276.567012) (xy 390.084819 -276.521736)
			(xy 390.073042 -276.473952) (xy 390.069082 -276.424898) (xy 389.730234 -276.424898) (xy 389.729739 -276.449505)
			(xy 389.721844 -276.498082) (xy 389.70626 -276.544763) (xy 389.683389 -276.58834) (xy 389.653824 -276.627684)
			(xy 389.618331 -276.661776) (xy 389.577828 -276.689732) (xy 389.533366 -276.71083) (xy 389.486095 -276.724522)
			(xy 389.43724 -276.730454) (xy 389.388065 -276.728473) (xy 389.339846 -276.718629) (xy 389.29383 -276.701177)
			(xy 389.251209 -276.67657) (xy 389.213088 -276.645445) (xy 389.180453 -276.608608) (xy 389.15415 -276.567012)
			(xy 389.134859 -276.521736) (xy 389.123082 -276.473952) (xy 389.119122 -276.424898) (xy 388.780274 -276.424898)
			(xy 388.779779 -276.449505) (xy 388.771884 -276.498082) (xy 388.7563 -276.544763) (xy 388.733429 -276.58834)
			(xy 388.703864 -276.627684) (xy 388.668371 -276.661776) (xy 388.627868 -276.689732) (xy 388.583406 -276.71083)
			(xy 388.536135 -276.724522) (xy 388.48728 -276.730454) (xy 388.438105 -276.728473) (xy 388.389886 -276.718629)
			(xy 388.34387 -276.701177) (xy 388.301249 -276.67657) (xy 388.263128 -276.645445) (xy 388.230493 -276.608608)
			(xy 388.20419 -276.567012) (xy 388.184899 -276.521736) (xy 388.173122 -276.473952) (xy 388.169162 -276.424898)
			(xy 387.830314 -276.424898) (xy 387.829819 -276.449505) (xy 387.821924 -276.498082) (xy 387.80634 -276.544763)
			(xy 387.783469 -276.58834) (xy 387.753904 -276.627684) (xy 387.718411 -276.661776) (xy 387.677908 -276.689732)
			(xy 387.633446 -276.71083) (xy 387.586175 -276.724522) (xy 387.53732 -276.730454) (xy 387.488145 -276.728473)
			(xy 387.439926 -276.718629) (xy 387.39391 -276.701177) (xy 387.351289 -276.67657) (xy 387.313168 -276.645445)
			(xy 387.280533 -276.608608) (xy 387.25423 -276.567012) (xy 387.234939 -276.521736) (xy 387.223162 -276.473952)
			(xy 387.219202 -276.424898) (xy 386.880354 -276.424898) (xy 386.879859 -276.449505) (xy 386.871964 -276.498082)
			(xy 386.85638 -276.544763) (xy 386.833509 -276.58834) (xy 386.803944 -276.627684) (xy 386.768451 -276.661776)
			(xy 386.727948 -276.689732) (xy 386.683486 -276.71083) (xy 386.636215 -276.724522) (xy 386.58736 -276.730454)
			(xy 386.538185 -276.728473) (xy 386.489966 -276.718629) (xy 386.44395 -276.701177) (xy 386.401329 -276.67657)
			(xy 386.363208 -276.645445) (xy 386.330573 -276.608608) (xy 386.30427 -276.567012) (xy 386.284979 -276.521736)
			(xy 386.273202 -276.473952) (xy 386.269242 -276.424898) (xy 385.93014 -276.424898) (xy 385.929645 -276.449505)
			(xy 385.92175 -276.498082) (xy 385.906166 -276.544763) (xy 385.883295 -276.58834) (xy 385.85373 -276.627684)
			(xy 385.818237 -276.661776) (xy 385.777734 -276.689732) (xy 385.733272 -276.71083) (xy 385.686001 -276.724522)
			(xy 385.637146 -276.730454) (xy 385.587971 -276.728473) (xy 385.539752 -276.718629) (xy 385.493736 -276.701177)
			(xy 385.451115 -276.67657) (xy 385.412994 -276.645445) (xy 385.380359 -276.608608) (xy 385.354056 -276.567012)
			(xy 385.334765 -276.521736) (xy 385.322988 -276.473952) (xy 385.319028 -276.424898) (xy 384.98018 -276.424898)
			(xy 384.979685 -276.449505) (xy 384.97179 -276.498082) (xy 384.956206 -276.544763) (xy 384.933335 -276.58834)
			(xy 384.90377 -276.627684) (xy 384.868277 -276.661776) (xy 384.827774 -276.689732) (xy 384.783312 -276.71083)
			(xy 384.736041 -276.724522) (xy 384.687186 -276.730454) (xy 384.638011 -276.728473) (xy 384.589792 -276.718629)
			(xy 384.543776 -276.701177) (xy 384.501155 -276.67657) (xy 384.463034 -276.645445) (xy 384.430399 -276.608608)
			(xy 384.404096 -276.567012) (xy 384.384805 -276.521736) (xy 384.373028 -276.473952) (xy 384.369068 -276.424898)
			(xy 383.78638 -276.424898) (xy 383.78638 -276.899878) (xy 392.443982 -276.899878) (xy 392.447942 -276.850824)
			(xy 392.459719 -276.80304) (xy 392.47901 -276.757764) (xy 392.505313 -276.716168) (xy 392.537948 -276.679331)
			(xy 392.576069 -276.648206) (xy 392.61869 -276.623599) (xy 392.664706 -276.606147) (xy 392.712925 -276.596303)
			(xy 392.7621 -276.594322) (xy 392.810955 -276.600254) (xy 392.858226 -276.613946) (xy 392.902688 -276.635044)
			(xy 392.943191 -276.663) (xy 392.978684 -276.697092) (xy 393.008249 -276.736436) (xy 393.03112 -276.780013)
			(xy 393.046704 -276.826694) (xy 393.054599 -276.875271) (xy 393.055094 -276.899878) (xy 393.394196 -276.899878)
			(xy 393.398156 -276.850824) (xy 393.409933 -276.80304) (xy 393.429224 -276.757764) (xy 393.455527 -276.716168)
			(xy 393.488162 -276.679331) (xy 393.526283 -276.648206) (xy 393.568904 -276.623599) (xy 393.61492 -276.606147)
			(xy 393.663139 -276.596303) (xy 393.712314 -276.594322) (xy 393.761169 -276.600254) (xy 393.80844 -276.613946)
			(xy 393.852902 -276.635044) (xy 393.893405 -276.663) (xy 393.928898 -276.697092) (xy 393.958463 -276.736436)
			(xy 393.981334 -276.780013) (xy 393.996918 -276.826694) (xy 394.004813 -276.875271) (xy 394.005308 -276.899878)
			(xy 394.344156 -276.899878) (xy 394.348116 -276.850824) (xy 394.359893 -276.80304) (xy 394.379184 -276.757764)
			(xy 394.405487 -276.716168) (xy 394.438122 -276.679331) (xy 394.476243 -276.648206) (xy 394.518864 -276.623599)
			(xy 394.56488 -276.606147) (xy 394.613099 -276.596303) (xy 394.662274 -276.594322) (xy 394.711129 -276.600254)
			(xy 394.7584 -276.613946) (xy 394.802862 -276.635044) (xy 394.843365 -276.663) (xy 394.878858 -276.697092)
			(xy 394.908423 -276.736436) (xy 394.931294 -276.780013) (xy 394.946878 -276.826694) (xy 394.954773 -276.875271)
			(xy 394.955268 -276.899878) (xy 395.294116 -276.899878) (xy 395.298076 -276.850824) (xy 395.309853 -276.80304)
			(xy 395.329144 -276.757764) (xy 395.355447 -276.716168) (xy 395.388082 -276.679331) (xy 395.426203 -276.648206)
			(xy 395.468824 -276.623599) (xy 395.51484 -276.606147) (xy 395.563059 -276.596303) (xy 395.612234 -276.594322)
			(xy 395.661089 -276.600254) (xy 395.70836 -276.613946) (xy 395.752822 -276.635044) (xy 395.793325 -276.663)
			(xy 395.828818 -276.697092) (xy 395.858383 -276.736436) (xy 395.881254 -276.780013) (xy 395.896838 -276.826694)
			(xy 395.904733 -276.875271) (xy 395.905228 -276.899878) (xy 396.244076 -276.899878) (xy 396.248036 -276.850824)
			(xy 396.259813 -276.80304) (xy 396.279104 -276.757764) (xy 396.305407 -276.716168) (xy 396.338042 -276.679331)
			(xy 396.376163 -276.648206) (xy 396.418784 -276.623599) (xy 396.4648 -276.606147) (xy 396.513019 -276.596303)
			(xy 396.562194 -276.594322) (xy 396.611049 -276.600254) (xy 396.65832 -276.613946) (xy 396.702782 -276.635044)
			(xy 396.743285 -276.663) (xy 396.778778 -276.697092) (xy 396.808343 -276.736436) (xy 396.831214 -276.780013)
			(xy 396.846798 -276.826694) (xy 396.854693 -276.875271) (xy 396.855188 -276.899878) (xy 397.194036 -276.899878)
			(xy 397.197996 -276.850824) (xy 397.209773 -276.80304) (xy 397.229064 -276.757764) (xy 397.255367 -276.716168)
			(xy 397.288002 -276.679331) (xy 397.326123 -276.648206) (xy 397.368744 -276.623599) (xy 397.41476 -276.606147)
			(xy 397.462979 -276.596303) (xy 397.512154 -276.594322) (xy 397.561009 -276.600254) (xy 397.60828 -276.613946)
			(xy 397.652742 -276.635044) (xy 397.693245 -276.663) (xy 397.728738 -276.697092) (xy 397.758303 -276.736436)
			(xy 397.781174 -276.780013) (xy 397.796758 -276.826694) (xy 397.804653 -276.875271) (xy 397.805148 -276.899878)
			(xy 398.143996 -276.899878) (xy 398.147956 -276.850824) (xy 398.159733 -276.80304) (xy 398.179024 -276.757764)
			(xy 398.205327 -276.716168) (xy 398.237962 -276.679331) (xy 398.276083 -276.648206) (xy 398.318704 -276.623599)
			(xy 398.36472 -276.606147) (xy 398.412939 -276.596303) (xy 398.462114 -276.594322) (xy 398.510969 -276.600254)
			(xy 398.55824 -276.613946) (xy 398.602702 -276.635044) (xy 398.643205 -276.663) (xy 398.678698 -276.697092)
			(xy 398.708263 -276.736436) (xy 398.731134 -276.780013) (xy 398.746718 -276.826694) (xy 398.754613 -276.875271)
			(xy 398.755108 -276.899878) (xy 399.09421 -276.899878) (xy 399.09817 -276.850824) (xy 399.109947 -276.80304)
			(xy 399.129238 -276.757764) (xy 399.155541 -276.716168) (xy 399.188176 -276.679331) (xy 399.226297 -276.648206)
			(xy 399.268918 -276.623599) (xy 399.314934 -276.606147) (xy 399.363153 -276.596303) (xy 399.412328 -276.594322)
			(xy 399.461183 -276.600254) (xy 399.508454 -276.613946) (xy 399.552916 -276.635044) (xy 399.593419 -276.663)
			(xy 399.628912 -276.697092) (xy 399.658477 -276.736436) (xy 399.681348 -276.780013) (xy 399.696932 -276.826694)
			(xy 399.704827 -276.875271) (xy 399.705322 -276.899878) (xy 400.04417 -276.899878) (xy 400.04813 -276.850824)
			(xy 400.059907 -276.80304) (xy 400.079198 -276.757764) (xy 400.105501 -276.716168) (xy 400.138136 -276.679331)
			(xy 400.176257 -276.648206) (xy 400.218878 -276.623599) (xy 400.264894 -276.606147) (xy 400.313113 -276.596303)
			(xy 400.362288 -276.594322) (xy 400.411143 -276.600254) (xy 400.458414 -276.613946) (xy 400.502876 -276.635044)
			(xy 400.543379 -276.663) (xy 400.578872 -276.697092) (xy 400.608437 -276.736436) (xy 400.631308 -276.780013)
			(xy 400.646892 -276.826694) (xy 400.654787 -276.875271) (xy 400.655282 -276.899878) (xy 400.99413 -276.899878)
			(xy 400.99809 -276.850824) (xy 401.009867 -276.80304) (xy 401.029158 -276.757764) (xy 401.055461 -276.716168)
			(xy 401.088096 -276.679331) (xy 401.126217 -276.648206) (xy 401.168838 -276.623599) (xy 401.214854 -276.606147)
			(xy 401.263073 -276.596303) (xy 401.312248 -276.594322) (xy 401.361103 -276.600254) (xy 401.408374 -276.613946)
			(xy 401.452836 -276.635044) (xy 401.493339 -276.663) (xy 401.528832 -276.697092) (xy 401.558397 -276.736436)
			(xy 401.581268 -276.780013) (xy 401.596852 -276.826694) (xy 401.604747 -276.875271) (xy 401.605242 -276.899878)
			(xy 401.94409 -276.899878) (xy 401.94805 -276.850824) (xy 401.959827 -276.80304) (xy 401.979118 -276.757764)
			(xy 402.005421 -276.716168) (xy 402.038056 -276.679331) (xy 402.076177 -276.648206) (xy 402.118798 -276.623599)
			(xy 402.164814 -276.606147) (xy 402.213033 -276.596303) (xy 402.262208 -276.594322) (xy 402.311063 -276.600254)
			(xy 402.358334 -276.613946) (xy 402.402796 -276.635044) (xy 402.443299 -276.663) (xy 402.478792 -276.697092)
			(xy 402.508357 -276.736436) (xy 402.531228 -276.780013) (xy 402.546812 -276.826694) (xy 402.554707 -276.875271)
			(xy 402.555202 -276.899878) (xy 402.89405 -276.899878) (xy 402.89801 -276.850824) (xy 402.909787 -276.80304)
			(xy 402.929078 -276.757764) (xy 402.955381 -276.716168) (xy 402.988016 -276.679331) (xy 403.026137 -276.648206)
			(xy 403.068758 -276.623599) (xy 403.114774 -276.606147) (xy 403.162993 -276.596303) (xy 403.212168 -276.594322)
			(xy 403.261023 -276.600254) (xy 403.308294 -276.613946) (xy 403.352756 -276.635044) (xy 403.393259 -276.663)
			(xy 403.428752 -276.697092) (xy 403.458317 -276.736436) (xy 403.481188 -276.780013) (xy 403.496772 -276.826694)
			(xy 403.504667 -276.875271) (xy 403.505162 -276.899878) (xy 403.84401 -276.899878) (xy 403.84797 -276.850824)
			(xy 403.859747 -276.80304) (xy 403.879038 -276.757764) (xy 403.905341 -276.716168) (xy 403.937976 -276.679331)
			(xy 403.976097 -276.648206) (xy 404.018718 -276.623599) (xy 404.064734 -276.606147) (xy 404.112953 -276.596303)
			(xy 404.162128 -276.594322) (xy 404.210983 -276.600254) (xy 404.258254 -276.613946) (xy 404.302716 -276.635044)
			(xy 404.343219 -276.663) (xy 404.378712 -276.697092) (xy 404.408277 -276.736436) (xy 404.431148 -276.780013)
			(xy 404.446732 -276.826694) (xy 404.454627 -276.875271) (xy 404.455122 -276.899878) (xy 404.794224 -276.899878)
			(xy 404.798184 -276.850824) (xy 404.809961 -276.80304) (xy 404.829252 -276.757764) (xy 404.855555 -276.716168)
			(xy 404.88819 -276.679331) (xy 404.926311 -276.648206) (xy 404.968932 -276.623599) (xy 405.014948 -276.606147)
			(xy 405.063167 -276.596303) (xy 405.112342 -276.594322) (xy 405.161197 -276.600254) (xy 405.208468 -276.613946)
			(xy 405.25293 -276.635044) (xy 405.293433 -276.663) (xy 405.328926 -276.697092) (xy 405.358491 -276.736436)
			(xy 405.381362 -276.780013) (xy 405.396946 -276.826694) (xy 405.404841 -276.875271) (xy 405.405336 -276.899878)
			(xy 405.744184 -276.899878) (xy 405.748144 -276.850824) (xy 405.759921 -276.80304) (xy 405.779212 -276.757764)
			(xy 405.805515 -276.716168) (xy 405.83815 -276.679331) (xy 405.876271 -276.648206) (xy 405.918892 -276.623599)
			(xy 405.964908 -276.606147) (xy 406.013127 -276.596303) (xy 406.062302 -276.594322) (xy 406.111157 -276.600254)
			(xy 406.158428 -276.613946) (xy 406.20289 -276.635044) (xy 406.243393 -276.663) (xy 406.278886 -276.697092)
			(xy 406.308451 -276.736436) (xy 406.331322 -276.780013) (xy 406.346906 -276.826694) (xy 406.354801 -276.875271)
			(xy 406.355296 -276.899878) (xy 406.694144 -276.899878) (xy 406.698104 -276.850824) (xy 406.709881 -276.80304)
			(xy 406.729172 -276.757764) (xy 406.755475 -276.716168) (xy 406.78811 -276.679331) (xy 406.826231 -276.648206)
			(xy 406.868852 -276.623599) (xy 406.914868 -276.606147) (xy 406.963087 -276.596303) (xy 407.012262 -276.594322)
			(xy 407.061117 -276.600254) (xy 407.108388 -276.613946) (xy 407.15285 -276.635044) (xy 407.193353 -276.663)
			(xy 407.228846 -276.697092) (xy 407.258411 -276.736436) (xy 407.281282 -276.780013) (xy 407.296866 -276.826694)
			(xy 407.304761 -276.875271) (xy 407.305256 -276.899878) (xy 407.644104 -276.899878) (xy 407.648064 -276.850824)
			(xy 407.659841 -276.80304) (xy 407.679132 -276.757764) (xy 407.705435 -276.716168) (xy 407.73807 -276.679331)
			(xy 407.776191 -276.648206) (xy 407.818812 -276.623599) (xy 407.864828 -276.606147) (xy 407.913047 -276.596303)
			(xy 407.962222 -276.594322) (xy 408.011077 -276.600254) (xy 408.058348 -276.613946) (xy 408.10281 -276.635044)
			(xy 408.143313 -276.663) (xy 408.178806 -276.697092) (xy 408.208371 -276.736436) (xy 408.231242 -276.780013)
			(xy 408.246826 -276.826694) (xy 408.254721 -276.875271) (xy 408.255216 -276.899878) (xy 408.594064 -276.899878)
			(xy 408.598024 -276.850824) (xy 408.609801 -276.80304) (xy 408.629092 -276.757764) (xy 408.655395 -276.716168)
			(xy 408.68803 -276.679331) (xy 408.726151 -276.648206) (xy 408.768772 -276.623599) (xy 408.814788 -276.606147)
			(xy 408.863007 -276.596303) (xy 408.912182 -276.594322) (xy 408.961037 -276.600254) (xy 409.008308 -276.613946)
			(xy 409.05277 -276.635044) (xy 409.093273 -276.663) (xy 409.128766 -276.697092) (xy 409.158331 -276.736436)
			(xy 409.181202 -276.780013) (xy 409.196786 -276.826694) (xy 409.204681 -276.875271) (xy 409.205176 -276.899878)
			(xy 409.544024 -276.899878) (xy 409.547984 -276.850824) (xy 409.559761 -276.80304) (xy 409.579052 -276.757764)
			(xy 409.605355 -276.716168) (xy 409.63799 -276.679331) (xy 409.676111 -276.648206) (xy 409.718732 -276.623599)
			(xy 409.764748 -276.606147) (xy 409.812967 -276.596303) (xy 409.862142 -276.594322) (xy 409.910997 -276.600254)
			(xy 409.958268 -276.613946) (xy 410.00273 -276.635044) (xy 410.043233 -276.663) (xy 410.078726 -276.697092)
			(xy 410.108291 -276.736436) (xy 410.131162 -276.780013) (xy 410.146746 -276.826694) (xy 410.154641 -276.875271)
			(xy 410.155136 -276.899878) (xy 410.493984 -276.899878) (xy 410.497944 -276.850824) (xy 410.509721 -276.80304)
			(xy 410.529012 -276.757764) (xy 410.555315 -276.716168) (xy 410.58795 -276.679331) (xy 410.626071 -276.648206)
			(xy 410.668692 -276.623599) (xy 410.714708 -276.606147) (xy 410.762927 -276.596303) (xy 410.812102 -276.594322)
			(xy 410.860957 -276.600254) (xy 410.908228 -276.613946) (xy 410.95269 -276.635044) (xy 410.993193 -276.663)
			(xy 411.028686 -276.697092) (xy 411.058251 -276.736436) (xy 411.081122 -276.780013) (xy 411.096706 -276.826694)
			(xy 411.104601 -276.875271) (xy 411.105096 -276.899878) (xy 411.444198 -276.899878) (xy 411.448158 -276.850824)
			(xy 411.459935 -276.80304) (xy 411.479226 -276.757764) (xy 411.505529 -276.716168) (xy 411.538164 -276.679331)
			(xy 411.576285 -276.648206) (xy 411.618906 -276.623599) (xy 411.664922 -276.606147) (xy 411.713141 -276.596303)
			(xy 411.762316 -276.594322) (xy 411.811171 -276.600254) (xy 411.858442 -276.613946) (xy 411.902904 -276.635044)
			(xy 411.943407 -276.663) (xy 411.9789 -276.697092) (xy 412.008465 -276.736436) (xy 412.031336 -276.780013)
			(xy 412.04692 -276.826694) (xy 412.054815 -276.875271) (xy 412.05531 -276.899878) (xy 412.394158 -276.899878)
			(xy 412.398118 -276.850824) (xy 412.409895 -276.80304) (xy 412.429186 -276.757764) (xy 412.455489 -276.716168)
			(xy 412.488124 -276.679331) (xy 412.526245 -276.648206) (xy 412.568866 -276.623599) (xy 412.614882 -276.606147)
			(xy 412.663101 -276.596303) (xy 412.712276 -276.594322) (xy 412.761131 -276.600254) (xy 412.808402 -276.613946)
			(xy 412.852864 -276.635044) (xy 412.893367 -276.663) (xy 412.92886 -276.697092) (xy 412.958425 -276.736436)
			(xy 412.981296 -276.780013) (xy 412.99688 -276.826694) (xy 413.004775 -276.875271) (xy 413.00527 -276.899878)
			(xy 413.344118 -276.899878) (xy 413.348078 -276.850824) (xy 413.359855 -276.80304) (xy 413.379146 -276.757764)
			(xy 413.405449 -276.716168) (xy 413.438084 -276.679331) (xy 413.476205 -276.648206) (xy 413.518826 -276.623599)
			(xy 413.564842 -276.606147) (xy 413.613061 -276.596303) (xy 413.662236 -276.594322) (xy 413.711091 -276.600254)
			(xy 413.758362 -276.613946) (xy 413.802824 -276.635044) (xy 413.843327 -276.663) (xy 413.87882 -276.697092)
			(xy 413.908385 -276.736436) (xy 413.931256 -276.780013) (xy 413.94684 -276.826694) (xy 413.954735 -276.875271)
			(xy 413.95523 -276.899878) (xy 414.294078 -276.899878) (xy 414.298038 -276.850824) (xy 414.309815 -276.80304)
			(xy 414.329106 -276.757764) (xy 414.355409 -276.716168) (xy 414.388044 -276.679331) (xy 414.426165 -276.648206)
			(xy 414.468786 -276.623599) (xy 414.514802 -276.606147) (xy 414.563021 -276.596303) (xy 414.612196 -276.594322)
			(xy 414.661051 -276.600254) (xy 414.708322 -276.613946) (xy 414.752784 -276.635044) (xy 414.793287 -276.663)
			(xy 414.82878 -276.697092) (xy 414.858345 -276.736436) (xy 414.881216 -276.780013) (xy 414.8968 -276.826694)
			(xy 414.904695 -276.875271) (xy 414.90519 -276.899878) (xy 415.244038 -276.899878) (xy 415.247998 -276.850824)
			(xy 415.259775 -276.80304) (xy 415.279066 -276.757764) (xy 415.305369 -276.716168) (xy 415.338004 -276.679331)
			(xy 415.376125 -276.648206) (xy 415.418746 -276.623599) (xy 415.464762 -276.606147) (xy 415.512981 -276.596303)
			(xy 415.562156 -276.594322) (xy 415.611011 -276.600254) (xy 415.658282 -276.613946) (xy 415.702744 -276.635044)
			(xy 415.743247 -276.663) (xy 415.77874 -276.697092) (xy 415.808305 -276.736436) (xy 415.831176 -276.780013)
			(xy 415.84676 -276.826694) (xy 415.854655 -276.875271) (xy 415.85515 -276.899878) (xy 416.193998 -276.899878)
			(xy 416.197958 -276.850824) (xy 416.209735 -276.80304) (xy 416.229026 -276.757764) (xy 416.255329 -276.716168)
			(xy 416.287964 -276.679331) (xy 416.326085 -276.648206) (xy 416.368706 -276.623599) (xy 416.414722 -276.606147)
			(xy 416.462941 -276.596303) (xy 416.512116 -276.594322) (xy 416.560971 -276.600254) (xy 416.608242 -276.613946)
			(xy 416.652704 -276.635044) (xy 416.693207 -276.663) (xy 416.7287 -276.697092) (xy 416.758265 -276.736436)
			(xy 416.781136 -276.780013) (xy 416.79672 -276.826694) (xy 416.804615 -276.875271) (xy 416.80511 -276.899878)
			(xy 417.144212 -276.899878) (xy 417.148172 -276.850824) (xy 417.159949 -276.80304) (xy 417.17924 -276.757764)
			(xy 417.205543 -276.716168) (xy 417.238178 -276.679331) (xy 417.276299 -276.648206) (xy 417.31892 -276.623599)
			(xy 417.364936 -276.606147) (xy 417.413155 -276.596303) (xy 417.46233 -276.594322) (xy 417.511185 -276.600254)
			(xy 417.558456 -276.613946) (xy 417.602918 -276.635044) (xy 417.643421 -276.663) (xy 417.678914 -276.697092)
			(xy 417.708479 -276.736436) (xy 417.73135 -276.780013) (xy 417.746934 -276.826694) (xy 417.754829 -276.875271)
			(xy 417.755324 -276.899878) (xy 418.094172 -276.899878) (xy 418.098132 -276.850824) (xy 418.109909 -276.80304)
			(xy 418.1292 -276.757764) (xy 418.155503 -276.716168) (xy 418.188138 -276.679331) (xy 418.226259 -276.648206)
			(xy 418.26888 -276.623599) (xy 418.314896 -276.606147) (xy 418.363115 -276.596303) (xy 418.41229 -276.594322)
			(xy 418.461145 -276.600254) (xy 418.508416 -276.613946) (xy 418.552878 -276.635044) (xy 418.593381 -276.663)
			(xy 418.628874 -276.697092) (xy 418.658439 -276.736436) (xy 418.68131 -276.780013) (xy 418.696894 -276.826694)
			(xy 418.704789 -276.875271) (xy 418.705284 -276.899878) (xy 419.044132 -276.899878) (xy 419.048092 -276.850824)
			(xy 419.059869 -276.80304) (xy 419.07916 -276.757764) (xy 419.105463 -276.716168) (xy 419.138098 -276.679331)
			(xy 419.176219 -276.648206) (xy 419.21884 -276.623599) (xy 419.264856 -276.606147) (xy 419.313075 -276.596303)
			(xy 419.36225 -276.594322) (xy 419.411105 -276.600254) (xy 419.458376 -276.613946) (xy 419.502838 -276.635044)
			(xy 419.543341 -276.663) (xy 419.578834 -276.697092) (xy 419.608399 -276.736436) (xy 419.63127 -276.780013)
			(xy 419.646854 -276.826694) (xy 419.654749 -276.875271) (xy 419.655244 -276.899878) (xy 419.994092 -276.899878)
			(xy 419.998052 -276.850824) (xy 420.009829 -276.80304) (xy 420.02912 -276.757764) (xy 420.055423 -276.716168)
			(xy 420.088058 -276.679331) (xy 420.126179 -276.648206) (xy 420.1688 -276.623599) (xy 420.214816 -276.606147)
			(xy 420.263035 -276.596303) (xy 420.31221 -276.594322) (xy 420.361065 -276.600254) (xy 420.408336 -276.613946)
			(xy 420.452798 -276.635044) (xy 420.493301 -276.663) (xy 420.528794 -276.697092) (xy 420.558359 -276.736436)
			(xy 420.58123 -276.780013) (xy 420.596814 -276.826694) (xy 420.604709 -276.875271) (xy 420.605204 -276.899878)
			(xy 420.944052 -276.899878) (xy 420.948012 -276.850824) (xy 420.959789 -276.80304) (xy 420.97908 -276.757764)
			(xy 421.005383 -276.716168) (xy 421.038018 -276.679331) (xy 421.076139 -276.648206) (xy 421.11876 -276.623599)
			(xy 421.164776 -276.606147) (xy 421.212995 -276.596303) (xy 421.26217 -276.594322) (xy 421.311025 -276.600254)
			(xy 421.358296 -276.613946) (xy 421.402758 -276.635044) (xy 421.443261 -276.663) (xy 421.478754 -276.697092)
			(xy 421.508319 -276.736436) (xy 421.53119 -276.780013) (xy 421.546774 -276.826694) (xy 421.554669 -276.875271)
			(xy 421.555164 -276.899878) (xy 421.554669 -276.924485) (xy 421.546774 -276.973062) (xy 421.53119 -277.019743)
			(xy 421.508319 -277.06332) (xy 421.478754 -277.102664) (xy 421.443261 -277.136756) (xy 421.402758 -277.164712)
			(xy 421.358296 -277.18581) (xy 421.311025 -277.199502) (xy 421.26217 -277.205434) (xy 421.212995 -277.203453)
			(xy 421.164776 -277.193609) (xy 421.11876 -277.176157) (xy 421.076139 -277.15155) (xy 421.038018 -277.120425)
			(xy 421.005383 -277.083588) (xy 420.97908 -277.041992) (xy 420.959789 -276.996716) (xy 420.948012 -276.948932)
			(xy 420.944052 -276.899878) (xy 420.605204 -276.899878) (xy 420.604709 -276.924485) (xy 420.596814 -276.973062)
			(xy 420.58123 -277.019743) (xy 420.558359 -277.06332) (xy 420.528794 -277.102664) (xy 420.493301 -277.136756)
			(xy 420.452798 -277.164712) (xy 420.408336 -277.18581) (xy 420.361065 -277.199502) (xy 420.31221 -277.205434)
			(xy 420.263035 -277.203453) (xy 420.214816 -277.193609) (xy 420.1688 -277.176157) (xy 420.126179 -277.15155)
			(xy 420.088058 -277.120425) (xy 420.055423 -277.083588) (xy 420.02912 -277.041992) (xy 420.009829 -276.996716)
			(xy 419.998052 -276.948932) (xy 419.994092 -276.899878) (xy 419.655244 -276.899878) (xy 419.654749 -276.924485)
			(xy 419.646854 -276.973062) (xy 419.63127 -277.019743) (xy 419.608399 -277.06332) (xy 419.578834 -277.102664)
			(xy 419.543341 -277.136756) (xy 419.502838 -277.164712) (xy 419.458376 -277.18581) (xy 419.411105 -277.199502)
			(xy 419.36225 -277.205434) (xy 419.313075 -277.203453) (xy 419.264856 -277.193609) (xy 419.21884 -277.176157)
			(xy 419.176219 -277.15155) (xy 419.138098 -277.120425) (xy 419.105463 -277.083588) (xy 419.07916 -277.041992)
			(xy 419.059869 -276.996716) (xy 419.048092 -276.948932) (xy 419.044132 -276.899878) (xy 418.705284 -276.899878)
			(xy 418.704789 -276.924485) (xy 418.696894 -276.973062) (xy 418.68131 -277.019743) (xy 418.658439 -277.06332)
			(xy 418.628874 -277.102664) (xy 418.593381 -277.136756) (xy 418.552878 -277.164712) (xy 418.508416 -277.18581)
			(xy 418.461145 -277.199502) (xy 418.41229 -277.205434) (xy 418.363115 -277.203453) (xy 418.314896 -277.193609)
			(xy 418.26888 -277.176157) (xy 418.226259 -277.15155) (xy 418.188138 -277.120425) (xy 418.155503 -277.083588)
			(xy 418.1292 -277.041992) (xy 418.109909 -276.996716) (xy 418.098132 -276.948932) (xy 418.094172 -276.899878)
			(xy 417.755324 -276.899878) (xy 417.754829 -276.924485) (xy 417.746934 -276.973062) (xy 417.73135 -277.019743)
			(xy 417.708479 -277.06332) (xy 417.678914 -277.102664) (xy 417.643421 -277.136756) (xy 417.602918 -277.164712)
			(xy 417.558456 -277.18581) (xy 417.511185 -277.199502) (xy 417.46233 -277.205434) (xy 417.413155 -277.203453)
			(xy 417.364936 -277.193609) (xy 417.31892 -277.176157) (xy 417.276299 -277.15155) (xy 417.238178 -277.120425)
			(xy 417.205543 -277.083588) (xy 417.17924 -277.041992) (xy 417.159949 -276.996716) (xy 417.148172 -276.948932)
			(xy 417.144212 -276.899878) (xy 416.80511 -276.899878) (xy 416.804615 -276.924485) (xy 416.79672 -276.973062)
			(xy 416.781136 -277.019743) (xy 416.758265 -277.06332) (xy 416.7287 -277.102664) (xy 416.693207 -277.136756)
			(xy 416.652704 -277.164712) (xy 416.608242 -277.18581) (xy 416.560971 -277.199502) (xy 416.512116 -277.205434)
			(xy 416.462941 -277.203453) (xy 416.414722 -277.193609) (xy 416.368706 -277.176157) (xy 416.326085 -277.15155)
			(xy 416.287964 -277.120425) (xy 416.255329 -277.083588) (xy 416.229026 -277.041992) (xy 416.209735 -276.996716)
			(xy 416.197958 -276.948932) (xy 416.193998 -276.899878) (xy 415.85515 -276.899878) (xy 415.854655 -276.924485)
			(xy 415.84676 -276.973062) (xy 415.831176 -277.019743) (xy 415.808305 -277.06332) (xy 415.77874 -277.102664)
			(xy 415.743247 -277.136756) (xy 415.702744 -277.164712) (xy 415.658282 -277.18581) (xy 415.611011 -277.199502)
			(xy 415.562156 -277.205434) (xy 415.512981 -277.203453) (xy 415.464762 -277.193609) (xy 415.418746 -277.176157)
			(xy 415.376125 -277.15155) (xy 415.338004 -277.120425) (xy 415.305369 -277.083588) (xy 415.279066 -277.041992)
			(xy 415.259775 -276.996716) (xy 415.247998 -276.948932) (xy 415.244038 -276.899878) (xy 414.90519 -276.899878)
			(xy 414.904695 -276.924485) (xy 414.8968 -276.973062) (xy 414.881216 -277.019743) (xy 414.858345 -277.06332)
			(xy 414.82878 -277.102664) (xy 414.793287 -277.136756) (xy 414.752784 -277.164712) (xy 414.708322 -277.18581)
			(xy 414.661051 -277.199502) (xy 414.612196 -277.205434) (xy 414.563021 -277.203453) (xy 414.514802 -277.193609)
			(xy 414.468786 -277.176157) (xy 414.426165 -277.15155) (xy 414.388044 -277.120425) (xy 414.355409 -277.083588)
			(xy 414.329106 -277.041992) (xy 414.309815 -276.996716) (xy 414.298038 -276.948932) (xy 414.294078 -276.899878)
			(xy 413.95523 -276.899878) (xy 413.954735 -276.924485) (xy 413.94684 -276.973062) (xy 413.931256 -277.019743)
			(xy 413.908385 -277.06332) (xy 413.87882 -277.102664) (xy 413.843327 -277.136756) (xy 413.802824 -277.164712)
			(xy 413.758362 -277.18581) (xy 413.711091 -277.199502) (xy 413.662236 -277.205434) (xy 413.613061 -277.203453)
			(xy 413.564842 -277.193609) (xy 413.518826 -277.176157) (xy 413.476205 -277.15155) (xy 413.438084 -277.120425)
			(xy 413.405449 -277.083588) (xy 413.379146 -277.041992) (xy 413.359855 -276.996716) (xy 413.348078 -276.948932)
			(xy 413.344118 -276.899878) (xy 413.00527 -276.899878) (xy 413.004775 -276.924485) (xy 412.99688 -276.973062)
			(xy 412.981296 -277.019743) (xy 412.958425 -277.06332) (xy 412.92886 -277.102664) (xy 412.893367 -277.136756)
			(xy 412.852864 -277.164712) (xy 412.808402 -277.18581) (xy 412.761131 -277.199502) (xy 412.712276 -277.205434)
			(xy 412.663101 -277.203453) (xy 412.614882 -277.193609) (xy 412.568866 -277.176157) (xy 412.526245 -277.15155)
			(xy 412.488124 -277.120425) (xy 412.455489 -277.083588) (xy 412.429186 -277.041992) (xy 412.409895 -276.996716)
			(xy 412.398118 -276.948932) (xy 412.394158 -276.899878) (xy 412.05531 -276.899878) (xy 412.054815 -276.924485)
			(xy 412.04692 -276.973062) (xy 412.031336 -277.019743) (xy 412.008465 -277.06332) (xy 411.9789 -277.102664)
			(xy 411.943407 -277.136756) (xy 411.902904 -277.164712) (xy 411.858442 -277.18581) (xy 411.811171 -277.199502)
			(xy 411.762316 -277.205434) (xy 411.713141 -277.203453) (xy 411.664922 -277.193609) (xy 411.618906 -277.176157)
			(xy 411.576285 -277.15155) (xy 411.538164 -277.120425) (xy 411.505529 -277.083588) (xy 411.479226 -277.041992)
			(xy 411.459935 -276.996716) (xy 411.448158 -276.948932) (xy 411.444198 -276.899878) (xy 411.105096 -276.899878)
			(xy 411.104601 -276.924485) (xy 411.096706 -276.973062) (xy 411.081122 -277.019743) (xy 411.058251 -277.06332)
			(xy 411.028686 -277.102664) (xy 410.993193 -277.136756) (xy 410.95269 -277.164712) (xy 410.908228 -277.18581)
			(xy 410.860957 -277.199502) (xy 410.812102 -277.205434) (xy 410.762927 -277.203453) (xy 410.714708 -277.193609)
			(xy 410.668692 -277.176157) (xy 410.626071 -277.15155) (xy 410.58795 -277.120425) (xy 410.555315 -277.083588)
			(xy 410.529012 -277.041992) (xy 410.509721 -276.996716) (xy 410.497944 -276.948932) (xy 410.493984 -276.899878)
			(xy 410.155136 -276.899878) (xy 410.154641 -276.924485) (xy 410.146746 -276.973062) (xy 410.131162 -277.019743)
			(xy 410.108291 -277.06332) (xy 410.078726 -277.102664) (xy 410.043233 -277.136756) (xy 410.00273 -277.164712)
			(xy 409.958268 -277.18581) (xy 409.910997 -277.199502) (xy 409.862142 -277.205434) (xy 409.812967 -277.203453)
			(xy 409.764748 -277.193609) (xy 409.718732 -277.176157) (xy 409.676111 -277.15155) (xy 409.63799 -277.120425)
			(xy 409.605355 -277.083588) (xy 409.579052 -277.041992) (xy 409.559761 -276.996716) (xy 409.547984 -276.948932)
			(xy 409.544024 -276.899878) (xy 409.205176 -276.899878) (xy 409.204681 -276.924485) (xy 409.196786 -276.973062)
			(xy 409.181202 -277.019743) (xy 409.158331 -277.06332) (xy 409.128766 -277.102664) (xy 409.093273 -277.136756)
			(xy 409.05277 -277.164712) (xy 409.008308 -277.18581) (xy 408.961037 -277.199502) (xy 408.912182 -277.205434)
			(xy 408.863007 -277.203453) (xy 408.814788 -277.193609) (xy 408.768772 -277.176157) (xy 408.726151 -277.15155)
			(xy 408.68803 -277.120425) (xy 408.655395 -277.083588) (xy 408.629092 -277.041992) (xy 408.609801 -276.996716)
			(xy 408.598024 -276.948932) (xy 408.594064 -276.899878) (xy 408.255216 -276.899878) (xy 408.254721 -276.924485)
			(xy 408.246826 -276.973062) (xy 408.231242 -277.019743) (xy 408.208371 -277.06332) (xy 408.178806 -277.102664)
			(xy 408.143313 -277.136756) (xy 408.10281 -277.164712) (xy 408.058348 -277.18581) (xy 408.011077 -277.199502)
			(xy 407.962222 -277.205434) (xy 407.913047 -277.203453) (xy 407.864828 -277.193609) (xy 407.818812 -277.176157)
			(xy 407.776191 -277.15155) (xy 407.73807 -277.120425) (xy 407.705435 -277.083588) (xy 407.679132 -277.041992)
			(xy 407.659841 -276.996716) (xy 407.648064 -276.948932) (xy 407.644104 -276.899878) (xy 407.305256 -276.899878)
			(xy 407.304761 -276.924485) (xy 407.296866 -276.973062) (xy 407.281282 -277.019743) (xy 407.258411 -277.06332)
			(xy 407.228846 -277.102664) (xy 407.193353 -277.136756) (xy 407.15285 -277.164712) (xy 407.108388 -277.18581)
			(xy 407.061117 -277.199502) (xy 407.012262 -277.205434) (xy 406.963087 -277.203453) (xy 406.914868 -277.193609)
			(xy 406.868852 -277.176157) (xy 406.826231 -277.15155) (xy 406.78811 -277.120425) (xy 406.755475 -277.083588)
			(xy 406.729172 -277.041992) (xy 406.709881 -276.996716) (xy 406.698104 -276.948932) (xy 406.694144 -276.899878)
			(xy 406.355296 -276.899878) (xy 406.354801 -276.924485) (xy 406.346906 -276.973062) (xy 406.331322 -277.019743)
			(xy 406.308451 -277.06332) (xy 406.278886 -277.102664) (xy 406.243393 -277.136756) (xy 406.20289 -277.164712)
			(xy 406.158428 -277.18581) (xy 406.111157 -277.199502) (xy 406.062302 -277.205434) (xy 406.013127 -277.203453)
			(xy 405.964908 -277.193609) (xy 405.918892 -277.176157) (xy 405.876271 -277.15155) (xy 405.83815 -277.120425)
			(xy 405.805515 -277.083588) (xy 405.779212 -277.041992) (xy 405.759921 -276.996716) (xy 405.748144 -276.948932)
			(xy 405.744184 -276.899878) (xy 405.405336 -276.899878) (xy 405.404841 -276.924485) (xy 405.396946 -276.973062)
			(xy 405.381362 -277.019743) (xy 405.358491 -277.06332) (xy 405.328926 -277.102664) (xy 405.293433 -277.136756)
			(xy 405.25293 -277.164712) (xy 405.208468 -277.18581) (xy 405.161197 -277.199502) (xy 405.112342 -277.205434)
			(xy 405.063167 -277.203453) (xy 405.014948 -277.193609) (xy 404.968932 -277.176157) (xy 404.926311 -277.15155)
			(xy 404.88819 -277.120425) (xy 404.855555 -277.083588) (xy 404.829252 -277.041992) (xy 404.809961 -276.996716)
			(xy 404.798184 -276.948932) (xy 404.794224 -276.899878) (xy 404.455122 -276.899878) (xy 404.454627 -276.924485)
			(xy 404.446732 -276.973062) (xy 404.431148 -277.019743) (xy 404.408277 -277.06332) (xy 404.378712 -277.102664)
			(xy 404.343219 -277.136756) (xy 404.302716 -277.164712) (xy 404.258254 -277.18581) (xy 404.210983 -277.199502)
			(xy 404.162128 -277.205434) (xy 404.112953 -277.203453) (xy 404.064734 -277.193609) (xy 404.018718 -277.176157)
			(xy 403.976097 -277.15155) (xy 403.937976 -277.120425) (xy 403.905341 -277.083588) (xy 403.879038 -277.041992)
			(xy 403.859747 -276.996716) (xy 403.84797 -276.948932) (xy 403.84401 -276.899878) (xy 403.505162 -276.899878)
			(xy 403.504667 -276.924485) (xy 403.496772 -276.973062) (xy 403.481188 -277.019743) (xy 403.458317 -277.06332)
			(xy 403.428752 -277.102664) (xy 403.393259 -277.136756) (xy 403.352756 -277.164712) (xy 403.308294 -277.18581)
			(xy 403.261023 -277.199502) (xy 403.212168 -277.205434) (xy 403.162993 -277.203453) (xy 403.114774 -277.193609)
			(xy 403.068758 -277.176157) (xy 403.026137 -277.15155) (xy 402.988016 -277.120425) (xy 402.955381 -277.083588)
			(xy 402.929078 -277.041992) (xy 402.909787 -276.996716) (xy 402.89801 -276.948932) (xy 402.89405 -276.899878)
			(xy 402.555202 -276.899878) (xy 402.554707 -276.924485) (xy 402.546812 -276.973062) (xy 402.531228 -277.019743)
			(xy 402.508357 -277.06332) (xy 402.478792 -277.102664) (xy 402.443299 -277.136756) (xy 402.402796 -277.164712)
			(xy 402.358334 -277.18581) (xy 402.311063 -277.199502) (xy 402.262208 -277.205434) (xy 402.213033 -277.203453)
			(xy 402.164814 -277.193609) (xy 402.118798 -277.176157) (xy 402.076177 -277.15155) (xy 402.038056 -277.120425)
			(xy 402.005421 -277.083588) (xy 401.979118 -277.041992) (xy 401.959827 -276.996716) (xy 401.94805 -276.948932)
			(xy 401.94409 -276.899878) (xy 401.605242 -276.899878) (xy 401.604747 -276.924485) (xy 401.596852 -276.973062)
			(xy 401.581268 -277.019743) (xy 401.558397 -277.06332) (xy 401.528832 -277.102664) (xy 401.493339 -277.136756)
			(xy 401.452836 -277.164712) (xy 401.408374 -277.18581) (xy 401.361103 -277.199502) (xy 401.312248 -277.205434)
			(xy 401.263073 -277.203453) (xy 401.214854 -277.193609) (xy 401.168838 -277.176157) (xy 401.126217 -277.15155)
			(xy 401.088096 -277.120425) (xy 401.055461 -277.083588) (xy 401.029158 -277.041992) (xy 401.009867 -276.996716)
			(xy 400.99809 -276.948932) (xy 400.99413 -276.899878) (xy 400.655282 -276.899878) (xy 400.654787 -276.924485)
			(xy 400.646892 -276.973062) (xy 400.631308 -277.019743) (xy 400.608437 -277.06332) (xy 400.578872 -277.102664)
			(xy 400.543379 -277.136756) (xy 400.502876 -277.164712) (xy 400.458414 -277.18581) (xy 400.411143 -277.199502)
			(xy 400.362288 -277.205434) (xy 400.313113 -277.203453) (xy 400.264894 -277.193609) (xy 400.218878 -277.176157)
			(xy 400.176257 -277.15155) (xy 400.138136 -277.120425) (xy 400.105501 -277.083588) (xy 400.079198 -277.041992)
			(xy 400.059907 -276.996716) (xy 400.04813 -276.948932) (xy 400.04417 -276.899878) (xy 399.705322 -276.899878)
			(xy 399.704827 -276.924485) (xy 399.696932 -276.973062) (xy 399.681348 -277.019743) (xy 399.658477 -277.06332)
			(xy 399.628912 -277.102664) (xy 399.593419 -277.136756) (xy 399.552916 -277.164712) (xy 399.508454 -277.18581)
			(xy 399.461183 -277.199502) (xy 399.412328 -277.205434) (xy 399.363153 -277.203453) (xy 399.314934 -277.193609)
			(xy 399.268918 -277.176157) (xy 399.226297 -277.15155) (xy 399.188176 -277.120425) (xy 399.155541 -277.083588)
			(xy 399.129238 -277.041992) (xy 399.109947 -276.996716) (xy 399.09817 -276.948932) (xy 399.09421 -276.899878)
			(xy 398.755108 -276.899878) (xy 398.754613 -276.924485) (xy 398.746718 -276.973062) (xy 398.731134 -277.019743)
			(xy 398.708263 -277.06332) (xy 398.678698 -277.102664) (xy 398.643205 -277.136756) (xy 398.602702 -277.164712)
			(xy 398.55824 -277.18581) (xy 398.510969 -277.199502) (xy 398.462114 -277.205434) (xy 398.412939 -277.203453)
			(xy 398.36472 -277.193609) (xy 398.318704 -277.176157) (xy 398.276083 -277.15155) (xy 398.237962 -277.120425)
			(xy 398.205327 -277.083588) (xy 398.179024 -277.041992) (xy 398.159733 -276.996716) (xy 398.147956 -276.948932)
			(xy 398.143996 -276.899878) (xy 397.805148 -276.899878) (xy 397.804653 -276.924485) (xy 397.796758 -276.973062)
			(xy 397.781174 -277.019743) (xy 397.758303 -277.06332) (xy 397.728738 -277.102664) (xy 397.693245 -277.136756)
			(xy 397.652742 -277.164712) (xy 397.60828 -277.18581) (xy 397.561009 -277.199502) (xy 397.512154 -277.205434)
			(xy 397.462979 -277.203453) (xy 397.41476 -277.193609) (xy 397.368744 -277.176157) (xy 397.326123 -277.15155)
			(xy 397.288002 -277.120425) (xy 397.255367 -277.083588) (xy 397.229064 -277.041992) (xy 397.209773 -276.996716)
			(xy 397.197996 -276.948932) (xy 397.194036 -276.899878) (xy 396.855188 -276.899878) (xy 396.854693 -276.924485)
			(xy 396.846798 -276.973062) (xy 396.831214 -277.019743) (xy 396.808343 -277.06332) (xy 396.778778 -277.102664)
			(xy 396.743285 -277.136756) (xy 396.702782 -277.164712) (xy 396.65832 -277.18581) (xy 396.611049 -277.199502)
			(xy 396.562194 -277.205434) (xy 396.513019 -277.203453) (xy 396.4648 -277.193609) (xy 396.418784 -277.176157)
			(xy 396.376163 -277.15155) (xy 396.338042 -277.120425) (xy 396.305407 -277.083588) (xy 396.279104 -277.041992)
			(xy 396.259813 -276.996716) (xy 396.248036 -276.948932) (xy 396.244076 -276.899878) (xy 395.905228 -276.899878)
			(xy 395.904733 -276.924485) (xy 395.896838 -276.973062) (xy 395.881254 -277.019743) (xy 395.858383 -277.06332)
			(xy 395.828818 -277.102664) (xy 395.793325 -277.136756) (xy 395.752822 -277.164712) (xy 395.70836 -277.18581)
			(xy 395.661089 -277.199502) (xy 395.612234 -277.205434) (xy 395.563059 -277.203453) (xy 395.51484 -277.193609)
			(xy 395.468824 -277.176157) (xy 395.426203 -277.15155) (xy 395.388082 -277.120425) (xy 395.355447 -277.083588)
			(xy 395.329144 -277.041992) (xy 395.309853 -276.996716) (xy 395.298076 -276.948932) (xy 395.294116 -276.899878)
			(xy 394.955268 -276.899878) (xy 394.954773 -276.924485) (xy 394.946878 -276.973062) (xy 394.931294 -277.019743)
			(xy 394.908423 -277.06332) (xy 394.878858 -277.102664) (xy 394.843365 -277.136756) (xy 394.802862 -277.164712)
			(xy 394.7584 -277.18581) (xy 394.711129 -277.199502) (xy 394.662274 -277.205434) (xy 394.613099 -277.203453)
			(xy 394.56488 -277.193609) (xy 394.518864 -277.176157) (xy 394.476243 -277.15155) (xy 394.438122 -277.120425)
			(xy 394.405487 -277.083588) (xy 394.379184 -277.041992) (xy 394.359893 -276.996716) (xy 394.348116 -276.948932)
			(xy 394.344156 -276.899878) (xy 394.005308 -276.899878) (xy 394.004813 -276.924485) (xy 393.996918 -276.973062)
			(xy 393.981334 -277.019743) (xy 393.958463 -277.06332) (xy 393.928898 -277.102664) (xy 393.893405 -277.136756)
			(xy 393.852902 -277.164712) (xy 393.80844 -277.18581) (xy 393.761169 -277.199502) (xy 393.712314 -277.205434)
			(xy 393.663139 -277.203453) (xy 393.61492 -277.193609) (xy 393.568904 -277.176157) (xy 393.526283 -277.15155)
			(xy 393.488162 -277.120425) (xy 393.455527 -277.083588) (xy 393.429224 -277.041992) (xy 393.409933 -276.996716)
			(xy 393.398156 -276.948932) (xy 393.394196 -276.899878) (xy 393.055094 -276.899878) (xy 393.054599 -276.924485)
			(xy 393.046704 -276.973062) (xy 393.03112 -277.019743) (xy 393.008249 -277.06332) (xy 392.978684 -277.102664)
			(xy 392.943191 -277.136756) (xy 392.902688 -277.164712) (xy 392.858226 -277.18581) (xy 392.810955 -277.199502)
			(xy 392.7621 -277.205434) (xy 392.712925 -277.203453) (xy 392.664706 -277.193609) (xy 392.61869 -277.176157)
			(xy 392.576069 -277.15155) (xy 392.537948 -277.120425) (xy 392.505313 -277.083588) (xy 392.47901 -277.041992)
			(xy 392.459719 -276.996716) (xy 392.447942 -276.948932) (xy 392.443982 -276.899878) (xy 383.78638 -276.899878)
			(xy 383.78638 -277.374858) (xy 384.369068 -277.374858) (xy 384.373028 -277.325804) (xy 384.384805 -277.27802)
			(xy 384.404096 -277.232744) (xy 384.430399 -277.191148) (xy 384.463034 -277.154311) (xy 384.501155 -277.123186)
			(xy 384.543776 -277.098579) (xy 384.589792 -277.081127) (xy 384.638011 -277.071283) (xy 384.687186 -277.069302)
			(xy 384.736041 -277.075234) (xy 384.783312 -277.088926) (xy 384.827774 -277.110024) (xy 384.868277 -277.13798)
			(xy 384.90377 -277.172072) (xy 384.933335 -277.211416) (xy 384.956206 -277.254993) (xy 384.97179 -277.301674)
			(xy 384.979685 -277.350251) (xy 384.98018 -277.374858) (xy 385.319028 -277.374858) (xy 385.322988 -277.325804)
			(xy 385.334765 -277.27802) (xy 385.354056 -277.232744) (xy 385.380359 -277.191148) (xy 385.412994 -277.154311)
			(xy 385.451115 -277.123186) (xy 385.493736 -277.098579) (xy 385.539752 -277.081127) (xy 385.587971 -277.071283)
			(xy 385.637146 -277.069302) (xy 385.686001 -277.075234) (xy 385.733272 -277.088926) (xy 385.777734 -277.110024)
			(xy 385.818237 -277.13798) (xy 385.85373 -277.172072) (xy 385.883295 -277.211416) (xy 385.906166 -277.254993)
			(xy 385.92175 -277.301674) (xy 385.929645 -277.350251) (xy 385.93014 -277.374858) (xy 386.269242 -277.374858)
			(xy 386.273202 -277.325804) (xy 386.284979 -277.27802) (xy 386.30427 -277.232744) (xy 386.330573 -277.191148)
			(xy 386.363208 -277.154311) (xy 386.401329 -277.123186) (xy 386.44395 -277.098579) (xy 386.489966 -277.081127)
			(xy 386.538185 -277.071283) (xy 386.58736 -277.069302) (xy 386.636215 -277.075234) (xy 386.683486 -277.088926)
			(xy 386.727948 -277.110024) (xy 386.768451 -277.13798) (xy 386.803944 -277.172072) (xy 386.833509 -277.211416)
			(xy 386.85638 -277.254993) (xy 386.871964 -277.301674) (xy 386.879859 -277.350251) (xy 386.880354 -277.374858)
			(xy 387.219202 -277.374858) (xy 387.223162 -277.325804) (xy 387.234939 -277.27802) (xy 387.25423 -277.232744)
			(xy 387.280533 -277.191148) (xy 387.313168 -277.154311) (xy 387.351289 -277.123186) (xy 387.39391 -277.098579)
			(xy 387.439926 -277.081127) (xy 387.488145 -277.071283) (xy 387.53732 -277.069302) (xy 387.586175 -277.075234)
			(xy 387.633446 -277.088926) (xy 387.677908 -277.110024) (xy 387.718411 -277.13798) (xy 387.753904 -277.172072)
			(xy 387.783469 -277.211416) (xy 387.80634 -277.254993) (xy 387.821924 -277.301674) (xy 387.829819 -277.350251)
			(xy 387.830314 -277.374858) (xy 388.169162 -277.374858) (xy 388.173122 -277.325804) (xy 388.184899 -277.27802)
			(xy 388.20419 -277.232744) (xy 388.230493 -277.191148) (xy 388.263128 -277.154311) (xy 388.301249 -277.123186)
			(xy 388.34387 -277.098579) (xy 388.389886 -277.081127) (xy 388.438105 -277.071283) (xy 388.48728 -277.069302)
			(xy 388.536135 -277.075234) (xy 388.583406 -277.088926) (xy 388.627868 -277.110024) (xy 388.668371 -277.13798)
			(xy 388.703864 -277.172072) (xy 388.733429 -277.211416) (xy 388.7563 -277.254993) (xy 388.771884 -277.301674)
			(xy 388.779779 -277.350251) (xy 388.780274 -277.374858) (xy 389.119122 -277.374858) (xy 389.123082 -277.325804)
			(xy 389.134859 -277.27802) (xy 389.15415 -277.232744) (xy 389.180453 -277.191148) (xy 389.213088 -277.154311)
			(xy 389.251209 -277.123186) (xy 389.29383 -277.098579) (xy 389.339846 -277.081127) (xy 389.388065 -277.071283)
			(xy 389.43724 -277.069302) (xy 389.486095 -277.075234) (xy 389.533366 -277.088926) (xy 389.577828 -277.110024)
			(xy 389.618331 -277.13798) (xy 389.653824 -277.172072) (xy 389.683389 -277.211416) (xy 389.70626 -277.254993)
			(xy 389.721844 -277.301674) (xy 389.729739 -277.350251) (xy 389.730234 -277.374858) (xy 390.069082 -277.374858)
			(xy 390.073042 -277.325804) (xy 390.084819 -277.27802) (xy 390.10411 -277.232744) (xy 390.130413 -277.191148)
			(xy 390.163048 -277.154311) (xy 390.201169 -277.123186) (xy 390.24379 -277.098579) (xy 390.289806 -277.081127)
			(xy 390.338025 -277.071283) (xy 390.3872 -277.069302) (xy 390.436055 -277.075234) (xy 390.483326 -277.088926)
			(xy 390.527788 -277.110024) (xy 390.568291 -277.13798) (xy 390.603784 -277.172072) (xy 390.633349 -277.211416)
			(xy 390.65622 -277.254993) (xy 390.671804 -277.301674) (xy 390.679699 -277.350251) (xy 390.680194 -277.374858)
			(xy 391.019042 -277.374858) (xy 391.023002 -277.325804) (xy 391.034779 -277.27802) (xy 391.05407 -277.232744)
			(xy 391.080373 -277.191148) (xy 391.113008 -277.154311) (xy 391.151129 -277.123186) (xy 391.19375 -277.098579)
			(xy 391.239766 -277.081127) (xy 391.287985 -277.071283) (xy 391.33716 -277.069302) (xy 391.386015 -277.075234)
			(xy 391.433286 -277.088926) (xy 391.477748 -277.110024) (xy 391.518251 -277.13798) (xy 391.553744 -277.172072)
			(xy 391.583309 -277.211416) (xy 391.60618 -277.254993) (xy 391.621764 -277.301674) (xy 391.629659 -277.350251)
			(xy 391.630154 -277.374858) (xy 391.629659 -277.399465) (xy 391.621764 -277.448042) (xy 391.60618 -277.494723)
			(xy 391.583309 -277.5383) (xy 391.553744 -277.577644) (xy 391.518251 -277.611736) (xy 391.477748 -277.639692)
			(xy 391.433286 -277.66079) (xy 391.386015 -277.674482) (xy 391.33716 -277.680414) (xy 391.287985 -277.678433)
			(xy 391.239766 -277.668589) (xy 391.19375 -277.651137) (xy 391.151129 -277.62653) (xy 391.113008 -277.595405)
			(xy 391.080373 -277.558568) (xy 391.05407 -277.516972) (xy 391.034779 -277.471696) (xy 391.023002 -277.423912)
			(xy 391.019042 -277.374858) (xy 390.680194 -277.374858) (xy 390.679699 -277.399465) (xy 390.671804 -277.448042)
			(xy 390.65622 -277.494723) (xy 390.633349 -277.5383) (xy 390.603784 -277.577644) (xy 390.568291 -277.611736)
			(xy 390.527788 -277.639692) (xy 390.483326 -277.66079) (xy 390.436055 -277.674482) (xy 390.3872 -277.680414)
			(xy 390.338025 -277.678433) (xy 390.289806 -277.668589) (xy 390.24379 -277.651137) (xy 390.201169 -277.62653)
			(xy 390.163048 -277.595405) (xy 390.130413 -277.558568) (xy 390.10411 -277.516972) (xy 390.084819 -277.471696)
			(xy 390.073042 -277.423912) (xy 390.069082 -277.374858) (xy 389.730234 -277.374858) (xy 389.729739 -277.399465)
			(xy 389.721844 -277.448042) (xy 389.70626 -277.494723) (xy 389.683389 -277.5383) (xy 389.653824 -277.577644)
			(xy 389.618331 -277.611736) (xy 389.577828 -277.639692) (xy 389.533366 -277.66079) (xy 389.486095 -277.674482)
			(xy 389.43724 -277.680414) (xy 389.388065 -277.678433) (xy 389.339846 -277.668589) (xy 389.29383 -277.651137)
			(xy 389.251209 -277.62653) (xy 389.213088 -277.595405) (xy 389.180453 -277.558568) (xy 389.15415 -277.516972)
			(xy 389.134859 -277.471696) (xy 389.123082 -277.423912) (xy 389.119122 -277.374858) (xy 388.780274 -277.374858)
			(xy 388.779779 -277.399465) (xy 388.771884 -277.448042) (xy 388.7563 -277.494723) (xy 388.733429 -277.5383)
			(xy 388.703864 -277.577644) (xy 388.668371 -277.611736) (xy 388.627868 -277.639692) (xy 388.583406 -277.66079)
			(xy 388.536135 -277.674482) (xy 388.48728 -277.680414) (xy 388.438105 -277.678433) (xy 388.389886 -277.668589)
			(xy 388.34387 -277.651137) (xy 388.301249 -277.62653) (xy 388.263128 -277.595405) (xy 388.230493 -277.558568)
			(xy 388.20419 -277.516972) (xy 388.184899 -277.471696) (xy 388.173122 -277.423912) (xy 388.169162 -277.374858)
			(xy 387.830314 -277.374858) (xy 387.829819 -277.399465) (xy 387.821924 -277.448042) (xy 387.80634 -277.494723)
			(xy 387.783469 -277.5383) (xy 387.753904 -277.577644) (xy 387.718411 -277.611736) (xy 387.677908 -277.639692)
			(xy 387.633446 -277.66079) (xy 387.586175 -277.674482) (xy 387.53732 -277.680414) (xy 387.488145 -277.678433)
			(xy 387.439926 -277.668589) (xy 387.39391 -277.651137) (xy 387.351289 -277.62653) (xy 387.313168 -277.595405)
			(xy 387.280533 -277.558568) (xy 387.25423 -277.516972) (xy 387.234939 -277.471696) (xy 387.223162 -277.423912)
			(xy 387.219202 -277.374858) (xy 386.880354 -277.374858) (xy 386.879859 -277.399465) (xy 386.871964 -277.448042)
			(xy 386.85638 -277.494723) (xy 386.833509 -277.5383) (xy 386.803944 -277.577644) (xy 386.768451 -277.611736)
			(xy 386.727948 -277.639692) (xy 386.683486 -277.66079) (xy 386.636215 -277.674482) (xy 386.58736 -277.680414)
			(xy 386.538185 -277.678433) (xy 386.489966 -277.668589) (xy 386.44395 -277.651137) (xy 386.401329 -277.62653)
			(xy 386.363208 -277.595405) (xy 386.330573 -277.558568) (xy 386.30427 -277.516972) (xy 386.284979 -277.471696)
			(xy 386.273202 -277.423912) (xy 386.269242 -277.374858) (xy 385.93014 -277.374858) (xy 385.929645 -277.399465)
			(xy 385.92175 -277.448042) (xy 385.906166 -277.494723) (xy 385.883295 -277.5383) (xy 385.85373 -277.577644)
			(xy 385.818237 -277.611736) (xy 385.777734 -277.639692) (xy 385.733272 -277.66079) (xy 385.686001 -277.674482)
			(xy 385.637146 -277.680414) (xy 385.587971 -277.678433) (xy 385.539752 -277.668589) (xy 385.493736 -277.651137)
			(xy 385.451115 -277.62653) (xy 385.412994 -277.595405) (xy 385.380359 -277.558568) (xy 385.354056 -277.516972)
			(xy 385.334765 -277.471696) (xy 385.322988 -277.423912) (xy 385.319028 -277.374858) (xy 384.98018 -277.374858)
			(xy 384.979685 -277.399465) (xy 384.97179 -277.448042) (xy 384.956206 -277.494723) (xy 384.933335 -277.5383)
			(xy 384.90377 -277.577644) (xy 384.868277 -277.611736) (xy 384.827774 -277.639692) (xy 384.783312 -277.66079)
			(xy 384.736041 -277.674482) (xy 384.687186 -277.680414) (xy 384.638011 -277.678433) (xy 384.589792 -277.668589)
			(xy 384.543776 -277.651137) (xy 384.501155 -277.62653) (xy 384.463034 -277.595405) (xy 384.430399 -277.558568)
			(xy 384.404096 -277.516972) (xy 384.384805 -277.471696) (xy 384.373028 -277.423912) (xy 384.369068 -277.374858)
			(xy 383.78638 -277.374858) (xy 383.78638 -277.875546) (xy 392.423138 -277.875546) (xy 392.423138 -277.82413)
			(xy 392.431181 -277.773348) (xy 392.447069 -277.724449) (xy 392.470412 -277.678637) (xy 392.500633 -277.637041)
			(xy 392.536989 -277.600685) (xy 392.578585 -277.570464) (xy 392.624397 -277.547121) (xy 392.673296 -277.531233)
			(xy 392.724078 -277.52319) (xy 392.775494 -277.52319) (xy 392.826276 -277.531233) (xy 392.875175 -277.547121)
			(xy 392.920987 -277.570464) (xy 392.962583 -277.600685) (xy 392.998939 -277.637041) (xy 393.02916 -277.678637)
			(xy 393.052503 -277.724449) (xy 393.068391 -277.773348) (xy 393.076434 -277.82413) (xy 393.076938 -277.849838)
			(xy 393.394196 -277.849838) (xy 393.398156 -277.800784) (xy 393.409933 -277.753) (xy 393.429224 -277.707724)
			(xy 393.455527 -277.666128) (xy 393.488162 -277.629291) (xy 393.526283 -277.598166) (xy 393.568904 -277.573559)
			(xy 393.61492 -277.556107) (xy 393.663139 -277.546263) (xy 393.712314 -277.544282) (xy 393.761169 -277.550214)
			(xy 393.80844 -277.563906) (xy 393.852902 -277.585004) (xy 393.893405 -277.61296) (xy 393.928898 -277.647052)
			(xy 393.958463 -277.686396) (xy 393.981334 -277.729973) (xy 393.996918 -277.776654) (xy 394.004813 -277.825231)
			(xy 394.005308 -277.849838) (xy 394.004813 -277.874445) (xy 394.004634 -277.875546) (xy 394.323312 -277.875546)
			(xy 394.323312 -277.82413) (xy 394.331355 -277.773348) (xy 394.347243 -277.724449) (xy 394.370586 -277.678637)
			(xy 394.400807 -277.637041) (xy 394.437163 -277.600685) (xy 394.478759 -277.570464) (xy 394.524571 -277.547121)
			(xy 394.57347 -277.531233) (xy 394.624252 -277.52319) (xy 394.675668 -277.52319) (xy 394.72645 -277.531233)
			(xy 394.775349 -277.547121) (xy 394.821161 -277.570464) (xy 394.862757 -277.600685) (xy 394.899113 -277.637041)
			(xy 394.929334 -277.678637) (xy 394.952677 -277.724449) (xy 394.968565 -277.773348) (xy 394.976608 -277.82413)
			(xy 394.977112 -277.849838) (xy 395.294116 -277.849838) (xy 395.298076 -277.800784) (xy 395.309853 -277.753)
			(xy 395.329144 -277.707724) (xy 395.355447 -277.666128) (xy 395.388082 -277.629291) (xy 395.426203 -277.598166)
			(xy 395.468824 -277.573559) (xy 395.51484 -277.556107) (xy 395.563059 -277.546263) (xy 395.612234 -277.544282)
			(xy 395.661089 -277.550214) (xy 395.70836 -277.563906) (xy 395.752822 -277.585004) (xy 395.793325 -277.61296)
			(xy 395.828818 -277.647052) (xy 395.858383 -277.686396) (xy 395.881254 -277.729973) (xy 395.896838 -277.776654)
			(xy 395.904733 -277.825231) (xy 395.905228 -277.849838) (xy 395.904733 -277.874445) (xy 395.904554 -277.875546)
			(xy 396.223232 -277.875546) (xy 396.223232 -277.82413) (xy 396.231275 -277.773348) (xy 396.247163 -277.724449)
			(xy 396.270506 -277.678637) (xy 396.300727 -277.637041) (xy 396.337083 -277.600685) (xy 396.378679 -277.570464)
			(xy 396.424491 -277.547121) (xy 396.47339 -277.531233) (xy 396.524172 -277.52319) (xy 396.575588 -277.52319)
			(xy 396.62637 -277.531233) (xy 396.675269 -277.547121) (xy 396.721081 -277.570464) (xy 396.762677 -277.600685)
			(xy 396.799033 -277.637041) (xy 396.829254 -277.678637) (xy 396.852597 -277.724449) (xy 396.868485 -277.773348)
			(xy 396.876528 -277.82413) (xy 396.877032 -277.849838) (xy 397.194036 -277.849838) (xy 397.197996 -277.800784)
			(xy 397.209773 -277.753) (xy 397.229064 -277.707724) (xy 397.255367 -277.666128) (xy 397.288002 -277.629291)
			(xy 397.326123 -277.598166) (xy 397.368744 -277.573559) (xy 397.41476 -277.556107) (xy 397.462979 -277.546263)
			(xy 397.512154 -277.544282) (xy 397.561009 -277.550214) (xy 397.60828 -277.563906) (xy 397.652742 -277.585004)
			(xy 397.693245 -277.61296) (xy 397.728738 -277.647052) (xy 397.758303 -277.686396) (xy 397.781174 -277.729973)
			(xy 397.796758 -277.776654) (xy 397.804653 -277.825231) (xy 397.805148 -277.849838) (xy 397.804653 -277.874445)
			(xy 397.804474 -277.875546) (xy 398.123152 -277.875546) (xy 398.123152 -277.82413) (xy 398.131195 -277.773348)
			(xy 398.147083 -277.724449) (xy 398.170426 -277.678637) (xy 398.200647 -277.637041) (xy 398.237003 -277.600685)
			(xy 398.278599 -277.570464) (xy 398.324411 -277.547121) (xy 398.37331 -277.531233) (xy 398.424092 -277.52319)
			(xy 398.475508 -277.52319) (xy 398.52629 -277.531233) (xy 398.575189 -277.547121) (xy 398.621001 -277.570464)
			(xy 398.662597 -277.600685) (xy 398.698953 -277.637041) (xy 398.729174 -277.678637) (xy 398.752517 -277.724449)
			(xy 398.768405 -277.773348) (xy 398.776448 -277.82413) (xy 398.776952 -277.849838) (xy 399.09421 -277.849838)
			(xy 399.09817 -277.800784) (xy 399.109947 -277.753) (xy 399.129238 -277.707724) (xy 399.155541 -277.666128)
			(xy 399.188176 -277.629291) (xy 399.226297 -277.598166) (xy 399.268918 -277.573559) (xy 399.314934 -277.556107)
			(xy 399.363153 -277.546263) (xy 399.412328 -277.544282) (xy 399.461183 -277.550214) (xy 399.508454 -277.563906)
			(xy 399.552916 -277.585004) (xy 399.593419 -277.61296) (xy 399.628912 -277.647052) (xy 399.658477 -277.686396)
			(xy 399.681348 -277.729973) (xy 399.696932 -277.776654) (xy 399.704827 -277.825231) (xy 399.705322 -277.849838)
			(xy 399.704827 -277.874445) (xy 399.704648 -277.875546) (xy 400.023326 -277.875546) (xy 400.023326 -277.82413)
			(xy 400.031369 -277.773348) (xy 400.047257 -277.724449) (xy 400.0706 -277.678637) (xy 400.100821 -277.637041)
			(xy 400.137177 -277.600685) (xy 400.178773 -277.570464) (xy 400.224585 -277.547121) (xy 400.273484 -277.531233)
			(xy 400.324266 -277.52319) (xy 400.375682 -277.52319) (xy 400.426464 -277.531233) (xy 400.475363 -277.547121)
			(xy 400.521175 -277.570464) (xy 400.562771 -277.600685) (xy 400.599127 -277.637041) (xy 400.629348 -277.678637)
			(xy 400.652691 -277.724449) (xy 400.668579 -277.773348) (xy 400.676622 -277.82413) (xy 400.677126 -277.849838)
			(xy 400.99413 -277.849838) (xy 400.99809 -277.800784) (xy 401.009867 -277.753) (xy 401.029158 -277.707724)
			(xy 401.055461 -277.666128) (xy 401.088096 -277.629291) (xy 401.126217 -277.598166) (xy 401.168838 -277.573559)
			(xy 401.214854 -277.556107) (xy 401.263073 -277.546263) (xy 401.312248 -277.544282) (xy 401.361103 -277.550214)
			(xy 401.408374 -277.563906) (xy 401.452836 -277.585004) (xy 401.493339 -277.61296) (xy 401.528832 -277.647052)
			(xy 401.558397 -277.686396) (xy 401.581268 -277.729973) (xy 401.596852 -277.776654) (xy 401.604747 -277.825231)
			(xy 401.605242 -277.849838) (xy 401.604747 -277.874445) (xy 401.604568 -277.875546) (xy 401.923246 -277.875546)
			(xy 401.923246 -277.82413) (xy 401.931289 -277.773348) (xy 401.947177 -277.724449) (xy 401.97052 -277.678637)
			(xy 402.000741 -277.637041) (xy 402.037097 -277.600685) (xy 402.078693 -277.570464) (xy 402.124505 -277.547121)
			(xy 402.173404 -277.531233) (xy 402.224186 -277.52319) (xy 402.275602 -277.52319) (xy 402.326384 -277.531233)
			(xy 402.375283 -277.547121) (xy 402.421095 -277.570464) (xy 402.462691 -277.600685) (xy 402.499047 -277.637041)
			(xy 402.529268 -277.678637) (xy 402.552611 -277.724449) (xy 402.568499 -277.773348) (xy 402.576542 -277.82413)
			(xy 402.577046 -277.849838) (xy 402.89405 -277.849838) (xy 402.89801 -277.800784) (xy 402.909787 -277.753)
			(xy 402.929078 -277.707724) (xy 402.955381 -277.666128) (xy 402.988016 -277.629291) (xy 403.026137 -277.598166)
			(xy 403.068758 -277.573559) (xy 403.114774 -277.556107) (xy 403.162993 -277.546263) (xy 403.212168 -277.544282)
			(xy 403.261023 -277.550214) (xy 403.308294 -277.563906) (xy 403.352756 -277.585004) (xy 403.393259 -277.61296)
			(xy 403.428752 -277.647052) (xy 403.458317 -277.686396) (xy 403.481188 -277.729973) (xy 403.496772 -277.776654)
			(xy 403.504667 -277.825231) (xy 403.505162 -277.849838) (xy 403.504667 -277.874445) (xy 403.504488 -277.875546)
			(xy 403.823166 -277.875546) (xy 403.823166 -277.82413) (xy 403.831209 -277.773348) (xy 403.847097 -277.724449)
			(xy 403.87044 -277.678637) (xy 403.900661 -277.637041) (xy 403.937017 -277.600685) (xy 403.978613 -277.570464)
			(xy 404.024425 -277.547121) (xy 404.073324 -277.531233) (xy 404.124106 -277.52319) (xy 404.175522 -277.52319)
			(xy 404.226304 -277.531233) (xy 404.275203 -277.547121) (xy 404.321015 -277.570464) (xy 404.362611 -277.600685)
			(xy 404.398967 -277.637041) (xy 404.429188 -277.678637) (xy 404.452531 -277.724449) (xy 404.468419 -277.773348)
			(xy 404.476462 -277.82413) (xy 404.476966 -277.849838) (xy 404.794224 -277.849838) (xy 404.798184 -277.800784)
			(xy 404.809961 -277.753) (xy 404.829252 -277.707724) (xy 404.855555 -277.666128) (xy 404.88819 -277.629291)
			(xy 404.926311 -277.598166) (xy 404.968932 -277.573559) (xy 405.014948 -277.556107) (xy 405.063167 -277.546263)
			(xy 405.112342 -277.544282) (xy 405.161197 -277.550214) (xy 405.208468 -277.563906) (xy 405.25293 -277.585004)
			(xy 405.293433 -277.61296) (xy 405.328926 -277.647052) (xy 405.358491 -277.686396) (xy 405.381362 -277.729973)
			(xy 405.396946 -277.776654) (xy 405.404841 -277.825231) (xy 405.405336 -277.849838) (xy 405.404841 -277.874445)
			(xy 405.404662 -277.875546) (xy 405.72334 -277.875546) (xy 405.72334 -277.82413) (xy 405.731383 -277.773348)
			(xy 405.747271 -277.724449) (xy 405.770614 -277.678637) (xy 405.800835 -277.637041) (xy 405.837191 -277.600685)
			(xy 405.878787 -277.570464) (xy 405.924599 -277.547121) (xy 405.973498 -277.531233) (xy 406.02428 -277.52319)
			(xy 406.075696 -277.52319) (xy 406.126478 -277.531233) (xy 406.175377 -277.547121) (xy 406.221189 -277.570464)
			(xy 406.262785 -277.600685) (xy 406.299141 -277.637041) (xy 406.329362 -277.678637) (xy 406.352705 -277.724449)
			(xy 406.368593 -277.773348) (xy 406.376636 -277.82413) (xy 406.37714 -277.849838) (xy 406.694144 -277.849838)
			(xy 406.698104 -277.800784) (xy 406.709881 -277.753) (xy 406.729172 -277.707724) (xy 406.755475 -277.666128)
			(xy 406.78811 -277.629291) (xy 406.826231 -277.598166) (xy 406.868852 -277.573559) (xy 406.914868 -277.556107)
			(xy 406.963087 -277.546263) (xy 407.012262 -277.544282) (xy 407.061117 -277.550214) (xy 407.108388 -277.563906)
			(xy 407.15285 -277.585004) (xy 407.193353 -277.61296) (xy 407.228846 -277.647052) (xy 407.258411 -277.686396)
			(xy 407.281282 -277.729973) (xy 407.296866 -277.776654) (xy 407.304761 -277.825231) (xy 407.305256 -277.849838)
			(xy 407.304761 -277.874445) (xy 407.304582 -277.875546) (xy 407.623006 -277.875546) (xy 407.623006 -277.82413)
			(xy 407.631049 -277.773348) (xy 407.646937 -277.724449) (xy 407.67028 -277.678637) (xy 407.700501 -277.637041)
			(xy 407.736857 -277.600685) (xy 407.778453 -277.570464) (xy 407.824265 -277.547121) (xy 407.873164 -277.531233)
			(xy 407.923946 -277.52319) (xy 407.975362 -277.52319) (xy 408.026144 -277.531233) (xy 408.075043 -277.547121)
			(xy 408.120855 -277.570464) (xy 408.162451 -277.600685) (xy 408.198807 -277.637041) (xy 408.229028 -277.678637)
			(xy 408.252371 -277.724449) (xy 408.268259 -277.773348) (xy 408.276302 -277.82413) (xy 408.276806 -277.849838)
			(xy 408.594064 -277.849838) (xy 408.598024 -277.800784) (xy 408.609801 -277.753) (xy 408.629092 -277.707724)
			(xy 408.655395 -277.666128) (xy 408.68803 -277.629291) (xy 408.726151 -277.598166) (xy 408.768772 -277.573559)
			(xy 408.814788 -277.556107) (xy 408.863007 -277.546263) (xy 408.912182 -277.544282) (xy 408.961037 -277.550214)
			(xy 409.008308 -277.563906) (xy 409.05277 -277.585004) (xy 409.093273 -277.61296) (xy 409.128766 -277.647052)
			(xy 409.158331 -277.686396) (xy 409.181202 -277.729973) (xy 409.196786 -277.776654) (xy 409.204681 -277.825231)
			(xy 409.205176 -277.849838) (xy 409.204681 -277.874445) (xy 409.204502 -277.875546) (xy 409.522926 -277.875546)
			(xy 409.522926 -277.82413) (xy 409.530969 -277.773348) (xy 409.546857 -277.724449) (xy 409.5702 -277.678637)
			(xy 409.600421 -277.637041) (xy 409.636777 -277.600685) (xy 409.678373 -277.570464) (xy 409.724185 -277.547121)
			(xy 409.773084 -277.531233) (xy 409.823866 -277.52319) (xy 409.875282 -277.52319) (xy 409.926064 -277.531233)
			(xy 409.974963 -277.547121) (xy 410.020775 -277.570464) (xy 410.062371 -277.600685) (xy 410.098727 -277.637041)
			(xy 410.128948 -277.678637) (xy 410.152291 -277.724449) (xy 410.168179 -277.773348) (xy 410.176222 -277.82413)
			(xy 410.176726 -277.849838) (xy 410.493984 -277.849838) (xy 410.497944 -277.800784) (xy 410.509721 -277.753)
			(xy 410.529012 -277.707724) (xy 410.555315 -277.666128) (xy 410.58795 -277.629291) (xy 410.626071 -277.598166)
			(xy 410.668692 -277.573559) (xy 410.714708 -277.556107) (xy 410.762927 -277.546263) (xy 410.812102 -277.544282)
			(xy 410.860957 -277.550214) (xy 410.908228 -277.563906) (xy 410.95269 -277.585004) (xy 410.993193 -277.61296)
			(xy 411.028686 -277.647052) (xy 411.058251 -277.686396) (xy 411.081122 -277.729973) (xy 411.096706 -277.776654)
			(xy 411.104601 -277.825231) (xy 411.105096 -277.849838) (xy 411.104601 -277.874445) (xy 411.104422 -277.875546)
			(xy 411.4231 -277.875546) (xy 411.4231 -277.82413) (xy 411.431143 -277.773348) (xy 411.447031 -277.724449)
			(xy 411.470374 -277.678637) (xy 411.500595 -277.637041) (xy 411.536951 -277.600685) (xy 411.578547 -277.570464)
			(xy 411.624359 -277.547121) (xy 411.673258 -277.531233) (xy 411.72404 -277.52319) (xy 411.775456 -277.52319)
			(xy 411.826238 -277.531233) (xy 411.875137 -277.547121) (xy 411.920949 -277.570464) (xy 411.962545 -277.600685)
			(xy 411.998901 -277.637041) (xy 412.029122 -277.678637) (xy 412.052465 -277.724449) (xy 412.068353 -277.773348)
			(xy 412.076396 -277.82413) (xy 412.0769 -277.849838) (xy 412.394158 -277.849838) (xy 412.398118 -277.800784)
			(xy 412.409895 -277.753) (xy 412.429186 -277.707724) (xy 412.455489 -277.666128) (xy 412.488124 -277.629291)
			(xy 412.526245 -277.598166) (xy 412.568866 -277.573559) (xy 412.614882 -277.556107) (xy 412.663101 -277.546263)
			(xy 412.712276 -277.544282) (xy 412.761131 -277.550214) (xy 412.808402 -277.563906) (xy 412.852864 -277.585004)
			(xy 412.893367 -277.61296) (xy 412.92886 -277.647052) (xy 412.958425 -277.686396) (xy 412.981296 -277.729973)
			(xy 412.99688 -277.776654) (xy 413.004775 -277.825231) (xy 413.00527 -277.849838) (xy 413.004775 -277.874445)
			(xy 413.004596 -277.875546) (xy 413.32302 -277.875546) (xy 413.32302 -277.82413) (xy 413.331063 -277.773348)
			(xy 413.346951 -277.724449) (xy 413.370294 -277.678637) (xy 413.400515 -277.637041) (xy 413.436871 -277.600685)
			(xy 413.478467 -277.570464) (xy 413.524279 -277.547121) (xy 413.573178 -277.531233) (xy 413.62396 -277.52319)
			(xy 413.675376 -277.52319) (xy 413.726158 -277.531233) (xy 413.775057 -277.547121) (xy 413.820869 -277.570464)
			(xy 413.862465 -277.600685) (xy 413.898821 -277.637041) (xy 413.929042 -277.678637) (xy 413.952385 -277.724449)
			(xy 413.968273 -277.773348) (xy 413.976316 -277.82413) (xy 413.97682 -277.849838) (xy 414.294078 -277.849838)
			(xy 414.298038 -277.800784) (xy 414.309815 -277.753) (xy 414.329106 -277.707724) (xy 414.355409 -277.666128)
			(xy 414.388044 -277.629291) (xy 414.426165 -277.598166) (xy 414.468786 -277.573559) (xy 414.514802 -277.556107)
			(xy 414.563021 -277.546263) (xy 414.612196 -277.544282) (xy 414.661051 -277.550214) (xy 414.708322 -277.563906)
			(xy 414.752784 -277.585004) (xy 414.793287 -277.61296) (xy 414.82878 -277.647052) (xy 414.858345 -277.686396)
			(xy 414.881216 -277.729973) (xy 414.8968 -277.776654) (xy 414.904695 -277.825231) (xy 414.90519 -277.849838)
			(xy 414.904695 -277.874445) (xy 414.904516 -277.875546) (xy 415.22294 -277.875546) (xy 415.22294 -277.82413)
			(xy 415.230983 -277.773348) (xy 415.246871 -277.724449) (xy 415.270214 -277.678637) (xy 415.300435 -277.637041)
			(xy 415.336791 -277.600685) (xy 415.378387 -277.570464) (xy 415.424199 -277.547121) (xy 415.473098 -277.531233)
			(xy 415.52388 -277.52319) (xy 415.575296 -277.52319) (xy 415.626078 -277.531233) (xy 415.674977 -277.547121)
			(xy 415.720789 -277.570464) (xy 415.762385 -277.600685) (xy 415.798741 -277.637041) (xy 415.828962 -277.678637)
			(xy 415.852305 -277.724449) (xy 415.868193 -277.773348) (xy 415.876236 -277.82413) (xy 415.87674 -277.849838)
			(xy 416.193998 -277.849838) (xy 416.197958 -277.800784) (xy 416.209735 -277.753) (xy 416.229026 -277.707724)
			(xy 416.255329 -277.666128) (xy 416.287964 -277.629291) (xy 416.326085 -277.598166) (xy 416.368706 -277.573559)
			(xy 416.414722 -277.556107) (xy 416.462941 -277.546263) (xy 416.512116 -277.544282) (xy 416.560971 -277.550214)
			(xy 416.608242 -277.563906) (xy 416.652704 -277.585004) (xy 416.693207 -277.61296) (xy 416.7287 -277.647052)
			(xy 416.758265 -277.686396) (xy 416.781136 -277.729973) (xy 416.79672 -277.776654) (xy 416.804615 -277.825231)
			(xy 416.80511 -277.849838) (xy 416.804615 -277.874445) (xy 416.804436 -277.875546) (xy 417.123114 -277.875546)
			(xy 417.123114 -277.82413) (xy 417.131157 -277.773348) (xy 417.147045 -277.724449) (xy 417.170388 -277.678637)
			(xy 417.200609 -277.637041) (xy 417.236965 -277.600685) (xy 417.278561 -277.570464) (xy 417.324373 -277.547121)
			(xy 417.373272 -277.531233) (xy 417.424054 -277.52319) (xy 417.47547 -277.52319) (xy 417.526252 -277.531233)
			(xy 417.575151 -277.547121) (xy 417.620963 -277.570464) (xy 417.662559 -277.600685) (xy 417.698915 -277.637041)
			(xy 417.729136 -277.678637) (xy 417.752479 -277.724449) (xy 417.768367 -277.773348) (xy 417.77641 -277.82413)
			(xy 417.776914 -277.849838) (xy 418.094172 -277.849838) (xy 418.098132 -277.800784) (xy 418.109909 -277.753)
			(xy 418.1292 -277.707724) (xy 418.155503 -277.666128) (xy 418.188138 -277.629291) (xy 418.226259 -277.598166)
			(xy 418.26888 -277.573559) (xy 418.314896 -277.556107) (xy 418.363115 -277.546263) (xy 418.41229 -277.544282)
			(xy 418.461145 -277.550214) (xy 418.508416 -277.563906) (xy 418.552878 -277.585004) (xy 418.593381 -277.61296)
			(xy 418.628874 -277.647052) (xy 418.658439 -277.686396) (xy 418.68131 -277.729973) (xy 418.696894 -277.776654)
			(xy 418.704789 -277.825231) (xy 418.705284 -277.849838) (xy 418.704789 -277.874445) (xy 418.70461 -277.875546)
			(xy 419.023034 -277.875546) (xy 419.023034 -277.82413) (xy 419.031077 -277.773348) (xy 419.046965 -277.724449)
			(xy 419.070308 -277.678637) (xy 419.100529 -277.637041) (xy 419.136885 -277.600685) (xy 419.178481 -277.570464)
			(xy 419.224293 -277.547121) (xy 419.273192 -277.531233) (xy 419.323974 -277.52319) (xy 419.37539 -277.52319)
			(xy 419.426172 -277.531233) (xy 419.475071 -277.547121) (xy 419.520883 -277.570464) (xy 419.562479 -277.600685)
			(xy 419.598835 -277.637041) (xy 419.629056 -277.678637) (xy 419.652399 -277.724449) (xy 419.668287 -277.773348)
			(xy 419.67633 -277.82413) (xy 419.676834 -277.849838) (xy 419.994092 -277.849838) (xy 419.998052 -277.800784)
			(xy 420.009829 -277.753) (xy 420.02912 -277.707724) (xy 420.055423 -277.666128) (xy 420.088058 -277.629291)
			(xy 420.126179 -277.598166) (xy 420.1688 -277.573559) (xy 420.214816 -277.556107) (xy 420.263035 -277.546263)
			(xy 420.31221 -277.544282) (xy 420.361065 -277.550214) (xy 420.408336 -277.563906) (xy 420.452798 -277.585004)
			(xy 420.493301 -277.61296) (xy 420.528794 -277.647052) (xy 420.558359 -277.686396) (xy 420.58123 -277.729973)
			(xy 420.596814 -277.776654) (xy 420.604709 -277.825231) (xy 420.605204 -277.849838) (xy 420.604709 -277.874445)
			(xy 420.60453 -277.875546) (xy 420.922954 -277.875546) (xy 420.922954 -277.82413) (xy 420.930997 -277.773348)
			(xy 420.946885 -277.724449) (xy 420.970228 -277.678637) (xy 421.000449 -277.637041) (xy 421.036805 -277.600685)
			(xy 421.078401 -277.570464) (xy 421.124213 -277.547121) (xy 421.173112 -277.531233) (xy 421.223894 -277.52319)
			(xy 421.27531 -277.52319) (xy 421.326092 -277.531233) (xy 421.374991 -277.547121) (xy 421.420803 -277.570464)
			(xy 421.462399 -277.600685) (xy 421.498755 -277.637041) (xy 421.528976 -277.678637) (xy 421.552319 -277.724449)
			(xy 421.568207 -277.773348) (xy 421.57625 -277.82413) (xy 421.576754 -277.849838) (xy 421.57625 -277.875546)
			(xy 421.568207 -277.926328) (xy 421.552319 -277.975227) (xy 421.528976 -278.021039) (xy 421.498755 -278.062635)
			(xy 421.462399 -278.098991) (xy 421.420803 -278.129212) (xy 421.374991 -278.152555) (xy 421.326092 -278.168443)
			(xy 421.27531 -278.176486) (xy 421.223894 -278.176486) (xy 421.173112 -278.168443) (xy 421.124213 -278.152555)
			(xy 421.078401 -278.129212) (xy 421.036805 -278.098991) (xy 421.000449 -278.062635) (xy 420.970228 -278.021039)
			(xy 420.946885 -277.975227) (xy 420.930997 -277.926328) (xy 420.922954 -277.875546) (xy 420.60453 -277.875546)
			(xy 420.596814 -277.923022) (xy 420.58123 -277.969703) (xy 420.558359 -278.01328) (xy 420.528794 -278.052624)
			(xy 420.493301 -278.086716) (xy 420.452798 -278.114672) (xy 420.408336 -278.13577) (xy 420.361065 -278.149462)
			(xy 420.31221 -278.155394) (xy 420.263035 -278.153413) (xy 420.214816 -278.143569) (xy 420.1688 -278.126117)
			(xy 420.126179 -278.10151) (xy 420.088058 -278.070385) (xy 420.055423 -278.033548) (xy 420.02912 -277.991952)
			(xy 420.009829 -277.946676) (xy 419.998052 -277.898892) (xy 419.994092 -277.849838) (xy 419.676834 -277.849838)
			(xy 419.67633 -277.875546) (xy 419.668287 -277.926328) (xy 419.652399 -277.975227) (xy 419.629056 -278.021039)
			(xy 419.598835 -278.062635) (xy 419.562479 -278.098991) (xy 419.520883 -278.129212) (xy 419.475071 -278.152555)
			(xy 419.426172 -278.168443) (xy 419.37539 -278.176486) (xy 419.323974 -278.176486) (xy 419.273192 -278.168443)
			(xy 419.224293 -278.152555) (xy 419.178481 -278.129212) (xy 419.136885 -278.098991) (xy 419.100529 -278.062635)
			(xy 419.070308 -278.021039) (xy 419.046965 -277.975227) (xy 419.031077 -277.926328) (xy 419.023034 -277.875546)
			(xy 418.70461 -277.875546) (xy 418.696894 -277.923022) (xy 418.68131 -277.969703) (xy 418.658439 -278.01328)
			(xy 418.628874 -278.052624) (xy 418.593381 -278.086716) (xy 418.552878 -278.114672) (xy 418.508416 -278.13577)
			(xy 418.461145 -278.149462) (xy 418.41229 -278.155394) (xy 418.363115 -278.153413) (xy 418.314896 -278.143569)
			(xy 418.26888 -278.126117) (xy 418.226259 -278.10151) (xy 418.188138 -278.070385) (xy 418.155503 -278.033548)
			(xy 418.1292 -277.991952) (xy 418.109909 -277.946676) (xy 418.098132 -277.898892) (xy 418.094172 -277.849838)
			(xy 417.776914 -277.849838) (xy 417.77641 -277.875546) (xy 417.768367 -277.926328) (xy 417.752479 -277.975227)
			(xy 417.729136 -278.021039) (xy 417.698915 -278.062635) (xy 417.662559 -278.098991) (xy 417.620963 -278.129212)
			(xy 417.575151 -278.152555) (xy 417.526252 -278.168443) (xy 417.47547 -278.176486) (xy 417.424054 -278.176486)
			(xy 417.373272 -278.168443) (xy 417.324373 -278.152555) (xy 417.278561 -278.129212) (xy 417.236965 -278.098991)
			(xy 417.200609 -278.062635) (xy 417.170388 -278.021039) (xy 417.147045 -277.975227) (xy 417.131157 -277.926328)
			(xy 417.123114 -277.875546) (xy 416.804436 -277.875546) (xy 416.79672 -277.923022) (xy 416.781136 -277.969703)
			(xy 416.758265 -278.01328) (xy 416.7287 -278.052624) (xy 416.693207 -278.086716) (xy 416.652704 -278.114672)
			(xy 416.608242 -278.13577) (xy 416.560971 -278.149462) (xy 416.512116 -278.155394) (xy 416.462941 -278.153413)
			(xy 416.414722 -278.143569) (xy 416.368706 -278.126117) (xy 416.326085 -278.10151) (xy 416.287964 -278.070385)
			(xy 416.255329 -278.033548) (xy 416.229026 -277.991952) (xy 416.209735 -277.946676) (xy 416.197958 -277.898892)
			(xy 416.193998 -277.849838) (xy 415.87674 -277.849838) (xy 415.876236 -277.875546) (xy 415.868193 -277.926328)
			(xy 415.852305 -277.975227) (xy 415.828962 -278.021039) (xy 415.798741 -278.062635) (xy 415.762385 -278.098991)
			(xy 415.720789 -278.129212) (xy 415.674977 -278.152555) (xy 415.626078 -278.168443) (xy 415.575296 -278.176486)
			(xy 415.52388 -278.176486) (xy 415.473098 -278.168443) (xy 415.424199 -278.152555) (xy 415.378387 -278.129212)
			(xy 415.336791 -278.098991) (xy 415.300435 -278.062635) (xy 415.270214 -278.021039) (xy 415.246871 -277.975227)
			(xy 415.230983 -277.926328) (xy 415.22294 -277.875546) (xy 414.904516 -277.875546) (xy 414.8968 -277.923022)
			(xy 414.881216 -277.969703) (xy 414.858345 -278.01328) (xy 414.82878 -278.052624) (xy 414.793287 -278.086716)
			(xy 414.752784 -278.114672) (xy 414.708322 -278.13577) (xy 414.661051 -278.149462) (xy 414.612196 -278.155394)
			(xy 414.563021 -278.153413) (xy 414.514802 -278.143569) (xy 414.468786 -278.126117) (xy 414.426165 -278.10151)
			(xy 414.388044 -278.070385) (xy 414.355409 -278.033548) (xy 414.329106 -277.991952) (xy 414.309815 -277.946676)
			(xy 414.298038 -277.898892) (xy 414.294078 -277.849838) (xy 413.97682 -277.849838) (xy 413.976316 -277.875546)
			(xy 413.968273 -277.926328) (xy 413.952385 -277.975227) (xy 413.929042 -278.021039) (xy 413.898821 -278.062635)
			(xy 413.862465 -278.098991) (xy 413.820869 -278.129212) (xy 413.775057 -278.152555) (xy 413.726158 -278.168443)
			(xy 413.675376 -278.176486) (xy 413.62396 -278.176486) (xy 413.573178 -278.168443) (xy 413.524279 -278.152555)
			(xy 413.478467 -278.129212) (xy 413.436871 -278.098991) (xy 413.400515 -278.062635) (xy 413.370294 -278.021039)
			(xy 413.346951 -277.975227) (xy 413.331063 -277.926328) (xy 413.32302 -277.875546) (xy 413.004596 -277.875546)
			(xy 412.99688 -277.923022) (xy 412.981296 -277.969703) (xy 412.958425 -278.01328) (xy 412.92886 -278.052624)
			(xy 412.893367 -278.086716) (xy 412.852864 -278.114672) (xy 412.808402 -278.13577) (xy 412.761131 -278.149462)
			(xy 412.712276 -278.155394) (xy 412.663101 -278.153413) (xy 412.614882 -278.143569) (xy 412.568866 -278.126117)
			(xy 412.526245 -278.10151) (xy 412.488124 -278.070385) (xy 412.455489 -278.033548) (xy 412.429186 -277.991952)
			(xy 412.409895 -277.946676) (xy 412.398118 -277.898892) (xy 412.394158 -277.849838) (xy 412.0769 -277.849838)
			(xy 412.076396 -277.875546) (xy 412.068353 -277.926328) (xy 412.052465 -277.975227) (xy 412.029122 -278.021039)
			(xy 411.998901 -278.062635) (xy 411.962545 -278.098991) (xy 411.920949 -278.129212) (xy 411.875137 -278.152555)
			(xy 411.826238 -278.168443) (xy 411.775456 -278.176486) (xy 411.72404 -278.176486) (xy 411.673258 -278.168443)
			(xy 411.624359 -278.152555) (xy 411.578547 -278.129212) (xy 411.536951 -278.098991) (xy 411.500595 -278.062635)
			(xy 411.470374 -278.021039) (xy 411.447031 -277.975227) (xy 411.431143 -277.926328) (xy 411.4231 -277.875546)
			(xy 411.104422 -277.875546) (xy 411.096706 -277.923022) (xy 411.081122 -277.969703) (xy 411.058251 -278.01328)
			(xy 411.028686 -278.052624) (xy 410.993193 -278.086716) (xy 410.95269 -278.114672) (xy 410.908228 -278.13577)
			(xy 410.860957 -278.149462) (xy 410.812102 -278.155394) (xy 410.762927 -278.153413) (xy 410.714708 -278.143569)
			(xy 410.668692 -278.126117) (xy 410.626071 -278.10151) (xy 410.58795 -278.070385) (xy 410.555315 -278.033548)
			(xy 410.529012 -277.991952) (xy 410.509721 -277.946676) (xy 410.497944 -277.898892) (xy 410.493984 -277.849838)
			(xy 410.176726 -277.849838) (xy 410.176222 -277.875546) (xy 410.168179 -277.926328) (xy 410.152291 -277.975227)
			(xy 410.128948 -278.021039) (xy 410.098727 -278.062635) (xy 410.062371 -278.098991) (xy 410.020775 -278.129212)
			(xy 409.974963 -278.152555) (xy 409.926064 -278.168443) (xy 409.875282 -278.176486) (xy 409.823866 -278.176486)
			(xy 409.773084 -278.168443) (xy 409.724185 -278.152555) (xy 409.678373 -278.129212) (xy 409.636777 -278.098991)
			(xy 409.600421 -278.062635) (xy 409.5702 -278.021039) (xy 409.546857 -277.975227) (xy 409.530969 -277.926328)
			(xy 409.522926 -277.875546) (xy 409.204502 -277.875546) (xy 409.196786 -277.923022) (xy 409.181202 -277.969703)
			(xy 409.158331 -278.01328) (xy 409.128766 -278.052624) (xy 409.093273 -278.086716) (xy 409.05277 -278.114672)
			(xy 409.008308 -278.13577) (xy 408.961037 -278.149462) (xy 408.912182 -278.155394) (xy 408.863007 -278.153413)
			(xy 408.814788 -278.143569) (xy 408.768772 -278.126117) (xy 408.726151 -278.10151) (xy 408.68803 -278.070385)
			(xy 408.655395 -278.033548) (xy 408.629092 -277.991952) (xy 408.609801 -277.946676) (xy 408.598024 -277.898892)
			(xy 408.594064 -277.849838) (xy 408.276806 -277.849838) (xy 408.276302 -277.875546) (xy 408.268259 -277.926328)
			(xy 408.252371 -277.975227) (xy 408.229028 -278.021039) (xy 408.198807 -278.062635) (xy 408.162451 -278.098991)
			(xy 408.120855 -278.129212) (xy 408.075043 -278.152555) (xy 408.026144 -278.168443) (xy 407.975362 -278.176486)
			(xy 407.923946 -278.176486) (xy 407.873164 -278.168443) (xy 407.824265 -278.152555) (xy 407.778453 -278.129212)
			(xy 407.736857 -278.098991) (xy 407.700501 -278.062635) (xy 407.67028 -278.021039) (xy 407.646937 -277.975227)
			(xy 407.631049 -277.926328) (xy 407.623006 -277.875546) (xy 407.304582 -277.875546) (xy 407.296866 -277.923022)
			(xy 407.281282 -277.969703) (xy 407.258411 -278.01328) (xy 407.228846 -278.052624) (xy 407.193353 -278.086716)
			(xy 407.15285 -278.114672) (xy 407.108388 -278.13577) (xy 407.061117 -278.149462) (xy 407.012262 -278.155394)
			(xy 406.963087 -278.153413) (xy 406.914868 -278.143569) (xy 406.868852 -278.126117) (xy 406.826231 -278.10151)
			(xy 406.78811 -278.070385) (xy 406.755475 -278.033548) (xy 406.729172 -277.991952) (xy 406.709881 -277.946676)
			(xy 406.698104 -277.898892) (xy 406.694144 -277.849838) (xy 406.37714 -277.849838) (xy 406.376636 -277.875546)
			(xy 406.368593 -277.926328) (xy 406.352705 -277.975227) (xy 406.329362 -278.021039) (xy 406.299141 -278.062635)
			(xy 406.262785 -278.098991) (xy 406.221189 -278.129212) (xy 406.175377 -278.152555) (xy 406.126478 -278.168443)
			(xy 406.075696 -278.176486) (xy 406.02428 -278.176486) (xy 405.973498 -278.168443) (xy 405.924599 -278.152555)
			(xy 405.878787 -278.129212) (xy 405.837191 -278.098991) (xy 405.800835 -278.062635) (xy 405.770614 -278.021039)
			(xy 405.747271 -277.975227) (xy 405.731383 -277.926328) (xy 405.72334 -277.875546) (xy 405.404662 -277.875546)
			(xy 405.396946 -277.923022) (xy 405.381362 -277.969703) (xy 405.358491 -278.01328) (xy 405.328926 -278.052624)
			(xy 405.293433 -278.086716) (xy 405.25293 -278.114672) (xy 405.208468 -278.13577) (xy 405.161197 -278.149462)
			(xy 405.112342 -278.155394) (xy 405.063167 -278.153413) (xy 405.014948 -278.143569) (xy 404.968932 -278.126117)
			(xy 404.926311 -278.10151) (xy 404.88819 -278.070385) (xy 404.855555 -278.033548) (xy 404.829252 -277.991952)
			(xy 404.809961 -277.946676) (xy 404.798184 -277.898892) (xy 404.794224 -277.849838) (xy 404.476966 -277.849838)
			(xy 404.476462 -277.875546) (xy 404.468419 -277.926328) (xy 404.452531 -277.975227) (xy 404.429188 -278.021039)
			(xy 404.398967 -278.062635) (xy 404.362611 -278.098991) (xy 404.321015 -278.129212) (xy 404.275203 -278.152555)
			(xy 404.226304 -278.168443) (xy 404.175522 -278.176486) (xy 404.124106 -278.176486) (xy 404.073324 -278.168443)
			(xy 404.024425 -278.152555) (xy 403.978613 -278.129212) (xy 403.937017 -278.098991) (xy 403.900661 -278.062635)
			(xy 403.87044 -278.021039) (xy 403.847097 -277.975227) (xy 403.831209 -277.926328) (xy 403.823166 -277.875546)
			(xy 403.504488 -277.875546) (xy 403.496772 -277.923022) (xy 403.481188 -277.969703) (xy 403.458317 -278.01328)
			(xy 403.428752 -278.052624) (xy 403.393259 -278.086716) (xy 403.352756 -278.114672) (xy 403.308294 -278.13577)
			(xy 403.261023 -278.149462) (xy 403.212168 -278.155394) (xy 403.162993 -278.153413) (xy 403.114774 -278.143569)
			(xy 403.068758 -278.126117) (xy 403.026137 -278.10151) (xy 402.988016 -278.070385) (xy 402.955381 -278.033548)
			(xy 402.929078 -277.991952) (xy 402.909787 -277.946676) (xy 402.89801 -277.898892) (xy 402.89405 -277.849838)
			(xy 402.577046 -277.849838) (xy 402.576542 -277.875546) (xy 402.568499 -277.926328) (xy 402.552611 -277.975227)
			(xy 402.529268 -278.021039) (xy 402.499047 -278.062635) (xy 402.462691 -278.098991) (xy 402.421095 -278.129212)
			(xy 402.375283 -278.152555) (xy 402.326384 -278.168443) (xy 402.275602 -278.176486) (xy 402.224186 -278.176486)
			(xy 402.173404 -278.168443) (xy 402.124505 -278.152555) (xy 402.078693 -278.129212) (xy 402.037097 -278.098991)
			(xy 402.000741 -278.062635) (xy 401.97052 -278.021039) (xy 401.947177 -277.975227) (xy 401.931289 -277.926328)
			(xy 401.923246 -277.875546) (xy 401.604568 -277.875546) (xy 401.596852 -277.923022) (xy 401.581268 -277.969703)
			(xy 401.558397 -278.01328) (xy 401.528832 -278.052624) (xy 401.493339 -278.086716) (xy 401.452836 -278.114672)
			(xy 401.408374 -278.13577) (xy 401.361103 -278.149462) (xy 401.312248 -278.155394) (xy 401.263073 -278.153413)
			(xy 401.214854 -278.143569) (xy 401.168838 -278.126117) (xy 401.126217 -278.10151) (xy 401.088096 -278.070385)
			(xy 401.055461 -278.033548) (xy 401.029158 -277.991952) (xy 401.009867 -277.946676) (xy 400.99809 -277.898892)
			(xy 400.99413 -277.849838) (xy 400.677126 -277.849838) (xy 400.676622 -277.875546) (xy 400.668579 -277.926328)
			(xy 400.652691 -277.975227) (xy 400.629348 -278.021039) (xy 400.599127 -278.062635) (xy 400.562771 -278.098991)
			(xy 400.521175 -278.129212) (xy 400.475363 -278.152555) (xy 400.426464 -278.168443) (xy 400.375682 -278.176486)
			(xy 400.324266 -278.176486) (xy 400.273484 -278.168443) (xy 400.224585 -278.152555) (xy 400.178773 -278.129212)
			(xy 400.137177 -278.098991) (xy 400.100821 -278.062635) (xy 400.0706 -278.021039) (xy 400.047257 -277.975227)
			(xy 400.031369 -277.926328) (xy 400.023326 -277.875546) (xy 399.704648 -277.875546) (xy 399.696932 -277.923022)
			(xy 399.681348 -277.969703) (xy 399.658477 -278.01328) (xy 399.628912 -278.052624) (xy 399.593419 -278.086716)
			(xy 399.552916 -278.114672) (xy 399.508454 -278.13577) (xy 399.461183 -278.149462) (xy 399.412328 -278.155394)
			(xy 399.363153 -278.153413) (xy 399.314934 -278.143569) (xy 399.268918 -278.126117) (xy 399.226297 -278.10151)
			(xy 399.188176 -278.070385) (xy 399.155541 -278.033548) (xy 399.129238 -277.991952) (xy 399.109947 -277.946676)
			(xy 399.09817 -277.898892) (xy 399.09421 -277.849838) (xy 398.776952 -277.849838) (xy 398.776448 -277.875546)
			(xy 398.768405 -277.926328) (xy 398.752517 -277.975227) (xy 398.729174 -278.021039) (xy 398.698953 -278.062635)
			(xy 398.662597 -278.098991) (xy 398.621001 -278.129212) (xy 398.575189 -278.152555) (xy 398.52629 -278.168443)
			(xy 398.475508 -278.176486) (xy 398.424092 -278.176486) (xy 398.37331 -278.168443) (xy 398.324411 -278.152555)
			(xy 398.278599 -278.129212) (xy 398.237003 -278.098991) (xy 398.200647 -278.062635) (xy 398.170426 -278.021039)
			(xy 398.147083 -277.975227) (xy 398.131195 -277.926328) (xy 398.123152 -277.875546) (xy 397.804474 -277.875546)
			(xy 397.796758 -277.923022) (xy 397.781174 -277.969703) (xy 397.758303 -278.01328) (xy 397.728738 -278.052624)
			(xy 397.693245 -278.086716) (xy 397.652742 -278.114672) (xy 397.60828 -278.13577) (xy 397.561009 -278.149462)
			(xy 397.512154 -278.155394) (xy 397.462979 -278.153413) (xy 397.41476 -278.143569) (xy 397.368744 -278.126117)
			(xy 397.326123 -278.10151) (xy 397.288002 -278.070385) (xy 397.255367 -278.033548) (xy 397.229064 -277.991952)
			(xy 397.209773 -277.946676) (xy 397.197996 -277.898892) (xy 397.194036 -277.849838) (xy 396.877032 -277.849838)
			(xy 396.876528 -277.875546) (xy 396.868485 -277.926328) (xy 396.852597 -277.975227) (xy 396.829254 -278.021039)
			(xy 396.799033 -278.062635) (xy 396.762677 -278.098991) (xy 396.721081 -278.129212) (xy 396.675269 -278.152555)
			(xy 396.62637 -278.168443) (xy 396.575588 -278.176486) (xy 396.524172 -278.176486) (xy 396.47339 -278.168443)
			(xy 396.424491 -278.152555) (xy 396.378679 -278.129212) (xy 396.337083 -278.098991) (xy 396.300727 -278.062635)
			(xy 396.270506 -278.021039) (xy 396.247163 -277.975227) (xy 396.231275 -277.926328) (xy 396.223232 -277.875546)
			(xy 395.904554 -277.875546) (xy 395.896838 -277.923022) (xy 395.881254 -277.969703) (xy 395.858383 -278.01328)
			(xy 395.828818 -278.052624) (xy 395.793325 -278.086716) (xy 395.752822 -278.114672) (xy 395.70836 -278.13577)
			(xy 395.661089 -278.149462) (xy 395.612234 -278.155394) (xy 395.563059 -278.153413) (xy 395.51484 -278.143569)
			(xy 395.468824 -278.126117) (xy 395.426203 -278.10151) (xy 395.388082 -278.070385) (xy 395.355447 -278.033548)
			(xy 395.329144 -277.991952) (xy 395.309853 -277.946676) (xy 395.298076 -277.898892) (xy 395.294116 -277.849838)
			(xy 394.977112 -277.849838) (xy 394.976608 -277.875546) (xy 394.968565 -277.926328) (xy 394.952677 -277.975227)
			(xy 394.929334 -278.021039) (xy 394.899113 -278.062635) (xy 394.862757 -278.098991) (xy 394.821161 -278.129212)
			(xy 394.775349 -278.152555) (xy 394.72645 -278.168443) (xy 394.675668 -278.176486) (xy 394.624252 -278.176486)
			(xy 394.57347 -278.168443) (xy 394.524571 -278.152555) (xy 394.478759 -278.129212) (xy 394.437163 -278.098991)
			(xy 394.400807 -278.062635) (xy 394.370586 -278.021039) (xy 394.347243 -277.975227) (xy 394.331355 -277.926328)
			(xy 394.323312 -277.875546) (xy 394.004634 -277.875546) (xy 393.996918 -277.923022) (xy 393.981334 -277.969703)
			(xy 393.958463 -278.01328) (xy 393.928898 -278.052624) (xy 393.893405 -278.086716) (xy 393.852902 -278.114672)
			(xy 393.80844 -278.13577) (xy 393.761169 -278.149462) (xy 393.712314 -278.155394) (xy 393.663139 -278.153413)
			(xy 393.61492 -278.143569) (xy 393.568904 -278.126117) (xy 393.526283 -278.10151) (xy 393.488162 -278.070385)
			(xy 393.455527 -278.033548) (xy 393.429224 -277.991952) (xy 393.409933 -277.946676) (xy 393.398156 -277.898892)
			(xy 393.394196 -277.849838) (xy 393.076938 -277.849838) (xy 393.076434 -277.875546) (xy 393.068391 -277.926328)
			(xy 393.052503 -277.975227) (xy 393.02916 -278.021039) (xy 392.998939 -278.062635) (xy 392.962583 -278.098991)
			(xy 392.920987 -278.129212) (xy 392.875175 -278.152555) (xy 392.826276 -278.168443) (xy 392.775494 -278.176486)
			(xy 392.724078 -278.176486) (xy 392.673296 -278.168443) (xy 392.624397 -278.152555) (xy 392.578585 -278.129212)
			(xy 392.536989 -278.098991) (xy 392.500633 -278.062635) (xy 392.470412 -278.021039) (xy 392.447069 -277.975227)
			(xy 392.431181 -277.926328) (xy 392.423138 -277.875546) (xy 383.78638 -277.875546) (xy 383.78638 -278.324818)
			(xy 384.369068 -278.324818) (xy 384.373028 -278.275764) (xy 384.384805 -278.22798) (xy 384.404096 -278.182704)
			(xy 384.430399 -278.141108) (xy 384.463034 -278.104271) (xy 384.501155 -278.073146) (xy 384.543776 -278.048539)
			(xy 384.589792 -278.031087) (xy 384.638011 -278.021243) (xy 384.687186 -278.019262) (xy 384.736041 -278.025194)
			(xy 384.783312 -278.038886) (xy 384.827774 -278.059984) (xy 384.868277 -278.08794) (xy 384.90377 -278.122032)
			(xy 384.933335 -278.161376) (xy 384.956206 -278.204953) (xy 384.97179 -278.251634) (xy 384.979685 -278.300211)
			(xy 384.98018 -278.324818) (xy 385.319028 -278.324818) (xy 385.322988 -278.275764) (xy 385.334765 -278.22798)
			(xy 385.354056 -278.182704) (xy 385.380359 -278.141108) (xy 385.412994 -278.104271) (xy 385.451115 -278.073146)
			(xy 385.493736 -278.048539) (xy 385.539752 -278.031087) (xy 385.587971 -278.021243) (xy 385.637146 -278.019262)
			(xy 385.686001 -278.025194) (xy 385.733272 -278.038886) (xy 385.777734 -278.059984) (xy 385.818237 -278.08794)
			(xy 385.85373 -278.122032) (xy 385.883295 -278.161376) (xy 385.906166 -278.204953) (xy 385.92175 -278.251634)
			(xy 385.929645 -278.300211) (xy 385.93014 -278.324818) (xy 386.269242 -278.324818) (xy 386.273202 -278.275764)
			(xy 386.284979 -278.22798) (xy 386.30427 -278.182704) (xy 386.330573 -278.141108) (xy 386.363208 -278.104271)
			(xy 386.401329 -278.073146) (xy 386.44395 -278.048539) (xy 386.489966 -278.031087) (xy 386.538185 -278.021243)
			(xy 386.58736 -278.019262) (xy 386.636215 -278.025194) (xy 386.683486 -278.038886) (xy 386.727948 -278.059984)
			(xy 386.768451 -278.08794) (xy 386.803944 -278.122032) (xy 386.833509 -278.161376) (xy 386.85638 -278.204953)
			(xy 386.871964 -278.251634) (xy 386.879859 -278.300211) (xy 386.880354 -278.324818) (xy 387.219202 -278.324818)
			(xy 387.223162 -278.275764) (xy 387.234939 -278.22798) (xy 387.25423 -278.182704) (xy 387.280533 -278.141108)
			(xy 387.313168 -278.104271) (xy 387.351289 -278.073146) (xy 387.39391 -278.048539) (xy 387.439926 -278.031087)
			(xy 387.488145 -278.021243) (xy 387.53732 -278.019262) (xy 387.586175 -278.025194) (xy 387.633446 -278.038886)
			(xy 387.677908 -278.059984) (xy 387.718411 -278.08794) (xy 387.753904 -278.122032) (xy 387.783469 -278.161376)
			(xy 387.80634 -278.204953) (xy 387.821924 -278.251634) (xy 387.829819 -278.300211) (xy 387.830314 -278.324818)
			(xy 388.169162 -278.324818) (xy 388.173122 -278.275764) (xy 388.184899 -278.22798) (xy 388.20419 -278.182704)
			(xy 388.230493 -278.141108) (xy 388.263128 -278.104271) (xy 388.301249 -278.073146) (xy 388.34387 -278.048539)
			(xy 388.389886 -278.031087) (xy 388.438105 -278.021243) (xy 388.48728 -278.019262) (xy 388.536135 -278.025194)
			(xy 388.583406 -278.038886) (xy 388.627868 -278.059984) (xy 388.668371 -278.08794) (xy 388.703864 -278.122032)
			(xy 388.733429 -278.161376) (xy 388.7563 -278.204953) (xy 388.771884 -278.251634) (xy 388.779779 -278.300211)
			(xy 388.780274 -278.324818) (xy 389.119122 -278.324818) (xy 389.123082 -278.275764) (xy 389.134859 -278.22798)
			(xy 389.15415 -278.182704) (xy 389.180453 -278.141108) (xy 389.213088 -278.104271) (xy 389.251209 -278.073146)
			(xy 389.29383 -278.048539) (xy 389.339846 -278.031087) (xy 389.388065 -278.021243) (xy 389.43724 -278.019262)
			(xy 389.486095 -278.025194) (xy 389.533366 -278.038886) (xy 389.577828 -278.059984) (xy 389.618331 -278.08794)
			(xy 389.653824 -278.122032) (xy 389.683389 -278.161376) (xy 389.70626 -278.204953) (xy 389.721844 -278.251634)
			(xy 389.729739 -278.300211) (xy 389.730234 -278.324818) (xy 390.069082 -278.324818) (xy 390.073042 -278.275764)
			(xy 390.084819 -278.22798) (xy 390.10411 -278.182704) (xy 390.130413 -278.141108) (xy 390.163048 -278.104271)
			(xy 390.201169 -278.073146) (xy 390.24379 -278.048539) (xy 390.289806 -278.031087) (xy 390.338025 -278.021243)
			(xy 390.3872 -278.019262) (xy 390.436055 -278.025194) (xy 390.483326 -278.038886) (xy 390.527788 -278.059984)
			(xy 390.568291 -278.08794) (xy 390.603784 -278.122032) (xy 390.633349 -278.161376) (xy 390.65622 -278.204953)
			(xy 390.671804 -278.251634) (xy 390.679699 -278.300211) (xy 390.680194 -278.324818) (xy 391.019042 -278.324818)
			(xy 391.023002 -278.275764) (xy 391.034779 -278.22798) (xy 391.05407 -278.182704) (xy 391.080373 -278.141108)
			(xy 391.113008 -278.104271) (xy 391.151129 -278.073146) (xy 391.19375 -278.048539) (xy 391.239766 -278.031087)
			(xy 391.287985 -278.021243) (xy 391.33716 -278.019262) (xy 391.386015 -278.025194) (xy 391.433286 -278.038886)
			(xy 391.477748 -278.059984) (xy 391.518251 -278.08794) (xy 391.553744 -278.122032) (xy 391.583309 -278.161376)
			(xy 391.60618 -278.204953) (xy 391.621764 -278.251634) (xy 391.629659 -278.300211) (xy 391.630154 -278.324818)
			(xy 391.629659 -278.349425) (xy 391.621764 -278.398002) (xy 391.60618 -278.444683) (xy 391.583309 -278.48826)
			(xy 391.553744 -278.527604) (xy 391.518251 -278.561696) (xy 391.477748 -278.589652) (xy 391.433286 -278.61075)
			(xy 391.386015 -278.624442) (xy 391.33716 -278.630374) (xy 391.287985 -278.628393) (xy 391.239766 -278.618549)
			(xy 391.19375 -278.601097) (xy 391.151129 -278.57649) (xy 391.113008 -278.545365) (xy 391.080373 -278.508528)
			(xy 391.05407 -278.466932) (xy 391.034779 -278.421656) (xy 391.023002 -278.373872) (xy 391.019042 -278.324818)
			(xy 390.680194 -278.324818) (xy 390.679699 -278.349425) (xy 390.671804 -278.398002) (xy 390.65622 -278.444683)
			(xy 390.633349 -278.48826) (xy 390.603784 -278.527604) (xy 390.568291 -278.561696) (xy 390.527788 -278.589652)
			(xy 390.483326 -278.61075) (xy 390.436055 -278.624442) (xy 390.3872 -278.630374) (xy 390.338025 -278.628393)
			(xy 390.289806 -278.618549) (xy 390.24379 -278.601097) (xy 390.201169 -278.57649) (xy 390.163048 -278.545365)
			(xy 390.130413 -278.508528) (xy 390.10411 -278.466932) (xy 390.084819 -278.421656) (xy 390.073042 -278.373872)
			(xy 390.069082 -278.324818) (xy 389.730234 -278.324818) (xy 389.729739 -278.349425) (xy 389.721844 -278.398002)
			(xy 389.70626 -278.444683) (xy 389.683389 -278.48826) (xy 389.653824 -278.527604) (xy 389.618331 -278.561696)
			(xy 389.577828 -278.589652) (xy 389.533366 -278.61075) (xy 389.486095 -278.624442) (xy 389.43724 -278.630374)
			(xy 389.388065 -278.628393) (xy 389.339846 -278.618549) (xy 389.29383 -278.601097) (xy 389.251209 -278.57649)
			(xy 389.213088 -278.545365) (xy 389.180453 -278.508528) (xy 389.15415 -278.466932) (xy 389.134859 -278.421656)
			(xy 389.123082 -278.373872) (xy 389.119122 -278.324818) (xy 388.780274 -278.324818) (xy 388.779779 -278.349425)
			(xy 388.771884 -278.398002) (xy 388.7563 -278.444683) (xy 388.733429 -278.48826) (xy 388.703864 -278.527604)
			(xy 388.668371 -278.561696) (xy 388.627868 -278.589652) (xy 388.583406 -278.61075) (xy 388.536135 -278.624442)
			(xy 388.48728 -278.630374) (xy 388.438105 -278.628393) (xy 388.389886 -278.618549) (xy 388.34387 -278.601097)
			(xy 388.301249 -278.57649) (xy 388.263128 -278.545365) (xy 388.230493 -278.508528) (xy 388.20419 -278.466932)
			(xy 388.184899 -278.421656) (xy 388.173122 -278.373872) (xy 388.169162 -278.324818) (xy 387.830314 -278.324818)
			(xy 387.829819 -278.349425) (xy 387.821924 -278.398002) (xy 387.80634 -278.444683) (xy 387.783469 -278.48826)
			(xy 387.753904 -278.527604) (xy 387.718411 -278.561696) (xy 387.677908 -278.589652) (xy 387.633446 -278.61075)
			(xy 387.586175 -278.624442) (xy 387.53732 -278.630374) (xy 387.488145 -278.628393) (xy 387.439926 -278.618549)
			(xy 387.39391 -278.601097) (xy 387.351289 -278.57649) (xy 387.313168 -278.545365) (xy 387.280533 -278.508528)
			(xy 387.25423 -278.466932) (xy 387.234939 -278.421656) (xy 387.223162 -278.373872) (xy 387.219202 -278.324818)
			(xy 386.880354 -278.324818) (xy 386.879859 -278.349425) (xy 386.871964 -278.398002) (xy 386.85638 -278.444683)
			(xy 386.833509 -278.48826) (xy 386.803944 -278.527604) (xy 386.768451 -278.561696) (xy 386.727948 -278.589652)
			(xy 386.683486 -278.61075) (xy 386.636215 -278.624442) (xy 386.58736 -278.630374) (xy 386.538185 -278.628393)
			(xy 386.489966 -278.618549) (xy 386.44395 -278.601097) (xy 386.401329 -278.57649) (xy 386.363208 -278.545365)
			(xy 386.330573 -278.508528) (xy 386.30427 -278.466932) (xy 386.284979 -278.421656) (xy 386.273202 -278.373872)
			(xy 386.269242 -278.324818) (xy 385.93014 -278.324818) (xy 385.929645 -278.349425) (xy 385.92175 -278.398002)
			(xy 385.906166 -278.444683) (xy 385.883295 -278.48826) (xy 385.85373 -278.527604) (xy 385.818237 -278.561696)
			(xy 385.777734 -278.589652) (xy 385.733272 -278.61075) (xy 385.686001 -278.624442) (xy 385.637146 -278.630374)
			(xy 385.587971 -278.628393) (xy 385.539752 -278.618549) (xy 385.493736 -278.601097) (xy 385.451115 -278.57649)
			(xy 385.412994 -278.545365) (xy 385.380359 -278.508528) (xy 385.354056 -278.466932) (xy 385.334765 -278.421656)
			(xy 385.322988 -278.373872) (xy 385.319028 -278.324818) (xy 384.98018 -278.324818) (xy 384.979685 -278.349425)
			(xy 384.97179 -278.398002) (xy 384.956206 -278.444683) (xy 384.933335 -278.48826) (xy 384.90377 -278.527604)
			(xy 384.868277 -278.561696) (xy 384.827774 -278.589652) (xy 384.783312 -278.61075) (xy 384.736041 -278.624442)
			(xy 384.687186 -278.630374) (xy 384.638011 -278.628393) (xy 384.589792 -278.618549) (xy 384.543776 -278.601097)
			(xy 384.501155 -278.57649) (xy 384.463034 -278.545365) (xy 384.430399 -278.508528) (xy 384.404096 -278.466932)
			(xy 384.384805 -278.421656) (xy 384.373028 -278.373872) (xy 384.369068 -278.324818) (xy 383.78638 -278.324818)
			(xy 383.78638 -279.274778) (xy 384.369068 -279.274778) (xy 384.373028 -279.225724) (xy 384.384805 -279.17794)
			(xy 384.404096 -279.132664) (xy 384.430399 -279.091068) (xy 384.463034 -279.054231) (xy 384.501155 -279.023106)
			(xy 384.543776 -278.998499) (xy 384.589792 -278.981047) (xy 384.638011 -278.971203) (xy 384.687186 -278.969222)
			(xy 384.736041 -278.975154) (xy 384.783312 -278.988846) (xy 384.827774 -279.009944) (xy 384.868277 -279.0379)
			(xy 384.90377 -279.071992) (xy 384.933335 -279.111336) (xy 384.956206 -279.154913) (xy 384.97179 -279.201594)
			(xy 384.979685 -279.250171) (xy 384.98018 -279.274778) (xy 385.319028 -279.274778) (xy 385.322988 -279.225724)
			(xy 385.334765 -279.17794) (xy 385.354056 -279.132664) (xy 385.380359 -279.091068) (xy 385.412994 -279.054231)
			(xy 385.451115 -279.023106) (xy 385.493736 -278.998499) (xy 385.539752 -278.981047) (xy 385.587971 -278.971203)
			(xy 385.637146 -278.969222) (xy 385.686001 -278.975154) (xy 385.733272 -278.988846) (xy 385.777734 -279.009944)
			(xy 385.818237 -279.0379) (xy 385.85373 -279.071992) (xy 385.883295 -279.111336) (xy 385.906166 -279.154913)
			(xy 385.92175 -279.201594) (xy 385.929645 -279.250171) (xy 385.93014 -279.274778) (xy 386.269242 -279.274778)
			(xy 386.273202 -279.225724) (xy 386.284979 -279.17794) (xy 386.30427 -279.132664) (xy 386.330573 -279.091068)
			(xy 386.363208 -279.054231) (xy 386.401329 -279.023106) (xy 386.44395 -278.998499) (xy 386.489966 -278.981047)
			(xy 386.538185 -278.971203) (xy 386.58736 -278.969222) (xy 386.636215 -278.975154) (xy 386.683486 -278.988846)
			(xy 386.727948 -279.009944) (xy 386.768451 -279.0379) (xy 386.803944 -279.071992) (xy 386.833509 -279.111336)
			(xy 386.85638 -279.154913) (xy 386.871964 -279.201594) (xy 386.879859 -279.250171) (xy 386.880354 -279.274778)
			(xy 387.219202 -279.274778) (xy 387.223162 -279.225724) (xy 387.234939 -279.17794) (xy 387.25423 -279.132664)
			(xy 387.280533 -279.091068) (xy 387.313168 -279.054231) (xy 387.351289 -279.023106) (xy 387.39391 -278.998499)
			(xy 387.439926 -278.981047) (xy 387.488145 -278.971203) (xy 387.53732 -278.969222) (xy 387.586175 -278.975154)
			(xy 387.633446 -278.988846) (xy 387.677908 -279.009944) (xy 387.718411 -279.0379) (xy 387.753904 -279.071992)
			(xy 387.783469 -279.111336) (xy 387.80634 -279.154913) (xy 387.821924 -279.201594) (xy 387.829819 -279.250171)
			(xy 387.830314 -279.274778) (xy 388.169162 -279.274778) (xy 388.173122 -279.225724) (xy 388.184899 -279.17794)
			(xy 388.20419 -279.132664) (xy 388.230493 -279.091068) (xy 388.263128 -279.054231) (xy 388.301249 -279.023106)
			(xy 388.34387 -278.998499) (xy 388.389886 -278.981047) (xy 388.438105 -278.971203) (xy 388.48728 -278.969222)
			(xy 388.536135 -278.975154) (xy 388.583406 -278.988846) (xy 388.627868 -279.009944) (xy 388.668371 -279.0379)
			(xy 388.703864 -279.071992) (xy 388.733429 -279.111336) (xy 388.7563 -279.154913) (xy 388.771884 -279.201594)
			(xy 388.779779 -279.250171) (xy 388.780274 -279.274778) (xy 389.119122 -279.274778) (xy 389.123082 -279.225724)
			(xy 389.134859 -279.17794) (xy 389.15415 -279.132664) (xy 389.180453 -279.091068) (xy 389.213088 -279.054231)
			(xy 389.251209 -279.023106) (xy 389.29383 -278.998499) (xy 389.339846 -278.981047) (xy 389.388065 -278.971203)
			(xy 389.43724 -278.969222) (xy 389.486095 -278.975154) (xy 389.533366 -278.988846) (xy 389.577828 -279.009944)
			(xy 389.618331 -279.0379) (xy 389.653824 -279.071992) (xy 389.683389 -279.111336) (xy 389.70626 -279.154913)
			(xy 389.721844 -279.201594) (xy 389.729739 -279.250171) (xy 389.730234 -279.274778) (xy 390.069082 -279.274778)
			(xy 390.073042 -279.225724) (xy 390.084819 -279.17794) (xy 390.10411 -279.132664) (xy 390.130413 -279.091068)
			(xy 390.163048 -279.054231) (xy 390.201169 -279.023106) (xy 390.24379 -278.998499) (xy 390.289806 -278.981047)
			(xy 390.338025 -278.971203) (xy 390.3872 -278.969222) (xy 390.436055 -278.975154) (xy 390.483326 -278.988846)
			(xy 390.527788 -279.009944) (xy 390.568291 -279.0379) (xy 390.603784 -279.071992) (xy 390.633349 -279.111336)
			(xy 390.65622 -279.154913) (xy 390.671804 -279.201594) (xy 390.679699 -279.250171) (xy 390.680194 -279.274778)
			(xy 391.019042 -279.274778) (xy 391.023002 -279.225724) (xy 391.034779 -279.17794) (xy 391.05407 -279.132664)
			(xy 391.080373 -279.091068) (xy 391.113008 -279.054231) (xy 391.151129 -279.023106) (xy 391.19375 -278.998499)
			(xy 391.239766 -278.981047) (xy 391.287985 -278.971203) (xy 391.33716 -278.969222) (xy 391.386015 -278.975154)
			(xy 391.433286 -278.988846) (xy 391.477748 -279.009944) (xy 391.518251 -279.0379) (xy 391.553744 -279.071992)
			(xy 391.583309 -279.111336) (xy 391.60618 -279.154913) (xy 391.621764 -279.201594) (xy 391.629659 -279.250171)
			(xy 391.630154 -279.274778) (xy 391.630154 -279.2748) (xy 391.968918 -279.2748) (xy 391.97309 -279.224453)
			(xy 391.985492 -279.175479) (xy 392.005786 -279.129215) (xy 392.033418 -279.086921) (xy 392.067634 -279.049753)
			(xy 392.107502 -279.018724) (xy 392.151933 -278.99468) (xy 392.199715 -278.978277) (xy 392.249546 -278.969962)
			(xy 392.274806 -278.96947) (xy 392.284677 -278.969542) (xy 392.304378 -278.970814) (xy 392.314176 -278.97201)
			(xy 392.326114 -278.973534) (xy 392.34872 -278.96566) (xy 392.42238 -278.889206) (xy 392.429238 -278.866346)
			(xy 392.42746 -278.854408) (xy 392.425303 -278.840859) (xy 392.423015 -278.813517) (xy 392.422888 -278.799798)
			(xy 392.423382 -278.774108) (xy 392.43142 -278.723361) (xy 392.447298 -278.674496) (xy 392.470624 -278.628717)
			(xy 392.500825 -278.58715) (xy 392.537156 -278.550819) (xy 392.578724 -278.52062) (xy 392.624504 -278.497295)
			(xy 392.673369 -278.481418) (xy 392.724116 -278.473381) (xy 392.775496 -278.473382) (xy 392.826243 -278.481421)
			(xy 392.875108 -278.497299) (xy 392.920887 -278.520626) (xy 392.962453 -278.550827) (xy 392.998783 -278.587159)
			(xy 393.028982 -278.628727) (xy 393.052307 -278.674507) (xy 393.068183 -278.723373) (xy 393.076219 -278.77412)
			(xy 393.076218 -278.799798) (xy 393.394196 -278.799798) (xy 393.398156 -278.750744) (xy 393.409933 -278.70296)
			(xy 393.429224 -278.657684) (xy 393.455527 -278.616088) (xy 393.488162 -278.579251) (xy 393.526283 -278.548126)
			(xy 393.568904 -278.523519) (xy 393.61492 -278.506067) (xy 393.663139 -278.496223) (xy 393.712314 -278.494242)
			(xy 393.761169 -278.500174) (xy 393.80844 -278.513866) (xy 393.852902 -278.534964) (xy 393.893405 -278.56292)
			(xy 393.928898 -278.597012) (xy 393.958463 -278.636356) (xy 393.981334 -278.679933) (xy 393.996918 -278.726614)
			(xy 394.004813 -278.775191) (xy 394.005308 -278.799798) (xy 394.004813 -278.824405) (xy 394.004634 -278.825506)
			(xy 394.323312 -278.825506) (xy 394.323312 -278.77409) (xy 394.331355 -278.723308) (xy 394.347243 -278.674409)
			(xy 394.370586 -278.628597) (xy 394.400807 -278.587001) (xy 394.437163 -278.550645) (xy 394.478759 -278.520424)
			(xy 394.524571 -278.497081) (xy 394.57347 -278.481193) (xy 394.624252 -278.47315) (xy 394.675668 -278.47315)
			(xy 394.72645 -278.481193) (xy 394.775349 -278.497081) (xy 394.821161 -278.520424) (xy 394.862757 -278.550645)
			(xy 394.899113 -278.587001) (xy 394.929334 -278.628597) (xy 394.952677 -278.674409) (xy 394.968565 -278.723308)
			(xy 394.976608 -278.77409) (xy 394.977112 -278.799798) (xy 395.294116 -278.799798) (xy 395.298076 -278.750744)
			(xy 395.309853 -278.70296) (xy 395.329144 -278.657684) (xy 395.355447 -278.616088) (xy 395.388082 -278.579251)
			(xy 395.426203 -278.548126) (xy 395.468824 -278.523519) (xy 395.51484 -278.506067) (xy 395.563059 -278.496223)
			(xy 395.612234 -278.494242) (xy 395.661089 -278.500174) (xy 395.70836 -278.513866) (xy 395.752822 -278.534964)
			(xy 395.793325 -278.56292) (xy 395.828818 -278.597012) (xy 395.858383 -278.636356) (xy 395.881254 -278.679933)
			(xy 395.896838 -278.726614) (xy 395.904733 -278.775191) (xy 395.905228 -278.799798) (xy 395.904733 -278.824405)
			(xy 395.904554 -278.825506) (xy 396.223232 -278.825506) (xy 396.223232 -278.77409) (xy 396.231275 -278.723308)
			(xy 396.247163 -278.674409) (xy 396.270506 -278.628597) (xy 396.300727 -278.587001) (xy 396.337083 -278.550645)
			(xy 396.378679 -278.520424) (xy 396.424491 -278.497081) (xy 396.47339 -278.481193) (xy 396.524172 -278.47315)
			(xy 396.575588 -278.47315) (xy 396.62637 -278.481193) (xy 396.675269 -278.497081) (xy 396.721081 -278.520424)
			(xy 396.762677 -278.550645) (xy 396.799033 -278.587001) (xy 396.829254 -278.628597) (xy 396.852597 -278.674409)
			(xy 396.868485 -278.723308) (xy 396.876528 -278.77409) (xy 396.877032 -278.799798) (xy 397.194036 -278.799798)
			(xy 397.197996 -278.750744) (xy 397.209773 -278.70296) (xy 397.229064 -278.657684) (xy 397.255367 -278.616088)
			(xy 397.288002 -278.579251) (xy 397.326123 -278.548126) (xy 397.368744 -278.523519) (xy 397.41476 -278.506067)
			(xy 397.462979 -278.496223) (xy 397.512154 -278.494242) (xy 397.561009 -278.500174) (xy 397.60828 -278.513866)
			(xy 397.652742 -278.534964) (xy 397.693245 -278.56292) (xy 397.728738 -278.597012) (xy 397.758303 -278.636356)
			(xy 397.781174 -278.679933) (xy 397.796758 -278.726614) (xy 397.804653 -278.775191) (xy 397.805148 -278.799798)
			(xy 397.804653 -278.824405) (xy 397.804474 -278.825506) (xy 398.123152 -278.825506) (xy 398.123152 -278.77409)
			(xy 398.131195 -278.723308) (xy 398.147083 -278.674409) (xy 398.170426 -278.628597) (xy 398.200647 -278.587001)
			(xy 398.237003 -278.550645) (xy 398.278599 -278.520424) (xy 398.324411 -278.497081) (xy 398.37331 -278.481193)
			(xy 398.424092 -278.47315) (xy 398.475508 -278.47315) (xy 398.52629 -278.481193) (xy 398.575189 -278.497081)
			(xy 398.621001 -278.520424) (xy 398.662597 -278.550645) (xy 398.698953 -278.587001) (xy 398.729174 -278.628597)
			(xy 398.752517 -278.674409) (xy 398.768405 -278.723308) (xy 398.776448 -278.77409) (xy 398.776952 -278.799798)
			(xy 399.09421 -278.799798) (xy 399.09817 -278.750744) (xy 399.109947 -278.70296) (xy 399.129238 -278.657684)
			(xy 399.155541 -278.616088) (xy 399.188176 -278.579251) (xy 399.226297 -278.548126) (xy 399.268918 -278.523519)
			(xy 399.314934 -278.506067) (xy 399.363153 -278.496223) (xy 399.412328 -278.494242) (xy 399.461183 -278.500174)
			(xy 399.508454 -278.513866) (xy 399.552916 -278.534964) (xy 399.593419 -278.56292) (xy 399.628912 -278.597012)
			(xy 399.658477 -278.636356) (xy 399.681348 -278.679933) (xy 399.696932 -278.726614) (xy 399.704827 -278.775191)
			(xy 399.705322 -278.799798) (xy 399.704827 -278.824405) (xy 399.704648 -278.825506) (xy 400.023326 -278.825506)
			(xy 400.023326 -278.77409) (xy 400.031369 -278.723308) (xy 400.047257 -278.674409) (xy 400.0706 -278.628597)
			(xy 400.100821 -278.587001) (xy 400.137177 -278.550645) (xy 400.178773 -278.520424) (xy 400.224585 -278.497081)
			(xy 400.273484 -278.481193) (xy 400.324266 -278.47315) (xy 400.375682 -278.47315) (xy 400.426464 -278.481193)
			(xy 400.475363 -278.497081) (xy 400.521175 -278.520424) (xy 400.562771 -278.550645) (xy 400.599127 -278.587001)
			(xy 400.629348 -278.628597) (xy 400.652691 -278.674409) (xy 400.668579 -278.723308) (xy 400.676622 -278.77409)
			(xy 400.677126 -278.799798) (xy 400.99413 -278.799798) (xy 400.99809 -278.750744) (xy 401.009867 -278.70296)
			(xy 401.029158 -278.657684) (xy 401.055461 -278.616088) (xy 401.088096 -278.579251) (xy 401.126217 -278.548126)
			(xy 401.168838 -278.523519) (xy 401.214854 -278.506067) (xy 401.263073 -278.496223) (xy 401.312248 -278.494242)
			(xy 401.361103 -278.500174) (xy 401.408374 -278.513866) (xy 401.452836 -278.534964) (xy 401.493339 -278.56292)
			(xy 401.528832 -278.597012) (xy 401.558397 -278.636356) (xy 401.581268 -278.679933) (xy 401.596852 -278.726614)
			(xy 401.604747 -278.775191) (xy 401.605242 -278.799798) (xy 401.604747 -278.824405) (xy 401.604568 -278.825506)
			(xy 401.923246 -278.825506) (xy 401.923246 -278.77409) (xy 401.931289 -278.723308) (xy 401.947177 -278.674409)
			(xy 401.97052 -278.628597) (xy 402.000741 -278.587001) (xy 402.037097 -278.550645) (xy 402.078693 -278.520424)
			(xy 402.124505 -278.497081) (xy 402.173404 -278.481193) (xy 402.224186 -278.47315) (xy 402.275602 -278.47315)
			(xy 402.326384 -278.481193) (xy 402.375283 -278.497081) (xy 402.421095 -278.520424) (xy 402.462691 -278.550645)
			(xy 402.499047 -278.587001) (xy 402.529268 -278.628597) (xy 402.552611 -278.674409) (xy 402.568499 -278.723308)
			(xy 402.576542 -278.77409) (xy 402.577046 -278.799798) (xy 402.89405 -278.799798) (xy 402.89801 -278.750744)
			(xy 402.909787 -278.70296) (xy 402.929078 -278.657684) (xy 402.955381 -278.616088) (xy 402.988016 -278.579251)
			(xy 403.026137 -278.548126) (xy 403.068758 -278.523519) (xy 403.114774 -278.506067) (xy 403.162993 -278.496223)
			(xy 403.212168 -278.494242) (xy 403.261023 -278.500174) (xy 403.308294 -278.513866) (xy 403.352756 -278.534964)
			(xy 403.393259 -278.56292) (xy 403.428752 -278.597012) (xy 403.458317 -278.636356) (xy 403.481188 -278.679933)
			(xy 403.496772 -278.726614) (xy 403.504667 -278.775191) (xy 403.505162 -278.799798) (xy 403.504667 -278.824405)
			(xy 403.504488 -278.825506) (xy 403.823166 -278.825506) (xy 403.823166 -278.77409) (xy 403.831209 -278.723308)
			(xy 403.847097 -278.674409) (xy 403.87044 -278.628597) (xy 403.900661 -278.587001) (xy 403.937017 -278.550645)
			(xy 403.978613 -278.520424) (xy 404.024425 -278.497081) (xy 404.073324 -278.481193) (xy 404.124106 -278.47315)
			(xy 404.175522 -278.47315) (xy 404.226304 -278.481193) (xy 404.275203 -278.497081) (xy 404.321015 -278.520424)
			(xy 404.362611 -278.550645) (xy 404.398967 -278.587001) (xy 404.429188 -278.628597) (xy 404.452531 -278.674409)
			(xy 404.468419 -278.723308) (xy 404.476462 -278.77409) (xy 404.476966 -278.799798) (xy 404.794224 -278.799798)
			(xy 404.798184 -278.750744) (xy 404.809961 -278.70296) (xy 404.829252 -278.657684) (xy 404.855555 -278.616088)
			(xy 404.88819 -278.579251) (xy 404.926311 -278.548126) (xy 404.968932 -278.523519) (xy 405.014948 -278.506067)
			(xy 405.063167 -278.496223) (xy 405.112342 -278.494242) (xy 405.161197 -278.500174) (xy 405.208468 -278.513866)
			(xy 405.25293 -278.534964) (xy 405.293433 -278.56292) (xy 405.328926 -278.597012) (xy 405.358491 -278.636356)
			(xy 405.381362 -278.679933) (xy 405.396946 -278.726614) (xy 405.404841 -278.775191) (xy 405.405336 -278.799798)
			(xy 405.404841 -278.824405) (xy 405.404662 -278.825506) (xy 405.72334 -278.825506) (xy 405.72334 -278.77409)
			(xy 405.731383 -278.723308) (xy 405.747271 -278.674409) (xy 405.770614 -278.628597) (xy 405.800835 -278.587001)
			(xy 405.837191 -278.550645) (xy 405.878787 -278.520424) (xy 405.924599 -278.497081) (xy 405.973498 -278.481193)
			(xy 406.02428 -278.47315) (xy 406.075696 -278.47315) (xy 406.126478 -278.481193) (xy 406.175377 -278.497081)
			(xy 406.221189 -278.520424) (xy 406.262785 -278.550645) (xy 406.299141 -278.587001) (xy 406.329362 -278.628597)
			(xy 406.352705 -278.674409) (xy 406.368593 -278.723308) (xy 406.376636 -278.77409) (xy 406.37714 -278.799798)
			(xy 406.694144 -278.799798) (xy 406.698104 -278.750744) (xy 406.709881 -278.70296) (xy 406.729172 -278.657684)
			(xy 406.755475 -278.616088) (xy 406.78811 -278.579251) (xy 406.826231 -278.548126) (xy 406.868852 -278.523519)
			(xy 406.914868 -278.506067) (xy 406.963087 -278.496223) (xy 407.012262 -278.494242) (xy 407.061117 -278.500174)
			(xy 407.108388 -278.513866) (xy 407.15285 -278.534964) (xy 407.193353 -278.56292) (xy 407.228846 -278.597012)
			(xy 407.258411 -278.636356) (xy 407.281282 -278.679933) (xy 407.296866 -278.726614) (xy 407.304761 -278.775191)
			(xy 407.305256 -278.799798) (xy 407.304761 -278.824405) (xy 407.304582 -278.825506) (xy 407.623006 -278.825506)
			(xy 407.623006 -278.77409) (xy 407.631049 -278.723308) (xy 407.646937 -278.674409) (xy 407.67028 -278.628597)
			(xy 407.700501 -278.587001) (xy 407.736857 -278.550645) (xy 407.778453 -278.520424) (xy 407.824265 -278.497081)
			(xy 407.873164 -278.481193) (xy 407.923946 -278.47315) (xy 407.975362 -278.47315) (xy 408.026144 -278.481193)
			(xy 408.075043 -278.497081) (xy 408.120855 -278.520424) (xy 408.162451 -278.550645) (xy 408.198807 -278.587001)
			(xy 408.229028 -278.628597) (xy 408.252371 -278.674409) (xy 408.268259 -278.723308) (xy 408.276302 -278.77409)
			(xy 408.276806 -278.799798) (xy 408.594064 -278.799798) (xy 408.598024 -278.750744) (xy 408.609801 -278.70296)
			(xy 408.629092 -278.657684) (xy 408.655395 -278.616088) (xy 408.68803 -278.579251) (xy 408.726151 -278.548126)
			(xy 408.768772 -278.523519) (xy 408.814788 -278.506067) (xy 408.863007 -278.496223) (xy 408.912182 -278.494242)
			(xy 408.961037 -278.500174) (xy 409.008308 -278.513866) (xy 409.05277 -278.534964) (xy 409.093273 -278.56292)
			(xy 409.128766 -278.597012) (xy 409.158331 -278.636356) (xy 409.181202 -278.679933) (xy 409.196786 -278.726614)
			(xy 409.204681 -278.775191) (xy 409.205176 -278.799798) (xy 409.204681 -278.824405) (xy 409.204502 -278.825506)
			(xy 409.522926 -278.825506) (xy 409.522926 -278.77409) (xy 409.530969 -278.723308) (xy 409.546857 -278.674409)
			(xy 409.5702 -278.628597) (xy 409.600421 -278.587001) (xy 409.636777 -278.550645) (xy 409.678373 -278.520424)
			(xy 409.724185 -278.497081) (xy 409.773084 -278.481193) (xy 409.823866 -278.47315) (xy 409.875282 -278.47315)
			(xy 409.926064 -278.481193) (xy 409.974963 -278.497081) (xy 410.020775 -278.520424) (xy 410.062371 -278.550645)
			(xy 410.098727 -278.587001) (xy 410.128948 -278.628597) (xy 410.152291 -278.674409) (xy 410.168179 -278.723308)
			(xy 410.176222 -278.77409) (xy 410.176726 -278.799798) (xy 410.493984 -278.799798) (xy 410.497944 -278.750744)
			(xy 410.509721 -278.70296) (xy 410.529012 -278.657684) (xy 410.555315 -278.616088) (xy 410.58795 -278.579251)
			(xy 410.626071 -278.548126) (xy 410.668692 -278.523519) (xy 410.714708 -278.506067) (xy 410.762927 -278.496223)
			(xy 410.812102 -278.494242) (xy 410.860957 -278.500174) (xy 410.908228 -278.513866) (xy 410.95269 -278.534964)
			(xy 410.993193 -278.56292) (xy 411.028686 -278.597012) (xy 411.058251 -278.636356) (xy 411.081122 -278.679933)
			(xy 411.096706 -278.726614) (xy 411.104601 -278.775191) (xy 411.105096 -278.799798) (xy 411.104601 -278.824405)
			(xy 411.104422 -278.825506) (xy 411.4231 -278.825506) (xy 411.4231 -278.77409) (xy 411.431143 -278.723308)
			(xy 411.447031 -278.674409) (xy 411.470374 -278.628597) (xy 411.500595 -278.587001) (xy 411.536951 -278.550645)
			(xy 411.578547 -278.520424) (xy 411.624359 -278.497081) (xy 411.673258 -278.481193) (xy 411.72404 -278.47315)
			(xy 411.775456 -278.47315) (xy 411.826238 -278.481193) (xy 411.875137 -278.497081) (xy 411.920949 -278.520424)
			(xy 411.962545 -278.550645) (xy 411.998901 -278.587001) (xy 412.029122 -278.628597) (xy 412.052465 -278.674409)
			(xy 412.068353 -278.723308) (xy 412.076396 -278.77409) (xy 412.0769 -278.799798) (xy 412.394158 -278.799798)
			(xy 412.398118 -278.750744) (xy 412.409895 -278.70296) (xy 412.429186 -278.657684) (xy 412.455489 -278.616088)
			(xy 412.488124 -278.579251) (xy 412.526245 -278.548126) (xy 412.568866 -278.523519) (xy 412.614882 -278.506067)
			(xy 412.663101 -278.496223) (xy 412.712276 -278.494242) (xy 412.761131 -278.500174) (xy 412.808402 -278.513866)
			(xy 412.852864 -278.534964) (xy 412.893367 -278.56292) (xy 412.92886 -278.597012) (xy 412.958425 -278.636356)
			(xy 412.981296 -278.679933) (xy 412.99688 -278.726614) (xy 413.004775 -278.775191) (xy 413.00527 -278.799798)
			(xy 413.004775 -278.824405) (xy 413.004596 -278.825506) (xy 413.32302 -278.825506) (xy 413.32302 -278.77409)
			(xy 413.331063 -278.723308) (xy 413.346951 -278.674409) (xy 413.370294 -278.628597) (xy 413.400515 -278.587001)
			(xy 413.436871 -278.550645) (xy 413.478467 -278.520424) (xy 413.524279 -278.497081) (xy 413.573178 -278.481193)
			(xy 413.62396 -278.47315) (xy 413.675376 -278.47315) (xy 413.726158 -278.481193) (xy 413.775057 -278.497081)
			(xy 413.820869 -278.520424) (xy 413.862465 -278.550645) (xy 413.898821 -278.587001) (xy 413.929042 -278.628597)
			(xy 413.952385 -278.674409) (xy 413.968273 -278.723308) (xy 413.976316 -278.77409) (xy 413.97682 -278.799798)
			(xy 414.294078 -278.799798) (xy 414.298038 -278.750744) (xy 414.309815 -278.70296) (xy 414.329106 -278.657684)
			(xy 414.355409 -278.616088) (xy 414.388044 -278.579251) (xy 414.426165 -278.548126) (xy 414.468786 -278.523519)
			(xy 414.514802 -278.506067) (xy 414.563021 -278.496223) (xy 414.612196 -278.494242) (xy 414.661051 -278.500174)
			(xy 414.708322 -278.513866) (xy 414.752784 -278.534964) (xy 414.793287 -278.56292) (xy 414.82878 -278.597012)
			(xy 414.858345 -278.636356) (xy 414.881216 -278.679933) (xy 414.8968 -278.726614) (xy 414.904695 -278.775191)
			(xy 414.90519 -278.799798) (xy 414.904695 -278.824405) (xy 414.904516 -278.825506) (xy 415.22294 -278.825506)
			(xy 415.22294 -278.77409) (xy 415.230983 -278.723308) (xy 415.246871 -278.674409) (xy 415.270214 -278.628597)
			(xy 415.300435 -278.587001) (xy 415.336791 -278.550645) (xy 415.378387 -278.520424) (xy 415.424199 -278.497081)
			(xy 415.473098 -278.481193) (xy 415.52388 -278.47315) (xy 415.575296 -278.47315) (xy 415.626078 -278.481193)
			(xy 415.674977 -278.497081) (xy 415.720789 -278.520424) (xy 415.762385 -278.550645) (xy 415.798741 -278.587001)
			(xy 415.828962 -278.628597) (xy 415.852305 -278.674409) (xy 415.868193 -278.723308) (xy 415.876236 -278.77409)
			(xy 415.87674 -278.799798) (xy 416.193998 -278.799798) (xy 416.197958 -278.750744) (xy 416.209735 -278.70296)
			(xy 416.229026 -278.657684) (xy 416.255329 -278.616088) (xy 416.287964 -278.579251) (xy 416.326085 -278.548126)
			(xy 416.368706 -278.523519) (xy 416.414722 -278.506067) (xy 416.462941 -278.496223) (xy 416.512116 -278.494242)
			(xy 416.560971 -278.500174) (xy 416.608242 -278.513866) (xy 416.652704 -278.534964) (xy 416.693207 -278.56292)
			(xy 416.7287 -278.597012) (xy 416.758265 -278.636356) (xy 416.781136 -278.679933) (xy 416.79672 -278.726614)
			(xy 416.804615 -278.775191) (xy 416.80511 -278.799798) (xy 416.804615 -278.824405) (xy 416.804436 -278.825506)
			(xy 417.123114 -278.825506) (xy 417.123114 -278.77409) (xy 417.131157 -278.723308) (xy 417.147045 -278.674409)
			(xy 417.170388 -278.628597) (xy 417.200609 -278.587001) (xy 417.236965 -278.550645) (xy 417.278561 -278.520424)
			(xy 417.324373 -278.497081) (xy 417.373272 -278.481193) (xy 417.424054 -278.47315) (xy 417.47547 -278.47315)
			(xy 417.526252 -278.481193) (xy 417.575151 -278.497081) (xy 417.620963 -278.520424) (xy 417.662559 -278.550645)
			(xy 417.698915 -278.587001) (xy 417.729136 -278.628597) (xy 417.752479 -278.674409) (xy 417.768367 -278.723308)
			(xy 417.77641 -278.77409) (xy 417.776914 -278.799798) (xy 418.094172 -278.799798) (xy 418.098132 -278.750744)
			(xy 418.109909 -278.70296) (xy 418.1292 -278.657684) (xy 418.155503 -278.616088) (xy 418.188138 -278.579251)
			(xy 418.226259 -278.548126) (xy 418.26888 -278.523519) (xy 418.314896 -278.506067) (xy 418.363115 -278.496223)
			(xy 418.41229 -278.494242) (xy 418.461145 -278.500174) (xy 418.508416 -278.513866) (xy 418.552878 -278.534964)
			(xy 418.593381 -278.56292) (xy 418.628874 -278.597012) (xy 418.658439 -278.636356) (xy 418.68131 -278.679933)
			(xy 418.696894 -278.726614) (xy 418.704789 -278.775191) (xy 418.705284 -278.799798) (xy 418.704789 -278.824405)
			(xy 418.70461 -278.825506) (xy 419.023034 -278.825506) (xy 419.023034 -278.77409) (xy 419.031077 -278.723308)
			(xy 419.046965 -278.674409) (xy 419.070308 -278.628597) (xy 419.100529 -278.587001) (xy 419.136885 -278.550645)
			(xy 419.178481 -278.520424) (xy 419.224293 -278.497081) (xy 419.273192 -278.481193) (xy 419.323974 -278.47315)
			(xy 419.37539 -278.47315) (xy 419.426172 -278.481193) (xy 419.475071 -278.497081) (xy 419.520883 -278.520424)
			(xy 419.562479 -278.550645) (xy 419.598835 -278.587001) (xy 419.629056 -278.628597) (xy 419.652399 -278.674409)
			(xy 419.668287 -278.723308) (xy 419.67633 -278.77409) (xy 419.676834 -278.799798) (xy 419.994092 -278.799798)
			(xy 419.998052 -278.750744) (xy 420.009829 -278.70296) (xy 420.02912 -278.657684) (xy 420.055423 -278.616088)
			(xy 420.088058 -278.579251) (xy 420.126179 -278.548126) (xy 420.1688 -278.523519) (xy 420.214816 -278.506067)
			(xy 420.263035 -278.496223) (xy 420.31221 -278.494242) (xy 420.361065 -278.500174) (xy 420.408336 -278.513866)
			(xy 420.452798 -278.534964) (xy 420.493301 -278.56292) (xy 420.528794 -278.597012) (xy 420.558359 -278.636356)
			(xy 420.58123 -278.679933) (xy 420.596814 -278.726614) (xy 420.604709 -278.775191) (xy 420.605204 -278.799798)
			(xy 420.604709 -278.824405) (xy 420.60453 -278.825506) (xy 420.922954 -278.825506) (xy 420.922954 -278.77409)
			(xy 420.930997 -278.723308) (xy 420.946885 -278.674409) (xy 420.970228 -278.628597) (xy 421.000449 -278.587001)
			(xy 421.036805 -278.550645) (xy 421.078401 -278.520424) (xy 421.124213 -278.497081) (xy 421.173112 -278.481193)
			(xy 421.223894 -278.47315) (xy 421.27531 -278.47315) (xy 421.326092 -278.481193) (xy 421.374991 -278.497081)
			(xy 421.420803 -278.520424) (xy 421.462399 -278.550645) (xy 421.498755 -278.587001) (xy 421.528976 -278.628597)
			(xy 421.552319 -278.674409) (xy 421.568207 -278.723308) (xy 421.57625 -278.77409) (xy 421.576754 -278.799798)
			(xy 421.57625 -278.825506) (xy 421.568207 -278.876288) (xy 421.552319 -278.925187) (xy 421.528976 -278.970999)
			(xy 421.498755 -279.012595) (xy 421.462399 -279.048951) (xy 421.420803 -279.079172) (xy 421.374991 -279.102515)
			(xy 421.326092 -279.118403) (xy 421.27531 -279.126446) (xy 421.223894 -279.126446) (xy 421.173112 -279.118403)
			(xy 421.124213 -279.102515) (xy 421.078401 -279.079172) (xy 421.036805 -279.048951) (xy 421.000449 -279.012595)
			(xy 420.970228 -278.970999) (xy 420.946885 -278.925187) (xy 420.930997 -278.876288) (xy 420.922954 -278.825506)
			(xy 420.60453 -278.825506) (xy 420.596814 -278.872982) (xy 420.58123 -278.919663) (xy 420.558359 -278.96324)
			(xy 420.528794 -279.002584) (xy 420.493301 -279.036676) (xy 420.452798 -279.064632) (xy 420.408336 -279.08573)
			(xy 420.361065 -279.099422) (xy 420.31221 -279.105354) (xy 420.263035 -279.103373) (xy 420.214816 -279.093529)
			(xy 420.1688 -279.076077) (xy 420.126179 -279.05147) (xy 420.088058 -279.020345) (xy 420.055423 -278.983508)
			(xy 420.02912 -278.941912) (xy 420.009829 -278.896636) (xy 419.998052 -278.848852) (xy 419.994092 -278.799798)
			(xy 419.676834 -278.799798) (xy 419.67633 -278.825506) (xy 419.668287 -278.876288) (xy 419.652399 -278.925187)
			(xy 419.629056 -278.970999) (xy 419.598835 -279.012595) (xy 419.562479 -279.048951) (xy 419.520883 -279.079172)
			(xy 419.475071 -279.102515) (xy 419.426172 -279.118403) (xy 419.37539 -279.126446) (xy 419.323974 -279.126446)
			(xy 419.273192 -279.118403) (xy 419.224293 -279.102515) (xy 419.178481 -279.079172) (xy 419.136885 -279.048951)
			(xy 419.100529 -279.012595) (xy 419.070308 -278.970999) (xy 419.046965 -278.925187) (xy 419.031077 -278.876288)
			(xy 419.023034 -278.825506) (xy 418.70461 -278.825506) (xy 418.696894 -278.872982) (xy 418.68131 -278.919663)
			(xy 418.658439 -278.96324) (xy 418.628874 -279.002584) (xy 418.593381 -279.036676) (xy 418.552878 -279.064632)
			(xy 418.508416 -279.08573) (xy 418.461145 -279.099422) (xy 418.41229 -279.105354) (xy 418.363115 -279.103373)
			(xy 418.314896 -279.093529) (xy 418.26888 -279.076077) (xy 418.226259 -279.05147) (xy 418.188138 -279.020345)
			(xy 418.155503 -278.983508) (xy 418.1292 -278.941912) (xy 418.109909 -278.896636) (xy 418.098132 -278.848852)
			(xy 418.094172 -278.799798) (xy 417.776914 -278.799798) (xy 417.77641 -278.825506) (xy 417.768367 -278.876288)
			(xy 417.752479 -278.925187) (xy 417.729136 -278.970999) (xy 417.698915 -279.012595) (xy 417.662559 -279.048951)
			(xy 417.620963 -279.079172) (xy 417.575151 -279.102515) (xy 417.526252 -279.118403) (xy 417.47547 -279.126446)
			(xy 417.424054 -279.126446) (xy 417.373272 -279.118403) (xy 417.324373 -279.102515) (xy 417.278561 -279.079172)
			(xy 417.236965 -279.048951) (xy 417.200609 -279.012595) (xy 417.170388 -278.970999) (xy 417.147045 -278.925187)
			(xy 417.131157 -278.876288) (xy 417.123114 -278.825506) (xy 416.804436 -278.825506) (xy 416.79672 -278.872982)
			(xy 416.781136 -278.919663) (xy 416.758265 -278.96324) (xy 416.7287 -279.002584) (xy 416.693207 -279.036676)
			(xy 416.652704 -279.064632) (xy 416.608242 -279.08573) (xy 416.560971 -279.099422) (xy 416.512116 -279.105354)
			(xy 416.462941 -279.103373) (xy 416.414722 -279.093529) (xy 416.368706 -279.076077) (xy 416.326085 -279.05147)
			(xy 416.287964 -279.020345) (xy 416.255329 -278.983508) (xy 416.229026 -278.941912) (xy 416.209735 -278.896636)
			(xy 416.197958 -278.848852) (xy 416.193998 -278.799798) (xy 415.87674 -278.799798) (xy 415.876236 -278.825506)
			(xy 415.868193 -278.876288) (xy 415.852305 -278.925187) (xy 415.828962 -278.970999) (xy 415.798741 -279.012595)
			(xy 415.762385 -279.048951) (xy 415.720789 -279.079172) (xy 415.674977 -279.102515) (xy 415.626078 -279.118403)
			(xy 415.575296 -279.126446) (xy 415.52388 -279.126446) (xy 415.473098 -279.118403) (xy 415.424199 -279.102515)
			(xy 415.378387 -279.079172) (xy 415.336791 -279.048951) (xy 415.300435 -279.012595) (xy 415.270214 -278.970999)
			(xy 415.246871 -278.925187) (xy 415.230983 -278.876288) (xy 415.22294 -278.825506) (xy 414.904516 -278.825506)
			(xy 414.8968 -278.872982) (xy 414.881216 -278.919663) (xy 414.858345 -278.96324) (xy 414.82878 -279.002584)
			(xy 414.793287 -279.036676) (xy 414.752784 -279.064632) (xy 414.708322 -279.08573) (xy 414.661051 -279.099422)
			(xy 414.612196 -279.105354) (xy 414.563021 -279.103373) (xy 414.514802 -279.093529) (xy 414.468786 -279.076077)
			(xy 414.426165 -279.05147) (xy 414.388044 -279.020345) (xy 414.355409 -278.983508) (xy 414.329106 -278.941912)
			(xy 414.309815 -278.896636) (xy 414.298038 -278.848852) (xy 414.294078 -278.799798) (xy 413.97682 -278.799798)
			(xy 413.976316 -278.825506) (xy 413.968273 -278.876288) (xy 413.952385 -278.925187) (xy 413.929042 -278.970999)
			(xy 413.898821 -279.012595) (xy 413.862465 -279.048951) (xy 413.820869 -279.079172) (xy 413.775057 -279.102515)
			(xy 413.726158 -279.118403) (xy 413.675376 -279.126446) (xy 413.62396 -279.126446) (xy 413.573178 -279.118403)
			(xy 413.524279 -279.102515) (xy 413.478467 -279.079172) (xy 413.436871 -279.048951) (xy 413.400515 -279.012595)
			(xy 413.370294 -278.970999) (xy 413.346951 -278.925187) (xy 413.331063 -278.876288) (xy 413.32302 -278.825506)
			(xy 413.004596 -278.825506) (xy 412.99688 -278.872982) (xy 412.981296 -278.919663) (xy 412.958425 -278.96324)
			(xy 412.92886 -279.002584) (xy 412.893367 -279.036676) (xy 412.852864 -279.064632) (xy 412.808402 -279.08573)
			(xy 412.761131 -279.099422) (xy 412.712276 -279.105354) (xy 412.663101 -279.103373) (xy 412.614882 -279.093529)
			(xy 412.568866 -279.076077) (xy 412.526245 -279.05147) (xy 412.488124 -279.020345) (xy 412.455489 -278.983508)
			(xy 412.429186 -278.941912) (xy 412.409895 -278.896636) (xy 412.398118 -278.848852) (xy 412.394158 -278.799798)
			(xy 412.0769 -278.799798) (xy 412.076396 -278.825506) (xy 412.068353 -278.876288) (xy 412.052465 -278.925187)
			(xy 412.029122 -278.970999) (xy 411.998901 -279.012595) (xy 411.962545 -279.048951) (xy 411.920949 -279.079172)
			(xy 411.875137 -279.102515) (xy 411.826238 -279.118403) (xy 411.775456 -279.126446) (xy 411.72404 -279.126446)
			(xy 411.673258 -279.118403) (xy 411.624359 -279.102515) (xy 411.578547 -279.079172) (xy 411.536951 -279.048951)
			(xy 411.500595 -279.012595) (xy 411.470374 -278.970999) (xy 411.447031 -278.925187) (xy 411.431143 -278.876288)
			(xy 411.4231 -278.825506) (xy 411.104422 -278.825506) (xy 411.096706 -278.872982) (xy 411.081122 -278.919663)
			(xy 411.058251 -278.96324) (xy 411.028686 -279.002584) (xy 410.993193 -279.036676) (xy 410.95269 -279.064632)
			(xy 410.908228 -279.08573) (xy 410.860957 -279.099422) (xy 410.812102 -279.105354) (xy 410.762927 -279.103373)
			(xy 410.714708 -279.093529) (xy 410.668692 -279.076077) (xy 410.626071 -279.05147) (xy 410.58795 -279.020345)
			(xy 410.555315 -278.983508) (xy 410.529012 -278.941912) (xy 410.509721 -278.896636) (xy 410.497944 -278.848852)
			(xy 410.493984 -278.799798) (xy 410.176726 -278.799798) (xy 410.176222 -278.825506) (xy 410.168179 -278.876288)
			(xy 410.152291 -278.925187) (xy 410.128948 -278.970999) (xy 410.098727 -279.012595) (xy 410.062371 -279.048951)
			(xy 410.020775 -279.079172) (xy 409.974963 -279.102515) (xy 409.926064 -279.118403) (xy 409.875282 -279.126446)
			(xy 409.823866 -279.126446) (xy 409.773084 -279.118403) (xy 409.724185 -279.102515) (xy 409.678373 -279.079172)
			(xy 409.636777 -279.048951) (xy 409.600421 -279.012595) (xy 409.5702 -278.970999) (xy 409.546857 -278.925187)
			(xy 409.530969 -278.876288) (xy 409.522926 -278.825506) (xy 409.204502 -278.825506) (xy 409.196786 -278.872982)
			(xy 409.181202 -278.919663) (xy 409.158331 -278.96324) (xy 409.128766 -279.002584) (xy 409.093273 -279.036676)
			(xy 409.05277 -279.064632) (xy 409.008308 -279.08573) (xy 408.961037 -279.099422) (xy 408.912182 -279.105354)
			(xy 408.863007 -279.103373) (xy 408.814788 -279.093529) (xy 408.768772 -279.076077) (xy 408.726151 -279.05147)
			(xy 408.68803 -279.020345) (xy 408.655395 -278.983508) (xy 408.629092 -278.941912) (xy 408.609801 -278.896636)
			(xy 408.598024 -278.848852) (xy 408.594064 -278.799798) (xy 408.276806 -278.799798) (xy 408.276302 -278.825506)
			(xy 408.268259 -278.876288) (xy 408.252371 -278.925187) (xy 408.229028 -278.970999) (xy 408.198807 -279.012595)
			(xy 408.162451 -279.048951) (xy 408.120855 -279.079172) (xy 408.075043 -279.102515) (xy 408.026144 -279.118403)
			(xy 407.975362 -279.126446) (xy 407.923946 -279.126446) (xy 407.873164 -279.118403) (xy 407.824265 -279.102515)
			(xy 407.778453 -279.079172) (xy 407.736857 -279.048951) (xy 407.700501 -279.012595) (xy 407.67028 -278.970999)
			(xy 407.646937 -278.925187) (xy 407.631049 -278.876288) (xy 407.623006 -278.825506) (xy 407.304582 -278.825506)
			(xy 407.296866 -278.872982) (xy 407.281282 -278.919663) (xy 407.258411 -278.96324) (xy 407.228846 -279.002584)
			(xy 407.193353 -279.036676) (xy 407.15285 -279.064632) (xy 407.108388 -279.08573) (xy 407.061117 -279.099422)
			(xy 407.012262 -279.105354) (xy 406.963087 -279.103373) (xy 406.914868 -279.093529) (xy 406.868852 -279.076077)
			(xy 406.826231 -279.05147) (xy 406.78811 -279.020345) (xy 406.755475 -278.983508) (xy 406.729172 -278.941912)
			(xy 406.709881 -278.896636) (xy 406.698104 -278.848852) (xy 406.694144 -278.799798) (xy 406.37714 -278.799798)
			(xy 406.376636 -278.825506) (xy 406.368593 -278.876288) (xy 406.352705 -278.925187) (xy 406.329362 -278.970999)
			(xy 406.299141 -279.012595) (xy 406.262785 -279.048951) (xy 406.221189 -279.079172) (xy 406.175377 -279.102515)
			(xy 406.126478 -279.118403) (xy 406.075696 -279.126446) (xy 406.02428 -279.126446) (xy 405.973498 -279.118403)
			(xy 405.924599 -279.102515) (xy 405.878787 -279.079172) (xy 405.837191 -279.048951) (xy 405.800835 -279.012595)
			(xy 405.770614 -278.970999) (xy 405.747271 -278.925187) (xy 405.731383 -278.876288) (xy 405.72334 -278.825506)
			(xy 405.404662 -278.825506) (xy 405.396946 -278.872982) (xy 405.381362 -278.919663) (xy 405.358491 -278.96324)
			(xy 405.328926 -279.002584) (xy 405.293433 -279.036676) (xy 405.25293 -279.064632) (xy 405.208468 -279.08573)
			(xy 405.161197 -279.099422) (xy 405.112342 -279.105354) (xy 405.063167 -279.103373) (xy 405.014948 -279.093529)
			(xy 404.968932 -279.076077) (xy 404.926311 -279.05147) (xy 404.88819 -279.020345) (xy 404.855555 -278.983508)
			(xy 404.829252 -278.941912) (xy 404.809961 -278.896636) (xy 404.798184 -278.848852) (xy 404.794224 -278.799798)
			(xy 404.476966 -278.799798) (xy 404.476462 -278.825506) (xy 404.468419 -278.876288) (xy 404.452531 -278.925187)
			(xy 404.429188 -278.970999) (xy 404.398967 -279.012595) (xy 404.362611 -279.048951) (xy 404.321015 -279.079172)
			(xy 404.275203 -279.102515) (xy 404.226304 -279.118403) (xy 404.175522 -279.126446) (xy 404.124106 -279.126446)
			(xy 404.073324 -279.118403) (xy 404.024425 -279.102515) (xy 403.978613 -279.079172) (xy 403.937017 -279.048951)
			(xy 403.900661 -279.012595) (xy 403.87044 -278.970999) (xy 403.847097 -278.925187) (xy 403.831209 -278.876288)
			(xy 403.823166 -278.825506) (xy 403.504488 -278.825506) (xy 403.496772 -278.872982) (xy 403.481188 -278.919663)
			(xy 403.458317 -278.96324) (xy 403.428752 -279.002584) (xy 403.393259 -279.036676) (xy 403.352756 -279.064632)
			(xy 403.308294 -279.08573) (xy 403.261023 -279.099422) (xy 403.212168 -279.105354) (xy 403.162993 -279.103373)
			(xy 403.114774 -279.093529) (xy 403.068758 -279.076077) (xy 403.026137 -279.05147) (xy 402.988016 -279.020345)
			(xy 402.955381 -278.983508) (xy 402.929078 -278.941912) (xy 402.909787 -278.896636) (xy 402.89801 -278.848852)
			(xy 402.89405 -278.799798) (xy 402.577046 -278.799798) (xy 402.576542 -278.825506) (xy 402.568499 -278.876288)
			(xy 402.552611 -278.925187) (xy 402.529268 -278.970999) (xy 402.499047 -279.012595) (xy 402.462691 -279.048951)
			(xy 402.421095 -279.079172) (xy 402.375283 -279.102515) (xy 402.326384 -279.118403) (xy 402.275602 -279.126446)
			(xy 402.224186 -279.126446) (xy 402.173404 -279.118403) (xy 402.124505 -279.102515) (xy 402.078693 -279.079172)
			(xy 402.037097 -279.048951) (xy 402.000741 -279.012595) (xy 401.97052 -278.970999) (xy 401.947177 -278.925187)
			(xy 401.931289 -278.876288) (xy 401.923246 -278.825506) (xy 401.604568 -278.825506) (xy 401.596852 -278.872982)
			(xy 401.581268 -278.919663) (xy 401.558397 -278.96324) (xy 401.528832 -279.002584) (xy 401.493339 -279.036676)
			(xy 401.452836 -279.064632) (xy 401.408374 -279.08573) (xy 401.361103 -279.099422) (xy 401.312248 -279.105354)
			(xy 401.263073 -279.103373) (xy 401.214854 -279.093529) (xy 401.168838 -279.076077) (xy 401.126217 -279.05147)
			(xy 401.088096 -279.020345) (xy 401.055461 -278.983508) (xy 401.029158 -278.941912) (xy 401.009867 -278.896636)
			(xy 400.99809 -278.848852) (xy 400.99413 -278.799798) (xy 400.677126 -278.799798) (xy 400.676622 -278.825506)
			(xy 400.668579 -278.876288) (xy 400.652691 -278.925187) (xy 400.629348 -278.970999) (xy 400.599127 -279.012595)
			(xy 400.562771 -279.048951) (xy 400.521175 -279.079172) (xy 400.475363 -279.102515) (xy 400.426464 -279.118403)
			(xy 400.375682 -279.126446) (xy 400.324266 -279.126446) (xy 400.273484 -279.118403) (xy 400.224585 -279.102515)
			(xy 400.178773 -279.079172) (xy 400.137177 -279.048951) (xy 400.100821 -279.012595) (xy 400.0706 -278.970999)
			(xy 400.047257 -278.925187) (xy 400.031369 -278.876288) (xy 400.023326 -278.825506) (xy 399.704648 -278.825506)
			(xy 399.696932 -278.872982) (xy 399.681348 -278.919663) (xy 399.658477 -278.96324) (xy 399.628912 -279.002584)
			(xy 399.593419 -279.036676) (xy 399.552916 -279.064632) (xy 399.508454 -279.08573) (xy 399.461183 -279.099422)
			(xy 399.412328 -279.105354) (xy 399.363153 -279.103373) (xy 399.314934 -279.093529) (xy 399.268918 -279.076077)
			(xy 399.226297 -279.05147) (xy 399.188176 -279.020345) (xy 399.155541 -278.983508) (xy 399.129238 -278.941912)
			(xy 399.109947 -278.896636) (xy 399.09817 -278.848852) (xy 399.09421 -278.799798) (xy 398.776952 -278.799798)
			(xy 398.776448 -278.825506) (xy 398.768405 -278.876288) (xy 398.752517 -278.925187) (xy 398.729174 -278.970999)
			(xy 398.698953 -279.012595) (xy 398.662597 -279.048951) (xy 398.621001 -279.079172) (xy 398.575189 -279.102515)
			(xy 398.52629 -279.118403) (xy 398.475508 -279.126446) (xy 398.424092 -279.126446) (xy 398.37331 -279.118403)
			(xy 398.324411 -279.102515) (xy 398.278599 -279.079172) (xy 398.237003 -279.048951) (xy 398.200647 -279.012595)
			(xy 398.170426 -278.970999) (xy 398.147083 -278.925187) (xy 398.131195 -278.876288) (xy 398.123152 -278.825506)
			(xy 397.804474 -278.825506) (xy 397.796758 -278.872982) (xy 397.781174 -278.919663) (xy 397.758303 -278.96324)
			(xy 397.728738 -279.002584) (xy 397.693245 -279.036676) (xy 397.652742 -279.064632) (xy 397.60828 -279.08573)
			(xy 397.561009 -279.099422) (xy 397.512154 -279.105354) (xy 397.462979 -279.103373) (xy 397.41476 -279.093529)
			(xy 397.368744 -279.076077) (xy 397.326123 -279.05147) (xy 397.288002 -279.020345) (xy 397.255367 -278.983508)
			(xy 397.229064 -278.941912) (xy 397.209773 -278.896636) (xy 397.197996 -278.848852) (xy 397.194036 -278.799798)
			(xy 396.877032 -278.799798) (xy 396.876528 -278.825506) (xy 396.868485 -278.876288) (xy 396.852597 -278.925187)
			(xy 396.829254 -278.970999) (xy 396.799033 -279.012595) (xy 396.762677 -279.048951) (xy 396.721081 -279.079172)
			(xy 396.675269 -279.102515) (xy 396.62637 -279.118403) (xy 396.575588 -279.126446) (xy 396.524172 -279.126446)
			(xy 396.47339 -279.118403) (xy 396.424491 -279.102515) (xy 396.378679 -279.079172) (xy 396.337083 -279.048951)
			(xy 396.300727 -279.012595) (xy 396.270506 -278.970999) (xy 396.247163 -278.925187) (xy 396.231275 -278.876288)
			(xy 396.223232 -278.825506) (xy 395.904554 -278.825506) (xy 395.896838 -278.872982) (xy 395.881254 -278.919663)
			(xy 395.858383 -278.96324) (xy 395.828818 -279.002584) (xy 395.793325 -279.036676) (xy 395.752822 -279.064632)
			(xy 395.70836 -279.08573) (xy 395.661089 -279.099422) (xy 395.612234 -279.105354) (xy 395.563059 -279.103373)
			(xy 395.51484 -279.093529) (xy 395.468824 -279.076077) (xy 395.426203 -279.05147) (xy 395.388082 -279.020345)
			(xy 395.355447 -278.983508) (xy 395.329144 -278.941912) (xy 395.309853 -278.896636) (xy 395.298076 -278.848852)
			(xy 395.294116 -278.799798) (xy 394.977112 -278.799798) (xy 394.976608 -278.825506) (xy 394.968565 -278.876288)
			(xy 394.952677 -278.925187) (xy 394.929334 -278.970999) (xy 394.899113 -279.012595) (xy 394.862757 -279.048951)
			(xy 394.821161 -279.079172) (xy 394.775349 -279.102515) (xy 394.72645 -279.118403) (xy 394.675668 -279.126446)
			(xy 394.624252 -279.126446) (xy 394.57347 -279.118403) (xy 394.524571 -279.102515) (xy 394.478759 -279.079172)
			(xy 394.437163 -279.048951) (xy 394.400807 -279.012595) (xy 394.370586 -278.970999) (xy 394.347243 -278.925187)
			(xy 394.331355 -278.876288) (xy 394.323312 -278.825506) (xy 394.004634 -278.825506) (xy 393.996918 -278.872982)
			(xy 393.981334 -278.919663) (xy 393.958463 -278.96324) (xy 393.928898 -279.002584) (xy 393.893405 -279.036676)
			(xy 393.852902 -279.064632) (xy 393.80844 -279.08573) (xy 393.761169 -279.099422) (xy 393.712314 -279.105354)
			(xy 393.663139 -279.103373) (xy 393.61492 -279.093529) (xy 393.568904 -279.076077) (xy 393.526283 -279.05147)
			(xy 393.488162 -279.020345) (xy 393.455527 -278.983508) (xy 393.429224 -278.941912) (xy 393.409933 -278.896636)
			(xy 393.398156 -278.848852) (xy 393.394196 -278.799798) (xy 393.076218 -278.799798) (xy 393.076217 -278.8255)
			(xy 393.068178 -278.876247) (xy 393.052299 -278.925111) (xy 393.028972 -278.97089) (xy 392.99877 -279.012456)
			(xy 392.962438 -279.048786) (xy 392.92087 -279.078984) (xy 392.875089 -279.102309) (xy 392.826223 -279.118184)
			(xy 392.775476 -279.126219) (xy 392.749786 -279.126696) (xy 392.736068 -279.12655) (xy 392.708727 -279.124261)
			(xy 392.695176 -279.122124) (xy 392.683238 -279.120346) (xy 392.660378 -279.127204) (xy 392.583924 -279.200864)
			(xy 392.57605 -279.22347) (xy 392.577574 -279.235408) (xy 392.578758 -279.245208) (xy 392.580032 -279.264908)
			(xy 392.580114 -279.274778) (xy 392.579934 -279.288961) (xy 392.577264 -279.317201) (xy 392.57478 -279.331166)
			(xy 392.572494 -279.343612) (xy 392.57986 -279.367234) (xy 392.65733 -279.444704) (xy 392.680952 -279.45207)
			(xy 392.693398 -279.449784) (xy 392.707365 -279.447312) (xy 392.735604 -279.444637) (xy 392.749786 -279.44445)
			(xy 392.774609 -279.444963) (xy 392.823601 -279.452993) (xy 392.870649 -279.468843) (xy 392.914512 -279.492097)
			(xy 392.954036 -279.52214) (xy 392.988178 -279.558182) (xy 393.016039 -279.599274) (xy 393.036884 -279.644331)
			(xy 393.050166 -279.692167) (xy 393.055533 -279.741522) (xy 393.053706 -279.775212) (xy 393.373352 -279.775212)
			(xy 393.373352 -279.723796) (xy 393.381395 -279.673014) (xy 393.397283 -279.624115) (xy 393.420626 -279.578303)
			(xy 393.450847 -279.536707) (xy 393.487203 -279.500351) (xy 393.528799 -279.47013) (xy 393.574611 -279.446787)
			(xy 393.62351 -279.430899) (xy 393.674292 -279.422856) (xy 393.725708 -279.422856) (xy 393.77649 -279.430899)
			(xy 393.825389 -279.446787) (xy 393.871201 -279.47013) (xy 393.912797 -279.500351) (xy 393.949153 -279.536707)
			(xy 393.979374 -279.578303) (xy 394.002717 -279.624115) (xy 394.018605 -279.673014) (xy 394.026648 -279.723796)
			(xy 394.027152 -279.749504) (xy 394.027147 -279.749758) (xy 394.344156 -279.749758) (xy 394.348116 -279.700704)
			(xy 394.359893 -279.65292) (xy 394.379184 -279.607644) (xy 394.405487 -279.566048) (xy 394.438122 -279.529211)
			(xy 394.476243 -279.498086) (xy 394.518864 -279.473479) (xy 394.56488 -279.456027) (xy 394.613099 -279.446183)
			(xy 394.662274 -279.444202) (xy 394.711129 -279.450134) (xy 394.7584 -279.463826) (xy 394.802862 -279.484924)
			(xy 394.843365 -279.51288) (xy 394.878858 -279.546972) (xy 394.908423 -279.586316) (xy 394.931294 -279.629893)
			(xy 394.946878 -279.676574) (xy 394.954773 -279.725151) (xy 394.955268 -279.749758) (xy 394.954773 -279.774365)
			(xy 394.954635 -279.775212) (xy 395.273272 -279.775212) (xy 395.273272 -279.723796) (xy 395.281315 -279.673014)
			(xy 395.297203 -279.624115) (xy 395.320546 -279.578303) (xy 395.350767 -279.536707) (xy 395.387123 -279.500351)
			(xy 395.428719 -279.47013) (xy 395.474531 -279.446787) (xy 395.52343 -279.430899) (xy 395.574212 -279.422856)
			(xy 395.625628 -279.422856) (xy 395.67641 -279.430899) (xy 395.725309 -279.446787) (xy 395.771121 -279.47013)
			(xy 395.812717 -279.500351) (xy 395.849073 -279.536707) (xy 395.879294 -279.578303) (xy 395.902637 -279.624115)
			(xy 395.918525 -279.673014) (xy 395.926568 -279.723796) (xy 395.927072 -279.749504) (xy 395.927067 -279.749758)
			(xy 396.244076 -279.749758) (xy 396.248036 -279.700704) (xy 396.259813 -279.65292) (xy 396.279104 -279.607644)
			(xy 396.305407 -279.566048) (xy 396.338042 -279.529211) (xy 396.376163 -279.498086) (xy 396.418784 -279.473479)
			(xy 396.4648 -279.456027) (xy 396.513019 -279.446183) (xy 396.562194 -279.444202) (xy 396.611049 -279.450134)
			(xy 396.65832 -279.463826) (xy 396.702782 -279.484924) (xy 396.743285 -279.51288) (xy 396.778778 -279.546972)
			(xy 396.808343 -279.586316) (xy 396.831214 -279.629893) (xy 396.846798 -279.676574) (xy 396.854693 -279.725151)
			(xy 396.855188 -279.749758) (xy 396.854693 -279.774365) (xy 396.854555 -279.775212) (xy 397.173192 -279.775212)
			(xy 397.173192 -279.723796) (xy 397.181235 -279.673014) (xy 397.197123 -279.624115) (xy 397.220466 -279.578303)
			(xy 397.250687 -279.536707) (xy 397.287043 -279.500351) (xy 397.328639 -279.47013) (xy 397.374451 -279.446787)
			(xy 397.42335 -279.430899) (xy 397.474132 -279.422856) (xy 397.525548 -279.422856) (xy 397.57633 -279.430899)
			(xy 397.625229 -279.446787) (xy 397.671041 -279.47013) (xy 397.712637 -279.500351) (xy 397.748993 -279.536707)
			(xy 397.779214 -279.578303) (xy 397.802557 -279.624115) (xy 397.818445 -279.673014) (xy 397.826488 -279.723796)
			(xy 397.826992 -279.749504) (xy 397.826987 -279.749758) (xy 398.143996 -279.749758) (xy 398.147956 -279.700704)
			(xy 398.159733 -279.65292) (xy 398.179024 -279.607644) (xy 398.205327 -279.566048) (xy 398.237962 -279.529211)
			(xy 398.276083 -279.498086) (xy 398.318704 -279.473479) (xy 398.36472 -279.456027) (xy 398.412939 -279.446183)
			(xy 398.462114 -279.444202) (xy 398.510969 -279.450134) (xy 398.55824 -279.463826) (xy 398.602702 -279.484924)
			(xy 398.643205 -279.51288) (xy 398.678698 -279.546972) (xy 398.708263 -279.586316) (xy 398.731134 -279.629893)
			(xy 398.746718 -279.676574) (xy 398.754613 -279.725151) (xy 398.755108 -279.749758) (xy 398.754613 -279.774365)
			(xy 398.754475 -279.775212) (xy 399.073366 -279.775212) (xy 399.073366 -279.723796) (xy 399.081409 -279.673014)
			(xy 399.097297 -279.624115) (xy 399.12064 -279.578303) (xy 399.150861 -279.536707) (xy 399.187217 -279.500351)
			(xy 399.228813 -279.47013) (xy 399.274625 -279.446787) (xy 399.323524 -279.430899) (xy 399.374306 -279.422856)
			(xy 399.425722 -279.422856) (xy 399.476504 -279.430899) (xy 399.525403 -279.446787) (xy 399.571215 -279.47013)
			(xy 399.612811 -279.500351) (xy 399.649167 -279.536707) (xy 399.679388 -279.578303) (xy 399.702731 -279.624115)
			(xy 399.718619 -279.673014) (xy 399.726662 -279.723796) (xy 399.727166 -279.749504) (xy 399.727161 -279.749758)
			(xy 400.04417 -279.749758) (xy 400.04813 -279.700704) (xy 400.059907 -279.65292) (xy 400.079198 -279.607644)
			(xy 400.105501 -279.566048) (xy 400.138136 -279.529211) (xy 400.176257 -279.498086) (xy 400.218878 -279.473479)
			(xy 400.264894 -279.456027) (xy 400.313113 -279.446183) (xy 400.362288 -279.444202) (xy 400.411143 -279.450134)
			(xy 400.458414 -279.463826) (xy 400.502876 -279.484924) (xy 400.543379 -279.51288) (xy 400.578872 -279.546972)
			(xy 400.608437 -279.586316) (xy 400.631308 -279.629893) (xy 400.646892 -279.676574) (xy 400.654787 -279.725151)
			(xy 400.655282 -279.749758) (xy 400.654787 -279.774365) (xy 400.654649 -279.775212) (xy 400.973286 -279.775212)
			(xy 400.973286 -279.723796) (xy 400.981329 -279.673014) (xy 400.997217 -279.624115) (xy 401.02056 -279.578303)
			(xy 401.050781 -279.536707) (xy 401.087137 -279.500351) (xy 401.128733 -279.47013) (xy 401.174545 -279.446787)
			(xy 401.223444 -279.430899) (xy 401.274226 -279.422856) (xy 401.325642 -279.422856) (xy 401.376424 -279.430899)
			(xy 401.425323 -279.446787) (xy 401.471135 -279.47013) (xy 401.512731 -279.500351) (xy 401.549087 -279.536707)
			(xy 401.579308 -279.578303) (xy 401.602651 -279.624115) (xy 401.618539 -279.673014) (xy 401.626582 -279.723796)
			(xy 401.627086 -279.749504) (xy 401.627081 -279.749758) (xy 401.94409 -279.749758) (xy 401.94805 -279.700704)
			(xy 401.959827 -279.65292) (xy 401.979118 -279.607644) (xy 402.005421 -279.566048) (xy 402.038056 -279.529211)
			(xy 402.076177 -279.498086) (xy 402.118798 -279.473479) (xy 402.164814 -279.456027) (xy 402.213033 -279.446183)
			(xy 402.262208 -279.444202) (xy 402.311063 -279.450134) (xy 402.358334 -279.463826) (xy 402.402796 -279.484924)
			(xy 402.443299 -279.51288) (xy 402.478792 -279.546972) (xy 402.508357 -279.586316) (xy 402.531228 -279.629893)
			(xy 402.546812 -279.676574) (xy 402.554707 -279.725151) (xy 402.555202 -279.749758) (xy 402.554707 -279.774365)
			(xy 402.554569 -279.775212) (xy 402.873206 -279.775212) (xy 402.873206 -279.723796) (xy 402.881249 -279.673014)
			(xy 402.897137 -279.624115) (xy 402.92048 -279.578303) (xy 402.950701 -279.536707) (xy 402.987057 -279.500351)
			(xy 403.028653 -279.47013) (xy 403.074465 -279.446787) (xy 403.123364 -279.430899) (xy 403.174146 -279.422856)
			(xy 403.225562 -279.422856) (xy 403.276344 -279.430899) (xy 403.325243 -279.446787) (xy 403.371055 -279.47013)
			(xy 403.412651 -279.500351) (xy 403.449007 -279.536707) (xy 403.479228 -279.578303) (xy 403.502571 -279.624115)
			(xy 403.518459 -279.673014) (xy 403.526502 -279.723796) (xy 403.527006 -279.749504) (xy 403.527001 -279.749758)
			(xy 403.84401 -279.749758) (xy 403.84797 -279.700704) (xy 403.859747 -279.65292) (xy 403.879038 -279.607644)
			(xy 403.905341 -279.566048) (xy 403.937976 -279.529211) (xy 403.976097 -279.498086) (xy 404.018718 -279.473479)
			(xy 404.064734 -279.456027) (xy 404.112953 -279.446183) (xy 404.162128 -279.444202) (xy 404.210983 -279.450134)
			(xy 404.258254 -279.463826) (xy 404.302716 -279.484924) (xy 404.343219 -279.51288) (xy 404.378712 -279.546972)
			(xy 404.408277 -279.586316) (xy 404.431148 -279.629893) (xy 404.446732 -279.676574) (xy 404.454627 -279.725151)
			(xy 404.455122 -279.749758) (xy 404.454627 -279.774365) (xy 404.454489 -279.775212) (xy 404.773126 -279.775212)
			(xy 404.773126 -279.723796) (xy 404.781169 -279.673014) (xy 404.797057 -279.624115) (xy 404.8204 -279.578303)
			(xy 404.850621 -279.536707) (xy 404.886977 -279.500351) (xy 404.928573 -279.47013) (xy 404.974385 -279.446787)
			(xy 405.023284 -279.430899) (xy 405.074066 -279.422856) (xy 405.125482 -279.422856) (xy 405.176264 -279.430899)
			(xy 405.225163 -279.446787) (xy 405.270975 -279.47013) (xy 405.312571 -279.500351) (xy 405.348927 -279.536707)
			(xy 405.379148 -279.578303) (xy 405.402491 -279.624115) (xy 405.418379 -279.673014) (xy 405.426422 -279.723796)
			(xy 405.426926 -279.749504) (xy 405.426921 -279.749758) (xy 405.744184 -279.749758) (xy 405.748144 -279.700704)
			(xy 405.759921 -279.65292) (xy 405.779212 -279.607644) (xy 405.805515 -279.566048) (xy 405.83815 -279.529211)
			(xy 405.876271 -279.498086) (xy 405.918892 -279.473479) (xy 405.964908 -279.456027) (xy 406.013127 -279.446183)
			(xy 406.062302 -279.444202) (xy 406.111157 -279.450134) (xy 406.158428 -279.463826) (xy 406.20289 -279.484924)
			(xy 406.243393 -279.51288) (xy 406.278886 -279.546972) (xy 406.308451 -279.586316) (xy 406.331322 -279.629893)
			(xy 406.346906 -279.676574) (xy 406.354801 -279.725151) (xy 406.355296 -279.749758) (xy 406.354801 -279.774365)
			(xy 406.354663 -279.775212) (xy 406.6733 -279.775212) (xy 406.6733 -279.723796) (xy 406.681343 -279.673014)
			(xy 406.697231 -279.624115) (xy 406.720574 -279.578303) (xy 406.750795 -279.536707) (xy 406.787151 -279.500351)
			(xy 406.828747 -279.47013) (xy 406.874559 -279.446787) (xy 406.923458 -279.430899) (xy 406.97424 -279.422856)
			(xy 407.025656 -279.422856) (xy 407.076438 -279.430899) (xy 407.125337 -279.446787) (xy 407.171149 -279.47013)
			(xy 407.212745 -279.500351) (xy 407.249101 -279.536707) (xy 407.279322 -279.578303) (xy 407.302665 -279.624115)
			(xy 407.318553 -279.673014) (xy 407.326596 -279.723796) (xy 407.3271 -279.749504) (xy 407.327095 -279.749758)
			(xy 407.644104 -279.749758) (xy 407.648064 -279.700704) (xy 407.659841 -279.65292) (xy 407.679132 -279.607644)
			(xy 407.705435 -279.566048) (xy 407.73807 -279.529211) (xy 407.776191 -279.498086) (xy 407.818812 -279.473479)
			(xy 407.864828 -279.456027) (xy 407.913047 -279.446183) (xy 407.962222 -279.444202) (xy 408.011077 -279.450134)
			(xy 408.058348 -279.463826) (xy 408.10281 -279.484924) (xy 408.143313 -279.51288) (xy 408.178806 -279.546972)
			(xy 408.208371 -279.586316) (xy 408.231242 -279.629893) (xy 408.246826 -279.676574) (xy 408.254721 -279.725151)
			(xy 408.255216 -279.749758) (xy 408.254721 -279.774365) (xy 408.254583 -279.775212) (xy 408.57322 -279.775212)
			(xy 408.57322 -279.723796) (xy 408.581263 -279.673014) (xy 408.597151 -279.624115) (xy 408.620494 -279.578303)
			(xy 408.650715 -279.536707) (xy 408.687071 -279.500351) (xy 408.728667 -279.47013) (xy 408.774479 -279.446787)
			(xy 408.823378 -279.430899) (xy 408.87416 -279.422856) (xy 408.925576 -279.422856) (xy 408.976358 -279.430899)
			(xy 409.025257 -279.446787) (xy 409.071069 -279.47013) (xy 409.112665 -279.500351) (xy 409.149021 -279.536707)
			(xy 409.179242 -279.578303) (xy 409.202585 -279.624115) (xy 409.218473 -279.673014) (xy 409.226516 -279.723796)
			(xy 409.22702 -279.749504) (xy 409.227015 -279.749758) (xy 409.544024 -279.749758) (xy 409.547984 -279.700704)
			(xy 409.559761 -279.65292) (xy 409.579052 -279.607644) (xy 409.605355 -279.566048) (xy 409.63799 -279.529211)
			(xy 409.676111 -279.498086) (xy 409.718732 -279.473479) (xy 409.764748 -279.456027) (xy 409.812967 -279.446183)
			(xy 409.862142 -279.444202) (xy 409.910997 -279.450134) (xy 409.958268 -279.463826) (xy 410.00273 -279.484924)
			(xy 410.043233 -279.51288) (xy 410.078726 -279.546972) (xy 410.108291 -279.586316) (xy 410.131162 -279.629893)
			(xy 410.146746 -279.676574) (xy 410.154641 -279.725151) (xy 410.155136 -279.749758) (xy 410.154641 -279.774365)
			(xy 410.154503 -279.775212) (xy 410.47314 -279.775212) (xy 410.47314 -279.723796) (xy 410.481183 -279.673014)
			(xy 410.497071 -279.624115) (xy 410.520414 -279.578303) (xy 410.550635 -279.536707) (xy 410.586991 -279.500351)
			(xy 410.628587 -279.47013) (xy 410.674399 -279.446787) (xy 410.723298 -279.430899) (xy 410.77408 -279.422856)
			(xy 410.825496 -279.422856) (xy 410.876278 -279.430899) (xy 410.925177 -279.446787) (xy 410.970989 -279.47013)
			(xy 411.012585 -279.500351) (xy 411.048941 -279.536707) (xy 411.079162 -279.578303) (xy 411.102505 -279.624115)
			(xy 411.118393 -279.673014) (xy 411.126436 -279.723796) (xy 411.12694 -279.749504) (xy 411.126935 -279.749758)
			(xy 411.444198 -279.749758) (xy 411.448158 -279.700704) (xy 411.459935 -279.65292) (xy 411.479226 -279.607644)
			(xy 411.505529 -279.566048) (xy 411.538164 -279.529211) (xy 411.576285 -279.498086) (xy 411.618906 -279.473479)
			(xy 411.664922 -279.456027) (xy 411.713141 -279.446183) (xy 411.762316 -279.444202) (xy 411.811171 -279.450134)
			(xy 411.858442 -279.463826) (xy 411.902904 -279.484924) (xy 411.943407 -279.51288) (xy 411.9789 -279.546972)
			(xy 412.008465 -279.586316) (xy 412.031336 -279.629893) (xy 412.04692 -279.676574) (xy 412.054815 -279.725151)
			(xy 412.05531 -279.749758) (xy 412.054815 -279.774365) (xy 412.054677 -279.775212) (xy 412.373314 -279.775212)
			(xy 412.373314 -279.723796) (xy 412.381357 -279.673014) (xy 412.397245 -279.624115) (xy 412.420588 -279.578303)
			(xy 412.450809 -279.536707) (xy 412.487165 -279.500351) (xy 412.528761 -279.47013) (xy 412.574573 -279.446787)
			(xy 412.623472 -279.430899) (xy 412.674254 -279.422856) (xy 412.72567 -279.422856) (xy 412.776452 -279.430899)
			(xy 412.825351 -279.446787) (xy 412.871163 -279.47013) (xy 412.912759 -279.500351) (xy 412.949115 -279.536707)
			(xy 412.979336 -279.578303) (xy 413.002679 -279.624115) (xy 413.018567 -279.673014) (xy 413.02661 -279.723796)
			(xy 413.027114 -279.749504) (xy 413.027109 -279.749758) (xy 413.344118 -279.749758) (xy 413.348078 -279.700704)
			(xy 413.359855 -279.65292) (xy 413.379146 -279.607644) (xy 413.405449 -279.566048) (xy 413.438084 -279.529211)
			(xy 413.476205 -279.498086) (xy 413.518826 -279.473479) (xy 413.564842 -279.456027) (xy 413.613061 -279.446183)
			(xy 413.662236 -279.444202) (xy 413.711091 -279.450134) (xy 413.758362 -279.463826) (xy 413.802824 -279.484924)
			(xy 413.843327 -279.51288) (xy 413.87882 -279.546972) (xy 413.908385 -279.586316) (xy 413.931256 -279.629893)
			(xy 413.94684 -279.676574) (xy 413.954735 -279.725151) (xy 413.95523 -279.749758) (xy 413.954735 -279.774365)
			(xy 413.954597 -279.775212) (xy 414.273234 -279.775212) (xy 414.273234 -279.723796) (xy 414.281277 -279.673014)
			(xy 414.297165 -279.624115) (xy 414.320508 -279.578303) (xy 414.350729 -279.536707) (xy 414.387085 -279.500351)
			(xy 414.428681 -279.47013) (xy 414.474493 -279.446787) (xy 414.523392 -279.430899) (xy 414.574174 -279.422856)
			(xy 414.62559 -279.422856) (xy 414.676372 -279.430899) (xy 414.725271 -279.446787) (xy 414.771083 -279.47013)
			(xy 414.812679 -279.500351) (xy 414.849035 -279.536707) (xy 414.879256 -279.578303) (xy 414.902599 -279.624115)
			(xy 414.918487 -279.673014) (xy 414.92653 -279.723796) (xy 414.927034 -279.749504) (xy 414.927029 -279.749758)
			(xy 415.244038 -279.749758) (xy 415.247998 -279.700704) (xy 415.259775 -279.65292) (xy 415.279066 -279.607644)
			(xy 415.305369 -279.566048) (xy 415.338004 -279.529211) (xy 415.376125 -279.498086) (xy 415.418746 -279.473479)
			(xy 415.464762 -279.456027) (xy 415.512981 -279.446183) (xy 415.562156 -279.444202) (xy 415.611011 -279.450134)
			(xy 415.658282 -279.463826) (xy 415.702744 -279.484924) (xy 415.743247 -279.51288) (xy 415.77874 -279.546972)
			(xy 415.808305 -279.586316) (xy 415.831176 -279.629893) (xy 415.84676 -279.676574) (xy 415.854655 -279.725151)
			(xy 415.85515 -279.749758) (xy 415.854655 -279.774365) (xy 415.854517 -279.775212) (xy 416.173154 -279.775212)
			(xy 416.173154 -279.723796) (xy 416.181197 -279.673014) (xy 416.197085 -279.624115) (xy 416.220428 -279.578303)
			(xy 416.250649 -279.536707) (xy 416.287005 -279.500351) (xy 416.328601 -279.47013) (xy 416.374413 -279.446787)
			(xy 416.423312 -279.430899) (xy 416.474094 -279.422856) (xy 416.52551 -279.422856) (xy 416.576292 -279.430899)
			(xy 416.625191 -279.446787) (xy 416.671003 -279.47013) (xy 416.712599 -279.500351) (xy 416.748955 -279.536707)
			(xy 416.779176 -279.578303) (xy 416.802519 -279.624115) (xy 416.818407 -279.673014) (xy 416.82645 -279.723796)
			(xy 416.826954 -279.749504) (xy 416.826949 -279.749758) (xy 417.144212 -279.749758) (xy 417.148172 -279.700704)
			(xy 417.159949 -279.65292) (xy 417.17924 -279.607644) (xy 417.205543 -279.566048) (xy 417.238178 -279.529211)
			(xy 417.276299 -279.498086) (xy 417.31892 -279.473479) (xy 417.364936 -279.456027) (xy 417.413155 -279.446183)
			(xy 417.46233 -279.444202) (xy 417.511185 -279.450134) (xy 417.558456 -279.463826) (xy 417.602918 -279.484924)
			(xy 417.643421 -279.51288) (xy 417.678914 -279.546972) (xy 417.708479 -279.586316) (xy 417.73135 -279.629893)
			(xy 417.746934 -279.676574) (xy 417.754829 -279.725151) (xy 417.755324 -279.749758) (xy 417.754829 -279.774365)
			(xy 417.754691 -279.775212) (xy 418.073328 -279.775212) (xy 418.073328 -279.723796) (xy 418.081371 -279.673014)
			(xy 418.097259 -279.624115) (xy 418.120602 -279.578303) (xy 418.150823 -279.536707) (xy 418.187179 -279.500351)
			(xy 418.228775 -279.47013) (xy 418.274587 -279.446787) (xy 418.323486 -279.430899) (xy 418.374268 -279.422856)
			(xy 418.425684 -279.422856) (xy 418.476466 -279.430899) (xy 418.525365 -279.446787) (xy 418.571177 -279.47013)
			(xy 418.612773 -279.500351) (xy 418.649129 -279.536707) (xy 418.67935 -279.578303) (xy 418.702693 -279.624115)
			(xy 418.718581 -279.673014) (xy 418.726624 -279.723796) (xy 418.727128 -279.749504) (xy 418.727123 -279.749758)
			(xy 419.044132 -279.749758) (xy 419.048092 -279.700704) (xy 419.059869 -279.65292) (xy 419.07916 -279.607644)
			(xy 419.105463 -279.566048) (xy 419.138098 -279.529211) (xy 419.176219 -279.498086) (xy 419.21884 -279.473479)
			(xy 419.264856 -279.456027) (xy 419.313075 -279.446183) (xy 419.36225 -279.444202) (xy 419.411105 -279.450134)
			(xy 419.458376 -279.463826) (xy 419.502838 -279.484924) (xy 419.543341 -279.51288) (xy 419.578834 -279.546972)
			(xy 419.608399 -279.586316) (xy 419.63127 -279.629893) (xy 419.646854 -279.676574) (xy 419.654749 -279.725151)
			(xy 419.655244 -279.749758) (xy 419.654749 -279.774365) (xy 419.654611 -279.775212) (xy 419.973248 -279.775212)
			(xy 419.973248 -279.723796) (xy 419.981291 -279.673014) (xy 419.997179 -279.624115) (xy 420.020522 -279.578303)
			(xy 420.050743 -279.536707) (xy 420.087099 -279.500351) (xy 420.128695 -279.47013) (xy 420.174507 -279.446787)
			(xy 420.223406 -279.430899) (xy 420.274188 -279.422856) (xy 420.325604 -279.422856) (xy 420.376386 -279.430899)
			(xy 420.425285 -279.446787) (xy 420.471097 -279.47013) (xy 420.512693 -279.500351) (xy 420.549049 -279.536707)
			(xy 420.57927 -279.578303) (xy 420.602613 -279.624115) (xy 420.618501 -279.673014) (xy 420.626544 -279.723796)
			(xy 420.627048 -279.749504) (xy 420.627043 -279.749758) (xy 420.944052 -279.749758) (xy 420.948012 -279.700704)
			(xy 420.959789 -279.65292) (xy 420.97908 -279.607644) (xy 421.005383 -279.566048) (xy 421.038018 -279.529211)
			(xy 421.076139 -279.498086) (xy 421.11876 -279.473479) (xy 421.164776 -279.456027) (xy 421.212995 -279.446183)
			(xy 421.26217 -279.444202) (xy 421.311025 -279.450134) (xy 421.358296 -279.463826) (xy 421.402758 -279.484924)
			(xy 421.443261 -279.51288) (xy 421.478754 -279.546972) (xy 421.508319 -279.586316) (xy 421.53119 -279.629893)
			(xy 421.546774 -279.676574) (xy 421.554669 -279.725151) (xy 421.555164 -279.749758) (xy 421.554669 -279.774365)
			(xy 421.546774 -279.822942) (xy 421.53119 -279.869623) (xy 421.508319 -279.9132) (xy 421.478754 -279.952544)
			(xy 421.443261 -279.986636) (xy 421.402758 -280.014592) (xy 421.358296 -280.03569) (xy 421.311025 -280.049382)
			(xy 421.26217 -280.055314) (xy 421.212995 -280.053333) (xy 421.164776 -280.043489) (xy 421.11876 -280.026037)
			(xy 421.076139 -280.00143) (xy 421.038018 -279.970305) (xy 421.005383 -279.933468) (xy 420.97908 -279.891872)
			(xy 420.959789 -279.846596) (xy 420.948012 -279.798812) (xy 420.944052 -279.749758) (xy 420.627043 -279.749758)
			(xy 420.626544 -279.775212) (xy 420.618501 -279.825994) (xy 420.602613 -279.874893) (xy 420.57927 -279.920705)
			(xy 420.549049 -279.962301) (xy 420.512693 -279.998657) (xy 420.471097 -280.028878) (xy 420.425285 -280.052221)
			(xy 420.376386 -280.068109) (xy 420.325604 -280.076152) (xy 420.274188 -280.076152) (xy 420.223406 -280.068109)
			(xy 420.174507 -280.052221) (xy 420.128695 -280.028878) (xy 420.087099 -279.998657) (xy 420.050743 -279.962301)
			(xy 420.020522 -279.920705) (xy 419.997179 -279.874893) (xy 419.981291 -279.825994) (xy 419.973248 -279.775212)
			(xy 419.654611 -279.775212) (xy 419.646854 -279.822942) (xy 419.63127 -279.869623) (xy 419.608399 -279.9132)
			(xy 419.578834 -279.952544) (xy 419.543341 -279.986636) (xy 419.502838 -280.014592) (xy 419.458376 -280.03569)
			(xy 419.411105 -280.049382) (xy 419.36225 -280.055314) (xy 419.313075 -280.053333) (xy 419.264856 -280.043489)
			(xy 419.21884 -280.026037) (xy 419.176219 -280.00143) (xy 419.138098 -279.970305) (xy 419.105463 -279.933468)
			(xy 419.07916 -279.891872) (xy 419.059869 -279.846596) (xy 419.048092 -279.798812) (xy 419.044132 -279.749758)
			(xy 418.727123 -279.749758) (xy 418.726624 -279.775212) (xy 418.718581 -279.825994) (xy 418.702693 -279.874893)
			(xy 418.67935 -279.920705) (xy 418.649129 -279.962301) (xy 418.612773 -279.998657) (xy 418.571177 -280.028878)
			(xy 418.525365 -280.052221) (xy 418.476466 -280.068109) (xy 418.425684 -280.076152) (xy 418.374268 -280.076152)
			(xy 418.323486 -280.068109) (xy 418.274587 -280.052221) (xy 418.228775 -280.028878) (xy 418.187179 -279.998657)
			(xy 418.150823 -279.962301) (xy 418.120602 -279.920705) (xy 418.097259 -279.874893) (xy 418.081371 -279.825994)
			(xy 418.073328 -279.775212) (xy 417.754691 -279.775212) (xy 417.746934 -279.822942) (xy 417.73135 -279.869623)
			(xy 417.708479 -279.9132) (xy 417.678914 -279.952544) (xy 417.643421 -279.986636) (xy 417.602918 -280.014592)
			(xy 417.558456 -280.03569) (xy 417.511185 -280.049382) (xy 417.46233 -280.055314) (xy 417.413155 -280.053333)
			(xy 417.364936 -280.043489) (xy 417.31892 -280.026037) (xy 417.276299 -280.00143) (xy 417.238178 -279.970305)
			(xy 417.205543 -279.933468) (xy 417.17924 -279.891872) (xy 417.159949 -279.846596) (xy 417.148172 -279.798812)
			(xy 417.144212 -279.749758) (xy 416.826949 -279.749758) (xy 416.82645 -279.775212) (xy 416.818407 -279.825994)
			(xy 416.802519 -279.874893) (xy 416.779176 -279.920705) (xy 416.748955 -279.962301) (xy 416.712599 -279.998657)
			(xy 416.671003 -280.028878) (xy 416.625191 -280.052221) (xy 416.576292 -280.068109) (xy 416.52551 -280.076152)
			(xy 416.474094 -280.076152) (xy 416.423312 -280.068109) (xy 416.374413 -280.052221) (xy 416.328601 -280.028878)
			(xy 416.287005 -279.998657) (xy 416.250649 -279.962301) (xy 416.220428 -279.920705) (xy 416.197085 -279.874893)
			(xy 416.181197 -279.825994) (xy 416.173154 -279.775212) (xy 415.854517 -279.775212) (xy 415.84676 -279.822942)
			(xy 415.831176 -279.869623) (xy 415.808305 -279.9132) (xy 415.77874 -279.952544) (xy 415.743247 -279.986636)
			(xy 415.702744 -280.014592) (xy 415.658282 -280.03569) (xy 415.611011 -280.049382) (xy 415.562156 -280.055314)
			(xy 415.512981 -280.053333) (xy 415.464762 -280.043489) (xy 415.418746 -280.026037) (xy 415.376125 -280.00143)
			(xy 415.338004 -279.970305) (xy 415.305369 -279.933468) (xy 415.279066 -279.891872) (xy 415.259775 -279.846596)
			(xy 415.247998 -279.798812) (xy 415.244038 -279.749758) (xy 414.927029 -279.749758) (xy 414.92653 -279.775212)
			(xy 414.918487 -279.825994) (xy 414.902599 -279.874893) (xy 414.879256 -279.920705) (xy 414.849035 -279.962301)
			(xy 414.812679 -279.998657) (xy 414.771083 -280.028878) (xy 414.725271 -280.052221) (xy 414.676372 -280.068109)
			(xy 414.62559 -280.076152) (xy 414.574174 -280.076152) (xy 414.523392 -280.068109) (xy 414.474493 -280.052221)
			(xy 414.428681 -280.028878) (xy 414.387085 -279.998657) (xy 414.350729 -279.962301) (xy 414.320508 -279.920705)
			(xy 414.297165 -279.874893) (xy 414.281277 -279.825994) (xy 414.273234 -279.775212) (xy 413.954597 -279.775212)
			(xy 413.94684 -279.822942) (xy 413.931256 -279.869623) (xy 413.908385 -279.9132) (xy 413.87882 -279.952544)
			(xy 413.843327 -279.986636) (xy 413.802824 -280.014592) (xy 413.758362 -280.03569) (xy 413.711091 -280.049382)
			(xy 413.662236 -280.055314) (xy 413.613061 -280.053333) (xy 413.564842 -280.043489) (xy 413.518826 -280.026037)
			(xy 413.476205 -280.00143) (xy 413.438084 -279.970305) (xy 413.405449 -279.933468) (xy 413.379146 -279.891872)
			(xy 413.359855 -279.846596) (xy 413.348078 -279.798812) (xy 413.344118 -279.749758) (xy 413.027109 -279.749758)
			(xy 413.02661 -279.775212) (xy 413.018567 -279.825994) (xy 413.002679 -279.874893) (xy 412.979336 -279.920705)
			(xy 412.949115 -279.962301) (xy 412.912759 -279.998657) (xy 412.871163 -280.028878) (xy 412.825351 -280.052221)
			(xy 412.776452 -280.068109) (xy 412.72567 -280.076152) (xy 412.674254 -280.076152) (xy 412.623472 -280.068109)
			(xy 412.574573 -280.052221) (xy 412.528761 -280.028878) (xy 412.487165 -279.998657) (xy 412.450809 -279.962301)
			(xy 412.420588 -279.920705) (xy 412.397245 -279.874893) (xy 412.381357 -279.825994) (xy 412.373314 -279.775212)
			(xy 412.054677 -279.775212) (xy 412.04692 -279.822942) (xy 412.031336 -279.869623) (xy 412.008465 -279.9132)
			(xy 411.9789 -279.952544) (xy 411.943407 -279.986636) (xy 411.902904 -280.014592) (xy 411.858442 -280.03569)
			(xy 411.811171 -280.049382) (xy 411.762316 -280.055314) (xy 411.713141 -280.053333) (xy 411.664922 -280.043489)
			(xy 411.618906 -280.026037) (xy 411.576285 -280.00143) (xy 411.538164 -279.970305) (xy 411.505529 -279.933468)
			(xy 411.479226 -279.891872) (xy 411.459935 -279.846596) (xy 411.448158 -279.798812) (xy 411.444198 -279.749758)
			(xy 411.126935 -279.749758) (xy 411.126436 -279.775212) (xy 411.118393 -279.825994) (xy 411.102505 -279.874893)
			(xy 411.079162 -279.920705) (xy 411.048941 -279.962301) (xy 411.012585 -279.998657) (xy 410.970989 -280.028878)
			(xy 410.925177 -280.052221) (xy 410.876278 -280.068109) (xy 410.825496 -280.076152) (xy 410.77408 -280.076152)
			(xy 410.723298 -280.068109) (xy 410.674399 -280.052221) (xy 410.628587 -280.028878) (xy 410.586991 -279.998657)
			(xy 410.550635 -279.962301) (xy 410.520414 -279.920705) (xy 410.497071 -279.874893) (xy 410.481183 -279.825994)
			(xy 410.47314 -279.775212) (xy 410.154503 -279.775212) (xy 410.146746 -279.822942) (xy 410.131162 -279.869623)
			(xy 410.108291 -279.9132) (xy 410.078726 -279.952544) (xy 410.043233 -279.986636) (xy 410.00273 -280.014592)
			(xy 409.958268 -280.03569) (xy 409.910997 -280.049382) (xy 409.862142 -280.055314) (xy 409.812967 -280.053333)
			(xy 409.764748 -280.043489) (xy 409.718732 -280.026037) (xy 409.676111 -280.00143) (xy 409.63799 -279.970305)
			(xy 409.605355 -279.933468) (xy 409.579052 -279.891872) (xy 409.559761 -279.846596) (xy 409.547984 -279.798812)
			(xy 409.544024 -279.749758) (xy 409.227015 -279.749758) (xy 409.226516 -279.775212) (xy 409.218473 -279.825994)
			(xy 409.202585 -279.874893) (xy 409.179242 -279.920705) (xy 409.149021 -279.962301) (xy 409.112665 -279.998657)
			(xy 409.071069 -280.028878) (xy 409.025257 -280.052221) (xy 408.976358 -280.068109) (xy 408.925576 -280.076152)
			(xy 408.87416 -280.076152) (xy 408.823378 -280.068109) (xy 408.774479 -280.052221) (xy 408.728667 -280.028878)
			(xy 408.687071 -279.998657) (xy 408.650715 -279.962301) (xy 408.620494 -279.920705) (xy 408.597151 -279.874893)
			(xy 408.581263 -279.825994) (xy 408.57322 -279.775212) (xy 408.254583 -279.775212) (xy 408.246826 -279.822942)
			(xy 408.231242 -279.869623) (xy 408.208371 -279.9132) (xy 408.178806 -279.952544) (xy 408.143313 -279.986636)
			(xy 408.10281 -280.014592) (xy 408.058348 -280.03569) (xy 408.011077 -280.049382) (xy 407.962222 -280.055314)
			(xy 407.913047 -280.053333) (xy 407.864828 -280.043489) (xy 407.818812 -280.026037) (xy 407.776191 -280.00143)
			(xy 407.73807 -279.970305) (xy 407.705435 -279.933468) (xy 407.679132 -279.891872) (xy 407.659841 -279.846596)
			(xy 407.648064 -279.798812) (xy 407.644104 -279.749758) (xy 407.327095 -279.749758) (xy 407.326596 -279.775212)
			(xy 407.318553 -279.825994) (xy 407.302665 -279.874893) (xy 407.279322 -279.920705) (xy 407.249101 -279.962301)
			(xy 407.212745 -279.998657) (xy 407.171149 -280.028878) (xy 407.125337 -280.052221) (xy 407.076438 -280.068109)
			(xy 407.025656 -280.076152) (xy 406.97424 -280.076152) (xy 406.923458 -280.068109) (xy 406.874559 -280.052221)
			(xy 406.828747 -280.028878) (xy 406.787151 -279.998657) (xy 406.750795 -279.962301) (xy 406.720574 -279.920705)
			(xy 406.697231 -279.874893) (xy 406.681343 -279.825994) (xy 406.6733 -279.775212) (xy 406.354663 -279.775212)
			(xy 406.346906 -279.822942) (xy 406.331322 -279.869623) (xy 406.308451 -279.9132) (xy 406.278886 -279.952544)
			(xy 406.243393 -279.986636) (xy 406.20289 -280.014592) (xy 406.158428 -280.03569) (xy 406.111157 -280.049382)
			(xy 406.062302 -280.055314) (xy 406.013127 -280.053333) (xy 405.964908 -280.043489) (xy 405.918892 -280.026037)
			(xy 405.876271 -280.00143) (xy 405.83815 -279.970305) (xy 405.805515 -279.933468) (xy 405.779212 -279.891872)
			(xy 405.759921 -279.846596) (xy 405.748144 -279.798812) (xy 405.744184 -279.749758) (xy 405.426921 -279.749758)
			(xy 405.426422 -279.775212) (xy 405.418379 -279.825994) (xy 405.402491 -279.874893) (xy 405.379148 -279.920705)
			(xy 405.348927 -279.962301) (xy 405.312571 -279.998657) (xy 405.270975 -280.028878) (xy 405.225163 -280.052221)
			(xy 405.176264 -280.068109) (xy 405.125482 -280.076152) (xy 405.074066 -280.076152) (xy 405.023284 -280.068109)
			(xy 404.974385 -280.052221) (xy 404.928573 -280.028878) (xy 404.886977 -279.998657) (xy 404.850621 -279.962301)
			(xy 404.8204 -279.920705) (xy 404.797057 -279.874893) (xy 404.781169 -279.825994) (xy 404.773126 -279.775212)
			(xy 404.454489 -279.775212) (xy 404.446732 -279.822942) (xy 404.431148 -279.869623) (xy 404.408277 -279.9132)
			(xy 404.378712 -279.952544) (xy 404.343219 -279.986636) (xy 404.302716 -280.014592) (xy 404.258254 -280.03569)
			(xy 404.210983 -280.049382) (xy 404.162128 -280.055314) (xy 404.112953 -280.053333) (xy 404.064734 -280.043489)
			(xy 404.018718 -280.026037) (xy 403.976097 -280.00143) (xy 403.937976 -279.970305) (xy 403.905341 -279.933468)
			(xy 403.879038 -279.891872) (xy 403.859747 -279.846596) (xy 403.84797 -279.798812) (xy 403.84401 -279.749758)
			(xy 403.527001 -279.749758) (xy 403.526502 -279.775212) (xy 403.518459 -279.825994) (xy 403.502571 -279.874893)
			(xy 403.479228 -279.920705) (xy 403.449007 -279.962301) (xy 403.412651 -279.998657) (xy 403.371055 -280.028878)
			(xy 403.325243 -280.052221) (xy 403.276344 -280.068109) (xy 403.225562 -280.076152) (xy 403.174146 -280.076152)
			(xy 403.123364 -280.068109) (xy 403.074465 -280.052221) (xy 403.028653 -280.028878) (xy 402.987057 -279.998657)
			(xy 402.950701 -279.962301) (xy 402.92048 -279.920705) (xy 402.897137 -279.874893) (xy 402.881249 -279.825994)
			(xy 402.873206 -279.775212) (xy 402.554569 -279.775212) (xy 402.546812 -279.822942) (xy 402.531228 -279.869623)
			(xy 402.508357 -279.9132) (xy 402.478792 -279.952544) (xy 402.443299 -279.986636) (xy 402.402796 -280.014592)
			(xy 402.358334 -280.03569) (xy 402.311063 -280.049382) (xy 402.262208 -280.055314) (xy 402.213033 -280.053333)
			(xy 402.164814 -280.043489) (xy 402.118798 -280.026037) (xy 402.076177 -280.00143) (xy 402.038056 -279.970305)
			(xy 402.005421 -279.933468) (xy 401.979118 -279.891872) (xy 401.959827 -279.846596) (xy 401.94805 -279.798812)
			(xy 401.94409 -279.749758) (xy 401.627081 -279.749758) (xy 401.626582 -279.775212) (xy 401.618539 -279.825994)
			(xy 401.602651 -279.874893) (xy 401.579308 -279.920705) (xy 401.549087 -279.962301) (xy 401.512731 -279.998657)
			(xy 401.471135 -280.028878) (xy 401.425323 -280.052221) (xy 401.376424 -280.068109) (xy 401.325642 -280.076152)
			(xy 401.274226 -280.076152) (xy 401.223444 -280.068109) (xy 401.174545 -280.052221) (xy 401.128733 -280.028878)
			(xy 401.087137 -279.998657) (xy 401.050781 -279.962301) (xy 401.02056 -279.920705) (xy 400.997217 -279.874893)
			(xy 400.981329 -279.825994) (xy 400.973286 -279.775212) (xy 400.654649 -279.775212) (xy 400.646892 -279.822942)
			(xy 400.631308 -279.869623) (xy 400.608437 -279.9132) (xy 400.578872 -279.952544) (xy 400.543379 -279.986636)
			(xy 400.502876 -280.014592) (xy 400.458414 -280.03569) (xy 400.411143 -280.049382) (xy 400.362288 -280.055314)
			(xy 400.313113 -280.053333) (xy 400.264894 -280.043489) (xy 400.218878 -280.026037) (xy 400.176257 -280.00143)
			(xy 400.138136 -279.970305) (xy 400.105501 -279.933468) (xy 400.079198 -279.891872) (xy 400.059907 -279.846596)
			(xy 400.04813 -279.798812) (xy 400.04417 -279.749758) (xy 399.727161 -279.749758) (xy 399.726662 -279.775212)
			(xy 399.718619 -279.825994) (xy 399.702731 -279.874893) (xy 399.679388 -279.920705) (xy 399.649167 -279.962301)
			(xy 399.612811 -279.998657) (xy 399.571215 -280.028878) (xy 399.525403 -280.052221) (xy 399.476504 -280.068109)
			(xy 399.425722 -280.076152) (xy 399.374306 -280.076152) (xy 399.323524 -280.068109) (xy 399.274625 -280.052221)
			(xy 399.228813 -280.028878) (xy 399.187217 -279.998657) (xy 399.150861 -279.962301) (xy 399.12064 -279.920705)
			(xy 399.097297 -279.874893) (xy 399.081409 -279.825994) (xy 399.073366 -279.775212) (xy 398.754475 -279.775212)
			(xy 398.746718 -279.822942) (xy 398.731134 -279.869623) (xy 398.708263 -279.9132) (xy 398.678698 -279.952544)
			(xy 398.643205 -279.986636) (xy 398.602702 -280.014592) (xy 398.55824 -280.03569) (xy 398.510969 -280.049382)
			(xy 398.462114 -280.055314) (xy 398.412939 -280.053333) (xy 398.36472 -280.043489) (xy 398.318704 -280.026037)
			(xy 398.276083 -280.00143) (xy 398.237962 -279.970305) (xy 398.205327 -279.933468) (xy 398.179024 -279.891872)
			(xy 398.159733 -279.846596) (xy 398.147956 -279.798812) (xy 398.143996 -279.749758) (xy 397.826987 -279.749758)
			(xy 397.826488 -279.775212) (xy 397.818445 -279.825994) (xy 397.802557 -279.874893) (xy 397.779214 -279.920705)
			(xy 397.748993 -279.962301) (xy 397.712637 -279.998657) (xy 397.671041 -280.028878) (xy 397.625229 -280.052221)
			(xy 397.57633 -280.068109) (xy 397.525548 -280.076152) (xy 397.474132 -280.076152) (xy 397.42335 -280.068109)
			(xy 397.374451 -280.052221) (xy 397.328639 -280.028878) (xy 397.287043 -279.998657) (xy 397.250687 -279.962301)
			(xy 397.220466 -279.920705) (xy 397.197123 -279.874893) (xy 397.181235 -279.825994) (xy 397.173192 -279.775212)
			(xy 396.854555 -279.775212) (xy 396.846798 -279.822942) (xy 396.831214 -279.869623) (xy 396.808343 -279.9132)
			(xy 396.778778 -279.952544) (xy 396.743285 -279.986636) (xy 396.702782 -280.014592) (xy 396.65832 -280.03569)
			(xy 396.611049 -280.049382) (xy 396.562194 -280.055314) (xy 396.513019 -280.053333) (xy 396.4648 -280.043489)
			(xy 396.418784 -280.026037) (xy 396.376163 -280.00143) (xy 396.338042 -279.970305) (xy 396.305407 -279.933468)
			(xy 396.279104 -279.891872) (xy 396.259813 -279.846596) (xy 396.248036 -279.798812) (xy 396.244076 -279.749758)
			(xy 395.927067 -279.749758) (xy 395.926568 -279.775212) (xy 395.918525 -279.825994) (xy 395.902637 -279.874893)
			(xy 395.879294 -279.920705) (xy 395.849073 -279.962301) (xy 395.812717 -279.998657) (xy 395.771121 -280.028878)
			(xy 395.725309 -280.052221) (xy 395.67641 -280.068109) (xy 395.625628 -280.076152) (xy 395.574212 -280.076152)
			(xy 395.52343 -280.068109) (xy 395.474531 -280.052221) (xy 395.428719 -280.028878) (xy 395.387123 -279.998657)
			(xy 395.350767 -279.962301) (xy 395.320546 -279.920705) (xy 395.297203 -279.874893) (xy 395.281315 -279.825994)
			(xy 395.273272 -279.775212) (xy 394.954635 -279.775212) (xy 394.946878 -279.822942) (xy 394.931294 -279.869623)
			(xy 394.908423 -279.9132) (xy 394.878858 -279.952544) (xy 394.843365 -279.986636) (xy 394.802862 -280.014592)
			(xy 394.7584 -280.03569) (xy 394.711129 -280.049382) (xy 394.662274 -280.055314) (xy 394.613099 -280.053333)
			(xy 394.56488 -280.043489) (xy 394.518864 -280.026037) (xy 394.476243 -280.00143) (xy 394.438122 -279.970305)
			(xy 394.405487 -279.933468) (xy 394.379184 -279.891872) (xy 394.359893 -279.846596) (xy 394.348116 -279.798812)
			(xy 394.344156 -279.749758) (xy 394.027147 -279.749758) (xy 394.026648 -279.775212) (xy 394.018605 -279.825994)
			(xy 394.002717 -279.874893) (xy 393.979374 -279.920705) (xy 393.949153 -279.962301) (xy 393.912797 -279.998657)
			(xy 393.871201 -280.028878) (xy 393.825389 -280.052221) (xy 393.77649 -280.068109) (xy 393.725708 -280.076152)
			(xy 393.674292 -280.076152) (xy 393.62351 -280.068109) (xy 393.574611 -280.052221) (xy 393.528799 -280.028878)
			(xy 393.487203 -279.998657) (xy 393.450847 -279.962301) (xy 393.420626 -279.920705) (xy 393.397283 -279.874893)
			(xy 393.381395 -279.825994) (xy 393.373352 -279.775212) (xy 393.053706 -279.775212) (xy 393.052844 -279.791095)
			(xy 393.042171 -279.83958) (xy 393.023794 -279.8857) (xy 392.998197 -279.928238) (xy 392.966055 -279.966075)
			(xy 392.928215 -279.998213) (xy 392.885674 -280.023806) (xy 392.839553 -280.042179) (xy 392.791068 -280.052848)
			(xy 392.741494 -280.055532) (xy 392.69214 -280.050161) (xy 392.644305 -280.036875) (xy 392.599249 -280.016025)
			(xy 392.558161 -279.98816) (xy 392.522121 -279.954015) (xy 392.492081 -279.914489) (xy 392.468832 -279.870623)
			(xy 392.452986 -279.823574) (xy 392.444961 -279.774581) (xy 392.444478 -279.749758) (xy 392.444649 -279.735575)
			(xy 392.447325 -279.707335) (xy 392.449812 -279.69337) (xy 392.452098 -279.680924) (xy 392.444732 -279.657302)
			(xy 392.367262 -279.579832) (xy 392.34364 -279.572466) (xy 392.331194 -279.574752) (xy 392.317228 -279.577225)
			(xy 392.288988 -279.579899) (xy 392.274806 -279.580086) (xy 392.249546 -279.579638) (xy 392.199715 -279.571323)
			(xy 392.151933 -279.55492) (xy 392.107502 -279.530876) (xy 392.067634 -279.499847) (xy 392.033418 -279.462679)
			(xy 392.005786 -279.420385) (xy 391.985492 -279.374121) (xy 391.97309 -279.325147) (xy 391.968918 -279.2748)
			(xy 391.630154 -279.2748) (xy 391.629659 -279.299385) (xy 391.621764 -279.347962) (xy 391.60618 -279.394643)
			(xy 391.583309 -279.43822) (xy 391.553744 -279.477564) (xy 391.518251 -279.511656) (xy 391.477748 -279.539612)
			(xy 391.433286 -279.56071) (xy 391.386015 -279.574402) (xy 391.33716 -279.580334) (xy 391.287985 -279.578353)
			(xy 391.239766 -279.568509) (xy 391.19375 -279.551057) (xy 391.151129 -279.52645) (xy 391.113008 -279.495325)
			(xy 391.080373 -279.458488) (xy 391.05407 -279.416892) (xy 391.034779 -279.371616) (xy 391.023002 -279.323832)
			(xy 391.019042 -279.274778) (xy 390.680194 -279.274778) (xy 390.679699 -279.299385) (xy 390.671804 -279.347962)
			(xy 390.65622 -279.394643) (xy 390.633349 -279.43822) (xy 390.603784 -279.477564) (xy 390.568291 -279.511656)
			(xy 390.527788 -279.539612) (xy 390.483326 -279.56071) (xy 390.436055 -279.574402) (xy 390.3872 -279.580334)
			(xy 390.338025 -279.578353) (xy 390.289806 -279.568509) (xy 390.24379 -279.551057) (xy 390.201169 -279.52645)
			(xy 390.163048 -279.495325) (xy 390.130413 -279.458488) (xy 390.10411 -279.416892) (xy 390.084819 -279.371616)
			(xy 390.073042 -279.323832) (xy 390.069082 -279.274778) (xy 389.730234 -279.274778) (xy 389.729739 -279.299385)
			(xy 389.721844 -279.347962) (xy 389.70626 -279.394643) (xy 389.683389 -279.43822) (xy 389.653824 -279.477564)
			(xy 389.618331 -279.511656) (xy 389.577828 -279.539612) (xy 389.533366 -279.56071) (xy 389.486095 -279.574402)
			(xy 389.43724 -279.580334) (xy 389.388065 -279.578353) (xy 389.339846 -279.568509) (xy 389.29383 -279.551057)
			(xy 389.251209 -279.52645) (xy 389.213088 -279.495325) (xy 389.180453 -279.458488) (xy 389.15415 -279.416892)
			(xy 389.134859 -279.371616) (xy 389.123082 -279.323832) (xy 389.119122 -279.274778) (xy 388.780274 -279.274778)
			(xy 388.779779 -279.299385) (xy 388.771884 -279.347962) (xy 388.7563 -279.394643) (xy 388.733429 -279.43822)
			(xy 388.703864 -279.477564) (xy 388.668371 -279.511656) (xy 388.627868 -279.539612) (xy 388.583406 -279.56071)
			(xy 388.536135 -279.574402) (xy 388.48728 -279.580334) (xy 388.438105 -279.578353) (xy 388.389886 -279.568509)
			(xy 388.34387 -279.551057) (xy 388.301249 -279.52645) (xy 388.263128 -279.495325) (xy 388.230493 -279.458488)
			(xy 388.20419 -279.416892) (xy 388.184899 -279.371616) (xy 388.173122 -279.323832) (xy 388.169162 -279.274778)
			(xy 387.830314 -279.274778) (xy 387.829819 -279.299385) (xy 387.821924 -279.347962) (xy 387.80634 -279.394643)
			(xy 387.783469 -279.43822) (xy 387.753904 -279.477564) (xy 387.718411 -279.511656) (xy 387.677908 -279.539612)
			(xy 387.633446 -279.56071) (xy 387.586175 -279.574402) (xy 387.53732 -279.580334) (xy 387.488145 -279.578353)
			(xy 387.439926 -279.568509) (xy 387.39391 -279.551057) (xy 387.351289 -279.52645) (xy 387.313168 -279.495325)
			(xy 387.280533 -279.458488) (xy 387.25423 -279.416892) (xy 387.234939 -279.371616) (xy 387.223162 -279.323832)
			(xy 387.219202 -279.274778) (xy 386.880354 -279.274778) (xy 386.879859 -279.299385) (xy 386.871964 -279.347962)
			(xy 386.85638 -279.394643) (xy 386.833509 -279.43822) (xy 386.803944 -279.477564) (xy 386.768451 -279.511656)
			(xy 386.727948 -279.539612) (xy 386.683486 -279.56071) (xy 386.636215 -279.574402) (xy 386.58736 -279.580334)
			(xy 386.538185 -279.578353) (xy 386.489966 -279.568509) (xy 386.44395 -279.551057) (xy 386.401329 -279.52645)
			(xy 386.363208 -279.495325) (xy 386.330573 -279.458488) (xy 386.30427 -279.416892) (xy 386.284979 -279.371616)
			(xy 386.273202 -279.323832) (xy 386.269242 -279.274778) (xy 385.93014 -279.274778) (xy 385.929645 -279.299385)
			(xy 385.92175 -279.347962) (xy 385.906166 -279.394643) (xy 385.883295 -279.43822) (xy 385.85373 -279.477564)
			(xy 385.818237 -279.511656) (xy 385.777734 -279.539612) (xy 385.733272 -279.56071) (xy 385.686001 -279.574402)
			(xy 385.637146 -279.580334) (xy 385.587971 -279.578353) (xy 385.539752 -279.568509) (xy 385.493736 -279.551057)
			(xy 385.451115 -279.52645) (xy 385.412994 -279.495325) (xy 385.380359 -279.458488) (xy 385.354056 -279.416892)
			(xy 385.334765 -279.371616) (xy 385.322988 -279.323832) (xy 385.319028 -279.274778) (xy 384.98018 -279.274778)
			(xy 384.979685 -279.299385) (xy 384.97179 -279.347962) (xy 384.956206 -279.394643) (xy 384.933335 -279.43822)
			(xy 384.90377 -279.477564) (xy 384.868277 -279.511656) (xy 384.827774 -279.539612) (xy 384.783312 -279.56071)
			(xy 384.736041 -279.574402) (xy 384.687186 -279.580334) (xy 384.638011 -279.578353) (xy 384.589792 -279.568509)
			(xy 384.543776 -279.551057) (xy 384.501155 -279.52645) (xy 384.463034 -279.495325) (xy 384.430399 -279.458488)
			(xy 384.404096 -279.416892) (xy 384.384805 -279.371616) (xy 384.373028 -279.323832) (xy 384.369068 -279.274778)
			(xy 383.78638 -279.274778) (xy 383.78638 -280.224738) (xy 384.369068 -280.224738) (xy 384.373028 -280.175684)
			(xy 384.384805 -280.1279) (xy 384.404096 -280.082624) (xy 384.430399 -280.041028) (xy 384.463034 -280.004191)
			(xy 384.501155 -279.973066) (xy 384.543776 -279.948459) (xy 384.589792 -279.931007) (xy 384.638011 -279.921163)
			(xy 384.687186 -279.919182) (xy 384.736041 -279.925114) (xy 384.783312 -279.938806) (xy 384.827774 -279.959904)
			(xy 384.868277 -279.98786) (xy 384.90377 -280.021952) (xy 384.933335 -280.061296) (xy 384.956206 -280.104873)
			(xy 384.97179 -280.151554) (xy 384.979685 -280.200131) (xy 384.98018 -280.224738) (xy 385.319028 -280.224738)
			(xy 385.322988 -280.175684) (xy 385.334765 -280.1279) (xy 385.354056 -280.082624) (xy 385.380359 -280.041028)
			(xy 385.412994 -280.004191) (xy 385.451115 -279.973066) (xy 385.493736 -279.948459) (xy 385.539752 -279.931007)
			(xy 385.587971 -279.921163) (xy 385.637146 -279.919182) (xy 385.686001 -279.925114) (xy 385.733272 -279.938806)
			(xy 385.777734 -279.959904) (xy 385.818237 -279.98786) (xy 385.85373 -280.021952) (xy 385.883295 -280.061296)
			(xy 385.906166 -280.104873) (xy 385.92175 -280.151554) (xy 385.929645 -280.200131) (xy 385.93014 -280.224738)
			(xy 386.269242 -280.224738) (xy 386.273202 -280.175684) (xy 386.284979 -280.1279) (xy 386.30427 -280.082624)
			(xy 386.330573 -280.041028) (xy 386.363208 -280.004191) (xy 386.401329 -279.973066) (xy 386.44395 -279.948459)
			(xy 386.489966 -279.931007) (xy 386.538185 -279.921163) (xy 386.58736 -279.919182) (xy 386.636215 -279.925114)
			(xy 386.683486 -279.938806) (xy 386.727948 -279.959904) (xy 386.768451 -279.98786) (xy 386.803944 -280.021952)
			(xy 386.833509 -280.061296) (xy 386.85638 -280.104873) (xy 386.871964 -280.151554) (xy 386.879859 -280.200131)
			(xy 386.880354 -280.224738) (xy 387.219202 -280.224738) (xy 387.223162 -280.175684) (xy 387.234939 -280.1279)
			(xy 387.25423 -280.082624) (xy 387.280533 -280.041028) (xy 387.313168 -280.004191) (xy 387.351289 -279.973066)
			(xy 387.39391 -279.948459) (xy 387.439926 -279.931007) (xy 387.488145 -279.921163) (xy 387.53732 -279.919182)
			(xy 387.586175 -279.925114) (xy 387.633446 -279.938806) (xy 387.677908 -279.959904) (xy 387.718411 -279.98786)
			(xy 387.753904 -280.021952) (xy 387.783469 -280.061296) (xy 387.80634 -280.104873) (xy 387.821924 -280.151554)
			(xy 387.829819 -280.200131) (xy 387.830314 -280.224738) (xy 388.169162 -280.224738) (xy 388.173122 -280.175684)
			(xy 388.184899 -280.1279) (xy 388.20419 -280.082624) (xy 388.230493 -280.041028) (xy 388.263128 -280.004191)
			(xy 388.301249 -279.973066) (xy 388.34387 -279.948459) (xy 388.389886 -279.931007) (xy 388.438105 -279.921163)
			(xy 388.48728 -279.919182) (xy 388.536135 -279.925114) (xy 388.583406 -279.938806) (xy 388.627868 -279.959904)
			(xy 388.668371 -279.98786) (xy 388.703864 -280.021952) (xy 388.733429 -280.061296) (xy 388.7563 -280.104873)
			(xy 388.771884 -280.151554) (xy 388.779779 -280.200131) (xy 388.780274 -280.224738) (xy 389.119122 -280.224738)
			(xy 389.123082 -280.175684) (xy 389.134859 -280.1279) (xy 389.15415 -280.082624) (xy 389.180453 -280.041028)
			(xy 389.213088 -280.004191) (xy 389.251209 -279.973066) (xy 389.29383 -279.948459) (xy 389.339846 -279.931007)
			(xy 389.388065 -279.921163) (xy 389.43724 -279.919182) (xy 389.486095 -279.925114) (xy 389.533366 -279.938806)
			(xy 389.577828 -279.959904) (xy 389.618331 -279.98786) (xy 389.653824 -280.021952) (xy 389.683389 -280.061296)
			(xy 389.70626 -280.104873) (xy 389.721844 -280.151554) (xy 389.729739 -280.200131) (xy 389.730234 -280.224738)
			(xy 390.069082 -280.224738) (xy 390.073042 -280.175684) (xy 390.084819 -280.1279) (xy 390.10411 -280.082624)
			(xy 390.130413 -280.041028) (xy 390.163048 -280.004191) (xy 390.201169 -279.973066) (xy 390.24379 -279.948459)
			(xy 390.289806 -279.931007) (xy 390.338025 -279.921163) (xy 390.3872 -279.919182) (xy 390.436055 -279.925114)
			(xy 390.483326 -279.938806) (xy 390.527788 -279.959904) (xy 390.568291 -279.98786) (xy 390.603784 -280.021952)
			(xy 390.633349 -280.061296) (xy 390.65622 -280.104873) (xy 390.671804 -280.151554) (xy 390.679699 -280.200131)
			(xy 390.680194 -280.224738) (xy 391.019042 -280.224738) (xy 391.023002 -280.175684) (xy 391.034779 -280.1279)
			(xy 391.05407 -280.082624) (xy 391.080373 -280.041028) (xy 391.113008 -280.004191) (xy 391.151129 -279.973066)
			(xy 391.19375 -279.948459) (xy 391.239766 -279.931007) (xy 391.287985 -279.921163) (xy 391.33716 -279.919182)
			(xy 391.386015 -279.925114) (xy 391.433286 -279.938806) (xy 391.477748 -279.959904) (xy 391.518251 -279.98786)
			(xy 391.553744 -280.021952) (xy 391.583309 -280.061296) (xy 391.60618 -280.104873) (xy 391.621764 -280.151554)
			(xy 391.629659 -280.200131) (xy 391.630154 -280.224738) (xy 391.629659 -280.249345) (xy 391.621764 -280.297922)
			(xy 391.60618 -280.344603) (xy 391.583309 -280.38818) (xy 391.553744 -280.427524) (xy 391.518251 -280.461616)
			(xy 391.477748 -280.489572) (xy 391.433286 -280.51067) (xy 391.386015 -280.524362) (xy 391.33716 -280.530294)
			(xy 391.287985 -280.528313) (xy 391.239766 -280.518469) (xy 391.19375 -280.501017) (xy 391.151129 -280.47641)
			(xy 391.113008 -280.445285) (xy 391.080373 -280.408448) (xy 391.05407 -280.366852) (xy 391.034779 -280.321576)
			(xy 391.023002 -280.273792) (xy 391.019042 -280.224738) (xy 390.680194 -280.224738) (xy 390.679699 -280.249345)
			(xy 390.671804 -280.297922) (xy 390.65622 -280.344603) (xy 390.633349 -280.38818) (xy 390.603784 -280.427524)
			(xy 390.568291 -280.461616) (xy 390.527788 -280.489572) (xy 390.483326 -280.51067) (xy 390.436055 -280.524362)
			(xy 390.3872 -280.530294) (xy 390.338025 -280.528313) (xy 390.289806 -280.518469) (xy 390.24379 -280.501017)
			(xy 390.201169 -280.47641) (xy 390.163048 -280.445285) (xy 390.130413 -280.408448) (xy 390.10411 -280.366852)
			(xy 390.084819 -280.321576) (xy 390.073042 -280.273792) (xy 390.069082 -280.224738) (xy 389.730234 -280.224738)
			(xy 389.729739 -280.249345) (xy 389.721844 -280.297922) (xy 389.70626 -280.344603) (xy 389.683389 -280.38818)
			(xy 389.653824 -280.427524) (xy 389.618331 -280.461616) (xy 389.577828 -280.489572) (xy 389.533366 -280.51067)
			(xy 389.486095 -280.524362) (xy 389.43724 -280.530294) (xy 389.388065 -280.528313) (xy 389.339846 -280.518469)
			(xy 389.29383 -280.501017) (xy 389.251209 -280.47641) (xy 389.213088 -280.445285) (xy 389.180453 -280.408448)
			(xy 389.15415 -280.366852) (xy 389.134859 -280.321576) (xy 389.123082 -280.273792) (xy 389.119122 -280.224738)
			(xy 388.780274 -280.224738) (xy 388.779779 -280.249345) (xy 388.771884 -280.297922) (xy 388.7563 -280.344603)
			(xy 388.733429 -280.38818) (xy 388.703864 -280.427524) (xy 388.668371 -280.461616) (xy 388.627868 -280.489572)
			(xy 388.583406 -280.51067) (xy 388.536135 -280.524362) (xy 388.48728 -280.530294) (xy 388.438105 -280.528313)
			(xy 388.389886 -280.518469) (xy 388.34387 -280.501017) (xy 388.301249 -280.47641) (xy 388.263128 -280.445285)
			(xy 388.230493 -280.408448) (xy 388.20419 -280.366852) (xy 388.184899 -280.321576) (xy 388.173122 -280.273792)
			(xy 388.169162 -280.224738) (xy 387.830314 -280.224738) (xy 387.829819 -280.249345) (xy 387.821924 -280.297922)
			(xy 387.80634 -280.344603) (xy 387.783469 -280.38818) (xy 387.753904 -280.427524) (xy 387.718411 -280.461616)
			(xy 387.677908 -280.489572) (xy 387.633446 -280.51067) (xy 387.586175 -280.524362) (xy 387.53732 -280.530294)
			(xy 387.488145 -280.528313) (xy 387.439926 -280.518469) (xy 387.39391 -280.501017) (xy 387.351289 -280.47641)
			(xy 387.313168 -280.445285) (xy 387.280533 -280.408448) (xy 387.25423 -280.366852) (xy 387.234939 -280.321576)
			(xy 387.223162 -280.273792) (xy 387.219202 -280.224738) (xy 386.880354 -280.224738) (xy 386.879859 -280.249345)
			(xy 386.871964 -280.297922) (xy 386.85638 -280.344603) (xy 386.833509 -280.38818) (xy 386.803944 -280.427524)
			(xy 386.768451 -280.461616) (xy 386.727948 -280.489572) (xy 386.683486 -280.51067) (xy 386.636215 -280.524362)
			(xy 386.58736 -280.530294) (xy 386.538185 -280.528313) (xy 386.489966 -280.518469) (xy 386.44395 -280.501017)
			(xy 386.401329 -280.47641) (xy 386.363208 -280.445285) (xy 386.330573 -280.408448) (xy 386.30427 -280.366852)
			(xy 386.284979 -280.321576) (xy 386.273202 -280.273792) (xy 386.269242 -280.224738) (xy 385.93014 -280.224738)
			(xy 385.929645 -280.249345) (xy 385.92175 -280.297922) (xy 385.906166 -280.344603) (xy 385.883295 -280.38818)
			(xy 385.85373 -280.427524) (xy 385.818237 -280.461616) (xy 385.777734 -280.489572) (xy 385.733272 -280.51067)
			(xy 385.686001 -280.524362) (xy 385.637146 -280.530294) (xy 385.587971 -280.528313) (xy 385.539752 -280.518469)
			(xy 385.493736 -280.501017) (xy 385.451115 -280.47641) (xy 385.412994 -280.445285) (xy 385.380359 -280.408448)
			(xy 385.354056 -280.366852) (xy 385.334765 -280.321576) (xy 385.322988 -280.273792) (xy 385.319028 -280.224738)
			(xy 384.98018 -280.224738) (xy 384.979685 -280.249345) (xy 384.97179 -280.297922) (xy 384.956206 -280.344603)
			(xy 384.933335 -280.38818) (xy 384.90377 -280.427524) (xy 384.868277 -280.461616) (xy 384.827774 -280.489572)
			(xy 384.783312 -280.51067) (xy 384.736041 -280.524362) (xy 384.687186 -280.530294) (xy 384.638011 -280.528313)
			(xy 384.589792 -280.518469) (xy 384.543776 -280.501017) (xy 384.501155 -280.47641) (xy 384.463034 -280.445285)
			(xy 384.430399 -280.408448) (xy 384.404096 -280.366852) (xy 384.384805 -280.321576) (xy 384.373028 -280.273792)
			(xy 384.369068 -280.224738) (xy 383.78638 -280.224738) (xy 383.78638 -281.174952) (xy 384.369068 -281.174952)
			(xy 384.373028 -281.125898) (xy 384.384805 -281.078114) (xy 384.404096 -281.032838) (xy 384.430399 -280.991242)
			(xy 384.463034 -280.954405) (xy 384.501155 -280.92328) (xy 384.543776 -280.898673) (xy 384.589792 -280.881221)
			(xy 384.638011 -280.871377) (xy 384.687186 -280.869396) (xy 384.736041 -280.875328) (xy 384.783312 -280.88902)
			(xy 384.827774 -280.910118) (xy 384.868277 -280.938074) (xy 384.90377 -280.972166) (xy 384.933335 -281.01151)
			(xy 384.956206 -281.055087) (xy 384.97179 -281.101768) (xy 384.979685 -281.150345) (xy 384.98018 -281.174952)
			(xy 385.319028 -281.174952) (xy 385.322988 -281.125898) (xy 385.334765 -281.078114) (xy 385.354056 -281.032838)
			(xy 385.380359 -280.991242) (xy 385.412994 -280.954405) (xy 385.451115 -280.92328) (xy 385.493736 -280.898673)
			(xy 385.539752 -280.881221) (xy 385.587971 -280.871377) (xy 385.637146 -280.869396) (xy 385.686001 -280.875328)
			(xy 385.733272 -280.88902) (xy 385.777734 -280.910118) (xy 385.818237 -280.938074) (xy 385.85373 -280.972166)
			(xy 385.883295 -281.01151) (xy 385.906166 -281.055087) (xy 385.92175 -281.101768) (xy 385.929645 -281.150345)
			(xy 385.93014 -281.174952) (xy 386.269242 -281.174952) (xy 386.273202 -281.125898) (xy 386.284979 -281.078114)
			(xy 386.30427 -281.032838) (xy 386.330573 -280.991242) (xy 386.363208 -280.954405) (xy 386.401329 -280.92328)
			(xy 386.44395 -280.898673) (xy 386.489966 -280.881221) (xy 386.538185 -280.871377) (xy 386.58736 -280.869396)
			(xy 386.636215 -280.875328) (xy 386.683486 -280.88902) (xy 386.727948 -280.910118) (xy 386.768451 -280.938074)
			(xy 386.803944 -280.972166) (xy 386.833509 -281.01151) (xy 386.85638 -281.055087) (xy 386.871964 -281.101768)
			(xy 386.879859 -281.150345) (xy 386.880354 -281.174952) (xy 387.219202 -281.174952) (xy 387.223162 -281.125898)
			(xy 387.234939 -281.078114) (xy 387.25423 -281.032838) (xy 387.280533 -280.991242) (xy 387.313168 -280.954405)
			(xy 387.351289 -280.92328) (xy 387.39391 -280.898673) (xy 387.439926 -280.881221) (xy 387.488145 -280.871377)
			(xy 387.53732 -280.869396) (xy 387.586175 -280.875328) (xy 387.633446 -280.88902) (xy 387.677908 -280.910118)
			(xy 387.718411 -280.938074) (xy 387.753904 -280.972166) (xy 387.783469 -281.01151) (xy 387.80634 -281.055087)
			(xy 387.821924 -281.101768) (xy 387.829819 -281.150345) (xy 387.830314 -281.174952) (xy 388.169162 -281.174952)
			(xy 388.173122 -281.125898) (xy 388.184899 -281.078114) (xy 388.20419 -281.032838) (xy 388.230493 -280.991242)
			(xy 388.263128 -280.954405) (xy 388.301249 -280.92328) (xy 388.34387 -280.898673) (xy 388.389886 -280.881221)
			(xy 388.438105 -280.871377) (xy 388.48728 -280.869396) (xy 388.536135 -280.875328) (xy 388.583406 -280.88902)
			(xy 388.627868 -280.910118) (xy 388.668371 -280.938074) (xy 388.703864 -280.972166) (xy 388.733429 -281.01151)
			(xy 388.7563 -281.055087) (xy 388.771884 -281.101768) (xy 388.779779 -281.150345) (xy 388.780274 -281.174952)
			(xy 389.119122 -281.174952) (xy 389.123082 -281.125898) (xy 389.134859 -281.078114) (xy 389.15415 -281.032838)
			(xy 389.180453 -280.991242) (xy 389.213088 -280.954405) (xy 389.251209 -280.92328) (xy 389.29383 -280.898673)
			(xy 389.339846 -280.881221) (xy 389.388065 -280.871377) (xy 389.43724 -280.869396) (xy 389.486095 -280.875328)
			(xy 389.533366 -280.88902) (xy 389.577828 -280.910118) (xy 389.618331 -280.938074) (xy 389.653824 -280.972166)
			(xy 389.683389 -281.01151) (xy 389.70626 -281.055087) (xy 389.721844 -281.101768) (xy 389.729739 -281.150345)
			(xy 389.730234 -281.174952) (xy 390.069082 -281.174952) (xy 390.073042 -281.125898) (xy 390.084819 -281.078114)
			(xy 390.10411 -281.032838) (xy 390.130413 -280.991242) (xy 390.163048 -280.954405) (xy 390.201169 -280.92328)
			(xy 390.24379 -280.898673) (xy 390.289806 -280.881221) (xy 390.338025 -280.871377) (xy 390.3872 -280.869396)
			(xy 390.436055 -280.875328) (xy 390.483326 -280.88902) (xy 390.527788 -280.910118) (xy 390.568291 -280.938074)
			(xy 390.603784 -280.972166) (xy 390.633349 -281.01151) (xy 390.65622 -281.055087) (xy 390.671804 -281.101768)
			(xy 390.679699 -281.150345) (xy 390.680194 -281.174952) (xy 391.019042 -281.174952) (xy 391.023002 -281.125898)
			(xy 391.034779 -281.078114) (xy 391.05407 -281.032838) (xy 391.080373 -280.991242) (xy 391.113008 -280.954405)
			(xy 391.151129 -280.92328) (xy 391.19375 -280.898673) (xy 391.239766 -280.881221) (xy 391.287985 -280.871377)
			(xy 391.33716 -280.869396) (xy 391.386015 -280.875328) (xy 391.433286 -280.88902) (xy 391.477748 -280.910118)
			(xy 391.518251 -280.938074) (xy 391.553744 -280.972166) (xy 391.583309 -281.01151) (xy 391.60618 -281.055087)
			(xy 391.621764 -281.101768) (xy 391.629659 -281.150345) (xy 391.629989 -281.166729) (xy 391.969032 -281.166729)
			(xy 391.974399 -281.117368) (xy 391.987681 -281.069526) (xy 392.008528 -281.024463) (xy 392.036391 -280.983367)
			(xy 392.070536 -280.94732) (xy 392.110063 -280.917272) (xy 392.15393 -280.894015) (xy 392.200983 -280.878161)
			(xy 392.24998 -280.870129) (xy 392.274806 -280.869644) (xy 392.288989 -280.869819) (xy 392.317229 -280.872492)
			(xy 392.331194 -280.874978) (xy 392.345156 -280.877182) (xy 392.373296 -280.874604) (xy 392.399651 -280.864411)
			(xy 392.422203 -280.847384) (xy 392.439224 -280.824827) (xy 392.44941 -280.798469) (xy 392.451981 -280.770329)
			(xy 392.449812 -280.75636) (xy 392.447324 -280.742332) (xy 392.444654 -280.713964) (xy 392.444478 -280.699718)
			(xy 392.444959 -280.674895) (xy 392.452988 -280.625903) (xy 392.468837 -280.578855) (xy 392.492089 -280.534991)
			(xy 392.522132 -280.495468) (xy 392.558173 -280.461325) (xy 392.599263 -280.433463) (xy 392.64432 -280.412615)
			(xy 392.692156 -280.399332) (xy 392.74151 -280.393963) (xy 392.791083 -280.39665) (xy 392.839569 -280.407321)
			(xy 392.885689 -280.425696) (xy 392.928228 -280.451291) (xy 392.966066 -280.483431) (xy 392.998207 -280.521269)
			(xy 393.023802 -280.563808) (xy 393.042177 -280.609928) (xy 393.052849 -280.658413) (xy 393.055537 -280.707986)
			(xy 393.05364 -280.725426) (xy 393.373352 -280.725426) (xy 393.373352 -280.67401) (xy 393.381395 -280.623228)
			(xy 393.397283 -280.574329) (xy 393.420626 -280.528517) (xy 393.450847 -280.486921) (xy 393.487203 -280.450565)
			(xy 393.528799 -280.420344) (xy 393.574611 -280.397001) (xy 393.62351 -280.381113) (xy 393.674292 -280.37307)
			(xy 393.725708 -280.37307) (xy 393.77649 -280.381113) (xy 393.825389 -280.397001) (xy 393.871201 -280.420344)
			(xy 393.912797 -280.450565) (xy 393.949153 -280.486921) (xy 393.979374 -280.528517) (xy 394.002717 -280.574329)
			(xy 394.018605 -280.623228) (xy 394.026648 -280.67401) (xy 394.027152 -280.699718) (xy 394.344156 -280.699718)
			(xy 394.348116 -280.650664) (xy 394.359893 -280.60288) (xy 394.379184 -280.557604) (xy 394.405487 -280.516008)
			(xy 394.438122 -280.479171) (xy 394.476243 -280.448046) (xy 394.518864 -280.423439) (xy 394.56488 -280.405987)
			(xy 394.613099 -280.396143) (xy 394.662274 -280.394162) (xy 394.711129 -280.400094) (xy 394.7584 -280.413786)
			(xy 394.802862 -280.434884) (xy 394.843365 -280.46284) (xy 394.878858 -280.496932) (xy 394.908423 -280.536276)
			(xy 394.931294 -280.579853) (xy 394.946878 -280.626534) (xy 394.954773 -280.675111) (xy 394.955268 -280.699718)
			(xy 394.954773 -280.724325) (xy 394.954594 -280.725426) (xy 395.273272 -280.725426) (xy 395.273272 -280.67401)
			(xy 395.281315 -280.623228) (xy 395.297203 -280.574329) (xy 395.320546 -280.528517) (xy 395.350767 -280.486921)
			(xy 395.387123 -280.450565) (xy 395.428719 -280.420344) (xy 395.474531 -280.397001) (xy 395.52343 -280.381113)
			(xy 395.574212 -280.37307) (xy 395.625628 -280.37307) (xy 395.67641 -280.381113) (xy 395.725309 -280.397001)
			(xy 395.771121 -280.420344) (xy 395.812717 -280.450565) (xy 395.849073 -280.486921) (xy 395.879294 -280.528517)
			(xy 395.902637 -280.574329) (xy 395.918525 -280.623228) (xy 395.926568 -280.67401) (xy 395.927072 -280.699718)
			(xy 396.244076 -280.699718) (xy 396.248036 -280.650664) (xy 396.259813 -280.60288) (xy 396.279104 -280.557604)
			(xy 396.305407 -280.516008) (xy 396.338042 -280.479171) (xy 396.376163 -280.448046) (xy 396.418784 -280.423439)
			(xy 396.4648 -280.405987) (xy 396.513019 -280.396143) (xy 396.562194 -280.394162) (xy 396.611049 -280.400094)
			(xy 396.65832 -280.413786) (xy 396.702782 -280.434884) (xy 396.743285 -280.46284) (xy 396.778778 -280.496932)
			(xy 396.808343 -280.536276) (xy 396.831214 -280.579853) (xy 396.846798 -280.626534) (xy 396.854693 -280.675111)
			(xy 396.855188 -280.699718) (xy 396.854693 -280.724325) (xy 396.854514 -280.725426) (xy 397.173192 -280.725426)
			(xy 397.173192 -280.67401) (xy 397.181235 -280.623228) (xy 397.197123 -280.574329) (xy 397.220466 -280.528517)
			(xy 397.250687 -280.486921) (xy 397.287043 -280.450565) (xy 397.328639 -280.420344) (xy 397.374451 -280.397001)
			(xy 397.42335 -280.381113) (xy 397.474132 -280.37307) (xy 397.525548 -280.37307) (xy 397.57633 -280.381113)
			(xy 397.625229 -280.397001) (xy 397.671041 -280.420344) (xy 397.712637 -280.450565) (xy 397.748993 -280.486921)
			(xy 397.779214 -280.528517) (xy 397.802557 -280.574329) (xy 397.818445 -280.623228) (xy 397.826488 -280.67401)
			(xy 397.826992 -280.699718) (xy 398.143996 -280.699718) (xy 398.147956 -280.650664) (xy 398.159733 -280.60288)
			(xy 398.179024 -280.557604) (xy 398.205327 -280.516008) (xy 398.237962 -280.479171) (xy 398.276083 -280.448046)
			(xy 398.318704 -280.423439) (xy 398.36472 -280.405987) (xy 398.412939 -280.396143) (xy 398.462114 -280.394162)
			(xy 398.510969 -280.400094) (xy 398.55824 -280.413786) (xy 398.602702 -280.434884) (xy 398.643205 -280.46284)
			(xy 398.678698 -280.496932) (xy 398.708263 -280.536276) (xy 398.731134 -280.579853) (xy 398.746718 -280.626534)
			(xy 398.754613 -280.675111) (xy 398.755108 -280.699718) (xy 398.754613 -280.724325) (xy 398.754434 -280.725426)
			(xy 399.073366 -280.725426) (xy 399.073366 -280.67401) (xy 399.081409 -280.623228) (xy 399.097297 -280.574329)
			(xy 399.12064 -280.528517) (xy 399.150861 -280.486921) (xy 399.187217 -280.450565) (xy 399.228813 -280.420344)
			(xy 399.274625 -280.397001) (xy 399.323524 -280.381113) (xy 399.374306 -280.37307) (xy 399.425722 -280.37307)
			(xy 399.476504 -280.381113) (xy 399.525403 -280.397001) (xy 399.571215 -280.420344) (xy 399.612811 -280.450565)
			(xy 399.649167 -280.486921) (xy 399.679388 -280.528517) (xy 399.702731 -280.574329) (xy 399.718619 -280.623228)
			(xy 399.726662 -280.67401) (xy 399.727166 -280.699718) (xy 400.04417 -280.699718) (xy 400.04813 -280.650664)
			(xy 400.059907 -280.60288) (xy 400.079198 -280.557604) (xy 400.105501 -280.516008) (xy 400.138136 -280.479171)
			(xy 400.176257 -280.448046) (xy 400.218878 -280.423439) (xy 400.264894 -280.405987) (xy 400.313113 -280.396143)
			(xy 400.362288 -280.394162) (xy 400.411143 -280.400094) (xy 400.458414 -280.413786) (xy 400.502876 -280.434884)
			(xy 400.543379 -280.46284) (xy 400.578872 -280.496932) (xy 400.608437 -280.536276) (xy 400.631308 -280.579853)
			(xy 400.646892 -280.626534) (xy 400.654787 -280.675111) (xy 400.655282 -280.699718) (xy 400.654787 -280.724325)
			(xy 400.654608 -280.725426) (xy 400.973286 -280.725426) (xy 400.973286 -280.67401) (xy 400.981329 -280.623228)
			(xy 400.997217 -280.574329) (xy 401.02056 -280.528517) (xy 401.050781 -280.486921) (xy 401.087137 -280.450565)
			(xy 401.128733 -280.420344) (xy 401.174545 -280.397001) (xy 401.223444 -280.381113) (xy 401.274226 -280.37307)
			(xy 401.325642 -280.37307) (xy 401.376424 -280.381113) (xy 401.425323 -280.397001) (xy 401.471135 -280.420344)
			(xy 401.512731 -280.450565) (xy 401.549087 -280.486921) (xy 401.579308 -280.528517) (xy 401.602651 -280.574329)
			(xy 401.618539 -280.623228) (xy 401.626582 -280.67401) (xy 401.627086 -280.699718) (xy 401.94409 -280.699718)
			(xy 401.94805 -280.650664) (xy 401.959827 -280.60288) (xy 401.979118 -280.557604) (xy 402.005421 -280.516008)
			(xy 402.038056 -280.479171) (xy 402.076177 -280.448046) (xy 402.118798 -280.423439) (xy 402.164814 -280.405987)
			(xy 402.213033 -280.396143) (xy 402.262208 -280.394162) (xy 402.311063 -280.400094) (xy 402.358334 -280.413786)
			(xy 402.402796 -280.434884) (xy 402.443299 -280.46284) (xy 402.478792 -280.496932) (xy 402.508357 -280.536276)
			(xy 402.531228 -280.579853) (xy 402.546812 -280.626534) (xy 402.554707 -280.675111) (xy 402.555202 -280.699718)
			(xy 402.554707 -280.724325) (xy 402.554528 -280.725426) (xy 402.873206 -280.725426) (xy 402.873206 -280.67401)
			(xy 402.881249 -280.623228) (xy 402.897137 -280.574329) (xy 402.92048 -280.528517) (xy 402.950701 -280.486921)
			(xy 402.987057 -280.450565) (xy 403.028653 -280.420344) (xy 403.074465 -280.397001) (xy 403.123364 -280.381113)
			(xy 403.174146 -280.37307) (xy 403.225562 -280.37307) (xy 403.276344 -280.381113) (xy 403.325243 -280.397001)
			(xy 403.371055 -280.420344) (xy 403.412651 -280.450565) (xy 403.449007 -280.486921) (xy 403.479228 -280.528517)
			(xy 403.502571 -280.574329) (xy 403.518459 -280.623228) (xy 403.526502 -280.67401) (xy 403.527006 -280.699718)
			(xy 403.84401 -280.699718) (xy 403.84797 -280.650664) (xy 403.859747 -280.60288) (xy 403.879038 -280.557604)
			(xy 403.905341 -280.516008) (xy 403.937976 -280.479171) (xy 403.976097 -280.448046) (xy 404.018718 -280.423439)
			(xy 404.064734 -280.405987) (xy 404.112953 -280.396143) (xy 404.162128 -280.394162) (xy 404.210983 -280.400094)
			(xy 404.258254 -280.413786) (xy 404.302716 -280.434884) (xy 404.343219 -280.46284) (xy 404.378712 -280.496932)
			(xy 404.408277 -280.536276) (xy 404.431148 -280.579853) (xy 404.446732 -280.626534) (xy 404.454627 -280.675111)
			(xy 404.455122 -280.699718) (xy 404.454627 -280.724325) (xy 404.454448 -280.725426) (xy 404.773126 -280.725426)
			(xy 404.773126 -280.67401) (xy 404.781169 -280.623228) (xy 404.797057 -280.574329) (xy 404.8204 -280.528517)
			(xy 404.850621 -280.486921) (xy 404.886977 -280.450565) (xy 404.928573 -280.420344) (xy 404.974385 -280.397001)
			(xy 405.023284 -280.381113) (xy 405.074066 -280.37307) (xy 405.125482 -280.37307) (xy 405.176264 -280.381113)
			(xy 405.225163 -280.397001) (xy 405.270975 -280.420344) (xy 405.312571 -280.450565) (xy 405.348927 -280.486921)
			(xy 405.379148 -280.528517) (xy 405.402491 -280.574329) (xy 405.418379 -280.623228) (xy 405.426422 -280.67401)
			(xy 405.426926 -280.699718) (xy 405.744184 -280.699718) (xy 405.748144 -280.650664) (xy 405.759921 -280.60288)
			(xy 405.779212 -280.557604) (xy 405.805515 -280.516008) (xy 405.83815 -280.479171) (xy 405.876271 -280.448046)
			(xy 405.918892 -280.423439) (xy 405.964908 -280.405987) (xy 406.013127 -280.396143) (xy 406.062302 -280.394162)
			(xy 406.111157 -280.400094) (xy 406.158428 -280.413786) (xy 406.20289 -280.434884) (xy 406.243393 -280.46284)
			(xy 406.278886 -280.496932) (xy 406.308451 -280.536276) (xy 406.331322 -280.579853) (xy 406.346906 -280.626534)
			(xy 406.354801 -280.675111) (xy 406.355296 -280.699718) (xy 406.354801 -280.724325) (xy 406.354622 -280.725426)
			(xy 406.6733 -280.725426) (xy 406.6733 -280.67401) (xy 406.681343 -280.623228) (xy 406.697231 -280.574329)
			(xy 406.720574 -280.528517) (xy 406.750795 -280.486921) (xy 406.787151 -280.450565) (xy 406.828747 -280.420344)
			(xy 406.874559 -280.397001) (xy 406.923458 -280.381113) (xy 406.97424 -280.37307) (xy 407.025656 -280.37307)
			(xy 407.076438 -280.381113) (xy 407.125337 -280.397001) (xy 407.171149 -280.420344) (xy 407.212745 -280.450565)
			(xy 407.249101 -280.486921) (xy 407.279322 -280.528517) (xy 407.302665 -280.574329) (xy 407.318553 -280.623228)
			(xy 407.326596 -280.67401) (xy 407.3271 -280.699718) (xy 407.644104 -280.699718) (xy 407.648064 -280.650664)
			(xy 407.659841 -280.60288) (xy 407.679132 -280.557604) (xy 407.705435 -280.516008) (xy 407.73807 -280.479171)
			(xy 407.776191 -280.448046) (xy 407.818812 -280.423439) (xy 407.864828 -280.405987) (xy 407.913047 -280.396143)
			(xy 407.962222 -280.394162) (xy 408.011077 -280.400094) (xy 408.058348 -280.413786) (xy 408.10281 -280.434884)
			(xy 408.143313 -280.46284) (xy 408.178806 -280.496932) (xy 408.208371 -280.536276) (xy 408.231242 -280.579853)
			(xy 408.246826 -280.626534) (xy 408.254721 -280.675111) (xy 408.255216 -280.699718) (xy 408.254721 -280.724325)
			(xy 408.254542 -280.725426) (xy 408.57322 -280.725426) (xy 408.57322 -280.67401) (xy 408.581263 -280.623228)
			(xy 408.597151 -280.574329) (xy 408.620494 -280.528517) (xy 408.650715 -280.486921) (xy 408.687071 -280.450565)
			(xy 408.728667 -280.420344) (xy 408.774479 -280.397001) (xy 408.823378 -280.381113) (xy 408.87416 -280.37307)
			(xy 408.925576 -280.37307) (xy 408.976358 -280.381113) (xy 409.025257 -280.397001) (xy 409.071069 -280.420344)
			(xy 409.112665 -280.450565) (xy 409.149021 -280.486921) (xy 409.179242 -280.528517) (xy 409.202585 -280.574329)
			(xy 409.218473 -280.623228) (xy 409.226516 -280.67401) (xy 409.22702 -280.699718) (xy 409.544024 -280.699718)
			(xy 409.547984 -280.650664) (xy 409.559761 -280.60288) (xy 409.579052 -280.557604) (xy 409.605355 -280.516008)
			(xy 409.63799 -280.479171) (xy 409.676111 -280.448046) (xy 409.718732 -280.423439) (xy 409.764748 -280.405987)
			(xy 409.812967 -280.396143) (xy 409.862142 -280.394162) (xy 409.910997 -280.400094) (xy 409.958268 -280.413786)
			(xy 410.00273 -280.434884) (xy 410.043233 -280.46284) (xy 410.078726 -280.496932) (xy 410.108291 -280.536276)
			(xy 410.131162 -280.579853) (xy 410.146746 -280.626534) (xy 410.154641 -280.675111) (xy 410.155136 -280.699718)
			(xy 410.154641 -280.724325) (xy 410.154462 -280.725426) (xy 410.47314 -280.725426) (xy 410.47314 -280.67401)
			(xy 410.481183 -280.623228) (xy 410.497071 -280.574329) (xy 410.520414 -280.528517) (xy 410.550635 -280.486921)
			(xy 410.586991 -280.450565) (xy 410.628587 -280.420344) (xy 410.674399 -280.397001) (xy 410.723298 -280.381113)
			(xy 410.77408 -280.37307) (xy 410.825496 -280.37307) (xy 410.876278 -280.381113) (xy 410.925177 -280.397001)
			(xy 410.970989 -280.420344) (xy 411.012585 -280.450565) (xy 411.048941 -280.486921) (xy 411.079162 -280.528517)
			(xy 411.102505 -280.574329) (xy 411.118393 -280.623228) (xy 411.126436 -280.67401) (xy 411.12694 -280.699718)
			(xy 411.444198 -280.699718) (xy 411.448158 -280.650664) (xy 411.459935 -280.60288) (xy 411.479226 -280.557604)
			(xy 411.505529 -280.516008) (xy 411.538164 -280.479171) (xy 411.576285 -280.448046) (xy 411.618906 -280.423439)
			(xy 411.664922 -280.405987) (xy 411.713141 -280.396143) (xy 411.762316 -280.394162) (xy 411.811171 -280.400094)
			(xy 411.858442 -280.413786) (xy 411.902904 -280.434884) (xy 411.943407 -280.46284) (xy 411.9789 -280.496932)
			(xy 412.008465 -280.536276) (xy 412.031336 -280.579853) (xy 412.04692 -280.626534) (xy 412.054815 -280.675111)
			(xy 412.05531 -280.699718) (xy 412.054815 -280.724325) (xy 412.054636 -280.725426) (xy 412.373314 -280.725426)
			(xy 412.373314 -280.67401) (xy 412.381357 -280.623228) (xy 412.397245 -280.574329) (xy 412.420588 -280.528517)
			(xy 412.450809 -280.486921) (xy 412.487165 -280.450565) (xy 412.528761 -280.420344) (xy 412.574573 -280.397001)
			(xy 412.623472 -280.381113) (xy 412.674254 -280.37307) (xy 412.72567 -280.37307) (xy 412.776452 -280.381113)
			(xy 412.825351 -280.397001) (xy 412.871163 -280.420344) (xy 412.912759 -280.450565) (xy 412.949115 -280.486921)
			(xy 412.979336 -280.528517) (xy 413.002679 -280.574329) (xy 413.018567 -280.623228) (xy 413.02661 -280.67401)
			(xy 413.027114 -280.699718) (xy 413.344118 -280.699718) (xy 413.348078 -280.650664) (xy 413.359855 -280.60288)
			(xy 413.379146 -280.557604) (xy 413.405449 -280.516008) (xy 413.438084 -280.479171) (xy 413.476205 -280.448046)
			(xy 413.518826 -280.423439) (xy 413.564842 -280.405987) (xy 413.613061 -280.396143) (xy 413.662236 -280.394162)
			(xy 413.711091 -280.400094) (xy 413.758362 -280.413786) (xy 413.802824 -280.434884) (xy 413.843327 -280.46284)
			(xy 413.87882 -280.496932) (xy 413.908385 -280.536276) (xy 413.931256 -280.579853) (xy 413.94684 -280.626534)
			(xy 413.954735 -280.675111) (xy 413.95523 -280.699718) (xy 413.954735 -280.724325) (xy 413.954556 -280.725426)
			(xy 414.273234 -280.725426) (xy 414.273234 -280.67401) (xy 414.281277 -280.623228) (xy 414.297165 -280.574329)
			(xy 414.320508 -280.528517) (xy 414.350729 -280.486921) (xy 414.387085 -280.450565) (xy 414.428681 -280.420344)
			(xy 414.474493 -280.397001) (xy 414.523392 -280.381113) (xy 414.574174 -280.37307) (xy 414.62559 -280.37307)
			(xy 414.676372 -280.381113) (xy 414.725271 -280.397001) (xy 414.771083 -280.420344) (xy 414.812679 -280.450565)
			(xy 414.849035 -280.486921) (xy 414.879256 -280.528517) (xy 414.902599 -280.574329) (xy 414.918487 -280.623228)
			(xy 414.92653 -280.67401) (xy 414.927034 -280.699718) (xy 415.244038 -280.699718) (xy 415.247998 -280.650664)
			(xy 415.259775 -280.60288) (xy 415.279066 -280.557604) (xy 415.305369 -280.516008) (xy 415.338004 -280.479171)
			(xy 415.376125 -280.448046) (xy 415.418746 -280.423439) (xy 415.464762 -280.405987) (xy 415.512981 -280.396143)
			(xy 415.562156 -280.394162) (xy 415.611011 -280.400094) (xy 415.658282 -280.413786) (xy 415.702744 -280.434884)
			(xy 415.743247 -280.46284) (xy 415.77874 -280.496932) (xy 415.808305 -280.536276) (xy 415.831176 -280.579853)
			(xy 415.84676 -280.626534) (xy 415.854655 -280.675111) (xy 415.85515 -280.699718) (xy 415.854655 -280.724325)
			(xy 415.854476 -280.725426) (xy 416.173154 -280.725426) (xy 416.173154 -280.67401) (xy 416.181197 -280.623228)
			(xy 416.197085 -280.574329) (xy 416.220428 -280.528517) (xy 416.250649 -280.486921) (xy 416.287005 -280.450565)
			(xy 416.328601 -280.420344) (xy 416.374413 -280.397001) (xy 416.423312 -280.381113) (xy 416.474094 -280.37307)
			(xy 416.52551 -280.37307) (xy 416.576292 -280.381113) (xy 416.625191 -280.397001) (xy 416.671003 -280.420344)
			(xy 416.712599 -280.450565) (xy 416.748955 -280.486921) (xy 416.779176 -280.528517) (xy 416.802519 -280.574329)
			(xy 416.818407 -280.623228) (xy 416.82645 -280.67401) (xy 416.826954 -280.699718) (xy 417.144212 -280.699718)
			(xy 417.148172 -280.650664) (xy 417.159949 -280.60288) (xy 417.17924 -280.557604) (xy 417.205543 -280.516008)
			(xy 417.238178 -280.479171) (xy 417.276299 -280.448046) (xy 417.31892 -280.423439) (xy 417.364936 -280.405987)
			(xy 417.413155 -280.396143) (xy 417.46233 -280.394162) (xy 417.511185 -280.400094) (xy 417.558456 -280.413786)
			(xy 417.602918 -280.434884) (xy 417.643421 -280.46284) (xy 417.678914 -280.496932) (xy 417.708479 -280.536276)
			(xy 417.73135 -280.579853) (xy 417.746934 -280.626534) (xy 417.754829 -280.675111) (xy 417.755324 -280.699718)
			(xy 417.754829 -280.724325) (xy 417.75465 -280.725426) (xy 418.073328 -280.725426) (xy 418.073328 -280.67401)
			(xy 418.081371 -280.623228) (xy 418.097259 -280.574329) (xy 418.120602 -280.528517) (xy 418.150823 -280.486921)
			(xy 418.187179 -280.450565) (xy 418.228775 -280.420344) (xy 418.274587 -280.397001) (xy 418.323486 -280.381113)
			(xy 418.374268 -280.37307) (xy 418.425684 -280.37307) (xy 418.476466 -280.381113) (xy 418.525365 -280.397001)
			(xy 418.571177 -280.420344) (xy 418.612773 -280.450565) (xy 418.649129 -280.486921) (xy 418.67935 -280.528517)
			(xy 418.702693 -280.574329) (xy 418.718581 -280.623228) (xy 418.726624 -280.67401) (xy 418.727128 -280.699718)
			(xy 419.044132 -280.699718) (xy 419.048092 -280.650664) (xy 419.059869 -280.60288) (xy 419.07916 -280.557604)
			(xy 419.105463 -280.516008) (xy 419.138098 -280.479171) (xy 419.176219 -280.448046) (xy 419.21884 -280.423439)
			(xy 419.264856 -280.405987) (xy 419.313075 -280.396143) (xy 419.36225 -280.394162) (xy 419.411105 -280.400094)
			(xy 419.458376 -280.413786) (xy 419.502838 -280.434884) (xy 419.543341 -280.46284) (xy 419.578834 -280.496932)
			(xy 419.608399 -280.536276) (xy 419.63127 -280.579853) (xy 419.646854 -280.626534) (xy 419.654749 -280.675111)
			(xy 419.655244 -280.699718) (xy 419.654749 -280.724325) (xy 419.65457 -280.725426) (xy 419.973248 -280.725426)
			(xy 419.973248 -280.67401) (xy 419.981291 -280.623228) (xy 419.997179 -280.574329) (xy 420.020522 -280.528517)
			(xy 420.050743 -280.486921) (xy 420.087099 -280.450565) (xy 420.128695 -280.420344) (xy 420.174507 -280.397001)
			(xy 420.223406 -280.381113) (xy 420.274188 -280.37307) (xy 420.325604 -280.37307) (xy 420.376386 -280.381113)
			(xy 420.425285 -280.397001) (xy 420.471097 -280.420344) (xy 420.512693 -280.450565) (xy 420.549049 -280.486921)
			(xy 420.57927 -280.528517) (xy 420.602613 -280.574329) (xy 420.618501 -280.623228) (xy 420.626544 -280.67401)
			(xy 420.627048 -280.699718) (xy 420.944052 -280.699718) (xy 420.948012 -280.650664) (xy 420.959789 -280.60288)
			(xy 420.97908 -280.557604) (xy 421.005383 -280.516008) (xy 421.038018 -280.479171) (xy 421.076139 -280.448046)
			(xy 421.11876 -280.423439) (xy 421.164776 -280.405987) (xy 421.212995 -280.396143) (xy 421.26217 -280.394162)
			(xy 421.311025 -280.400094) (xy 421.358296 -280.413786) (xy 421.402758 -280.434884) (xy 421.443261 -280.46284)
			(xy 421.478754 -280.496932) (xy 421.508319 -280.536276) (xy 421.53119 -280.579853) (xy 421.546774 -280.626534)
			(xy 421.554669 -280.675111) (xy 421.555164 -280.699718) (xy 421.554669 -280.724325) (xy 421.546774 -280.772902)
			(xy 421.53119 -280.819583) (xy 421.508319 -280.86316) (xy 421.478754 -280.902504) (xy 421.443261 -280.936596)
			(xy 421.402758 -280.964552) (xy 421.358296 -280.98565) (xy 421.311025 -280.999342) (xy 421.26217 -281.005274)
			(xy 421.212995 -281.003293) (xy 421.164776 -280.993449) (xy 421.11876 -280.975997) (xy 421.076139 -280.95139)
			(xy 421.038018 -280.920265) (xy 421.005383 -280.883428) (xy 420.97908 -280.841832) (xy 420.959789 -280.796556)
			(xy 420.948012 -280.748772) (xy 420.944052 -280.699718) (xy 420.627048 -280.699718) (xy 420.626544 -280.725426)
			(xy 420.618501 -280.776208) (xy 420.602613 -280.825107) (xy 420.57927 -280.870919) (xy 420.549049 -280.912515)
			(xy 420.512693 -280.948871) (xy 420.471097 -280.979092) (xy 420.425285 -281.002435) (xy 420.376386 -281.018323)
			(xy 420.325604 -281.026366) (xy 420.274188 -281.026366) (xy 420.223406 -281.018323) (xy 420.174507 -281.002435)
			(xy 420.128695 -280.979092) (xy 420.087099 -280.948871) (xy 420.050743 -280.912515) (xy 420.020522 -280.870919)
			(xy 419.997179 -280.825107) (xy 419.981291 -280.776208) (xy 419.973248 -280.725426) (xy 419.65457 -280.725426)
			(xy 419.646854 -280.772902) (xy 419.63127 -280.819583) (xy 419.608399 -280.86316) (xy 419.578834 -280.902504)
			(xy 419.543341 -280.936596) (xy 419.502838 -280.964552) (xy 419.458376 -280.98565) (xy 419.411105 -280.999342)
			(xy 419.36225 -281.005274) (xy 419.313075 -281.003293) (xy 419.264856 -280.993449) (xy 419.21884 -280.975997)
			(xy 419.176219 -280.95139) (xy 419.138098 -280.920265) (xy 419.105463 -280.883428) (xy 419.07916 -280.841832)
			(xy 419.059869 -280.796556) (xy 419.048092 -280.748772) (xy 419.044132 -280.699718) (xy 418.727128 -280.699718)
			(xy 418.726624 -280.725426) (xy 418.718581 -280.776208) (xy 418.702693 -280.825107) (xy 418.67935 -280.870919)
			(xy 418.649129 -280.912515) (xy 418.612773 -280.948871) (xy 418.571177 -280.979092) (xy 418.525365 -281.002435)
			(xy 418.476466 -281.018323) (xy 418.425684 -281.026366) (xy 418.374268 -281.026366) (xy 418.323486 -281.018323)
			(xy 418.274587 -281.002435) (xy 418.228775 -280.979092) (xy 418.187179 -280.948871) (xy 418.150823 -280.912515)
			(xy 418.120602 -280.870919) (xy 418.097259 -280.825107) (xy 418.081371 -280.776208) (xy 418.073328 -280.725426)
			(xy 417.75465 -280.725426) (xy 417.746934 -280.772902) (xy 417.73135 -280.819583) (xy 417.708479 -280.86316)
			(xy 417.678914 -280.902504) (xy 417.643421 -280.936596) (xy 417.602918 -280.964552) (xy 417.558456 -280.98565)
			(xy 417.511185 -280.999342) (xy 417.46233 -281.005274) (xy 417.413155 -281.003293) (xy 417.364936 -280.993449)
			(xy 417.31892 -280.975997) (xy 417.276299 -280.95139) (xy 417.238178 -280.920265) (xy 417.205543 -280.883428)
			(xy 417.17924 -280.841832) (xy 417.159949 -280.796556) (xy 417.148172 -280.748772) (xy 417.144212 -280.699718)
			(xy 416.826954 -280.699718) (xy 416.82645 -280.725426) (xy 416.818407 -280.776208) (xy 416.802519 -280.825107)
			(xy 416.779176 -280.870919) (xy 416.748955 -280.912515) (xy 416.712599 -280.948871) (xy 416.671003 -280.979092)
			(xy 416.625191 -281.002435) (xy 416.576292 -281.018323) (xy 416.52551 -281.026366) (xy 416.474094 -281.026366)
			(xy 416.423312 -281.018323) (xy 416.374413 -281.002435) (xy 416.328601 -280.979092) (xy 416.287005 -280.948871)
			(xy 416.250649 -280.912515) (xy 416.220428 -280.870919) (xy 416.197085 -280.825107) (xy 416.181197 -280.776208)
			(xy 416.173154 -280.725426) (xy 415.854476 -280.725426) (xy 415.84676 -280.772902) (xy 415.831176 -280.819583)
			(xy 415.808305 -280.86316) (xy 415.77874 -280.902504) (xy 415.743247 -280.936596) (xy 415.702744 -280.964552)
			(xy 415.658282 -280.98565) (xy 415.611011 -280.999342) (xy 415.562156 -281.005274) (xy 415.512981 -281.003293)
			(xy 415.464762 -280.993449) (xy 415.418746 -280.975997) (xy 415.376125 -280.95139) (xy 415.338004 -280.920265)
			(xy 415.305369 -280.883428) (xy 415.279066 -280.841832) (xy 415.259775 -280.796556) (xy 415.247998 -280.748772)
			(xy 415.244038 -280.699718) (xy 414.927034 -280.699718) (xy 414.92653 -280.725426) (xy 414.918487 -280.776208)
			(xy 414.902599 -280.825107) (xy 414.879256 -280.870919) (xy 414.849035 -280.912515) (xy 414.812679 -280.948871)
			(xy 414.771083 -280.979092) (xy 414.725271 -281.002435) (xy 414.676372 -281.018323) (xy 414.62559 -281.026366)
			(xy 414.574174 -281.026366) (xy 414.523392 -281.018323) (xy 414.474493 -281.002435) (xy 414.428681 -280.979092)
			(xy 414.387085 -280.948871) (xy 414.350729 -280.912515) (xy 414.320508 -280.870919) (xy 414.297165 -280.825107)
			(xy 414.281277 -280.776208) (xy 414.273234 -280.725426) (xy 413.954556 -280.725426) (xy 413.94684 -280.772902)
			(xy 413.931256 -280.819583) (xy 413.908385 -280.86316) (xy 413.87882 -280.902504) (xy 413.843327 -280.936596)
			(xy 413.802824 -280.964552) (xy 413.758362 -280.98565) (xy 413.711091 -280.999342) (xy 413.662236 -281.005274)
			(xy 413.613061 -281.003293) (xy 413.564842 -280.993449) (xy 413.518826 -280.975997) (xy 413.476205 -280.95139)
			(xy 413.438084 -280.920265) (xy 413.405449 -280.883428) (xy 413.379146 -280.841832) (xy 413.359855 -280.796556)
			(xy 413.348078 -280.748772) (xy 413.344118 -280.699718) (xy 413.027114 -280.699718) (xy 413.02661 -280.725426)
			(xy 413.018567 -280.776208) (xy 413.002679 -280.825107) (xy 412.979336 -280.870919) (xy 412.949115 -280.912515)
			(xy 412.912759 -280.948871) (xy 412.871163 -280.979092) (xy 412.825351 -281.002435) (xy 412.776452 -281.018323)
			(xy 412.72567 -281.026366) (xy 412.674254 -281.026366) (xy 412.623472 -281.018323) (xy 412.574573 -281.002435)
			(xy 412.528761 -280.979092) (xy 412.487165 -280.948871) (xy 412.450809 -280.912515) (xy 412.420588 -280.870919)
			(xy 412.397245 -280.825107) (xy 412.381357 -280.776208) (xy 412.373314 -280.725426) (xy 412.054636 -280.725426)
			(xy 412.04692 -280.772902) (xy 412.031336 -280.819583) (xy 412.008465 -280.86316) (xy 411.9789 -280.902504)
			(xy 411.943407 -280.936596) (xy 411.902904 -280.964552) (xy 411.858442 -280.98565) (xy 411.811171 -280.999342)
			(xy 411.762316 -281.005274) (xy 411.713141 -281.003293) (xy 411.664922 -280.993449) (xy 411.618906 -280.975997)
			(xy 411.576285 -280.95139) (xy 411.538164 -280.920265) (xy 411.505529 -280.883428) (xy 411.479226 -280.841832)
			(xy 411.459935 -280.796556) (xy 411.448158 -280.748772) (xy 411.444198 -280.699718) (xy 411.12694 -280.699718)
			(xy 411.126436 -280.725426) (xy 411.118393 -280.776208) (xy 411.102505 -280.825107) (xy 411.079162 -280.870919)
			(xy 411.048941 -280.912515) (xy 411.012585 -280.948871) (xy 410.970989 -280.979092) (xy 410.925177 -281.002435)
			(xy 410.876278 -281.018323) (xy 410.825496 -281.026366) (xy 410.77408 -281.026366) (xy 410.723298 -281.018323)
			(xy 410.674399 -281.002435) (xy 410.628587 -280.979092) (xy 410.586991 -280.948871) (xy 410.550635 -280.912515)
			(xy 410.520414 -280.870919) (xy 410.497071 -280.825107) (xy 410.481183 -280.776208) (xy 410.47314 -280.725426)
			(xy 410.154462 -280.725426) (xy 410.146746 -280.772902) (xy 410.131162 -280.819583) (xy 410.108291 -280.86316)
			(xy 410.078726 -280.902504) (xy 410.043233 -280.936596) (xy 410.00273 -280.964552) (xy 409.958268 -280.98565)
			(xy 409.910997 -280.999342) (xy 409.862142 -281.005274) (xy 409.812967 -281.003293) (xy 409.764748 -280.993449)
			(xy 409.718732 -280.975997) (xy 409.676111 -280.95139) (xy 409.63799 -280.920265) (xy 409.605355 -280.883428)
			(xy 409.579052 -280.841832) (xy 409.559761 -280.796556) (xy 409.547984 -280.748772) (xy 409.544024 -280.699718)
			(xy 409.22702 -280.699718) (xy 409.226516 -280.725426) (xy 409.218473 -280.776208) (xy 409.202585 -280.825107)
			(xy 409.179242 -280.870919) (xy 409.149021 -280.912515) (xy 409.112665 -280.948871) (xy 409.071069 -280.979092)
			(xy 409.025257 -281.002435) (xy 408.976358 -281.018323) (xy 408.925576 -281.026366) (xy 408.87416 -281.026366)
			(xy 408.823378 -281.018323) (xy 408.774479 -281.002435) (xy 408.728667 -280.979092) (xy 408.687071 -280.948871)
			(xy 408.650715 -280.912515) (xy 408.620494 -280.870919) (xy 408.597151 -280.825107) (xy 408.581263 -280.776208)
			(xy 408.57322 -280.725426) (xy 408.254542 -280.725426) (xy 408.246826 -280.772902) (xy 408.231242 -280.819583)
			(xy 408.208371 -280.86316) (xy 408.178806 -280.902504) (xy 408.143313 -280.936596) (xy 408.10281 -280.964552)
			(xy 408.058348 -280.98565) (xy 408.011077 -280.999342) (xy 407.962222 -281.005274) (xy 407.913047 -281.003293)
			(xy 407.864828 -280.993449) (xy 407.818812 -280.975997) (xy 407.776191 -280.95139) (xy 407.73807 -280.920265)
			(xy 407.705435 -280.883428) (xy 407.679132 -280.841832) (xy 407.659841 -280.796556) (xy 407.648064 -280.748772)
			(xy 407.644104 -280.699718) (xy 407.3271 -280.699718) (xy 407.326596 -280.725426) (xy 407.318553 -280.776208)
			(xy 407.302665 -280.825107) (xy 407.279322 -280.870919) (xy 407.249101 -280.912515) (xy 407.212745 -280.948871)
			(xy 407.171149 -280.979092) (xy 407.125337 -281.002435) (xy 407.076438 -281.018323) (xy 407.025656 -281.026366)
			(xy 406.97424 -281.026366) (xy 406.923458 -281.018323) (xy 406.874559 -281.002435) (xy 406.828747 -280.979092)
			(xy 406.787151 -280.948871) (xy 406.750795 -280.912515) (xy 406.720574 -280.870919) (xy 406.697231 -280.825107)
			(xy 406.681343 -280.776208) (xy 406.6733 -280.725426) (xy 406.354622 -280.725426) (xy 406.346906 -280.772902)
			(xy 406.331322 -280.819583) (xy 406.308451 -280.86316) (xy 406.278886 -280.902504) (xy 406.243393 -280.936596)
			(xy 406.20289 -280.964552) (xy 406.158428 -280.98565) (xy 406.111157 -280.999342) (xy 406.062302 -281.005274)
			(xy 406.013127 -281.003293) (xy 405.964908 -280.993449) (xy 405.918892 -280.975997) (xy 405.876271 -280.95139)
			(xy 405.83815 -280.920265) (xy 405.805515 -280.883428) (xy 405.779212 -280.841832) (xy 405.759921 -280.796556)
			(xy 405.748144 -280.748772) (xy 405.744184 -280.699718) (xy 405.426926 -280.699718) (xy 405.426422 -280.725426)
			(xy 405.418379 -280.776208) (xy 405.402491 -280.825107) (xy 405.379148 -280.870919) (xy 405.348927 -280.912515)
			(xy 405.312571 -280.948871) (xy 405.270975 -280.979092) (xy 405.225163 -281.002435) (xy 405.176264 -281.018323)
			(xy 405.125482 -281.026366) (xy 405.074066 -281.026366) (xy 405.023284 -281.018323) (xy 404.974385 -281.002435)
			(xy 404.928573 -280.979092) (xy 404.886977 -280.948871) (xy 404.850621 -280.912515) (xy 404.8204 -280.870919)
			(xy 404.797057 -280.825107) (xy 404.781169 -280.776208) (xy 404.773126 -280.725426) (xy 404.454448 -280.725426)
			(xy 404.446732 -280.772902) (xy 404.431148 -280.819583) (xy 404.408277 -280.86316) (xy 404.378712 -280.902504)
			(xy 404.343219 -280.936596) (xy 404.302716 -280.964552) (xy 404.258254 -280.98565) (xy 404.210983 -280.999342)
			(xy 404.162128 -281.005274) (xy 404.112953 -281.003293) (xy 404.064734 -280.993449) (xy 404.018718 -280.975997)
			(xy 403.976097 -280.95139) (xy 403.937976 -280.920265) (xy 403.905341 -280.883428) (xy 403.879038 -280.841832)
			(xy 403.859747 -280.796556) (xy 403.84797 -280.748772) (xy 403.84401 -280.699718) (xy 403.527006 -280.699718)
			(xy 403.526502 -280.725426) (xy 403.518459 -280.776208) (xy 403.502571 -280.825107) (xy 403.479228 -280.870919)
			(xy 403.449007 -280.912515) (xy 403.412651 -280.948871) (xy 403.371055 -280.979092) (xy 403.325243 -281.002435)
			(xy 403.276344 -281.018323) (xy 403.225562 -281.026366) (xy 403.174146 -281.026366) (xy 403.123364 -281.018323)
			(xy 403.074465 -281.002435) (xy 403.028653 -280.979092) (xy 402.987057 -280.948871) (xy 402.950701 -280.912515)
			(xy 402.92048 -280.870919) (xy 402.897137 -280.825107) (xy 402.881249 -280.776208) (xy 402.873206 -280.725426)
			(xy 402.554528 -280.725426) (xy 402.546812 -280.772902) (xy 402.531228 -280.819583) (xy 402.508357 -280.86316)
			(xy 402.478792 -280.902504) (xy 402.443299 -280.936596) (xy 402.402796 -280.964552) (xy 402.358334 -280.98565)
			(xy 402.311063 -280.999342) (xy 402.262208 -281.005274) (xy 402.213033 -281.003293) (xy 402.164814 -280.993449)
			(xy 402.118798 -280.975997) (xy 402.076177 -280.95139) (xy 402.038056 -280.920265) (xy 402.005421 -280.883428)
			(xy 401.979118 -280.841832) (xy 401.959827 -280.796556) (xy 401.94805 -280.748772) (xy 401.94409 -280.699718)
			(xy 401.627086 -280.699718) (xy 401.626582 -280.725426) (xy 401.618539 -280.776208) (xy 401.602651 -280.825107)
			(xy 401.579308 -280.870919) (xy 401.549087 -280.912515) (xy 401.512731 -280.948871) (xy 401.471135 -280.979092)
			(xy 401.425323 -281.002435) (xy 401.376424 -281.018323) (xy 401.325642 -281.026366) (xy 401.274226 -281.026366)
			(xy 401.223444 -281.018323) (xy 401.174545 -281.002435) (xy 401.128733 -280.979092) (xy 401.087137 -280.948871)
			(xy 401.050781 -280.912515) (xy 401.02056 -280.870919) (xy 400.997217 -280.825107) (xy 400.981329 -280.776208)
			(xy 400.973286 -280.725426) (xy 400.654608 -280.725426) (xy 400.646892 -280.772902) (xy 400.631308 -280.819583)
			(xy 400.608437 -280.86316) (xy 400.578872 -280.902504) (xy 400.543379 -280.936596) (xy 400.502876 -280.964552)
			(xy 400.458414 -280.98565) (xy 400.411143 -280.999342) (xy 400.362288 -281.005274) (xy 400.313113 -281.003293)
			(xy 400.264894 -280.993449) (xy 400.218878 -280.975997) (xy 400.176257 -280.95139) (xy 400.138136 -280.920265)
			(xy 400.105501 -280.883428) (xy 400.079198 -280.841832) (xy 400.059907 -280.796556) (xy 400.04813 -280.748772)
			(xy 400.04417 -280.699718) (xy 399.727166 -280.699718) (xy 399.726662 -280.725426) (xy 399.718619 -280.776208)
			(xy 399.702731 -280.825107) (xy 399.679388 -280.870919) (xy 399.649167 -280.912515) (xy 399.612811 -280.948871)
			(xy 399.571215 -280.979092) (xy 399.525403 -281.002435) (xy 399.476504 -281.018323) (xy 399.425722 -281.026366)
			(xy 399.374306 -281.026366) (xy 399.323524 -281.018323) (xy 399.274625 -281.002435) (xy 399.228813 -280.979092)
			(xy 399.187217 -280.948871) (xy 399.150861 -280.912515) (xy 399.12064 -280.870919) (xy 399.097297 -280.825107)
			(xy 399.081409 -280.776208) (xy 399.073366 -280.725426) (xy 398.754434 -280.725426) (xy 398.746718 -280.772902)
			(xy 398.731134 -280.819583) (xy 398.708263 -280.86316) (xy 398.678698 -280.902504) (xy 398.643205 -280.936596)
			(xy 398.602702 -280.964552) (xy 398.55824 -280.98565) (xy 398.510969 -280.999342) (xy 398.462114 -281.005274)
			(xy 398.412939 -281.003293) (xy 398.36472 -280.993449) (xy 398.318704 -280.975997) (xy 398.276083 -280.95139)
			(xy 398.237962 -280.920265) (xy 398.205327 -280.883428) (xy 398.179024 -280.841832) (xy 398.159733 -280.796556)
			(xy 398.147956 -280.748772) (xy 398.143996 -280.699718) (xy 397.826992 -280.699718) (xy 397.826488 -280.725426)
			(xy 397.818445 -280.776208) (xy 397.802557 -280.825107) (xy 397.779214 -280.870919) (xy 397.748993 -280.912515)
			(xy 397.712637 -280.948871) (xy 397.671041 -280.979092) (xy 397.625229 -281.002435) (xy 397.57633 -281.018323)
			(xy 397.525548 -281.026366) (xy 397.474132 -281.026366) (xy 397.42335 -281.018323) (xy 397.374451 -281.002435)
			(xy 397.328639 -280.979092) (xy 397.287043 -280.948871) (xy 397.250687 -280.912515) (xy 397.220466 -280.870919)
			(xy 397.197123 -280.825107) (xy 397.181235 -280.776208) (xy 397.173192 -280.725426) (xy 396.854514 -280.725426)
			(xy 396.846798 -280.772902) (xy 396.831214 -280.819583) (xy 396.808343 -280.86316) (xy 396.778778 -280.902504)
			(xy 396.743285 -280.936596) (xy 396.702782 -280.964552) (xy 396.65832 -280.98565) (xy 396.611049 -280.999342)
			(xy 396.562194 -281.005274) (xy 396.513019 -281.003293) (xy 396.4648 -280.993449) (xy 396.418784 -280.975997)
			(xy 396.376163 -280.95139) (xy 396.338042 -280.920265) (xy 396.305407 -280.883428) (xy 396.279104 -280.841832)
			(xy 396.259813 -280.796556) (xy 396.248036 -280.748772) (xy 396.244076 -280.699718) (xy 395.927072 -280.699718)
			(xy 395.926568 -280.725426) (xy 395.918525 -280.776208) (xy 395.902637 -280.825107) (xy 395.879294 -280.870919)
			(xy 395.849073 -280.912515) (xy 395.812717 -280.948871) (xy 395.771121 -280.979092) (xy 395.725309 -281.002435)
			(xy 395.67641 -281.018323) (xy 395.625628 -281.026366) (xy 395.574212 -281.026366) (xy 395.52343 -281.018323)
			(xy 395.474531 -281.002435) (xy 395.428719 -280.979092) (xy 395.387123 -280.948871) (xy 395.350767 -280.912515)
			(xy 395.320546 -280.870919) (xy 395.297203 -280.825107) (xy 395.281315 -280.776208) (xy 395.273272 -280.725426)
			(xy 394.954594 -280.725426) (xy 394.946878 -280.772902) (xy 394.931294 -280.819583) (xy 394.908423 -280.86316)
			(xy 394.878858 -280.902504) (xy 394.843365 -280.936596) (xy 394.802862 -280.964552) (xy 394.7584 -280.98565)
			(xy 394.711129 -280.999342) (xy 394.662274 -281.005274) (xy 394.613099 -281.003293) (xy 394.56488 -280.993449)
			(xy 394.518864 -280.975997) (xy 394.476243 -280.95139) (xy 394.438122 -280.920265) (xy 394.405487 -280.883428)
			(xy 394.379184 -280.841832) (xy 394.359893 -280.796556) (xy 394.348116 -280.748772) (xy 394.344156 -280.699718)
			(xy 394.027152 -280.699718) (xy 394.026648 -280.725426) (xy 394.018605 -280.776208) (xy 394.002717 -280.825107)
			(xy 393.979374 -280.870919) (xy 393.949153 -280.912515) (xy 393.912797 -280.948871) (xy 393.871201 -280.979092)
			(xy 393.825389 -281.002435) (xy 393.77649 -281.018323) (xy 393.725708 -281.026366) (xy 393.674292 -281.026366)
			(xy 393.62351 -281.018323) (xy 393.574611 -281.002435) (xy 393.528799 -280.979092) (xy 393.487203 -280.948871)
			(xy 393.450847 -280.912515) (xy 393.420626 -280.870919) (xy 393.397283 -280.825107) (xy 393.381395 -280.776208)
			(xy 393.373352 -280.725426) (xy 393.05364 -280.725426) (xy 393.050168 -280.75734) (xy 393.036886 -280.805176)
			(xy 393.016039 -280.850233) (xy 392.988178 -280.891324) (xy 392.954035 -280.927365) (xy 392.914512 -280.957408)
			(xy 392.870648 -280.980661) (xy 392.823601 -280.996511) (xy 392.774609 -281.004541) (xy 392.749786 -281.005026)
			(xy 392.735603 -281.004851) (xy 392.707363 -281.002178) (xy 392.693398 -280.999692) (xy 392.679434 -280.997515)
			(xy 392.6513 -281.000095) (xy 392.62495 -281.010286) (xy 392.602401 -281.027308) (xy 392.585381 -281.049858)
			(xy 392.575193 -281.076209) (xy 392.572616 -281.104343) (xy 392.57478 -281.11831) (xy 392.577264 -281.132339)
			(xy 392.579936 -281.160706) (xy 392.580114 -281.174952) (xy 392.579674 -281.199778) (xy 392.571649 -281.248776)
			(xy 392.555802 -281.295831) (xy 392.532551 -281.339702) (xy 392.502508 -281.379233) (xy 392.466466 -281.413383)
			(xy 392.425373 -281.441252) (xy 392.380313 -281.462105) (xy 392.332473 -281.475393) (xy 392.283113 -281.480767)
			(xy 392.233535 -281.478083) (xy 392.185043 -281.467414) (xy 392.138916 -281.44904) (xy 392.09637 -281.423445)
			(xy 392.058525 -281.391304) (xy 392.026379 -281.353464) (xy 392.000779 -281.310921) (xy 391.982398 -281.264797)
			(xy 391.971722 -281.216307) (xy 391.969032 -281.166729) (xy 391.629989 -281.166729) (xy 391.630154 -281.174952)
			(xy 391.629659 -281.199559) (xy 391.621764 -281.248136) (xy 391.60618 -281.294817) (xy 391.583309 -281.338394)
			(xy 391.553744 -281.377738) (xy 391.518251 -281.41183) (xy 391.477748 -281.439786) (xy 391.433286 -281.460884)
			(xy 391.386015 -281.474576) (xy 391.33716 -281.480508) (xy 391.287985 -281.478527) (xy 391.239766 -281.468683)
			(xy 391.19375 -281.451231) (xy 391.151129 -281.426624) (xy 391.113008 -281.395499) (xy 391.080373 -281.358662)
			(xy 391.05407 -281.317066) (xy 391.034779 -281.27179) (xy 391.023002 -281.224006) (xy 391.019042 -281.174952)
			(xy 390.680194 -281.174952) (xy 390.679699 -281.199559) (xy 390.671804 -281.248136) (xy 390.65622 -281.294817)
			(xy 390.633349 -281.338394) (xy 390.603784 -281.377738) (xy 390.568291 -281.41183) (xy 390.527788 -281.439786)
			(xy 390.483326 -281.460884) (xy 390.436055 -281.474576) (xy 390.3872 -281.480508) (xy 390.338025 -281.478527)
			(xy 390.289806 -281.468683) (xy 390.24379 -281.451231) (xy 390.201169 -281.426624) (xy 390.163048 -281.395499)
			(xy 390.130413 -281.358662) (xy 390.10411 -281.317066) (xy 390.084819 -281.27179) (xy 390.073042 -281.224006)
			(xy 390.069082 -281.174952) (xy 389.730234 -281.174952) (xy 389.729739 -281.199559) (xy 389.721844 -281.248136)
			(xy 389.70626 -281.294817) (xy 389.683389 -281.338394) (xy 389.653824 -281.377738) (xy 389.618331 -281.41183)
			(xy 389.577828 -281.439786) (xy 389.533366 -281.460884) (xy 389.486095 -281.474576) (xy 389.43724 -281.480508)
			(xy 389.388065 -281.478527) (xy 389.339846 -281.468683) (xy 389.29383 -281.451231) (xy 389.251209 -281.426624)
			(xy 389.213088 -281.395499) (xy 389.180453 -281.358662) (xy 389.15415 -281.317066) (xy 389.134859 -281.27179)
			(xy 389.123082 -281.224006) (xy 389.119122 -281.174952) (xy 388.780274 -281.174952) (xy 388.779779 -281.199559)
			(xy 388.771884 -281.248136) (xy 388.7563 -281.294817) (xy 388.733429 -281.338394) (xy 388.703864 -281.377738)
			(xy 388.668371 -281.41183) (xy 388.627868 -281.439786) (xy 388.583406 -281.460884) (xy 388.536135 -281.474576)
			(xy 388.48728 -281.480508) (xy 388.438105 -281.478527) (xy 388.389886 -281.468683) (xy 388.34387 -281.451231)
			(xy 388.301249 -281.426624) (xy 388.263128 -281.395499) (xy 388.230493 -281.358662) (xy 388.20419 -281.317066)
			(xy 388.184899 -281.27179) (xy 388.173122 -281.224006) (xy 388.169162 -281.174952) (xy 387.830314 -281.174952)
			(xy 387.829819 -281.199559) (xy 387.821924 -281.248136) (xy 387.80634 -281.294817) (xy 387.783469 -281.338394)
			(xy 387.753904 -281.377738) (xy 387.718411 -281.41183) (xy 387.677908 -281.439786) (xy 387.633446 -281.460884)
			(xy 387.586175 -281.474576) (xy 387.53732 -281.480508) (xy 387.488145 -281.478527) (xy 387.439926 -281.468683)
			(xy 387.39391 -281.451231) (xy 387.351289 -281.426624) (xy 387.313168 -281.395499) (xy 387.280533 -281.358662)
			(xy 387.25423 -281.317066) (xy 387.234939 -281.27179) (xy 387.223162 -281.224006) (xy 387.219202 -281.174952)
			(xy 386.880354 -281.174952) (xy 386.879859 -281.199559) (xy 386.871964 -281.248136) (xy 386.85638 -281.294817)
			(xy 386.833509 -281.338394) (xy 386.803944 -281.377738) (xy 386.768451 -281.41183) (xy 386.727948 -281.439786)
			(xy 386.683486 -281.460884) (xy 386.636215 -281.474576) (xy 386.58736 -281.480508) (xy 386.538185 -281.478527)
			(xy 386.489966 -281.468683) (xy 386.44395 -281.451231) (xy 386.401329 -281.426624) (xy 386.363208 -281.395499)
			(xy 386.330573 -281.358662) (xy 386.30427 -281.317066) (xy 386.284979 -281.27179) (xy 386.273202 -281.224006)
			(xy 386.269242 -281.174952) (xy 385.93014 -281.174952) (xy 385.929645 -281.199559) (xy 385.92175 -281.248136)
			(xy 385.906166 -281.294817) (xy 385.883295 -281.338394) (xy 385.85373 -281.377738) (xy 385.818237 -281.41183)
			(xy 385.777734 -281.439786) (xy 385.733272 -281.460884) (xy 385.686001 -281.474576) (xy 385.637146 -281.480508)
			(xy 385.587971 -281.478527) (xy 385.539752 -281.468683) (xy 385.493736 -281.451231) (xy 385.451115 -281.426624)
			(xy 385.412994 -281.395499) (xy 385.380359 -281.358662) (xy 385.354056 -281.317066) (xy 385.334765 -281.27179)
			(xy 385.322988 -281.224006) (xy 385.319028 -281.174952) (xy 384.98018 -281.174952) (xy 384.979685 -281.199559)
			(xy 384.97179 -281.248136) (xy 384.956206 -281.294817) (xy 384.933335 -281.338394) (xy 384.90377 -281.377738)
			(xy 384.868277 -281.41183) (xy 384.827774 -281.439786) (xy 384.783312 -281.460884) (xy 384.736041 -281.474576)
			(xy 384.687186 -281.480508) (xy 384.638011 -281.478527) (xy 384.589792 -281.468683) (xy 384.543776 -281.451231)
			(xy 384.501155 -281.426624) (xy 384.463034 -281.395499) (xy 384.430399 -281.358662) (xy 384.404096 -281.317066)
			(xy 384.384805 -281.27179) (xy 384.373028 -281.224006) (xy 384.369068 -281.174952) (xy 383.78638 -281.174952)
			(xy 383.78638 -282.124912) (xy 384.369068 -282.124912) (xy 384.373028 -282.075858) (xy 384.384805 -282.028074)
			(xy 384.404096 -281.982798) (xy 384.430399 -281.941202) (xy 384.463034 -281.904365) (xy 384.501155 -281.87324)
			(xy 384.543776 -281.848633) (xy 384.589792 -281.831181) (xy 384.638011 -281.821337) (xy 384.687186 -281.819356)
			(xy 384.736041 -281.825288) (xy 384.783312 -281.83898) (xy 384.827774 -281.860078) (xy 384.868277 -281.888034)
			(xy 384.90377 -281.922126) (xy 384.933335 -281.96147) (xy 384.956206 -282.005047) (xy 384.97179 -282.051728)
			(xy 384.979685 -282.100305) (xy 384.98018 -282.124912) (xy 385.319028 -282.124912) (xy 385.322988 -282.075858)
			(xy 385.334765 -282.028074) (xy 385.354056 -281.982798) (xy 385.380359 -281.941202) (xy 385.412994 -281.904365)
			(xy 385.451115 -281.87324) (xy 385.493736 -281.848633) (xy 385.539752 -281.831181) (xy 385.587971 -281.821337)
			(xy 385.637146 -281.819356) (xy 385.686001 -281.825288) (xy 385.733272 -281.83898) (xy 385.777734 -281.860078)
			(xy 385.818237 -281.888034) (xy 385.85373 -281.922126) (xy 385.883295 -281.96147) (xy 385.906166 -282.005047)
			(xy 385.92175 -282.051728) (xy 385.929645 -282.100305) (xy 385.93014 -282.124912) (xy 386.269242 -282.124912)
			(xy 386.273202 -282.075858) (xy 386.284979 -282.028074) (xy 386.30427 -281.982798) (xy 386.330573 -281.941202)
			(xy 386.363208 -281.904365) (xy 386.401329 -281.87324) (xy 386.44395 -281.848633) (xy 386.489966 -281.831181)
			(xy 386.538185 -281.821337) (xy 386.58736 -281.819356) (xy 386.636215 -281.825288) (xy 386.683486 -281.83898)
			(xy 386.727948 -281.860078) (xy 386.768451 -281.888034) (xy 386.803944 -281.922126) (xy 386.833509 -281.96147)
			(xy 386.85638 -282.005047) (xy 386.871964 -282.051728) (xy 386.879859 -282.100305) (xy 386.880354 -282.124912)
			(xy 387.219202 -282.124912) (xy 387.223162 -282.075858) (xy 387.234939 -282.028074) (xy 387.25423 -281.982798)
			(xy 387.280533 -281.941202) (xy 387.313168 -281.904365) (xy 387.351289 -281.87324) (xy 387.39391 -281.848633)
			(xy 387.439926 -281.831181) (xy 387.488145 -281.821337) (xy 387.53732 -281.819356) (xy 387.586175 -281.825288)
			(xy 387.633446 -281.83898) (xy 387.677908 -281.860078) (xy 387.718411 -281.888034) (xy 387.753904 -281.922126)
			(xy 387.783469 -281.96147) (xy 387.80634 -282.005047) (xy 387.821924 -282.051728) (xy 387.829819 -282.100305)
			(xy 387.830314 -282.124912) (xy 388.169162 -282.124912) (xy 388.173122 -282.075858) (xy 388.184899 -282.028074)
			(xy 388.20419 -281.982798) (xy 388.230493 -281.941202) (xy 388.263128 -281.904365) (xy 388.301249 -281.87324)
			(xy 388.34387 -281.848633) (xy 388.389886 -281.831181) (xy 388.438105 -281.821337) (xy 388.48728 -281.819356)
			(xy 388.536135 -281.825288) (xy 388.583406 -281.83898) (xy 388.627868 -281.860078) (xy 388.668371 -281.888034)
			(xy 388.703864 -281.922126) (xy 388.733429 -281.96147) (xy 388.7563 -282.005047) (xy 388.771884 -282.051728)
			(xy 388.779779 -282.100305) (xy 388.780274 -282.124912) (xy 389.119122 -282.124912) (xy 389.123082 -282.075858)
			(xy 389.134859 -282.028074) (xy 389.15415 -281.982798) (xy 389.180453 -281.941202) (xy 389.213088 -281.904365)
			(xy 389.251209 -281.87324) (xy 389.29383 -281.848633) (xy 389.339846 -281.831181) (xy 389.388065 -281.821337)
			(xy 389.43724 -281.819356) (xy 389.486095 -281.825288) (xy 389.533366 -281.83898) (xy 389.577828 -281.860078)
			(xy 389.618331 -281.888034) (xy 389.653824 -281.922126) (xy 389.683389 -281.96147) (xy 389.70626 -282.005047)
			(xy 389.721844 -282.051728) (xy 389.729739 -282.100305) (xy 389.730234 -282.124912) (xy 390.069082 -282.124912)
			(xy 390.073042 -282.075858) (xy 390.084819 -282.028074) (xy 390.10411 -281.982798) (xy 390.130413 -281.941202)
			(xy 390.163048 -281.904365) (xy 390.201169 -281.87324) (xy 390.24379 -281.848633) (xy 390.289806 -281.831181)
			(xy 390.338025 -281.821337) (xy 390.3872 -281.819356) (xy 390.436055 -281.825288) (xy 390.483326 -281.83898)
			(xy 390.527788 -281.860078) (xy 390.568291 -281.888034) (xy 390.603784 -281.922126) (xy 390.633349 -281.96147)
			(xy 390.65622 -282.005047) (xy 390.671804 -282.051728) (xy 390.679699 -282.100305) (xy 390.680194 -282.124912)
			(xy 391.019042 -282.124912) (xy 391.023002 -282.075858) (xy 391.034779 -282.028074) (xy 391.05407 -281.982798)
			(xy 391.080373 -281.941202) (xy 391.113008 -281.904365) (xy 391.151129 -281.87324) (xy 391.19375 -281.848633)
			(xy 391.239766 -281.831181) (xy 391.287985 -281.821337) (xy 391.33716 -281.819356) (xy 391.386015 -281.825288)
			(xy 391.433286 -281.83898) (xy 391.477748 -281.860078) (xy 391.518251 -281.888034) (xy 391.553744 -281.922126)
			(xy 391.583309 -281.96147) (xy 391.60618 -282.005047) (xy 391.621764 -282.051728) (xy 391.629659 -282.100305)
			(xy 391.630154 -282.124912) (xy 391.969002 -282.124912) (xy 391.972962 -282.075858) (xy 391.984739 -282.028074)
			(xy 392.00403 -281.982798) (xy 392.030333 -281.941202) (xy 392.062968 -281.904365) (xy 392.101089 -281.87324)
			(xy 392.14371 -281.848633) (xy 392.189726 -281.831181) (xy 392.237945 -281.821337) (xy 392.28712 -281.819356)
			(xy 392.335975 -281.825288) (xy 392.383246 -281.83898) (xy 392.427708 -281.860078) (xy 392.468211 -281.888034)
			(xy 392.503704 -281.922126) (xy 392.533269 -281.96147) (xy 392.55614 -282.005047) (xy 392.571724 -282.051728)
			(xy 392.579619 -282.100305) (xy 392.579947 -282.116601) (xy 392.919294 -282.116601) (xy 392.924663 -282.067252)
			(xy 392.937946 -282.019423) (xy 392.958792 -281.974372) (xy 392.986652 -281.933287) (xy 393.020792 -281.897251)
			(xy 393.060312 -281.867212) (xy 393.104171 -281.843963) (xy 393.151213 -281.828116) (xy 393.2002 -281.820088)
			(xy 393.22502 -281.819604) (xy 393.239203 -281.819778) (xy 393.267443 -281.822452) (xy 393.281408 -281.824938)
			(xy 393.293854 -281.827224) (xy 393.317476 -281.819858) (xy 393.394946 -281.742388) (xy 393.402312 -281.718766)
			(xy 393.400026 -281.70632) (xy 393.397543 -281.692355) (xy 393.394875 -281.664115) (xy 393.394692 -281.649932)
			(xy 393.395214 -281.624677) (xy 393.403527 -281.574855) (xy 393.419928 -281.527081) (xy 393.443969 -281.482658)
			(xy 393.474993 -281.442798) (xy 393.512155 -281.408588) (xy 393.554441 -281.380962) (xy 393.600697 -281.360672)
			(xy 393.649662 -281.348272) (xy 393.7 -281.344101) (xy 393.750338 -281.348272) (xy 393.799303 -281.360672)
			(xy 393.845559 -281.380962) (xy 393.887845 -281.408588) (xy 393.925007 -281.442798) (xy 393.956031 -281.482658)
			(xy 393.980072 -281.527081) (xy 393.996473 -281.574855) (xy 394.004786 -281.624677) (xy 394.005308 -281.649932)
			(xy 394.005136 -281.664115) (xy 394.002461 -281.692355) (xy 393.999974 -281.70632) (xy 393.997688 -281.718766)
			(xy 394.005054 -281.742388) (xy 394.082524 -281.819858) (xy 394.106146 -281.827224) (xy 394.118592 -281.824938)
			(xy 394.132559 -281.822467) (xy 394.160798 -281.819791) (xy 394.17498 -281.819604) (xy 394.189163 -281.819783)
			(xy 394.217403 -281.822454) (xy 394.231368 -281.824938) (xy 394.243814 -281.827224) (xy 394.267436 -281.819858)
			(xy 394.344906 -281.742388) (xy 394.352272 -281.718766) (xy 394.349986 -281.70632) (xy 394.347502 -281.692355)
			(xy 394.344835 -281.664115) (xy 394.344652 -281.649932) (xy 394.345143 -281.625107) (xy 394.353171 -281.576111)
			(xy 394.36902 -281.529059) (xy 394.392273 -281.485192) (xy 394.422316 -281.445664) (xy 394.458359 -281.411518)
			(xy 394.499452 -281.383653) (xy 394.544512 -281.362804) (xy 394.592351 -281.349519) (xy 394.641709 -281.344149)
			(xy 394.691286 -281.346836) (xy 394.739774 -281.357509) (xy 394.785898 -281.375885) (xy 394.82844 -281.401482)
			(xy 394.866281 -281.433625) (xy 394.898422 -281.471466) (xy 394.924018 -281.51401) (xy 394.942394 -281.560133)
			(xy 394.953065 -281.608622) (xy 394.955302 -281.649932) (xy 395.294116 -281.649932) (xy 395.298076 -281.600878)
			(xy 395.309853 -281.553094) (xy 395.329144 -281.507818) (xy 395.355447 -281.466222) (xy 395.388082 -281.429385)
			(xy 395.426203 -281.39826) (xy 395.468824 -281.373653) (xy 395.51484 -281.356201) (xy 395.563059 -281.346357)
			(xy 395.612234 -281.344376) (xy 395.661089 -281.350308) (xy 395.70836 -281.364) (xy 395.752822 -281.385098)
			(xy 395.793325 -281.413054) (xy 395.828818 -281.447146) (xy 395.858383 -281.48649) (xy 395.881254 -281.530067)
			(xy 395.896838 -281.576748) (xy 395.904733 -281.625325) (xy 395.905228 -281.649932) (xy 396.244076 -281.649932)
			(xy 396.248036 -281.600878) (xy 396.259813 -281.553094) (xy 396.279104 -281.507818) (xy 396.305407 -281.466222)
			(xy 396.338042 -281.429385) (xy 396.376163 -281.39826) (xy 396.418784 -281.373653) (xy 396.4648 -281.356201)
			(xy 396.513019 -281.346357) (xy 396.562194 -281.344376) (xy 396.611049 -281.350308) (xy 396.65832 -281.364)
			(xy 396.702782 -281.385098) (xy 396.743285 -281.413054) (xy 396.778778 -281.447146) (xy 396.808343 -281.48649)
			(xy 396.831214 -281.530067) (xy 396.846798 -281.576748) (xy 396.854693 -281.625325) (xy 396.855188 -281.649932)
			(xy 397.194036 -281.649932) (xy 397.197996 -281.600878) (xy 397.209773 -281.553094) (xy 397.229064 -281.507818)
			(xy 397.255367 -281.466222) (xy 397.288002 -281.429385) (xy 397.326123 -281.39826) (xy 397.368744 -281.373653)
			(xy 397.41476 -281.356201) (xy 397.462979 -281.346357) (xy 397.512154 -281.344376) (xy 397.561009 -281.350308)
			(xy 397.60828 -281.364) (xy 397.652742 -281.385098) (xy 397.693245 -281.413054) (xy 397.728738 -281.447146)
			(xy 397.758303 -281.48649) (xy 397.781174 -281.530067) (xy 397.796758 -281.576748) (xy 397.804653 -281.625325)
			(xy 397.805148 -281.649932) (xy 398.143996 -281.649932) (xy 398.147956 -281.600878) (xy 398.159733 -281.553094)
			(xy 398.179024 -281.507818) (xy 398.205327 -281.466222) (xy 398.237962 -281.429385) (xy 398.276083 -281.39826)
			(xy 398.318704 -281.373653) (xy 398.36472 -281.356201) (xy 398.412939 -281.346357) (xy 398.462114 -281.344376)
			(xy 398.510969 -281.350308) (xy 398.55824 -281.364) (xy 398.602702 -281.385098) (xy 398.643205 -281.413054)
			(xy 398.678698 -281.447146) (xy 398.708263 -281.48649) (xy 398.731134 -281.530067) (xy 398.746718 -281.576748)
			(xy 398.754613 -281.625325) (xy 398.755108 -281.649932) (xy 399.09421 -281.649932) (xy 399.09817 -281.600878)
			(xy 399.109947 -281.553094) (xy 399.129238 -281.507818) (xy 399.155541 -281.466222) (xy 399.188176 -281.429385)
			(xy 399.226297 -281.39826) (xy 399.268918 -281.373653) (xy 399.314934 -281.356201) (xy 399.363153 -281.346357)
			(xy 399.412328 -281.344376) (xy 399.461183 -281.350308) (xy 399.508454 -281.364) (xy 399.552916 -281.385098)
			(xy 399.593419 -281.413054) (xy 399.628912 -281.447146) (xy 399.658477 -281.48649) (xy 399.681348 -281.530067)
			(xy 399.696932 -281.576748) (xy 399.704827 -281.625325) (xy 399.705322 -281.649932) (xy 400.04417 -281.649932)
			(xy 400.04813 -281.600878) (xy 400.059907 -281.553094) (xy 400.079198 -281.507818) (xy 400.105501 -281.466222)
			(xy 400.138136 -281.429385) (xy 400.176257 -281.39826) (xy 400.218878 -281.373653) (xy 400.264894 -281.356201)
			(xy 400.313113 -281.346357) (xy 400.362288 -281.344376) (xy 400.411143 -281.350308) (xy 400.458414 -281.364)
			(xy 400.502876 -281.385098) (xy 400.543379 -281.413054) (xy 400.578872 -281.447146) (xy 400.608437 -281.48649)
			(xy 400.631308 -281.530067) (xy 400.646892 -281.576748) (xy 400.654787 -281.625325) (xy 400.655282 -281.649932)
			(xy 400.99413 -281.649932) (xy 400.99809 -281.600878) (xy 401.009867 -281.553094) (xy 401.029158 -281.507818)
			(xy 401.055461 -281.466222) (xy 401.088096 -281.429385) (xy 401.126217 -281.39826) (xy 401.168838 -281.373653)
			(xy 401.214854 -281.356201) (xy 401.263073 -281.346357) (xy 401.312248 -281.344376) (xy 401.361103 -281.350308)
			(xy 401.408374 -281.364) (xy 401.452836 -281.385098) (xy 401.493339 -281.413054) (xy 401.528832 -281.447146)
			(xy 401.558397 -281.48649) (xy 401.581268 -281.530067) (xy 401.596852 -281.576748) (xy 401.604747 -281.625325)
			(xy 401.605242 -281.649932) (xy 401.94409 -281.649932) (xy 401.94805 -281.600878) (xy 401.959827 -281.553094)
			(xy 401.979118 -281.507818) (xy 402.005421 -281.466222) (xy 402.038056 -281.429385) (xy 402.076177 -281.39826)
			(xy 402.118798 -281.373653) (xy 402.164814 -281.356201) (xy 402.213033 -281.346357) (xy 402.262208 -281.344376)
			(xy 402.311063 -281.350308) (xy 402.358334 -281.364) (xy 402.402796 -281.385098) (xy 402.443299 -281.413054)
			(xy 402.478792 -281.447146) (xy 402.508357 -281.48649) (xy 402.531228 -281.530067) (xy 402.546812 -281.576748)
			(xy 402.554707 -281.625325) (xy 402.555202 -281.649932) (xy 402.89405 -281.649932) (xy 402.89801 -281.600878)
			(xy 402.909787 -281.553094) (xy 402.929078 -281.507818) (xy 402.955381 -281.466222) (xy 402.988016 -281.429385)
			(xy 403.026137 -281.39826) (xy 403.068758 -281.373653) (xy 403.114774 -281.356201) (xy 403.162993 -281.346357)
			(xy 403.212168 -281.344376) (xy 403.261023 -281.350308) (xy 403.308294 -281.364) (xy 403.352756 -281.385098)
			(xy 403.393259 -281.413054) (xy 403.428752 -281.447146) (xy 403.458317 -281.48649) (xy 403.481188 -281.530067)
			(xy 403.496772 -281.576748) (xy 403.504667 -281.625325) (xy 403.505162 -281.649932) (xy 403.84401 -281.649932)
			(xy 403.84797 -281.600878) (xy 403.859747 -281.553094) (xy 403.879038 -281.507818) (xy 403.905341 -281.466222)
			(xy 403.937976 -281.429385) (xy 403.976097 -281.39826) (xy 404.018718 -281.373653) (xy 404.064734 -281.356201)
			(xy 404.112953 -281.346357) (xy 404.162128 -281.344376) (xy 404.210983 -281.350308) (xy 404.258254 -281.364)
			(xy 404.302716 -281.385098) (xy 404.343219 -281.413054) (xy 404.378712 -281.447146) (xy 404.408277 -281.48649)
			(xy 404.431148 -281.530067) (xy 404.446732 -281.576748) (xy 404.454627 -281.625325) (xy 404.455122 -281.649932)
			(xy 404.794224 -281.649932) (xy 404.798184 -281.600878) (xy 404.809961 -281.553094) (xy 404.829252 -281.507818)
			(xy 404.855555 -281.466222) (xy 404.88819 -281.429385) (xy 404.926311 -281.39826) (xy 404.968932 -281.373653)
			(xy 405.014948 -281.356201) (xy 405.063167 -281.346357) (xy 405.112342 -281.344376) (xy 405.161197 -281.350308)
			(xy 405.208468 -281.364) (xy 405.25293 -281.385098) (xy 405.293433 -281.413054) (xy 405.328926 -281.447146)
			(xy 405.358491 -281.48649) (xy 405.381362 -281.530067) (xy 405.396946 -281.576748) (xy 405.404841 -281.625325)
			(xy 405.405336 -281.649932) (xy 405.744184 -281.649932) (xy 405.748144 -281.600878) (xy 405.759921 -281.553094)
			(xy 405.779212 -281.507818) (xy 405.805515 -281.466222) (xy 405.83815 -281.429385) (xy 405.876271 -281.39826)
			(xy 405.918892 -281.373653) (xy 405.964908 -281.356201) (xy 406.013127 -281.346357) (xy 406.062302 -281.344376)
			(xy 406.111157 -281.350308) (xy 406.158428 -281.364) (xy 406.20289 -281.385098) (xy 406.243393 -281.413054)
			(xy 406.278886 -281.447146) (xy 406.308451 -281.48649) (xy 406.331322 -281.530067) (xy 406.346906 -281.576748)
			(xy 406.354801 -281.625325) (xy 406.355296 -281.649932) (xy 406.694144 -281.649932) (xy 406.698104 -281.600878)
			(xy 406.709881 -281.553094) (xy 406.729172 -281.507818) (xy 406.755475 -281.466222) (xy 406.78811 -281.429385)
			(xy 406.826231 -281.39826) (xy 406.868852 -281.373653) (xy 406.914868 -281.356201) (xy 406.963087 -281.346357)
			(xy 407.012262 -281.344376) (xy 407.061117 -281.350308) (xy 407.108388 -281.364) (xy 407.15285 -281.385098)
			(xy 407.193353 -281.413054) (xy 407.228846 -281.447146) (xy 407.258411 -281.48649) (xy 407.281282 -281.530067)
			(xy 407.296866 -281.576748) (xy 407.304761 -281.625325) (xy 407.305256 -281.649932) (xy 407.644104 -281.649932)
			(xy 407.648064 -281.600878) (xy 407.659841 -281.553094) (xy 407.679132 -281.507818) (xy 407.705435 -281.466222)
			(xy 407.73807 -281.429385) (xy 407.776191 -281.39826) (xy 407.818812 -281.373653) (xy 407.864828 -281.356201)
			(xy 407.913047 -281.346357) (xy 407.962222 -281.344376) (xy 408.011077 -281.350308) (xy 408.058348 -281.364)
			(xy 408.10281 -281.385098) (xy 408.143313 -281.413054) (xy 408.178806 -281.447146) (xy 408.208371 -281.48649)
			(xy 408.231242 -281.530067) (xy 408.246826 -281.576748) (xy 408.254721 -281.625325) (xy 408.255216 -281.649932)
			(xy 408.594064 -281.649932) (xy 408.598024 -281.600878) (xy 408.609801 -281.553094) (xy 408.629092 -281.507818)
			(xy 408.655395 -281.466222) (xy 408.68803 -281.429385) (xy 408.726151 -281.39826) (xy 408.768772 -281.373653)
			(xy 408.814788 -281.356201) (xy 408.863007 -281.346357) (xy 408.912182 -281.344376) (xy 408.961037 -281.350308)
			(xy 409.008308 -281.364) (xy 409.05277 -281.385098) (xy 409.093273 -281.413054) (xy 409.128766 -281.447146)
			(xy 409.158331 -281.48649) (xy 409.181202 -281.530067) (xy 409.196786 -281.576748) (xy 409.204681 -281.625325)
			(xy 409.205176 -281.649932) (xy 409.544024 -281.649932) (xy 409.547984 -281.600878) (xy 409.559761 -281.553094)
			(xy 409.579052 -281.507818) (xy 409.605355 -281.466222) (xy 409.63799 -281.429385) (xy 409.676111 -281.39826)
			(xy 409.718732 -281.373653) (xy 409.764748 -281.356201) (xy 409.812967 -281.346357) (xy 409.862142 -281.344376)
			(xy 409.910997 -281.350308) (xy 409.958268 -281.364) (xy 410.00273 -281.385098) (xy 410.043233 -281.413054)
			(xy 410.078726 -281.447146) (xy 410.108291 -281.48649) (xy 410.131162 -281.530067) (xy 410.146746 -281.576748)
			(xy 410.154641 -281.625325) (xy 410.155136 -281.649932) (xy 410.493984 -281.649932) (xy 410.497944 -281.600878)
			(xy 410.509721 -281.553094) (xy 410.529012 -281.507818) (xy 410.555315 -281.466222) (xy 410.58795 -281.429385)
			(xy 410.626071 -281.39826) (xy 410.668692 -281.373653) (xy 410.714708 -281.356201) (xy 410.762927 -281.346357)
			(xy 410.812102 -281.344376) (xy 410.860957 -281.350308) (xy 410.908228 -281.364) (xy 410.95269 -281.385098)
			(xy 410.993193 -281.413054) (xy 411.028686 -281.447146) (xy 411.058251 -281.48649) (xy 411.081122 -281.530067)
			(xy 411.096706 -281.576748) (xy 411.104601 -281.625325) (xy 411.105096 -281.649932) (xy 411.444198 -281.649932)
			(xy 411.448158 -281.600878) (xy 411.459935 -281.553094) (xy 411.479226 -281.507818) (xy 411.505529 -281.466222)
			(xy 411.538164 -281.429385) (xy 411.576285 -281.39826) (xy 411.618906 -281.373653) (xy 411.664922 -281.356201)
			(xy 411.713141 -281.346357) (xy 411.762316 -281.344376) (xy 411.811171 -281.350308) (xy 411.858442 -281.364)
			(xy 411.902904 -281.385098) (xy 411.943407 -281.413054) (xy 411.9789 -281.447146) (xy 412.008465 -281.48649)
			(xy 412.031336 -281.530067) (xy 412.04692 -281.576748) (xy 412.054815 -281.625325) (xy 412.05531 -281.649932)
			(xy 412.394158 -281.649932) (xy 412.398118 -281.600878) (xy 412.409895 -281.553094) (xy 412.429186 -281.507818)
			(xy 412.455489 -281.466222) (xy 412.488124 -281.429385) (xy 412.526245 -281.39826) (xy 412.568866 -281.373653)
			(xy 412.614882 -281.356201) (xy 412.663101 -281.346357) (xy 412.712276 -281.344376) (xy 412.761131 -281.350308)
			(xy 412.808402 -281.364) (xy 412.852864 -281.385098) (xy 412.893367 -281.413054) (xy 412.92886 -281.447146)
			(xy 412.958425 -281.48649) (xy 412.981296 -281.530067) (xy 412.99688 -281.576748) (xy 413.004775 -281.625325)
			(xy 413.00527 -281.649932) (xy 413.344118 -281.649932) (xy 413.348078 -281.600878) (xy 413.359855 -281.553094)
			(xy 413.379146 -281.507818) (xy 413.405449 -281.466222) (xy 413.438084 -281.429385) (xy 413.476205 -281.39826)
			(xy 413.518826 -281.373653) (xy 413.564842 -281.356201) (xy 413.613061 -281.346357) (xy 413.662236 -281.344376)
			(xy 413.711091 -281.350308) (xy 413.758362 -281.364) (xy 413.802824 -281.385098) (xy 413.843327 -281.413054)
			(xy 413.87882 -281.447146) (xy 413.908385 -281.48649) (xy 413.931256 -281.530067) (xy 413.94684 -281.576748)
			(xy 413.954735 -281.625325) (xy 413.95523 -281.649932) (xy 414.294078 -281.649932) (xy 414.298038 -281.600878)
			(xy 414.309815 -281.553094) (xy 414.329106 -281.507818) (xy 414.355409 -281.466222) (xy 414.388044 -281.429385)
			(xy 414.426165 -281.39826) (xy 414.468786 -281.373653) (xy 414.514802 -281.356201) (xy 414.563021 -281.346357)
			(xy 414.612196 -281.344376) (xy 414.661051 -281.350308) (xy 414.708322 -281.364) (xy 414.752784 -281.385098)
			(xy 414.793287 -281.413054) (xy 414.82878 -281.447146) (xy 414.858345 -281.48649) (xy 414.881216 -281.530067)
			(xy 414.8968 -281.576748) (xy 414.904695 -281.625325) (xy 414.90519 -281.649932) (xy 415.244038 -281.649932)
			(xy 415.247998 -281.600878) (xy 415.259775 -281.553094) (xy 415.279066 -281.507818) (xy 415.305369 -281.466222)
			(xy 415.338004 -281.429385) (xy 415.376125 -281.39826) (xy 415.418746 -281.373653) (xy 415.464762 -281.356201)
			(xy 415.512981 -281.346357) (xy 415.562156 -281.344376) (xy 415.611011 -281.350308) (xy 415.658282 -281.364)
			(xy 415.702744 -281.385098) (xy 415.743247 -281.413054) (xy 415.77874 -281.447146) (xy 415.808305 -281.48649)
			(xy 415.831176 -281.530067) (xy 415.84676 -281.576748) (xy 415.854655 -281.625325) (xy 415.85515 -281.649932)
			(xy 416.193998 -281.649932) (xy 416.197958 -281.600878) (xy 416.209735 -281.553094) (xy 416.229026 -281.507818)
			(xy 416.255329 -281.466222) (xy 416.287964 -281.429385) (xy 416.326085 -281.39826) (xy 416.368706 -281.373653)
			(xy 416.414722 -281.356201) (xy 416.462941 -281.346357) (xy 416.512116 -281.344376) (xy 416.560971 -281.350308)
			(xy 416.608242 -281.364) (xy 416.652704 -281.385098) (xy 416.693207 -281.413054) (xy 416.7287 -281.447146)
			(xy 416.758265 -281.48649) (xy 416.781136 -281.530067) (xy 416.79672 -281.576748) (xy 416.804615 -281.625325)
			(xy 416.80511 -281.649932) (xy 417.144212 -281.649932) (xy 417.148172 -281.600878) (xy 417.159949 -281.553094)
			(xy 417.17924 -281.507818) (xy 417.205543 -281.466222) (xy 417.238178 -281.429385) (xy 417.276299 -281.39826)
			(xy 417.31892 -281.373653) (xy 417.364936 -281.356201) (xy 417.413155 -281.346357) (xy 417.46233 -281.344376)
			(xy 417.511185 -281.350308) (xy 417.558456 -281.364) (xy 417.602918 -281.385098) (xy 417.643421 -281.413054)
			(xy 417.678914 -281.447146) (xy 417.708479 -281.48649) (xy 417.73135 -281.530067) (xy 417.746934 -281.576748)
			(xy 417.754829 -281.625325) (xy 417.755324 -281.649932) (xy 418.094172 -281.649932) (xy 418.098132 -281.600878)
			(xy 418.109909 -281.553094) (xy 418.1292 -281.507818) (xy 418.155503 -281.466222) (xy 418.188138 -281.429385)
			(xy 418.226259 -281.39826) (xy 418.26888 -281.373653) (xy 418.314896 -281.356201) (xy 418.363115 -281.346357)
			(xy 418.41229 -281.344376) (xy 418.461145 -281.350308) (xy 418.508416 -281.364) (xy 418.552878 -281.385098)
			(xy 418.593381 -281.413054) (xy 418.628874 -281.447146) (xy 418.658439 -281.48649) (xy 418.68131 -281.530067)
			(xy 418.696894 -281.576748) (xy 418.704789 -281.625325) (xy 418.705284 -281.649932) (xy 419.044132 -281.649932)
			(xy 419.048092 -281.600878) (xy 419.059869 -281.553094) (xy 419.07916 -281.507818) (xy 419.105463 -281.466222)
			(xy 419.138098 -281.429385) (xy 419.176219 -281.39826) (xy 419.21884 -281.373653) (xy 419.264856 -281.356201)
			(xy 419.313075 -281.346357) (xy 419.36225 -281.344376) (xy 419.411105 -281.350308) (xy 419.458376 -281.364)
			(xy 419.502838 -281.385098) (xy 419.543341 -281.413054) (xy 419.578834 -281.447146) (xy 419.608399 -281.48649)
			(xy 419.63127 -281.530067) (xy 419.646854 -281.576748) (xy 419.654749 -281.625325) (xy 419.655244 -281.649932)
			(xy 419.994092 -281.649932) (xy 419.998052 -281.600878) (xy 420.009829 -281.553094) (xy 420.02912 -281.507818)
			(xy 420.055423 -281.466222) (xy 420.088058 -281.429385) (xy 420.126179 -281.39826) (xy 420.1688 -281.373653)
			(xy 420.214816 -281.356201) (xy 420.263035 -281.346357) (xy 420.31221 -281.344376) (xy 420.361065 -281.350308)
			(xy 420.408336 -281.364) (xy 420.452798 -281.385098) (xy 420.493301 -281.413054) (xy 420.528794 -281.447146)
			(xy 420.558359 -281.48649) (xy 420.58123 -281.530067) (xy 420.596814 -281.576748) (xy 420.604709 -281.625325)
			(xy 420.605204 -281.649932) (xy 420.944052 -281.649932) (xy 420.948012 -281.600878) (xy 420.959789 -281.553094)
			(xy 420.97908 -281.507818) (xy 421.005383 -281.466222) (xy 421.038018 -281.429385) (xy 421.076139 -281.39826)
			(xy 421.11876 -281.373653) (xy 421.164776 -281.356201) (xy 421.212995 -281.346357) (xy 421.26217 -281.344376)
			(xy 421.311025 -281.350308) (xy 421.358296 -281.364) (xy 421.402758 -281.385098) (xy 421.443261 -281.413054)
			(xy 421.478754 -281.447146) (xy 421.508319 -281.48649) (xy 421.53119 -281.530067) (xy 421.546774 -281.576748)
			(xy 421.554669 -281.625325) (xy 421.555164 -281.649932) (xy 421.554669 -281.674539) (xy 421.546774 -281.723116)
			(xy 421.53119 -281.769797) (xy 421.508319 -281.813374) (xy 421.478754 -281.852718) (xy 421.443261 -281.88681)
			(xy 421.402758 -281.914766) (xy 421.358296 -281.935864) (xy 421.311025 -281.949556) (xy 421.26217 -281.955488)
			(xy 421.212995 -281.953507) (xy 421.164776 -281.943663) (xy 421.11876 -281.926211) (xy 421.076139 -281.901604)
			(xy 421.038018 -281.870479) (xy 421.005383 -281.833642) (xy 420.97908 -281.792046) (xy 420.959789 -281.74677)
			(xy 420.948012 -281.698986) (xy 420.944052 -281.649932) (xy 420.605204 -281.649932) (xy 420.604709 -281.674539)
			(xy 420.596814 -281.723116) (xy 420.58123 -281.769797) (xy 420.558359 -281.813374) (xy 420.528794 -281.852718)
			(xy 420.493301 -281.88681) (xy 420.452798 -281.914766) (xy 420.408336 -281.935864) (xy 420.361065 -281.949556)
			(xy 420.31221 -281.955488) (xy 420.263035 -281.953507) (xy 420.214816 -281.943663) (xy 420.1688 -281.926211)
			(xy 420.126179 -281.901604) (xy 420.088058 -281.870479) (xy 420.055423 -281.833642) (xy 420.02912 -281.792046)
			(xy 420.009829 -281.74677) (xy 419.998052 -281.698986) (xy 419.994092 -281.649932) (xy 419.655244 -281.649932)
			(xy 419.654749 -281.674539) (xy 419.646854 -281.723116) (xy 419.63127 -281.769797) (xy 419.608399 -281.813374)
			(xy 419.578834 -281.852718) (xy 419.543341 -281.88681) (xy 419.502838 -281.914766) (xy 419.458376 -281.935864)
			(xy 419.411105 -281.949556) (xy 419.36225 -281.955488) (xy 419.313075 -281.953507) (xy 419.264856 -281.943663)
			(xy 419.21884 -281.926211) (xy 419.176219 -281.901604) (xy 419.138098 -281.870479) (xy 419.105463 -281.833642)
			(xy 419.07916 -281.792046) (xy 419.059869 -281.74677) (xy 419.048092 -281.698986) (xy 419.044132 -281.649932)
			(xy 418.705284 -281.649932) (xy 418.704789 -281.674539) (xy 418.696894 -281.723116) (xy 418.68131 -281.769797)
			(xy 418.658439 -281.813374) (xy 418.628874 -281.852718) (xy 418.593381 -281.88681) (xy 418.552878 -281.914766)
			(xy 418.508416 -281.935864) (xy 418.461145 -281.949556) (xy 418.41229 -281.955488) (xy 418.363115 -281.953507)
			(xy 418.314896 -281.943663) (xy 418.26888 -281.926211) (xy 418.226259 -281.901604) (xy 418.188138 -281.870479)
			(xy 418.155503 -281.833642) (xy 418.1292 -281.792046) (xy 418.109909 -281.74677) (xy 418.098132 -281.698986)
			(xy 418.094172 -281.649932) (xy 417.755324 -281.649932) (xy 417.754829 -281.674539) (xy 417.746934 -281.723116)
			(xy 417.73135 -281.769797) (xy 417.708479 -281.813374) (xy 417.678914 -281.852718) (xy 417.643421 -281.88681)
			(xy 417.602918 -281.914766) (xy 417.558456 -281.935864) (xy 417.511185 -281.949556) (xy 417.46233 -281.955488)
			(xy 417.413155 -281.953507) (xy 417.364936 -281.943663) (xy 417.31892 -281.926211) (xy 417.276299 -281.901604)
			(xy 417.238178 -281.870479) (xy 417.205543 -281.833642) (xy 417.17924 -281.792046) (xy 417.159949 -281.74677)
			(xy 417.148172 -281.698986) (xy 417.144212 -281.649932) (xy 416.80511 -281.649932) (xy 416.804615 -281.674539)
			(xy 416.79672 -281.723116) (xy 416.781136 -281.769797) (xy 416.758265 -281.813374) (xy 416.7287 -281.852718)
			(xy 416.693207 -281.88681) (xy 416.652704 -281.914766) (xy 416.608242 -281.935864) (xy 416.560971 -281.949556)
			(xy 416.512116 -281.955488) (xy 416.462941 -281.953507) (xy 416.414722 -281.943663) (xy 416.368706 -281.926211)
			(xy 416.326085 -281.901604) (xy 416.287964 -281.870479) (xy 416.255329 -281.833642) (xy 416.229026 -281.792046)
			(xy 416.209735 -281.74677) (xy 416.197958 -281.698986) (xy 416.193998 -281.649932) (xy 415.85515 -281.649932)
			(xy 415.854655 -281.674539) (xy 415.84676 -281.723116) (xy 415.831176 -281.769797) (xy 415.808305 -281.813374)
			(xy 415.77874 -281.852718) (xy 415.743247 -281.88681) (xy 415.702744 -281.914766) (xy 415.658282 -281.935864)
			(xy 415.611011 -281.949556) (xy 415.562156 -281.955488) (xy 415.512981 -281.953507) (xy 415.464762 -281.943663)
			(xy 415.418746 -281.926211) (xy 415.376125 -281.901604) (xy 415.338004 -281.870479) (xy 415.305369 -281.833642)
			(xy 415.279066 -281.792046) (xy 415.259775 -281.74677) (xy 415.247998 -281.698986) (xy 415.244038 -281.649932)
			(xy 414.90519 -281.649932) (xy 414.904695 -281.674539) (xy 414.8968 -281.723116) (xy 414.881216 -281.769797)
			(xy 414.858345 -281.813374) (xy 414.82878 -281.852718) (xy 414.793287 -281.88681) (xy 414.752784 -281.914766)
			(xy 414.708322 -281.935864) (xy 414.661051 -281.949556) (xy 414.612196 -281.955488) (xy 414.563021 -281.953507)
			(xy 414.514802 -281.943663) (xy 414.468786 -281.926211) (xy 414.426165 -281.901604) (xy 414.388044 -281.870479)
			(xy 414.355409 -281.833642) (xy 414.329106 -281.792046) (xy 414.309815 -281.74677) (xy 414.298038 -281.698986)
			(xy 414.294078 -281.649932) (xy 413.95523 -281.649932) (xy 413.954735 -281.674539) (xy 413.94684 -281.723116)
			(xy 413.931256 -281.769797) (xy 413.908385 -281.813374) (xy 413.87882 -281.852718) (xy 413.843327 -281.88681)
			(xy 413.802824 -281.914766) (xy 413.758362 -281.935864) (xy 413.711091 -281.949556) (xy 413.662236 -281.955488)
			(xy 413.613061 -281.953507) (xy 413.564842 -281.943663) (xy 413.518826 -281.926211) (xy 413.476205 -281.901604)
			(xy 413.438084 -281.870479) (xy 413.405449 -281.833642) (xy 413.379146 -281.792046) (xy 413.359855 -281.74677)
			(xy 413.348078 -281.698986) (xy 413.344118 -281.649932) (xy 413.00527 -281.649932) (xy 413.004775 -281.674539)
			(xy 412.99688 -281.723116) (xy 412.981296 -281.769797) (xy 412.958425 -281.813374) (xy 412.92886 -281.852718)
			(xy 412.893367 -281.88681) (xy 412.852864 -281.914766) (xy 412.808402 -281.935864) (xy 412.761131 -281.949556)
			(xy 412.712276 -281.955488) (xy 412.663101 -281.953507) (xy 412.614882 -281.943663) (xy 412.568866 -281.926211)
			(xy 412.526245 -281.901604) (xy 412.488124 -281.870479) (xy 412.455489 -281.833642) (xy 412.429186 -281.792046)
			(xy 412.409895 -281.74677) (xy 412.398118 -281.698986) (xy 412.394158 -281.649932) (xy 412.05531 -281.649932)
			(xy 412.054815 -281.674539) (xy 412.04692 -281.723116) (xy 412.031336 -281.769797) (xy 412.008465 -281.813374)
			(xy 411.9789 -281.852718) (xy 411.943407 -281.88681) (xy 411.902904 -281.914766) (xy 411.858442 -281.935864)
			(xy 411.811171 -281.949556) (xy 411.762316 -281.955488) (xy 411.713141 -281.953507) (xy 411.664922 -281.943663)
			(xy 411.618906 -281.926211) (xy 411.576285 -281.901604) (xy 411.538164 -281.870479) (xy 411.505529 -281.833642)
			(xy 411.479226 -281.792046) (xy 411.459935 -281.74677) (xy 411.448158 -281.698986) (xy 411.444198 -281.649932)
			(xy 411.105096 -281.649932) (xy 411.104601 -281.674539) (xy 411.096706 -281.723116) (xy 411.081122 -281.769797)
			(xy 411.058251 -281.813374) (xy 411.028686 -281.852718) (xy 410.993193 -281.88681) (xy 410.95269 -281.914766)
			(xy 410.908228 -281.935864) (xy 410.860957 -281.949556) (xy 410.812102 -281.955488) (xy 410.762927 -281.953507)
			(xy 410.714708 -281.943663) (xy 410.668692 -281.926211) (xy 410.626071 -281.901604) (xy 410.58795 -281.870479)
			(xy 410.555315 -281.833642) (xy 410.529012 -281.792046) (xy 410.509721 -281.74677) (xy 410.497944 -281.698986)
			(xy 410.493984 -281.649932) (xy 410.155136 -281.649932) (xy 410.154641 -281.674539) (xy 410.146746 -281.723116)
			(xy 410.131162 -281.769797) (xy 410.108291 -281.813374) (xy 410.078726 -281.852718) (xy 410.043233 -281.88681)
			(xy 410.00273 -281.914766) (xy 409.958268 -281.935864) (xy 409.910997 -281.949556) (xy 409.862142 -281.955488)
			(xy 409.812967 -281.953507) (xy 409.764748 -281.943663) (xy 409.718732 -281.926211) (xy 409.676111 -281.901604)
			(xy 409.63799 -281.870479) (xy 409.605355 -281.833642) (xy 409.579052 -281.792046) (xy 409.559761 -281.74677)
			(xy 409.547984 -281.698986) (xy 409.544024 -281.649932) (xy 409.205176 -281.649932) (xy 409.204681 -281.674539)
			(xy 409.196786 -281.723116) (xy 409.181202 -281.769797) (xy 409.158331 -281.813374) (xy 409.128766 -281.852718)
			(xy 409.093273 -281.88681) (xy 409.05277 -281.914766) (xy 409.008308 -281.935864) (xy 408.961037 -281.949556)
			(xy 408.912182 -281.955488) (xy 408.863007 -281.953507) (xy 408.814788 -281.943663) (xy 408.768772 -281.926211)
			(xy 408.726151 -281.901604) (xy 408.68803 -281.870479) (xy 408.655395 -281.833642) (xy 408.629092 -281.792046)
			(xy 408.609801 -281.74677) (xy 408.598024 -281.698986) (xy 408.594064 -281.649932) (xy 408.255216 -281.649932)
			(xy 408.254721 -281.674539) (xy 408.246826 -281.723116) (xy 408.231242 -281.769797) (xy 408.208371 -281.813374)
			(xy 408.178806 -281.852718) (xy 408.143313 -281.88681) (xy 408.10281 -281.914766) (xy 408.058348 -281.935864)
			(xy 408.011077 -281.949556) (xy 407.962222 -281.955488) (xy 407.913047 -281.953507) (xy 407.864828 -281.943663)
			(xy 407.818812 -281.926211) (xy 407.776191 -281.901604) (xy 407.73807 -281.870479) (xy 407.705435 -281.833642)
			(xy 407.679132 -281.792046) (xy 407.659841 -281.74677) (xy 407.648064 -281.698986) (xy 407.644104 -281.649932)
			(xy 407.305256 -281.649932) (xy 407.304761 -281.674539) (xy 407.296866 -281.723116) (xy 407.281282 -281.769797)
			(xy 407.258411 -281.813374) (xy 407.228846 -281.852718) (xy 407.193353 -281.88681) (xy 407.15285 -281.914766)
			(xy 407.108388 -281.935864) (xy 407.061117 -281.949556) (xy 407.012262 -281.955488) (xy 406.963087 -281.953507)
			(xy 406.914868 -281.943663) (xy 406.868852 -281.926211) (xy 406.826231 -281.901604) (xy 406.78811 -281.870479)
			(xy 406.755475 -281.833642) (xy 406.729172 -281.792046) (xy 406.709881 -281.74677) (xy 406.698104 -281.698986)
			(xy 406.694144 -281.649932) (xy 406.355296 -281.649932) (xy 406.354801 -281.674539) (xy 406.346906 -281.723116)
			(xy 406.331322 -281.769797) (xy 406.308451 -281.813374) (xy 406.278886 -281.852718) (xy 406.243393 -281.88681)
			(xy 406.20289 -281.914766) (xy 406.158428 -281.935864) (xy 406.111157 -281.949556) (xy 406.062302 -281.955488)
			(xy 406.013127 -281.953507) (xy 405.964908 -281.943663) (xy 405.918892 -281.926211) (xy 405.876271 -281.901604)
			(xy 405.83815 -281.870479) (xy 405.805515 -281.833642) (xy 405.779212 -281.792046) (xy 405.759921 -281.74677)
			(xy 405.748144 -281.698986) (xy 405.744184 -281.649932) (xy 405.405336 -281.649932) (xy 405.404841 -281.674539)
			(xy 405.396946 -281.723116) (xy 405.381362 -281.769797) (xy 405.358491 -281.813374) (xy 405.328926 -281.852718)
			(xy 405.293433 -281.88681) (xy 405.25293 -281.914766) (xy 405.208468 -281.935864) (xy 405.161197 -281.949556)
			(xy 405.112342 -281.955488) (xy 405.063167 -281.953507) (xy 405.014948 -281.943663) (xy 404.968932 -281.926211)
			(xy 404.926311 -281.901604) (xy 404.88819 -281.870479) (xy 404.855555 -281.833642) (xy 404.829252 -281.792046)
			(xy 404.809961 -281.74677) (xy 404.798184 -281.698986) (xy 404.794224 -281.649932) (xy 404.455122 -281.649932)
			(xy 404.454627 -281.674539) (xy 404.446732 -281.723116) (xy 404.431148 -281.769797) (xy 404.408277 -281.813374)
			(xy 404.378712 -281.852718) (xy 404.343219 -281.88681) (xy 404.302716 -281.914766) (xy 404.258254 -281.935864)
			(xy 404.210983 -281.949556) (xy 404.162128 -281.955488) (xy 404.112953 -281.953507) (xy 404.064734 -281.943663)
			(xy 404.018718 -281.926211) (xy 403.976097 -281.901604) (xy 403.937976 -281.870479) (xy 403.905341 -281.833642)
			(xy 403.879038 -281.792046) (xy 403.859747 -281.74677) (xy 403.84797 -281.698986) (xy 403.84401 -281.649932)
			(xy 403.505162 -281.649932) (xy 403.504667 -281.674539) (xy 403.496772 -281.723116) (xy 403.481188 -281.769797)
			(xy 403.458317 -281.813374) (xy 403.428752 -281.852718) (xy 403.393259 -281.88681) (xy 403.352756 -281.914766)
			(xy 403.308294 -281.935864) (xy 403.261023 -281.949556) (xy 403.212168 -281.955488) (xy 403.162993 -281.953507)
			(xy 403.114774 -281.943663) (xy 403.068758 -281.926211) (xy 403.026137 -281.901604) (xy 402.988016 -281.870479)
			(xy 402.955381 -281.833642) (xy 402.929078 -281.792046) (xy 402.909787 -281.74677) (xy 402.89801 -281.698986)
			(xy 402.89405 -281.649932) (xy 402.555202 -281.649932) (xy 402.554707 -281.674539) (xy 402.546812 -281.723116)
			(xy 402.531228 -281.769797) (xy 402.508357 -281.813374) (xy 402.478792 -281.852718) (xy 402.443299 -281.88681)
			(xy 402.402796 -281.914766) (xy 402.358334 -281.935864) (xy 402.311063 -281.949556) (xy 402.262208 -281.955488)
			(xy 402.213033 -281.953507) (xy 402.164814 -281.943663) (xy 402.118798 -281.926211) (xy 402.076177 -281.901604)
			(xy 402.038056 -281.870479) (xy 402.005421 -281.833642) (xy 401.979118 -281.792046) (xy 401.959827 -281.74677)
			(xy 401.94805 -281.698986) (xy 401.94409 -281.649932) (xy 401.605242 -281.649932) (xy 401.604747 -281.674539)
			(xy 401.596852 -281.723116) (xy 401.581268 -281.769797) (xy 401.558397 -281.813374) (xy 401.528832 -281.852718)
			(xy 401.493339 -281.88681) (xy 401.452836 -281.914766) (xy 401.408374 -281.935864) (xy 401.361103 -281.949556)
			(xy 401.312248 -281.955488) (xy 401.263073 -281.953507) (xy 401.214854 -281.943663) (xy 401.168838 -281.926211)
			(xy 401.126217 -281.901604) (xy 401.088096 -281.870479) (xy 401.055461 -281.833642) (xy 401.029158 -281.792046)
			(xy 401.009867 -281.74677) (xy 400.99809 -281.698986) (xy 400.99413 -281.649932) (xy 400.655282 -281.649932)
			(xy 400.654787 -281.674539) (xy 400.646892 -281.723116) (xy 400.631308 -281.769797) (xy 400.608437 -281.813374)
			(xy 400.578872 -281.852718) (xy 400.543379 -281.88681) (xy 400.502876 -281.914766) (xy 400.458414 -281.935864)
			(xy 400.411143 -281.949556) (xy 400.362288 -281.955488) (xy 400.313113 -281.953507) (xy 400.264894 -281.943663)
			(xy 400.218878 -281.926211) (xy 400.176257 -281.901604) (xy 400.138136 -281.870479) (xy 400.105501 -281.833642)
			(xy 400.079198 -281.792046) (xy 400.059907 -281.74677) (xy 400.04813 -281.698986) (xy 400.04417 -281.649932)
			(xy 399.705322 -281.649932) (xy 399.704827 -281.674539) (xy 399.696932 -281.723116) (xy 399.681348 -281.769797)
			(xy 399.658477 -281.813374) (xy 399.628912 -281.852718) (xy 399.593419 -281.88681) (xy 399.552916 -281.914766)
			(xy 399.508454 -281.935864) (xy 399.461183 -281.949556) (xy 399.412328 -281.955488) (xy 399.363153 -281.953507)
			(xy 399.314934 -281.943663) (xy 399.268918 -281.926211) (xy 399.226297 -281.901604) (xy 399.188176 -281.870479)
			(xy 399.155541 -281.833642) (xy 399.129238 -281.792046) (xy 399.109947 -281.74677) (xy 399.09817 -281.698986)
			(xy 399.09421 -281.649932) (xy 398.755108 -281.649932) (xy 398.754613 -281.674539) (xy 398.746718 -281.723116)
			(xy 398.731134 -281.769797) (xy 398.708263 -281.813374) (xy 398.678698 -281.852718) (xy 398.643205 -281.88681)
			(xy 398.602702 -281.914766) (xy 398.55824 -281.935864) (xy 398.510969 -281.949556) (xy 398.462114 -281.955488)
			(xy 398.412939 -281.953507) (xy 398.36472 -281.943663) (xy 398.318704 -281.926211) (xy 398.276083 -281.901604)
			(xy 398.237962 -281.870479) (xy 398.205327 -281.833642) (xy 398.179024 -281.792046) (xy 398.159733 -281.74677)
			(xy 398.147956 -281.698986) (xy 398.143996 -281.649932) (xy 397.805148 -281.649932) (xy 397.804653 -281.674539)
			(xy 397.796758 -281.723116) (xy 397.781174 -281.769797) (xy 397.758303 -281.813374) (xy 397.728738 -281.852718)
			(xy 397.693245 -281.88681) (xy 397.652742 -281.914766) (xy 397.60828 -281.935864) (xy 397.561009 -281.949556)
			(xy 397.512154 -281.955488) (xy 397.462979 -281.953507) (xy 397.41476 -281.943663) (xy 397.368744 -281.926211)
			(xy 397.326123 -281.901604) (xy 397.288002 -281.870479) (xy 397.255367 -281.833642) (xy 397.229064 -281.792046)
			(xy 397.209773 -281.74677) (xy 397.197996 -281.698986) (xy 397.194036 -281.649932) (xy 396.855188 -281.649932)
			(xy 396.854693 -281.674539) (xy 396.846798 -281.723116) (xy 396.831214 -281.769797) (xy 396.808343 -281.813374)
			(xy 396.778778 -281.852718) (xy 396.743285 -281.88681) (xy 396.702782 -281.914766) (xy 396.65832 -281.935864)
			(xy 396.611049 -281.949556) (xy 396.562194 -281.955488) (xy 396.513019 -281.953507) (xy 396.4648 -281.943663)
			(xy 396.418784 -281.926211) (xy 396.376163 -281.901604) (xy 396.338042 -281.870479) (xy 396.305407 -281.833642)
			(xy 396.279104 -281.792046) (xy 396.259813 -281.74677) (xy 396.248036 -281.698986) (xy 396.244076 -281.649932)
			(xy 395.905228 -281.649932) (xy 395.904733 -281.674539) (xy 395.896838 -281.723116) (xy 395.881254 -281.769797)
			(xy 395.858383 -281.813374) (xy 395.828818 -281.852718) (xy 395.793325 -281.88681) (xy 395.752822 -281.914766)
			(xy 395.70836 -281.935864) (xy 395.661089 -281.949556) (xy 395.612234 -281.955488) (xy 395.563059 -281.953507)
			(xy 395.51484 -281.943663) (xy 395.468824 -281.926211) (xy 395.426203 -281.901604) (xy 395.388082 -281.870479)
			(xy 395.355447 -281.833642) (xy 395.329144 -281.792046) (xy 395.309853 -281.74677) (xy 395.298076 -281.698986)
			(xy 395.294116 -281.649932) (xy 394.955302 -281.649932) (xy 394.95575 -281.658199) (xy 394.950379 -281.707557)
			(xy 394.937094 -281.755396) (xy 394.916243 -281.800455) (xy 394.888377 -281.841547) (xy 394.85423 -281.877589)
			(xy 394.814702 -281.907632) (xy 394.770833 -281.930883) (xy 394.723781 -281.946731) (xy 394.674785 -281.954757)
			(xy 394.64996 -281.95524) (xy 394.635777 -281.955068) (xy 394.607537 -281.952393) (xy 394.593572 -281.949906)
			(xy 394.581126 -281.94762) (xy 394.557504 -281.954986) (xy 394.480034 -282.032456) (xy 394.472668 -282.056078)
			(xy 394.474954 -282.068524) (xy 394.477429 -282.08249) (xy 394.480102 -282.11073) (xy 394.480288 -282.124912)
			(xy 394.479766 -282.150167) (xy 394.471453 -282.199989) (xy 394.455052 -282.247763) (xy 394.431011 -282.292186)
			(xy 394.399987 -282.332046) (xy 394.362825 -282.366256) (xy 394.320539 -282.393882) (xy 394.274283 -282.414172)
			(xy 394.225318 -282.426572) (xy 394.17498 -282.430743) (xy 394.124642 -282.426572) (xy 394.075677 -282.414172)
			(xy 394.029421 -282.393882) (xy 393.987135 -282.366256) (xy 393.949973 -282.332046) (xy 393.918949 -282.292186)
			(xy 393.894908 -282.247763) (xy 393.878507 -282.199989) (xy 393.870194 -282.150167) (xy 393.869672 -282.124912)
			(xy 393.869851 -282.110729) (xy 393.872521 -282.082489) (xy 393.875006 -282.068524) (xy 393.877292 -282.056078)
			(xy 393.869926 -282.032456) (xy 393.792456 -281.954986) (xy 393.768834 -281.94762) (xy 393.756388 -281.949906)
			(xy 393.742422 -281.95238) (xy 393.714182 -281.955053) (xy 393.7 -281.95524) (xy 393.685817 -281.955063)
			(xy 393.657577 -281.952391) (xy 393.643612 -281.949906) (xy 393.631166 -281.94762) (xy 393.607544 -281.954986)
			(xy 393.530074 -282.032456) (xy 393.522708 -282.056078) (xy 393.524994 -282.068524) (xy 393.52747 -282.08249)
			(xy 393.530142 -282.110729) (xy 393.530328 -282.124912) (xy 393.529809 -282.149732) (xy 393.521776 -282.198718)
			(xy 393.505924 -282.245759) (xy 393.482671 -282.289615) (xy 393.452628 -282.329132) (xy 393.416588 -282.363268)
			(xy 393.3755 -282.391123) (xy 393.330447 -282.411965) (xy 393.282616 -282.425243) (xy 393.233267 -282.430607)
			(xy 393.1837 -282.427917) (xy 393.135221 -282.417244) (xy 393.089107 -282.398868) (xy 393.046574 -282.373274)
			(xy 393.008742 -282.341135) (xy 392.976608 -282.3033) (xy 392.951018 -282.260764) (xy 392.932647 -282.214649)
			(xy 392.921978 -282.166169) (xy 392.919294 -282.116601) (xy 392.579947 -282.116601) (xy 392.580114 -282.124912)
			(xy 392.579619 -282.149519) (xy 392.571724 -282.198096) (xy 392.55614 -282.244777) (xy 392.533269 -282.288354)
			(xy 392.503704 -282.327698) (xy 392.468211 -282.36179) (xy 392.427708 -282.389746) (xy 392.383246 -282.410844)
			(xy 392.335975 -282.424536) (xy 392.28712 -282.430468) (xy 392.237945 -282.428487) (xy 392.189726 -282.418643)
			(xy 392.14371 -282.401191) (xy 392.101089 -282.376584) (xy 392.062968 -282.345459) (xy 392.030333 -282.308622)
			(xy 392.00403 -282.267026) (xy 391.984739 -282.22175) (xy 391.972962 -282.173966) (xy 391.969002 -282.124912)
			(xy 391.630154 -282.124912) (xy 391.629659 -282.149519) (xy 391.621764 -282.198096) (xy 391.60618 -282.244777)
			(xy 391.583309 -282.288354) (xy 391.553744 -282.327698) (xy 391.518251 -282.36179) (xy 391.477748 -282.389746)
			(xy 391.433286 -282.410844) (xy 391.386015 -282.424536) (xy 391.33716 -282.430468) (xy 391.287985 -282.428487)
			(xy 391.239766 -282.418643) (xy 391.19375 -282.401191) (xy 391.151129 -282.376584) (xy 391.113008 -282.345459)
			(xy 391.080373 -282.308622) (xy 391.05407 -282.267026) (xy 391.034779 -282.22175) (xy 391.023002 -282.173966)
			(xy 391.019042 -282.124912) (xy 390.680194 -282.124912) (xy 390.679699 -282.149519) (xy 390.671804 -282.198096)
			(xy 390.65622 -282.244777) (xy 390.633349 -282.288354) (xy 390.603784 -282.327698) (xy 390.568291 -282.36179)
			(xy 390.527788 -282.389746) (xy 390.483326 -282.410844) (xy 390.436055 -282.424536) (xy 390.3872 -282.430468)
			(xy 390.338025 -282.428487) (xy 390.289806 -282.418643) (xy 390.24379 -282.401191) (xy 390.201169 -282.376584)
			(xy 390.163048 -282.345459) (xy 390.130413 -282.308622) (xy 390.10411 -282.267026) (xy 390.084819 -282.22175)
			(xy 390.073042 -282.173966) (xy 390.069082 -282.124912) (xy 389.730234 -282.124912) (xy 389.729739 -282.149519)
			(xy 389.721844 -282.198096) (xy 389.70626 -282.244777) (xy 389.683389 -282.288354) (xy 389.653824 -282.327698)
			(xy 389.618331 -282.36179) (xy 389.577828 -282.389746) (xy 389.533366 -282.410844) (xy 389.486095 -282.424536)
			(xy 389.43724 -282.430468) (xy 389.388065 -282.428487) (xy 389.339846 -282.418643) (xy 389.29383 -282.401191)
			(xy 389.251209 -282.376584) (xy 389.213088 -282.345459) (xy 389.180453 -282.308622) (xy 389.15415 -282.267026)
			(xy 389.134859 -282.22175) (xy 389.123082 -282.173966) (xy 389.119122 -282.124912) (xy 388.780274 -282.124912)
			(xy 388.779779 -282.149519) (xy 388.771884 -282.198096) (xy 388.7563 -282.244777) (xy 388.733429 -282.288354)
			(xy 388.703864 -282.327698) (xy 388.668371 -282.36179) (xy 388.627868 -282.389746) (xy 388.583406 -282.410844)
			(xy 388.536135 -282.424536) (xy 388.48728 -282.430468) (xy 388.438105 -282.428487) (xy 388.389886 -282.418643)
			(xy 388.34387 -282.401191) (xy 388.301249 -282.376584) (xy 388.263128 -282.345459) (xy 388.230493 -282.308622)
			(xy 388.20419 -282.267026) (xy 388.184899 -282.22175) (xy 388.173122 -282.173966) (xy 388.169162 -282.124912)
			(xy 387.830314 -282.124912) (xy 387.829819 -282.149519) (xy 387.821924 -282.198096) (xy 387.80634 -282.244777)
			(xy 387.783469 -282.288354) (xy 387.753904 -282.327698) (xy 387.718411 -282.36179) (xy 387.677908 -282.389746)
			(xy 387.633446 -282.410844) (xy 387.586175 -282.424536) (xy 387.53732 -282.430468) (xy 387.488145 -282.428487)
			(xy 387.439926 -282.418643) (xy 387.39391 -282.401191) (xy 387.351289 -282.376584) (xy 387.313168 -282.345459)
			(xy 387.280533 -282.308622) (xy 387.25423 -282.267026) (xy 387.234939 -282.22175) (xy 387.223162 -282.173966)
			(xy 387.219202 -282.124912) (xy 386.880354 -282.124912) (xy 386.879859 -282.149519) (xy 386.871964 -282.198096)
			(xy 386.85638 -282.244777) (xy 386.833509 -282.288354) (xy 386.803944 -282.327698) (xy 386.768451 -282.36179)
			(xy 386.727948 -282.389746) (xy 386.683486 -282.410844) (xy 386.636215 -282.424536) (xy 386.58736 -282.430468)
			(xy 386.538185 -282.428487) (xy 386.489966 -282.418643) (xy 386.44395 -282.401191) (xy 386.401329 -282.376584)
			(xy 386.363208 -282.345459) (xy 386.330573 -282.308622) (xy 386.30427 -282.267026) (xy 386.284979 -282.22175)
			(xy 386.273202 -282.173966) (xy 386.269242 -282.124912) (xy 385.93014 -282.124912) (xy 385.929645 -282.149519)
			(xy 385.92175 -282.198096) (xy 385.906166 -282.244777) (xy 385.883295 -282.288354) (xy 385.85373 -282.327698)
			(xy 385.818237 -282.36179) (xy 385.777734 -282.389746) (xy 385.733272 -282.410844) (xy 385.686001 -282.424536)
			(xy 385.637146 -282.430468) (xy 385.587971 -282.428487) (xy 385.539752 -282.418643) (xy 385.493736 -282.401191)
			(xy 385.451115 -282.376584) (xy 385.412994 -282.345459) (xy 385.380359 -282.308622) (xy 385.354056 -282.267026)
			(xy 385.334765 -282.22175) (xy 385.322988 -282.173966) (xy 385.319028 -282.124912) (xy 384.98018 -282.124912)
			(xy 384.979685 -282.149519) (xy 384.97179 -282.198096) (xy 384.956206 -282.244777) (xy 384.933335 -282.288354)
			(xy 384.90377 -282.327698) (xy 384.868277 -282.36179) (xy 384.827774 -282.389746) (xy 384.783312 -282.410844)
			(xy 384.736041 -282.424536) (xy 384.687186 -282.430468) (xy 384.638011 -282.428487) (xy 384.589792 -282.418643)
			(xy 384.543776 -282.401191) (xy 384.501155 -282.376584) (xy 384.463034 -282.345459) (xy 384.430399 -282.308622)
			(xy 384.404096 -282.267026) (xy 384.384805 -282.22175) (xy 384.373028 -282.173966) (xy 384.369068 -282.124912)
			(xy 383.78638 -282.124912) (xy 383.78638 -283.074872) (xy 384.369068 -283.074872) (xy 384.373028 -283.025818)
			(xy 384.384805 -282.978034) (xy 384.404096 -282.932758) (xy 384.430399 -282.891162) (xy 384.463034 -282.854325)
			(xy 384.501155 -282.8232) (xy 384.543776 -282.798593) (xy 384.589792 -282.781141) (xy 384.638011 -282.771297)
			(xy 384.687186 -282.769316) (xy 384.736041 -282.775248) (xy 384.783312 -282.78894) (xy 384.827774 -282.810038)
			(xy 384.868277 -282.837994) (xy 384.90377 -282.872086) (xy 384.933335 -282.91143) (xy 384.956206 -282.955007)
			(xy 384.97179 -283.001688) (xy 384.979685 -283.050265) (xy 384.98018 -283.074872) (xy 385.319028 -283.074872)
			(xy 385.322988 -283.025818) (xy 385.334765 -282.978034) (xy 385.354056 -282.932758) (xy 385.380359 -282.891162)
			(xy 385.412994 -282.854325) (xy 385.451115 -282.8232) (xy 385.493736 -282.798593) (xy 385.539752 -282.781141)
			(xy 385.587971 -282.771297) (xy 385.637146 -282.769316) (xy 385.686001 -282.775248) (xy 385.733272 -282.78894)
			(xy 385.777734 -282.810038) (xy 385.818237 -282.837994) (xy 385.85373 -282.872086) (xy 385.883295 -282.91143)
			(xy 385.906166 -282.955007) (xy 385.92175 -283.001688) (xy 385.929645 -283.050265) (xy 385.93014 -283.074872)
			(xy 386.269242 -283.074872) (xy 386.273202 -283.025818) (xy 386.284979 -282.978034) (xy 386.30427 -282.932758)
			(xy 386.330573 -282.891162) (xy 386.363208 -282.854325) (xy 386.401329 -282.8232) (xy 386.44395 -282.798593)
			(xy 386.489966 -282.781141) (xy 386.538185 -282.771297) (xy 386.58736 -282.769316) (xy 386.636215 -282.775248)
			(xy 386.683486 -282.78894) (xy 386.727948 -282.810038) (xy 386.768451 -282.837994) (xy 386.803944 -282.872086)
			(xy 386.833509 -282.91143) (xy 386.85638 -282.955007) (xy 386.871964 -283.001688) (xy 386.879859 -283.050265)
			(xy 386.880354 -283.074872) (xy 387.219202 -283.074872) (xy 387.223162 -283.025818) (xy 387.234939 -282.978034)
			(xy 387.25423 -282.932758) (xy 387.280533 -282.891162) (xy 387.313168 -282.854325) (xy 387.351289 -282.8232)
			(xy 387.39391 -282.798593) (xy 387.439926 -282.781141) (xy 387.488145 -282.771297) (xy 387.53732 -282.769316)
			(xy 387.586175 -282.775248) (xy 387.633446 -282.78894) (xy 387.677908 -282.810038) (xy 387.718411 -282.837994)
			(xy 387.753904 -282.872086) (xy 387.783469 -282.91143) (xy 387.80634 -282.955007) (xy 387.821924 -283.001688)
			(xy 387.829819 -283.050265) (xy 387.830314 -283.074872) (xy 388.169162 -283.074872) (xy 388.173122 -283.025818)
			(xy 388.184899 -282.978034) (xy 388.20419 -282.932758) (xy 388.230493 -282.891162) (xy 388.263128 -282.854325)
			(xy 388.301249 -282.8232) (xy 388.34387 -282.798593) (xy 388.389886 -282.781141) (xy 388.438105 -282.771297)
			(xy 388.48728 -282.769316) (xy 388.536135 -282.775248) (xy 388.583406 -282.78894) (xy 388.627868 -282.810038)
			(xy 388.668371 -282.837994) (xy 388.703864 -282.872086) (xy 388.733429 -282.91143) (xy 388.7563 -282.955007)
			(xy 388.771884 -283.001688) (xy 388.779779 -283.050265) (xy 388.780274 -283.074872) (xy 389.119122 -283.074872)
			(xy 389.123082 -283.025818) (xy 389.134859 -282.978034) (xy 389.15415 -282.932758) (xy 389.180453 -282.891162)
			(xy 389.213088 -282.854325) (xy 389.251209 -282.8232) (xy 389.29383 -282.798593) (xy 389.339846 -282.781141)
			(xy 389.388065 -282.771297) (xy 389.43724 -282.769316) (xy 389.486095 -282.775248) (xy 389.533366 -282.78894)
			(xy 389.577828 -282.810038) (xy 389.618331 -282.837994) (xy 389.653824 -282.872086) (xy 389.683389 -282.91143)
			(xy 389.70626 -282.955007) (xy 389.721844 -283.001688) (xy 389.729739 -283.050265) (xy 389.730234 -283.074872)
			(xy 390.069082 -283.074872) (xy 390.073042 -283.025818) (xy 390.084819 -282.978034) (xy 390.10411 -282.932758)
			(xy 390.130413 -282.891162) (xy 390.163048 -282.854325) (xy 390.201169 -282.8232) (xy 390.24379 -282.798593)
			(xy 390.289806 -282.781141) (xy 390.338025 -282.771297) (xy 390.3872 -282.769316) (xy 390.436055 -282.775248)
			(xy 390.483326 -282.78894) (xy 390.527788 -282.810038) (xy 390.568291 -282.837994) (xy 390.603784 -282.872086)
			(xy 390.633349 -282.91143) (xy 390.65622 -282.955007) (xy 390.671804 -283.001688) (xy 390.679699 -283.050265)
			(xy 390.680194 -283.074872) (xy 391.019042 -283.074872) (xy 391.023002 -283.025818) (xy 391.034779 -282.978034)
			(xy 391.05407 -282.932758) (xy 391.080373 -282.891162) (xy 391.113008 -282.854325) (xy 391.151129 -282.8232)
			(xy 391.19375 -282.798593) (xy 391.239766 -282.781141) (xy 391.287985 -282.771297) (xy 391.33716 -282.769316)
			(xy 391.386015 -282.775248) (xy 391.433286 -282.78894) (xy 391.477748 -282.810038) (xy 391.518251 -282.837994)
			(xy 391.553744 -282.872086) (xy 391.583309 -282.91143) (xy 391.60618 -282.955007) (xy 391.621764 -283.001688)
			(xy 391.629659 -283.050265) (xy 391.630154 -283.074872) (xy 391.969002 -283.074872) (xy 391.972962 -283.025818)
			(xy 391.984739 -282.978034) (xy 392.00403 -282.932758) (xy 392.030333 -282.891162) (xy 392.062968 -282.854325)
			(xy 392.101089 -282.8232) (xy 392.14371 -282.798593) (xy 392.189726 -282.781141) (xy 392.237945 -282.771297)
			(xy 392.28712 -282.769316) (xy 392.335975 -282.775248) (xy 392.383246 -282.78894) (xy 392.427708 -282.810038)
			(xy 392.468211 -282.837994) (xy 392.503704 -282.872086) (xy 392.533269 -282.91143) (xy 392.55614 -282.955007)
			(xy 392.571724 -283.001688) (xy 392.579619 -283.050265) (xy 392.580114 -283.074872) (xy 392.919216 -283.074872)
			(xy 392.923176 -283.025818) (xy 392.934953 -282.978034) (xy 392.954244 -282.932758) (xy 392.980547 -282.891162)
			(xy 393.013182 -282.854325) (xy 393.051303 -282.8232) (xy 393.093924 -282.798593) (xy 393.13994 -282.781141)
			(xy 393.188159 -282.771297) (xy 393.237334 -282.769316) (xy 393.286189 -282.775248) (xy 393.33346 -282.78894)
			(xy 393.377922 -282.810038) (xy 393.418425 -282.837994) (xy 393.453918 -282.872086) (xy 393.483483 -282.91143)
			(xy 393.506354 -282.955007) (xy 393.521938 -283.001688) (xy 393.529833 -283.050265) (xy 393.530328 -283.074872)
			(xy 393.869176 -283.074872) (xy 393.873136 -283.025818) (xy 393.884913 -282.978034) (xy 393.904204 -282.932758)
			(xy 393.930507 -282.891162) (xy 393.963142 -282.854325) (xy 394.001263 -282.8232) (xy 394.043884 -282.798593)
			(xy 394.0899 -282.781141) (xy 394.138119 -282.771297) (xy 394.187294 -282.769316) (xy 394.236149 -282.775248)
			(xy 394.28342 -282.78894) (xy 394.327882 -282.810038) (xy 394.368385 -282.837994) (xy 394.403878 -282.872086)
			(xy 394.433443 -282.91143) (xy 394.456314 -282.955007) (xy 394.471898 -283.001688) (xy 394.479793 -283.050265)
			(xy 394.480288 -283.074872) (xy 394.819136 -283.074872) (xy 394.823096 -283.025818) (xy 394.834873 -282.978034)
			(xy 394.854164 -282.932758) (xy 394.880467 -282.891162) (xy 394.913102 -282.854325) (xy 394.951223 -282.8232)
			(xy 394.993844 -282.798593) (xy 395.03986 -282.781141) (xy 395.088079 -282.771297) (xy 395.137254 -282.769316)
			(xy 395.186109 -282.775248) (xy 395.23338 -282.78894) (xy 395.277842 -282.810038) (xy 395.318345 -282.837994)
			(xy 395.353838 -282.872086) (xy 395.383403 -282.91143) (xy 395.406274 -282.955007) (xy 395.421858 -283.001688)
			(xy 395.429753 -283.050265) (xy 395.430248 -283.074872) (xy 395.769096 -283.074872) (xy 395.773056 -283.025818)
			(xy 395.784833 -282.978034) (xy 395.804124 -282.932758) (xy 395.830427 -282.891162) (xy 395.863062 -282.854325)
			(xy 395.901183 -282.8232) (xy 395.943804 -282.798593) (xy 395.98982 -282.781141) (xy 396.038039 -282.771297)
			(xy 396.087214 -282.769316) (xy 396.136069 -282.775248) (xy 396.18334 -282.78894) (xy 396.227802 -282.810038)
			(xy 396.268305 -282.837994) (xy 396.303798 -282.872086) (xy 396.333363 -282.91143) (xy 396.356234 -282.955007)
			(xy 396.371818 -283.001688) (xy 396.379713 -283.050265) (xy 396.380208 -283.074872) (xy 396.719056 -283.074872)
			(xy 396.723016 -283.025818) (xy 396.734793 -282.978034) (xy 396.754084 -282.932758) (xy 396.780387 -282.891162)
			(xy 396.813022 -282.854325) (xy 396.851143 -282.8232) (xy 396.893764 -282.798593) (xy 396.93978 -282.781141)
			(xy 396.987999 -282.771297) (xy 397.037174 -282.769316) (xy 397.086029 -282.775248) (xy 397.1333 -282.78894)
			(xy 397.177762 -282.810038) (xy 397.218265 -282.837994) (xy 397.253758 -282.872086) (xy 397.283323 -282.91143)
			(xy 397.306194 -282.955007) (xy 397.321778 -283.001688) (xy 397.329673 -283.050265) (xy 397.330168 -283.074872)
			(xy 397.669016 -283.074872) (xy 397.672976 -283.025818) (xy 397.684753 -282.978034) (xy 397.704044 -282.932758)
			(xy 397.730347 -282.891162) (xy 397.762982 -282.854325) (xy 397.801103 -282.8232) (xy 397.843724 -282.798593)
			(xy 397.88974 -282.781141) (xy 397.937959 -282.771297) (xy 397.987134 -282.769316) (xy 398.035989 -282.775248)
			(xy 398.08326 -282.78894) (xy 398.127722 -282.810038) (xy 398.168225 -282.837994) (xy 398.203718 -282.872086)
			(xy 398.233283 -282.91143) (xy 398.256154 -282.955007) (xy 398.271738 -283.001688) (xy 398.279633 -283.050265)
			(xy 398.280128 -283.074872) (xy 398.61923 -283.074872) (xy 398.62319 -283.025818) (xy 398.634967 -282.978034)
			(xy 398.654258 -282.932758) (xy 398.680561 -282.891162) (xy 398.713196 -282.854325) (xy 398.751317 -282.8232)
			(xy 398.793938 -282.798593) (xy 398.839954 -282.781141) (xy 398.888173 -282.771297) (xy 398.937348 -282.769316)
			(xy 398.986203 -282.775248) (xy 399.033474 -282.78894) (xy 399.077936 -282.810038) (xy 399.118439 -282.837994)
			(xy 399.153932 -282.872086) (xy 399.183497 -282.91143) (xy 399.206368 -282.955007) (xy 399.221952 -283.001688)
			(xy 399.229847 -283.050265) (xy 399.230342 -283.074872) (xy 399.56919 -283.074872) (xy 399.57315 -283.025818)
			(xy 399.584927 -282.978034) (xy 399.604218 -282.932758) (xy 399.630521 -282.891162) (xy 399.663156 -282.854325)
			(xy 399.701277 -282.8232) (xy 399.743898 -282.798593) (xy 399.789914 -282.781141) (xy 399.838133 -282.771297)
			(xy 399.887308 -282.769316) (xy 399.936163 -282.775248) (xy 399.983434 -282.78894) (xy 400.027896 -282.810038)
			(xy 400.068399 -282.837994) (xy 400.103892 -282.872086) (xy 400.133457 -282.91143) (xy 400.156328 -282.955007)
			(xy 400.171912 -283.001688) (xy 400.179807 -283.050265) (xy 400.180302 -283.074872) (xy 400.51915 -283.074872)
			(xy 400.52311 -283.025818) (xy 400.534887 -282.978034) (xy 400.554178 -282.932758) (xy 400.580481 -282.891162)
			(xy 400.613116 -282.854325) (xy 400.651237 -282.8232) (xy 400.693858 -282.798593) (xy 400.739874 -282.781141)
			(xy 400.788093 -282.771297) (xy 400.837268 -282.769316) (xy 400.886123 -282.775248) (xy 400.933394 -282.78894)
			(xy 400.977856 -282.810038) (xy 401.018359 -282.837994) (xy 401.053852 -282.872086) (xy 401.083417 -282.91143)
			(xy 401.106288 -282.955007) (xy 401.121872 -283.001688) (xy 401.129767 -283.050265) (xy 401.130262 -283.074872)
			(xy 401.46911 -283.074872) (xy 401.47307 -283.025818) (xy 401.484847 -282.978034) (xy 401.504138 -282.932758)
			(xy 401.530441 -282.891162) (xy 401.563076 -282.854325) (xy 401.601197 -282.8232) (xy 401.643818 -282.798593)
			(xy 401.689834 -282.781141) (xy 401.738053 -282.771297) (xy 401.787228 -282.769316) (xy 401.836083 -282.775248)
			(xy 401.883354 -282.78894) (xy 401.927816 -282.810038) (xy 401.968319 -282.837994) (xy 402.003812 -282.872086)
			(xy 402.033377 -282.91143) (xy 402.056248 -282.955007) (xy 402.071832 -283.001688) (xy 402.079727 -283.050265)
			(xy 402.080056 -283.066644) (xy 402.419152 -283.066644) (xy 402.424516 -283.017288) (xy 402.437793 -282.969451)
			(xy 402.458636 -282.924391) (xy 402.486493 -282.883297) (xy 402.520631 -282.847251) (xy 402.560152 -282.817203)
			(xy 402.604013 -282.793944) (xy 402.651059 -282.778088) (xy 402.700051 -282.770052) (xy 402.724874 -282.769564)
			(xy 402.739057 -282.769745) (xy 402.767297 -282.772414) (xy 402.781262 -282.774898) (xy 402.793708 -282.777184)
			(xy 402.81733 -282.769818) (xy 402.8948 -282.692348) (xy 402.902166 -282.668726) (xy 402.89988 -282.65628)
			(xy 402.897404 -282.642314) (xy 402.894732 -282.614074) (xy 402.894546 -282.599892) (xy 402.895068 -282.574637)
			(xy 402.903381 -282.524815) (xy 402.919782 -282.477041) (xy 402.943823 -282.432618) (xy 402.974847 -282.392758)
			(xy 403.012009 -282.358548) (xy 403.054295 -282.330922) (xy 403.100551 -282.310632) (xy 403.149516 -282.298232)
			(xy 403.199854 -282.294061) (xy 403.250192 -282.298232) (xy 403.299157 -282.310632) (xy 403.345413 -282.330922)
			(xy 403.387699 -282.358548) (xy 403.424861 -282.392758) (xy 403.455885 -282.432618) (xy 403.479926 -282.477041)
			(xy 403.496327 -282.524815) (xy 403.50464 -282.574637) (xy 403.505162 -282.599892) (xy 403.504985 -282.614075)
			(xy 403.502313 -282.642315) (xy 403.499828 -282.65628) (xy 403.497542 -282.668726) (xy 403.504908 -282.692348)
			(xy 403.582378 -282.769818) (xy 403.606 -282.777184) (xy 403.618446 -282.774898) (xy 403.632411 -282.772419)
			(xy 403.660651 -282.769749) (xy 403.674834 -282.769564) (xy 403.699652 -282.770115) (xy 403.748633 -282.77815)
			(xy 403.795669 -282.794004) (xy 403.839521 -282.817259) (xy 403.879032 -282.847302) (xy 403.913163 -282.883341)
			(xy 403.941014 -282.924427) (xy 403.96185 -282.969478) (xy 403.975124 -283.017306) (xy 403.980486 -283.066651)
			(xy 403.980039 -283.074872) (xy 404.319244 -283.074872) (xy 404.323204 -283.025818) (xy 404.334981 -282.978034)
			(xy 404.354272 -282.932758) (xy 404.380575 -282.891162) (xy 404.41321 -282.854325) (xy 404.451331 -282.8232)
			(xy 404.493952 -282.798593) (xy 404.539968 -282.781141) (xy 404.588187 -282.771297) (xy 404.637362 -282.769316)
			(xy 404.686217 -282.775248) (xy 404.733488 -282.78894) (xy 404.77795 -282.810038) (xy 404.818453 -282.837994)
			(xy 404.853946 -282.872086) (xy 404.883511 -282.91143) (xy 404.906382 -282.955007) (xy 404.921966 -283.001688)
			(xy 404.929861 -283.050265) (xy 404.930356 -283.074872) (xy 405.269204 -283.074872) (xy 405.273164 -283.025818)
			(xy 405.284941 -282.978034) (xy 405.304232 -282.932758) (xy 405.330535 -282.891162) (xy 405.36317 -282.854325)
			(xy 405.401291 -282.8232) (xy 405.443912 -282.798593) (xy 405.489928 -282.781141) (xy 405.538147 -282.771297)
			(xy 405.587322 -282.769316) (xy 405.636177 -282.775248) (xy 405.683448 -282.78894) (xy 405.72791 -282.810038)
			(xy 405.768413 -282.837994) (xy 405.803906 -282.872086) (xy 405.833471 -282.91143) (xy 405.856342 -282.955007)
			(xy 405.871926 -283.001688) (xy 405.879821 -283.050265) (xy 405.880316 -283.074872) (xy 406.219164 -283.074872)
			(xy 406.223124 -283.025818) (xy 406.234901 -282.978034) (xy 406.254192 -282.932758) (xy 406.280495 -282.891162)
			(xy 406.31313 -282.854325) (xy 406.351251 -282.8232) (xy 406.393872 -282.798593) (xy 406.439888 -282.781141)
			(xy 406.488107 -282.771297) (xy 406.537282 -282.769316) (xy 406.586137 -282.775248) (xy 406.633408 -282.78894)
			(xy 406.67787 -282.810038) (xy 406.718373 -282.837994) (xy 406.753866 -282.872086) (xy 406.783431 -282.91143)
			(xy 406.806302 -282.955007) (xy 406.821886 -283.001688) (xy 406.829781 -283.050265) (xy 406.830276 -283.074872)
			(xy 408.119084 -283.074872) (xy 408.123044 -283.025818) (xy 408.134821 -282.978034) (xy 408.154112 -282.932758)
			(xy 408.180415 -282.891162) (xy 408.21305 -282.854325) (xy 408.251171 -282.8232) (xy 408.293792 -282.798593)
			(xy 408.339808 -282.781141) (xy 408.388027 -282.771297) (xy 408.437202 -282.769316) (xy 408.486057 -282.775248)
			(xy 408.533328 -282.78894) (xy 408.57779 -282.810038) (xy 408.618293 -282.837994) (xy 408.653786 -282.872086)
			(xy 408.683351 -282.91143) (xy 408.706222 -282.955007) (xy 408.721806 -283.001688) (xy 408.729701 -283.050265)
			(xy 408.730196 -283.074872) (xy 409.069044 -283.074872) (xy 409.073004 -283.025818) (xy 409.084781 -282.978034)
			(xy 409.104072 -282.932758) (xy 409.130375 -282.891162) (xy 409.16301 -282.854325) (xy 409.201131 -282.8232)
			(xy 409.243752 -282.798593) (xy 409.289768 -282.781141) (xy 409.337987 -282.771297) (xy 409.387162 -282.769316)
			(xy 409.436017 -282.775248) (xy 409.483288 -282.78894) (xy 409.52775 -282.810038) (xy 409.568253 -282.837994)
			(xy 409.603746 -282.872086) (xy 409.633311 -282.91143) (xy 409.656182 -282.955007) (xy 409.671766 -283.001688)
			(xy 409.679661 -283.050265) (xy 409.680156 -283.074872) (xy 410.019004 -283.074872) (xy 410.022964 -283.025818)
			(xy 410.034741 -282.978034) (xy 410.054032 -282.932758) (xy 410.080335 -282.891162) (xy 410.11297 -282.854325)
			(xy 410.151091 -282.8232) (xy 410.193712 -282.798593) (xy 410.239728 -282.781141) (xy 410.287947 -282.771297)
			(xy 410.337122 -282.769316) (xy 410.385977 -282.775248) (xy 410.433248 -282.78894) (xy 410.47771 -282.810038)
			(xy 410.518213 -282.837994) (xy 410.553706 -282.872086) (xy 410.583271 -282.91143) (xy 410.606142 -282.955007)
			(xy 410.621726 -283.001688) (xy 410.629621 -283.050265) (xy 410.630116 -283.074872) (xy 410.969218 -283.074872)
			(xy 410.973178 -283.025818) (xy 410.984955 -282.978034) (xy 411.004246 -282.932758) (xy 411.030549 -282.891162)
			(xy 411.063184 -282.854325) (xy 411.101305 -282.8232) (xy 411.143926 -282.798593) (xy 411.189942 -282.781141)
			(xy 411.238161 -282.771297) (xy 411.287336 -282.769316) (xy 411.336191 -282.775248) (xy 411.383462 -282.78894)
			(xy 411.427924 -282.810038) (xy 411.468427 -282.837994) (xy 411.50392 -282.872086) (xy 411.533485 -282.91143)
			(xy 411.556356 -282.955007) (xy 411.57194 -283.001688) (xy 411.579835 -283.050265) (xy 411.58033 -283.074872)
			(xy 411.919178 -283.074872) (xy 411.923138 -283.025818) (xy 411.934915 -282.978034) (xy 411.954206 -282.932758)
			(xy 411.980509 -282.891162) (xy 412.013144 -282.854325) (xy 412.051265 -282.8232) (xy 412.093886 -282.798593)
			(xy 412.139902 -282.781141) (xy 412.188121 -282.771297) (xy 412.237296 -282.769316) (xy 412.286151 -282.775248)
			(xy 412.333422 -282.78894) (xy 412.377884 -282.810038) (xy 412.418387 -282.837994) (xy 412.45388 -282.872086)
			(xy 412.483445 -282.91143) (xy 412.506316 -282.955007) (xy 412.5219 -283.001688) (xy 412.529795 -283.050265)
			(xy 412.53029 -283.074872) (xy 412.869138 -283.074872) (xy 412.873098 -283.025818) (xy 412.884875 -282.978034)
			(xy 412.904166 -282.932758) (xy 412.930469 -282.891162) (xy 412.963104 -282.854325) (xy 413.001225 -282.8232)
			(xy 413.043846 -282.798593) (xy 413.089862 -282.781141) (xy 413.138081 -282.771297) (xy 413.187256 -282.769316)
			(xy 413.236111 -282.775248) (xy 413.283382 -282.78894) (xy 413.327844 -282.810038) (xy 413.368347 -282.837994)
			(xy 413.40384 -282.872086) (xy 413.433405 -282.91143) (xy 413.456276 -282.955007) (xy 413.47186 -283.001688)
			(xy 413.479755 -283.050265) (xy 413.48025 -283.074872) (xy 413.819098 -283.074872) (xy 413.823058 -283.025818)
			(xy 413.834835 -282.978034) (xy 413.854126 -282.932758) (xy 413.880429 -282.891162) (xy 413.913064 -282.854325)
			(xy 413.951185 -282.8232) (xy 413.993806 -282.798593) (xy 414.039822 -282.781141) (xy 414.088041 -282.771297)
			(xy 414.137216 -282.769316) (xy 414.186071 -282.775248) (xy 414.233342 -282.78894) (xy 414.277804 -282.810038)
			(xy 414.318307 -282.837994) (xy 414.3538 -282.872086) (xy 414.383365 -282.91143) (xy 414.406236 -282.955007)
			(xy 414.42182 -283.001688) (xy 414.429715 -283.050265) (xy 414.43021 -283.074872) (xy 414.769058 -283.074872)
			(xy 414.773018 -283.025818) (xy 414.784795 -282.978034) (xy 414.804086 -282.932758) (xy 414.830389 -282.891162)
			(xy 414.863024 -282.854325) (xy 414.901145 -282.8232) (xy 414.943766 -282.798593) (xy 414.989782 -282.781141)
			(xy 415.038001 -282.771297) (xy 415.087176 -282.769316) (xy 415.136031 -282.775248) (xy 415.183302 -282.78894)
			(xy 415.227764 -282.810038) (xy 415.268267 -282.837994) (xy 415.30376 -282.872086) (xy 415.333325 -282.91143)
			(xy 415.356196 -282.955007) (xy 415.37178 -283.001688) (xy 415.379675 -283.050265) (xy 415.38017 -283.074872)
			(xy 415.719018 -283.074872) (xy 415.722978 -283.025818) (xy 415.734755 -282.978034) (xy 415.754046 -282.932758)
			(xy 415.780349 -282.891162) (xy 415.812984 -282.854325) (xy 415.851105 -282.8232) (xy 415.893726 -282.798593)
			(xy 415.939742 -282.781141) (xy 415.987961 -282.771297) (xy 416.037136 -282.769316) (xy 416.085991 -282.775248)
			(xy 416.133262 -282.78894) (xy 416.177724 -282.810038) (xy 416.218227 -282.837994) (xy 416.25372 -282.872086)
			(xy 416.283285 -282.91143) (xy 416.306156 -282.955007) (xy 416.32174 -283.001688) (xy 416.329635 -283.050265)
			(xy 416.33013 -283.074872) (xy 416.668978 -283.074872) (xy 416.672938 -283.025818) (xy 416.684715 -282.978034)
			(xy 416.704006 -282.932758) (xy 416.730309 -282.891162) (xy 416.762944 -282.854325) (xy 416.801065 -282.8232)
			(xy 416.843686 -282.798593) (xy 416.889702 -282.781141) (xy 416.937921 -282.771297) (xy 416.987096 -282.769316)
			(xy 417.035951 -282.775248) (xy 417.083222 -282.78894) (xy 417.127684 -282.810038) (xy 417.168187 -282.837994)
			(xy 417.20368 -282.872086) (xy 417.233245 -282.91143) (xy 417.256116 -282.955007) (xy 417.2717 -283.001688)
			(xy 417.279595 -283.050265) (xy 417.28009 -283.074872) (xy 417.619192 -283.074872) (xy 417.623152 -283.025818)
			(xy 417.634929 -282.978034) (xy 417.65422 -282.932758) (xy 417.680523 -282.891162) (xy 417.713158 -282.854325)
			(xy 417.751279 -282.8232) (xy 417.7939 -282.798593) (xy 417.839916 -282.781141) (xy 417.888135 -282.771297)
			(xy 417.93731 -282.769316) (xy 417.986165 -282.775248) (xy 418.033436 -282.78894) (xy 418.077898 -282.810038)
			(xy 418.118401 -282.837994) (xy 418.153894 -282.872086) (xy 418.183459 -282.91143) (xy 418.20633 -282.955007)
			(xy 418.221914 -283.001688) (xy 418.229809 -283.050265) (xy 418.230304 -283.074872) (xy 418.569152 -283.074872)
			(xy 418.573112 -283.025818) (xy 418.584889 -282.978034) (xy 418.60418 -282.932758) (xy 418.630483 -282.891162)
			(xy 418.663118 -282.854325) (xy 418.701239 -282.8232) (xy 418.74386 -282.798593) (xy 418.789876 -282.781141)
			(xy 418.838095 -282.771297) (xy 418.88727 -282.769316) (xy 418.936125 -282.775248) (xy 418.983396 -282.78894)
			(xy 419.027858 -282.810038) (xy 419.068361 -282.837994) (xy 419.103854 -282.872086) (xy 419.133419 -282.91143)
			(xy 419.15629 -282.955007) (xy 419.171874 -283.001688) (xy 419.179769 -283.050265) (xy 419.180264 -283.074872)
			(xy 419.519112 -283.074872) (xy 419.523072 -283.025818) (xy 419.534849 -282.978034) (xy 419.55414 -282.932758)
			(xy 419.580443 -282.891162) (xy 419.613078 -282.854325) (xy 419.651199 -282.8232) (xy 419.69382 -282.798593)
			(xy 419.739836 -282.781141) (xy 419.788055 -282.771297) (xy 419.83723 -282.769316) (xy 419.886085 -282.775248)
			(xy 419.933356 -282.78894) (xy 419.977818 -282.810038) (xy 420.018321 -282.837994) (xy 420.053814 -282.872086)
			(xy 420.083379 -282.91143) (xy 420.10625 -282.955007) (xy 420.121834 -283.001688) (xy 420.129729 -283.050265)
			(xy 420.130224 -283.074872) (xy 420.469072 -283.074872) (xy 420.473032 -283.025818) (xy 420.484809 -282.978034)
			(xy 420.5041 -282.932758) (xy 420.530403 -282.891162) (xy 420.563038 -282.854325) (xy 420.601159 -282.8232)
			(xy 420.64378 -282.798593) (xy 420.689796 -282.781141) (xy 420.738015 -282.771297) (xy 420.78719 -282.769316)
			(xy 420.836045 -282.775248) (xy 420.883316 -282.78894) (xy 420.927778 -282.810038) (xy 420.968281 -282.837994)
			(xy 421.003774 -282.872086) (xy 421.033339 -282.91143) (xy 421.05621 -282.955007) (xy 421.071794 -283.001688)
			(xy 421.079689 -283.050265) (xy 421.080184 -283.074872) (xy 421.079689 -283.099479) (xy 421.071794 -283.148056)
			(xy 421.05621 -283.194737) (xy 421.033339 -283.238314) (xy 421.003774 -283.277658) (xy 420.968281 -283.31175)
			(xy 420.927778 -283.339706) (xy 420.883316 -283.360804) (xy 420.836045 -283.374496) (xy 420.78719 -283.380428)
			(xy 420.738015 -283.378447) (xy 420.689796 -283.368603) (xy 420.64378 -283.351151) (xy 420.601159 -283.326544)
			(xy 420.563038 -283.295419) (xy 420.530403 -283.258582) (xy 420.5041 -283.216986) (xy 420.484809 -283.17171)
			(xy 420.473032 -283.123926) (xy 420.469072 -283.074872) (xy 420.130224 -283.074872) (xy 420.129729 -283.099479)
			(xy 420.121834 -283.148056) (xy 420.10625 -283.194737) (xy 420.083379 -283.238314) (xy 420.053814 -283.277658)
			(xy 420.018321 -283.31175) (xy 419.977818 -283.339706) (xy 419.933356 -283.360804) (xy 419.886085 -283.374496)
			(xy 419.83723 -283.380428) (xy 419.788055 -283.378447) (xy 419.739836 -283.368603) (xy 419.69382 -283.351151)
			(xy 419.651199 -283.326544) (xy 419.613078 -283.295419) (xy 419.580443 -283.258582) (xy 419.55414 -283.216986)
			(xy 419.534849 -283.17171) (xy 419.523072 -283.123926) (xy 419.519112 -283.074872) (xy 419.180264 -283.074872)
			(xy 419.179769 -283.099479) (xy 419.171874 -283.148056) (xy 419.15629 -283.194737) (xy 419.133419 -283.238314)
			(xy 419.103854 -283.277658) (xy 419.068361 -283.31175) (xy 419.027858 -283.339706) (xy 418.983396 -283.360804)
			(xy 418.936125 -283.374496) (xy 418.88727 -283.380428) (xy 418.838095 -283.378447) (xy 418.789876 -283.368603)
			(xy 418.74386 -283.351151) (xy 418.701239 -283.326544) (xy 418.663118 -283.295419) (xy 418.630483 -283.258582)
			(xy 418.60418 -283.216986) (xy 418.584889 -283.17171) (xy 418.573112 -283.123926) (xy 418.569152 -283.074872)
			(xy 418.230304 -283.074872) (xy 418.229809 -283.099479) (xy 418.221914 -283.148056) (xy 418.20633 -283.194737)
			(xy 418.183459 -283.238314) (xy 418.153894 -283.277658) (xy 418.118401 -283.31175) (xy 418.077898 -283.339706)
			(xy 418.033436 -283.360804) (xy 417.986165 -283.374496) (xy 417.93731 -283.380428) (xy 417.888135 -283.378447)
			(xy 417.839916 -283.368603) (xy 417.7939 -283.351151) (xy 417.751279 -283.326544) (xy 417.713158 -283.295419)
			(xy 417.680523 -283.258582) (xy 417.65422 -283.216986) (xy 417.634929 -283.17171) (xy 417.623152 -283.123926)
			(xy 417.619192 -283.074872) (xy 417.28009 -283.074872) (xy 417.279595 -283.099479) (xy 417.2717 -283.148056)
			(xy 417.256116 -283.194737) (xy 417.233245 -283.238314) (xy 417.20368 -283.277658) (xy 417.168187 -283.31175)
			(xy 417.127684 -283.339706) (xy 417.083222 -283.360804) (xy 417.035951 -283.374496) (xy 416.987096 -283.380428)
			(xy 416.937921 -283.378447) (xy 416.889702 -283.368603) (xy 416.843686 -283.351151) (xy 416.801065 -283.326544)
			(xy 416.762944 -283.295419) (xy 416.730309 -283.258582) (xy 416.704006 -283.216986) (xy 416.684715 -283.17171)
			(xy 416.672938 -283.123926) (xy 416.668978 -283.074872) (xy 416.33013 -283.074872) (xy 416.329635 -283.099479)
			(xy 416.32174 -283.148056) (xy 416.306156 -283.194737) (xy 416.283285 -283.238314) (xy 416.25372 -283.277658)
			(xy 416.218227 -283.31175) (xy 416.177724 -283.339706) (xy 416.133262 -283.360804) (xy 416.085991 -283.374496)
			(xy 416.037136 -283.380428) (xy 415.987961 -283.378447) (xy 415.939742 -283.368603) (xy 415.893726 -283.351151)
			(xy 415.851105 -283.326544) (xy 415.812984 -283.295419) (xy 415.780349 -283.258582) (xy 415.754046 -283.216986)
			(xy 415.734755 -283.17171) (xy 415.722978 -283.123926) (xy 415.719018 -283.074872) (xy 415.38017 -283.074872)
			(xy 415.379675 -283.099479) (xy 415.37178 -283.148056) (xy 415.356196 -283.194737) (xy 415.333325 -283.238314)
			(xy 415.30376 -283.277658) (xy 415.268267 -283.31175) (xy 415.227764 -283.339706) (xy 415.183302 -283.360804)
			(xy 415.136031 -283.374496) (xy 415.087176 -283.380428) (xy 415.038001 -283.378447) (xy 414.989782 -283.368603)
			(xy 414.943766 -283.351151) (xy 414.901145 -283.326544) (xy 414.863024 -283.295419) (xy 414.830389 -283.258582)
			(xy 414.804086 -283.216986) (xy 414.784795 -283.17171) (xy 414.773018 -283.123926) (xy 414.769058 -283.074872)
			(xy 414.43021 -283.074872) (xy 414.429715 -283.099479) (xy 414.42182 -283.148056) (xy 414.406236 -283.194737)
			(xy 414.383365 -283.238314) (xy 414.3538 -283.277658) (xy 414.318307 -283.31175) (xy 414.277804 -283.339706)
			(xy 414.233342 -283.360804) (xy 414.186071 -283.374496) (xy 414.137216 -283.380428) (xy 414.088041 -283.378447)
			(xy 414.039822 -283.368603) (xy 413.993806 -283.351151) (xy 413.951185 -283.326544) (xy 413.913064 -283.295419)
			(xy 413.880429 -283.258582) (xy 413.854126 -283.216986) (xy 413.834835 -283.17171) (xy 413.823058 -283.123926)
			(xy 413.819098 -283.074872) (xy 413.48025 -283.074872) (xy 413.479755 -283.099479) (xy 413.47186 -283.148056)
			(xy 413.456276 -283.194737) (xy 413.433405 -283.238314) (xy 413.40384 -283.277658) (xy 413.368347 -283.31175)
			(xy 413.327844 -283.339706) (xy 413.283382 -283.360804) (xy 413.236111 -283.374496) (xy 413.187256 -283.380428)
			(xy 413.138081 -283.378447) (xy 413.089862 -283.368603) (xy 413.043846 -283.351151) (xy 413.001225 -283.326544)
			(xy 412.963104 -283.295419) (xy 412.930469 -283.258582) (xy 412.904166 -283.216986) (xy 412.884875 -283.17171)
			(xy 412.873098 -283.123926) (xy 412.869138 -283.074872) (xy 412.53029 -283.074872) (xy 412.529795 -283.099479)
			(xy 412.5219 -283.148056) (xy 412.506316 -283.194737) (xy 412.483445 -283.238314) (xy 412.45388 -283.277658)
			(xy 412.418387 -283.31175) (xy 412.377884 -283.339706) (xy 412.333422 -283.360804) (xy 412.286151 -283.374496)
			(xy 412.237296 -283.380428) (xy 412.188121 -283.378447) (xy 412.139902 -283.368603) (xy 412.093886 -283.351151)
			(xy 412.051265 -283.326544) (xy 412.013144 -283.295419) (xy 411.980509 -283.258582) (xy 411.954206 -283.216986)
			(xy 411.934915 -283.17171) (xy 411.923138 -283.123926) (xy 411.919178 -283.074872) (xy 411.58033 -283.074872)
			(xy 411.579835 -283.099479) (xy 411.57194 -283.148056) (xy 411.556356 -283.194737) (xy 411.533485 -283.238314)
			(xy 411.50392 -283.277658) (xy 411.468427 -283.31175) (xy 411.427924 -283.339706) (xy 411.383462 -283.360804)
			(xy 411.336191 -283.374496) (xy 411.287336 -283.380428) (xy 411.238161 -283.378447) (xy 411.189942 -283.368603)
			(xy 411.143926 -283.351151) (xy 411.101305 -283.326544) (xy 411.063184 -283.295419) (xy 411.030549 -283.258582)
			(xy 411.004246 -283.216986) (xy 410.984955 -283.17171) (xy 410.973178 -283.123926) (xy 410.969218 -283.074872)
			(xy 410.630116 -283.074872) (xy 410.629621 -283.099479) (xy 410.621726 -283.148056) (xy 410.606142 -283.194737)
			(xy 410.583271 -283.238314) (xy 410.553706 -283.277658) (xy 410.518213 -283.31175) (xy 410.47771 -283.339706)
			(xy 410.433248 -283.360804) (xy 410.385977 -283.374496) (xy 410.337122 -283.380428) (xy 410.287947 -283.378447)
			(xy 410.239728 -283.368603) (xy 410.193712 -283.351151) (xy 410.151091 -283.326544) (xy 410.11297 -283.295419)
			(xy 410.080335 -283.258582) (xy 410.054032 -283.216986) (xy 410.034741 -283.17171) (xy 410.022964 -283.123926)
			(xy 410.019004 -283.074872) (xy 409.680156 -283.074872) (xy 409.679661 -283.099479) (xy 409.671766 -283.148056)
			(xy 409.656182 -283.194737) (xy 409.633311 -283.238314) (xy 409.603746 -283.277658) (xy 409.568253 -283.31175)
			(xy 409.52775 -283.339706) (xy 409.483288 -283.360804) (xy 409.436017 -283.374496) (xy 409.387162 -283.380428)
			(xy 409.337987 -283.378447) (xy 409.289768 -283.368603) (xy 409.243752 -283.351151) (xy 409.201131 -283.326544)
			(xy 409.16301 -283.295419) (xy 409.130375 -283.258582) (xy 409.104072 -283.216986) (xy 409.084781 -283.17171)
			(xy 409.073004 -283.123926) (xy 409.069044 -283.074872) (xy 408.730196 -283.074872) (xy 408.729701 -283.099479)
			(xy 408.721806 -283.148056) (xy 408.706222 -283.194737) (xy 408.683351 -283.238314) (xy 408.653786 -283.277658)
			(xy 408.618293 -283.31175) (xy 408.57779 -283.339706) (xy 408.533328 -283.360804) (xy 408.486057 -283.374496)
			(xy 408.437202 -283.380428) (xy 408.388027 -283.378447) (xy 408.339808 -283.368603) (xy 408.293792 -283.351151)
			(xy 408.251171 -283.326544) (xy 408.21305 -283.295419) (xy 408.180415 -283.258582) (xy 408.154112 -283.216986)
			(xy 408.134821 -283.17171) (xy 408.123044 -283.123926) (xy 408.119084 -283.074872) (xy 406.830276 -283.074872)
			(xy 406.829781 -283.099479) (xy 406.821886 -283.148056) (xy 406.806302 -283.194737) (xy 406.783431 -283.238314)
			(xy 406.753866 -283.277658) (xy 406.718373 -283.31175) (xy 406.67787 -283.339706) (xy 406.633408 -283.360804)
			(xy 406.586137 -283.374496) (xy 406.537282 -283.380428) (xy 406.488107 -283.378447) (xy 406.439888 -283.368603)
			(xy 406.393872 -283.351151) (xy 406.351251 -283.326544) (xy 406.31313 -283.295419) (xy 406.280495 -283.258582)
			(xy 406.254192 -283.216986) (xy 406.234901 -283.17171) (xy 406.223124 -283.123926) (xy 406.219164 -283.074872)
			(xy 405.880316 -283.074872) (xy 405.879821 -283.099479) (xy 405.871926 -283.148056) (xy 405.856342 -283.194737)
			(xy 405.833471 -283.238314) (xy 405.803906 -283.277658) (xy 405.768413 -283.31175) (xy 405.72791 -283.339706)
			(xy 405.683448 -283.360804) (xy 405.636177 -283.374496) (xy 405.587322 -283.380428) (xy 405.538147 -283.378447)
			(xy 405.489928 -283.368603) (xy 405.443912 -283.351151) (xy 405.401291 -283.326544) (xy 405.36317 -283.295419)
			(xy 405.330535 -283.258582) (xy 405.304232 -283.216986) (xy 405.284941 -283.17171) (xy 405.273164 -283.123926)
			(xy 405.269204 -283.074872) (xy 404.930356 -283.074872) (xy 404.929861 -283.099479) (xy 404.921966 -283.148056)
			(xy 404.906382 -283.194737) (xy 404.883511 -283.238314) (xy 404.853946 -283.277658) (xy 404.818453 -283.31175)
			(xy 404.77795 -283.339706) (xy 404.733488 -283.360804) (xy 404.686217 -283.374496) (xy 404.637362 -283.380428)
			(xy 404.588187 -283.378447) (xy 404.539968 -283.368603) (xy 404.493952 -283.351151) (xy 404.451331 -283.326544)
			(xy 404.41321 -283.295419) (xy 404.380575 -283.258582) (xy 404.354272 -283.216986) (xy 404.334981 -283.17171)
			(xy 404.323204 -283.123926) (xy 404.319244 -283.074872) (xy 403.980039 -283.074872) (xy 403.977793 -283.116214)
			(xy 403.967118 -283.164689) (xy 403.948741 -283.210797) (xy 403.923147 -283.253326) (xy 403.891009 -283.291153)
			(xy 403.853175 -283.323283) (xy 403.810642 -283.348869) (xy 403.764529 -283.367236) (xy 403.716053 -283.377902)
			(xy 403.666489 -283.380584) (xy 403.617145 -283.375213) (xy 403.569319 -283.361929) (xy 403.524273 -283.341083)
			(xy 403.483192 -283.313224) (xy 403.44716 -283.279086) (xy 403.417125 -283.239568) (xy 403.39388 -283.195712)
			(xy 403.378035 -283.148673) (xy 403.370009 -283.09969) (xy 403.369526 -283.074872) (xy 403.369698 -283.060689)
			(xy 403.372373 -283.032449) (xy 403.37486 -283.018484) (xy 403.377146 -283.006038) (xy 403.36978 -282.982416)
			(xy 403.29231 -282.904946) (xy 403.268688 -282.89758) (xy 403.256242 -282.899866) (xy 403.242277 -282.902346)
			(xy 403.214037 -282.905016) (xy 403.199854 -282.9052) (xy 403.185671 -282.905016) (xy 403.157431 -282.902349)
			(xy 403.143466 -282.899866) (xy 403.13102 -282.89758) (xy 403.107398 -282.904946) (xy 403.029928 -282.982416)
			(xy 403.022562 -283.006038) (xy 403.024848 -283.018484) (xy 403.027332 -283.032449) (xy 403.029999 -283.060689)
			(xy 403.030182 -283.074872) (xy 403.029752 -283.099695) (xy 403.021725 -283.148688) (xy 403.005877 -283.195737)
			(xy 402.982626 -283.239602) (xy 402.952585 -283.279128) (xy 402.916545 -283.313273) (xy 402.875456 -283.341138)
			(xy 402.8304 -283.361988) (xy 402.782565 -283.375274) (xy 402.73321 -283.380646) (xy 402.683636 -283.377963)
			(xy 402.63515 -283.367295) (xy 402.589028 -283.348923) (xy 402.546486 -283.323331) (xy 402.508644 -283.291194)
			(xy 402.4765 -283.253358) (xy 402.450901 -283.210821) (xy 402.432521 -283.164702) (xy 402.421845 -283.116217)
			(xy 402.419152 -283.066644) (xy 402.080056 -283.066644) (xy 402.080222 -283.074872) (xy 402.079727 -283.099479)
			(xy 402.071832 -283.148056) (xy 402.056248 -283.194737) (xy 402.033377 -283.238314) (xy 402.003812 -283.277658)
			(xy 401.968319 -283.31175) (xy 401.927816 -283.339706) (xy 401.883354 -283.360804) (xy 401.836083 -283.374496)
			(xy 401.787228 -283.380428) (xy 401.738053 -283.378447) (xy 401.689834 -283.368603) (xy 401.643818 -283.351151)
			(xy 401.601197 -283.326544) (xy 401.563076 -283.295419) (xy 401.530441 -283.258582) (xy 401.504138 -283.216986)
			(xy 401.484847 -283.17171) (xy 401.47307 -283.123926) (xy 401.46911 -283.074872) (xy 401.130262 -283.074872)
			(xy 401.129767 -283.099479) (xy 401.121872 -283.148056) (xy 401.106288 -283.194737) (xy 401.083417 -283.238314)
			(xy 401.053852 -283.277658) (xy 401.018359 -283.31175) (xy 400.977856 -283.339706) (xy 400.933394 -283.360804)
			(xy 400.886123 -283.374496) (xy 400.837268 -283.380428) (xy 400.788093 -283.378447) (xy 400.739874 -283.368603)
			(xy 400.693858 -283.351151) (xy 400.651237 -283.326544) (xy 400.613116 -283.295419) (xy 400.580481 -283.258582)
			(xy 400.554178 -283.216986) (xy 400.534887 -283.17171) (xy 400.52311 -283.123926) (xy 400.51915 -283.074872)
			(xy 400.180302 -283.074872) (xy 400.179807 -283.099479) (xy 400.171912 -283.148056) (xy 400.156328 -283.194737)
			(xy 400.133457 -283.238314) (xy 400.103892 -283.277658) (xy 400.068399 -283.31175) (xy 400.027896 -283.339706)
			(xy 399.983434 -283.360804) (xy 399.936163 -283.374496) (xy 399.887308 -283.380428) (xy 399.838133 -283.378447)
			(xy 399.789914 -283.368603) (xy 399.743898 -283.351151) (xy 399.701277 -283.326544) (xy 399.663156 -283.295419)
			(xy 399.630521 -283.258582) (xy 399.604218 -283.216986) (xy 399.584927 -283.17171) (xy 399.57315 -283.123926)
			(xy 399.56919 -283.074872) (xy 399.230342 -283.074872) (xy 399.229847 -283.099479) (xy 399.221952 -283.148056)
			(xy 399.206368 -283.194737) (xy 399.183497 -283.238314) (xy 399.153932 -283.277658) (xy 399.118439 -283.31175)
			(xy 399.077936 -283.339706) (xy 399.033474 -283.360804) (xy 398.986203 -283.374496) (xy 398.937348 -283.380428)
			(xy 398.888173 -283.378447) (xy 398.839954 -283.368603) (xy 398.793938 -283.351151) (xy 398.751317 -283.326544)
			(xy 398.713196 -283.295419) (xy 398.680561 -283.258582) (xy 398.654258 -283.216986) (xy 398.634967 -283.17171)
			(xy 398.62319 -283.123926) (xy 398.61923 -283.074872) (xy 398.280128 -283.074872) (xy 398.279633 -283.099479)
			(xy 398.271738 -283.148056) (xy 398.256154 -283.194737) (xy 398.233283 -283.238314) (xy 398.203718 -283.277658)
			(xy 398.168225 -283.31175) (xy 398.127722 -283.339706) (xy 398.08326 -283.360804) (xy 398.035989 -283.374496)
			(xy 397.987134 -283.380428) (xy 397.937959 -283.378447) (xy 397.88974 -283.368603) (xy 397.843724 -283.351151)
			(xy 397.801103 -283.326544) (xy 397.762982 -283.295419) (xy 397.730347 -283.258582) (xy 397.704044 -283.216986)
			(xy 397.684753 -283.17171) (xy 397.672976 -283.123926) (xy 397.669016 -283.074872) (xy 397.330168 -283.074872)
			(xy 397.329673 -283.099479) (xy 397.321778 -283.148056) (xy 397.306194 -283.194737) (xy 397.283323 -283.238314)
			(xy 397.253758 -283.277658) (xy 397.218265 -283.31175) (xy 397.177762 -283.339706) (xy 397.1333 -283.360804)
			(xy 397.086029 -283.374496) (xy 397.037174 -283.380428) (xy 396.987999 -283.378447) (xy 396.93978 -283.368603)
			(xy 396.893764 -283.351151) (xy 396.851143 -283.326544) (xy 396.813022 -283.295419) (xy 396.780387 -283.258582)
			(xy 396.754084 -283.216986) (xy 396.734793 -283.17171) (xy 396.723016 -283.123926) (xy 396.719056 -283.074872)
			(xy 396.380208 -283.074872) (xy 396.379713 -283.099479) (xy 396.371818 -283.148056) (xy 396.356234 -283.194737)
			(xy 396.333363 -283.238314) (xy 396.303798 -283.277658) (xy 396.268305 -283.31175) (xy 396.227802 -283.339706)
			(xy 396.18334 -283.360804) (xy 396.136069 -283.374496) (xy 396.087214 -283.380428) (xy 396.038039 -283.378447)
			(xy 395.98982 -283.368603) (xy 395.943804 -283.351151) (xy 395.901183 -283.326544) (xy 395.863062 -283.295419)
			(xy 395.830427 -283.258582) (xy 395.804124 -283.216986) (xy 395.784833 -283.17171) (xy 395.773056 -283.123926)
			(xy 395.769096 -283.074872) (xy 395.430248 -283.074872) (xy 395.429753 -283.099479) (xy 395.421858 -283.148056)
			(xy 395.406274 -283.194737) (xy 395.383403 -283.238314) (xy 395.353838 -283.277658) (xy 395.318345 -283.31175)
			(xy 395.277842 -283.339706) (xy 395.23338 -283.360804) (xy 395.186109 -283.374496) (xy 395.137254 -283.380428)
			(xy 395.088079 -283.378447) (xy 395.03986 -283.368603) (xy 394.993844 -283.351151) (xy 394.951223 -283.326544)
			(xy 394.913102 -283.295419) (xy 394.880467 -283.258582) (xy 394.854164 -283.216986) (xy 394.834873 -283.17171)
			(xy 394.823096 -283.123926) (xy 394.819136 -283.074872) (xy 394.480288 -283.074872) (xy 394.479793 -283.099479)
			(xy 394.471898 -283.148056) (xy 394.456314 -283.194737) (xy 394.433443 -283.238314) (xy 394.403878 -283.277658)
			(xy 394.368385 -283.31175) (xy 394.327882 -283.339706) (xy 394.28342 -283.360804) (xy 394.236149 -283.374496)
			(xy 394.187294 -283.380428) (xy 394.138119 -283.378447) (xy 394.0899 -283.368603) (xy 394.043884 -283.351151)
			(xy 394.001263 -283.326544) (xy 393.963142 -283.295419) (xy 393.930507 -283.258582) (xy 393.904204 -283.216986)
			(xy 393.884913 -283.17171) (xy 393.873136 -283.123926) (xy 393.869176 -283.074872) (xy 393.530328 -283.074872)
			(xy 393.529833 -283.099479) (xy 393.521938 -283.148056) (xy 393.506354 -283.194737) (xy 393.483483 -283.238314)
			(xy 393.453918 -283.277658) (xy 393.418425 -283.31175) (xy 393.377922 -283.339706) (xy 393.33346 -283.360804)
			(xy 393.286189 -283.374496) (xy 393.237334 -283.380428) (xy 393.188159 -283.378447) (xy 393.13994 -283.368603)
			(xy 393.093924 -283.351151) (xy 393.051303 -283.326544) (xy 393.013182 -283.295419) (xy 392.980547 -283.258582)
			(xy 392.954244 -283.216986) (xy 392.934953 -283.17171) (xy 392.923176 -283.123926) (xy 392.919216 -283.074872)
			(xy 392.580114 -283.074872) (xy 392.579619 -283.099479) (xy 392.571724 -283.148056) (xy 392.55614 -283.194737)
			(xy 392.533269 -283.238314) (xy 392.503704 -283.277658) (xy 392.468211 -283.31175) (xy 392.427708 -283.339706)
			(xy 392.383246 -283.360804) (xy 392.335975 -283.374496) (xy 392.28712 -283.380428) (xy 392.237945 -283.378447)
			(xy 392.189726 -283.368603) (xy 392.14371 -283.351151) (xy 392.101089 -283.326544) (xy 392.062968 -283.295419)
			(xy 392.030333 -283.258582) (xy 392.00403 -283.216986) (xy 391.984739 -283.17171) (xy 391.972962 -283.123926)
			(xy 391.969002 -283.074872) (xy 391.630154 -283.074872) (xy 391.629659 -283.099479) (xy 391.621764 -283.148056)
			(xy 391.60618 -283.194737) (xy 391.583309 -283.238314) (xy 391.553744 -283.277658) (xy 391.518251 -283.31175)
			(xy 391.477748 -283.339706) (xy 391.433286 -283.360804) (xy 391.386015 -283.374496) (xy 391.33716 -283.380428)
			(xy 391.287985 -283.378447) (xy 391.239766 -283.368603) (xy 391.19375 -283.351151) (xy 391.151129 -283.326544)
			(xy 391.113008 -283.295419) (xy 391.080373 -283.258582) (xy 391.05407 -283.216986) (xy 391.034779 -283.17171)
			(xy 391.023002 -283.123926) (xy 391.019042 -283.074872) (xy 390.680194 -283.074872) (xy 390.679699 -283.099479)
			(xy 390.671804 -283.148056) (xy 390.65622 -283.194737) (xy 390.633349 -283.238314) (xy 390.603784 -283.277658)
			(xy 390.568291 -283.31175) (xy 390.527788 -283.339706) (xy 390.483326 -283.360804) (xy 390.436055 -283.374496)
			(xy 390.3872 -283.380428) (xy 390.338025 -283.378447) (xy 390.289806 -283.368603) (xy 390.24379 -283.351151)
			(xy 390.201169 -283.326544) (xy 390.163048 -283.295419) (xy 390.130413 -283.258582) (xy 390.10411 -283.216986)
			(xy 390.084819 -283.17171) (xy 390.073042 -283.123926) (xy 390.069082 -283.074872) (xy 389.730234 -283.074872)
			(xy 389.729739 -283.099479) (xy 389.721844 -283.148056) (xy 389.70626 -283.194737) (xy 389.683389 -283.238314)
			(xy 389.653824 -283.277658) (xy 389.618331 -283.31175) (xy 389.577828 -283.339706) (xy 389.533366 -283.360804)
			(xy 389.486095 -283.374496) (xy 389.43724 -283.380428) (xy 389.388065 -283.378447) (xy 389.339846 -283.368603)
			(xy 389.29383 -283.351151) (xy 389.251209 -283.326544) (xy 389.213088 -283.295419) (xy 389.180453 -283.258582)
			(xy 389.15415 -283.216986) (xy 389.134859 -283.17171) (xy 389.123082 -283.123926) (xy 389.119122 -283.074872)
			(xy 388.780274 -283.074872) (xy 388.779779 -283.099479) (xy 388.771884 -283.148056) (xy 388.7563 -283.194737)
			(xy 388.733429 -283.238314) (xy 388.703864 -283.277658) (xy 388.668371 -283.31175) (xy 388.627868 -283.339706)
			(xy 388.583406 -283.360804) (xy 388.536135 -283.374496) (xy 388.48728 -283.380428) (xy 388.438105 -283.378447)
			(xy 388.389886 -283.368603) (xy 388.34387 -283.351151) (xy 388.301249 -283.326544) (xy 388.263128 -283.295419)
			(xy 388.230493 -283.258582) (xy 388.20419 -283.216986) (xy 388.184899 -283.17171) (xy 388.173122 -283.123926)
			(xy 388.169162 -283.074872) (xy 387.830314 -283.074872) (xy 387.829819 -283.099479) (xy 387.821924 -283.148056)
			(xy 387.80634 -283.194737) (xy 387.783469 -283.238314) (xy 387.753904 -283.277658) (xy 387.718411 -283.31175)
			(xy 387.677908 -283.339706) (xy 387.633446 -283.360804) (xy 387.586175 -283.374496) (xy 387.53732 -283.380428)
			(xy 387.488145 -283.378447) (xy 387.439926 -283.368603) (xy 387.39391 -283.351151) (xy 387.351289 -283.326544)
			(xy 387.313168 -283.295419) (xy 387.280533 -283.258582) (xy 387.25423 -283.216986) (xy 387.234939 -283.17171)
			(xy 387.223162 -283.123926) (xy 387.219202 -283.074872) (xy 386.880354 -283.074872) (xy 386.879859 -283.099479)
			(xy 386.871964 -283.148056) (xy 386.85638 -283.194737) (xy 386.833509 -283.238314) (xy 386.803944 -283.277658)
			(xy 386.768451 -283.31175) (xy 386.727948 -283.339706) (xy 386.683486 -283.360804) (xy 386.636215 -283.374496)
			(xy 386.58736 -283.380428) (xy 386.538185 -283.378447) (xy 386.489966 -283.368603) (xy 386.44395 -283.351151)
			(xy 386.401329 -283.326544) (xy 386.363208 -283.295419) (xy 386.330573 -283.258582) (xy 386.30427 -283.216986)
			(xy 386.284979 -283.17171) (xy 386.273202 -283.123926) (xy 386.269242 -283.074872) (xy 385.93014 -283.074872)
			(xy 385.929645 -283.099479) (xy 385.92175 -283.148056) (xy 385.906166 -283.194737) (xy 385.883295 -283.238314)
			(xy 385.85373 -283.277658) (xy 385.818237 -283.31175) (xy 385.777734 -283.339706) (xy 385.733272 -283.360804)
			(xy 385.686001 -283.374496) (xy 385.637146 -283.380428) (xy 385.587971 -283.378447) (xy 385.539752 -283.368603)
			(xy 385.493736 -283.351151) (xy 385.451115 -283.326544) (xy 385.412994 -283.295419) (xy 385.380359 -283.258582)
			(xy 385.354056 -283.216986) (xy 385.334765 -283.17171) (xy 385.322988 -283.123926) (xy 385.319028 -283.074872)
			(xy 384.98018 -283.074872) (xy 384.979685 -283.099479) (xy 384.97179 -283.148056) (xy 384.956206 -283.194737)
			(xy 384.933335 -283.238314) (xy 384.90377 -283.277658) (xy 384.868277 -283.31175) (xy 384.827774 -283.339706)
			(xy 384.783312 -283.360804) (xy 384.736041 -283.374496) (xy 384.687186 -283.380428) (xy 384.638011 -283.378447)
			(xy 384.589792 -283.368603) (xy 384.543776 -283.351151) (xy 384.501155 -283.326544) (xy 384.463034 -283.295419)
			(xy 384.430399 -283.258582) (xy 384.404096 -283.216986) (xy 384.384805 -283.17171) (xy 384.373028 -283.123926)
			(xy 384.369068 -283.074872) (xy 383.78638 -283.074872) (xy 383.78638 -284.024832) (xy 384.369068 -284.024832)
			(xy 384.373028 -283.975778) (xy 384.384805 -283.927994) (xy 384.404096 -283.882718) (xy 384.430399 -283.841122)
			(xy 384.463034 -283.804285) (xy 384.501155 -283.77316) (xy 384.543776 -283.748553) (xy 384.589792 -283.731101)
			(xy 384.638011 -283.721257) (xy 384.687186 -283.719276) (xy 384.736041 -283.725208) (xy 384.783312 -283.7389)
			(xy 384.827774 -283.759998) (xy 384.868277 -283.787954) (xy 384.90377 -283.822046) (xy 384.933335 -283.86139)
			(xy 384.956206 -283.904967) (xy 384.97179 -283.951648) (xy 384.979685 -284.000225) (xy 384.98018 -284.024832)
			(xy 385.319028 -284.024832) (xy 385.322988 -283.975778) (xy 385.334765 -283.927994) (xy 385.354056 -283.882718)
			(xy 385.380359 -283.841122) (xy 385.412994 -283.804285) (xy 385.451115 -283.77316) (xy 385.493736 -283.748553)
			(xy 385.539752 -283.731101) (xy 385.587971 -283.721257) (xy 385.637146 -283.719276) (xy 385.686001 -283.725208)
			(xy 385.733272 -283.7389) (xy 385.777734 -283.759998) (xy 385.818237 -283.787954) (xy 385.85373 -283.822046)
			(xy 385.883295 -283.86139) (xy 385.906166 -283.904967) (xy 385.92175 -283.951648) (xy 385.929645 -284.000225)
			(xy 385.93014 -284.024832) (xy 386.269242 -284.024832) (xy 386.273202 -283.975778) (xy 386.284979 -283.927994)
			(xy 386.30427 -283.882718) (xy 386.330573 -283.841122) (xy 386.363208 -283.804285) (xy 386.401329 -283.77316)
			(xy 386.44395 -283.748553) (xy 386.489966 -283.731101) (xy 386.538185 -283.721257) (xy 386.58736 -283.719276)
			(xy 386.636215 -283.725208) (xy 386.683486 -283.7389) (xy 386.727948 -283.759998) (xy 386.768451 -283.787954)
			(xy 386.803944 -283.822046) (xy 386.833509 -283.86139) (xy 386.85638 -283.904967) (xy 386.871964 -283.951648)
			(xy 386.879859 -284.000225) (xy 386.880354 -284.024832) (xy 387.219202 -284.024832) (xy 387.223162 -283.975778)
			(xy 387.234939 -283.927994) (xy 387.25423 -283.882718) (xy 387.280533 -283.841122) (xy 387.313168 -283.804285)
			(xy 387.351289 -283.77316) (xy 387.39391 -283.748553) (xy 387.439926 -283.731101) (xy 387.488145 -283.721257)
			(xy 387.53732 -283.719276) (xy 387.586175 -283.725208) (xy 387.633446 -283.7389) (xy 387.677908 -283.759998)
			(xy 387.718411 -283.787954) (xy 387.753904 -283.822046) (xy 387.783469 -283.86139) (xy 387.80634 -283.904967)
			(xy 387.821924 -283.951648) (xy 387.829819 -284.000225) (xy 387.830314 -284.024832) (xy 388.169162 -284.024832)
			(xy 388.173122 -283.975778) (xy 388.184899 -283.927994) (xy 388.20419 -283.882718) (xy 388.230493 -283.841122)
			(xy 388.263128 -283.804285) (xy 388.301249 -283.77316) (xy 388.34387 -283.748553) (xy 388.389886 -283.731101)
			(xy 388.438105 -283.721257) (xy 388.48728 -283.719276) (xy 388.536135 -283.725208) (xy 388.583406 -283.7389)
			(xy 388.627868 -283.759998) (xy 388.668371 -283.787954) (xy 388.703864 -283.822046) (xy 388.733429 -283.86139)
			(xy 388.7563 -283.904967) (xy 388.771884 -283.951648) (xy 388.779779 -284.000225) (xy 388.780274 -284.024832)
			(xy 391.019042 -284.024832) (xy 391.023002 -283.975778) (xy 391.034779 -283.927994) (xy 391.05407 -283.882718)
			(xy 391.080373 -283.841122) (xy 391.113008 -283.804285) (xy 391.151129 -283.77316) (xy 391.19375 -283.748553)
			(xy 391.239766 -283.731101) (xy 391.287985 -283.721257) (xy 391.33716 -283.719276) (xy 391.386015 -283.725208)
			(xy 391.433286 -283.7389) (xy 391.477748 -283.759998) (xy 391.518251 -283.787954) (xy 391.553744 -283.822046)
			(xy 391.583309 -283.86139) (xy 391.60618 -283.904967) (xy 391.621764 -283.951648) (xy 391.629659 -284.000225)
			(xy 391.630154 -284.024832) (xy 391.969002 -284.024832) (xy 391.972962 -283.975778) (xy 391.984739 -283.927994)
			(xy 392.00403 -283.882718) (xy 392.030333 -283.841122) (xy 392.062968 -283.804285) (xy 392.101089 -283.77316)
			(xy 392.14371 -283.748553) (xy 392.189726 -283.731101) (xy 392.237945 -283.721257) (xy 392.28712 -283.719276)
			(xy 392.335975 -283.725208) (xy 392.383246 -283.7389) (xy 392.427708 -283.759998) (xy 392.468211 -283.787954)
			(xy 392.503704 -283.822046) (xy 392.533269 -283.86139) (xy 392.55614 -283.904967) (xy 392.571724 -283.951648)
			(xy 392.579619 -284.000225) (xy 392.580114 -284.024832) (xy 392.919216 -284.024832) (xy 392.923176 -283.975778)
			(xy 392.934953 -283.927994) (xy 392.954244 -283.882718) (xy 392.980547 -283.841122) (xy 393.013182 -283.804285)
			(xy 393.051303 -283.77316) (xy 393.093924 -283.748553) (xy 393.13994 -283.731101) (xy 393.188159 -283.721257)
			(xy 393.237334 -283.719276) (xy 393.286189 -283.725208) (xy 393.33346 -283.7389) (xy 393.377922 -283.759998)
			(xy 393.418425 -283.787954) (xy 393.453918 -283.822046) (xy 393.483483 -283.86139) (xy 393.506354 -283.904967)
			(xy 393.521938 -283.951648) (xy 393.529833 -284.000225) (xy 393.530328 -284.024832) (xy 393.869176 -284.024832)
			(xy 393.873136 -283.975778) (xy 393.884913 -283.927994) (xy 393.904204 -283.882718) (xy 393.930507 -283.841122)
			(xy 393.963142 -283.804285) (xy 394.001263 -283.77316) (xy 394.043884 -283.748553) (xy 394.0899 -283.731101)
			(xy 394.138119 -283.721257) (xy 394.187294 -283.719276) (xy 394.236149 -283.725208) (xy 394.28342 -283.7389)
			(xy 394.327882 -283.759998) (xy 394.368385 -283.787954) (xy 394.403878 -283.822046) (xy 394.433443 -283.86139)
			(xy 394.456314 -283.904967) (xy 394.471898 -283.951648) (xy 394.479793 -284.000225) (xy 394.480288 -284.024832)
			(xy 394.819136 -284.024832) (xy 394.823096 -283.975778) (xy 394.834873 -283.927994) (xy 394.854164 -283.882718)
			(xy 394.880467 -283.841122) (xy 394.913102 -283.804285) (xy 394.951223 -283.77316) (xy 394.993844 -283.748553)
			(xy 395.03986 -283.731101) (xy 395.088079 -283.721257) (xy 395.137254 -283.719276) (xy 395.186109 -283.725208)
			(xy 395.23338 -283.7389) (xy 395.277842 -283.759998) (xy 395.318345 -283.787954) (xy 395.353838 -283.822046)
			(xy 395.383403 -283.86139) (xy 395.406274 -283.904967) (xy 395.421858 -283.951648) (xy 395.429753 -284.000225)
			(xy 395.430248 -284.024832) (xy 395.769096 -284.024832) (xy 395.773056 -283.975778) (xy 395.784833 -283.927994)
			(xy 395.804124 -283.882718) (xy 395.830427 -283.841122) (xy 395.863062 -283.804285) (xy 395.901183 -283.77316)
			(xy 395.943804 -283.748553) (xy 395.98982 -283.731101) (xy 396.038039 -283.721257) (xy 396.087214 -283.719276)
			(xy 396.136069 -283.725208) (xy 396.18334 -283.7389) (xy 396.227802 -283.759998) (xy 396.268305 -283.787954)
			(xy 396.303798 -283.822046) (xy 396.333363 -283.86139) (xy 396.356234 -283.904967) (xy 396.371818 -283.951648)
			(xy 396.379713 -284.000225) (xy 396.380208 -284.024832) (xy 396.719056 -284.024832) (xy 396.723016 -283.975778)
			(xy 396.734793 -283.927994) (xy 396.754084 -283.882718) (xy 396.780387 -283.841122) (xy 396.813022 -283.804285)
			(xy 396.851143 -283.77316) (xy 396.893764 -283.748553) (xy 396.93978 -283.731101) (xy 396.987999 -283.721257)
			(xy 397.037174 -283.719276) (xy 397.086029 -283.725208) (xy 397.1333 -283.7389) (xy 397.177762 -283.759998)
			(xy 397.218265 -283.787954) (xy 397.253758 -283.822046) (xy 397.283323 -283.86139) (xy 397.306194 -283.904967)
			(xy 397.321778 -283.951648) (xy 397.329673 -284.000225) (xy 397.330168 -284.024832) (xy 397.669016 -284.024832)
			(xy 397.672976 -283.975778) (xy 397.684753 -283.927994) (xy 397.704044 -283.882718) (xy 397.730347 -283.841122)
			(xy 397.762982 -283.804285) (xy 397.801103 -283.77316) (xy 397.843724 -283.748553) (xy 397.88974 -283.731101)
			(xy 397.937959 -283.721257) (xy 397.987134 -283.719276) (xy 398.035989 -283.725208) (xy 398.08326 -283.7389)
			(xy 398.127722 -283.759998) (xy 398.168225 -283.787954) (xy 398.203718 -283.822046) (xy 398.233283 -283.86139)
			(xy 398.256154 -283.904967) (xy 398.271738 -283.951648) (xy 398.279633 -284.000225) (xy 398.280128 -284.024832)
			(xy 398.61923 -284.024832) (xy 398.62319 -283.975778) (xy 398.634967 -283.927994) (xy 398.654258 -283.882718)
			(xy 398.680561 -283.841122) (xy 398.713196 -283.804285) (xy 398.751317 -283.77316) (xy 398.793938 -283.748553)
			(xy 398.839954 -283.731101) (xy 398.888173 -283.721257) (xy 398.937348 -283.719276) (xy 398.986203 -283.725208)
			(xy 399.033474 -283.7389) (xy 399.077936 -283.759998) (xy 399.118439 -283.787954) (xy 399.153932 -283.822046)
			(xy 399.183497 -283.86139) (xy 399.206368 -283.904967) (xy 399.221952 -283.951648) (xy 399.229847 -284.000225)
			(xy 399.230342 -284.024832) (xy 399.56919 -284.024832) (xy 399.57315 -283.975778) (xy 399.584927 -283.927994)
			(xy 399.604218 -283.882718) (xy 399.630521 -283.841122) (xy 399.663156 -283.804285) (xy 399.701277 -283.77316)
			(xy 399.743898 -283.748553) (xy 399.789914 -283.731101) (xy 399.838133 -283.721257) (xy 399.887308 -283.719276)
			(xy 399.936163 -283.725208) (xy 399.983434 -283.7389) (xy 400.027896 -283.759998) (xy 400.068399 -283.787954)
			(xy 400.103892 -283.822046) (xy 400.133457 -283.86139) (xy 400.156328 -283.904967) (xy 400.171912 -283.951648)
			(xy 400.179807 -284.000225) (xy 400.180302 -284.024832) (xy 400.51915 -284.024832) (xy 400.52311 -283.975778)
			(xy 400.534887 -283.927994) (xy 400.554178 -283.882718) (xy 400.580481 -283.841122) (xy 400.613116 -283.804285)
			(xy 400.651237 -283.77316) (xy 400.693858 -283.748553) (xy 400.739874 -283.731101) (xy 400.788093 -283.721257)
			(xy 400.837268 -283.719276) (xy 400.886123 -283.725208) (xy 400.933394 -283.7389) (xy 400.977856 -283.759998)
			(xy 401.018359 -283.787954) (xy 401.053852 -283.822046) (xy 401.083417 -283.86139) (xy 401.106288 -283.904967)
			(xy 401.121872 -283.951648) (xy 401.129767 -284.000225) (xy 401.130262 -284.024832) (xy 401.46911 -284.024832)
			(xy 401.47307 -283.975778) (xy 401.484847 -283.927994) (xy 401.504138 -283.882718) (xy 401.530441 -283.841122)
			(xy 401.563076 -283.804285) (xy 401.601197 -283.77316) (xy 401.643818 -283.748553) (xy 401.689834 -283.731101)
			(xy 401.738053 -283.721257) (xy 401.787228 -283.719276) (xy 401.836083 -283.725208) (xy 401.883354 -283.7389)
			(xy 401.927816 -283.759998) (xy 401.968319 -283.787954) (xy 402.003812 -283.822046) (xy 402.033377 -283.86139)
			(xy 402.056248 -283.904967) (xy 402.071832 -283.951648) (xy 402.079727 -284.000225) (xy 402.080222 -284.024832)
			(xy 402.41907 -284.024832) (xy 402.42303 -283.975778) (xy 402.434807 -283.927994) (xy 402.454098 -283.882718)
			(xy 402.480401 -283.841122) (xy 402.513036 -283.804285) (xy 402.551157 -283.77316) (xy 402.593778 -283.748553)
			(xy 402.639794 -283.731101) (xy 402.688013 -283.721257) (xy 402.737188 -283.719276) (xy 402.786043 -283.725208)
			(xy 402.833314 -283.7389) (xy 402.877776 -283.759998) (xy 402.918279 -283.787954) (xy 402.953772 -283.822046)
			(xy 402.983337 -283.86139) (xy 403.006208 -283.904967) (xy 403.021792 -283.951648) (xy 403.029687 -284.000225)
			(xy 403.030182 -284.024832) (xy 403.36903 -284.024832) (xy 403.37299 -283.975778) (xy 403.384767 -283.927994)
			(xy 403.404058 -283.882718) (xy 403.430361 -283.841122) (xy 403.462996 -283.804285) (xy 403.501117 -283.77316)
			(xy 403.543738 -283.748553) (xy 403.589754 -283.731101) (xy 403.637973 -283.721257) (xy 403.687148 -283.719276)
			(xy 403.736003 -283.725208) (xy 403.783274 -283.7389) (xy 403.827736 -283.759998) (xy 403.868239 -283.787954)
			(xy 403.903732 -283.822046) (xy 403.933297 -283.86139) (xy 403.956168 -283.904967) (xy 403.971752 -283.951648)
			(xy 403.979647 -284.000225) (xy 403.980142 -284.024832) (xy 404.31899 -284.024832) (xy 404.32295 -283.975778)
			(xy 404.334727 -283.927994) (xy 404.354018 -283.882718) (xy 404.380321 -283.841122) (xy 404.412956 -283.804285)
			(xy 404.451077 -283.77316) (xy 404.493698 -283.748553) (xy 404.539714 -283.731101) (xy 404.587933 -283.721257)
			(xy 404.637108 -283.719276) (xy 404.685963 -283.725208) (xy 404.733234 -283.7389) (xy 404.777696 -283.759998)
			(xy 404.818199 -283.787954) (xy 404.853692 -283.822046) (xy 404.883257 -283.86139) (xy 404.906128 -283.904967)
			(xy 404.921712 -283.951648) (xy 404.929607 -284.000225) (xy 404.930102 -284.024832) (xy 405.269204 -284.024832)
			(xy 405.273164 -283.975778) (xy 405.284941 -283.927994) (xy 405.304232 -283.882718) (xy 405.330535 -283.841122)
			(xy 405.36317 -283.804285) (xy 405.401291 -283.77316) (xy 405.443912 -283.748553) (xy 405.489928 -283.731101)
			(xy 405.538147 -283.721257) (xy 405.587322 -283.719276) (xy 405.636177 -283.725208) (xy 405.683448 -283.7389)
			(xy 405.72791 -283.759998) (xy 405.768413 -283.787954) (xy 405.803906 -283.822046) (xy 405.833471 -283.86139)
			(xy 405.856342 -283.904967) (xy 405.871926 -283.951648) (xy 405.879821 -284.000225) (xy 405.880316 -284.024832)
			(xy 406.219164 -284.024832) (xy 406.223124 -283.975778) (xy 406.234901 -283.927994) (xy 406.254192 -283.882718)
			(xy 406.280495 -283.841122) (xy 406.31313 -283.804285) (xy 406.351251 -283.77316) (xy 406.393872 -283.748553)
			(xy 406.439888 -283.731101) (xy 406.488107 -283.721257) (xy 406.537282 -283.719276) (xy 406.586137 -283.725208)
			(xy 406.633408 -283.7389) (xy 406.67787 -283.759998) (xy 406.718373 -283.787954) (xy 406.753866 -283.822046)
			(xy 406.783431 -283.86139) (xy 406.806302 -283.904967) (xy 406.821886 -283.951648) (xy 406.829781 -284.000225)
			(xy 406.830276 -284.024832) (xy 408.119084 -284.024832) (xy 408.123044 -283.975778) (xy 408.134821 -283.927994)
			(xy 408.154112 -283.882718) (xy 408.180415 -283.841122) (xy 408.21305 -283.804285) (xy 408.251171 -283.77316)
			(xy 408.293792 -283.748553) (xy 408.339808 -283.731101) (xy 408.388027 -283.721257) (xy 408.437202 -283.719276)
			(xy 408.486057 -283.725208) (xy 408.533328 -283.7389) (xy 408.57779 -283.759998) (xy 408.618293 -283.787954)
			(xy 408.653786 -283.822046) (xy 408.683351 -283.86139) (xy 408.706222 -283.904967) (xy 408.721806 -283.951648)
			(xy 408.729701 -284.000225) (xy 408.730196 -284.024832) (xy 409.069044 -284.024832) (xy 409.073004 -283.975778)
			(xy 409.084781 -283.927994) (xy 409.104072 -283.882718) (xy 409.130375 -283.841122) (xy 409.16301 -283.804285)
			(xy 409.201131 -283.77316) (xy 409.243752 -283.748553) (xy 409.289768 -283.731101) (xy 409.337987 -283.721257)
			(xy 409.387162 -283.719276) (xy 409.436017 -283.725208) (xy 409.483288 -283.7389) (xy 409.52775 -283.759998)
			(xy 409.568253 -283.787954) (xy 409.603746 -283.822046) (xy 409.633311 -283.86139) (xy 409.656182 -283.904967)
			(xy 409.671766 -283.951648) (xy 409.679661 -284.000225) (xy 409.680156 -284.024832) (xy 410.019004 -284.024832)
			(xy 410.022964 -283.975778) (xy 410.034741 -283.927994) (xy 410.054032 -283.882718) (xy 410.080335 -283.841122)
			(xy 410.11297 -283.804285) (xy 410.151091 -283.77316) (xy 410.193712 -283.748553) (xy 410.239728 -283.731101)
			(xy 410.287947 -283.721257) (xy 410.337122 -283.719276) (xy 410.385977 -283.725208) (xy 410.433248 -283.7389)
			(xy 410.47771 -283.759998) (xy 410.518213 -283.787954) (xy 410.553706 -283.822046) (xy 410.583271 -283.86139)
			(xy 410.606142 -283.904967) (xy 410.621726 -283.951648) (xy 410.629621 -284.000225) (xy 410.630116 -284.024832)
			(xy 410.969218 -284.024832) (xy 410.973178 -283.975778) (xy 410.984955 -283.927994) (xy 411.004246 -283.882718)
			(xy 411.030549 -283.841122) (xy 411.063184 -283.804285) (xy 411.101305 -283.77316) (xy 411.143926 -283.748553)
			(xy 411.189942 -283.731101) (xy 411.238161 -283.721257) (xy 411.287336 -283.719276) (xy 411.336191 -283.725208)
			(xy 411.383462 -283.7389) (xy 411.427924 -283.759998) (xy 411.468427 -283.787954) (xy 411.50392 -283.822046)
			(xy 411.533485 -283.86139) (xy 411.556356 -283.904967) (xy 411.57194 -283.951648) (xy 411.579835 -284.000225)
			(xy 411.58033 -284.024832) (xy 411.919178 -284.024832) (xy 411.923138 -283.975778) (xy 411.934915 -283.927994)
			(xy 411.954206 -283.882718) (xy 411.980509 -283.841122) (xy 412.013144 -283.804285) (xy 412.051265 -283.77316)
			(xy 412.093886 -283.748553) (xy 412.139902 -283.731101) (xy 412.188121 -283.721257) (xy 412.237296 -283.719276)
			(xy 412.286151 -283.725208) (xy 412.333422 -283.7389) (xy 412.377884 -283.759998) (xy 412.418387 -283.787954)
			(xy 412.45388 -283.822046) (xy 412.483445 -283.86139) (xy 412.506316 -283.904967) (xy 412.5219 -283.951648)
			(xy 412.529795 -284.000225) (xy 412.53029 -284.024832) (xy 412.869138 -284.024832) (xy 412.873098 -283.975778)
			(xy 412.884875 -283.927994) (xy 412.904166 -283.882718) (xy 412.930469 -283.841122) (xy 412.963104 -283.804285)
			(xy 413.001225 -283.77316) (xy 413.043846 -283.748553) (xy 413.089862 -283.731101) (xy 413.138081 -283.721257)
			(xy 413.187256 -283.719276) (xy 413.236111 -283.725208) (xy 413.283382 -283.7389) (xy 413.327844 -283.759998)
			(xy 413.368347 -283.787954) (xy 413.40384 -283.822046) (xy 413.433405 -283.86139) (xy 413.456276 -283.904967)
			(xy 413.47186 -283.951648) (xy 413.479755 -284.000225) (xy 413.48025 -284.024832) (xy 413.819098 -284.024832)
			(xy 413.823058 -283.975778) (xy 413.834835 -283.927994) (xy 413.854126 -283.882718) (xy 413.880429 -283.841122)
			(xy 413.913064 -283.804285) (xy 413.951185 -283.77316) (xy 413.993806 -283.748553) (xy 414.039822 -283.731101)
			(xy 414.088041 -283.721257) (xy 414.137216 -283.719276) (xy 414.186071 -283.725208) (xy 414.233342 -283.7389)
			(xy 414.277804 -283.759998) (xy 414.318307 -283.787954) (xy 414.3538 -283.822046) (xy 414.383365 -283.86139)
			(xy 414.406236 -283.904967) (xy 414.42182 -283.951648) (xy 414.429715 -284.000225) (xy 414.43021 -284.024832)
			(xy 414.769058 -284.024832) (xy 414.773018 -283.975778) (xy 414.784795 -283.927994) (xy 414.804086 -283.882718)
			(xy 414.830389 -283.841122) (xy 414.863024 -283.804285) (xy 414.901145 -283.77316) (xy 414.943766 -283.748553)
			(xy 414.989782 -283.731101) (xy 415.038001 -283.721257) (xy 415.087176 -283.719276) (xy 415.136031 -283.725208)
			(xy 415.183302 -283.7389) (xy 415.227764 -283.759998) (xy 415.268267 -283.787954) (xy 415.30376 -283.822046)
			(xy 415.333325 -283.86139) (xy 415.356196 -283.904967) (xy 415.37178 -283.951648) (xy 415.379675 -284.000225)
			(xy 415.38017 -284.024832) (xy 415.719018 -284.024832) (xy 415.722978 -283.975778) (xy 415.734755 -283.927994)
			(xy 415.754046 -283.882718) (xy 415.780349 -283.841122) (xy 415.812984 -283.804285) (xy 415.851105 -283.77316)
			(xy 415.893726 -283.748553) (xy 415.939742 -283.731101) (xy 415.987961 -283.721257) (xy 416.037136 -283.719276)
			(xy 416.085991 -283.725208) (xy 416.133262 -283.7389) (xy 416.177724 -283.759998) (xy 416.218227 -283.787954)
			(xy 416.25372 -283.822046) (xy 416.283285 -283.86139) (xy 416.306156 -283.904967) (xy 416.32174 -283.951648)
			(xy 416.329635 -284.000225) (xy 416.33013 -284.024832) (xy 416.668978 -284.024832) (xy 416.672938 -283.975778)
			(xy 416.684715 -283.927994) (xy 416.704006 -283.882718) (xy 416.730309 -283.841122) (xy 416.762944 -283.804285)
			(xy 416.801065 -283.77316) (xy 416.843686 -283.748553) (xy 416.889702 -283.731101) (xy 416.937921 -283.721257)
			(xy 416.987096 -283.719276) (xy 417.035951 -283.725208) (xy 417.083222 -283.7389) (xy 417.127684 -283.759998)
			(xy 417.168187 -283.787954) (xy 417.20368 -283.822046) (xy 417.233245 -283.86139) (xy 417.256116 -283.904967)
			(xy 417.2717 -283.951648) (xy 417.279595 -284.000225) (xy 417.28009 -284.024832) (xy 417.619192 -284.024832)
			(xy 417.623152 -283.975778) (xy 417.634929 -283.927994) (xy 417.65422 -283.882718) (xy 417.680523 -283.841122)
			(xy 417.713158 -283.804285) (xy 417.751279 -283.77316) (xy 417.7939 -283.748553) (xy 417.839916 -283.731101)
			(xy 417.888135 -283.721257) (xy 417.93731 -283.719276) (xy 417.986165 -283.725208) (xy 418.033436 -283.7389)
			(xy 418.077898 -283.759998) (xy 418.118401 -283.787954) (xy 418.153894 -283.822046) (xy 418.183459 -283.86139)
			(xy 418.20633 -283.904967) (xy 418.221914 -283.951648) (xy 418.229809 -284.000225) (xy 418.230304 -284.024832)
			(xy 418.569152 -284.024832) (xy 418.573112 -283.975778) (xy 418.584889 -283.927994) (xy 418.60418 -283.882718)
			(xy 418.630483 -283.841122) (xy 418.663118 -283.804285) (xy 418.701239 -283.77316) (xy 418.74386 -283.748553)
			(xy 418.789876 -283.731101) (xy 418.838095 -283.721257) (xy 418.88727 -283.719276) (xy 418.936125 -283.725208)
			(xy 418.983396 -283.7389) (xy 419.027858 -283.759998) (xy 419.068361 -283.787954) (xy 419.103854 -283.822046)
			(xy 419.133419 -283.86139) (xy 419.15629 -283.904967) (xy 419.171874 -283.951648) (xy 419.179769 -284.000225)
			(xy 419.180264 -284.024832) (xy 419.179769 -284.049439) (xy 419.171874 -284.098016) (xy 419.15629 -284.144697)
			(xy 419.133419 -284.188274) (xy 419.103854 -284.227618) (xy 419.068361 -284.26171) (xy 419.027858 -284.289666)
			(xy 418.983396 -284.310764) (xy 418.936125 -284.324456) (xy 418.88727 -284.330388) (xy 418.838095 -284.328407)
			(xy 418.789876 -284.318563) (xy 418.74386 -284.301111) (xy 418.701239 -284.276504) (xy 418.663118 -284.245379)
			(xy 418.630483 -284.208542) (xy 418.60418 -284.166946) (xy 418.584889 -284.12167) (xy 418.573112 -284.073886)
			(xy 418.569152 -284.024832) (xy 418.230304 -284.024832) (xy 418.229809 -284.049439) (xy 418.221914 -284.098016)
			(xy 418.20633 -284.144697) (xy 418.183459 -284.188274) (xy 418.153894 -284.227618) (xy 418.118401 -284.26171)
			(xy 418.077898 -284.289666) (xy 418.033436 -284.310764) (xy 417.986165 -284.324456) (xy 417.93731 -284.330388)
			(xy 417.888135 -284.328407) (xy 417.839916 -284.318563) (xy 417.7939 -284.301111) (xy 417.751279 -284.276504)
			(xy 417.713158 -284.245379) (xy 417.680523 -284.208542) (xy 417.65422 -284.166946) (xy 417.634929 -284.12167)
			(xy 417.623152 -284.073886) (xy 417.619192 -284.024832) (xy 417.28009 -284.024832) (xy 417.279595 -284.049439)
			(xy 417.2717 -284.098016) (xy 417.256116 -284.144697) (xy 417.233245 -284.188274) (xy 417.20368 -284.227618)
			(xy 417.168187 -284.26171) (xy 417.127684 -284.289666) (xy 417.083222 -284.310764) (xy 417.035951 -284.324456)
			(xy 416.987096 -284.330388) (xy 416.937921 -284.328407) (xy 416.889702 -284.318563) (xy 416.843686 -284.301111)
			(xy 416.801065 -284.276504) (xy 416.762944 -284.245379) (xy 416.730309 -284.208542) (xy 416.704006 -284.166946)
			(xy 416.684715 -284.12167) (xy 416.672938 -284.073886) (xy 416.668978 -284.024832) (xy 416.33013 -284.024832)
			(xy 416.329635 -284.049439) (xy 416.32174 -284.098016) (xy 416.306156 -284.144697) (xy 416.283285 -284.188274)
			(xy 416.25372 -284.227618) (xy 416.218227 -284.26171) (xy 416.177724 -284.289666) (xy 416.133262 -284.310764)
			(xy 416.085991 -284.324456) (xy 416.037136 -284.330388) (xy 415.987961 -284.328407) (xy 415.939742 -284.318563)
			(xy 415.893726 -284.301111) (xy 415.851105 -284.276504) (xy 415.812984 -284.245379) (xy 415.780349 -284.208542)
			(xy 415.754046 -284.166946) (xy 415.734755 -284.12167) (xy 415.722978 -284.073886) (xy 415.719018 -284.024832)
			(xy 415.38017 -284.024832) (xy 415.379675 -284.049439) (xy 415.37178 -284.098016) (xy 415.356196 -284.144697)
			(xy 415.333325 -284.188274) (xy 415.30376 -284.227618) (xy 415.268267 -284.26171) (xy 415.227764 -284.289666)
			(xy 415.183302 -284.310764) (xy 415.136031 -284.324456) (xy 415.087176 -284.330388) (xy 415.038001 -284.328407)
			(xy 414.989782 -284.318563) (xy 414.943766 -284.301111) (xy 414.901145 -284.276504) (xy 414.863024 -284.245379)
			(xy 414.830389 -284.208542) (xy 414.804086 -284.166946) (xy 414.784795 -284.12167) (xy 414.773018 -284.073886)
			(xy 414.769058 -284.024832) (xy 414.43021 -284.024832) (xy 414.429715 -284.049439) (xy 414.42182 -284.098016)
			(xy 414.406236 -284.144697) (xy 414.383365 -284.188274) (xy 414.3538 -284.227618) (xy 414.318307 -284.26171)
			(xy 414.277804 -284.289666) (xy 414.233342 -284.310764) (xy 414.186071 -284.324456) (xy 414.137216 -284.330388)
			(xy 414.088041 -284.328407) (xy 414.039822 -284.318563) (xy 413.993806 -284.301111) (xy 413.951185 -284.276504)
			(xy 413.913064 -284.245379) (xy 413.880429 -284.208542) (xy 413.854126 -284.166946) (xy 413.834835 -284.12167)
			(xy 413.823058 -284.073886) (xy 413.819098 -284.024832) (xy 413.48025 -284.024832) (xy 413.479755 -284.049439)
			(xy 413.47186 -284.098016) (xy 413.456276 -284.144697) (xy 413.433405 -284.188274) (xy 413.40384 -284.227618)
			(xy 413.368347 -284.26171) (xy 413.327844 -284.289666) (xy 413.283382 -284.310764) (xy 413.236111 -284.324456)
			(xy 413.187256 -284.330388) (xy 413.138081 -284.328407) (xy 413.089862 -284.318563) (xy 413.043846 -284.301111)
			(xy 413.001225 -284.276504) (xy 412.963104 -284.245379) (xy 412.930469 -284.208542) (xy 412.904166 -284.166946)
			(xy 412.884875 -284.12167) (xy 412.873098 -284.073886) (xy 412.869138 -284.024832) (xy 412.53029 -284.024832)
			(xy 412.529795 -284.049439) (xy 412.5219 -284.098016) (xy 412.506316 -284.144697) (xy 412.483445 -284.188274)
			(xy 412.45388 -284.227618) (xy 412.418387 -284.26171) (xy 412.377884 -284.289666) (xy 412.333422 -284.310764)
			(xy 412.286151 -284.324456) (xy 412.237296 -284.330388) (xy 412.188121 -284.328407) (xy 412.139902 -284.318563)
			(xy 412.093886 -284.301111) (xy 412.051265 -284.276504) (xy 412.013144 -284.245379) (xy 411.980509 -284.208542)
			(xy 411.954206 -284.166946) (xy 411.934915 -284.12167) (xy 411.923138 -284.073886) (xy 411.919178 -284.024832)
			(xy 411.58033 -284.024832) (xy 411.579835 -284.049439) (xy 411.57194 -284.098016) (xy 411.556356 -284.144697)
			(xy 411.533485 -284.188274) (xy 411.50392 -284.227618) (xy 411.468427 -284.26171) (xy 411.427924 -284.289666)
			(xy 411.383462 -284.310764) (xy 411.336191 -284.324456) (xy 411.287336 -284.330388) (xy 411.238161 -284.328407)
			(xy 411.189942 -284.318563) (xy 411.143926 -284.301111) (xy 411.101305 -284.276504) (xy 411.063184 -284.245379)
			(xy 411.030549 -284.208542) (xy 411.004246 -284.166946) (xy 410.984955 -284.12167) (xy 410.973178 -284.073886)
			(xy 410.969218 -284.024832) (xy 410.630116 -284.024832) (xy 410.629621 -284.049439) (xy 410.621726 -284.098016)
			(xy 410.606142 -284.144697) (xy 410.583271 -284.188274) (xy 410.553706 -284.227618) (xy 410.518213 -284.26171)
			(xy 410.47771 -284.289666) (xy 410.433248 -284.310764) (xy 410.385977 -284.324456) (xy 410.337122 -284.330388)
			(xy 410.287947 -284.328407) (xy 410.239728 -284.318563) (xy 410.193712 -284.301111) (xy 410.151091 -284.276504)
			(xy 410.11297 -284.245379) (xy 410.080335 -284.208542) (xy 410.054032 -284.166946) (xy 410.034741 -284.12167)
			(xy 410.022964 -284.073886) (xy 410.019004 -284.024832) (xy 409.680156 -284.024832) (xy 409.679661 -284.049439)
			(xy 409.671766 -284.098016) (xy 409.656182 -284.144697) (xy 409.633311 -284.188274) (xy 409.603746 -284.227618)
			(xy 409.568253 -284.26171) (xy 409.52775 -284.289666) (xy 409.483288 -284.310764) (xy 409.436017 -284.324456)
			(xy 409.387162 -284.330388) (xy 409.337987 -284.328407) (xy 409.289768 -284.318563) (xy 409.243752 -284.301111)
			(xy 409.201131 -284.276504) (xy 409.16301 -284.245379) (xy 409.130375 -284.208542) (xy 409.104072 -284.166946)
			(xy 409.084781 -284.12167) (xy 409.073004 -284.073886) (xy 409.069044 -284.024832) (xy 408.730196 -284.024832)
			(xy 408.729701 -284.049439) (xy 408.721806 -284.098016) (xy 408.706222 -284.144697) (xy 408.683351 -284.188274)
			(xy 408.653786 -284.227618) (xy 408.618293 -284.26171) (xy 408.57779 -284.289666) (xy 408.533328 -284.310764)
			(xy 408.486057 -284.324456) (xy 408.437202 -284.330388) (xy 408.388027 -284.328407) (xy 408.339808 -284.318563)
			(xy 408.293792 -284.301111) (xy 408.251171 -284.276504) (xy 408.21305 -284.245379) (xy 408.180415 -284.208542)
			(xy 408.154112 -284.166946) (xy 408.134821 -284.12167) (xy 408.123044 -284.073886) (xy 408.119084 -284.024832)
			(xy 406.830276 -284.024832) (xy 406.829781 -284.049439) (xy 406.821886 -284.098016) (xy 406.806302 -284.144697)
			(xy 406.783431 -284.188274) (xy 406.753866 -284.227618) (xy 406.718373 -284.26171) (xy 406.67787 -284.289666)
			(xy 406.633408 -284.310764) (xy 406.586137 -284.324456) (xy 406.537282 -284.330388) (xy 406.488107 -284.328407)
			(xy 406.439888 -284.318563) (xy 406.393872 -284.301111) (xy 406.351251 -284.276504) (xy 406.31313 -284.245379)
			(xy 406.280495 -284.208542) (xy 406.254192 -284.166946) (xy 406.234901 -284.12167) (xy 406.223124 -284.073886)
			(xy 406.219164 -284.024832) (xy 405.880316 -284.024832) (xy 405.879821 -284.049439) (xy 405.871926 -284.098016)
			(xy 405.856342 -284.144697) (xy 405.833471 -284.188274) (xy 405.803906 -284.227618) (xy 405.768413 -284.26171)
			(xy 405.72791 -284.289666) (xy 405.683448 -284.310764) (xy 405.636177 -284.324456) (xy 405.587322 -284.330388)
			(xy 405.538147 -284.328407) (xy 405.489928 -284.318563) (xy 405.443912 -284.301111) (xy 405.401291 -284.276504)
			(xy 405.36317 -284.245379) (xy 405.330535 -284.208542) (xy 405.304232 -284.166946) (xy 405.284941 -284.12167)
			(xy 405.273164 -284.073886) (xy 405.269204 -284.024832) (xy 404.930102 -284.024832) (xy 404.929607 -284.049439)
			(xy 404.921712 -284.098016) (xy 404.906128 -284.144697) (xy 404.883257 -284.188274) (xy 404.853692 -284.227618)
			(xy 404.818199 -284.26171) (xy 404.777696 -284.289666) (xy 404.733234 -284.310764) (xy 404.685963 -284.324456)
			(xy 404.637108 -284.330388) (xy 404.587933 -284.328407) (xy 404.539714 -284.318563) (xy 404.493698 -284.301111)
			(xy 404.451077 -284.276504) (xy 404.412956 -284.245379) (xy 404.380321 -284.208542) (xy 404.354018 -284.166946)
			(xy 404.334727 -284.12167) (xy 404.32295 -284.073886) (xy 404.31899 -284.024832) (xy 403.980142 -284.024832)
			(xy 403.979647 -284.049439) (xy 403.971752 -284.098016) (xy 403.956168 -284.144697) (xy 403.933297 -284.188274)
			(xy 403.903732 -284.227618) (xy 403.868239 -284.26171) (xy 403.827736 -284.289666) (xy 403.783274 -284.310764)
			(xy 403.736003 -284.324456) (xy 403.687148 -284.330388) (xy 403.637973 -284.328407) (xy 403.589754 -284.318563)
			(xy 403.543738 -284.301111) (xy 403.501117 -284.276504) (xy 403.462996 -284.245379) (xy 403.430361 -284.208542)
			(xy 403.404058 -284.166946) (xy 403.384767 -284.12167) (xy 403.37299 -284.073886) (xy 403.36903 -284.024832)
			(xy 403.030182 -284.024832) (xy 403.029687 -284.049439) (xy 403.021792 -284.098016) (xy 403.006208 -284.144697)
			(xy 402.983337 -284.188274) (xy 402.953772 -284.227618) (xy 402.918279 -284.26171) (xy 402.877776 -284.289666)
			(xy 402.833314 -284.310764) (xy 402.786043 -284.324456) (xy 402.737188 -284.330388) (xy 402.688013 -284.328407)
			(xy 402.639794 -284.318563) (xy 402.593778 -284.301111) (xy 402.551157 -284.276504) (xy 402.513036 -284.245379)
			(xy 402.480401 -284.208542) (xy 402.454098 -284.166946) (xy 402.434807 -284.12167) (xy 402.42303 -284.073886)
			(xy 402.41907 -284.024832) (xy 402.080222 -284.024832) (xy 402.079727 -284.049439) (xy 402.071832 -284.098016)
			(xy 402.056248 -284.144697) (xy 402.033377 -284.188274) (xy 402.003812 -284.227618) (xy 401.968319 -284.26171)
			(xy 401.927816 -284.289666) (xy 401.883354 -284.310764) (xy 401.836083 -284.324456) (xy 401.787228 -284.330388)
			(xy 401.738053 -284.328407) (xy 401.689834 -284.318563) (xy 401.643818 -284.301111) (xy 401.601197 -284.276504)
			(xy 401.563076 -284.245379) (xy 401.530441 -284.208542) (xy 401.504138 -284.166946) (xy 401.484847 -284.12167)
			(xy 401.47307 -284.073886) (xy 401.46911 -284.024832) (xy 401.130262 -284.024832) (xy 401.129767 -284.049439)
			(xy 401.121872 -284.098016) (xy 401.106288 -284.144697) (xy 401.083417 -284.188274) (xy 401.053852 -284.227618)
			(xy 401.018359 -284.26171) (xy 400.977856 -284.289666) (xy 400.933394 -284.310764) (xy 400.886123 -284.324456)
			(xy 400.837268 -284.330388) (xy 400.788093 -284.328407) (xy 400.739874 -284.318563) (xy 400.693858 -284.301111)
			(xy 400.651237 -284.276504) (xy 400.613116 -284.245379) (xy 400.580481 -284.208542) (xy 400.554178 -284.166946)
			(xy 400.534887 -284.12167) (xy 400.52311 -284.073886) (xy 400.51915 -284.024832) (xy 400.180302 -284.024832)
			(xy 400.179807 -284.049439) (xy 400.171912 -284.098016) (xy 400.156328 -284.144697) (xy 400.133457 -284.188274)
			(xy 400.103892 -284.227618) (xy 400.068399 -284.26171) (xy 400.027896 -284.289666) (xy 399.983434 -284.310764)
			(xy 399.936163 -284.324456) (xy 399.887308 -284.330388) (xy 399.838133 -284.328407) (xy 399.789914 -284.318563)
			(xy 399.743898 -284.301111) (xy 399.701277 -284.276504) (xy 399.663156 -284.245379) (xy 399.630521 -284.208542)
			(xy 399.604218 -284.166946) (xy 399.584927 -284.12167) (xy 399.57315 -284.073886) (xy 399.56919 -284.024832)
			(xy 399.230342 -284.024832) (xy 399.229847 -284.049439) (xy 399.221952 -284.098016) (xy 399.206368 -284.144697)
			(xy 399.183497 -284.188274) (xy 399.153932 -284.227618) (xy 399.118439 -284.26171) (xy 399.077936 -284.289666)
			(xy 399.033474 -284.310764) (xy 398.986203 -284.324456) (xy 398.937348 -284.330388) (xy 398.888173 -284.328407)
			(xy 398.839954 -284.318563) (xy 398.793938 -284.301111) (xy 398.751317 -284.276504) (xy 398.713196 -284.245379)
			(xy 398.680561 -284.208542) (xy 398.654258 -284.166946) (xy 398.634967 -284.12167) (xy 398.62319 -284.073886)
			(xy 398.61923 -284.024832) (xy 398.280128 -284.024832) (xy 398.279633 -284.049439) (xy 398.271738 -284.098016)
			(xy 398.256154 -284.144697) (xy 398.233283 -284.188274) (xy 398.203718 -284.227618) (xy 398.168225 -284.26171)
			(xy 398.127722 -284.289666) (xy 398.08326 -284.310764) (xy 398.035989 -284.324456) (xy 397.987134 -284.330388)
			(xy 397.937959 -284.328407) (xy 397.88974 -284.318563) (xy 397.843724 -284.301111) (xy 397.801103 -284.276504)
			(xy 397.762982 -284.245379) (xy 397.730347 -284.208542) (xy 397.704044 -284.166946) (xy 397.684753 -284.12167)
			(xy 397.672976 -284.073886) (xy 397.669016 -284.024832) (xy 397.330168 -284.024832) (xy 397.329673 -284.049439)
			(xy 397.321778 -284.098016) (xy 397.306194 -284.144697) (xy 397.283323 -284.188274) (xy 397.253758 -284.227618)
			(xy 397.218265 -284.26171) (xy 397.177762 -284.289666) (xy 397.1333 -284.310764) (xy 397.086029 -284.324456)
			(xy 397.037174 -284.330388) (xy 396.987999 -284.328407) (xy 396.93978 -284.318563) (xy 396.893764 -284.301111)
			(xy 396.851143 -284.276504) (xy 396.813022 -284.245379) (xy 396.780387 -284.208542) (xy 396.754084 -284.166946)
			(xy 396.734793 -284.12167) (xy 396.723016 -284.073886) (xy 396.719056 -284.024832) (xy 396.380208 -284.024832)
			(xy 396.379713 -284.049439) (xy 396.371818 -284.098016) (xy 396.356234 -284.144697) (xy 396.333363 -284.188274)
			(xy 396.303798 -284.227618) (xy 396.268305 -284.26171) (xy 396.227802 -284.289666) (xy 396.18334 -284.310764)
			(xy 396.136069 -284.324456) (xy 396.087214 -284.330388) (xy 396.038039 -284.328407) (xy 395.98982 -284.318563)
			(xy 395.943804 -284.301111) (xy 395.901183 -284.276504) (xy 395.863062 -284.245379) (xy 395.830427 -284.208542)
			(xy 395.804124 -284.166946) (xy 395.784833 -284.12167) (xy 395.773056 -284.073886) (xy 395.769096 -284.024832)
			(xy 395.430248 -284.024832) (xy 395.429753 -284.049439) (xy 395.421858 -284.098016) (xy 395.406274 -284.144697)
			(xy 395.383403 -284.188274) (xy 395.353838 -284.227618) (xy 395.318345 -284.26171) (xy 395.277842 -284.289666)
			(xy 395.23338 -284.310764) (xy 395.186109 -284.324456) (xy 395.137254 -284.330388) (xy 395.088079 -284.328407)
			(xy 395.03986 -284.318563) (xy 394.993844 -284.301111) (xy 394.951223 -284.276504) (xy 394.913102 -284.245379)
			(xy 394.880467 -284.208542) (xy 394.854164 -284.166946) (xy 394.834873 -284.12167) (xy 394.823096 -284.073886)
			(xy 394.819136 -284.024832) (xy 394.480288 -284.024832) (xy 394.479793 -284.049439) (xy 394.471898 -284.098016)
			(xy 394.456314 -284.144697) (xy 394.433443 -284.188274) (xy 394.403878 -284.227618) (xy 394.368385 -284.26171)
			(xy 394.327882 -284.289666) (xy 394.28342 -284.310764) (xy 394.236149 -284.324456) (xy 394.187294 -284.330388)
			(xy 394.138119 -284.328407) (xy 394.0899 -284.318563) (xy 394.043884 -284.301111) (xy 394.001263 -284.276504)
			(xy 393.963142 -284.245379) (xy 393.930507 -284.208542) (xy 393.904204 -284.166946) (xy 393.884913 -284.12167)
			(xy 393.873136 -284.073886) (xy 393.869176 -284.024832) (xy 393.530328 -284.024832) (xy 393.529833 -284.049439)
			(xy 393.521938 -284.098016) (xy 393.506354 -284.144697) (xy 393.483483 -284.188274) (xy 393.453918 -284.227618)
			(xy 393.418425 -284.26171) (xy 393.377922 -284.289666) (xy 393.33346 -284.310764) (xy 393.286189 -284.324456)
			(xy 393.237334 -284.330388) (xy 393.188159 -284.328407) (xy 393.13994 -284.318563) (xy 393.093924 -284.301111)
			(xy 393.051303 -284.276504) (xy 393.013182 -284.245379) (xy 392.980547 -284.208542) (xy 392.954244 -284.166946)
			(xy 392.934953 -284.12167) (xy 392.923176 -284.073886) (xy 392.919216 -284.024832) (xy 392.580114 -284.024832)
			(xy 392.579619 -284.049439) (xy 392.571724 -284.098016) (xy 392.55614 -284.144697) (xy 392.533269 -284.188274)
			(xy 392.503704 -284.227618) (xy 392.468211 -284.26171) (xy 392.427708 -284.289666) (xy 392.383246 -284.310764)
			(xy 392.335975 -284.324456) (xy 392.28712 -284.330388) (xy 392.237945 -284.328407) (xy 392.189726 -284.318563)
			(xy 392.14371 -284.301111) (xy 392.101089 -284.276504) (xy 392.062968 -284.245379) (xy 392.030333 -284.208542)
			(xy 392.00403 -284.166946) (xy 391.984739 -284.12167) (xy 391.972962 -284.073886) (xy 391.969002 -284.024832)
			(xy 391.630154 -284.024832) (xy 391.629659 -284.049439) (xy 391.621764 -284.098016) (xy 391.60618 -284.144697)
			(xy 391.583309 -284.188274) (xy 391.553744 -284.227618) (xy 391.518251 -284.26171) (xy 391.477748 -284.289666)
			(xy 391.433286 -284.310764) (xy 391.386015 -284.324456) (xy 391.33716 -284.330388) (xy 391.287985 -284.328407)
			(xy 391.239766 -284.318563) (xy 391.19375 -284.301111) (xy 391.151129 -284.276504) (xy 391.113008 -284.245379)
			(xy 391.080373 -284.208542) (xy 391.05407 -284.166946) (xy 391.034779 -284.12167) (xy 391.023002 -284.073886)
			(xy 391.019042 -284.024832) (xy 388.780274 -284.024832) (xy 388.779779 -284.049439) (xy 388.771884 -284.098016)
			(xy 388.7563 -284.144697) (xy 388.733429 -284.188274) (xy 388.703864 -284.227618) (xy 388.668371 -284.26171)
			(xy 388.627868 -284.289666) (xy 388.583406 -284.310764) (xy 388.536135 -284.324456) (xy 388.48728 -284.330388)
			(xy 388.438105 -284.328407) (xy 388.389886 -284.318563) (xy 388.34387 -284.301111) (xy 388.301249 -284.276504)
			(xy 388.263128 -284.245379) (xy 388.230493 -284.208542) (xy 388.20419 -284.166946) (xy 388.184899 -284.12167)
			(xy 388.173122 -284.073886) (xy 388.169162 -284.024832) (xy 387.830314 -284.024832) (xy 387.829819 -284.049439)
			(xy 387.821924 -284.098016) (xy 387.80634 -284.144697) (xy 387.783469 -284.188274) (xy 387.753904 -284.227618)
			(xy 387.718411 -284.26171) (xy 387.677908 -284.289666) (xy 387.633446 -284.310764) (xy 387.586175 -284.324456)
			(xy 387.53732 -284.330388) (xy 387.488145 -284.328407) (xy 387.439926 -284.318563) (xy 387.39391 -284.301111)
			(xy 387.351289 -284.276504) (xy 387.313168 -284.245379) (xy 387.280533 -284.208542) (xy 387.25423 -284.166946)
			(xy 387.234939 -284.12167) (xy 387.223162 -284.073886) (xy 387.219202 -284.024832) (xy 386.880354 -284.024832)
			(xy 386.879859 -284.049439) (xy 386.871964 -284.098016) (xy 386.85638 -284.144697) (xy 386.833509 -284.188274)
			(xy 386.803944 -284.227618) (xy 386.768451 -284.26171) (xy 386.727948 -284.289666) (xy 386.683486 -284.310764)
			(xy 386.636215 -284.324456) (xy 386.58736 -284.330388) (xy 386.538185 -284.328407) (xy 386.489966 -284.318563)
			(xy 386.44395 -284.301111) (xy 386.401329 -284.276504) (xy 386.363208 -284.245379) (xy 386.330573 -284.208542)
			(xy 386.30427 -284.166946) (xy 386.284979 -284.12167) (xy 386.273202 -284.073886) (xy 386.269242 -284.024832)
			(xy 385.93014 -284.024832) (xy 385.929645 -284.049439) (xy 385.92175 -284.098016) (xy 385.906166 -284.144697)
			(xy 385.883295 -284.188274) (xy 385.85373 -284.227618) (xy 385.818237 -284.26171) (xy 385.777734 -284.289666)
			(xy 385.733272 -284.310764) (xy 385.686001 -284.324456) (xy 385.637146 -284.330388) (xy 385.587971 -284.328407)
			(xy 385.539752 -284.318563) (xy 385.493736 -284.301111) (xy 385.451115 -284.276504) (xy 385.412994 -284.245379)
			(xy 385.380359 -284.208542) (xy 385.354056 -284.166946) (xy 385.334765 -284.12167) (xy 385.322988 -284.073886)
			(xy 385.319028 -284.024832) (xy 384.98018 -284.024832) (xy 384.979685 -284.049439) (xy 384.97179 -284.098016)
			(xy 384.956206 -284.144697) (xy 384.933335 -284.188274) (xy 384.90377 -284.227618) (xy 384.868277 -284.26171)
			(xy 384.827774 -284.289666) (xy 384.783312 -284.310764) (xy 384.736041 -284.324456) (xy 384.687186 -284.330388)
			(xy 384.638011 -284.328407) (xy 384.589792 -284.318563) (xy 384.543776 -284.301111) (xy 384.501155 -284.276504)
			(xy 384.463034 -284.245379) (xy 384.430399 -284.208542) (xy 384.404096 -284.166946) (xy 384.384805 -284.12167)
			(xy 384.373028 -284.073886) (xy 384.369068 -284.024832) (xy 383.78638 -284.024832) (xy 383.78638 -284.83814)
			(xy 383.786843 -284.848016) (xy 383.79429 -284.866311) (xy 383.800858 -284.8737) (xy 383.801112 -284.873954)
			(xy 383.90195 -284.974792) (xy 384.369068 -284.974792) (xy 384.373028 -284.925738) (xy 384.384805 -284.877954)
			(xy 384.404096 -284.832678) (xy 384.430399 -284.791082) (xy 384.463034 -284.754245) (xy 384.501155 -284.72312)
			(xy 384.543776 -284.698513) (xy 384.589792 -284.681061) (xy 384.638011 -284.671217) (xy 384.687186 -284.669236)
			(xy 384.736041 -284.675168) (xy 384.783312 -284.68886) (xy 384.827774 -284.709958) (xy 384.868277 -284.737914)
			(xy 384.90377 -284.772006) (xy 384.933335 -284.81135) (xy 384.956206 -284.854927) (xy 384.97179 -284.901608)
			(xy 384.979685 -284.950185) (xy 384.98018 -284.974792) (xy 385.319028 -284.974792) (xy 385.322988 -284.925738)
			(xy 385.334765 -284.877954) (xy 385.354056 -284.832678) (xy 385.380359 -284.791082) (xy 385.412994 -284.754245)
			(xy 385.451115 -284.72312) (xy 385.493736 -284.698513) (xy 385.539752 -284.681061) (xy 385.587971 -284.671217)
			(xy 385.637146 -284.669236) (xy 385.686001 -284.675168) (xy 385.733272 -284.68886) (xy 385.777734 -284.709958)
			(xy 385.818237 -284.737914) (xy 385.85373 -284.772006) (xy 385.883295 -284.81135) (xy 385.906166 -284.854927)
			(xy 385.92175 -284.901608) (xy 385.929645 -284.950185) (xy 385.93014 -284.974792) (xy 386.269242 -284.974792)
			(xy 386.273202 -284.925738) (xy 386.284979 -284.877954) (xy 386.30427 -284.832678) (xy 386.330573 -284.791082)
			(xy 386.363208 -284.754245) (xy 386.401329 -284.72312) (xy 386.44395 -284.698513) (xy 386.489966 -284.681061)
			(xy 386.538185 -284.671217) (xy 386.58736 -284.669236) (xy 386.636215 -284.675168) (xy 386.683486 -284.68886)
			(xy 386.727948 -284.709958) (xy 386.768451 -284.737914) (xy 386.803944 -284.772006) (xy 386.833509 -284.81135)
			(xy 386.85638 -284.854927) (xy 386.871964 -284.901608) (xy 386.879859 -284.950185) (xy 386.880354 -284.974792)
			(xy 387.219202 -284.974792) (xy 387.223162 -284.925738) (xy 387.234939 -284.877954) (xy 387.25423 -284.832678)
			(xy 387.280533 -284.791082) (xy 387.313168 -284.754245) (xy 387.351289 -284.72312) (xy 387.39391 -284.698513)
			(xy 387.439926 -284.681061) (xy 387.488145 -284.671217) (xy 387.53732 -284.669236) (xy 387.586175 -284.675168)
			(xy 387.633446 -284.68886) (xy 387.677908 -284.709958) (xy 387.718411 -284.737914) (xy 387.753904 -284.772006)
			(xy 387.783469 -284.81135) (xy 387.80634 -284.854927) (xy 387.821924 -284.901608) (xy 387.829819 -284.950185)
			(xy 387.830314 -284.974792) (xy 388.169162 -284.974792) (xy 388.173122 -284.925738) (xy 388.184899 -284.877954)
			(xy 388.20419 -284.832678) (xy 388.230493 -284.791082) (xy 388.263128 -284.754245) (xy 388.301249 -284.72312)
			(xy 388.34387 -284.698513) (xy 388.389886 -284.681061) (xy 388.438105 -284.671217) (xy 388.48728 -284.669236)
			(xy 388.536135 -284.675168) (xy 388.583406 -284.68886) (xy 388.627868 -284.709958) (xy 388.668371 -284.737914)
			(xy 388.703864 -284.772006) (xy 388.733429 -284.81135) (xy 388.7563 -284.854927) (xy 388.771884 -284.901608)
			(xy 388.779779 -284.950185) (xy 388.780274 -284.974792) (xy 388.779779 -284.999399) (xy 388.771884 -285.047976)
			(xy 388.7563 -285.094657) (xy 388.733429 -285.138234) (xy 388.703864 -285.177578) (xy 388.668371 -285.21167)
			(xy 388.627868 -285.239626) (xy 388.583406 -285.260724) (xy 388.536135 -285.274416) (xy 388.48728 -285.280348)
			(xy 388.438105 -285.278367) (xy 388.389886 -285.268523) (xy 388.34387 -285.251071) (xy 388.301249 -285.226464)
			(xy 388.263128 -285.195339) (xy 388.230493 -285.158502) (xy 388.20419 -285.116906) (xy 388.184899 -285.07163)
			(xy 388.173122 -285.023846) (xy 388.169162 -284.974792) (xy 387.830314 -284.974792) (xy 387.829819 -284.999399)
			(xy 387.821924 -285.047976) (xy 387.80634 -285.094657) (xy 387.783469 -285.138234) (xy 387.753904 -285.177578)
			(xy 387.718411 -285.21167) (xy 387.677908 -285.239626) (xy 387.633446 -285.260724) (xy 387.586175 -285.274416)
			(xy 387.53732 -285.280348) (xy 387.488145 -285.278367) (xy 387.439926 -285.268523) (xy 387.39391 -285.251071)
			(xy 387.351289 -285.226464) (xy 387.313168 -285.195339) (xy 387.280533 -285.158502) (xy 387.25423 -285.116906)
			(xy 387.234939 -285.07163) (xy 387.223162 -285.023846) (xy 387.219202 -284.974792) (xy 386.880354 -284.974792)
			(xy 386.879859 -284.999399) (xy 386.871964 -285.047976) (xy 386.85638 -285.094657) (xy 386.833509 -285.138234)
			(xy 386.803944 -285.177578) (xy 386.768451 -285.21167) (xy 386.727948 -285.239626) (xy 386.683486 -285.260724)
			(xy 386.636215 -285.274416) (xy 386.58736 -285.280348) (xy 386.538185 -285.278367) (xy 386.489966 -285.268523)
			(xy 386.44395 -285.251071) (xy 386.401329 -285.226464) (xy 386.363208 -285.195339) (xy 386.330573 -285.158502)
			(xy 386.30427 -285.116906) (xy 386.284979 -285.07163) (xy 386.273202 -285.023846) (xy 386.269242 -284.974792)
			(xy 385.93014 -284.974792) (xy 385.929645 -284.999399) (xy 385.92175 -285.047976) (xy 385.906166 -285.094657)
			(xy 385.883295 -285.138234) (xy 385.85373 -285.177578) (xy 385.818237 -285.21167) (xy 385.777734 -285.239626)
			(xy 385.733272 -285.260724) (xy 385.686001 -285.274416) (xy 385.637146 -285.280348) (xy 385.587971 -285.278367)
			(xy 385.539752 -285.268523) (xy 385.493736 -285.251071) (xy 385.451115 -285.226464) (xy 385.412994 -285.195339)
			(xy 385.380359 -285.158502) (xy 385.354056 -285.116906) (xy 385.334765 -285.07163) (xy 385.322988 -285.023846)
			(xy 385.319028 -284.974792) (xy 384.98018 -284.974792) (xy 384.979685 -284.999399) (xy 384.97179 -285.047976)
			(xy 384.956206 -285.094657) (xy 384.933335 -285.138234) (xy 384.90377 -285.177578) (xy 384.868277 -285.21167)
			(xy 384.827774 -285.239626) (xy 384.783312 -285.260724) (xy 384.736041 -285.274416) (xy 384.687186 -285.280348)
			(xy 384.638011 -285.278367) (xy 384.589792 -285.268523) (xy 384.543776 -285.251071) (xy 384.501155 -285.226464)
			(xy 384.463034 -285.195339) (xy 384.430399 -285.158502) (xy 384.404096 -285.116906) (xy 384.384805 -285.07163)
			(xy 384.373028 -285.023846) (xy 384.369068 -284.974792) (xy 383.90195 -284.974792) (xy 384.54457 -285.617412)
			(xy 384.549515 -285.622) (xy 384.56122 -285.628694) (xy 384.567684 -285.63062) (xy 384.574094 -285.632033)
			(xy 384.587215 -285.631916) (xy 384.593592 -285.630366) (xy 384.5941 -285.630366) (xy 384.613839 -285.625271)
			(xy 384.654235 -285.619798) (xy 384.674618 -285.619444) (xy 384.683 -285.619444) (xy 384.708669 -285.620662)
			(xy 384.759081 -285.630617) (xy 384.807117 -285.648866) (xy 384.851421 -285.674896) (xy 384.890746 -285.707972)
			(xy 384.923982 -285.747162) (xy 384.950192 -285.79136) (xy 384.968637 -285.839321) (xy 384.978797 -285.889692)
			(xy 384.98018 -285.915354) (xy 384.98018 -285.915862) (xy 384.980893 -285.925769) (xy 384.988858 -285.943945)
			(xy 384.995674 -285.951168) (xy 385.046474 -286.000444) (xy 385.053827 -286.006921) (xy 385.07199 -286.014226)
			(xy 385.08178 -286.014668) (xy 385.217924 -286.014668) (xy 385.227713 -286.014226) (xy 385.245877 -286.006919)
			(xy 385.25323 -286.000444) (xy 385.311396 -285.944056) (xy 385.31927 -285.926022) (xy 385.319524 -285.916116)
			(xy 385.32071 -285.891328) (xy 385.330113 -285.842604) (xy 385.347269 -285.796041) (xy 385.371727 -285.752864)
			(xy 385.402844 -285.714208) (xy 385.439799 -285.681091) (xy 385.481623 -285.654384) (xy 385.527214 -285.634789)
			(xy 385.575372 -285.622823) (xy 385.624832 -285.618798) (xy 385.674292 -285.622823) (xy 385.72245 -285.634789)
			(xy 385.768041 -285.654384) (xy 385.809865 -285.681091) (xy 385.84682 -285.714208) (xy 385.877937 -285.752864)
			(xy 385.902395 -285.796041) (xy 385.919551 -285.842604) (xy 385.928954 -285.891328) (xy 385.93014 -285.916116)
			(xy 385.930394 -285.926022) (xy 385.938268 -285.944056) (xy 385.996434 -286.000444) (xy 386.003785 -286.006928)
			(xy 386.021948 -286.014247) (xy 386.03174 -286.014668) (xy 386.168138 -286.014668) (xy 386.177926 -286.014223)
			(xy 386.196086 -286.006913) (xy 386.203444 -286.000444) (xy 386.26161 -285.944056) (xy 386.269484 -285.926022)
			(xy 386.269738 -285.916116) (xy 386.270924 -285.891328) (xy 386.280327 -285.842604) (xy 386.297483 -285.796041)
			(xy 386.321941 -285.752864) (xy 386.353058 -285.714208) (xy 386.390013 -285.681091) (xy 386.431837 -285.654384)
			(xy 386.477428 -285.634789) (xy 386.525586 -285.622823) (xy 386.575046 -285.618798) (xy 386.624506 -285.622823)
			(xy 386.672664 -285.634789) (xy 386.718255 -285.654384) (xy 386.760079 -285.681091) (xy 386.797034 -285.714208)
			(xy 386.828151 -285.752864) (xy 386.852609 -285.796041) (xy 386.869765 -285.842604) (xy 386.879168 -285.891328)
			(xy 386.880354 -285.916116) (xy 386.880608 -285.926022) (xy 386.888482 -285.944056) (xy 386.946648 -286.000444)
			(xy 386.953999 -286.006926) (xy 386.972162 -286.01424) (xy 386.981954 -286.014668) (xy 387.118098 -286.014668)
			(xy 387.127881 -286.014213) (xy 387.146026 -286.006887) (xy 387.153404 -286.000444) (xy 387.21157 -285.944056)
			(xy 387.219444 -285.926022) (xy 387.219698 -285.916116) (xy 387.220884 -285.891328) (xy 387.230287 -285.842604)
			(xy 387.247443 -285.796041) (xy 387.271901 -285.752864) (xy 387.303018 -285.714208) (xy 387.339973 -285.681091)
			(xy 387.381797 -285.654384) (xy 387.427388 -285.634789) (xy 387.475546 -285.622823) (xy 387.525006 -285.618798)
			(xy 387.574466 -285.622823) (xy 387.622624 -285.634789) (xy 387.668215 -285.654384) (xy 387.710039 -285.681091)
			(xy 387.746994 -285.714208) (xy 387.778111 -285.752864) (xy 387.802569 -285.796041) (xy 387.819725 -285.842604)
			(xy 387.829128 -285.891328) (xy 387.830314 -285.916116) (xy 387.830568 -285.926022) (xy 387.838442 -285.944056)
			(xy 387.896608 -286.000444) (xy 387.903958 -286.006932) (xy 387.92212 -286.01426) (xy 387.931914 -286.014668)
			(xy 388.068058 -286.014668) (xy 388.077844 -286.01422) (xy 388.096 -286.006905) (xy 388.103364 -286.000444)
			(xy 388.16153 -285.944056) (xy 388.169404 -285.926022) (xy 388.169658 -285.916116) (xy 388.170758 -285.89257)
			(xy 388.17931 -285.846218) (xy 388.194885 -285.801731) (xy 388.217113 -285.760167) (xy 388.245466 -285.722513)
			(xy 388.27927 -285.689665) (xy 388.31772 -285.662403) (xy 388.359905 -285.641375) (xy 388.40482 -285.627082)
			(xy 388.451398 -285.619862) (xy 388.474966 -285.619444) (xy 388.502691 -285.620054) (xy 388.55723 -285.630069)
			(xy 388.609067 -285.649758) (xy 388.656501 -285.678476) (xy 388.677658 -285.696406) (xy 388.685184 -285.702593)
			(xy 388.703475 -285.709248) (xy 388.713218 -285.70936) (xy 388.78256 -285.707074) (xy 388.792132 -285.706376)
			(xy 388.809752 -285.698802) (xy 388.81685 -285.692342) (xy 389.21436 -285.294832) (xy 389.22176 -285.287992)
			(xy 389.240359 -285.280274) (xy 389.250428 -285.279846) (xy 390.972548 -285.279846) (xy 390.981441 -285.279514)
			(xy 390.998155 -285.273433) (xy 391.011771 -285.261991) (xy 391.01649 -285.254446) (xy 391.060432 -285.178246)
			(xy 391.0646 -285.170372) (xy 391.067709 -285.15284) (xy 391.064627 -285.135304) (xy 391.060432 -285.127446)
			(xy 391.04757 -285.104083) (xy 391.029324 -285.053973) (xy 391.020061 -285.001456) (xy 391.019538 -284.974792)
			(xy 391.02006 -284.949537) (xy 391.028373 -284.899715) (xy 391.044774 -284.851941) (xy 391.068815 -284.807518)
			(xy 391.099839 -284.767658) (xy 391.137001 -284.733448) (xy 391.179287 -284.705822) (xy 391.225543 -284.685532)
			(xy 391.274508 -284.673132) (xy 391.324846 -284.668961) (xy 391.375184 -284.673132) (xy 391.424149 -284.685532)
			(xy 391.470405 -284.705822) (xy 391.512691 -284.733448) (xy 391.549853 -284.767658) (xy 391.580877 -284.807518)
			(xy 391.604918 -284.851941) (xy 391.621319 -284.899715) (xy 391.629632 -284.949537) (xy 391.630154 -284.974792)
			(xy 391.629575 -285.001452) (xy 391.620322 -285.053963) (xy 391.602095 -285.104072) (xy 391.58926 -285.127446)
			(xy 391.585109 -285.13532) (xy 391.58203 -285.15284) (xy 391.585136 -285.170356) (xy 391.58926 -285.178246)
			(xy 391.633202 -285.254446) (xy 391.637982 -285.261939) (xy 391.651586 -285.273355) (xy 391.668265 -285.279455)
			(xy 391.677144 -285.279846) (xy 392.872722 -285.279846) (xy 392.881617 -285.279518) (xy 392.898338 -285.273443)
			(xy 392.911962 -285.262003) (xy 392.916664 -285.254446) (xy 392.960606 -285.178246) (xy 392.964775 -285.170372)
			(xy 392.967886 -285.15284) (xy 392.964803 -285.135303) (xy 392.960606 -285.127446) (xy 392.947745 -285.104083)
			(xy 392.929501 -285.053973) (xy 392.920239 -285.001456) (xy 392.919712 -284.974792) (xy 392.920234 -284.949537)
			(xy 392.928547 -284.899715) (xy 392.944948 -284.851941) (xy 392.968989 -284.807518) (xy 393.000013 -284.767658)
			(xy 393.037175 -284.733448) (xy 393.079461 -284.705822) (xy 393.125717 -284.685532) (xy 393.174682 -284.673132)
			(xy 393.22502 -284.668961) (xy 393.275358 -284.673132) (xy 393.324323 -284.685532) (xy 393.370579 -284.705822)
			(xy 393.412865 -284.733448) (xy 393.450027 -284.767658) (xy 393.481051 -284.807518) (xy 393.505092 -284.851941)
			(xy 393.521493 -284.899715) (xy 393.529806 -284.949537) (xy 393.530328 -284.974792) (xy 393.529749 -285.001452)
			(xy 393.520495 -285.053963) (xy 393.502266 -285.104071) (xy 393.489434 -285.127446) (xy 393.485285 -285.13532)
			(xy 393.482208 -285.15284) (xy 393.485312 -285.170355) (xy 393.489434 -285.178246) (xy 393.533376 -285.254446)
			(xy 393.53816 -285.261931) (xy 393.551767 -285.273327) (xy 393.568444 -285.279404) (xy 393.577318 -285.279846)
			(xy 393.822682 -285.279846) (xy 393.831572 -285.279508) (xy 393.848277 -285.27342) (xy 393.861884 -285.261975)
			(xy 393.866624 -285.254446) (xy 393.910566 -285.178246) (xy 393.914732 -285.170371) (xy 393.917839 -285.15284)
			(xy 393.914759 -285.135304) (xy 393.910566 -285.127446) (xy 393.897706 -285.104082) (xy 393.879465 -285.053972)
			(xy 393.870204 -285.001456) (xy 393.869672 -284.974792) (xy 393.870194 -284.949537) (xy 393.878507 -284.899715)
			(xy 393.894908 -284.851941) (xy 393.918949 -284.807518) (xy 393.949973 -284.767658) (xy 393.987135 -284.733448)
			(xy 394.029421 -284.705822) (xy 394.075677 -284.685532) (xy 394.124642 -284.673132) (xy 394.17498 -284.668961)
			(xy 394.225318 -284.673132) (xy 394.274283 -284.685532) (xy 394.320539 -284.705822) (xy 394.362825 -284.733448)
			(xy 394.399987 -284.767658) (xy 394.431011 -284.807518) (xy 394.455052 -284.851941) (xy 394.471453 -284.899715)
			(xy 394.479766 -284.949537) (xy 394.480288 -284.974792) (xy 394.479709 -285.001452) (xy 394.470457 -285.053964)
			(xy 394.452231 -285.104073) (xy 394.439394 -285.127446) (xy 394.435241 -285.135319) (xy 394.43216 -285.15284)
			(xy 394.435268 -285.170356) (xy 394.439394 -285.178246) (xy 394.483336 -285.254446) (xy 394.488118 -285.261935)
			(xy 394.501723 -285.273342) (xy 394.518401 -285.279432) (xy 394.527278 -285.279846) (xy 394.772642 -285.279846)
			(xy 394.781536 -285.279515) (xy 394.798251 -285.273435) (xy 394.811869 -285.261994) (xy 394.816584 -285.254446)
			(xy 394.860526 -285.178246) (xy 394.864694 -285.170372) (xy 394.867804 -285.15284) (xy 394.864722 -285.135304)
			(xy 394.860526 -285.127446) (xy 394.847664 -285.104083) (xy 394.829419 -285.053973) (xy 394.820156 -285.001456)
			(xy 394.819632 -284.974792) (xy 394.820154 -284.949537) (xy 394.828467 -284.899715) (xy 394.844868 -284.851941)
			(xy 394.868909 -284.807518) (xy 394.899933 -284.767658) (xy 394.937095 -284.733448) (xy 394.979381 -284.705822)
			(xy 395.025637 -284.685532) (xy 395.074602 -284.673132) (xy 395.12494 -284.668961) (xy 395.175278 -284.673132)
			(xy 395.224243 -284.685532) (xy 395.270499 -284.705822) (xy 395.312785 -284.733448) (xy 395.349947 -284.767658)
			(xy 395.380971 -284.807518) (xy 395.405012 -284.851941) (xy 395.421413 -284.899715) (xy 395.429726 -284.949537)
			(xy 395.430248 -284.974792) (xy 395.429669 -285.001452) (xy 395.420415 -285.053963) (xy 395.402188 -285.104071)
			(xy 395.389354 -285.127446) (xy 395.385203 -285.13532) (xy 395.382125 -285.15284) (xy 395.385231 -285.170356)
			(xy 395.389354 -285.178246) (xy 395.433296 -285.254446) (xy 395.438076 -285.261939) (xy 395.45168 -285.273357)
			(xy 395.468359 -285.279459) (xy 395.477238 -285.279846) (xy 395.722602 -285.279846) (xy 395.73149 -285.279505)
			(xy 395.74819 -285.273413) (xy 395.761792 -285.261966) (xy 395.766544 -285.254446) (xy 395.810486 -285.178246)
			(xy 395.81465 -285.170371) (xy 395.817756 -285.15284) (xy 395.814678 -285.135305) (xy 395.810486 -285.127446)
			(xy 395.797625 -285.104082) (xy 395.779383 -285.053973) (xy 395.770121 -285.001456) (xy 395.769592 -284.974792)
			(xy 395.770114 -284.949537) (xy 395.778427 -284.899715) (xy 395.794828 -284.851941) (xy 395.818869 -284.807518)
			(xy 395.849893 -284.767658) (xy 395.887055 -284.733448) (xy 395.929341 -284.705822) (xy 395.975597 -284.685532)
			(xy 396.024562 -284.673132) (xy 396.0749 -284.668961) (xy 396.125238 -284.673132) (xy 396.174203 -284.685532)
			(xy 396.220459 -284.705822) (xy 396.262745 -284.733448) (xy 396.299907 -284.767658) (xy 396.330931 -284.807518)
			(xy 396.354972 -284.851941) (xy 396.371373 -284.899715) (xy 396.379686 -284.949537) (xy 396.380208 -284.974792)
			(xy 396.379629 -285.001452) (xy 396.370374 -285.053963) (xy 396.352145 -285.10407) (xy 396.339314 -285.127446)
			(xy 396.335166 -285.135321) (xy 396.332091 -285.15284) (xy 396.335193 -285.170355) (xy 396.339314 -285.178246)
			(xy 396.383256 -285.254446) (xy 396.388039 -285.261933) (xy 396.401645 -285.273335) (xy 396.418323 -285.279417)
			(xy 396.427198 -285.279846) (xy 396.672562 -285.279846) (xy 396.681454 -285.279511) (xy 396.698164 -285.273428)
			(xy 396.711777 -285.261984) (xy 396.716504 -285.254446) (xy 396.760446 -285.178246) (xy 396.764613 -285.170372)
			(xy 396.767721 -285.15284) (xy 396.764641 -285.135304) (xy 396.760446 -285.127446) (xy 396.747587 -285.104082)
			(xy 396.729347 -285.053972) (xy 396.720086 -285.001455) (xy 396.719552 -284.974792) (xy 396.720074 -284.949537)
			(xy 396.728387 -284.899715) (xy 396.744788 -284.851941) (xy 396.768829 -284.807518) (xy 396.799853 -284.767658)
			(xy 396.837015 -284.733448) (xy 396.879301 -284.705822) (xy 396.925557 -284.685532) (xy 396.974522 -284.673132)
			(xy 397.02486 -284.668961) (xy 397.075198 -284.673132) (xy 397.124163 -284.685532) (xy 397.170419 -284.705822)
			(xy 397.212705 -284.733448) (xy 397.249867 -284.767658) (xy 397.280891 -284.807518) (xy 397.304932 -284.851941)
			(xy 397.321333 -284.899715) (xy 397.329646 -284.949537) (xy 397.330168 -284.974792) (xy 397.329589 -285.001452)
			(xy 397.320336 -285.053964) (xy 397.30211 -285.104072) (xy 397.289274 -285.127446) (xy 397.285122 -285.135319)
			(xy 397.282042 -285.15284) (xy 397.285149 -285.170356) (xy 397.289274 -285.178246) (xy 397.333216 -285.254446)
			(xy 397.337997 -285.261937) (xy 397.351602 -285.27335) (xy 397.36828 -285.279445) (xy 397.377158 -285.279846)
			(xy 397.622522 -285.279846) (xy 397.631417 -285.279518) (xy 397.648138 -285.273443) (xy 397.661762 -285.262003)
			(xy 397.666464 -285.254446) (xy 397.710406 -285.178246) (xy 397.714575 -285.170372) (xy 397.717686 -285.15284)
			(xy 397.714603 -285.135303) (xy 397.710406 -285.127446) (xy 397.697545 -285.104083) (xy 397.679301 -285.053973)
			(xy 397.670039 -285.001456) (xy 397.669512 -284.974792) (xy 397.670034 -284.949537) (xy 397.678347 -284.899715)
			(xy 397.694748 -284.851941) (xy 397.718789 -284.807518) (xy 397.749813 -284.767658) (xy 397.786975 -284.733448)
			(xy 397.829261 -284.705822) (xy 397.875517 -284.685532) (xy 397.924482 -284.673132) (xy 397.97482 -284.668961)
			(xy 398.025158 -284.673132) (xy 398.074123 -284.685532) (xy 398.120379 -284.705822) (xy 398.162665 -284.733448)
			(xy 398.199827 -284.767658) (xy 398.230851 -284.807518) (xy 398.254892 -284.851941) (xy 398.271293 -284.899715)
			(xy 398.279606 -284.949537) (xy 398.280128 -284.974792) (xy 398.279549 -285.001452) (xy 398.270295 -285.053963)
			(xy 398.252066 -285.104071) (xy 398.239234 -285.127446) (xy 398.235085 -285.13532) (xy 398.232008 -285.15284)
			(xy 398.235112 -285.170355) (xy 398.239234 -285.178246) (xy 398.283176 -285.254446) (xy 398.28796 -285.261931)
			(xy 398.301567 -285.273327) (xy 398.318244 -285.279404) (xy 398.327118 -285.279846) (xy 398.572736 -285.279846)
			(xy 398.58163 -285.279516) (xy 398.598347 -285.273438) (xy 398.611967 -285.261996) (xy 398.616678 -285.254446)
			(xy 398.66062 -285.178246) (xy 398.664788 -285.170372) (xy 398.667898 -285.15284) (xy 398.664816 -285.135303)
			(xy 398.66062 -285.127446) (xy 398.647758 -285.104083) (xy 398.629513 -285.053973) (xy 398.620251 -285.001456)
			(xy 398.619726 -284.974792) (xy 398.620248 -284.949537) (xy 398.628561 -284.899715) (xy 398.644962 -284.851941)
			(xy 398.669003 -284.807518) (xy 398.700027 -284.767658) (xy 398.737189 -284.733448) (xy 398.779475 -284.705822)
			(xy 398.825731 -284.685532) (xy 398.874696 -284.673132) (xy 398.925034 -284.668961) (xy 398.975372 -284.673132)
			(xy 399.024337 -284.685532) (xy 399.070593 -284.705822) (xy 399.112879 -284.733448) (xy 399.150041 -284.767658)
			(xy 399.181065 -284.807518) (xy 399.205106 -284.851941) (xy 399.221507 -284.899715) (xy 399.22982 -284.949537)
			(xy 399.230342 -284.974792) (xy 399.229763 -285.001452) (xy 399.220509 -285.053963) (xy 399.202282 -285.104071)
			(xy 399.189448 -285.127446) (xy 399.185298 -285.13532) (xy 399.18222 -285.15284) (xy 399.185325 -285.170356)
			(xy 399.189448 -285.178246) (xy 399.23339 -285.254446) (xy 399.23817 -285.26194) (xy 399.251773 -285.27336)
			(xy 399.268453 -285.279463) (xy 399.277332 -285.279846) (xy 399.522696 -285.279846) (xy 399.531585 -285.279506)
			(xy 399.548286 -285.273415) (xy 399.561889 -285.261969) (xy 399.566638 -285.254446) (xy 399.61058 -285.178246)
			(xy 399.614745 -285.170371) (xy 399.617851 -285.15284) (xy 399.614772 -285.135305) (xy 399.61058 -285.127446)
			(xy 399.59772 -285.104082) (xy 399.579477 -285.053972) (xy 399.570216 -285.001456) (xy 399.569686 -284.974792)
			(xy 399.570208 -284.949537) (xy 399.578521 -284.899715) (xy 399.594922 -284.851941) (xy 399.618963 -284.807518)
			(xy 399.649987 -284.767658) (xy 399.687149 -284.733448) (xy 399.729435 -284.705822) (xy 399.775691 -284.685532)
			(xy 399.824656 -284.673132) (xy 399.874994 -284.668961) (xy 399.925332 -284.673132) (xy 399.974297 -284.685532)
			(xy 400.020553 -284.705822) (xy 400.062839 -284.733448) (xy 400.100001 -284.767658) (xy 400.131025 -284.807518)
			(xy 400.155066 -284.851941) (xy 400.171467 -284.899715) (xy 400.17978 -284.949537) (xy 400.180302 -284.974792)
			(xy 400.179723 -285.001452) (xy 400.170468 -285.053963) (xy 400.152238 -285.104069) (xy 400.139408 -285.127446)
			(xy 400.135254 -285.135319) (xy 400.132172 -285.15284) (xy 400.135281 -285.170357) (xy 400.139408 -285.178246)
			(xy 400.18335 -285.254446) (xy 400.188132 -285.261934) (xy 400.201739 -285.273337) (xy 400.218416 -285.279422)
			(xy 400.227292 -285.279846) (xy 400.472656 -285.279846) (xy 400.481548 -285.279512) (xy 400.49826 -285.27343)
			(xy 400.511874 -285.261987) (xy 400.516598 -285.254446) (xy 400.56054 -285.178246) (xy 400.564707 -285.170372)
			(xy 400.567816 -285.15284) (xy 400.564735 -285.135304) (xy 400.56054 -285.127446) (xy 400.547681 -285.104082)
			(xy 400.529441 -285.053972) (xy 400.520181 -285.001455) (xy 400.519646 -284.974792) (xy 400.520168 -284.949537)
			(xy 400.528481 -284.899715) (xy 400.544882 -284.851941) (xy 400.568923 -284.807518) (xy 400.599947 -284.767658)
			(xy 400.637109 -284.733448) (xy 400.679395 -284.705822) (xy 400.725651 -284.685532) (xy 400.774616 -284.673132)
			(xy 400.824954 -284.668961) (xy 400.875292 -284.673132) (xy 400.924257 -284.685532) (xy 400.970513 -284.705822)
			(xy 401.012799 -284.733448) (xy 401.049961 -284.767658) (xy 401.080985 -284.807518) (xy 401.105026 -284.851941)
			(xy 401.121427 -284.899715) (xy 401.12974 -284.949537) (xy 401.130262 -284.974792) (xy 401.129683 -285.001452)
			(xy 401.12043 -285.053964) (xy 401.102203 -285.104072) (xy 401.089368 -285.127446) (xy 401.085216 -285.135319)
			(xy 401.082137 -285.15284) (xy 401.085244 -285.170356) (xy 401.089368 -285.178246) (xy 401.13331 -285.254446)
			(xy 401.138091 -285.261938) (xy 401.151695 -285.273352) (xy 401.168374 -285.27945) (xy 401.177252 -285.279846)
			(xy 401.422616 -285.279846) (xy 401.431512 -285.279519) (xy 401.448234 -285.273445) (xy 401.461859 -285.262005)
			(xy 401.466558 -285.254446) (xy 401.5105 -285.178246) (xy 401.51467 -285.170372) (xy 401.517781 -285.15284)
			(xy 401.514697 -285.135303) (xy 401.5105 -285.127446) (xy 401.497639 -285.104083) (xy 401.479395 -285.053973)
			(xy 401.470133 -285.001456) (xy 401.469606 -284.974792) (xy 401.470128 -284.949537) (xy 401.478441 -284.899715)
			(xy 401.494842 -284.851941) (xy 401.518883 -284.807518) (xy 401.549907 -284.767658) (xy 401.587069 -284.733448)
			(xy 401.629355 -284.705822) (xy 401.675611 -284.685532) (xy 401.724576 -284.673132) (xy 401.774914 -284.668961)
			(xy 401.825252 -284.673132) (xy 401.874217 -284.685532) (xy 401.920473 -284.705822) (xy 401.962759 -284.733448)
			(xy 401.999921 -284.767658) (xy 402.030945 -284.807518) (xy 402.054986 -284.851941) (xy 402.071387 -284.899715)
			(xy 402.0797 -284.949537) (xy 402.080222 -284.974792) (xy 402.079643 -285.001452) (xy 402.070389 -285.053963)
			(xy 402.05216 -285.10407) (xy 402.039328 -285.127446) (xy 402.035179 -285.13532) (xy 402.032103 -285.15284)
			(xy 402.035206 -285.170355) (xy 402.039328 -285.178246) (xy 402.08327 -285.254446) (xy 402.088054 -285.261931)
			(xy 402.101661 -285.273329) (xy 402.118338 -285.279408) (xy 402.127212 -285.279846) (xy 402.372576 -285.279846)
			(xy 402.381467 -285.279509) (xy 402.398173 -285.273422) (xy 402.411782 -285.261978) (xy 402.416518 -285.254446)
			(xy 402.46046 -285.178246) (xy 402.464626 -285.170371) (xy 402.467733 -285.15284) (xy 402.464654 -285.135304)
			(xy 402.46046 -285.127446) (xy 402.4476 -285.104082) (xy 402.429359 -285.053972) (xy 402.420099 -285.001455)
			(xy 402.419566 -284.974792) (xy 402.420088 -284.949537) (xy 402.428401 -284.899715) (xy 402.444802 -284.851941)
			(xy 402.468843 -284.807518) (xy 402.499867 -284.767658) (xy 402.537029 -284.733448) (xy 402.579315 -284.705822)
			(xy 402.625571 -284.685532) (xy 402.674536 -284.673132) (xy 402.724874 -284.668961) (xy 402.775212 -284.673132)
			(xy 402.824177 -284.685532) (xy 402.870433 -284.705822) (xy 402.912719 -284.733448) (xy 402.949881 -284.767658)
			(xy 402.980905 -284.807518) (xy 403.004946 -284.851941) (xy 403.021347 -284.899715) (xy 403.02966 -284.949537)
			(xy 403.030182 -284.974792) (xy 403.029603 -285.001452) (xy 403.02035 -285.053964) (xy 403.002125 -285.104073)
			(xy 402.989288 -285.127446) (xy 402.985135 -285.135319) (xy 402.982055 -285.15284) (xy 402.985163 -285.170356)
			(xy 402.989288 -285.178246) (xy 403.03323 -285.254446) (xy 403.038012 -285.261936) (xy 403.051617 -285.273345)
			(xy 403.068295 -285.279436) (xy 403.077172 -285.279846) (xy 403.322536 -285.279846) (xy 403.33143 -285.279516)
			(xy 403.348147 -285.273438) (xy 403.361767 -285.261996) (xy 403.366478 -285.254446) (xy 403.41042 -285.178246)
			(xy 403.414588 -285.170372) (xy 403.417698 -285.15284) (xy 403.414616 -285.135303) (xy 403.41042 -285.127446)
			(xy 403.397558 -285.104083) (xy 403.379313 -285.053973) (xy 403.370051 -285.001456) (xy 403.369526 -284.974792)
			(xy 403.370048 -284.949537) (xy 403.378361 -284.899715) (xy 403.394762 -284.851941) (xy 403.418803 -284.807518)
			(xy 403.449827 -284.767658) (xy 403.486989 -284.733448) (xy 403.529275 -284.705822) (xy 403.575531 -284.685532)
			(xy 403.624496 -284.673132) (xy 403.674834 -284.668961) (xy 403.725172 -284.673132) (xy 403.774137 -284.685532)
			(xy 403.820393 -284.705822) (xy 403.862679 -284.733448) (xy 403.899841 -284.767658) (xy 403.930865 -284.807518)
			(xy 403.954906 -284.851941) (xy 403.971307 -284.899715) (xy 403.97962 -284.949537) (xy 403.980142 -284.974792)
			(xy 403.979563 -285.001452) (xy 403.970309 -285.053963) (xy 403.952082 -285.104071) (xy 403.939248 -285.127446)
			(xy 403.935098 -285.13532) (xy 403.93202 -285.15284) (xy 403.935125 -285.170356) (xy 403.939248 -285.178246)
			(xy 403.98319 -285.254446) (xy 403.98797 -285.26194) (xy 404.001573 -285.27336) (xy 404.018253 -285.279463)
			(xy 404.027132 -285.279846) (xy 404.272496 -285.279846) (xy 404.281385 -285.279506) (xy 404.298086 -285.273415)
			(xy 404.311689 -285.261969) (xy 404.316438 -285.254446) (xy 404.36038 -285.178246) (xy 404.364545 -285.170371)
			(xy 404.367651 -285.15284) (xy 404.364572 -285.135305) (xy 404.36038 -285.127446) (xy 404.34752 -285.104082)
			(xy 404.329277 -285.053972) (xy 404.320016 -285.001456) (xy 404.319486 -284.974792) (xy 404.320008 -284.949537)
			(xy 404.328321 -284.899715) (xy 404.344722 -284.851941) (xy 404.368763 -284.807518) (xy 404.399787 -284.767658)
			(xy 404.436949 -284.733448) (xy 404.479235 -284.705822) (xy 404.525491 -284.685532) (xy 404.574456 -284.673132)
			(xy 404.624794 -284.668961) (xy 404.675132 -284.673132) (xy 404.724097 -284.685532) (xy 404.770353 -284.705822)
			(xy 404.812639 -284.733448) (xy 404.849801 -284.767658) (xy 404.880825 -284.807518) (xy 404.904866 -284.851941)
			(xy 404.921267 -284.899715) (xy 404.92958 -284.949537) (xy 404.930102 -284.974792) (xy 404.929523 -285.001452)
			(xy 404.920268 -285.053963) (xy 404.902038 -285.104069) (xy 404.889208 -285.127446) (xy 404.885054 -285.135319)
			(xy 404.881972 -285.15284) (xy 404.885081 -285.170357) (xy 404.889208 -285.178246) (xy 404.93315 -285.254446)
			(xy 404.937932 -285.261934) (xy 404.951539 -285.273337) (xy 404.968216 -285.279422) (xy 404.977092 -285.279846)
			(xy 405.22271 -285.279846) (xy 405.231607 -285.27952) (xy 405.24833 -285.273448) (xy 405.261957 -285.262008)
			(xy 405.266652 -285.254446) (xy 405.310594 -285.178246) (xy 405.314764 -285.170373) (xy 405.317876 -285.15284)
			(xy 405.314792 -285.135303) (xy 405.310594 -285.127446) (xy 405.297733 -285.104083) (xy 405.27949 -285.053973)
			(xy 405.270228 -285.001456) (xy 405.2697 -284.974792) (xy 405.270222 -284.949537) (xy 405.278535 -284.899715)
			(xy 405.294936 -284.851941) (xy 405.318977 -284.807518) (xy 405.350001 -284.767658) (xy 405.387163 -284.733448)
			(xy 405.429449 -284.705822) (xy 405.475705 -284.685532) (xy 405.52467 -284.673132) (xy 405.575008 -284.668961)
			(xy 405.625346 -284.673132) (xy 405.674311 -284.685532) (xy 405.720567 -284.705822) (xy 405.762853 -284.733448)
			(xy 405.800015 -284.767658) (xy 405.831039 -284.807518) (xy 405.85508 -284.851941) (xy 405.871481 -284.899715)
			(xy 405.879794 -284.949537) (xy 405.880316 -284.974792) (xy 405.879737 -285.001452) (xy 405.870482 -285.053963)
			(xy 405.852253 -285.10407) (xy 405.839422 -285.127446) (xy 405.835273 -285.13532) (xy 405.832197 -285.15284)
			(xy 405.835301 -285.170355) (xy 405.839422 -285.178246) (xy 405.883364 -285.254446) (xy 405.888147 -285.261932)
			(xy 405.901754 -285.273332) (xy 405.918431 -285.279412) (xy 405.927306 -285.279846) (xy 406.17267 -285.279846)
			(xy 406.181561 -285.27951) (xy 406.198269 -285.273425) (xy 406.21188 -285.261981) (xy 406.216612 -285.254446)
			(xy 406.260554 -285.178246) (xy 406.26472 -285.170372) (xy 406.267828 -285.15284) (xy 406.264748 -285.135304)
			(xy 406.260554 -285.127446) (xy 406.247695 -285.104082) (xy 406.229454 -285.053972) (xy 406.220193 -285.001455)
			(xy 406.21966 -284.974792) (xy 406.220182 -284.949537) (xy 406.228495 -284.899715) (xy 406.244896 -284.851941)
			(xy 406.268937 -284.807518) (xy 406.299961 -284.767658) (xy 406.337123 -284.733448) (xy 406.379409 -284.705822)
			(xy 406.425665 -284.685532) (xy 406.47463 -284.673132) (xy 406.524968 -284.668961) (xy 406.575306 -284.673132)
			(xy 406.624271 -284.685532) (xy 406.670527 -284.705822) (xy 406.712813 -284.733448) (xy 406.749975 -284.767658)
			(xy 406.780999 -284.807518) (xy 406.80504 -284.851941) (xy 406.821441 -284.899715) (xy 406.829754 -284.949537)
			(xy 406.830276 -284.974792) (xy 406.829697 -285.001452) (xy 406.820444 -285.053964) (xy 406.802218 -285.104073)
			(xy 406.789382 -285.127446) (xy 406.78523 -285.135319) (xy 406.78215 -285.15284) (xy 406.785257 -285.170356)
			(xy 406.789382 -285.178246) (xy 406.833324 -285.254446) (xy 406.838105 -285.261937) (xy 406.85171 -285.273347)
			(xy 406.868389 -285.27944) (xy 406.877266 -285.279846) (xy 408.07259 -285.279846) (xy 408.081479 -285.279507)
			(xy 408.098183 -285.273417) (xy 408.111787 -285.261972) (xy 408.116532 -285.254446) (xy 408.160474 -285.178246)
			(xy 408.164639 -285.170371) (xy 408.167746 -285.15284) (xy 408.164667 -285.135304) (xy 408.160474 -285.127446)
			(xy 408.147614 -285.104082) (xy 408.129372 -285.053972) (xy 408.120111 -285.001456) (xy 408.11958 -284.974792)
			(xy 408.120102 -284.949537) (xy 408.128415 -284.899715) (xy 408.144816 -284.851941) (xy 408.168857 -284.807518)
			(xy 408.199881 -284.767658) (xy 408.237043 -284.733448) (xy 408.279329 -284.705822) (xy 408.325585 -284.685532)
			(xy 408.37455 -284.673132) (xy 408.424888 -284.668961) (xy 408.475226 -284.673132) (xy 408.524191 -284.685532)
			(xy 408.570447 -284.705822) (xy 408.612733 -284.733448) (xy 408.649895 -284.767658) (xy 408.680919 -284.807518)
			(xy 408.70496 -284.851941) (xy 408.721361 -284.899715) (xy 408.729674 -284.949537) (xy 408.730196 -284.974792)
			(xy 408.729617 -285.001452) (xy 408.720362 -285.053963) (xy 408.702132 -285.104069) (xy 408.689302 -285.127446)
			(xy 408.685148 -285.135319) (xy 408.682067 -285.15284) (xy 408.685176 -285.170356) (xy 408.689302 -285.178246)
			(xy 408.733244 -285.254446) (xy 408.738026 -285.261934) (xy 408.751632 -285.27334) (xy 408.76831 -285.279426)
			(xy 408.777186 -285.279846) (xy 409.02255 -285.279846) (xy 409.031443 -285.279513) (xy 409.048156 -285.273432)
			(xy 409.061772 -285.26199) (xy 409.066492 -285.254446) (xy 409.110434 -285.178246) (xy 409.114601 -285.170372)
			(xy 409.11771 -285.15284) (xy 409.114629 -285.135304) (xy 409.110434 -285.127446) (xy 409.097575 -285.104082)
			(xy 409.079336 -285.053972) (xy 409.070076 -285.001455) (xy 409.06954 -284.974792) (xy 409.070062 -284.949537)
			(xy 409.078375 -284.899715) (xy 409.094776 -284.851941) (xy 409.118817 -284.807518) (xy 409.149841 -284.767658)
			(xy 409.187003 -284.733448) (xy 409.229289 -284.705822) (xy 409.275545 -284.685532) (xy 409.32451 -284.673132)
			(xy 409.374848 -284.668961) (xy 409.425186 -284.673132) (xy 409.474151 -284.685532) (xy 409.520407 -284.705822)
			(xy 409.562693 -284.733448) (xy 409.599855 -284.767658) (xy 409.630879 -284.807518) (xy 409.65492 -284.851941)
			(xy 409.671321 -284.899715) (xy 409.679634 -284.949537) (xy 409.680156 -284.974792) (xy 409.679577 -285.001452)
			(xy 409.670324 -285.053964) (xy 409.652097 -285.104072) (xy 409.639262 -285.127446) (xy 409.635111 -285.13532)
			(xy 409.632032 -285.15284) (xy 409.635138 -285.170356) (xy 409.639262 -285.178246) (xy 409.683204 -285.254446)
			(xy 409.687984 -285.261939) (xy 409.701589 -285.273354) (xy 409.718268 -285.279454) (xy 409.727146 -285.279846)
			(xy 409.97251 -285.279846) (xy 409.981407 -285.27952) (xy 409.99813 -285.273448) (xy 410.011757 -285.262008)
			(xy 410.016452 -285.254446) (xy 410.060394 -285.178246) (xy 410.064564 -285.170373) (xy 410.067676 -285.15284)
			(xy 410.064592 -285.135303) (xy 410.060394 -285.127446) (xy 410.047533 -285.104083) (xy 410.02929 -285.053973)
			(xy 410.020028 -285.001456) (xy 410.0195 -284.974792) (xy 410.020022 -284.949537) (xy 410.028335 -284.899715)
			(xy 410.044736 -284.851941) (xy 410.068777 -284.807518) (xy 410.099801 -284.767658) (xy 410.136963 -284.733448)
			(xy 410.179249 -284.705822) (xy 410.225505 -284.685532) (xy 410.27447 -284.673132) (xy 410.324808 -284.668961)
			(xy 410.375146 -284.673132) (xy 410.424111 -284.685532) (xy 410.470367 -284.705822) (xy 410.512653 -284.733448)
			(xy 410.549815 -284.767658) (xy 410.580839 -284.807518) (xy 410.60488 -284.851941) (xy 410.621281 -284.899715)
			(xy 410.629594 -284.949537) (xy 410.630116 -284.974792) (xy 410.629537 -285.001452) (xy 410.620282 -285.053963)
			(xy 410.602053 -285.10407) (xy 410.589222 -285.127446) (xy 410.585073 -285.13532) (xy 410.581997 -285.15284)
			(xy 410.585101 -285.170355) (xy 410.589222 -285.178246) (xy 410.633164 -285.254446) (xy 410.637947 -285.261932)
			(xy 410.651554 -285.273332) (xy 410.668231 -285.279412) (xy 410.677106 -285.279846) (xy 410.922724 -285.279846)
			(xy 410.931619 -285.279518) (xy 410.948339 -285.273442) (xy 410.961962 -285.262002) (xy 410.966666 -285.254446)
			(xy 411.010608 -285.178246) (xy 411.014777 -285.170372) (xy 411.017888 -285.15284) (xy 411.014805 -285.135303)
			(xy 411.010608 -285.127446) (xy 410.997747 -285.104083) (xy 410.979502 -285.053973) (xy 410.97024 -285.001456)
			(xy 410.969714 -284.974792) (xy 410.970236 -284.949537) (xy 410.978549 -284.899715) (xy 410.99495 -284.851941)
			(xy 411.018991 -284.807518) (xy 411.050015 -284.767658) (xy 411.087177 -284.733448) (xy 411.129463 -284.705822)
			(xy 411.175719 -284.685532) (xy 411.224684 -284.673132) (xy 411.275022 -284.668961) (xy 411.32536 -284.673132)
			(xy 411.374325 -284.685532) (xy 411.420581 -284.705822) (xy 411.462867 -284.733448) (xy 411.500029 -284.767658)
			(xy 411.531053 -284.807518) (xy 411.555094 -284.851941) (xy 411.571495 -284.899715) (xy 411.579808 -284.949537)
			(xy 411.58033 -284.974792) (xy 411.579751 -285.001452) (xy 411.570497 -285.053963) (xy 411.552269 -285.104071)
			(xy 411.539436 -285.127446) (xy 411.535286 -285.13532) (xy 411.53221 -285.15284) (xy 411.535314 -285.170355)
			(xy 411.539436 -285.178246) (xy 411.583378 -285.254446) (xy 411.588162 -285.26193) (xy 411.601769 -285.273326)
			(xy 411.618446 -285.279402) (xy 411.62732 -285.279846) (xy 411.872684 -285.279846) (xy 411.881574 -285.279508)
			(xy 411.898279 -285.273419) (xy 411.911885 -285.261975) (xy 411.916626 -285.254446) (xy 411.960568 -285.178246)
			(xy 411.964733 -285.170371) (xy 411.96784 -285.15284) (xy 411.964761 -285.135304) (xy 411.960568 -285.127446)
			(xy 411.947708 -285.104082) (xy 411.929466 -285.053972) (xy 411.920205 -285.001456) (xy 411.919674 -284.974792)
			(xy 411.920196 -284.949537) (xy 411.928509 -284.899715) (xy 411.94491 -284.851941) (xy 411.968951 -284.807518)
			(xy 411.999975 -284.767658) (xy 412.037137 -284.733448) (xy 412.079423 -284.705822) (xy 412.125679 -284.685532)
			(xy 412.174644 -284.673132) (xy 412.224982 -284.668961) (xy 412.27532 -284.673132) (xy 412.324285 -284.685532)
			(xy 412.370541 -284.705822) (xy 412.412827 -284.733448) (xy 412.449989 -284.767658) (xy 412.481013 -284.807518)
			(xy 412.505054 -284.851941) (xy 412.521455 -284.899715) (xy 412.529768 -284.949537) (xy 412.53029 -284.974792)
			(xy 412.529711 -285.001452) (xy 412.520459 -285.053964) (xy 412.502234 -285.104073) (xy 412.489396 -285.127446)
			(xy 412.485243 -285.135319) (xy 412.482162 -285.15284) (xy 412.48527 -285.170356) (xy 412.489396 -285.178246)
			(xy 412.533338 -285.254446) (xy 412.53812 -285.261935) (xy 412.551726 -285.273342) (xy 412.568404 -285.27943)
			(xy 412.57728 -285.279846) (xy 412.822644 -285.279846) (xy 412.831538 -285.279514) (xy 412.848252 -285.273435)
			(xy 412.86187 -285.261993) (xy 412.866586 -285.254446) (xy 412.910528 -285.178246) (xy 412.914696 -285.170372)
			(xy 412.917805 -285.15284) (xy 412.914723 -285.135304) (xy 412.910528 -285.127446) (xy 412.897666 -285.104083)
			(xy 412.87942 -285.053973) (xy 412.870158 -285.001456) (xy 412.869634 -284.974792) (xy 412.870156 -284.949537)
			(xy 412.878469 -284.899715) (xy 412.89487 -284.851941) (xy 412.918911 -284.807518) (xy 412.949935 -284.767658)
			(xy 412.987097 -284.733448) (xy 413.029383 -284.705822) (xy 413.075639 -284.685532) (xy 413.124604 -284.673132)
			(xy 413.174942 -284.668961) (xy 413.22528 -284.673132) (xy 413.274245 -284.685532) (xy 413.320501 -284.705822)
			(xy 413.362787 -284.733448) (xy 413.399949 -284.767658) (xy 413.430973 -284.807518) (xy 413.455014 -284.851941)
			(xy 413.471415 -284.899715) (xy 413.479728 -284.949537) (xy 413.48025 -284.974792) (xy 413.479671 -285.001452)
			(xy 413.470417 -285.053963) (xy 413.45219 -285.104072) (xy 413.439356 -285.127446) (xy 413.435205 -285.13532)
			(xy 413.432127 -285.15284) (xy 413.435233 -285.170356) (xy 413.439356 -285.178246) (xy 413.483298 -285.254446)
			(xy 413.488078 -285.261939) (xy 413.501682 -285.273357) (xy 413.518361 -285.279458) (xy 413.52724 -285.279846)
			(xy 413.772604 -285.279846) (xy 413.781501 -285.279521) (xy 413.798226 -285.27345) (xy 413.811855 -285.262011)
			(xy 413.816546 -285.254446) (xy 413.860488 -285.178246) (xy 413.864652 -285.170371) (xy 413.867758 -285.15284)
			(xy 413.86468 -285.135305) (xy 413.860488 -285.127446) (xy 413.847627 -285.104082) (xy 413.829384 -285.053973)
			(xy 413.820123 -285.001456) (xy 413.819594 -284.974792) (xy 413.820116 -284.949537) (xy 413.828429 -284.899715)
			(xy 413.84483 -284.851941) (xy 413.868871 -284.807518) (xy 413.899895 -284.767658) (xy 413.937057 -284.733448)
			(xy 413.979343 -284.705822) (xy 414.025599 -284.685532) (xy 414.074564 -284.673132) (xy 414.124902 -284.668961)
			(xy 414.17524 -284.673132) (xy 414.224205 -284.685532) (xy 414.270461 -284.705822) (xy 414.312747 -284.733448)
			(xy 414.349909 -284.767658) (xy 414.380933 -284.807518) (xy 414.404974 -284.851941) (xy 414.421375 -284.899715)
			(xy 414.429688 -284.949537) (xy 414.43021 -284.974792) (xy 414.429631 -285.001452) (xy 414.420376 -285.053963)
			(xy 414.402147 -285.10407) (xy 414.389316 -285.127446) (xy 414.385168 -285.13532) (xy 414.382092 -285.15284)
			(xy 414.385195 -285.170355) (xy 414.389316 -285.178246) (xy 414.433258 -285.254446) (xy 414.438041 -285.261933)
			(xy 414.451648 -285.273334) (xy 414.468325 -285.279416) (xy 414.4772 -285.279846) (xy 414.722564 -285.279846)
			(xy 414.731456 -285.279511) (xy 414.748166 -285.273427) (xy 414.761777 -285.261984) (xy 414.766506 -285.254446)
			(xy 414.810448 -285.178246) (xy 414.814615 -285.170372) (xy 414.817723 -285.15284) (xy 414.814642 -285.135304)
			(xy 414.810448 -285.127446) (xy 414.797589 -285.104082) (xy 414.779348 -285.053972) (xy 414.770088 -285.001455)
			(xy 414.769554 -284.974792) (xy 414.770076 -284.949537) (xy 414.778389 -284.899715) (xy 414.79479 -284.851941)
			(xy 414.818831 -284.807518) (xy 414.849855 -284.767658) (xy 414.887017 -284.733448) (xy 414.929303 -284.705822)
			(xy 414.975559 -284.685532) (xy 415.024524 -284.673132) (xy 415.074862 -284.668961) (xy 415.1252 -284.673132)
			(xy 415.174165 -284.685532) (xy 415.220421 -284.705822) (xy 415.262707 -284.733448) (xy 415.299869 -284.767658)
			(xy 415.330893 -284.807518) (xy 415.354934 -284.851941) (xy 415.371335 -284.899715) (xy 415.379648 -284.949537)
			(xy 415.38017 -284.974792) (xy 415.379591 -285.001452) (xy 415.370338 -285.053964) (xy 415.352112 -285.104072)
			(xy 415.339276 -285.127446) (xy 415.335124 -285.135319) (xy 415.332045 -285.15284) (xy 415.335152 -285.170356)
			(xy 415.339276 -285.178246) (xy 415.383218 -285.254446) (xy 415.387999 -285.261937) (xy 415.401604 -285.273349)
			(xy 415.418282 -285.279444) (xy 415.42716 -285.279846) (xy 415.672524 -285.279846) (xy 415.681419 -285.279518)
			(xy 415.698139 -285.273442) (xy 415.711762 -285.262002) (xy 415.716466 -285.254446) (xy 415.760408 -285.178246)
			(xy 415.764577 -285.170372) (xy 415.767688 -285.15284) (xy 415.764605 -285.135303) (xy 415.760408 -285.127446)
			(xy 415.747547 -285.104083) (xy 415.729302 -285.053973) (xy 415.72004 -285.001456) (xy 415.719514 -284.974792)
			(xy 415.720036 -284.949537) (xy 415.728349 -284.899715) (xy 415.74475 -284.851941) (xy 415.768791 -284.807518)
			(xy 415.799815 -284.767658) (xy 415.836977 -284.733448) (xy 415.879263 -284.705822) (xy 415.925519 -284.685532)
			(xy 415.974484 -284.673132) (xy 416.024822 -284.668961) (xy 416.07516 -284.673132) (xy 416.124125 -284.685532)
			(xy 416.170381 -284.705822) (xy 416.212667 -284.733448) (xy 416.249829 -284.767658) (xy 416.280853 -284.807518)
			(xy 416.304894 -284.851941) (xy 416.321295 -284.899715) (xy 416.329608 -284.949537) (xy 416.33013 -284.974792)
			(xy 416.329551 -285.001452) (xy 416.320297 -285.053963) (xy 416.302069 -285.104071) (xy 416.289236 -285.127446)
			(xy 416.285086 -285.13532) (xy 416.28201 -285.15284) (xy 416.285114 -285.170355) (xy 416.289236 -285.178246)
			(xy 416.333178 -285.254446) (xy 416.337962 -285.26193) (xy 416.351569 -285.273326) (xy 416.368246 -285.279402)
			(xy 416.37712 -285.279846) (xy 416.622484 -285.279846) (xy 416.631374 -285.279508) (xy 416.648079 -285.273419)
			(xy 416.661685 -285.261975) (xy 416.666426 -285.254446) (xy 416.710368 -285.178246) (xy 416.714533 -285.170371)
			(xy 416.71764 -285.15284) (xy 416.714561 -285.135304) (xy 416.710368 -285.127446) (xy 416.697508 -285.104082)
			(xy 416.679266 -285.053972) (xy 416.670005 -285.001456) (xy 416.669474 -284.974792) (xy 416.669996 -284.949537)
			(xy 416.678309 -284.899715) (xy 416.69471 -284.851941) (xy 416.718751 -284.807518) (xy 416.749775 -284.767658)
			(xy 416.786937 -284.733448) (xy 416.829223 -284.705822) (xy 416.875479 -284.685532) (xy 416.924444 -284.673132)
			(xy 416.974782 -284.668961) (xy 417.02512 -284.673132) (xy 417.074085 -284.685532) (xy 417.120341 -284.705822)
			(xy 417.162627 -284.733448) (xy 417.199789 -284.767658) (xy 417.230813 -284.807518) (xy 417.254854 -284.851941)
			(xy 417.271255 -284.899715) (xy 417.279568 -284.949537) (xy 417.28009 -284.974792) (xy 417.279511 -285.001452)
			(xy 417.270259 -285.053964) (xy 417.252034 -285.104073) (xy 417.239196 -285.127446) (xy 417.235043 -285.135319)
			(xy 417.231962 -285.15284) (xy 417.23507 -285.170356) (xy 417.239196 -285.178246) (xy 417.283138 -285.254446)
			(xy 417.28792 -285.261935) (xy 417.301526 -285.273342) (xy 417.318204 -285.27943) (xy 417.32708 -285.279846)
			(xy 417.572698 -285.279846) (xy 417.581587 -285.279506) (xy 417.598288 -285.273414) (xy 417.61189 -285.261968)
			(xy 417.61664 -285.254446) (xy 417.660582 -285.178246) (xy 417.664746 -285.170371) (xy 417.667853 -285.15284)
			(xy 417.664774 -285.135305) (xy 417.660582 -285.127446) (xy 417.647722 -285.104082) (xy 417.629479 -285.053972)
			(xy 417.620218 -285.001456) (xy 417.619688 -284.974792) (xy 417.62021 -284.949537) (xy 417.628523 -284.899715)
			(xy 417.644924 -284.851941) (xy 417.668965 -284.807518) (xy 417.699989 -284.767658) (xy 417.737151 -284.733448)
			(xy 417.779437 -284.705822) (xy 417.825693 -284.685532) (xy 417.874658 -284.673132) (xy 417.924996 -284.668961)
			(xy 417.975334 -284.673132) (xy 418.024299 -284.685532) (xy 418.070555 -284.705822) (xy 418.112841 -284.733448)
			(xy 418.150003 -284.767658) (xy 418.181027 -284.807518) (xy 418.205068 -284.851941) (xy 418.221469 -284.899715)
			(xy 418.229782 -284.949537) (xy 418.230304 -284.974792) (xy 418.229725 -285.001452) (xy 418.22047 -285.053963)
			(xy 418.20224 -285.10407) (xy 418.18941 -285.127446) (xy 418.185262 -285.135321) (xy 418.182187 -285.15284)
			(xy 418.18529 -285.170355) (xy 418.18941 -285.178246) (xy 418.233352 -285.254446) (xy 418.238134 -285.261934)
			(xy 418.251741 -285.273337) (xy 418.268418 -285.279421) (xy 418.277294 -285.279846) (xy 418.522658 -285.279846)
			(xy 418.53155 -285.279512) (xy 418.548262 -285.273429) (xy 418.561875 -285.261986) (xy 418.5666 -285.254446)
			(xy 418.610542 -285.178246) (xy 418.614709 -285.170372) (xy 418.617818 -285.15284) (xy 418.614737 -285.135304)
			(xy 418.610542 -285.127446) (xy 418.597683 -285.104082) (xy 418.579443 -285.053972) (xy 418.570183 -285.001455)
			(xy 418.569648 -284.974792) (xy 418.57017 -284.949537) (xy 418.578483 -284.899715) (xy 418.594884 -284.851941)
			(xy 418.618925 -284.807518) (xy 418.649949 -284.767658) (xy 418.687111 -284.733448) (xy 418.729397 -284.705822)
			(xy 418.775653 -284.685532) (xy 418.824618 -284.673132) (xy 418.874956 -284.668961) (xy 418.925294 -284.673132)
			(xy 418.974259 -284.685532) (xy 419.020515 -284.705822) (xy 419.062801 -284.733448) (xy 419.099963 -284.767658)
			(xy 419.130987 -284.807518) (xy 419.155028 -284.851941) (xy 419.171429 -284.899715) (xy 419.179742 -284.949537)
			(xy 419.180264 -284.974792) (xy 419.179685 -285.001452) (xy 419.170432 -285.053964) (xy 419.152205 -285.104072)
			(xy 419.13937 -285.127446) (xy 419.135218 -285.135319) (xy 419.132139 -285.15284) (xy 419.135246 -285.170356)
			(xy 419.13937 -285.178246) (xy 419.183312 -285.254446) (xy 419.188093 -285.261938) (xy 419.201697 -285.273351)
			(xy 419.218376 -285.279448) (xy 419.227254 -285.279846) (xy 421.372538 -285.279846) (xy 421.381432 -285.279515)
			(xy 421.398149 -285.273437) (xy 421.411768 -285.261995) (xy 421.41648 -285.254446) (xy 421.460422 -285.178246)
			(xy 421.46459 -285.170372) (xy 421.4677 -285.15284) (xy 421.464618 -285.135304) (xy 421.460422 -285.127446)
			(xy 421.44756 -285.104083) (xy 421.429315 -285.053973) (xy 421.420052 -285.001456) (xy 421.419528 -284.974792)
			(xy 421.419975 -284.9508) (xy 421.427483 -284.903408) (xy 421.442312 -284.857774) (xy 421.464099 -284.815021)
			(xy 421.492305 -284.776204) (xy 421.526237 -284.742277) (xy 421.565059 -284.714076) (xy 421.607814 -284.692296)
			(xy 421.653451 -284.677472) (xy 421.700844 -284.669971) (xy 421.724836 -284.669484) (xy 421.739018 -284.669677)
			(xy 421.767257 -284.672352) (xy 421.781224 -284.674818) (xy 421.79367 -284.677104) (xy 421.817292 -284.669738)
			(xy 421.894762 -284.592268) (xy 421.902128 -284.568646) (xy 421.899842 -284.5562) (xy 421.897356 -284.542235)
			(xy 421.894683 -284.513995) (xy 421.894508 -284.499812) (xy 421.895017 -284.474694) (xy 421.903239 -284.425136)
			(xy 421.919464 -284.377593) (xy 421.943253 -284.333347) (xy 421.973965 -284.293593) (xy 422.01077 -284.259403)
			(xy 422.052677 -284.2317) (xy 422.098553 -284.211231) (xy 422.147161 -284.198549) (xy 422.17213 -284.195774)
			(xy 422.181077 -284.194561) (xy 422.19735 -284.186767) (xy 422.20388 -284.180534) (xy 422.225216 -284.15869)
			(xy 422.231706 -284.151342) (xy 422.239039 -284.133179) (xy 422.23944 -284.123384) (xy 422.23944 -283.92628)
			(xy 422.238998 -283.916491) (xy 422.23169 -283.898329) (xy 422.225216 -283.890974) (xy 422.20388 -283.86913)
			(xy 422.197357 -283.862881) (xy 422.181086 -283.855068) (xy 422.17213 -283.85389) (xy 422.147166 -283.851106)
			(xy 422.098566 -283.838425) (xy 422.052698 -283.81796) (xy 422.010799 -283.790262) (xy 421.974 -283.756078)
			(xy 421.943293 -283.716331) (xy 421.919507 -283.672093) (xy 421.903285 -283.624558) (xy 421.895063 -283.575009)
			(xy 421.895064 -283.524782) (xy 421.903287 -283.475233) (xy 421.919511 -283.427699) (xy 421.943298 -283.383462)
			(xy 421.974006 -283.343716) (xy 422.010806 -283.309533) (xy 422.052706 -283.281836) (xy 422.098575 -283.261372)
			(xy 422.147175 -283.248693) (xy 422.17213 -283.245814) (xy 422.181075 -283.244599) (xy 422.197343 -283.236798)
			(xy 422.20388 -283.230574) (xy 422.225216 -283.20873) (xy 422.231697 -283.201379) (xy 422.239008 -283.183215)
			(xy 422.23944 -283.173424) (xy 422.23944 -282.02636) (xy 422.238994 -282.016573) (xy 422.231681 -281.998415)
			(xy 422.225216 -281.991054) (xy 422.20388 -281.96921) (xy 422.197356 -281.962964) (xy 422.181084 -281.955153)
			(xy 422.17213 -281.95397) (xy 422.14716 -281.951185) (xy 422.098547 -281.938503) (xy 422.052666 -281.918033)
			(xy 422.010756 -281.890329) (xy 421.973946 -281.856137) (xy 421.94323 -281.81638) (xy 421.919437 -281.772132)
			(xy 421.903209 -281.724585) (xy 421.894984 -281.675023) (xy 421.894984 -281.624783) (xy 421.903208 -281.575221)
			(xy 421.919435 -281.527674) (xy 421.943227 -281.483425) (xy 421.973942 -281.443667) (xy 422.010751 -281.409475)
			(xy 422.052661 -281.381769) (xy 422.098541 -281.361299) (xy 422.147154 -281.348616) (xy 422.17213 -281.345894)
			(xy 422.181074 -281.344678) (xy 422.19734 -281.336875) (xy 422.20388 -281.330654) (xy 422.225216 -281.30881)
			(xy 422.231709 -281.301463) (xy 422.239049 -281.2833) (xy 422.23944 -281.273504) (xy 422.23944 -281.09799)
			(xy 422.238938 -281.08818) (xy 422.231491 -281.070023) (xy 422.224962 -281.062684) (xy 422.20388 -281.04084)
			(xy 422.197305 -281.034557) (xy 422.180898 -281.026745) (xy 422.171876 -281.0256) (xy 422.146428 -281.022923)
			(xy 422.096749 -281.010669) (xy 422.049584 -280.99083) (xy 422.006083 -280.963888) (xy 421.967309 -280.930501)
			(xy 421.934206 -280.891484) (xy 421.907582 -280.847789) (xy 421.888087 -280.80048) (xy 421.876197 -280.750713)
			(xy 421.8722 -280.699702) (xy 421.876196 -280.64869) (xy 421.888086 -280.598923) (xy 421.907581 -280.551614)
			(xy 421.934204 -280.507918) (xy 421.967307 -280.468901) (xy 422.006081 -280.435514) (xy 422.049581 -280.408572)
			(xy 422.096746 -280.388732) (xy 422.146425 -280.376478) (xy 422.171876 -280.373836) (xy 422.180882 -280.37264)
			(xy 422.197273 -280.364832) (xy 422.20388 -280.358596) (xy 422.224962 -280.336752) (xy 422.231509 -280.329424)
			(xy 422.238958 -280.311261) (xy 422.23944 -280.301446) (xy 422.23944 -280.147776) (xy 422.238935 -280.137967)
			(xy 422.231485 -280.119813) (xy 422.224962 -280.11247) (xy 422.20388 -280.090626) (xy 422.197305 -280.084344)
			(xy 422.180897 -280.076534) (xy 422.171876 -280.075386) (xy 422.146429 -280.072709) (xy 422.096752 -280.060456)
			(xy 422.049589 -280.040617) (xy 422.006091 -280.013676) (xy 421.967318 -279.980291) (xy 421.934216 -279.941275)
			(xy 421.907594 -279.897581) (xy 421.8881 -279.850275) (xy 421.87621 -279.80051) (xy 421.872214 -279.7495)
			(xy 421.87621 -279.698491) (xy 421.8881 -279.648726) (xy 421.907594 -279.601419) (xy 421.934216 -279.557725)
			(xy 421.967317 -279.51871) (xy 422.00609 -279.485324) (xy 422.049589 -279.458383) (xy 422.096751 -279.438544)
			(xy 422.146428 -279.426291) (xy 422.171876 -279.423622) (xy 422.180882 -279.422426) (xy 422.197272 -279.414616)
			(xy 422.20388 -279.408382) (xy 422.224962 -279.386538) (xy 422.231507 -279.37921) (xy 422.238951 -279.361046)
			(xy 422.23944 -279.351232) (xy 422.23944 -279.176226) (xy 422.238988 -279.166441) (xy 422.231666 -279.148293)
			(xy 422.225216 -279.14092) (xy 422.20388 -279.119076) (xy 422.197354 -279.112833) (xy 422.181082 -279.105028)
			(xy 422.17213 -279.103836) (xy 422.147162 -279.101051) (xy 422.098555 -279.08837) (xy 422.05268 -279.067902)
			(xy 422.010774 -279.0402) (xy 421.973969 -279.006012) (xy 421.943257 -278.966259) (xy 421.919467 -278.922015)
			(xy 421.903241 -278.874474) (xy 421.895018 -278.824917) (xy 421.895018 -278.774683) (xy 421.903242 -278.725126)
			(xy 421.919467 -278.677584) (xy 421.943257 -278.63334) (xy 421.973969 -278.593588) (xy 422.010774 -278.559399)
			(xy 422.05268 -278.531698) (xy 422.098556 -278.51123) (xy 422.147163 -278.498549) (xy 422.17213 -278.49576)
			(xy 422.181076 -278.494547) (xy 422.197348 -278.486751) (xy 422.20388 -278.48052) (xy 422.225216 -278.458676)
			(xy 422.231704 -278.451327) (xy 422.239031 -278.433164) (xy 422.23944 -278.42337) (xy 422.23944 -278.226266)
			(xy 422.238996 -278.216478) (xy 422.231683 -278.198319) (xy 422.225216 -278.19096) (xy 422.20388 -278.169116)
			(xy 422.197356 -278.162869) (xy 422.181085 -278.155057) (xy 422.17213 -278.153876) (xy 422.147159 -278.151091)
			(xy 422.098545 -278.138409) (xy 422.052664 -278.117939) (xy 422.010752 -278.090234) (xy 421.973942 -278.056041)
			(xy 421.943225 -278.016284) (xy 421.919432 -277.972035) (xy 421.903204 -277.924487) (xy 421.894978 -277.874924)
			(xy 421.894978 -277.824683) (xy 421.903202 -277.77512) (xy 421.919429 -277.727572) (xy 421.943222 -277.683322)
			(xy 421.973937 -277.643564) (xy 422.010747 -277.60937) (xy 422.052658 -277.581664) (xy 422.098539 -277.561194)
			(xy 422.147152 -277.54851) (xy 422.17213 -277.5458) (xy 422.181075 -277.544584) (xy 422.197341 -277.536782)
			(xy 422.20388 -277.53056) (xy 422.225216 -277.508716) (xy 422.231695 -277.501364) (xy 422.239001 -277.483201)
			(xy 422.23944 -277.47341) (xy 422.23944 -277.276306) (xy 422.238985 -277.266523) (xy 422.231658 -277.248379)
			(xy 422.225216 -277.241) (xy 422.20388 -277.219156) (xy 422.197353 -277.212915) (xy 422.181081 -277.205113)
			(xy 422.17213 -277.203916) (xy 422.147153 -277.201146) (xy 422.098523 -277.188489) (xy 422.052623 -277.168037)
			(xy 422.010692 -277.140345) (xy 421.973863 -277.106159) (xy 421.94313 -277.066402) (xy 421.919323 -277.022149)
			(xy 421.903086 -276.974595) (xy 421.894856 -276.925023) (xy 421.894857 -276.874773) (xy 421.903087 -276.825201)
			(xy 421.919325 -276.777647) (xy 421.943132 -276.733394) (xy 421.973865 -276.693639) (xy 422.010695 -276.659453)
			(xy 422.052626 -276.631761) (xy 422.098527 -276.61131) (xy 422.147157 -276.598653) (xy 422.17213 -276.59584)
			(xy 422.181076 -276.594626) (xy 422.197346 -276.586828) (xy 422.20388 -276.5806) (xy 422.225216 -276.558756)
			(xy 422.231701 -276.551406) (xy 422.239021 -276.533243) (xy 422.23944 -276.52345) (xy 422.23944 -276.34819)
			(xy 422.238938 -276.33838) (xy 422.231491 -276.320223) (xy 422.224962 -276.312884) (xy 422.20388 -276.29104)
			(xy 422.197305 -276.284757) (xy 422.180898 -276.276945) (xy 422.171876 -276.2758) (xy 422.146428 -276.273123)
			(xy 422.096749 -276.260869) (xy 422.049584 -276.24103) (xy 422.006083 -276.214088) (xy 421.967309 -276.180701)
			(xy 421.934206 -276.141684) (xy 421.907582 -276.097989) (xy 421.888087 -276.05068) (xy 421.876197 -276.000913)
			(xy 421.8722 -275.949902) (xy 421.876196 -275.89889) (xy 421.888086 -275.849123) (xy 421.907581 -275.801814)
			(xy 421.934204 -275.758118) (xy 421.967307 -275.719101) (xy 422.006081 -275.685714) (xy 422.049581 -275.658772)
			(xy 422.096746 -275.638932) (xy 422.146425 -275.626678) (xy 422.171876 -275.624036) (xy 422.180882 -275.62284)
			(xy 422.197273 -275.615032) (xy 422.20388 -275.608796) (xy 422.224962 -275.586952) (xy 422.231509 -275.579624)
			(xy 422.238958 -275.561461) (xy 422.23944 -275.551646) (xy 422.23944 -275.39823) (xy 422.238945 -275.388417)
			(xy 422.231508 -275.370249) (xy 422.224962 -275.362924) (xy 422.20388 -275.34108) (xy 422.197308 -275.334792)
			(xy 422.1809 -275.326974) (xy 422.171876 -275.32584) (xy 422.146432 -275.323163) (xy 422.096763 -275.310911)
			(xy 422.049607 -275.291074) (xy 422.006115 -275.264137) (xy 421.967348 -275.230756) (xy 421.934251 -275.191745)
			(xy 421.907633 -275.148057) (xy 421.888142 -275.100757) (xy 421.876255 -275.050999) (xy 421.87226 -274.999996)
			(xy 421.876256 -274.948994) (xy 421.888145 -274.899236) (xy 421.907636 -274.851937) (xy 421.934255 -274.808249)
			(xy 421.967353 -274.769239) (xy 422.00612 -274.735859) (xy 422.049613 -274.708922) (xy 422.09677 -274.689087)
			(xy 422.14644 -274.676836) (xy 422.171876 -274.674076) (xy 422.18088 -274.672878) (xy 422.197266 -274.665064)
			(xy 422.20388 -274.658836) (xy 422.224962 -274.636992) (xy 422.231515 -274.629666) (xy 422.238978 -274.611503)
			(xy 422.23944 -274.601686) (xy 422.23944 -274.426172) (xy 422.238997 -274.416384) (xy 422.231686 -274.398223)
			(xy 422.225216 -274.390866) (xy 422.20388 -274.369022) (xy 422.197357 -274.362774) (xy 422.181085 -274.354962)
			(xy 422.17213 -274.353782) (xy 422.147159 -274.350997) (xy 422.098544 -274.338315) (xy 422.052661 -274.317844)
			(xy 422.010749 -274.290139) (xy 421.973938 -274.255946) (xy 421.943221 -274.216188) (xy 421.919427 -274.171937)
			(xy 421.903198 -274.124389) (xy 421.894972 -274.074825) (xy 421.894972 -274.024583) (xy 421.903196 -273.975019)
			(xy 421.919424 -273.92747) (xy 421.943216 -273.883219) (xy 421.973932 -273.84346) (xy 422.010743 -273.809266)
			(xy 422.052654 -273.78156) (xy 422.098536 -273.761088) (xy 422.147151 -273.748404) (xy 422.17213 -273.745706)
			(xy 422.181075 -273.744491) (xy 422.197342 -273.736689) (xy 422.20388 -273.730466) (xy 422.225216 -273.708622)
			(xy 422.231696 -273.70127) (xy 422.239004 -273.683107) (xy 422.23944 -273.673316) (xy 422.23944 -273.476212)
			(xy 422.238986 -273.466429) (xy 422.23166 -273.448283) (xy 422.225216 -273.440906) (xy 422.20388 -273.419062)
			(xy 422.197353 -273.412821) (xy 422.181082 -273.405018) (xy 422.17213 -273.403822) (xy 422.147164 -273.401037)
			(xy 422.098559 -273.388356) (xy 422.052685 -273.367889) (xy 422.010782 -273.340189) (xy 421.973978 -273.306002)
			(xy 421.943268 -273.266251) (xy 421.919479 -273.222009) (xy 421.903255 -273.174469) (xy 421.895031 -273.124915)
			(xy 421.895032 -273.074683) (xy 421.903255 -273.025128) (xy 421.91948 -272.977589) (xy 421.943269 -272.933347)
			(xy 421.97398 -272.893596) (xy 422.010784 -272.85941) (xy 422.052688 -272.831709) (xy 422.098561 -272.811243)
			(xy 422.147166 -272.798562) (xy 422.17213 -272.795746) (xy 422.181076 -272.794532) (xy 422.197346 -272.786735)
			(xy 422.20388 -272.780506) (xy 422.225216 -272.758662) (xy 422.231702 -272.751312) (xy 422.239024 -272.733149)
			(xy 422.23944 -272.723356) (xy 422.23944 -255.96469) (xy 422.239013 -255.954622) (xy 422.23129 -255.936026)
			(xy 422.224454 -255.928622) (xy 416.036506 -249.740674) (xy 416.029394 -249.733308) (xy 416.010598 -249.725688)
			(xy 390.406128 -249.725688) (xy 390.396063 -249.726124) (xy 390.377477 -249.733855) (xy 390.37006 -249.740674)
			(xy 389.22452 -250.886214) (xy 389.216705 -250.894846) (xy 389.209157 -250.916848) (xy 389.212014 -250.939933)
			(xy 389.217916 -250.949968) (xy 389.232581 -250.973342) (xy 389.255757 -251.023418) (xy 389.271481 -251.076309)
			(xy 389.279425 -251.130913) (xy 389.279892 -251.158502) (xy 389.279429 -251.185754) (xy 389.271671 -251.239704)
			(xy 389.256315 -251.292001) (xy 389.233672 -251.34158) (xy 389.204204 -251.387431) (xy 389.16851 -251.428623)
			(xy 389.127317 -251.464315) (xy 389.081464 -251.493781) (xy 389.031884 -251.516421) (xy 388.979587 -251.531775)
			(xy 388.925636 -251.53953) (xy 388.898384 -251.54001) (xy 388.871249 -251.539531) (xy 388.817526 -251.531838)
			(xy 388.765436 -251.51661) (xy 388.71603 -251.494153) (xy 388.670304 -251.464922) (xy 388.629183 -251.429506)
			(xy 388.593495 -251.38862) (xy 388.563961 -251.343089) (xy 388.541178 -251.293832) (xy 388.525605 -251.241844)
			(xy 388.517557 -251.188173) (xy 388.516876 -251.161042) (xy 388.516876 -251.150628) (xy 388.509256 -251.132594)
			(xy 388.45109 -251.074936) (xy 388.44372 -251.068192) (xy 388.425258 -251.060597) (xy 388.415276 -251.060204)
			(xy 387.349492 -251.060204) (xy 387.339525 -251.06068) (xy 387.321086 -251.068253) (xy 387.313678 -251.074936)
			(xy 387.255512 -251.132594) (xy 387.247892 -251.150628) (xy 387.247892 -251.161042) (xy 387.247234 -251.188175)
			(xy 387.239185 -251.241848) (xy 387.223611 -251.293838) (xy 387.200826 -251.343097) (xy 387.171291 -251.38863)
			(xy 387.135601 -251.429517) (xy 387.094477 -251.464934) (xy 387.048748 -251.494166) (xy 386.999339 -251.516622)
			(xy 386.947246 -251.53185) (xy 386.893521 -251.539541) (xy 386.839247 -251.539541) (xy 386.785522 -251.53185)
			(xy 386.733429 -251.516622) (xy 386.68402 -251.494166) (xy 386.638291 -251.464934) (xy 386.597167 -251.429517)
			(xy 386.561477 -251.38863) (xy 386.531942 -251.343097) (xy 386.509157 -251.293838) (xy 386.493583 -251.241848)
			(xy 386.485534 -251.188175) (xy 386.484876 -251.161042) (xy 386.484876 -251.150628) (xy 386.477256 -251.132594)
			(xy 386.41909 -251.074936) (xy 386.41172 -251.068192) (xy 386.393258 -251.060597) (xy 386.383276 -251.060204)
			(xy 386.333492 -251.060204) (xy 386.323525 -251.06068) (xy 386.305086 -251.068253) (xy 386.297678 -251.074936)
			(xy 386.239512 -251.132594) (xy 386.231892 -251.150628) (xy 386.231892 -251.161042) (xy 386.231234 -251.188175)
			(xy 386.223185 -251.241848) (xy 386.207611 -251.293838) (xy 386.184826 -251.343097) (xy 386.155291 -251.38863)
			(xy 386.119601 -251.429517) (xy 386.078477 -251.464934) (xy 386.032748 -251.494166) (xy 385.983339 -251.516622)
			(xy 385.931246 -251.53185) (xy 385.877521 -251.539541) (xy 385.823247 -251.539541) (xy 385.769522 -251.53185)
			(xy 385.717429 -251.516622) (xy 385.66802 -251.494166) (xy 385.622291 -251.464934) (xy 385.581167 -251.429517)
			(xy 385.545477 -251.38863) (xy 385.515942 -251.343097) (xy 385.493157 -251.293838) (xy 385.477583 -251.241848)
			(xy 385.469534 -251.188175) (xy 385.468876 -251.161042) (xy 385.468876 -251.150628) (xy 385.461256 -251.132594)
			(xy 385.40309 -251.074936) (xy 385.39572 -251.068192) (xy 385.377258 -251.060597) (xy 385.367276 -251.060204)
			(xy 385.317492 -251.060204) (xy 385.307525 -251.06068) (xy 385.289086 -251.068253) (xy 385.281678 -251.074936)
			(xy 385.223512 -251.132594) (xy 385.215892 -251.150628) (xy 385.215892 -251.161042) (xy 385.215234 -251.188175)
			(xy 385.207185 -251.241848) (xy 385.191611 -251.293838) (xy 385.168826 -251.343097) (xy 385.139291 -251.38863)
			(xy 385.103601 -251.429517) (xy 385.062477 -251.464934) (xy 385.016748 -251.494166) (xy 384.967339 -251.516622)
			(xy 384.915246 -251.53185) (xy 384.861521 -251.539541) (xy 384.807247 -251.539541) (xy 384.753522 -251.53185)
			(xy 384.701429 -251.516622) (xy 384.65202 -251.494166) (xy 384.606291 -251.464934) (xy 384.565167 -251.429517)
			(xy 384.529477 -251.38863) (xy 384.499942 -251.343097) (xy 384.477157 -251.293838) (xy 384.461583 -251.241848)
			(xy 384.453534 -251.188175) (xy 384.452876 -251.161042) (xy 384.452876 -251.150628) (xy 384.445256 -251.132594)
			(xy 384.38709 -251.074936) (xy 384.37972 -251.068192) (xy 384.361258 -251.060597) (xy 384.351276 -251.060204)
			(xy 384.301492 -251.060204) (xy 384.291525 -251.06068) (xy 384.273086 -251.068253) (xy 384.265678 -251.074936)
			(xy 384.207512 -251.132594) (xy 384.199892 -251.150628) (xy 384.199892 -251.161042) (xy 384.199234 -251.188175)
			(xy 384.191185 -251.241848) (xy 384.175611 -251.293838) (xy 384.152826 -251.343097) (xy 384.123291 -251.38863)
			(xy 384.087601 -251.429517) (xy 384.046477 -251.464934) (xy 384.000748 -251.494166) (xy 383.951339 -251.516622)
			(xy 383.899246 -251.53185) (xy 383.845521 -251.539541) (xy 383.791247 -251.539541) (xy 383.737522 -251.53185)
			(xy 383.685429 -251.516622) (xy 383.63602 -251.494166) (xy 383.590291 -251.464934) (xy 383.549167 -251.429517)
			(xy 383.513477 -251.38863) (xy 383.483942 -251.343097) (xy 383.461157 -251.293838) (xy 383.445583 -251.241848)
			(xy 383.437534 -251.188175) (xy 383.436876 -251.161042) (xy 383.436876 -251.150628) (xy 383.429256 -251.132594)
			(xy 383.37109 -251.074936) (xy 383.36372 -251.068192) (xy 383.345258 -251.060597) (xy 383.335276 -251.060204)
			(xy 383.285492 -251.060204) (xy 383.275525 -251.06068) (xy 383.257086 -251.068253) (xy 383.249678 -251.074936)
			(xy 383.191512 -251.132594) (xy 383.183892 -251.150628) (xy 383.183892 -251.161042) (xy 383.183234 -251.188175)
			(xy 383.175185 -251.241848) (xy 383.159611 -251.293838) (xy 383.136826 -251.343097) (xy 383.107291 -251.38863)
			(xy 383.071601 -251.429517) (xy 383.030477 -251.464934) (xy 382.984748 -251.494166) (xy 382.935339 -251.516622)
			(xy 382.883246 -251.53185) (xy 382.829521 -251.539541) (xy 382.775247 -251.539541) (xy 382.721522 -251.53185)
			(xy 382.669429 -251.516622) (xy 382.62002 -251.494166) (xy 382.574291 -251.464934) (xy 382.533167 -251.429517)
			(xy 382.497477 -251.38863) (xy 382.467942 -251.343097) (xy 382.445157 -251.293838) (xy 382.429583 -251.241848)
			(xy 382.421534 -251.188175) (xy 382.420876 -251.161042) (xy 382.420876 -251.150628) (xy 382.413256 -251.132594)
			(xy 382.35509 -251.074936) (xy 382.34772 -251.068192) (xy 382.329258 -251.060597) (xy 382.319276 -251.060204)
			(xy 382.269492 -251.060204) (xy 382.259525 -251.06068) (xy 382.241086 -251.068253) (xy 382.233678 -251.074936)
			(xy 382.175512 -251.132594) (xy 382.167892 -251.150628) (xy 382.167892 -251.161042) (xy 382.167234 -251.188175)
			(xy 382.159185 -251.241848) (xy 382.143611 -251.293838) (xy 382.120826 -251.343097) (xy 382.091291 -251.38863)
			(xy 382.055601 -251.429517) (xy 382.014477 -251.464934) (xy 381.968748 -251.494166) (xy 381.919339 -251.516622)
			(xy 381.867246 -251.53185) (xy 381.813521 -251.539541) (xy 381.759247 -251.539541) (xy 381.705522 -251.53185)
			(xy 381.653429 -251.516622) (xy 381.60402 -251.494166) (xy 381.558291 -251.464934) (xy 381.517167 -251.429517)
			(xy 381.481477 -251.38863) (xy 381.451942 -251.343097) (xy 381.429157 -251.293838) (xy 381.413583 -251.241848)
			(xy 381.405534 -251.188175) (xy 381.404876 -251.161042) (xy 381.404876 -251.150628) (xy 381.397256 -251.132594)
			(xy 381.33909 -251.074936) (xy 381.33172 -251.068192) (xy 381.313258 -251.060597) (xy 381.303276 -251.060204)
			(xy 381.253492 -251.060204) (xy 381.243525 -251.06068) (xy 381.225086 -251.068253) (xy 381.217678 -251.074936)
			(xy 381.159512 -251.132594) (xy 381.151892 -251.150628) (xy 381.151892 -251.161042) (xy 381.151234 -251.188175)
			(xy 381.143185 -251.241848) (xy 381.127611 -251.293838) (xy 381.104826 -251.343097) (xy 381.075291 -251.38863)
			(xy 381.039601 -251.429517) (xy 380.998477 -251.464934) (xy 380.952748 -251.494166) (xy 380.903339 -251.516622)
			(xy 380.851246 -251.53185) (xy 380.797521 -251.539541) (xy 380.743247 -251.539541) (xy 380.689522 -251.53185)
			(xy 380.637429 -251.516622) (xy 380.58802 -251.494166) (xy 380.542291 -251.464934) (xy 380.501167 -251.429517)
			(xy 380.465477 -251.38863) (xy 380.435942 -251.343097) (xy 380.413157 -251.293838) (xy 380.397583 -251.241848)
			(xy 380.389534 -251.188175) (xy 380.388876 -251.161042) (xy 380.388876 -251.150628) (xy 380.381256 -251.132594)
			(xy 380.32309 -251.074936) (xy 380.31572 -251.068192) (xy 380.297258 -251.060597) (xy 380.287276 -251.060204)
			(xy 380.237492 -251.060204) (xy 380.227525 -251.06068) (xy 380.209086 -251.068253) (xy 380.201678 -251.074936)
			(xy 380.143512 -251.132594) (xy 380.135892 -251.150628) (xy 380.135892 -251.161042) (xy 380.135234 -251.188175)
			(xy 380.127185 -251.241848) (xy 380.111611 -251.293838) (xy 380.088826 -251.343097) (xy 380.059291 -251.38863)
			(xy 380.023601 -251.429517) (xy 379.982477 -251.464934) (xy 379.936748 -251.494166) (xy 379.887339 -251.516622)
			(xy 379.835246 -251.53185) (xy 379.781521 -251.539541) (xy 379.727247 -251.539541) (xy 379.673522 -251.53185)
			(xy 379.621429 -251.516622) (xy 379.57202 -251.494166) (xy 379.526291 -251.464934) (xy 379.485167 -251.429517)
			(xy 379.449477 -251.38863) (xy 379.419942 -251.343097) (xy 379.397157 -251.293838) (xy 379.381583 -251.241848)
			(xy 379.373534 -251.188175) (xy 379.372876 -251.161042) (xy 379.372876 -251.150628) (xy 379.365256 -251.132594)
			(xy 379.30709 -251.074936) (xy 379.29972 -251.068192) (xy 379.281258 -251.060597) (xy 379.271276 -251.060204)
			(xy 379.221492 -251.060204) (xy 379.211525 -251.06068) (xy 379.193086 -251.068253) (xy 379.185678 -251.074936)
			(xy 379.127512 -251.132594) (xy 379.119892 -251.150628) (xy 379.119892 -251.161042) (xy 379.119234 -251.188175)
			(xy 379.111185 -251.241848) (xy 379.095611 -251.293838) (xy 379.072826 -251.343097) (xy 379.043291 -251.38863)
			(xy 379.007601 -251.429517) (xy 378.966477 -251.464934) (xy 378.920748 -251.494166) (xy 378.871339 -251.516622)
			(xy 378.819246 -251.53185) (xy 378.765521 -251.539541) (xy 378.711247 -251.539541) (xy 378.657522 -251.53185)
			(xy 378.605429 -251.516622) (xy 378.55602 -251.494166) (xy 378.510291 -251.464934) (xy 378.469167 -251.429517)
			(xy 378.433477 -251.38863) (xy 378.403942 -251.343097) (xy 378.381157 -251.293838) (xy 378.365583 -251.241848)
			(xy 378.357534 -251.188175) (xy 378.356876 -251.161042) (xy 378.356876 -251.150628) (xy 378.349256 -251.132594)
			(xy 378.29109 -251.074936) (xy 378.28372 -251.068192) (xy 378.265258 -251.060597) (xy 378.255276 -251.060204)
			(xy 378.205492 -251.060204) (xy 378.195525 -251.06068) (xy 378.177086 -251.068253) (xy 378.169678 -251.074936)
			(xy 378.111512 -251.132594) (xy 378.103892 -251.150628) (xy 378.103892 -251.161042) (xy 378.103234 -251.188175)
			(xy 378.095185 -251.241848) (xy 378.079611 -251.293838) (xy 378.056826 -251.343097) (xy 378.027291 -251.38863)
			(xy 377.991601 -251.429517) (xy 377.950477 -251.464934) (xy 377.904748 -251.494166) (xy 377.855339 -251.516622)
			(xy 377.803246 -251.53185) (xy 377.749521 -251.539541) (xy 377.695247 -251.539541) (xy 377.641522 -251.53185)
			(xy 377.589429 -251.516622) (xy 377.54002 -251.494166) (xy 377.494291 -251.464934) (xy 377.453167 -251.429517)
			(xy 377.417477 -251.38863) (xy 377.387942 -251.343097) (xy 377.365157 -251.293838) (xy 377.349583 -251.241848)
			(xy 377.341534 -251.188175) (xy 377.340876 -251.161042) (xy 377.340876 -251.150628) (xy 377.333256 -251.132594)
			(xy 377.27509 -251.074936) (xy 377.26772 -251.068192) (xy 377.249258 -251.060597) (xy 377.239276 -251.060204)
			(xy 377.189492 -251.060204) (xy 377.179525 -251.06068) (xy 377.161086 -251.068253) (xy 377.153678 -251.074936)
			(xy 377.095512 -251.132594) (xy 377.087892 -251.150628) (xy 377.087892 -251.161042) (xy 377.087234 -251.188175)
			(xy 377.079185 -251.241848) (xy 377.063611 -251.293838) (xy 377.040826 -251.343097) (xy 377.011291 -251.38863)
			(xy 376.975601 -251.429517) (xy 376.934477 -251.464934) (xy 376.888748 -251.494166) (xy 376.839339 -251.516622)
			(xy 376.787246 -251.53185) (xy 376.733521 -251.539541) (xy 376.679247 -251.539541) (xy 376.625522 -251.53185)
			(xy 376.573429 -251.516622) (xy 376.52402 -251.494166) (xy 376.478291 -251.464934) (xy 376.437167 -251.429517)
			(xy 376.401477 -251.38863) (xy 376.371942 -251.343097) (xy 376.349157 -251.293838) (xy 376.333583 -251.241848)
			(xy 376.325534 -251.188175) (xy 376.324876 -251.161042) (xy 376.324876 -251.150628) (xy 376.317256 -251.132594)
			(xy 376.25909 -251.074936) (xy 376.25172 -251.068192) (xy 376.233258 -251.060597) (xy 376.223276 -251.060204)
			(xy 376.173492 -251.060204) (xy 376.163525 -251.06068) (xy 376.145086 -251.068253) (xy 376.137678 -251.074936)
			(xy 376.079512 -251.132594) (xy 376.071892 -251.150628) (xy 376.071892 -251.161042) (xy 376.071234 -251.188175)
			(xy 376.063185 -251.241848) (xy 376.047611 -251.293838) (xy 376.024826 -251.343097) (xy 375.995291 -251.38863)
			(xy 375.959601 -251.429517) (xy 375.918477 -251.464934) (xy 375.872748 -251.494166) (xy 375.823339 -251.516622)
			(xy 375.771246 -251.53185) (xy 375.717521 -251.539541) (xy 375.663247 -251.539541) (xy 375.609522 -251.53185)
			(xy 375.557429 -251.516622) (xy 375.50802 -251.494166) (xy 375.462291 -251.464934) (xy 375.421167 -251.429517)
			(xy 375.385477 -251.38863) (xy 375.355942 -251.343097) (xy 375.333157 -251.293838) (xy 375.317583 -251.241848)
			(xy 375.309534 -251.188175) (xy 375.308876 -251.161042) (xy 375.308876 -251.150628) (xy 375.301256 -251.132594)
			(xy 375.24309 -251.074936) (xy 375.23572 -251.068192) (xy 375.217258 -251.060597) (xy 375.207276 -251.060204)
			(xy 375.157492 -251.060204) (xy 375.147525 -251.06068) (xy 375.129086 -251.068253) (xy 375.121678 -251.074936)
			(xy 375.063512 -251.132594) (xy 375.055892 -251.150628) (xy 375.055892 -251.161042) (xy 375.055234 -251.188175)
			(xy 375.047185 -251.241848) (xy 375.031611 -251.293838) (xy 375.008826 -251.343097) (xy 374.979291 -251.38863)
			(xy 374.943601 -251.429517) (xy 374.902477 -251.464934) (xy 374.856748 -251.494166) (xy 374.807339 -251.516622)
			(xy 374.755246 -251.53185) (xy 374.701521 -251.539541) (xy 374.647247 -251.539541) (xy 374.593522 -251.53185)
			(xy 374.541429 -251.516622) (xy 374.49202 -251.494166) (xy 374.446291 -251.464934) (xy 374.405167 -251.429517)
			(xy 374.369477 -251.38863) (xy 374.339942 -251.343097) (xy 374.317157 -251.293838) (xy 374.301583 -251.241848)
			(xy 374.293534 -251.188175) (xy 374.292876 -251.161042) (xy 374.292876 -251.150628) (xy 374.285256 -251.132594)
			(xy 374.22709 -251.074936) (xy 374.21972 -251.068192) (xy 374.201258 -251.060597) (xy 374.191276 -251.060204)
			(xy 374.138952 -251.060204) (xy 374.128951 -251.0607) (xy 374.110476 -251.068369) (xy 374.096339 -251.08252)
			(xy 374.08869 -251.101003) (xy 374.088152 -251.111004) (xy 374.088152 -251.113798) (xy 374.088406 -251.116592)
			(xy 374.089481 -251.127036) (xy 374.090624 -251.148003) (xy 374.090692 -251.158502) (xy 374.090229 -251.185754)
			(xy 374.082471 -251.239704) (xy 374.067115 -251.292001) (xy 374.044472 -251.34158) (xy 374.015004 -251.387431)
			(xy 373.97931 -251.428623) (xy 373.938117 -251.464315) (xy 373.892264 -251.493781) (xy 373.842684 -251.516421)
			(xy 373.790387 -251.531775) (xy 373.736436 -251.53953) (xy 373.709184 -251.54001) (xy 373.682049 -251.539531)
			(xy 373.628326 -251.531838) (xy 373.576236 -251.51661) (xy 373.52683 -251.494153) (xy 373.481104 -251.464922)
			(xy 373.439983 -251.429506) (xy 373.404295 -251.38862) (xy 373.374761 -251.343089) (xy 373.351978 -251.293832)
			(xy 373.336405 -251.241844) (xy 373.328357 -251.188173) (xy 373.327676 -251.161042) (xy 373.327676 -251.150628)
			(xy 373.320056 -251.132594) (xy 373.26189 -251.074936) (xy 373.25452 -251.068192) (xy 373.236058 -251.060597)
			(xy 373.226076 -251.060204) (xy 373.125492 -251.060204) (xy 373.115525 -251.06068) (xy 373.097086 -251.068253)
			(xy 373.089678 -251.074936) (xy 373.031512 -251.132594) (xy 373.023892 -251.150628) (xy 373.023892 -251.161042)
			(xy 373.023234 -251.188175) (xy 373.015185 -251.241848) (xy 372.999611 -251.293838) (xy 372.976826 -251.343097)
			(xy 372.947291 -251.38863) (xy 372.911601 -251.429517) (xy 372.870477 -251.464934) (xy 372.824748 -251.494166)
			(xy 372.775339 -251.516622) (xy 372.723246 -251.53185) (xy 372.669521 -251.539541) (xy 372.615247 -251.539541)
			(xy 372.561522 -251.53185) (xy 372.509429 -251.516622) (xy 372.46002 -251.494166) (xy 372.414291 -251.464934)
			(xy 372.373167 -251.429517) (xy 372.337477 -251.38863) (xy 372.307942 -251.343097) (xy 372.285157 -251.293838)
			(xy 372.269583 -251.241848) (xy 372.261534 -251.188175) (xy 372.260876 -251.161042) (xy 372.260876 -251.150628)
			(xy 372.253256 -251.132594) (xy 372.19509 -251.074936) (xy 372.18772 -251.068192) (xy 372.169258 -251.060597)
			(xy 372.159276 -251.060204) (xy 371.175788 -251.060204) (xy 371.163654 -251.060831) (xy 371.142037 -251.071846)
			(xy 371.134386 -251.081286) (xy 371.079014 -251.158248) (xy 371.075458 -251.182378) (xy 371.079522 -251.194062)
			(xy 371.088809 -251.223616) (xy 371.098768 -251.284755) (xy 371.099334 -251.315728) (xy 371.098848 -251.342979)
			(xy 371.091092 -251.396927) (xy 371.075737 -251.449222) (xy 371.053095 -251.498799) (xy 371.023629 -251.544649)
			(xy 370.987938 -251.58584) (xy 370.946747 -251.621531) (xy 370.900897 -251.650997) (xy 370.85132 -251.673639)
			(xy 370.799025 -251.688994) (xy 370.745077 -251.69675) (xy 370.690575 -251.69675) (xy 370.636627 -251.688994)
			(xy 370.584332 -251.673639) (xy 370.534755 -251.650997) (xy 370.488905 -251.621531) (xy 370.447714 -251.58584)
			(xy 370.412023 -251.544649) (xy 370.382557 -251.498799) (xy 370.359915 -251.449222) (xy 370.34456 -251.396927)
			(xy 370.336804 -251.342979) (xy 370.336318 -251.315728) (xy 370.336899 -251.284756) (xy 370.34685 -251.223617)
			(xy 370.35613 -251.194062) (xy 370.360194 -251.182378) (xy 370.356638 -251.158248) (xy 370.301266 -251.081286)
			(xy 370.293602 -251.071868) (xy 370.271989 -251.060878) (xy 370.259864 -251.060204) (xy 369.26266 -251.060204)
			(xy 369.252696 -251.060686) (xy 369.234265 -251.068267) (xy 369.226846 -251.074936) (xy 367.990628 -252.311154)
			(xy 367.983228 -252.317994) (xy 367.964629 -252.32571) (xy 367.95456 -252.32614) (xy 360.099102 -252.32614)
			(xy 360.090179 -252.326525) (xy 360.073405 -252.332621) (xy 360.066336 -252.338078) (xy 360.045633 -252.354888)
			(xy 360.000419 -252.383167) (xy 359.951707 -252.404874) (xy 359.900446 -252.419585) (xy 359.847637 -252.427012)
			(xy 359.794307 -252.427012) (xy 359.741498 -252.419585) (xy 359.690237 -252.404874) (xy 359.641525 -252.383167)
			(xy 359.596311 -252.354888) (xy 359.575608 -252.338078) (xy 359.568558 -252.332584) (xy 359.551774 -252.326476)
			(xy 359.542842 -252.32614) (xy 356.126542 -252.32614) (xy 356.116478 -252.325705) (xy 356.097894 -252.317969)
			(xy 356.090474 -252.311154) (xy 355.578664 -251.799344) (xy 355.575362 -251.797058) (xy 355.551325 -251.779004)
			(xy 355.506691 -251.738729) (xy 355.466414 -251.694096) (xy 355.448362 -251.670058) (xy 355.446076 -251.666756)
			(xy 354.537772 -250.758452) (xy 354.53066 -250.751086) (xy 354.511864 -250.743466) (xy 348.713044 -250.743466)
			(xy 348.687644 -250.76023) (xy 348.681802 -250.774454) (xy 348.670485 -250.800016) (xy 348.64147 -250.847798)
			(xy 348.605793 -250.890834) (xy 348.564218 -250.928205) (xy 348.517635 -250.959108) (xy 348.467041 -250.982884)
			(xy 348.41352 -250.999023) (xy 348.358217 -251.00718) (xy 348.302315 -251.00718) (xy 348.247012 -250.999023)
			(xy 348.193491 -250.982884) (xy 348.142897 -250.959108) (xy 348.096314 -250.928205) (xy 348.054739 -250.890834)
			(xy 348.019062 -250.847798) (xy 347.990047 -250.800016) (xy 347.97873 -250.774454) (xy 347.972888 -250.76023)
			(xy 347.947488 -250.743466) (xy 347.45803 -250.743466) (xy 347.447967 -250.743904) (xy 347.429387 -250.751643)
			(xy 347.421962 -250.758452) (xy 346.255848 -251.924566) (xy 350.94113 -251.924566) (xy 350.945201 -251.868944)
			(xy 350.957327 -251.814507) (xy 350.97725 -251.762416) (xy 351.004546 -251.713781) (xy 351.038632 -251.669638)
			(xy 351.078781 -251.630929) (xy 351.124139 -251.598478) (xy 351.173739 -251.572977) (xy 351.226523 -251.55497)
			(xy 351.281366 -251.54484) (xy 351.3371 -251.542803) (xy 351.392537 -251.548903) (xy 351.446494 -251.563009)
			(xy 351.497823 -251.584821) (xy 351.545429 -251.613875) (xy 351.588297 -251.64955) (xy 351.625514 -251.691087)
			(xy 351.656287 -251.7376) (xy 351.679959 -251.788097) (xy 351.696027 -251.841504) (xy 351.704147 -251.89668)
			(xy 351.704656 -251.924566) (xy 351.704147 -251.952452) (xy 351.696027 -252.007628) (xy 351.679959 -252.061035)
			(xy 351.656287 -252.111532) (xy 351.655797 -252.112272) (xy 352.47275 -252.112272) (xy 352.476821 -252.05665)
			(xy 352.488947 -252.002213) (xy 352.50887 -251.950122) (xy 352.536166 -251.901487) (xy 352.570252 -251.857344)
			(xy 352.610401 -251.818635) (xy 352.655759 -251.786184) (xy 352.705359 -251.760683) (xy 352.758143 -251.742676)
			(xy 352.812986 -251.732546) (xy 352.86872 -251.730509) (xy 352.924157 -251.736609) (xy 352.978114 -251.750715)
			(xy 353.029443 -251.772527) (xy 353.077049 -251.801581) (xy 353.119917 -251.837256) (xy 353.157134 -251.878793)
			(xy 353.187907 -251.925306) (xy 353.211579 -251.975803) (xy 353.227647 -252.02921) (xy 353.235767 -252.084386)
			(xy 353.236276 -252.112272) (xy 353.235767 -252.140158) (xy 353.227647 -252.195334) (xy 353.211579 -252.248741)
			(xy 353.187907 -252.299238) (xy 353.157134 -252.345751) (xy 353.119917 -252.387288) (xy 353.077049 -252.422963)
			(xy 353.029443 -252.452017) (xy 352.978114 -252.473829) (xy 352.924157 -252.487935) (xy 352.86872 -252.494035)
			(xy 352.812986 -252.491998) (xy 352.758143 -252.481868) (xy 352.705359 -252.463861) (xy 352.655759 -252.43836)
			(xy 352.610401 -252.405909) (xy 352.570252 -252.3672) (xy 352.536166 -252.323057) (xy 352.50887 -252.274422)
			(xy 352.488947 -252.222331) (xy 352.476821 -252.167894) (xy 352.47275 -252.112272) (xy 351.655797 -252.112272)
			(xy 351.625514 -252.158045) (xy 351.588297 -252.199582) (xy 351.545429 -252.235257) (xy 351.497823 -252.264311)
			(xy 351.446494 -252.286123) (xy 351.392537 -252.300229) (xy 351.3371 -252.306329) (xy 351.281366 -252.304292)
			(xy 351.226523 -252.294162) (xy 351.173739 -252.276155) (xy 351.124139 -252.250654) (xy 351.078781 -252.218203)
			(xy 351.038632 -252.179494) (xy 351.004546 -252.135351) (xy 350.97725 -252.086716) (xy 350.957327 -252.034625)
			(xy 350.945201 -251.980188) (xy 350.94113 -251.924566) (xy 346.255848 -251.924566) (xy 346.135198 -252.045216)
			(xy 346.128173 -252.052893) (xy 346.120416 -252.072182) (xy 346.120899 -252.092966) (xy 346.124784 -252.10262)
			(xy 346.171774 -252.203712) (xy 346.198952 -252.219714) (xy 346.215208 -252.218444) (xy 346.245942 -252.217174)
			(xy 346.273194 -252.217663) (xy 346.327143 -252.225425) (xy 346.379438 -252.240787) (xy 346.429014 -252.263434)
			(xy 346.474863 -252.292906) (xy 346.516051 -252.328603) (xy 346.55174 -252.369798) (xy 346.581203 -252.415653)
			(xy 346.60384 -252.465234) (xy 346.619191 -252.517532) (xy 346.626943 -252.571482) (xy 346.626938 -252.625986)
			(xy 346.619176 -252.679935) (xy 346.603816 -252.73223) (xy 346.58117 -252.781807) (xy 346.551699 -252.827657)
			(xy 346.516003 -252.868846) (xy 346.474809 -252.904535) (xy 346.428954 -252.933999) (xy 346.379374 -252.956637)
			(xy 346.327076 -252.971989) (xy 346.273126 -252.979742) (xy 346.218622 -252.979738) (xy 346.164673 -252.971978)
			(xy 346.112377 -252.956619) (xy 346.0628 -252.933974) (xy 346.01695 -252.904504) (xy 345.97576 -252.868809)
			(xy 345.94007 -252.827615) (xy 345.910605 -252.781762) (xy 345.887966 -252.732181) (xy 345.872613 -252.679884)
			(xy 345.864859 -252.625934) (xy 345.864434 -252.598682) (xy 345.865704 -252.567948) (xy 345.866974 -252.551692)
			(xy 345.850972 -252.524514) (xy 345.74988 -252.477524) (xy 345.740231 -252.47361) (xy 345.719435 -252.473099)
			(xy 345.700151 -252.480898) (xy 345.692476 -252.487938) (xy 345.125294 -253.05512) (xy 350.523808 -253.05512)
			(xy 350.527879 -252.999498) (xy 350.540005 -252.945061) (xy 350.559928 -252.89297) (xy 350.587224 -252.844335)
			(xy 350.62131 -252.800192) (xy 350.661459 -252.761483) (xy 350.706817 -252.729032) (xy 350.756417 -252.703531)
			(xy 350.809201 -252.685524) (xy 350.864044 -252.675394) (xy 350.919778 -252.673357) (xy 350.975215 -252.679457)
			(xy 351.029172 -252.693563) (xy 351.080501 -252.715375) (xy 351.128107 -252.744429) (xy 351.170975 -252.780104)
			(xy 351.208192 -252.821641) (xy 351.238965 -252.868154) (xy 351.262637 -252.918651) (xy 351.278705 -252.972058)
			(xy 351.286825 -253.027234) (xy 351.287334 -253.05512) (xy 351.286825 -253.083006) (xy 351.278705 -253.138182)
			(xy 351.262637 -253.191589) (xy 351.238965 -253.242086) (xy 351.208192 -253.288599) (xy 351.170975 -253.330136)
			(xy 351.128107 -253.365811) (xy 351.091979 -253.38786) (xy 358.443274 -253.38786) (xy 358.447345 -253.332238)
			(xy 358.459471 -253.277801) (xy 358.479394 -253.22571) (xy 358.50669 -253.177075) (xy 358.540776 -253.132932)
			(xy 358.580925 -253.094223) (xy 358.626283 -253.061772) (xy 358.675883 -253.036271) (xy 358.728667 -253.018264)
			(xy 358.78351 -253.008134) (xy 358.839244 -253.006097) (xy 358.894681 -253.012197) (xy 358.948638 -253.026303)
			(xy 358.999967 -253.048115) (xy 359.047573 -253.077169) (xy 359.090441 -253.112844) (xy 359.127658 -253.154381)
			(xy 359.143657 -253.178564) (xy 360.485942 -253.178564) (xy 360.490013 -253.122942) (xy 360.502139 -253.068505)
			(xy 360.522062 -253.016414) (xy 360.549358 -252.967779) (xy 360.583444 -252.923636) (xy 360.623593 -252.884927)
			(xy 360.668951 -252.852476) (xy 360.718551 -252.826975) (xy 360.771335 -252.808968) (xy 360.826178 -252.798838)
			(xy 360.881912 -252.796801) (xy 360.937349 -252.802901) (xy 360.991306 -252.817007) (xy 361.042635 -252.838819)
			(xy 361.090241 -252.867873) (xy 361.133109 -252.903548) (xy 361.170326 -252.945085) (xy 361.201099 -252.991598)
			(xy 361.224771 -253.042095) (xy 361.240839 -253.095502) (xy 361.248959 -253.150678) (xy 361.249468 -253.178564)
			(xy 362.549438 -253.178564) (xy 362.553509 -253.122942) (xy 362.565635 -253.068505) (xy 362.585558 -253.016414)
			(xy 362.612854 -252.967779) (xy 362.64694 -252.923636) (xy 362.687089 -252.884927) (xy 362.732447 -252.852476)
			(xy 362.782047 -252.826975) (xy 362.834831 -252.808968) (xy 362.889674 -252.798838) (xy 362.945408 -252.796801)
			(xy 363.000845 -252.802901) (xy 363.054802 -252.817007) (xy 363.106131 -252.838819) (xy 363.153737 -252.867873)
			(xy 363.196605 -252.903548) (xy 363.233822 -252.945085) (xy 363.264595 -252.991598) (xy 363.288267 -253.042095)
			(xy 363.304335 -253.095502) (xy 363.312455 -253.150678) (xy 363.312964 -253.178564) (xy 363.312455 -253.20645)
			(xy 363.304335 -253.261626) (xy 363.288267 -253.315033) (xy 363.264595 -253.36553) (xy 363.233822 -253.412043)
			(xy 363.196605 -253.45358) (xy 363.193168 -253.45644) (xy 372.260366 -253.45644) (xy 372.264437 -253.400818)
			(xy 372.276563 -253.346381) (xy 372.296486 -253.29429) (xy 372.323782 -253.245655) (xy 372.357868 -253.201512)
			(xy 372.398017 -253.162803) (xy 372.443375 -253.130352) (xy 372.492975 -253.104851) (xy 372.545759 -253.086844)
			(xy 372.600602 -253.076714) (xy 372.656336 -253.074677) (xy 372.711773 -253.080777) (xy 372.76573 -253.094883)
			(xy 372.817059 -253.116695) (xy 372.864665 -253.145749) (xy 372.907533 -253.181424) (xy 372.94475 -253.222961)
			(xy 372.975523 -253.269474) (xy 372.999195 -253.319971) (xy 373.015263 -253.373378) (xy 373.023383 -253.428554)
			(xy 373.023892 -253.45644) (xy 373.276366 -253.45644) (xy 373.280437 -253.400818) (xy 373.292563 -253.346381)
			(xy 373.312486 -253.29429) (xy 373.339782 -253.245655) (xy 373.373868 -253.201512) (xy 373.414017 -253.162803)
			(xy 373.459375 -253.130352) (xy 373.508975 -253.104851) (xy 373.561759 -253.086844) (xy 373.616602 -253.076714)
			(xy 373.672336 -253.074677) (xy 373.727773 -253.080777) (xy 373.78173 -253.094883) (xy 373.833059 -253.116695)
			(xy 373.880665 -253.145749) (xy 373.923533 -253.181424) (xy 373.96075 -253.222961) (xy 373.991523 -253.269474)
			(xy 374.015195 -253.319971) (xy 374.031263 -253.373378) (xy 374.039383 -253.428554) (xy 374.039892 -253.45644)
			(xy 374.292366 -253.45644) (xy 374.296437 -253.400818) (xy 374.308563 -253.346381) (xy 374.328486 -253.29429)
			(xy 374.355782 -253.245655) (xy 374.389868 -253.201512) (xy 374.430017 -253.162803) (xy 374.475375 -253.130352)
			(xy 374.524975 -253.104851) (xy 374.577759 -253.086844) (xy 374.632602 -253.076714) (xy 374.688336 -253.074677)
			(xy 374.743773 -253.080777) (xy 374.79773 -253.094883) (xy 374.849059 -253.116695) (xy 374.896665 -253.145749)
			(xy 374.939533 -253.181424) (xy 374.97675 -253.222961) (xy 375.007523 -253.269474) (xy 375.031195 -253.319971)
			(xy 375.047263 -253.373378) (xy 375.055383 -253.428554) (xy 375.055892 -253.45644) (xy 375.308366 -253.45644)
			(xy 375.312437 -253.400818) (xy 375.324563 -253.346381) (xy 375.344486 -253.29429) (xy 375.371782 -253.245655)
			(xy 375.405868 -253.201512) (xy 375.446017 -253.162803) (xy 375.491375 -253.130352) (xy 375.540975 -253.104851)
			(xy 375.593759 -253.086844) (xy 375.648602 -253.076714) (xy 375.704336 -253.074677) (xy 375.759773 -253.080777)
			(xy 375.81373 -253.094883) (xy 375.865059 -253.116695) (xy 375.912665 -253.145749) (xy 375.955533 -253.181424)
			(xy 375.99275 -253.222961) (xy 376.023523 -253.269474) (xy 376.047195 -253.319971) (xy 376.063263 -253.373378)
			(xy 376.071383 -253.428554) (xy 376.071892 -253.45644) (xy 376.324366 -253.45644) (xy 376.328437 -253.400818)
			(xy 376.340563 -253.346381) (xy 376.360486 -253.29429) (xy 376.387782 -253.245655) (xy 376.421868 -253.201512)
			(xy 376.462017 -253.162803) (xy 376.507375 -253.130352) (xy 376.556975 -253.104851) (xy 376.609759 -253.086844)
			(xy 376.664602 -253.076714) (xy 376.720336 -253.074677) (xy 376.775773 -253.080777) (xy 376.82973 -253.094883)
			(xy 376.881059 -253.116695) (xy 376.928665 -253.145749) (xy 376.971533 -253.181424) (xy 377.00875 -253.222961)
			(xy 377.039523 -253.269474) (xy 377.063195 -253.319971) (xy 377.079263 -253.373378) (xy 377.087383 -253.428554)
			(xy 377.087892 -253.45644) (xy 377.340366 -253.45644) (xy 377.344437 -253.400818) (xy 377.356563 -253.346381)
			(xy 377.376486 -253.29429) (xy 377.403782 -253.245655) (xy 377.437868 -253.201512) (xy 377.478017 -253.162803)
			(xy 377.523375 -253.130352) (xy 377.572975 -253.104851) (xy 377.625759 -253.086844) (xy 377.680602 -253.076714)
			(xy 377.736336 -253.074677) (xy 377.791773 -253.080777) (xy 377.84573 -253.094883) (xy 377.897059 -253.116695)
			(xy 377.944665 -253.145749) (xy 377.987533 -253.181424) (xy 378.02475 -253.222961) (xy 378.055523 -253.269474)
			(xy 378.079195 -253.319971) (xy 378.095263 -253.373378) (xy 378.103383 -253.428554) (xy 378.103892 -253.45644)
			(xy 378.356366 -253.45644) (xy 378.360437 -253.400818) (xy 378.372563 -253.346381) (xy 378.392486 -253.29429)
			(xy 378.419782 -253.245655) (xy 378.453868 -253.201512) (xy 378.494017 -253.162803) (xy 378.539375 -253.130352)
			(xy 378.588975 -253.104851) (xy 378.641759 -253.086844) (xy 378.696602 -253.076714) (xy 378.752336 -253.074677)
			(xy 378.807773 -253.080777) (xy 378.86173 -253.094883) (xy 378.913059 -253.116695) (xy 378.960665 -253.145749)
			(xy 379.003533 -253.181424) (xy 379.04075 -253.222961) (xy 379.071523 -253.269474) (xy 379.095195 -253.319971)
			(xy 379.111263 -253.373378) (xy 379.119383 -253.428554) (xy 379.119892 -253.45644) (xy 379.372366 -253.45644)
			(xy 379.376437 -253.400818) (xy 379.388563 -253.346381) (xy 379.408486 -253.29429) (xy 379.435782 -253.245655)
			(xy 379.469868 -253.201512) (xy 379.510017 -253.162803) (xy 379.555375 -253.130352) (xy 379.604975 -253.104851)
			(xy 379.657759 -253.086844) (xy 379.712602 -253.076714) (xy 379.768336 -253.074677) (xy 379.823773 -253.080777)
			(xy 379.87773 -253.094883) (xy 379.929059 -253.116695) (xy 379.976665 -253.145749) (xy 380.019533 -253.181424)
			(xy 380.05675 -253.222961) (xy 380.087523 -253.269474) (xy 380.111195 -253.319971) (xy 380.127263 -253.373378)
			(xy 380.135383 -253.428554) (xy 380.135892 -253.45644) (xy 380.388366 -253.45644) (xy 380.392437 -253.400818)
			(xy 380.404563 -253.346381) (xy 380.424486 -253.29429) (xy 380.451782 -253.245655) (xy 380.485868 -253.201512)
			(xy 380.526017 -253.162803) (xy 380.571375 -253.130352) (xy 380.620975 -253.104851) (xy 380.673759 -253.086844)
			(xy 380.728602 -253.076714) (xy 380.784336 -253.074677) (xy 380.839773 -253.080777) (xy 380.89373 -253.094883)
			(xy 380.945059 -253.116695) (xy 380.992665 -253.145749) (xy 381.035533 -253.181424) (xy 381.07275 -253.222961)
			(xy 381.103523 -253.269474) (xy 381.127195 -253.319971) (xy 381.143263 -253.373378) (xy 381.151383 -253.428554)
			(xy 381.151892 -253.45644) (xy 381.404366 -253.45644) (xy 381.408437 -253.400818) (xy 381.420563 -253.346381)
			(xy 381.440486 -253.29429) (xy 381.467782 -253.245655) (xy 381.501868 -253.201512) (xy 381.542017 -253.162803)
			(xy 381.587375 -253.130352) (xy 381.636975 -253.104851) (xy 381.689759 -253.086844) (xy 381.744602 -253.076714)
			(xy 381.800336 -253.074677) (xy 381.855773 -253.080777) (xy 381.90973 -253.094883) (xy 381.961059 -253.116695)
			(xy 382.008665 -253.145749) (xy 382.051533 -253.181424) (xy 382.08875 -253.222961) (xy 382.119523 -253.269474)
			(xy 382.143195 -253.319971) (xy 382.159263 -253.373378) (xy 382.167383 -253.428554) (xy 382.167892 -253.45644)
			(xy 382.420366 -253.45644) (xy 382.424437 -253.400818) (xy 382.436563 -253.346381) (xy 382.456486 -253.29429)
			(xy 382.483782 -253.245655) (xy 382.517868 -253.201512) (xy 382.558017 -253.162803) (xy 382.603375 -253.130352)
			(xy 382.652975 -253.104851) (xy 382.705759 -253.086844) (xy 382.760602 -253.076714) (xy 382.816336 -253.074677)
			(xy 382.871773 -253.080777) (xy 382.92573 -253.094883) (xy 382.977059 -253.116695) (xy 383.024665 -253.145749)
			(xy 383.067533 -253.181424) (xy 383.10475 -253.222961) (xy 383.135523 -253.269474) (xy 383.159195 -253.319971)
			(xy 383.175263 -253.373378) (xy 383.183383 -253.428554) (xy 383.183892 -253.45644) (xy 383.436366 -253.45644)
			(xy 383.440437 -253.400818) (xy 383.452563 -253.346381) (xy 383.472486 -253.29429) (xy 383.499782 -253.245655)
			(xy 383.533868 -253.201512) (xy 383.574017 -253.162803) (xy 383.619375 -253.130352) (xy 383.668975 -253.104851)
			(xy 383.721759 -253.086844) (xy 383.776602 -253.076714) (xy 383.832336 -253.074677) (xy 383.887773 -253.080777)
			(xy 383.94173 -253.094883) (xy 383.993059 -253.116695) (xy 384.040665 -253.145749) (xy 384.083533 -253.181424)
			(xy 384.12075 -253.222961) (xy 384.151523 -253.269474) (xy 384.175195 -253.319971) (xy 384.191263 -253.373378)
			(xy 384.199383 -253.428554) (xy 384.199892 -253.45644) (xy 384.452366 -253.45644) (xy 384.456437 -253.400818)
			(xy 384.468563 -253.346381) (xy 384.488486 -253.29429) (xy 384.515782 -253.245655) (xy 384.549868 -253.201512)
			(xy 384.590017 -253.162803) (xy 384.635375 -253.130352) (xy 384.684975 -253.104851) (xy 384.737759 -253.086844)
			(xy 384.792602 -253.076714) (xy 384.848336 -253.074677) (xy 384.903773 -253.080777) (xy 384.95773 -253.094883)
			(xy 385.009059 -253.116695) (xy 385.056665 -253.145749) (xy 385.099533 -253.181424) (xy 385.13675 -253.222961)
			(xy 385.167523 -253.269474) (xy 385.191195 -253.319971) (xy 385.207263 -253.373378) (xy 385.215383 -253.428554)
			(xy 385.215892 -253.45644) (xy 385.468366 -253.45644) (xy 385.472437 -253.400818) (xy 385.484563 -253.346381)
			(xy 385.504486 -253.29429) (xy 385.531782 -253.245655) (xy 385.565868 -253.201512) (xy 385.606017 -253.162803)
			(xy 385.651375 -253.130352) (xy 385.700975 -253.104851) (xy 385.753759 -253.086844) (xy 385.808602 -253.076714)
			(xy 385.864336 -253.074677) (xy 385.919773 -253.080777) (xy 385.97373 -253.094883) (xy 386.025059 -253.116695)
			(xy 386.072665 -253.145749) (xy 386.115533 -253.181424) (xy 386.15275 -253.222961) (xy 386.183523 -253.269474)
			(xy 386.207195 -253.319971) (xy 386.223263 -253.373378) (xy 386.231383 -253.428554) (xy 386.231892 -253.45644)
			(xy 386.484366 -253.45644) (xy 386.488437 -253.400818) (xy 386.500563 -253.346381) (xy 386.520486 -253.29429)
			(xy 386.547782 -253.245655) (xy 386.581868 -253.201512) (xy 386.622017 -253.162803) (xy 386.667375 -253.130352)
			(xy 386.716975 -253.104851) (xy 386.769759 -253.086844) (xy 386.824602 -253.076714) (xy 386.880336 -253.074677)
			(xy 386.935773 -253.080777) (xy 386.98973 -253.094883) (xy 387.041059 -253.116695) (xy 387.088665 -253.145749)
			(xy 387.131533 -253.181424) (xy 387.16875 -253.222961) (xy 387.199523 -253.269474) (xy 387.223195 -253.319971)
			(xy 387.239263 -253.373378) (xy 387.247383 -253.428554) (xy 387.247892 -253.45644) (xy 387.500366 -253.45644)
			(xy 387.504437 -253.400818) (xy 387.516563 -253.346381) (xy 387.536486 -253.29429) (xy 387.563782 -253.245655)
			(xy 387.597868 -253.201512) (xy 387.638017 -253.162803) (xy 387.683375 -253.130352) (xy 387.732975 -253.104851)
			(xy 387.785759 -253.086844) (xy 387.840602 -253.076714) (xy 387.896336 -253.074677) (xy 387.951773 -253.080777)
			(xy 388.00573 -253.094883) (xy 388.057059 -253.116695) (xy 388.104665 -253.145749) (xy 388.147533 -253.181424)
			(xy 388.18475 -253.222961) (xy 388.215523 -253.269474) (xy 388.239195 -253.319971) (xy 388.255263 -253.373378)
			(xy 388.263383 -253.428554) (xy 388.263892 -253.45644) (xy 388.516366 -253.45644) (xy 388.520437 -253.400818)
			(xy 388.532563 -253.346381) (xy 388.552486 -253.29429) (xy 388.579782 -253.245655) (xy 388.613868 -253.201512)
			(xy 388.654017 -253.162803) (xy 388.699375 -253.130352) (xy 388.748975 -253.104851) (xy 388.801759 -253.086844)
			(xy 388.856602 -253.076714) (xy 388.912336 -253.074677) (xy 388.967773 -253.080777) (xy 389.02173 -253.094883)
			(xy 389.073059 -253.116695) (xy 389.120665 -253.145749) (xy 389.163533 -253.181424) (xy 389.20075 -253.222961)
			(xy 389.231523 -253.269474) (xy 389.255195 -253.319971) (xy 389.271263 -253.373378) (xy 389.279383 -253.428554)
			(xy 389.279892 -253.45644) (xy 389.279383 -253.484326) (xy 389.271263 -253.539502) (xy 389.255195 -253.592909)
			(xy 389.231523 -253.643406) (xy 389.20075 -253.689919) (xy 389.163533 -253.731456) (xy 389.120665 -253.767131)
			(xy 389.073059 -253.796185) (xy 389.02173 -253.817997) (xy 388.967773 -253.832103) (xy 388.912336 -253.838203)
			(xy 388.856602 -253.836166) (xy 388.801759 -253.826036) (xy 388.748975 -253.808029) (xy 388.699375 -253.782528)
			(xy 388.654017 -253.750077) (xy 388.613868 -253.711368) (xy 388.579782 -253.667225) (xy 388.552486 -253.61859)
			(xy 388.532563 -253.566499) (xy 388.520437 -253.512062) (xy 388.516366 -253.45644) (xy 388.263892 -253.45644)
			(xy 388.263383 -253.484326) (xy 388.255263 -253.539502) (xy 388.239195 -253.592909) (xy 388.215523 -253.643406)
			(xy 388.18475 -253.689919) (xy 388.147533 -253.731456) (xy 388.104665 -253.767131) (xy 388.057059 -253.796185)
			(xy 388.00573 -253.817997) (xy 387.951773 -253.832103) (xy 387.896336 -253.838203) (xy 387.840602 -253.836166)
			(xy 387.785759 -253.826036) (xy 387.732975 -253.808029) (xy 387.683375 -253.782528) (xy 387.638017 -253.750077)
			(xy 387.597868 -253.711368) (xy 387.563782 -253.667225) (xy 387.536486 -253.61859) (xy 387.516563 -253.566499)
			(xy 387.504437 -253.512062) (xy 387.500366 -253.45644) (xy 387.247892 -253.45644) (xy 387.247383 -253.484326)
			(xy 387.239263 -253.539502) (xy 387.223195 -253.592909) (xy 387.199523 -253.643406) (xy 387.16875 -253.689919)
			(xy 387.131533 -253.731456) (xy 387.088665 -253.767131) (xy 387.041059 -253.796185) (xy 386.98973 -253.817997)
			(xy 386.935773 -253.832103) (xy 386.880336 -253.838203) (xy 386.824602 -253.836166) (xy 386.769759 -253.826036)
			(xy 386.716975 -253.808029) (xy 386.667375 -253.782528) (xy 386.622017 -253.750077) (xy 386.581868 -253.711368)
			(xy 386.547782 -253.667225) (xy 386.520486 -253.61859) (xy 386.500563 -253.566499) (xy 386.488437 -253.512062)
			(xy 386.484366 -253.45644) (xy 386.231892 -253.45644) (xy 386.231383 -253.484326) (xy 386.223263 -253.539502)
			(xy 386.207195 -253.592909) (xy 386.183523 -253.643406) (xy 386.15275 -253.689919) (xy 386.115533 -253.731456)
			(xy 386.072665 -253.767131) (xy 386.025059 -253.796185) (xy 385.97373 -253.817997) (xy 385.919773 -253.832103)
			(xy 385.864336 -253.838203) (xy 385.808602 -253.836166) (xy 385.753759 -253.826036) (xy 385.700975 -253.808029)
			(xy 385.651375 -253.782528) (xy 385.606017 -253.750077) (xy 385.565868 -253.711368) (xy 385.531782 -253.667225)
			(xy 385.504486 -253.61859) (xy 385.484563 -253.566499) (xy 385.472437 -253.512062) (xy 385.468366 -253.45644)
			(xy 385.215892 -253.45644) (xy 385.215383 -253.484326) (xy 385.207263 -253.539502) (xy 385.191195 -253.592909)
			(xy 385.167523 -253.643406) (xy 385.13675 -253.689919) (xy 385.099533 -253.731456) (xy 385.056665 -253.767131)
			(xy 385.009059 -253.796185) (xy 384.95773 -253.817997) (xy 384.903773 -253.832103) (xy 384.848336 -253.838203)
			(xy 384.792602 -253.836166) (xy 384.737759 -253.826036) (xy 384.684975 -253.808029) (xy 384.635375 -253.782528)
			(xy 384.590017 -253.750077) (xy 384.549868 -253.711368) (xy 384.515782 -253.667225) (xy 384.488486 -253.61859)
			(xy 384.468563 -253.566499) (xy 384.456437 -253.512062) (xy 384.452366 -253.45644) (xy 384.199892 -253.45644)
			(xy 384.199383 -253.484326) (xy 384.191263 -253.539502) (xy 384.175195 -253.592909) (xy 384.151523 -253.643406)
			(xy 384.12075 -253.689919) (xy 384.083533 -253.731456) (xy 384.040665 -253.767131) (xy 383.993059 -253.796185)
			(xy 383.94173 -253.817997) (xy 383.887773 -253.832103) (xy 383.832336 -253.838203) (xy 383.776602 -253.836166)
			(xy 383.721759 -253.826036) (xy 383.668975 -253.808029) (xy 383.619375 -253.782528) (xy 383.574017 -253.750077)
			(xy 383.533868 -253.711368) (xy 383.499782 -253.667225) (xy 383.472486 -253.61859) (xy 383.452563 -253.566499)
			(xy 383.440437 -253.512062) (xy 383.436366 -253.45644) (xy 383.183892 -253.45644) (xy 383.183383 -253.484326)
			(xy 383.175263 -253.539502) (xy 383.159195 -253.592909) (xy 383.135523 -253.643406) (xy 383.10475 -253.689919)
			(xy 383.067533 -253.731456) (xy 383.024665 -253.767131) (xy 382.977059 -253.796185) (xy 382.92573 -253.817997)
			(xy 382.871773 -253.832103) (xy 382.816336 -253.838203) (xy 382.760602 -253.836166) (xy 382.705759 -253.826036)
			(xy 382.652975 -253.808029) (xy 382.603375 -253.782528) (xy 382.558017 -253.750077) (xy 382.517868 -253.711368)
			(xy 382.483782 -253.667225) (xy 382.456486 -253.61859) (xy 382.436563 -253.566499) (xy 382.424437 -253.512062)
			(xy 382.420366 -253.45644) (xy 382.167892 -253.45644) (xy 382.167383 -253.484326) (xy 382.159263 -253.539502)
			(xy 382.143195 -253.592909) (xy 382.119523 -253.643406) (xy 382.08875 -253.689919) (xy 382.051533 -253.731456)
			(xy 382.008665 -253.767131) (xy 381.961059 -253.796185) (xy 381.90973 -253.817997) (xy 381.855773 -253.832103)
			(xy 381.800336 -253.838203) (xy 381.744602 -253.836166) (xy 381.689759 -253.826036) (xy 381.636975 -253.808029)
			(xy 381.587375 -253.782528) (xy 381.542017 -253.750077) (xy 381.501868 -253.711368) (xy 381.467782 -253.667225)
			(xy 381.440486 -253.61859) (xy 381.420563 -253.566499) (xy 381.408437 -253.512062) (xy 381.404366 -253.45644)
			(xy 381.151892 -253.45644) (xy 381.151383 -253.484326) (xy 381.143263 -253.539502) (xy 381.127195 -253.592909)
			(xy 381.103523 -253.643406) (xy 381.07275 -253.689919) (xy 381.035533 -253.731456) (xy 380.992665 -253.767131)
			(xy 380.945059 -253.796185) (xy 380.89373 -253.817997) (xy 380.839773 -253.832103) (xy 380.784336 -253.838203)
			(xy 380.728602 -253.836166) (xy 380.673759 -253.826036) (xy 380.620975 -253.808029) (xy 380.571375 -253.782528)
			(xy 380.526017 -253.750077) (xy 380.485868 -253.711368) (xy 380.451782 -253.667225) (xy 380.424486 -253.61859)
			(xy 380.404563 -253.566499) (xy 380.392437 -253.512062) (xy 380.388366 -253.45644) (xy 380.135892 -253.45644)
			(xy 380.135383 -253.484326) (xy 380.127263 -253.539502) (xy 380.111195 -253.592909) (xy 380.087523 -253.643406)
			(xy 380.05675 -253.689919) (xy 380.019533 -253.731456) (xy 379.976665 -253.767131) (xy 379.929059 -253.796185)
			(xy 379.87773 -253.817997) (xy 379.823773 -253.832103) (xy 379.768336 -253.838203) (xy 379.712602 -253.836166)
			(xy 379.657759 -253.826036) (xy 379.604975 -253.808029) (xy 379.555375 -253.782528) (xy 379.510017 -253.750077)
			(xy 379.469868 -253.711368) (xy 379.435782 -253.667225) (xy 379.408486 -253.61859) (xy 379.388563 -253.566499)
			(xy 379.376437 -253.512062) (xy 379.372366 -253.45644) (xy 379.119892 -253.45644) (xy 379.119383 -253.484326)
			(xy 379.111263 -253.539502) (xy 379.095195 -253.592909) (xy 379.071523 -253.643406) (xy 379.04075 -253.689919)
			(xy 379.003533 -253.731456) (xy 378.960665 -253.767131) (xy 378.913059 -253.796185) (xy 378.86173 -253.817997)
			(xy 378.807773 -253.832103) (xy 378.752336 -253.838203) (xy 378.696602 -253.836166) (xy 378.641759 -253.826036)
			(xy 378.588975 -253.808029) (xy 378.539375 -253.782528) (xy 378.494017 -253.750077) (xy 378.453868 -253.711368)
			(xy 378.419782 -253.667225) (xy 378.392486 -253.61859) (xy 378.372563 -253.566499) (xy 378.360437 -253.512062)
			(xy 378.356366 -253.45644) (xy 378.103892 -253.45644) (xy 378.103383 -253.484326) (xy 378.095263 -253.539502)
			(xy 378.079195 -253.592909) (xy 378.055523 -253.643406) (xy 378.02475 -253.689919) (xy 377.987533 -253.731456)
			(xy 377.944665 -253.767131) (xy 377.897059 -253.796185) (xy 377.84573 -253.817997) (xy 377.791773 -253.832103)
			(xy 377.736336 -253.838203) (xy 377.680602 -253.836166) (xy 377.625759 -253.826036) (xy 377.572975 -253.808029)
			(xy 377.523375 -253.782528) (xy 377.478017 -253.750077) (xy 377.437868 -253.711368) (xy 377.403782 -253.667225)
			(xy 377.376486 -253.61859) (xy 377.356563 -253.566499) (xy 377.344437 -253.512062) (xy 377.340366 -253.45644)
			(xy 377.087892 -253.45644) (xy 377.087383 -253.484326) (xy 377.079263 -253.539502) (xy 377.063195 -253.592909)
			(xy 377.039523 -253.643406) (xy 377.00875 -253.689919) (xy 376.971533 -253.731456) (xy 376.928665 -253.767131)
			(xy 376.881059 -253.796185) (xy 376.82973 -253.817997) (xy 376.775773 -253.832103) (xy 376.720336 -253.838203)
			(xy 376.664602 -253.836166) (xy 376.609759 -253.826036) (xy 376.556975 -253.808029) (xy 376.507375 -253.782528)
			(xy 376.462017 -253.750077) (xy 376.421868 -253.711368) (xy 376.387782 -253.667225) (xy 376.360486 -253.61859)
			(xy 376.340563 -253.566499) (xy 376.328437 -253.512062) (xy 376.324366 -253.45644) (xy 376.071892 -253.45644)
			(xy 376.071383 -253.484326) (xy 376.063263 -253.539502) (xy 376.047195 -253.592909) (xy 376.023523 -253.643406)
			(xy 375.99275 -253.689919) (xy 375.955533 -253.731456) (xy 375.912665 -253.767131) (xy 375.865059 -253.796185)
			(xy 375.81373 -253.817997) (xy 375.759773 -253.832103) (xy 375.704336 -253.838203) (xy 375.648602 -253.836166)
			(xy 375.593759 -253.826036) (xy 375.540975 -253.808029) (xy 375.491375 -253.782528) (xy 375.446017 -253.750077)
			(xy 375.405868 -253.711368) (xy 375.371782 -253.667225) (xy 375.344486 -253.61859) (xy 375.324563 -253.566499)
			(xy 375.312437 -253.512062) (xy 375.308366 -253.45644) (xy 375.055892 -253.45644) (xy 375.055383 -253.484326)
			(xy 375.047263 -253.539502) (xy 375.031195 -253.592909) (xy 375.007523 -253.643406) (xy 374.97675 -253.689919)
			(xy 374.939533 -253.731456) (xy 374.896665 -253.767131) (xy 374.849059 -253.796185) (xy 374.79773 -253.817997)
			(xy 374.743773 -253.832103) (xy 374.688336 -253.838203) (xy 374.632602 -253.836166) (xy 374.577759 -253.826036)
			(xy 374.524975 -253.808029) (xy 374.475375 -253.782528) (xy 374.430017 -253.750077) (xy 374.389868 -253.711368)
			(xy 374.355782 -253.667225) (xy 374.328486 -253.61859) (xy 374.308563 -253.566499) (xy 374.296437 -253.512062)
			(xy 374.292366 -253.45644) (xy 374.039892 -253.45644) (xy 374.039383 -253.484326) (xy 374.031263 -253.539502)
			(xy 374.015195 -253.592909) (xy 373.991523 -253.643406) (xy 373.96075 -253.689919) (xy 373.923533 -253.731456)
			(xy 373.880665 -253.767131) (xy 373.833059 -253.796185) (xy 373.78173 -253.817997) (xy 373.727773 -253.832103)
			(xy 373.672336 -253.838203) (xy 373.616602 -253.836166) (xy 373.561759 -253.826036) (xy 373.508975 -253.808029)
			(xy 373.459375 -253.782528) (xy 373.414017 -253.750077) (xy 373.373868 -253.711368) (xy 373.339782 -253.667225)
			(xy 373.312486 -253.61859) (xy 373.292563 -253.566499) (xy 373.280437 -253.512062) (xy 373.276366 -253.45644)
			(xy 373.023892 -253.45644) (xy 373.023383 -253.484326) (xy 373.015263 -253.539502) (xy 372.999195 -253.592909)
			(xy 372.975523 -253.643406) (xy 372.94475 -253.689919) (xy 372.907533 -253.731456) (xy 372.864665 -253.767131)
			(xy 372.817059 -253.796185) (xy 372.76573 -253.817997) (xy 372.711773 -253.832103) (xy 372.656336 -253.838203)
			(xy 372.600602 -253.836166) (xy 372.545759 -253.826036) (xy 372.492975 -253.808029) (xy 372.443375 -253.782528)
			(xy 372.398017 -253.750077) (xy 372.357868 -253.711368) (xy 372.323782 -253.667225) (xy 372.296486 -253.61859)
			(xy 372.276563 -253.566499) (xy 372.264437 -253.512062) (xy 372.260366 -253.45644) (xy 363.193168 -253.45644)
			(xy 363.153737 -253.489255) (xy 363.106131 -253.518309) (xy 363.054802 -253.540121) (xy 363.000845 -253.554227)
			(xy 362.945408 -253.560327) (xy 362.889674 -253.55829) (xy 362.834831 -253.54816) (xy 362.782047 -253.530153)
			(xy 362.732447 -253.504652) (xy 362.687089 -253.472201) (xy 362.64694 -253.433492) (xy 362.612854 -253.389349)
			(xy 362.585558 -253.340714) (xy 362.565635 -253.288623) (xy 362.553509 -253.234186) (xy 362.549438 -253.178564)
			(xy 361.249468 -253.178564) (xy 361.248959 -253.20645) (xy 361.240839 -253.261626) (xy 361.224771 -253.315033)
			(xy 361.201099 -253.36553) (xy 361.170326 -253.412043) (xy 361.133109 -253.45358) (xy 361.090241 -253.489255)
			(xy 361.042635 -253.518309) (xy 360.991306 -253.540121) (xy 360.937349 -253.554227) (xy 360.881912 -253.560327)
			(xy 360.826178 -253.55829) (xy 360.771335 -253.54816) (xy 360.718551 -253.530153) (xy 360.668951 -253.504652)
			(xy 360.623593 -253.472201) (xy 360.583444 -253.433492) (xy 360.549358 -253.389349) (xy 360.522062 -253.340714)
			(xy 360.502139 -253.288623) (xy 360.490013 -253.234186) (xy 360.485942 -253.178564) (xy 359.143657 -253.178564)
			(xy 359.158431 -253.200894) (xy 359.182103 -253.251391) (xy 359.198171 -253.304798) (xy 359.206291 -253.359974)
			(xy 359.2068 -253.38786) (xy 359.206291 -253.415746) (xy 359.198171 -253.470922) (xy 359.182103 -253.524329)
			(xy 359.158431 -253.574826) (xy 359.127658 -253.621339) (xy 359.090441 -253.662876) (xy 359.047573 -253.698551)
			(xy 358.999967 -253.727605) (xy 358.948638 -253.749417) (xy 358.894681 -253.763523) (xy 358.839244 -253.769623)
			(xy 358.78351 -253.767586) (xy 358.728667 -253.757456) (xy 358.675883 -253.739449) (xy 358.626283 -253.713948)
			(xy 358.580925 -253.681497) (xy 358.540776 -253.642788) (xy 358.50669 -253.598645) (xy 358.479394 -253.55001)
			(xy 358.459471 -253.497919) (xy 358.447345 -253.443482) (xy 358.443274 -253.38786) (xy 351.091979 -253.38786)
			(xy 351.080501 -253.394865) (xy 351.029172 -253.416677) (xy 350.975215 -253.430783) (xy 350.919778 -253.436883)
			(xy 350.864044 -253.434846) (xy 350.809201 -253.424716) (xy 350.756417 -253.406709) (xy 350.706817 -253.381208)
			(xy 350.661459 -253.348757) (xy 350.62131 -253.310048) (xy 350.587224 -253.265905) (xy 350.559928 -253.21727)
			(xy 350.540005 -253.165179) (xy 350.527879 -253.110742) (xy 350.523808 -253.05512) (xy 345.125294 -253.05512)
			(xy 343.935962 -254.244452) (xy 346.050848 -254.244452) (xy 346.050848 -254.189948) (xy 346.058604 -254.135999)
			(xy 346.073959 -254.083702) (xy 346.0966 -254.034123) (xy 346.126065 -253.98827) (xy 346.161757 -253.947078)
			(xy 346.202946 -253.911383) (xy 346.248797 -253.881914) (xy 346.298374 -253.859269) (xy 346.350669 -253.84391)
			(xy 346.404618 -253.83615) (xy 346.43187 -253.835662) (xy 346.460027 -253.836189) (xy 346.515728 -253.844484)
			(xy 346.569602 -253.860883) (xy 346.620477 -253.885029) (xy 346.667247 -253.916396) (xy 346.68841 -253.934976)
			(xy 346.695776 -253.94158) (xy 346.713302 -253.948184) (xy 346.802202 -253.947168) (xy 346.819728 -253.940056)
			(xy 346.82684 -253.933452) (xy 346.848201 -253.9139) (xy 346.89576 -253.880865) (xy 346.947767 -253.855401)
			(xy 347.003027 -253.838093) (xy 347.060269 -253.829341) (xy 347.089222 -253.828804) (xy 347.116474 -253.829257)
			(xy 347.170424 -253.837017) (xy 347.22272 -253.852376) (xy 347.272298 -253.87502) (xy 347.318149 -253.90449)
			(xy 347.359339 -253.940185) (xy 347.39503 -253.981378) (xy 347.424496 -254.027232) (xy 347.447136 -254.076812)
			(xy 347.46249 -254.129109) (xy 347.465327 -254.148844) (xy 349.868234 -254.148844) (xy 349.872305 -254.093222)
			(xy 349.884431 -254.038785) (xy 349.904354 -253.986694) (xy 349.93165 -253.938059) (xy 349.965736 -253.893916)
			(xy 350.005885 -253.855207) (xy 350.051243 -253.822756) (xy 350.100843 -253.797255) (xy 350.153627 -253.779248)
			(xy 350.20847 -253.769118) (xy 350.264204 -253.767081) (xy 350.319641 -253.773181) (xy 350.373598 -253.787287)
			(xy 350.424927 -253.809099) (xy 350.472533 -253.838153) (xy 350.515401 -253.873828) (xy 350.552618 -253.915365)
			(xy 350.583391 -253.961878) (xy 350.594237 -253.985014) (xy 353.918772 -253.985014) (xy 353.922843 -253.929392)
			(xy 353.934969 -253.874955) (xy 353.954892 -253.822864) (xy 353.982188 -253.774229) (xy 354.016274 -253.730086)
			(xy 354.056423 -253.691377) (xy 354.101781 -253.658926) (xy 354.151381 -253.633425) (xy 354.204165 -253.615418)
			(xy 354.259008 -253.605288) (xy 354.314742 -253.603251) (xy 354.370179 -253.609351) (xy 354.424136 -253.623457)
			(xy 354.475465 -253.645269) (xy 354.523071 -253.674323) (xy 354.565939 -253.709998) (xy 354.603156 -253.751535)
			(xy 354.633929 -253.798048) (xy 354.657601 -253.848545) (xy 354.673669 -253.901952) (xy 354.681789 -253.957128)
			(xy 354.682298 -253.985014) (xy 354.681789 -254.0129) (xy 354.673669 -254.068076) (xy 354.657601 -254.121483)
			(xy 354.633929 -254.17198) (xy 354.618987 -254.194564) (xy 360.485942 -254.194564) (xy 360.490013 -254.138942)
			(xy 360.502139 -254.084505) (xy 360.522062 -254.032414) (xy 360.549358 -253.983779) (xy 360.583444 -253.939636)
			(xy 360.623593 -253.900927) (xy 360.668951 -253.868476) (xy 360.718551 -253.842975) (xy 360.771335 -253.824968)
			(xy 360.826178 -253.814838) (xy 360.881912 -253.812801) (xy 360.937349 -253.818901) (xy 360.991306 -253.833007)
			(xy 361.042635 -253.854819) (xy 361.090241 -253.883873) (xy 361.133109 -253.919548) (xy 361.170326 -253.961085)
			(xy 361.201099 -254.007598) (xy 361.224771 -254.058095) (xy 361.240839 -254.111502) (xy 361.248959 -254.166678)
			(xy 361.249468 -254.194564) (xy 362.517942 -254.194564) (xy 362.522013 -254.138942) (xy 362.534139 -254.084505)
			(xy 362.554062 -254.032414) (xy 362.581358 -253.983779) (xy 362.615444 -253.939636) (xy 362.655593 -253.900927)
			(xy 362.700951 -253.868476) (xy 362.750551 -253.842975) (xy 362.803335 -253.824968) (xy 362.858178 -253.814838)
			(xy 362.913912 -253.812801) (xy 362.969349 -253.818901) (xy 363.023306 -253.833007) (xy 363.074635 -253.854819)
			(xy 363.122241 -253.883873) (xy 363.165109 -253.919548) (xy 363.202326 -253.961085) (xy 363.233099 -254.007598)
			(xy 363.256771 -254.058095) (xy 363.272839 -254.111502) (xy 363.280959 -254.166678) (xy 363.281468 -254.194564)
			(xy 363.280959 -254.22245) (xy 363.272839 -254.277626) (xy 363.256771 -254.331033) (xy 363.233099 -254.38153)
			(xy 363.202326 -254.428043) (xy 363.165109 -254.46958) (xy 363.122241 -254.505255) (xy 363.074635 -254.534309)
			(xy 363.023306 -254.556121) (xy 362.969349 -254.570227) (xy 362.913912 -254.576327) (xy 362.858178 -254.57429)
			(xy 362.803335 -254.56416) (xy 362.750551 -254.546153) (xy 362.700951 -254.520652) (xy 362.655593 -254.488201)
			(xy 362.615444 -254.449492) (xy 362.581358 -254.405349) (xy 362.554062 -254.356714) (xy 362.534139 -254.304623)
			(xy 362.522013 -254.250186) (xy 362.517942 -254.194564) (xy 361.249468 -254.194564) (xy 361.248959 -254.22245)
			(xy 361.240839 -254.277626) (xy 361.224771 -254.331033) (xy 361.201099 -254.38153) (xy 361.170326 -254.428043)
			(xy 361.133109 -254.46958) (xy 361.090241 -254.505255) (xy 361.042635 -254.534309) (xy 360.991306 -254.556121)
			(xy 360.937349 -254.570227) (xy 360.881912 -254.576327) (xy 360.826178 -254.57429) (xy 360.771335 -254.56416)
			(xy 360.718551 -254.546153) (xy 360.668951 -254.520652) (xy 360.623593 -254.488201) (xy 360.583444 -254.449492)
			(xy 360.549358 -254.405349) (xy 360.522062 -254.356714) (xy 360.502139 -254.304623) (xy 360.490013 -254.250186)
			(xy 360.485942 -254.194564) (xy 354.618987 -254.194564) (xy 354.603156 -254.218493) (xy 354.565939 -254.26003)
			(xy 354.523071 -254.295705) (xy 354.475465 -254.324759) (xy 354.424136 -254.346571) (xy 354.370179 -254.360677)
			(xy 354.314742 -254.366777) (xy 354.259008 -254.36474) (xy 354.204165 -254.35461) (xy 354.151381 -254.336603)
			(xy 354.101781 -254.311102) (xy 354.056423 -254.278651) (xy 354.016274 -254.239942) (xy 353.982188 -254.195799)
			(xy 353.954892 -254.147164) (xy 353.934969 -254.095073) (xy 353.922843 -254.040636) (xy 353.918772 -253.985014)
			(xy 350.594237 -253.985014) (xy 350.607063 -254.012375) (xy 350.623131 -254.065782) (xy 350.631251 -254.120958)
			(xy 350.63176 -254.148844) (xy 350.631251 -254.17673) (xy 350.623131 -254.231906) (xy 350.607063 -254.285313)
			(xy 350.583391 -254.33581) (xy 350.552618 -254.382323) (xy 350.515401 -254.42386) (xy 350.472533 -254.459535)
			(xy 350.424927 -254.488589) (xy 350.373598 -254.510401) (xy 350.319641 -254.524507) (xy 350.264204 -254.530607)
			(xy 350.20847 -254.52857) (xy 350.153627 -254.51844) (xy 350.100843 -254.500433) (xy 350.051243 -254.474932)
			(xy 350.005885 -254.442481) (xy 349.965736 -254.403772) (xy 349.93165 -254.359629) (xy 349.904354 -254.310994)
			(xy 349.884431 -254.258903) (xy 349.872305 -254.204466) (xy 349.868234 -254.148844) (xy 347.465327 -254.148844)
			(xy 347.470245 -254.18306) (xy 347.47073 -254.210312) (xy 347.470152 -254.240498) (xy 347.460597 -254.30011)
			(xy 347.441791 -254.35748) (xy 347.414201 -254.411179) (xy 347.396816 -254.435864) (xy 347.389704 -254.44577)
			(xy 347.38564 -254.4699) (xy 347.41866 -254.571754) (xy 347.435932 -254.588772) (xy 347.447616 -254.592582)
			(xy 347.475707 -254.602283) (xy 347.516875 -254.623062) (xy 374.28373 -254.623062) (xy 374.287801 -254.56744)
			(xy 374.299927 -254.513003) (xy 374.31985 -254.460912) (xy 374.347146 -254.412277) (xy 374.381232 -254.368134)
			(xy 374.421381 -254.329425) (xy 374.466739 -254.296974) (xy 374.516339 -254.271473) (xy 374.569123 -254.253466)
			(xy 374.623966 -254.243336) (xy 374.6797 -254.241299) (xy 374.735137 -254.247399) (xy 374.789094 -254.261505)
			(xy 374.840423 -254.283317) (xy 374.888029 -254.312371) (xy 374.930897 -254.348046) (xy 374.968114 -254.389583)
			(xy 374.998887 -254.436096) (xy 375.022559 -254.486593) (xy 375.038627 -254.54) (xy 375.046747 -254.595176)
			(xy 375.047256 -254.623062) (xy 376.181872 -254.623062) (xy 376.185943 -254.56744) (xy 376.198069 -254.513003)
			(xy 376.217992 -254.460912) (xy 376.245288 -254.412277) (xy 376.279374 -254.368134) (xy 376.319523 -254.329425)
			(xy 376.364881 -254.296974) (xy 376.414481 -254.271473) (xy 376.467265 -254.253466) (xy 376.522108 -254.243336)
			(xy 376.577842 -254.241299) (xy 376.633279 -254.247399) (xy 376.687236 -254.261505) (xy 376.738565 -254.283317)
			(xy 376.786171 -254.312371) (xy 376.829039 -254.348046) (xy 376.866256 -254.389583) (xy 376.897029 -254.436096)
			(xy 376.920701 -254.486593) (xy 376.930657 -254.519684) (xy 377.383546 -254.519684) (xy 377.387617 -254.464062)
			(xy 377.399743 -254.409625) (xy 377.419666 -254.357534) (xy 377.446962 -254.308899) (xy 377.481048 -254.264756)
			(xy 377.521197 -254.226047) (xy 377.566555 -254.193596) (xy 377.616155 -254.168095) (xy 377.668939 -254.150088)
			(xy 377.723782 -254.139958) (xy 377.779516 -254.137921) (xy 377.834953 -254.144021) (xy 377.88891 -254.158127)
			(xy 377.940239 -254.179939) (xy 377.987845 -254.208993) (xy 378.030713 -254.244668) (xy 378.06793 -254.286205)
			(xy 378.098703 -254.332718) (xy 378.122375 -254.383215) (xy 378.138443 -254.436622) (xy 378.146563 -254.491798)
			(xy 378.147072 -254.519684) (xy 378.146563 -254.54757) (xy 378.138443 -254.602746) (xy 378.122375 -254.656153)
			(xy 378.098703 -254.70665) (xy 378.06793 -254.753163) (xy 378.030713 -254.7947) (xy 377.987845 -254.830375)
			(xy 377.940239 -254.859429) (xy 377.88891 -254.881241) (xy 377.834953 -254.895347) (xy 377.779516 -254.901447)
			(xy 377.723782 -254.89941) (xy 377.668939 -254.88928) (xy 377.616155 -254.871273) (xy 377.566555 -254.845772)
			(xy 377.521197 -254.813321) (xy 377.481048 -254.774612) (xy 377.446962 -254.730469) (xy 377.419666 -254.681834)
			(xy 377.399743 -254.629743) (xy 377.387617 -254.575306) (xy 377.383546 -254.519684) (xy 376.930657 -254.519684)
			(xy 376.936769 -254.54) (xy 376.944889 -254.595176) (xy 376.945398 -254.623062) (xy 376.944889 -254.650948)
			(xy 376.936769 -254.706124) (xy 376.920701 -254.759531) (xy 376.897029 -254.810028) (xy 376.866256 -254.856541)
			(xy 376.829039 -254.898078) (xy 376.786171 -254.933753) (xy 376.738565 -254.962807) (xy 376.687236 -254.984619)
			(xy 376.633279 -254.998725) (xy 376.577842 -255.004825) (xy 376.522108 -255.002788) (xy 376.467265 -254.992658)
			(xy 376.414481 -254.974651) (xy 376.364881 -254.94915) (xy 376.319523 -254.916699) (xy 376.279374 -254.87799)
			(xy 376.245288 -254.833847) (xy 376.217992 -254.785212) (xy 376.198069 -254.733121) (xy 376.185943 -254.678684)
			(xy 376.181872 -254.623062) (xy 375.047256 -254.623062) (xy 375.046747 -254.650948) (xy 375.038627 -254.706124)
			(xy 375.022559 -254.759531) (xy 374.998887 -254.810028) (xy 374.968114 -254.856541) (xy 374.930897 -254.898078)
			(xy 374.888029 -254.933753) (xy 374.840423 -254.962807) (xy 374.789094 -254.984619) (xy 374.735137 -254.998725)
			(xy 374.6797 -255.004825) (xy 374.623966 -255.002788) (xy 374.569123 -254.992658) (xy 374.516339 -254.974651)
			(xy 374.466739 -254.94915) (xy 374.421381 -254.916699) (xy 374.381232 -254.87799) (xy 374.347146 -254.833847)
			(xy 374.31985 -254.785212) (xy 374.299927 -254.733121) (xy 374.287801 -254.678684) (xy 374.28373 -254.623062)
			(xy 347.516875 -254.623062) (xy 347.528758 -254.62906) (xy 347.57702 -254.663731) (xy 347.61933 -254.70546)
			(xy 347.654665 -254.753238) (xy 347.682174 -254.805913) (xy 347.692218 -254.833882) (xy 347.696282 -254.84582)
			(xy 347.713554 -254.862584) (xy 347.815662 -254.894588) (xy 347.839284 -254.890524) (xy 347.849444 -254.882904)
			(xy 347.874308 -254.865095) (xy 347.928538 -254.836823) (xy 347.986583 -254.817565) (xy 348.046958 -254.807814)
			(xy 348.077536 -254.807212) (xy 348.104139 -254.807704) (xy 348.15683 -254.815077) (xy 348.207985 -254.829704)
			(xy 348.25661 -254.851299) (xy 348.301761 -254.879444) (xy 348.342561 -254.913592) (xy 348.378218 -254.95308)
			(xy 348.393512 -254.974852) (xy 348.400988 -254.984826) (xy 348.422973 -254.996525) (xy 348.435422 -254.997204)
			(xy 348.51975 -254.997204) (xy 348.532201 -254.996536) (xy 348.554178 -254.984825) (xy 348.56166 -254.974852)
			(xy 348.576972 -254.953094) (xy 348.612635 -254.913614) (xy 348.653435 -254.87947) (xy 348.698582 -254.851322)
			(xy 348.747201 -254.829718) (xy 348.798349 -254.815075) (xy 348.851035 -254.807677) (xy 348.877636 -254.807212)
			(xy 348.904887 -254.80766) (xy 348.958834 -254.815421) (xy 349.011127 -254.83078) (xy 349.060702 -254.853425)
			(xy 349.10655 -254.882894) (xy 349.147738 -254.918587) (xy 349.183428 -254.959778) (xy 349.212892 -255.00563)
			(xy 349.235532 -255.055207) (xy 349.250886 -255.107502) (xy 349.251425 -255.11125) (xy 353.193856 -255.11125)
			(xy 353.197927 -255.055628) (xy 353.210053 -255.001191) (xy 353.229976 -254.9491) (xy 353.257272 -254.900465)
			(xy 353.291358 -254.856322) (xy 353.331507 -254.817613) (xy 353.376865 -254.785162) (xy 353.426465 -254.759661)
			(xy 353.479249 -254.741654) (xy 353.534092 -254.731524) (xy 353.589826 -254.729487) (xy 353.645263 -254.735587)
			(xy 353.69922 -254.749693) (xy 353.750549 -254.771505) (xy 353.798155 -254.800559) (xy 353.841023 -254.836234)
			(xy 353.87824 -254.877771) (xy 353.909013 -254.924284) (xy 353.932685 -254.974781) (xy 353.948753 -255.028188)
			(xy 353.956873 -255.083364) (xy 353.957382 -255.11125) (xy 353.956873 -255.139136) (xy 353.948753 -255.194312)
			(xy 353.943863 -255.210564) (xy 360.485942 -255.210564) (xy 360.490013 -255.154942) (xy 360.502139 -255.100505)
			(xy 360.522062 -255.048414) (xy 360.549358 -254.999779) (xy 360.583444 -254.955636) (xy 360.623593 -254.916927)
			(xy 360.668951 -254.884476) (xy 360.718551 -254.858975) (xy 360.771335 -254.840968) (xy 360.826178 -254.830838)
			(xy 360.881912 -254.828801) (xy 360.937349 -254.834901) (xy 360.991306 -254.849007) (xy 361.042635 -254.870819)
			(xy 361.090241 -254.899873) (xy 361.133109 -254.935548) (xy 361.170326 -254.977085) (xy 361.201099 -255.023598)
			(xy 361.224771 -255.074095) (xy 361.240839 -255.127502) (xy 361.248959 -255.182678) (xy 361.249468 -255.210564)
			(xy 361.248959 -255.23845) (xy 361.240839 -255.293626) (xy 361.224771 -255.347033) (xy 361.217303 -255.362964)
			(xy 364.277908 -255.362964) (xy 364.281979 -255.307342) (xy 364.294105 -255.252905) (xy 364.314028 -255.200814)
			(xy 364.341324 -255.152179) (xy 364.37541 -255.108036) (xy 364.415559 -255.069327) (xy 364.460917 -255.036876)
			(xy 364.510517 -255.011375) (xy 364.563301 -254.993368) (xy 364.618144 -254.983238) (xy 364.673878 -254.981201)
			(xy 364.729315 -254.987301) (xy 364.783272 -255.001407) (xy 364.834601 -255.023219) (xy 364.882207 -255.052273)
			(xy 364.925075 -255.087948) (xy 364.962292 -255.129485) (xy 364.993065 -255.175998) (xy 365.015222 -255.223264)
			(xy 378.137672 -255.223264) (xy 378.141743 -255.167642) (xy 378.153869 -255.113205) (xy 378.173792 -255.061114)
			(xy 378.201088 -255.012479) (xy 378.235174 -254.968336) (xy 378.275323 -254.929627) (xy 378.320681 -254.897176)
			(xy 378.370281 -254.871675) (xy 378.423065 -254.853668) (xy 378.477908 -254.843538) (xy 378.533642 -254.841501)
			(xy 378.589079 -254.847601) (xy 378.643036 -254.861707) (xy 378.694365 -254.883519) (xy 378.741971 -254.912573)
			(xy 378.784839 -254.948248) (xy 378.822056 -254.989785) (xy 378.852829 -255.036298) (xy 378.876501 -255.086795)
			(xy 378.892569 -255.140202) (xy 378.900689 -255.195378) (xy 378.901198 -255.223264) (xy 378.900689 -255.25115)
			(xy 378.892569 -255.306326) (xy 378.876501 -255.359733) (xy 378.852829 -255.41023) (xy 378.822056 -255.456743)
			(xy 378.784839 -255.49828) (xy 378.741971 -255.533955) (xy 378.694365 -255.563009) (xy 378.643036 -255.584821)
			(xy 378.589079 -255.598927) (xy 378.533642 -255.605027) (xy 378.477908 -255.60299) (xy 378.423065 -255.59286)
			(xy 378.370281 -255.574853) (xy 378.320681 -255.549352) (xy 378.275323 -255.516901) (xy 378.235174 -255.478192)
			(xy 378.201088 -255.434049) (xy 378.173792 -255.385414) (xy 378.153869 -255.333323) (xy 378.141743 -255.278886)
			(xy 378.137672 -255.223264) (xy 365.015222 -255.223264) (xy 365.016737 -255.226495) (xy 365.032805 -255.279902)
			(xy 365.040925 -255.335078) (xy 365.041434 -255.362964) (xy 365.040925 -255.39085) (xy 365.032805 -255.446026)
			(xy 365.016737 -255.499433) (xy 364.993065 -255.54993) (xy 364.962292 -255.596443) (xy 364.925075 -255.63798)
			(xy 364.882207 -255.673655) (xy 364.834601 -255.702709) (xy 364.783272 -255.724521) (xy 364.729315 -255.738627)
			(xy 364.673878 -255.744727) (xy 364.618144 -255.74269) (xy 364.563301 -255.73256) (xy 364.510517 -255.714553)
			(xy 364.460917 -255.689052) (xy 364.415559 -255.656601) (xy 364.37541 -255.617892) (xy 364.341324 -255.573749)
			(xy 364.314028 -255.525114) (xy 364.294105 -255.473023) (xy 364.281979 -255.418586) (xy 364.277908 -255.362964)
			(xy 361.217303 -255.362964) (xy 361.201099 -255.39753) (xy 361.170326 -255.444043) (xy 361.133109 -255.48558)
			(xy 361.090241 -255.521255) (xy 361.042635 -255.550309) (xy 360.991306 -255.572121) (xy 360.937349 -255.586227)
			(xy 360.881912 -255.592327) (xy 360.826178 -255.59029) (xy 360.771335 -255.58016) (xy 360.718551 -255.562153)
			(xy 360.668951 -255.536652) (xy 360.623593 -255.504201) (xy 360.583444 -255.465492) (xy 360.549358 -255.421349)
			(xy 360.522062 -255.372714) (xy 360.502139 -255.320623) (xy 360.490013 -255.266186) (xy 360.485942 -255.210564)
			(xy 353.943863 -255.210564) (xy 353.932685 -255.247719) (xy 353.909013 -255.298216) (xy 353.87824 -255.344729)
			(xy 353.841023 -255.386266) (xy 353.798155 -255.421941) (xy 353.750549 -255.450995) (xy 353.69922 -255.472807)
			(xy 353.645263 -255.486913) (xy 353.589826 -255.493013) (xy 353.534092 -255.490976) (xy 353.479249 -255.480846)
			(xy 353.426465 -255.462839) (xy 353.376865 -255.437338) (xy 353.331507 -255.404887) (xy 353.291358 -255.366178)
			(xy 353.257272 -255.322035) (xy 353.229976 -255.2734) (xy 353.210053 -255.221309) (xy 353.197927 -255.166872)
			(xy 353.193856 -255.11125) (xy 349.251425 -255.11125) (xy 349.258642 -255.161449) (xy 349.258642 -255.215951)
			(xy 349.250886 -255.269898) (xy 349.235532 -255.322193) (xy 349.212892 -255.37177) (xy 349.183428 -255.417622)
			(xy 349.147738 -255.458813) (xy 349.10655 -255.494506) (xy 349.060702 -255.523975) (xy 349.011127 -255.54662)
			(xy 348.958834 -255.561979) (xy 348.904887 -255.56974) (xy 348.877636 -255.570228) (xy 348.851031 -255.569783)
			(xy 348.798337 -255.562405) (xy 348.74718 -255.547772) (xy 348.698554 -255.52617) (xy 348.653403 -255.498017)
			(xy 348.612605 -255.46386) (xy 348.576951 -255.424364) (xy 348.56166 -255.402588) (xy 348.554141 -255.392654)
			(xy 348.532188 -255.380932) (xy 348.51975 -255.380236) (xy 348.435422 -255.380236) (xy 348.422966 -255.380871)
			(xy 348.400989 -255.392604) (xy 348.393512 -255.402588) (xy 348.37823 -255.424368) (xy 348.342561 -255.463845)
			(xy 348.301754 -255.497987) (xy 348.256602 -255.526131) (xy 348.207979 -255.547732) (xy 348.156828 -255.562371)
			(xy 348.104139 -255.569765) (xy 348.077536 -255.570228) (xy 348.051131 -255.569786) (xy 347.998827 -255.562482)
			(xy 347.94803 -255.548036) (xy 347.89971 -255.526724) (xy 347.854789 -255.498954) (xy 347.814127 -255.465255)
			(xy 347.7785 -255.426271) (xy 347.748587 -255.382748) (xy 347.724962 -255.335516) (xy 347.716094 -255.31064)
			(xy 347.71203 -255.298702) (xy 347.694758 -255.281938) (xy 347.59265 -255.249934) (xy 347.569028 -255.253998)
			(xy 347.558868 -255.261618) (xy 347.534002 -255.279424) (xy 347.479773 -255.307696) (xy 347.421728 -255.326955)
			(xy 347.361354 -255.336707) (xy 347.330776 -255.33731) (xy 347.299402 -255.336686) (xy 347.237503 -255.326404)
			(xy 347.178118 -255.306137) (xy 347.150182 -255.291844) (xy 347.14053 -255.286764) (xy 347.118686 -255.28524)
			(xy 347.026484 -255.319784) (xy 347.01099 -255.335024) (xy 347.00718 -255.345438) (xy 346.996458 -255.37223)
			(xy 346.968165 -255.422523) (xy 346.93262 -255.467981) (xy 346.890634 -255.507566) (xy 346.843165 -255.540377)
			(xy 346.791295 -255.565663) (xy 346.736209 -255.582849) (xy 346.679162 -255.591542) (xy 346.65031 -255.592072)
			(xy 346.623054 -255.591682) (xy 346.569097 -255.583925) (xy 346.516793 -255.568569) (xy 346.467207 -255.545924)
			(xy 346.421348 -255.516454) (xy 346.38015 -255.480757) (xy 346.344452 -255.43956) (xy 346.31498 -255.393702)
			(xy 346.292335 -255.344116) (xy 346.276977 -255.291813) (xy 346.269219 -255.237856) (xy 346.269219 -255.183344)
			(xy 346.276977 -255.129387) (xy 346.292335 -255.077084) (xy 346.31498 -255.027498) (xy 346.344452 -254.98164)
			(xy 346.38015 -254.940443) (xy 346.421348 -254.904746) (xy 346.467207 -254.875276) (xy 346.516793 -254.852631)
			(xy 346.569097 -254.837275) (xy 346.623054 -254.829518) (xy 346.65031 -254.829056) (xy 346.681683 -254.829689)
			(xy 346.743582 -254.839968) (xy 346.802967 -254.860231) (xy 346.830904 -254.874522) (xy 346.840556 -254.879602)
			(xy 346.8624 -254.881126) (xy 346.954602 -254.846582) (xy 346.970096 -254.831342) (xy 346.973906 -254.820928)
			(xy 346.983484 -254.796871) (xy 347.00821 -254.751376) (xy 347.023182 -254.73025) (xy 347.030294 -254.720344)
			(xy 347.034358 -254.696214) (xy 347.001338 -254.59436) (xy 346.984066 -254.577342) (xy 346.972382 -254.573532)
			(xy 346.946709 -254.56474) (xy 346.897956 -254.54091) (xy 346.853065 -254.510421) (xy 346.832682 -254.492506)
			(xy 346.825316 -254.485902) (xy 346.80779 -254.479298) (xy 346.71889 -254.480314) (xy 346.701364 -254.487426)
			(xy 346.694252 -254.49403) (xy 346.672892 -254.513582) (xy 346.625333 -254.546618) (xy 346.573325 -254.572083)
			(xy 346.518065 -254.58939) (xy 346.460824 -254.598142) (xy 346.43187 -254.598678) (xy 346.404618 -254.59825)
			(xy 346.350669 -254.59049) (xy 346.298374 -254.575131) (xy 346.248797 -254.552486) (xy 346.202946 -254.523017)
			(xy 346.161757 -254.487322) (xy 346.126065 -254.44613) (xy 346.0966 -254.400277) (xy 346.073959 -254.350698)
			(xy 346.058604 -254.298401) (xy 346.050848 -254.244452) (xy 343.935962 -254.244452) (xy 341.95385 -256.226564)
			(xy 358.420668 -256.226564) (xy 358.424739 -256.170942) (xy 358.436865 -256.116505) (xy 358.456788 -256.064414)
			(xy 358.484084 -256.015779) (xy 358.51817 -255.971636) (xy 358.558319 -255.932927) (xy 358.603677 -255.900476)
			(xy 358.653277 -255.874975) (xy 358.706061 -255.856968) (xy 358.760904 -255.846838) (xy 358.816638 -255.844801)
			(xy 358.872075 -255.850901) (xy 358.926032 -255.865007) (xy 358.977361 -255.886819) (xy 359.024967 -255.915873)
			(xy 359.067835 -255.951548) (xy 359.105052 -255.993085) (xy 359.135825 -256.039598) (xy 359.159497 -256.090095)
			(xy 359.175565 -256.143502) (xy 359.183685 -256.198678) (xy 359.184194 -256.226564) (xy 360.485942 -256.226564)
			(xy 360.490013 -256.170942) (xy 360.502139 -256.116505) (xy 360.522062 -256.064414) (xy 360.549358 -256.015779)
			(xy 360.583444 -255.971636) (xy 360.623593 -255.932927) (xy 360.668951 -255.900476) (xy 360.718551 -255.874975)
			(xy 360.771335 -255.856968) (xy 360.826178 -255.846838) (xy 360.881912 -255.844801) (xy 360.937349 -255.850901)
			(xy 360.991306 -255.865007) (xy 361.042635 -255.886819) (xy 361.081581 -255.910588) (xy 370.17655 -255.910588)
			(xy 370.180621 -255.854966) (xy 370.192747 -255.800529) (xy 370.21267 -255.748438) (xy 370.239966 -255.699803)
			(xy 370.274052 -255.65566) (xy 370.314201 -255.616951) (xy 370.359559 -255.5845) (xy 370.409159 -255.558999)
			(xy 370.461943 -255.540992) (xy 370.516786 -255.530862) (xy 370.57252 -255.528825) (xy 370.627957 -255.534925)
			(xy 370.681914 -255.549031) (xy 370.733243 -255.570843) (xy 370.780849 -255.599897) (xy 370.823717 -255.635572)
			(xy 370.860934 -255.677109) (xy 370.871743 -255.693446) (xy 371.065618 -255.693446) (xy 371.065618 -255.638954)
			(xy 371.073372 -255.585016) (xy 371.088724 -255.532731) (xy 371.111359 -255.483162) (xy 371.140817 -255.437319)
			(xy 371.1765 -255.396134) (xy 371.21768 -255.360446) (xy 371.26352 -255.330982) (xy 371.313086 -255.30834)
			(xy 371.365369 -255.292983) (xy 371.419306 -255.285221) (xy 371.446552 -255.284732) (xy 371.475504 -255.285312)
			(xy 371.532742 -255.294063) (xy 371.588003 -255.311356) (xy 371.640019 -255.336794) (xy 371.687598 -255.369795)
			(xy 371.729649 -255.409602) (xy 371.765207 -255.455301) (xy 371.7798 -255.480312) (xy 371.787615 -255.493169)
			(xy 371.809268 -255.514035) (xy 371.836061 -255.527686) (xy 371.865669 -255.532938) (xy 371.895523 -255.529336)
			(xy 371.923031 -255.517191) (xy 371.945808 -255.497558) (xy 371.954298 -255.485138) (xy 371.969379 -255.462142)
			(xy 372.005086 -255.420318) (xy 372.046426 -255.384052) (xy 372.092544 -255.354096) (xy 372.142484 -255.33107)
			(xy 372.195212 -255.315451) (xy 372.249636 -255.307562) (xy 372.277132 -255.307084) (xy 372.304381 -255.307588)
			(xy 372.358324 -255.315348) (xy 372.410614 -255.330706) (xy 372.460186 -255.353348) (xy 372.506032 -255.382815)
			(xy 372.547217 -255.418505) (xy 372.582905 -255.459694) (xy 372.612367 -255.505542) (xy 372.635006 -255.555116)
			(xy 372.650359 -255.607407) (xy 372.658114 -255.661351) (xy 372.658114 -255.715849) (xy 372.650359 -255.769793)
			(xy 372.635006 -255.822084) (xy 372.612367 -255.871658) (xy 372.582905 -255.917506) (xy 372.547217 -255.958695)
			(xy 372.506032 -255.994385) (xy 372.460186 -256.023852) (xy 372.410614 -256.046494) (xy 372.358324 -256.061852)
			(xy 372.304381 -256.069612) (xy 372.277132 -256.0701) (xy 372.248178 -256.069567) (xy 372.190936 -256.060812)
			(xy 372.135672 -256.043514) (xy 372.083654 -256.018068) (xy 372.036076 -255.985059) (xy 371.994027 -255.945244)
			(xy 371.958474 -255.899535) (xy 371.943884 -255.87452) (xy 371.936088 -255.861654) (xy 371.914426 -255.8408)
			(xy 371.88763 -255.827159) (xy 371.858023 -255.821912) (xy 371.828171 -255.825514) (xy 371.800663 -255.837654)
			(xy 371.777881 -255.857278) (xy 371.769386 -255.869694) (xy 371.754326 -255.892705) (xy 371.718615 -255.934527)
			(xy 371.67727 -255.970791) (xy 371.631149 -256.000744) (xy 371.581206 -256.023768) (xy 371.528475 -256.039385)
			(xy 371.474049 -256.047271) (xy 371.446552 -256.047748) (xy 371.419306 -256.047179) (xy 371.365369 -256.039417)
			(xy 371.313086 -256.02406) (xy 371.26352 -256.001418) (xy 371.21768 -255.971954) (xy 371.1765 -255.936266)
			(xy 371.140817 -255.895081) (xy 371.111359 -255.849238) (xy 371.088724 -255.799669) (xy 371.073372 -255.747384)
			(xy 371.065618 -255.693446) (xy 370.871743 -255.693446) (xy 370.891707 -255.723622) (xy 370.915379 -255.774119)
			(xy 370.931447 -255.827526) (xy 370.939567 -255.882702) (xy 370.940076 -255.910588) (xy 370.939567 -255.938474)
			(xy 370.931447 -255.99365) (xy 370.915379 -256.047057) (xy 370.891707 -256.097554) (xy 370.884664 -256.1082)
			(xy 374.28373 -256.1082) (xy 374.287801 -256.052578) (xy 374.299927 -255.998141) (xy 374.31985 -255.94605)
			(xy 374.347146 -255.897415) (xy 374.381232 -255.853272) (xy 374.421381 -255.814563) (xy 374.466739 -255.782112)
			(xy 374.516339 -255.756611) (xy 374.569123 -255.738604) (xy 374.623966 -255.728474) (xy 374.6797 -255.726437)
			(xy 374.735137 -255.732537) (xy 374.789094 -255.746643) (xy 374.840423 -255.768455) (xy 374.888029 -255.797509)
			(xy 374.930897 -255.833184) (xy 374.968114 -255.874721) (xy 374.998887 -255.921234) (xy 375.022559 -255.971731)
			(xy 375.038627 -256.025138) (xy 375.046747 -256.080314) (xy 375.04708 -256.098548) (xy 376.181872 -256.098548)
			(xy 376.185943 -256.042926) (xy 376.198069 -255.988489) (xy 376.217992 -255.936398) (xy 376.245288 -255.887763)
			(xy 376.279374 -255.84362) (xy 376.319523 -255.804911) (xy 376.364881 -255.77246) (xy 376.414481 -255.746959)
			(xy 376.467265 -255.728952) (xy 376.522108 -255.718822) (xy 376.577842 -255.716785) (xy 376.633279 -255.722885)
			(xy 376.687236 -255.736991) (xy 376.738565 -255.758803) (xy 376.786171 -255.787857) (xy 376.829039 -255.823532)
			(xy 376.866256 -255.865069) (xy 376.897029 -255.911582) (xy 376.920701 -255.962079) (xy 376.936769 -256.015486)
			(xy 376.944889 -256.070662) (xy 376.945398 -256.098548) (xy 376.944889 -256.126434) (xy 376.936769 -256.18161)
			(xy 376.920701 -256.235017) (xy 376.897029 -256.285514) (xy 376.866256 -256.332027) (xy 376.829039 -256.373564)
			(xy 376.826213 -256.375916) (xy 377.069602 -256.375916) (xy 377.073673 -256.320294) (xy 377.085799 -256.265857)
			(xy 377.105722 -256.213766) (xy 377.133018 -256.165131) (xy 377.167104 -256.120988) (xy 377.207253 -256.082279)
			(xy 377.252611 -256.049828) (xy 377.302211 -256.024327) (xy 377.354995 -256.00632) (xy 377.409838 -255.99619)
			(xy 377.465572 -255.994153) (xy 377.521009 -256.000253) (xy 377.574966 -256.014359) (xy 377.626295 -256.036171)
			(xy 377.673901 -256.065225) (xy 377.716769 -256.1009) (xy 377.753986 -256.142437) (xy 377.784759 -256.18895)
			(xy 377.808431 -256.239447) (xy 377.824499 -256.292854) (xy 377.832619 -256.34803) (xy 377.833128 -256.375916)
			(xy 378.545088 -256.375916) (xy 378.549159 -256.320294) (xy 378.561285 -256.265857) (xy 378.581208 -256.213766)
			(xy 378.608504 -256.165131) (xy 378.64259 -256.120988) (xy 378.682739 -256.082279) (xy 378.728097 -256.049828)
			(xy 378.777697 -256.024327) (xy 378.830481 -256.00632) (xy 378.885324 -255.99619) (xy 378.941058 -255.994153)
			(xy 378.996495 -256.000253) (xy 379.050452 -256.014359) (xy 379.101781 -256.036171) (xy 379.149387 -256.065225)
			(xy 379.192255 -256.1009) (xy 379.229472 -256.142437) (xy 379.260245 -256.18895) (xy 379.283917 -256.239447)
			(xy 379.299985 -256.292854) (xy 379.308105 -256.34803) (xy 379.308614 -256.375916) (xy 379.434088 -256.375916)
			(xy 379.438159 -256.320294) (xy 379.450285 -256.265857) (xy 379.470208 -256.213766) (xy 379.497504 -256.165131)
			(xy 379.53159 -256.120988) (xy 379.571739 -256.082279) (xy 379.617097 -256.049828) (xy 379.666697 -256.024327)
			(xy 379.719481 -256.00632) (xy 379.774324 -255.99619) (xy 379.830058 -255.994153) (xy 379.885495 -256.000253)
			(xy 379.939452 -256.014359) (xy 379.990781 -256.036171) (xy 380.038387 -256.065225) (xy 380.081255 -256.1009)
			(xy 380.118472 -256.142437) (xy 380.149245 -256.18895) (xy 380.172917 -256.239447) (xy 380.188985 -256.292854)
			(xy 380.197105 -256.34803) (xy 380.197614 -256.375916) (xy 380.197105 -256.403802) (xy 380.188985 -256.458978)
			(xy 380.172917 -256.512385) (xy 380.149245 -256.562882) (xy 380.118472 -256.609395) (xy 380.081255 -256.650932)
			(xy 380.038387 -256.686607) (xy 379.990781 -256.715661) (xy 379.939452 -256.737473) (xy 379.885495 -256.751579)
			(xy 379.830058 -256.757679) (xy 379.774324 -256.755642) (xy 379.719481 -256.745512) (xy 379.666697 -256.727505)
			(xy 379.617097 -256.702004) (xy 379.571739 -256.669553) (xy 379.53159 -256.630844) (xy 379.497504 -256.586701)
			(xy 379.470208 -256.538066) (xy 379.450285 -256.485975) (xy 379.438159 -256.431538) (xy 379.434088 -256.375916)
			(xy 379.308614 -256.375916) (xy 379.308105 -256.403802) (xy 379.299985 -256.458978) (xy 379.283917 -256.512385)
			(xy 379.260245 -256.562882) (xy 379.229472 -256.609395) (xy 379.192255 -256.650932) (xy 379.149387 -256.686607)
			(xy 379.101781 -256.715661) (xy 379.050452 -256.737473) (xy 378.996495 -256.751579) (xy 378.941058 -256.757679)
			(xy 378.885324 -256.755642) (xy 378.830481 -256.745512) (xy 378.777697 -256.727505) (xy 378.728097 -256.702004)
			(xy 378.682739 -256.669553) (xy 378.64259 -256.630844) (xy 378.608504 -256.586701) (xy 378.581208 -256.538066)
			(xy 378.561285 -256.485975) (xy 378.549159 -256.431538) (xy 378.545088 -256.375916) (xy 377.833128 -256.375916)
			(xy 377.832619 -256.403802) (xy 377.824499 -256.458978) (xy 377.808431 -256.512385) (xy 377.784759 -256.562882)
			(xy 377.753986 -256.609395) (xy 377.716769 -256.650932) (xy 377.673901 -256.686607) (xy 377.626295 -256.715661)
			(xy 377.574966 -256.737473) (xy 377.521009 -256.751579) (xy 377.465572 -256.757679) (xy 377.409838 -256.755642)
			(xy 377.354995 -256.745512) (xy 377.302211 -256.727505) (xy 377.252611 -256.702004) (xy 377.207253 -256.669553)
			(xy 377.167104 -256.630844) (xy 377.133018 -256.586701) (xy 377.105722 -256.538066) (xy 377.085799 -256.485975)
			(xy 377.073673 -256.431538) (xy 377.069602 -256.375916) (xy 376.826213 -256.375916) (xy 376.786171 -256.409239)
			(xy 376.738565 -256.438293) (xy 376.687236 -256.460105) (xy 376.633279 -256.474211) (xy 376.577842 -256.480311)
			(xy 376.522108 -256.478274) (xy 376.467265 -256.468144) (xy 376.414481 -256.450137) (xy 376.364881 -256.424636)
			(xy 376.319523 -256.392185) (xy 376.279374 -256.353476) (xy 376.245288 -256.309333) (xy 376.217992 -256.260698)
			(xy 376.198069 -256.208607) (xy 376.185943 -256.15417) (xy 376.181872 -256.098548) (xy 375.04708 -256.098548)
			(xy 375.047256 -256.1082) (xy 375.046747 -256.136086) (xy 375.038627 -256.191262) (xy 375.022559 -256.244669)
			(xy 374.998887 -256.295166) (xy 374.968114 -256.341679) (xy 374.930897 -256.383216) (xy 374.888029 -256.418891)
			(xy 374.840423 -256.447945) (xy 374.789094 -256.469757) (xy 374.735137 -256.483863) (xy 374.6797 -256.489963)
			(xy 374.623966 -256.487926) (xy 374.569123 -256.477796) (xy 374.516339 -256.459789) (xy 374.466739 -256.434288)
			(xy 374.421381 -256.401837) (xy 374.381232 -256.363128) (xy 374.347146 -256.318985) (xy 374.31985 -256.27035)
			(xy 374.299927 -256.218259) (xy 374.287801 -256.163822) (xy 374.28373 -256.1082) (xy 370.884664 -256.1082)
			(xy 370.860934 -256.144067) (xy 370.823717 -256.185604) (xy 370.780849 -256.221279) (xy 370.733243 -256.250333)
			(xy 370.681914 -256.272145) (xy 370.627957 -256.286251) (xy 370.57252 -256.292351) (xy 370.516786 -256.290314)
			(xy 370.461943 -256.280184) (xy 370.409159 -256.262177) (xy 370.359559 -256.236676) (xy 370.314201 -256.204225)
			(xy 370.274052 -256.165516) (xy 370.239966 -256.121373) (xy 370.21267 -256.072738) (xy 370.192747 -256.020647)
			(xy 370.180621 -255.96621) (xy 370.17655 -255.910588) (xy 361.081581 -255.910588) (xy 361.090241 -255.915873)
			(xy 361.133109 -255.951548) (xy 361.170326 -255.993085) (xy 361.201099 -256.039598) (xy 361.224771 -256.090095)
			(xy 361.240839 -256.143502) (xy 361.248959 -256.198678) (xy 361.249468 -256.226564) (xy 361.248959 -256.25445)
			(xy 361.240839 -256.309626) (xy 361.224771 -256.363033) (xy 361.201099 -256.41353) (xy 361.170326 -256.460043)
			(xy 361.133109 -256.50158) (xy 361.090241 -256.537255) (xy 361.042635 -256.566309) (xy 360.991306 -256.588121)
			(xy 360.937349 -256.602227) (xy 360.91193 -256.605024) (xy 365.598708 -256.605024) (xy 365.602779 -256.549402)
			(xy 365.614905 -256.494965) (xy 365.634828 -256.442874) (xy 365.662124 -256.394239) (xy 365.69621 -256.350096)
			(xy 365.736359 -256.311387) (xy 365.781717 -256.278936) (xy 365.831317 -256.253435) (xy 365.884101 -256.235428)
			(xy 365.938944 -256.225298) (xy 365.994678 -256.223261) (xy 366.050115 -256.229361) (xy 366.104072 -256.243467)
			(xy 366.155401 -256.265279) (xy 366.203007 -256.294333) (xy 366.245875 -256.330008) (xy 366.283092 -256.371545)
			(xy 366.313865 -256.418058) (xy 366.337537 -256.468555) (xy 366.353605 -256.521962) (xy 366.361725 -256.577138)
			(xy 366.362234 -256.605024) (xy 366.361725 -256.63291) (xy 366.353605 -256.688086) (xy 366.337537 -256.741493)
			(xy 366.313865 -256.79199) (xy 366.283092 -256.838503) (xy 366.245875 -256.88004) (xy 366.203007 -256.915715)
			(xy 366.155401 -256.944769) (xy 366.104072 -256.966581) (xy 366.050115 -256.980687) (xy 365.994678 -256.986787)
			(xy 365.938944 -256.98475) (xy 365.884101 -256.97462) (xy 365.831317 -256.956613) (xy 365.781717 -256.931112)
			(xy 365.736359 -256.898661) (xy 365.69621 -256.859952) (xy 365.662124 -256.815809) (xy 365.634828 -256.767174)
			(xy 365.614905 -256.715083) (xy 365.602779 -256.660646) (xy 365.598708 -256.605024) (xy 360.91193 -256.605024)
			(xy 360.881912 -256.608327) (xy 360.826178 -256.60629) (xy 360.771335 -256.59616) (xy 360.718551 -256.578153)
			(xy 360.668951 -256.552652) (xy 360.623593 -256.520201) (xy 360.583444 -256.481492) (xy 360.549358 -256.437349)
			(xy 360.522062 -256.388714) (xy 360.502139 -256.336623) (xy 360.490013 -256.282186) (xy 360.485942 -256.226564)
			(xy 359.184194 -256.226564) (xy 359.183685 -256.25445) (xy 359.175565 -256.309626) (xy 359.159497 -256.363033)
			(xy 359.135825 -256.41353) (xy 359.105052 -256.460043) (xy 359.067835 -256.50158) (xy 359.024967 -256.537255)
			(xy 358.977361 -256.566309) (xy 358.926032 -256.588121) (xy 358.872075 -256.602227) (xy 358.816638 -256.608327)
			(xy 358.760904 -256.60629) (xy 358.706061 -256.59616) (xy 358.653277 -256.578153) (xy 358.603677 -256.552652)
			(xy 358.558319 -256.520201) (xy 358.51817 -256.481492) (xy 358.484084 -256.437349) (xy 358.456788 -256.388714)
			(xy 358.436865 -256.336623) (xy 358.424739 -256.282186) (xy 358.420668 -256.226564) (xy 341.95385 -256.226564)
			(xy 341.049864 -257.13055) (xy 348.495618 -257.13055) (xy 348.499689 -257.074928) (xy 348.511815 -257.020491)
			(xy 348.531738 -256.9684) (xy 348.559034 -256.919765) (xy 348.59312 -256.875622) (xy 348.633269 -256.836913)
			(xy 348.678627 -256.804462) (xy 348.728227 -256.778961) (xy 348.781011 -256.760954) (xy 348.835854 -256.750824)
			(xy 348.891588 -256.748787) (xy 348.947025 -256.754887) (xy 349.000982 -256.768993) (xy 349.052311 -256.790805)
			(xy 349.099917 -256.819859) (xy 349.142785 -256.855534) (xy 349.156608 -256.870962) (xy 351.069908 -256.870962)
			(xy 351.073979 -256.81534) (xy 351.086105 -256.760903) (xy 351.106028 -256.708812) (xy 351.133324 -256.660177)
			(xy 351.16741 -256.616034) (xy 351.207559 -256.577325) (xy 351.252917 -256.544874) (xy 351.302517 -256.519373)
			(xy 351.355301 -256.501366) (xy 351.410144 -256.491236) (xy 351.465878 -256.489199) (xy 351.521315 -256.495299)
			(xy 351.575272 -256.509405) (xy 351.626601 -256.531217) (xy 351.674207 -256.560271) (xy 351.717075 -256.595946)
			(xy 351.754292 -256.637483) (xy 351.785065 -256.683996) (xy 351.808737 -256.734493) (xy 351.824805 -256.7879)
			(xy 351.832925 -256.843076) (xy 351.833434 -256.870962) (xy 352.593908 -256.870962) (xy 352.597979 -256.81534)
			(xy 352.610105 -256.760903) (xy 352.630028 -256.708812) (xy 352.657324 -256.660177) (xy 352.69141 -256.616034)
			(xy 352.731559 -256.577325) (xy 352.776917 -256.544874) (xy 352.826517 -256.519373) (xy 352.879301 -256.501366)
			(xy 352.934144 -256.491236) (xy 352.989878 -256.489199) (xy 353.045315 -256.495299) (xy 353.099272 -256.509405)
			(xy 353.150601 -256.531217) (xy 353.198207 -256.560271) (xy 353.241075 -256.595946) (xy 353.278292 -256.637483)
			(xy 353.309065 -256.683996) (xy 353.332737 -256.734493) (xy 353.348805 -256.7879) (xy 353.356925 -256.843076)
			(xy 353.357434 -256.870962) (xy 354.117908 -256.870962) (xy 354.121979 -256.81534) (xy 354.134105 -256.760903)
			(xy 354.154028 -256.708812) (xy 354.181324 -256.660177) (xy 354.21541 -256.616034) (xy 354.255559 -256.577325)
			(xy 354.300917 -256.544874) (xy 354.350517 -256.519373) (xy 354.403301 -256.501366) (xy 354.458144 -256.491236)
			(xy 354.513878 -256.489199) (xy 354.569315 -256.495299) (xy 354.623272 -256.509405) (xy 354.674601 -256.531217)
			(xy 354.722207 -256.560271) (xy 354.765075 -256.595946) (xy 354.802292 -256.637483) (xy 354.833065 -256.683996)
			(xy 354.856737 -256.734493) (xy 354.872805 -256.7879) (xy 354.880925 -256.843076) (xy 354.881434 -256.870962)
			(xy 354.880925 -256.898848) (xy 354.872805 -256.954024) (xy 354.856737 -257.007431) (xy 354.833065 -257.057928)
			(xy 354.802292 -257.104441) (xy 354.792326 -257.115564) (xy 360.485942 -257.115564) (xy 360.490013 -257.059942)
			(xy 360.502139 -257.005505) (xy 360.522062 -256.953414) (xy 360.549358 -256.904779) (xy 360.583444 -256.860636)
			(xy 360.623593 -256.821927) (xy 360.668951 -256.789476) (xy 360.718551 -256.763975) (xy 360.771335 -256.745968)
			(xy 360.826178 -256.735838) (xy 360.881912 -256.733801) (xy 360.937349 -256.739901) (xy 360.991306 -256.754007)
			(xy 361.042635 -256.775819) (xy 361.090241 -256.804873) (xy 361.133109 -256.840548) (xy 361.170326 -256.882085)
			(xy 361.201099 -256.928598) (xy 361.224771 -256.979095) (xy 361.227314 -256.987548) (xy 376.181872 -256.987548)
			(xy 376.185943 -256.931926) (xy 376.198069 -256.877489) (xy 376.217992 -256.825398) (xy 376.245288 -256.776763)
			(xy 376.279374 -256.73262) (xy 376.319523 -256.693911) (xy 376.364881 -256.66146) (xy 376.414481 -256.635959)
			(xy 376.467265 -256.617952) (xy 376.522108 -256.607822) (xy 376.577842 -256.605785) (xy 376.633279 -256.611885)
			(xy 376.687236 -256.625991) (xy 376.738565 -256.647803) (xy 376.786171 -256.676857) (xy 376.829039 -256.712532)
			(xy 376.866256 -256.754069) (xy 376.897029 -256.800582) (xy 376.920701 -256.851079) (xy 376.936769 -256.904486)
			(xy 376.944889 -256.959662) (xy 376.945398 -256.987548) (xy 376.944889 -257.015434) (xy 376.936769 -257.07061)
			(xy 376.920701 -257.124017) (xy 376.914185 -257.137916) (xy 382.596136 -257.137916) (xy 382.596671 -257.108533)
			(xy 382.605701 -257.050465) (xy 382.623533 -256.994471) (xy 382.649745 -256.941875) (xy 382.683717 -256.893924)
			(xy 382.724644 -256.851753) (xy 382.747774 -256.833624) (xy 382.757172 -256.826258) (xy 382.767586 -256.805684)
			(xy 382.76911 -256.701798) (xy 382.759204 -256.680716) (xy 382.75006 -256.67335) (xy 382.728198 -256.655161)
			(xy 382.68966 -256.613337) (xy 382.657756 -256.566258) (xy 382.633192 -256.514965) (xy 382.616511 -256.460595)
			(xy 382.608084 -256.404352) (xy 382.607566 -256.375916) (xy 382.608052 -256.348665) (xy 382.615808 -256.294717)
			(xy 382.631163 -256.242422) (xy 382.653805 -256.192845) (xy 382.683271 -256.146995) (xy 382.718962 -256.105804)
			(xy 382.760153 -256.070113) (xy 382.806003 -256.040647) (xy 382.85558 -256.018005) (xy 382.907875 -256.00265)
			(xy 382.961823 -255.994894) (xy 383.016325 -255.994894) (xy 383.070273 -256.00265) (xy 383.122568 -256.018005)
			(xy 383.172145 -256.040647) (xy 383.217995 -256.070113) (xy 383.259186 -256.105804) (xy 383.294877 -256.146995)
			(xy 383.324343 -256.192845) (xy 383.346985 -256.242422) (xy 383.36234 -256.294717) (xy 383.370096 -256.348665)
			(xy 383.370582 -256.375916) (xy 383.370063 -256.405299) (xy 383.361029 -256.463367) (xy 383.343193 -256.519362)
			(xy 383.316978 -256.571958) (xy 383.283003 -256.619908) (xy 383.242074 -256.662079) (xy 383.218944 -256.680208)
			(xy 383.209546 -256.687574) (xy 383.199132 -256.708148) (xy 383.197608 -256.812034) (xy 383.207514 -256.833116)
			(xy 383.216658 -256.840482) (xy 383.238471 -256.858728) (xy 383.277015 -256.900538) (xy 383.308928 -256.947604)
			(xy 383.333501 -256.998886) (xy 383.350191 -257.053247) (xy 383.358629 -257.109483) (xy 383.359152 -257.137916)
			(xy 383.992626 -257.137916) (xy 383.996697 -257.082294) (xy 384.008823 -257.027857) (xy 384.028746 -256.975766)
			(xy 384.056042 -256.927131) (xy 384.090128 -256.882988) (xy 384.130277 -256.844279) (xy 384.175635 -256.811828)
			(xy 384.225235 -256.786327) (xy 384.278019 -256.76832) (xy 384.332862 -256.75819) (xy 384.388596 -256.756153)
			(xy 384.444033 -256.762253) (xy 384.49799 -256.776359) (xy 384.549319 -256.798171) (xy 384.596925 -256.827225)
			(xy 384.639793 -256.8629) (xy 384.67701 -256.904437) (xy 384.707783 -256.95095) (xy 384.731455 -257.001447)
			(xy 384.747523 -257.054854) (xy 384.755643 -257.11003) (xy 384.756152 -257.137916) (xy 384.879086 -257.137916)
			(xy 384.883157 -257.082294) (xy 384.895283 -257.027857) (xy 384.915206 -256.975766) (xy 384.942502 -256.927131)
			(xy 384.976588 -256.882988) (xy 385.016737 -256.844279) (xy 385.062095 -256.811828) (xy 385.111695 -256.786327)
			(xy 385.164479 -256.76832) (xy 385.219322 -256.75819) (xy 385.275056 -256.756153) (xy 385.330493 -256.762253)
			(xy 385.38445 -256.776359) (xy 385.435779 -256.798171) (xy 385.483385 -256.827225) (xy 385.526253 -256.8629)
			(xy 385.56347 -256.904437) (xy 385.594243 -256.95095) (xy 385.617915 -257.001447) (xy 385.633983 -257.054854)
			(xy 385.642103 -257.11003) (xy 385.642612 -257.137916) (xy 385.642103 -257.165802) (xy 385.633983 -257.220978)
			(xy 385.617915 -257.274385) (xy 385.594243 -257.324882) (xy 385.56347 -257.371395) (xy 385.526253 -257.412932)
			(xy 385.483385 -257.448607) (xy 385.435779 -257.477661) (xy 385.38445 -257.499473) (xy 385.330493 -257.513579)
			(xy 385.275056 -257.519679) (xy 385.219322 -257.517642) (xy 385.164479 -257.507512) (xy 385.111695 -257.489505)
			(xy 385.062095 -257.464004) (xy 385.016737 -257.431553) (xy 384.976588 -257.392844) (xy 384.942502 -257.348701)
			(xy 384.915206 -257.300066) (xy 384.895283 -257.247975) (xy 384.883157 -257.193538) (xy 384.879086 -257.137916)
			(xy 384.756152 -257.137916) (xy 384.755643 -257.165802) (xy 384.747523 -257.220978) (xy 384.731455 -257.274385)
			(xy 384.707783 -257.324882) (xy 384.67701 -257.371395) (xy 384.639793 -257.412932) (xy 384.596925 -257.448607)
			(xy 384.549319 -257.477661) (xy 384.49799 -257.499473) (xy 384.444033 -257.513579) (xy 384.388596 -257.519679)
			(xy 384.332862 -257.517642) (xy 384.278019 -257.507512) (xy 384.225235 -257.489505) (xy 384.175635 -257.464004)
			(xy 384.130277 -257.431553) (xy 384.090128 -257.392844) (xy 384.056042 -257.348701) (xy 384.028746 -257.300066)
			(xy 384.008823 -257.247975) (xy 383.996697 -257.193538) (xy 383.992626 -257.137916) (xy 383.359152 -257.137916)
			(xy 383.358666 -257.165167) (xy 383.35091 -257.219115) (xy 383.335555 -257.27141) (xy 383.312913 -257.320987)
			(xy 383.283447 -257.366837) (xy 383.247756 -257.408028) (xy 383.206565 -257.443719) (xy 383.160715 -257.473185)
			(xy 383.111138 -257.495827) (xy 383.058843 -257.511182) (xy 383.004895 -257.518938) (xy 382.950393 -257.518938)
			(xy 382.896445 -257.511182) (xy 382.84415 -257.495827) (xy 382.794573 -257.473185) (xy 382.748723 -257.443719)
			(xy 382.707532 -257.408028) (xy 382.671841 -257.366837) (xy 382.642375 -257.320987) (xy 382.619733 -257.27141)
			(xy 382.604378 -257.219115) (xy 382.596622 -257.165167) (xy 382.596136 -257.137916) (xy 376.914185 -257.137916)
			(xy 376.897029 -257.174514) (xy 376.866256 -257.221027) (xy 376.829039 -257.262564) (xy 376.786171 -257.298239)
			(xy 376.738565 -257.327293) (xy 376.687236 -257.349105) (xy 376.633279 -257.363211) (xy 376.577842 -257.369311)
			(xy 376.522108 -257.367274) (xy 376.467265 -257.357144) (xy 376.414481 -257.339137) (xy 376.364881 -257.313636)
			(xy 376.319523 -257.281185) (xy 376.279374 -257.242476) (xy 376.245288 -257.198333) (xy 376.217992 -257.149698)
			(xy 376.198069 -257.097607) (xy 376.185943 -257.04317) (xy 376.181872 -256.987548) (xy 361.227314 -256.987548)
			(xy 361.240839 -257.032502) (xy 361.248959 -257.087678) (xy 361.249468 -257.115564) (xy 361.248959 -257.14345)
			(xy 361.240839 -257.198626) (xy 361.224771 -257.252033) (xy 361.201099 -257.30253) (xy 361.170326 -257.349043)
			(xy 361.133109 -257.39058) (xy 361.090241 -257.426255) (xy 361.042635 -257.455309) (xy 360.998152 -257.474212)
			(xy 370.2718 -257.474212) (xy 370.275871 -257.41859) (xy 370.287997 -257.364153) (xy 370.30792 -257.312062)
			(xy 370.335216 -257.263427) (xy 370.369302 -257.219284) (xy 370.409451 -257.180575) (xy 370.454809 -257.148124)
			(xy 370.504409 -257.122623) (xy 370.557193 -257.104616) (xy 370.612036 -257.094486) (xy 370.66777 -257.092449)
			(xy 370.723207 -257.098549) (xy 370.777164 -257.112655) (xy 370.828493 -257.134467) (xy 370.876099 -257.163521)
			(xy 370.918967 -257.199196) (xy 370.956184 -257.240733) (xy 370.986957 -257.287246) (xy 371.010629 -257.337743)
			(xy 371.026697 -257.39115) (xy 371.034817 -257.446326) (xy 371.035326 -257.474212) (xy 371.034817 -257.502098)
			(xy 371.026697 -257.557274) (xy 371.010629 -257.610681) (xy 370.986957 -257.661178) (xy 370.956184 -257.707691)
			(xy 370.918967 -257.749228) (xy 370.876099 -257.784903) (xy 370.828493 -257.813957) (xy 370.777164 -257.835769)
			(xy 370.723207 -257.849875) (xy 370.66777 -257.855975) (xy 370.612036 -257.853938) (xy 370.557193 -257.843808)
			(xy 370.504409 -257.825801) (xy 370.454809 -257.8003) (xy 370.409451 -257.767849) (xy 370.369302 -257.72914)
			(xy 370.335216 -257.684997) (xy 370.30792 -257.636362) (xy 370.287997 -257.584271) (xy 370.275871 -257.529834)
			(xy 370.2718 -257.474212) (xy 360.998152 -257.474212) (xy 360.991306 -257.477121) (xy 360.937349 -257.491227)
			(xy 360.881912 -257.497327) (xy 360.826178 -257.49529) (xy 360.771335 -257.48516) (xy 360.718551 -257.467153)
			(xy 360.668951 -257.441652) (xy 360.623593 -257.409201) (xy 360.583444 -257.370492) (xy 360.549358 -257.326349)
			(xy 360.522062 -257.277714) (xy 360.502139 -257.225623) (xy 360.490013 -257.171186) (xy 360.485942 -257.115564)
			(xy 354.792326 -257.115564) (xy 354.765075 -257.145978) (xy 354.722207 -257.181653) (xy 354.674601 -257.210707)
			(xy 354.623272 -257.232519) (xy 354.569315 -257.246625) (xy 354.513878 -257.252725) (xy 354.458144 -257.250688)
			(xy 354.403301 -257.240558) (xy 354.350517 -257.222551) (xy 354.300917 -257.19705) (xy 354.255559 -257.164599)
			(xy 354.21541 -257.12589) (xy 354.181324 -257.081747) (xy 354.154028 -257.033112) (xy 354.134105 -256.981021)
			(xy 354.121979 -256.926584) (xy 354.117908 -256.870962) (xy 353.357434 -256.870962) (xy 353.356925 -256.898848)
			(xy 353.348805 -256.954024) (xy 353.332737 -257.007431) (xy 353.309065 -257.057928) (xy 353.278292 -257.104441)
			(xy 353.241075 -257.145978) (xy 353.198207 -257.181653) (xy 353.150601 -257.210707) (xy 353.099272 -257.232519)
			(xy 353.045315 -257.246625) (xy 352.989878 -257.252725) (xy 352.934144 -257.250688) (xy 352.879301 -257.240558)
			(xy 352.826517 -257.222551) (xy 352.776917 -257.19705) (xy 352.731559 -257.164599) (xy 352.69141 -257.12589)
			(xy 352.657324 -257.081747) (xy 352.630028 -257.033112) (xy 352.610105 -256.981021) (xy 352.597979 -256.926584)
			(xy 352.593908 -256.870962) (xy 351.833434 -256.870962) (xy 351.832925 -256.898848) (xy 351.824805 -256.954024)
			(xy 351.808737 -257.007431) (xy 351.785065 -257.057928) (xy 351.754292 -257.104441) (xy 351.717075 -257.145978)
			(xy 351.674207 -257.181653) (xy 351.626601 -257.210707) (xy 351.575272 -257.232519) (xy 351.521315 -257.246625)
			(xy 351.465878 -257.252725) (xy 351.410144 -257.250688) (xy 351.355301 -257.240558) (xy 351.302517 -257.222551)
			(xy 351.252917 -257.19705) (xy 351.207559 -257.164599) (xy 351.16741 -257.12589) (xy 351.133324 -257.081747)
			(xy 351.106028 -257.033112) (xy 351.086105 -256.981021) (xy 351.073979 -256.926584) (xy 351.069908 -256.870962)
			(xy 349.156608 -256.870962) (xy 349.180002 -256.897071) (xy 349.210775 -256.943584) (xy 349.234447 -256.994081)
			(xy 349.250515 -257.047488) (xy 349.258635 -257.102664) (xy 349.259144 -257.13055) (xy 349.258635 -257.158436)
			(xy 349.250515 -257.213612) (xy 349.234447 -257.267019) (xy 349.210775 -257.317516) (xy 349.180002 -257.364029)
			(xy 349.142785 -257.405566) (xy 349.099917 -257.441241) (xy 349.052311 -257.470295) (xy 349.000982 -257.492107)
			(xy 348.947025 -257.506213) (xy 348.891588 -257.512313) (xy 348.835854 -257.510276) (xy 348.781011 -257.500146)
			(xy 348.728227 -257.482139) (xy 348.678627 -257.456638) (xy 348.633269 -257.424187) (xy 348.59312 -257.385478)
			(xy 348.559034 -257.341335) (xy 348.531738 -257.2927) (xy 348.511815 -257.240609) (xy 348.499689 -257.186172)
			(xy 348.495618 -257.13055) (xy 341.049864 -257.13055) (xy 340.160864 -258.01955) (xy 348.623128 -258.01955)
			(xy 348.623602 -257.992297) (xy 348.631353 -257.938344) (xy 348.646705 -257.886044) (xy 348.669344 -257.836462)
			(xy 348.69881 -257.790607) (xy 348.734503 -257.749413) (xy 348.775696 -257.713718) (xy 348.82155 -257.684251)
			(xy 348.871131 -257.661609) (xy 348.923431 -257.646256) (xy 348.977383 -257.638503) (xy 349.004636 -257.638042)
			(xy 349.031693 -257.638468) (xy 349.085261 -257.646131) (xy 349.13721 -257.661285) (xy 349.186497 -257.683626)
			(xy 349.232134 -257.712706) (xy 349.273205 -257.74794) (xy 349.308887 -257.788624) (xy 349.338463 -257.83394)
			(xy 349.35033 -257.85826) (xy 349.354394 -257.866642) (xy 349.367602 -257.879596) (xy 349.447104 -257.913886)
			(xy 349.465646 -257.914648) (xy 349.474536 -257.9116) (xy 349.50386 -257.902475) (xy 349.564481 -257.892654)
			(xy 349.595186 -257.892042) (xy 349.622443 -257.892404) (xy 349.676403 -257.90016) (xy 349.728709 -257.915517)
			(xy 349.778298 -257.938162) (xy 349.824158 -257.967633) (xy 349.865358 -258.003332) (xy 349.901058 -258.04453)
			(xy 349.930531 -258.09039) (xy 349.953178 -258.139978) (xy 349.968537 -258.192284) (xy 349.976295 -258.246243)
			(xy 349.976295 -258.300757) (xy 349.968537 -258.354716) (xy 349.956719 -258.394962) (xy 351.069908 -258.394962)
			(xy 351.073979 -258.33934) (xy 351.086105 -258.284903) (xy 351.106028 -258.232812) (xy 351.133324 -258.184177)
			(xy 351.16741 -258.140034) (xy 351.207559 -258.101325) (xy 351.252917 -258.068874) (xy 351.302517 -258.043373)
			(xy 351.355301 -258.025366) (xy 351.410144 -258.015236) (xy 351.465878 -258.013199) (xy 351.521315 -258.019299)
			(xy 351.575272 -258.033405) (xy 351.626601 -258.055217) (xy 351.674207 -258.084271) (xy 351.717075 -258.119946)
			(xy 351.754292 -258.161483) (xy 351.785065 -258.207996) (xy 351.808737 -258.258493) (xy 351.824805 -258.3119)
			(xy 351.832925 -258.367076) (xy 351.833434 -258.394962) (xy 354.117908 -258.394962) (xy 354.121979 -258.33934)
			(xy 354.134105 -258.284903) (xy 354.154028 -258.232812) (xy 354.181324 -258.184177) (xy 354.21541 -258.140034)
			(xy 354.255559 -258.101325) (xy 354.300917 -258.068874) (xy 354.350517 -258.043373) (xy 354.403301 -258.025366)
			(xy 354.458144 -258.015236) (xy 354.513878 -258.013199) (xy 354.569315 -258.019299) (xy 354.623272 -258.033405)
			(xy 354.674601 -258.055217) (xy 354.722207 -258.084271) (xy 354.765075 -258.119946) (xy 354.775485 -258.131564)
			(xy 358.458768 -258.131564) (xy 358.462839 -258.075942) (xy 358.474965 -258.021505) (xy 358.494888 -257.969414)
			(xy 358.522184 -257.920779) (xy 358.55627 -257.876636) (xy 358.596419 -257.837927) (xy 358.641777 -257.805476)
			(xy 358.691377 -257.779975) (xy 358.744161 -257.761968) (xy 358.799004 -257.751838) (xy 358.854738 -257.749801)
			(xy 358.910175 -257.755901) (xy 358.964132 -257.770007) (xy 359.015461 -257.791819) (xy 359.063067 -257.820873)
			(xy 359.105935 -257.856548) (xy 359.143152 -257.898085) (xy 359.173925 -257.944598) (xy 359.197597 -257.995095)
			(xy 359.213665 -258.048502) (xy 359.221785 -258.103678) (xy 359.222294 -258.131564) (xy 360.485942 -258.131564)
			(xy 360.490013 -258.075942) (xy 360.502139 -258.021505) (xy 360.522062 -257.969414) (xy 360.549358 -257.920779)
			(xy 360.583444 -257.876636) (xy 360.623593 -257.837927) (xy 360.668951 -257.805476) (xy 360.718551 -257.779975)
			(xy 360.771335 -257.761968) (xy 360.826178 -257.751838) (xy 360.881912 -257.749801) (xy 360.937349 -257.755901)
			(xy 360.991306 -257.770007) (xy 361.042635 -257.791819) (xy 361.090241 -257.820873) (xy 361.133109 -257.856548)
			(xy 361.170326 -257.898085) (xy 361.201099 -257.944598) (xy 361.224771 -257.995095) (xy 361.240839 -258.048502)
			(xy 361.248959 -258.103678) (xy 361.249468 -258.131564) (xy 362.517942 -258.131564) (xy 362.522013 -258.075942)
			(xy 362.534139 -258.021505) (xy 362.554062 -257.969414) (xy 362.581358 -257.920779) (xy 362.615444 -257.876636)
			(xy 362.655593 -257.837927) (xy 362.700951 -257.805476) (xy 362.750551 -257.779975) (xy 362.803335 -257.761968)
			(xy 362.858178 -257.751838) (xy 362.913912 -257.749801) (xy 362.969349 -257.755901) (xy 363.023306 -257.770007)
			(xy 363.074635 -257.791819) (xy 363.122241 -257.820873) (xy 363.165109 -257.856548) (xy 363.202326 -257.898085)
			(xy 363.233099 -257.944598) (xy 363.256771 -257.995095) (xy 363.272839 -258.048502) (xy 363.280959 -258.103678)
			(xy 363.281468 -258.131564) (xy 363.280959 -258.15945) (xy 363.272839 -258.214626) (xy 363.256771 -258.268033)
			(xy 363.233099 -258.31853) (xy 363.202326 -258.365043) (xy 363.165109 -258.40658) (xy 363.122241 -258.442255)
			(xy 363.074635 -258.471309) (xy 363.023306 -258.493121) (xy 362.969349 -258.507227) (xy 362.913912 -258.513327)
			(xy 362.858178 -258.51129) (xy 362.803335 -258.50116) (xy 362.750551 -258.483153) (xy 362.700951 -258.457652)
			(xy 362.655593 -258.425201) (xy 362.615444 -258.386492) (xy 362.581358 -258.342349) (xy 362.554062 -258.293714)
			(xy 362.534139 -258.241623) (xy 362.522013 -258.187186) (xy 362.517942 -258.131564) (xy 361.249468 -258.131564)
			(xy 361.248959 -258.15945) (xy 361.240839 -258.214626) (xy 361.224771 -258.268033) (xy 361.201099 -258.31853)
			(xy 361.170326 -258.365043) (xy 361.133109 -258.40658) (xy 361.090241 -258.442255) (xy 361.042635 -258.471309)
			(xy 360.991306 -258.493121) (xy 360.937349 -258.507227) (xy 360.881912 -258.513327) (xy 360.826178 -258.51129)
			(xy 360.771335 -258.50116) (xy 360.718551 -258.483153) (xy 360.668951 -258.457652) (xy 360.623593 -258.425201)
			(xy 360.583444 -258.386492) (xy 360.549358 -258.342349) (xy 360.522062 -258.293714) (xy 360.502139 -258.241623)
			(xy 360.490013 -258.187186) (xy 360.485942 -258.131564) (xy 359.222294 -258.131564) (xy 359.221785 -258.15945)
			(xy 359.213665 -258.214626) (xy 359.197597 -258.268033) (xy 359.173925 -258.31853) (xy 359.143152 -258.365043)
			(xy 359.105935 -258.40658) (xy 359.063067 -258.442255) (xy 359.015461 -258.471309) (xy 358.964132 -258.493121)
			(xy 358.910175 -258.507227) (xy 358.854738 -258.513327) (xy 358.799004 -258.51129) (xy 358.744161 -258.50116)
			(xy 358.691377 -258.483153) (xy 358.641777 -258.457652) (xy 358.596419 -258.425201) (xy 358.55627 -258.386492)
			(xy 358.522184 -258.342349) (xy 358.494888 -258.293714) (xy 358.474965 -258.241623) (xy 358.462839 -258.187186)
			(xy 358.458768 -258.131564) (xy 354.775485 -258.131564) (xy 354.802292 -258.161483) (xy 354.833065 -258.207996)
			(xy 354.856737 -258.258493) (xy 354.872805 -258.3119) (xy 354.880925 -258.367076) (xy 354.881434 -258.394962)
			(xy 354.880925 -258.422848) (xy 354.872805 -258.478024) (xy 354.856737 -258.531431) (xy 354.833065 -258.581928)
			(xy 354.802292 -258.628441) (xy 354.769112 -258.665472) (xy 369.426488 -258.665472) (xy 369.430559 -258.60985)
			(xy 369.442685 -258.555413) (xy 369.462608 -258.503322) (xy 369.489904 -258.454687) (xy 369.52399 -258.410544)
			(xy 369.564139 -258.371835) (xy 369.609497 -258.339384) (xy 369.659097 -258.313883) (xy 369.711881 -258.295876)
			(xy 369.766724 -258.285746) (xy 369.822458 -258.283709) (xy 369.877895 -258.289809) (xy 369.931852 -258.303915)
			(xy 369.983181 -258.325727) (xy 370.030787 -258.354781) (xy 370.073655 -258.390456) (xy 370.110872 -258.431993)
			(xy 370.141645 -258.478506) (xy 370.165317 -258.529003) (xy 370.181385 -258.58241) (xy 370.189505 -258.637586)
			(xy 370.189731 -258.649978) (xy 371.226332 -258.649978) (xy 371.230403 -258.594356) (xy 371.242529 -258.539919)
			(xy 371.262452 -258.487828) (xy 371.289748 -258.439193) (xy 371.323834 -258.39505) (xy 371.363983 -258.356341)
			(xy 371.409341 -258.32389) (xy 371.458941 -258.298389) (xy 371.511725 -258.280382) (xy 371.566568 -258.270252)
			(xy 371.622302 -258.268215) (xy 371.675403 -258.274058) (xy 377.069602 -258.274058) (xy 377.073673 -258.218436)
			(xy 377.085799 -258.163999) (xy 377.105722 -258.111908) (xy 377.133018 -258.063273) (xy 377.167104 -258.01913)
			(xy 377.207253 -257.980421) (xy 377.252611 -257.94797) (xy 377.302211 -257.922469) (xy 377.354995 -257.904462)
			(xy 377.409838 -257.894332) (xy 377.465572 -257.892295) (xy 377.521009 -257.898395) (xy 377.574966 -257.912501)
			(xy 377.626295 -257.934313) (xy 377.673901 -257.963367) (xy 377.716769 -257.999042) (xy 377.753986 -258.040579)
			(xy 377.784759 -258.087092) (xy 377.808431 -258.137589) (xy 377.824499 -258.190996) (xy 377.832619 -258.246172)
			(xy 377.833128 -258.274058) (xy 378.55474 -258.274058) (xy 378.558811 -258.218436) (xy 378.570937 -258.163999)
			(xy 378.59086 -258.111908) (xy 378.618156 -258.063273) (xy 378.652242 -258.01913) (xy 378.692391 -257.980421)
			(xy 378.737749 -257.94797) (xy 378.787349 -257.922469) (xy 378.840133 -257.904462) (xy 378.894976 -257.894332)
			(xy 378.95071 -257.892295) (xy 379.006147 -257.898395) (xy 379.060104 -257.912501) (xy 379.111433 -257.934313)
			(xy 379.159039 -257.963367) (xy 379.201907 -257.999042) (xy 379.239124 -258.040579) (xy 379.269897 -258.087092)
			(xy 379.293569 -258.137589) (xy 379.309637 -258.190996) (xy 379.317757 -258.246172) (xy 379.318266 -258.274058)
			(xy 379.317757 -258.301944) (xy 379.309637 -258.35712) (xy 379.293569 -258.410527) (xy 379.269897 -258.461024)
			(xy 379.239124 -258.507537) (xy 379.201907 -258.549074) (xy 379.159039 -258.584749) (xy 379.111433 -258.613803)
			(xy 379.060104 -258.635615) (xy 379.006147 -258.649721) (xy 378.95071 -258.655821) (xy 378.894976 -258.653784)
			(xy 378.840133 -258.643654) (xy 378.787349 -258.625647) (xy 378.737749 -258.600146) (xy 378.692391 -258.567695)
			(xy 378.652242 -258.528986) (xy 378.618156 -258.484843) (xy 378.59086 -258.436208) (xy 378.570937 -258.384117)
			(xy 378.558811 -258.32968) (xy 378.55474 -258.274058) (xy 377.833128 -258.274058) (xy 377.832619 -258.301944)
			(xy 377.824499 -258.35712) (xy 377.808431 -258.410527) (xy 377.784759 -258.461024) (xy 377.753986 -258.507537)
			(xy 377.716769 -258.549074) (xy 377.673901 -258.584749) (xy 377.626295 -258.613803) (xy 377.574966 -258.635615)
			(xy 377.521009 -258.649721) (xy 377.465572 -258.655821) (xy 377.409838 -258.653784) (xy 377.354995 -258.643654)
			(xy 377.302211 -258.625647) (xy 377.252611 -258.600146) (xy 377.207253 -258.567695) (xy 377.167104 -258.528986)
			(xy 377.133018 -258.484843) (xy 377.105722 -258.436208) (xy 377.085799 -258.384117) (xy 377.073673 -258.32968)
			(xy 377.069602 -258.274058) (xy 371.675403 -258.274058) (xy 371.677739 -258.274315) (xy 371.731696 -258.288421)
			(xy 371.783025 -258.310233) (xy 371.830631 -258.339287) (xy 371.873499 -258.374962) (xy 371.910716 -258.416499)
			(xy 371.941489 -258.463012) (xy 371.965161 -258.513509) (xy 371.981229 -258.566916) (xy 371.989349 -258.622092)
			(xy 371.989858 -258.649978) (xy 371.989349 -258.677864) (xy 371.987397 -258.691126) (xy 372.710708 -258.691126)
			(xy 372.714779 -258.635504) (xy 372.726905 -258.581067) (xy 372.746828 -258.528976) (xy 372.774124 -258.480341)
			(xy 372.80821 -258.436198) (xy 372.848359 -258.397489) (xy 372.893717 -258.365038) (xy 372.943317 -258.339537)
			(xy 372.996101 -258.32153) (xy 373.050944 -258.3114) (xy 373.106678 -258.309363) (xy 373.162115 -258.315463)
			(xy 373.216072 -258.329569) (xy 373.267401 -258.351381) (xy 373.315007 -258.380435) (xy 373.357875 -258.41611)
			(xy 373.395092 -258.457647) (xy 373.425865 -258.50416) (xy 373.449537 -258.554657) (xy 373.465605 -258.608064)
			(xy 373.473725 -258.66324) (xy 373.474234 -258.691126) (xy 373.473725 -258.719012) (xy 373.465605 -258.774188)
			(xy 373.449537 -258.827595) (xy 373.425865 -258.878092) (xy 373.395092 -258.924605) (xy 373.357875 -258.966142)
			(xy 373.315007 -259.001817) (xy 373.267401 -259.030871) (xy 373.216072 -259.052683) (xy 373.162115 -259.066789)
			(xy 373.106678 -259.072889) (xy 373.050944 -259.070852) (xy 372.996101 -259.060722) (xy 372.943317 -259.042715)
			(xy 372.893717 -259.017214) (xy 372.848359 -258.984763) (xy 372.80821 -258.946054) (xy 372.774124 -258.901911)
			(xy 372.746828 -258.853276) (xy 372.726905 -258.801185) (xy 372.714779 -258.746748) (xy 372.710708 -258.691126)
			(xy 371.987397 -258.691126) (xy 371.981229 -258.73304) (xy 371.965161 -258.786447) (xy 371.941489 -258.836944)
			(xy 371.910716 -258.883457) (xy 371.873499 -258.924994) (xy 371.830631 -258.960669) (xy 371.783025 -258.989723)
			(xy 371.731696 -259.011535) (xy 371.677739 -259.025641) (xy 371.622302 -259.031741) (xy 371.566568 -259.029704)
			(xy 371.511725 -259.019574) (xy 371.458941 -259.001567) (xy 371.409341 -258.976066) (xy 371.363983 -258.943615)
			(xy 371.323834 -258.904906) (xy 371.289748 -258.860763) (xy 371.262452 -258.812128) (xy 371.242529 -258.760037)
			(xy 371.230403 -258.7056) (xy 371.226332 -258.649978) (xy 370.189731 -258.649978) (xy 370.190014 -258.665472)
			(xy 370.189505 -258.693358) (xy 370.181385 -258.748534) (xy 370.165317 -258.801941) (xy 370.141645 -258.852438)
			(xy 370.110872 -258.898951) (xy 370.073655 -258.940488) (xy 370.030787 -258.976163) (xy 369.983181 -259.005217)
			(xy 369.931852 -259.027029) (xy 369.877895 -259.041135) (xy 369.822458 -259.047235) (xy 369.766724 -259.045198)
			(xy 369.711881 -259.035068) (xy 369.659097 -259.017061) (xy 369.609497 -258.99156) (xy 369.564139 -258.959109)
			(xy 369.52399 -258.9204) (xy 369.489904 -258.876257) (xy 369.462608 -258.827622) (xy 369.442685 -258.775531)
			(xy 369.430559 -258.721094) (xy 369.426488 -258.665472) (xy 354.769112 -258.665472) (xy 354.765075 -258.669978)
			(xy 354.722207 -258.705653) (xy 354.674601 -258.734707) (xy 354.623272 -258.756519) (xy 354.569315 -258.770625)
			(xy 354.513878 -258.776725) (xy 354.458144 -258.774688) (xy 354.403301 -258.764558) (xy 354.350517 -258.746551)
			(xy 354.300917 -258.72105) (xy 354.255559 -258.688599) (xy 354.21541 -258.64989) (xy 354.181324 -258.605747)
			(xy 354.154028 -258.557112) (xy 354.134105 -258.505021) (xy 354.121979 -258.450584) (xy 354.117908 -258.394962)
			(xy 351.833434 -258.394962) (xy 351.832925 -258.422848) (xy 351.824805 -258.478024) (xy 351.808737 -258.531431)
			(xy 351.785065 -258.581928) (xy 351.754292 -258.628441) (xy 351.717075 -258.669978) (xy 351.674207 -258.705653)
			(xy 351.626601 -258.734707) (xy 351.575272 -258.756519) (xy 351.521315 -258.770625) (xy 351.465878 -258.776725)
			(xy 351.410144 -258.774688) (xy 351.355301 -258.764558) (xy 351.302517 -258.746551) (xy 351.252917 -258.72105)
			(xy 351.207559 -258.688599) (xy 351.16741 -258.64989) (xy 351.133324 -258.605747) (xy 351.106028 -258.557112)
			(xy 351.086105 -258.505021) (xy 351.073979 -258.450584) (xy 351.069908 -258.394962) (xy 349.956719 -258.394962)
			(xy 349.953178 -258.407022) (xy 349.930531 -258.45661) (xy 349.901058 -258.50247) (xy 349.865358 -258.543668)
			(xy 349.824158 -258.579367) (xy 349.778298 -258.608838) (xy 349.728709 -258.631483) (xy 349.676403 -258.64684)
			(xy 349.622443 -258.654596) (xy 349.595186 -258.655058) (xy 349.574638 -258.654758) (xy 349.533782 -258.650305)
			(xy 349.513652 -258.646168) (xy 349.501714 -258.643628) (xy 349.478346 -258.649724) (xy 349.39859 -258.720336)
			(xy 349.3897 -258.742688) (xy 349.390716 -258.75488) (xy 349.392494 -258.79044) (xy 349.392008 -258.817691)
			(xy 349.384252 -258.871639) (xy 349.368897 -258.923934) (xy 349.346255 -258.973511) (xy 349.316789 -259.019361)
			(xy 349.281098 -259.060552) (xy 349.239907 -259.096243) (xy 349.194057 -259.125709) (xy 349.14448 -259.148351)
			(xy 349.092185 -259.163706) (xy 349.038237 -259.171462) (xy 348.983735 -259.171462) (xy 348.929787 -259.163706)
			(xy 348.877492 -259.148351) (xy 348.827915 -259.125709) (xy 348.782065 -259.096243) (xy 348.740874 -259.060552)
			(xy 348.705183 -259.019361) (xy 348.675717 -258.973511) (xy 348.653075 -258.923934) (xy 348.63772 -258.871639)
			(xy 348.629964 -258.817691) (xy 348.629478 -258.79044) (xy 348.630055 -258.761315) (xy 348.638916 -258.703744)
			(xy 348.656424 -258.648188) (xy 348.682173 -258.595939) (xy 348.715562 -258.548209) (xy 348.755818 -258.506109)
			(xy 348.778576 -258.487926) (xy 348.787974 -258.48056) (xy 348.798388 -258.459224) (xy 348.797626 -258.354068)
			(xy 348.786958 -258.332986) (xy 348.777052 -258.325874) (xy 348.753624 -258.307704) (xy 348.712094 -258.265398)
			(xy 348.677603 -258.21718) (xy 348.650979 -258.164211) (xy 348.632864 -258.107762) (xy 348.623692 -258.049192)
			(xy 348.623128 -258.01955) (xy 340.160864 -258.01955) (xy 338.457286 -259.723128) (xy 338.44989 -259.72998)
			(xy 338.431291 -259.737721) (xy 338.421218 -259.738114) (xy 338.25815 -259.738114) (xy 338.248159 -259.738643)
			(xy 338.229715 -259.746345) (xy 338.222336 -259.7531) (xy 338.192832 -259.782564) (xy 344.363802 -259.782564)
			(xy 344.364285 -259.756519) (xy 344.371376 -259.704915) (xy 344.385422 -259.654755) (xy 344.40616 -259.606973)
			(xy 344.433206 -259.562455) (xy 344.466057 -259.522031) (xy 344.504102 -259.486452) (xy 344.546633 -259.456379)
			(xy 344.569542 -259.443982) (xy 344.581287 -259.437376) (xy 344.601097 -259.419124) (xy 344.615446 -259.396327)
			(xy 344.623336 -259.370572) (xy 344.624217 -259.343649) (xy 344.618028 -259.317433) (xy 344.6052 -259.293747)
			(xy 344.596212 -259.283708) (xy 344.576539 -259.262313) (xy 344.543262 -259.214663) (xy 344.517606 -259.162512)
			(xy 344.500166 -259.107071) (xy 344.491346 -259.049624) (xy 344.490802 -259.020564) (xy 344.491288 -258.993313)
			(xy 344.499044 -258.939365) (xy 344.514399 -258.88707) (xy 344.537041 -258.837493) (xy 344.566507 -258.791643)
			(xy 344.602198 -258.750452) (xy 344.643389 -258.714761) (xy 344.689239 -258.685295) (xy 344.738816 -258.662653)
			(xy 344.791111 -258.647298) (xy 344.845059 -258.639542) (xy 344.899561 -258.639542) (xy 344.953509 -258.647298)
			(xy 345.005804 -258.662653) (xy 345.055381 -258.685295) (xy 345.101231 -258.714761) (xy 345.142422 -258.750452)
			(xy 345.178113 -258.791643) (xy 345.207579 -258.837493) (xy 345.230221 -258.88707) (xy 345.245576 -258.939365)
			(xy 345.253332 -258.993313) (xy 345.253818 -259.020564) (xy 345.379292 -259.020564) (xy 345.383363 -258.964942)
			(xy 345.395489 -258.910505) (xy 345.415412 -258.858414) (xy 345.442708 -258.809779) (xy 345.476794 -258.765636)
			(xy 345.516943 -258.726927) (xy 345.562301 -258.694476) (xy 345.611901 -258.668975) (xy 345.664685 -258.650968)
			(xy 345.719528 -258.640838) (xy 345.775262 -258.638801) (xy 345.830699 -258.644901) (xy 345.884656 -258.659007)
			(xy 345.935985 -258.680819) (xy 345.983591 -258.709873) (xy 346.026459 -258.745548) (xy 346.058717 -258.78155)
			(xy 347.060518 -258.78155) (xy 347.064589 -258.725928) (xy 347.076715 -258.671491) (xy 347.096638 -258.6194)
			(xy 347.123934 -258.570765) (xy 347.15802 -258.526622) (xy 347.198169 -258.487913) (xy 347.243527 -258.455462)
			(xy 347.293127 -258.429961) (xy 347.345911 -258.411954) (xy 347.400754 -258.401824) (xy 347.456488 -258.399787)
			(xy 347.511925 -258.405887) (xy 347.565882 -258.419993) (xy 347.617211 -258.441805) (xy 347.664817 -258.470859)
			(xy 347.707685 -258.506534) (xy 347.744902 -258.548071) (xy 347.775675 -258.594584) (xy 347.799347 -258.645081)
			(xy 347.815415 -258.698488) (xy 347.823535 -258.753664) (xy 347.824044 -258.78155) (xy 347.823535 -258.809436)
			(xy 347.815415 -258.864612) (xy 347.799347 -258.918019) (xy 347.775675 -258.968516) (xy 347.744902 -259.015029)
			(xy 347.707685 -259.056566) (xy 347.664817 -259.092241) (xy 347.617211 -259.121295) (xy 347.565882 -259.143107)
			(xy 347.511925 -259.157213) (xy 347.456488 -259.163313) (xy 347.400754 -259.161276) (xy 347.345911 -259.151146)
			(xy 347.293127 -259.133139) (xy 347.243527 -259.107638) (xy 347.198169 -259.075187) (xy 347.15802 -259.036478)
			(xy 347.123934 -258.992335) (xy 347.096638 -258.9437) (xy 347.076715 -258.891609) (xy 347.064589 -258.837172)
			(xy 347.060518 -258.78155) (xy 346.058717 -258.78155) (xy 346.063676 -258.787085) (xy 346.094449 -258.833598)
			(xy 346.118121 -258.884095) (xy 346.134189 -258.937502) (xy 346.142309 -258.992678) (xy 346.142818 -259.020564)
			(xy 346.142309 -259.04845) (xy 346.134189 -259.103626) (xy 346.118121 -259.157033) (xy 346.094449 -259.20753)
			(xy 346.063676 -259.254043) (xy 346.026459 -259.29558) (xy 345.983591 -259.331255) (xy 345.935985 -259.360309)
			(xy 345.884656 -259.382121) (xy 345.830699 -259.396227) (xy 345.775262 -259.402327) (xy 345.719528 -259.40029)
			(xy 345.664685 -259.39016) (xy 345.611901 -259.372153) (xy 345.562301 -259.346652) (xy 345.516943 -259.314201)
			(xy 345.476794 -259.275492) (xy 345.442708 -259.231349) (xy 345.415412 -259.182714) (xy 345.395489 -259.130623)
			(xy 345.383363 -259.076186) (xy 345.379292 -259.020564) (xy 345.253818 -259.020564) (xy 345.253401 -259.046611)
			(xy 345.246304 -259.09822) (xy 345.232252 -259.148384) (xy 345.211505 -259.196169) (xy 345.18445 -259.240687)
			(xy 345.151589 -259.281109) (xy 345.113534 -259.316685) (xy 345.070992 -259.346753) (xy 345.048078 -259.359146)
			(xy 345.036307 -259.365705) (xy 345.016506 -259.383972) (xy 345.002166 -259.406779) (xy 344.994284 -259.43254)
			(xy 344.993407 -259.459466) (xy 344.999597 -259.485685) (xy 345.012422 -259.509377) (xy 345.021408 -259.51942)
			(xy 345.036122 -259.535422) (xy 346.407738 -259.535422) (xy 346.411809 -259.4798) (xy 346.423935 -259.425363)
			(xy 346.443858 -259.373272) (xy 346.471154 -259.324637) (xy 346.50524 -259.280494) (xy 346.545389 -259.241785)
			(xy 346.590747 -259.209334) (xy 346.640347 -259.183833) (xy 346.693131 -259.165826) (xy 346.747974 -259.155696)
			(xy 346.803708 -259.153659) (xy 346.859145 -259.159759) (xy 346.913102 -259.173865) (xy 346.955213 -259.19176)
			(xy 355.780592 -259.19176) (xy 355.784663 -259.136138) (xy 355.796789 -259.081701) (xy 355.816712 -259.02961)
			(xy 355.844008 -258.980975) (xy 355.878094 -258.936832) (xy 355.918243 -258.898123) (xy 355.963601 -258.865672)
			(xy 356.013201 -258.840171) (xy 356.065985 -258.822164) (xy 356.120828 -258.812034) (xy 356.176562 -258.809997)
			(xy 356.231999 -258.816097) (xy 356.285956 -258.830203) (xy 356.337285 -258.852015) (xy 356.384891 -258.881069)
			(xy 356.427759 -258.916744) (xy 356.464976 -258.958281) (xy 356.495749 -259.004794) (xy 356.519421 -259.055291)
			(xy 356.535489 -259.108698) (xy 356.541209 -259.147564) (xy 362.539024 -259.147564) (xy 362.543095 -259.091942)
			(xy 362.555221 -259.037505) (xy 362.575144 -258.985414) (xy 362.60244 -258.936779) (xy 362.636526 -258.892636)
			(xy 362.676675 -258.853927) (xy 362.722033 -258.821476) (xy 362.771633 -258.795975) (xy 362.824417 -258.777968)
			(xy 362.87926 -258.767838) (xy 362.934994 -258.765801) (xy 362.990431 -258.771901) (xy 363.044388 -258.786007)
			(xy 363.095717 -258.807819) (xy 363.143323 -258.836873) (xy 363.186191 -258.872548) (xy 363.223408 -258.914085)
			(xy 363.254181 -258.960598) (xy 363.277853 -259.011095) (xy 363.293921 -259.064502) (xy 363.302041 -259.119678)
			(xy 363.30255 -259.147564) (xy 363.302041 -259.17545) (xy 363.293921 -259.230626) (xy 363.277853 -259.284033)
			(xy 363.254181 -259.33453) (xy 363.223408 -259.381043) (xy 363.186191 -259.42258) (xy 363.143323 -259.458255)
			(xy 363.110941 -259.478018) (xy 365.532922 -259.478018) (xy 365.536993 -259.422396) (xy 365.549119 -259.367959)
			(xy 365.569042 -259.315868) (xy 365.596338 -259.267233) (xy 365.630424 -259.22309) (xy 365.670573 -259.184381)
			(xy 365.715931 -259.15193) (xy 365.765531 -259.126429) (xy 365.818315 -259.108422) (xy 365.873158 -259.098292)
			(xy 365.928892 -259.096255) (xy 365.984329 -259.102355) (xy 366.038286 -259.116461) (xy 366.089615 -259.138273)
			(xy 366.137221 -259.167327) (xy 366.180089 -259.203002) (xy 366.217306 -259.244539) (xy 366.248079 -259.291052)
			(xy 366.271751 -259.341549) (xy 366.287819 -259.394956) (xy 366.295939 -259.450132) (xy 366.296448 -259.478018)
			(xy 366.295939 -259.505904) (xy 366.287819 -259.56108) (xy 366.271751 -259.614487) (xy 366.248079 -259.664984)
			(xy 366.217306 -259.711497) (xy 366.180089 -259.753034) (xy 366.137221 -259.788709) (xy 366.089615 -259.817763)
			(xy 366.038286 -259.839575) (xy 365.984329 -259.853681) (xy 365.928892 -259.859781) (xy 365.873158 -259.857744)
			(xy 365.818315 -259.847614) (xy 365.765531 -259.829607) (xy 365.715931 -259.804106) (xy 365.670573 -259.771655)
			(xy 365.630424 -259.732946) (xy 365.596338 -259.688803) (xy 365.569042 -259.640168) (xy 365.549119 -259.588077)
			(xy 365.536993 -259.53364) (xy 365.532922 -259.478018) (xy 363.110941 -259.478018) (xy 363.095717 -259.487309)
			(xy 363.044388 -259.509121) (xy 362.990431 -259.523227) (xy 362.934994 -259.529327) (xy 362.87926 -259.52729)
			(xy 362.824417 -259.51716) (xy 362.771633 -259.499153) (xy 362.722033 -259.473652) (xy 362.676675 -259.441201)
			(xy 362.636526 -259.402492) (xy 362.60244 -259.358349) (xy 362.575144 -259.309714) (xy 362.555221 -259.257623)
			(xy 362.543095 -259.203186) (xy 362.539024 -259.147564) (xy 356.541209 -259.147564) (xy 356.543609 -259.163874)
			(xy 356.544118 -259.19176) (xy 356.543609 -259.219646) (xy 356.535489 -259.274822) (xy 356.519421 -259.328229)
			(xy 356.495749 -259.378726) (xy 356.464976 -259.425239) (xy 356.427759 -259.466776) (xy 356.384891 -259.502451)
			(xy 356.337285 -259.531505) (xy 356.285956 -259.553317) (xy 356.231999 -259.567423) (xy 356.176562 -259.573523)
			(xy 356.120828 -259.571486) (xy 356.065985 -259.561356) (xy 356.013201 -259.543349) (xy 355.963601 -259.517848)
			(xy 355.918243 -259.485397) (xy 355.878094 -259.446688) (xy 355.844008 -259.402545) (xy 355.816712 -259.35391)
			(xy 355.796789 -259.301819) (xy 355.784663 -259.247382) (xy 355.780592 -259.19176) (xy 346.955213 -259.19176)
			(xy 346.964431 -259.195677) (xy 347.012037 -259.224731) (xy 347.054905 -259.260406) (xy 347.092122 -259.301943)
			(xy 347.122895 -259.348456) (xy 347.146567 -259.398953) (xy 347.162635 -259.45236) (xy 347.170755 -259.507536)
			(xy 347.171264 -259.535422) (xy 347.170755 -259.563308) (xy 347.162635 -259.618484) (xy 347.146567 -259.671891)
			(xy 347.122895 -259.722388) (xy 347.092122 -259.768901) (xy 347.054905 -259.810438) (xy 347.012037 -259.846113)
			(xy 346.964431 -259.875167) (xy 346.913102 -259.896979) (xy 346.859145 -259.911085) (xy 346.803708 -259.917185)
			(xy 346.747974 -259.915148) (xy 346.693131 -259.905018) (xy 346.640347 -259.887011) (xy 346.590747 -259.86151)
			(xy 346.545389 -259.829059) (xy 346.50524 -259.79035) (xy 346.471154 -259.746207) (xy 346.443858 -259.697572)
			(xy 346.423935 -259.645481) (xy 346.411809 -259.591044) (xy 346.407738 -259.535422) (xy 345.036122 -259.535422)
			(xy 345.041081 -259.540815) (xy 345.074361 -259.588464) (xy 345.100018 -259.640614) (xy 345.117458 -259.696056)
			(xy 345.126275 -259.753504) (xy 345.126818 -259.782564) (xy 345.126332 -259.809815) (xy 345.118576 -259.863763)
			(xy 345.103221 -259.916058) (xy 345.101895 -259.918962) (xy 351.069908 -259.918962) (xy 351.073979 -259.86334)
			(xy 351.086105 -259.808903) (xy 351.106028 -259.756812) (xy 351.133324 -259.708177) (xy 351.16741 -259.664034)
			(xy 351.207559 -259.625325) (xy 351.252917 -259.592874) (xy 351.302517 -259.567373) (xy 351.355301 -259.549366)
			(xy 351.410144 -259.539236) (xy 351.465878 -259.537199) (xy 351.521315 -259.543299) (xy 351.575272 -259.557405)
			(xy 351.626601 -259.579217) (xy 351.674207 -259.608271) (xy 351.717075 -259.643946) (xy 351.754292 -259.685483)
			(xy 351.785065 -259.731996) (xy 351.808737 -259.782493) (xy 351.824805 -259.8359) (xy 351.832925 -259.891076)
			(xy 351.833434 -259.918962) (xy 352.593908 -259.918962) (xy 352.597979 -259.86334) (xy 352.610105 -259.808903)
			(xy 352.630028 -259.756812) (xy 352.657324 -259.708177) (xy 352.69141 -259.664034) (xy 352.731559 -259.625325)
			(xy 352.776917 -259.592874) (xy 352.826517 -259.567373) (xy 352.879301 -259.549366) (xy 352.934144 -259.539236)
			(xy 352.989878 -259.537199) (xy 353.045315 -259.543299) (xy 353.099272 -259.557405) (xy 353.150601 -259.579217)
			(xy 353.198207 -259.608271) (xy 353.241075 -259.643946) (xy 353.278292 -259.685483) (xy 353.309065 -259.731996)
			(xy 353.332737 -259.782493) (xy 353.348805 -259.8359) (xy 353.356925 -259.891076) (xy 353.357434 -259.918962)
			(xy 354.117908 -259.918962) (xy 354.121979 -259.86334) (xy 354.134105 -259.808903) (xy 354.154028 -259.756812)
			(xy 354.181324 -259.708177) (xy 354.21541 -259.664034) (xy 354.255559 -259.625325) (xy 354.300917 -259.592874)
			(xy 354.350517 -259.567373) (xy 354.403301 -259.549366) (xy 354.458144 -259.539236) (xy 354.513878 -259.537199)
			(xy 354.569315 -259.543299) (xy 354.623272 -259.557405) (xy 354.674601 -259.579217) (xy 354.722207 -259.608271)
			(xy 354.765075 -259.643946) (xy 354.802292 -259.685483) (xy 354.833065 -259.731996) (xy 354.856737 -259.782493)
			(xy 354.872805 -259.8359) (xy 354.880925 -259.891076) (xy 354.881434 -259.918962) (xy 354.880961 -259.94487)
			(xy 369.513102 -259.94487) (xy 369.517173 -259.889248) (xy 369.529299 -259.834811) (xy 369.549222 -259.78272)
			(xy 369.576518 -259.734085) (xy 369.610604 -259.689942) (xy 369.650753 -259.651233) (xy 369.696111 -259.618782)
			(xy 369.745711 -259.593281) (xy 369.798495 -259.575274) (xy 369.853338 -259.565144) (xy 369.909072 -259.563107)
			(xy 369.964509 -259.569207) (xy 369.991702 -259.576316) (xy 377.069602 -259.576316) (xy 377.073673 -259.520694)
			(xy 377.085799 -259.466257) (xy 377.105722 -259.414166) (xy 377.133018 -259.365531) (xy 377.167104 -259.321388)
			(xy 377.207253 -259.282679) (xy 377.252611 -259.250228) (xy 377.302211 -259.224727) (xy 377.354995 -259.20672)
			(xy 377.409838 -259.19659) (xy 377.465572 -259.194553) (xy 377.521009 -259.200653) (xy 377.574966 -259.214759)
			(xy 377.626295 -259.236571) (xy 377.673901 -259.265625) (xy 377.716769 -259.3013) (xy 377.753986 -259.342837)
			(xy 377.784759 -259.38935) (xy 377.808431 -259.439847) (xy 377.824499 -259.493254) (xy 377.832619 -259.54843)
			(xy 377.833128 -259.576316) (xy 378.545088 -259.576316) (xy 378.549159 -259.520694) (xy 378.561285 -259.466257)
			(xy 378.581208 -259.414166) (xy 378.608504 -259.365531) (xy 378.64259 -259.321388) (xy 378.682739 -259.282679)
			(xy 378.728097 -259.250228) (xy 378.777697 -259.224727) (xy 378.830481 -259.20672) (xy 378.885324 -259.19659)
			(xy 378.941058 -259.194553) (xy 378.996495 -259.200653) (xy 379.050452 -259.214759) (xy 379.101781 -259.236571)
			(xy 379.149387 -259.265625) (xy 379.192255 -259.3013) (xy 379.229472 -259.342837) (xy 379.260245 -259.38935)
			(xy 379.283917 -259.439847) (xy 379.299985 -259.493254) (xy 379.308105 -259.54843) (xy 379.308614 -259.576316)
			(xy 379.434088 -259.576316) (xy 379.438159 -259.520694) (xy 379.450285 -259.466257) (xy 379.470208 -259.414166)
			(xy 379.497504 -259.365531) (xy 379.53159 -259.321388) (xy 379.571739 -259.282679) (xy 379.617097 -259.250228)
			(xy 379.666697 -259.224727) (xy 379.719481 -259.20672) (xy 379.774324 -259.19659) (xy 379.830058 -259.194553)
			(xy 379.885495 -259.200653) (xy 379.939452 -259.214759) (xy 379.990781 -259.236571) (xy 380.038387 -259.265625)
			(xy 380.081255 -259.3013) (xy 380.118472 -259.342837) (xy 380.149245 -259.38935) (xy 380.172917 -259.439847)
			(xy 380.188985 -259.493254) (xy 380.197105 -259.54843) (xy 380.197614 -259.576316) (xy 380.197105 -259.604202)
			(xy 380.188985 -259.659378) (xy 380.172917 -259.712785) (xy 380.149245 -259.763282) (xy 380.118472 -259.809795)
			(xy 380.081255 -259.851332) (xy 380.038387 -259.887007) (xy 379.990781 -259.916061) (xy 379.939452 -259.937873)
			(xy 379.885495 -259.951979) (xy 379.830058 -259.958079) (xy 379.774324 -259.956042) (xy 379.719481 -259.945912)
			(xy 379.666697 -259.927905) (xy 379.617097 -259.902404) (xy 379.571739 -259.869953) (xy 379.53159 -259.831244)
			(xy 379.497504 -259.787101) (xy 379.470208 -259.738466) (xy 379.450285 -259.686375) (xy 379.438159 -259.631938)
			(xy 379.434088 -259.576316) (xy 379.308614 -259.576316) (xy 379.308105 -259.604202) (xy 379.299985 -259.659378)
			(xy 379.283917 -259.712785) (xy 379.260245 -259.763282) (xy 379.229472 -259.809795) (xy 379.192255 -259.851332)
			(xy 379.149387 -259.887007) (xy 379.101781 -259.916061) (xy 379.050452 -259.937873) (xy 378.996495 -259.951979)
			(xy 378.941058 -259.958079) (xy 378.885324 -259.956042) (xy 378.830481 -259.945912) (xy 378.777697 -259.927905)
			(xy 378.728097 -259.902404) (xy 378.682739 -259.869953) (xy 378.64259 -259.831244) (xy 378.608504 -259.787101)
			(xy 378.581208 -259.738466) (xy 378.561285 -259.686375) (xy 378.549159 -259.631938) (xy 378.545088 -259.576316)
			(xy 377.833128 -259.576316) (xy 377.832619 -259.604202) (xy 377.824499 -259.659378) (xy 377.808431 -259.712785)
			(xy 377.784759 -259.763282) (xy 377.753986 -259.809795) (xy 377.716769 -259.851332) (xy 377.673901 -259.887007)
			(xy 377.626295 -259.916061) (xy 377.574966 -259.937873) (xy 377.521009 -259.951979) (xy 377.465572 -259.958079)
			(xy 377.409838 -259.956042) (xy 377.354995 -259.945912) (xy 377.302211 -259.927905) (xy 377.252611 -259.902404)
			(xy 377.207253 -259.869953) (xy 377.167104 -259.831244) (xy 377.133018 -259.787101) (xy 377.105722 -259.738466)
			(xy 377.085799 -259.686375) (xy 377.073673 -259.631938) (xy 377.069602 -259.576316) (xy 369.991702 -259.576316)
			(xy 370.018466 -259.583313) (xy 370.069795 -259.605125) (xy 370.117401 -259.634179) (xy 370.160269 -259.669854)
			(xy 370.197486 -259.711391) (xy 370.228259 -259.757904) (xy 370.251931 -259.808401) (xy 370.267999 -259.861808)
			(xy 370.276119 -259.916984) (xy 370.276628 -259.94487) (xy 370.276119 -259.972756) (xy 370.267999 -260.027932)
			(xy 370.255162 -260.0706) (xy 371.942866 -260.0706) (xy 371.946937 -260.014978) (xy 371.959063 -259.960541)
			(xy 371.978986 -259.90845) (xy 372.006282 -259.859815) (xy 372.040368 -259.815672) (xy 372.080517 -259.776963)
			(xy 372.125875 -259.744512) (xy 372.175475 -259.719011) (xy 372.228259 -259.701004) (xy 372.283102 -259.690874)
			(xy 372.338836 -259.688837) (xy 372.394273 -259.694937) (xy 372.44823 -259.709043) (xy 372.499559 -259.730855)
			(xy 372.547165 -259.759909) (xy 372.590033 -259.795584) (xy 372.62725 -259.837121) (xy 372.658023 -259.883634)
			(xy 372.681695 -259.934131) (xy 372.697763 -259.987538) (xy 372.705883 -260.042714) (xy 372.706392 -260.0706)
			(xy 372.705883 -260.098486) (xy 372.697763 -260.153662) (xy 372.695701 -260.160516) (xy 376.181872 -260.160516)
			(xy 376.185943 -260.104894) (xy 376.198069 -260.050457) (xy 376.217992 -259.998366) (xy 376.245288 -259.949731)
			(xy 376.279374 -259.905588) (xy 376.319523 -259.866879) (xy 376.364881 -259.834428) (xy 376.414481 -259.808927)
			(xy 376.467265 -259.79092) (xy 376.522108 -259.78079) (xy 376.577842 -259.778753) (xy 376.633279 -259.784853)
			(xy 376.687236 -259.798959) (xy 376.738565 -259.820771) (xy 376.786171 -259.849825) (xy 376.829039 -259.8855)
			(xy 376.866256 -259.927037) (xy 376.897029 -259.97355) (xy 376.920701 -260.024047) (xy 376.936769 -260.077454)
			(xy 376.944889 -260.13263) (xy 376.945398 -260.160516) (xy 376.944889 -260.188402) (xy 376.936769 -260.243578)
			(xy 376.920701 -260.296985) (xy 376.901326 -260.338316) (xy 382.596136 -260.338316) (xy 382.596671 -260.308933)
			(xy 382.605701 -260.250865) (xy 382.623533 -260.194871) (xy 382.649745 -260.142275) (xy 382.683717 -260.094324)
			(xy 382.724644 -260.052153) (xy 382.747774 -260.034024) (xy 382.757172 -260.026658) (xy 382.767586 -260.006084)
			(xy 382.76911 -259.902198) (xy 382.759204 -259.881116) (xy 382.75006 -259.87375) (xy 382.728198 -259.855561)
			(xy 382.68966 -259.813737) (xy 382.657756 -259.766658) (xy 382.633192 -259.715365) (xy 382.616511 -259.660995)
			(xy 382.608084 -259.604752) (xy 382.607566 -259.576316) (xy 382.608052 -259.549065) (xy 382.615808 -259.495117)
			(xy 382.631163 -259.442822) (xy 382.653805 -259.393245) (xy 382.683271 -259.347395) (xy 382.718962 -259.306204)
			(xy 382.760153 -259.270513) (xy 382.806003 -259.241047) (xy 382.85558 -259.218405) (xy 382.907875 -259.20305)
			(xy 382.961823 -259.195294) (xy 383.016325 -259.195294) (xy 383.070273 -259.20305) (xy 383.122568 -259.218405)
			(xy 383.172145 -259.241047) (xy 383.217995 -259.270513) (xy 383.259186 -259.306204) (xy 383.294877 -259.347395)
			(xy 383.324343 -259.393245) (xy 383.326982 -259.399024) (xy 386.435598 -259.399024) (xy 386.439669 -259.343402)
			(xy 386.451795 -259.288965) (xy 386.471718 -259.236874) (xy 386.499014 -259.188239) (xy 386.5331 -259.144096)
			(xy 386.573249 -259.105387) (xy 386.618607 -259.072936) (xy 386.668207 -259.047435) (xy 386.720991 -259.029428)
			(xy 386.775834 -259.019298) (xy 386.831568 -259.017261) (xy 386.887005 -259.023361) (xy 386.940962 -259.037467)
			(xy 386.992291 -259.059279) (xy 387.039897 -259.088333) (xy 387.082765 -259.124008) (xy 387.119982 -259.165545)
			(xy 387.150755 -259.212058) (xy 387.174427 -259.262555) (xy 387.190495 -259.315962) (xy 387.198615 -259.371138)
			(xy 387.199124 -259.399024) (xy 387.198615 -259.42691) (xy 387.190495 -259.482086) (xy 387.174427 -259.535493)
			(xy 387.150755 -259.58599) (xy 387.119982 -259.632503) (xy 387.082765 -259.67404) (xy 387.039897 -259.709715)
			(xy 386.992291 -259.738769) (xy 386.940962 -259.760581) (xy 386.887005 -259.774687) (xy 386.831568 -259.780787)
			(xy 386.775834 -259.77875) (xy 386.720991 -259.76862) (xy 386.668207 -259.750613) (xy 386.618607 -259.725112)
			(xy 386.573249 -259.692661) (xy 386.5331 -259.653952) (xy 386.499014 -259.609809) (xy 386.471718 -259.561174)
			(xy 386.451795 -259.509083) (xy 386.439669 -259.454646) (xy 386.435598 -259.399024) (xy 383.326982 -259.399024)
			(xy 383.346985 -259.442822) (xy 383.36234 -259.495117) (xy 383.370096 -259.549065) (xy 383.370582 -259.576316)
			(xy 383.370063 -259.605699) (xy 383.361029 -259.663767) (xy 383.343193 -259.719762) (xy 383.316978 -259.772358)
			(xy 383.283003 -259.820308) (xy 383.242074 -259.862479) (xy 383.218944 -259.880608) (xy 383.209546 -259.887974)
			(xy 383.199132 -259.908548) (xy 383.197608 -260.012434) (xy 383.207514 -260.033516) (xy 383.216658 -260.040882)
			(xy 383.238471 -260.059128) (xy 383.277015 -260.100938) (xy 383.308928 -260.148004) (xy 383.333501 -260.199286)
			(xy 383.350191 -260.253647) (xy 383.358629 -260.309883) (xy 383.359152 -260.338316) (xy 383.992626 -260.338316)
			(xy 383.996697 -260.282694) (xy 384.008823 -260.228257) (xy 384.028746 -260.176166) (xy 384.056042 -260.127531)
			(xy 384.090128 -260.083388) (xy 384.130277 -260.044679) (xy 384.175635 -260.012228) (xy 384.225235 -259.986727)
			(xy 384.278019 -259.96872) (xy 384.332862 -259.95859) (xy 384.388596 -259.956553) (xy 384.444033 -259.962653)
			(xy 384.49799 -259.976759) (xy 384.549319 -259.998571) (xy 384.596925 -260.027625) (xy 384.639793 -260.0633)
			(xy 384.67701 -260.104837) (xy 384.707783 -260.15135) (xy 384.731455 -260.201847) (xy 384.747523 -260.255254)
			(xy 384.755643 -260.31043) (xy 384.756152 -260.338316) (xy 384.879086 -260.338316) (xy 384.883157 -260.282694)
			(xy 384.895283 -260.228257) (xy 384.915206 -260.176166) (xy 384.942502 -260.127531) (xy 384.976588 -260.083388)
			(xy 385.016737 -260.044679) (xy 385.062095 -260.012228) (xy 385.111695 -259.986727) (xy 385.164479 -259.96872)
			(xy 385.219322 -259.95859) (xy 385.275056 -259.956553) (xy 385.330493 -259.962653) (xy 385.38445 -259.976759)
			(xy 385.435779 -259.998571) (xy 385.483385 -260.027625) (xy 385.526253 -260.0633) (xy 385.56347 -260.104837)
			(xy 385.594243 -260.15135) (xy 385.617915 -260.201847) (xy 385.633983 -260.255254) (xy 385.642103 -260.31043)
			(xy 385.642612 -260.338316) (xy 385.642103 -260.366202) (xy 385.641123 -260.37286) (xy 387.427722 -260.37286)
			(xy 387.431793 -260.317238) (xy 387.443919 -260.262801) (xy 387.463842 -260.21071) (xy 387.491138 -260.162075)
			(xy 387.525224 -260.117932) (xy 387.565373 -260.079223) (xy 387.610731 -260.046772) (xy 387.660331 -260.021271)
			(xy 387.713115 -260.003264) (xy 387.767958 -259.993134) (xy 387.823692 -259.991097) (xy 387.879129 -259.997197)
			(xy 387.933086 -260.011303) (xy 387.984415 -260.033115) (xy 388.032021 -260.062169) (xy 388.074889 -260.097844)
			(xy 388.112106 -260.139381) (xy 388.142879 -260.185894) (xy 388.166551 -260.236391) (xy 388.182619 -260.289798)
			(xy 388.190739 -260.344974) (xy 388.191248 -260.37286) (xy 388.190739 -260.400746) (xy 388.182619 -260.455922)
			(xy 388.166551 -260.509329) (xy 388.142879 -260.559826) (xy 388.112106 -260.606339) (xy 388.074889 -260.647876)
			(xy 388.032021 -260.683551) (xy 387.984415 -260.712605) (xy 387.933086 -260.734417) (xy 387.879129 -260.748523)
			(xy 387.823692 -260.754623) (xy 387.767958 -260.752586) (xy 387.713115 -260.742456) (xy 387.660331 -260.724449)
			(xy 387.610731 -260.698948) (xy 387.565373 -260.666497) (xy 387.525224 -260.627788) (xy 387.491138 -260.583645)
			(xy 387.463842 -260.53501) (xy 387.443919 -260.482919) (xy 387.431793 -260.428482) (xy 387.427722 -260.37286)
			(xy 385.641123 -260.37286) (xy 385.633983 -260.421378) (xy 385.617915 -260.474785) (xy 385.594243 -260.525282)
			(xy 385.56347 -260.571795) (xy 385.526253 -260.613332) (xy 385.483385 -260.649007) (xy 385.435779 -260.678061)
			(xy 385.38445 -260.699873) (xy 385.330493 -260.713979) (xy 385.275056 -260.720079) (xy 385.219322 -260.718042)
			(xy 385.164479 -260.707912) (xy 385.111695 -260.689905) (xy 385.062095 -260.664404) (xy 385.016737 -260.631953)
			(xy 384.976588 -260.593244) (xy 384.942502 -260.549101) (xy 384.915206 -260.500466) (xy 384.895283 -260.448375)
			(xy 384.883157 -260.393938) (xy 384.879086 -260.338316) (xy 384.756152 -260.338316) (xy 384.755643 -260.366202)
			(xy 384.747523 -260.421378) (xy 384.731455 -260.474785) (xy 384.707783 -260.525282) (xy 384.67701 -260.571795)
			(xy 384.639793 -260.613332) (xy 384.596925 -260.649007) (xy 384.549319 -260.678061) (xy 384.49799 -260.699873)
			(xy 384.444033 -260.713979) (xy 384.388596 -260.720079) (xy 384.332862 -260.718042) (xy 384.278019 -260.707912)
			(xy 384.225235 -260.689905) (xy 384.175635 -260.664404) (xy 384.130277 -260.631953) (xy 384.090128 -260.593244)
			(xy 384.056042 -260.549101) (xy 384.028746 -260.500466) (xy 384.008823 -260.448375) (xy 383.996697 -260.393938)
			(xy 383.992626 -260.338316) (xy 383.359152 -260.338316) (xy 383.358666 -260.365567) (xy 383.35091 -260.419515)
			(xy 383.335555 -260.47181) (xy 383.312913 -260.521387) (xy 383.283447 -260.567237) (xy 383.247756 -260.608428)
			(xy 383.206565 -260.644119) (xy 383.160715 -260.673585) (xy 383.111138 -260.696227) (xy 383.058843 -260.711582)
			(xy 383.004895 -260.719338) (xy 382.950393 -260.719338) (xy 382.896445 -260.711582) (xy 382.84415 -260.696227)
			(xy 382.794573 -260.673585) (xy 382.748723 -260.644119) (xy 382.707532 -260.608428) (xy 382.671841 -260.567237)
			(xy 382.642375 -260.521387) (xy 382.619733 -260.47181) (xy 382.604378 -260.419515) (xy 382.596622 -260.365567)
			(xy 382.596136 -260.338316) (xy 376.901326 -260.338316) (xy 376.897029 -260.347482) (xy 376.866256 -260.393995)
			(xy 376.829039 -260.435532) (xy 376.786171 -260.471207) (xy 376.738565 -260.500261) (xy 376.687236 -260.522073)
			(xy 376.633279 -260.536179) (xy 376.577842 -260.542279) (xy 376.522108 -260.540242) (xy 376.467265 -260.530112)
			(xy 376.414481 -260.512105) (xy 376.364881 -260.486604) (xy 376.319523 -260.454153) (xy 376.279374 -260.415444)
			(xy 376.245288 -260.371301) (xy 376.217992 -260.322666) (xy 376.198069 -260.270575) (xy 376.185943 -260.216138)
			(xy 376.181872 -260.160516) (xy 372.695701 -260.160516) (xy 372.681695 -260.207069) (xy 372.658023 -260.257566)
			(xy 372.62725 -260.304079) (xy 372.590033 -260.345616) (xy 372.547165 -260.381291) (xy 372.499559 -260.410345)
			(xy 372.44823 -260.432157) (xy 372.394273 -260.446263) (xy 372.338836 -260.452363) (xy 372.283102 -260.450326)
			(xy 372.228259 -260.440196) (xy 372.175475 -260.422189) (xy 372.125875 -260.396688) (xy 372.080517 -260.364237)
			(xy 372.040368 -260.325528) (xy 372.006282 -260.281385) (xy 371.978986 -260.23275) (xy 371.959063 -260.180659)
			(xy 371.946937 -260.126222) (xy 371.942866 -260.0706) (xy 370.255162 -260.0706) (xy 370.251931 -260.081339)
			(xy 370.228259 -260.131836) (xy 370.197486 -260.178349) (xy 370.160269 -260.219886) (xy 370.117401 -260.255561)
			(xy 370.069795 -260.284615) (xy 370.018466 -260.306427) (xy 369.964509 -260.320533) (xy 369.909072 -260.326633)
			(xy 369.853338 -260.324596) (xy 369.798495 -260.314466) (xy 369.745711 -260.296459) (xy 369.696111 -260.270958)
			(xy 369.650753 -260.238507) (xy 369.610604 -260.199798) (xy 369.576518 -260.155655) (xy 369.549222 -260.10702)
			(xy 369.529299 -260.054929) (xy 369.517173 -260.000492) (xy 369.513102 -259.94487) (xy 354.880961 -259.94487)
			(xy 354.880925 -259.946848) (xy 354.872805 -260.002024) (xy 354.856737 -260.055431) (xy 354.833065 -260.105928)
			(xy 354.802292 -260.152441) (xy 354.765075 -260.193978) (xy 354.722207 -260.229653) (xy 354.674601 -260.258707)
			(xy 354.623272 -260.280519) (xy 354.569315 -260.294625) (xy 354.513878 -260.300725) (xy 354.458144 -260.298688)
			(xy 354.403301 -260.288558) (xy 354.350517 -260.270551) (xy 354.300917 -260.24505) (xy 354.255559 -260.212599)
			(xy 354.21541 -260.17389) (xy 354.181324 -260.129747) (xy 354.154028 -260.081112) (xy 354.134105 -260.029021)
			(xy 354.121979 -259.974584) (xy 354.117908 -259.918962) (xy 353.357434 -259.918962) (xy 353.356925 -259.946848)
			(xy 353.348805 -260.002024) (xy 353.332737 -260.055431) (xy 353.309065 -260.105928) (xy 353.278292 -260.152441)
			(xy 353.241075 -260.193978) (xy 353.198207 -260.229653) (xy 353.150601 -260.258707) (xy 353.099272 -260.280519)
			(xy 353.045315 -260.294625) (xy 352.989878 -260.300725) (xy 352.934144 -260.298688) (xy 352.879301 -260.288558)
			(xy 352.826517 -260.270551) (xy 352.776917 -260.24505) (xy 352.731559 -260.212599) (xy 352.69141 -260.17389)
			(xy 352.657324 -260.129747) (xy 352.630028 -260.081112) (xy 352.610105 -260.029021) (xy 352.597979 -259.974584)
			(xy 352.593908 -259.918962) (xy 351.833434 -259.918962) (xy 351.832925 -259.946848) (xy 351.824805 -260.002024)
			(xy 351.808737 -260.055431) (xy 351.785065 -260.105928) (xy 351.754292 -260.152441) (xy 351.717075 -260.193978)
			(xy 351.674207 -260.229653) (xy 351.626601 -260.258707) (xy 351.575272 -260.280519) (xy 351.521315 -260.294625)
			(xy 351.465878 -260.300725) (xy 351.410144 -260.298688) (xy 351.355301 -260.288558) (xy 351.302517 -260.270551)
			(xy 351.252917 -260.24505) (xy 351.207559 -260.212599) (xy 351.16741 -260.17389) (xy 351.133324 -260.129747)
			(xy 351.106028 -260.081112) (xy 351.086105 -260.029021) (xy 351.073979 -259.974584) (xy 351.069908 -259.918962)
			(xy 345.101895 -259.918962) (xy 345.080579 -259.965635) (xy 345.051113 -260.011485) (xy 345.015422 -260.052676)
			(xy 344.974231 -260.088367) (xy 344.928381 -260.117833) (xy 344.878804 -260.140475) (xy 344.826509 -260.15583)
			(xy 344.772561 -260.163586) (xy 344.718059 -260.163586) (xy 344.664111 -260.15583) (xy 344.611816 -260.140475)
			(xy 344.562239 -260.117833) (xy 344.516389 -260.088367) (xy 344.475198 -260.052676) (xy 344.439507 -260.011485)
			(xy 344.410041 -259.965635) (xy 344.387399 -259.916058) (xy 344.372044 -259.863763) (xy 344.364288 -259.809815)
			(xy 344.363802 -259.782564) (xy 338.192832 -259.782564) (xy 338.035138 -259.940044) (xy 338.013467 -259.960898)
			(xy 337.964832 -259.996271) (xy 337.911266 -260.023609) (xy 337.854086 -260.04224) (xy 337.794697 -260.051705)
			(xy 337.764628 -260.052312) (xy 333.120746 -260.052312) (xy 333.110783 -260.052796) (xy 333.092357 -260.060382)
			(xy 333.084932 -260.067044) (xy 331.937106 -261.21487) (xy 331.929709 -261.22172) (xy 331.911111 -261.229462)
			(xy 331.901038 -261.229856) (xy 331.523086 -261.229856) (xy 331.513101 -261.230398) (xy 331.494678 -261.238121)
			(xy 331.487272 -261.244842) (xy 331.385602 -261.346442) (xy 340.147402 -261.346442) (xy 340.147836 -261.320125)
			(xy 340.15506 -261.26799) (xy 340.169377 -261.217342) (xy 340.190515 -261.16914) (xy 340.218073 -261.124299)
			(xy 340.25153 -261.083668) (xy 340.270592 -261.065518) (xy 340.277986 -261.05799) (xy 340.286515 -261.038715)
			(xy 340.287102 -261.02818) (xy 340.287102 -260.953504) (xy 340.286583 -260.942953) (xy 340.278041 -260.923658)
			(xy 340.270592 -260.916166) (xy 340.251495 -260.89805) (xy 340.218019 -260.857425) (xy 340.190451 -260.812581)
			(xy 340.169315 -260.76437) (xy 340.155014 -260.713709) (xy 340.14782 -260.661563) (xy 340.147402 -260.635242)
			(xy 340.147894 -260.60799) (xy 340.155646 -260.554039) (xy 340.170997 -260.501741) (xy 340.193635 -260.452161)
			(xy 340.2231 -260.406307) (xy 340.258791 -260.365114) (xy 340.299981 -260.329419) (xy 340.345833 -260.299951)
			(xy 340.395411 -260.277308) (xy 340.447708 -260.261953) (xy 340.501658 -260.254197) (xy 340.52891 -260.253734)
			(xy 340.555226 -260.25419) (xy 340.60736 -260.261408) (xy 340.658009 -260.27572) (xy 340.706211 -260.296853)
			(xy 340.751053 -260.324409) (xy 340.791684 -260.357863) (xy 340.809834 -260.376924) (xy 340.817351 -260.384332)
			(xy 340.836634 -260.392855) (xy 340.847172 -260.393434) (xy 340.921848 -260.393434) (xy 340.932395 -260.39288)
			(xy 340.95169 -260.384361) (xy 340.959186 -260.376924) (xy 340.977332 -260.357856) (xy 341.01795 -260.324376)
			(xy 341.062788 -260.296803) (xy 341.110993 -260.275663) (xy 341.161649 -260.261356) (xy 341.213791 -260.254156)
			(xy 341.24011 -260.253734) (xy 341.267365 -260.254146) (xy 341.32132 -260.261905) (xy 341.373621 -260.277265)
			(xy 341.423205 -260.299911) (xy 341.46906 -260.329384) (xy 341.510253 -260.365083) (xy 341.545947 -260.406282)
			(xy 341.575414 -260.452141) (xy 341.598054 -260.501727) (xy 341.613406 -260.554031) (xy 341.621158 -260.607987)
			(xy 341.621618 -260.635242) (xy 341.621167 -260.661558) (xy 341.619781 -260.671564) (xy 344.363292 -260.671564)
			(xy 344.367363 -260.615942) (xy 344.379489 -260.561505) (xy 344.399412 -260.509414) (xy 344.426708 -260.460779)
			(xy 344.460794 -260.416636) (xy 344.500943 -260.377927) (xy 344.546301 -260.345476) (xy 344.595901 -260.319975)
			(xy 344.648685 -260.301968) (xy 344.703528 -260.291838) (xy 344.759262 -260.289801) (xy 344.814699 -260.295901)
			(xy 344.868656 -260.310007) (xy 344.919985 -260.331819) (xy 344.967591 -260.360873) (xy 345.010459 -260.396548)
			(xy 345.047676 -260.438085) (xy 345.078449 -260.484598) (xy 345.102121 -260.535095) (xy 345.118189 -260.588502)
			(xy 345.126309 -260.643678) (xy 345.126818 -260.671564) (xy 345.126309 -260.69945) (xy 345.118189 -260.754626)
			(xy 345.102121 -260.808033) (xy 345.078449 -260.85853) (xy 345.047676 -260.905043) (xy 345.010459 -260.94658)
			(xy 344.967591 -260.982255) (xy 344.919985 -261.011309) (xy 344.868656 -261.033121) (xy 344.814699 -261.047227)
			(xy 344.759262 -261.053327) (xy 344.703528 -261.05129) (xy 344.648685 -261.04116) (xy 344.595901 -261.023153)
			(xy 344.546301 -260.997652) (xy 344.500943 -260.965201) (xy 344.460794 -260.926492) (xy 344.426708 -260.882349)
			(xy 344.399412 -260.833714) (xy 344.379489 -260.781623) (xy 344.367363 -260.727186) (xy 344.363292 -260.671564)
			(xy 341.619781 -260.671564) (xy 341.613946 -260.713692) (xy 341.599632 -260.76434) (xy 341.578497 -260.812542)
			(xy 341.550942 -260.857384) (xy 341.517488 -260.898016) (xy 341.498428 -260.916166) (xy 341.491043 -260.923702)
			(xy 341.482508 -260.942971) (xy 341.481918 -260.953504) (xy 341.481918 -261.02818) (xy 341.482439 -261.038731)
			(xy 341.490979 -261.058026) (xy 341.498428 -261.065518) (xy 341.517502 -261.083658) (xy 341.550984 -261.124276)
			(xy 341.578557 -261.169115) (xy 341.599697 -261.217321) (xy 341.599794 -261.217664) (xy 346.340428 -261.217664)
			(xy 346.344499 -261.162042) (xy 346.356625 -261.107605) (xy 346.376548 -261.055514) (xy 346.403844 -261.006879)
			(xy 346.43793 -260.962736) (xy 346.478079 -260.924027) (xy 346.523437 -260.891576) (xy 346.573037 -260.866075)
			(xy 346.625821 -260.848068) (xy 346.680664 -260.837938) (xy 346.736398 -260.835901) (xy 346.791835 -260.842001)
			(xy 346.845792 -260.856107) (xy 346.897121 -260.877919) (xy 346.944727 -260.906973) (xy 346.987595 -260.942648)
			(xy 347.024812 -260.984185) (xy 347.055585 -261.030698) (xy 347.079257 -261.081195) (xy 347.095325 -261.134602)
			(xy 347.103445 -261.189778) (xy 347.103954 -261.217664) (xy 347.103445 -261.24555) (xy 347.095325 -261.300726)
			(xy 347.079257 -261.354133) (xy 347.055585 -261.40463) (xy 347.024812 -261.451143) (xy 346.987595 -261.49268)
			(xy 346.944727 -261.528355) (xy 346.897121 -261.557409) (xy 346.845792 -261.579221) (xy 346.791835 -261.593327)
			(xy 346.736398 -261.599427) (xy 346.680664 -261.59739) (xy 346.625821 -261.58726) (xy 346.573037 -261.569253)
			(xy 346.523437 -261.543752) (xy 346.478079 -261.511301) (xy 346.43793 -261.472592) (xy 346.403844 -261.428449)
			(xy 346.376548 -261.379814) (xy 346.356625 -261.327723) (xy 346.344499 -261.273286) (xy 346.340428 -261.217664)
			(xy 341.599794 -261.217664) (xy 341.614001 -261.267979) (xy 341.621198 -261.320122) (xy 341.621618 -261.346442)
			(xy 341.621161 -261.373694) (xy 341.613399 -261.427642) (xy 341.598039 -261.479937) (xy 341.575394 -261.529513)
			(xy 341.545924 -261.575363) (xy 341.51023 -261.616553) (xy 341.469038 -261.652244) (xy 341.423185 -261.681709)
			(xy 341.410365 -261.687564) (xy 344.363292 -261.687564) (xy 344.367363 -261.631942) (xy 344.379489 -261.577505)
			(xy 344.399412 -261.525414) (xy 344.426708 -261.476779) (xy 344.460794 -261.432636) (xy 344.500943 -261.393927)
			(xy 344.546301 -261.361476) (xy 344.595901 -261.335975) (xy 344.648685 -261.317968) (xy 344.703528 -261.307838)
			(xy 344.759262 -261.305801) (xy 344.814699 -261.311901) (xy 344.868656 -261.326007) (xy 344.919985 -261.347819)
			(xy 344.967591 -261.376873) (xy 345.010459 -261.412548) (xy 345.047676 -261.454085) (xy 345.078449 -261.500598)
			(xy 345.102121 -261.551095) (xy 345.118189 -261.604502) (xy 345.126309 -261.659678) (xy 345.126595 -261.675372)
			(xy 349.274636 -261.675372) (xy 349.278707 -261.61975) (xy 349.290833 -261.565313) (xy 349.310756 -261.513222)
			(xy 349.338052 -261.464587) (xy 349.372138 -261.420444) (xy 349.412287 -261.381735) (xy 349.457645 -261.349284)
			(xy 349.507245 -261.323783) (xy 349.560029 -261.305776) (xy 349.614872 -261.295646) (xy 349.670606 -261.293609)
			(xy 349.726043 -261.299709) (xy 349.78 -261.313815) (xy 349.831329 -261.335627) (xy 349.878935 -261.364681)
			(xy 349.921803 -261.400356) (xy 349.95902 -261.441893) (xy 349.989793 -261.488406) (xy 350.002565 -261.515652)
			(xy 351.594883 -261.515652) (xy 351.594883 -261.461148) (xy 351.60264 -261.407198) (xy 351.617997 -261.354902)
			(xy 351.64064 -261.305324) (xy 351.670108 -261.259473) (xy 351.705802 -261.218282) (xy 351.746995 -261.182591)
			(xy 351.792848 -261.153126) (xy 351.842428 -261.130487) (xy 351.894726 -261.115135) (xy 351.948676 -261.107381)
			(xy 351.975928 -261.10692) (xy 352.004527 -261.107402) (xy 352.061083 -261.115945) (xy 352.115731 -261.132835)
			(xy 352.167244 -261.157694) (xy 352.214469 -261.189964) (xy 352.232231 -261.206488) (xy 364.15853 -261.206488)
			(xy 364.159016 -261.179237) (xy 364.166772 -261.125289) (xy 364.182127 -261.072994) (xy 364.204769 -261.023417)
			(xy 364.234235 -260.977567) (xy 364.269926 -260.936376) (xy 364.311117 -260.900685) (xy 364.356967 -260.871219)
			(xy 364.406544 -260.848577) (xy 364.458839 -260.833222) (xy 364.512787 -260.825466) (xy 364.567289 -260.825466)
			(xy 364.621237 -260.833222) (xy 364.673532 -260.848577) (xy 364.723109 -260.871219) (xy 364.768959 -260.900685)
			(xy 364.81015 -260.936376) (xy 364.845841 -260.977567) (xy 364.875307 -261.023417) (xy 364.897949 -261.072994)
			(xy 364.913304 -261.125289) (xy 364.92106 -261.179237) (xy 364.921546 -261.206488) (xy 364.921526 -261.207758)
			(xy 370.377464 -261.207758) (xy 370.381535 -261.152136) (xy 370.393661 -261.097699) (xy 370.413584 -261.045608)
			(xy 370.44088 -260.996973) (xy 370.474966 -260.95283) (xy 370.515115 -260.914121) (xy 370.560473 -260.88167)
			(xy 370.610073 -260.856169) (xy 370.662857 -260.838162) (xy 370.7177 -260.828032) (xy 370.773434 -260.825995)
			(xy 370.828871 -260.832095) (xy 370.882828 -260.846201) (xy 370.934157 -260.868013) (xy 370.981763 -260.897067)
			(xy 371.024631 -260.932742) (xy 371.061848 -260.974279) (xy 371.092621 -261.020792) (xy 371.116293 -261.071289)
			(xy 371.132361 -261.124696) (xy 371.140481 -261.179872) (xy 371.14099 -261.207758) (xy 371.140481 -261.235644)
			(xy 371.132361 -261.29082) (xy 371.116293 -261.344227) (xy 371.092621 -261.394724) (xy 371.061848 -261.441237)
			(xy 371.024631 -261.482774) (xy 370.981763 -261.518449) (xy 370.934157 -261.547503) (xy 370.882828 -261.569315)
			(xy 370.828871 -261.583421) (xy 370.773434 -261.589521) (xy 370.7177 -261.587484) (xy 370.662857 -261.577354)
			(xy 370.610073 -261.559347) (xy 370.560473 -261.533846) (xy 370.515115 -261.501395) (xy 370.474966 -261.462686)
			(xy 370.44088 -261.418543) (xy 370.413584 -261.369908) (xy 370.393661 -261.317817) (xy 370.381535 -261.26338)
			(xy 370.377464 -261.207758) (xy 364.921526 -261.207758) (xy 364.921137 -261.23249) (xy 364.914063 -261.284011)
			(xy 364.900057 -261.334093) (xy 364.879379 -261.381809) (xy 364.852412 -261.426275) (xy 364.819656 -261.466667)
			(xy 364.781718 -261.502236) (xy 364.760764 -261.517638) (xy 364.749404 -261.526182) (xy 364.731627 -261.548352)
			(xy 364.72064 -261.574559) (xy 364.717291 -261.602779) (xy 364.721839 -261.63083) (xy 364.733933 -261.656545)
			(xy 364.752639 -261.677937) (xy 364.76432 -261.68604) (xy 364.786942 -261.701158) (xy 364.793034 -261.706451)
			(xy 371.85676 -261.706451) (xy 371.85676 -261.651949) (xy 371.864516 -261.598002) (xy 371.87987 -261.545708)
			(xy 371.902509 -261.496131) (xy 371.931973 -261.45028) (xy 371.967662 -261.409089) (xy 372.00885 -261.373396)
			(xy 372.054698 -261.343927) (xy 372.104272 -261.321283) (xy 372.156565 -261.305924) (xy 372.210511 -261.298162)
			(xy 372.237762 -261.297674) (xy 372.265879 -261.298183) (xy 372.321506 -261.306428) (xy 372.375321 -261.322745)
			(xy 372.42616 -261.346782) (xy 372.472922 -261.378016) (xy 372.514596 -261.415774) (xy 372.550279 -261.459237)
			(xy 372.565168 -261.483094) (xy 372.57101 -261.493) (xy 372.589298 -261.505446) (xy 372.688358 -261.521448)
			(xy 372.709694 -261.515606) (xy 372.71833 -261.50824) (xy 372.739141 -261.491027) (xy 372.784716 -261.462051)
			(xy 372.833919 -261.439788) (xy 372.885769 -261.424681) (xy 372.939231 -261.417032) (xy 372.966234 -261.416546)
			(xy 372.99348 -261.417126) (xy 373.047418 -261.424886) (xy 373.099702 -261.440242) (xy 373.149269 -261.462883)
			(xy 373.19511 -261.492346) (xy 373.236291 -261.528033) (xy 373.271974 -261.569218) (xy 373.301434 -261.615061)
			(xy 373.32407 -261.66463) (xy 373.339421 -261.716915) (xy 373.347176 -261.770854) (xy 373.347176 -261.817955)
			(xy 373.819343 -261.817955) (xy 373.819343 -261.763445) (xy 373.827101 -261.709491) (xy 373.842458 -261.65719)
			(xy 373.865103 -261.607607) (xy 373.894574 -261.561751) (xy 373.930271 -261.520557) (xy 373.971467 -261.484862)
			(xy 374.017324 -261.455393) (xy 374.066909 -261.432751) (xy 374.11921 -261.417396) (xy 374.173165 -261.409642)
			(xy 374.20042 -261.40918) (xy 374.229336 -261.409726) (xy 374.286508 -261.418445) (xy 374.341707 -261.435695)
			(xy 374.39367 -261.461082) (xy 374.441204 -261.494022) (xy 374.48322 -261.533761) (xy 374.50141 -261.556246)
			(xy 374.508964 -261.565015) (xy 374.529729 -261.575193) (xy 374.541288 -261.575804) (xy 374.621552 -261.575804)
			(xy 374.633116 -261.575205) (xy 374.653887 -261.56503) (xy 374.66143 -261.556246) (xy 374.67959 -261.533737)
			(xy 374.721618 -261.494006) (xy 374.76916 -261.461071) (xy 374.821127 -261.435688) (xy 374.876329 -261.418437)
			(xy 374.933502 -261.409713) (xy 374.96242 -261.40918) (xy 374.989669 -261.409692) (xy 375.043613 -261.41745)
			(xy 375.095904 -261.432807) (xy 375.145477 -261.455448) (xy 375.175055 -261.474458) (xy 377.069602 -261.474458)
			(xy 377.073673 -261.418836) (xy 377.085799 -261.364399) (xy 377.105722 -261.312308) (xy 377.133018 -261.263673)
			(xy 377.167104 -261.21953) (xy 377.207253 -261.180821) (xy 377.252611 -261.14837) (xy 377.302211 -261.122869)
			(xy 377.354995 -261.104862) (xy 377.409838 -261.094732) (xy 377.465572 -261.092695) (xy 377.521009 -261.098795)
			(xy 377.574966 -261.112901) (xy 377.626295 -261.134713) (xy 377.673901 -261.163767) (xy 377.716769 -261.199442)
			(xy 377.753986 -261.240979) (xy 377.784759 -261.287492) (xy 377.808431 -261.337989) (xy 377.824499 -261.391396)
			(xy 377.832619 -261.446572) (xy 377.833128 -261.474458) (xy 378.55474 -261.474458) (xy 378.558811 -261.418836)
			(xy 378.570937 -261.364399) (xy 378.59086 -261.312308) (xy 378.618156 -261.263673) (xy 378.652242 -261.21953)
			(xy 378.692391 -261.180821) (xy 378.737749 -261.14837) (xy 378.787349 -261.122869) (xy 378.840133 -261.104862)
			(xy 378.894976 -261.094732) (xy 378.95071 -261.092695) (xy 379.006147 -261.098795) (xy 379.060104 -261.112901)
			(xy 379.111433 -261.134713) (xy 379.159039 -261.163767) (xy 379.201907 -261.199442) (xy 379.239124 -261.240979)
			(xy 379.269897 -261.287492) (xy 379.293569 -261.337989) (xy 379.309637 -261.391396) (xy 379.317757 -261.446572)
			(xy 379.318266 -261.474458) (xy 379.317757 -261.502344) (xy 379.309637 -261.55752) (xy 379.293569 -261.610927)
			(xy 379.269897 -261.661424) (xy 379.239124 -261.707937) (xy 379.201907 -261.749474) (xy 379.159039 -261.785149)
			(xy 379.111433 -261.814203) (xy 379.060104 -261.836015) (xy 379.006147 -261.850121) (xy 378.95071 -261.856221)
			(xy 378.894976 -261.854184) (xy 378.840133 -261.844054) (xy 378.787349 -261.826047) (xy 378.737749 -261.800546)
			(xy 378.692391 -261.768095) (xy 378.652242 -261.729386) (xy 378.618156 -261.685243) (xy 378.59086 -261.636608)
			(xy 378.570937 -261.584517) (xy 378.558811 -261.53008) (xy 378.55474 -261.474458) (xy 377.833128 -261.474458)
			(xy 377.832619 -261.502344) (xy 377.824499 -261.55752) (xy 377.808431 -261.610927) (xy 377.784759 -261.661424)
			(xy 377.753986 -261.707937) (xy 377.716769 -261.749474) (xy 377.673901 -261.785149) (xy 377.626295 -261.814203)
			(xy 377.574966 -261.836015) (xy 377.521009 -261.850121) (xy 377.465572 -261.856221) (xy 377.409838 -261.854184)
			(xy 377.354995 -261.844054) (xy 377.302211 -261.826047) (xy 377.252611 -261.800546) (xy 377.207253 -261.768095)
			(xy 377.167104 -261.729386) (xy 377.133018 -261.685243) (xy 377.105722 -261.636608) (xy 377.085799 -261.584517)
			(xy 377.073673 -261.53008) (xy 377.069602 -261.474458) (xy 375.175055 -261.474458) (xy 375.191323 -261.484914)
			(xy 375.23251 -261.520604) (xy 375.268198 -261.561793) (xy 375.297662 -261.607641) (xy 375.3203 -261.657215)
			(xy 375.335654 -261.709506) (xy 375.34341 -261.763451) (xy 375.34341 -261.817949) (xy 375.335654 -261.871894)
			(xy 375.3203 -261.924185) (xy 375.297662 -261.973759) (xy 375.268198 -262.019607) (xy 375.23251 -262.060796)
			(xy 375.191323 -262.096486) (xy 375.145477 -262.125952) (xy 375.095904 -262.148593) (xy 375.043613 -262.16395)
			(xy 374.989669 -262.171708) (xy 374.96242 -262.172196) (xy 374.933504 -262.171665) (xy 374.876333 -262.162939)
			(xy 374.821134 -262.145683) (xy 374.769173 -262.120294) (xy 374.721638 -262.087353) (xy 374.679621 -262.047614)
			(xy 374.66143 -262.02513) (xy 374.653863 -262.016374) (xy 374.633108 -262.00619) (xy 374.621552 -262.005572)
			(xy 374.541288 -262.005572) (xy 374.529715 -262.00611) (xy 374.508943 -262.016325) (xy 374.50141 -262.02513)
			(xy 374.483221 -262.047615) (xy 374.4412 -262.087349) (xy 374.393664 -262.120287) (xy 374.341703 -262.145674)
			(xy 374.286505 -262.162931) (xy 374.229336 -262.17166) (xy 374.20042 -262.172196) (xy 374.173165 -262.171758)
			(xy 374.11921 -262.164004) (xy 374.066909 -262.148649) (xy 374.017324 -262.126007) (xy 373.971467 -262.096538)
			(xy 373.930271 -262.060843) (xy 373.894574 -262.019649) (xy 373.865103 -261.973793) (xy 373.842458 -261.92421)
			(xy 373.827101 -261.871909) (xy 373.819343 -261.817955) (xy 373.347176 -261.817955) (xy 373.347176 -261.825346)
			(xy 373.339421 -261.879285) (xy 373.32407 -261.93157) (xy 373.301434 -261.981139) (xy 373.271974 -262.026982)
			(xy 373.236291 -262.068167) (xy 373.19511 -262.103854) (xy 373.149269 -262.133317) (xy 373.099702 -262.155958)
			(xy 373.047418 -262.171314) (xy 372.99348 -262.179074) (xy 372.966234 -262.179562) (xy 372.938117 -262.179038)
			(xy 372.882492 -262.170794) (xy 372.828678 -262.154478) (xy 372.77784 -262.130444) (xy 372.731078 -262.099211)
			(xy 372.689403 -262.061457) (xy 372.653719 -262.017997) (xy 372.638828 -261.994142) (xy 372.632986 -261.984236)
			(xy 372.614698 -261.97179) (xy 372.515638 -261.955788) (xy 372.494302 -261.96163) (xy 372.485666 -261.968996)
			(xy 372.464861 -261.986216) (xy 372.419284 -262.01519) (xy 372.370079 -262.037451) (xy 372.318228 -262.052557)
			(xy 372.264765 -262.060204) (xy 372.237762 -262.06069) (xy 372.210511 -262.060238) (xy 372.156565 -262.052476)
			(xy 372.104272 -262.037117) (xy 372.054698 -262.014473) (xy 372.00885 -261.985004) (xy 371.967662 -261.949311)
			(xy 371.931973 -261.90812) (xy 371.902509 -261.862269) (xy 371.87987 -261.812692) (xy 371.864516 -261.760398)
			(xy 371.85676 -261.706451) (xy 364.793034 -261.706451) (xy 364.828015 -261.736844) (xy 364.863601 -261.778004)
			(xy 364.892977 -261.823803) (xy 364.915548 -261.873312) (xy 364.930855 -261.925525) (xy 364.938588 -261.979383)
			(xy 364.939072 -262.006588) (xy 364.938586 -262.033839) (xy 364.93083 -262.087787) (xy 364.915475 -262.140082)
			(xy 364.892833 -262.189659) (xy 364.863367 -262.235509) (xy 364.827676 -262.2767) (xy 364.786485 -262.312391)
			(xy 364.740635 -262.341857) (xy 364.691058 -262.364499) (xy 364.638763 -262.379854) (xy 364.584815 -262.38761)
			(xy 364.530313 -262.38761) (xy 364.476365 -262.379854) (xy 364.42407 -262.364499) (xy 364.374493 -262.341857)
			(xy 364.328643 -262.312391) (xy 364.287452 -262.2767) (xy 364.251761 -262.235509) (xy 364.222295 -262.189659)
			(xy 364.199653 -262.140082) (xy 364.184298 -262.087787) (xy 364.176542 -262.033839) (xy 364.176056 -262.006588)
			(xy 364.176521 -261.980588) (xy 364.183586 -261.92907) (xy 364.197582 -261.878988) (xy 364.218251 -261.831272)
			(xy 364.245209 -261.786806) (xy 364.277957 -261.746413) (xy 364.315888 -261.710842) (xy 364.336838 -261.695438)
			(xy 364.348122 -261.686801) (xy 364.365897 -261.664652) (xy 364.376888 -261.638466) (xy 364.380247 -261.610265)
			(xy 364.375713 -261.58223) (xy 364.363637 -261.556526) (xy 364.344952 -261.535139) (xy 364.333282 -261.527036)
			(xy 364.310695 -261.511868) (xy 364.269621 -261.47619) (xy 364.234033 -261.435038) (xy 364.204653 -261.389248)
			(xy 364.182076 -261.339748) (xy 364.166761 -261.287542) (xy 364.159019 -261.233691) (xy 364.15853 -261.206488)
			(xy 352.232231 -261.206488) (xy 352.256348 -261.228923) (xy 352.291941 -261.273698) (xy 352.320451 -261.323284)
			(xy 352.34124 -261.37657) (xy 352.348038 -261.404354) (xy 352.350324 -261.413752) (xy 352.360484 -261.429246)
			(xy 352.431858 -261.479538) (xy 352.449638 -261.48411) (xy 352.45929 -261.483094) (xy 352.470548 -261.481798)
			(xy 352.49317 -261.480402) (xy 352.504502 -261.4803) (xy 352.531754 -261.48077) (xy 352.585702 -261.488527)
			(xy 352.637998 -261.503882) (xy 352.687576 -261.526524) (xy 352.733427 -261.555991) (xy 352.774618 -261.591683)
			(xy 352.81031 -261.632874) (xy 352.839777 -261.678726) (xy 352.862418 -261.728304) (xy 352.877774 -261.7806)
			(xy 352.882657 -261.814564) (xy 360.485942 -261.814564) (xy 360.490013 -261.758942) (xy 360.502139 -261.704505)
			(xy 360.522062 -261.652414) (xy 360.549358 -261.603779) (xy 360.583444 -261.559636) (xy 360.623593 -261.520927)
			(xy 360.668951 -261.488476) (xy 360.718551 -261.462975) (xy 360.771335 -261.444968) (xy 360.826178 -261.434838)
			(xy 360.881912 -261.432801) (xy 360.937349 -261.438901) (xy 360.991306 -261.453007) (xy 361.042635 -261.474819)
			(xy 361.090241 -261.503873) (xy 361.133109 -261.539548) (xy 361.170326 -261.581085) (xy 361.201099 -261.627598)
			(xy 361.224771 -261.678095) (xy 361.240839 -261.731502) (xy 361.248959 -261.786678) (xy 361.249468 -261.814564)
			(xy 361.248959 -261.84245) (xy 361.240839 -261.897626) (xy 361.224771 -261.951033) (xy 361.201099 -262.00153)
			(xy 361.170326 -262.048043) (xy 361.133109 -262.08958) (xy 361.090241 -262.125255) (xy 361.042635 -262.154309)
			(xy 360.991306 -262.176121) (xy 360.937349 -262.190227) (xy 360.881912 -262.196327) (xy 360.826178 -262.19429)
			(xy 360.771335 -262.18416) (xy 360.718551 -262.166153) (xy 360.668951 -262.140652) (xy 360.623593 -262.108201)
			(xy 360.583444 -262.069492) (xy 360.549358 -262.025349) (xy 360.522062 -261.976714) (xy 360.502139 -261.924623)
			(xy 360.490013 -261.870186) (xy 360.485942 -261.814564) (xy 352.882657 -261.814564) (xy 352.88553 -261.834548)
			(xy 352.88553 -261.889052) (xy 352.877774 -261.943) (xy 352.862418 -261.995296) (xy 352.839777 -262.044874)
			(xy 352.81031 -262.090726) (xy 352.774618 -262.131917) (xy 352.733427 -262.167609) (xy 352.687576 -262.197076)
			(xy 352.637998 -262.219718) (xy 352.585702 -262.235073) (xy 352.531754 -262.24283) (xy 352.504502 -262.243316)
			(xy 352.475905 -262.242779) (xy 352.419353 -262.234242) (xy 352.364708 -262.217357) (xy 352.313196 -262.192505)
			(xy 352.265972 -262.160241) (xy 352.224093 -262.121289) (xy 352.188498 -262.076522) (xy 352.159985 -262.026943)
			(xy 352.139193 -261.973663) (xy 352.132392 -261.945882) (xy 352.130106 -261.936484) (xy 352.119946 -261.92099)
			(xy 352.048572 -261.870698) (xy 352.030792 -261.866126) (xy 352.02114 -261.867142) (xy 352.009881 -261.868435)
			(xy 351.98726 -261.869833) (xy 351.975928 -261.869936) (xy 351.948676 -261.869419) (xy 351.894726 -261.861665)
			(xy 351.842428 -261.846313) (xy 351.792848 -261.823674) (xy 351.746995 -261.794209) (xy 351.705802 -261.758518)
			(xy 351.670108 -261.717327) (xy 351.64064 -261.671476) (xy 351.617997 -261.621898) (xy 351.60264 -261.569602)
			(xy 351.594883 -261.515652) (xy 350.002565 -261.515652) (xy 350.013465 -261.538903) (xy 350.029533 -261.59231)
			(xy 350.037653 -261.647486) (xy 350.038162 -261.675372) (xy 350.037653 -261.703258) (xy 350.029533 -261.758434)
			(xy 350.013465 -261.811841) (xy 349.989793 -261.862338) (xy 349.95902 -261.908851) (xy 349.921803 -261.950388)
			(xy 349.878935 -261.986063) (xy 349.831329 -262.015117) (xy 349.78 -262.036929) (xy 349.726043 -262.051035)
			(xy 349.670606 -262.057135) (xy 349.614872 -262.055098) (xy 349.560029 -262.044968) (xy 349.507245 -262.026961)
			(xy 349.457645 -262.00146) (xy 349.412287 -261.969009) (xy 349.372138 -261.9303) (xy 349.338052 -261.886157)
			(xy 349.310756 -261.837522) (xy 349.290833 -261.785431) (xy 349.278707 -261.730994) (xy 349.274636 -261.675372)
			(xy 345.126595 -261.675372) (xy 345.126818 -261.687564) (xy 345.126309 -261.71545) (xy 345.118189 -261.770626)
			(xy 345.102121 -261.824033) (xy 345.078449 -261.87453) (xy 345.047676 -261.921043) (xy 345.010459 -261.96258)
			(xy 344.967591 -261.998255) (xy 344.919985 -262.027309) (xy 344.868656 -262.049121) (xy 344.814699 -262.063227)
			(xy 344.759262 -262.069327) (xy 344.703528 -262.06729) (xy 344.648685 -262.05716) (xy 344.595901 -262.039153)
			(xy 344.546301 -262.013652) (xy 344.500943 -261.981201) (xy 344.460794 -261.942492) (xy 344.426708 -261.898349)
			(xy 344.399412 -261.849714) (xy 344.379489 -261.797623) (xy 344.367363 -261.743186) (xy 344.363292 -261.687564)
			(xy 341.410365 -261.687564) (xy 341.373607 -261.704351) (xy 341.321311 -261.719706) (xy 341.267362 -261.727464)
			(xy 341.24011 -261.72795) (xy 341.213792 -261.727553) (xy 341.161655 -261.720323) (xy 341.111005 -261.706001)
			(xy 341.062803 -261.684856) (xy 341.017962 -261.65729) (xy 340.977334 -261.623825) (xy 340.959186 -261.60476)
			(xy 340.951664 -261.597359) (xy 340.932385 -261.588832) (xy 340.921848 -261.58825) (xy 340.847172 -261.58825)
			(xy 340.836627 -261.588819) (xy 340.817332 -261.597328) (xy 340.809834 -261.60476) (xy 340.791675 -261.623815)
			(xy 340.751061 -261.657297) (xy 340.706226 -261.684872) (xy 340.658023 -261.706015) (xy 340.607369 -261.720324)
			(xy 340.555228 -261.727527) (xy 340.52891 -261.72795) (xy 340.501661 -261.727413) (xy 340.447717 -261.719659)
			(xy 340.395426 -261.704307) (xy 340.345852 -261.68167) (xy 340.300003 -261.652209) (xy 340.258814 -261.616523)
			(xy 340.223123 -261.575338) (xy 340.193655 -261.529494) (xy 340.171011 -261.479923) (xy 340.155653 -261.427634)
			(xy 340.147891 -261.373691) (xy 340.147402 -261.346442) (xy 331.385602 -261.346442) (xy 331.12075 -261.61111)
			(xy 331.099098 -261.631973) (xy 331.050454 -261.667313) (xy 330.996879 -261.694603) (xy 330.939692 -261.71317)
			(xy 330.880303 -261.722557) (xy 330.85024 -261.723124) (xy 316.8396 -261.723124) (xy 316.80954 -261.722535)
			(xy 316.750158 -261.713134) (xy 316.692977 -261.694564) (xy 316.639403 -261.667282) (xy 316.590753 -261.631958)
			(xy 316.56909 -261.61111) (xy 316.28969 -261.33171) (xy 316.268823 -261.310059) (xy 316.233476 -261.261417)
			(xy 316.206177 -261.207842) (xy 316.187601 -261.150655) (xy 316.178205 -261.091265) (xy 316.177676 -261.0612)
			(xy 316.178143 -261.033819) (xy 316.185944 -260.979615) (xy 316.201387 -260.927075) (xy 316.224158 -260.877271)
			(xy 316.253791 -260.831219) (xy 316.271402 -260.810248) (xy 316.28461 -260.795008) (xy 316.283086 -260.75513)
			(xy 315.218572 -259.690616) (xy 315.211173 -259.683772) (xy 315.192575 -259.676045) (xy 315.182504 -259.67563)
			(xy 306.430172 -259.67563) (xy 306.404772 -259.69214) (xy 306.398676 -259.705856) (xy 306.387127 -259.730922)
			(xy 306.357875 -259.777721) (xy 306.322186 -259.819818) (xy 306.280806 -259.856336) (xy 306.234598 -259.886512)
			(xy 306.184525 -259.909717) (xy 306.131631 -259.925468) (xy 306.07702 -259.933436) (xy 306.049426 -259.933948)
			(xy 306.019601 -259.933375) (xy 305.960677 -259.924098) (xy 305.903913 -259.905768) (xy 305.850693 -259.878829)
			(xy 305.802311 -259.843939) (xy 305.759947 -259.801946) (xy 305.741832 -259.778246) (xy 305.739546 -259.775198)
			(xy 305.736752 -259.772404) (xy 305.729391 -259.765635) (xy 305.710929 -259.757988) (xy 305.690947 -259.757988)
			(xy 305.672485 -259.765635) (xy 305.665124 -259.772404) (xy 305.654964 -259.78231) (xy 305.633312 -259.803174)
			(xy 305.584669 -259.838516) (xy 305.531093 -259.865808) (xy 305.473906 -259.884377) (xy 305.414517 -259.893766)
			(xy 305.384454 -259.894324) (xy 275.7424 -259.894324) (xy 275.71234 -259.893735) (xy 275.652958 -259.884334)
			(xy 275.595777 -259.865764) (xy 275.542203 -259.838482) (xy 275.493553 -259.803158) (xy 275.47189 -259.78231)
			(xy 273.81962 -258.130294) (xy 273.81227 -258.123497) (xy 273.793807 -258.115794) (xy 273.783806 -258.115308)
			(xy 272.646902 -258.115308) (xy 272.636831 -258.114886) (xy 272.618226 -258.107173) (xy 272.610834 -258.100322)
			(xy 272.011394 -257.500882) (xy 271.992852 -257.493262) (xy 271.982438 -257.493516) (xy 271.977612 -257.493516)
			(xy 271.950358 -257.493053) (xy 271.896406 -257.485298) (xy 271.844106 -257.469943) (xy 271.794524 -257.447301)
			(xy 271.748669 -257.417834) (xy 271.707474 -257.38214) (xy 271.671778 -257.340947) (xy 271.642308 -257.295094)
			(xy 271.619664 -257.245513) (xy 271.604306 -257.193214) (xy 271.596548 -257.139262) (xy 271.596104 -257.112008)
			(xy 271.596104 -257.107182) (xy 271.596358 -257.096768) (xy 271.588738 -257.078226) (xy 270.990822 -256.48031)
			(xy 270.983473 -256.473511) (xy 270.96501 -256.465805) (xy 270.955008 -256.465324) (xy 270.002 -256.465324)
			(xy 269.975925 -256.464855) (xy 269.924412 -256.456726) (xy 269.874806 -256.440637) (xy 269.828329 -256.416984)
			(xy 269.786124 -256.386351) (xy 269.767304 -256.368296) (xy 269.345918 -255.94691) (xy 269.338569 -255.940111)
			(xy 269.320106 -255.932407) (xy 269.310104 -255.931924) (xy 267.229844 -255.931924) (xy 267.219795 -255.932341)
			(xy 267.201229 -255.940041) (xy 267.187042 -255.954277) (xy 267.182854 -255.96342) (xy 267.141198 -256.064512)
			(xy 267.147294 -256.094738) (xy 267.158216 -256.10566) (xy 267.179105 -256.127271) (xy 267.2145 -256.175844)
			(xy 267.241845 -256.229364) (xy 267.260464 -256.286509) (xy 267.269897 -256.345865) (xy 267.270484 -256.375916)
			(xy 267.26992 -256.405295) (xy 267.260869 -256.463353) (xy 267.24303 -256.519339) (xy 267.216823 -256.571931)
			(xy 267.182868 -256.619886) (xy 267.141966 -256.662073) (xy 267.118846 -256.680208) (xy 267.109448 -256.687574)
			(xy 267.099034 -256.708148) (xy 267.09751 -256.812034) (xy 267.107416 -256.833116) (xy 267.11656 -256.840482)
			(xy 267.138385 -256.858712) (xy 267.176915 -256.900534) (xy 267.208817 -256.947606) (xy 267.233385 -256.99889)
			(xy 267.250076 -257.05325) (xy 267.258522 -257.109484) (xy 267.259054 -257.137916) (xy 267.892528 -257.137916)
			(xy 267.896599 -257.082294) (xy 267.908725 -257.027857) (xy 267.928648 -256.975766) (xy 267.955944 -256.927131)
			(xy 267.99003 -256.882988) (xy 268.030179 -256.844279) (xy 268.075537 -256.811828) (xy 268.125137 -256.786327)
			(xy 268.177921 -256.76832) (xy 268.232764 -256.75819) (xy 268.288498 -256.756153) (xy 268.343935 -256.762253)
			(xy 268.397892 -256.776359) (xy 268.449221 -256.798171) (xy 268.496827 -256.827225) (xy 268.539695 -256.8629)
			(xy 268.576912 -256.904437) (xy 268.607685 -256.95095) (xy 268.631357 -257.001447) (xy 268.647425 -257.054854)
			(xy 268.655545 -257.11003) (xy 268.656054 -257.137916) (xy 268.778988 -257.137916) (xy 268.783059 -257.082294)
			(xy 268.795185 -257.027857) (xy 268.815108 -256.975766) (xy 268.842404 -256.927131) (xy 268.87649 -256.882988)
			(xy 268.916639 -256.844279) (xy 268.961997 -256.811828) (xy 269.011597 -256.786327) (xy 269.064381 -256.76832)
			(xy 269.119224 -256.75819) (xy 269.174958 -256.756153) (xy 269.230395 -256.762253) (xy 269.284352 -256.776359)
			(xy 269.335681 -256.798171) (xy 269.383287 -256.827225) (xy 269.426155 -256.8629) (xy 269.463372 -256.904437)
			(xy 269.494145 -256.95095) (xy 269.517817 -257.001447) (xy 269.533885 -257.054854) (xy 269.542005 -257.11003)
			(xy 269.542514 -257.137916) (xy 269.542005 -257.165802) (xy 269.533885 -257.220978) (xy 269.517817 -257.274385)
			(xy 269.494145 -257.324882) (xy 269.463372 -257.371395) (xy 269.426155 -257.412932) (xy 269.383287 -257.448607)
			(xy 269.335681 -257.477661) (xy 269.284352 -257.499473) (xy 269.230395 -257.513579) (xy 269.174958 -257.519679)
			(xy 269.119224 -257.517642) (xy 269.064381 -257.507512) (xy 269.011597 -257.489505) (xy 268.961997 -257.464004)
			(xy 268.916639 -257.431553) (xy 268.87649 -257.392844) (xy 268.842404 -257.348701) (xy 268.815108 -257.300066)
			(xy 268.795185 -257.247975) (xy 268.783059 -257.193538) (xy 268.778988 -257.137916) (xy 268.656054 -257.137916)
			(xy 268.655545 -257.165802) (xy 268.647425 -257.220978) (xy 268.631357 -257.274385) (xy 268.607685 -257.324882)
			(xy 268.576912 -257.371395) (xy 268.539695 -257.412932) (xy 268.496827 -257.448607) (xy 268.449221 -257.477661)
			(xy 268.397892 -257.499473) (xy 268.343935 -257.513579) (xy 268.288498 -257.519679) (xy 268.232764 -257.517642)
			(xy 268.177921 -257.507512) (xy 268.125137 -257.489505) (xy 268.075537 -257.464004) (xy 268.030179 -257.431553)
			(xy 267.99003 -257.392844) (xy 267.955944 -257.348701) (xy 267.928648 -257.300066) (xy 267.908725 -257.247975)
			(xy 267.896599 -257.193538) (xy 267.892528 -257.137916) (xy 267.259054 -257.137916) (xy 267.258568 -257.165167)
			(xy 267.250812 -257.219115) (xy 267.235457 -257.27141) (xy 267.212815 -257.320987) (xy 267.183349 -257.366837)
			(xy 267.147658 -257.408028) (xy 267.106467 -257.443719) (xy 267.060617 -257.473185) (xy 267.01104 -257.495827)
			(xy 266.958745 -257.511182) (xy 266.904797 -257.518938) (xy 266.850295 -257.518938) (xy 266.796347 -257.511182)
			(xy 266.744052 -257.495827) (xy 266.694475 -257.473185) (xy 266.648625 -257.443719) (xy 266.607434 -257.408028)
			(xy 266.571743 -257.366837) (xy 266.542277 -257.320987) (xy 266.519635 -257.27141) (xy 266.50428 -257.219115)
			(xy 266.496524 -257.165167) (xy 266.496038 -257.137916) (xy 266.4966 -257.108536) (xy 266.505647 -257.050476)
			(xy 266.523484 -256.994487) (xy 266.549689 -256.941893) (xy 266.583643 -256.893936) (xy 266.624545 -256.851747)
			(xy 266.647676 -256.833624) (xy 266.657074 -256.826258) (xy 266.667488 -256.805684) (xy 266.669012 -256.701798)
			(xy 266.659106 -256.680716) (xy 266.649962 -256.67335) (xy 266.628139 -256.655118) (xy 266.589613 -256.613295)
			(xy 266.557714 -256.566221) (xy 266.533147 -256.514938) (xy 266.516455 -256.46058) (xy 266.508007 -256.404348)
			(xy 266.507468 -256.375916) (xy 266.50803 -256.345864) (xy 266.517457 -256.286503) (xy 266.536078 -256.229356)
			(xy 266.563434 -256.175838) (xy 266.598847 -256.127273) (xy 266.619736 -256.10566) (xy 266.630658 -256.094738)
			(xy 266.636754 -256.064512) (xy 266.595098 -255.96342) (xy 266.590891 -255.954285) (xy 266.576714 -255.940041)
			(xy 266.558156 -255.932328) (xy 266.548108 -255.931924) (xy 264.056876 -255.931924) (xy 264.046834 -255.932353)
			(xy 264.02829 -255.940067) (xy 264.014124 -255.954304) (xy 264.009886 -255.96342) (xy 263.96823 -256.064512)
			(xy 263.974326 -256.094738) (xy 263.985248 -256.10566) (xy 264.00614 -256.127269) (xy 264.041541 -256.17584)
			(xy 264.068891 -256.22936) (xy 264.087514 -256.286506) (xy 264.096948 -256.345864) (xy 264.097516 -256.375916)
			(xy 264.09703 -256.403167) (xy 264.089274 -256.457115) (xy 264.073919 -256.50941) (xy 264.051277 -256.558987)
			(xy 264.021811 -256.604837) (xy 263.98612 -256.646028) (xy 263.944929 -256.681719) (xy 263.899079 -256.711185)
			(xy 263.849502 -256.733827) (xy 263.797207 -256.749182) (xy 263.743259 -256.756938) (xy 263.688757 -256.756938)
			(xy 263.634809 -256.749182) (xy 263.582514 -256.733827) (xy 263.532937 -256.711185) (xy 263.487087 -256.681719)
			(xy 263.445896 -256.646028) (xy 263.410205 -256.604837) (xy 263.380739 -256.558987) (xy 263.358097 -256.50941)
			(xy 263.342742 -256.457115) (xy 263.334986 -256.403167) (xy 263.3345 -256.375916) (xy 263.335063 -256.345864)
			(xy 263.34449 -256.286504) (xy 263.363113 -256.229358) (xy 263.39047 -256.175841) (xy 263.425885 -256.127279)
			(xy 263.446768 -256.10566) (xy 263.45769 -256.094738) (xy 263.463786 -256.064512) (xy 263.42213 -255.96342)
			(xy 263.417925 -255.954281) (xy 263.403749 -255.940029) (xy 263.385191 -255.932304) (xy 263.37514 -255.931924)
			(xy 263.167876 -255.931924) (xy 263.157834 -255.932353) (xy 263.13929 -255.940067) (xy 263.125124 -255.954304)
			(xy 263.120886 -255.96342) (xy 263.07923 -256.064512) (xy 263.085326 -256.094738) (xy 263.096248 -256.10566)
			(xy 263.11714 -256.127269) (xy 263.152541 -256.17584) (xy 263.179891 -256.22936) (xy 263.198514 -256.286506)
			(xy 263.207948 -256.345864) (xy 263.208516 -256.375916) (xy 263.20803 -256.403167) (xy 263.200274 -256.457115)
			(xy 263.184919 -256.50941) (xy 263.162277 -256.558987) (xy 263.132811 -256.604837) (xy 263.09712 -256.646028)
			(xy 263.055929 -256.681719) (xy 263.010079 -256.711185) (xy 262.960502 -256.733827) (xy 262.908207 -256.749182)
			(xy 262.854259 -256.756938) (xy 262.799757 -256.756938) (xy 262.745809 -256.749182) (xy 262.693514 -256.733827)
			(xy 262.643937 -256.711185) (xy 262.598087 -256.681719) (xy 262.556896 -256.646028) (xy 262.521205 -256.604837)
			(xy 262.491739 -256.558987) (xy 262.469097 -256.50941) (xy 262.453742 -256.457115) (xy 262.445986 -256.403167)
			(xy 262.4455 -256.375916) (xy 262.446063 -256.345864) (xy 262.45549 -256.286504) (xy 262.474113 -256.229358)
			(xy 262.50147 -256.175841) (xy 262.536885 -256.127279) (xy 262.557768 -256.10566) (xy 262.56869 -256.094738)
			(xy 262.574786 -256.064512) (xy 262.53313 -255.96342) (xy 262.528925 -255.954281) (xy 262.514749 -255.940029)
			(xy 262.496191 -255.932304) (xy 262.48614 -255.931924) (xy 261.69239 -255.931924) (xy 261.682347 -255.932351)
			(xy 261.663798 -255.940062) (xy 261.649628 -255.954299) (xy 261.6454 -255.96342) (xy 261.603744 -256.064512)
			(xy 261.60984 -256.094738) (xy 261.620762 -256.10566) (xy 261.641653 -256.127269) (xy 261.677054 -256.175841)
			(xy 261.704403 -256.229361) (xy 261.723025 -256.286507) (xy 261.732459 -256.345865) (xy 261.73303 -256.375916)
			(xy 261.732544 -256.403167) (xy 261.724788 -256.457115) (xy 261.709433 -256.50941) (xy 261.686791 -256.558987)
			(xy 261.657325 -256.604837) (xy 261.621634 -256.646028) (xy 261.580443 -256.681719) (xy 261.534593 -256.711185)
			(xy 261.485016 -256.733827) (xy 261.432721 -256.749182) (xy 261.378773 -256.756938) (xy 261.324271 -256.756938)
			(xy 261.270323 -256.749182) (xy 261.218028 -256.733827) (xy 261.168451 -256.711185) (xy 261.122601 -256.681719)
			(xy 261.08141 -256.646028) (xy 261.045719 -256.604837) (xy 261.016253 -256.558987) (xy 260.993611 -256.50941)
			(xy 260.978256 -256.457115) (xy 260.9705 -256.403167) (xy 260.970014 -256.375916) (xy 260.970577 -256.345864)
			(xy 260.980004 -256.286504) (xy 260.998628 -256.229359) (xy 261.025986 -256.175842) (xy 261.061402 -256.127281)
			(xy 261.082282 -256.10566) (xy 261.093204 -256.094738) (xy 261.0993 -256.064512) (xy 261.057644 -255.96342)
			(xy 261.053435 -255.954291) (xy 261.039254 -255.940062) (xy 261.020698 -255.932368) (xy 261.010654 -255.931924)
			(xy 260.942582 -255.931924) (xy 260.931658 -255.932452) (xy 260.911791 -255.941547) (xy 260.904228 -255.94945)
			(xy 260.84657 -256.01549) (xy 260.84022 -256.036318) (xy 260.841744 -256.04724) (xy 260.843396 -256.060003)
			(xy 260.845174 -256.085679) (xy 260.8453 -256.098548) (xy 260.844814 -256.125799) (xy 260.837058 -256.179747)
			(xy 260.821703 -256.232042) (xy 260.799061 -256.281619) (xy 260.769595 -256.327469) (xy 260.733904 -256.36866)
			(xy 260.692713 -256.404351) (xy 260.646863 -256.433817) (xy 260.597286 -256.456459) (xy 260.544991 -256.471814)
			(xy 260.491043 -256.47957) (xy 260.436541 -256.47957) (xy 260.382593 -256.471814) (xy 260.330298 -256.456459)
			(xy 260.280721 -256.433817) (xy 260.234871 -256.404351) (xy 260.19368 -256.36866) (xy 260.157989 -256.327469)
			(xy 260.128523 -256.281619) (xy 260.105881 -256.232042) (xy 260.090526 -256.179747) (xy 260.08277 -256.125799)
			(xy 260.082284 -256.098548) (xy 260.082418 -256.08568) (xy 260.084197 -256.060004) (xy 260.08584 -256.04724)
			(xy 260.087364 -256.036318) (xy 260.081014 -256.01549) (xy 260.023356 -255.94945) (xy 260.015805 -255.941532)
			(xy 259.99593 -255.932436) (xy 259.985002 -255.931924) (xy 257.27152 -255.931924) (xy 257.246116 -255.931442)
			(xy 257.195899 -255.923704) (xy 257.147448 -255.908406) (xy 257.101894 -255.885904) (xy 257.060299 -255.856725)
			(xy 257.04165 -255.839468) (xy 257.034299 -255.832986) (xy 257.016136 -255.82567) (xy 257.006344 -255.825244)
			(xy 256.633726 -255.825244) (xy 256.623663 -255.824806) (xy 256.605083 -255.817066) (xy 256.597658 -255.810258)
			(xy 256.595372 -255.807972) (xy 256.553462 -255.807972) (xy 256.531618 -255.829816) (xy 256.527808 -255.83896)
			(xy 256.516371 -255.864318) (xy 256.487235 -255.911703) (xy 256.451531 -255.954359) (xy 256.410015 -255.991382)
			(xy 256.363565 -256.021989) (xy 256.313166 -256.04553) (xy 256.259884 -256.061509) (xy 256.204847 -256.069586)
			(xy 256.177034 -256.0701) (xy 256.14808 -256.069566) (xy 256.090835 -256.060821) (xy 256.035569 -256.043528)
			(xy 255.98355 -256.018082) (xy 255.935973 -255.985069) (xy 255.89393 -255.945247) (xy 255.858387 -255.899529)
			(xy 255.843786 -255.87452) (xy 255.837182 -255.862582) (xy 255.814576 -255.848866) (xy 255.699768 -255.845564)
			(xy 255.6764 -255.858264) (xy 255.669288 -255.869694) (xy 255.654208 -255.892689) (xy 255.618491 -255.934499)
			(xy 255.577146 -255.970753) (xy 255.531028 -256.0007) (xy 255.481091 -256.023723) (xy 255.428367 -256.039344)
			(xy 255.373948 -256.04724) (xy 255.346454 -256.047748) (xy 255.319204 -256.047259) (xy 255.265259 -256.039497)
			(xy 255.212967 -256.024139) (xy 255.163393 -256.001496) (xy 255.117546 -255.972029) (xy 255.076358 -255.936338)
			(xy 255.040668 -255.895149) (xy 255.011202 -255.849301) (xy 254.988559 -255.799727) (xy 254.973201 -255.747435)
			(xy 254.96544 -255.69349) (xy 254.964946 -255.66624) (xy 254.965427 -255.638778) (xy 254.973302 -255.584421)
			(xy 254.988882 -255.531753) (xy 255.011846 -255.48186) (xy 255.041719 -255.43577) (xy 255.059434 -255.41478)
			(xy 255.06934 -255.403604) (xy 255.073658 -255.373886) (xy 255.029462 -255.276096) (xy 255.025097 -255.267366)
			(xy 255.011071 -255.253817) (xy 254.992985 -255.246522) (xy 254.983234 -255.246124) (xy 228.74351 -255.246124)
			(xy 228.717434 -255.245655) (xy 228.665921 -255.237528) (xy 228.616314 -255.22144) (xy 228.569835 -255.197789)
			(xy 228.52763 -255.167156) (xy 228.508814 -255.149096) (xy 227.344732 -253.985014) (xy 227.33733 -253.978177)
			(xy 227.318732 -253.970465) (xy 227.308664 -253.970028) (xy 186.196224 -253.970028) (xy 186.186173 -253.969523)
			(xy 186.167611 -253.961803) (xy 186.160156 -253.955042) (xy 176.690274 -244.48516) (xy 176.682861 -244.478484)
			(xy 176.664425 -244.470918) (xy 176.65446 -244.470428) (xy 154.355038 -244.470428) (xy 154.345076 -244.470914)
			(xy 154.326653 -244.478504) (xy 154.319224 -244.48516) (xy 154.051762 -244.752622) (xy 154.045917 -244.758866)
			(xy 154.038427 -244.774231) (xy 154.036454 -244.79121) (xy 154.038046 -244.799612) (xy 154.059636 -244.896132)
			(xy 154.076908 -244.915436) (xy 154.089354 -244.920008) (xy 154.117486 -244.930768) (xy 154.170221 -244.959862)
			(xy 154.217733 -244.996876) (xy 154.258845 -245.04089) (xy 154.292536 -245.090814) (xy 154.305762 -245.117874)
			(xy 154.310588 -245.128034) (xy 154.32786 -245.142512) (xy 154.425142 -245.16842) (xy 154.447494 -245.164356)
			(xy 154.456638 -245.157752) (xy 154.48095 -245.141217) (xy 154.533586 -245.115024) (xy 154.589615 -245.09721)
			(xy 154.647713 -245.088198) (xy 154.67711 -245.087648) (xy 154.704364 -245.088135) (xy 154.758317 -245.095893)
			(xy 154.810616 -245.111251) (xy 154.860198 -245.133895) (xy 154.906052 -245.163365) (xy 154.947246 -245.199061)
			(xy 154.982941 -245.240256) (xy 155.01241 -245.286111) (xy 155.035053 -245.335693) (xy 155.050409 -245.387993)
			(xy 155.058166 -245.441946) (xy 155.058166 -245.496454) (xy 155.050409 -245.550407) (xy 155.035053 -245.602707)
			(xy 155.01241 -245.652289) (xy 154.982941 -245.698144) (xy 154.947246 -245.739339) (xy 154.906052 -245.775035)
			(xy 154.860198 -245.804505) (xy 154.810616 -245.827149) (xy 154.758317 -245.842507) (xy 154.704364 -245.850265)
			(xy 154.67711 -245.850664) (xy 154.650042 -245.850191) (xy 154.596449 -245.842534) (xy 154.544478 -245.827374)
			(xy 154.495174 -245.805014) (xy 154.449529 -245.775905) (xy 154.408461 -245.740632) (xy 154.372795 -245.699905)
			(xy 154.343249 -245.654541) (xy 154.331416 -245.630192) (xy 154.32659 -245.620032) (xy 154.309318 -245.605554)
			(xy 154.212036 -245.579646) (xy 154.189684 -245.58371) (xy 154.18054 -245.590314) (xy 154.156229 -245.606851)
			(xy 154.103594 -245.633051) (xy 154.047564 -245.650873) (xy 153.989466 -245.659896) (xy 153.960068 -245.660418)
			(xy 153.930842 -245.659865) (xy 153.873073 -245.650957) (xy 153.81734 -245.633339) (xy 153.764947 -245.607424)
			(xy 153.717122 -245.573819) (xy 153.674984 -245.53331) (xy 153.63952 -245.486847) (xy 153.61156 -245.435516)
			(xy 153.601166 -245.408196) (xy 153.596594 -245.39575) (xy 153.57729 -245.378478) (xy 153.48077 -245.356888)
			(xy 153.472367 -245.355384) (xy 153.455425 -245.357398) (xy 153.440068 -245.364829) (xy 153.43378 -245.370604)
			(xy 153.403554 -245.40083) (xy 153.397204 -245.411498) (xy 153.395172 -245.41734) (xy 153.386738 -245.4429)
			(xy 153.363688 -245.491538) (xy 153.334033 -245.536454) (xy 153.29836 -245.576758) (xy 153.257377 -245.611649)
			(xy 153.211899 -245.640435) (xy 153.162826 -245.662545) (xy 153.111134 -245.677539) (xy 153.057847 -245.685122)
			(xy 153.030936 -245.685564) (xy 153.003683 -245.685103) (xy 152.94973 -245.67735) (xy 152.89743 -245.661997)
			(xy 152.847849 -245.639356) (xy 152.801994 -245.609888) (xy 152.760801 -245.574194) (xy 152.725107 -245.532999)
			(xy 152.695641 -245.487144) (xy 152.673001 -245.437562) (xy 152.657648 -245.385262) (xy 152.649896 -245.331309)
			(xy 152.649428 -245.304056) (xy 152.649887 -245.277142) (xy 152.657448 -245.223848) (xy 152.672427 -245.172147)
			(xy 152.694527 -245.123066) (xy 152.72331 -245.07758) (xy 152.758202 -245.036593) (xy 152.79851 -245.00092)
			(xy 152.843434 -244.971268) (xy 152.892082 -244.948228) (xy 152.917652 -244.93982) (xy 152.923494 -244.937788)
			(xy 152.934162 -244.931438) (xy 153.319226 -244.546374) (xy 153.326022 -244.538988) (xy 153.33369 -244.520457)
			(xy 153.333662 -244.500401) (xy 153.330148 -244.491002) (xy 153.324306 -244.476778) (xy 153.298906 -244.45976)
			(xy 150.44039 -244.45976) (xy 150.430322 -244.459334) (xy 150.411724 -244.451612) (xy 150.404322 -244.444774)
			(xy 150.021544 -244.061996) (xy 150.01411 -244.05528) (xy 149.99561 -244.047644) (xy 149.975596 -244.047644)
			(xy 149.957096 -244.05528) (xy 149.949662 -244.061996) (xy 149.802088 -244.209316) (xy 149.794468 -244.215666)
			(xy 149.511258 -244.404388) (xy 149.488738 -244.418841) (xy 149.440284 -244.441548) (xy 149.388976 -244.45674)
			(xy 149.335971 -244.464073) (xy 149.282465 -244.463383) (xy 149.255988 -244.459506) (xy 149.245636 -244.458341)
			(xy 149.225456 -244.463427) (xy 149.208926 -244.47607) (xy 149.20341 -244.484906) (xy 149.188817 -244.509916)
			(xy 149.153258 -244.555615) (xy 149.111207 -244.595421) (xy 149.063628 -244.628421) (xy 149.011612 -244.65386)
			(xy 148.956352 -244.671153) (xy 148.899114 -244.679905) (xy 148.870162 -244.680486) (xy 148.855176 -244.680232)
			(xy 148.844734 -244.680294) (xy 148.825273 -244.687801) (xy 148.810436 -244.702462) (xy 148.806154 -244.711982)
			(xy 148.795807 -244.736272) (xy 148.768986 -244.781749) (xy 148.735736 -244.82276) (xy 148.696788 -244.858404)
			(xy 148.652999 -244.887898) (xy 148.60533 -244.910594) (xy 148.554829 -244.925993) (xy 148.502607 -244.933756)
			(xy 148.476208 -244.934232) (xy 147.066762 -244.934232) (xy 147.054124 -244.934916) (xy 147.031882 -244.946923)
			(xy 147.024344 -244.957092) (xy 146.970242 -245.038372) (xy 146.967956 -245.063264) (xy 146.973036 -245.075202)
			(xy 146.982443 -245.098699) (xy 146.995679 -245.147551) (xy 147.002347 -245.197723) (xy 147.002754 -245.22303)
			(xy 147.002266 -245.250281) (xy 146.994506 -245.304228) (xy 146.989708 -245.320566) (xy 151.397206 -245.320566)
			(xy 151.401277 -245.264944) (xy 151.413403 -245.210507) (xy 151.433326 -245.158416) (xy 151.460622 -245.109781)
			(xy 151.494708 -245.065638) (xy 151.534857 -245.026929) (xy 151.580215 -244.994478) (xy 151.629815 -244.968977)
			(xy 151.682599 -244.95097) (xy 151.737442 -244.94084) (xy 151.793176 -244.938803) (xy 151.848613 -244.944903)
			(xy 151.90257 -244.959009) (xy 151.953899 -244.980821) (xy 152.001505 -245.009875) (xy 152.044373 -245.04555)
			(xy 152.08159 -245.087087) (xy 152.112363 -245.1336) (xy 152.136035 -245.184097) (xy 152.152103 -245.237504)
			(xy 152.160223 -245.29268) (xy 152.160732 -245.320566) (xy 152.160223 -245.348452) (xy 152.152103 -245.403628)
			(xy 152.136035 -245.457035) (xy 152.112363 -245.507532) (xy 152.08159 -245.554045) (xy 152.044373 -245.595582)
			(xy 152.001505 -245.631257) (xy 151.953899 -245.660311) (xy 151.90257 -245.682123) (xy 151.848613 -245.696229)
			(xy 151.793176 -245.702329) (xy 151.737442 -245.700292) (xy 151.682599 -245.690162) (xy 151.629815 -245.672155)
			(xy 151.580215 -245.646654) (xy 151.534857 -245.614203) (xy 151.494708 -245.575494) (xy 151.460622 -245.531351)
			(xy 151.433326 -245.482716) (xy 151.413403 -245.430625) (xy 151.401277 -245.376188) (xy 151.397206 -245.320566)
			(xy 146.989708 -245.320566) (xy 146.979149 -245.356522) (xy 146.956507 -245.406098) (xy 146.927041 -245.451948)
			(xy 146.89135 -245.493138) (xy 146.850161 -245.528831) (xy 146.804312 -245.558299) (xy 146.754737 -245.580944)
			(xy 146.702444 -245.596303) (xy 146.648497 -245.604065) (xy 146.621246 -245.604538) (xy 146.59457 -245.604096)
			(xy 146.541737 -245.59667) (xy 146.490454 -245.581955) (xy 146.441721 -245.56024) (xy 146.396488 -245.531947)
			(xy 146.355639 -245.497628) (xy 146.319969 -245.457953) (xy 146.290173 -245.413696) (xy 146.278092 -245.389908)
			(xy 146.271996 -245.376954) (xy 146.248628 -245.361714) (xy 146.130518 -245.357396) (xy 146.106134 -245.370858)
			(xy 146.099022 -245.38305) (xy 146.084252 -245.407369) (xy 146.048634 -245.451738) (xy 146.00682 -245.490325)
			(xy 145.959739 -245.522272) (xy 145.908435 -245.546871) (xy 145.854046 -245.563577) (xy 145.797779 -245.572018)
			(xy 145.76933 -245.572534) (xy 145.742075 -245.572073) (xy 145.688119 -245.56432) (xy 145.635816 -245.548967)
			(xy 145.586231 -245.526326) (xy 145.540372 -245.496859) (xy 145.499174 -245.461166) (xy 145.463474 -245.419973)
			(xy 145.434001 -245.374118) (xy 145.411353 -245.324536) (xy 145.395992 -245.272235) (xy 145.388231 -245.218281)
			(xy 145.387822 -245.191026) (xy 145.388419 -245.159853) (xy 145.398497 -245.098328) (xy 145.407888 -245.068598)
			(xy 145.411952 -245.056914) (xy 145.408396 -245.032784) (xy 145.353024 -244.955568) (xy 145.345452 -244.946111)
			(xy 145.323969 -244.93499) (xy 145.311876 -244.934232) (xy 143.045434 -244.934232) (xy 143.035471 -244.933747)
			(xy 143.017044 -244.926163) (xy 143.00962 -244.9195) (xy 142.50924 -244.41912) (xy 142.502548 -244.411714)
			(xy 142.494953 -244.393277) (xy 142.494508 -244.383306) (xy 142.494508 -243.638324) (xy 142.494762 -243.6241)
			(xy 142.494762 -243.622068) (xy 142.494336 -243.612054) (xy 142.486659 -243.593554) (xy 142.472487 -243.579401)
			(xy 142.453977 -243.57175) (xy 142.443962 -243.571268) (xy 140.679678 -243.571268) (xy 140.650468 -243.59997)
			(xy 140.64996 -243.620798) (xy 140.648803 -243.648914) (xy 140.639245 -243.704366) (xy 140.621648 -243.757814)
			(xy 140.596393 -243.808098) (xy 140.564028 -243.854129) (xy 140.525254 -243.894908) (xy 140.480912 -243.92955)
			(xy 140.431964 -243.957306) (xy 140.37947 -243.977573) (xy 140.324569 -243.989912) (xy 140.268452 -243.994055)
			(xy 140.212335 -243.989912) (xy 140.157434 -243.977573) (xy 140.10494 -243.957306) (xy 140.055992 -243.92955)
			(xy 140.01165 -243.894908) (xy 139.972876 -243.854129) (xy 139.940511 -243.808098) (xy 139.915256 -243.757814)
			(xy 139.897659 -243.704366) (xy 139.888101 -243.648914) (xy 139.886944 -243.620798) (xy 139.886436 -243.59997)
			(xy 139.857226 -243.571268) (xy 131.427474 -243.571268) (xy 131.417405 -243.571695) (xy 131.398805 -243.579412)
			(xy 131.391406 -243.586254) (xy 131.213098 -243.764562) (xy 131.205701 -243.771412) (xy 131.187103 -243.779152)
			(xy 131.17703 -243.779548) (xy 104.4702 -243.779548) (xy 104.466644 -243.783104) (xy 103.278432 -243.783104)
			(xy 103.265697 -243.783804) (xy 103.243298 -243.795931) (xy 103.23576 -243.806218) (xy 103.220599 -243.828764)
			(xy 103.184909 -243.86973) (xy 103.143769 -243.905217) (xy 103.09801 -243.934509) (xy 103.048558 -243.957012)
			(xy 102.996413 -243.972272) (xy 102.942632 -243.97998) (xy 102.8883 -243.97998) (xy 102.834519 -243.972272)
			(xy 102.782374 -243.957012) (xy 102.732922 -243.934509) (xy 102.687163 -243.905217) (xy 102.646023 -243.86973)
			(xy 102.610333 -243.828764) (xy 102.595172 -243.806218) (xy 102.59031 -243.799287) (xy 102.576973 -243.788872)
			(xy 102.560962 -243.783396) (xy 102.5525 -243.783104) (xy 102.472236 -243.783104) (xy 102.463442 -243.783467)
			(xy 102.446888 -243.789409) (xy 102.433322 -243.800603) (xy 102.428548 -243.807996) (xy 102.41373 -243.832115)
			(xy 102.37809 -243.876094) (xy 102.336342 -243.914321) (xy 102.289402 -243.945958) (xy 102.238301 -243.970309)
			(xy 102.184163 -243.986841) (xy 102.128175 -243.995189) (xy 102.099872 -243.995702) (xy 102.072879 -243.995233)
			(xy 102.019433 -243.987625) (xy 101.967592 -243.972564) (xy 101.918388 -243.95035) (xy 101.872805 -243.921427)
			(xy 101.851968 -243.904262) (xy 101.84384 -243.89715) (xy 101.823266 -243.891054) (xy 101.727254 -243.903246)
			(xy 101.708966 -243.914422) (xy 101.702616 -243.923312) (xy 101.687269 -243.944549) (xy 101.651686 -243.983008)
			(xy 101.61117 -244.016231) (xy 101.566486 -244.043593) (xy 101.518475 -244.064576) (xy 101.468043 -244.078785)
			(xy 101.41614 -244.085954) (xy 101.389942 -244.08638) (xy 101.363052 -244.085923) (xy 101.309804 -244.078378)
			(xy 101.258143 -244.06343) (xy 101.209093 -244.041377) (xy 101.163625 -244.012656) (xy 101.12264 -243.977834)
			(xy 101.086951 -243.937603) (xy 101.057264 -243.89276) (xy 101.034168 -243.844192) (xy 101.025706 -243.818664)
			(xy 101.02088 -243.802662) (xy 100.99421 -243.783104) (xy 99.50958 -243.783104) (xy 99.480116 -243.811298)
			(xy 99.479354 -243.831872) (xy 99.477687 -243.85962) (xy 99.467323 -243.914231) (xy 99.449145 -243.966761)
			(xy 99.423537 -244.016098) (xy 99.391042 -244.061197) (xy 99.352348 -244.101104) (xy 99.308272 -244.134975)
			(xy 99.259749 -244.162093) (xy 99.207805 -244.181883) (xy 99.153539 -244.193927) (xy 99.0981 -244.19797)
			(xy 99.042661 -244.193927) (xy 98.988395 -244.181883) (xy 98.936451 -244.162093) (xy 98.887928 -244.134975)
			(xy 98.843852 -244.101104) (xy 98.805158 -244.061197) (xy 98.772663 -244.016098) (xy 98.747055 -243.966761)
			(xy 98.728877 -243.914231) (xy 98.718513 -243.85962) (xy 98.716846 -243.831872) (xy 98.716084 -243.811298)
			(xy 98.68662 -243.783104) (xy 98.320098 -243.783104) (xy 98.29038 -243.812314) (xy 98.290126 -243.833142)
			(xy 98.28918 -243.861406) (xy 98.279978 -243.917204) (xy 98.262641 -243.971032) (xy 98.237548 -244.021712)
			(xy 98.20525 -244.068132) (xy 98.166455 -244.109278) (xy 98.122011 -244.144246) (xy 98.072892 -244.172271)
			(xy 98.020175 -244.19274) (xy 97.965014 -244.205203) (xy 97.908618 -244.209388) (xy 97.852222 -244.205203)
			(xy 97.797061 -244.19274) (xy 97.744344 -244.172271) (xy 97.695225 -244.144246) (xy 97.650781 -244.109278)
			(xy 97.611986 -244.068132) (xy 97.579688 -244.021712) (xy 97.554595 -243.971032) (xy 97.537258 -243.917204)
			(xy 97.528056 -243.861406) (xy 97.52711 -243.833142) (xy 97.526856 -243.812314) (xy 97.497138 -243.783104)
			(xy 94.445074 -243.783104) (xy 94.415864 -243.80952) (xy 94.414086 -243.829078) (xy 94.41087 -243.857032)
			(xy 94.397271 -243.91163) (xy 94.375801 -243.96364) (xy 94.346924 -244.011932) (xy 94.311268 -244.055458)
			(xy 94.269605 -244.093276) (xy 94.222839 -244.124564) (xy 94.171985 -244.148644) (xy 94.118146 -244.164993)
			(xy 94.062489 -244.173258) (xy 94.006223 -244.173258) (xy 93.950566 -244.164993) (xy 93.896727 -244.148644)
			(xy 93.845873 -244.124564) (xy 93.799107 -244.093276) (xy 93.757444 -244.055458) (xy 93.721788 -244.011932)
			(xy 93.692911 -243.96364) (xy 93.671441 -243.91163) (xy 93.657842 -243.857032) (xy 93.654626 -243.829078)
			(xy 93.652848 -243.80952) (xy 93.623638 -243.783104) (xy 24.749506 -243.783104) (xy 24.739435 -243.783526)
			(xy 24.72083 -243.79124) (xy 24.713438 -243.79809) (xy 24.19858 -244.312948) (xy 95.852232 -244.312948)
			(xy 95.856303 -244.257326) (xy 95.868429 -244.202889) (xy 95.888352 -244.150798) (xy 95.915648 -244.102163)
			(xy 95.949734 -244.05802) (xy 95.989883 -244.019311) (xy 96.035241 -243.98686) (xy 96.084841 -243.961359)
			(xy 96.137625 -243.943352) (xy 96.192468 -243.933222) (xy 96.248202 -243.931185) (xy 96.303639 -243.937285)
			(xy 96.357596 -243.951391) (xy 96.408925 -243.973203) (xy 96.456531 -244.002257) (xy 96.499399 -244.037932)
			(xy 96.536616 -244.079469) (xy 96.567389 -244.125982) (xy 96.591061 -244.176479) (xy 96.607129 -244.229886)
			(xy 96.615249 -244.285062) (xy 96.615758 -244.312948) (xy 96.615249 -244.340834) (xy 96.607129 -244.39601)
			(xy 96.591061 -244.449417) (xy 96.567389 -244.499914) (xy 96.536616 -244.546427) (xy 96.518457 -244.566694)
			(xy 100.51999 -244.566694) (xy 100.524061 -244.511072) (xy 100.536187 -244.456635) (xy 100.55611 -244.404544)
			(xy 100.583406 -244.355909) (xy 100.617492 -244.311766) (xy 100.657641 -244.273057) (xy 100.702999 -244.240606)
			(xy 100.752599 -244.215105) (xy 100.805383 -244.197098) (xy 100.860226 -244.186968) (xy 100.91596 -244.184931)
			(xy 100.971397 -244.191031) (xy 101.025354 -244.205137) (xy 101.076683 -244.226949) (xy 101.124289 -244.256003)
			(xy 101.151817 -244.278912) (xy 134.358124 -244.278912) (xy 134.362195 -244.22329) (xy 134.374321 -244.168853)
			(xy 134.394244 -244.116762) (xy 134.42154 -244.068127) (xy 134.455626 -244.023984) (xy 134.495775 -243.985275)
			(xy 134.541133 -243.952824) (xy 134.590733 -243.927323) (xy 134.643517 -243.909316) (xy 134.69836 -243.899186)
			(xy 134.754094 -243.897149) (xy 134.809531 -243.903249) (xy 134.863488 -243.917355) (xy 134.914817 -243.939167)
			(xy 134.962423 -243.968221) (xy 135.005291 -244.003896) (xy 135.042508 -244.045433) (xy 135.073281 -244.091946)
			(xy 135.096953 -244.142443) (xy 135.113021 -244.19585) (xy 135.121141 -244.251026) (xy 135.12165 -244.278912)
			(xy 135.121141 -244.306798) (xy 135.113021 -244.361974) (xy 135.096953 -244.415381) (xy 135.073281 -244.465878)
			(xy 135.042508 -244.512391) (xy 135.005291 -244.553928) (xy 134.962423 -244.589603) (xy 134.914817 -244.618657)
			(xy 134.863488 -244.640469) (xy 134.809531 -244.654575) (xy 134.754094 -244.660675) (xy 134.69836 -244.658638)
			(xy 134.643517 -244.648508) (xy 134.590733 -244.630501) (xy 134.541133 -244.605) (xy 134.495775 -244.572549)
			(xy 134.455626 -244.53384) (xy 134.42154 -244.489697) (xy 134.394244 -244.441062) (xy 134.374321 -244.388971)
			(xy 134.362195 -244.334534) (xy 134.358124 -244.278912) (xy 101.151817 -244.278912) (xy 101.167157 -244.291678)
			(xy 101.204374 -244.333215) (xy 101.235147 -244.379728) (xy 101.258819 -244.430225) (xy 101.274887 -244.483632)
			(xy 101.283007 -244.538808) (xy 101.283516 -244.566694) (xy 101.283007 -244.59458) (xy 101.274887 -244.649756)
			(xy 101.258819 -244.703163) (xy 101.235147 -244.75366) (xy 101.204374 -244.800173) (xy 101.167157 -244.84171)
			(xy 101.161279 -244.846602) (xy 126.515112 -244.846602) (xy 126.519183 -244.79098) (xy 126.531309 -244.736543)
			(xy 126.551232 -244.684452) (xy 126.578528 -244.635817) (xy 126.612614 -244.591674) (xy 126.652763 -244.552965)
			(xy 126.698121 -244.520514) (xy 126.747721 -244.495013) (xy 126.800505 -244.477006) (xy 126.855348 -244.466876)
			(xy 126.911082 -244.464839) (xy 126.966519 -244.470939) (xy 127.020476 -244.485045) (xy 127.071805 -244.506857)
			(xy 127.119411 -244.535911) (xy 127.162279 -244.571586) (xy 127.199496 -244.613123) (xy 127.230269 -244.659636)
			(xy 127.253941 -244.710133) (xy 127.270009 -244.76354) (xy 127.278129 -244.818716) (xy 127.278638 -244.846602)
			(xy 127.278129 -244.874488) (xy 127.270009 -244.929664) (xy 127.253941 -244.983071) (xy 127.230269 -245.033568)
			(xy 127.204741 -245.072154) (xy 133.901178 -245.072154) (xy 133.905249 -245.016532) (xy 133.917375 -244.962095)
			(xy 133.937298 -244.910004) (xy 133.964594 -244.861369) (xy 133.99868 -244.817226) (xy 134.038829 -244.778517)
			(xy 134.084187 -244.746066) (xy 134.133787 -244.720565) (xy 134.186571 -244.702558) (xy 134.241414 -244.692428)
			(xy 134.297148 -244.690391) (xy 134.352585 -244.696491) (xy 134.406542 -244.710597) (xy 134.457871 -244.732409)
			(xy 134.505477 -244.761463) (xy 134.548345 -244.797138) (xy 134.585562 -244.838675) (xy 134.616335 -244.885188)
			(xy 134.640007 -244.935685) (xy 134.656075 -244.989092) (xy 134.664195 -245.044268) (xy 134.664704 -245.072154)
			(xy 134.664195 -245.10004) (xy 134.656075 -245.155216) (xy 134.640007 -245.208623) (xy 134.616335 -245.25912)
			(xy 134.585562 -245.305633) (xy 134.548345 -245.34717) (xy 134.505477 -245.382845) (xy 134.457871 -245.411899)
			(xy 134.406542 -245.433711) (xy 134.352585 -245.447817) (xy 134.297148 -245.453917) (xy 134.241414 -245.45188)
			(xy 134.186571 -245.44175) (xy 134.133787 -245.423743) (xy 134.084187 -245.398242) (xy 134.038829 -245.365791)
			(xy 133.99868 -245.327082) (xy 133.964594 -245.282939) (xy 133.937298 -245.234304) (xy 133.917375 -245.182213)
			(xy 133.905249 -245.127776) (xy 133.901178 -245.072154) (xy 127.204741 -245.072154) (xy 127.199496 -245.080081)
			(xy 127.162279 -245.121618) (xy 127.119411 -245.157293) (xy 127.071805 -245.186347) (xy 127.020476 -245.208159)
			(xy 126.966519 -245.222265) (xy 126.911082 -245.228365) (xy 126.855348 -245.226328) (xy 126.800505 -245.216198)
			(xy 126.747721 -245.198191) (xy 126.698121 -245.17269) (xy 126.652763 -245.140239) (xy 126.612614 -245.10153)
			(xy 126.578528 -245.057387) (xy 126.551232 -245.008752) (xy 126.531309 -244.956661) (xy 126.519183 -244.902224)
			(xy 126.515112 -244.846602) (xy 101.161279 -244.846602) (xy 101.124289 -244.877385) (xy 101.076683 -244.906439)
			(xy 101.025354 -244.928251) (xy 100.971397 -244.942357) (xy 100.91596 -244.948457) (xy 100.860226 -244.94642)
			(xy 100.805383 -244.93629) (xy 100.752599 -244.918283) (xy 100.702999 -244.892782) (xy 100.657641 -244.860331)
			(xy 100.617492 -244.821622) (xy 100.583406 -244.777479) (xy 100.55611 -244.728844) (xy 100.536187 -244.676753)
			(xy 100.524061 -244.622316) (xy 100.51999 -244.566694) (xy 96.518457 -244.566694) (xy 96.499399 -244.587964)
			(xy 96.456531 -244.623639) (xy 96.408925 -244.652693) (xy 96.357596 -244.674505) (xy 96.303639 -244.688611)
			(xy 96.248202 -244.694711) (xy 96.192468 -244.692674) (xy 96.137625 -244.682544) (xy 96.084841 -244.664537)
			(xy 96.035241 -244.639036) (xy 95.989883 -244.606585) (xy 95.949734 -244.567876) (xy 95.915648 -244.523733)
			(xy 95.888352 -244.475098) (xy 95.868429 -244.423007) (xy 95.856303 -244.36857) (xy 95.852232 -244.312948)
			(xy 24.19858 -244.312948) (xy 24.072596 -244.438932) (xy 24.065755 -244.446333) (xy 24.058033 -244.46493)
			(xy 24.05761 -244.475) (xy 24.05761 -244.808248) (xy 93.652338 -244.808248) (xy 93.656409 -244.752626)
			(xy 93.668535 -244.698189) (xy 93.688458 -244.646098) (xy 93.715754 -244.597463) (xy 93.74984 -244.55332)
			(xy 93.789989 -244.514611) (xy 93.835347 -244.48216) (xy 93.884947 -244.456659) (xy 93.937731 -244.438652)
			(xy 93.992574 -244.428522) (xy 94.048308 -244.426485) (xy 94.103745 -244.432585) (xy 94.157702 -244.446691)
			(xy 94.209031 -244.468503) (xy 94.256637 -244.497557) (xy 94.299505 -244.533232) (xy 94.336722 -244.574769)
			(xy 94.367495 -244.621282) (xy 94.391167 -244.671779) (xy 94.407235 -244.725186) (xy 94.415355 -244.780362)
			(xy 94.415864 -244.808248) (xy 94.415355 -244.836134) (xy 94.407235 -244.89131) (xy 94.391167 -244.944717)
			(xy 94.367495 -244.995214) (xy 94.336722 -245.041727) (xy 94.299505 -245.083264) (xy 94.256637 -245.118939)
			(xy 94.209031 -245.147993) (xy 94.157702 -245.169805) (xy 94.103745 -245.183911) (xy 94.048308 -245.190011)
			(xy 93.992574 -245.187974) (xy 93.937731 -245.177844) (xy 93.884947 -245.159837) (xy 93.835347 -245.134336)
			(xy 93.789989 -245.101885) (xy 93.74984 -245.063176) (xy 93.715754 -245.019033) (xy 93.688458 -244.970398)
			(xy 93.668535 -244.918307) (xy 93.656409 -244.86387) (xy 93.652338 -244.808248) (xy 24.05761 -244.808248)
			(xy 24.05761 -245.824248) (xy 93.652338 -245.824248) (xy 93.656409 -245.768626) (xy 93.668535 -245.714189)
			(xy 93.688458 -245.662098) (xy 93.715754 -245.613463) (xy 93.74984 -245.56932) (xy 93.789989 -245.530611)
			(xy 93.835347 -245.49816) (xy 93.884947 -245.472659) (xy 93.937731 -245.454652) (xy 93.992574 -245.444522)
			(xy 94.048308 -245.442485) (xy 94.103745 -245.448585) (xy 94.157702 -245.462691) (xy 94.209031 -245.484503)
			(xy 94.256637 -245.513557) (xy 94.299505 -245.549232) (xy 94.336722 -245.590769) (xy 94.367495 -245.637282)
			(xy 94.391167 -245.687779) (xy 94.407235 -245.741186) (xy 94.415355 -245.796362) (xy 94.415864 -245.824248)
			(xy 95.865694 -245.824248) (xy 95.869765 -245.768626) (xy 95.881891 -245.714189) (xy 95.901814 -245.662098)
			(xy 95.92911 -245.613463) (xy 95.963196 -245.56932) (xy 96.003345 -245.530611) (xy 96.048703 -245.49816)
			(xy 96.098303 -245.472659) (xy 96.151087 -245.454652) (xy 96.20593 -245.444522) (xy 96.261664 -245.442485)
			(xy 96.317101 -245.448585) (xy 96.371058 -245.462691) (xy 96.422387 -245.484503) (xy 96.469993 -245.513557)
			(xy 96.512861 -245.549232) (xy 96.550078 -245.590769) (xy 96.580851 -245.637282) (xy 96.604523 -245.687779)
			(xy 96.620591 -245.741186) (xy 96.628711 -245.796362) (xy 96.62922 -245.824248) (xy 96.628711 -245.852134)
			(xy 96.620591 -245.90731) (xy 96.609282 -245.944898) (xy 100.372416 -245.944898) (xy 100.376487 -245.889276)
			(xy 100.388613 -245.834839) (xy 100.408536 -245.782748) (xy 100.435832 -245.734113) (xy 100.469918 -245.68997)
			(xy 100.510067 -245.651261) (xy 100.555425 -245.61881) (xy 100.605025 -245.593309) (xy 100.657809 -245.575302)
			(xy 100.712652 -245.565172) (xy 100.768386 -245.563135) (xy 100.823823 -245.569235) (xy 100.87778 -245.583341)
			(xy 100.929109 -245.605153) (xy 100.976715 -245.634207) (xy 101.019583 -245.669882) (xy 101.0568 -245.711419)
			(xy 101.087573 -245.757932) (xy 101.111245 -245.808429) (xy 101.127313 -245.861836) (xy 101.135433 -245.917012)
			(xy 101.135942 -245.944898) (xy 101.135433 -245.972784) (xy 101.127313 -246.02796) (xy 101.111245 -246.081367)
			(xy 101.087573 -246.131864) (xy 101.0568 -246.178377) (xy 101.019583 -246.219914) (xy 100.976715 -246.255589)
			(xy 100.929109 -246.284643) (xy 100.87778 -246.306455) (xy 100.823823 -246.320561) (xy 100.768386 -246.326661)
			(xy 100.712652 -246.324624) (xy 100.657809 -246.314494) (xy 100.605025 -246.296487) (xy 100.555425 -246.270986)
			(xy 100.510067 -246.238535) (xy 100.469918 -246.199826) (xy 100.435832 -246.155683) (xy 100.408536 -246.107048)
			(xy 100.388613 -246.054957) (xy 100.376487 -246.00052) (xy 100.372416 -245.944898) (xy 96.609282 -245.944898)
			(xy 96.604523 -245.960717) (xy 96.580851 -246.011214) (xy 96.550078 -246.057727) (xy 96.512861 -246.099264)
			(xy 96.469993 -246.134939) (xy 96.422387 -246.163993) (xy 96.371058 -246.185805) (xy 96.317101 -246.199911)
			(xy 96.261664 -246.206011) (xy 96.20593 -246.203974) (xy 96.151087 -246.193844) (xy 96.098303 -246.175837)
			(xy 96.048703 -246.150336) (xy 96.003345 -246.117885) (xy 95.963196 -246.079176) (xy 95.92911 -246.035033)
			(xy 95.901814 -245.986398) (xy 95.881891 -245.934307) (xy 95.869765 -245.87987) (xy 95.865694 -245.824248)
			(xy 94.415864 -245.824248) (xy 94.415355 -245.852134) (xy 94.407235 -245.90731) (xy 94.391167 -245.960717)
			(xy 94.367495 -246.011214) (xy 94.336722 -246.057727) (xy 94.299505 -246.099264) (xy 94.256637 -246.134939)
			(xy 94.209031 -246.163993) (xy 94.157702 -246.185805) (xy 94.103745 -246.199911) (xy 94.048308 -246.206011)
			(xy 93.992574 -246.203974) (xy 93.937731 -246.193844) (xy 93.884947 -246.175837) (xy 93.835347 -246.150336)
			(xy 93.789989 -246.117885) (xy 93.74984 -246.079176) (xy 93.715754 -246.035033) (xy 93.688458 -245.986398)
			(xy 93.668535 -245.934307) (xy 93.656409 -245.87987) (xy 93.652338 -245.824248) (xy 24.05761 -245.824248)
			(xy 24.05761 -246.840248) (xy 93.652338 -246.840248) (xy 93.656409 -246.784626) (xy 93.668535 -246.730189)
			(xy 93.688458 -246.678098) (xy 93.715754 -246.629463) (xy 93.74984 -246.58532) (xy 93.789989 -246.546611)
			(xy 93.835347 -246.51416) (xy 93.884947 -246.488659) (xy 93.937731 -246.470652) (xy 93.992574 -246.460522)
			(xy 94.048308 -246.458485) (xy 94.103745 -246.464585) (xy 94.157702 -246.478691) (xy 94.209031 -246.500503)
			(xy 94.256637 -246.529557) (xy 94.299505 -246.565232) (xy 94.336722 -246.606769) (xy 94.367495 -246.653282)
			(xy 94.391167 -246.703779) (xy 94.407235 -246.757186) (xy 94.415355 -246.812362) (xy 94.415716 -246.83212)
			(xy 99.693474 -246.83212) (xy 99.697545 -246.776498) (xy 99.709671 -246.722061) (xy 99.729594 -246.66997)
			(xy 99.75689 -246.621335) (xy 99.790976 -246.577192) (xy 99.831125 -246.538483) (xy 99.876483 -246.506032)
			(xy 99.926083 -246.480531) (xy 99.978867 -246.462524) (xy 100.03371 -246.452394) (xy 100.089444 -246.450357)
			(xy 100.144881 -246.456457) (xy 100.198838 -246.470563) (xy 100.250167 -246.492375) (xy 100.297773 -246.521429)
			(xy 100.340641 -246.557104) (xy 100.377858 -246.598641) (xy 100.408631 -246.645154) (xy 100.432303 -246.695651)
			(xy 100.448371 -246.749058) (xy 100.456491 -246.804234) (xy 100.457 -246.83212) (xy 100.456491 -246.860006)
			(xy 100.448371 -246.915182) (xy 100.432303 -246.968589) (xy 100.408631 -247.019086) (xy 100.377858 -247.065599)
			(xy 100.340641 -247.107136) (xy 100.297773 -247.142811) (xy 100.250167 -247.171865) (xy 100.198838 -247.193677)
			(xy 100.144881 -247.207783) (xy 100.089444 -247.213883) (xy 100.03371 -247.211846) (xy 99.978867 -247.201716)
			(xy 99.926083 -247.183709) (xy 99.876483 -247.158208) (xy 99.831125 -247.125757) (xy 99.790976 -247.087048)
			(xy 99.75689 -247.042905) (xy 99.729594 -246.99427) (xy 99.709671 -246.942179) (xy 99.697545 -246.887742)
			(xy 99.693474 -246.83212) (xy 94.415716 -246.83212) (xy 94.415864 -246.840248) (xy 94.415355 -246.868134)
			(xy 94.407235 -246.92331) (xy 94.391167 -246.976717) (xy 94.367495 -247.027214) (xy 94.336722 -247.073727)
			(xy 94.299505 -247.115264) (xy 94.256637 -247.150939) (xy 94.209031 -247.179993) (xy 94.157702 -247.201805)
			(xy 94.103745 -247.215911) (xy 94.048308 -247.222011) (xy 93.992574 -247.219974) (xy 93.937731 -247.209844)
			(xy 93.884947 -247.191837) (xy 93.835347 -247.166336) (xy 93.789989 -247.133885) (xy 93.74984 -247.095176)
			(xy 93.715754 -247.051033) (xy 93.688458 -247.002398) (xy 93.668535 -246.950307) (xy 93.656409 -246.89587)
			(xy 93.652338 -246.840248) (xy 24.05761 -246.840248) (xy 24.05761 -247.599753) (xy 114.289785 -247.599753)
			(xy 114.289785 -247.545247) (xy 114.297543 -247.491297) (xy 114.3129 -247.439) (xy 114.335543 -247.389421)
			(xy 114.365013 -247.34357) (xy 114.400708 -247.30238) (xy 114.441902 -247.266689) (xy 114.487757 -247.237224)
			(xy 114.537338 -247.214586) (xy 114.589636 -247.199234) (xy 114.643587 -247.191483) (xy 114.67084 -247.191022)
			(xy 114.699703 -247.191532) (xy 114.756772 -247.200215) (xy 114.811879 -247.217405) (xy 114.863762 -247.242709)
			(xy 114.911236 -247.27555) (xy 114.953214 -247.315174) (xy 114.988735 -247.360677) (xy 115.003326 -247.385586)
			(xy 115.010438 -247.398032) (xy 115.034568 -247.411748) (xy 115.152678 -247.409208) (xy 115.1763 -247.394476)
			(xy 115.18265 -247.381776) (xy 115.194935 -247.358523) (xy 115.224882 -247.315293) (xy 115.260485 -247.276589)
			(xy 115.30107 -247.243144) (xy 115.345865 -247.215594) (xy 115.394021 -247.194461) (xy 115.444625 -247.180146)
			(xy 115.496715 -247.17292) (xy 115.52301 -247.17248) (xy 115.552381 -247.172987) (xy 115.610427 -247.182)
			(xy 115.666408 -247.199795) (xy 115.719004 -247.225953) (xy 115.766974 -247.259857) (xy 115.809186 -247.300708)
			(xy 115.844644 -247.347541) (xy 115.859052 -247.37314) (xy 115.865402 -247.385332) (xy 115.88877 -247.399556)
			(xy 116.004594 -247.40235) (xy 116.02847 -247.389396) (xy 116.035582 -247.377458) (xy 116.050432 -247.353639)
			(xy 116.086089 -247.310289) (xy 116.127714 -247.272634) (xy 116.17441 -247.241487) (xy 116.225167 -247.217521)
			(xy 116.278889 -247.201254) (xy 116.334415 -247.193038) (xy 116.36248 -247.192546) (xy 116.389731 -247.1931)
			(xy 116.443677 -247.200854) (xy 116.495971 -247.216206) (xy 116.545548 -247.238845) (xy 116.591398 -247.268309)
			(xy 116.632588 -247.303998) (xy 116.668279 -247.345186) (xy 116.697746 -247.391035) (xy 116.720387 -247.44061)
			(xy 116.735742 -247.492903) (xy 116.743499 -247.54685) (xy 116.743499 -247.60135) (xy 116.735742 -247.655297)
			(xy 116.720387 -247.70759) (xy 116.697746 -247.757165) (xy 116.668279 -247.803014) (xy 116.632588 -247.844202)
			(xy 116.591398 -247.879891) (xy 116.545548 -247.909355) (xy 116.495971 -247.931994) (xy 116.443677 -247.947346)
			(xy 116.389731 -247.9551) (xy 116.36248 -247.955562) (xy 116.333113 -247.95496) (xy 116.275072 -247.945963)
			(xy 116.219094 -247.928183) (xy 116.166499 -247.902039) (xy 116.118528 -247.86815) (xy 116.076313 -247.827314)
			(xy 116.04085 -247.780495) (xy 116.026438 -247.754902) (xy 116.020088 -247.74271) (xy 115.99672 -247.728486)
			(xy 115.880896 -247.725692) (xy 115.85702 -247.738646) (xy 115.849908 -247.750584) (xy 115.835044 -247.774394)
			(xy 115.799392 -247.817747) (xy 115.75777 -247.855405) (xy 115.711076 -247.886554) (xy 115.660321 -247.910521)
			(xy 115.6066 -247.926789) (xy 115.551075 -247.935004) (xy 115.52301 -247.935496) (xy 115.494149 -247.934937)
			(xy 115.437083 -247.926262) (xy 115.381977 -247.90908) (xy 115.330094 -247.883783) (xy 115.28262 -247.850951)
			(xy 115.24064 -247.811333) (xy 115.205116 -247.765838) (xy 115.190524 -247.740932) (xy 115.183412 -247.728486)
			(xy 115.159282 -247.71477) (xy 115.041172 -247.71731) (xy 115.01755 -247.732042) (xy 115.0112 -247.744742)
			(xy 114.998961 -247.76802) (xy 114.969007 -247.81125) (xy 114.933396 -247.849954) (xy 114.892805 -247.883396)
			(xy 114.848003 -247.910943) (xy 114.799841 -247.932072) (xy 114.749232 -247.946382) (xy 114.697137 -247.953601)
			(xy 114.67084 -247.954038) (xy 114.643587 -247.953517) (xy 114.589636 -247.945766) (xy 114.537338 -247.930414)
			(xy 114.487757 -247.907776) (xy 114.441902 -247.878311) (xy 114.400708 -247.84262) (xy 114.365013 -247.80143)
			(xy 114.335543 -247.755579) (xy 114.3129 -247.706) (xy 114.297543 -247.653703) (xy 114.289785 -247.599753)
			(xy 24.05761 -247.599753) (xy 24.05761 -248.199402) (xy 123.865384 -248.199402) (xy 123.869455 -248.14378)
			(xy 123.881581 -248.089343) (xy 123.901504 -248.037252) (xy 123.9288 -247.988617) (xy 123.962886 -247.944474)
			(xy 124.003035 -247.905765) (xy 124.048393 -247.873314) (xy 124.097993 -247.847813) (xy 124.150777 -247.829806)
			(xy 124.20562 -247.819676) (xy 124.261354 -247.817639) (xy 124.316791 -247.823739) (xy 124.370748 -247.837845)
			(xy 124.422077 -247.859657) (xy 124.469683 -247.888711) (xy 124.511861 -247.923812) (xy 124.852682 -247.923812)
			(xy 124.856753 -247.86819) (xy 124.868879 -247.813753) (xy 124.888802 -247.761662) (xy 124.916098 -247.713027)
			(xy 124.950184 -247.668884) (xy 124.990333 -247.630175) (xy 125.035691 -247.597724) (xy 125.085291 -247.572223)
			(xy 125.138075 -247.554216) (xy 125.192918 -247.544086) (xy 125.248652 -247.542049) (xy 125.304089 -247.548149)
			(xy 125.358046 -247.562255) (xy 125.409375 -247.584067) (xy 125.456981 -247.613121) (xy 125.499849 -247.648796)
			(xy 125.537066 -247.690333) (xy 125.567839 -247.736846) (xy 125.591511 -247.787343) (xy 125.607579 -247.84075)
			(xy 125.615699 -247.895926) (xy 125.616208 -247.923812) (xy 125.615699 -247.951698) (xy 125.607579 -248.006874)
			(xy 125.591511 -248.060281) (xy 125.567839 -248.110778) (xy 125.537066 -248.157291) (xy 125.499849 -248.198828)
			(xy 125.456981 -248.234503) (xy 125.409375 -248.263557) (xy 125.358046 -248.285369) (xy 125.304089 -248.299475)
			(xy 125.248652 -248.305575) (xy 125.192918 -248.303538) (xy 125.138075 -248.293408) (xy 125.085291 -248.275401)
			(xy 125.035691 -248.2499) (xy 124.990333 -248.217449) (xy 124.950184 -248.17874) (xy 124.916098 -248.134597)
			(xy 124.888802 -248.085962) (xy 124.868879 -248.033871) (xy 124.856753 -247.979434) (xy 124.852682 -247.923812)
			(xy 124.511861 -247.923812) (xy 124.512551 -247.924386) (xy 124.549768 -247.965923) (xy 124.580541 -248.012436)
			(xy 124.604213 -248.062933) (xy 124.620281 -248.11634) (xy 124.628401 -248.171516) (xy 124.62891 -248.199402)
			(xy 124.628401 -248.227288) (xy 124.620281 -248.282464) (xy 124.604213 -248.335871) (xy 124.580541 -248.386368)
			(xy 124.549768 -248.432881) (xy 124.512551 -248.474418) (xy 124.469683 -248.510093) (xy 124.422077 -248.539147)
			(xy 124.370748 -248.560959) (xy 124.316791 -248.575065) (xy 124.261354 -248.581165) (xy 124.20562 -248.579128)
			(xy 124.150777 -248.568998) (xy 124.097993 -248.550991) (xy 124.048393 -248.52549) (xy 124.003035 -248.493039)
			(xy 123.962886 -248.45433) (xy 123.9288 -248.410187) (xy 123.901504 -248.361552) (xy 123.881581 -248.309461)
			(xy 123.869455 -248.255024) (xy 123.865384 -248.199402) (xy 24.05761 -248.199402) (xy 24.05761 -248.652538)
			(xy 128.32029 -248.652538) (xy 128.324361 -248.596916) (xy 128.336487 -248.542479) (xy 128.35641 -248.490388)
			(xy 128.383706 -248.441753) (xy 128.417792 -248.39761) (xy 128.457941 -248.358901) (xy 128.503299 -248.32645)
			(xy 128.552899 -248.300949) (xy 128.605683 -248.282942) (xy 128.660526 -248.272812) (xy 128.71626 -248.270775)
			(xy 128.771697 -248.276875) (xy 128.825654 -248.290981) (xy 128.876983 -248.312793) (xy 128.924589 -248.341847)
			(xy 128.967457 -248.377522) (xy 129.004674 -248.419059) (xy 129.035447 -248.465572) (xy 129.059119 -248.516069)
			(xy 129.075187 -248.569476) (xy 129.083307 -248.624652) (xy 129.083816 -248.652538) (xy 129.083307 -248.680424)
			(xy 129.075187 -248.7356) (xy 129.059119 -248.789007) (xy 129.035447 -248.839504) (xy 129.004674 -248.886017)
			(xy 128.967457 -248.927554) (xy 128.924589 -248.963229) (xy 128.876983 -248.992283) (xy 128.825654 -249.014095)
			(xy 128.771697 -249.028201) (xy 128.71626 -249.034301) (xy 128.660526 -249.032264) (xy 128.605683 -249.022134)
			(xy 128.552899 -249.004127) (xy 128.503299 -248.978626) (xy 128.457941 -248.946175) (xy 128.417792 -248.907466)
			(xy 128.383706 -248.863323) (xy 128.35641 -248.814688) (xy 128.336487 -248.762597) (xy 128.324361 -248.70816)
			(xy 128.32029 -248.652538) (xy 24.05761 -248.652538) (xy 24.05761 -248.866914) (xy 24.058036 -248.876983)
			(xy 24.065755 -248.895583) (xy 24.072596 -248.902982) (xy 24.443182 -249.273568) (xy 127.616964 -249.273568)
			(xy 127.621035 -249.217946) (xy 127.633161 -249.163509) (xy 127.653084 -249.111418) (xy 127.68038 -249.062783)
			(xy 127.714466 -249.01864) (xy 127.754615 -248.979931) (xy 127.799973 -248.94748) (xy 127.849573 -248.921979)
			(xy 127.902357 -248.903972) (xy 127.9572 -248.893842) (xy 128.012934 -248.891805) (xy 128.068371 -248.897905)
			(xy 128.122328 -248.912011) (xy 128.173657 -248.933823) (xy 128.221263 -248.962877) (xy 128.264131 -248.998552)
			(xy 128.301348 -249.040089) (xy 128.332121 -249.086602) (xy 128.355793 -249.137099) (xy 128.371861 -249.190506)
			(xy 128.379981 -249.245682) (xy 128.38049 -249.273568) (xy 128.379981 -249.301454) (xy 128.376011 -249.328432)
			(xy 129.023616 -249.328432) (xy 129.027687 -249.27281) (xy 129.039813 -249.218373) (xy 129.059736 -249.166282)
			(xy 129.087032 -249.117647) (xy 129.121118 -249.073504) (xy 129.161267 -249.034795) (xy 129.206625 -249.002344)
			(xy 129.256225 -248.976843) (xy 129.309009 -248.958836) (xy 129.363852 -248.948706) (xy 129.419586 -248.946669)
			(xy 129.475023 -248.952769) (xy 129.52898 -248.966875) (xy 129.580309 -248.988687) (xy 129.627915 -249.017741)
			(xy 129.670783 -249.053416) (xy 129.708 -249.094953) (xy 129.738773 -249.141466) (xy 129.762445 -249.191963)
			(xy 129.778513 -249.24537) (xy 129.786633 -249.300546) (xy 129.787142 -249.328432) (xy 129.786633 -249.356318)
			(xy 129.778513 -249.411494) (xy 129.762445 -249.464901) (xy 129.738773 -249.515398) (xy 129.708 -249.561911)
			(xy 129.670783 -249.603448) (xy 129.627915 -249.639123) (xy 129.580309 -249.668177) (xy 129.52898 -249.689989)
			(xy 129.475023 -249.704095) (xy 129.419586 -249.710195) (xy 129.363852 -249.708158) (xy 129.309009 -249.698028)
			(xy 129.256225 -249.680021) (xy 129.206625 -249.65452) (xy 129.161267 -249.622069) (xy 129.121118 -249.58336)
			(xy 129.087032 -249.539217) (xy 129.059736 -249.490582) (xy 129.039813 -249.438491) (xy 129.027687 -249.384054)
			(xy 129.023616 -249.328432) (xy 128.376011 -249.328432) (xy 128.371861 -249.35663) (xy 128.355793 -249.410037)
			(xy 128.332121 -249.460534) (xy 128.301348 -249.507047) (xy 128.264131 -249.548584) (xy 128.221263 -249.584259)
			(xy 128.173657 -249.613313) (xy 128.122328 -249.635125) (xy 128.068371 -249.649231) (xy 128.012934 -249.655331)
			(xy 127.9572 -249.653294) (xy 127.902357 -249.643164) (xy 127.849573 -249.625157) (xy 127.799973 -249.599656)
			(xy 127.754615 -249.567205) (xy 127.714466 -249.528496) (xy 127.68038 -249.484353) (xy 127.653084 -249.435718)
			(xy 127.633161 -249.383627) (xy 127.621035 -249.32919) (xy 127.616964 -249.273568) (xy 24.443182 -249.273568)
			(xy 24.645874 -249.47626) (xy 24.653275 -249.483099) (xy 24.671873 -249.490813) (xy 24.681942 -249.491246)
			(xy 39.87292 -249.491246) (xy 39.882988 -249.491674) (xy 39.901582 -249.499399) (xy 39.908988 -249.506232)
			(xy 40.663403 -250.260647) (xy 127.657412 -250.260647) (xy 127.657412 -250.206153) (xy 127.665167 -250.152215)
			(xy 127.680518 -250.099929) (xy 127.703154 -250.050359) (xy 127.732613 -250.004515) (xy 127.768296 -249.96333)
			(xy 127.809477 -249.927641) (xy 127.855317 -249.898177) (xy 127.904884 -249.875535) (xy 127.957168 -249.860177)
			(xy 128.011105 -249.852415) (xy 128.038352 -249.851926) (xy 128.064669 -249.852356) (xy 128.116804 -249.85958)
			(xy 128.167453 -249.873897) (xy 128.215655 -249.895036) (xy 128.260497 -249.922595) (xy 128.301127 -249.956053)
			(xy 128.319276 -249.975116) (xy 128.326802 -249.982512) (xy 128.346079 -249.991039) (xy 128.356614 -249.991626)
			(xy 128.43129 -249.991626) (xy 128.44184 -249.991097) (xy 128.461134 -249.982561) (xy 128.468628 -249.975116)
			(xy 128.486752 -249.956026) (xy 128.527375 -249.922548) (xy 128.572217 -249.894979) (xy 128.620427 -249.873842)
			(xy 128.671086 -249.85954) (xy 128.723232 -249.852345) (xy 128.749552 -249.851926) (xy 128.77681 -249.852318)
			(xy 128.830771 -249.86007) (xy 128.883079 -249.875423) (xy 128.93267 -249.898065) (xy 128.978533 -249.927534)
			(xy 129.019735 -249.963231) (xy 129.055437 -250.004429) (xy 129.084912 -250.050288) (xy 129.10756 -250.099876)
			(xy 129.12292 -250.152182) (xy 129.130679 -250.206143) (xy 129.130679 -250.233688) (xy 129.72491 -250.233688)
			(xy 129.728981 -250.178066) (xy 129.741107 -250.123629) (xy 129.76103 -250.071538) (xy 129.788326 -250.022903)
			(xy 129.822412 -249.97876) (xy 129.862561 -249.940051) (xy 129.907919 -249.9076) (xy 129.957519 -249.882099)
			(xy 130.010303 -249.864092) (xy 130.065146 -249.853962) (xy 130.12088 -249.851925) (xy 130.176317 -249.858025)
			(xy 130.230274 -249.872131) (xy 130.281603 -249.893943) (xy 130.329209 -249.922997) (xy 130.372077 -249.958672)
			(xy 130.409294 -250.000209) (xy 130.440067 -250.046722) (xy 130.463739 -250.097219) (xy 130.479807 -250.150626)
			(xy 130.487927 -250.205802) (xy 130.488436 -250.233688) (xy 130.487927 -250.261574) (xy 130.479807 -250.31675)
			(xy 130.463739 -250.370157) (xy 130.440067 -250.420654) (xy 130.409294 -250.467167) (xy 130.372077 -250.508704)
			(xy 130.329209 -250.544379) (xy 130.281603 -250.573433) (xy 130.230274 -250.595245) (xy 130.176317 -250.609351)
			(xy 130.12088 -250.615451) (xy 130.065146 -250.613414) (xy 130.010303 -250.603284) (xy 129.957519 -250.585277)
			(xy 129.907919 -250.559776) (xy 129.862561 -250.527325) (xy 129.822412 -250.488616) (xy 129.788326 -250.444473)
			(xy 129.76103 -250.395838) (xy 129.741107 -250.343747) (xy 129.728981 -250.28931) (xy 129.72491 -250.233688)
			(xy 129.130679 -250.233688) (xy 129.130679 -250.260657) (xy 129.12292 -250.314618) (xy 129.10756 -250.366924)
			(xy 129.084912 -250.416512) (xy 129.055437 -250.462371) (xy 129.019735 -250.503569) (xy 128.978533 -250.539266)
			(xy 128.93267 -250.568735) (xy 128.883079 -250.591377) (xy 128.830771 -250.60673) (xy 128.77681 -250.614482)
			(xy 128.749552 -250.614942) (xy 128.723236 -250.614487) (xy 128.671103 -250.607266) (xy 128.620455 -250.592952)
			(xy 128.572254 -250.571818) (xy 128.527411 -250.544263) (xy 128.486779 -250.510811) (xy 128.468628 -250.491752)
			(xy 128.461091 -250.484368) (xy 128.441823 -250.475832) (xy 128.43129 -250.475242) (xy 128.356614 -250.475242)
			(xy 128.346062 -250.475753) (xy 128.326766 -250.484299) (xy 128.319276 -250.491752) (xy 128.301144 -250.510834)
			(xy 128.260524 -250.544314) (xy 128.215683 -250.571885) (xy 128.167475 -250.593023) (xy 128.116817 -250.607327)
			(xy 128.064672 -250.614523) (xy 128.038352 -250.614942) (xy 128.011105 -250.614385) (xy 127.957168 -250.606623)
			(xy 127.904884 -250.591265) (xy 127.855317 -250.568623) (xy 127.809477 -250.539159) (xy 127.768296 -250.50347)
			(xy 127.732613 -250.462285) (xy 127.703154 -250.416441) (xy 127.680518 -250.366871) (xy 127.665167 -250.314585)
			(xy 127.657412 -250.260647) (xy 40.663403 -250.260647) (xy 40.884348 -250.481592) (xy 40.891201 -250.488988)
			(xy 40.898947 -250.507586) (xy 40.899334 -250.51766) (xy 40.899334 -250.907296) (xy 40.899624 -250.915171)
			(xy 40.904402 -250.930177) (xy 40.908732 -250.93676) (xy 40.923672 -250.958416) (xy 40.948096 -251.005013)
			(xy 40.965881 -251.054527) (xy 40.976689 -251.106016) (xy 40.980314 -251.158502) (xy 40.976688 -251.210987)
			(xy 40.96588 -251.262476) (xy 40.948095 -251.311989) (xy 40.92367 -251.358587) (xy 40.913761 -251.372953)
			(xy 123.340055 -251.372953) (xy 123.340055 -251.318447) (xy 123.347813 -251.264494) (xy 123.363169 -251.212195)
			(xy 123.385813 -251.162614) (xy 123.415282 -251.116761) (xy 123.450977 -251.075568) (xy 123.492172 -251.039874)
			(xy 123.538027 -251.010406) (xy 123.587609 -250.987765) (xy 123.639908 -250.97241) (xy 123.69386 -250.964654)
			(xy 123.721114 -250.964192) (xy 123.750442 -250.96469) (xy 123.808409 -250.973665) (xy 123.86432 -250.991401)
			(xy 123.916861 -251.01748) (xy 123.964793 -251.051289) (xy 124.006991 -251.092033) (xy 124.025152 -251.115068)
			(xy 124.032264 -251.12472) (xy 124.053854 -251.135388) (xy 124.159518 -251.134372) (xy 124.180854 -251.123196)
			(xy 124.187966 -251.113544) (xy 124.206078 -251.089709) (xy 124.248477 -251.047451) (xy 124.296954 -251.01233)
			(xy 124.350318 -250.985208) (xy 124.407263 -250.96675) (xy 124.466391 -250.957408) (xy 124.496322 -250.956826)
			(xy 124.524828 -250.957385) (xy 124.581204 -250.965871) (xy 124.63569 -250.982651) (xy 124.687072 -251.007352)
			(xy 124.734207 -251.039424) (xy 124.776045 -251.078152) (xy 124.794264 -251.100082) (xy 124.80163 -251.109226)
			(xy 124.82195 -251.119132) (xy 124.924058 -251.120148) (xy 124.944378 -251.11075) (xy 124.951744 -251.101606)
			(xy 124.969957 -251.080469) (xy 125.01151 -251.043235) (xy 125.058048 -251.012457) (xy 125.108574 -250.988791)
			(xy 125.162011 -250.972743) (xy 125.217216 -250.964655) (xy 125.245114 -250.964192) (xy 125.272365 -250.964679)
			(xy 125.326311 -250.972437) (xy 125.378604 -250.987793) (xy 125.428179 -251.010435) (xy 125.474028 -251.039902)
			(xy 125.515217 -251.075593) (xy 125.550907 -251.116783) (xy 125.577717 -251.158502) (xy 140.060424 -251.158502)
			(xy 140.064495 -251.10288) (xy 140.076621 -251.048443) (xy 140.096544 -250.996352) (xy 140.12384 -250.947717)
			(xy 140.157926 -250.903574) (xy 140.198075 -250.864865) (xy 140.243433 -250.832414) (xy 140.293033 -250.806913)
			(xy 140.345817 -250.788906) (xy 140.40066 -250.778776) (xy 140.456394 -250.776739) (xy 140.511831 -250.782839)
			(xy 140.565788 -250.796945) (xy 140.617117 -250.818757) (xy 140.664723 -250.847811) (xy 140.707591 -250.883486)
			(xy 140.744808 -250.925023) (xy 140.775581 -250.971536) (xy 140.799253 -251.022033) (xy 140.815321 -251.07544)
			(xy 140.823441 -251.130616) (xy 140.82395 -251.158502) (xy 141.076424 -251.158502) (xy 141.080495 -251.10288)
			(xy 141.092621 -251.048443) (xy 141.112544 -250.996352) (xy 141.13984 -250.947717) (xy 141.173926 -250.903574)
			(xy 141.214075 -250.864865) (xy 141.259433 -250.832414) (xy 141.309033 -250.806913) (xy 141.361817 -250.788906)
			(xy 141.41666 -250.778776) (xy 141.472394 -250.776739) (xy 141.527831 -250.782839) (xy 141.581788 -250.796945)
			(xy 141.633117 -250.818757) (xy 141.680723 -250.847811) (xy 141.723591 -250.883486) (xy 141.760808 -250.925023)
			(xy 141.791581 -250.971536) (xy 141.815253 -251.022033) (xy 141.831321 -251.07544) (xy 141.839441 -251.130616)
			(xy 141.83995 -251.158502) (xy 142.092424 -251.158502) (xy 142.096495 -251.10288) (xy 142.108621 -251.048443)
			(xy 142.128544 -250.996352) (xy 142.15584 -250.947717) (xy 142.189926 -250.903574) (xy 142.230075 -250.864865)
			(xy 142.275433 -250.832414) (xy 142.325033 -250.806913) (xy 142.377817 -250.788906) (xy 142.43266 -250.778776)
			(xy 142.488394 -250.776739) (xy 142.543831 -250.782839) (xy 142.597788 -250.796945) (xy 142.649117 -250.818757)
			(xy 142.696723 -250.847811) (xy 142.739591 -250.883486) (xy 142.776808 -250.925023) (xy 142.807581 -250.971536)
			(xy 142.831253 -251.022033) (xy 142.847321 -251.07544) (xy 142.855441 -251.130616) (xy 142.85595 -251.158502)
			(xy 143.108424 -251.158502) (xy 143.112495 -251.10288) (xy 143.124621 -251.048443) (xy 143.144544 -250.996352)
			(xy 143.17184 -250.947717) (xy 143.205926 -250.903574) (xy 143.246075 -250.864865) (xy 143.291433 -250.832414)
			(xy 143.341033 -250.806913) (xy 143.393817 -250.788906) (xy 143.44866 -250.778776) (xy 143.504394 -250.776739)
			(xy 143.559831 -250.782839) (xy 143.613788 -250.796945) (xy 143.665117 -250.818757) (xy 143.712723 -250.847811)
			(xy 143.755591 -250.883486) (xy 143.792808 -250.925023) (xy 143.823581 -250.971536) (xy 143.847253 -251.022033)
			(xy 143.863321 -251.07544) (xy 143.871441 -251.130616) (xy 143.87195 -251.158502) (xy 144.124424 -251.158502)
			(xy 144.128495 -251.10288) (xy 144.140621 -251.048443) (xy 144.160544 -250.996352) (xy 144.18784 -250.947717)
			(xy 144.221926 -250.903574) (xy 144.262075 -250.864865) (xy 144.307433 -250.832414) (xy 144.357033 -250.806913)
			(xy 144.409817 -250.788906) (xy 144.46466 -250.778776) (xy 144.520394 -250.776739) (xy 144.575831 -250.782839)
			(xy 144.629788 -250.796945) (xy 144.681117 -250.818757) (xy 144.728723 -250.847811) (xy 144.771591 -250.883486)
			(xy 144.808808 -250.925023) (xy 144.839581 -250.971536) (xy 144.863253 -251.022033) (xy 144.879321 -251.07544)
			(xy 144.887441 -251.130616) (xy 144.88795 -251.158502) (xy 145.140424 -251.158502) (xy 145.144495 -251.10288)
			(xy 145.156621 -251.048443) (xy 145.176544 -250.996352) (xy 145.20384 -250.947717) (xy 145.237926 -250.903574)
			(xy 145.278075 -250.864865) (xy 145.323433 -250.832414) (xy 145.373033 -250.806913) (xy 145.425817 -250.788906)
			(xy 145.48066 -250.778776) (xy 145.536394 -250.776739) (xy 145.591831 -250.782839) (xy 145.645788 -250.796945)
			(xy 145.697117 -250.818757) (xy 145.744723 -250.847811) (xy 145.787591 -250.883486) (xy 145.824808 -250.925023)
			(xy 145.855581 -250.971536) (xy 145.879253 -251.022033) (xy 145.895321 -251.07544) (xy 145.903441 -251.130616)
			(xy 145.90395 -251.158502) (xy 146.156424 -251.158502) (xy 146.160495 -251.10288) (xy 146.172621 -251.048443)
			(xy 146.192544 -250.996352) (xy 146.21984 -250.947717) (xy 146.253926 -250.903574) (xy 146.294075 -250.864865)
			(xy 146.339433 -250.832414) (xy 146.389033 -250.806913) (xy 146.441817 -250.788906) (xy 146.49666 -250.778776)
			(xy 146.552394 -250.776739) (xy 146.607831 -250.782839) (xy 146.661788 -250.796945) (xy 146.713117 -250.818757)
			(xy 146.760723 -250.847811) (xy 146.803591 -250.883486) (xy 146.840808 -250.925023) (xy 146.871581 -250.971536)
			(xy 146.895253 -251.022033) (xy 146.911321 -251.07544) (xy 146.919441 -251.130616) (xy 146.91995 -251.158502)
			(xy 147.172424 -251.158502) (xy 147.176495 -251.10288) (xy 147.188621 -251.048443) (xy 147.208544 -250.996352)
			(xy 147.23584 -250.947717) (xy 147.269926 -250.903574) (xy 147.310075 -250.864865) (xy 147.355433 -250.832414)
			(xy 147.405033 -250.806913) (xy 147.457817 -250.788906) (xy 147.51266 -250.778776) (xy 147.568394 -250.776739)
			(xy 147.623831 -250.782839) (xy 147.677788 -250.796945) (xy 147.729117 -250.818757) (xy 147.776723 -250.847811)
			(xy 147.819591 -250.883486) (xy 147.856808 -250.925023) (xy 147.887581 -250.971536) (xy 147.911253 -251.022033)
			(xy 147.927321 -251.07544) (xy 147.935441 -251.130616) (xy 147.93595 -251.158502) (xy 148.188424 -251.158502)
			(xy 148.192495 -251.10288) (xy 148.204621 -251.048443) (xy 148.224544 -250.996352) (xy 148.25184 -250.947717)
			(xy 148.285926 -250.903574) (xy 148.326075 -250.864865) (xy 148.371433 -250.832414) (xy 148.421033 -250.806913)
			(xy 148.473817 -250.788906) (xy 148.52866 -250.778776) (xy 148.584394 -250.776739) (xy 148.639831 -250.782839)
			(xy 148.693788 -250.796945) (xy 148.745117 -250.818757) (xy 148.792723 -250.847811) (xy 148.835591 -250.883486)
			(xy 148.872808 -250.925023) (xy 148.903581 -250.971536) (xy 148.927253 -251.022033) (xy 148.943321 -251.07544)
			(xy 148.951441 -251.130616) (xy 148.95195 -251.158502) (xy 149.204424 -251.158502) (xy 149.208495 -251.10288)
			(xy 149.220621 -251.048443) (xy 149.240544 -250.996352) (xy 149.26784 -250.947717) (xy 149.301926 -250.903574)
			(xy 149.342075 -250.864865) (xy 149.387433 -250.832414) (xy 149.437033 -250.806913) (xy 149.489817 -250.788906)
			(xy 149.54466 -250.778776) (xy 149.600394 -250.776739) (xy 149.655831 -250.782839) (xy 149.709788 -250.796945)
			(xy 149.761117 -250.818757) (xy 149.808723 -250.847811) (xy 149.851591 -250.883486) (xy 149.888808 -250.925023)
			(xy 149.919581 -250.971536) (xy 149.943253 -251.022033) (xy 149.959321 -251.07544) (xy 149.967441 -251.130616)
			(xy 149.96795 -251.158502) (xy 150.220424 -251.158502) (xy 150.224495 -251.10288) (xy 150.236621 -251.048443)
			(xy 150.256544 -250.996352) (xy 150.28384 -250.947717) (xy 150.317926 -250.903574) (xy 150.358075 -250.864865)
			(xy 150.403433 -250.832414) (xy 150.453033 -250.806913) (xy 150.505817 -250.788906) (xy 150.56066 -250.778776)
			(xy 150.616394 -250.776739) (xy 150.671831 -250.782839) (xy 150.725788 -250.796945) (xy 150.777117 -250.818757)
			(xy 150.824723 -250.847811) (xy 150.867591 -250.883486) (xy 150.904808 -250.925023) (xy 150.935581 -250.971536)
			(xy 150.959253 -251.022033) (xy 150.975321 -251.07544) (xy 150.983441 -251.130616) (xy 150.98395 -251.158502)
			(xy 151.236424 -251.158502) (xy 151.240495 -251.10288) (xy 151.252621 -251.048443) (xy 151.272544 -250.996352)
			(xy 151.29984 -250.947717) (xy 151.333926 -250.903574) (xy 151.374075 -250.864865) (xy 151.419433 -250.832414)
			(xy 151.469033 -250.806913) (xy 151.521817 -250.788906) (xy 151.57666 -250.778776) (xy 151.632394 -250.776739)
			(xy 151.687831 -250.782839) (xy 151.741788 -250.796945) (xy 151.793117 -250.818757) (xy 151.840723 -250.847811)
			(xy 151.883591 -250.883486) (xy 151.920808 -250.925023) (xy 151.951581 -250.971536) (xy 151.975253 -251.022033)
			(xy 151.991321 -251.07544) (xy 151.999441 -251.130616) (xy 151.99995 -251.158502) (xy 152.252424 -251.158502)
			(xy 152.256495 -251.10288) (xy 152.268621 -251.048443) (xy 152.288544 -250.996352) (xy 152.31584 -250.947717)
			(xy 152.349926 -250.903574) (xy 152.390075 -250.864865) (xy 152.435433 -250.832414) (xy 152.485033 -250.806913)
			(xy 152.537817 -250.788906) (xy 152.59266 -250.778776) (xy 152.648394 -250.776739) (xy 152.703831 -250.782839)
			(xy 152.757788 -250.796945) (xy 152.809117 -250.818757) (xy 152.856723 -250.847811) (xy 152.899591 -250.883486)
			(xy 152.936808 -250.925023) (xy 152.967581 -250.971536) (xy 152.991253 -251.022033) (xy 153.007321 -251.07544)
			(xy 153.015441 -251.130616) (xy 153.01595 -251.158502) (xy 153.268424 -251.158502) (xy 153.272495 -251.10288)
			(xy 153.284621 -251.048443) (xy 153.304544 -250.996352) (xy 153.33184 -250.947717) (xy 153.365926 -250.903574)
			(xy 153.406075 -250.864865) (xy 153.451433 -250.832414) (xy 153.501033 -250.806913) (xy 153.553817 -250.788906)
			(xy 153.60866 -250.778776) (xy 153.664394 -250.776739) (xy 153.719831 -250.782839) (xy 153.773788 -250.796945)
			(xy 153.825117 -250.818757) (xy 153.872723 -250.847811) (xy 153.915591 -250.883486) (xy 153.952808 -250.925023)
			(xy 153.983581 -250.971536) (xy 154.007253 -251.022033) (xy 154.023321 -251.07544) (xy 154.031441 -251.130616)
			(xy 154.03195 -251.158502) (xy 154.284424 -251.158502) (xy 154.288495 -251.10288) (xy 154.300621 -251.048443)
			(xy 154.320544 -250.996352) (xy 154.34784 -250.947717) (xy 154.381926 -250.903574) (xy 154.422075 -250.864865)
			(xy 154.467433 -250.832414) (xy 154.517033 -250.806913) (xy 154.569817 -250.788906) (xy 154.62466 -250.778776)
			(xy 154.680394 -250.776739) (xy 154.735831 -250.782839) (xy 154.789788 -250.796945) (xy 154.841117 -250.818757)
			(xy 154.888723 -250.847811) (xy 154.931591 -250.883486) (xy 154.968808 -250.925023) (xy 154.999581 -250.971536)
			(xy 155.023253 -251.022033) (xy 155.039321 -251.07544) (xy 155.047441 -251.130616) (xy 155.04795 -251.158502)
			(xy 156.316424 -251.158502) (xy 156.320495 -251.10288) (xy 156.332621 -251.048443) (xy 156.352544 -250.996352)
			(xy 156.37984 -250.947717) (xy 156.413926 -250.903574) (xy 156.454075 -250.864865) (xy 156.499433 -250.832414)
			(xy 156.549033 -250.806913) (xy 156.601817 -250.788906) (xy 156.65666 -250.778776) (xy 156.712394 -250.776739)
			(xy 156.767831 -250.782839) (xy 156.821788 -250.796945) (xy 156.873117 -250.818757) (xy 156.920723 -250.847811)
			(xy 156.963591 -250.883486) (xy 157.000808 -250.925023) (xy 157.031581 -250.971536) (xy 157.055253 -251.022033)
			(xy 157.071321 -251.07544) (xy 157.079441 -251.130616) (xy 157.07995 -251.158502) (xy 157.079441 -251.186388)
			(xy 157.071321 -251.241564) (xy 157.055253 -251.294971) (xy 157.031581 -251.345468) (xy 157.000808 -251.391981)
			(xy 156.963591 -251.433518) (xy 156.920723 -251.469193) (xy 156.873117 -251.498247) (xy 156.821788 -251.520059)
			(xy 156.767831 -251.534165) (xy 156.712394 -251.540265) (xy 156.65666 -251.538228) (xy 156.601817 -251.528098)
			(xy 156.549033 -251.510091) (xy 156.499433 -251.48459) (xy 156.454075 -251.452139) (xy 156.413926 -251.41343)
			(xy 156.37984 -251.369287) (xy 156.352544 -251.320652) (xy 156.332621 -251.268561) (xy 156.320495 -251.214124)
			(xy 156.316424 -251.158502) (xy 155.04795 -251.158502) (xy 155.047441 -251.186388) (xy 155.039321 -251.241564)
			(xy 155.023253 -251.294971) (xy 154.999581 -251.345468) (xy 154.968808 -251.391981) (xy 154.931591 -251.433518)
			(xy 154.888723 -251.469193) (xy 154.841117 -251.498247) (xy 154.789788 -251.520059) (xy 154.735831 -251.534165)
			(xy 154.680394 -251.540265) (xy 154.62466 -251.538228) (xy 154.569817 -251.528098) (xy 154.517033 -251.510091)
			(xy 154.467433 -251.48459) (xy 154.422075 -251.452139) (xy 154.381926 -251.41343) (xy 154.34784 -251.369287)
			(xy 154.320544 -251.320652) (xy 154.300621 -251.268561) (xy 154.288495 -251.214124) (xy 154.284424 -251.158502)
			(xy 154.03195 -251.158502) (xy 154.031441 -251.186388) (xy 154.023321 -251.241564) (xy 154.007253 -251.294971)
			(xy 153.983581 -251.345468) (xy 153.952808 -251.391981) (xy 153.915591 -251.433518) (xy 153.872723 -251.469193)
			(xy 153.825117 -251.498247) (xy 153.773788 -251.520059) (xy 153.719831 -251.534165) (xy 153.664394 -251.540265)
			(xy 153.60866 -251.538228) (xy 153.553817 -251.528098) (xy 153.501033 -251.510091) (xy 153.451433 -251.48459)
			(xy 153.406075 -251.452139) (xy 153.365926 -251.41343) (xy 153.33184 -251.369287) (xy 153.304544 -251.320652)
			(xy 153.284621 -251.268561) (xy 153.272495 -251.214124) (xy 153.268424 -251.158502) (xy 153.01595 -251.158502)
			(xy 153.015441 -251.186388) (xy 153.007321 -251.241564) (xy 152.991253 -251.294971) (xy 152.967581 -251.345468)
			(xy 152.936808 -251.391981) (xy 152.899591 -251.433518) (xy 152.856723 -251.469193) (xy 152.809117 -251.498247)
			(xy 152.757788 -251.520059) (xy 152.703831 -251.534165) (xy 152.648394 -251.540265) (xy 152.59266 -251.538228)
			(xy 152.537817 -251.528098) (xy 152.485033 -251.510091) (xy 152.435433 -251.48459) (xy 152.390075 -251.452139)
			(xy 152.349926 -251.41343) (xy 152.31584 -251.369287) (xy 152.288544 -251.320652) (xy 152.268621 -251.268561)
			(xy 152.256495 -251.214124) (xy 152.252424 -251.158502) (xy 151.99995 -251.158502) (xy 151.999441 -251.186388)
			(xy 151.991321 -251.241564) (xy 151.975253 -251.294971) (xy 151.951581 -251.345468) (xy 151.920808 -251.391981)
			(xy 151.883591 -251.433518) (xy 151.840723 -251.469193) (xy 151.793117 -251.498247) (xy 151.741788 -251.520059)
			(xy 151.687831 -251.534165) (xy 151.632394 -251.540265) (xy 151.57666 -251.538228) (xy 151.521817 -251.528098)
			(xy 151.469033 -251.510091) (xy 151.419433 -251.48459) (xy 151.374075 -251.452139) (xy 151.333926 -251.41343)
			(xy 151.29984 -251.369287) (xy 151.272544 -251.320652) (xy 151.252621 -251.268561) (xy 151.240495 -251.214124)
			(xy 151.236424 -251.158502) (xy 150.98395 -251.158502) (xy 150.983441 -251.186388) (xy 150.975321 -251.241564)
			(xy 150.959253 -251.294971) (xy 150.935581 -251.345468) (xy 150.904808 -251.391981) (xy 150.867591 -251.433518)
			(xy 150.824723 -251.469193) (xy 150.777117 -251.498247) (xy 150.725788 -251.520059) (xy 150.671831 -251.534165)
			(xy 150.616394 -251.540265) (xy 150.56066 -251.538228) (xy 150.505817 -251.528098) (xy 150.453033 -251.510091)
			(xy 150.403433 -251.48459) (xy 150.358075 -251.452139) (xy 150.317926 -251.41343) (xy 150.28384 -251.369287)
			(xy 150.256544 -251.320652) (xy 150.236621 -251.268561) (xy 150.224495 -251.214124) (xy 150.220424 -251.158502)
			(xy 149.96795 -251.158502) (xy 149.967441 -251.186388) (xy 149.959321 -251.241564) (xy 149.943253 -251.294971)
			(xy 149.919581 -251.345468) (xy 149.888808 -251.391981) (xy 149.851591 -251.433518) (xy 149.808723 -251.469193)
			(xy 149.761117 -251.498247) (xy 149.709788 -251.520059) (xy 149.655831 -251.534165) (xy 149.600394 -251.540265)
			(xy 149.54466 -251.538228) (xy 149.489817 -251.528098) (xy 149.437033 -251.510091) (xy 149.387433 -251.48459)
			(xy 149.342075 -251.452139) (xy 149.301926 -251.41343) (xy 149.26784 -251.369287) (xy 149.240544 -251.320652)
			(xy 149.220621 -251.268561) (xy 149.208495 -251.214124) (xy 149.204424 -251.158502) (xy 148.95195 -251.158502)
			(xy 148.951441 -251.186388) (xy 148.943321 -251.241564) (xy 148.927253 -251.294971) (xy 148.903581 -251.345468)
			(xy 148.872808 -251.391981) (xy 148.835591 -251.433518) (xy 148.792723 -251.469193) (xy 148.745117 -251.498247)
			(xy 148.693788 -251.520059) (xy 148.639831 -251.534165) (xy 148.584394 -251.540265) (xy 148.52866 -251.538228)
			(xy 148.473817 -251.528098) (xy 148.421033 -251.510091) (xy 148.371433 -251.48459) (xy 148.326075 -251.452139)
			(xy 148.285926 -251.41343) (xy 148.25184 -251.369287) (xy 148.224544 -251.320652) (xy 148.204621 -251.268561)
			(xy 148.192495 -251.214124) (xy 148.188424 -251.158502) (xy 147.93595 -251.158502) (xy 147.935441 -251.186388)
			(xy 147.927321 -251.241564) (xy 147.911253 -251.294971) (xy 147.887581 -251.345468) (xy 147.856808 -251.391981)
			(xy 147.819591 -251.433518) (xy 147.776723 -251.469193) (xy 147.729117 -251.498247) (xy 147.677788 -251.520059)
			(xy 147.623831 -251.534165) (xy 147.568394 -251.540265) (xy 147.51266 -251.538228) (xy 147.457817 -251.528098)
			(xy 147.405033 -251.510091) (xy 147.355433 -251.48459) (xy 147.310075 -251.452139) (xy 147.269926 -251.41343)
			(xy 147.23584 -251.369287) (xy 147.208544 -251.320652) (xy 147.188621 -251.268561) (xy 147.176495 -251.214124)
			(xy 147.172424 -251.158502) (xy 146.91995 -251.158502) (xy 146.919441 -251.186388) (xy 146.911321 -251.241564)
			(xy 146.895253 -251.294971) (xy 146.871581 -251.345468) (xy 146.840808 -251.391981) (xy 146.803591 -251.433518)
			(xy 146.760723 -251.469193) (xy 146.713117 -251.498247) (xy 146.661788 -251.520059) (xy 146.607831 -251.534165)
			(xy 146.552394 -251.540265) (xy 146.49666 -251.538228) (xy 146.441817 -251.528098) (xy 146.389033 -251.510091)
			(xy 146.339433 -251.48459) (xy 146.294075 -251.452139) (xy 146.253926 -251.41343) (xy 146.21984 -251.369287)
			(xy 146.192544 -251.320652) (xy 146.172621 -251.268561) (xy 146.160495 -251.214124) (xy 146.156424 -251.158502)
			(xy 145.90395 -251.158502) (xy 145.903441 -251.186388) (xy 145.895321 -251.241564) (xy 145.879253 -251.294971)
			(xy 145.855581 -251.345468) (xy 145.824808 -251.391981) (xy 145.787591 -251.433518) (xy 145.744723 -251.469193)
			(xy 145.697117 -251.498247) (xy 145.645788 -251.520059) (xy 145.591831 -251.534165) (xy 145.536394 -251.540265)
			(xy 145.48066 -251.538228) (xy 145.425817 -251.528098) (xy 145.373033 -251.510091) (xy 145.323433 -251.48459)
			(xy 145.278075 -251.452139) (xy 145.237926 -251.41343) (xy 145.20384 -251.369287) (xy 145.176544 -251.320652)
			(xy 145.156621 -251.268561) (xy 145.144495 -251.214124) (xy 145.140424 -251.158502) (xy 144.88795 -251.158502)
			(xy 144.887441 -251.186388) (xy 144.879321 -251.241564) (xy 144.863253 -251.294971) (xy 144.839581 -251.345468)
			(xy 144.808808 -251.391981) (xy 144.771591 -251.433518) (xy 144.728723 -251.469193) (xy 144.681117 -251.498247)
			(xy 144.629788 -251.520059) (xy 144.575831 -251.534165) (xy 144.520394 -251.540265) (xy 144.46466 -251.538228)
			(xy 144.409817 -251.528098) (xy 144.357033 -251.510091) (xy 144.307433 -251.48459) (xy 144.262075 -251.452139)
			(xy 144.221926 -251.41343) (xy 144.18784 -251.369287) (xy 144.160544 -251.320652) (xy 144.140621 -251.268561)
			(xy 144.128495 -251.214124) (xy 144.124424 -251.158502) (xy 143.87195 -251.158502) (xy 143.871441 -251.186388)
			(xy 143.863321 -251.241564) (xy 143.847253 -251.294971) (xy 143.823581 -251.345468) (xy 143.792808 -251.391981)
			(xy 143.755591 -251.433518) (xy 143.712723 -251.469193) (xy 143.665117 -251.498247) (xy 143.613788 -251.520059)
			(xy 143.559831 -251.534165) (xy 143.504394 -251.540265) (xy 143.44866 -251.538228) (xy 143.393817 -251.528098)
			(xy 143.341033 -251.510091) (xy 143.291433 -251.48459) (xy 143.246075 -251.452139) (xy 143.205926 -251.41343)
			(xy 143.17184 -251.369287) (xy 143.144544 -251.320652) (xy 143.124621 -251.268561) (xy 143.112495 -251.214124)
			(xy 143.108424 -251.158502) (xy 142.85595 -251.158502) (xy 142.855441 -251.186388) (xy 142.847321 -251.241564)
			(xy 142.831253 -251.294971) (xy 142.807581 -251.345468) (xy 142.776808 -251.391981) (xy 142.739591 -251.433518)
			(xy 142.696723 -251.469193) (xy 142.649117 -251.498247) (xy 142.597788 -251.520059) (xy 142.543831 -251.534165)
			(xy 142.488394 -251.540265) (xy 142.43266 -251.538228) (xy 142.377817 -251.528098) (xy 142.325033 -251.510091)
			(xy 142.275433 -251.48459) (xy 142.230075 -251.452139) (xy 142.189926 -251.41343) (xy 142.15584 -251.369287)
			(xy 142.128544 -251.320652) (xy 142.108621 -251.268561) (xy 142.096495 -251.214124) (xy 142.092424 -251.158502)
			(xy 141.83995 -251.158502) (xy 141.839441 -251.186388) (xy 141.831321 -251.241564) (xy 141.815253 -251.294971)
			(xy 141.791581 -251.345468) (xy 141.760808 -251.391981) (xy 141.723591 -251.433518) (xy 141.680723 -251.469193)
			(xy 141.633117 -251.498247) (xy 141.581788 -251.520059) (xy 141.527831 -251.534165) (xy 141.472394 -251.540265)
			(xy 141.41666 -251.538228) (xy 141.361817 -251.528098) (xy 141.309033 -251.510091) (xy 141.259433 -251.48459)
			(xy 141.214075 -251.452139) (xy 141.173926 -251.41343) (xy 141.13984 -251.369287) (xy 141.112544 -251.320652)
			(xy 141.092621 -251.268561) (xy 141.080495 -251.214124) (xy 141.076424 -251.158502) (xy 140.82395 -251.158502)
			(xy 140.823441 -251.186388) (xy 140.815321 -251.241564) (xy 140.799253 -251.294971) (xy 140.775581 -251.345468)
			(xy 140.744808 -251.391981) (xy 140.707591 -251.433518) (xy 140.664723 -251.469193) (xy 140.617117 -251.498247)
			(xy 140.565788 -251.520059) (xy 140.511831 -251.534165) (xy 140.456394 -251.540265) (xy 140.40066 -251.538228)
			(xy 140.345817 -251.528098) (xy 140.293033 -251.510091) (xy 140.243433 -251.48459) (xy 140.198075 -251.452139)
			(xy 140.157926 -251.41343) (xy 140.12384 -251.369287) (xy 140.096544 -251.320652) (xy 140.076621 -251.268561)
			(xy 140.064495 -251.214124) (xy 140.060424 -251.158502) (xy 125.577717 -251.158502) (xy 125.580372 -251.162633)
			(xy 125.603012 -251.212209) (xy 125.618366 -251.264503) (xy 125.626122 -251.318449) (xy 125.626122 -251.372951)
			(xy 125.618366 -251.426897) (xy 125.603012 -251.479191) (xy 125.580372 -251.528767) (xy 125.550907 -251.574617)
			(xy 125.515217 -251.615807) (xy 125.474028 -251.651498) (xy 125.428179 -251.680965) (xy 125.378604 -251.703607)
			(xy 125.326311 -251.718963) (xy 125.272365 -251.726721) (xy 125.245114 -251.727208) (xy 125.216607 -251.726682)
			(xy 125.16023 -251.718187) (xy 125.105744 -251.701399) (xy 125.054362 -251.676692) (xy 125.007228 -251.644616)
			(xy 124.965391 -251.605884) (xy 124.947172 -251.583952) (xy 124.939806 -251.574808) (xy 124.919486 -251.564902)
			(xy 124.817378 -251.563886) (xy 124.797058 -251.573284) (xy 124.789692 -251.582428) (xy 124.771498 -251.603583)
			(xy 124.729942 -251.640818) (xy 124.683402 -251.671596) (xy 124.632871 -251.695259) (xy 124.57943 -251.711303)
			(xy 124.524221 -251.719383) (xy 124.496322 -251.719842) (xy 124.466995 -251.719304) (xy 124.409031 -251.710336)
			(xy 124.353121 -251.692607) (xy 124.300581 -251.666535) (xy 124.252647 -251.632733) (xy 124.210447 -251.591997)
			(xy 124.192284 -251.568966) (xy 124.185172 -251.559314) (xy 124.163582 -251.548646) (xy 124.057918 -251.549662)
			(xy 124.036582 -251.560838) (xy 124.02947 -251.57049) (xy 124.011346 -251.594316) (xy 123.968948 -251.636572)
			(xy 123.920474 -251.671693) (xy 123.867112 -251.698816) (xy 123.81017 -251.717277) (xy 123.751044 -251.726624)
			(xy 123.721114 -251.727208) (xy 123.69386 -251.726746) (xy 123.639908 -251.71899) (xy 123.587609 -251.703635)
			(xy 123.538027 -251.680994) (xy 123.492172 -251.651526) (xy 123.450977 -251.615832) (xy 123.415282 -251.574639)
			(xy 123.385813 -251.528786) (xy 123.363169 -251.479205) (xy 123.347813 -251.426906) (xy 123.340055 -251.372953)
			(xy 40.913761 -251.372953) (xy 40.908732 -251.380244) (xy 40.90441 -251.386831) (xy 40.899636 -251.401835)
			(xy 40.899334 -251.409708) (xy 40.899334 -252.112272) (xy 120.272554 -252.112272) (xy 120.276625 -252.05665)
			(xy 120.288751 -252.002213) (xy 120.308674 -251.950122) (xy 120.33597 -251.901487) (xy 120.370056 -251.857344)
			(xy 120.410205 -251.818635) (xy 120.455563 -251.786184) (xy 120.505163 -251.760683) (xy 120.557947 -251.742676)
			(xy 120.61279 -251.732546) (xy 120.668524 -251.730509) (xy 120.723961 -251.736609) (xy 120.777918 -251.750715)
			(xy 120.829247 -251.772527) (xy 120.876853 -251.801581) (xy 120.919721 -251.837256) (xy 120.956938 -251.878793)
			(xy 120.987711 -251.925306) (xy 121.011383 -251.975803) (xy 121.027451 -252.02921) (xy 121.035571 -252.084386)
			(xy 121.03608 -252.112272) (xy 121.035571 -252.140158) (xy 121.028984 -252.184916) (xy 132.344158 -252.184916)
			(xy 132.348229 -252.129294) (xy 132.360355 -252.074857) (xy 132.380278 -252.022766) (xy 132.407574 -251.974131)
			(xy 132.44166 -251.929988) (xy 132.481809 -251.891279) (xy 132.527167 -251.858828) (xy 132.576767 -251.833327)
			(xy 132.629551 -251.81532) (xy 132.684394 -251.80519) (xy 132.740128 -251.803153) (xy 132.795565 -251.809253)
			(xy 132.849522 -251.823359) (xy 132.900851 -251.845171) (xy 132.948457 -251.874225) (xy 132.991325 -251.9099)
			(xy 133.028542 -251.951437) (xy 133.059315 -251.99795) (xy 133.082987 -252.048447) (xy 133.099055 -252.101854)
			(xy 133.107175 -252.15703) (xy 133.107684 -252.184916) (xy 133.107175 -252.212802) (xy 133.099055 -252.267978)
			(xy 133.082987 -252.321385) (xy 133.059315 -252.371882) (xy 133.028542 -252.418395) (xy 132.991325 -252.459932)
			(xy 132.948457 -252.495607) (xy 132.900851 -252.524661) (xy 132.849522 -252.546473) (xy 132.795565 -252.560579)
			(xy 132.740128 -252.566679) (xy 132.684394 -252.564642) (xy 132.629551 -252.554512) (xy 132.576767 -252.536505)
			(xy 132.527167 -252.511004) (xy 132.481809 -252.478553) (xy 132.44166 -252.439844) (xy 132.407574 -252.395701)
			(xy 132.380278 -252.347066) (xy 132.360355 -252.294975) (xy 132.348229 -252.240538) (xy 132.344158 -252.184916)
			(xy 121.028984 -252.184916) (xy 121.027451 -252.195334) (xy 121.011383 -252.248741) (xy 120.987711 -252.299238)
			(xy 120.956938 -252.345751) (xy 120.919721 -252.387288) (xy 120.876853 -252.422963) (xy 120.829247 -252.452017)
			(xy 120.777918 -252.473829) (xy 120.723961 -252.487935) (xy 120.668524 -252.494035) (xy 120.61279 -252.491998)
			(xy 120.557947 -252.481868) (xy 120.505163 -252.463861) (xy 120.455563 -252.43836) (xy 120.410205 -252.405909)
			(xy 120.370056 -252.3672) (xy 120.33597 -252.323057) (xy 120.308674 -252.274422) (xy 120.288751 -252.222331)
			(xy 120.276625 -252.167894) (xy 120.272554 -252.112272) (xy 40.899334 -252.112272) (xy 40.899334 -252.598682)
			(xy 113.663728 -252.598682) (xy 113.667799 -252.54306) (xy 113.679925 -252.488623) (xy 113.699848 -252.436532)
			(xy 113.727144 -252.387897) (xy 113.76123 -252.343754) (xy 113.801379 -252.305045) (xy 113.846737 -252.272594)
			(xy 113.896337 -252.247093) (xy 113.949121 -252.229086) (xy 114.003964 -252.218956) (xy 114.059698 -252.216919)
			(xy 114.115135 -252.223019) (xy 114.169092 -252.237125) (xy 114.220421 -252.258937) (xy 114.268027 -252.287991)
			(xy 114.310895 -252.323666) (xy 114.348112 -252.365203) (xy 114.378885 -252.411716) (xy 114.402557 -252.462213)
			(xy 114.418625 -252.51562) (xy 114.426745 -252.570796) (xy 114.427254 -252.598682) (xy 114.426745 -252.626568)
			(xy 114.418625 -252.681744) (xy 114.402557 -252.735151) (xy 114.378885 -252.785648) (xy 114.348112 -252.832161)
			(xy 114.310895 -252.873698) (xy 114.268027 -252.909373) (xy 114.220421 -252.938427) (xy 114.169092 -252.960239)
			(xy 114.115135 -252.974345) (xy 114.059698 -252.980445) (xy 114.003964 -252.978408) (xy 113.949121 -252.968278)
			(xy 113.896337 -252.950271) (xy 113.846737 -252.92477) (xy 113.801379 -252.892319) (xy 113.76123 -252.85361)
			(xy 113.727144 -252.809467) (xy 113.699848 -252.760832) (xy 113.679925 -252.708741) (xy 113.667799 -252.654304)
			(xy 113.663728 -252.598682) (xy 40.899334 -252.598682) (xy 40.899334 -253.10592) (xy 118.323612 -253.10592)
			(xy 118.327683 -253.050298) (xy 118.339809 -252.995861) (xy 118.359732 -252.94377) (xy 118.387028 -252.895135)
			(xy 118.421114 -252.850992) (xy 118.461263 -252.812283) (xy 118.506621 -252.779832) (xy 118.556221 -252.754331)
			(xy 118.609005 -252.736324) (xy 118.663848 -252.726194) (xy 118.719582 -252.724157) (xy 118.775019 -252.730257)
			(xy 118.828976 -252.744363) (xy 118.880305 -252.766175) (xy 118.927911 -252.795229) (xy 118.970779 -252.830904)
			(xy 119.007996 -252.872441) (xy 119.038769 -252.918954) (xy 119.062441 -252.969451) (xy 119.078509 -253.022858)
			(xy 119.086629 -253.078034) (xy 119.087138 -253.10592) (xy 119.086629 -253.133806) (xy 119.078509 -253.188982)
			(xy 119.062441 -253.242389) (xy 119.038769 -253.292886) (xy 119.007996 -253.339399) (xy 118.970779 -253.380936)
			(xy 118.962459 -253.38786) (xy 126.243078 -253.38786) (xy 126.247149 -253.332238) (xy 126.259275 -253.277801)
			(xy 126.279198 -253.22571) (xy 126.306494 -253.177075) (xy 126.34058 -253.132932) (xy 126.380729 -253.094223)
			(xy 126.426087 -253.061772) (xy 126.475687 -253.036271) (xy 126.528471 -253.018264) (xy 126.583314 -253.008134)
			(xy 126.639048 -253.006097) (xy 126.694485 -253.012197) (xy 126.748442 -253.026303) (xy 126.799771 -253.048115)
			(xy 126.847377 -253.077169) (xy 126.890245 -253.112844) (xy 126.927462 -253.154381) (xy 126.943461 -253.178564)
			(xy 128.285746 -253.178564) (xy 128.289817 -253.122942) (xy 128.301943 -253.068505) (xy 128.321866 -253.016414)
			(xy 128.349162 -252.967779) (xy 128.383248 -252.923636) (xy 128.423397 -252.884927) (xy 128.468755 -252.852476)
			(xy 128.518355 -252.826975) (xy 128.571139 -252.808968) (xy 128.625982 -252.798838) (xy 128.681716 -252.796801)
			(xy 128.737153 -252.802901) (xy 128.79111 -252.817007) (xy 128.842439 -252.838819) (xy 128.890045 -252.867873)
			(xy 128.932913 -252.903548) (xy 128.97013 -252.945085) (xy 129.000903 -252.991598) (xy 129.024575 -253.042095)
			(xy 129.040643 -253.095502) (xy 129.048763 -253.150678) (xy 129.049272 -253.178564) (xy 130.349242 -253.178564)
			(xy 130.353313 -253.122942) (xy 130.365439 -253.068505) (xy 130.385362 -253.016414) (xy 130.412658 -252.967779)
			(xy 130.446744 -252.923636) (xy 130.486893 -252.884927) (xy 130.532251 -252.852476) (xy 130.581851 -252.826975)
			(xy 130.634635 -252.808968) (xy 130.689478 -252.798838) (xy 130.745212 -252.796801) (xy 130.800649 -252.802901)
			(xy 130.854606 -252.817007) (xy 130.905935 -252.838819) (xy 130.953541 -252.867873) (xy 130.996409 -252.903548)
			(xy 131.033626 -252.945085) (xy 131.064399 -252.991598) (xy 131.088071 -253.042095) (xy 131.104139 -253.095502)
			(xy 131.112259 -253.150678) (xy 131.112768 -253.178564) (xy 131.112259 -253.20645) (xy 131.104139 -253.261626)
			(xy 131.088071 -253.315033) (xy 131.064399 -253.36553) (xy 131.033626 -253.412043) (xy 130.996409 -253.45358)
			(xy 130.992972 -253.45644) (xy 140.060424 -253.45644) (xy 140.064495 -253.400818) (xy 140.076621 -253.346381)
			(xy 140.096544 -253.29429) (xy 140.12384 -253.245655) (xy 140.157926 -253.201512) (xy 140.198075 -253.162803)
			(xy 140.243433 -253.130352) (xy 140.293033 -253.104851) (xy 140.345817 -253.086844) (xy 140.40066 -253.076714)
			(xy 140.456394 -253.074677) (xy 140.511831 -253.080777) (xy 140.565788 -253.094883) (xy 140.617117 -253.116695)
			(xy 140.664723 -253.145749) (xy 140.707591 -253.181424) (xy 140.744808 -253.222961) (xy 140.775581 -253.269474)
			(xy 140.799253 -253.319971) (xy 140.815321 -253.373378) (xy 140.823441 -253.428554) (xy 140.82395 -253.45644)
			(xy 141.076424 -253.45644) (xy 141.080495 -253.400818) (xy 141.092621 -253.346381) (xy 141.112544 -253.29429)
			(xy 141.13984 -253.245655) (xy 141.173926 -253.201512) (xy 141.214075 -253.162803) (xy 141.259433 -253.130352)
			(xy 141.309033 -253.104851) (xy 141.361817 -253.086844) (xy 141.41666 -253.076714) (xy 141.472394 -253.074677)
			(xy 141.527831 -253.080777) (xy 141.581788 -253.094883) (xy 141.633117 -253.116695) (xy 141.680723 -253.145749)
			(xy 141.723591 -253.181424) (xy 141.760808 -253.222961) (xy 141.791581 -253.269474) (xy 141.815253 -253.319971)
			(xy 141.831321 -253.373378) (xy 141.839441 -253.428554) (xy 141.83995 -253.45644) (xy 142.092424 -253.45644)
			(xy 142.096495 -253.400818) (xy 142.108621 -253.346381) (xy 142.128544 -253.29429) (xy 142.15584 -253.245655)
			(xy 142.189926 -253.201512) (xy 142.230075 -253.162803) (xy 142.275433 -253.130352) (xy 142.325033 -253.104851)
			(xy 142.377817 -253.086844) (xy 142.43266 -253.076714) (xy 142.488394 -253.074677) (xy 142.543831 -253.080777)
			(xy 142.597788 -253.094883) (xy 142.649117 -253.116695) (xy 142.696723 -253.145749) (xy 142.739591 -253.181424)
			(xy 142.776808 -253.222961) (xy 142.807581 -253.269474) (xy 142.831253 -253.319971) (xy 142.847321 -253.373378)
			(xy 142.855441 -253.428554) (xy 142.85595 -253.45644) (xy 143.108424 -253.45644) (xy 143.112495 -253.400818)
			(xy 143.124621 -253.346381) (xy 143.144544 -253.29429) (xy 143.17184 -253.245655) (xy 143.205926 -253.201512)
			(xy 143.246075 -253.162803) (xy 143.291433 -253.130352) (xy 143.341033 -253.104851) (xy 143.393817 -253.086844)
			(xy 143.44866 -253.076714) (xy 143.504394 -253.074677) (xy 143.559831 -253.080777) (xy 143.613788 -253.094883)
			(xy 143.665117 -253.116695) (xy 143.712723 -253.145749) (xy 143.755591 -253.181424) (xy 143.792808 -253.222961)
			(xy 143.823581 -253.269474) (xy 143.847253 -253.319971) (xy 143.863321 -253.373378) (xy 143.871441 -253.428554)
			(xy 143.87195 -253.45644) (xy 144.124424 -253.45644) (xy 144.128495 -253.400818) (xy 144.140621 -253.346381)
			(xy 144.160544 -253.29429) (xy 144.18784 -253.245655) (xy 144.221926 -253.201512) (xy 144.262075 -253.162803)
			(xy 144.307433 -253.130352) (xy 144.357033 -253.104851) (xy 144.409817 -253.086844) (xy 144.46466 -253.076714)
			(xy 144.520394 -253.074677) (xy 144.575831 -253.080777) (xy 144.629788 -253.094883) (xy 144.681117 -253.116695)
			(xy 144.728723 -253.145749) (xy 144.771591 -253.181424) (xy 144.808808 -253.222961) (xy 144.839581 -253.269474)
			(xy 144.863253 -253.319971) (xy 144.879321 -253.373378) (xy 144.887441 -253.428554) (xy 144.88795 -253.45644)
			(xy 145.140424 -253.45644) (xy 145.144495 -253.400818) (xy 145.156621 -253.346381) (xy 145.176544 -253.29429)
			(xy 145.20384 -253.245655) (xy 145.237926 -253.201512) (xy 145.278075 -253.162803) (xy 145.323433 -253.130352)
			(xy 145.373033 -253.104851) (xy 145.425817 -253.086844) (xy 145.48066 -253.076714) (xy 145.536394 -253.074677)
			(xy 145.591831 -253.080777) (xy 145.645788 -253.094883) (xy 145.697117 -253.116695) (xy 145.744723 -253.145749)
			(xy 145.787591 -253.181424) (xy 145.824808 -253.222961) (xy 145.855581 -253.269474) (xy 145.879253 -253.319971)
			(xy 145.895321 -253.373378) (xy 145.903441 -253.428554) (xy 145.90395 -253.45644) (xy 146.156424 -253.45644)
			(xy 146.160495 -253.400818) (xy 146.172621 -253.346381) (xy 146.192544 -253.29429) (xy 146.21984 -253.245655)
			(xy 146.253926 -253.201512) (xy 146.294075 -253.162803) (xy 146.339433 -253.130352) (xy 146.389033 -253.104851)
			(xy 146.441817 -253.086844) (xy 146.49666 -253.076714) (xy 146.552394 -253.074677) (xy 146.607831 -253.080777)
			(xy 146.661788 -253.094883) (xy 146.713117 -253.116695) (xy 146.760723 -253.145749) (xy 146.803591 -253.181424)
			(xy 146.840808 -253.222961) (xy 146.871581 -253.269474) (xy 146.895253 -253.319971) (xy 146.911321 -253.373378)
			(xy 146.919441 -253.428554) (xy 146.91995 -253.45644) (xy 147.172424 -253.45644) (xy 147.176495 -253.400818)
			(xy 147.188621 -253.346381) (xy 147.208544 -253.29429) (xy 147.23584 -253.245655) (xy 147.269926 -253.201512)
			(xy 147.310075 -253.162803) (xy 147.355433 -253.130352) (xy 147.405033 -253.104851) (xy 147.457817 -253.086844)
			(xy 147.51266 -253.076714) (xy 147.568394 -253.074677) (xy 147.623831 -253.080777) (xy 147.677788 -253.094883)
			(xy 147.729117 -253.116695) (xy 147.776723 -253.145749) (xy 147.819591 -253.181424) (xy 147.856808 -253.222961)
			(xy 147.887581 -253.269474) (xy 147.911253 -253.319971) (xy 147.927321 -253.373378) (xy 147.935441 -253.428554)
			(xy 147.93595 -253.45644) (xy 148.188424 -253.45644) (xy 148.192495 -253.400818) (xy 148.204621 -253.346381)
			(xy 148.224544 -253.29429) (xy 148.25184 -253.245655) (xy 148.285926 -253.201512) (xy 148.326075 -253.162803)
			(xy 148.371433 -253.130352) (xy 148.421033 -253.104851) (xy 148.473817 -253.086844) (xy 148.52866 -253.076714)
			(xy 148.584394 -253.074677) (xy 148.639831 -253.080777) (xy 148.693788 -253.094883) (xy 148.745117 -253.116695)
			(xy 148.792723 -253.145749) (xy 148.835591 -253.181424) (xy 148.872808 -253.222961) (xy 148.903581 -253.269474)
			(xy 148.927253 -253.319971) (xy 148.943321 -253.373378) (xy 148.951441 -253.428554) (xy 148.95195 -253.45644)
			(xy 149.204424 -253.45644) (xy 149.208495 -253.400818) (xy 149.220621 -253.346381) (xy 149.240544 -253.29429)
			(xy 149.26784 -253.245655) (xy 149.301926 -253.201512) (xy 149.342075 -253.162803) (xy 149.387433 -253.130352)
			(xy 149.437033 -253.104851) (xy 149.489817 -253.086844) (xy 149.54466 -253.076714) (xy 149.600394 -253.074677)
			(xy 149.655831 -253.080777) (xy 149.709788 -253.094883) (xy 149.761117 -253.116695) (xy 149.808723 -253.145749)
			(xy 149.851591 -253.181424) (xy 149.888808 -253.222961) (xy 149.919581 -253.269474) (xy 149.943253 -253.319971)
			(xy 149.959321 -253.373378) (xy 149.967441 -253.428554) (xy 149.96795 -253.45644) (xy 150.220424 -253.45644)
			(xy 150.224495 -253.400818) (xy 150.236621 -253.346381) (xy 150.256544 -253.29429) (xy 150.28384 -253.245655)
			(xy 150.317926 -253.201512) (xy 150.358075 -253.162803) (xy 150.403433 -253.130352) (xy 150.453033 -253.104851)
			(xy 150.505817 -253.086844) (xy 150.56066 -253.076714) (xy 150.616394 -253.074677) (xy 150.671831 -253.080777)
			(xy 150.725788 -253.094883) (xy 150.777117 -253.116695) (xy 150.824723 -253.145749) (xy 150.867591 -253.181424)
			(xy 150.904808 -253.222961) (xy 150.935581 -253.269474) (xy 150.959253 -253.319971) (xy 150.975321 -253.373378)
			(xy 150.983441 -253.428554) (xy 150.98395 -253.45644) (xy 151.236424 -253.45644) (xy 151.240495 -253.400818)
			(xy 151.252621 -253.346381) (xy 151.272544 -253.29429) (xy 151.29984 -253.245655) (xy 151.333926 -253.201512)
			(xy 151.374075 -253.162803) (xy 151.419433 -253.130352) (xy 151.469033 -253.104851) (xy 151.521817 -253.086844)
			(xy 151.57666 -253.076714) (xy 151.632394 -253.074677) (xy 151.687831 -253.080777) (xy 151.741788 -253.094883)
			(xy 151.793117 -253.116695) (xy 151.840723 -253.145749) (xy 151.883591 -253.181424) (xy 151.920808 -253.222961)
			(xy 151.951581 -253.269474) (xy 151.975253 -253.319971) (xy 151.991321 -253.373378) (xy 151.999441 -253.428554)
			(xy 151.99995 -253.45644) (xy 152.252424 -253.45644) (xy 152.256495 -253.400818) (xy 152.268621 -253.346381)
			(xy 152.288544 -253.29429) (xy 152.31584 -253.245655) (xy 152.349926 -253.201512) (xy 152.390075 -253.162803)
			(xy 152.435433 -253.130352) (xy 152.485033 -253.104851) (xy 152.537817 -253.086844) (xy 152.59266 -253.076714)
			(xy 152.648394 -253.074677) (xy 152.703831 -253.080777) (xy 152.757788 -253.094883) (xy 152.809117 -253.116695)
			(xy 152.856723 -253.145749) (xy 152.899591 -253.181424) (xy 152.936808 -253.222961) (xy 152.967581 -253.269474)
			(xy 152.991253 -253.319971) (xy 153.007321 -253.373378) (xy 153.015441 -253.428554) (xy 153.01595 -253.45644)
			(xy 153.268424 -253.45644) (xy 153.272495 -253.400818) (xy 153.284621 -253.346381) (xy 153.304544 -253.29429)
			(xy 153.33184 -253.245655) (xy 153.365926 -253.201512) (xy 153.406075 -253.162803) (xy 153.451433 -253.130352)
			(xy 153.501033 -253.104851) (xy 153.553817 -253.086844) (xy 153.60866 -253.076714) (xy 153.664394 -253.074677)
			(xy 153.719831 -253.080777) (xy 153.773788 -253.094883) (xy 153.825117 -253.116695) (xy 153.872723 -253.145749)
			(xy 153.915591 -253.181424) (xy 153.952808 -253.222961) (xy 153.983581 -253.269474) (xy 154.007253 -253.319971)
			(xy 154.023321 -253.373378) (xy 154.031441 -253.428554) (xy 154.03195 -253.45644) (xy 154.284424 -253.45644)
			(xy 154.288495 -253.400818) (xy 154.300621 -253.346381) (xy 154.320544 -253.29429) (xy 154.34784 -253.245655)
			(xy 154.381926 -253.201512) (xy 154.422075 -253.162803) (xy 154.467433 -253.130352) (xy 154.517033 -253.104851)
			(xy 154.569817 -253.086844) (xy 154.62466 -253.076714) (xy 154.680394 -253.074677) (xy 154.735831 -253.080777)
			(xy 154.789788 -253.094883) (xy 154.841117 -253.116695) (xy 154.888723 -253.145749) (xy 154.931591 -253.181424)
			(xy 154.968808 -253.222961) (xy 154.999581 -253.269474) (xy 155.023253 -253.319971) (xy 155.039321 -253.373378)
			(xy 155.047441 -253.428554) (xy 155.04795 -253.45644) (xy 155.300424 -253.45644) (xy 155.304495 -253.400818)
			(xy 155.316621 -253.346381) (xy 155.336544 -253.29429) (xy 155.36384 -253.245655) (xy 155.397926 -253.201512)
			(xy 155.438075 -253.162803) (xy 155.483433 -253.130352) (xy 155.533033 -253.104851) (xy 155.585817 -253.086844)
			(xy 155.64066 -253.076714) (xy 155.696394 -253.074677) (xy 155.751831 -253.080777) (xy 155.805788 -253.094883)
			(xy 155.857117 -253.116695) (xy 155.904723 -253.145749) (xy 155.947591 -253.181424) (xy 155.984808 -253.222961)
			(xy 156.015581 -253.269474) (xy 156.039253 -253.319971) (xy 156.055321 -253.373378) (xy 156.063441 -253.428554)
			(xy 156.06395 -253.45644) (xy 156.316424 -253.45644) (xy 156.320495 -253.400818) (xy 156.332621 -253.346381)
			(xy 156.352544 -253.29429) (xy 156.37984 -253.245655) (xy 156.413926 -253.201512) (xy 156.454075 -253.162803)
			(xy 156.499433 -253.130352) (xy 156.549033 -253.104851) (xy 156.601817 -253.086844) (xy 156.65666 -253.076714)
			(xy 156.712394 -253.074677) (xy 156.767831 -253.080777) (xy 156.821788 -253.094883) (xy 156.873117 -253.116695)
			(xy 156.920723 -253.145749) (xy 156.963591 -253.181424) (xy 157.000808 -253.222961) (xy 157.031581 -253.269474)
			(xy 157.055253 -253.319971) (xy 157.071321 -253.373378) (xy 157.079441 -253.428554) (xy 157.07995 -253.45644)
			(xy 157.079441 -253.484326) (xy 157.071321 -253.539502) (xy 157.055253 -253.592909) (xy 157.031581 -253.643406)
			(xy 157.000808 -253.689919) (xy 156.963591 -253.731456) (xy 156.920723 -253.767131) (xy 156.873117 -253.796185)
			(xy 156.821788 -253.817997) (xy 156.767831 -253.832103) (xy 156.712394 -253.838203) (xy 156.65666 -253.836166)
			(xy 156.601817 -253.826036) (xy 156.549033 -253.808029) (xy 156.499433 -253.782528) (xy 156.454075 -253.750077)
			(xy 156.413926 -253.711368) (xy 156.37984 -253.667225) (xy 156.352544 -253.61859) (xy 156.332621 -253.566499)
			(xy 156.320495 -253.512062) (xy 156.316424 -253.45644) (xy 156.06395 -253.45644) (xy 156.063441 -253.484326)
			(xy 156.055321 -253.539502) (xy 156.039253 -253.592909) (xy 156.015581 -253.643406) (xy 155.984808 -253.689919)
			(xy 155.947591 -253.731456) (xy 155.904723 -253.767131) (xy 155.857117 -253.796185) (xy 155.805788 -253.817997)
			(xy 155.751831 -253.832103) (xy 155.696394 -253.838203) (xy 155.64066 -253.836166) (xy 155.585817 -253.826036)
			(xy 155.533033 -253.808029) (xy 155.483433 -253.782528) (xy 155.438075 -253.750077) (xy 155.397926 -253.711368)
			(xy 155.36384 -253.667225) (xy 155.336544 -253.61859) (xy 155.316621 -253.566499) (xy 155.304495 -253.512062)
			(xy 155.300424 -253.45644) (xy 155.04795 -253.45644) (xy 155.047441 -253.484326) (xy 155.039321 -253.539502)
			(xy 155.023253 -253.592909) (xy 154.999581 -253.643406) (xy 154.968808 -253.689919) (xy 154.931591 -253.731456)
			(xy 154.888723 -253.767131) (xy 154.841117 -253.796185) (xy 154.789788 -253.817997) (xy 154.735831 -253.832103)
			(xy 154.680394 -253.838203) (xy 154.62466 -253.836166) (xy 154.569817 -253.826036) (xy 154.517033 -253.808029)
			(xy 154.467433 -253.782528) (xy 154.422075 -253.750077) (xy 154.381926 -253.711368) (xy 154.34784 -253.667225)
			(xy 154.320544 -253.61859) (xy 154.300621 -253.566499) (xy 154.288495 -253.512062) (xy 154.284424 -253.45644)
			(xy 154.03195 -253.45644) (xy 154.031441 -253.484326) (xy 154.023321 -253.539502) (xy 154.007253 -253.592909)
			(xy 153.983581 -253.643406) (xy 153.952808 -253.689919) (xy 153.915591 -253.731456) (xy 153.872723 -253.767131)
			(xy 153.825117 -253.796185) (xy 153.773788 -253.817997) (xy 153.719831 -253.832103) (xy 153.664394 -253.838203)
			(xy 153.60866 -253.836166) (xy 153.553817 -253.826036) (xy 153.501033 -253.808029) (xy 153.451433 -253.782528)
			(xy 153.406075 -253.750077) (xy 153.365926 -253.711368) (xy 153.33184 -253.667225) (xy 153.304544 -253.61859)
			(xy 153.284621 -253.566499) (xy 153.272495 -253.512062) (xy 153.268424 -253.45644) (xy 153.01595 -253.45644)
			(xy 153.015441 -253.484326) (xy 153.007321 -253.539502) (xy 152.991253 -253.592909) (xy 152.967581 -253.643406)
			(xy 152.936808 -253.689919) (xy 152.899591 -253.731456) (xy 152.856723 -253.767131) (xy 152.809117 -253.796185)
			(xy 152.757788 -253.817997) (xy 152.703831 -253.832103) (xy 152.648394 -253.838203) (xy 152.59266 -253.836166)
			(xy 152.537817 -253.826036) (xy 152.485033 -253.808029) (xy 152.435433 -253.782528) (xy 152.390075 -253.750077)
			(xy 152.349926 -253.711368) (xy 152.31584 -253.667225) (xy 152.288544 -253.61859) (xy 152.268621 -253.566499)
			(xy 152.256495 -253.512062) (xy 152.252424 -253.45644) (xy 151.99995 -253.45644) (xy 151.999441 -253.484326)
			(xy 151.991321 -253.539502) (xy 151.975253 -253.592909) (xy 151.951581 -253.643406) (xy 151.920808 -253.689919)
			(xy 151.883591 -253.731456) (xy 151.840723 -253.767131) (xy 151.793117 -253.796185) (xy 151.741788 -253.817997)
			(xy 151.687831 -253.832103) (xy 151.632394 -253.838203) (xy 151.57666 -253.836166) (xy 151.521817 -253.826036)
			(xy 151.469033 -253.808029) (xy 151.419433 -253.782528) (xy 151.374075 -253.750077) (xy 151.333926 -253.711368)
			(xy 151.29984 -253.667225) (xy 151.272544 -253.61859) (xy 151.252621 -253.566499) (xy 151.240495 -253.512062)
			(xy 151.236424 -253.45644) (xy 150.98395 -253.45644) (xy 150.983441 -253.484326) (xy 150.975321 -253.539502)
			(xy 150.959253 -253.592909) (xy 150.935581 -253.643406) (xy 150.904808 -253.689919) (xy 150.867591 -253.731456)
			(xy 150.824723 -253.767131) (xy 150.777117 -253.796185) (xy 150.725788 -253.817997) (xy 150.671831 -253.832103)
			(xy 150.616394 -253.838203) (xy 150.56066 -253.836166) (xy 150.505817 -253.826036) (xy 150.453033 -253.808029)
			(xy 150.403433 -253.782528) (xy 150.358075 -253.750077) (xy 150.317926 -253.711368) (xy 150.28384 -253.667225)
			(xy 150.256544 -253.61859) (xy 150.236621 -253.566499) (xy 150.224495 -253.512062) (xy 150.220424 -253.45644)
			(xy 149.96795 -253.45644) (xy 149.967441 -253.484326) (xy 149.959321 -253.539502) (xy 149.943253 -253.592909)
			(xy 149.919581 -253.643406) (xy 149.888808 -253.689919) (xy 149.851591 -253.731456) (xy 149.808723 -253.767131)
			(xy 149.761117 -253.796185) (xy 149.709788 -253.817997) (xy 149.655831 -253.832103) (xy 149.600394 -253.838203)
			(xy 149.54466 -253.836166) (xy 149.489817 -253.826036) (xy 149.437033 -253.808029) (xy 149.387433 -253.782528)
			(xy 149.342075 -253.750077) (xy 149.301926 -253.711368) (xy 149.26784 -253.667225) (xy 149.240544 -253.61859)
			(xy 149.220621 -253.566499) (xy 149.208495 -253.512062) (xy 149.204424 -253.45644) (xy 148.95195 -253.45644)
			(xy 148.951441 -253.484326) (xy 148.943321 -253.539502) (xy 148.927253 -253.592909) (xy 148.903581 -253.643406)
			(xy 148.872808 -253.689919) (xy 148.835591 -253.731456) (xy 148.792723 -253.767131) (xy 148.745117 -253.796185)
			(xy 148.693788 -253.817997) (xy 148.639831 -253.832103) (xy 148.584394 -253.838203) (xy 148.52866 -253.836166)
			(xy 148.473817 -253.826036) (xy 148.421033 -253.808029) (xy 148.371433 -253.782528) (xy 148.326075 -253.750077)
			(xy 148.285926 -253.711368) (xy 148.25184 -253.667225) (xy 148.224544 -253.61859) (xy 148.204621 -253.566499)
			(xy 148.192495 -253.512062) (xy 148.188424 -253.45644) (xy 147.93595 -253.45644) (xy 147.935441 -253.484326)
			(xy 147.927321 -253.539502) (xy 147.911253 -253.592909) (xy 147.887581 -253.643406) (xy 147.856808 -253.689919)
			(xy 147.819591 -253.731456) (xy 147.776723 -253.767131) (xy 147.729117 -253.796185) (xy 147.677788 -253.817997)
			(xy 147.623831 -253.832103) (xy 147.568394 -253.838203) (xy 147.51266 -253.836166) (xy 147.457817 -253.826036)
			(xy 147.405033 -253.808029) (xy 147.355433 -253.782528) (xy 147.310075 -253.750077) (xy 147.269926 -253.711368)
			(xy 147.23584 -253.667225) (xy 147.208544 -253.61859) (xy 147.188621 -253.566499) (xy 147.176495 -253.512062)
			(xy 147.172424 -253.45644) (xy 146.91995 -253.45644) (xy 146.919441 -253.484326) (xy 146.911321 -253.539502)
			(xy 146.895253 -253.592909) (xy 146.871581 -253.643406) (xy 146.840808 -253.689919) (xy 146.803591 -253.731456)
			(xy 146.760723 -253.767131) (xy 146.713117 -253.796185) (xy 146.661788 -253.817997) (xy 146.607831 -253.832103)
			(xy 146.552394 -253.838203) (xy 146.49666 -253.836166) (xy 146.441817 -253.826036) (xy 146.389033 -253.808029)
			(xy 146.339433 -253.782528) (xy 146.294075 -253.750077) (xy 146.253926 -253.711368) (xy 146.21984 -253.667225)
			(xy 146.192544 -253.61859) (xy 146.172621 -253.566499) (xy 146.160495 -253.512062) (xy 146.156424 -253.45644)
			(xy 145.90395 -253.45644) (xy 145.903441 -253.484326) (xy 145.895321 -253.539502) (xy 145.879253 -253.592909)
			(xy 145.855581 -253.643406) (xy 145.824808 -253.689919) (xy 145.787591 -253.731456) (xy 145.744723 -253.767131)
			(xy 145.697117 -253.796185) (xy 145.645788 -253.817997) (xy 145.591831 -253.832103) (xy 145.536394 -253.838203)
			(xy 145.48066 -253.836166) (xy 145.425817 -253.826036) (xy 145.373033 -253.808029) (xy 145.323433 -253.782528)
			(xy 145.278075 -253.750077) (xy 145.237926 -253.711368) (xy 145.20384 -253.667225) (xy 145.176544 -253.61859)
			(xy 145.156621 -253.566499) (xy 145.144495 -253.512062) (xy 145.140424 -253.45644) (xy 144.88795 -253.45644)
			(xy 144.887441 -253.484326) (xy 144.879321 -253.539502) (xy 144.863253 -253.592909) (xy 144.839581 -253.643406)
			(xy 144.808808 -253.689919) (xy 144.771591 -253.731456) (xy 144.728723 -253.767131) (xy 144.681117 -253.796185)
			(xy 144.629788 -253.817997) (xy 144.575831 -253.832103) (xy 144.520394 -253.838203) (xy 144.46466 -253.836166)
			(xy 144.409817 -253.826036) (xy 144.357033 -253.808029) (xy 144.307433 -253.782528) (xy 144.262075 -253.750077)
			(xy 144.221926 -253.711368) (xy 144.18784 -253.667225) (xy 144.160544 -253.61859) (xy 144.140621 -253.566499)
			(xy 144.128495 -253.512062) (xy 144.124424 -253.45644) (xy 143.87195 -253.45644) (xy 143.871441 -253.484326)
			(xy 143.863321 -253.539502) (xy 143.847253 -253.592909) (xy 143.823581 -253.643406) (xy 143.792808 -253.689919)
			(xy 143.755591 -253.731456) (xy 143.712723 -253.767131) (xy 143.665117 -253.796185) (xy 143.613788 -253.817997)
			(xy 143.559831 -253.832103) (xy 143.504394 -253.838203) (xy 143.44866 -253.836166) (xy 143.393817 -253.826036)
			(xy 143.341033 -253.808029) (xy 143.291433 -253.782528) (xy 143.246075 -253.750077) (xy 143.205926 -253.711368)
			(xy 143.17184 -253.667225) (xy 143.144544 -253.61859) (xy 143.124621 -253.566499) (xy 143.112495 -253.512062)
			(xy 143.108424 -253.45644) (xy 142.85595 -253.45644) (xy 142.855441 -253.484326) (xy 142.847321 -253.539502)
			(xy 142.831253 -253.592909) (xy 142.807581 -253.643406) (xy 142.776808 -253.689919) (xy 142.739591 -253.731456)
			(xy 142.696723 -253.767131) (xy 142.649117 -253.796185) (xy 142.597788 -253.817997) (xy 142.543831 -253.832103)
			(xy 142.488394 -253.838203) (xy 142.43266 -253.836166) (xy 142.377817 -253.826036) (xy 142.325033 -253.808029)
			(xy 142.275433 -253.782528) (xy 142.230075 -253.750077) (xy 142.189926 -253.711368) (xy 142.15584 -253.667225)
			(xy 142.128544 -253.61859) (xy 142.108621 -253.566499) (xy 142.096495 -253.512062) (xy 142.092424 -253.45644)
			(xy 141.83995 -253.45644) (xy 141.839441 -253.484326) (xy 141.831321 -253.539502) (xy 141.815253 -253.592909)
			(xy 141.791581 -253.643406) (xy 141.760808 -253.689919) (xy 141.723591 -253.731456) (xy 141.680723 -253.767131)
			(xy 141.633117 -253.796185) (xy 141.581788 -253.817997) (xy 141.527831 -253.832103) (xy 141.472394 -253.838203)
			(xy 141.41666 -253.836166) (xy 141.361817 -253.826036) (xy 141.309033 -253.808029) (xy 141.259433 -253.782528)
			(xy 141.214075 -253.750077) (xy 141.173926 -253.711368) (xy 141.13984 -253.667225) (xy 141.112544 -253.61859)
			(xy 141.092621 -253.566499) (xy 141.080495 -253.512062) (xy 141.076424 -253.45644) (xy 140.82395 -253.45644)
			(xy 140.823441 -253.484326) (xy 140.815321 -253.539502) (xy 140.799253 -253.592909) (xy 140.775581 -253.643406)
			(xy 140.744808 -253.689919) (xy 140.707591 -253.731456) (xy 140.664723 -253.767131) (xy 140.617117 -253.796185)
			(xy 140.565788 -253.817997) (xy 140.511831 -253.832103) (xy 140.456394 -253.838203) (xy 140.40066 -253.836166)
			(xy 140.345817 -253.826036) (xy 140.293033 -253.808029) (xy 140.243433 -253.782528) (xy 140.198075 -253.750077)
			(xy 140.157926 -253.711368) (xy 140.12384 -253.667225) (xy 140.096544 -253.61859) (xy 140.076621 -253.566499)
			(xy 140.064495 -253.512062) (xy 140.060424 -253.45644) (xy 130.992972 -253.45644) (xy 130.953541 -253.489255)
			(xy 130.905935 -253.518309) (xy 130.854606 -253.540121) (xy 130.800649 -253.554227) (xy 130.745212 -253.560327)
			(xy 130.689478 -253.55829) (xy 130.634635 -253.54816) (xy 130.581851 -253.530153) (xy 130.532251 -253.504652)
			(xy 130.486893 -253.472201) (xy 130.446744 -253.433492) (xy 130.412658 -253.389349) (xy 130.385362 -253.340714)
			(xy 130.365439 -253.288623) (xy 130.353313 -253.234186) (xy 130.349242 -253.178564) (xy 129.049272 -253.178564)
			(xy 129.048763 -253.20645) (xy 129.040643 -253.261626) (xy 129.024575 -253.315033) (xy 129.000903 -253.36553)
			(xy 128.97013 -253.412043) (xy 128.932913 -253.45358) (xy 128.890045 -253.489255) (xy 128.842439 -253.518309)
			(xy 128.79111 -253.540121) (xy 128.737153 -253.554227) (xy 128.681716 -253.560327) (xy 128.625982 -253.55829)
			(xy 128.571139 -253.54816) (xy 128.518355 -253.530153) (xy 128.468755 -253.504652) (xy 128.423397 -253.472201)
			(xy 128.383248 -253.433492) (xy 128.349162 -253.389349) (xy 128.321866 -253.340714) (xy 128.301943 -253.288623)
			(xy 128.289817 -253.234186) (xy 128.285746 -253.178564) (xy 126.943461 -253.178564) (xy 126.958235 -253.200894)
			(xy 126.981907 -253.251391) (xy 126.997975 -253.304798) (xy 127.006095 -253.359974) (xy 127.006604 -253.38786)
			(xy 127.006095 -253.415746) (xy 126.997975 -253.470922) (xy 126.981907 -253.524329) (xy 126.958235 -253.574826)
			(xy 126.927462 -253.621339) (xy 126.890245 -253.662876) (xy 126.847377 -253.698551) (xy 126.799771 -253.727605)
			(xy 126.748442 -253.749417) (xy 126.694485 -253.763523) (xy 126.639048 -253.769623) (xy 126.583314 -253.767586)
			(xy 126.528471 -253.757456) (xy 126.475687 -253.739449) (xy 126.426087 -253.713948) (xy 126.380729 -253.681497)
			(xy 126.34058 -253.642788) (xy 126.306494 -253.598645) (xy 126.279198 -253.55001) (xy 126.259275 -253.497919)
			(xy 126.247149 -253.443482) (xy 126.243078 -253.38786) (xy 118.962459 -253.38786) (xy 118.927911 -253.416611)
			(xy 118.880305 -253.445665) (xy 118.828976 -253.467477) (xy 118.775019 -253.481583) (xy 118.719582 -253.487683)
			(xy 118.663848 -253.485646) (xy 118.609005 -253.475516) (xy 118.556221 -253.457509) (xy 118.506621 -253.432008)
			(xy 118.461263 -253.399557) (xy 118.421114 -253.360848) (xy 118.387028 -253.316705) (xy 118.359732 -253.26807)
			(xy 118.339809 -253.215979) (xy 118.327683 -253.161542) (xy 118.323612 -253.10592) (xy 40.899334 -253.10592)
			(xy 40.899334 -253.205234) (xy 40.89963 -253.213107) (xy 40.904417 -253.228107) (xy 40.908732 -253.234698)
			(xy 40.923669 -253.256354) (xy 40.948088 -253.302951) (xy 40.965868 -253.352463) (xy 40.976671 -253.40395)
			(xy 40.980292 -253.456433) (xy 40.976662 -253.508915) (xy 40.96585 -253.5604) (xy 40.948062 -253.609909)
			(xy 40.923635 -253.656502) (xy 40.908732 -253.678182) (xy 40.904401 -253.684766) (xy 40.899609 -253.69977)
			(xy 40.899334 -253.707646) (xy 40.899334 -254.302327) (xy 95.831717 -254.302327) (xy 95.83172 -254.247832)
			(xy 95.839478 -254.193892) (xy 95.854833 -254.141605) (xy 95.877473 -254.092036) (xy 95.906937 -254.046193)
			(xy 95.942625 -254.005009) (xy 95.98381 -253.969324) (xy 96.029655 -253.939863) (xy 96.079226 -253.917225)
			(xy 96.131514 -253.901873) (xy 96.185454 -253.894118) (xy 96.239949 -253.894118) (xy 96.293889 -253.901874)
			(xy 96.346177 -253.917226) (xy 96.395747 -253.939864) (xy 96.441592 -253.969325) (xy 96.482777 -254.005011)
			(xy 96.518465 -254.046195) (xy 96.547928 -254.092038) (xy 96.570568 -254.141608) (xy 96.585923 -254.193895)
			(xy 96.593194 -254.244452) (xy 113.850648 -254.244452) (xy 113.850648 -254.189948) (xy 113.858404 -254.135998)
			(xy 113.873759 -254.083701) (xy 113.8964 -254.034122) (xy 113.925866 -253.988269) (xy 113.961558 -253.947076)
			(xy 114.002748 -253.911382) (xy 114.048599 -253.881913) (xy 114.098177 -253.859268) (xy 114.150473 -253.84391)
			(xy 114.204422 -253.83615) (xy 114.231674 -253.835662) (xy 114.259831 -253.836187) (xy 114.315532 -253.844482)
			(xy 114.369406 -253.860881) (xy 114.420281 -253.885028) (xy 114.467051 -253.916396) (xy 114.488214 -253.934976)
			(xy 114.49558 -253.94158) (xy 114.513106 -253.948184) (xy 114.602006 -253.947168) (xy 114.619532 -253.940056)
			(xy 114.626644 -253.933452) (xy 114.648003 -253.913898) (xy 114.695563 -253.880863) (xy 114.747571 -253.855399)
			(xy 114.802831 -253.838092) (xy 114.860072 -253.82934) (xy 114.889026 -253.828804) (xy 114.916278 -253.829254)
			(xy 114.970228 -253.837014) (xy 115.022524 -253.852373) (xy 115.072102 -253.875018) (xy 115.117953 -253.904488)
			(xy 115.159143 -253.940183) (xy 115.194835 -253.981377) (xy 115.2243 -254.027231) (xy 115.24694 -254.076811)
			(xy 115.262294 -254.129109) (xy 115.267358 -254.164338) (xy 117.675912 -254.164338) (xy 117.679983 -254.108716)
			(xy 117.692109 -254.054279) (xy 117.712032 -254.002188) (xy 117.739328 -253.953553) (xy 117.773414 -253.90941)
			(xy 117.813563 -253.870701) (xy 117.858921 -253.83825) (xy 117.908521 -253.812749) (xy 117.961305 -253.794742)
			(xy 118.016148 -253.784612) (xy 118.071882 -253.782575) (xy 118.127319 -253.788675) (xy 118.181276 -253.802781)
			(xy 118.232605 -253.824593) (xy 118.280211 -253.853647) (xy 118.323079 -253.889322) (xy 118.360296 -253.930859)
			(xy 118.391069 -253.977372) (xy 118.394651 -253.985014) (xy 121.718576 -253.985014) (xy 121.722647 -253.929392)
			(xy 121.734773 -253.874955) (xy 121.754696 -253.822864) (xy 121.781992 -253.774229) (xy 121.816078 -253.730086)
			(xy 121.856227 -253.691377) (xy 121.901585 -253.658926) (xy 121.951185 -253.633425) (xy 122.003969 -253.615418)
			(xy 122.058812 -253.605288) (xy 122.114546 -253.603251) (xy 122.169983 -253.609351) (xy 122.22394 -253.623457)
			(xy 122.275269 -253.645269) (xy 122.322875 -253.674323) (xy 122.365743 -253.709998) (xy 122.40296 -253.751535)
			(xy 122.433733 -253.798048) (xy 122.457405 -253.848545) (xy 122.473473 -253.901952) (xy 122.481593 -253.957128)
			(xy 122.482102 -253.985014) (xy 122.481593 -254.0129) (xy 122.473473 -254.068076) (xy 122.457405 -254.121483)
			(xy 122.433733 -254.17198) (xy 122.418791 -254.194564) (xy 128.285746 -254.194564) (xy 128.289817 -254.138942)
			(xy 128.301943 -254.084505) (xy 128.321866 -254.032414) (xy 128.349162 -253.983779) (xy 128.383248 -253.939636)
			(xy 128.423397 -253.900927) (xy 128.468755 -253.868476) (xy 128.518355 -253.842975) (xy 128.571139 -253.824968)
			(xy 128.625982 -253.814838) (xy 128.681716 -253.812801) (xy 128.737153 -253.818901) (xy 128.79111 -253.833007)
			(xy 128.842439 -253.854819) (xy 128.890045 -253.883873) (xy 128.932913 -253.919548) (xy 128.97013 -253.961085)
			(xy 129.000903 -254.007598) (xy 129.024575 -254.058095) (xy 129.040643 -254.111502) (xy 129.048763 -254.166678)
			(xy 129.049272 -254.194564) (xy 130.317746 -254.194564) (xy 130.321817 -254.138942) (xy 130.333943 -254.084505)
			(xy 130.353866 -254.032414) (xy 130.381162 -253.983779) (xy 130.415248 -253.939636) (xy 130.455397 -253.900927)
			(xy 130.500755 -253.868476) (xy 130.550355 -253.842975) (xy 130.603139 -253.824968) (xy 130.657982 -253.814838)
			(xy 130.713716 -253.812801) (xy 130.769153 -253.818901) (xy 130.82311 -253.833007) (xy 130.874439 -253.854819)
			(xy 130.922045 -253.883873) (xy 130.964913 -253.919548) (xy 131.00213 -253.961085) (xy 131.032903 -254.007598)
			(xy 131.056575 -254.058095) (xy 131.072643 -254.111502) (xy 131.080763 -254.166678) (xy 131.081272 -254.194564)
			(xy 131.080763 -254.22245) (xy 131.072643 -254.277626) (xy 131.056575 -254.331033) (xy 131.032903 -254.38153)
			(xy 131.00213 -254.428043) (xy 130.964913 -254.46958) (xy 130.922045 -254.505255) (xy 130.874439 -254.534309)
			(xy 130.82311 -254.556121) (xy 130.769153 -254.570227) (xy 130.713716 -254.576327) (xy 130.657982 -254.57429)
			(xy 130.603139 -254.56416) (xy 130.550355 -254.546153) (xy 130.500755 -254.520652) (xy 130.455397 -254.488201)
			(xy 130.415248 -254.449492) (xy 130.381162 -254.405349) (xy 130.353866 -254.356714) (xy 130.333943 -254.304623)
			(xy 130.321817 -254.250186) (xy 130.317746 -254.194564) (xy 129.049272 -254.194564) (xy 129.048763 -254.22245)
			(xy 129.040643 -254.277626) (xy 129.024575 -254.331033) (xy 129.000903 -254.38153) (xy 128.97013 -254.428043)
			(xy 128.932913 -254.46958) (xy 128.890045 -254.505255) (xy 128.842439 -254.534309) (xy 128.79111 -254.556121)
			(xy 128.737153 -254.570227) (xy 128.681716 -254.576327) (xy 128.625982 -254.57429) (xy 128.571139 -254.56416)
			(xy 128.518355 -254.546153) (xy 128.468755 -254.520652) (xy 128.423397 -254.488201) (xy 128.383248 -254.449492)
			(xy 128.349162 -254.405349) (xy 128.321866 -254.356714) (xy 128.301943 -254.304623) (xy 128.289817 -254.250186)
			(xy 128.285746 -254.194564) (xy 122.418791 -254.194564) (xy 122.40296 -254.218493) (xy 122.365743 -254.26003)
			(xy 122.322875 -254.295705) (xy 122.275269 -254.324759) (xy 122.22394 -254.346571) (xy 122.169983 -254.360677)
			(xy 122.114546 -254.366777) (xy 122.058812 -254.36474) (xy 122.003969 -254.35461) (xy 121.951185 -254.336603)
			(xy 121.901585 -254.311102) (xy 121.856227 -254.278651) (xy 121.816078 -254.239942) (xy 121.781992 -254.195799)
			(xy 121.754696 -254.147164) (xy 121.734773 -254.095073) (xy 121.722647 -254.040636) (xy 121.718576 -253.985014)
			(xy 118.394651 -253.985014) (xy 118.414741 -254.027869) (xy 118.430809 -254.081276) (xy 118.438929 -254.136452)
			(xy 118.439438 -254.164338) (xy 118.438929 -254.192224) (xy 118.430809 -254.2474) (xy 118.414741 -254.300807)
			(xy 118.391069 -254.351304) (xy 118.360296 -254.397817) (xy 118.323079 -254.439354) (xy 118.280211 -254.475029)
			(xy 118.232605 -254.504083) (xy 118.181276 -254.525895) (xy 118.127319 -254.540001) (xy 118.071882 -254.546101)
			(xy 118.016148 -254.544064) (xy 117.961305 -254.533934) (xy 117.908521 -254.515927) (xy 117.858921 -254.490426)
			(xy 117.813563 -254.457975) (xy 117.773414 -254.419266) (xy 117.739328 -254.375123) (xy 117.712032 -254.326488)
			(xy 117.692109 -254.274397) (xy 117.679983 -254.21996) (xy 117.675912 -254.164338) (xy 115.267358 -254.164338)
			(xy 115.270049 -254.18306) (xy 115.270534 -254.210312) (xy 115.269955 -254.240498) (xy 115.260401 -254.30011)
			(xy 115.241595 -254.357479) (xy 115.214005 -254.411179) (xy 115.19662 -254.435864) (xy 115.189508 -254.44577)
			(xy 115.185444 -254.4699) (xy 115.218464 -254.571754) (xy 115.235736 -254.588772) (xy 115.24742 -254.592582)
			(xy 115.275512 -254.602281) (xy 115.328562 -254.629058) (xy 115.376825 -254.66373) (xy 115.419134 -254.705459)
			(xy 115.454469 -254.753238) (xy 115.481978 -254.805913) (xy 115.492022 -254.833882) (xy 115.496086 -254.84582)
			(xy 115.513358 -254.862584) (xy 115.615466 -254.894588) (xy 115.639088 -254.890524) (xy 115.649248 -254.882904)
			(xy 115.674111 -254.865093) (xy 115.728341 -254.836822) (xy 115.786387 -254.817564) (xy 115.846761 -254.807814)
			(xy 115.87734 -254.807212) (xy 115.903943 -254.807701) (xy 115.956634 -254.815075) (xy 116.007789 -254.829702)
			(xy 116.056414 -254.851298) (xy 116.101565 -254.879443) (xy 116.142365 -254.913592) (xy 116.178022 -254.95308)
			(xy 116.193316 -254.974852) (xy 116.20079 -254.984828) (xy 116.222777 -254.996526) (xy 116.235226 -254.997204)
			(xy 116.319554 -254.997204) (xy 116.332005 -254.996539) (xy 116.353982 -254.984826) (xy 116.361464 -254.974852)
			(xy 116.376773 -254.953092) (xy 116.412437 -254.913612) (xy 116.453238 -254.879468) (xy 116.498385 -254.851321)
			(xy 116.547004 -254.829717) (xy 116.598152 -254.815074) (xy 116.650839 -254.807677) (xy 116.67744 -254.807212)
			(xy 116.704691 -254.807661) (xy 116.758637 -254.815422) (xy 116.81093 -254.830781) (xy 116.860505 -254.853426)
			(xy 116.906352 -254.882895) (xy 116.94754 -254.918588) (xy 116.983229 -254.95978) (xy 117.012693 -255.005631)
			(xy 117.035333 -255.055208) (xy 117.050686 -255.107502) (xy 117.051225 -255.11125) (xy 120.99366 -255.11125)
			(xy 120.997731 -255.055628) (xy 121.009857 -255.001191) (xy 121.02978 -254.9491) (xy 121.057076 -254.900465)
			(xy 121.091162 -254.856322) (xy 121.131311 -254.817613) (xy 121.176669 -254.785162) (xy 121.226269 -254.759661)
			(xy 121.279053 -254.741654) (xy 121.333896 -254.731524) (xy 121.38963 -254.729487) (xy 121.445067 -254.735587)
			(xy 121.499024 -254.749693) (xy 121.550353 -254.771505) (xy 121.597959 -254.800559) (xy 121.640827 -254.836234)
			(xy 121.678044 -254.877771) (xy 121.708817 -254.924284) (xy 121.732489 -254.974781) (xy 121.748557 -255.028188)
			(xy 121.756677 -255.083364) (xy 121.757186 -255.11125) (xy 121.756677 -255.139136) (xy 121.748557 -255.194312)
			(xy 121.743667 -255.210564) (xy 128.285746 -255.210564) (xy 128.289817 -255.154942) (xy 128.301943 -255.100505)
			(xy 128.321866 -255.048414) (xy 128.349162 -254.999779) (xy 128.383248 -254.955636) (xy 128.423397 -254.916927)
			(xy 128.468755 -254.884476) (xy 128.518355 -254.858975) (xy 128.571139 -254.840968) (xy 128.625982 -254.830838)
			(xy 128.681716 -254.828801) (xy 128.737153 -254.834901) (xy 128.79111 -254.849007) (xy 128.842439 -254.870819)
			(xy 128.890045 -254.899873) (xy 128.932913 -254.935548) (xy 128.97013 -254.977085) (xy 129.000903 -255.023598)
			(xy 129.024575 -255.074095) (xy 129.040643 -255.127502) (xy 129.048763 -255.182678) (xy 129.049272 -255.210564)
			(xy 130.349242 -255.210564) (xy 130.353313 -255.154942) (xy 130.365439 -255.100505) (xy 130.385362 -255.048414)
			(xy 130.412658 -254.999779) (xy 130.446744 -254.955636) (xy 130.486893 -254.916927) (xy 130.532251 -254.884476)
			(xy 130.581851 -254.858975) (xy 130.634635 -254.840968) (xy 130.689478 -254.830838) (xy 130.745212 -254.828801)
			(xy 130.800649 -254.834901) (xy 130.854606 -254.849007) (xy 130.905935 -254.870819) (xy 130.953541 -254.899873)
			(xy 130.996409 -254.935548) (xy 131.033626 -254.977085) (xy 131.064399 -255.023598) (xy 131.088071 -255.074095)
			(xy 131.104139 -255.127502) (xy 131.104925 -255.13284) (xy 188.35573 -255.13284) (xy 188.359801 -255.077218)
			(xy 188.371927 -255.022781) (xy 188.39185 -254.97069) (xy 188.419146 -254.922055) (xy 188.453232 -254.877912)
			(xy 188.493381 -254.839203) (xy 188.538739 -254.806752) (xy 188.588339 -254.781251) (xy 188.641123 -254.763244)
			(xy 188.695966 -254.753114) (xy 188.7517 -254.751077) (xy 188.807137 -254.757177) (xy 188.861094 -254.771283)
			(xy 188.912423 -254.793095) (xy 188.960029 -254.822149) (xy 189.002897 -254.857824) (xy 189.040114 -254.899361)
			(xy 189.070887 -254.945874) (xy 189.094559 -254.996371) (xy 189.110627 -255.049778) (xy 189.118747 -255.104954)
			(xy 189.119256 -255.13284) (xy 189.118747 -255.160726) (xy 189.110627 -255.215902) (xy 189.094559 -255.269309)
			(xy 189.070887 -255.319806) (xy 189.040114 -255.366319) (xy 189.002897 -255.407856) (xy 188.960029 -255.443531)
			(xy 188.912423 -255.472585) (xy 188.861094 -255.494397) (xy 188.807137 -255.508503) (xy 188.7517 -255.514603)
			(xy 188.695966 -255.512566) (xy 188.641123 -255.502436) (xy 188.588339 -255.484429) (xy 188.538739 -255.458928)
			(xy 188.493381 -255.426477) (xy 188.453232 -255.387768) (xy 188.419146 -255.343625) (xy 188.39185 -255.29499)
			(xy 188.371927 -255.242899) (xy 188.359801 -255.188462) (xy 188.35573 -255.13284) (xy 131.104925 -255.13284)
			(xy 131.112259 -255.182678) (xy 131.112768 -255.210564) (xy 131.112259 -255.23845) (xy 131.104139 -255.293626)
			(xy 131.088071 -255.347033) (xy 131.064399 -255.39753) (xy 131.033626 -255.444043) (xy 130.996409 -255.48558)
			(xy 130.953541 -255.521255) (xy 130.905935 -255.550309) (xy 130.854606 -255.572121) (xy 130.800649 -255.586227)
			(xy 130.745212 -255.592327) (xy 130.689478 -255.59029) (xy 130.634635 -255.58016) (xy 130.581851 -255.562153)
			(xy 130.532251 -255.536652) (xy 130.486893 -255.504201) (xy 130.446744 -255.465492) (xy 130.412658 -255.421349)
			(xy 130.385362 -255.372714) (xy 130.365439 -255.320623) (xy 130.353313 -255.266186) (xy 130.349242 -255.210564)
			(xy 129.049272 -255.210564) (xy 129.048763 -255.23845) (xy 129.040643 -255.293626) (xy 129.024575 -255.347033)
			(xy 129.000903 -255.39753) (xy 128.97013 -255.444043) (xy 128.932913 -255.48558) (xy 128.890045 -255.521255)
			(xy 128.842439 -255.550309) (xy 128.79111 -255.572121) (xy 128.737153 -255.586227) (xy 128.681716 -255.592327)
			(xy 128.625982 -255.59029) (xy 128.571139 -255.58016) (xy 128.518355 -255.562153) (xy 128.468755 -255.536652)
			(xy 128.423397 -255.504201) (xy 128.383248 -255.465492) (xy 128.349162 -255.421349) (xy 128.321866 -255.372714)
			(xy 128.301943 -255.320623) (xy 128.289817 -255.266186) (xy 128.285746 -255.210564) (xy 121.743667 -255.210564)
			(xy 121.732489 -255.247719) (xy 121.708817 -255.298216) (xy 121.678044 -255.344729) (xy 121.640827 -255.386266)
			(xy 121.597959 -255.421941) (xy 121.550353 -255.450995) (xy 121.499024 -255.472807) (xy 121.445067 -255.486913)
			(xy 121.38963 -255.493013) (xy 121.333896 -255.490976) (xy 121.279053 -255.480846) (xy 121.226269 -255.462839)
			(xy 121.176669 -255.437338) (xy 121.131311 -255.404887) (xy 121.091162 -255.366178) (xy 121.057076 -255.322035)
			(xy 121.02978 -255.2734) (xy 121.009857 -255.221309) (xy 120.997731 -255.166872) (xy 120.99366 -255.11125)
			(xy 117.051225 -255.11125) (xy 117.058442 -255.161449) (xy 117.058442 -255.215951) (xy 117.050686 -255.269898)
			(xy 117.035332 -255.322192) (xy 117.012693 -255.371769) (xy 116.983229 -255.41762) (xy 116.94754 -255.458812)
			(xy 116.906352 -255.494505) (xy 116.860505 -255.523974) (xy 116.81093 -255.546619) (xy 116.758637 -255.561978)
			(xy 116.704691 -255.569739) (xy 116.67744 -255.570228) (xy 116.650836 -255.56978) (xy 116.598141 -255.562402)
			(xy 116.546984 -255.54777) (xy 116.498358 -255.526168) (xy 116.453207 -255.498016) (xy 116.412409 -255.46386)
			(xy 116.376755 -255.424364) (xy 116.361464 -255.402588) (xy 116.353943 -255.392656) (xy 116.331992 -255.380933)
			(xy 116.319554 -255.380236) (xy 116.235226 -255.380236) (xy 116.222771 -255.380874) (xy 116.200793 -255.392605)
			(xy 116.193316 -255.402588) (xy 116.178032 -255.424366) (xy 116.142363 -255.463844) (xy 116.101557 -255.497985)
			(xy 116.056405 -255.526129) (xy 116.007782 -255.547731) (xy 115.956631 -255.56237) (xy 115.903942 -255.569764)
			(xy 115.87734 -255.570228) (xy 115.850935 -255.569782) (xy 115.798631 -255.562479) (xy 115.747834 -255.548033)
			(xy 115.699514 -255.526722) (xy 115.654594 -255.498952) (xy 115.613931 -255.465254) (xy 115.578304 -255.426271)
			(xy 115.548392 -255.382748) (xy 115.524766 -255.335516) (xy 115.515898 -255.31064) (xy 115.511834 -255.298702)
			(xy 115.494562 -255.281938) (xy 115.392454 -255.249934) (xy 115.368832 -255.253998) (xy 115.358672 -255.261618)
			(xy 115.333805 -255.279422) (xy 115.279576 -255.307695) (xy 115.221532 -255.326954) (xy 115.161158 -255.336707)
			(xy 115.13058 -255.33731) (xy 115.099206 -255.336685) (xy 115.037307 -255.326403) (xy 114.977922 -255.306137)
			(xy 114.949986 -255.291844) (xy 114.940334 -255.286764) (xy 114.91849 -255.28524) (xy 114.826288 -255.319784)
			(xy 114.810794 -255.335024) (xy 114.806984 -255.345438) (xy 114.796259 -255.372229) (xy 114.767966 -255.422521)
			(xy 114.732422 -255.467979) (xy 114.690436 -255.507565) (xy 114.642967 -255.540375) (xy 114.591098 -255.565662)
			(xy 114.536012 -255.582848) (xy 114.478966 -255.591541) (xy 114.450114 -255.592072) (xy 114.422858 -255.591682)
			(xy 114.3689 -255.583926) (xy 114.316596 -255.56857) (xy 114.267009 -255.545926) (xy 114.22115 -255.516455)
			(xy 114.179952 -255.480758) (xy 114.144253 -255.439561) (xy 114.114781 -255.393703) (xy 114.092135 -255.344117)
			(xy 114.076777 -255.291813) (xy 114.069019 -255.237856) (xy 114.069019 -255.183344) (xy 114.076777 -255.129387)
			(xy 114.092135 -255.077083) (xy 114.114781 -255.027497) (xy 114.144253 -254.981639) (xy 114.179952 -254.940442)
			(xy 114.22115 -254.904745) (xy 114.267009 -254.875274) (xy 114.316596 -254.85263) (xy 114.3689 -254.837274)
			(xy 114.422858 -254.829518) (xy 114.450114 -254.829056) (xy 114.481487 -254.829688) (xy 114.543386 -254.839967)
			(xy 114.602771 -254.860231) (xy 114.630708 -254.874522) (xy 114.64036 -254.879602) (xy 114.662204 -254.881126)
			(xy 114.754406 -254.846582) (xy 114.7699 -254.831342) (xy 114.77371 -254.820928) (xy 114.783287 -254.796871)
			(xy 114.808014 -254.751376) (xy 114.822986 -254.73025) (xy 114.830098 -254.720344) (xy 114.834162 -254.696214)
			(xy 114.801142 -254.59436) (xy 114.78387 -254.577342) (xy 114.772186 -254.573532) (xy 114.746513 -254.564739)
			(xy 114.69776 -254.540909) (xy 114.652869 -254.510421) (xy 114.632486 -254.492506) (xy 114.62512 -254.485902)
			(xy 114.607594 -254.479298) (xy 114.518694 -254.480314) (xy 114.501168 -254.487426) (xy 114.494056 -254.49403)
			(xy 114.472694 -254.513581) (xy 114.425136 -254.546617) (xy 114.373129 -254.572082) (xy 114.317869 -254.589389)
			(xy 114.260627 -254.598142) (xy 114.231674 -254.598678) (xy 114.204422 -254.59825) (xy 114.150473 -254.59049)
			(xy 114.098177 -254.575132) (xy 114.048599 -254.552487) (xy 114.002748 -254.523018) (xy 113.961558 -254.487324)
			(xy 113.925866 -254.446131) (xy 113.8964 -254.400278) (xy 113.873759 -254.350699) (xy 113.858404 -254.298402)
			(xy 113.850648 -254.244452) (xy 96.593194 -254.244452) (xy 96.593681 -254.247835) (xy 96.594168 -254.275082)
			(xy 96.592898 -254.305816) (xy 96.591882 -254.31877) (xy 96.602804 -254.3429) (xy 96.692974 -254.409956)
			(xy 96.718882 -254.413512) (xy 96.731074 -254.408686) (xy 96.753249 -254.400414) (xy 96.799129 -254.388781)
			(xy 96.846093 -254.382899) (xy 96.869758 -254.382524) (xy 96.897011 -254.382994) (xy 96.950964 -254.390747)
			(xy 97.003263 -254.406099) (xy 97.052845 -254.428739) (xy 97.0987 -254.458205) (xy 97.139894 -254.493899)
			(xy 97.175589 -254.535092) (xy 97.205056 -254.580946) (xy 97.227698 -254.630527) (xy 97.243051 -254.682827)
			(xy 97.250805 -254.736779) (xy 97.251266 -254.764032) (xy 97.250669 -254.79308) (xy 97.241883 -254.850508)
			(xy 97.22449 -254.905939) (xy 97.198892 -254.958091) (xy 97.16568 -255.005757) (xy 97.125624 -255.047836)
			(xy 97.079649 -255.083352) (xy 97.02882 -255.111486) (xy 96.974312 -255.131586) (xy 96.945958 -255.13792)
			(xy 96.93275 -255.14046) (xy 96.912684 -255.157986) (xy 96.87433 -255.26492) (xy 96.878902 -255.291082)
			(xy 96.887284 -255.301496) (xy 96.903348 -255.321988) (xy 96.930369 -255.366498) (xy 96.951085 -255.414269)
			(xy 96.965111 -255.464413) (xy 96.972188 -255.515999) (xy 96.972628 -255.542034) (xy 96.972142 -255.569285)
			(xy 96.964386 -255.623233) (xy 96.949031 -255.675528) (xy 96.926389 -255.725105) (xy 96.896923 -255.770955)
			(xy 96.861232 -255.812146) (xy 96.820041 -255.847837) (xy 96.816859 -255.849882) (xy 97.080322 -255.849882)
			(xy 97.084393 -255.79426) (xy 97.096519 -255.739823) (xy 97.116442 -255.687732) (xy 97.143738 -255.639097)
			(xy 97.177824 -255.594954) (xy 97.217973 -255.556245) (xy 97.263331 -255.523794) (xy 97.312931 -255.498293)
			(xy 97.365715 -255.480286) (xy 97.420558 -255.470156) (xy 97.476292 -255.468119) (xy 97.531729 -255.474219)
			(xy 97.585686 -255.488325) (xy 97.637015 -255.510137) (xy 97.684621 -255.539191) (xy 97.727489 -255.574866)
			(xy 97.764706 -255.616403) (xy 97.795479 -255.662916) (xy 97.819151 -255.713413) (xy 97.835219 -255.76682)
			(xy 97.843339 -255.821996) (xy 97.843848 -255.849882) (xy 97.843339 -255.877768) (xy 97.835219 -255.932944)
			(xy 97.819151 -255.986351) (xy 97.795479 -256.036848) (xy 97.764706 -256.083361) (xy 97.727489 -256.124898)
			(xy 97.684621 -256.160573) (xy 97.637015 -256.189627) (xy 97.585686 -256.211439) (xy 97.531729 -256.225545)
			(xy 97.522468 -256.226564) (xy 126.220472 -256.226564) (xy 126.224543 -256.170942) (xy 126.236669 -256.116505)
			(xy 126.256592 -256.064414) (xy 126.283888 -256.015779) (xy 126.317974 -255.971636) (xy 126.358123 -255.932927)
			(xy 126.403481 -255.900476) (xy 126.453081 -255.874975) (xy 126.505865 -255.856968) (xy 126.560708 -255.846838)
			(xy 126.616442 -255.844801) (xy 126.671879 -255.850901) (xy 126.725836 -255.865007) (xy 126.777165 -255.886819)
			(xy 126.824771 -255.915873) (xy 126.867639 -255.951548) (xy 126.904856 -255.993085) (xy 126.935629 -256.039598)
			(xy 126.959301 -256.090095) (xy 126.975369 -256.143502) (xy 126.983489 -256.198678) (xy 126.983998 -256.226564)
			(xy 128.285746 -256.226564) (xy 128.289817 -256.170942) (xy 128.301943 -256.116505) (xy 128.321866 -256.064414)
			(xy 128.349162 -256.015779) (xy 128.383248 -255.971636) (xy 128.423397 -255.932927) (xy 128.468755 -255.900476)
			(xy 128.518355 -255.874975) (xy 128.571139 -255.856968) (xy 128.625982 -255.846838) (xy 128.681716 -255.844801)
			(xy 128.737153 -255.850901) (xy 128.79111 -255.865007) (xy 128.842439 -255.886819) (xy 128.881385 -255.910588)
			(xy 137.976608 -255.910588) (xy 137.980679 -255.854966) (xy 137.992805 -255.800529) (xy 138.012728 -255.748438)
			(xy 138.040024 -255.699803) (xy 138.07411 -255.65566) (xy 138.114259 -255.616951) (xy 138.159617 -255.5845)
			(xy 138.209217 -255.558999) (xy 138.262001 -255.540992) (xy 138.316844 -255.530862) (xy 138.372578 -255.528825)
			(xy 138.428015 -255.534925) (xy 138.481972 -255.549031) (xy 138.533301 -255.570843) (xy 138.580907 -255.599897)
			(xy 138.623775 -255.635572) (xy 138.660992 -255.677109) (xy 138.671803 -255.69345) (xy 138.865595 -255.69345)
			(xy 138.865595 -255.63895) (xy 138.873352 -255.585003) (xy 138.888707 -255.53271) (xy 138.911347 -255.483135)
			(xy 138.940813 -255.437286) (xy 138.976504 -255.396097) (xy 139.017694 -255.360407) (xy 139.063543 -255.330943)
			(xy 139.11312 -255.308303) (xy 139.165413 -255.29295) (xy 139.21936 -255.285195) (xy 139.24661 -255.284732)
			(xy 139.275563 -255.285266) (xy 139.332804 -255.294025) (xy 139.388066 -255.311326) (xy 139.440082 -255.336772)
			(xy 139.487661 -255.36978) (xy 139.52971 -255.409593) (xy 139.565266 -255.455299) (xy 139.579858 -255.480312)
			(xy 139.587594 -255.493222) (xy 139.609263 -255.514091) (xy 139.636073 -255.527742) (xy 139.665697 -255.532988)
			(xy 139.695565 -255.529375) (xy 139.723083 -255.517216) (xy 139.745865 -255.497567) (xy 139.754356 -255.485138)
			(xy 139.769465 -255.462161) (xy 139.805167 -255.420337) (xy 139.846503 -255.38407) (xy 139.892616 -255.354112)
			(xy 139.942551 -255.331082) (xy 139.995275 -255.315459) (xy 140.049695 -255.307565) (xy 140.07719 -255.307084)
			(xy 140.104443 -255.307563) (xy 140.158394 -255.315318) (xy 140.210692 -255.330673) (xy 140.260272 -255.353315)
			(xy 140.306125 -255.382782) (xy 140.347318 -255.418475) (xy 140.383012 -255.459667) (xy 140.412481 -255.505519)
			(xy 140.435123 -255.555099) (xy 140.45048 -255.607397) (xy 140.458237 -255.661347) (xy 140.458237 -255.715853)
			(xy 140.45048 -255.769803) (xy 140.435123 -255.822101) (xy 140.412481 -255.871681) (xy 140.383012 -255.917533)
			(xy 140.347318 -255.958725) (xy 140.306125 -255.994418) (xy 140.260272 -256.023885) (xy 140.210692 -256.046527)
			(xy 140.158394 -256.061882) (xy 140.104443 -256.069637) (xy 140.07719 -256.0701) (xy 140.048235 -256.069601)
			(xy 139.990991 -256.06084) (xy 139.935727 -256.043535) (xy 139.883709 -256.018084) (xy 139.836131 -255.98507)
			(xy 139.794083 -255.94525) (xy 139.758531 -255.899537) (xy 139.743942 -255.87452) (xy 139.736204 -255.861615)
			(xy 139.71453 -255.840759) (xy 139.687721 -255.827118) (xy 139.658103 -255.821876) (xy 139.628241 -255.825486)
			(xy 139.600725 -255.837636) (xy 139.57794 -255.857272) (xy 139.569444 -255.869694) (xy 139.554345 -255.892679)
			(xy 139.51864 -255.934501) (xy 139.477303 -255.970766) (xy 139.431188 -256.000723) (xy 139.381251 -256.023751)
			(xy 139.328526 -256.039374) (xy 139.274105 -256.047267) (xy 139.24661 -256.047748) (xy 139.21936 -256.047205)
			(xy 139.165413 -256.03945) (xy 139.11312 -256.024097) (xy 139.063543 -256.001457) (xy 139.017694 -255.971993)
			(xy 138.976504 -255.936303) (xy 138.940813 -255.895114) (xy 138.911347 -255.849265) (xy 138.888707 -255.79969)
			(xy 138.873352 -255.747397) (xy 138.865595 -255.69345) (xy 138.671803 -255.69345) (xy 138.691765 -255.723622)
			(xy 138.715437 -255.774119) (xy 138.731505 -255.827526) (xy 138.739625 -255.882702) (xy 138.740134 -255.910588)
			(xy 138.739625 -255.938474) (xy 138.731505 -255.99365) (xy 138.715437 -256.047057) (xy 138.691765 -256.097554)
			(xy 138.660992 -256.144067) (xy 138.623775 -256.185604) (xy 138.580907 -256.221279) (xy 138.533301 -256.250333)
			(xy 138.481972 -256.272145) (xy 138.428015 -256.286251) (xy 138.372578 -256.292351) (xy 138.316844 -256.290314)
			(xy 138.262001 -256.280184) (xy 138.209217 -256.262177) (xy 138.159617 -256.236676) (xy 138.114259 -256.204225)
			(xy 138.07411 -256.165516) (xy 138.040024 -256.121373) (xy 138.012728 -256.072738) (xy 137.992805 -256.020647)
			(xy 137.980679 -255.96621) (xy 137.976608 -255.910588) (xy 128.881385 -255.910588) (xy 128.890045 -255.915873)
			(xy 128.932913 -255.951548) (xy 128.97013 -255.993085) (xy 129.000903 -256.039598) (xy 129.024575 -256.090095)
			(xy 129.040643 -256.143502) (xy 129.048763 -256.198678) (xy 129.049272 -256.226564) (xy 129.048763 -256.25445)
			(xy 129.040643 -256.309626) (xy 129.024575 -256.363033) (xy 129.000903 -256.41353) (xy 128.97013 -256.460043)
			(xy 128.952556 -256.479657) (xy 141.379325 -256.479657) (xy 141.379325 -256.425143) (xy 141.387084 -256.371183)
			(xy 141.402444 -256.318878) (xy 141.425091 -256.26929) (xy 141.454566 -256.223431) (xy 141.490268 -256.182234)
			(xy 141.53147 -256.146537) (xy 141.577332 -256.117068) (xy 141.626923 -256.094427) (xy 141.67923 -256.079074)
			(xy 141.733191 -256.071322) (xy 141.760448 -256.070862) (xy 141.786764 -256.071315) (xy 141.838897 -256.078537)
			(xy 141.889545 -256.092851) (xy 141.937747 -256.113985) (xy 141.982589 -256.14154) (xy 142.023221 -256.174993)
			(xy 142.041372 -256.194052) (xy 142.048909 -256.201436) (xy 142.068177 -256.209972) (xy 142.07871 -256.210562)
			(xy 142.153386 -256.210562) (xy 142.163938 -256.21005) (xy 142.183234 -256.201504) (xy 142.190724 -256.194052)
			(xy 142.208857 -256.174971) (xy 142.249477 -256.141491) (xy 142.294317 -256.113919) (xy 142.342525 -256.092781)
			(xy 142.393183 -256.078477) (xy 142.445328 -256.071281) (xy 142.471648 -256.070862) (xy 142.498895 -256.071411)
			(xy 142.552833 -256.079173) (xy 142.605118 -256.094531) (xy 142.613912 -256.098548) (xy 143.98193 -256.098548)
			(xy 143.986001 -256.042926) (xy 143.998127 -255.988489) (xy 144.01805 -255.936398) (xy 144.045346 -255.887763)
			(xy 144.079432 -255.84362) (xy 144.119581 -255.804911) (xy 144.164939 -255.77246) (xy 144.214539 -255.746959)
			(xy 144.267323 -255.728952) (xy 144.322166 -255.718822) (xy 144.3779 -255.716785) (xy 144.433337 -255.722885)
			(xy 144.487294 -255.736991) (xy 144.538623 -255.758803) (xy 144.573824 -255.780286) (xy 189.018924 -255.780286)
			(xy 189.022995 -255.724664) (xy 189.035121 -255.670227) (xy 189.055044 -255.618136) (xy 189.08234 -255.569501)
			(xy 189.116426 -255.525358) (xy 189.156575 -255.486649) (xy 189.201933 -255.454198) (xy 189.251533 -255.428697)
			(xy 189.304317 -255.41069) (xy 189.35916 -255.40056) (xy 189.414894 -255.398523) (xy 189.470331 -255.404623)
			(xy 189.524288 -255.418729) (xy 189.575617 -255.440541) (xy 189.623223 -255.469595) (xy 189.666091 -255.50527)
			(xy 189.703308 -255.546807) (xy 189.734081 -255.59332) (xy 189.757753 -255.643817) (xy 189.773821 -255.697224)
			(xy 189.781941 -255.7524) (xy 189.782051 -255.758442) (xy 199.922382 -255.758442) (xy 199.926453 -255.70282)
			(xy 199.938579 -255.648383) (xy 199.958502 -255.596292) (xy 199.985798 -255.547657) (xy 200.019884 -255.503514)
			(xy 200.060033 -255.464805) (xy 200.105391 -255.432354) (xy 200.154991 -255.406853) (xy 200.207775 -255.388846)
			(xy 200.262618 -255.378716) (xy 200.318352 -255.376679) (xy 200.373789 -255.382779) (xy 200.427746 -255.396885)
			(xy 200.479075 -255.418697) (xy 200.526681 -255.447751) (xy 200.569549 -255.483426) (xy 200.606766 -255.524963)
			(xy 200.637539 -255.571476) (xy 200.661211 -255.621973) (xy 200.677279 -255.67538) (xy 200.685399 -255.730556)
			(xy 200.685908 -255.758442) (xy 215.692736 -255.758442) (xy 215.693195 -255.731188) (xy 215.700947 -255.677235)
			(xy 215.7163 -255.624934) (xy 215.738941 -255.575351) (xy 215.768408 -255.529496) (xy 215.804103 -255.488301)
			(xy 215.845297 -255.452607) (xy 215.891153 -255.42314) (xy 215.940736 -255.400499) (xy 215.993037 -255.385146)
			(xy 216.04699 -255.377394) (xy 216.074244 -255.376934) (xy 216.101583 -255.377377) (xy 216.155701 -255.385171)
			(xy 216.208154 -255.400608) (xy 216.257867 -255.423372) (xy 216.303824 -255.452996) (xy 216.345083 -255.488875)
			(xy 216.363296 -255.509268) (xy 216.370154 -255.517396) (xy 216.388696 -255.52654) (xy 216.483946 -255.530604)
			(xy 216.502996 -255.523492) (xy 216.51087 -255.516126) (xy 216.532322 -255.496096) (xy 216.580241 -255.462211)
			(xy 216.632784 -255.436062) (xy 216.68871 -255.418266) (xy 216.746702 -255.409242) (xy 216.776046 -255.408684)
			(xy 216.803298 -255.409135) (xy 216.857247 -255.416898) (xy 216.909541 -255.432258) (xy 216.959118 -255.454904)
			(xy 217.004968 -255.484374) (xy 217.046158 -255.520069) (xy 217.081848 -255.561262) (xy 217.111314 -255.607115)
			(xy 217.133955 -255.656694) (xy 217.149311 -255.708991) (xy 217.157068 -255.76294) (xy 217.157554 -255.790192)
			(xy 217.157096 -255.816948) (xy 217.149632 -255.869936) (xy 217.137935 -255.910588) (xy 254.076452 -255.910588)
			(xy 254.080523 -255.854966) (xy 254.092649 -255.800529) (xy 254.112572 -255.748438) (xy 254.139868 -255.699803)
			(xy 254.173954 -255.65566) (xy 254.214103 -255.616951) (xy 254.259461 -255.5845) (xy 254.309061 -255.558999)
			(xy 254.361845 -255.540992) (xy 254.416688 -255.530862) (xy 254.472422 -255.528825) (xy 254.527859 -255.534925)
			(xy 254.581816 -255.549031) (xy 254.633145 -255.570843) (xy 254.680751 -255.599897) (xy 254.723619 -255.635572)
			(xy 254.760836 -255.677109) (xy 254.791609 -255.723622) (xy 254.815281 -255.774119) (xy 254.831349 -255.827526)
			(xy 254.839469 -255.882702) (xy 254.839978 -255.910588) (xy 254.839469 -255.938474) (xy 254.831349 -255.99365)
			(xy 254.815281 -256.047057) (xy 254.791609 -256.097554) (xy 254.760836 -256.144067) (xy 254.723619 -256.185604)
			(xy 254.680751 -256.221279) (xy 254.633145 -256.250333) (xy 254.581816 -256.272145) (xy 254.527859 -256.286251)
			(xy 254.472422 -256.292351) (xy 254.416688 -256.290314) (xy 254.361845 -256.280184) (xy 254.309061 -256.262177)
			(xy 254.259461 -256.236676) (xy 254.214103 -256.204225) (xy 254.173954 -256.165516) (xy 254.139868 -256.121373)
			(xy 254.112572 -256.072738) (xy 254.092649 -256.020647) (xy 254.080523 -255.96621) (xy 254.076452 -255.910588)
			(xy 217.137935 -255.910588) (xy 217.134836 -255.92136) (xy 217.112997 -255.970212) (xy 217.084545 -256.015533)
			(xy 217.050038 -256.056432) (xy 217.010154 -256.092106) (xy 216.965675 -256.121856) (xy 216.917475 -256.145098)
			(xy 216.892124 -256.153666) (xy 216.881964 -256.156968) (xy 216.86647 -256.17043) (xy 216.825068 -256.255774)
			(xy 216.824052 -256.276094) (xy 216.827862 -256.286254) (xy 216.839252 -256.318605) (xy 216.851476 -256.385822)
			(xy 218.904818 -256.385822) (xy 218.908889 -256.3302) (xy 218.921015 -256.275763) (xy 218.940938 -256.223672)
			(xy 218.968234 -256.175037) (xy 219.00232 -256.130894) (xy 219.042469 -256.092185) (xy 219.087827 -256.059734)
			(xy 219.137427 -256.034233) (xy 219.190211 -256.016226) (xy 219.245054 -256.006096) (xy 219.300788 -256.004059)
			(xy 219.356225 -256.010159) (xy 219.410182 -256.024265) (xy 219.461511 -256.046077) (xy 219.509117 -256.075131)
			(xy 219.551985 -256.110806) (xy 219.589202 -256.152343) (xy 219.619975 -256.198856) (xy 219.643647 -256.249353)
			(xy 219.659715 -256.30276) (xy 219.667835 -256.357936) (xy 219.668344 -256.385822) (xy 219.667835 -256.413708)
			(xy 219.659715 -256.468884) (xy 219.656475 -256.479653) (xy 257.479248 -256.479653) (xy 257.479248 -256.425147)
			(xy 257.487005 -256.371196) (xy 257.502361 -256.318897) (xy 257.525003 -256.269317) (xy 257.554471 -256.223463)
			(xy 257.590164 -256.18227) (xy 257.631357 -256.146576) (xy 257.67721 -256.117107) (xy 257.72679 -256.094463)
			(xy 257.779088 -256.079106) (xy 257.833039 -256.071348) (xy 257.860292 -256.070862) (xy 257.886609 -256.071286)
			(xy 257.938744 -256.078514) (xy 257.989392 -256.092833) (xy 258.037593 -256.113973) (xy 258.082435 -256.141533)
			(xy 258.123066 -256.17499) (xy 258.141216 -256.194052) (xy 258.148736 -256.201455) (xy 258.168017 -256.20998)
			(xy 258.178554 -256.210562) (xy 258.25323 -256.210562) (xy 258.263778 -256.21002) (xy 258.283075 -256.201495)
			(xy 258.290568 -256.194052) (xy 258.308729 -256.174998) (xy 258.349342 -256.141516) (xy 258.394177 -256.113941)
			(xy 258.44238 -256.092797) (xy 258.493033 -256.078488) (xy 258.545174 -256.071285) (xy 258.571492 -256.070862)
			(xy 258.598743 -256.071385) (xy 258.652691 -256.07914) (xy 258.704985 -256.094494) (xy 258.754563 -256.117135)
			(xy 258.800413 -256.1466) (xy 258.841603 -256.182291) (xy 258.877295 -256.22348) (xy 258.906762 -256.26933)
			(xy 258.929403 -256.318907) (xy 258.944758 -256.371202) (xy 258.952515 -256.425149) (xy 258.952515 -256.479651)
			(xy 258.944758 -256.533598) (xy 258.929403 -256.585893) (xy 258.906762 -256.63547) (xy 258.877295 -256.68132)
			(xy 258.841603 -256.722509) (xy 258.800413 -256.7582) (xy 258.754563 -256.787665) (xy 258.704985 -256.810306)
			(xy 258.652691 -256.82566) (xy 258.598743 -256.833415) (xy 258.571492 -256.833878) (xy 258.545176 -256.833417)
			(xy 258.493042 -256.826199) (xy 258.442394 -256.811889) (xy 258.394192 -256.790756) (xy 258.34935 -256.763201)
			(xy 258.308718 -256.729748) (xy 258.290568 -256.710688) (xy 258.283062 -256.703268) (xy 258.26377 -256.694755)
			(xy 258.25323 -256.694178) (xy 258.178554 -256.694178) (xy 258.168007 -256.694729) (xy 258.148712 -256.70325)
			(xy 258.141216 -256.710688) (xy 258.123071 -256.729757) (xy 258.082453 -256.763237) (xy 258.037615 -256.790809)
			(xy 257.989409 -256.811949) (xy 257.938754 -256.826256) (xy 257.886611 -256.833456) (xy 257.860292 -256.833878)
			(xy 257.833039 -256.833452) (xy 257.779088 -256.825694) (xy 257.72679 -256.810337) (xy 257.67721 -256.787693)
			(xy 257.631357 -256.758224) (xy 257.590164 -256.72253) (xy 257.554471 -256.681337) (xy 257.525003 -256.635483)
			(xy 257.502361 -256.585903) (xy 257.487005 -256.533604) (xy 257.479248 -256.479653) (xy 219.656475 -256.479653)
			(xy 219.643647 -256.522291) (xy 219.619975 -256.572788) (xy 219.589202 -256.619301) (xy 219.551985 -256.660838)
			(xy 219.509117 -256.696513) (xy 219.461511 -256.725567) (xy 219.410182 -256.747379) (xy 219.356225 -256.761485)
			(xy 219.300788 -256.767585) (xy 219.245054 -256.765548) (xy 219.190211 -256.755418) (xy 219.137427 -256.737411)
			(xy 219.087827 -256.71191) (xy 219.042469 -256.679459) (xy 219.00232 -256.64075) (xy 218.968234 -256.596607)
			(xy 218.940938 -256.547972) (xy 218.921015 -256.495881) (xy 218.908889 -256.441444) (xy 218.904818 -256.385822)
			(xy 216.851476 -256.385822) (xy 216.851522 -256.386077) (xy 216.852246 -256.420366) (xy 216.85176 -256.447617)
			(xy 216.844004 -256.501565) (xy 216.828649 -256.55386) (xy 216.806007 -256.603437) (xy 216.776541 -256.649287)
			(xy 216.74085 -256.690478) (xy 216.699659 -256.726169) (xy 216.653809 -256.755635) (xy 216.604232 -256.778277)
			(xy 216.551937 -256.793632) (xy 216.497989 -256.801388) (xy 216.443487 -256.801388) (xy 216.389539 -256.793632)
			(xy 216.337244 -256.778277) (xy 216.287667 -256.755635) (xy 216.241817 -256.726169) (xy 216.200626 -256.690478)
			(xy 216.164935 -256.649287) (xy 216.135469 -256.603437) (xy 216.112827 -256.55386) (xy 216.097472 -256.501565)
			(xy 216.089716 -256.447617) (xy 216.08923 -256.420366) (xy 216.089607 -256.39588) (xy 216.09588 -256.347311)
			(xy 216.108319 -256.299944) (xy 216.11717 -256.27711) (xy 216.121742 -256.26568) (xy 216.119964 -256.242312)
			(xy 216.065862 -256.151888) (xy 216.045796 -256.139188) (xy 216.033858 -256.137918) (xy 216.006102 -256.134531)
			(xy 215.951964 -256.120529) (xy 215.900448 -256.09878) (xy 215.852656 -256.069748) (xy 215.80961 -256.034056)
			(xy 215.772232 -255.992465) (xy 215.74132 -255.945867) (xy 215.717537 -255.895258) (xy 215.701391 -255.841721)
			(xy 215.693228 -255.786401) (xy 215.692736 -255.758442) (xy 200.685908 -255.758442) (xy 200.685399 -255.786328)
			(xy 200.677279 -255.841504) (xy 200.661211 -255.894911) (xy 200.637539 -255.945408) (xy 200.606766 -255.991921)
			(xy 200.569549 -256.033458) (xy 200.526681 -256.069133) (xy 200.479075 -256.098187) (xy 200.427746 -256.119999)
			(xy 200.373789 -256.134105) (xy 200.318352 -256.140205) (xy 200.262618 -256.138168) (xy 200.207775 -256.128038)
			(xy 200.154991 -256.110031) (xy 200.105391 -256.08453) (xy 200.060033 -256.052079) (xy 200.019884 -256.01337)
			(xy 199.985798 -255.969227) (xy 199.958502 -255.920592) (xy 199.938579 -255.868501) (xy 199.926453 -255.814064)
			(xy 199.922382 -255.758442) (xy 189.782051 -255.758442) (xy 189.78245 -255.780286) (xy 189.781941 -255.808172)
			(xy 189.773821 -255.863348) (xy 189.757753 -255.916755) (xy 189.734081 -255.967252) (xy 189.703308 -256.013765)
			(xy 189.666091 -256.055302) (xy 189.623223 -256.090977) (xy 189.575617 -256.120031) (xy 189.524288 -256.141843)
			(xy 189.470331 -256.155949) (xy 189.414894 -256.162049) (xy 189.35916 -256.160012) (xy 189.304317 -256.149882)
			(xy 189.251533 -256.131875) (xy 189.201933 -256.106374) (xy 189.156575 -256.073923) (xy 189.116426 -256.035214)
			(xy 189.08234 -255.991071) (xy 189.055044 -255.942436) (xy 189.035121 -255.890345) (xy 189.022995 -255.835908)
			(xy 189.018924 -255.780286) (xy 144.573824 -255.780286) (xy 144.586229 -255.787857) (xy 144.629097 -255.823532)
			(xy 144.666314 -255.865069) (xy 144.697087 -255.911582) (xy 144.720759 -255.962079) (xy 144.736827 -256.015486)
			(xy 144.744947 -256.070662) (xy 144.745456 -256.098548) (xy 144.744947 -256.126434) (xy 144.736827 -256.18161)
			(xy 144.720759 -256.235017) (xy 144.697087 -256.285514) (xy 144.666314 -256.332027) (xy 144.629097 -256.373564)
			(xy 144.626271 -256.375916) (xy 144.86966 -256.375916) (xy 144.873731 -256.320294) (xy 144.885857 -256.265857)
			(xy 144.90578 -256.213766) (xy 144.933076 -256.165131) (xy 144.967162 -256.120988) (xy 145.007311 -256.082279)
			(xy 145.052669 -256.049828) (xy 145.102269 -256.024327) (xy 145.155053 -256.00632) (xy 145.209896 -255.99619)
			(xy 145.26563 -255.994153) (xy 145.321067 -256.000253) (xy 145.375024 -256.014359) (xy 145.426353 -256.036171)
			(xy 145.473959 -256.065225) (xy 145.516827 -256.1009) (xy 145.554044 -256.142437) (xy 145.584817 -256.18895)
			(xy 145.608489 -256.239447) (xy 145.624557 -256.292854) (xy 145.632677 -256.34803) (xy 145.633186 -256.375916)
			(xy 146.345146 -256.375916) (xy 146.349217 -256.320294) (xy 146.361343 -256.265857) (xy 146.381266 -256.213766)
			(xy 146.408562 -256.165131) (xy 146.442648 -256.120988) (xy 146.482797 -256.082279) (xy 146.528155 -256.049828)
			(xy 146.577755 -256.024327) (xy 146.630539 -256.00632) (xy 146.685382 -255.99619) (xy 146.741116 -255.994153)
			(xy 146.796553 -256.000253) (xy 146.85051 -256.014359) (xy 146.901839 -256.036171) (xy 146.949445 -256.065225)
			(xy 146.992313 -256.1009) (xy 147.02953 -256.142437) (xy 147.060303 -256.18895) (xy 147.083975 -256.239447)
			(xy 147.100043 -256.292854) (xy 147.108163 -256.34803) (xy 147.108672 -256.375916) (xy 147.234146 -256.375916)
			(xy 147.238217 -256.320294) (xy 147.250343 -256.265857) (xy 147.270266 -256.213766) (xy 147.297562 -256.165131)
			(xy 147.331648 -256.120988) (xy 147.371797 -256.082279) (xy 147.417155 -256.049828) (xy 147.466755 -256.024327)
			(xy 147.519539 -256.00632) (xy 147.574382 -255.99619) (xy 147.630116 -255.994153) (xy 147.685553 -256.000253)
			(xy 147.73951 -256.014359) (xy 147.790839 -256.036171) (xy 147.838445 -256.065225) (xy 147.881313 -256.1009)
			(xy 147.91853 -256.142437) (xy 147.949303 -256.18895) (xy 147.972975 -256.239447) (xy 147.989043 -256.292854)
			(xy 147.997163 -256.34803) (xy 147.997672 -256.375916) (xy 147.997163 -256.403802) (xy 147.989043 -256.458978)
			(xy 147.972975 -256.512385) (xy 147.949303 -256.562882) (xy 147.91853 -256.609395) (xy 147.881313 -256.650932)
			(xy 147.838445 -256.686607) (xy 147.790839 -256.715661) (xy 147.73951 -256.737473) (xy 147.685553 -256.751579)
			(xy 147.630116 -256.757679) (xy 147.574382 -256.755642) (xy 147.519539 -256.745512) (xy 147.466755 -256.727505)
			(xy 147.417155 -256.702004) (xy 147.371797 -256.669553) (xy 147.331648 -256.630844) (xy 147.297562 -256.586701)
			(xy 147.270266 -256.538066) (xy 147.250343 -256.485975) (xy 147.238217 -256.431538) (xy 147.234146 -256.375916)
			(xy 147.108672 -256.375916) (xy 147.108163 -256.403802) (xy 147.100043 -256.458978) (xy 147.083975 -256.512385)
			(xy 147.060303 -256.562882) (xy 147.02953 -256.609395) (xy 146.992313 -256.650932) (xy 146.949445 -256.686607)
			(xy 146.901839 -256.715661) (xy 146.85051 -256.737473) (xy 146.796553 -256.751579) (xy 146.741116 -256.757679)
			(xy 146.685382 -256.755642) (xy 146.630539 -256.745512) (xy 146.577755 -256.727505) (xy 146.528155 -256.702004)
			(xy 146.482797 -256.669553) (xy 146.442648 -256.630844) (xy 146.408562 -256.586701) (xy 146.381266 -256.538066)
			(xy 146.361343 -256.485975) (xy 146.349217 -256.431538) (xy 146.345146 -256.375916) (xy 145.633186 -256.375916)
			(xy 145.632677 -256.403802) (xy 145.624557 -256.458978) (xy 145.608489 -256.512385) (xy 145.584817 -256.562882)
			(xy 145.554044 -256.609395) (xy 145.516827 -256.650932) (xy 145.473959 -256.686607) (xy 145.426353 -256.715661)
			(xy 145.375024 -256.737473) (xy 145.321067 -256.751579) (xy 145.26563 -256.757679) (xy 145.209896 -256.755642)
			(xy 145.155053 -256.745512) (xy 145.102269 -256.727505) (xy 145.052669 -256.702004) (xy 145.007311 -256.669553)
			(xy 144.967162 -256.630844) (xy 144.933076 -256.586701) (xy 144.90578 -256.538066) (xy 144.885857 -256.485975)
			(xy 144.873731 -256.431538) (xy 144.86966 -256.375916) (xy 144.626271 -256.375916) (xy 144.586229 -256.409239)
			(xy 144.538623 -256.438293) (xy 144.487294 -256.460105) (xy 144.433337 -256.474211) (xy 144.3779 -256.480311)
			(xy 144.322166 -256.478274) (xy 144.267323 -256.468144) (xy 144.214539 -256.450137) (xy 144.164939 -256.424636)
			(xy 144.119581 -256.392185) (xy 144.079432 -256.353476) (xy 144.045346 -256.309333) (xy 144.01805 -256.260698)
			(xy 143.998127 -256.208607) (xy 143.986001 -256.15417) (xy 143.98193 -256.098548) (xy 142.613912 -256.098548)
			(xy 142.654685 -256.117173) (xy 142.700526 -256.146638) (xy 142.741707 -256.182327) (xy 142.777391 -256.223513)
			(xy 142.80685 -256.269357) (xy 142.829486 -256.318927) (xy 142.844837 -256.371214) (xy 142.852592 -256.425153)
			(xy 142.852592 -256.479647) (xy 142.844837 -256.533586) (xy 142.829486 -256.585873) (xy 142.80685 -256.635443)
			(xy 142.777391 -256.681287) (xy 142.741707 -256.722473) (xy 142.700526 -256.758162) (xy 142.654685 -256.787627)
			(xy 142.605118 -256.810269) (xy 142.552833 -256.825627) (xy 142.498895 -256.833389) (xy 142.471648 -256.833878)
			(xy 142.445331 -256.833446) (xy 142.393196 -256.826223) (xy 142.342547 -256.811906) (xy 142.294345 -256.790768)
			(xy 142.249504 -256.763208) (xy 142.208873 -256.72975) (xy 142.190724 -256.710688) (xy 142.183197 -256.703293)
			(xy 142.163921 -256.694765) (xy 142.153386 -256.694178) (xy 142.07871 -256.694178) (xy 142.06816 -256.694705)
			(xy 142.048865 -256.703242) (xy 142.041372 -256.710688) (xy 142.023249 -256.729779) (xy 141.982626 -256.763256)
			(xy 141.937783 -256.790825) (xy 141.889573 -256.811962) (xy 141.838914 -256.826264) (xy 141.786768 -256.833459)
			(xy 141.760448 -256.833878) (xy 141.733191 -256.833478) (xy 141.67923 -256.825726) (xy 141.626923 -256.810373)
			(xy 141.577332 -256.787732) (xy 141.53147 -256.758263) (xy 141.490268 -256.722566) (xy 141.454566 -256.681369)
			(xy 141.425091 -256.63551) (xy 141.402444 -256.585923) (xy 141.387084 -256.533617) (xy 141.379325 -256.479657)
			(xy 128.952556 -256.479657) (xy 128.932913 -256.50158) (xy 128.890045 -256.537255) (xy 128.842439 -256.566309)
			(xy 128.79111 -256.588121) (xy 128.737153 -256.602227) (xy 128.681716 -256.608327) (xy 128.625982 -256.60629)
			(xy 128.571139 -256.59616) (xy 128.518355 -256.578153) (xy 128.468755 -256.552652) (xy 128.423397 -256.520201)
			(xy 128.383248 -256.481492) (xy 128.349162 -256.437349) (xy 128.321866 -256.388714) (xy 128.301943 -256.336623)
			(xy 128.289817 -256.282186) (xy 128.285746 -256.226564) (xy 126.983998 -256.226564) (xy 126.983489 -256.25445)
			(xy 126.975369 -256.309626) (xy 126.959301 -256.363033) (xy 126.935629 -256.41353) (xy 126.904856 -256.460043)
			(xy 126.867639 -256.50158) (xy 126.824771 -256.537255) (xy 126.777165 -256.566309) (xy 126.725836 -256.588121)
			(xy 126.671879 -256.602227) (xy 126.616442 -256.608327) (xy 126.560708 -256.60629) (xy 126.505865 -256.59616)
			(xy 126.453081 -256.578153) (xy 126.403481 -256.552652) (xy 126.358123 -256.520201) (xy 126.317974 -256.481492)
			(xy 126.283888 -256.437349) (xy 126.256592 -256.388714) (xy 126.236669 -256.336623) (xy 126.224543 -256.282186)
			(xy 126.220472 -256.226564) (xy 97.522468 -256.226564) (xy 97.476292 -256.231645) (xy 97.420558 -256.229608)
			(xy 97.365715 -256.219478) (xy 97.312931 -256.201471) (xy 97.263331 -256.17597) (xy 97.217973 -256.143519)
			(xy 97.177824 -256.10481) (xy 97.143738 -256.060667) (xy 97.116442 -256.012032) (xy 97.096519 -255.959941)
			(xy 97.084393 -255.905504) (xy 97.080322 -255.849882) (xy 96.816859 -255.849882) (xy 96.774191 -255.877303)
			(xy 96.724614 -255.899945) (xy 96.672319 -255.9153) (xy 96.618371 -255.923056) (xy 96.563869 -255.923056)
			(xy 96.509921 -255.9153) (xy 96.457626 -255.899945) (xy 96.408049 -255.877303) (xy 96.362199 -255.847837)
			(xy 96.321008 -255.812146) (xy 96.285317 -255.770955) (xy 96.255851 -255.725105) (xy 96.233209 -255.675528)
			(xy 96.217854 -255.623233) (xy 96.210098 -255.569285) (xy 96.209612 -255.542034) (xy 96.210117 -255.512982)
			(xy 96.218909 -255.455547) (xy 96.236311 -255.40011) (xy 96.26192 -255.347955) (xy 96.295143 -255.300286)
			(xy 96.335212 -255.258208) (xy 96.381199 -255.222695) (xy 96.432041 -255.194567) (xy 96.486561 -255.174475)
			(xy 96.51492 -255.168146) (xy 96.528128 -255.165606) (xy 96.548194 -255.14808) (xy 96.586548 -255.041146)
			(xy 96.581976 -255.014984) (xy 96.573594 -255.00457) (xy 96.557511 -254.984092) (xy 96.530494 -254.939578)
			(xy 96.509782 -254.891803) (xy 96.49576 -254.841656) (xy 96.488688 -254.790068) (xy 96.48825 -254.764032)
			(xy 96.48952 -254.733298) (xy 96.490536 -254.720344) (xy 96.479614 -254.696214) (xy 96.389444 -254.629158)
			(xy 96.363536 -254.625602) (xy 96.351344 -254.630428) (xy 96.329167 -254.638696) (xy 96.283288 -254.65033)
			(xy 96.236325 -254.656214) (xy 96.21266 -254.65659) (xy 96.185413 -254.656079) (xy 96.131473 -254.648318)
			(xy 96.079187 -254.63296) (xy 96.029619 -254.610318) (xy 95.983777 -254.580851) (xy 95.942596 -254.545161)
			(xy 95.906912 -254.503974) (xy 95.877453 -254.458128) (xy 95.854819 -254.408556) (xy 95.839469 -254.356268)
			(xy 95.831717 -254.302327) (xy 40.899334 -254.302327) (xy 40.899334 -256.398776) (xy 96.403922 -256.398776)
			(xy 96.404408 -256.371525) (xy 96.412164 -256.317577) (xy 96.427519 -256.265282) (xy 96.450161 -256.215705)
			(xy 96.479627 -256.169855) (xy 96.515318 -256.128664) (xy 96.556509 -256.092973) (xy 96.602359 -256.063507)
			(xy 96.651936 -256.040865) (xy 96.704231 -256.02551) (xy 96.758179 -256.017754) (xy 96.812681 -256.017754)
			(xy 96.866629 -256.02551) (xy 96.918924 -256.040865) (xy 96.968501 -256.063507) (xy 97.014351 -256.092973)
			(xy 97.055542 -256.128664) (xy 97.091233 -256.169855) (xy 97.120699 -256.215705) (xy 97.143341 -256.265282)
			(xy 97.158696 -256.317577) (xy 97.166452 -256.371525) (xy 97.166938 -256.398776) (xy 97.16639 -256.427869)
			(xy 97.157545 -256.485378) (xy 97.140058 -256.540874) (xy 97.114334 -256.593065) (xy 97.098104 -256.617216)
			(xy 97.090768 -256.628449) (xy 97.081667 -256.653677) (xy 97.079451 -256.680405) (xy 97.084274 -256.706788)
			(xy 97.095802 -256.731003) (xy 97.11324 -256.75138) (xy 97.135384 -256.766511) (xy 97.160705 -256.775352)
			(xy 97.17405 -256.776728) (xy 97.202519 -256.779309) (xy 97.258266 -256.791956) (xy 97.311503 -256.812778)
			(xy 97.361037 -256.84131) (xy 97.40576 -256.876912) (xy 97.444671 -256.918788) (xy 97.476899 -256.966001)
			(xy 97.501722 -257.017494) (xy 97.518585 -257.072114) (xy 97.52711 -257.128638) (xy 97.527144 -257.13055)
			(xy 116.295422 -257.13055) (xy 116.299493 -257.074928) (xy 116.311619 -257.020491) (xy 116.331542 -256.9684)
			(xy 116.358838 -256.919765) (xy 116.392924 -256.875622) (xy 116.433073 -256.836913) (xy 116.478431 -256.804462)
			(xy 116.528031 -256.778961) (xy 116.580815 -256.760954) (xy 116.635658 -256.750824) (xy 116.691392 -256.748787)
			(xy 116.746829 -256.754887) (xy 116.800786 -256.768993) (xy 116.852115 -256.790805) (xy 116.899721 -256.819859)
			(xy 116.942589 -256.855534) (xy 116.956412 -256.870962) (xy 118.869712 -256.870962) (xy 118.873783 -256.81534)
			(xy 118.885909 -256.760903) (xy 118.905832 -256.708812) (xy 118.933128 -256.660177) (xy 118.967214 -256.616034)
			(xy 119.007363 -256.577325) (xy 119.052721 -256.544874) (xy 119.102321 -256.519373) (xy 119.155105 -256.501366)
			(xy 119.209948 -256.491236) (xy 119.265682 -256.489199) (xy 119.321119 -256.495299) (xy 119.375076 -256.509405)
			(xy 119.426405 -256.531217) (xy 119.474011 -256.560271) (xy 119.516879 -256.595946) (xy 119.554096 -256.637483)
			(xy 119.584869 -256.683996) (xy 119.608541 -256.734493) (xy 119.624609 -256.7879) (xy 119.632729 -256.843076)
			(xy 119.633238 -256.870962) (xy 120.393712 -256.870962) (xy 120.397783 -256.81534) (xy 120.409909 -256.760903)
			(xy 120.429832 -256.708812) (xy 120.457128 -256.660177) (xy 120.491214 -256.616034) (xy 120.531363 -256.577325)
			(xy 120.576721 -256.544874) (xy 120.626321 -256.519373) (xy 120.679105 -256.501366) (xy 120.733948 -256.491236)
			(xy 120.789682 -256.489199) (xy 120.845119 -256.495299) (xy 120.899076 -256.509405) (xy 120.950405 -256.531217)
			(xy 120.998011 -256.560271) (xy 121.040879 -256.595946) (xy 121.078096 -256.637483) (xy 121.108869 -256.683996)
			(xy 121.132541 -256.734493) (xy 121.148609 -256.7879) (xy 121.156729 -256.843076) (xy 121.157238 -256.870962)
			(xy 121.917712 -256.870962) (xy 121.921783 -256.81534) (xy 121.933909 -256.760903) (xy 121.953832 -256.708812)
			(xy 121.981128 -256.660177) (xy 122.015214 -256.616034) (xy 122.055363 -256.577325) (xy 122.100721 -256.544874)
			(xy 122.150321 -256.519373) (xy 122.203105 -256.501366) (xy 122.257948 -256.491236) (xy 122.313682 -256.489199)
			(xy 122.369119 -256.495299) (xy 122.423076 -256.509405) (xy 122.474405 -256.531217) (xy 122.522011 -256.560271)
			(xy 122.564879 -256.595946) (xy 122.602096 -256.637483) (xy 122.632869 -256.683996) (xy 122.656541 -256.734493)
			(xy 122.672609 -256.7879) (xy 122.680729 -256.843076) (xy 122.681238 -256.870962) (xy 122.680729 -256.898848)
			(xy 122.672609 -256.954024) (xy 122.656541 -257.007431) (xy 122.632869 -257.057928) (xy 122.602096 -257.104441)
			(xy 122.59213 -257.115564) (xy 128.285746 -257.115564) (xy 128.289817 -257.059942) (xy 128.301943 -257.005505)
			(xy 128.321866 -256.953414) (xy 128.349162 -256.904779) (xy 128.383248 -256.860636) (xy 128.423397 -256.821927)
			(xy 128.468755 -256.789476) (xy 128.518355 -256.763975) (xy 128.571139 -256.745968) (xy 128.625982 -256.735838)
			(xy 128.681716 -256.733801) (xy 128.737153 -256.739901) (xy 128.79111 -256.754007) (xy 128.842439 -256.775819)
			(xy 128.890045 -256.804873) (xy 128.932913 -256.840548) (xy 128.97013 -256.882085) (xy 129.000903 -256.928598)
			(xy 129.024575 -256.979095) (xy 129.027118 -256.987548) (xy 143.98193 -256.987548) (xy 143.986001 -256.931926)
			(xy 143.998127 -256.877489) (xy 144.01805 -256.825398) (xy 144.045346 -256.776763) (xy 144.079432 -256.73262)
			(xy 144.119581 -256.693911) (xy 144.164939 -256.66146) (xy 144.214539 -256.635959) (xy 144.267323 -256.617952)
			(xy 144.322166 -256.607822) (xy 144.3779 -256.605785) (xy 144.433337 -256.611885) (xy 144.487294 -256.625991)
			(xy 144.538623 -256.647803) (xy 144.586229 -256.676857) (xy 144.629097 -256.712532) (xy 144.666314 -256.754069)
			(xy 144.697087 -256.800582) (xy 144.720759 -256.851079) (xy 144.736827 -256.904486) (xy 144.744947 -256.959662)
			(xy 144.745456 -256.987548) (xy 144.744947 -257.015434) (xy 144.736827 -257.07061) (xy 144.720759 -257.124017)
			(xy 144.714243 -257.137916) (xy 150.396194 -257.137916) (xy 150.396746 -257.108534) (xy 150.405774 -257.050468)
			(xy 150.423604 -256.994474) (xy 150.449813 -256.941879) (xy 150.483782 -256.893927) (xy 150.524705 -256.851754)
			(xy 150.547832 -256.833624) (xy 150.55723 -256.826258) (xy 150.567644 -256.805684) (xy 150.569168 -256.701798)
			(xy 150.559262 -256.680716) (xy 150.550118 -256.67335) (xy 150.528267 -256.655147) (xy 150.489727 -256.613328)
			(xy 150.45782 -256.566252) (xy 150.433253 -256.514962) (xy 150.41657 -256.460593) (xy 150.408142 -256.404351)
			(xy 150.407624 -256.375916) (xy 150.40811 -256.348665) (xy 150.415866 -256.294717) (xy 150.431221 -256.242422)
			(xy 150.453863 -256.192845) (xy 150.483329 -256.146995) (xy 150.51902 -256.105804) (xy 150.560211 -256.070113)
			(xy 150.606061 -256.040647) (xy 150.655638 -256.018005) (xy 150.707933 -256.00265) (xy 150.761881 -255.994894)
			(xy 150.816383 -255.994894) (xy 150.870331 -256.00265) (xy 150.922626 -256.018005) (xy 150.972203 -256.040647)
			(xy 151.018053 -256.070113) (xy 151.059244 -256.105804) (xy 151.094935 -256.146995) (xy 151.124401 -256.192845)
			(xy 151.147043 -256.242422) (xy 151.162398 -256.294717) (xy 151.170154 -256.348665) (xy 151.17064 -256.375916)
			(xy 151.170098 -256.405298) (xy 151.161066 -256.463364) (xy 151.143233 -256.519357) (xy 151.117022 -256.571952)
			(xy 151.083052 -256.619904) (xy 151.042129 -256.662077) (xy 151.019002 -256.680208) (xy 151.009604 -256.687574)
			(xy 150.99919 -256.708148) (xy 150.997666 -256.812034) (xy 151.007572 -256.833116) (xy 151.016716 -256.840482)
			(xy 151.038541 -256.858714) (xy 151.077082 -256.900528) (xy 151.108991 -256.947598) (xy 151.133562 -256.998883)
			(xy 151.15025 -257.053245) (xy 151.158687 -257.109483) (xy 151.15921 -257.137916) (xy 151.792684 -257.137916)
			(xy 151.796755 -257.082294) (xy 151.808881 -257.027857) (xy 151.828804 -256.975766) (xy 151.8561 -256.927131)
			(xy 151.890186 -256.882988) (xy 151.930335 -256.844279) (xy 151.975693 -256.811828) (xy 152.025293 -256.786327)
			(xy 152.078077 -256.76832) (xy 152.13292 -256.75819) (xy 152.188654 -256.756153) (xy 152.244091 -256.762253)
			(xy 152.298048 -256.776359) (xy 152.349377 -256.798171) (xy 152.396983 -256.827225) (xy 152.439851 -256.8629)
			(xy 152.477068 -256.904437) (xy 152.507841 -256.95095) (xy 152.531513 -257.001447) (xy 152.547581 -257.054854)
			(xy 152.555701 -257.11003) (xy 152.55621 -257.137916) (xy 152.679144 -257.137916) (xy 152.683215 -257.082294)
			(xy 152.695341 -257.027857) (xy 152.715264 -256.975766) (xy 152.74256 -256.927131) (xy 152.776646 -256.882988)
			(xy 152.816795 -256.844279) (xy 152.862153 -256.811828) (xy 152.911753 -256.786327) (xy 152.964537 -256.76832)
			(xy 153.01938 -256.75819) (xy 153.075114 -256.756153) (xy 153.130551 -256.762253) (xy 153.184508 -256.776359)
			(xy 153.235837 -256.798171) (xy 153.283443 -256.827225) (xy 153.326311 -256.8629) (xy 153.363528 -256.904437)
			(xy 153.392314 -256.947947) (xy 213.216524 -256.947947) (xy 213.216524 -256.893453) (xy 213.224279 -256.839512)
			(xy 213.239632 -256.787225) (xy 213.26227 -256.737654) (xy 213.291732 -256.69181) (xy 213.327418 -256.650625)
			(xy 213.368602 -256.614938) (xy 213.414445 -256.585475) (xy 213.464015 -256.562836) (xy 213.516302 -256.547482)
			(xy 213.570243 -256.539725) (xy 213.59749 -256.539238) (xy 213.62595 -256.53978) (xy 213.68224 -256.548229)
			(xy 213.736647 -256.564955) (xy 213.787961 -256.589586) (xy 213.835042 -256.621575) (xy 213.876842 -256.66021)
			(xy 213.912432 -256.704631) (xy 213.927182 -256.728976) (xy 213.933532 -256.739898) (xy 213.954614 -256.753106)
			(xy 214.063326 -256.761234) (xy 214.085932 -256.751582) (xy 214.09406 -256.741676) (xy 214.10073 -256.733532)
			(xy 214.114835 -256.717902) (xy 214.122254 -256.710434) (xy 214.130636 -256.702052) (xy 214.138256 -256.680462)
			(xy 214.12708 -256.5781) (xy 214.114888 -256.558542) (xy 214.104982 -256.552192) (xy 214.082005 -256.53711)
			(xy 214.040184 -256.50145) (xy 214.003918 -256.460153) (xy 213.97396 -256.414076) (xy 213.950929 -256.364174)
			(xy 213.935305 -256.311482) (xy 213.927409 -256.257092) (xy 213.926928 -256.229612) (xy 213.927414 -256.202361)
			(xy 213.93517 -256.148413) (xy 213.950525 -256.096118) (xy 213.973167 -256.046541) (xy 214.002633 -256.000691)
			(xy 214.038324 -255.9595) (xy 214.079515 -255.923809) (xy 214.125365 -255.894343) (xy 214.174942 -255.871701)
			(xy 214.227237 -255.856346) (xy 214.281185 -255.84859) (xy 214.335687 -255.84859) (xy 214.389635 -255.856346)
			(xy 214.44193 -255.871701) (xy 214.491507 -255.894343) (xy 214.537357 -255.923809) (xy 214.578548 -255.9595)
			(xy 214.614239 -256.000691) (xy 214.643705 -256.046541) (xy 214.666347 -256.096118) (xy 214.681702 -256.148413)
			(xy 214.689458 -256.202361) (xy 214.689944 -256.229612) (xy 214.689381 -256.259772) (xy 214.679876 -256.319338)
			(xy 214.661119 -256.376667) (xy 214.633578 -256.430333) (xy 214.597938 -256.478998) (xy 214.576914 -256.50063)
			(xy 214.568532 -256.509012) (xy 214.560912 -256.530602) (xy 214.572088 -256.632964) (xy 214.58428 -256.652522)
			(xy 214.594186 -256.658872) (xy 214.617208 -256.673889) (xy 214.659025 -256.709562) (xy 214.695285 -256.750871)
			(xy 214.725237 -256.796959) (xy 214.74826 -256.846871) (xy 214.763877 -256.899572) (xy 214.771763 -256.953969)
			(xy 214.77224 -256.981452) (xy 214.772119 -256.987548) (xy 260.081774 -256.987548) (xy 260.085845 -256.931926)
			(xy 260.097971 -256.877489) (xy 260.117894 -256.825398) (xy 260.14519 -256.776763) (xy 260.179276 -256.73262)
			(xy 260.219425 -256.693911) (xy 260.264783 -256.66146) (xy 260.314383 -256.635959) (xy 260.367167 -256.617952)
			(xy 260.42201 -256.607822) (xy 260.477744 -256.605785) (xy 260.533181 -256.611885) (xy 260.587138 -256.625991)
			(xy 260.638467 -256.647803) (xy 260.686073 -256.676857) (xy 260.728941 -256.712532) (xy 260.766158 -256.754069)
			(xy 260.796931 -256.800582) (xy 260.820603 -256.851079) (xy 260.836671 -256.904486) (xy 260.844791 -256.959662)
			(xy 260.8453 -256.987548) (xy 260.844791 -257.015434) (xy 260.836671 -257.07061) (xy 260.820603 -257.124017)
			(xy 260.796931 -257.174514) (xy 260.766158 -257.221027) (xy 260.728941 -257.262564) (xy 260.686073 -257.298239)
			(xy 260.638467 -257.327293) (xy 260.587138 -257.349105) (xy 260.533181 -257.363211) (xy 260.477744 -257.369311)
			(xy 260.42201 -257.367274) (xy 260.367167 -257.357144) (xy 260.314383 -257.339137) (xy 260.264783 -257.313636)
			(xy 260.219425 -257.281185) (xy 260.179276 -257.242476) (xy 260.14519 -257.198333) (xy 260.117894 -257.149698)
			(xy 260.097971 -257.097607) (xy 260.085845 -257.04317) (xy 260.081774 -256.987548) (xy 214.772119 -256.987548)
			(xy 214.7717 -257.008702) (xy 214.763951 -257.062649) (xy 214.748602 -257.114943) (xy 214.725968 -257.164521)
			(xy 214.696508 -257.210373) (xy 214.660822 -257.251565) (xy 214.619637 -257.28726) (xy 214.573791 -257.316729)
			(xy 214.524218 -257.339374) (xy 214.471927 -257.354734) (xy 214.417982 -257.362494) (xy 214.390732 -257.36296)
			(xy 214.36227 -257.36248) (xy 214.305977 -257.35402) (xy 214.251569 -257.337283) (xy 214.200254 -257.312642)
			(xy 214.153174 -257.280643) (xy 214.111376 -257.242) (xy 214.075789 -257.197571) (xy 214.06104 -257.173222)
			(xy 214.05469 -257.1623) (xy 214.033608 -257.149092) (xy 213.924896 -257.140964) (xy 213.90229 -257.150616)
			(xy 213.894162 -257.160522) (xy 213.875924 -257.18222) (xy 213.834176 -257.220555) (xy 213.787215 -257.252291)
			(xy 213.736075 -257.276728) (xy 213.681882 -257.29333) (xy 213.625829 -257.30173) (xy 213.59749 -257.302254)
			(xy 213.570243 -257.301675) (xy 213.516302 -257.293918) (xy 213.464015 -257.278564) (xy 213.414445 -257.255925)
			(xy 213.368602 -257.226462) (xy 213.327418 -257.190775) (xy 213.291732 -257.14959) (xy 213.26227 -257.103746)
			(xy 213.239632 -257.054175) (xy 213.224279 -257.001888) (xy 213.216524 -256.947947) (xy 153.392314 -256.947947)
			(xy 153.394301 -256.95095) (xy 153.417973 -257.001447) (xy 153.434041 -257.054854) (xy 153.442161 -257.11003)
			(xy 153.44267 -257.137916) (xy 153.442161 -257.165802) (xy 153.434041 -257.220978) (xy 153.417973 -257.274385)
			(xy 153.394301 -257.324882) (xy 153.363528 -257.371395) (xy 153.326311 -257.412932) (xy 153.283443 -257.448607)
			(xy 153.235837 -257.477661) (xy 153.184508 -257.499473) (xy 153.130551 -257.513579) (xy 153.075114 -257.519679)
			(xy 153.01938 -257.517642) (xy 152.964537 -257.507512) (xy 152.911753 -257.489505) (xy 152.862153 -257.464004)
			(xy 152.816795 -257.431553) (xy 152.776646 -257.392844) (xy 152.74256 -257.348701) (xy 152.715264 -257.300066)
			(xy 152.695341 -257.247975) (xy 152.683215 -257.193538) (xy 152.679144 -257.137916) (xy 152.55621 -257.137916)
			(xy 152.555701 -257.165802) (xy 152.547581 -257.220978) (xy 152.531513 -257.274385) (xy 152.507841 -257.324882)
			(xy 152.477068 -257.371395) (xy 152.439851 -257.412932) (xy 152.396983 -257.448607) (xy 152.349377 -257.477661)
			(xy 152.298048 -257.499473) (xy 152.244091 -257.513579) (xy 152.188654 -257.519679) (xy 152.13292 -257.517642)
			(xy 152.078077 -257.507512) (xy 152.025293 -257.489505) (xy 151.975693 -257.464004) (xy 151.930335 -257.431553)
			(xy 151.890186 -257.392844) (xy 151.8561 -257.348701) (xy 151.828804 -257.300066) (xy 151.808881 -257.247975)
			(xy 151.796755 -257.193538) (xy 151.792684 -257.137916) (xy 151.15921 -257.137916) (xy 151.158724 -257.165167)
			(xy 151.150968 -257.219115) (xy 151.135613 -257.27141) (xy 151.112971 -257.320987) (xy 151.083505 -257.366837)
			(xy 151.047814 -257.408028) (xy 151.006623 -257.443719) (xy 150.960773 -257.473185) (xy 150.911196 -257.495827)
			(xy 150.858901 -257.511182) (xy 150.804953 -257.518938) (xy 150.750451 -257.518938) (xy 150.696503 -257.511182)
			(xy 150.644208 -257.495827) (xy 150.594631 -257.473185) (xy 150.548781 -257.443719) (xy 150.50759 -257.408028)
			(xy 150.471899 -257.366837) (xy 150.442433 -257.320987) (xy 150.419791 -257.27141) (xy 150.404436 -257.219115)
			(xy 150.39668 -257.165167) (xy 150.396194 -257.137916) (xy 144.714243 -257.137916) (xy 144.697087 -257.174514)
			(xy 144.666314 -257.221027) (xy 144.629097 -257.262564) (xy 144.586229 -257.298239) (xy 144.538623 -257.327293)
			(xy 144.487294 -257.349105) (xy 144.433337 -257.363211) (xy 144.3779 -257.369311) (xy 144.322166 -257.367274)
			(xy 144.267323 -257.357144) (xy 144.214539 -257.339137) (xy 144.164939 -257.313636) (xy 144.119581 -257.281185)
			(xy 144.079432 -257.242476) (xy 144.045346 -257.198333) (xy 144.01805 -257.149698) (xy 143.998127 -257.097607)
			(xy 143.986001 -257.04317) (xy 143.98193 -256.987548) (xy 129.027118 -256.987548) (xy 129.040643 -257.032502)
			(xy 129.048763 -257.087678) (xy 129.049272 -257.115564) (xy 129.048763 -257.14345) (xy 129.040643 -257.198626)
			(xy 129.024575 -257.252033) (xy 129.000903 -257.30253) (xy 128.97013 -257.349043) (xy 128.932913 -257.39058)
			(xy 128.890045 -257.426255) (xy 128.842439 -257.455309) (xy 128.797956 -257.474212) (xy 138.071858 -257.474212)
			(xy 138.075929 -257.41859) (xy 138.088055 -257.364153) (xy 138.107978 -257.312062) (xy 138.135274 -257.263427)
			(xy 138.16936 -257.219284) (xy 138.209509 -257.180575) (xy 138.254867 -257.148124) (xy 138.304467 -257.122623)
			(xy 138.357251 -257.104616) (xy 138.412094 -257.094486) (xy 138.467828 -257.092449) (xy 138.523265 -257.098549)
			(xy 138.577222 -257.112655) (xy 138.628551 -257.134467) (xy 138.676157 -257.163521) (xy 138.719025 -257.199196)
			(xy 138.756242 -257.240733) (xy 138.787015 -257.287246) (xy 138.810687 -257.337743) (xy 138.826755 -257.39115)
			(xy 138.834875 -257.446326) (xy 138.835384 -257.474212) (xy 138.834875 -257.502098) (xy 138.826755 -257.557274)
			(xy 138.810687 -257.610681) (xy 138.787015 -257.661178) (xy 138.756242 -257.707691) (xy 138.719025 -257.749228)
			(xy 138.676157 -257.784903) (xy 138.628551 -257.813957) (xy 138.577222 -257.835769) (xy 138.523265 -257.849875)
			(xy 138.467828 -257.855975) (xy 138.412094 -257.853938) (xy 138.357251 -257.843808) (xy 138.304467 -257.825801)
			(xy 138.254867 -257.8003) (xy 138.209509 -257.767849) (xy 138.16936 -257.72914) (xy 138.135274 -257.684997)
			(xy 138.107978 -257.636362) (xy 138.088055 -257.584271) (xy 138.075929 -257.529834) (xy 138.071858 -257.474212)
			(xy 128.797956 -257.474212) (xy 128.79111 -257.477121) (xy 128.737153 -257.491227) (xy 128.681716 -257.497327)
			(xy 128.625982 -257.49529) (xy 128.571139 -257.48516) (xy 128.518355 -257.467153) (xy 128.468755 -257.441652)
			(xy 128.423397 -257.409201) (xy 128.383248 -257.370492) (xy 128.349162 -257.326349) (xy 128.321866 -257.277714)
			(xy 128.301943 -257.225623) (xy 128.289817 -257.171186) (xy 128.285746 -257.115564) (xy 122.59213 -257.115564)
			(xy 122.564879 -257.145978) (xy 122.522011 -257.181653) (xy 122.474405 -257.210707) (xy 122.423076 -257.232519)
			(xy 122.369119 -257.246625) (xy 122.313682 -257.252725) (xy 122.257948 -257.250688) (xy 122.203105 -257.240558)
			(xy 122.150321 -257.222551) (xy 122.100721 -257.19705) (xy 122.055363 -257.164599) (xy 122.015214 -257.12589)
			(xy 121.981128 -257.081747) (xy 121.953832 -257.033112) (xy 121.933909 -256.981021) (xy 121.921783 -256.926584)
			(xy 121.917712 -256.870962) (xy 121.157238 -256.870962) (xy 121.156729 -256.898848) (xy 121.148609 -256.954024)
			(xy 121.132541 -257.007431) (xy 121.108869 -257.057928) (xy 121.078096 -257.104441) (xy 121.040879 -257.145978)
			(xy 120.998011 -257.181653) (xy 120.950405 -257.210707) (xy 120.899076 -257.232519) (xy 120.845119 -257.246625)
			(xy 120.789682 -257.252725) (xy 120.733948 -257.250688) (xy 120.679105 -257.240558) (xy 120.626321 -257.222551)
			(xy 120.576721 -257.19705) (xy 120.531363 -257.164599) (xy 120.491214 -257.12589) (xy 120.457128 -257.081747)
			(xy 120.429832 -257.033112) (xy 120.409909 -256.981021) (xy 120.397783 -256.926584) (xy 120.393712 -256.870962)
			(xy 119.633238 -256.870962) (xy 119.632729 -256.898848) (xy 119.624609 -256.954024) (xy 119.608541 -257.007431)
			(xy 119.584869 -257.057928) (xy 119.554096 -257.104441) (xy 119.516879 -257.145978) (xy 119.474011 -257.181653)
			(xy 119.426405 -257.210707) (xy 119.375076 -257.232519) (xy 119.321119 -257.246625) (xy 119.265682 -257.252725)
			(xy 119.209948 -257.250688) (xy 119.155105 -257.240558) (xy 119.102321 -257.222551) (xy 119.052721 -257.19705)
			(xy 119.007363 -257.164599) (xy 118.967214 -257.12589) (xy 118.933128 -257.081747) (xy 118.905832 -257.033112)
			(xy 118.885909 -256.981021) (xy 118.873783 -256.926584) (xy 118.869712 -256.870962) (xy 116.956412 -256.870962)
			(xy 116.979806 -256.897071) (xy 117.010579 -256.943584) (xy 117.034251 -256.994081) (xy 117.050319 -257.047488)
			(xy 117.058439 -257.102664) (xy 117.058948 -257.13055) (xy 117.058439 -257.158436) (xy 117.050319 -257.213612)
			(xy 117.034251 -257.267019) (xy 117.010579 -257.317516) (xy 116.979806 -257.364029) (xy 116.942589 -257.405566)
			(xy 116.899721 -257.441241) (xy 116.852115 -257.470295) (xy 116.800786 -257.492107) (xy 116.746829 -257.506213)
			(xy 116.691392 -257.512313) (xy 116.635658 -257.510276) (xy 116.580815 -257.500146) (xy 116.528031 -257.482139)
			(xy 116.478431 -257.456638) (xy 116.433073 -257.424187) (xy 116.392924 -257.385478) (xy 116.358838 -257.341335)
			(xy 116.331542 -257.2927) (xy 116.311619 -257.240609) (xy 116.299493 -257.186172) (xy 116.295422 -257.13055)
			(xy 97.527144 -257.13055) (xy 97.527618 -257.15722) (xy 97.527132 -257.184471) (xy 97.519376 -257.238419)
			(xy 97.504021 -257.290714) (xy 97.481379 -257.340291) (xy 97.451913 -257.386141) (xy 97.416222 -257.427332)
			(xy 97.375031 -257.463023) (xy 97.329181 -257.492489) (xy 97.279604 -257.515131) (xy 97.227309 -257.530486)
			(xy 97.173361 -257.538242) (xy 97.118859 -257.538242) (xy 97.064911 -257.530486) (xy 97.012616 -257.515131)
			(xy 96.963039 -257.492489) (xy 96.917189 -257.463023) (xy 96.875998 -257.427332) (xy 96.840307 -257.386141)
			(xy 96.810841 -257.340291) (xy 96.788199 -257.290714) (xy 96.772844 -257.238419) (xy 96.765088 -257.184471)
			(xy 96.764602 -257.15722) (xy 96.765141 -257.128127) (xy 96.773987 -257.070616) (xy 96.791477 -257.015121)
			(xy 96.817204 -256.962931) (xy 96.833436 -256.93878) (xy 96.840749 -256.927535) (xy 96.849843 -256.902311)
			(xy 96.852056 -256.875589) (xy 96.847233 -256.849213) (xy 96.835709 -256.825002) (xy 96.818278 -256.804628)
			(xy 96.796143 -256.789495) (xy 96.770832 -256.780649) (xy 96.75749 -256.779268) (xy 96.729024 -256.776657)
			(xy 96.673277 -256.764016) (xy 96.62004 -256.743199) (xy 96.570506 -256.714671) (xy 96.525782 -256.679072)
			(xy 96.48687 -256.637199) (xy 96.454642 -256.589988) (xy 96.429818 -256.538498) (xy 96.412955 -256.48388)
			(xy 96.404429 -256.427357) (xy 96.403922 -256.398776) (xy 40.899334 -256.398776) (xy 40.899334 -258.55803)
			(xy 84.450172 -258.55803) (xy 84.454243 -258.502408) (xy 84.466369 -258.447971) (xy 84.486292 -258.39588)
			(xy 84.513588 -258.347245) (xy 84.547674 -258.303102) (xy 84.587823 -258.264393) (xy 84.633181 -258.231942)
			(xy 84.682781 -258.206441) (xy 84.735565 -258.188434) (xy 84.790408 -258.178304) (xy 84.846142 -258.176267)
			(xy 84.901579 -258.182367) (xy 84.955536 -258.196473) (xy 85.006865 -258.218285) (xy 85.054471 -258.247339)
			(xy 85.097339 -258.283014) (xy 85.134556 -258.324551) (xy 85.165329 -258.371064) (xy 85.189001 -258.421561)
			(xy 85.205069 -258.474968) (xy 85.213189 -258.530144) (xy 85.213698 -258.55803) (xy 85.213189 -258.585916)
			(xy 85.205069 -258.641092) (xy 85.203389 -258.646676) (xy 85.359238 -258.646676) (xy 85.363309 -258.591054)
			(xy 85.375435 -258.536617) (xy 85.395358 -258.484526) (xy 85.422654 -258.435891) (xy 85.45674 -258.391748)
			(xy 85.496889 -258.353039) (xy 85.542247 -258.320588) (xy 85.591847 -258.295087) (xy 85.644631 -258.27708)
			(xy 85.699474 -258.26695) (xy 85.755208 -258.264913) (xy 85.810645 -258.271013) (xy 85.864602 -258.285119)
			(xy 85.915931 -258.306931) (xy 85.963537 -258.335985) (xy 86.006405 -258.37166) (xy 86.043622 -258.413197)
			(xy 86.074395 -258.45971) (xy 86.098067 -258.510207) (xy 86.114135 -258.563614) (xy 86.117462 -258.586224)
			(xy 86.25154 -258.586224) (xy 86.255611 -258.530602) (xy 86.267737 -258.476165) (xy 86.28766 -258.424074)
			(xy 86.314956 -258.375439) (xy 86.349042 -258.331296) (xy 86.389191 -258.292587) (xy 86.434549 -258.260136)
			(xy 86.484149 -258.234635) (xy 86.536933 -258.216628) (xy 86.591776 -258.206498) (xy 86.64751 -258.204461)
			(xy 86.702947 -258.210561) (xy 86.756904 -258.224667) (xy 86.808233 -258.246479) (xy 86.855839 -258.275533)
			(xy 86.898707 -258.311208) (xy 86.935924 -258.352745) (xy 86.966697 -258.399258) (xy 86.990369 -258.449755)
			(xy 87.006437 -258.503162) (xy 87.014557 -258.558338) (xy 87.015066 -258.586224) (xy 87.014557 -258.61411)
			(xy 87.006437 -258.669286) (xy 86.990369 -258.722693) (xy 86.966697 -258.77319) (xy 86.935924 -258.819703)
			(xy 86.898707 -258.86124) (xy 86.855839 -258.896915) (xy 86.81222 -258.923536) (xy 108.0897 -258.923536)
			(xy 108.090164 -258.896092) (xy 108.098019 -258.841769) (xy 108.113586 -258.789134) (xy 108.136543 -258.739277)
			(xy 108.166414 -258.693229) (xy 108.202583 -258.651943) (xy 108.2443 -258.616273) (xy 108.267246 -258.60121)
			(xy 108.278168 -258.594098) (xy 108.290868 -258.571492) (xy 108.29163 -258.46024) (xy 108.279438 -258.43738)
			(xy 108.26877 -258.430268) (xy 108.24645 -258.415055) (xy 108.205883 -258.379395) (xy 108.170755 -258.338366)
			(xy 108.141768 -258.292791) (xy 108.119503 -258.243581) (xy 108.104405 -258.191721) (xy 108.096776 -258.13825)
			(xy 108.096304 -258.111244) (xy 108.096796 -258.083992) (xy 108.104548 -258.030041) (xy 108.119899 -257.977743)
			(xy 108.142537 -257.928162) (xy 108.172001 -257.882308) (xy 108.207692 -257.841115) (xy 108.248883 -257.805421)
			(xy 108.294734 -257.775952) (xy 108.344313 -257.75331) (xy 108.39661 -257.737954) (xy 108.45056 -257.730199)
			(xy 108.477812 -257.729736) (xy 108.504128 -257.73019) (xy 108.556263 -257.737408) (xy 108.606911 -257.75172)
			(xy 108.655113 -257.772855) (xy 108.699955 -257.80041) (xy 108.740587 -257.833865) (xy 108.758736 -257.852926)
			(xy 108.766252 -257.860335) (xy 108.785536 -257.868858) (xy 108.796074 -257.869436) (xy 108.87075 -257.869436)
			(xy 108.881297 -257.868883) (xy 108.900591 -257.860363) (xy 108.908088 -257.852926) (xy 108.926234 -257.833857)
			(xy 108.966851 -257.800377) (xy 109.011689 -257.772805) (xy 109.059895 -257.751664) (xy 109.11055 -257.737358)
			(xy 109.162693 -257.730158) (xy 109.189012 -257.729736) (xy 109.215328 -257.73019) (xy 109.267463 -257.737408)
			(xy 109.318111 -257.75172) (xy 109.366313 -257.772855) (xy 109.411155 -257.80041) (xy 109.451787 -257.833865)
			(xy 109.469936 -257.852926) (xy 109.477452 -257.860335) (xy 109.496736 -257.868858) (xy 109.507274 -257.869436)
			(xy 109.58195 -257.869436) (xy 109.592497 -257.868883) (xy 109.611791 -257.860363) (xy 109.619288 -257.852926)
			(xy 109.637434 -257.833857) (xy 109.678051 -257.800377) (xy 109.722889 -257.772805) (xy 109.771095 -257.751664)
			(xy 109.82175 -257.737358) (xy 109.873893 -257.730158) (xy 109.900212 -257.729736) (xy 109.927467 -257.730144)
			(xy 109.981422 -257.737904) (xy 110.033724 -257.753263) (xy 110.083307 -257.775911) (xy 110.129162 -257.805384)
			(xy 110.170356 -257.841083) (xy 110.20605 -257.882282) (xy 110.235516 -257.928142) (xy 110.258156 -257.977728)
			(xy 110.270431 -258.01955) (xy 116.422932 -258.01955) (xy 116.423402 -257.992297) (xy 116.431153 -257.938344)
			(xy 116.446505 -257.886044) (xy 116.469144 -257.836461) (xy 116.498611 -257.790606) (xy 116.534304 -257.749411)
			(xy 116.575498 -257.713717) (xy 116.621352 -257.684249) (xy 116.670934 -257.661608) (xy 116.723234 -257.646255)
			(xy 116.777187 -257.638503) (xy 116.80444 -257.638042) (xy 116.831497 -257.638464) (xy 116.885066 -257.646128)
			(xy 116.937014 -257.661283) (xy 116.986301 -257.683624) (xy 117.031938 -257.712704) (xy 117.073009 -257.747939)
			(xy 117.108691 -257.788623) (xy 117.138267 -257.833939) (xy 117.150134 -257.85826) (xy 117.154198 -257.866642)
			(xy 117.167406 -257.879596) (xy 117.246908 -257.913886) (xy 117.26545 -257.914648) (xy 117.27434 -257.9116)
			(xy 117.30367 -257.902497) (xy 117.364286 -257.892662) (xy 117.39499 -257.892042) (xy 117.422247 -257.892404)
			(xy 117.476206 -257.900161) (xy 117.528512 -257.915518) (xy 117.5781 -257.938163) (xy 117.62396 -257.967635)
			(xy 117.66516 -258.003333) (xy 117.700859 -258.044532) (xy 117.730332 -258.090391) (xy 117.752978 -258.139979)
			(xy 117.768337 -258.192284) (xy 117.776095 -258.246243) (xy 117.776095 -258.300757) (xy 117.768337 -258.354716)
			(xy 117.756519 -258.394962) (xy 118.869712 -258.394962) (xy 118.873783 -258.33934) (xy 118.885909 -258.284903)
			(xy 118.905832 -258.232812) (xy 118.933128 -258.184177) (xy 118.967214 -258.140034) (xy 119.007363 -258.101325)
			(xy 119.052721 -258.068874) (xy 119.102321 -258.043373) (xy 119.155105 -258.025366) (xy 119.209948 -258.015236)
			(xy 119.265682 -258.013199) (xy 119.321119 -258.019299) (xy 119.375076 -258.033405) (xy 119.426405 -258.055217)
			(xy 119.474011 -258.084271) (xy 119.516879 -258.119946) (xy 119.554096 -258.161483) (xy 119.584869 -258.207996)
			(xy 119.608541 -258.258493) (xy 119.624609 -258.3119) (xy 119.632729 -258.367076) (xy 119.633238 -258.394962)
			(xy 121.917712 -258.394962) (xy 121.921783 -258.33934) (xy 121.933909 -258.284903) (xy 121.953832 -258.232812)
			(xy 121.981128 -258.184177) (xy 122.015214 -258.140034) (xy 122.055363 -258.101325) (xy 122.100721 -258.068874)
			(xy 122.150321 -258.043373) (xy 122.203105 -258.025366) (xy 122.257948 -258.015236) (xy 122.313682 -258.013199)
			(xy 122.369119 -258.019299) (xy 122.423076 -258.033405) (xy 122.474405 -258.055217) (xy 122.522011 -258.084271)
			(xy 122.564879 -258.119946) (xy 122.575289 -258.131564) (xy 126.258572 -258.131564) (xy 126.262643 -258.075942)
			(xy 126.274769 -258.021505) (xy 126.294692 -257.969414) (xy 126.321988 -257.920779) (xy 126.356074 -257.876636)
			(xy 126.396223 -257.837927) (xy 126.441581 -257.805476) (xy 126.491181 -257.779975) (xy 126.543965 -257.761968)
			(xy 126.598808 -257.751838) (xy 126.654542 -257.749801) (xy 126.709979 -257.755901) (xy 126.763936 -257.770007)
			(xy 126.815265 -257.791819) (xy 126.862871 -257.820873) (xy 126.905739 -257.856548) (xy 126.942956 -257.898085)
			(xy 126.973729 -257.944598) (xy 126.997401 -257.995095) (xy 127.013469 -258.048502) (xy 127.021589 -258.103678)
			(xy 127.022098 -258.131564) (xy 128.285746 -258.131564) (xy 128.289817 -258.075942) (xy 128.301943 -258.021505)
			(xy 128.321866 -257.969414) (xy 128.349162 -257.920779) (xy 128.383248 -257.876636) (xy 128.423397 -257.837927)
			(xy 128.468755 -257.805476) (xy 128.518355 -257.779975) (xy 128.571139 -257.761968) (xy 128.625982 -257.751838)
			(xy 128.681716 -257.749801) (xy 128.737153 -257.755901) (xy 128.79111 -257.770007) (xy 128.842439 -257.791819)
			(xy 128.890045 -257.820873) (xy 128.932913 -257.856548) (xy 128.97013 -257.898085) (xy 129.000903 -257.944598)
			(xy 129.024575 -257.995095) (xy 129.040643 -258.048502) (xy 129.048763 -258.103678) (xy 129.049272 -258.131564)
			(xy 130.317746 -258.131564) (xy 130.321817 -258.075942) (xy 130.333943 -258.021505) (xy 130.353866 -257.969414)
			(xy 130.381162 -257.920779) (xy 130.415248 -257.876636) (xy 130.455397 -257.837927) (xy 130.500755 -257.805476)
			(xy 130.550355 -257.779975) (xy 130.603139 -257.761968) (xy 130.657982 -257.751838) (xy 130.713716 -257.749801)
			(xy 130.769153 -257.755901) (xy 130.82311 -257.770007) (xy 130.874439 -257.791819) (xy 130.922045 -257.820873)
			(xy 130.964913 -257.856548) (xy 131.00213 -257.898085) (xy 131.032903 -257.944598) (xy 131.056575 -257.995095)
			(xy 131.072643 -258.048502) (xy 131.080763 -258.103678) (xy 131.081272 -258.131564) (xy 131.080763 -258.15945)
			(xy 131.072643 -258.214626) (xy 131.056575 -258.268033) (xy 131.032903 -258.31853) (xy 131.00213 -258.365043)
			(xy 130.964913 -258.40658) (xy 130.922045 -258.442255) (xy 130.874439 -258.471309) (xy 130.82311 -258.493121)
			(xy 130.769153 -258.507227) (xy 130.713716 -258.513327) (xy 130.657982 -258.51129) (xy 130.603139 -258.50116)
			(xy 130.550355 -258.483153) (xy 130.500755 -258.457652) (xy 130.455397 -258.425201) (xy 130.415248 -258.386492)
			(xy 130.381162 -258.342349) (xy 130.353866 -258.293714) (xy 130.333943 -258.241623) (xy 130.321817 -258.187186)
			(xy 130.317746 -258.131564) (xy 129.049272 -258.131564) (xy 129.048763 -258.15945) (xy 129.040643 -258.214626)
			(xy 129.024575 -258.268033) (xy 129.000903 -258.31853) (xy 128.97013 -258.365043) (xy 128.932913 -258.40658)
			(xy 128.890045 -258.442255) (xy 128.842439 -258.471309) (xy 128.79111 -258.493121) (xy 128.737153 -258.507227)
			(xy 128.681716 -258.513327) (xy 128.625982 -258.51129) (xy 128.571139 -258.50116) (xy 128.518355 -258.483153)
			(xy 128.468755 -258.457652) (xy 128.423397 -258.425201) (xy 128.383248 -258.386492) (xy 128.349162 -258.342349)
			(xy 128.321866 -258.293714) (xy 128.301943 -258.241623) (xy 128.289817 -258.187186) (xy 128.285746 -258.131564)
			(xy 127.022098 -258.131564) (xy 127.021589 -258.15945) (xy 127.013469 -258.214626) (xy 126.997401 -258.268033)
			(xy 126.973729 -258.31853) (xy 126.942956 -258.365043) (xy 126.905739 -258.40658) (xy 126.862871 -258.442255)
			(xy 126.815265 -258.471309) (xy 126.763936 -258.493121) (xy 126.709979 -258.507227) (xy 126.654542 -258.513327)
			(xy 126.598808 -258.51129) (xy 126.543965 -258.50116) (xy 126.491181 -258.483153) (xy 126.441581 -258.457652)
			(xy 126.396223 -258.425201) (xy 126.356074 -258.386492) (xy 126.321988 -258.342349) (xy 126.294692 -258.293714)
			(xy 126.274769 -258.241623) (xy 126.262643 -258.187186) (xy 126.258572 -258.131564) (xy 122.575289 -258.131564)
			(xy 122.602096 -258.161483) (xy 122.632869 -258.207996) (xy 122.656541 -258.258493) (xy 122.672609 -258.3119)
			(xy 122.680729 -258.367076) (xy 122.681238 -258.394962) (xy 122.680729 -258.422848) (xy 122.672609 -258.478024)
			(xy 122.656541 -258.531431) (xy 122.632869 -258.581928) (xy 122.602096 -258.628441) (xy 122.568916 -258.665472)
			(xy 137.226546 -258.665472) (xy 137.230617 -258.60985) (xy 137.242743 -258.555413) (xy 137.262666 -258.503322)
			(xy 137.289962 -258.454687) (xy 137.324048 -258.410544) (xy 137.364197 -258.371835) (xy 137.409555 -258.339384)
			(xy 137.459155 -258.313883) (xy 137.511939 -258.295876) (xy 137.566782 -258.285746) (xy 137.622516 -258.283709)
			(xy 137.677953 -258.289809) (xy 137.73191 -258.303915) (xy 137.783239 -258.325727) (xy 137.830845 -258.354781)
			(xy 137.873713 -258.390456) (xy 137.91093 -258.431993) (xy 137.941703 -258.478506) (xy 137.965375 -258.529003)
			(xy 137.981443 -258.58241) (xy 137.989563 -258.637586) (xy 137.989789 -258.649978) (xy 139.02639 -258.649978)
			(xy 139.030461 -258.594356) (xy 139.042587 -258.539919) (xy 139.06251 -258.487828) (xy 139.089806 -258.439193)
			(xy 139.123892 -258.39505) (xy 139.164041 -258.356341) (xy 139.209399 -258.32389) (xy 139.258999 -258.298389)
			(xy 139.311783 -258.280382) (xy 139.366626 -258.270252) (xy 139.42236 -258.268215) (xy 139.475461 -258.274058)
			(xy 144.86966 -258.274058) (xy 144.873731 -258.218436) (xy 144.885857 -258.163999) (xy 144.90578 -258.111908)
			(xy 144.933076 -258.063273) (xy 144.967162 -258.01913) (xy 145.007311 -257.980421) (xy 145.052669 -257.94797)
			(xy 145.102269 -257.922469) (xy 145.155053 -257.904462) (xy 145.209896 -257.894332) (xy 145.26563 -257.892295)
			(xy 145.321067 -257.898395) (xy 145.375024 -257.912501) (xy 145.426353 -257.934313) (xy 145.473959 -257.963367)
			(xy 145.516827 -257.999042) (xy 145.554044 -258.040579) (xy 145.584817 -258.087092) (xy 145.608489 -258.137589)
			(xy 145.624557 -258.190996) (xy 145.632677 -258.246172) (xy 145.633186 -258.274058) (xy 146.354798 -258.274058)
			(xy 146.358869 -258.218436) (xy 146.370995 -258.163999) (xy 146.390918 -258.111908) (xy 146.418214 -258.063273)
			(xy 146.4523 -258.01913) (xy 146.492449 -257.980421) (xy 146.537807 -257.94797) (xy 146.587407 -257.922469)
			(xy 146.640191 -257.904462) (xy 146.695034 -257.894332) (xy 146.750768 -257.892295) (xy 146.806205 -257.898395)
			(xy 146.860162 -257.912501) (xy 146.911491 -257.934313) (xy 146.959097 -257.963367) (xy 147.001965 -257.999042)
			(xy 147.039182 -258.040579) (xy 147.069955 -258.087092) (xy 147.093627 -258.137589) (xy 147.109695 -258.190996)
			(xy 147.117815 -258.246172) (xy 147.118324 -258.274058) (xy 147.117815 -258.301944) (xy 147.109695 -258.35712)
			(xy 147.093627 -258.410527) (xy 147.069955 -258.461024) (xy 147.039182 -258.507537) (xy 147.001965 -258.549074)
			(xy 146.959097 -258.584749) (xy 146.911491 -258.613803) (xy 146.860162 -258.635615) (xy 146.806205 -258.649721)
			(xy 146.750768 -258.655821) (xy 146.695034 -258.653784) (xy 146.640191 -258.643654) (xy 146.587407 -258.625647)
			(xy 146.537807 -258.600146) (xy 146.492449 -258.567695) (xy 146.4523 -258.528986) (xy 146.418214 -258.484843)
			(xy 146.390918 -258.436208) (xy 146.370995 -258.384117) (xy 146.358869 -258.32968) (xy 146.354798 -258.274058)
			(xy 145.633186 -258.274058) (xy 145.632677 -258.301944) (xy 145.624557 -258.35712) (xy 145.608489 -258.410527)
			(xy 145.584817 -258.461024) (xy 145.554044 -258.507537) (xy 145.516827 -258.549074) (xy 145.473959 -258.584749)
			(xy 145.426353 -258.613803) (xy 145.375024 -258.635615) (xy 145.321067 -258.649721) (xy 145.26563 -258.655821)
			(xy 145.209896 -258.653784) (xy 145.155053 -258.643654) (xy 145.102269 -258.625647) (xy 145.052669 -258.600146)
			(xy 145.007311 -258.567695) (xy 144.967162 -258.528986) (xy 144.933076 -258.484843) (xy 144.90578 -258.436208)
			(xy 144.885857 -258.384117) (xy 144.873731 -258.32968) (xy 144.86966 -258.274058) (xy 139.475461 -258.274058)
			(xy 139.477797 -258.274315) (xy 139.531754 -258.288421) (xy 139.583083 -258.310233) (xy 139.630689 -258.339287)
			(xy 139.673557 -258.374962) (xy 139.710774 -258.416499) (xy 139.741547 -258.463012) (xy 139.765219 -258.513509)
			(xy 139.781287 -258.566916) (xy 139.789407 -258.622092) (xy 139.789916 -258.649978) (xy 139.789407 -258.677864)
			(xy 139.787455 -258.691126) (xy 140.510766 -258.691126) (xy 140.514837 -258.635504) (xy 140.526963 -258.581067)
			(xy 140.546886 -258.528976) (xy 140.574182 -258.480341) (xy 140.608268 -258.436198) (xy 140.648417 -258.397489)
			(xy 140.693775 -258.365038) (xy 140.743375 -258.339537) (xy 140.796159 -258.32153) (xy 140.851002 -258.3114)
			(xy 140.906736 -258.309363) (xy 140.962173 -258.315463) (xy 141.01613 -258.329569) (xy 141.067459 -258.351381)
			(xy 141.115065 -258.380435) (xy 141.157933 -258.41611) (xy 141.19515 -258.457647) (xy 141.225923 -258.50416)
			(xy 141.249595 -258.554657) (xy 141.265663 -258.608064) (xy 141.273783 -258.66324) (xy 141.274292 -258.691126)
			(xy 141.273783 -258.719012) (xy 141.265663 -258.774188) (xy 141.249595 -258.827595) (xy 141.225923 -258.878092)
			(xy 141.208293 -258.90474) (xy 215.021922 -258.90474) (xy 215.022507 -258.875858) (xy 215.031222 -258.818755)
			(xy 215.048443 -258.763617) (xy 215.073777 -258.711705) (xy 215.106645 -258.664203) (xy 215.146296 -258.622198)
			(xy 215.168734 -258.604004) (xy 215.1761 -258.598162) (xy 215.185752 -258.582668) (xy 215.202008 -258.498594)
			(xy 215.19896 -258.480814) (xy 215.194134 -258.472686) (xy 215.181872 -258.450793) (xy 215.162588 -258.404465)
			(xy 215.149545 -258.356009) (xy 215.142968 -258.306261) (xy 215.142572 -258.28117) (xy 215.143058 -258.253919)
			(xy 215.150814 -258.199971) (xy 215.166169 -258.147676) (xy 215.188811 -258.098099) (xy 215.218277 -258.052249)
			(xy 215.253968 -258.011058) (xy 215.295159 -257.975367) (xy 215.341009 -257.945901) (xy 215.390586 -257.923259)
			(xy 215.442881 -257.907904) (xy 215.496829 -257.900148) (xy 215.551331 -257.900148) (xy 215.605279 -257.907904)
			(xy 215.657574 -257.923259) (xy 215.707151 -257.945901) (xy 215.753001 -257.975367) (xy 215.794192 -258.011058)
			(xy 215.829883 -258.052249) (xy 215.859349 -258.098099) (xy 215.881991 -258.147676) (xy 215.897346 -258.199971)
			(xy 215.905102 -258.253919) (xy 215.905588 -258.28117) (xy 215.905044 -258.310054) (xy 215.896326 -258.367161)
			(xy 215.879099 -258.4223) (xy 215.853757 -258.474214) (xy 215.82088 -258.521714) (xy 215.781219 -258.563715)
			(xy 215.758776 -258.581906) (xy 215.75141 -258.587748) (xy 215.741758 -258.603242) (xy 215.725502 -258.687316)
			(xy 215.72855 -258.705096) (xy 215.733376 -258.713224) (xy 215.745643 -258.735115) (xy 215.764926 -258.781443)
			(xy 215.770697 -258.802886) (xy 218.32392 -258.802886) (xy 218.327991 -258.747264) (xy 218.340117 -258.692827)
			(xy 218.36004 -258.640736) (xy 218.387336 -258.592101) (xy 218.421422 -258.547958) (xy 218.461571 -258.509249)
			(xy 218.506929 -258.476798) (xy 218.556529 -258.451297) (xy 218.609313 -258.43329) (xy 218.664156 -258.42316)
			(xy 218.71989 -258.421123) (xy 218.775327 -258.427223) (xy 218.829284 -258.441329) (xy 218.880613 -258.463141)
			(xy 218.928219 -258.492195) (xy 218.971087 -258.52787) (xy 219.008304 -258.569407) (xy 219.039077 -258.61592)
			(xy 219.062749 -258.666417) (xy 219.078817 -258.719824) (xy 219.085135 -258.762754) (xy 219.812106 -258.762754)
			(xy 219.816177 -258.707132) (xy 219.828303 -258.652695) (xy 219.848226 -258.600604) (xy 219.875522 -258.551969)
			(xy 219.909608 -258.507826) (xy 219.949757 -258.469117) (xy 219.995115 -258.436666) (xy 220.044715 -258.411165)
			(xy 220.097499 -258.393158) (xy 220.152342 -258.383028) (xy 220.208076 -258.380991) (xy 220.263513 -258.387091)
			(xy 220.31747 -258.401197) (xy 220.368799 -258.423009) (xy 220.416405 -258.452063) (xy 220.459273 -258.487738)
			(xy 220.49649 -258.529275) (xy 220.527263 -258.575788) (xy 220.550935 -258.626285) (xy 220.567003 -258.679692)
			(xy 220.575123 -258.734868) (xy 220.575632 -258.762754) (xy 220.575123 -258.79064) (xy 220.570368 -258.822952)
			(xy 221.320612 -258.822952) (xy 221.324683 -258.76733) (xy 221.336809 -258.712893) (xy 221.356732 -258.660802)
			(xy 221.384028 -258.612167) (xy 221.418114 -258.568024) (xy 221.458263 -258.529315) (xy 221.503621 -258.496864)
			(xy 221.553221 -258.471363) (xy 221.606005 -258.453356) (xy 221.660848 -258.443226) (xy 221.716582 -258.441189)
			(xy 221.772019 -258.447289) (xy 221.825976 -258.461395) (xy 221.877305 -258.483207) (xy 221.924911 -258.512261)
			(xy 221.967779 -258.547936) (xy 222.004996 -258.589473) (xy 222.035769 -258.635986) (xy 222.059441 -258.686483)
			(xy 222.075509 -258.73989) (xy 222.078874 -258.762754) (xy 222.828864 -258.762754) (xy 222.832935 -258.707132)
			(xy 222.845061 -258.652695) (xy 222.864984 -258.600604) (xy 222.89228 -258.551969) (xy 222.926366 -258.507826)
			(xy 222.966515 -258.469117) (xy 223.011873 -258.436666) (xy 223.061473 -258.411165) (xy 223.114257 -258.393158)
			(xy 223.1691 -258.383028) (xy 223.224834 -258.380991) (xy 223.280271 -258.387091) (xy 223.334228 -258.401197)
			(xy 223.385557 -258.423009) (xy 223.433163 -258.452063) (xy 223.476031 -258.487738) (xy 223.513248 -258.529275)
			(xy 223.544021 -258.575788) (xy 223.567693 -258.626285) (xy 223.583761 -258.679692) (xy 223.591881 -258.734868)
			(xy 223.59239 -258.762754) (xy 223.591881 -258.79064) (xy 223.583761 -258.845816) (xy 223.567693 -258.899223)
			(xy 223.544021 -258.94972) (xy 223.513248 -258.996233) (xy 223.476031 -259.03777) (xy 223.433163 -259.073445)
			(xy 223.385557 -259.102499) (xy 223.334228 -259.124311) (xy 223.280271 -259.138417) (xy 223.224834 -259.144517)
			(xy 223.1691 -259.14248) (xy 223.114257 -259.13235) (xy 223.061473 -259.114343) (xy 223.011873 -259.088842)
			(xy 222.966515 -259.056391) (xy 222.926366 -259.017682) (xy 222.89228 -258.973539) (xy 222.864984 -258.924904)
			(xy 222.845061 -258.872813) (xy 222.832935 -258.818376) (xy 222.828864 -258.762754) (xy 222.078874 -258.762754)
			(xy 222.083629 -258.795066) (xy 222.084138 -258.822952) (xy 222.083629 -258.850838) (xy 222.075509 -258.906014)
			(xy 222.059441 -258.959421) (xy 222.035769 -259.009918) (xy 222.004996 -259.056431) (xy 221.967779 -259.097968)
			(xy 221.924911 -259.133643) (xy 221.877305 -259.162697) (xy 221.825976 -259.184509) (xy 221.772019 -259.198615)
			(xy 221.716582 -259.204715) (xy 221.660848 -259.202678) (xy 221.606005 -259.192548) (xy 221.553221 -259.174541)
			(xy 221.503621 -259.14904) (xy 221.458263 -259.116589) (xy 221.418114 -259.07788) (xy 221.384028 -259.033737)
			(xy 221.356732 -258.985102) (xy 221.336809 -258.933011) (xy 221.324683 -258.878574) (xy 221.320612 -258.822952)
			(xy 220.570368 -258.822952) (xy 220.567003 -258.845816) (xy 220.550935 -258.899223) (xy 220.527263 -258.94972)
			(xy 220.49649 -258.996233) (xy 220.459273 -259.03777) (xy 220.416405 -259.073445) (xy 220.368799 -259.102499)
			(xy 220.31747 -259.124311) (xy 220.263513 -259.138417) (xy 220.208076 -259.144517) (xy 220.152342 -259.14248)
			(xy 220.097499 -259.13235) (xy 220.044715 -259.114343) (xy 219.995115 -259.088842) (xy 219.949757 -259.056391)
			(xy 219.909608 -259.017682) (xy 219.875522 -258.973539) (xy 219.848226 -258.924904) (xy 219.828303 -258.872813)
			(xy 219.816177 -258.818376) (xy 219.812106 -258.762754) (xy 219.085135 -258.762754) (xy 219.086937 -258.775)
			(xy 219.087446 -258.802886) (xy 219.086937 -258.830772) (xy 219.078817 -258.885948) (xy 219.062749 -258.939355)
			(xy 219.039077 -258.989852) (xy 219.008304 -259.036365) (xy 218.971087 -259.077902) (xy 218.928219 -259.113577)
			(xy 218.880613 -259.142631) (xy 218.829284 -259.164443) (xy 218.775327 -259.178549) (xy 218.71989 -259.184649)
			(xy 218.664156 -259.182612) (xy 218.609313 -259.172482) (xy 218.556529 -259.154475) (xy 218.506929 -259.128974)
			(xy 218.461571 -259.096523) (xy 218.421422 -259.057814) (xy 218.387336 -259.013671) (xy 218.36004 -258.965036)
			(xy 218.340117 -258.912945) (xy 218.327991 -258.858508) (xy 218.32392 -258.802886) (xy 215.770697 -258.802886)
			(xy 215.777968 -258.8299) (xy 215.784542 -258.879649) (xy 215.784938 -258.90474) (xy 215.784443 -258.931788)
			(xy 215.776802 -258.985342) (xy 215.761678 -259.037281) (xy 215.739375 -259.086566) (xy 215.710339 -259.13221)
			(xy 215.675151 -259.173298) (xy 215.655144 -259.191506) (xy 215.646762 -259.198872) (xy 215.637872 -259.218684)
			(xy 215.638294 -259.273802) (xy 219.062806 -259.273802) (xy 219.066877 -259.21818) (xy 219.079003 -259.163743)
			(xy 219.098926 -259.111652) (xy 219.126222 -259.063017) (xy 219.160308 -259.018874) (xy 219.200457 -258.980165)
			(xy 219.245815 -258.947714) (xy 219.295415 -258.922213) (xy 219.348199 -258.904206) (xy 219.403042 -258.894076)
			(xy 219.458776 -258.892039) (xy 219.514213 -258.898139) (xy 219.56817 -258.912245) (xy 219.619499 -258.934057)
			(xy 219.667105 -258.963111) (xy 219.709973 -258.998786) (xy 219.74719 -259.040323) (xy 219.777963 -259.086836)
			(xy 219.801635 -259.137333) (xy 219.817703 -259.19074) (xy 219.825823 -259.245916) (xy 219.826332 -259.273802)
			(xy 219.825823 -259.301688) (xy 219.817703 -259.356864) (xy 219.801635 -259.410271) (xy 219.777963 -259.460768)
			(xy 219.74719 -259.507281) (xy 219.709973 -259.548818) (xy 219.667105 -259.584493) (xy 219.619499 -259.613547)
			(xy 219.56817 -259.635359) (xy 219.514213 -259.649465) (xy 219.458776 -259.655565) (xy 219.403042 -259.653528)
			(xy 219.348199 -259.643398) (xy 219.295415 -259.625391) (xy 219.245815 -259.59989) (xy 219.200457 -259.567439)
			(xy 219.160308 -259.52873) (xy 219.126222 -259.484587) (xy 219.098926 -259.435952) (xy 219.079003 -259.383861)
			(xy 219.066877 -259.329424) (xy 219.062806 -259.273802) (xy 215.638294 -259.273802) (xy 215.638634 -259.318252)
			(xy 215.647778 -259.33781) (xy 215.656414 -259.345176) (xy 215.677148 -259.363406) (xy 215.713683 -259.404797)
			(xy 215.743871 -259.45102) (xy 215.767084 -259.501111) (xy 215.782835 -259.554025) (xy 215.790797 -259.608656)
			(xy 215.791288 -259.63626) (xy 215.790802 -259.663511) (xy 215.783046 -259.717459) (xy 215.767691 -259.769754)
			(xy 215.745049 -259.819331) (xy 215.715583 -259.865181) (xy 215.679892 -259.906372) (xy 215.661808 -259.922041)
			(xy 218.284257 -259.922041) (xy 218.284258 -259.867535) (xy 218.292017 -259.813584) (xy 218.307375 -259.761286)
			(xy 218.33002 -259.711706) (xy 218.35949 -259.665853) (xy 218.395186 -259.624662) (xy 218.436381 -259.58897)
			(xy 218.482236 -259.559504) (xy 218.531818 -259.536863) (xy 218.584117 -259.52151) (xy 218.638069 -259.513756)
			(xy 218.692575 -259.513759) (xy 218.746526 -259.521519) (xy 218.798824 -259.536879) (xy 218.848403 -259.559525)
			(xy 218.894255 -259.588996) (xy 218.935445 -259.624693) (xy 218.971136 -259.665889) (xy 219.000601 -259.711745)
			(xy 219.02324 -259.761327) (xy 219.038592 -259.813627) (xy 219.046345 -259.867579) (xy 219.046806 -259.894832)
			(xy 219.80728 -259.894832) (xy 219.811351 -259.83921) (xy 219.823477 -259.784773) (xy 219.8434 -259.732682)
			(xy 219.870696 -259.684047) (xy 219.904782 -259.639904) (xy 219.944931 -259.601195) (xy 219.990289 -259.568744)
			(xy 220.039889 -259.543243) (xy 220.092673 -259.525236) (xy 220.147516 -259.515106) (xy 220.20325 -259.513069)
			(xy 220.258687 -259.519169) (xy 220.312644 -259.533275) (xy 220.363973 -259.555087) (xy 220.411579 -259.584141)
			(xy 220.454447 -259.619816) (xy 220.491664 -259.661353) (xy 220.522437 -259.707866) (xy 220.546109 -259.758363)
			(xy 220.562177 -259.81177) (xy 220.570297 -259.866946) (xy 220.570806 -259.894832) (xy 220.570297 -259.922718)
			(xy 220.562177 -259.977894) (xy 220.546109 -260.031301) (xy 220.522437 -260.081798) (xy 220.491664 -260.128311)
			(xy 220.454447 -260.169848) (xy 220.411579 -260.205523) (xy 220.363973 -260.234577) (xy 220.312644 -260.256389)
			(xy 220.258687 -260.270495) (xy 220.20325 -260.276595) (xy 220.147516 -260.274558) (xy 220.092673 -260.264428)
			(xy 220.039889 -260.246421) (xy 219.990289 -260.22092) (xy 219.944931 -260.188469) (xy 219.904782 -260.14976)
			(xy 219.870696 -260.105617) (xy 219.8434 -260.056982) (xy 219.823477 -260.004891) (xy 219.811351 -259.950454)
			(xy 219.80728 -259.894832) (xy 219.046806 -259.894832) (xy 219.046298 -259.91312) (xy 219.04579 -259.92709)
			(xy 219.058236 -259.95122) (xy 219.156534 -260.013196) (xy 219.183712 -260.014212) (xy 219.195904 -260.007608)
			(xy 219.223904 -259.99323) (xy 219.283452 -259.972857) (xy 219.345537 -259.962531) (xy 219.377006 -259.961888)
			(xy 219.404257 -259.962382) (xy 219.458203 -259.970139) (xy 219.510497 -259.985495) (xy 219.560073 -260.008136)
			(xy 219.605922 -260.037602) (xy 219.647111 -260.073293) (xy 219.682801 -260.114483) (xy 219.712267 -260.160333)
			(xy 219.734907 -260.209909) (xy 219.750262 -260.262203) (xy 219.758018 -260.316149) (xy 219.758018 -260.370651)
			(xy 219.750262 -260.424597) (xy 219.734907 -260.476891) (xy 219.712267 -260.526467) (xy 219.682801 -260.572317)
			(xy 219.647111 -260.613507) (xy 219.605922 -260.649198) (xy 219.560073 -260.678664) (xy 219.510497 -260.701305)
			(xy 219.458203 -260.716661) (xy 219.404257 -260.724418) (xy 219.377006 -260.724904) (xy 219.345537 -260.724274)
			(xy 219.283452 -260.713942) (xy 219.223906 -260.693558) (xy 219.195904 -260.679184) (xy 219.183712 -260.67258)
			(xy 219.156026 -260.673596) (xy 219.057728 -260.73608) (xy 219.045282 -260.760718) (xy 219.046044 -260.774688)
			(xy 219.046806 -260.797548) (xy 219.046271 -260.824748) (xy 219.808326 -260.824748) (xy 219.808326 -260.770252)
			(xy 219.816082 -260.716312) (xy 219.831435 -260.664024) (xy 219.854073 -260.614453) (xy 219.883535 -260.568608)
			(xy 219.919222 -260.527423) (xy 219.960407 -260.491736) (xy 220.006251 -260.462274) (xy 220.055822 -260.439635)
			(xy 220.10811 -260.424282) (xy 220.16205 -260.416526) (xy 220.189298 -260.41604) (xy 220.218233 -260.416577)
			(xy 220.275439 -260.425323) (xy 220.330667 -260.442613) (xy 220.382647 -260.468052) (xy 220.406722 -260.484112)
			(xy 220.416374 -260.490716) (xy 220.43898 -260.494272) (xy 220.53804 -260.4643) (xy 220.554804 -260.448806)
			(xy 220.559122 -260.43763) (xy 220.569672 -260.412025) (xy 220.597175 -260.363958) (xy 220.63134 -260.320373)
			(xy 220.671447 -260.282186) (xy 220.716655 -260.2502) (xy 220.766013 -260.225087) (xy 220.818483 -260.207375)
			(xy 220.845634 -260.201918) (xy 220.857572 -260.199886) (xy 220.87713 -260.1849) (xy 220.923104 -260.088634)
			(xy 220.922342 -260.06425) (xy 220.9165 -260.053582) (xy 220.901891 -260.02538) (xy 220.881173 -259.965344)
			(xy 220.870658 -259.902711) (xy 220.870018 -259.870956) (xy 220.870504 -259.843705) (xy 220.87826 -259.789757)
			(xy 220.893615 -259.737462) (xy 220.916257 -259.687885) (xy 220.945723 -259.642035) (xy 220.981414 -259.600844)
			(xy 221.022605 -259.565153) (xy 221.068455 -259.535687) (xy 221.118032 -259.513045) (xy 221.170327 -259.49769)
			(xy 221.224275 -259.489934) (xy 221.278777 -259.489934) (xy 221.332725 -259.49769) (xy 221.38502 -259.513045)
			(xy 221.434597 -259.535687) (xy 221.480447 -259.565153) (xy 221.521638 -259.600844) (xy 221.557329 -259.642035)
			(xy 221.586795 -259.687885) (xy 221.609437 -259.737462) (xy 221.624792 -259.789757) (xy 221.632548 -259.843705)
			(xy 221.633034 -259.870956) (xy 221.63257 -259.897484) (xy 221.629126 -259.922049) (xy 222.09431 -259.922049)
			(xy 222.09431 -259.867551) (xy 222.102066 -259.813608) (xy 222.11742 -259.761318) (xy 222.140059 -259.711745)
			(xy 222.169522 -259.665899) (xy 222.205211 -259.624712) (xy 222.246397 -259.589024) (xy 222.292243 -259.55956)
			(xy 222.341816 -259.53692) (xy 222.394106 -259.521566) (xy 222.448049 -259.51381) (xy 222.475298 -259.513324)
			(xy 222.502454 -259.513832) (xy 222.55622 -259.521514) (xy 222.608354 -259.536736) (xy 222.657806 -259.559192)
			(xy 222.703577 -259.588429) (xy 222.724472 -259.60578) (xy 222.734124 -259.614162) (xy 222.758508 -259.61975)
			(xy 222.864172 -259.591302) (xy 222.882714 -259.57403) (xy 222.886778 -259.562092) (xy 222.895716 -259.53738)
			(xy 222.919477 -259.490508) (xy 222.949448 -259.447341) (xy 222.985061 -259.408698) (xy 223.025643 -259.37531)
			(xy 223.070423 -259.347809) (xy 223.118556 -259.326717) (xy 223.169128 -259.312432) (xy 223.221182 -259.305226)
			(xy 223.247458 -259.30479) (xy 223.276335 -259.305319) (xy 223.333429 -259.314026) (xy 223.388561 -259.331233)
			(xy 223.440472 -259.356546) (xy 223.487979 -259.389389) (xy 223.529997 -259.429013) (xy 223.565569 -259.474513)
			(xy 223.593882 -259.524851) (xy 223.604582 -259.551678) (xy 223.6089 -259.563362) (xy 223.626426 -259.579618)
			(xy 223.729296 -259.608066) (xy 223.752918 -259.60324) (xy 223.76257 -259.59562) (xy 223.782847 -259.580074)
			(xy 223.826799 -259.554018) (xy 223.873834 -259.534057) (xy 223.923112 -259.520548) (xy 223.97375 -259.513733)
			(xy 223.999298 -259.513324) (xy 224.026553 -259.513723) (xy 224.080509 -259.52148) (xy 224.127427 -259.535256)
			(xy 224.434045 -259.535256) (xy 224.434045 -259.480744) (xy 224.441803 -259.426788) (xy 224.457162 -259.374485)
			(xy 224.479809 -259.3249) (xy 224.509282 -259.279044) (xy 224.544981 -259.237849) (xy 224.586181 -259.202154)
			(xy 224.632041 -259.172687) (xy 224.681628 -259.150046) (xy 224.733933 -259.134694) (xy 224.78789 -259.126942)
			(xy 224.815146 -259.126482) (xy 224.843547 -259.127031) (xy 224.899723 -259.135445) (xy 224.95403 -259.152096)
			(xy 225.005267 -259.176616) (xy 225.052303 -259.208462) (xy 225.094096 -259.24693) (xy 225.129724 -259.291169)
			(xy 225.158398 -259.340203) (xy 225.179485 -259.392946) (xy 225.192518 -259.448233) (xy 225.195384 -259.476494)
			(xy 225.1964 -259.489448) (xy 225.21037 -259.510784) (xy 225.307398 -259.56387) (xy 225.332798 -259.56387)
			(xy 225.344228 -259.558028) (xy 225.367276 -259.546235) (xy 225.415828 -259.528259) (xy 225.441002 -259.522214)
			(xy 225.454972 -259.519166) (xy 225.4758 -259.499354) (xy 225.505772 -259.384038) (xy 225.497644 -259.35686)
			(xy 225.486722 -259.347208) (xy 225.467038 -259.329023) (xy 225.43244 -259.288097) (xy 225.403909 -259.242734)
			(xy 225.382005 -259.193825) (xy 225.36716 -259.142332) (xy 225.359665 -259.089269) (xy 225.359214 -259.062474)
			(xy 225.3597 -259.035223) (xy 225.367456 -258.981275) (xy 225.382811 -258.92898) (xy 225.405453 -258.879403)
			(xy 225.434919 -258.833553) (xy 225.47061 -258.792362) (xy 225.511801 -258.756671) (xy 225.557651 -258.727205)
			(xy 225.607228 -258.704563) (xy 225.659523 -258.689208) (xy 225.713471 -258.681452) (xy 225.767973 -258.681452)
			(xy 225.821921 -258.689208) (xy 225.874216 -258.704563) (xy 225.923793 -258.727205) (xy 225.969643 -258.756671)
			(xy 226.010834 -258.792362) (xy 226.046525 -258.833553) (xy 226.075991 -258.879403) (xy 226.098633 -258.92898)
			(xy 226.113988 -258.981275) (xy 226.121744 -259.035223) (xy 226.12223 -259.062474) (xy 226.121754 -259.08635)
			(xy 226.47783 -259.08635) (xy 226.478316 -259.059099) (xy 226.486072 -259.005151) (xy 226.501427 -258.952856)
			(xy 226.524069 -258.903279) (xy 226.553535 -258.857429) (xy 226.589226 -258.816238) (xy 226.630417 -258.780547)
			(xy 226.676267 -258.751081) (xy 226.725844 -258.728439) (xy 226.778139 -258.713084) (xy 226.832087 -258.705328)
			(xy 226.886589 -258.705328) (xy 226.940537 -258.713084) (xy 226.992832 -258.728439) (xy 227.042409 -258.751081)
			(xy 227.088259 -258.780547) (xy 227.12945 -258.816238) (xy 227.165141 -258.857429) (xy 227.194607 -258.903279)
			(xy 227.217249 -258.952856) (xy 227.232604 -259.005151) (xy 227.240261 -259.05841) (xy 227.6381 -259.05841)
			(xy 227.642171 -259.002788) (xy 227.654297 -258.948351) (xy 227.67422 -258.89626) (xy 227.701516 -258.847625)
			(xy 227.735602 -258.803482) (xy 227.775751 -258.764773) (xy 227.821109 -258.732322) (xy 227.870709 -258.706821)
			(xy 227.923493 -258.688814) (xy 227.978336 -258.678684) (xy 228.03407 -258.676647) (xy 228.089507 -258.682747)
			(xy 228.143464 -258.696853) (xy 228.194793 -258.718665) (xy 228.242399 -258.747719) (xy 228.285267 -258.783394)
			(xy 228.322484 -258.824931) (xy 228.353257 -258.871444) (xy 228.376929 -258.921941) (xy 228.392997 -258.975348)
			(xy 228.401117 -259.030524) (xy 228.401626 -259.05841) (xy 228.401117 -259.086296) (xy 228.392997 -259.141472)
			(xy 228.376929 -259.194879) (xy 228.353257 -259.245376) (xy 228.322484 -259.291889) (xy 228.285267 -259.333426)
			(xy 228.242399 -259.369101) (xy 228.194793 -259.398155) (xy 228.143464 -259.419967) (xy 228.089507 -259.434073)
			(xy 228.03407 -259.440173) (xy 227.978336 -259.438136) (xy 227.923493 -259.428006) (xy 227.870709 -259.409999)
			(xy 227.821109 -259.384498) (xy 227.775751 -259.352047) (xy 227.735602 -259.313338) (xy 227.701516 -259.269195)
			(xy 227.67422 -259.22056) (xy 227.654297 -259.168469) (xy 227.642171 -259.114032) (xy 227.6381 -259.05841)
			(xy 227.240261 -259.05841) (xy 227.24036 -259.059099) (xy 227.240846 -259.08635) (xy 227.240446 -259.111959)
			(xy 227.233581 -259.162717) (xy 227.219995 -259.212101) (xy 227.199931 -259.259227) (xy 227.173749 -259.303249)
			(xy 227.14192 -259.343378) (xy 227.123752 -259.361432) (xy 227.113279 -259.372223) (xy 227.098618 -259.398462)
			(xy 227.092232 -259.427832) (xy 227.094676 -259.45779) (xy 227.105738 -259.485737) (xy 227.124458 -259.509252)
			(xy 227.149215 -259.526296) (xy 227.163376 -259.531358) (xy 227.188707 -259.539976) (xy 227.236898 -259.563222)
			(xy 227.281369 -259.592973) (xy 227.321249 -259.628643) (xy 227.355755 -259.669535) (xy 227.38421 -259.714845)
			(xy 227.406057 -259.763687) (xy 227.420868 -259.815101) (xy 227.428351 -259.86808) (xy 227.428806 -259.894832)
			(xy 228.18928 -259.894832) (xy 228.193351 -259.83921) (xy 228.205477 -259.784773) (xy 228.2254 -259.732682)
			(xy 228.252696 -259.684047) (xy 228.286782 -259.639904) (xy 228.326931 -259.601195) (xy 228.372289 -259.568744)
			(xy 228.421889 -259.543243) (xy 228.474673 -259.525236) (xy 228.529516 -259.515106) (xy 228.58525 -259.513069)
			(xy 228.640687 -259.519169) (xy 228.694644 -259.533275) (xy 228.745973 -259.555087) (xy 228.793579 -259.584141)
			(xy 228.836447 -259.619816) (xy 228.873664 -259.661353) (xy 228.904437 -259.707866) (xy 228.928109 -259.758363)
			(xy 228.944177 -259.81177) (xy 228.952297 -259.866946) (xy 228.952319 -259.868162) (xy 230.35768 -259.868162)
			(xy 230.358172 -259.839355) (xy 230.366827 -259.782396) (xy 230.383949 -259.727386) (xy 230.40915 -259.675576)
			(xy 230.441855 -259.628146) (xy 230.481321 -259.586173) (xy 230.526651 -259.550613) (xy 230.576812 -259.522274)
			(xy 230.603552 -259.511546) (xy 230.614728 -259.507228) (xy 230.630476 -259.490464) (xy 230.660956 -259.390642)
			(xy 230.657146 -259.367528) (xy 230.650034 -259.357876) (xy 230.633415 -259.333531) (xy 230.607105 -259.280784)
			(xy 230.589226 -259.224618) (xy 230.580202 -259.166368) (xy 230.579676 -259.136896) (xy 230.580126 -259.109419)
			(xy 230.587983 -259.05503) (xy 230.603575 -259.002335) (xy 230.626579 -258.952428) (xy 230.641144 -258.929124)
			(xy 230.646478 -258.920996) (xy 230.650288 -258.902454) (xy 230.635302 -258.815078) (xy 230.625396 -258.799076)
			(xy 230.617776 -258.79298) (xy 230.594936 -258.774778) (xy 230.554469 -258.732675) (xy 230.520896 -258.684893)
			(xy 230.495001 -258.63255) (xy 230.477391 -258.57687) (xy 230.468477 -258.519157) (xy 230.467916 -258.489958)
			(xy 230.468421 -258.460384) (xy 230.477543 -258.401944) (xy 230.495576 -258.345612) (xy 230.522089 -258.292739)
			(xy 230.556445 -258.244592) (xy 230.597822 -258.202326) (xy 230.645227 -258.166954) (xy 230.671116 -258.152646)
			(xy 230.682038 -258.147058) (xy 230.695754 -258.127246) (xy 230.711248 -258.021836) (xy 230.703628 -257.998976)
			(xy 230.694738 -257.99034) (xy 230.673549 -257.968668) (xy 230.637586 -257.919885) (xy 230.60979 -257.866028)
			(xy 230.590861 -257.808453) (xy 230.581276 -257.748609) (xy 230.580692 -257.718306) (xy 230.581178 -257.691055)
			(xy 230.588934 -257.637107) (xy 230.604289 -257.584812) (xy 230.626931 -257.535235) (xy 230.656397 -257.489385)
			(xy 230.692088 -257.448194) (xy 230.733279 -257.412503) (xy 230.779129 -257.383037) (xy 230.828706 -257.360395)
			(xy 230.881001 -257.34504) (xy 230.934949 -257.337284) (xy 230.989451 -257.337284) (xy 231.043399 -257.34504)
			(xy 231.095694 -257.360395) (xy 231.145271 -257.383037) (xy 231.191121 -257.412503) (xy 231.232312 -257.448194)
			(xy 231.268003 -257.489385) (xy 231.297469 -257.535235) (xy 231.320111 -257.584812) (xy 231.335466 -257.637107)
			(xy 231.343222 -257.691055) (xy 231.343708 -257.718306) (xy 231.343161 -257.747878) (xy 231.334046 -257.806316)
			(xy 231.316019 -257.862646) (xy 231.289513 -257.915519) (xy 231.255163 -257.963666) (xy 231.213793 -258.005934)
			(xy 231.166394 -258.041309) (xy 231.140508 -258.055618) (xy 231.129586 -258.061206) (xy 231.11587 -258.081018)
			(xy 231.100376 -258.186428) (xy 231.107996 -258.209288) (xy 231.116886 -258.217924) (xy 231.13811 -258.239563)
			(xy 231.174068 -258.288356) (xy 231.201856 -258.342221) (xy 231.220777 -258.399803) (xy 231.230353 -258.459653)
			(xy 231.230932 -258.489958) (xy 231.230459 -258.517434) (xy 231.222609 -258.571822) (xy 231.207024 -258.624518)
			(xy 231.184026 -258.674426) (xy 231.169464 -258.69773) (xy 231.16413 -258.705858) (xy 231.16032 -258.7244)
			(xy 231.173781 -258.802886) (xy 234.574078 -258.802886) (xy 234.578149 -258.747264) (xy 234.590275 -258.692827)
			(xy 234.610198 -258.640736) (xy 234.637494 -258.592101) (xy 234.67158 -258.547958) (xy 234.711729 -258.509249)
			(xy 234.757087 -258.476798) (xy 234.806687 -258.451297) (xy 234.859471 -258.43329) (xy 234.914314 -258.42316)
			(xy 234.970048 -258.421123) (xy 235.025485 -258.427223) (xy 235.079442 -258.441329) (xy 235.130771 -258.463141)
			(xy 235.178377 -258.492195) (xy 235.221245 -258.52787) (xy 235.258462 -258.569407) (xy 235.289235 -258.61592)
			(xy 235.312907 -258.666417) (xy 235.328975 -258.719824) (xy 235.335293 -258.762754) (xy 236.062264 -258.762754)
			(xy 236.066335 -258.707132) (xy 236.078461 -258.652695) (xy 236.098384 -258.600604) (xy 236.12568 -258.551969)
			(xy 236.159766 -258.507826) (xy 236.199915 -258.469117) (xy 236.245273 -258.436666) (xy 236.294873 -258.411165)
			(xy 236.347657 -258.393158) (xy 236.4025 -258.383028) (xy 236.458234 -258.380991) (xy 236.513671 -258.387091)
			(xy 236.567628 -258.401197) (xy 236.618957 -258.423009) (xy 236.666563 -258.452063) (xy 236.709431 -258.487738)
			(xy 236.746648 -258.529275) (xy 236.777421 -258.575788) (xy 236.801093 -258.626285) (xy 236.817161 -258.679692)
			(xy 236.825281 -258.734868) (xy 236.82579 -258.762754) (xy 236.825281 -258.79064) (xy 236.820526 -258.822952)
			(xy 237.57077 -258.822952) (xy 237.574841 -258.76733) (xy 237.586967 -258.712893) (xy 237.60689 -258.660802)
			(xy 237.634186 -258.612167) (xy 237.668272 -258.568024) (xy 237.708421 -258.529315) (xy 237.753779 -258.496864)
			(xy 237.803379 -258.471363) (xy 237.856163 -258.453356) (xy 237.911006 -258.443226) (xy 237.96674 -258.441189)
			(xy 238.022177 -258.447289) (xy 238.076134 -258.461395) (xy 238.127463 -258.483207) (xy 238.175069 -258.512261)
			(xy 238.217937 -258.547936) (xy 238.255154 -258.589473) (xy 238.285927 -258.635986) (xy 238.309599 -258.686483)
			(xy 238.325667 -258.73989) (xy 238.333787 -258.795066) (xy 238.334296 -258.822952) (xy 238.333787 -258.850838)
			(xy 238.325667 -258.906014) (xy 238.309599 -258.959421) (xy 238.285927 -259.009918) (xy 238.255154 -259.056431)
			(xy 238.217937 -259.097968) (xy 238.175069 -259.133643) (xy 238.127463 -259.162697) (xy 238.076134 -259.184509)
			(xy 238.022177 -259.198615) (xy 237.96674 -259.204715) (xy 237.911006 -259.202678) (xy 237.856163 -259.192548)
			(xy 237.803379 -259.174541) (xy 237.753779 -259.14904) (xy 237.708421 -259.116589) (xy 237.668272 -259.07788)
			(xy 237.634186 -259.033737) (xy 237.60689 -258.985102) (xy 237.586967 -258.933011) (xy 237.574841 -258.878574)
			(xy 237.57077 -258.822952) (xy 236.820526 -258.822952) (xy 236.817161 -258.845816) (xy 236.801093 -258.899223)
			(xy 236.777421 -258.94972) (xy 236.746648 -258.996233) (xy 236.709431 -259.03777) (xy 236.666563 -259.073445)
			(xy 236.618957 -259.102499) (xy 236.567628 -259.124311) (xy 236.513671 -259.138417) (xy 236.458234 -259.144517)
			(xy 236.4025 -259.14248) (xy 236.347657 -259.13235) (xy 236.294873 -259.114343) (xy 236.245273 -259.088842)
			(xy 236.199915 -259.056391) (xy 236.159766 -259.017682) (xy 236.12568 -258.973539) (xy 236.098384 -258.924904)
			(xy 236.078461 -258.872813) (xy 236.066335 -258.818376) (xy 236.062264 -258.762754) (xy 235.335293 -258.762754)
			(xy 235.337095 -258.775) (xy 235.337604 -258.802886) (xy 235.337095 -258.830772) (xy 235.328975 -258.885948)
			(xy 235.312907 -258.939355) (xy 235.289235 -258.989852) (xy 235.258462 -259.036365) (xy 235.221245 -259.077902)
			(xy 235.178377 -259.113577) (xy 235.130771 -259.142631) (xy 235.079442 -259.164443) (xy 235.025485 -259.178549)
			(xy 234.970048 -259.184649) (xy 234.914314 -259.182612) (xy 234.859471 -259.172482) (xy 234.806687 -259.154475)
			(xy 234.757087 -259.128974) (xy 234.711729 -259.096523) (xy 234.67158 -259.057814) (xy 234.637494 -259.013671)
			(xy 234.610198 -258.965036) (xy 234.590275 -258.912945) (xy 234.578149 -258.858508) (xy 234.574078 -258.802886)
			(xy 231.173781 -258.802886) (xy 231.175306 -258.811776) (xy 231.185212 -258.827778) (xy 231.192832 -258.833874)
			(xy 231.215699 -258.852043) (xy 231.256164 -258.894153) (xy 231.289734 -258.941942) (xy 231.315624 -258.994292)
			(xy 231.333228 -259.049977) (xy 231.342135 -259.107695) (xy 231.342692 -259.136896) (xy 231.342118 -259.165699)
			(xy 231.333471 -259.222653) (xy 231.316358 -259.277658) (xy 231.291169 -259.329465) (xy 231.258475 -259.376895)
			(xy 231.219021 -259.41887) (xy 231.173704 -259.454434) (xy 231.123554 -259.482779) (xy 231.09682 -259.493512)
			(xy 231.085644 -259.49783) (xy 231.069896 -259.514594) (xy 231.039416 -259.614416) (xy 231.043226 -259.63753)
			(xy 231.050338 -259.647182) (xy 231.066936 -259.671541) (xy 231.093251 -259.724282) (xy 231.111137 -259.780445)
			(xy 231.120167 -259.838691) (xy 231.120696 -259.868162) (xy 231.12021 -259.895413) (xy 231.116433 -259.921687)
			(xy 234.534472 -259.921687) (xy 234.534526 -259.867157) (xy 234.542344 -259.81319) (xy 234.557768 -259.760887)
			(xy 234.580481 -259.711312) (xy 234.610023 -259.665478) (xy 234.645789 -259.624316) (xy 234.687053 -259.588667)
			(xy 234.732972 -259.559257) (xy 234.782611 -259.536686) (xy 234.834959 -259.521412) (xy 234.888948 -259.513749)
			(xy 234.943477 -259.513851) (xy 234.997437 -259.521716) (xy 235.049727 -259.537185) (xy 235.099281 -259.559942)
			(xy 235.14509 -259.589524) (xy 235.18622 -259.625327) (xy 235.221833 -259.666622) (xy 235.251203 -259.712567)
			(xy 235.273731 -259.762226) (xy 235.288958 -259.814586) (xy 235.296575 -259.868582) (xy 235.296964 -259.895848)
			(xy 235.296964 -259.910326) (xy 235.311442 -259.934456) (xy 235.417106 -259.98932) (xy 235.4453 -259.987542)
			(xy 235.456984 -259.97916) (xy 235.481224 -259.962724) (xy 235.533701 -259.936723) (xy 235.589534 -259.919043)
			(xy 235.647411 -259.910097) (xy 235.676694 -259.909564) (xy 235.706164 -259.910128) (xy 235.764406 -259.919156)
			(xy 235.820569 -259.93703) (xy 235.873318 -259.963324) (xy 235.897674 -259.979922) (xy 235.909358 -259.988304)
			(xy 235.937552 -259.990336) (xy 236.04347 -259.935218) (xy 236.057948 -259.911088) (xy 236.057948 -259.894832)
			(xy 236.058421 -259.867576) (xy 236.066174 -259.813617) (xy 236.081529 -259.761312) (xy 236.104171 -259.711724)
			(xy 236.13364 -259.665863) (xy 236.169336 -259.624663) (xy 236.210532 -259.588963) (xy 236.25639 -259.559489)
			(xy 236.305975 -259.536842) (xy 236.358279 -259.521483) (xy 236.412237 -259.513723) (xy 236.46675 -259.513723)
			(xy 236.520708 -259.52148) (xy 236.573012 -259.536838) (xy 236.622599 -259.559483) (xy 236.668457 -259.588955)
			(xy 236.709655 -259.624654) (xy 236.745352 -259.665852) (xy 236.774823 -259.711712) (xy 236.797467 -259.761299)
			(xy 236.812823 -259.813604) (xy 236.820578 -259.867562) (xy 236.820576 -259.922075) (xy 236.812815 -259.976032)
			(xy 236.808987 -259.989066) (xy 237.085376 -259.989066) (xy 237.089447 -259.933444) (xy 237.101573 -259.879007)
			(xy 237.121496 -259.826916) (xy 237.148792 -259.778281) (xy 237.182878 -259.734138) (xy 237.223027 -259.695429)
			(xy 237.268385 -259.662978) (xy 237.317985 -259.637477) (xy 237.370769 -259.61947) (xy 237.425612 -259.60934)
			(xy 237.481346 -259.607303) (xy 237.536783 -259.613403) (xy 237.59074 -259.627509) (xy 237.642069 -259.649321)
			(xy 237.689675 -259.678375) (xy 237.732543 -259.71405) (xy 237.76976 -259.755587) (xy 237.800533 -259.8021)
			(xy 237.824205 -259.852597) (xy 237.836912 -259.894832) (xy 238.343948 -259.894832) (xy 238.344369 -259.868281)
			(xy 238.351735 -259.815693) (xy 238.366329 -259.764636) (xy 238.387868 -259.716099) (xy 238.415936 -259.671021)
			(xy 238.449988 -259.630276) (xy 238.489367 -259.594651) (xy 238.51108 -259.579364) (xy 238.520986 -259.572506)
			(xy 238.53267 -259.551932) (xy 238.53775 -259.446776) (xy 238.528352 -259.425186) (xy 238.518954 -259.417312)
			(xy 238.497942 -259.399102) (xy 238.460944 -259.357596) (xy 238.43036 -259.311161) (xy 238.406837 -259.26078)
			(xy 238.390872 -259.207519) (xy 238.382804 -259.152505) (xy 238.382302 -259.124704) (xy 238.382759 -259.097451)
			(xy 238.390516 -259.043499) (xy 238.405872 -258.991201) (xy 238.428515 -258.94162) (xy 238.457983 -258.895766)
			(xy 238.493677 -258.854573) (xy 238.534871 -258.818879) (xy 238.580725 -258.789412) (xy 238.630306 -258.76677)
			(xy 238.682605 -258.751414) (xy 238.736557 -258.743659) (xy 238.76381 -258.743196) (xy 238.793748 -258.743735)
			(xy 238.852894 -258.753052) (xy 238.90985 -258.771517) (xy 238.936784 -258.784598) (xy 238.947706 -258.790186)
			(xy 238.972344 -258.790186) (xy 239.067594 -258.740656) (xy 239.081564 -258.720844) (xy 239.083342 -258.708652)
			(xy 239.087733 -258.681741) (xy 239.103073 -258.629421) (xy 239.125704 -258.579817) (xy 239.155165 -258.533939)
			(xy 239.190857 -258.492722) (xy 239.232052 -258.457006) (xy 239.277911 -258.427516) (xy 239.327502 -258.404855)
			(xy 239.379812 -258.389483) (xy 239.433779 -258.381714) (xy 239.46104 -258.381246) (xy 239.48829 -258.38174)
			(xy 239.542235 -258.389501) (xy 239.594527 -258.404859) (xy 239.644101 -258.427502) (xy 239.689949 -258.456968)
			(xy 239.731138 -258.492658) (xy 239.766829 -258.533846) (xy 239.796296 -258.579693) (xy 239.818939 -258.629267)
			(xy 239.834297 -258.681559) (xy 239.838817 -258.71297) (xy 242.868194 -258.71297) (xy 242.872265 -258.657348)
			(xy 242.884391 -258.602911) (xy 242.904314 -258.55082) (xy 242.93161 -258.502185) (xy 242.965696 -258.458042)
			(xy 243.005845 -258.419333) (xy 243.051203 -258.386882) (xy 243.100803 -258.361381) (xy 243.153587 -258.343374)
			(xy 243.20843 -258.333244) (xy 243.264164 -258.331207) (xy 243.319601 -258.337307) (xy 243.373558 -258.351413)
			(xy 243.424887 -258.373225) (xy 243.472493 -258.402279) (xy 243.515361 -258.437954) (xy 243.552578 -258.479491)
			(xy 243.583351 -258.526004) (xy 243.607023 -258.576501) (xy 243.623091 -258.629908) (xy 243.631211 -258.685084)
			(xy 243.63172 -258.71297) (xy 243.631211 -258.740856) (xy 243.623091 -258.796032) (xy 243.607023 -258.849439)
			(xy 243.583351 -258.899936) (xy 243.552578 -258.946449) (xy 243.515361 -258.987986) (xy 243.472493 -259.023661)
			(xy 243.424887 -259.052715) (xy 243.373558 -259.074527) (xy 243.319601 -259.088633) (xy 243.264164 -259.094733)
			(xy 243.20843 -259.092696) (xy 243.153587 -259.082566) (xy 243.100803 -259.064559) (xy 243.051203 -259.039058)
			(xy 243.005845 -259.006607) (xy 242.965696 -258.967898) (xy 242.93161 -258.923755) (xy 242.904314 -258.87512)
			(xy 242.884391 -258.823029) (xy 242.872265 -258.768592) (xy 242.868194 -258.71297) (xy 239.838817 -258.71297)
			(xy 239.842059 -258.735504) (xy 239.842548 -258.762754) (xy 239.842112 -258.788647) (xy 239.835118 -258.839958)
			(xy 239.821239 -258.88985) (xy 239.800731 -258.937402) (xy 239.773972 -258.981738) (xy 239.741454 -259.022042)
			(xy 239.722914 -259.040122) (xy 239.714024 -259.048504) (xy 239.705896 -259.070602) (xy 239.71758 -259.17525)
			(xy 239.73028 -259.195316) (xy 239.740694 -259.201412) (xy 239.765181 -259.216591) (xy 239.809722 -259.253128)
			(xy 239.848258 -259.295951) (xy 239.879912 -259.344085) (xy 239.903964 -259.396433) (xy 239.909741 -259.41655)
			(xy 240.657632 -259.41655) (xy 240.661703 -259.360928) (xy 240.673829 -259.306491) (xy 240.693752 -259.2544)
			(xy 240.721048 -259.205765) (xy 240.755134 -259.161622) (xy 240.795283 -259.122913) (xy 240.840641 -259.090462)
			(xy 240.890241 -259.064961) (xy 240.943025 -259.046954) (xy 240.997868 -259.036824) (xy 241.053602 -259.034787)
			(xy 241.109039 -259.040887) (xy 241.162996 -259.054993) (xy 241.214325 -259.076805) (xy 241.261931 -259.105859)
			(xy 241.304799 -259.141534) (xy 241.342016 -259.183071) (xy 241.372789 -259.229584) (xy 241.396461 -259.280081)
			(xy 241.412529 -259.333488) (xy 241.420649 -259.388664) (xy 241.421158 -259.41655) (xy 241.420649 -259.444436)
			(xy 241.412529 -259.499612) (xy 241.396461 -259.553019) (xy 241.372789 -259.603516) (xy 241.342016 -259.650029)
			(xy 241.304799 -259.691566) (xy 241.261931 -259.727241) (xy 241.214325 -259.756295) (xy 241.162996 -259.778107)
			(xy 241.109039 -259.792213) (xy 241.053602 -259.798313) (xy 240.997868 -259.796276) (xy 240.943025 -259.786146)
			(xy 240.890241 -259.768139) (xy 240.840641 -259.742638) (xy 240.795283 -259.710187) (xy 240.755134 -259.671478)
			(xy 240.721048 -259.627335) (xy 240.693752 -259.5787) (xy 240.673829 -259.526609) (xy 240.661703 -259.472172)
			(xy 240.657632 -259.41655) (xy 239.909741 -259.41655) (xy 239.919865 -259.451805) (xy 239.924082 -259.480304)
			(xy 239.925606 -259.49275) (xy 239.93983 -259.51307) (xy 240.036096 -259.563108) (xy 240.060734 -259.562854)
			(xy 240.07191 -259.557012) (xy 240.099447 -259.543219) (xy 240.15787 -259.523738) (xy 240.218663 -259.513891)
			(xy 240.249456 -259.513324) (xy 240.276713 -259.51372) (xy 240.330673 -259.521472) (xy 240.382981 -259.536826)
			(xy 240.432571 -259.559468) (xy 240.478433 -259.588937) (xy 240.519635 -259.624634) (xy 240.555336 -259.665831)
			(xy 240.584811 -259.71169) (xy 240.607459 -259.761278) (xy 240.622818 -259.813583) (xy 240.630577 -259.867543)
			(xy 240.630577 -259.922047) (xy 241.39251 -259.922047) (xy 241.39251 -259.867553) (xy 241.400265 -259.813614)
			(xy 241.415616 -259.761327) (xy 241.438252 -259.711757) (xy 241.467712 -259.665913) (xy 241.503396 -259.624727)
			(xy 241.544577 -259.589038) (xy 241.590418 -259.559573) (xy 241.639986 -259.536932) (xy 241.692271 -259.521574)
			(xy 241.746209 -259.513813) (xy 241.773456 -259.513324) (xy 241.799269 -259.513781) (xy 241.850422 -259.520745)
			(xy 241.900166 -259.534552) (xy 241.947591 -259.554949) (xy 241.991828 -259.581562) (xy 242.012216 -259.597398)
			(xy 242.022884 -259.606034) (xy 242.050062 -259.610098) (xy 242.157504 -259.56768) (xy 242.174522 -259.546344)
			(xy 242.176554 -259.532628) (xy 242.180907 -259.505753) (xy 242.196298 -259.45353) (xy 242.21896 -259.404027)
			(xy 242.248433 -259.358251) (xy 242.284117 -259.317132) (xy 242.325286 -259.281507) (xy 242.371105 -259.2521)
			(xy 242.420639 -259.229508) (xy 242.472884 -259.214191) (xy 242.526776 -259.206462) (xy 242.553998 -259.205984)
			(xy 242.583172 -259.206572) (xy 242.640838 -259.215478) (xy 242.696478 -259.233052) (xy 242.748797 -259.258886)
			(xy 242.796577 -259.292378) (xy 242.838707 -259.332749) (xy 242.874204 -259.379058) (xy 242.902245 -259.430228)
			(xy 242.922174 -259.485069) (xy 242.928394 -259.513578) (xy 242.93068 -259.526278) (xy 242.946682 -259.545836)
			(xy 243.04879 -259.588) (xy 243.073936 -259.58546) (xy 243.084604 -259.578094) (xy 243.108317 -259.562756)
			(xy 243.159328 -259.538527) (xy 243.213357 -259.522091) (xy 243.269219 -259.513809) (xy 243.297456 -259.513324)
			(xy 243.329118 -259.513932) (xy 243.391575 -259.524379) (xy 243.451451 -259.544992) (xy 243.479574 -259.559552)
			(xy 243.490242 -259.565394) (xy 243.514372 -259.566156) (xy 243.610384 -259.521452) (xy 243.62537 -259.502656)
			(xy 243.627656 -259.490718) (xy 243.633944 -259.462496) (xy 243.653883 -259.408224) (xy 243.681785 -259.357584)
			(xy 243.717012 -259.311737) (xy 243.758756 -259.271731) (xy 243.80606 -259.238485) (xy 243.85784 -259.21276)
			(xy 243.885212 -259.203444) (xy 243.898928 -259.199126) (xy 243.91747 -259.17779) (xy 243.937536 -259.06095)
			(xy 243.927122 -259.034534) (xy 243.915692 -259.025898) (xy 243.892709 -259.007773) (xy 243.852111 -258.965608)
			(xy 243.818428 -258.917738) (xy 243.79245 -258.865285) (xy 243.774788 -258.809481) (xy 243.765854 -258.751634)
			(xy 243.765324 -258.722368) (xy 243.76581 -258.695117) (xy 243.773566 -258.641169) (xy 243.788921 -258.588874)
			(xy 243.811563 -258.539297) (xy 243.841029 -258.493447) (xy 243.87672 -258.452256) (xy 243.917911 -258.416565)
			(xy 243.963761 -258.387099) (xy 244.013338 -258.364457) (xy 244.065633 -258.349102) (xy 244.119581 -258.341346)
			(xy 244.174083 -258.341346) (xy 244.228031 -258.349102) (xy 244.280326 -258.364457) (xy 244.329903 -258.387099)
			(xy 244.375753 -258.416565) (xy 244.416944 -258.452256) (xy 244.452635 -258.493447) (xy 244.482101 -258.539297)
			(xy 244.504743 -258.588874) (xy 244.520098 -258.641169) (xy 244.527854 -258.695117) (xy 244.52834 -258.722368)
			(xy 244.527849 -258.749108) (xy 244.520376 -258.802064) (xy 244.505586 -258.853459) (xy 244.483769 -258.902288)
			(xy 244.455351 -258.947593) (xy 244.420888 -258.98849) (xy 244.381055 -259.024177) (xy 244.336632 -259.053956)
			(xy 244.288488 -259.077244) (xy 244.269149 -259.08381) (xy 250.631452 -259.08381) (xy 250.63186 -259.057936)
			(xy 250.638843 -259.006661) (xy 250.652695 -258.956802) (xy 250.673162 -258.909273) (xy 250.699868 -258.864949)
			(xy 250.732322 -258.824643) (xy 250.769928 -258.789095) (xy 250.79071 -258.773676) (xy 250.800183 -258.766118)
			(xy 250.811314 -258.744626) (xy 250.812046 -258.732528) (xy 250.812046 -258.649724) (xy 250.811296 -258.63763)
			(xy 250.80017 -258.616146) (xy 250.79071 -258.608576) (xy 250.769944 -258.593139) (xy 250.732352 -258.557584)
			(xy 250.699909 -258.517277) (xy 250.673208 -258.472955) (xy 250.652741 -258.425433) (xy 250.638882 -258.375581)
			(xy 250.631886 -258.324313) (xy 250.631452 -258.298442) (xy 250.631904 -258.27064) (xy 250.639966 -258.215624)
			(xy 250.655925 -258.162359) (xy 250.679444 -258.111974) (xy 250.710025 -258.065534) (xy 250.74702 -258.024024)
			(xy 250.789647 -257.98832) (xy 250.813062 -257.973322) (xy 250.82373 -257.966972) (xy 250.83643 -257.946144)
			(xy 250.84405 -257.83921) (xy 250.834398 -257.816604) (xy 250.825 -257.80873) (xy 250.803889 -257.790522)
			(xy 250.766691 -257.748999) (xy 250.735934 -257.702504) (xy 250.712273 -257.652026) (xy 250.696213 -257.598642)
			(xy 250.688096 -257.543488) (xy 250.687586 -257.515614) (xy 250.688072 -257.488363) (xy 250.695828 -257.434415)
			(xy 250.711183 -257.38212) (xy 250.733825 -257.332543) (xy 250.763291 -257.286693) (xy 250.798982 -257.245502)
			(xy 250.840173 -257.209811) (xy 250.886023 -257.180345) (xy 250.9356 -257.157703) (xy 250.987895 -257.142348)
			(xy 251.041843 -257.134592) (xy 251.096345 -257.134592) (xy 251.150293 -257.142348) (xy 251.202588 -257.157703)
			(xy 251.252165 -257.180345) (xy 251.298015 -257.209811) (xy 251.339206 -257.245502) (xy 251.374897 -257.286693)
			(xy 251.404363 -257.332543) (xy 251.427005 -257.38212) (xy 251.44236 -257.434415) (xy 251.448082 -257.474212)
			(xy 254.171702 -257.474212) (xy 254.175773 -257.41859) (xy 254.187899 -257.364153) (xy 254.207822 -257.312062)
			(xy 254.235118 -257.263427) (xy 254.269204 -257.219284) (xy 254.309353 -257.180575) (xy 254.354711 -257.148124)
			(xy 254.404311 -257.122623) (xy 254.457095 -257.104616) (xy 254.511938 -257.094486) (xy 254.567672 -257.092449)
			(xy 254.623109 -257.098549) (xy 254.677066 -257.112655) (xy 254.728395 -257.134467) (xy 254.776001 -257.163521)
			(xy 254.818869 -257.199196) (xy 254.856086 -257.240733) (xy 254.886859 -257.287246) (xy 254.910531 -257.337743)
			(xy 254.926599 -257.39115) (xy 254.934719 -257.446326) (xy 254.935228 -257.474212) (xy 254.934719 -257.502098)
			(xy 254.926599 -257.557274) (xy 254.910531 -257.610681) (xy 254.886859 -257.661178) (xy 254.856086 -257.707691)
			(xy 254.818869 -257.749228) (xy 254.776001 -257.784903) (xy 254.728395 -257.813957) (xy 254.677066 -257.835769)
			(xy 254.623109 -257.849875) (xy 254.567672 -257.855975) (xy 254.511938 -257.853938) (xy 254.457095 -257.843808)
			(xy 254.404311 -257.825801) (xy 254.354711 -257.8003) (xy 254.309353 -257.767849) (xy 254.269204 -257.72914)
			(xy 254.235118 -257.684997) (xy 254.207822 -257.636362) (xy 254.187899 -257.584271) (xy 254.175773 -257.529834)
			(xy 254.171702 -257.474212) (xy 251.448082 -257.474212) (xy 251.450116 -257.488363) (xy 251.450602 -257.515614)
			(xy 251.45009 -257.543414) (xy 251.442036 -257.598426) (xy 251.426085 -257.651688) (xy 251.402575 -257.702072)
			(xy 251.372005 -257.748512) (xy 251.335019 -257.790025) (xy 251.292402 -257.825733) (xy 251.268992 -257.840734)
			(xy 251.258324 -257.847084) (xy 251.245624 -257.867912) (xy 251.238004 -257.974846) (xy 251.247656 -257.997452)
			(xy 251.257054 -258.005326) (xy 251.278134 -258.023568) (xy 251.315337 -258.065082) (xy 251.346099 -258.11157)
			(xy 251.369765 -258.162042) (xy 251.385438 -258.214114) (xy 256.61061 -258.214114) (xy 256.614681 -258.158492)
			(xy 256.626807 -258.104055) (xy 256.64673 -258.051964) (xy 256.674026 -258.003329) (xy 256.708112 -257.959186)
			(xy 256.748261 -257.920477) (xy 256.793619 -257.888026) (xy 256.843219 -257.862525) (xy 256.896003 -257.844518)
			(xy 256.950846 -257.834388) (xy 257.00658 -257.832351) (xy 257.062017 -257.838451) (xy 257.115974 -257.852557)
			(xy 257.167303 -257.874369) (xy 257.214909 -257.903423) (xy 257.257777 -257.939098) (xy 257.294994 -257.980635)
			(xy 257.325767 -258.027148) (xy 257.349439 -258.077645) (xy 257.365507 -258.131052) (xy 257.373627 -258.186228)
			(xy 257.374136 -258.214114) (xy 257.373627 -258.242) (xy 257.368909 -258.274058) (xy 260.969504 -258.274058)
			(xy 260.973575 -258.218436) (xy 260.985701 -258.163999) (xy 261.005624 -258.111908) (xy 261.03292 -258.063273)
			(xy 261.067006 -258.01913) (xy 261.107155 -257.980421) (xy 261.152513 -257.94797) (xy 261.202113 -257.922469)
			(xy 261.254897 -257.904462) (xy 261.30974 -257.894332) (xy 261.365474 -257.892295) (xy 261.420911 -257.898395)
			(xy 261.474868 -257.912501) (xy 261.526197 -257.934313) (xy 261.573803 -257.963367) (xy 261.616671 -257.999042)
			(xy 261.653888 -258.040579) (xy 261.684661 -258.087092) (xy 261.708333 -258.137589) (xy 261.724401 -258.190996)
			(xy 261.732521 -258.246172) (xy 261.73303 -258.274058) (xy 262.454642 -258.274058) (xy 262.458713 -258.218436)
			(xy 262.470839 -258.163999) (xy 262.490762 -258.111908) (xy 262.518058 -258.063273) (xy 262.552144 -258.01913)
			(xy 262.592293 -257.980421) (xy 262.637651 -257.94797) (xy 262.687251 -257.922469) (xy 262.740035 -257.904462)
			(xy 262.794878 -257.894332) (xy 262.850612 -257.892295) (xy 262.906049 -257.898395) (xy 262.960006 -257.912501)
			(xy 263.011335 -257.934313) (xy 263.058941 -257.963367) (xy 263.101809 -257.999042) (xy 263.139026 -258.040579)
			(xy 263.169799 -258.087092) (xy 263.193471 -258.137589) (xy 263.209539 -258.190996) (xy 263.217659 -258.246172)
			(xy 263.218168 -258.274058) (xy 263.217659 -258.301944) (xy 263.209539 -258.35712) (xy 263.193471 -258.410527)
			(xy 263.169799 -258.461024) (xy 263.139026 -258.507537) (xy 263.101809 -258.549074) (xy 263.058941 -258.584749)
			(xy 263.011335 -258.613803) (xy 262.960006 -258.635615) (xy 262.906049 -258.649721) (xy 262.850612 -258.655821)
			(xy 262.794878 -258.653784) (xy 262.740035 -258.643654) (xy 262.687251 -258.625647) (xy 262.637651 -258.600146)
			(xy 262.592293 -258.567695) (xy 262.552144 -258.528986) (xy 262.518058 -258.484843) (xy 262.490762 -258.436208)
			(xy 262.470839 -258.384117) (xy 262.458713 -258.32968) (xy 262.454642 -258.274058) (xy 261.73303 -258.274058)
			(xy 261.732521 -258.301944) (xy 261.724401 -258.35712) (xy 261.708333 -258.410527) (xy 261.684661 -258.461024)
			(xy 261.653888 -258.507537) (xy 261.616671 -258.549074) (xy 261.573803 -258.584749) (xy 261.526197 -258.613803)
			(xy 261.474868 -258.635615) (xy 261.420911 -258.649721) (xy 261.365474 -258.655821) (xy 261.30974 -258.653784)
			(xy 261.254897 -258.643654) (xy 261.202113 -258.625647) (xy 261.152513 -258.600146) (xy 261.107155 -258.567695)
			(xy 261.067006 -258.528986) (xy 261.03292 -258.484843) (xy 261.005624 -258.436208) (xy 260.985701 -258.384117)
			(xy 260.973575 -258.32968) (xy 260.969504 -258.274058) (xy 257.368909 -258.274058) (xy 257.365507 -258.297176)
			(xy 257.349439 -258.350583) (xy 257.325767 -258.40108) (xy 257.294994 -258.447593) (xy 257.257777 -258.48913)
			(xy 257.214909 -258.524805) (xy 257.167303 -258.553859) (xy 257.115974 -258.575671) (xy 257.062017 -258.589777)
			(xy 257.00658 -258.595877) (xy 256.950846 -258.59384) (xy 256.896003 -258.58371) (xy 256.843219 -258.565703)
			(xy 256.793619 -258.540202) (xy 256.748261 -258.507751) (xy 256.708112 -258.469042) (xy 256.674026 -258.424899)
			(xy 256.64673 -258.376264) (xy 256.626807 -258.324173) (xy 256.614681 -258.269736) (xy 256.61061 -258.214114)
			(xy 251.385438 -258.214114) (xy 251.385831 -258.215421) (xy 251.393955 -258.27057) (xy 251.394468 -258.298442)
			(xy 251.394016 -258.324315) (xy 251.38704 -258.375587) (xy 251.373195 -258.425445) (xy 251.352735 -258.472973)
			(xy 251.326036 -258.517298) (xy 251.293589 -258.557606) (xy 251.255989 -258.593155) (xy 251.23521 -258.608576)
			(xy 251.225762 -258.616161) (xy 251.214617 -258.637632) (xy 251.213874 -258.649724) (xy 251.213874 -258.6736)
			(xy 253.541782 -258.6736) (xy 253.545853 -258.617978) (xy 253.557979 -258.563541) (xy 253.577902 -258.51145)
			(xy 253.605198 -258.462815) (xy 253.639284 -258.418672) (xy 253.679433 -258.379963) (xy 253.724791 -258.347512)
			(xy 253.774391 -258.322011) (xy 253.827175 -258.304004) (xy 253.882018 -258.293874) (xy 253.937752 -258.291837)
			(xy 253.993189 -258.297937) (xy 254.047146 -258.312043) (xy 254.098475 -258.333855) (xy 254.146081 -258.362909)
			(xy 254.188949 -258.398584) (xy 254.226166 -258.440121) (xy 254.256939 -258.486634) (xy 254.280611 -258.537131)
			(xy 254.296679 -258.590538) (xy 254.304799 -258.645714) (xy 254.304877 -258.649978) (xy 255.126234 -258.649978)
			(xy 255.130305 -258.594356) (xy 255.142431 -258.539919) (xy 255.162354 -258.487828) (xy 255.18965 -258.439193)
			(xy 255.223736 -258.39505) (xy 255.263885 -258.356341) (xy 255.309243 -258.32389) (xy 255.358843 -258.298389)
			(xy 255.411627 -258.280382) (xy 255.46647 -258.270252) (xy 255.522204 -258.268215) (xy 255.577641 -258.274315)
			(xy 255.631598 -258.288421) (xy 255.682927 -258.310233) (xy 255.730533 -258.339287) (xy 255.773401 -258.374962)
			(xy 255.810618 -258.416499) (xy 255.841391 -258.463012) (xy 255.865063 -258.513509) (xy 255.881131 -258.566916)
			(xy 255.889251 -258.622092) (xy 255.88976 -258.649978) (xy 255.889251 -258.677864) (xy 255.881131 -258.73304)
			(xy 255.865063 -258.786447) (xy 255.841391 -258.836944) (xy 255.810618 -258.883457) (xy 255.773401 -258.924994)
			(xy 255.730533 -258.960669) (xy 255.682927 -258.989723) (xy 255.631598 -259.011535) (xy 255.577641 -259.025641)
			(xy 255.522204 -259.031741) (xy 255.46647 -259.029704) (xy 255.411627 -259.019574) (xy 255.358843 -259.001567)
			(xy 255.309243 -258.976066) (xy 255.263885 -258.943615) (xy 255.223736 -258.904906) (xy 255.18965 -258.860763)
			(xy 255.162354 -258.812128) (xy 255.142431 -258.760037) (xy 255.130305 -258.7056) (xy 255.126234 -258.649978)
			(xy 254.304877 -258.649978) (xy 254.305308 -258.6736) (xy 254.304799 -258.701486) (xy 254.296679 -258.756662)
			(xy 254.280611 -258.810069) (xy 254.256939 -258.860566) (xy 254.226166 -258.907079) (xy 254.188949 -258.948616)
			(xy 254.146081 -258.984291) (xy 254.098475 -259.013345) (xy 254.047146 -259.035157) (xy 253.993189 -259.049263)
			(xy 253.937752 -259.055363) (xy 253.882018 -259.053326) (xy 253.827175 -259.043196) (xy 253.774391 -259.025189)
			(xy 253.724791 -258.999688) (xy 253.679433 -258.967237) (xy 253.639284 -258.928528) (xy 253.605198 -258.884385)
			(xy 253.577902 -258.83575) (xy 253.557979 -258.783659) (xy 253.545853 -258.729222) (xy 253.541782 -258.6736)
			(xy 251.213874 -258.6736) (xy 251.213874 -258.732528) (xy 251.214586 -258.744628) (xy 251.225738 -258.766111)
			(xy 251.23521 -258.773676) (xy 251.255958 -258.789136) (xy 251.293549 -258.824688) (xy 251.325994 -258.864992)
			(xy 251.352696 -258.909309) (xy 251.373166 -258.956828) (xy 251.387029 -259.006676) (xy 251.394031 -259.05794)
			(xy 251.394468 -259.08381) (xy 251.393982 -259.111061) (xy 251.386226 -259.165009) (xy 251.370871 -259.217304)
			(xy 251.348229 -259.266881) (xy 251.318763 -259.312731) (xy 251.283072 -259.353922) (xy 251.241881 -259.389613)
			(xy 251.196031 -259.419079) (xy 251.146454 -259.441721) (xy 251.094159 -259.457076) (xy 251.040211 -259.464832)
			(xy 250.985709 -259.464832) (xy 250.931761 -259.457076) (xy 250.879466 -259.441721) (xy 250.829889 -259.419079)
			(xy 250.784039 -259.389613) (xy 250.742848 -259.353922) (xy 250.707157 -259.312731) (xy 250.677691 -259.266881)
			(xy 250.655049 -259.217304) (xy 250.639694 -259.165009) (xy 250.631938 -259.111061) (xy 250.631452 -259.08381)
			(xy 244.269149 -259.08381) (xy 244.263164 -259.085842) (xy 244.249448 -259.09016) (xy 244.230906 -259.111496)
			(xy 244.21084 -259.228336) (xy 244.221254 -259.254752) (xy 244.232684 -259.263388) (xy 244.255656 -259.281528)
			(xy 244.296255 -259.323689) (xy 244.32994 -259.371556) (xy 244.35592 -259.424005) (xy 244.373585 -259.479807)
			(xy 244.382521 -259.537652) (xy 244.383052 -259.566918) (xy 244.382539 -259.594168) (xy 244.374781 -259.648112)
			(xy 244.359426 -259.700404) (xy 244.336786 -259.749978) (xy 244.307322 -259.795826) (xy 244.271634 -259.837015)
			(xy 244.230447 -259.872706) (xy 244.196024 -259.894832) (xy 244.439438 -259.894832) (xy 244.443509 -259.83921)
			(xy 244.455635 -259.784773) (xy 244.475558 -259.732682) (xy 244.502854 -259.684047) (xy 244.53694 -259.639904)
			(xy 244.577089 -259.601195) (xy 244.622447 -259.568744) (xy 244.672047 -259.543243) (xy 244.724831 -259.525236)
			(xy 244.779674 -259.515106) (xy 244.835408 -259.513069) (xy 244.890845 -259.519169) (xy 244.944802 -259.533275)
			(xy 244.996131 -259.555087) (xy 245.030915 -259.576316) (xy 262.44499 -259.576316) (xy 262.449061 -259.520694)
			(xy 262.461187 -259.466257) (xy 262.48111 -259.414166) (xy 262.508406 -259.365531) (xy 262.542492 -259.321388)
			(xy 262.582641 -259.282679) (xy 262.627999 -259.250228) (xy 262.677599 -259.224727) (xy 262.730383 -259.20672)
			(xy 262.785226 -259.19659) (xy 262.84096 -259.194553) (xy 262.896397 -259.200653) (xy 262.950354 -259.214759)
			(xy 263.001683 -259.236571) (xy 263.049289 -259.265625) (xy 263.092157 -259.3013) (xy 263.129374 -259.342837)
			(xy 263.160147 -259.38935) (xy 263.183819 -259.439847) (xy 263.199887 -259.493254) (xy 263.208007 -259.54843)
			(xy 263.208516 -259.576316) (xy 263.33399 -259.576316) (xy 263.338061 -259.520694) (xy 263.350187 -259.466257)
			(xy 263.37011 -259.414166) (xy 263.397406 -259.365531) (xy 263.431492 -259.321388) (xy 263.471641 -259.282679)
			(xy 263.516999 -259.250228) (xy 263.566599 -259.224727) (xy 263.619383 -259.20672) (xy 263.674226 -259.19659)
			(xy 263.72996 -259.194553) (xy 263.785397 -259.200653) (xy 263.839354 -259.214759) (xy 263.890683 -259.236571)
			(xy 263.938289 -259.265625) (xy 263.981157 -259.3013) (xy 264.018374 -259.342837) (xy 264.049147 -259.38935)
			(xy 264.072819 -259.439847) (xy 264.088887 -259.493254) (xy 264.097007 -259.54843) (xy 264.097516 -259.576316)
			(xy 264.097007 -259.604202) (xy 264.088887 -259.659378) (xy 264.072819 -259.712785) (xy 264.049147 -259.763282)
			(xy 264.018374 -259.809795) (xy 263.981157 -259.851332) (xy 263.938289 -259.887007) (xy 263.890683 -259.916061)
			(xy 263.839354 -259.937873) (xy 263.785397 -259.951979) (xy 263.72996 -259.958079) (xy 263.674226 -259.956042)
			(xy 263.619383 -259.945912) (xy 263.566599 -259.927905) (xy 263.516999 -259.902404) (xy 263.471641 -259.869953)
			(xy 263.431492 -259.831244) (xy 263.397406 -259.787101) (xy 263.37011 -259.738466) (xy 263.350187 -259.686375)
			(xy 263.338061 -259.631938) (xy 263.33399 -259.576316) (xy 263.208516 -259.576316) (xy 263.208007 -259.604202)
			(xy 263.199887 -259.659378) (xy 263.183819 -259.712785) (xy 263.160147 -259.763282) (xy 263.129374 -259.809795)
			(xy 263.092157 -259.851332) (xy 263.049289 -259.887007) (xy 263.001683 -259.916061) (xy 262.950354 -259.937873)
			(xy 262.896397 -259.951979) (xy 262.84096 -259.958079) (xy 262.785226 -259.956042) (xy 262.730383 -259.945912)
			(xy 262.677599 -259.927905) (xy 262.627999 -259.902404) (xy 262.582641 -259.869953) (xy 262.542492 -259.831244)
			(xy 262.508406 -259.787101) (xy 262.48111 -259.738466) (xy 262.461187 -259.686375) (xy 262.449061 -259.631938)
			(xy 262.44499 -259.576316) (xy 245.030915 -259.576316) (xy 245.043737 -259.584141) (xy 245.086605 -259.619816)
			(xy 245.123822 -259.661353) (xy 245.154595 -259.707866) (xy 245.178267 -259.758363) (xy 245.194335 -259.81177)
			(xy 245.202455 -259.866946) (xy 245.202964 -259.894832) (xy 245.202455 -259.922718) (xy 245.194335 -259.977894)
			(xy 245.178267 -260.031301) (xy 245.154595 -260.081798) (xy 245.150576 -260.087872) (xy 250.630942 -260.087872)
			(xy 250.635013 -260.03225) (xy 250.647139 -259.977813) (xy 250.667062 -259.925722) (xy 250.694358 -259.877087)
			(xy 250.728444 -259.832944) (xy 250.768593 -259.794235) (xy 250.813951 -259.761784) (xy 250.863551 -259.736283)
			(xy 250.916335 -259.718276) (xy 250.971178 -259.708146) (xy 251.026912 -259.706109) (xy 251.082349 -259.712209)
			(xy 251.136306 -259.726315) (xy 251.187635 -259.748127) (xy 251.235241 -259.777181) (xy 251.278109 -259.812856)
			(xy 251.315326 -259.854393) (xy 251.346099 -259.900906) (xy 251.369771 -259.951403) (xy 251.385839 -260.00481)
			(xy 251.389204 -260.027674) (xy 254.29159 -260.027674) (xy 254.295661 -259.972052) (xy 254.307787 -259.917615)
			(xy 254.32771 -259.865524) (xy 254.355006 -259.816889) (xy 254.389092 -259.772746) (xy 254.429241 -259.734037)
			(xy 254.474599 -259.701586) (xy 254.524199 -259.676085) (xy 254.576983 -259.658078) (xy 254.631826 -259.647948)
			(xy 254.68756 -259.645911) (xy 254.742997 -259.652011) (xy 254.796954 -259.666117) (xy 254.848283 -259.687929)
			(xy 254.895889 -259.716983) (xy 254.938757 -259.752658) (xy 254.975974 -259.794195) (xy 255.006747 -259.840708)
			(xy 255.030419 -259.891205) (xy 255.046487 -259.944612) (xy 255.054607 -259.999788) (xy 255.055116 -260.027674)
			(xy 255.054607 -260.05556) (xy 255.052394 -260.0706) (xy 255.842768 -260.0706) (xy 255.846839 -260.014978)
			(xy 255.858965 -259.960541) (xy 255.878888 -259.90845) (xy 255.906184 -259.859815) (xy 255.94027 -259.815672)
			(xy 255.980419 -259.776963) (xy 256.025777 -259.744512) (xy 256.075377 -259.719011) (xy 256.128161 -259.701004)
			(xy 256.183004 -259.690874) (xy 256.238738 -259.688837) (xy 256.294175 -259.694937) (xy 256.348132 -259.709043)
			(xy 256.399461 -259.730855) (xy 256.447067 -259.759909) (xy 256.489935 -259.795584) (xy 256.527152 -259.837121)
			(xy 256.557925 -259.883634) (xy 256.581597 -259.934131) (xy 256.597665 -259.987538) (xy 256.605785 -260.042714)
			(xy 256.606294 -260.0706) (xy 256.605816 -260.096762) (xy 259.858762 -260.096762) (xy 259.862833 -260.04114)
			(xy 259.874959 -259.986703) (xy 259.894882 -259.934612) (xy 259.922178 -259.885977) (xy 259.956264 -259.841834)
			(xy 259.996413 -259.803125) (xy 260.041771 -259.770674) (xy 260.091371 -259.745173) (xy 260.144155 -259.727166)
			(xy 260.198998 -259.717036) (xy 260.254732 -259.714999) (xy 260.310169 -259.721099) (xy 260.364126 -259.735205)
			(xy 260.415455 -259.757017) (xy 260.463061 -259.786071) (xy 260.505929 -259.821746) (xy 260.543146 -259.863283)
			(xy 260.573919 -259.909796) (xy 260.597591 -259.960293) (xy 260.613659 -260.0137) (xy 260.621779 -260.068876)
			(xy 260.622288 -260.096762) (xy 260.621779 -260.124648) (xy 260.613659 -260.179824) (xy 260.597591 -260.233231)
			(xy 260.573919 -260.283728) (xy 260.543146 -260.330241) (xy 260.535911 -260.338316) (xy 266.496038 -260.338316)
			(xy 266.496612 -260.308935) (xy 266.505639 -260.250871) (xy 266.523466 -260.194879) (xy 266.549671 -260.142284)
			(xy 266.583634 -260.094331) (xy 266.624551 -260.052156) (xy 266.647676 -260.034024) (xy 266.657074 -260.026658)
			(xy 266.667488 -260.006084) (xy 266.669012 -259.902198) (xy 266.659106 -259.881116) (xy 266.649962 -259.87375)
			(xy 266.6281 -259.85556) (xy 266.589562 -259.813737) (xy 266.557658 -259.766658) (xy 266.533094 -259.715365)
			(xy 266.516413 -259.660995) (xy 266.507986 -259.604752) (xy 266.507468 -259.576316) (xy 266.507954 -259.549065)
			(xy 266.51571 -259.495117) (xy 266.531065 -259.442822) (xy 266.553707 -259.393245) (xy 266.583173 -259.347395)
			(xy 266.618864 -259.306204) (xy 266.660055 -259.270513) (xy 266.705905 -259.241047) (xy 266.755482 -259.218405)
			(xy 266.807777 -259.20305) (xy 266.861725 -259.195294) (xy 266.916227 -259.195294) (xy 266.970175 -259.20305)
			(xy 267.02247 -259.218405) (xy 267.072047 -259.241047) (xy 267.117897 -259.270513) (xy 267.159088 -259.306204)
			(xy 267.194779 -259.347395) (xy 267.224245 -259.393245) (xy 267.246887 -259.442822) (xy 267.262242 -259.495117)
			(xy 267.269998 -259.549065) (xy 267.270484 -259.576316) (xy 267.269964 -259.605699) (xy 267.26093 -259.663767)
			(xy 267.243095 -259.719762) (xy 267.216879 -259.772357) (xy 267.182905 -259.820308) (xy 267.141976 -259.862479)
			(xy 267.118846 -259.880608) (xy 267.109448 -259.887974) (xy 267.099034 -259.908548) (xy 267.09751 -260.012434)
			(xy 267.107416 -260.033516) (xy 267.11656 -260.040882) (xy 267.138373 -260.059128) (xy 267.176918 -260.100937)
			(xy 267.20883 -260.148004) (xy 267.233403 -260.199286) (xy 267.250093 -260.253647) (xy 267.258531 -260.309883)
			(xy 267.259054 -260.338316) (xy 267.892528 -260.338316) (xy 267.896599 -260.282694) (xy 267.908725 -260.228257)
			(xy 267.928648 -260.176166) (xy 267.955944 -260.127531) (xy 267.99003 -260.083388) (xy 268.030179 -260.044679)
			(xy 268.075537 -260.012228) (xy 268.125137 -259.986727) (xy 268.177921 -259.96872) (xy 268.232764 -259.95859)
			(xy 268.288498 -259.956553) (xy 268.343935 -259.962653) (xy 268.397892 -259.976759) (xy 268.449221 -259.998571)
			(xy 268.496827 -260.027625) (xy 268.539695 -260.0633) (xy 268.576912 -260.104837) (xy 268.607685 -260.15135)
			(xy 268.631357 -260.201847) (xy 268.647425 -260.255254) (xy 268.655545 -260.31043) (xy 268.656054 -260.338316)
			(xy 268.778988 -260.338316) (xy 268.783059 -260.282694) (xy 268.795185 -260.228257) (xy 268.815108 -260.176166)
			(xy 268.842404 -260.127531) (xy 268.87649 -260.083388) (xy 268.916639 -260.044679) (xy 268.961997 -260.012228)
			(xy 269.011597 -259.986727) (xy 269.064381 -259.96872) (xy 269.119224 -259.95859) (xy 269.174958 -259.956553)
			(xy 269.230395 -259.962653) (xy 269.284352 -259.976759) (xy 269.335681 -259.998571) (xy 269.383287 -260.027625)
			(xy 269.426155 -260.0633) (xy 269.463372 -260.104837) (xy 269.494145 -260.15135) (xy 269.517817 -260.201847)
			(xy 269.533885 -260.255254) (xy 269.542005 -260.31043) (xy 269.542514 -260.338316) (xy 269.542005 -260.366202)
			(xy 269.533885 -260.421378) (xy 269.517817 -260.474785) (xy 269.494145 -260.525282) (xy 269.463372 -260.571795)
			(xy 269.426155 -260.613332) (xy 269.383287 -260.649007) (xy 269.335681 -260.678061) (xy 269.284352 -260.699873)
			(xy 269.230395 -260.713979) (xy 269.174958 -260.720079) (xy 269.119224 -260.718042) (xy 269.064381 -260.707912)
			(xy 269.011597 -260.689905) (xy 268.961997 -260.664404) (xy 268.916639 -260.631953) (xy 268.87649 -260.593244)
			(xy 268.842404 -260.549101) (xy 268.815108 -260.500466) (xy 268.795185 -260.448375) (xy 268.783059 -260.393938)
			(xy 268.778988 -260.338316) (xy 268.656054 -260.338316) (xy 268.655545 -260.366202) (xy 268.647425 -260.421378)
			(xy 268.631357 -260.474785) (xy 268.607685 -260.525282) (xy 268.576912 -260.571795) (xy 268.539695 -260.613332)
			(xy 268.496827 -260.649007) (xy 268.449221 -260.678061) (xy 268.397892 -260.699873) (xy 268.343935 -260.713979)
			(xy 268.288498 -260.720079) (xy 268.232764 -260.718042) (xy 268.177921 -260.707912) (xy 268.125137 -260.689905)
			(xy 268.075537 -260.664404) (xy 268.030179 -260.631953) (xy 267.99003 -260.593244) (xy 267.955944 -260.549101)
			(xy 267.928648 -260.500466) (xy 267.908725 -260.448375) (xy 267.896599 -260.393938) (xy 267.892528 -260.338316)
			(xy 267.259054 -260.338316) (xy 267.258568 -260.365567) (xy 267.250812 -260.419515) (xy 267.235457 -260.47181)
			(xy 267.212815 -260.521387) (xy 267.183349 -260.567237) (xy 267.147658 -260.608428) (xy 267.106467 -260.644119)
			(xy 267.060617 -260.673585) (xy 267.01104 -260.696227) (xy 266.958745 -260.711582) (xy 266.904797 -260.719338)
			(xy 266.850295 -260.719338) (xy 266.796347 -260.711582) (xy 266.744052 -260.696227) (xy 266.694475 -260.673585)
			(xy 266.648625 -260.644119) (xy 266.607434 -260.608428) (xy 266.571743 -260.567237) (xy 266.542277 -260.521387)
			(xy 266.519635 -260.47181) (xy 266.50428 -260.419515) (xy 266.496524 -260.365567) (xy 266.496038 -260.338316)
			(xy 260.535911 -260.338316) (xy 260.505929 -260.371778) (xy 260.463061 -260.407453) (xy 260.415455 -260.436507)
			(xy 260.364126 -260.458319) (xy 260.310169 -260.472425) (xy 260.254732 -260.478525) (xy 260.198998 -260.476488)
			(xy 260.144155 -260.466358) (xy 260.091371 -260.448351) (xy 260.041771 -260.42285) (xy 259.996413 -260.390399)
			(xy 259.956264 -260.35169) (xy 259.922178 -260.307547) (xy 259.894882 -260.258912) (xy 259.874959 -260.206821)
			(xy 259.862833 -260.152384) (xy 259.858762 -260.096762) (xy 256.605816 -260.096762) (xy 256.605785 -260.098486)
			(xy 256.597665 -260.153662) (xy 256.581597 -260.207069) (xy 256.557925 -260.257566) (xy 256.527152 -260.304079)
			(xy 256.489935 -260.345616) (xy 256.447067 -260.381291) (xy 256.399461 -260.410345) (xy 256.348132 -260.432157)
			(xy 256.294175 -260.446263) (xy 256.238738 -260.452363) (xy 256.183004 -260.450326) (xy 256.128161 -260.440196)
			(xy 256.075377 -260.422189) (xy 256.025777 -260.396688) (xy 255.980419 -260.364237) (xy 255.94027 -260.325528)
			(xy 255.906184 -260.281385) (xy 255.878888 -260.23275) (xy 255.858965 -260.180659) (xy 255.846839 -260.126222)
			(xy 255.842768 -260.0706) (xy 255.052394 -260.0706) (xy 255.046487 -260.110736) (xy 255.030419 -260.164143)
			(xy 255.006747 -260.21464) (xy 254.975974 -260.261153) (xy 254.938757 -260.30269) (xy 254.895889 -260.338365)
			(xy 254.848283 -260.367419) (xy 254.796954 -260.389231) (xy 254.742997 -260.403337) (xy 254.68756 -260.409437)
			(xy 254.631826 -260.4074) (xy 254.576983 -260.39727) (xy 254.524199 -260.379263) (xy 254.474599 -260.353762)
			(xy 254.429241 -260.321311) (xy 254.389092 -260.282602) (xy 254.355006 -260.238459) (xy 254.32771 -260.189824)
			(xy 254.307787 -260.137733) (xy 254.295661 -260.083296) (xy 254.29159 -260.027674) (xy 251.389204 -260.027674)
			(xy 251.393959 -260.059986) (xy 251.394468 -260.087872) (xy 251.393959 -260.115758) (xy 251.385839 -260.170934)
			(xy 251.369771 -260.224341) (xy 251.346099 -260.274838) (xy 251.315326 -260.321351) (xy 251.278109 -260.362888)
			(xy 251.235241 -260.398563) (xy 251.187635 -260.427617) (xy 251.136306 -260.449429) (xy 251.082349 -260.463535)
			(xy 251.026912 -260.469635) (xy 250.971178 -260.467598) (xy 250.916335 -260.457468) (xy 250.863551 -260.439461)
			(xy 250.813951 -260.41396) (xy 250.768593 -260.381509) (xy 250.728444 -260.3428) (xy 250.694358 -260.298657)
			(xy 250.667062 -260.250022) (xy 250.647139 -260.197931) (xy 250.635013 -260.143494) (xy 250.630942 -260.087872)
			(xy 245.150576 -260.087872) (xy 245.123822 -260.128311) (xy 245.086605 -260.169848) (xy 245.043737 -260.205523)
			(xy 244.996131 -260.234577) (xy 244.944802 -260.256389) (xy 244.890845 -260.270495) (xy 244.835408 -260.276595)
			(xy 244.779674 -260.274558) (xy 244.724831 -260.264428) (xy 244.672047 -260.246421) (xy 244.622447 -260.22092)
			(xy 244.577089 -260.188469) (xy 244.53694 -260.14976) (xy 244.502854 -260.105617) (xy 244.475558 -260.056982)
			(xy 244.455635 -260.004891) (xy 244.443509 -259.950454) (xy 244.439438 -259.894832) (xy 244.196024 -259.894832)
			(xy 244.184601 -259.902174) (xy 244.135028 -259.924817) (xy 244.082738 -259.940176) (xy 244.028794 -259.947937)
			(xy 244.001544 -259.948426) (xy 243.969882 -259.947812) (xy 243.907425 -259.937367) (xy 243.84755 -259.916756)
			(xy 243.819426 -259.902198) (xy 243.808758 -259.896356) (xy 243.784628 -259.895594) (xy 243.688616 -259.940298)
			(xy 243.67363 -259.959094) (xy 243.671344 -259.971032) (xy 243.664987 -259.99938) (xy 243.644876 -260.053881)
			(xy 243.616737 -260.104705) (xy 243.58122 -260.150677) (xy 243.539147 -260.190735) (xy 243.491488 -260.223953)
			(xy 243.439346 -260.249565) (xy 243.383924 -260.266979) (xy 243.326503 -260.275792) (xy 243.297456 -260.27634)
			(xy 243.26828 -260.275764) (xy 243.210611 -260.266864) (xy 243.154967 -260.249293) (xy 243.102645 -260.22346)
			(xy 243.054862 -260.189966) (xy 243.012732 -260.149593) (xy 242.977235 -260.103279) (xy 242.949199 -260.052103)
			(xy 242.929275 -259.997258) (xy 242.92306 -259.968746) (xy 242.920774 -259.956046) (xy 242.904772 -259.936488)
			(xy 242.802664 -259.894324) (xy 242.777518 -259.896864) (xy 242.76685 -259.90423) (xy 242.743125 -259.919548)
			(xy 242.692118 -259.943781) (xy 242.638093 -259.960222) (xy 242.582234 -259.968511) (xy 242.553998 -259.969)
			(xy 242.528184 -259.968585) (xy 242.477028 -259.961613) (xy 242.427283 -259.947798) (xy 242.379859 -259.927391)
			(xy 242.335624 -259.900768) (xy 242.315238 -259.884926) (xy 242.30457 -259.87629) (xy 242.277392 -259.872226)
			(xy 242.16995 -259.914644) (xy 242.152932 -259.93598) (xy 242.1509 -259.949696) (xy 242.146514 -259.976565)
			(xy 242.131122 -260.028784) (xy 242.108462 -260.078283) (xy 242.078991 -260.124057) (xy 242.043311 -260.165174)
			(xy 242.002146 -260.200799) (xy 241.956333 -260.230207) (xy 241.906803 -260.252802) (xy 241.854564 -260.268123)
			(xy 241.800676 -260.275859) (xy 241.773456 -260.27634) (xy 241.746209 -260.275787) (xy 241.692271 -260.268026)
			(xy 241.639986 -260.252668) (xy 241.590418 -260.230027) (xy 241.544577 -260.200562) (xy 241.503396 -260.164873)
			(xy 241.467712 -260.123687) (xy 241.438252 -260.077843) (xy 241.415616 -260.028273) (xy 241.400265 -259.975986)
			(xy 241.39251 -259.922047) (xy 240.630577 -259.922047) (xy 240.630577 -259.922057) (xy 240.622818 -259.976017)
			(xy 240.607459 -260.028322) (xy 240.584811 -260.07791) (xy 240.555336 -260.123769) (xy 240.519635 -260.164966)
			(xy 240.478433 -260.200663) (xy 240.432571 -260.230132) (xy 240.382981 -260.252774) (xy 240.330673 -260.268128)
			(xy 240.276713 -260.27588) (xy 240.249456 -260.27634) (xy 240.221935 -260.275908) (xy 240.167468 -260.267972)
			(xy 240.114705 -260.252298) (xy 240.064738 -260.229212) (xy 240.018603 -260.199192) (xy 239.977256 -260.16286)
			(xy 239.941552 -260.120969) (xy 239.912233 -260.074386) (xy 239.889904 -260.024076) (xy 239.875029 -259.971082)
			(xy 239.870996 -259.943854) (xy 239.869472 -259.931408) (xy 239.855248 -259.911088) (xy 239.758982 -259.86105)
			(xy 239.734344 -259.861304) (xy 239.723168 -259.867146) (xy 239.695634 -259.880944) (xy 239.637209 -259.900423)
			(xy 239.576415 -259.910268) (xy 239.545622 -259.910834) (xy 239.518373 -259.910301) (xy 239.464428 -259.902549)
			(xy 239.412136 -259.887198) (xy 239.36256 -259.864561) (xy 239.316711 -259.835099) (xy 239.275521 -259.799413)
			(xy 239.239829 -259.758227) (xy 239.210362 -259.712382) (xy 239.187719 -259.662809) (xy 239.172362 -259.610519)
			(xy 239.164602 -259.556575) (xy 239.164114 -259.529326) (xy 239.164586 -259.502292) (xy 239.172228 -259.448767)
			(xy 239.187349 -259.396857) (xy 239.209646 -259.347601) (xy 239.238673 -259.301985) (xy 239.273848 -259.260924)
			(xy 239.314467 -259.225239) (xy 239.336834 -259.210048) (xy 239.344464 -259.204602) (xy 239.355416 -259.189405)
			(xy 239.360185 -259.171289) (xy 239.358136 -259.152669) (xy 239.349541 -259.136024) (xy 239.335545 -259.123572)
			(xy 239.326928 -259.119878) (xy 239.31701 -259.116102) (xy 239.297568 -259.107587) (xy 239.288066 -259.10286)
			(xy 239.277144 -259.097272) (xy 239.252506 -259.097272) (xy 239.157256 -259.146802) (xy 239.143286 -259.166614)
			(xy 239.141508 -259.178806) (xy 239.137315 -259.204926) (xy 239.122632 -259.255748) (xy 239.101065 -259.304054)
			(xy 239.07303 -259.348915) (xy 239.039063 -259.389471) (xy 238.999818 -259.424944) (xy 238.978186 -259.440172)
			(xy 238.96828 -259.44703) (xy 238.956596 -259.467604) (xy 238.951516 -259.57276) (xy 238.960914 -259.59435)
			(xy 238.970312 -259.602224) (xy 238.991286 -259.620476) (xy 239.028289 -259.661972) (xy 239.058878 -259.708398)
			(xy 239.082408 -259.758771) (xy 239.098381 -259.812025) (xy 239.106457 -259.867033) (xy 239.106964 -259.894832)
			(xy 239.106478 -259.922083) (xy 239.098722 -259.976031) (xy 239.083367 -260.028326) (xy 239.060725 -260.077903)
			(xy 239.031259 -260.123753) (xy 238.995568 -260.164944) (xy 238.954377 -260.200635) (xy 238.908527 -260.230101)
			(xy 238.85895 -260.252743) (xy 238.806655 -260.268098) (xy 238.752707 -260.275854) (xy 238.698205 -260.275854)
			(xy 238.644257 -260.268098) (xy 238.591962 -260.252743) (xy 238.542385 -260.230101) (xy 238.496535 -260.200635)
			(xy 238.455344 -260.164944) (xy 238.419653 -260.123753) (xy 238.390187 -260.077903) (xy 238.367545 -260.028326)
			(xy 238.35219 -259.976031) (xy 238.344434 -259.922083) (xy 238.343948 -259.894832) (xy 237.836912 -259.894832)
			(xy 237.840273 -259.906004) (xy 237.848393 -259.96118) (xy 237.848902 -259.989066) (xy 237.848393 -260.016952)
			(xy 237.840273 -260.072128) (xy 237.824205 -260.125535) (xy 237.800533 -260.176032) (xy 237.76976 -260.222545)
			(xy 237.732543 -260.264082) (xy 237.689675 -260.299757) (xy 237.642069 -260.328811) (xy 237.59074 -260.350623)
			(xy 237.536783 -260.364729) (xy 237.481346 -260.370829) (xy 237.425612 -260.368792) (xy 237.370769 -260.358662)
			(xy 237.317985 -260.340655) (xy 237.268385 -260.315154) (xy 237.223027 -260.282703) (xy 237.182878 -260.243994)
			(xy 237.148792 -260.199851) (xy 237.121496 -260.151216) (xy 237.101573 -260.099125) (xy 237.089447 -260.044688)
			(xy 237.085376 -259.989066) (xy 236.808987 -259.989066) (xy 236.797454 -260.028336) (xy 236.774805 -260.077921)
			(xy 236.74533 -260.123778) (xy 236.709628 -260.164973) (xy 236.668427 -260.200667) (xy 236.622566 -260.230135)
			(xy 236.572977 -260.252775) (xy 236.520671 -260.268128) (xy 236.466712 -260.27588) (xy 236.439456 -260.27634)
			(xy 236.409985 -260.275818) (xy 236.351739 -260.26678) (xy 236.295576 -260.248895) (xy 236.24283 -260.222587)
			(xy 236.218476 -260.205982) (xy 236.206792 -260.1976) (xy 236.178598 -260.195568) (xy 236.07268 -260.250686)
			(xy 236.058202 -260.274816) (xy 236.058202 -260.291072) (xy 236.057752 -260.31835) (xy 236.049985 -260.372349)
			(xy 236.034606 -260.424692) (xy 236.011927 -260.474311) (xy 235.982412 -260.520193) (xy 235.946663 -260.561403)
			(xy 235.905408 -260.5971) (xy 235.859489 -260.626558) (xy 235.809842 -260.649174) (xy 235.75748 -260.664487)
			(xy 235.70347 -260.672186) (xy 235.648915 -260.672114) (xy 235.594926 -260.664271) (xy 235.542605 -260.648818)
			(xy 235.493019 -260.62607) (xy 235.447178 -260.59649) (xy 235.406018 -260.560683) (xy 235.370379 -260.519378)
			(xy 235.340986 -260.473417) (xy 235.31844 -260.423739) (xy 235.3032 -260.371355) (xy 235.295576 -260.317335)
			(xy 235.295186 -260.290056) (xy 235.295186 -260.275578) (xy 235.280708 -260.251448) (xy 235.175044 -260.196584)
			(xy 235.14685 -260.198362) (xy 235.135166 -260.206744) (xy 235.110912 -260.223159) (xy 235.05844 -260.249164)
			(xy 235.002612 -260.26685) (xy 234.944737 -260.275803) (xy 234.915456 -260.27634) (xy 234.888191 -260.275798)
			(xy 234.834218 -260.268027) (xy 234.781901 -260.25265) (xy 234.732306 -260.22998) (xy 234.686446 -260.200479)
			(xy 234.645253 -260.164748) (xy 234.609568 -260.123516) (xy 234.580118 -260.077622) (xy 234.557502 -260.028003)
			(xy 234.542183 -259.975669) (xy 234.534472 -259.921687) (xy 231.116433 -259.921687) (xy 231.112454 -259.949361)
			(xy 231.097099 -260.001656) (xy 231.074457 -260.051233) (xy 231.044991 -260.097083) (xy 231.0093 -260.138274)
			(xy 230.968109 -260.173965) (xy 230.922259 -260.203431) (xy 230.872682 -260.226073) (xy 230.820387 -260.241428)
			(xy 230.766439 -260.249184) (xy 230.711937 -260.249184) (xy 230.657989 -260.241428) (xy 230.605694 -260.226073)
			(xy 230.556117 -260.203431) (xy 230.510267 -260.173965) (xy 230.469076 -260.138274) (xy 230.433385 -260.097083)
			(xy 230.403919 -260.051233) (xy 230.381277 -260.001656) (xy 230.365922 -259.949361) (xy 230.358166 -259.895413)
			(xy 230.35768 -259.868162) (xy 228.952319 -259.868162) (xy 228.952806 -259.894832) (xy 228.952297 -259.922718)
			(xy 228.944177 -259.977894) (xy 228.928109 -260.031301) (xy 228.904437 -260.081798) (xy 228.873664 -260.128311)
			(xy 228.836447 -260.169848) (xy 228.793579 -260.205523) (xy 228.745973 -260.234577) (xy 228.694644 -260.256389)
			(xy 228.640687 -260.270495) (xy 228.58525 -260.276595) (xy 228.529516 -260.274558) (xy 228.474673 -260.264428)
			(xy 228.421889 -260.246421) (xy 228.372289 -260.22092) (xy 228.326931 -260.188469) (xy 228.286782 -260.14976)
			(xy 228.252696 -260.105617) (xy 228.2254 -260.056982) (xy 228.205477 -260.004891) (xy 228.193351 -259.950454)
			(xy 228.18928 -259.894832) (xy 227.428806 -259.894832) (xy 227.42832 -259.922083) (xy 227.420564 -259.976031)
			(xy 227.405209 -260.028326) (xy 227.382567 -260.077903) (xy 227.353101 -260.123753) (xy 227.31741 -260.164944)
			(xy 227.276219 -260.200635) (xy 227.230369 -260.230101) (xy 227.180792 -260.252743) (xy 227.128497 -260.268098)
			(xy 227.074549 -260.275854) (xy 227.020047 -260.275854) (xy 226.966099 -260.268098) (xy 226.913804 -260.252743)
			(xy 226.864227 -260.230101) (xy 226.818377 -260.200635) (xy 226.777186 -260.164944) (xy 226.741495 -260.123753)
			(xy 226.712029 -260.077903) (xy 226.689387 -260.028326) (xy 226.674032 -259.976031) (xy 226.666276 -259.922083)
			(xy 226.66579 -259.894832) (xy 226.666234 -259.869224) (xy 226.673088 -259.818468) (xy 226.686665 -259.769084)
			(xy 226.706721 -259.721958) (xy 226.732895 -259.677935) (xy 226.764719 -259.637805) (xy 226.782884 -259.61975)
			(xy 226.793403 -259.608997) (xy 226.808076 -259.582749) (xy 226.814466 -259.553366) (xy 226.812018 -259.523395)
			(xy 226.800945 -259.495437) (xy 226.782207 -259.471919) (xy 226.75743 -259.454879) (xy 226.74326 -259.449824)
			(xy 226.71791 -259.44126) (xy 226.669719 -259.418004) (xy 226.625249 -259.388245) (xy 226.585372 -259.352567)
			(xy 226.550869 -259.311669) (xy 226.522416 -259.266352) (xy 226.500572 -259.217506) (xy 226.485764 -259.166087)
			(xy 226.478284 -259.113104) (xy 226.47783 -259.08635) (xy 226.121754 -259.08635) (xy 226.121658 -259.091178)
			(xy 226.113087 -259.147942) (xy 226.096104 -259.202781) (xy 226.071094 -259.254454) (xy 226.038621 -259.301795)
			(xy 225.99942 -259.343733) (xy 225.954375 -259.379322) (xy 225.904504 -259.407758) (xy 225.850935 -259.428397)
			(xy 225.823018 -259.435092) (xy 225.809048 -259.43814) (xy 225.78822 -259.457952) (xy 225.758248 -259.573268)
			(xy 225.766376 -259.600446) (xy 225.777298 -259.610098) (xy 225.796989 -259.628276) (xy 225.831586 -259.669203)
			(xy 225.860115 -259.714568) (xy 225.882018 -259.763479) (xy 225.896862 -259.814973) (xy 225.904355 -259.868037)
			(xy 225.904806 -259.894832) (xy 225.904352 -259.922084) (xy 225.896591 -259.976033) (xy 225.881232 -260.028329)
			(xy 225.858587 -260.077906) (xy 225.829117 -260.123756) (xy 225.793422 -260.164946) (xy 225.752229 -260.200637)
			(xy 225.706376 -260.230103) (xy 225.656797 -260.252744) (xy 225.6045 -260.268098) (xy 225.55055 -260.275854)
			(xy 225.523298 -260.27634) (xy 225.494895 -260.275822) (xy 225.438714 -260.267411) (xy 225.384402 -260.250762)
			(xy 225.33316 -260.226242) (xy 225.286121 -260.194393) (xy 225.244326 -260.155921) (xy 225.208699 -260.111675)
			(xy 225.180027 -260.062635) (xy 225.158946 -260.009885) (xy 225.145921 -259.954592) (xy 225.14306 -259.926328)
			(xy 225.142044 -259.913374) (xy 225.128074 -259.892038) (xy 225.031046 -259.838952) (xy 225.005646 -259.838952)
			(xy 224.994216 -259.844794) (xy 224.966493 -259.85888) (xy 224.907593 -259.878807) (xy 224.846236 -259.888892)
			(xy 224.815146 -259.889498) (xy 224.78789 -259.889058) (xy 224.733933 -259.881306) (xy 224.681628 -259.865954)
			(xy 224.632041 -259.843313) (xy 224.586181 -259.813846) (xy 224.544981 -259.778151) (xy 224.509282 -259.736956)
			(xy 224.479809 -259.6911) (xy 224.457162 -259.641515) (xy 224.441803 -259.589212) (xy 224.434045 -259.535256)
			(xy 224.127427 -259.535256) (xy 224.132812 -259.536837) (xy 224.182396 -259.559482) (xy 224.228253 -259.588952)
			(xy 224.26945 -259.624649) (xy 224.305147 -259.665845) (xy 224.334617 -259.711702) (xy 224.357262 -259.761287)
			(xy 224.372619 -259.813589) (xy 224.380377 -259.867545) (xy 224.380377 -259.922055) (xy 224.372619 -259.976011)
			(xy 224.357262 -260.028313) (xy 224.334617 -260.077898) (xy 224.305147 -260.123755) (xy 224.26945 -260.164951)
			(xy 224.228253 -260.200648) (xy 224.182396 -260.230118) (xy 224.132812 -260.252763) (xy 224.080509 -260.26812)
			(xy 224.026553 -260.275877) (xy 223.999298 -260.27634) (xy 223.970424 -260.275743) (xy 223.913333 -260.267045)
			(xy 223.858204 -260.249848) (xy 223.806294 -260.224544) (xy 223.758788 -260.19171) (xy 223.716768 -260.152096)
			(xy 223.681194 -260.106605) (xy 223.652877 -260.056275) (xy 223.642174 -260.029452) (xy 223.637856 -260.017768)
			(xy 223.62033 -260.001512) (xy 223.51746 -259.973064) (xy 223.493838 -259.97789) (xy 223.484186 -259.98551)
			(xy 223.463883 -260.001021) (xy 223.419939 -260.027085) (xy 223.372911 -260.047053) (xy 223.323639 -260.06057)
			(xy 223.273004 -260.067393) (xy 223.247458 -260.067806) (xy 223.2203 -260.06734) (xy 223.166532 -260.059651)
			(xy 223.114396 -260.04442) (xy 223.064945 -260.021954) (xy 223.019177 -259.992707) (xy 222.998284 -259.97535)
			(xy 222.988632 -259.966968) (xy 222.964248 -259.96138) (xy 222.858584 -259.989828) (xy 222.840042 -260.0071)
			(xy 222.835978 -260.019038) (xy 222.827009 -260.043738) (xy 222.803249 -260.090607) (xy 222.773281 -260.133771)
			(xy 222.737671 -260.172413) (xy 222.697093 -260.205801) (xy 222.652317 -260.233303) (xy 222.60419 -260.254399)
			(xy 222.553622 -260.268688) (xy 222.501572 -260.275901) (xy 222.475298 -260.27634) (xy 222.448049 -260.27579)
			(xy 222.394106 -260.268034) (xy 222.341816 -260.25268) (xy 222.292243 -260.23004) (xy 222.246397 -260.200576)
			(xy 222.205211 -260.164888) (xy 222.169522 -260.123701) (xy 222.140059 -260.077855) (xy 222.11742 -260.028282)
			(xy 222.102066 -259.975992) (xy 222.09431 -259.922049) (xy 221.629126 -259.922049) (xy 221.625203 -259.950027)
			(xy 221.610633 -260.001044) (xy 221.58914 -260.049552) (xy 221.561137 -260.094617) (xy 221.527166 -260.135372)
			(xy 221.487879 -260.171031) (xy 221.444034 -260.200907) (xy 221.396474 -260.224425) (xy 221.346117 -260.241133)
			(xy 221.320106 -260.246368) (xy 221.308168 -260.2484) (xy 221.28861 -260.263386) (xy 221.242636 -260.359652)
			(xy 221.243398 -260.384036) (xy 221.24924 -260.394704) (xy 221.259371 -260.413967) (xy 221.27567 -260.454325)
			(xy 221.281752 -260.475222) (xy 221.285562 -260.48843) (xy 221.304104 -260.506972) (xy 221.41434 -260.537452)
			(xy 221.439994 -260.530848) (xy 221.4499 -260.521704) (xy 221.471308 -260.501997) (xy 221.519006 -260.468673)
			(xy 221.571206 -260.442969) (xy 221.6267 -260.425479) (xy 221.684206 -260.416609) (xy 221.713298 -260.41604)
			(xy 221.740554 -260.416407) (xy 221.794512 -260.424165) (xy 221.846817 -260.439522) (xy 221.896404 -260.462168)
			(xy 221.942263 -260.491639) (xy 221.983461 -260.527337) (xy 222.019159 -260.568535) (xy 222.048631 -260.614394)
			(xy 222.071277 -260.663981) (xy 222.086635 -260.716286) (xy 222.094393 -260.770244) (xy 222.094393 -260.797548)
			(xy 222.85528 -260.797548) (xy 222.859351 -260.741926) (xy 222.871477 -260.687489) (xy 222.8914 -260.635398)
			(xy 222.918696 -260.586763) (xy 222.952782 -260.54262) (xy 222.992931 -260.503911) (xy 223.038289 -260.47146)
			(xy 223.087889 -260.445959) (xy 223.140673 -260.427952) (xy 223.195516 -260.417822) (xy 223.25125 -260.415785)
			(xy 223.306687 -260.421885) (xy 223.360644 -260.435991) (xy 223.411973 -260.457803) (xy 223.459579 -260.486857)
			(xy 223.502447 -260.522532) (xy 223.539664 -260.564069) (xy 223.570437 -260.610582) (xy 223.594109 -260.661079)
			(xy 223.610177 -260.714486) (xy 223.618297 -260.769662) (xy 223.618806 -260.797548) (xy 224.37928 -260.797548)
			(xy 224.383351 -260.741926) (xy 224.395477 -260.687489) (xy 224.4154 -260.635398) (xy 224.442696 -260.586763)
			(xy 224.476782 -260.54262) (xy 224.516931 -260.503911) (xy 224.562289 -260.47146) (xy 224.611889 -260.445959)
			(xy 224.664673 -260.427952) (xy 224.719516 -260.417822) (xy 224.77525 -260.415785) (xy 224.830687 -260.421885)
			(xy 224.884644 -260.435991) (xy 224.935973 -260.457803) (xy 224.983579 -260.486857) (xy 225.026447 -260.522532)
			(xy 225.063664 -260.564069) (xy 225.094437 -260.610582) (xy 225.118109 -260.661079) (xy 225.134177 -260.714486)
			(xy 225.142297 -260.769662) (xy 225.142806 -260.797548) (xy 225.90328 -260.797548) (xy 225.907351 -260.741926)
			(xy 225.919477 -260.687489) (xy 225.9394 -260.635398) (xy 225.966696 -260.586763) (xy 226.000782 -260.54262)
			(xy 226.040931 -260.503911) (xy 226.086289 -260.47146) (xy 226.135889 -260.445959) (xy 226.188673 -260.427952)
			(xy 226.243516 -260.417822) (xy 226.29925 -260.415785) (xy 226.354687 -260.421885) (xy 226.408644 -260.435991)
			(xy 226.459973 -260.457803) (xy 226.507579 -260.486857) (xy 226.550447 -260.522532) (xy 226.587664 -260.564069)
			(xy 226.618437 -260.610582) (xy 226.642109 -260.661079) (xy 226.658177 -260.714486) (xy 226.666297 -260.769662)
			(xy 226.666806 -260.797548) (xy 226.666297 -260.825434) (xy 226.662065 -260.85419) (xy 227.048058 -260.85419)
			(xy 227.052129 -260.798568) (xy 227.064255 -260.744131) (xy 227.084178 -260.69204) (xy 227.111474 -260.643405)
			(xy 227.14556 -260.599262) (xy 227.185709 -260.560553) (xy 227.231067 -260.528102) (xy 227.280667 -260.502601)
			(xy 227.333451 -260.484594) (xy 227.388294 -260.474464) (xy 227.444028 -260.472427) (xy 227.499465 -260.478527)
			(xy 227.553422 -260.492633) (xy 227.604751 -260.514445) (xy 227.652357 -260.543499) (xy 227.695225 -260.579174)
			(xy 227.732442 -260.620711) (xy 227.763215 -260.667224) (xy 227.786887 -260.717721) (xy 227.802955 -260.771128)
			(xy 227.806843 -260.797548) (xy 228.18928 -260.797548) (xy 228.193351 -260.741926) (xy 228.205477 -260.687489)
			(xy 228.2254 -260.635398) (xy 228.252696 -260.586763) (xy 228.286782 -260.54262) (xy 228.326931 -260.503911)
			(xy 228.372289 -260.47146) (xy 228.421889 -260.445959) (xy 228.474673 -260.427952) (xy 228.529516 -260.417822)
			(xy 228.58525 -260.415785) (xy 228.640687 -260.421885) (xy 228.694644 -260.435991) (xy 228.745973 -260.457803)
			(xy 228.793579 -260.486857) (xy 228.836447 -260.522532) (xy 228.873664 -260.564069) (xy 228.904437 -260.610582)
			(xy 228.928109 -260.661079) (xy 228.944177 -260.714486) (xy 228.952297 -260.769662) (xy 228.952806 -260.797548)
			(xy 234.533438 -260.797548) (xy 234.537509 -260.741926) (xy 234.549635 -260.687489) (xy 234.569558 -260.635398)
			(xy 234.596854 -260.586763) (xy 234.63094 -260.54262) (xy 234.671089 -260.503911) (xy 234.716447 -260.47146)
			(xy 234.766047 -260.445959) (xy 234.818831 -260.427952) (xy 234.873674 -260.417822) (xy 234.929408 -260.415785)
			(xy 234.984845 -260.421885) (xy 235.038802 -260.435991) (xy 235.090131 -260.457803) (xy 235.137737 -260.486857)
			(xy 235.180605 -260.522532) (xy 235.217822 -260.564069) (xy 235.248595 -260.610582) (xy 235.272267 -260.661079)
			(xy 235.288335 -260.714486) (xy 235.296455 -260.769662) (xy 235.296964 -260.797548) (xy 236.057438 -260.797548)
			(xy 236.061509 -260.741926) (xy 236.073635 -260.687489) (xy 236.093558 -260.635398) (xy 236.120854 -260.586763)
			(xy 236.15494 -260.54262) (xy 236.195089 -260.503911) (xy 236.240447 -260.47146) (xy 236.290047 -260.445959)
			(xy 236.342831 -260.427952) (xy 236.397674 -260.417822) (xy 236.453408 -260.415785) (xy 236.508845 -260.421885)
			(xy 236.562802 -260.435991) (xy 236.614131 -260.457803) (xy 236.661737 -260.486857) (xy 236.704605 -260.522532)
			(xy 236.741822 -260.564069) (xy 236.772595 -260.610582) (xy 236.796267 -260.661079) (xy 236.812335 -260.714486)
			(xy 236.820455 -260.769662) (xy 236.820964 -260.797548) (xy 237.581438 -260.797548) (xy 237.585509 -260.741926)
			(xy 237.597635 -260.687489) (xy 237.617558 -260.635398) (xy 237.644854 -260.586763) (xy 237.67894 -260.54262)
			(xy 237.719089 -260.503911) (xy 237.764447 -260.47146) (xy 237.814047 -260.445959) (xy 237.866831 -260.427952)
			(xy 237.921674 -260.417822) (xy 237.977408 -260.415785) (xy 238.032845 -260.421885) (xy 238.086802 -260.435991)
			(xy 238.138131 -260.457803) (xy 238.185737 -260.486857) (xy 238.228605 -260.522532) (xy 238.265822 -260.564069)
			(xy 238.296595 -260.610582) (xy 238.320267 -260.661079) (xy 238.336335 -260.714486) (xy 238.344455 -260.769662)
			(xy 238.344964 -260.797548) (xy 239.105438 -260.797548) (xy 239.109509 -260.741926) (xy 239.121635 -260.687489)
			(xy 239.141558 -260.635398) (xy 239.168854 -260.586763) (xy 239.20294 -260.54262) (xy 239.243089 -260.503911)
			(xy 239.288447 -260.47146) (xy 239.338047 -260.445959) (xy 239.390831 -260.427952) (xy 239.445674 -260.417822)
			(xy 239.501408 -260.415785) (xy 239.556845 -260.421885) (xy 239.610802 -260.435991) (xy 239.662131 -260.457803)
			(xy 239.709737 -260.486857) (xy 239.752605 -260.522532) (xy 239.789822 -260.564069) (xy 239.820595 -260.610582)
			(xy 239.844267 -260.661079) (xy 239.860335 -260.714486) (xy 239.868455 -260.769662) (xy 239.868964 -260.797548)
			(xy 240.629438 -260.797548) (xy 240.633509 -260.741926) (xy 240.645635 -260.687489) (xy 240.665558 -260.635398)
			(xy 240.692854 -260.586763) (xy 240.72694 -260.54262) (xy 240.767089 -260.503911) (xy 240.812447 -260.47146)
			(xy 240.862047 -260.445959) (xy 240.914831 -260.427952) (xy 240.969674 -260.417822) (xy 241.025408 -260.415785)
			(xy 241.080845 -260.421885) (xy 241.134802 -260.435991) (xy 241.186131 -260.457803) (xy 241.233737 -260.486857)
			(xy 241.276605 -260.522532) (xy 241.313822 -260.564069) (xy 241.344595 -260.610582) (xy 241.368267 -260.661079)
			(xy 241.384335 -260.714486) (xy 241.392455 -260.769662) (xy 241.392964 -260.797548) (xy 242.153438 -260.797548)
			(xy 242.157509 -260.741926) (xy 242.169635 -260.687489) (xy 242.189558 -260.635398) (xy 242.216854 -260.586763)
			(xy 242.25094 -260.54262) (xy 242.291089 -260.503911) (xy 242.336447 -260.47146) (xy 242.386047 -260.445959)
			(xy 242.438831 -260.427952) (xy 242.493674 -260.417822) (xy 242.549408 -260.415785) (xy 242.604845 -260.421885)
			(xy 242.658802 -260.435991) (xy 242.710131 -260.457803) (xy 242.757737 -260.486857) (xy 242.800605 -260.522532)
			(xy 242.837822 -260.564069) (xy 242.868595 -260.610582) (xy 242.892267 -260.661079) (xy 242.908335 -260.714486)
			(xy 242.916455 -260.769662) (xy 242.916964 -260.797548) (xy 242.916455 -260.825434) (xy 242.912223 -260.85419)
			(xy 243.298216 -260.85419) (xy 243.302287 -260.798568) (xy 243.314413 -260.744131) (xy 243.334336 -260.69204)
			(xy 243.361632 -260.643405) (xy 243.395718 -260.599262) (xy 243.435867 -260.560553) (xy 243.481225 -260.528102)
			(xy 243.530825 -260.502601) (xy 243.583609 -260.484594) (xy 243.638452 -260.474464) (xy 243.694186 -260.472427)
			(xy 243.749623 -260.478527) (xy 243.80358 -260.492633) (xy 243.854909 -260.514445) (xy 243.902515 -260.543499)
			(xy 243.945383 -260.579174) (xy 243.9826 -260.620711) (xy 244.013373 -260.667224) (xy 244.037045 -260.717721)
			(xy 244.053113 -260.771128) (xy 244.057001 -260.797548) (xy 244.439438 -260.797548) (xy 244.443509 -260.741926)
			(xy 244.455635 -260.687489) (xy 244.475558 -260.635398) (xy 244.502854 -260.586763) (xy 244.53694 -260.54262)
			(xy 244.577089 -260.503911) (xy 244.622447 -260.47146) (xy 244.672047 -260.445959) (xy 244.724831 -260.427952)
			(xy 244.779674 -260.417822) (xy 244.835408 -260.415785) (xy 244.890845 -260.421885) (xy 244.944802 -260.435991)
			(xy 244.996131 -260.457803) (xy 245.043737 -260.486857) (xy 245.086605 -260.522532) (xy 245.123822 -260.564069)
			(xy 245.154595 -260.610582) (xy 245.178267 -260.661079) (xy 245.194335 -260.714486) (xy 245.202455 -260.769662)
			(xy 245.202964 -260.797548) (xy 245.202455 -260.825434) (xy 245.194335 -260.88061) (xy 245.178267 -260.934017)
			(xy 245.154595 -260.984514) (xy 245.123822 -261.031027) (xy 245.086605 -261.072564) (xy 245.043737 -261.108239)
			(xy 244.996131 -261.137293) (xy 244.944802 -261.159105) (xy 244.890845 -261.173211) (xy 244.835408 -261.179311)
			(xy 244.779674 -261.177274) (xy 244.724831 -261.167144) (xy 244.672047 -261.149137) (xy 244.622447 -261.123636)
			(xy 244.577089 -261.091185) (xy 244.53694 -261.052476) (xy 244.502854 -261.008333) (xy 244.475558 -260.959698)
			(xy 244.455635 -260.907607) (xy 244.443509 -260.85317) (xy 244.439438 -260.797548) (xy 244.057001 -260.797548)
			(xy 244.061233 -260.826304) (xy 244.061742 -260.85419) (xy 244.061233 -260.882076) (xy 244.053113 -260.937252)
			(xy 244.037045 -260.990659) (xy 244.013373 -261.041156) (xy 243.9826 -261.087669) (xy 243.945383 -261.129206)
			(xy 243.902515 -261.164881) (xy 243.854909 -261.193935) (xy 243.80358 -261.215747) (xy 243.749623 -261.229853)
			(xy 243.694186 -261.235953) (xy 243.638452 -261.233916) (xy 243.583609 -261.223786) (xy 243.530825 -261.205779)
			(xy 243.481225 -261.180278) (xy 243.435867 -261.147827) (xy 243.395718 -261.109118) (xy 243.361632 -261.064975)
			(xy 243.334336 -261.01634) (xy 243.314413 -260.964249) (xy 243.302287 -260.909812) (xy 243.298216 -260.85419)
			(xy 242.912223 -260.85419) (xy 242.908335 -260.88061) (xy 242.892267 -260.934017) (xy 242.868595 -260.984514)
			(xy 242.837822 -261.031027) (xy 242.800605 -261.072564) (xy 242.757737 -261.108239) (xy 242.710131 -261.137293)
			(xy 242.658802 -261.159105) (xy 242.604845 -261.173211) (xy 242.549408 -261.179311) (xy 242.493674 -261.177274)
			(xy 242.438831 -261.167144) (xy 242.386047 -261.149137) (xy 242.336447 -261.123636) (xy 242.291089 -261.091185)
			(xy 242.25094 -261.052476) (xy 242.216854 -261.008333) (xy 242.189558 -260.959698) (xy 242.169635 -260.907607)
			(xy 242.157509 -260.85317) (xy 242.153438 -260.797548) (xy 241.392964 -260.797548) (xy 241.392455 -260.825434)
			(xy 241.384335 -260.88061) (xy 241.368267 -260.934017) (xy 241.344595 -260.984514) (xy 241.313822 -261.031027)
			(xy 241.276605 -261.072564) (xy 241.233737 -261.108239) (xy 241.186131 -261.137293) (xy 241.134802 -261.159105)
			(xy 241.080845 -261.173211) (xy 241.025408 -261.179311) (xy 240.969674 -261.177274) (xy 240.914831 -261.167144)
			(xy 240.862047 -261.149137) (xy 240.812447 -261.123636) (xy 240.767089 -261.091185) (xy 240.72694 -261.052476)
			(xy 240.692854 -261.008333) (xy 240.665558 -260.959698) (xy 240.645635 -260.907607) (xy 240.633509 -260.85317)
			(xy 240.629438 -260.797548) (xy 239.868964 -260.797548) (xy 239.868455 -260.825434) (xy 239.860335 -260.88061)
			(xy 239.844267 -260.934017) (xy 239.820595 -260.984514) (xy 239.789822 -261.031027) (xy 239.752605 -261.072564)
			(xy 239.709737 -261.108239) (xy 239.662131 -261.137293) (xy 239.610802 -261.159105) (xy 239.556845 -261.173211)
			(xy 239.501408 -261.179311) (xy 239.445674 -261.177274) (xy 239.390831 -261.167144) (xy 239.338047 -261.149137)
			(xy 239.288447 -261.123636) (xy 239.243089 -261.091185) (xy 239.20294 -261.052476) (xy 239.168854 -261.008333)
			(xy 239.141558 -260.959698) (xy 239.121635 -260.907607) (xy 239.109509 -260.85317) (xy 239.105438 -260.797548)
			(xy 238.344964 -260.797548) (xy 238.344455 -260.825434) (xy 238.336335 -260.88061) (xy 238.320267 -260.934017)
			(xy 238.296595 -260.984514) (xy 238.265822 -261.031027) (xy 238.228605 -261.072564) (xy 238.185737 -261.108239)
			(xy 238.138131 -261.137293) (xy 238.086802 -261.159105) (xy 238.032845 -261.173211) (xy 237.977408 -261.179311)
			(xy 237.921674 -261.177274) (xy 237.866831 -261.167144) (xy 237.814047 -261.149137) (xy 237.764447 -261.123636)
			(xy 237.719089 -261.091185) (xy 237.67894 -261.052476) (xy 237.644854 -261.008333) (xy 237.617558 -260.959698)
			(xy 237.597635 -260.907607) (xy 237.585509 -260.85317) (xy 237.581438 -260.797548) (xy 236.820964 -260.797548)
			(xy 236.820455 -260.825434) (xy 236.812335 -260.88061) (xy 236.796267 -260.934017) (xy 236.772595 -260.984514)
			(xy 236.741822 -261.031027) (xy 236.704605 -261.072564) (xy 236.661737 -261.108239) (xy 236.614131 -261.137293)
			(xy 236.562802 -261.159105) (xy 236.508845 -261.173211) (xy 236.453408 -261.179311) (xy 236.397674 -261.177274)
			(xy 236.342831 -261.167144) (xy 236.290047 -261.149137) (xy 236.240447 -261.123636) (xy 236.195089 -261.091185)
			(xy 236.15494 -261.052476) (xy 236.120854 -261.008333) (xy 236.093558 -260.959698) (xy 236.073635 -260.907607)
			(xy 236.061509 -260.85317) (xy 236.057438 -260.797548) (xy 235.296964 -260.797548) (xy 235.296455 -260.825434)
			(xy 235.288335 -260.88061) (xy 235.272267 -260.934017) (xy 235.248595 -260.984514) (xy 235.217822 -261.031027)
			(xy 235.180605 -261.072564) (xy 235.137737 -261.108239) (xy 235.090131 -261.137293) (xy 235.038802 -261.159105)
			(xy 234.984845 -261.173211) (xy 234.929408 -261.179311) (xy 234.873674 -261.177274) (xy 234.818831 -261.167144)
			(xy 234.766047 -261.149137) (xy 234.716447 -261.123636) (xy 234.671089 -261.091185) (xy 234.63094 -261.052476)
			(xy 234.596854 -261.008333) (xy 234.569558 -260.959698) (xy 234.549635 -260.907607) (xy 234.537509 -260.85317)
			(xy 234.533438 -260.797548) (xy 228.952806 -260.797548) (xy 228.952297 -260.825434) (xy 228.944177 -260.88061)
			(xy 228.928109 -260.934017) (xy 228.904437 -260.984514) (xy 228.873664 -261.031027) (xy 228.836447 -261.072564)
			(xy 228.793579 -261.108239) (xy 228.745973 -261.137293) (xy 228.694644 -261.159105) (xy 228.640687 -261.173211)
			(xy 228.58525 -261.179311) (xy 228.529516 -261.177274) (xy 228.474673 -261.167144) (xy 228.421889 -261.149137)
			(xy 228.372289 -261.123636) (xy 228.326931 -261.091185) (xy 228.286782 -261.052476) (xy 228.252696 -261.008333)
			(xy 228.2254 -260.959698) (xy 228.205477 -260.907607) (xy 228.193351 -260.85317) (xy 228.18928 -260.797548)
			(xy 227.806843 -260.797548) (xy 227.811075 -260.826304) (xy 227.811584 -260.85419) (xy 227.811075 -260.882076)
			(xy 227.802955 -260.937252) (xy 227.786887 -260.990659) (xy 227.763215 -261.041156) (xy 227.732442 -261.087669)
			(xy 227.695225 -261.129206) (xy 227.652357 -261.164881) (xy 227.604751 -261.193935) (xy 227.553422 -261.215747)
			(xy 227.499465 -261.229853) (xy 227.444028 -261.235953) (xy 227.388294 -261.233916) (xy 227.333451 -261.223786)
			(xy 227.280667 -261.205779) (xy 227.231067 -261.180278) (xy 227.185709 -261.147827) (xy 227.14556 -261.109118)
			(xy 227.111474 -261.064975) (xy 227.084178 -261.01634) (xy 227.064255 -260.964249) (xy 227.052129 -260.909812)
			(xy 227.048058 -260.85419) (xy 226.662065 -260.85419) (xy 226.658177 -260.88061) (xy 226.642109 -260.934017)
			(xy 226.618437 -260.984514) (xy 226.587664 -261.031027) (xy 226.550447 -261.072564) (xy 226.507579 -261.108239)
			(xy 226.459973 -261.137293) (xy 226.408644 -261.159105) (xy 226.354687 -261.173211) (xy 226.29925 -261.179311)
			(xy 226.243516 -261.177274) (xy 226.188673 -261.167144) (xy 226.135889 -261.149137) (xy 226.086289 -261.123636)
			(xy 226.040931 -261.091185) (xy 226.000782 -261.052476) (xy 225.966696 -261.008333) (xy 225.9394 -260.959698)
			(xy 225.919477 -260.907607) (xy 225.907351 -260.85317) (xy 225.90328 -260.797548) (xy 225.142806 -260.797548)
			(xy 225.142297 -260.825434) (xy 225.134177 -260.88061) (xy 225.118109 -260.934017) (xy 225.094437 -260.984514)
			(xy 225.063664 -261.031027) (xy 225.026447 -261.072564) (xy 224.983579 -261.108239) (xy 224.935973 -261.137293)
			(xy 224.884644 -261.159105) (xy 224.830687 -261.173211) (xy 224.77525 -261.179311) (xy 224.719516 -261.177274)
			(xy 224.664673 -261.167144) (xy 224.611889 -261.149137) (xy 224.562289 -261.123636) (xy 224.516931 -261.091185)
			(xy 224.476782 -261.052476) (xy 224.442696 -261.008333) (xy 224.4154 -260.959698) (xy 224.395477 -260.907607)
			(xy 224.383351 -260.85317) (xy 224.37928 -260.797548) (xy 223.618806 -260.797548) (xy 223.618297 -260.825434)
			(xy 223.610177 -260.88061) (xy 223.594109 -260.934017) (xy 223.570437 -260.984514) (xy 223.539664 -261.031027)
			(xy 223.502447 -261.072564) (xy 223.459579 -261.108239) (xy 223.411973 -261.137293) (xy 223.360644 -261.159105)
			(xy 223.306687 -261.173211) (xy 223.25125 -261.179311) (xy 223.195516 -261.177274) (xy 223.140673 -261.167144)
			(xy 223.087889 -261.149137) (xy 223.038289 -261.123636) (xy 222.992931 -261.091185) (xy 222.952782 -261.052476)
			(xy 222.918696 -261.008333) (xy 222.8914 -260.959698) (xy 222.871477 -260.907607) (xy 222.859351 -260.85317)
			(xy 222.85528 -260.797548) (xy 222.094393 -260.797548) (xy 222.094393 -260.824756) (xy 222.086635 -260.878714)
			(xy 222.071277 -260.931019) (xy 222.048631 -260.980606) (xy 222.019159 -261.026465) (xy 221.983461 -261.067663)
			(xy 221.942263 -261.103361) (xy 221.896404 -261.132832) (xy 221.846817 -261.155478) (xy 221.794512 -261.170835)
			(xy 221.740554 -261.178593) (xy 221.713298 -261.179056) (xy 221.685738 -261.178577) (xy 221.631194 -261.170631)
			(xy 221.57836 -261.15492) (xy 221.528337 -261.13177) (xy 221.482166 -261.101664) (xy 221.440807 -261.065227)
			(xy 221.405121 -261.023218) (xy 221.375851 -260.976512) (xy 221.353606 -260.92608) (xy 221.34576 -260.899656)
			(xy 221.34195 -260.886448) (xy 221.323408 -260.867906) (xy 221.213172 -260.837426) (xy 221.187518 -260.84403)
			(xy 221.177612 -260.853174) (xy 221.156211 -260.872888) (xy 221.10851 -260.906208) (xy 221.056308 -260.93191)
			(xy 221.000812 -260.949398) (xy 220.943307 -260.958268) (xy 220.914214 -260.958838) (xy 220.885279 -260.958299)
			(xy 220.828072 -260.949555) (xy 220.772845 -260.932264) (xy 220.720865 -260.906826) (xy 220.69679 -260.890766)
			(xy 220.687138 -260.884162) (xy 220.664532 -260.880606) (xy 220.565472 -260.910578) (xy 220.548708 -260.926072)
			(xy 220.54439 -260.937248) (xy 220.533428 -260.963594) (xy 220.504841 -261.012979) (xy 220.469222 -261.057558)
			(xy 220.427364 -261.096339) (xy 220.3802 -261.128457) (xy 220.328781 -261.153198) (xy 220.274252 -261.17001)
			(xy 220.217829 -261.178518) (xy 220.189298 -261.179056) (xy 220.16205 -261.178474) (xy 220.10811 -261.170718)
			(xy 220.055822 -261.155365) (xy 220.006251 -261.132726) (xy 219.960407 -261.103264) (xy 219.919222 -261.067577)
			(xy 219.883535 -261.026392) (xy 219.854073 -260.980547) (xy 219.831435 -260.930976) (xy 219.816082 -260.878688)
			(xy 219.808326 -260.824748) (xy 219.046271 -260.824748) (xy 219.04627 -260.824795) (xy 219.038509 -260.878733)
			(xy 219.02315 -260.931018) (xy 219.000506 -260.980585) (xy 218.97104 -261.026425) (xy 218.935349 -261.067605)
			(xy 218.894162 -261.103287) (xy 218.848316 -261.132744) (xy 218.798744 -261.155377) (xy 218.746456 -261.170725)
			(xy 218.692516 -261.178476) (xy 218.638022 -261.178472) (xy 218.584083 -261.170712) (xy 218.531797 -261.155355)
			(xy 218.482229 -261.132714) (xy 218.436388 -261.10325) (xy 218.395206 -261.067561) (xy 218.359523 -261.026375)
			(xy 218.330064 -260.98053) (xy 218.307428 -260.930959) (xy 218.292078 -260.878672) (xy 218.284325 -260.824732)
			(xy 218.284327 -260.770238) (xy 218.292084 -260.716299) (xy 218.307439 -260.664013) (xy 218.330078 -260.614444)
			(xy 218.35954 -260.568601) (xy 218.395227 -260.527418) (xy 218.436412 -260.491733) (xy 218.482255 -260.462272)
			(xy 218.531825 -260.439634) (xy 218.584112 -260.424282) (xy 218.638051 -260.416526) (xy 218.665298 -260.41604)
			(xy 218.696767 -260.416675) (xy 218.758851 -260.427006) (xy 218.818397 -260.447388) (xy 218.8464 -260.46176)
			(xy 218.858592 -260.468364) (xy 218.886278 -260.467348) (xy 218.984576 -260.404864) (xy 218.997022 -260.380226)
			(xy 218.99626 -260.366256) (xy 218.995498 -260.343396) (xy 218.996006 -260.325108) (xy 218.996514 -260.311138)
			(xy 218.984068 -260.287008) (xy 218.88577 -260.225032) (xy 218.858592 -260.224016) (xy 218.8464 -260.23062)
			(xy 218.818397 -260.244991) (xy 218.75885 -260.265368) (xy 218.696766 -260.275696) (xy 218.665298 -260.27634)
			(xy 218.638045 -260.275842) (xy 218.584093 -260.268085) (xy 218.531795 -260.252728) (xy 218.482215 -260.230085)
			(xy 218.436361 -260.200616) (xy 218.395169 -260.164921) (xy 218.359476 -260.123727) (xy 218.330008 -260.077873)
			(xy 218.307367 -260.028292) (xy 218.292012 -259.975993) (xy 218.284257 -259.922041) (xy 215.661808 -259.922041)
			(xy 215.638701 -259.942063) (xy 215.592851 -259.971529) (xy 215.543274 -259.994171) (xy 215.490979 -260.009526)
			(xy 215.437031 -260.017282) (xy 215.382529 -260.017282) (xy 215.328581 -260.009526) (xy 215.276286 -259.994171)
			(xy 215.226709 -259.971529) (xy 215.180859 -259.942063) (xy 215.139668 -259.906372) (xy 215.103977 -259.865181)
			(xy 215.074511 -259.819331) (xy 215.051869 -259.769754) (xy 215.036514 -259.717459) (xy 215.028758 -259.663511)
			(xy 215.028272 -259.63626) (xy 215.028797 -259.609213) (xy 215.036436 -259.555662) (xy 215.051556 -259.503724)
			(xy 215.073854 -259.45444) (xy 215.102883 -259.408796) (xy 215.138063 -259.367705) (xy 215.158066 -259.349494)
			(xy 215.166448 -259.342128) (xy 215.175338 -259.322316) (xy 215.174576 -259.222748) (xy 215.165432 -259.20319)
			(xy 215.156796 -259.195824) (xy 215.136064 -259.177591) (xy 215.099529 -259.136202) (xy 215.069339 -259.089979)
			(xy 215.046127 -259.039888) (xy 215.030375 -258.986975) (xy 215.022413 -258.932344) (xy 215.021922 -258.90474)
			(xy 141.208293 -258.90474) (xy 141.19515 -258.924605) (xy 141.157933 -258.966142) (xy 141.115065 -259.001817)
			(xy 141.067459 -259.030871) (xy 141.01613 -259.052683) (xy 140.962173 -259.066789) (xy 140.906736 -259.072889)
			(xy 140.851002 -259.070852) (xy 140.796159 -259.060722) (xy 140.743375 -259.042715) (xy 140.693775 -259.017214)
			(xy 140.648417 -258.984763) (xy 140.608268 -258.946054) (xy 140.574182 -258.901911) (xy 140.546886 -258.853276)
			(xy 140.526963 -258.801185) (xy 140.514837 -258.746748) (xy 140.510766 -258.691126) (xy 139.787455 -258.691126)
			(xy 139.781287 -258.73304) (xy 139.765219 -258.786447) (xy 139.741547 -258.836944) (xy 139.710774 -258.883457)
			(xy 139.673557 -258.924994) (xy 139.630689 -258.960669) (xy 139.583083 -258.989723) (xy 139.531754 -259.011535)
			(xy 139.477797 -259.025641) (xy 139.42236 -259.031741) (xy 139.366626 -259.029704) (xy 139.311783 -259.019574)
			(xy 139.258999 -259.001567) (xy 139.209399 -258.976066) (xy 139.164041 -258.943615) (xy 139.123892 -258.904906)
			(xy 139.089806 -258.860763) (xy 139.06251 -258.812128) (xy 139.042587 -258.760037) (xy 139.030461 -258.7056)
			(xy 139.02639 -258.649978) (xy 137.989789 -258.649978) (xy 137.990072 -258.665472) (xy 137.989563 -258.693358)
			(xy 137.981443 -258.748534) (xy 137.965375 -258.801941) (xy 137.941703 -258.852438) (xy 137.91093 -258.898951)
			(xy 137.873713 -258.940488) (xy 137.830845 -258.976163) (xy 137.783239 -259.005217) (xy 137.73191 -259.027029)
			(xy 137.677953 -259.041135) (xy 137.622516 -259.047235) (xy 137.566782 -259.045198) (xy 137.511939 -259.035068)
			(xy 137.459155 -259.017061) (xy 137.409555 -258.99156) (xy 137.364197 -258.959109) (xy 137.324048 -258.9204)
			(xy 137.289962 -258.876257) (xy 137.262666 -258.827622) (xy 137.242743 -258.775531) (xy 137.230617 -258.721094)
			(xy 137.226546 -258.665472) (xy 122.568916 -258.665472) (xy 122.564879 -258.669978) (xy 122.522011 -258.705653)
			(xy 122.474405 -258.734707) (xy 122.423076 -258.756519) (xy 122.369119 -258.770625) (xy 122.313682 -258.776725)
			(xy 122.257948 -258.774688) (xy 122.203105 -258.764558) (xy 122.150321 -258.746551) (xy 122.100721 -258.72105)
			(xy 122.055363 -258.688599) (xy 122.015214 -258.64989) (xy 121.981128 -258.605747) (xy 121.953832 -258.557112)
			(xy 121.933909 -258.505021) (xy 121.921783 -258.450584) (xy 121.917712 -258.394962) (xy 119.633238 -258.394962)
			(xy 119.632729 -258.422848) (xy 119.624609 -258.478024) (xy 119.608541 -258.531431) (xy 119.584869 -258.581928)
			(xy 119.554096 -258.628441) (xy 119.516879 -258.669978) (xy 119.474011 -258.705653) (xy 119.426405 -258.734707)
			(xy 119.375076 -258.756519) (xy 119.321119 -258.770625) (xy 119.265682 -258.776725) (xy 119.209948 -258.774688)
			(xy 119.155105 -258.764558) (xy 119.102321 -258.746551) (xy 119.052721 -258.72105) (xy 119.007363 -258.688599)
			(xy 118.967214 -258.64989) (xy 118.933128 -258.605747) (xy 118.905832 -258.557112) (xy 118.885909 -258.505021)
			(xy 118.873783 -258.450584) (xy 118.869712 -258.394962) (xy 117.756519 -258.394962) (xy 117.752978 -258.407021)
			(xy 117.730332 -258.456609) (xy 117.700859 -258.502468) (xy 117.66516 -258.543667) (xy 117.62396 -258.579365)
			(xy 117.5781 -258.608837) (xy 117.528512 -258.631482) (xy 117.476206 -258.646839) (xy 117.422247 -258.654596)
			(xy 117.39499 -258.655058) (xy 117.374442 -258.654758) (xy 117.333586 -258.650305) (xy 117.313456 -258.646168)
			(xy 117.301518 -258.643628) (xy 117.27815 -258.649724) (xy 117.198394 -258.720336) (xy 117.189504 -258.742688)
			(xy 117.19052 -258.75488) (xy 117.192298 -258.79044) (xy 117.191812 -258.817691) (xy 117.184056 -258.871639)
			(xy 117.168701 -258.923934) (xy 117.146059 -258.973511) (xy 117.116593 -259.019361) (xy 117.080902 -259.060552)
			(xy 117.039711 -259.096243) (xy 116.993861 -259.125709) (xy 116.944284 -259.148351) (xy 116.891989 -259.163706)
			(xy 116.838041 -259.171462) (xy 116.783539 -259.171462) (xy 116.729591 -259.163706) (xy 116.677296 -259.148351)
			(xy 116.627719 -259.125709) (xy 116.581869 -259.096243) (xy 116.540678 -259.060552) (xy 116.504987 -259.019361)
			(xy 116.475521 -258.973511) (xy 116.452879 -258.923934) (xy 116.437524 -258.871639) (xy 116.429768 -258.817691)
			(xy 116.429282 -258.79044) (xy 116.429857 -258.761315) (xy 116.438719 -258.703744) (xy 116.456227 -258.648188)
			(xy 116.481976 -258.595939) (xy 116.515366 -258.548209) (xy 116.555622 -258.506109) (xy 116.57838 -258.487926)
			(xy 116.587778 -258.48056) (xy 116.598192 -258.459224) (xy 116.59743 -258.354068) (xy 116.586762 -258.332986)
			(xy 116.576856 -258.325874) (xy 116.553429 -258.307703) (xy 116.511899 -258.265397) (xy 116.477407 -258.21718)
			(xy 116.450783 -258.16421) (xy 116.432668 -258.107762) (xy 116.423496 -258.049192) (xy 116.422932 -258.01955)
			(xy 110.270431 -258.01955) (xy 110.273508 -258.030032) (xy 110.28126 -258.083989) (xy 110.28172 -258.111244)
			(xy 110.281231 -258.138687) (xy 110.273379 -258.193009) (xy 110.257816 -258.245642) (xy 110.234863 -258.295499)
			(xy 110.204996 -258.341547) (xy 110.168831 -258.382834) (xy 110.127118 -258.418506) (xy 110.104174 -258.43357)
			(xy 110.093252 -258.440682) (xy 110.080552 -258.463288) (xy 110.07979 -258.57454) (xy 110.091982 -258.5974)
			(xy 110.10265 -258.604512) (xy 110.124965 -258.619731) (xy 110.165531 -258.655391) (xy 110.200659 -258.696419)
			(xy 110.229646 -258.741994) (xy 110.251912 -258.791202) (xy 110.267012 -258.84306) (xy 110.274642 -258.89653)
			(xy 110.275116 -258.923536) (xy 110.274656 -258.950788) (xy 110.266894 -259.004736) (xy 110.251535 -259.057031)
			(xy 110.22889 -259.106608) (xy 110.199421 -259.152457) (xy 110.163727 -259.193647) (xy 110.122535 -259.229338)
			(xy 110.076683 -259.258804) (xy 110.027104 -259.281445) (xy 109.974809 -259.2968) (xy 109.92086 -259.304558)
			(xy 109.893608 -259.305044) (xy 109.867291 -259.304618) (xy 109.815157 -259.29739) (xy 109.764508 -259.283071)
			(xy 109.716307 -259.261931) (xy 109.671466 -259.234372) (xy 109.630834 -259.200915) (xy 109.612684 -259.181854)
			(xy 109.605163 -259.174451) (xy 109.585883 -259.165926) (xy 109.575346 -259.165344) (xy 109.50067 -259.165344)
			(xy 109.490121 -259.165884) (xy 109.470825 -259.17441) (xy 109.463332 -259.181854) (xy 109.445173 -259.200909)
			(xy 109.404559 -259.234391) (xy 109.359724 -259.261966) (xy 109.311521 -259.283109) (xy 109.260867 -259.297418)
			(xy 109.208726 -259.304621) (xy 109.182408 -259.305044) (xy 109.156091 -259.304618) (xy 109.103957 -259.29739)
			(xy 109.053308 -259.283071) (xy 109.005107 -259.261931) (xy 108.960266 -259.234372) (xy 108.919634 -259.200915)
			(xy 108.901484 -259.181854) (xy 108.893963 -259.174451) (xy 108.874683 -259.165926) (xy 108.864146 -259.165344)
			(xy 108.78947 -259.165344) (xy 108.778921 -259.165884) (xy 108.759625 -259.17441) (xy 108.752132 -259.181854)
			(xy 108.733973 -259.200909) (xy 108.693359 -259.234391) (xy 108.648524 -259.261966) (xy 108.600321 -259.283109)
			(xy 108.549667 -259.297418) (xy 108.497526 -259.304621) (xy 108.471208 -259.305044) (xy 108.443959 -259.304515)
			(xy 108.390014 -259.29676) (xy 108.337723 -259.281408) (xy 108.288148 -259.258771) (xy 108.242299 -259.229308)
			(xy 108.20111 -259.193622) (xy 108.165418 -259.152436) (xy 108.135951 -259.106591) (xy 108.113307 -259.057019)
			(xy 108.097949 -259.004729) (xy 108.090188 -258.950785) (xy 108.0897 -258.923536) (xy 86.81222 -258.923536)
			(xy 86.808233 -258.925969) (xy 86.756904 -258.947781) (xy 86.702947 -258.961887) (xy 86.64751 -258.967987)
			(xy 86.591776 -258.96595) (xy 86.536933 -258.95582) (xy 86.484149 -258.937813) (xy 86.434549 -258.912312)
			(xy 86.389191 -258.879861) (xy 86.349042 -258.841152) (xy 86.314956 -258.797009) (xy 86.28766 -258.748374)
			(xy 86.267737 -258.696283) (xy 86.255611 -258.641846) (xy 86.25154 -258.586224) (xy 86.117462 -258.586224)
			(xy 86.122255 -258.61879) (xy 86.122764 -258.646676) (xy 86.122255 -258.674562) (xy 86.114135 -258.729738)
			(xy 86.098067 -258.783145) (xy 86.074395 -258.833642) (xy 86.043622 -258.880155) (xy 86.006405 -258.921692)
			(xy 85.963537 -258.957367) (xy 85.915931 -258.986421) (xy 85.864602 -259.008233) (xy 85.810645 -259.022339)
			(xy 85.755208 -259.028439) (xy 85.699474 -259.026402) (xy 85.644631 -259.016272) (xy 85.591847 -258.998265)
			(xy 85.542247 -258.972764) (xy 85.496889 -258.940313) (xy 85.45674 -258.901604) (xy 85.422654 -258.857461)
			(xy 85.395358 -258.808826) (xy 85.375435 -258.756735) (xy 85.363309 -258.702298) (xy 85.359238 -258.646676)
			(xy 85.203389 -258.646676) (xy 85.189001 -258.694499) (xy 85.165329 -258.744996) (xy 85.134556 -258.791509)
			(xy 85.097339 -258.833046) (xy 85.054471 -258.868721) (xy 85.006865 -258.897775) (xy 84.955536 -258.919587)
			(xy 84.901579 -258.933693) (xy 84.846142 -258.939793) (xy 84.790408 -258.937756) (xy 84.735565 -258.927626)
			(xy 84.682781 -258.909619) (xy 84.633181 -258.884118) (xy 84.587823 -258.851667) (xy 84.547674 -258.812958)
			(xy 84.513588 -258.768815) (xy 84.486292 -258.72018) (xy 84.466369 -258.668089) (xy 84.454243 -258.613652)
			(xy 84.450172 -258.55803) (xy 40.899334 -258.55803) (xy 40.899334 -259.782564) (xy 112.163606 -259.782564)
			(xy 112.164087 -259.756519) (xy 112.171178 -259.704915) (xy 112.185224 -259.654755) (xy 112.205962 -259.606972)
			(xy 112.233009 -259.562455) (xy 112.26586 -259.522031) (xy 112.303905 -259.486451) (xy 112.346436 -259.456379)
			(xy 112.369346 -259.443982) (xy 112.381091 -259.437376) (xy 112.400901 -259.419124) (xy 112.41525 -259.396327)
			(xy 112.423139 -259.370572) (xy 112.42402 -259.34365) (xy 112.417831 -259.317434) (xy 112.405003 -259.293748)
			(xy 112.396016 -259.283708) (xy 112.376344 -259.262312) (xy 112.343067 -259.214662) (xy 112.31741 -259.162512)
			(xy 112.29997 -259.107071) (xy 112.291151 -259.049624) (xy 112.290606 -259.020564) (xy 112.291092 -258.993313)
			(xy 112.298848 -258.939365) (xy 112.314203 -258.88707) (xy 112.336845 -258.837493) (xy 112.366311 -258.791643)
			(xy 112.402002 -258.750452) (xy 112.443193 -258.714761) (xy 112.489043 -258.685295) (xy 112.53862 -258.662653)
			(xy 112.590915 -258.647298) (xy 112.644863 -258.639542) (xy 112.699365 -258.639542) (xy 112.753313 -258.647298)
			(xy 112.805608 -258.662653) (xy 112.855185 -258.685295) (xy 112.901035 -258.714761) (xy 112.942226 -258.750452)
			(xy 112.977917 -258.791643) (xy 113.007383 -258.837493) (xy 113.030025 -258.88707) (xy 113.04538 -258.939365)
			(xy 113.053136 -258.993313) (xy 113.053622 -259.020564) (xy 113.179096 -259.020564) (xy 113.183167 -258.964942)
			(xy 113.195293 -258.910505) (xy 113.215216 -258.858414) (xy 113.242512 -258.809779) (xy 113.276598 -258.765636)
			(xy 113.316747 -258.726927) (xy 113.362105 -258.694476) (xy 113.411705 -258.668975) (xy 113.464489 -258.650968)
			(xy 113.519332 -258.640838) (xy 113.575066 -258.638801) (xy 113.630503 -258.644901) (xy 113.68446 -258.659007)
			(xy 113.735789 -258.680819) (xy 113.783395 -258.709873) (xy 113.826263 -258.745548) (xy 113.858521 -258.78155)
			(xy 114.860322 -258.78155) (xy 114.864393 -258.725928) (xy 114.876519 -258.671491) (xy 114.896442 -258.6194)
			(xy 114.923738 -258.570765) (xy 114.957824 -258.526622) (xy 114.997973 -258.487913) (xy 115.043331 -258.455462)
			(xy 115.092931 -258.429961) (xy 115.145715 -258.411954) (xy 115.200558 -258.401824) (xy 115.256292 -258.399787)
			(xy 115.311729 -258.405887) (xy 115.365686 -258.419993) (xy 115.417015 -258.441805) (xy 115.464621 -258.470859)
			(xy 115.507489 -258.506534) (xy 115.544706 -258.548071) (xy 115.575479 -258.594584) (xy 115.599151 -258.645081)
			(xy 115.615219 -258.698488) (xy 115.623339 -258.753664) (xy 115.623848 -258.78155) (xy 115.623339 -258.809436)
			(xy 115.615219 -258.864612) (xy 115.599151 -258.918019) (xy 115.575479 -258.968516) (xy 115.544706 -259.015029)
			(xy 115.507489 -259.056566) (xy 115.464621 -259.092241) (xy 115.417015 -259.121295) (xy 115.365686 -259.143107)
			(xy 115.311729 -259.157213) (xy 115.256292 -259.163313) (xy 115.200558 -259.161276) (xy 115.145715 -259.151146)
			(xy 115.092931 -259.133139) (xy 115.043331 -259.107638) (xy 114.997973 -259.075187) (xy 114.957824 -259.036478)
			(xy 114.923738 -258.992335) (xy 114.896442 -258.9437) (xy 114.876519 -258.891609) (xy 114.864393 -258.837172)
			(xy 114.860322 -258.78155) (xy 113.858521 -258.78155) (xy 113.86348 -258.787085) (xy 113.894253 -258.833598)
			(xy 113.917925 -258.884095) (xy 113.933993 -258.937502) (xy 113.942113 -258.992678) (xy 113.942622 -259.020564)
			(xy 113.942113 -259.04845) (xy 113.933993 -259.103626) (xy 113.917925 -259.157033) (xy 113.894253 -259.20753)
			(xy 113.86348 -259.254043) (xy 113.826263 -259.29558) (xy 113.783395 -259.331255) (xy 113.735789 -259.360309)
			(xy 113.68446 -259.382121) (xy 113.630503 -259.396227) (xy 113.575066 -259.402327) (xy 113.519332 -259.40029)
			(xy 113.464489 -259.39016) (xy 113.411705 -259.372153) (xy 113.362105 -259.346652) (xy 113.316747 -259.314201)
			(xy 113.276598 -259.275492) (xy 113.242512 -259.231349) (xy 113.215216 -259.182714) (xy 113.195293 -259.130623)
			(xy 113.183167 -259.076186) (xy 113.179096 -259.020564) (xy 113.053622 -259.020564) (xy 113.053203 -259.046611)
			(xy 113.046106 -259.09822) (xy 113.032054 -259.148383) (xy 113.011307 -259.196168) (xy 112.984252 -259.240686)
			(xy 112.951392 -259.281109) (xy 112.913337 -259.316685) (xy 112.870796 -259.346753) (xy 112.847882 -259.359146)
			(xy 112.836111 -259.365705) (xy 112.816309 -259.383972) (xy 112.801969 -259.406779) (xy 112.794087 -259.43254)
			(xy 112.79321 -259.459466) (xy 112.7994 -259.485686) (xy 112.812226 -259.509377) (xy 112.821212 -259.51942)
			(xy 112.835926 -259.535422) (xy 114.207542 -259.535422) (xy 114.211613 -259.4798) (xy 114.223739 -259.425363)
			(xy 114.243662 -259.373272) (xy 114.270958 -259.324637) (xy 114.305044 -259.280494) (xy 114.345193 -259.241785)
			(xy 114.390551 -259.209334) (xy 114.440151 -259.183833) (xy 114.492935 -259.165826) (xy 114.547778 -259.155696)
			(xy 114.603512 -259.153659) (xy 114.658949 -259.159759) (xy 114.712906 -259.173865) (xy 114.755017 -259.19176)
			(xy 123.580396 -259.19176) (xy 123.584467 -259.136138) (xy 123.596593 -259.081701) (xy 123.616516 -259.02961)
			(xy 123.643812 -258.980975) (xy 123.677898 -258.936832) (xy 123.718047 -258.898123) (xy 123.763405 -258.865672)
			(xy 123.813005 -258.840171) (xy 123.865789 -258.822164) (xy 123.920632 -258.812034) (xy 123.976366 -258.809997)
			(xy 124.031803 -258.816097) (xy 124.08576 -258.830203) (xy 124.137089 -258.852015) (xy 124.184695 -258.881069)
			(xy 124.227563 -258.916744) (xy 124.26478 -258.958281) (xy 124.295553 -259.004794) (xy 124.319225 -259.055291)
			(xy 124.335293 -259.108698) (xy 124.341013 -259.147564) (xy 130.338828 -259.147564) (xy 130.342899 -259.091942)
			(xy 130.355025 -259.037505) (xy 130.374948 -258.985414) (xy 130.402244 -258.936779) (xy 130.43633 -258.892636)
			(xy 130.476479 -258.853927) (xy 130.521837 -258.821476) (xy 130.571437 -258.795975) (xy 130.624221 -258.777968)
			(xy 130.679064 -258.767838) (xy 130.734798 -258.765801) (xy 130.790235 -258.771901) (xy 130.844192 -258.786007)
			(xy 130.895521 -258.807819) (xy 130.943127 -258.836873) (xy 130.985995 -258.872548) (xy 131.023212 -258.914085)
			(xy 131.053985 -258.960598) (xy 131.077657 -259.011095) (xy 131.093725 -259.064502) (xy 131.101845 -259.119678)
			(xy 131.102354 -259.147564) (xy 131.101845 -259.17545) (xy 131.093725 -259.230626) (xy 131.077657 -259.284033)
			(xy 131.053985 -259.33453) (xy 131.023212 -259.381043) (xy 130.985995 -259.42258) (xy 130.943127 -259.458255)
			(xy 130.895521 -259.487309) (xy 130.844192 -259.509121) (xy 130.790235 -259.523227) (xy 130.734798 -259.529327)
			(xy 130.679064 -259.52729) (xy 130.624221 -259.51716) (xy 130.571437 -259.499153) (xy 130.521837 -259.473652)
			(xy 130.476479 -259.441201) (xy 130.43633 -259.402492) (xy 130.402244 -259.358349) (xy 130.374948 -259.309714)
			(xy 130.355025 -259.257623) (xy 130.342899 -259.203186) (xy 130.338828 -259.147564) (xy 124.341013 -259.147564)
			(xy 124.343413 -259.163874) (xy 124.343922 -259.19176) (xy 124.343413 -259.219646) (xy 124.335293 -259.274822)
			(xy 124.319225 -259.328229) (xy 124.295553 -259.378726) (xy 124.26478 -259.425239) (xy 124.227563 -259.466776)
			(xy 124.184695 -259.502451) (xy 124.137089 -259.531505) (xy 124.08576 -259.553317) (xy 124.031803 -259.567423)
			(xy 123.976366 -259.573523) (xy 123.920632 -259.571486) (xy 123.865789 -259.561356) (xy 123.813005 -259.543349)
			(xy 123.763405 -259.517848) (xy 123.718047 -259.485397) (xy 123.677898 -259.446688) (xy 123.643812 -259.402545)
			(xy 123.616516 -259.35391) (xy 123.596593 -259.301819) (xy 123.584467 -259.247382) (xy 123.580396 -259.19176)
			(xy 114.755017 -259.19176) (xy 114.764235 -259.195677) (xy 114.811841 -259.224731) (xy 114.854709 -259.260406)
			(xy 114.891926 -259.301943) (xy 114.922699 -259.348456) (xy 114.946371 -259.398953) (xy 114.962439 -259.45236)
			(xy 114.970559 -259.507536) (xy 114.971068 -259.535422) (xy 114.970559 -259.563308) (xy 114.962439 -259.618484)
			(xy 114.946371 -259.671891) (xy 114.922699 -259.722388) (xy 114.891926 -259.768901) (xy 114.854709 -259.810438)
			(xy 114.811841 -259.846113) (xy 114.764235 -259.875167) (xy 114.712906 -259.896979) (xy 114.658949 -259.911085)
			(xy 114.603512 -259.917185) (xy 114.547778 -259.915148) (xy 114.492935 -259.905018) (xy 114.440151 -259.887011)
			(xy 114.390551 -259.86151) (xy 114.345193 -259.829059) (xy 114.305044 -259.79035) (xy 114.270958 -259.746207)
			(xy 114.243662 -259.697572) (xy 114.223739 -259.645481) (xy 114.211613 -259.591044) (xy 114.207542 -259.535422)
			(xy 112.835926 -259.535422) (xy 112.840885 -259.540815) (xy 112.874165 -259.588464) (xy 112.899823 -259.640614)
			(xy 112.917262 -259.696056) (xy 112.926079 -259.753504) (xy 112.926622 -259.782564) (xy 112.926136 -259.809815)
			(xy 112.91838 -259.863763) (xy 112.903025 -259.916058) (xy 112.901699 -259.918962) (xy 118.869712 -259.918962)
			(xy 118.873783 -259.86334) (xy 118.885909 -259.808903) (xy 118.905832 -259.756812) (xy 118.933128 -259.708177)
			(xy 118.967214 -259.664034) (xy 119.007363 -259.625325) (xy 119.052721 -259.592874) (xy 119.102321 -259.567373)
			(xy 119.155105 -259.549366) (xy 119.209948 -259.539236) (xy 119.265682 -259.537199) (xy 119.321119 -259.543299)
			(xy 119.375076 -259.557405) (xy 119.426405 -259.579217) (xy 119.474011 -259.608271) (xy 119.516879 -259.643946)
			(xy 119.554096 -259.685483) (xy 119.584869 -259.731996) (xy 119.608541 -259.782493) (xy 119.624609 -259.8359)
			(xy 119.632729 -259.891076) (xy 119.633238 -259.918962) (xy 120.393712 -259.918962) (xy 120.397783 -259.86334)
			(xy 120.409909 -259.808903) (xy 120.429832 -259.756812) (xy 120.457128 -259.708177) (xy 120.491214 -259.664034)
			(xy 120.531363 -259.625325) (xy 120.576721 -259.592874) (xy 120.626321 -259.567373) (xy 120.679105 -259.549366)
			(xy 120.733948 -259.539236) (xy 120.789682 -259.537199) (xy 120.845119 -259.543299) (xy 120.899076 -259.557405)
			(xy 120.950405 -259.579217) (xy 120.998011 -259.608271) (xy 121.040879 -259.643946) (xy 121.078096 -259.685483)
			(xy 121.108869 -259.731996) (xy 121.132541 -259.782493) (xy 121.148609 -259.8359) (xy 121.156729 -259.891076)
			(xy 121.157238 -259.918962) (xy 121.917712 -259.918962) (xy 121.921783 -259.86334) (xy 121.933909 -259.808903)
			(xy 121.953832 -259.756812) (xy 121.981128 -259.708177) (xy 122.015214 -259.664034) (xy 122.055363 -259.625325)
			(xy 122.100721 -259.592874) (xy 122.150321 -259.567373) (xy 122.203105 -259.549366) (xy 122.257948 -259.539236)
			(xy 122.313682 -259.537199) (xy 122.369119 -259.543299) (xy 122.423076 -259.557405) (xy 122.467578 -259.576316)
			(xy 146.345146 -259.576316) (xy 146.349217 -259.520694) (xy 146.361343 -259.466257) (xy 146.381266 -259.414166)
			(xy 146.408562 -259.365531) (xy 146.442648 -259.321388) (xy 146.482797 -259.282679) (xy 146.528155 -259.250228)
			(xy 146.577755 -259.224727) (xy 146.630539 -259.20672) (xy 146.685382 -259.19659) (xy 146.741116 -259.194553)
			(xy 146.796553 -259.200653) (xy 146.85051 -259.214759) (xy 146.901839 -259.236571) (xy 146.949445 -259.265625)
			(xy 146.992313 -259.3013) (xy 147.02953 -259.342837) (xy 147.060303 -259.38935) (xy 147.083975 -259.439847)
			(xy 147.100043 -259.493254) (xy 147.108163 -259.54843) (xy 147.108672 -259.576316) (xy 147.234146 -259.576316)
			(xy 147.238217 -259.520694) (xy 147.250343 -259.466257) (xy 147.270266 -259.414166) (xy 147.297562 -259.365531)
			(xy 147.331648 -259.321388) (xy 147.371797 -259.282679) (xy 147.417155 -259.250228) (xy 147.466755 -259.224727)
			(xy 147.519539 -259.20672) (xy 147.574382 -259.19659) (xy 147.630116 -259.194553) (xy 147.685553 -259.200653)
			(xy 147.73951 -259.214759) (xy 147.790839 -259.236571) (xy 147.838445 -259.265625) (xy 147.881313 -259.3013)
			(xy 147.91853 -259.342837) (xy 147.949303 -259.38935) (xy 147.972975 -259.439847) (xy 147.989043 -259.493254)
			(xy 147.997163 -259.54843) (xy 147.997672 -259.576316) (xy 147.997163 -259.604202) (xy 147.989043 -259.659378)
			(xy 147.972975 -259.712785) (xy 147.949303 -259.763282) (xy 147.91853 -259.809795) (xy 147.881313 -259.851332)
			(xy 147.838445 -259.887007) (xy 147.790839 -259.916061) (xy 147.73951 -259.937873) (xy 147.685553 -259.951979)
			(xy 147.630116 -259.958079) (xy 147.574382 -259.956042) (xy 147.519539 -259.945912) (xy 147.466755 -259.927905)
			(xy 147.417155 -259.902404) (xy 147.371797 -259.869953) (xy 147.331648 -259.831244) (xy 147.297562 -259.787101)
			(xy 147.270266 -259.738466) (xy 147.250343 -259.686375) (xy 147.238217 -259.631938) (xy 147.234146 -259.576316)
			(xy 147.108672 -259.576316) (xy 147.108163 -259.604202) (xy 147.100043 -259.659378) (xy 147.083975 -259.712785)
			(xy 147.060303 -259.763282) (xy 147.02953 -259.809795) (xy 146.992313 -259.851332) (xy 146.949445 -259.887007)
			(xy 146.901839 -259.916061) (xy 146.85051 -259.937873) (xy 146.796553 -259.951979) (xy 146.741116 -259.958079)
			(xy 146.685382 -259.956042) (xy 146.630539 -259.945912) (xy 146.577755 -259.927905) (xy 146.528155 -259.902404)
			(xy 146.482797 -259.869953) (xy 146.442648 -259.831244) (xy 146.408562 -259.787101) (xy 146.381266 -259.738466)
			(xy 146.361343 -259.686375) (xy 146.349217 -259.631938) (xy 146.345146 -259.576316) (xy 122.467578 -259.576316)
			(xy 122.474405 -259.579217) (xy 122.522011 -259.608271) (xy 122.564879 -259.643946) (xy 122.602096 -259.685483)
			(xy 122.632869 -259.731996) (xy 122.656541 -259.782493) (xy 122.672609 -259.8359) (xy 122.680729 -259.891076)
			(xy 122.681238 -259.918962) (xy 122.680729 -259.946848) (xy 122.672609 -260.002024) (xy 122.664892 -260.027674)
			(xy 138.191746 -260.027674) (xy 138.195817 -259.972052) (xy 138.207943 -259.917615) (xy 138.227866 -259.865524)
			(xy 138.255162 -259.816889) (xy 138.289248 -259.772746) (xy 138.329397 -259.734037) (xy 138.374755 -259.701586)
			(xy 138.424355 -259.676085) (xy 138.477139 -259.658078) (xy 138.531982 -259.647948) (xy 138.587716 -259.645911)
			(xy 138.643153 -259.652011) (xy 138.69711 -259.666117) (xy 138.748439 -259.687929) (xy 138.796045 -259.716983)
			(xy 138.838913 -259.752658) (xy 138.87613 -259.794195) (xy 138.906903 -259.840708) (xy 138.930575 -259.891205)
			(xy 138.946643 -259.944612) (xy 138.954763 -259.999788) (xy 138.955272 -260.027674) (xy 138.954763 -260.05556)
			(xy 138.95255 -260.0706) (xy 139.742924 -260.0706) (xy 139.746995 -260.014978) (xy 139.759121 -259.960541)
			(xy 139.779044 -259.90845) (xy 139.80634 -259.859815) (xy 139.840426 -259.815672) (xy 139.880575 -259.776963)
			(xy 139.925933 -259.744512) (xy 139.975533 -259.719011) (xy 140.028317 -259.701004) (xy 140.08316 -259.690874)
			(xy 140.138894 -259.688837) (xy 140.194331 -259.694937) (xy 140.248288 -259.709043) (xy 140.299617 -259.730855)
			(xy 140.347223 -259.759909) (xy 140.390091 -259.795584) (xy 140.427308 -259.837121) (xy 140.458081 -259.883634)
			(xy 140.481753 -259.934131) (xy 140.497821 -259.987538) (xy 140.505941 -260.042714) (xy 140.50645 -260.0706)
			(xy 140.505972 -260.096762) (xy 143.758918 -260.096762) (xy 143.762989 -260.04114) (xy 143.775115 -259.986703)
			(xy 143.795038 -259.934612) (xy 143.822334 -259.885977) (xy 143.85642 -259.841834) (xy 143.896569 -259.803125)
			(xy 143.941927 -259.770674) (xy 143.991527 -259.745173) (xy 144.044311 -259.727166) (xy 144.099154 -259.717036)
			(xy 144.154888 -259.714999) (xy 144.210325 -259.721099) (xy 144.264282 -259.735205) (xy 144.315611 -259.757017)
			(xy 144.363217 -259.786071) (xy 144.406085 -259.821746) (xy 144.443302 -259.863283) (xy 144.474075 -259.909796)
			(xy 144.497747 -259.960293) (xy 144.513815 -260.0137) (xy 144.521935 -260.068876) (xy 144.522444 -260.096762)
			(xy 144.521935 -260.124648) (xy 144.513815 -260.179824) (xy 144.497747 -260.233231) (xy 144.474075 -260.283728)
			(xy 144.443302 -260.330241) (xy 144.436067 -260.338316) (xy 150.396194 -260.338316) (xy 150.396746 -260.308934)
			(xy 150.405774 -260.250868) (xy 150.423604 -260.194874) (xy 150.449813 -260.142279) (xy 150.483782 -260.094327)
			(xy 150.524705 -260.052154) (xy 150.547832 -260.034024) (xy 150.55723 -260.026658) (xy 150.567644 -260.006084)
			(xy 150.569168 -259.902198) (xy 150.559262 -259.881116) (xy 150.550118 -259.87375) (xy 150.528267 -259.855547)
			(xy 150.489727 -259.813728) (xy 150.45782 -259.766652) (xy 150.433253 -259.715362) (xy 150.41657 -259.660993)
			(xy 150.408142 -259.604751) (xy 150.407624 -259.576316) (xy 150.40811 -259.549065) (xy 150.415866 -259.495117)
			(xy 150.431221 -259.442822) (xy 150.453863 -259.393245) (xy 150.483329 -259.347395) (xy 150.51902 -259.306204)
			(xy 150.560211 -259.270513) (xy 150.606061 -259.241047) (xy 150.655638 -259.218405) (xy 150.707933 -259.20305)
			(xy 150.761881 -259.195294) (xy 150.816383 -259.195294) (xy 150.870331 -259.20305) (xy 150.922626 -259.218405)
			(xy 150.972203 -259.241047) (xy 151.018053 -259.270513) (xy 151.059244 -259.306204) (xy 151.094935 -259.347395)
			(xy 151.124401 -259.393245) (xy 151.147043 -259.442822) (xy 151.162398 -259.495117) (xy 151.170154 -259.549065)
			(xy 151.17064 -259.576316) (xy 151.170098 -259.605698) (xy 151.161066 -259.663764) (xy 151.143233 -259.719757)
			(xy 151.117022 -259.772352) (xy 151.083052 -259.820304) (xy 151.042129 -259.862477) (xy 151.019002 -259.880608)
			(xy 151.009604 -259.887974) (xy 150.99919 -259.908548) (xy 150.997666 -260.012434) (xy 151.007572 -260.033516)
			(xy 151.016716 -260.040882) (xy 151.038541 -260.059114) (xy 151.077082 -260.100928) (xy 151.108991 -260.147998)
			(xy 151.133562 -260.199283) (xy 151.15025 -260.253645) (xy 151.158687 -260.309883) (xy 151.15921 -260.338316)
			(xy 151.792684 -260.338316) (xy 151.796755 -260.282694) (xy 151.808881 -260.228257) (xy 151.828804 -260.176166)
			(xy 151.8561 -260.127531) (xy 151.890186 -260.083388) (xy 151.930335 -260.044679) (xy 151.975693 -260.012228)
			(xy 152.025293 -259.986727) (xy 152.078077 -259.96872) (xy 152.13292 -259.95859) (xy 152.188654 -259.956553)
			(xy 152.244091 -259.962653) (xy 152.298048 -259.976759) (xy 152.349377 -259.998571) (xy 152.396983 -260.027625)
			(xy 152.439851 -260.0633) (xy 152.477068 -260.104837) (xy 152.507841 -260.15135) (xy 152.531513 -260.201847)
			(xy 152.547581 -260.255254) (xy 152.555701 -260.31043) (xy 152.55621 -260.338316) (xy 152.679144 -260.338316)
			(xy 152.683215 -260.282694) (xy 152.695341 -260.228257) (xy 152.715264 -260.176166) (xy 152.74256 -260.127531)
			(xy 152.776646 -260.083388) (xy 152.816795 -260.044679) (xy 152.862153 -260.012228) (xy 152.911753 -259.986727)
			(xy 152.964537 -259.96872) (xy 153.01938 -259.95859) (xy 153.075114 -259.956553) (xy 153.130551 -259.962653)
			(xy 153.184508 -259.976759) (xy 153.235837 -259.998571) (xy 153.283443 -260.027625) (xy 153.326311 -260.0633)
			(xy 153.363528 -260.104837) (xy 153.394301 -260.15135) (xy 153.417973 -260.201847) (xy 153.434041 -260.255254)
			(xy 153.442161 -260.31043) (xy 153.44267 -260.338316) (xy 153.442161 -260.366202) (xy 153.434041 -260.421378)
			(xy 153.421892 -260.46176) (xy 200.706226 -260.46176) (xy 200.710297 -260.406138) (xy 200.722423 -260.351701)
			(xy 200.742346 -260.29961) (xy 200.769642 -260.250975) (xy 200.803728 -260.206832) (xy 200.843877 -260.168123)
			(xy 200.889235 -260.135672) (xy 200.938835 -260.110171) (xy 200.991619 -260.092164) (xy 201.046462 -260.082034)
			(xy 201.102196 -260.079997) (xy 201.157633 -260.086097) (xy 201.21159 -260.100203) (xy 201.262919 -260.122015)
			(xy 201.310525 -260.151069) (xy 201.353393 -260.186744) (xy 201.39061 -260.228281) (xy 201.421383 -260.274794)
			(xy 201.445055 -260.325291) (xy 201.461123 -260.378698) (xy 201.469243 -260.433874) (xy 201.469752 -260.46176)
			(xy 202.724256 -260.46176) (xy 202.728327 -260.406138) (xy 202.740453 -260.351701) (xy 202.760376 -260.29961)
			(xy 202.787672 -260.250975) (xy 202.821758 -260.206832) (xy 202.861907 -260.168123) (xy 202.907265 -260.135672)
			(xy 202.956865 -260.110171) (xy 203.009649 -260.092164) (xy 203.064492 -260.082034) (xy 203.120226 -260.079997)
			(xy 203.175663 -260.086097) (xy 203.22962 -260.100203) (xy 203.280949 -260.122015) (xy 203.328555 -260.151069)
			(xy 203.371423 -260.186744) (xy 203.40864 -260.228281) (xy 203.439413 -260.274794) (xy 203.463085 -260.325291)
			(xy 203.479153 -260.378698) (xy 203.487273 -260.433874) (xy 203.487782 -260.46176) (xy 203.487273 -260.489646)
			(xy 203.479153 -260.544822) (xy 203.463085 -260.598229) (xy 203.439413 -260.648726) (xy 203.40864 -260.695239)
			(xy 203.371423 -260.736776) (xy 203.328555 -260.772451) (xy 203.280949 -260.801505) (xy 203.22962 -260.823317)
			(xy 203.175663 -260.837423) (xy 203.120226 -260.843523) (xy 203.064492 -260.841486) (xy 203.009649 -260.831356)
			(xy 202.956865 -260.813349) (xy 202.907265 -260.787848) (xy 202.861907 -260.755397) (xy 202.821758 -260.716688)
			(xy 202.787672 -260.672545) (xy 202.760376 -260.62391) (xy 202.740453 -260.571819) (xy 202.728327 -260.517382)
			(xy 202.724256 -260.46176) (xy 201.469752 -260.46176) (xy 201.469243 -260.489646) (xy 201.461123 -260.544822)
			(xy 201.445055 -260.598229) (xy 201.421383 -260.648726) (xy 201.39061 -260.695239) (xy 201.353393 -260.736776)
			(xy 201.310525 -260.772451) (xy 201.262919 -260.801505) (xy 201.21159 -260.823317) (xy 201.157633 -260.837423)
			(xy 201.102196 -260.843523) (xy 201.046462 -260.841486) (xy 200.991619 -260.831356) (xy 200.938835 -260.813349)
			(xy 200.889235 -260.787848) (xy 200.843877 -260.755397) (xy 200.803728 -260.716688) (xy 200.769642 -260.672545)
			(xy 200.742346 -260.62391) (xy 200.722423 -260.571819) (xy 200.710297 -260.517382) (xy 200.706226 -260.46176)
			(xy 153.421892 -260.46176) (xy 153.417973 -260.474785) (xy 153.394301 -260.525282) (xy 153.363528 -260.571795)
			(xy 153.326311 -260.613332) (xy 153.283443 -260.649007) (xy 153.235837 -260.678061) (xy 153.184508 -260.699873)
			(xy 153.130551 -260.713979) (xy 153.075114 -260.720079) (xy 153.01938 -260.718042) (xy 152.964537 -260.707912)
			(xy 152.911753 -260.689905) (xy 152.862153 -260.664404) (xy 152.816795 -260.631953) (xy 152.776646 -260.593244)
			(xy 152.74256 -260.549101) (xy 152.715264 -260.500466) (xy 152.695341 -260.448375) (xy 152.683215 -260.393938)
			(xy 152.679144 -260.338316) (xy 152.55621 -260.338316) (xy 152.555701 -260.366202) (xy 152.547581 -260.421378)
			(xy 152.531513 -260.474785) (xy 152.507841 -260.525282) (xy 152.477068 -260.571795) (xy 152.439851 -260.613332)
			(xy 152.396983 -260.649007) (xy 152.349377 -260.678061) (xy 152.298048 -260.699873) (xy 152.244091 -260.713979)
			(xy 152.188654 -260.720079) (xy 152.13292 -260.718042) (xy 152.078077 -260.707912) (xy 152.025293 -260.689905)
			(xy 151.975693 -260.664404) (xy 151.930335 -260.631953) (xy 151.890186 -260.593244) (xy 151.8561 -260.549101)
			(xy 151.828804 -260.500466) (xy 151.808881 -260.448375) (xy 151.796755 -260.393938) (xy 151.792684 -260.338316)
			(xy 151.15921 -260.338316) (xy 151.158724 -260.365567) (xy 151.150968 -260.419515) (xy 151.135613 -260.47181)
			(xy 151.112971 -260.521387) (xy 151.083505 -260.567237) (xy 151.047814 -260.608428) (xy 151.006623 -260.644119)
			(xy 150.960773 -260.673585) (xy 150.911196 -260.696227) (xy 150.858901 -260.711582) (xy 150.804953 -260.719338)
			(xy 150.750451 -260.719338) (xy 150.696503 -260.711582) (xy 150.644208 -260.696227) (xy 150.594631 -260.673585)
			(xy 150.548781 -260.644119) (xy 150.50759 -260.608428) (xy 150.471899 -260.567237) (xy 150.442433 -260.521387)
			(xy 150.419791 -260.47181) (xy 150.404436 -260.419515) (xy 150.39668 -260.365567) (xy 150.396194 -260.338316)
			(xy 144.436067 -260.338316) (xy 144.406085 -260.371778) (xy 144.363217 -260.407453) (xy 144.315611 -260.436507)
			(xy 144.264282 -260.458319) (xy 144.210325 -260.472425) (xy 144.154888 -260.478525) (xy 144.099154 -260.476488)
			(xy 144.044311 -260.466358) (xy 143.991527 -260.448351) (xy 143.941927 -260.42285) (xy 143.896569 -260.390399)
			(xy 143.85642 -260.35169) (xy 143.822334 -260.307547) (xy 143.795038 -260.258912) (xy 143.775115 -260.206821)
			(xy 143.762989 -260.152384) (xy 143.758918 -260.096762) (xy 140.505972 -260.096762) (xy 140.505941 -260.098486)
			(xy 140.497821 -260.153662) (xy 140.481753 -260.207069) (xy 140.458081 -260.257566) (xy 140.427308 -260.304079)
			(xy 140.390091 -260.345616) (xy 140.347223 -260.381291) (xy 140.299617 -260.410345) (xy 140.248288 -260.432157)
			(xy 140.194331 -260.446263) (xy 140.138894 -260.452363) (xy 140.08316 -260.450326) (xy 140.028317 -260.440196)
			(xy 139.975533 -260.422189) (xy 139.925933 -260.396688) (xy 139.880575 -260.364237) (xy 139.840426 -260.325528)
			(xy 139.80634 -260.281385) (xy 139.779044 -260.23275) (xy 139.759121 -260.180659) (xy 139.746995 -260.126222)
			(xy 139.742924 -260.0706) (xy 138.95255 -260.0706) (xy 138.946643 -260.110736) (xy 138.930575 -260.164143)
			(xy 138.906903 -260.21464) (xy 138.87613 -260.261153) (xy 138.838913 -260.30269) (xy 138.796045 -260.338365)
			(xy 138.748439 -260.367419) (xy 138.69711 -260.389231) (xy 138.643153 -260.403337) (xy 138.587716 -260.409437)
			(xy 138.531982 -260.4074) (xy 138.477139 -260.39727) (xy 138.424355 -260.379263) (xy 138.374755 -260.353762)
			(xy 138.329397 -260.321311) (xy 138.289248 -260.282602) (xy 138.255162 -260.238459) (xy 138.227866 -260.189824)
			(xy 138.207943 -260.137733) (xy 138.195817 -260.083296) (xy 138.191746 -260.027674) (xy 122.664892 -260.027674)
			(xy 122.656541 -260.055431) (xy 122.632869 -260.105928) (xy 122.602096 -260.152441) (xy 122.564879 -260.193978)
			(xy 122.522011 -260.229653) (xy 122.474405 -260.258707) (xy 122.423076 -260.280519) (xy 122.369119 -260.294625)
			(xy 122.313682 -260.300725) (xy 122.257948 -260.298688) (xy 122.203105 -260.288558) (xy 122.150321 -260.270551)
			(xy 122.100721 -260.24505) (xy 122.055363 -260.212599) (xy 122.015214 -260.17389) (xy 121.981128 -260.129747)
			(xy 121.953832 -260.081112) (xy 121.933909 -260.029021) (xy 121.921783 -259.974584) (xy 121.917712 -259.918962)
			(xy 121.157238 -259.918962) (xy 121.156729 -259.946848) (xy 121.148609 -260.002024) (xy 121.132541 -260.055431)
			(xy 121.108869 -260.105928) (xy 121.078096 -260.152441) (xy 121.040879 -260.193978) (xy 120.998011 -260.229653)
			(xy 120.950405 -260.258707) (xy 120.899076 -260.280519) (xy 120.845119 -260.294625) (xy 120.789682 -260.300725)
			(xy 120.733948 -260.298688) (xy 120.679105 -260.288558) (xy 120.626321 -260.270551) (xy 120.576721 -260.24505)
			(xy 120.531363 -260.212599) (xy 120.491214 -260.17389) (xy 120.457128 -260.129747) (xy 120.429832 -260.081112)
			(xy 120.409909 -260.029021) (xy 120.397783 -259.974584) (xy 120.393712 -259.918962) (xy 119.633238 -259.918962)
			(xy 119.632729 -259.946848) (xy 119.624609 -260.002024) (xy 119.608541 -260.055431) (xy 119.584869 -260.105928)
			(xy 119.554096 -260.152441) (xy 119.516879 -260.193978) (xy 119.474011 -260.229653) (xy 119.426405 -260.258707)
			(xy 119.375076 -260.280519) (xy 119.321119 -260.294625) (xy 119.265682 -260.300725) (xy 119.209948 -260.298688)
			(xy 119.155105 -260.288558) (xy 119.102321 -260.270551) (xy 119.052721 -260.24505) (xy 119.007363 -260.212599)
			(xy 118.967214 -260.17389) (xy 118.933128 -260.129747) (xy 118.905832 -260.081112) (xy 118.885909 -260.029021)
			(xy 118.873783 -259.974584) (xy 118.869712 -259.918962) (xy 112.901699 -259.918962) (xy 112.880383 -259.965635)
			(xy 112.850917 -260.011485) (xy 112.815226 -260.052676) (xy 112.774035 -260.088367) (xy 112.728185 -260.117833)
			(xy 112.678608 -260.140475) (xy 112.626313 -260.15583) (xy 112.572365 -260.163586) (xy 112.517863 -260.163586)
			(xy 112.463915 -260.15583) (xy 112.41162 -260.140475) (xy 112.362043 -260.117833) (xy 112.316193 -260.088367)
			(xy 112.275002 -260.052676) (xy 112.239311 -260.011485) (xy 112.209845 -259.965635) (xy 112.187203 -259.916058)
			(xy 112.171848 -259.863763) (xy 112.164092 -259.809815) (xy 112.163606 -259.782564) (xy 40.899334 -259.782564)
			(xy 40.899334 -260.671564) (xy 112.163096 -260.671564) (xy 112.167167 -260.615942) (xy 112.179293 -260.561505)
			(xy 112.199216 -260.509414) (xy 112.226512 -260.460779) (xy 112.260598 -260.416636) (xy 112.300747 -260.377927)
			(xy 112.346105 -260.345476) (xy 112.395705 -260.319975) (xy 112.448489 -260.301968) (xy 112.503332 -260.291838)
			(xy 112.559066 -260.289801) (xy 112.614503 -260.295901) (xy 112.66846 -260.310007) (xy 112.719789 -260.331819)
			(xy 112.767395 -260.360873) (xy 112.810263 -260.396548) (xy 112.84748 -260.438085) (xy 112.878253 -260.484598)
			(xy 112.901925 -260.535095) (xy 112.917993 -260.588502) (xy 112.926113 -260.643678) (xy 112.926622 -260.671564)
			(xy 112.926113 -260.69945) (xy 112.917993 -260.754626) (xy 112.901925 -260.808033) (xy 112.878253 -260.85853)
			(xy 112.84748 -260.905043) (xy 112.810263 -260.94658) (xy 112.767395 -260.982255) (xy 112.719789 -261.011309)
			(xy 112.66846 -261.033121) (xy 112.614503 -261.047227) (xy 112.559066 -261.053327) (xy 112.503332 -261.05129)
			(xy 112.448489 -261.04116) (xy 112.395705 -261.023153) (xy 112.346105 -260.997652) (xy 112.300747 -260.965201)
			(xy 112.260598 -260.926492) (xy 112.226512 -260.882349) (xy 112.199216 -260.833714) (xy 112.179293 -260.781623)
			(xy 112.167167 -260.727186) (xy 112.163096 -260.671564) (xy 40.899334 -260.671564) (xy 40.899334 -261.217664)
			(xy 114.140232 -261.217664) (xy 114.144303 -261.162042) (xy 114.156429 -261.107605) (xy 114.176352 -261.055514)
			(xy 114.203648 -261.006879) (xy 114.237734 -260.962736) (xy 114.277883 -260.924027) (xy 114.323241 -260.891576)
			(xy 114.372841 -260.866075) (xy 114.425625 -260.848068) (xy 114.480468 -260.837938) (xy 114.536202 -260.835901)
			(xy 114.591639 -260.842001) (xy 114.645596 -260.856107) (xy 114.696925 -260.877919) (xy 114.744531 -260.906973)
			(xy 114.787399 -260.942648) (xy 114.824616 -260.984185) (xy 114.855389 -261.030698) (xy 114.879061 -261.081195)
			(xy 114.895129 -261.134602) (xy 114.903249 -261.189778) (xy 114.903758 -261.217664) (xy 114.903249 -261.24555)
			(xy 114.895129 -261.300726) (xy 114.879061 -261.354133) (xy 114.855389 -261.40463) (xy 114.824616 -261.451143)
			(xy 114.787399 -261.49268) (xy 114.744531 -261.528355) (xy 114.696925 -261.557409) (xy 114.645596 -261.579221)
			(xy 114.591639 -261.593327) (xy 114.536202 -261.599427) (xy 114.480468 -261.59739) (xy 114.425625 -261.58726)
			(xy 114.372841 -261.569253) (xy 114.323241 -261.543752) (xy 114.277883 -261.511301) (xy 114.237734 -261.472592)
			(xy 114.203648 -261.428449) (xy 114.176352 -261.379814) (xy 114.156429 -261.327723) (xy 114.144303 -261.273286)
			(xy 114.140232 -261.217664) (xy 40.899334 -261.217664) (xy 40.899334 -261.687564) (xy 112.163096 -261.687564)
			(xy 112.167167 -261.631942) (xy 112.179293 -261.577505) (xy 112.199216 -261.525414) (xy 112.226512 -261.476779)
			(xy 112.260598 -261.432636) (xy 112.300747 -261.393927) (xy 112.346105 -261.361476) (xy 112.395705 -261.335975)
			(xy 112.448489 -261.317968) (xy 112.503332 -261.307838) (xy 112.559066 -261.305801) (xy 112.614503 -261.311901)
			(xy 112.66846 -261.326007) (xy 112.719789 -261.347819) (xy 112.767395 -261.376873) (xy 112.810263 -261.412548)
			(xy 112.84748 -261.454085) (xy 112.878253 -261.500598) (xy 112.901925 -261.551095) (xy 112.917993 -261.604502)
			(xy 112.926113 -261.659678) (xy 112.926399 -261.675372) (xy 117.07444 -261.675372) (xy 117.078511 -261.61975)
			(xy 117.090637 -261.565313) (xy 117.11056 -261.513222) (xy 117.137856 -261.464587) (xy 117.171942 -261.420444)
			(xy 117.212091 -261.381735) (xy 117.257449 -261.349284) (xy 117.307049 -261.323783) (xy 117.359833 -261.305776)
			(xy 117.414676 -261.295646) (xy 117.47041 -261.293609) (xy 117.525847 -261.299709) (xy 117.579804 -261.313815)
			(xy 117.631133 -261.335627) (xy 117.678739 -261.364681) (xy 117.721607 -261.400356) (xy 117.758824 -261.441893)
			(xy 117.789597 -261.488406) (xy 117.802369 -261.515652) (xy 119.394683 -261.515652) (xy 119.394683 -261.461148)
			(xy 119.402441 -261.407198) (xy 119.417797 -261.354901) (xy 119.44044 -261.305323) (xy 119.469909 -261.259471)
			(xy 119.505604 -261.218281) (xy 119.546797 -261.18259) (xy 119.592651 -261.153125) (xy 119.642231 -261.130486)
			(xy 119.694529 -261.115134) (xy 119.74848 -261.107381) (xy 119.775732 -261.10692) (xy 119.804331 -261.107398)
			(xy 119.860888 -261.115942) (xy 119.915535 -261.132832) (xy 119.967049 -261.157692) (xy 120.014274 -261.189963)
			(xy 120.033402 -261.207758) (xy 131.571492 -261.207758) (xy 131.571978 -261.180507) (xy 131.579734 -261.126559)
			(xy 131.595089 -261.074264) (xy 131.617731 -261.024687) (xy 131.647197 -260.978837) (xy 131.682888 -260.937646)
			(xy 131.724079 -260.901955) (xy 131.769929 -260.872489) (xy 131.819506 -260.849847) (xy 131.871801 -260.834492)
			(xy 131.925749 -260.826736) (xy 131.980251 -260.826736) (xy 132.034199 -260.834492) (xy 132.086494 -260.849847)
			(xy 132.136071 -260.872489) (xy 132.181921 -260.901955) (xy 132.223112 -260.937646) (xy 132.258803 -260.978837)
			(xy 132.288269 -261.024687) (xy 132.310911 -261.074264) (xy 132.326266 -261.126559) (xy 132.334022 -261.180507)
			(xy 132.334508 -261.207758) (xy 132.333983 -261.237165) (xy 132.324961 -261.295282) (xy 132.307126 -261.351326)
			(xy 132.280899 -261.403968) (xy 132.246902 -261.451961) (xy 132.226812 -261.473442) (xy 132.218938 -261.48157)
			(xy 132.211572 -261.502398) (xy 132.221732 -261.602474) (xy 132.233162 -261.621524) (xy 132.24256 -261.627874)
			(xy 132.264152 -261.643196) (xy 132.303296 -261.678846) (xy 132.337136 -261.719565) (xy 132.365021 -261.764572)
			(xy 132.376365 -261.79025) (xy 141.61948 -261.79025) (xy 141.61948 -261.73575) (xy 141.627236 -261.681804)
			(xy 141.64259 -261.629512) (xy 141.665229 -261.579936) (xy 141.694693 -261.534087) (xy 141.730382 -261.492898)
			(xy 141.771569 -261.457206) (xy 141.817417 -261.42774) (xy 141.866991 -261.405097) (xy 141.919283 -261.38974)
			(xy 141.973228 -261.381981) (xy 142.000478 -261.381494) (xy 142.029396 -261.381992) (xy 142.08657 -261.39072)
			(xy 142.141771 -261.40798) (xy 142.193733 -261.433375) (xy 142.241266 -261.466324) (xy 142.28328 -261.506071)
			(xy 142.301468 -261.52856) (xy 142.309038 -261.537313) (xy 142.329791 -261.547499) (xy 142.341346 -261.548118)
			(xy 142.42161 -261.548118) (xy 142.433178 -261.547547) (xy 142.453948 -261.537352) (xy 142.461488 -261.52856)
			(xy 142.479676 -261.506074) (xy 142.521697 -261.466341) (xy 142.569233 -261.433403) (xy 142.621195 -261.408016)
			(xy 142.676393 -261.390759) (xy 142.733562 -261.38203) (xy 142.762478 -261.381494) (xy 142.788259 -261.381921)
			(xy 142.839351 -261.388863) (xy 142.889043 -261.402624) (xy 142.936429 -261.422951) (xy 142.980645 -261.449476)
			(xy 143.020886 -261.481715) (xy 143.056417 -261.51908) (xy 143.07185 -261.539736) (xy 143.078708 -261.549388)
			(xy 143.099282 -261.56031) (xy 143.203168 -261.56412) (xy 143.224504 -261.554722) (xy 143.232124 -261.545578)
			(xy 143.250359 -261.524629) (xy 143.291834 -261.487692) (xy 143.338226 -261.457159) (xy 143.388556 -261.433676)
			(xy 143.441758 -261.417737) (xy 143.496709 -261.409682) (xy 143.524478 -261.40918) (xy 143.553396 -261.409684)
			(xy 143.610569 -261.418411) (xy 143.66577 -261.43567) (xy 143.717732 -261.461064) (xy 143.765265 -261.494012)
			(xy 143.80728 -261.533758) (xy 143.825468 -261.556246) (xy 143.83304 -261.564997) (xy 143.853791 -261.575184)
			(xy 143.865346 -261.575804) (xy 143.94561 -261.575804) (xy 143.957178 -261.575238) (xy 143.977949 -261.56504)
			(xy 143.985488 -261.556246) (xy 144.003672 -261.533757) (xy 144.045695 -261.494025) (xy 144.093232 -261.461088)
			(xy 144.145194 -261.435701) (xy 144.200392 -261.418445) (xy 144.257562 -261.409716) (xy 144.286478 -261.40918)
			(xy 144.313731 -261.409666) (xy 144.367683 -261.41742) (xy 144.419981 -261.432774) (xy 144.469563 -261.455414)
			(xy 144.499198 -261.474458) (xy 144.86966 -261.474458) (xy 144.873731 -261.418836) (xy 144.885857 -261.364399)
			(xy 144.90578 -261.312308) (xy 144.933076 -261.263673) (xy 144.967162 -261.21953) (xy 145.007311 -261.180821)
			(xy 145.052669 -261.14837) (xy 145.102269 -261.122869) (xy 145.155053 -261.104862) (xy 145.209896 -261.094732)
			(xy 145.26563 -261.092695) (xy 145.321067 -261.098795) (xy 145.375024 -261.112901) (xy 145.426353 -261.134713)
			(xy 145.473959 -261.163767) (xy 145.516827 -261.199442) (xy 145.554044 -261.240979) (xy 145.584817 -261.287492)
			(xy 145.608489 -261.337989) (xy 145.624557 -261.391396) (xy 145.632677 -261.446572) (xy 145.633186 -261.474458)
			(xy 146.354798 -261.474458) (xy 146.358869 -261.418836) (xy 146.370995 -261.364399) (xy 146.390918 -261.312308)
			(xy 146.418214 -261.263673) (xy 146.4523 -261.21953) (xy 146.492449 -261.180821) (xy 146.537807 -261.14837)
			(xy 146.587407 -261.122869) (xy 146.640191 -261.104862) (xy 146.695034 -261.094732) (xy 146.750768 -261.092695)
			(xy 146.806205 -261.098795) (xy 146.860162 -261.112901) (xy 146.911491 -261.134713) (xy 146.959097 -261.163767)
			(xy 147.001965 -261.199442) (xy 147.039182 -261.240979) (xy 147.069955 -261.287492) (xy 147.093627 -261.337989)
			(xy 147.109695 -261.391396) (xy 147.117815 -261.446572) (xy 147.118324 -261.474458) (xy 147.117815 -261.502344)
			(xy 147.109695 -261.55752) (xy 147.093627 -261.610927) (xy 147.069955 -261.661424) (xy 147.039182 -261.707937)
			(xy 147.008278 -261.742428) (xy 157.474158 -261.742428) (xy 157.474644 -261.715177) (xy 157.4824 -261.661229)
			(xy 157.497755 -261.608934) (xy 157.520397 -261.559357) (xy 157.549863 -261.513507) (xy 157.585554 -261.472316)
			(xy 157.626745 -261.436625) (xy 157.672595 -261.407159) (xy 157.722172 -261.384517) (xy 157.774467 -261.369162)
			(xy 157.828415 -261.361406) (xy 157.882917 -261.361406) (xy 157.936865 -261.369162) (xy 157.98916 -261.384517)
			(xy 158.038737 -261.407159) (xy 158.084587 -261.436625) (xy 158.125778 -261.472316) (xy 158.161469 -261.513507)
			(xy 158.190935 -261.559357) (xy 158.213577 -261.608934) (xy 158.228932 -261.661229) (xy 158.236688 -261.715177)
			(xy 158.237174 -261.742428) (xy 158.236651 -261.771382) (xy 158.229523 -261.817955) (xy 257.719243 -261.817955)
			(xy 257.719243 -261.763445) (xy 257.727001 -261.709491) (xy 257.742358 -261.657189) (xy 257.765003 -261.607606)
			(xy 257.794474 -261.56175) (xy 257.830171 -261.520556) (xy 257.871368 -261.484861) (xy 257.917225 -261.455393)
			(xy 257.96681 -261.432751) (xy 258.019112 -261.417396) (xy 258.073067 -261.409641) (xy 258.100322 -261.40918)
			(xy 258.129238 -261.409724) (xy 258.18641 -261.418444) (xy 258.241609 -261.435694) (xy 258.293572 -261.461081)
			(xy 258.341106 -261.494022) (xy 258.383122 -261.533761) (xy 258.401312 -261.556246) (xy 258.408865 -261.565016)
			(xy 258.429631 -261.575193) (xy 258.44119 -261.575804) (xy 258.521454 -261.575804) (xy 258.533018 -261.575206)
			(xy 258.55379 -261.565031) (xy 258.561332 -261.556246) (xy 258.578085 -261.535463) (xy 258.616439 -261.498333)
			(xy 258.659593 -261.466911) (xy 258.706707 -261.441812) (xy 258.756859 -261.423526) (xy 258.80907 -261.412409)
			(xy 258.862322 -261.408679) (xy 258.915574 -261.412409) (xy 258.967785 -261.423526) (xy 259.017937 -261.441812)
			(xy 259.065051 -261.466911) (xy 259.108205 -261.498333) (xy 259.146559 -261.535463) (xy 259.163312 -261.556246)
			(xy 259.170865 -261.565016) (xy 259.191631 -261.575193) (xy 259.20319 -261.575804) (xy 259.283454 -261.575804)
			(xy 259.295018 -261.575206) (xy 259.31579 -261.565031) (xy 259.323332 -261.556246) (xy 259.340085 -261.535463)
			(xy 259.378439 -261.498333) (xy 259.421593 -261.466911) (xy 259.468707 -261.441812) (xy 259.518859 -261.423526)
			(xy 259.57107 -261.412409) (xy 259.624322 -261.408679) (xy 259.677574 -261.412409) (xy 259.729785 -261.423526)
			(xy 259.779937 -261.441812) (xy 259.827051 -261.466911) (xy 259.870205 -261.498333) (xy 259.908559 -261.535463)
			(xy 259.925312 -261.556246) (xy 259.932865 -261.565016) (xy 259.953631 -261.575193) (xy 259.96519 -261.575804)
			(xy 260.045454 -261.575804) (xy 260.057018 -261.575206) (xy 260.07779 -261.565031) (xy 260.085332 -261.556246)
			(xy 260.103491 -261.533736) (xy 260.145519 -261.494005) (xy 260.193061 -261.461071) (xy 260.245029 -261.435687)
			(xy 260.300231 -261.418436) (xy 260.357404 -261.409712) (xy 260.386322 -261.40918) (xy 260.413571 -261.409692)
			(xy 260.467515 -261.417451) (xy 260.519805 -261.432807) (xy 260.569378 -261.455449) (xy 260.598954 -261.474458)
			(xy 260.969504 -261.474458) (xy 260.973575 -261.418836) (xy 260.985701 -261.364399) (xy 261.005624 -261.312308)
			(xy 261.03292 -261.263673) (xy 261.067006 -261.21953) (xy 261.107155 -261.180821) (xy 261.152513 -261.14837)
			(xy 261.202113 -261.122869) (xy 261.254897 -261.104862) (xy 261.30974 -261.094732) (xy 261.365474 -261.092695)
			(xy 261.420911 -261.098795) (xy 261.474868 -261.112901) (xy 261.526197 -261.134713) (xy 261.573803 -261.163767)
			(xy 261.616671 -261.199442) (xy 261.653888 -261.240979) (xy 261.684661 -261.287492) (xy 261.708333 -261.337989)
			(xy 261.724401 -261.391396) (xy 261.732521 -261.446572) (xy 261.73303 -261.474458) (xy 262.454642 -261.474458)
			(xy 262.458713 -261.418836) (xy 262.470839 -261.364399) (xy 262.490762 -261.312308) (xy 262.518058 -261.263673)
			(xy 262.552144 -261.21953) (xy 262.592293 -261.180821) (xy 262.637651 -261.14837) (xy 262.687251 -261.122869)
			(xy 262.740035 -261.104862) (xy 262.794878 -261.094732) (xy 262.850612 -261.092695) (xy 262.906049 -261.098795)
			(xy 262.960006 -261.112901) (xy 263.011335 -261.134713) (xy 263.058941 -261.163767) (xy 263.101809 -261.199442)
			(xy 263.139026 -261.240979) (xy 263.169799 -261.287492) (xy 263.193471 -261.337989) (xy 263.209539 -261.391396)
			(xy 263.217659 -261.446572) (xy 263.218168 -261.474458) (xy 263.218164 -261.474674) (xy 272.950813 -261.474674)
			(xy 272.958567 -261.420716) (xy 272.973921 -261.36841) (xy 272.996562 -261.318822) (xy 273.026031 -261.272962)
			(xy 273.061726 -261.231762) (xy 273.102922 -261.196061) (xy 273.148778 -261.166586) (xy 273.198363 -261.143938)
			(xy 273.250667 -261.128577) (xy 273.304624 -261.120816) (xy 273.359136 -261.120814) (xy 273.413094 -261.128569)
			(xy 273.465399 -261.143924) (xy 273.514986 -261.166567) (xy 273.560846 -261.196037) (xy 273.602046 -261.231733)
			(xy 273.637745 -261.27293) (xy 273.667218 -261.318787) (xy 273.689865 -261.368373) (xy 273.705225 -261.420677)
			(xy 273.712984 -261.474634) (xy 273.713448 -261.50189) (xy 273.713333 -261.513861) (xy 273.71181 -261.537754)
			(xy 273.7104 -261.549642) (xy 273.708622 -261.563358) (xy 273.71929 -261.588504) (xy 273.812 -261.6581)
			(xy 273.839178 -261.661148) (xy 273.851624 -261.65556) (xy 273.875736 -261.645592) (xy 273.925989 -261.631563)
			(xy 273.977683 -261.624495) (xy 274.00377 -261.624064) (xy 274.031021 -261.624583) (xy 274.084968 -261.632335)
			(xy 274.137263 -261.647686) (xy 274.186842 -261.670323) (xy 274.232693 -261.699785) (xy 274.273886 -261.735473)
			(xy 274.30958 -261.77666) (xy 274.339049 -261.822507) (xy 274.361694 -261.872082) (xy 274.377052 -261.924375)
			(xy 274.384813 -261.978321) (xy 274.385278 -262.005572) (xy 274.384769 -262.033274) (xy 274.376764 -262.088097)
			(xy 274.360919 -262.141186) (xy 274.337566 -262.191428) (xy 274.334959 -262.195564) (xy 348.581978 -262.195564)
			(xy 348.586049 -262.139942) (xy 348.598175 -262.085505) (xy 348.618098 -262.033414) (xy 348.645394 -261.984779)
			(xy 348.67948 -261.940636) (xy 348.719629 -261.901927) (xy 348.764987 -261.869476) (xy 348.814587 -261.843975)
			(xy 348.867371 -261.825968) (xy 348.922214 -261.815838) (xy 348.977948 -261.813801) (xy 349.033385 -261.819901)
			(xy 349.087342 -261.834007) (xy 349.138671 -261.855819) (xy 349.186277 -261.884873) (xy 349.229145 -261.920548)
			(xy 349.266362 -261.962085) (xy 349.297135 -262.008598) (xy 349.320807 -262.059095) (xy 349.336875 -262.112502)
			(xy 349.344995 -262.167678) (xy 349.345504 -262.195564) (xy 349.344995 -262.22345) (xy 349.336875 -262.278626)
			(xy 349.320807 -262.332033) (xy 349.297135 -262.38253) (xy 349.266362 -262.429043) (xy 349.229145 -262.47058)
			(xy 349.186277 -262.506255) (xy 349.138671 -262.535309) (xy 349.087342 -262.557121) (xy 349.033385 -262.571227)
			(xy 348.977948 -262.577327) (xy 348.922214 -262.57529) (xy 348.867371 -262.56516) (xy 348.814587 -262.547153)
			(xy 348.764987 -262.521652) (xy 348.719629 -262.489201) (xy 348.67948 -262.450492) (xy 348.645394 -262.406349)
			(xy 348.618098 -262.357714) (xy 348.598175 -262.305623) (xy 348.586049 -262.251186) (xy 348.581978 -262.195564)
			(xy 274.334959 -262.195564) (xy 274.322794 -262.214868) (xy 274.31619 -262.225028) (xy 274.313396 -262.248904)
			(xy 274.349972 -262.348218) (xy 274.367498 -262.364728) (xy 274.379182 -262.36803) (xy 274.405171 -262.376201)
			(xy 274.454711 -262.398864) (xy 274.500524 -262.428341) (xy 274.541679 -262.464034) (xy 274.57734 -262.505218)
			(xy 274.606781 -262.551054) (xy 274.629404 -262.600612) (xy 274.64475 -262.652883) (xy 274.652039 -262.703564)
			(xy 344.363292 -262.703564) (xy 344.367363 -262.647942) (xy 344.379489 -262.593505) (xy 344.399412 -262.541414)
			(xy 344.426708 -262.492779) (xy 344.460794 -262.448636) (xy 344.500943 -262.409927) (xy 344.546301 -262.377476)
			(xy 344.595901 -262.351975) (xy 344.648685 -262.333968) (xy 344.703528 -262.323838) (xy 344.759262 -262.321801)
			(xy 344.814699 -262.327901) (xy 344.868656 -262.342007) (xy 344.919985 -262.363819) (xy 344.967591 -262.392873)
			(xy 345.010459 -262.428548) (xy 345.047676 -262.470085) (xy 345.078449 -262.516598) (xy 345.102121 -262.567095)
			(xy 345.106269 -262.580882) (xy 351.353118 -262.580882) (xy 351.357189 -262.52526) (xy 351.369315 -262.470823)
			(xy 351.389238 -262.418732) (xy 351.416534 -262.370097) (xy 351.45062 -262.325954) (xy 351.490769 -262.287245)
			(xy 351.536127 -262.254794) (xy 351.585727 -262.229293) (xy 351.638511 -262.211286) (xy 351.693354 -262.201156)
			(xy 351.749088 -262.199119) (xy 351.804525 -262.205219) (xy 351.858482 -262.219325) (xy 351.909811 -262.241137)
			(xy 351.957417 -262.270191) (xy 352.000285 -262.305866) (xy 352.037502 -262.347403) (xy 352.068275 -262.393916)
			(xy 352.091947 -262.444413) (xy 352.108015 -262.49782) (xy 352.116135 -262.552996) (xy 352.116644 -262.580882)
			(xy 352.116135 -262.608768) (xy 352.108015 -262.663944) (xy 352.091947 -262.717351) (xy 352.068275 -262.767848)
			(xy 352.037502 -262.814361) (xy 352.000285 -262.855898) (xy 351.957417 -262.891573) (xy 351.909811 -262.920627)
			(xy 351.858482 -262.942439) (xy 351.804525 -262.956545) (xy 351.749088 -262.962645) (xy 351.693354 -262.960608)
			(xy 351.638511 -262.950478) (xy 351.585727 -262.932471) (xy 351.536127 -262.90697) (xy 351.490769 -262.874519)
			(xy 351.45062 -262.83581) (xy 351.416534 -262.791667) (xy 351.389238 -262.743032) (xy 351.369315 -262.690941)
			(xy 351.357189 -262.636504) (xy 351.353118 -262.580882) (xy 345.106269 -262.580882) (xy 345.118189 -262.620502)
			(xy 345.126309 -262.675678) (xy 345.126818 -262.703564) (xy 345.126309 -262.73145) (xy 345.118189 -262.786626)
			(xy 345.102121 -262.840033) (xy 345.078449 -262.89053) (xy 345.047676 -262.937043) (xy 345.010459 -262.97858)
			(xy 344.967591 -263.014255) (xy 344.919985 -263.043309) (xy 344.868656 -263.065121) (xy 344.842863 -263.071864)
			(xy 348.581978 -263.071864) (xy 348.586049 -263.016242) (xy 348.598175 -262.961805) (xy 348.618098 -262.909714)
			(xy 348.645394 -262.861079) (xy 348.67948 -262.816936) (xy 348.719629 -262.778227) (xy 348.764987 -262.745776)
			(xy 348.814587 -262.720275) (xy 348.867371 -262.702268) (xy 348.922214 -262.692138) (xy 348.977948 -262.690101)
			(xy 349.033385 -262.696201) (xy 349.087342 -262.710307) (xy 349.138671 -262.732119) (xy 349.186277 -262.761173)
			(xy 349.229145 -262.796848) (xy 349.266362 -262.838385) (xy 349.297135 -262.884898) (xy 349.320807 -262.935395)
			(xy 349.336875 -262.988802) (xy 349.344995 -263.043978) (xy 349.345504 -263.071864) (xy 349.344995 -263.09975)
			(xy 349.336875 -263.154926) (xy 349.328317 -263.18337) (xy 355.16896 -263.18337) (xy 355.173031 -263.127748)
			(xy 355.185157 -263.073311) (xy 355.20508 -263.02122) (xy 355.232376 -262.972585) (xy 355.266462 -262.928442)
			(xy 355.306611 -262.889733) (xy 355.351969 -262.857282) (xy 355.401569 -262.831781) (xy 355.454353 -262.813774)
			(xy 355.509196 -262.803644) (xy 355.56493 -262.801607) (xy 355.620367 -262.807707) (xy 355.674324 -262.821813)
			(xy 355.725653 -262.843625) (xy 355.773259 -262.872679) (xy 355.816127 -262.908354) (xy 355.819709 -262.912352)
			(xy 373.468898 -262.912352) (xy 373.472969 -262.85673) (xy 373.485095 -262.802293) (xy 373.505018 -262.750202)
			(xy 373.532314 -262.701567) (xy 373.5664 -262.657424) (xy 373.606549 -262.618715) (xy 373.651907 -262.586264)
			(xy 373.701507 -262.560763) (xy 373.754291 -262.542756) (xy 373.809134 -262.532626) (xy 373.864868 -262.530589)
			(xy 373.920305 -262.536689) (xy 373.974262 -262.550795) (xy 374.025591 -262.572607) (xy 374.073197 -262.601661)
			(xy 374.116065 -262.637336) (xy 374.153282 -262.678873) (xy 374.184055 -262.725386) (xy 374.207727 -262.775883)
			(xy 374.223795 -262.82929) (xy 374.231915 -262.884466) (xy 374.232424 -262.912352) (xy 374.232359 -262.915908)
			(xy 375.442478 -262.915908) (xy 375.446549 -262.860286) (xy 375.458675 -262.805849) (xy 375.478598 -262.753758)
			(xy 375.505894 -262.705123) (xy 375.53998 -262.66098) (xy 375.580129 -262.622271) (xy 375.625487 -262.58982)
			(xy 375.675087 -262.564319) (xy 375.727871 -262.546312) (xy 375.782714 -262.536182) (xy 375.838448 -262.534145)
			(xy 375.893885 -262.540245) (xy 375.947842 -262.554351) (xy 375.999171 -262.576163) (xy 376.046777 -262.605217)
			(xy 376.089645 -262.640892) (xy 376.126862 -262.682429) (xy 376.157635 -262.728942) (xy 376.178125 -262.772652)
			(xy 381.52527 -262.772652) (xy 381.529341 -262.71703) (xy 381.541467 -262.662593) (xy 381.56139 -262.610502)
			(xy 381.588686 -262.561867) (xy 381.622772 -262.517724) (xy 381.662921 -262.479015) (xy 381.708279 -262.446564)
			(xy 381.757879 -262.421063) (xy 381.810663 -262.403056) (xy 381.865506 -262.392926) (xy 381.92124 -262.390889)
			(xy 381.976677 -262.396989) (xy 382.030634 -262.411095) (xy 382.081963 -262.432907) (xy 382.129569 -262.461961)
			(xy 382.172437 -262.497636) (xy 382.209654 -262.539173) (xy 382.240427 -262.585686) (xy 382.264099 -262.636183)
			(xy 382.280167 -262.68959) (xy 382.288287 -262.744766) (xy 382.288796 -262.772652) (xy 382.288287 -262.800538)
			(xy 382.280167 -262.855714) (xy 382.264099 -262.909121) (xy 382.240427 -262.959618) (xy 382.209654 -263.006131)
			(xy 382.195136 -263.022334) (xy 386.231128 -263.022334) (xy 386.235199 -262.966712) (xy 386.247325 -262.912275)
			(xy 386.267248 -262.860184) (xy 386.294544 -262.811549) (xy 386.32863 -262.767406) (xy 386.368779 -262.728697)
			(xy 386.414137 -262.696246) (xy 386.463737 -262.670745) (xy 386.516521 -262.652738) (xy 386.571364 -262.642608)
			(xy 386.627098 -262.640571) (xy 386.682535 -262.646671) (xy 386.736492 -262.660777) (xy 386.787821 -262.682589)
			(xy 386.835427 -262.711643) (xy 386.878295 -262.747318) (xy 386.915512 -262.788855) (xy 386.946285 -262.835368)
			(xy 386.969957 -262.885865) (xy 386.986025 -262.939272) (xy 386.994145 -262.994448) (xy 386.994654 -263.022334)
			(xy 386.994145 -263.05022) (xy 386.986025 -263.105396) (xy 386.969957 -263.158803) (xy 386.946285 -263.2093)
			(xy 386.915512 -263.255813) (xy 386.878295 -263.29735) (xy 386.835427 -263.333025) (xy 386.787821 -263.362079)
			(xy 386.736492 -263.383891) (xy 386.682535 -263.397997) (xy 386.627098 -263.404097) (xy 386.571364 -263.40206)
			(xy 386.516521 -263.39193) (xy 386.463737 -263.373923) (xy 386.414137 -263.348422) (xy 386.368779 -263.315971)
			(xy 386.32863 -263.277262) (xy 386.294544 -263.233119) (xy 386.267248 -263.184484) (xy 386.247325 -263.132393)
			(xy 386.235199 -263.077956) (xy 386.231128 -263.022334) (xy 382.195136 -263.022334) (xy 382.172437 -263.047668)
			(xy 382.129569 -263.083343) (xy 382.081963 -263.112397) (xy 382.030634 -263.134209) (xy 381.976677 -263.148315)
			(xy 381.92124 -263.154415) (xy 381.865506 -263.152378) (xy 381.810663 -263.142248) (xy 381.757879 -263.124241)
			(xy 381.708279 -263.09874) (xy 381.662921 -263.066289) (xy 381.622772 -263.02758) (xy 381.588686 -262.983437)
			(xy 381.56139 -262.934802) (xy 381.541467 -262.882711) (xy 381.529341 -262.828274) (xy 381.52527 -262.772652)
			(xy 376.178125 -262.772652) (xy 376.181307 -262.779439) (xy 376.197375 -262.832846) (xy 376.205495 -262.888022)
			(xy 376.206004 -262.915908) (xy 376.205495 -262.943794) (xy 376.197375 -262.99897) (xy 376.181307 -263.052377)
			(xy 376.157635 -263.102874) (xy 376.126862 -263.149387) (xy 376.089645 -263.190924) (xy 376.046777 -263.226599)
			(xy 375.999171 -263.255653) (xy 375.947842 -263.277465) (xy 375.893885 -263.291571) (xy 375.838448 -263.297671)
			(xy 375.782714 -263.295634) (xy 375.727871 -263.285504) (xy 375.675087 -263.267497) (xy 375.625487 -263.241996)
			(xy 375.580129 -263.209545) (xy 375.53998 -263.170836) (xy 375.505894 -263.126693) (xy 375.478598 -263.078058)
			(xy 375.458675 -263.025967) (xy 375.446549 -262.97153) (xy 375.442478 -262.915908) (xy 374.232359 -262.915908)
			(xy 374.231915 -262.940238) (xy 374.223795 -262.995414) (xy 374.207727 -263.048821) (xy 374.184055 -263.099318)
			(xy 374.153282 -263.145831) (xy 374.116065 -263.187368) (xy 374.073197 -263.223043) (xy 374.025591 -263.252097)
			(xy 373.974262 -263.273909) (xy 373.920305 -263.288015) (xy 373.864868 -263.294115) (xy 373.809134 -263.292078)
			(xy 373.754291 -263.281948) (xy 373.701507 -263.263941) (xy 373.651907 -263.23844) (xy 373.606549 -263.205989)
			(xy 373.5664 -263.16728) (xy 373.532314 -263.123137) (xy 373.505018 -263.074502) (xy 373.485095 -263.022411)
			(xy 373.472969 -262.967974) (xy 373.468898 -262.912352) (xy 355.819709 -262.912352) (xy 355.853344 -262.949891)
			(xy 355.884117 -262.996404) (xy 355.907789 -263.046901) (xy 355.923857 -263.100308) (xy 355.931977 -263.155484)
			(xy 355.932486 -263.18337) (xy 355.931977 -263.211256) (xy 355.923857 -263.266432) (xy 355.907789 -263.319839)
			(xy 355.884117 -263.370336) (xy 355.853344 -263.416849) (xy 355.816127 -263.458386) (xy 355.773259 -263.494061)
			(xy 355.725653 -263.523115) (xy 355.674324 -263.544927) (xy 355.620367 -263.559033) (xy 355.56493 -263.565133)
			(xy 355.509196 -263.563096) (xy 355.454353 -263.552966) (xy 355.401569 -263.534959) (xy 355.351969 -263.509458)
			(xy 355.306611 -263.477007) (xy 355.266462 -263.438298) (xy 355.232376 -263.394155) (xy 355.20508 -263.34552)
			(xy 355.185157 -263.293429) (xy 355.173031 -263.238992) (xy 355.16896 -263.18337) (xy 349.328317 -263.18337)
			(xy 349.320807 -263.208333) (xy 349.297135 -263.25883) (xy 349.266362 -263.305343) (xy 349.229145 -263.34688)
			(xy 349.186277 -263.382555) (xy 349.138671 -263.411609) (xy 349.087342 -263.433421) (xy 349.033385 -263.447527)
			(xy 348.977948 -263.453627) (xy 348.922214 -263.45159) (xy 348.867371 -263.44146) (xy 348.814587 -263.423453)
			(xy 348.764987 -263.397952) (xy 348.719629 -263.365501) (xy 348.67948 -263.326792) (xy 348.645394 -263.282649)
			(xy 348.618098 -263.234014) (xy 348.598175 -263.181923) (xy 348.586049 -263.127486) (xy 348.581978 -263.071864)
			(xy 344.842863 -263.071864) (xy 344.814699 -263.079227) (xy 344.759262 -263.085327) (xy 344.703528 -263.08329)
			(xy 344.648685 -263.07316) (xy 344.595901 -263.055153) (xy 344.546301 -263.029652) (xy 344.500943 -262.997201)
			(xy 344.460794 -262.958492) (xy 344.426708 -262.914349) (xy 344.399412 -262.865714) (xy 344.379489 -262.813623)
			(xy 344.367363 -262.759186) (xy 344.363292 -262.703564) (xy 274.652039 -262.703564) (xy 274.652505 -262.706805)
			(xy 274.652994 -262.734044) (xy 274.652508 -262.761295) (xy 274.644752 -262.815243) (xy 274.629397 -262.867538)
			(xy 274.606755 -262.917115) (xy 274.577289 -262.962965) (xy 274.541598 -263.004156) (xy 274.500407 -263.039847)
			(xy 274.454557 -263.069313) (xy 274.40498 -263.091955) (xy 274.352685 -263.10731) (xy 274.298737 -263.115066)
			(xy 274.244235 -263.115066) (xy 274.190287 -263.10731) (xy 274.137992 -263.091955) (xy 274.088415 -263.069313)
			(xy 274.042565 -263.039847) (xy 274.001374 -263.004156) (xy 273.965683 -262.962965) (xy 273.936217 -262.917115)
			(xy 273.913575 -262.867538) (xy 273.89822 -262.815243) (xy 273.890464 -262.761295) (xy 273.889978 -262.734044)
			(xy 273.890486 -262.706342) (xy 273.898489 -262.651519) (xy 273.914335 -262.598429) (xy 273.937689 -262.548188)
			(xy 273.952462 -262.524748) (xy 273.959066 -262.514588) (xy 273.96186 -262.490712) (xy 273.925284 -262.391398)
			(xy 273.907758 -262.374888) (xy 273.896074 -262.371586) (xy 273.870071 -262.363455) (xy 273.820526 -262.340793)
			(xy 273.774708 -262.311313) (xy 273.73355 -262.275616) (xy 273.697889 -262.234427) (xy 273.668449 -262.188584)
			(xy 273.64583 -262.13902) (xy 273.630491 -262.086741) (xy 273.622745 -262.032813) (xy 273.622262 -262.005572)
			(xy 273.622373 -261.993601) (xy 273.623899 -261.969708) (xy 273.62531 -261.95782) (xy 273.627088 -261.944104)
			(xy 273.61642 -261.918958) (xy 273.52371 -261.849362) (xy 273.496532 -261.846314) (xy 273.484086 -261.851902)
			(xy 273.459972 -261.861865) (xy 273.40972 -261.875896) (xy 273.358027 -261.882966) (xy 273.33194 -261.883398)
			(xy 273.304684 -261.882988) (xy 273.250725 -261.875235) (xy 273.19842 -261.859883) (xy 273.148831 -261.837242)
			(xy 273.10297 -261.807775) (xy 273.061769 -261.772081) (xy 273.026067 -261.730886) (xy 272.996591 -261.68503)
			(xy 272.973942 -261.635446) (xy 272.958579 -261.583143) (xy 272.950817 -261.529186) (xy 272.950813 -261.474674)
			(xy 263.218164 -261.474674) (xy 263.217659 -261.502344) (xy 263.209539 -261.55752) (xy 263.193471 -261.610927)
			(xy 263.169799 -261.661424) (xy 263.139026 -261.707937) (xy 263.101809 -261.749474) (xy 263.058941 -261.785149)
			(xy 263.011335 -261.814203) (xy 262.960006 -261.836015) (xy 262.906049 -261.850121) (xy 262.850612 -261.856221)
			(xy 262.794878 -261.854184) (xy 262.740035 -261.844054) (xy 262.687251 -261.826047) (xy 262.637651 -261.800546)
			(xy 262.592293 -261.768095) (xy 262.552144 -261.729386) (xy 262.518058 -261.685243) (xy 262.490762 -261.636608)
			(xy 262.470839 -261.584517) (xy 262.458713 -261.53008) (xy 262.454642 -261.474458) (xy 261.73303 -261.474458)
			(xy 261.732521 -261.502344) (xy 261.724401 -261.55752) (xy 261.708333 -261.610927) (xy 261.684661 -261.661424)
			(xy 261.653888 -261.707937) (xy 261.616671 -261.749474) (xy 261.573803 -261.785149) (xy 261.526197 -261.814203)
			(xy 261.474868 -261.836015) (xy 261.420911 -261.850121) (xy 261.365474 -261.856221) (xy 261.30974 -261.854184)
			(xy 261.254897 -261.844054) (xy 261.202113 -261.826047) (xy 261.152513 -261.800546) (xy 261.107155 -261.768095)
			(xy 261.067006 -261.729386) (xy 261.03292 -261.685243) (xy 261.005624 -261.636608) (xy 260.985701 -261.584517)
			(xy 260.973575 -261.53008) (xy 260.969504 -261.474458) (xy 260.598954 -261.474458) (xy 260.615224 -261.484915)
			(xy 260.656411 -261.520605) (xy 260.692099 -261.561793) (xy 260.721562 -261.607641) (xy 260.744201 -261.657215)
			(xy 260.759554 -261.709507) (xy 260.76731 -261.763451) (xy 260.76731 -261.817949) (xy 260.759554 -261.871893)
			(xy 260.744201 -261.924185) (xy 260.721562 -261.973759) (xy 260.692099 -262.019607) (xy 260.656411 -262.060795)
			(xy 260.615224 -262.096485) (xy 260.569378 -262.125951) (xy 260.519805 -262.148593) (xy 260.467515 -262.163949)
			(xy 260.413571 -262.171708) (xy 260.386322 -262.172196) (xy 260.357406 -262.171663) (xy 260.300235 -262.162937)
			(xy 260.245036 -262.145682) (xy 260.193075 -262.120294) (xy 260.14554 -262.087353) (xy 260.103523 -262.047614)
			(xy 260.085332 -262.02513) (xy 260.077764 -262.016375) (xy 260.057009 -262.006191) (xy 260.045454 -262.005572)
			(xy 259.96519 -262.005572) (xy 259.953617 -262.006112) (xy 259.932845 -262.016325) (xy 259.925312 -262.02513)
			(xy 259.908559 -262.045913) (xy 259.870205 -262.083043) (xy 259.827051 -262.114465) (xy 259.779937 -262.139564)
			(xy 259.729785 -262.15785) (xy 259.677574 -262.168967) (xy 259.624322 -262.172697) (xy 259.57107 -262.168967)
			(xy 259.518859 -262.15785) (xy 259.468707 -262.139564) (xy 259.421593 -262.114465) (xy 259.378439 -262.083043)
			(xy 259.340085 -262.045913) (xy 259.323332 -262.02513) (xy 259.315764 -262.016375) (xy 259.295009 -262.006191)
			(xy 259.283454 -262.005572) (xy 259.20319 -262.005572) (xy 259.191617 -262.006112) (xy 259.170845 -262.016325)
			(xy 259.163312 -262.02513) (xy 259.146559 -262.045913) (xy 259.108205 -262.083043) (xy 259.065051 -262.114465)
			(xy 259.017937 -262.139564) (xy 258.967785 -262.15785) (xy 258.915574 -262.168967) (xy 258.862322 -262.172697)
			(xy 258.80907 -262.168967) (xy 258.756859 -262.15785) (xy 258.706707 -262.139564) (xy 258.659593 -262.114465)
			(xy 258.616439 -262.083043) (xy 258.578085 -262.045913) (xy 258.561332 -262.02513) (xy 258.553764 -262.016375)
			(xy 258.533009 -262.006191) (xy 258.521454 -262.005572) (xy 258.44119 -262.005572) (xy 258.429617 -262.006112)
			(xy 258.408845 -262.016325) (xy 258.401312 -262.02513) (xy 258.383122 -262.047614) (xy 258.341101 -262.087348)
			(xy 258.293566 -262.120286) (xy 258.241604 -262.145674) (xy 258.186407 -262.16293) (xy 258.129238 -262.17166)
			(xy 258.100322 -262.172196) (xy 258.073067 -262.171759) (xy 258.019112 -262.164004) (xy 257.96681 -262.148649)
			(xy 257.917225 -262.126007) (xy 257.871368 -262.096539) (xy 257.830171 -262.060844) (xy 257.794474 -262.01965)
			(xy 257.765003 -261.973794) (xy 257.742358 -261.924211) (xy 257.727001 -261.871909) (xy 257.719243 -261.817955)
			(xy 158.229523 -261.817955) (xy 158.22789 -261.828623) (xy 158.210586 -261.883885) (xy 158.185138 -261.935901)
			(xy 158.152129 -261.983479) (xy 158.112314 -262.025528) (xy 158.066608 -262.061084) (xy 158.041594 -262.075676)
			(xy 158.029689 -262.08289) (xy 158.009983 -262.102534) (xy 157.996317 -262.126771) (xy 157.989707 -262.153798)
			(xy 157.990643 -262.181606) (xy 157.999057 -262.208128) (xy 158.014323 -262.23139) (xy 158.035305 -262.249664)
			(xy 158.04769 -262.256016) (xy 158.071847 -262.267919) (xy 158.11678 -262.297609) (xy 158.157094 -262.333319)
			(xy 158.191989 -262.374339) (xy 158.220773 -262.419857) (xy 158.242875 -262.468968) (xy 158.257855 -262.520698)
			(xy 158.265417 -262.57402) (xy 158.265876 -262.600948) (xy 158.26539 -262.628199) (xy 158.257634 -262.682147)
			(xy 158.242279 -262.734442) (xy 158.219637 -262.784019) (xy 158.190171 -262.829869) (xy 158.15448 -262.87106)
			(xy 158.113289 -262.906751) (xy 158.104574 -262.912352) (xy 257.3688 -262.912352) (xy 257.372871 -262.85673)
			(xy 257.384997 -262.802293) (xy 257.40492 -262.750202) (xy 257.432216 -262.701567) (xy 257.466302 -262.657424)
			(xy 257.506451 -262.618715) (xy 257.551809 -262.586264) (xy 257.601409 -262.560763) (xy 257.654193 -262.542756)
			(xy 257.709036 -262.532626) (xy 257.76477 -262.530589) (xy 257.820207 -262.536689) (xy 257.874164 -262.550795)
			(xy 257.925493 -262.572607) (xy 257.973099 -262.601661) (xy 258.015967 -262.637336) (xy 258.053184 -262.678873)
			(xy 258.083957 -262.725386) (xy 258.107629 -262.775883) (xy 258.123697 -262.82929) (xy 258.131817 -262.884466)
			(xy 258.132326 -262.912352) (xy 258.132205 -262.918956) (xy 259.356858 -262.918956) (xy 259.360929 -262.863334)
			(xy 259.373055 -262.808897) (xy 259.392978 -262.756806) (xy 259.420274 -262.708171) (xy 259.45436 -262.664028)
			(xy 259.494509 -262.625319) (xy 259.539867 -262.592868) (xy 259.589467 -262.567367) (xy 259.642251 -262.54936)
			(xy 259.697094 -262.53923) (xy 259.752828 -262.537193) (xy 259.808265 -262.543293) (xy 259.862222 -262.557399)
			(xy 259.913551 -262.579211) (xy 259.961157 -262.608265) (xy 260.004025 -262.64394) (xy 260.041242 -262.685477)
			(xy 260.072015 -262.73199) (xy 260.095687 -262.782487) (xy 260.111755 -262.835894) (xy 260.119875 -262.89107)
			(xy 260.120384 -262.918956) (xy 260.119875 -262.946842) (xy 260.111755 -263.002018) (xy 260.107925 -263.014747)
			(xy 264.681514 -263.014747) (xy 264.681514 -262.960253) (xy 264.689269 -262.906314) (xy 264.704621 -262.854027)
			(xy 264.727257 -262.804457) (xy 264.756717 -262.758613) (xy 264.792401 -262.717428) (xy 264.833583 -262.68174)
			(xy 264.879424 -262.652275) (xy 264.928991 -262.629634) (xy 264.981277 -262.614277) (xy 265.035215 -262.606517)
			(xy 265.062462 -262.606028) (xy 265.093475 -262.606629) (xy 265.154687 -262.616652) (xy 265.213472 -262.636442)
			(xy 265.268284 -262.665477) (xy 265.293348 -262.683752) (xy 265.304384 -262.691639) (xy 265.329499 -262.701857)
			(xy 265.35642 -262.705089) (xy 265.38324 -262.701108) (xy 265.40806 -262.690194) (xy 265.429124 -262.673122)
			(xy 265.44494 -262.651098) (xy 265.450066 -262.63854) (xy 265.460733 -262.611673) (xy 265.48898 -262.56124)
			(xy 265.524513 -262.515646) (xy 265.566518 -262.475936) (xy 265.614034 -262.443018) (xy 265.665973 -262.417646)
			(xy 265.721145 -262.400401) (xy 265.778288 -262.391678) (xy 265.80719 -262.391144) (xy 265.83444 -262.391703)
			(xy 265.888385 -262.399457) (xy 265.940678 -262.414811) (xy 265.990253 -262.43745) (xy 266.036101 -262.466914)
			(xy 266.07729 -262.502603) (xy 266.11298 -262.543791) (xy 266.142446 -262.589638) (xy 266.165086 -262.639213)
			(xy 266.18044 -262.691505) (xy 266.188197 -262.74545) (xy 266.188197 -262.79995) (xy 266.18044 -262.853895)
			(xy 266.165086 -262.906187) (xy 266.142446 -262.955762) (xy 266.11298 -263.001609) (xy 266.07729 -263.042797)
			(xy 266.036101 -263.078486) (xy 265.990253 -263.10795) (xy 265.940678 -263.130589) (xy 265.888385 -263.145943)
			(xy 265.83444 -263.153697) (xy 265.80719 -263.15416) (xy 265.776175 -263.153587) (xy 265.714963 -263.143555)
			(xy 265.656177 -263.123758) (xy 265.601367 -263.094715) (xy 265.576304 -263.076436) (xy 265.565304 -263.068497)
			(xy 265.540178 -263.058286) (xy 265.513248 -263.055062) (xy 265.486422 -263.059052) (xy 265.461597 -263.069974)
			(xy 265.44053 -263.087055) (xy 265.424713 -263.109086) (xy 265.419586 -263.121648) (xy 265.408953 -263.14853)
			(xy 265.380703 -263.198965) (xy 265.345166 -263.24456) (xy 265.303156 -263.28427) (xy 265.255634 -263.317187)
			(xy 265.20369 -263.342556) (xy 265.148513 -263.359796) (xy 265.091366 -263.368513) (xy 265.062462 -263.369044)
			(xy 265.035215 -263.368483) (xy 264.981277 -263.360723) (xy 264.928991 -263.345366) (xy 264.879424 -263.322725)
			(xy 264.833583 -263.29326) (xy 264.792401 -263.257572) (xy 264.756717 -263.216387) (xy 264.727257 -263.170543)
			(xy 264.704621 -263.120973) (xy 264.689269 -263.068686) (xy 264.681514 -263.014747) (xy 260.107925 -263.014747)
			(xy 260.095687 -263.055425) (xy 260.072015 -263.105922) (xy 260.041242 -263.152435) (xy 260.004025 -263.193972)
			(xy 259.961157 -263.229647) (xy 259.913551 -263.258701) (xy 259.862222 -263.280513) (xy 259.808265 -263.294619)
			(xy 259.752828 -263.300719) (xy 259.697094 -263.298682) (xy 259.642251 -263.288552) (xy 259.589467 -263.270545)
			(xy 259.539867 -263.245044) (xy 259.494509 -263.212593) (xy 259.45436 -263.173884) (xy 259.420274 -263.129741)
			(xy 259.392978 -263.081106) (xy 259.373055 -263.029015) (xy 259.360929 -262.974578) (xy 259.356858 -262.918956)
			(xy 258.132205 -262.918956) (xy 258.131817 -262.940238) (xy 258.123697 -262.995414) (xy 258.107629 -263.048821)
			(xy 258.083957 -263.099318) (xy 258.053184 -263.145831) (xy 258.015967 -263.187368) (xy 257.973099 -263.223043)
			(xy 257.925493 -263.252097) (xy 257.874164 -263.273909) (xy 257.820207 -263.288015) (xy 257.76477 -263.294115)
			(xy 257.709036 -263.292078) (xy 257.654193 -263.281948) (xy 257.601409 -263.263941) (xy 257.551809 -263.23844)
			(xy 257.506451 -263.205989) (xy 257.466302 -263.16728) (xy 257.432216 -263.123137) (xy 257.40492 -263.074502)
			(xy 257.384997 -263.022411) (xy 257.372871 -262.967974) (xy 257.3688 -262.912352) (xy 158.104574 -262.912352)
			(xy 158.067439 -262.936217) (xy 158.017862 -262.958859) (xy 157.965567 -262.974214) (xy 157.911619 -262.98197)
			(xy 157.857117 -262.98197) (xy 157.803169 -262.974214) (xy 157.750874 -262.958859) (xy 157.701297 -262.936217)
			(xy 157.655447 -262.906751) (xy 157.614256 -262.87106) (xy 157.578565 -262.829869) (xy 157.549099 -262.784019)
			(xy 157.526457 -262.734442) (xy 157.511102 -262.682147) (xy 157.503346 -262.628199) (xy 157.50286 -262.600948)
			(xy 157.503426 -262.571996) (xy 157.512177 -262.514756) (xy 157.529472 -262.459494) (xy 157.554912 -262.407477)
			(xy 157.587916 -262.359898) (xy 157.627725 -262.317848) (xy 157.673428 -262.282291) (xy 157.69844 -262.2677)
			(xy 157.710363 -262.260516) (xy 157.730064 -262.240864) (xy 157.743725 -262.216622) (xy 157.750331 -262.189591)
			(xy 157.749391 -262.161781) (xy 157.740976 -262.135258) (xy 157.72571 -262.111993) (xy 157.704729 -262.093715)
			(xy 157.692344 -262.08736) (xy 157.668225 -262.075383) (xy 157.623293 -262.045704) (xy 157.582978 -262.010006)
			(xy 157.548079 -261.968996) (xy 157.51929 -261.923489) (xy 157.497182 -261.874387) (xy 157.482193 -261.822667)
			(xy 157.474622 -261.769352) (xy 157.474158 -261.742428) (xy 147.008278 -261.742428) (xy 147.001965 -261.749474)
			(xy 146.959097 -261.785149) (xy 146.911491 -261.814203) (xy 146.860162 -261.836015) (xy 146.806205 -261.850121)
			(xy 146.750768 -261.856221) (xy 146.695034 -261.854184) (xy 146.640191 -261.844054) (xy 146.587407 -261.826047)
			(xy 146.537807 -261.800546) (xy 146.492449 -261.768095) (xy 146.4523 -261.729386) (xy 146.418214 -261.685243)
			(xy 146.390918 -261.636608) (xy 146.370995 -261.584517) (xy 146.358869 -261.53008) (xy 146.354798 -261.474458)
			(xy 145.633186 -261.474458) (xy 145.632677 -261.502344) (xy 145.624557 -261.55752) (xy 145.608489 -261.610927)
			(xy 145.584817 -261.661424) (xy 145.554044 -261.707937) (xy 145.516827 -261.749474) (xy 145.473959 -261.785149)
			(xy 145.426353 -261.814203) (xy 145.375024 -261.836015) (xy 145.321067 -261.850121) (xy 145.26563 -261.856221)
			(xy 145.209896 -261.854184) (xy 145.155053 -261.844054) (xy 145.102269 -261.826047) (xy 145.052669 -261.800546)
			(xy 145.007311 -261.768095) (xy 144.967162 -261.729386) (xy 144.933076 -261.685243) (xy 144.90578 -261.636608)
			(xy 144.885857 -261.584517) (xy 144.873731 -261.53008) (xy 144.86966 -261.474458) (xy 144.499198 -261.474458)
			(xy 144.515417 -261.484881) (xy 144.556611 -261.520573) (xy 144.592306 -261.561765) (xy 144.621775 -261.607618)
			(xy 144.644419 -261.657198) (xy 144.659775 -261.709496) (xy 144.667533 -261.763447) (xy 144.667533 -261.817953)
			(xy 144.659775 -261.871904) (xy 144.644419 -261.924202) (xy 144.621775 -261.973782) (xy 144.592306 -262.019635)
			(xy 144.556611 -262.060827) (xy 144.515417 -262.096519) (xy 144.469563 -262.125986) (xy 144.419981 -262.148626)
			(xy 144.367683 -262.16398) (xy 144.313731 -262.171734) (xy 144.286478 -262.172196) (xy 144.257563 -262.171623)
			(xy 144.200394 -262.162906) (xy 144.145197 -262.145659) (xy 144.093235 -262.120277) (xy 144.045699 -262.087343)
			(xy 144.00368 -262.047611) (xy 143.985488 -262.02513) (xy 143.977939 -262.016355) (xy 143.95717 -262.006182)
			(xy 143.94561 -262.005572) (xy 143.865346 -262.005572) (xy 143.853778 -262.006144) (xy 143.833005 -262.016335)
			(xy 143.825468 -262.02513) (xy 143.807303 -262.047635) (xy 143.765277 -262.087368) (xy 143.717736 -262.120303)
			(xy 143.66577 -262.145688) (xy 143.610568 -262.162939) (xy 143.553395 -262.171664) (xy 143.524478 -262.172196)
			(xy 143.498698 -262.171731) (xy 143.447607 -262.164796) (xy 143.397916 -262.151043) (xy 143.35053 -262.130721)
			(xy 143.306314 -262.104202) (xy 143.266072 -262.071968) (xy 143.230539 -262.034608) (xy 143.215106 -262.013954)
			(xy 143.208248 -262.004302) (xy 143.187674 -261.99338) (xy 143.083788 -261.98957) (xy 143.062452 -261.998968)
			(xy 143.054832 -262.008112) (xy 143.036618 -262.02908) (xy 142.995138 -262.066016) (xy 142.948742 -262.096546)
			(xy 142.898409 -262.120027) (xy 142.845203 -262.135961) (xy 142.790248 -262.144011) (xy 142.762478 -262.14451)
			(xy 142.733561 -262.14397) (xy 142.67639 -262.13525) (xy 142.62119 -262.117999) (xy 142.569227 -262.092611)
			(xy 142.521693 -262.05967) (xy 142.479677 -262.019929) (xy 142.461488 -261.997444) (xy 142.453937 -261.988672)
			(xy 142.43317 -261.978496) (xy 142.42161 -261.977886) (xy 142.341346 -261.977886) (xy 142.329782 -261.978488)
			(xy 142.309011 -261.988661) (xy 142.301468 -261.997444) (xy 142.283306 -262.019952) (xy 142.241279 -262.059684)
			(xy 142.193738 -262.092618) (xy 142.141771 -262.118002) (xy 142.086569 -262.135254) (xy 142.029396 -262.143978)
			(xy 142.000478 -262.14451) (xy 141.973228 -262.144019) (xy 141.919283 -262.13626) (xy 141.866991 -262.120903)
			(xy 141.817417 -262.09826) (xy 141.771569 -262.068794) (xy 141.730382 -262.033102) (xy 141.694693 -261.991913)
			(xy 141.665229 -261.946064) (xy 141.64259 -261.896488) (xy 141.627236 -261.844196) (xy 141.61948 -261.79025)
			(xy 132.376365 -261.79025) (xy 132.386417 -261.813002) (xy 132.400911 -261.863924) (xy 132.408226 -261.916361)
			(xy 132.408676 -261.942834) (xy 132.40819 -261.970085) (xy 132.400434 -262.024033) (xy 132.385079 -262.076328)
			(xy 132.362437 -262.125905) (xy 132.332971 -262.171755) (xy 132.29728 -262.212946) (xy 132.256089 -262.248637)
			(xy 132.210239 -262.278103) (xy 132.160662 -262.300745) (xy 132.108367 -262.3161) (xy 132.054419 -262.323856)
			(xy 131.999917 -262.323856) (xy 131.945969 -262.3161) (xy 131.893674 -262.300745) (xy 131.844097 -262.278103)
			(xy 131.798247 -262.248637) (xy 131.757056 -262.212946) (xy 131.721365 -262.171755) (xy 131.691899 -262.125905)
			(xy 131.669257 -262.076328) (xy 131.653902 -262.024033) (xy 131.646146 -261.970085) (xy 131.64566 -261.942834)
			(xy 131.646189 -261.913427) (xy 131.655211 -261.85531) (xy 131.673046 -261.799267) (xy 131.699272 -261.746625)
			(xy 131.733267 -261.698632) (xy 131.753356 -261.67715) (xy 131.76123 -261.669022) (xy 131.768596 -261.648194)
			(xy 131.758436 -261.548118) (xy 131.747006 -261.529068) (xy 131.737608 -261.522718) (xy 131.716027 -261.50738)
			(xy 131.67688 -261.471735) (xy 131.643037 -261.431019) (xy 131.615149 -261.386016) (xy 131.593752 -261.337588)
			(xy 131.579256 -261.286667) (xy 131.571941 -261.23423) (xy 131.571492 -261.207758) (xy 120.033402 -261.207758)
			(xy 120.056152 -261.228922) (xy 120.091745 -261.273697) (xy 120.120256 -261.323283) (xy 120.141044 -261.37657)
			(xy 120.147842 -261.404354) (xy 120.150128 -261.413752) (xy 120.160288 -261.429246) (xy 120.231662 -261.479538)
			(xy 120.249442 -261.48411) (xy 120.259094 -261.483094) (xy 120.270352 -261.481798) (xy 120.292974 -261.480402)
			(xy 120.304306 -261.4803) (xy 120.331558 -261.48077) (xy 120.385506 -261.488528) (xy 120.437801 -261.503884)
			(xy 120.487378 -261.526526) (xy 120.533229 -261.555993) (xy 120.574419 -261.591685) (xy 120.610111 -261.632876)
			(xy 120.639577 -261.678727) (xy 120.662219 -261.728305) (xy 120.677574 -261.7806) (xy 120.682457 -261.814564)
			(xy 128.285746 -261.814564) (xy 128.289817 -261.758942) (xy 128.301943 -261.704505) (xy 128.321866 -261.652414)
			(xy 128.349162 -261.603779) (xy 128.383248 -261.559636) (xy 128.423397 -261.520927) (xy 128.468755 -261.488476)
			(xy 128.518355 -261.462975) (xy 128.571139 -261.444968) (xy 128.625982 -261.434838) (xy 128.681716 -261.432801)
			(xy 128.737153 -261.438901) (xy 128.79111 -261.453007) (xy 128.842439 -261.474819) (xy 128.890045 -261.503873)
			(xy 128.932913 -261.539548) (xy 128.97013 -261.581085) (xy 129.000903 -261.627598) (xy 129.024575 -261.678095)
			(xy 129.040643 -261.731502) (xy 129.048763 -261.786678) (xy 129.049272 -261.814564) (xy 130.388104 -261.814564)
			(xy 130.392175 -261.758942) (xy 130.404301 -261.704505) (xy 130.424224 -261.652414) (xy 130.45152 -261.603779)
			(xy 130.485606 -261.559636) (xy 130.525755 -261.520927) (xy 130.571113 -261.488476) (xy 130.620713 -261.462975)
			(xy 130.673497 -261.444968) (xy 130.72834 -261.434838) (xy 130.784074 -261.432801) (xy 130.839511 -261.438901)
			(xy 130.893468 -261.453007) (xy 130.944797 -261.474819) (xy 130.992403 -261.503873) (xy 131.035271 -261.539548)
			(xy 131.072488 -261.581085) (xy 131.103261 -261.627598) (xy 131.126933 -261.678095) (xy 131.143001 -261.731502)
			(xy 131.151121 -261.786678) (xy 131.15163 -261.814564) (xy 131.151121 -261.84245) (xy 131.143001 -261.897626)
			(xy 131.126933 -261.951033) (xy 131.103261 -262.00153) (xy 131.072488 -262.048043) (xy 131.035271 -262.08958)
			(xy 130.992403 -262.125255) (xy 130.944797 -262.154309) (xy 130.893468 -262.176121) (xy 130.839511 -262.190227)
			(xy 130.784074 -262.196327) (xy 130.72834 -262.19429) (xy 130.673497 -262.18416) (xy 130.620713 -262.166153)
			(xy 130.571113 -262.140652) (xy 130.525755 -262.108201) (xy 130.485606 -262.069492) (xy 130.45152 -262.025349)
			(xy 130.424224 -261.976714) (xy 130.404301 -261.924623) (xy 130.392175 -261.870186) (xy 130.388104 -261.814564)
			(xy 129.049272 -261.814564) (xy 129.048763 -261.84245) (xy 129.040643 -261.897626) (xy 129.024575 -261.951033)
			(xy 129.000903 -262.00153) (xy 128.97013 -262.048043) (xy 128.932913 -262.08958) (xy 128.890045 -262.125255)
			(xy 128.842439 -262.154309) (xy 128.79111 -262.176121) (xy 128.737153 -262.190227) (xy 128.681716 -262.196327)
			(xy 128.625982 -262.19429) (xy 128.571139 -262.18416) (xy 128.518355 -262.166153) (xy 128.468755 -262.140652)
			(xy 128.423397 -262.108201) (xy 128.383248 -262.069492) (xy 128.349162 -262.025349) (xy 128.321866 -261.976714)
			(xy 128.301943 -261.924623) (xy 128.289817 -261.870186) (xy 128.285746 -261.814564) (xy 120.682457 -261.814564)
			(xy 120.68533 -261.834548) (xy 120.68533 -261.889052) (xy 120.677574 -261.943) (xy 120.662219 -261.995295)
			(xy 120.639577 -262.044873) (xy 120.610111 -262.090724) (xy 120.574419 -262.131915) (xy 120.533229 -262.167607)
			(xy 120.487378 -262.197074) (xy 120.437801 -262.219716) (xy 120.385506 -262.235072) (xy 120.331558 -262.24283)
			(xy 120.304306 -262.243316) (xy 120.275709 -262.242776) (xy 120.219157 -262.234239) (xy 120.164512 -262.217355)
			(xy 120.113001 -262.192503) (xy 120.065776 -262.16024) (xy 120.023897 -262.121288) (xy 119.988302 -262.076522)
			(xy 119.959789 -262.026943) (xy 119.938997 -261.973663) (xy 119.932196 -261.945882) (xy 119.92991 -261.936484)
			(xy 119.91975 -261.92099) (xy 119.848376 -261.870698) (xy 119.830596 -261.866126) (xy 119.820944 -261.867142)
			(xy 119.809685 -261.868435) (xy 119.787064 -261.869833) (xy 119.775732 -261.869936) (xy 119.74848 -261.869419)
			(xy 119.694529 -261.861666) (xy 119.642231 -261.846314) (xy 119.592651 -261.823675) (xy 119.546797 -261.79421)
			(xy 119.505604 -261.758519) (xy 119.469909 -261.717329) (xy 119.44044 -261.671477) (xy 119.417797 -261.621899)
			(xy 119.402441 -261.569602) (xy 119.394683 -261.515652) (xy 117.802369 -261.515652) (xy 117.813269 -261.538903)
			(xy 117.829337 -261.59231) (xy 117.837457 -261.647486) (xy 117.837966 -261.675372) (xy 117.837457 -261.703258)
			(xy 117.829337 -261.758434) (xy 117.813269 -261.811841) (xy 117.789597 -261.862338) (xy 117.758824 -261.908851)
			(xy 117.721607 -261.950388) (xy 117.678739 -261.986063) (xy 117.631133 -262.015117) (xy 117.579804 -262.036929)
			(xy 117.525847 -262.051035) (xy 117.47041 -262.057135) (xy 117.414676 -262.055098) (xy 117.359833 -262.044968)
			(xy 117.307049 -262.026961) (xy 117.257449 -262.00146) (xy 117.212091 -261.969009) (xy 117.171942 -261.9303)
			(xy 117.137856 -261.886157) (xy 117.11056 -261.837522) (xy 117.090637 -261.785431) (xy 117.078511 -261.730994)
			(xy 117.07444 -261.675372) (xy 112.926399 -261.675372) (xy 112.926622 -261.687564) (xy 112.926113 -261.71545)
			(xy 112.917993 -261.770626) (xy 112.901925 -261.824033) (xy 112.878253 -261.87453) (xy 112.84748 -261.921043)
			(xy 112.810263 -261.96258) (xy 112.767395 -261.998255) (xy 112.719789 -262.027309) (xy 112.66846 -262.049121)
			(xy 112.614503 -262.063227) (xy 112.559066 -262.069327) (xy 112.503332 -262.06729) (xy 112.448489 -262.05716)
			(xy 112.395705 -262.039153) (xy 112.346105 -262.013652) (xy 112.300747 -261.981201) (xy 112.260598 -261.942492)
			(xy 112.226512 -261.898349) (xy 112.199216 -261.849714) (xy 112.179293 -261.797623) (xy 112.167167 -261.743186)
			(xy 112.163096 -261.687564) (xy 40.899334 -261.687564) (xy 40.899334 -262.195564) (xy 116.381782 -262.195564)
			(xy 116.385853 -262.139942) (xy 116.397979 -262.085505) (xy 116.417902 -262.033414) (xy 116.445198 -261.984779)
			(xy 116.479284 -261.940636) (xy 116.519433 -261.901927) (xy 116.564791 -261.869476) (xy 116.614391 -261.843975)
			(xy 116.667175 -261.825968) (xy 116.722018 -261.815838) (xy 116.777752 -261.813801) (xy 116.833189 -261.819901)
			(xy 116.887146 -261.834007) (xy 116.938475 -261.855819) (xy 116.986081 -261.884873) (xy 117.028949 -261.920548)
			(xy 117.066166 -261.962085) (xy 117.096939 -262.008598) (xy 117.120611 -262.059095) (xy 117.136679 -262.112502)
			(xy 117.144799 -262.167678) (xy 117.145308 -262.195564) (xy 117.144799 -262.22345) (xy 117.136679 -262.278626)
			(xy 117.120611 -262.332033) (xy 117.096939 -262.38253) (xy 117.066166 -262.429043) (xy 117.028949 -262.47058)
			(xy 116.986081 -262.506255) (xy 116.938475 -262.535309) (xy 116.887146 -262.557121) (xy 116.833189 -262.571227)
			(xy 116.777752 -262.577327) (xy 116.722018 -262.57529) (xy 116.667175 -262.56516) (xy 116.614391 -262.547153)
			(xy 116.564791 -262.521652) (xy 116.519433 -262.489201) (xy 116.479284 -262.450492) (xy 116.445198 -262.406349)
			(xy 116.417902 -262.357714) (xy 116.397979 -262.305623) (xy 116.385853 -262.251186) (xy 116.381782 -262.195564)
			(xy 40.899334 -262.195564) (xy 40.899334 -262.703564) (xy 112.163096 -262.703564) (xy 112.167167 -262.647942)
			(xy 112.179293 -262.593505) (xy 112.199216 -262.541414) (xy 112.226512 -262.492779) (xy 112.260598 -262.448636)
			(xy 112.300747 -262.409927) (xy 112.346105 -262.377476) (xy 112.395705 -262.351975) (xy 112.448489 -262.333968)
			(xy 112.503332 -262.323838) (xy 112.559066 -262.321801) (xy 112.614503 -262.327901) (xy 112.66846 -262.342007)
			(xy 112.719789 -262.363819) (xy 112.767395 -262.392873) (xy 112.810263 -262.428548) (xy 112.84748 -262.470085)
			(xy 112.878253 -262.516598) (xy 112.901925 -262.567095) (xy 112.906073 -262.580882) (xy 119.152922 -262.580882)
			(xy 119.156993 -262.52526) (xy 119.169119 -262.470823) (xy 119.189042 -262.418732) (xy 119.216338 -262.370097)
			(xy 119.250424 -262.325954) (xy 119.290573 -262.287245) (xy 119.335931 -262.254794) (xy 119.385531 -262.229293)
			(xy 119.438315 -262.211286) (xy 119.493158 -262.201156) (xy 119.548892 -262.199119) (xy 119.604329 -262.205219)
			(xy 119.658286 -262.219325) (xy 119.709615 -262.241137) (xy 119.757221 -262.270191) (xy 119.800089 -262.305866)
			(xy 119.837306 -262.347403) (xy 119.868079 -262.393916) (xy 119.891751 -262.444413) (xy 119.907819 -262.49782)
			(xy 119.915939 -262.552996) (xy 119.916448 -262.580882) (xy 119.915939 -262.608768) (xy 119.907819 -262.663944)
			(xy 119.891751 -262.717351) (xy 119.868079 -262.767848) (xy 119.837306 -262.814361) (xy 119.800089 -262.855898)
			(xy 119.757221 -262.891573) (xy 119.709615 -262.920627) (xy 119.658286 -262.942439) (xy 119.604329 -262.956545)
			(xy 119.548892 -262.962645) (xy 119.493158 -262.960608) (xy 119.438315 -262.950478) (xy 119.385531 -262.932471)
			(xy 119.335931 -262.90697) (xy 119.290573 -262.874519) (xy 119.250424 -262.83581) (xy 119.216338 -262.791667)
			(xy 119.189042 -262.743032) (xy 119.169119 -262.690941) (xy 119.156993 -262.636504) (xy 119.152922 -262.580882)
			(xy 112.906073 -262.580882) (xy 112.917993 -262.620502) (xy 112.926113 -262.675678) (xy 112.926622 -262.703564)
			(xy 112.926113 -262.73145) (xy 112.917993 -262.786626) (xy 112.901925 -262.840033) (xy 112.878253 -262.89053)
			(xy 112.84748 -262.937043) (xy 112.810263 -262.97858) (xy 112.767395 -263.014255) (xy 112.719789 -263.043309)
			(xy 112.66846 -263.065121) (xy 112.642667 -263.071864) (xy 116.381782 -263.071864) (xy 116.385853 -263.016242)
			(xy 116.397979 -262.961805) (xy 116.417902 -262.909714) (xy 116.445198 -262.861079) (xy 116.479284 -262.816936)
			(xy 116.519433 -262.778227) (xy 116.564791 -262.745776) (xy 116.614391 -262.720275) (xy 116.667175 -262.702268)
			(xy 116.722018 -262.692138) (xy 116.777752 -262.690101) (xy 116.833189 -262.696201) (xy 116.887146 -262.710307)
			(xy 116.938475 -262.732119) (xy 116.986081 -262.761173) (xy 117.028949 -262.796848) (xy 117.066166 -262.838385)
			(xy 117.096939 -262.884898) (xy 117.120611 -262.935395) (xy 117.136679 -262.988802) (xy 117.144799 -263.043978)
			(xy 117.145308 -263.071864) (xy 117.144799 -263.09975) (xy 117.136679 -263.154926) (xy 117.128121 -263.18337)
			(xy 122.968764 -263.18337) (xy 122.972835 -263.127748) (xy 122.984961 -263.073311) (xy 123.004884 -263.02122)
			(xy 123.03218 -262.972585) (xy 123.066266 -262.928442) (xy 123.106415 -262.889733) (xy 123.151773 -262.857282)
			(xy 123.201373 -262.831781) (xy 123.254157 -262.813774) (xy 123.309 -262.803644) (xy 123.364734 -262.801607)
			(xy 123.420171 -262.807707) (xy 123.474128 -262.821813) (xy 123.525457 -262.843625) (xy 123.573063 -262.872679)
			(xy 123.615931 -262.908354) (xy 123.619513 -262.912352) (xy 141.268956 -262.912352) (xy 141.273027 -262.85673)
			(xy 141.285153 -262.802293) (xy 141.305076 -262.750202) (xy 141.332372 -262.701567) (xy 141.366458 -262.657424)
			(xy 141.406607 -262.618715) (xy 141.451965 -262.586264) (xy 141.501565 -262.560763) (xy 141.554349 -262.542756)
			(xy 141.609192 -262.532626) (xy 141.664926 -262.530589) (xy 141.720363 -262.536689) (xy 141.77432 -262.550795)
			(xy 141.825649 -262.572607) (xy 141.873255 -262.601661) (xy 141.916123 -262.637336) (xy 141.95334 -262.678873)
			(xy 141.984113 -262.725386) (xy 142.007785 -262.775883) (xy 142.023853 -262.82929) (xy 142.031973 -262.884466)
			(xy 142.032482 -262.912352) (xy 142.032417 -262.915908) (xy 143.242536 -262.915908) (xy 143.246607 -262.860286)
			(xy 143.258733 -262.805849) (xy 143.278656 -262.753758) (xy 143.305952 -262.705123) (xy 143.340038 -262.66098)
			(xy 143.380187 -262.622271) (xy 143.425545 -262.58982) (xy 143.475145 -262.564319) (xy 143.527929 -262.546312)
			(xy 143.582772 -262.536182) (xy 143.638506 -262.534145) (xy 143.693943 -262.540245) (xy 143.7479 -262.554351)
			(xy 143.799229 -262.576163) (xy 143.846835 -262.605217) (xy 143.889703 -262.640892) (xy 143.92692 -262.682429)
			(xy 143.957693 -262.728942) (xy 143.981365 -262.779439) (xy 143.997433 -262.832846) (xy 143.999639 -262.847836)
			(xy 148.939502 -262.847836) (xy 148.943573 -262.792214) (xy 148.955699 -262.737777) (xy 148.975622 -262.685686)
			(xy 149.002918 -262.637051) (xy 149.037004 -262.592908) (xy 149.077153 -262.554199) (xy 149.122511 -262.521748)
			(xy 149.172111 -262.496247) (xy 149.224895 -262.47824) (xy 149.279738 -262.46811) (xy 149.335472 -262.466073)
			(xy 149.390909 -262.472173) (xy 149.444866 -262.486279) (xy 149.496195 -262.508091) (xy 149.543801 -262.537145)
			(xy 149.586669 -262.57282) (xy 149.623886 -262.614357) (xy 149.654659 -262.66087) (xy 149.678331 -262.711367)
			(xy 149.694399 -262.764774) (xy 149.702519 -262.81995) (xy 149.703028 -262.847836) (xy 149.702519 -262.875722)
			(xy 149.700007 -262.892794) (xy 149.960074 -262.892794) (xy 149.964145 -262.837172) (xy 149.976271 -262.782735)
			(xy 149.996194 -262.730644) (xy 150.02349 -262.682009) (xy 150.057576 -262.637866) (xy 150.097725 -262.599157)
			(xy 150.143083 -262.566706) (xy 150.192683 -262.541205) (xy 150.245467 -262.523198) (xy 150.30031 -262.513068)
			(xy 150.356044 -262.511031) (xy 150.411481 -262.517131) (xy 150.465438 -262.531237) (xy 150.516767 -262.553049)
			(xy 150.564373 -262.582103) (xy 150.607241 -262.617778) (xy 150.644458 -262.659315) (xy 150.675231 -262.705828)
			(xy 150.698903 -262.756325) (xy 150.714971 -262.809732) (xy 150.721924 -262.85698) (xy 153.136852 -262.85698)
			(xy 153.140923 -262.801358) (xy 153.153049 -262.746921) (xy 153.172972 -262.69483) (xy 153.200268 -262.646195)
			(xy 153.234354 -262.602052) (xy 153.274503 -262.563343) (xy 153.319861 -262.530892) (xy 153.369461 -262.505391)
			(xy 153.422245 -262.487384) (xy 153.477088 -262.477254) (xy 153.532822 -262.475217) (xy 153.588259 -262.481317)
			(xy 153.642216 -262.495423) (xy 153.693545 -262.517235) (xy 153.741151 -262.546289) (xy 153.784019 -262.581964)
			(xy 153.821236 -262.623501) (xy 153.852009 -262.670014) (xy 153.875681 -262.720511) (xy 153.891749 -262.773918)
			(xy 153.899869 -262.829094) (xy 153.900378 -262.85698) (xy 153.899869 -262.884866) (xy 153.891749 -262.940042)
			(xy 153.875681 -262.993449) (xy 153.852009 -263.043946) (xy 153.821236 -263.090459) (xy 153.784019 -263.131996)
			(xy 153.741151 -263.167671) (xy 153.693545 -263.196725) (xy 153.642216 -263.218537) (xy 153.588259 -263.232643)
			(xy 153.532822 -263.238743) (xy 153.477088 -263.236706) (xy 153.422245 -263.226576) (xy 153.369461 -263.208569)
			(xy 153.319861 -263.183068) (xy 153.274503 -263.150617) (xy 153.234354 -263.111908) (xy 153.200268 -263.067765)
			(xy 153.172972 -263.01913) (xy 153.153049 -262.967039) (xy 153.140923 -262.912602) (xy 153.136852 -262.85698)
			(xy 150.721924 -262.85698) (xy 150.723091 -262.864908) (xy 150.7236 -262.892794) (xy 150.723091 -262.92068)
			(xy 150.714971 -262.975856) (xy 150.698903 -263.029263) (xy 150.675231 -263.07976) (xy 150.644458 -263.126273)
			(xy 150.607241 -263.16781) (xy 150.564373 -263.203485) (xy 150.516767 -263.232539) (xy 150.465438 -263.254351)
			(xy 150.411481 -263.268457) (xy 150.356044 -263.274557) (xy 150.30031 -263.27252) (xy 150.245467 -263.26239)
			(xy 150.192683 -263.244383) (xy 150.143083 -263.218882) (xy 150.097725 -263.186431) (xy 150.057576 -263.147722)
			(xy 150.02349 -263.103579) (xy 149.996194 -263.054944) (xy 149.976271 -263.002853) (xy 149.964145 -262.948416)
			(xy 149.960074 -262.892794) (xy 149.700007 -262.892794) (xy 149.694399 -262.930898) (xy 149.678331 -262.984305)
			(xy 149.654659 -263.034802) (xy 149.623886 -263.081315) (xy 149.586669 -263.122852) (xy 149.543801 -263.158527)
			(xy 149.496195 -263.187581) (xy 149.444866 -263.209393) (xy 149.390909 -263.223499) (xy 149.335472 -263.229599)
			(xy 149.279738 -263.227562) (xy 149.224895 -263.217432) (xy 149.172111 -263.199425) (xy 149.122511 -263.173924)
			(xy 149.077153 -263.141473) (xy 149.037004 -263.102764) (xy 149.002918 -263.058621) (xy 148.975622 -263.009986)
			(xy 148.955699 -262.957895) (xy 148.943573 -262.903458) (xy 148.939502 -262.847836) (xy 143.999639 -262.847836)
			(xy 144.005553 -262.888022) (xy 144.006062 -262.915908) (xy 144.005553 -262.943794) (xy 143.997433 -262.99897)
			(xy 143.981365 -263.052377) (xy 143.957693 -263.102874) (xy 143.92692 -263.149387) (xy 143.889703 -263.190924)
			(xy 143.846835 -263.226599) (xy 143.799229 -263.255653) (xy 143.7479 -263.277465) (xy 143.693943 -263.291571)
			(xy 143.638506 -263.297671) (xy 143.582772 -263.295634) (xy 143.527929 -263.285504) (xy 143.475145 -263.267497)
			(xy 143.425545 -263.241996) (xy 143.380187 -263.209545) (xy 143.340038 -263.170836) (xy 143.305952 -263.126693)
			(xy 143.278656 -263.078058) (xy 143.258733 -263.025967) (xy 143.246607 -262.97153) (xy 143.242536 -262.915908)
			(xy 142.032417 -262.915908) (xy 142.031973 -262.940238) (xy 142.023853 -262.995414) (xy 142.007785 -263.048821)
			(xy 141.984113 -263.099318) (xy 141.95334 -263.145831) (xy 141.916123 -263.187368) (xy 141.873255 -263.223043)
			(xy 141.825649 -263.252097) (xy 141.77432 -263.273909) (xy 141.720363 -263.288015) (xy 141.664926 -263.294115)
			(xy 141.609192 -263.292078) (xy 141.554349 -263.281948) (xy 141.501565 -263.263941) (xy 141.451965 -263.23844)
			(xy 141.406607 -263.205989) (xy 141.366458 -263.16728) (xy 141.332372 -263.123137) (xy 141.305076 -263.074502)
			(xy 141.285153 -263.022411) (xy 141.273027 -262.967974) (xy 141.268956 -262.912352) (xy 123.619513 -262.912352)
			(xy 123.653148 -262.949891) (xy 123.683921 -262.996404) (xy 123.707593 -263.046901) (xy 123.723661 -263.100308)
			(xy 123.731781 -263.155484) (xy 123.73229 -263.18337) (xy 123.731781 -263.211256) (xy 123.723661 -263.266432)
			(xy 123.707593 -263.319839) (xy 123.683921 -263.370336) (xy 123.679062 -263.37768) (xy 154.048204 -263.37768)
			(xy 154.052275 -263.322058) (xy 154.064401 -263.267621) (xy 154.084324 -263.21553) (xy 154.11162 -263.166895)
			(xy 154.145706 -263.122752) (xy 154.185855 -263.084043) (xy 154.231213 -263.051592) (xy 154.280813 -263.026091)
			(xy 154.333597 -263.008084) (xy 154.38844 -262.997954) (xy 154.444174 -262.995917) (xy 154.499611 -263.002017)
			(xy 154.553568 -263.016123) (xy 154.604897 -263.037935) (xy 154.652503 -263.066989) (xy 154.695371 -263.102664)
			(xy 154.732588 -263.144201) (xy 154.763361 -263.190714) (xy 154.787033 -263.241211) (xy 154.803101 -263.294618)
			(xy 154.811221 -263.349794) (xy 154.81173 -263.37768) (xy 270.148048 -263.37768) (xy 270.152119 -263.322058)
			(xy 270.164245 -263.267621) (xy 270.184168 -263.21553) (xy 270.211464 -263.166895) (xy 270.24555 -263.122752)
			(xy 270.285699 -263.084043) (xy 270.331057 -263.051592) (xy 270.380657 -263.026091) (xy 270.433441 -263.008084)
			(xy 270.488284 -262.997954) (xy 270.544018 -262.995917) (xy 270.599455 -263.002017) (xy 270.653412 -263.016123)
			(xy 270.704741 -263.037935) (xy 270.752347 -263.066989) (xy 270.795215 -263.102664) (xy 270.832432 -263.144201)
			(xy 270.863205 -263.190714) (xy 270.886877 -263.241211) (xy 270.902945 -263.294618) (xy 270.911065 -263.349794)
			(xy 270.911574 -263.37768) (xy 270.911065 -263.405566) (xy 270.902945 -263.460742) (xy 270.886877 -263.514149)
			(xy 270.863205 -263.564646) (xy 270.832432 -263.611159) (xy 270.822238 -263.622536) (xy 273.729194 -263.622536)
			(xy 273.733265 -263.566914) (xy 273.745391 -263.512477) (xy 273.765314 -263.460386) (xy 273.79261 -263.411751)
			(xy 273.826696 -263.367608) (xy 273.866845 -263.328899) (xy 273.912203 -263.296448) (xy 273.961803 -263.270947)
			(xy 274.014587 -263.25294) (xy 274.06943 -263.24281) (xy 274.125164 -263.240773) (xy 274.180601 -263.246873)
			(xy 274.234558 -263.260979) (xy 274.285887 -263.282791) (xy 274.32733 -263.308084) (xy 331.439772 -263.308084)
			(xy 331.443843 -263.252462) (xy 331.455969 -263.198025) (xy 331.475892 -263.145934) (xy 331.503188 -263.097299)
			(xy 331.537274 -263.053156) (xy 331.577423 -263.014447) (xy 331.622781 -262.981996) (xy 331.672381 -262.956495)
			(xy 331.725165 -262.938488) (xy 331.780008 -262.928358) (xy 331.835742 -262.926321) (xy 331.891179 -262.932421)
			(xy 331.945136 -262.946527) (xy 331.996465 -262.968339) (xy 332.044071 -262.997393) (xy 332.086939 -263.033068)
			(xy 332.124156 -263.074605) (xy 332.154929 -263.121118) (xy 332.178601 -263.171615) (xy 332.194669 -263.225022)
			(xy 332.202789 -263.280198) (xy 332.203298 -263.308084) (xy 332.202789 -263.33597) (xy 332.194669 -263.391146)
			(xy 332.181489 -263.434955) (xy 332.34293 -263.434955) (xy 332.34293 -263.380445) (xy 332.350687 -263.326491)
			(xy 332.366044 -263.27419) (xy 332.388688 -263.224607) (xy 332.418158 -263.178751) (xy 332.453854 -263.137555)
			(xy 332.495049 -263.101859) (xy 332.540905 -263.072389) (xy 332.590488 -263.049745) (xy 332.642789 -263.034388)
			(xy 332.696743 -263.02663) (xy 332.723998 -263.026144) (xy 332.751944 -263.026637) (xy 332.807235 -263.034803)
			(xy 332.860745 -263.050945) (xy 332.911328 -263.07472) (xy 332.957903 -263.105617) (xy 332.979014 -263.123934)
			(xy 332.98765 -263.131808) (xy 333.009748 -263.138158) (xy 333.111348 -263.120886) (xy 333.130144 -263.107678)
			(xy 333.135732 -263.097518) (xy 333.150295 -263.07235) (xy 333.1858 -263.026304) (xy 333.227879 -262.986178)
			(xy 333.275558 -262.9529) (xy 333.327735 -262.927241) (xy 333.3832 -262.909794) (xy 333.44067 -262.900964)
			(xy 333.469742 -262.900414) (xy 333.496993 -262.900859) (xy 333.550939 -262.908621) (xy 333.603232 -262.92398)
			(xy 333.652807 -262.946625) (xy 333.698654 -262.976094) (xy 333.739842 -263.011788) (xy 333.775531 -263.052979)
			(xy 333.804995 -263.09883) (xy 333.827635 -263.148408) (xy 333.842988 -263.200702) (xy 333.850744 -263.254649)
			(xy 333.850744 -263.309151) (xy 333.842988 -263.363098) (xy 333.827635 -263.415392) (xy 333.804995 -263.46497)
			(xy 333.775531 -263.510821) (xy 333.739842 -263.552012) (xy 333.698654 -263.587706) (xy 333.652807 -263.617175)
			(xy 333.603232 -263.63982) (xy 333.550939 -263.655179) (xy 333.496993 -263.662941) (xy 333.469742 -263.66343)
			(xy 333.441797 -263.66292) (xy 333.386506 -263.654759) (xy 333.332996 -263.638621) (xy 333.282413 -263.61485)
			(xy 333.235838 -263.583956) (xy 333.214726 -263.56564) (xy 333.20609 -263.557766) (xy 333.183992 -263.551416)
			(xy 333.082392 -263.568688) (xy 333.063596 -263.581896) (xy 333.058008 -263.592056) (xy 333.043478 -263.617245)
			(xy 333.007969 -263.663292) (xy 332.965885 -263.703418) (xy 332.9182 -263.736695) (xy 332.866018 -263.76235)
			(xy 332.810547 -263.779791) (xy 332.753072 -263.788614) (xy 332.723998 -263.78916) (xy 332.696743 -263.78877)
			(xy 332.642789 -263.781012) (xy 332.590488 -263.765655) (xy 332.540905 -263.743011) (xy 332.495049 -263.713541)
			(xy 332.453854 -263.677845) (xy 332.418158 -263.636649) (xy 332.388688 -263.590793) (xy 332.366044 -263.54121)
			(xy 332.350687 -263.488909) (xy 332.34293 -263.434955) (xy 332.181489 -263.434955) (xy 332.178601 -263.444553)
			(xy 332.154929 -263.49505) (xy 332.124156 -263.541563) (xy 332.086939 -263.5831) (xy 332.044071 -263.618775)
			(xy 331.996465 -263.647829) (xy 331.945136 -263.669641) (xy 331.891179 -263.683747) (xy 331.835742 -263.689847)
			(xy 331.780008 -263.68781) (xy 331.725165 -263.67768) (xy 331.672381 -263.659673) (xy 331.622781 -263.634172)
			(xy 331.577423 -263.601721) (xy 331.537274 -263.563012) (xy 331.503188 -263.518869) (xy 331.475892 -263.470234)
			(xy 331.455969 -263.418143) (xy 331.443843 -263.363706) (xy 331.439772 -263.308084) (xy 274.32733 -263.308084)
			(xy 274.333493 -263.311845) (xy 274.376361 -263.34752) (xy 274.413578 -263.389057) (xy 274.444351 -263.43557)
			(xy 274.468023 -263.486067) (xy 274.484091 -263.539474) (xy 274.492211 -263.59465) (xy 274.49272 -263.622536)
			(xy 274.492211 -263.650422) (xy 274.484091 -263.705598) (xy 274.468023 -263.759005) (xy 274.444351 -263.809502)
			(xy 274.413578 -263.856015) (xy 274.376361 -263.897552) (xy 274.333493 -263.933227) (xy 274.285887 -263.962281)
			(xy 274.234558 -263.984093) (xy 274.19905 -263.993376) (xy 333.820006 -263.993376) (xy 333.824077 -263.937754)
			(xy 333.836203 -263.883317) (xy 333.856126 -263.831226) (xy 333.883422 -263.782591) (xy 333.917508 -263.738448)
			(xy 333.957657 -263.699739) (xy 334.003015 -263.667288) (xy 334.052615 -263.641787) (xy 334.105399 -263.62378)
			(xy 334.160242 -263.61365) (xy 334.215976 -263.611613) (xy 334.271413 -263.617713) (xy 334.32537 -263.631819)
			(xy 334.376699 -263.653631) (xy 334.424305 -263.682685) (xy 334.467173 -263.71836) (xy 334.50439 -263.759897)
			(xy 334.535163 -263.80641) (xy 334.558835 -263.856907) (xy 334.574903 -263.910314) (xy 334.583023 -263.96549)
			(xy 334.583532 -263.993376) (xy 334.583023 -264.021262) (xy 334.574903 -264.076438) (xy 334.558835 -264.129845)
			(xy 334.535163 -264.180342) (xy 334.50439 -264.226855) (xy 334.467173 -264.268392) (xy 334.424305 -264.304067)
			(xy 334.376699 -264.333121) (xy 334.35194 -264.343642) (xy 334.727296 -264.343642) (xy 334.727843 -264.314856)
			(xy 334.736488 -264.257936) (xy 334.753589 -264.202961) (xy 334.778756 -264.151181) (xy 334.811418 -264.10377)
			(xy 334.850834 -264.061806) (xy 334.896108 -264.026241) (xy 334.946213 -263.997884) (xy 335.000009 -263.977377)
			(xy 335.028032 -263.97077) (xy 335.04147 -263.967361) (xy 335.066009 -263.954495) (xy 335.086182 -263.935502)
			(xy 335.100501 -263.911781) (xy 335.10791 -263.885083) (xy 335.107864 -263.857376) (xy 335.100364 -263.830703)
			(xy 335.093564 -263.818624) (xy 335.080413 -263.796127) (xy 335.059626 -263.748344) (xy 335.045535 -263.698177)
			(xy 335.038402 -263.646558) (xy 335.037938 -263.620504) (xy 335.038424 -263.593253) (xy 335.04618 -263.539305)
			(xy 335.061535 -263.48701) (xy 335.084177 -263.437433) (xy 335.113643 -263.391583) (xy 335.149334 -263.350392)
			(xy 335.190525 -263.314701) (xy 335.236375 -263.285235) (xy 335.285952 -263.262593) (xy 335.338247 -263.247238)
			(xy 335.392195 -263.239482) (xy 335.446697 -263.239482) (xy 335.500645 -263.247238) (xy 335.55294 -263.262593)
			(xy 335.602517 -263.285235) (xy 335.648367 -263.314701) (xy 335.689558 -263.350392) (xy 335.725249 -263.391583)
			(xy 335.754715 -263.437433) (xy 335.777357 -263.48701) (xy 335.792712 -263.539305) (xy 335.800468 -263.593253)
			(xy 335.800954 -263.620504) (xy 335.800488 -263.649294) (xy 335.791834 -263.706219) (xy 335.774725 -263.761197)
			(xy 335.749548 -263.81298) (xy 335.716876 -263.860392) (xy 335.67745 -263.902356) (xy 335.632165 -263.937918)
			(xy 335.582051 -263.966271) (xy 335.528245 -263.986772) (xy 335.500218 -263.993376) (xy 335.486767 -263.996746)
			(xy 335.462216 -264.00961) (xy 335.442034 -264.028609) (xy 335.427711 -264.052338) (xy 335.420305 -264.079047)
			(xy 335.420361 -264.106764) (xy 335.427876 -264.133443) (xy 335.434686 -264.145522) (xy 335.44786 -264.168006)
			(xy 335.468641 -264.215794) (xy 335.482725 -264.265965) (xy 335.4891 -264.312146) (xy 335.602324 -264.312146)
			(xy 335.606395 -264.256524) (xy 335.618521 -264.202087) (xy 335.638444 -264.149996) (xy 335.66574 -264.101361)
			(xy 335.699826 -264.057218) (xy 335.739975 -264.018509) (xy 335.785333 -263.986058) (xy 335.834933 -263.960557)
			(xy 335.887717 -263.94255) (xy 335.94256 -263.93242) (xy 335.998294 -263.930383) (xy 336.053731 -263.936483)
			(xy 336.107688 -263.950589) (xy 336.159017 -263.972401) (xy 336.206623 -264.001455) (xy 336.249491 -264.03713)
			(xy 336.286708 -264.078667) (xy 336.317481 -264.12518) (xy 336.319516 -264.12952) (xy 346.649292 -264.12952)
			(xy 346.653363 -264.073898) (xy 346.665489 -264.019461) (xy 346.685412 -263.96737) (xy 346.712708 -263.918735)
			(xy 346.746794 -263.874592) (xy 346.786943 -263.835883) (xy 346.832301 -263.803432) (xy 346.881901 -263.777931)
			(xy 346.934685 -263.759924) (xy 346.989528 -263.749794) (xy 347.045262 -263.747757) (xy 347.100699 -263.753857)
			(xy 347.154656 -263.767963) (xy 347.200951 -263.787636) (xy 349.771968 -263.787636) (xy 349.776039 -263.732014)
			(xy 349.788165 -263.677577) (xy 349.808088 -263.625486) (xy 349.835384 -263.576851) (xy 349.86947 -263.532708)
			(xy 349.909619 -263.493999) (xy 349.954977 -263.461548) (xy 350.004577 -263.436047) (xy 350.057361 -263.41804)
			(xy 350.112204 -263.40791) (xy 350.167938 -263.405873) (xy 350.223375 -263.411973) (xy 350.277332 -263.426079)
			(xy 350.328661 -263.447891) (xy 350.376267 -263.476945) (xy 350.419135 -263.51262) (xy 350.456352 -263.554157)
			(xy 350.487125 -263.60067) (xy 350.510797 -263.651167) (xy 350.526865 -263.704574) (xy 350.534985 -263.75975)
			(xy 350.535494 -263.787636) (xy 350.534985 -263.815522) (xy 350.534192 -263.82091) (xy 351.643948 -263.82091)
			(xy 351.648019 -263.765288) (xy 351.660145 -263.710851) (xy 351.680068 -263.65876) (xy 351.707364 -263.610125)
			(xy 351.74145 -263.565982) (xy 351.781599 -263.527273) (xy 351.826957 -263.494822) (xy 351.876557 -263.469321)
			(xy 351.929341 -263.451314) (xy 351.984184 -263.441184) (xy 352.039918 -263.439147) (xy 352.095355 -263.445247)
			(xy 352.149312 -263.459353) (xy 352.200641 -263.481165) (xy 352.248247 -263.510219) (xy 352.291115 -263.545894)
			(xy 352.328332 -263.587431) (xy 352.359105 -263.633944) (xy 352.382777 -263.684441) (xy 352.398845 -263.737848)
			(xy 352.406965 -263.793024) (xy 352.407474 -263.82091) (xy 352.406965 -263.848796) (xy 352.398845 -263.903972)
			(xy 352.382777 -263.957379) (xy 352.359105 -264.007876) (xy 352.328332 -264.054389) (xy 352.291115 -264.095926)
			(xy 352.281574 -264.103866) (xy 355.18039 -264.103866) (xy 355.184461 -264.048244) (xy 355.196587 -263.993807)
			(xy 355.21651 -263.941716) (xy 355.243806 -263.893081) (xy 355.277892 -263.848938) (xy 355.318041 -263.810229)
			(xy 355.363399 -263.777778) (xy 355.412999 -263.752277) (xy 355.465783 -263.73427) (xy 355.520626 -263.72414)
			(xy 355.57636 -263.722103) (xy 355.631797 -263.728203) (xy 355.685754 -263.742309) (xy 355.737083 -263.764121)
			(xy 355.784689 -263.793175) (xy 355.827557 -263.82885) (xy 355.864774 -263.870387) (xy 355.895547 -263.9169)
			(xy 355.919219 -263.967397) (xy 355.935287 -264.020804) (xy 355.943407 -264.07598) (xy 355.943916 -264.103866)
			(xy 355.943407 -264.131752) (xy 355.935287 -264.186928) (xy 355.919219 -264.240335) (xy 355.895547 -264.290832)
			(xy 355.864774 -264.337345) (xy 355.837512 -264.367772) (xy 386.190488 -264.367772) (xy 386.194559 -264.31215)
			(xy 386.206685 -264.257713) (xy 386.226608 -264.205622) (xy 386.253904 -264.156987) (xy 386.28799 -264.112844)
			(xy 386.328139 -264.074135) (xy 386.373497 -264.041684) (xy 386.423097 -264.016183) (xy 386.475881 -263.998176)
			(xy 386.530724 -263.988046) (xy 386.586458 -263.986009) (xy 386.641895 -263.992109) (xy 386.695852 -264.006215)
			(xy 386.747181 -264.028027) (xy 386.794787 -264.057081) (xy 386.837655 -264.092756) (xy 386.874872 -264.134293)
			(xy 386.905645 -264.180806) (xy 386.929317 -264.231303) (xy 386.945385 -264.28471) (xy 386.953505 -264.339886)
			(xy 386.954014 -264.367772) (xy 386.953505 -264.395658) (xy 386.945385 -264.450834) (xy 386.929317 -264.504241)
			(xy 386.905645 -264.554738) (xy 386.874872 -264.601251) (xy 386.853299 -264.625328) (xy 388.763 -264.625328)
			(xy 388.767071 -264.569706) (xy 388.779197 -264.515269) (xy 388.79912 -264.463178) (xy 388.826416 -264.414543)
			(xy 388.860502 -264.3704) (xy 388.900651 -264.331691) (xy 388.946009 -264.29924) (xy 388.995609 -264.273739)
			(xy 389.048393 -264.255732) (xy 389.103236 -264.245602) (xy 389.15897 -264.243565) (xy 389.214407 -264.249665)
			(xy 389.268364 -264.263771) (xy 389.319693 -264.285583) (xy 389.367299 -264.314637) (xy 389.410167 -264.350312)
			(xy 389.447384 -264.391849) (xy 389.478157 -264.438362) (xy 389.501829 -264.488859) (xy 389.517897 -264.542266)
			(xy 389.526017 -264.597442) (xy 389.526526 -264.625328) (xy 389.526017 -264.653214) (xy 389.517897 -264.70839)
			(xy 389.501829 -264.761797) (xy 389.478157 -264.812294) (xy 389.447384 -264.858807) (xy 389.410167 -264.900344)
			(xy 389.367299 -264.936019) (xy 389.319693 -264.965073) (xy 389.268364 -264.986885) (xy 389.214407 -265.000991)
			(xy 389.15897 -265.007091) (xy 389.103236 -265.005054) (xy 389.048393 -264.994924) (xy 388.995609 -264.976917)
			(xy 388.946009 -264.951416) (xy 388.900651 -264.918965) (xy 388.860502 -264.880256) (xy 388.826416 -264.836113)
			(xy 388.79912 -264.787478) (xy 388.779197 -264.735387) (xy 388.767071 -264.68095) (xy 388.763 -264.625328)
			(xy 386.853299 -264.625328) (xy 386.837655 -264.642788) (xy 386.794787 -264.678463) (xy 386.747181 -264.707517)
			(xy 386.695852 -264.729329) (xy 386.641895 -264.743435) (xy 386.586458 -264.749535) (xy 386.530724 -264.747498)
			(xy 386.475881 -264.737368) (xy 386.423097 -264.719361) (xy 386.373497 -264.69386) (xy 386.328139 -264.661409)
			(xy 386.28799 -264.6227) (xy 386.253904 -264.578557) (xy 386.226608 -264.529922) (xy 386.206685 -264.477831)
			(xy 386.194559 -264.423394) (xy 386.190488 -264.367772) (xy 355.837512 -264.367772) (xy 355.827557 -264.378882)
			(xy 355.784689 -264.414557) (xy 355.737083 -264.443611) (xy 355.685754 -264.465423) (xy 355.631797 -264.479529)
			(xy 355.57636 -264.485629) (xy 355.520626 -264.483592) (xy 355.465783 -264.473462) (xy 355.412999 -264.455455)
			(xy 355.363399 -264.429954) (xy 355.318041 -264.397503) (xy 355.277892 -264.358794) (xy 355.243806 -264.314651)
			(xy 355.21651 -264.266016) (xy 355.196587 -264.213925) (xy 355.184461 -264.159488) (xy 355.18039 -264.103866)
			(xy 352.281574 -264.103866) (xy 352.248247 -264.131601) (xy 352.200641 -264.160655) (xy 352.149312 -264.182467)
			(xy 352.095355 -264.196573) (xy 352.039918 -264.202673) (xy 351.984184 -264.200636) (xy 351.929341 -264.190506)
			(xy 351.876557 -264.172499) (xy 351.826957 -264.146998) (xy 351.781599 -264.114547) (xy 351.74145 -264.075838)
			(xy 351.707364 -264.031695) (xy 351.680068 -263.98306) (xy 351.660145 -263.930969) (xy 351.648019 -263.876532)
			(xy 351.643948 -263.82091) (xy 350.534192 -263.82091) (xy 350.526865 -263.870698) (xy 350.510797 -263.924105)
			(xy 350.487125 -263.974602) (xy 350.456352 -264.021115) (xy 350.419135 -264.062652) (xy 350.376267 -264.098327)
			(xy 350.328661 -264.127381) (xy 350.277332 -264.149193) (xy 350.223375 -264.163299) (xy 350.167938 -264.169399)
			(xy 350.112204 -264.167362) (xy 350.057361 -264.157232) (xy 350.004577 -264.139225) (xy 349.954977 -264.113724)
			(xy 349.909619 -264.081273) (xy 349.86947 -264.042564) (xy 349.835384 -263.998421) (xy 349.808088 -263.949786)
			(xy 349.788165 -263.897695) (xy 349.776039 -263.843258) (xy 349.771968 -263.787636) (xy 347.200951 -263.787636)
			(xy 347.205985 -263.789775) (xy 347.253591 -263.818829) (xy 347.296459 -263.854504) (xy 347.333676 -263.896041)
			(xy 347.364449 -263.942554) (xy 347.388121 -263.993051) (xy 347.404189 -264.046458) (xy 347.412309 -264.101634)
			(xy 347.412818 -264.12952) (xy 347.412309 -264.157406) (xy 347.404189 -264.212582) (xy 347.388121 -264.265989)
			(xy 347.364449 -264.316486) (xy 347.333676 -264.362999) (xy 347.296459 -264.404536) (xy 347.253591 -264.440211)
			(xy 347.205985 -264.469265) (xy 347.154656 -264.491077) (xy 347.100699 -264.505183) (xy 347.045262 -264.511283)
			(xy 346.989528 -264.509246) (xy 346.934685 -264.499116) (xy 346.881901 -264.481109) (xy 346.832301 -264.455608)
			(xy 346.786943 -264.423157) (xy 346.746794 -264.384448) (xy 346.712708 -264.340305) (xy 346.685412 -264.29167)
			(xy 346.665489 -264.239579) (xy 346.653363 -264.185142) (xy 346.649292 -264.12952) (xy 336.319516 -264.12952)
			(xy 336.341153 -264.175677) (xy 336.357221 -264.229084) (xy 336.365341 -264.28426) (xy 336.36585 -264.312146)
			(xy 336.365341 -264.340032) (xy 336.357221 -264.395208) (xy 336.341153 -264.448615) (xy 336.317481 -264.499112)
			(xy 336.286708 -264.545625) (xy 336.249491 -264.587162) (xy 336.206623 -264.622837) (xy 336.159017 -264.651891)
			(xy 336.107688 -264.673703) (xy 336.053731 -264.687809) (xy 335.998294 -264.693909) (xy 335.94256 -264.691872)
			(xy 335.887717 -264.681742) (xy 335.834933 -264.663735) (xy 335.785333 -264.638234) (xy 335.739975 -264.605783)
			(xy 335.699826 -264.567074) (xy 335.66574 -264.522931) (xy 335.638444 -264.474296) (xy 335.618521 -264.422205)
			(xy 335.606395 -264.367768) (xy 335.602324 -264.312146) (xy 335.4891 -264.312146) (xy 335.489851 -264.317587)
			(xy 335.490312 -264.343642) (xy 335.489826 -264.370893) (xy 335.48207 -264.424841) (xy 335.466715 -264.477136)
			(xy 335.444073 -264.526713) (xy 335.414607 -264.572563) (xy 335.378916 -264.613754) (xy 335.337725 -264.649445)
			(xy 335.291875 -264.678911) (xy 335.242298 -264.701553) (xy 335.190003 -264.716908) (xy 335.136055 -264.724664)
			(xy 335.081553 -264.724664) (xy 335.027605 -264.716908) (xy 334.97531 -264.701553) (xy 334.925733 -264.678911)
			(xy 334.879883 -264.649445) (xy 334.838692 -264.613754) (xy 334.803001 -264.572563) (xy 334.773535 -264.526713)
			(xy 334.750893 -264.477136) (xy 334.735538 -264.424841) (xy 334.727782 -264.370893) (xy 334.727296 -264.343642)
			(xy 334.35194 -264.343642) (xy 334.32537 -264.354933) (xy 334.271413 -264.369039) (xy 334.215976 -264.375139)
			(xy 334.160242 -264.373102) (xy 334.105399 -264.362972) (xy 334.052615 -264.344965) (xy 334.003015 -264.319464)
			(xy 333.957657 -264.287013) (xy 333.917508 -264.248304) (xy 333.883422 -264.204161) (xy 333.856126 -264.155526)
			(xy 333.836203 -264.103435) (xy 333.824077 -264.048998) (xy 333.820006 -263.993376) (xy 274.19905 -263.993376)
			(xy 274.180601 -263.998199) (xy 274.125164 -264.004299) (xy 274.06943 -264.002262) (xy 274.014587 -263.992132)
			(xy 273.961803 -263.974125) (xy 273.912203 -263.948624) (xy 273.866845 -263.916173) (xy 273.826696 -263.877464)
			(xy 273.79261 -263.833321) (xy 273.765314 -263.784686) (xy 273.745391 -263.732595) (xy 273.733265 -263.678158)
			(xy 273.729194 -263.622536) (xy 270.822238 -263.622536) (xy 270.795215 -263.652696) (xy 270.752347 -263.688371)
			(xy 270.704741 -263.717425) (xy 270.653412 -263.739237) (xy 270.599455 -263.753343) (xy 270.544018 -263.759443)
			(xy 270.488284 -263.757406) (xy 270.433441 -263.747276) (xy 270.380657 -263.729269) (xy 270.331057 -263.703768)
			(xy 270.285699 -263.671317) (xy 270.24555 -263.632608) (xy 270.211464 -263.588465) (xy 270.184168 -263.53983)
			(xy 270.164245 -263.487739) (xy 270.152119 -263.433302) (xy 270.148048 -263.37768) (xy 154.81173 -263.37768)
			(xy 154.811221 -263.405566) (xy 154.803101 -263.460742) (xy 154.787033 -263.514149) (xy 154.763361 -263.564646)
			(xy 154.732588 -263.611159) (xy 154.695371 -263.652696) (xy 154.652503 -263.688371) (xy 154.604897 -263.717425)
			(xy 154.553568 -263.739237) (xy 154.499611 -263.753343) (xy 154.444174 -263.759443) (xy 154.38844 -263.757406)
			(xy 154.333597 -263.747276) (xy 154.280813 -263.729269) (xy 154.231213 -263.703768) (xy 154.185855 -263.671317)
			(xy 154.145706 -263.632608) (xy 154.11162 -263.588465) (xy 154.084324 -263.53983) (xy 154.064401 -263.487739)
			(xy 154.052275 -263.433302) (xy 154.048204 -263.37768) (xy 123.679062 -263.37768) (xy 123.653148 -263.416849)
			(xy 123.615931 -263.458386) (xy 123.573063 -263.494061) (xy 123.525457 -263.523115) (xy 123.474128 -263.544927)
			(xy 123.420171 -263.559033) (xy 123.364734 -263.565133) (xy 123.309 -263.563096) (xy 123.254157 -263.552966)
			(xy 123.201373 -263.534959) (xy 123.151773 -263.509458) (xy 123.106415 -263.477007) (xy 123.066266 -263.438298)
			(xy 123.03218 -263.394155) (xy 123.004884 -263.34552) (xy 122.984961 -263.293429) (xy 122.972835 -263.238992)
			(xy 122.968764 -263.18337) (xy 117.128121 -263.18337) (xy 117.120611 -263.208333) (xy 117.096939 -263.25883)
			(xy 117.066166 -263.305343) (xy 117.028949 -263.34688) (xy 116.986081 -263.382555) (xy 116.938475 -263.411609)
			(xy 116.887146 -263.433421) (xy 116.833189 -263.447527) (xy 116.777752 -263.453627) (xy 116.722018 -263.45159)
			(xy 116.667175 -263.44146) (xy 116.614391 -263.423453) (xy 116.564791 -263.397952) (xy 116.519433 -263.365501)
			(xy 116.479284 -263.326792) (xy 116.445198 -263.282649) (xy 116.417902 -263.234014) (xy 116.397979 -263.181923)
			(xy 116.385853 -263.127486) (xy 116.381782 -263.071864) (xy 112.642667 -263.071864) (xy 112.614503 -263.079227)
			(xy 112.559066 -263.085327) (xy 112.503332 -263.08329) (xy 112.448489 -263.07316) (xy 112.395705 -263.055153)
			(xy 112.346105 -263.029652) (xy 112.300747 -262.997201) (xy 112.260598 -262.958492) (xy 112.226512 -262.914349)
			(xy 112.199216 -262.865714) (xy 112.179293 -262.813623) (xy 112.167167 -262.759186) (xy 112.163096 -262.703564)
			(xy 40.899334 -262.703564) (xy 40.899334 -264.12952) (xy 114.449096 -264.12952) (xy 114.453167 -264.073898)
			(xy 114.465293 -264.019461) (xy 114.485216 -263.96737) (xy 114.512512 -263.918735) (xy 114.546598 -263.874592)
			(xy 114.586747 -263.835883) (xy 114.632105 -263.803432) (xy 114.681705 -263.777931) (xy 114.734489 -263.759924)
			(xy 114.789332 -263.749794) (xy 114.845066 -263.747757) (xy 114.900503 -263.753857) (xy 114.95446 -263.767963)
			(xy 115.000755 -263.787636) (xy 117.571772 -263.787636) (xy 117.575843 -263.732014) (xy 117.587969 -263.677577)
			(xy 117.607892 -263.625486) (xy 117.635188 -263.576851) (xy 117.669274 -263.532708) (xy 117.709423 -263.493999)
			(xy 117.754781 -263.461548) (xy 117.804381 -263.436047) (xy 117.857165 -263.41804) (xy 117.912008 -263.40791)
			(xy 117.967742 -263.405873) (xy 118.023179 -263.411973) (xy 118.077136 -263.426079) (xy 118.128465 -263.447891)
			(xy 118.176071 -263.476945) (xy 118.218939 -263.51262) (xy 118.256156 -263.554157) (xy 118.286929 -263.60067)
			(xy 118.310601 -263.651167) (xy 118.326669 -263.704574) (xy 118.334789 -263.75975) (xy 118.335298 -263.787636)
			(xy 118.334789 -263.815522) (xy 118.333996 -263.82091) (xy 119.443752 -263.82091) (xy 119.447823 -263.765288)
			(xy 119.459949 -263.710851) (xy 119.479872 -263.65876) (xy 119.507168 -263.610125) (xy 119.541254 -263.565982)
			(xy 119.581403 -263.527273) (xy 119.626761 -263.494822) (xy 119.676361 -263.469321) (xy 119.729145 -263.451314)
			(xy 119.783988 -263.441184) (xy 119.839722 -263.439147) (xy 119.895159 -263.445247) (xy 119.949116 -263.459353)
			(xy 120.000445 -263.481165) (xy 120.048051 -263.510219) (xy 120.090919 -263.545894) (xy 120.128136 -263.587431)
			(xy 120.158909 -263.633944) (xy 120.182581 -263.684441) (xy 120.198649 -263.737848) (xy 120.206769 -263.793024)
			(xy 120.207278 -263.82091) (xy 120.206769 -263.848796) (xy 120.198649 -263.903972) (xy 120.182581 -263.957379)
			(xy 120.158909 -264.007876) (xy 120.128136 -264.054389) (xy 120.090919 -264.095926) (xy 120.050552 -264.12952)
			(xy 122.980194 -264.12952) (xy 122.984265 -264.073898) (xy 122.996391 -264.019461) (xy 123.016314 -263.96737)
			(xy 123.04361 -263.918735) (xy 123.077696 -263.874592) (xy 123.117845 -263.835883) (xy 123.163203 -263.803432)
			(xy 123.212803 -263.777931) (xy 123.265587 -263.759924) (xy 123.32043 -263.749794) (xy 123.376164 -263.747757)
			(xy 123.431601 -263.753857) (xy 123.485558 -263.767963) (xy 123.536887 -263.789775) (xy 123.584493 -263.818829)
			(xy 123.627361 -263.854504) (xy 123.664578 -263.896041) (xy 123.695351 -263.942554) (xy 123.719023 -263.993051)
			(xy 123.735091 -264.046458) (xy 123.743211 -264.101634) (xy 123.74372 -264.12952) (xy 123.743211 -264.157406)
			(xy 123.735091 -264.212582) (xy 123.723171 -264.252202) (xy 157.136336 -264.252202) (xy 157.140407 -264.19658)
			(xy 157.152533 -264.142143) (xy 157.172456 -264.090052) (xy 157.199752 -264.041417) (xy 157.233838 -263.997274)
			(xy 157.273987 -263.958565) (xy 157.319345 -263.926114) (xy 157.368945 -263.900613) (xy 157.421729 -263.882606)
			(xy 157.476572 -263.872476) (xy 157.532306 -263.870439) (xy 157.587743 -263.876539) (xy 157.6417 -263.890645)
			(xy 157.693029 -263.912457) (xy 157.740635 -263.941511) (xy 157.783503 -263.977186) (xy 157.82072 -264.018723)
			(xy 157.851493 -264.065236) (xy 157.875165 -264.115733) (xy 157.891233 -264.16914) (xy 157.899353 -264.224316)
			(xy 157.89983 -264.250424) (xy 268.14983 -264.250424) (xy 268.153901 -264.194802) (xy 268.166027 -264.140365)
			(xy 268.18595 -264.088274) (xy 268.213246 -264.039639) (xy 268.247332 -263.995496) (xy 268.287481 -263.956787)
			(xy 268.332839 -263.924336) (xy 268.382439 -263.898835) (xy 268.435223 -263.880828) (xy 268.490066 -263.870698)
			(xy 268.5458 -263.868661) (xy 268.601237 -263.874761) (xy 268.655194 -263.888867) (xy 268.706523 -263.910679)
			(xy 268.754129 -263.939733) (xy 268.796997 -263.975408) (xy 268.834214 -264.016945) (xy 268.864987 -264.063458)
			(xy 268.888659 -264.113955) (xy 268.904727 -264.167362) (xy 268.912847 -264.222538) (xy 268.913356 -264.250424)
			(xy 268.912847 -264.27831) (xy 268.909064 -264.304018) (xy 270.618964 -264.304018) (xy 270.623035 -264.248396)
			(xy 270.635161 -264.193959) (xy 270.655084 -264.141868) (xy 270.68238 -264.093233) (xy 270.716466 -264.04909)
			(xy 270.756615 -264.010381) (xy 270.801973 -263.97793) (xy 270.851573 -263.952429) (xy 270.904357 -263.934422)
			(xy 270.9592 -263.924292) (xy 271.014934 -263.922255) (xy 271.070371 -263.928355) (xy 271.124328 -263.942461)
			(xy 271.175657 -263.964273) (xy 271.223263 -263.993327) (xy 271.266131 -264.029002) (xy 271.303348 -264.070539)
			(xy 271.334121 -264.117052) (xy 271.357793 -264.167549) (xy 271.373861 -264.220956) (xy 271.381981 -264.276132)
			(xy 271.38249 -264.304018) (xy 271.381981 -264.331904) (xy 271.373861 -264.38708) (xy 271.357793 -264.440487)
			(xy 271.334121 -264.490984) (xy 271.329262 -264.498328) (xy 273.06854 -264.498328) (xy 273.072611 -264.442706)
			(xy 273.084737 -264.388269) (xy 273.10466 -264.336178) (xy 273.131956 -264.287543) (xy 273.166042 -264.2434)
			(xy 273.206191 -264.204691) (xy 273.251549 -264.17224) (xy 273.301149 -264.146739) (xy 273.353933 -264.128732)
			(xy 273.408776 -264.118602) (xy 273.46451 -264.116565) (xy 273.519947 -264.122665) (xy 273.573904 -264.136771)
			(xy 273.625233 -264.158583) (xy 273.672839 -264.187637) (xy 273.715707 -264.223312) (xy 273.752924 -264.264849)
			(xy 273.783697 -264.311362) (xy 273.807369 -264.361859) (xy 273.823437 -264.415266) (xy 273.831557 -264.470442)
			(xy 273.832066 -264.498328) (xy 273.831557 -264.526214) (xy 273.823437 -264.58139) (xy 273.807369 -264.634797)
			(xy 273.783697 -264.685294) (xy 273.752924 -264.731807) (xy 273.715707 -264.773344) (xy 273.672839 -264.809019)
			(xy 273.625233 -264.838073) (xy 273.573904 -264.859885) (xy 273.519947 -264.873991) (xy 273.487603 -264.87755)
			(xy 333.781906 -264.87755) (xy 333.785977 -264.821928) (xy 333.798103 -264.767491) (xy 333.818026 -264.7154)
			(xy 333.845322 -264.666765) (xy 333.879408 -264.622622) (xy 333.919557 -264.583913) (xy 333.964915 -264.551462)
			(xy 334.014515 -264.525961) (xy 334.067299 -264.507954) (xy 334.122142 -264.497824) (xy 334.177876 -264.495787)
			(xy 334.233313 -264.501887) (xy 334.28727 -264.515993) (xy 334.338599 -264.537805) (xy 334.386205 -264.566859)
			(xy 334.429073 -264.602534) (xy 334.46629 -264.644071) (xy 334.497063 -264.690584) (xy 334.520735 -264.741081)
			(xy 334.536803 -264.794488) (xy 334.544923 -264.849664) (xy 334.545432 -264.87755) (xy 334.544923 -264.905436)
			(xy 334.537252 -264.95756) (xy 346.13418 -264.95756) (xy 346.138251 -264.901938) (xy 346.150377 -264.847501)
			(xy 346.1703 -264.79541) (xy 346.197596 -264.746775) (xy 346.231682 -264.702632) (xy 346.271831 -264.663923)
			(xy 346.317189 -264.631472) (xy 346.366789 -264.605971) (xy 346.419573 -264.587964) (xy 346.474416 -264.577834)
			(xy 346.53015 -264.575797) (xy 346.585587 -264.581897) (xy 346.639544 -264.596003) (xy 346.690873 -264.617815)
			(xy 346.738479 -264.646869) (xy 346.781347 -264.682544) (xy 346.818564 -264.724081) (xy 346.849337 -264.770594)
			(xy 346.873009 -264.821091) (xy 346.889077 -264.874498) (xy 346.897197 -264.929674) (xy 346.897312 -264.93597)
			(xy 352.61753 -264.93597) (xy 352.621601 -264.880348) (xy 352.633727 -264.825911) (xy 352.65365 -264.77382)
			(xy 352.680946 -264.725185) (xy 352.715032 -264.681042) (xy 352.755181 -264.642333) (xy 352.800539 -264.609882)
			(xy 352.850139 -264.584381) (xy 352.902923 -264.566374) (xy 352.957766 -264.556244) (xy 353.0135 -264.554207)
			(xy 353.068937 -264.560307) (xy 353.122894 -264.574413) (xy 353.174223 -264.596225) (xy 353.221829 -264.625279)
			(xy 353.264697 -264.660954) (xy 353.301914 -264.702491) (xy 353.332687 -264.749004) (xy 353.356359 -264.799501)
			(xy 353.372427 -264.852908) (xy 353.380547 -264.908084) (xy 353.381056 -264.93597) (xy 353.380547 -264.963856)
			(xy 353.372427 -265.019032) (xy 353.356359 -265.072439) (xy 353.332687 -265.122936) (xy 353.301914 -265.169449)
			(xy 353.264697 -265.210986) (xy 353.221829 -265.246661) (xy 353.174223 -265.275715) (xy 353.122894 -265.297527)
			(xy 353.068937 -265.311633) (xy 353.0135 -265.317733) (xy 352.957766 -265.315696) (xy 352.902923 -265.305566)
			(xy 352.850139 -265.287559) (xy 352.800539 -265.262058) (xy 352.755181 -265.229607) (xy 352.715032 -265.190898)
			(xy 352.680946 -265.146755) (xy 352.65365 -265.09812) (xy 352.633727 -265.046029) (xy 352.621601 -264.991592)
			(xy 352.61753 -264.93597) (xy 346.897312 -264.93597) (xy 346.897706 -264.95756) (xy 346.897197 -264.985446)
			(xy 346.889077 -265.040622) (xy 346.873009 -265.094029) (xy 346.849337 -265.144526) (xy 346.818564 -265.191039)
			(xy 346.781347 -265.232576) (xy 346.738479 -265.268251) (xy 346.690873 -265.297305) (xy 346.639544 -265.319117)
			(xy 346.585587 -265.333223) (xy 346.53015 -265.339323) (xy 346.474416 -265.337286) (xy 346.419573 -265.327156)
			(xy 346.366789 -265.309149) (xy 346.317189 -265.283648) (xy 346.271831 -265.251197) (xy 346.231682 -265.212488)
			(xy 346.197596 -265.168345) (xy 346.1703 -265.11971) (xy 346.150377 -265.067619) (xy 346.138251 -265.013182)
			(xy 346.13418 -264.95756) (xy 334.537252 -264.95756) (xy 334.536803 -264.960612) (xy 334.520735 -265.014019)
			(xy 334.497063 -265.064516) (xy 334.46629 -265.111029) (xy 334.429073 -265.152566) (xy 334.386205 -265.188241)
			(xy 334.338599 -265.217295) (xy 334.28727 -265.239107) (xy 334.233313 -265.253213) (xy 334.177876 -265.259313)
			(xy 334.122142 -265.257276) (xy 334.067299 -265.247146) (xy 334.014515 -265.229139) (xy 333.964915 -265.203638)
			(xy 333.919557 -265.171187) (xy 333.879408 -265.132478) (xy 333.845322 -265.088335) (xy 333.818026 -265.0397)
			(xy 333.798103 -264.987609) (xy 333.785977 -264.933172) (xy 333.781906 -264.87755) (xy 273.487603 -264.87755)
			(xy 273.46451 -264.880091) (xy 273.408776 -264.878054) (xy 273.353933 -264.867924) (xy 273.301149 -264.849917)
			(xy 273.251549 -264.824416) (xy 273.206191 -264.791965) (xy 273.166042 -264.753256) (xy 273.131956 -264.709113)
			(xy 273.10466 -264.660478) (xy 273.084737 -264.608387) (xy 273.072611 -264.55395) (xy 273.06854 -264.498328)
			(xy 271.329262 -264.498328) (xy 271.303348 -264.537497) (xy 271.266131 -264.579034) (xy 271.223263 -264.614709)
			(xy 271.175657 -264.643763) (xy 271.124328 -264.665575) (xy 271.070371 -264.679681) (xy 271.014934 -264.685781)
			(xy 270.9592 -264.683744) (xy 270.904357 -264.673614) (xy 270.851573 -264.655607) (xy 270.801973 -264.630106)
			(xy 270.756615 -264.597655) (xy 270.716466 -264.558946) (xy 270.68238 -264.514803) (xy 270.655084 -264.466168)
			(xy 270.635161 -264.414077) (xy 270.623035 -264.35964) (xy 270.618964 -264.304018) (xy 268.909064 -264.304018)
			(xy 268.904727 -264.333486) (xy 268.888659 -264.386893) (xy 268.864987 -264.43739) (xy 268.834214 -264.483903)
			(xy 268.796997 -264.52544) (xy 268.754129 -264.561115) (xy 268.706523 -264.590169) (xy 268.655194 -264.611981)
			(xy 268.601237 -264.626087) (xy 268.5458 -264.632187) (xy 268.490066 -264.63015) (xy 268.435223 -264.62002)
			(xy 268.382439 -264.602013) (xy 268.332839 -264.576512) (xy 268.287481 -264.544061) (xy 268.247332 -264.505352)
			(xy 268.213246 -264.461209) (xy 268.18595 -264.412574) (xy 268.166027 -264.360483) (xy 268.153901 -264.306046)
			(xy 268.14983 -264.250424) (xy 157.89983 -264.250424) (xy 157.899862 -264.252202) (xy 157.899353 -264.280088)
			(xy 157.891233 -264.335264) (xy 157.875165 -264.388671) (xy 157.851493 -264.439168) (xy 157.82072 -264.485681)
			(xy 157.783503 -264.527218) (xy 157.740635 -264.562893) (xy 157.693029 -264.591947) (xy 157.6417 -264.613759)
			(xy 157.587743 -264.627865) (xy 157.532306 -264.633965) (xy 157.476572 -264.631928) (xy 157.421729 -264.621798)
			(xy 157.368945 -264.603791) (xy 157.319345 -264.57829) (xy 157.273987 -264.545839) (xy 157.233838 -264.50713)
			(xy 157.199752 -264.462987) (xy 157.172456 -264.414352) (xy 157.152533 -264.362261) (xy 157.140407 -264.307824)
			(xy 157.136336 -264.252202) (xy 123.723171 -264.252202) (xy 123.719023 -264.265989) (xy 123.695351 -264.316486)
			(xy 123.664578 -264.362999) (xy 123.627361 -264.404536) (xy 123.584493 -264.440211) (xy 123.536887 -264.469265)
			(xy 123.485558 -264.491077) (xy 123.431601 -264.505183) (xy 123.376164 -264.511283) (xy 123.32043 -264.509246)
			(xy 123.265587 -264.499116) (xy 123.212803 -264.481109) (xy 123.163203 -264.455608) (xy 123.117845 -264.423157)
			(xy 123.077696 -264.384448) (xy 123.04361 -264.340305) (xy 123.016314 -264.29167) (xy 122.996391 -264.239579)
			(xy 122.984265 -264.185142) (xy 122.980194 -264.12952) (xy 120.050552 -264.12952) (xy 120.048051 -264.131601)
			(xy 120.000445 -264.160655) (xy 119.949116 -264.182467) (xy 119.895159 -264.196573) (xy 119.839722 -264.202673)
			(xy 119.783988 -264.200636) (xy 119.729145 -264.190506) (xy 119.676361 -264.172499) (xy 119.626761 -264.146998)
			(xy 119.581403 -264.114547) (xy 119.541254 -264.075838) (xy 119.507168 -264.031695) (xy 119.479872 -263.98306)
			(xy 119.459949 -263.930969) (xy 119.447823 -263.876532) (xy 119.443752 -263.82091) (xy 118.333996 -263.82091)
			(xy 118.326669 -263.870698) (xy 118.310601 -263.924105) (xy 118.286929 -263.974602) (xy 118.256156 -264.021115)
			(xy 118.218939 -264.062652) (xy 118.176071 -264.098327) (xy 118.128465 -264.127381) (xy 118.077136 -264.149193)
			(xy 118.023179 -264.163299) (xy 117.967742 -264.169399) (xy 117.912008 -264.167362) (xy 117.857165 -264.157232)
			(xy 117.804381 -264.139225) (xy 117.754781 -264.113724) (xy 117.709423 -264.081273) (xy 117.669274 -264.042564)
			(xy 117.635188 -263.998421) (xy 117.607892 -263.949786) (xy 117.587969 -263.897695) (xy 117.575843 -263.843258)
			(xy 117.571772 -263.787636) (xy 115.000755 -263.787636) (xy 115.005789 -263.789775) (xy 115.053395 -263.818829)
			(xy 115.096263 -263.854504) (xy 115.13348 -263.896041) (xy 115.164253 -263.942554) (xy 115.187925 -263.993051)
			(xy 115.203993 -264.046458) (xy 115.212113 -264.101634) (xy 115.212622 -264.12952) (xy 115.212113 -264.157406)
			(xy 115.203993 -264.212582) (xy 115.187925 -264.265989) (xy 115.164253 -264.316486) (xy 115.13348 -264.362999)
			(xy 115.096263 -264.404536) (xy 115.053395 -264.440211) (xy 115.005789 -264.469265) (xy 114.95446 -264.491077)
			(xy 114.900503 -264.505183) (xy 114.845066 -264.511283) (xy 114.789332 -264.509246) (xy 114.734489 -264.499116)
			(xy 114.681705 -264.481109) (xy 114.632105 -264.455608) (xy 114.586747 -264.423157) (xy 114.546598 -264.384448)
			(xy 114.512512 -264.340305) (xy 114.485216 -264.29167) (xy 114.465293 -264.239579) (xy 114.453167 -264.185142)
			(xy 114.449096 -264.12952) (xy 40.899334 -264.12952) (xy 40.899334 -264.532872) (xy 41.281094 -264.532872)
			(xy 41.285165 -264.47725) (xy 41.297291 -264.422813) (xy 41.317214 -264.370722) (xy 41.34451 -264.322087)
			(xy 41.378596 -264.277944) (xy 41.418745 -264.239235) (xy 41.464103 -264.206784) (xy 41.513703 -264.181283)
			(xy 41.566487 -264.163276) (xy 41.62133 -264.153146) (xy 41.677064 -264.151109) (xy 41.732501 -264.157209)
			(xy 41.786458 -264.171315) (xy 41.837787 -264.193127) (xy 41.885393 -264.222181) (xy 41.928261 -264.257856)
			(xy 41.965478 -264.299393) (xy 41.996251 -264.345906) (xy 42.019923 -264.396403) (xy 42.035991 -264.44981)
			(xy 42.044111 -264.504986) (xy 42.04462 -264.532872) (xy 42.044111 -264.560758) (xy 42.035991 -264.615934)
			(xy 42.019923 -264.669341) (xy 41.996251 -264.719838) (xy 41.965478 -264.766351) (xy 41.928261 -264.807888)
			(xy 41.885393 -264.843563) (xy 41.837787 -264.872617) (xy 41.786458 -264.894429) (xy 41.732501 -264.908535)
			(xy 41.677064 -264.914635) (xy 41.62133 -264.912598) (xy 41.566487 -264.902468) (xy 41.513703 -264.884461)
			(xy 41.464103 -264.85896) (xy 41.418745 -264.826509) (xy 41.378596 -264.7878) (xy 41.34451 -264.743657)
			(xy 41.317214 -264.695022) (xy 41.297291 -264.642931) (xy 41.285165 -264.588494) (xy 41.281094 -264.532872)
			(xy 40.899334 -264.532872) (xy 40.899334 -264.762742) (xy 40.92067 -264.790174) (xy 40.937688 -264.794492)
			(xy 40.964832 -264.801806) (xy 41.016769 -264.823316) (xy 41.064988 -264.852214) (xy 41.108444 -264.887875)
			(xy 41.146198 -264.929527) (xy 41.16493 -264.95756) (xy 113.933984 -264.95756) (xy 113.938055 -264.901938)
			(xy 113.950181 -264.847501) (xy 113.970104 -264.79541) (xy 113.9974 -264.746775) (xy 114.031486 -264.702632)
			(xy 114.071635 -264.663923) (xy 114.116993 -264.631472) (xy 114.166593 -264.605971) (xy 114.219377 -264.587964)
			(xy 114.27422 -264.577834) (xy 114.329954 -264.575797) (xy 114.385391 -264.581897) (xy 114.439348 -264.596003)
			(xy 114.490677 -264.617815) (xy 114.538283 -264.646869) (xy 114.581151 -264.682544) (xy 114.618368 -264.724081)
			(xy 114.649141 -264.770594) (xy 114.672813 -264.821091) (xy 114.688881 -264.874498) (xy 114.697001 -264.929674)
			(xy 114.697116 -264.93597) (xy 120.417334 -264.93597) (xy 120.421405 -264.880348) (xy 120.433531 -264.825911)
			(xy 120.453454 -264.77382) (xy 120.48075 -264.725185) (xy 120.514836 -264.681042) (xy 120.554985 -264.642333)
			(xy 120.600343 -264.609882) (xy 120.649943 -264.584381) (xy 120.702727 -264.566374) (xy 120.75757 -264.556244)
			(xy 120.813304 -264.554207) (xy 120.868741 -264.560307) (xy 120.922698 -264.574413) (xy 120.974027 -264.596225)
			(xy 121.021633 -264.625279) (xy 121.043667 -264.643616) (xy 153.652218 -264.643616) (xy 153.656289 -264.587994)
			(xy 153.668415 -264.533557) (xy 153.688338 -264.481466) (xy 153.715634 -264.432831) (xy 153.74972 -264.388688)
			(xy 153.789869 -264.349979) (xy 153.835227 -264.317528) (xy 153.884827 -264.292027) (xy 153.937611 -264.27402)
			(xy 153.992454 -264.26389) (xy 154.048188 -264.261853) (xy 154.103625 -264.267953) (xy 154.157582 -264.282059)
			(xy 154.208911 -264.303871) (xy 154.256517 -264.332925) (xy 154.299385 -264.3686) (xy 154.336602 -264.410137)
			(xy 154.367375 -264.45665) (xy 154.391047 -264.507147) (xy 154.407115 -264.560554) (xy 154.415235 -264.61573)
			(xy 154.415744 -264.643616) (xy 154.415235 -264.671502) (xy 154.407115 -264.726678) (xy 154.391047 -264.780085)
			(xy 154.367375 -264.830582) (xy 154.336602 -264.877095) (xy 154.299385 -264.918632) (xy 154.256517 -264.954307)
			(xy 154.208911 -264.983361) (xy 154.157582 -265.005173) (xy 154.103625 -265.019279) (xy 154.048188 -265.025379)
			(xy 153.992454 -265.023342) (xy 153.937611 -265.013212) (xy 153.884827 -264.995205) (xy 153.835227 -264.969704)
			(xy 153.789869 -264.937253) (xy 153.74972 -264.898544) (xy 153.715634 -264.854401) (xy 153.688338 -264.805766)
			(xy 153.668415 -264.753675) (xy 153.656289 -264.699238) (xy 153.652218 -264.643616) (xy 121.043667 -264.643616)
			(xy 121.064501 -264.660954) (xy 121.101718 -264.702491) (xy 121.132491 -264.749004) (xy 121.156163 -264.799501)
			(xy 121.172231 -264.852908) (xy 121.180351 -264.908084) (xy 121.18086 -264.93597) (xy 121.180351 -264.963856)
			(xy 121.172231 -265.019032) (xy 121.156163 -265.072439) (xy 121.132491 -265.122936) (xy 121.104946 -265.16457)
			(xy 156.563058 -265.16457) (xy 156.567129 -265.108948) (xy 156.579255 -265.054511) (xy 156.599178 -265.00242)
			(xy 156.626474 -264.953785) (xy 156.66056 -264.909642) (xy 156.700709 -264.870933) (xy 156.746067 -264.838482)
			(xy 156.795667 -264.812981) (xy 156.848451 -264.794974) (xy 156.903294 -264.784844) (xy 156.959028 -264.782807)
			(xy 157.014465 -264.788907) (xy 157.068422 -264.803013) (xy 157.119751 -264.824825) (xy 157.167357 -264.853879)
			(xy 157.210225 -264.889554) (xy 157.247442 -264.931091) (xy 157.278215 -264.977604) (xy 157.301887 -265.028101)
			(xy 157.317955 -265.081508) (xy 157.326075 -265.136684) (xy 157.326584 -265.16457) (xy 157.326075 -265.192456)
			(xy 157.317955 -265.247632) (xy 157.301887 -265.301039) (xy 157.278215 -265.351536) (xy 157.247442 -265.398049)
			(xy 157.210225 -265.439586) (xy 157.167357 -265.475261) (xy 157.131645 -265.497056) (xy 273.915122 -265.497056)
			(xy 273.919193 -265.441434) (xy 273.931319 -265.386997) (xy 273.951242 -265.334906) (xy 273.978538 -265.286271)
			(xy 274.012624 -265.242128) (xy 274.052773 -265.203419) (xy 274.098131 -265.170968) (xy 274.147731 -265.145467)
			(xy 274.200515 -265.12746) (xy 274.255358 -265.11733) (xy 274.311092 -265.115293) (xy 274.366529 -265.121393)
			(xy 274.420486 -265.135499) (xy 274.471815 -265.157311) (xy 274.519421 -265.186365) (xy 274.562289 -265.22204)
			(xy 274.599506 -265.263577) (xy 274.630279 -265.31009) (xy 274.653951 -265.360587) (xy 274.670019 -265.413994)
			(xy 274.678139 -265.46917) (xy 274.678648 -265.497056) (xy 274.678139 -265.524942) (xy 274.670019 -265.580118)
			(xy 274.653951 -265.633525) (xy 274.630279 -265.684022) (xy 274.599506 -265.730535) (xy 274.562289 -265.772072)
			(xy 274.519421 -265.807747) (xy 274.471815 -265.836801) (xy 274.420486 -265.858613) (xy 274.366529 -265.872719)
			(xy 274.311092 -265.878819) (xy 274.255358 -265.876782) (xy 274.200515 -265.866652) (xy 274.147731 -265.848645)
			(xy 274.098131 -265.823144) (xy 274.052773 -265.790693) (xy 274.012624 -265.751984) (xy 273.978538 -265.707841)
			(xy 273.951242 -265.659206) (xy 273.931319 -265.607115) (xy 273.919193 -265.552678) (xy 273.915122 -265.497056)
			(xy 157.131645 -265.497056) (xy 157.119751 -265.504315) (xy 157.068422 -265.526127) (xy 157.014465 -265.540233)
			(xy 156.959028 -265.546333) (xy 156.903294 -265.544296) (xy 156.848451 -265.534166) (xy 156.795667 -265.516159)
			(xy 156.746067 -265.490658) (xy 156.700709 -265.458207) (xy 156.66056 -265.419498) (xy 156.626474 -265.375355)
			(xy 156.599178 -265.32672) (xy 156.579255 -265.274629) (xy 156.567129 -265.220192) (xy 156.563058 -265.16457)
			(xy 121.104946 -265.16457) (xy 121.101718 -265.169449) (xy 121.064501 -265.210986) (xy 121.021633 -265.246661)
			(xy 120.974027 -265.275715) (xy 120.922698 -265.297527) (xy 120.868741 -265.311633) (xy 120.813304 -265.317733)
			(xy 120.75757 -265.315696) (xy 120.702727 -265.305566) (xy 120.649943 -265.287559) (xy 120.600343 -265.262058)
			(xy 120.554985 -265.229607) (xy 120.514836 -265.190898) (xy 120.48075 -265.146755) (xy 120.453454 -265.09812)
			(xy 120.433531 -265.046029) (xy 120.421405 -264.991592) (xy 120.417334 -264.93597) (xy 114.697116 -264.93597)
			(xy 114.69751 -264.95756) (xy 114.697001 -264.985446) (xy 114.688881 -265.040622) (xy 114.672813 -265.094029)
			(xy 114.649141 -265.144526) (xy 114.618368 -265.191039) (xy 114.581151 -265.232576) (xy 114.538283 -265.268251)
			(xy 114.490677 -265.297305) (xy 114.439348 -265.319117) (xy 114.385391 -265.333223) (xy 114.329954 -265.339323)
			(xy 114.27422 -265.337286) (xy 114.219377 -265.327156) (xy 114.166593 -265.309149) (xy 114.116993 -265.283648)
			(xy 114.071635 -265.251197) (xy 114.031486 -265.212488) (xy 113.9974 -265.168345) (xy 113.970104 -265.11971)
			(xy 113.950181 -265.067619) (xy 113.938055 -265.013182) (xy 113.933984 -264.95756) (xy 41.16493 -264.95756)
			(xy 41.177431 -264.976267) (xy 41.201467 -265.027084) (xy 41.217787 -265.080878) (xy 41.226037 -265.136485)
			(xy 41.226038 -265.1927) (xy 41.21779 -265.248307) (xy 41.201473 -265.302102) (xy 41.177438 -265.35292)
			(xy 41.146207 -265.399662) (xy 41.108455 -265.441315) (xy 41.065 -265.476977) (xy 41.016782 -265.505878)
			(xy 40.964846 -265.52739) (xy 40.937688 -265.534648) (xy 40.92067 -265.538966) (xy 40.899334 -265.566398)
			(xy 40.899334 -266.136374) (xy 40.915844 -266.16152) (xy 40.930068 -266.167616) (xy 40.955351 -266.179071)
			(xy 41.002588 -266.208217) (xy 41.045103 -266.2439) (xy 41.081998 -266.285367) (xy 41.112495 -266.331743)
			(xy 41.135949 -266.382048) (xy 41.151867 -266.435222) (xy 41.159911 -266.49014) (xy 41.159912 -266.545645)
			(xy 41.15187 -266.600564) (xy 41.135955 -266.653738) (xy 41.112502 -266.704045) (xy 41.082007 -266.750422)
			(xy 41.045113 -266.79189) (xy 41.002599 -266.827575) (xy 40.955364 -266.856722) (xy 40.930068 -266.868148)
			(xy 40.915844 -266.874244) (xy 40.899334 -266.89939) (xy 40.899334 -267.215366) (xy 40.917368 -267.241274)
			(xy 40.932354 -267.246862) (xy 40.959315 -267.25749) (xy 41.00993 -267.285711) (xy 41.055701 -267.321255)
			(xy 41.095576 -267.363307) (xy 41.128641 -267.410899) (xy 41.154135 -267.462941) (xy 41.171475 -267.518238)
			(xy 41.180261 -267.575519) (xy 41.180766 -267.604494) (xy 41.180255 -267.632762) (xy 41.171915 -267.688681)
			(xy 41.155418 -267.742757) (xy 41.131124 -267.793808) (xy 41.099565 -267.840717) (xy 41.061431 -267.882457)
			(xy 41.039796 -267.900658) (xy 41.030398 -267.908278) (xy 41.020492 -267.929868) (xy 41.024302 -268.035024)
			(xy 41.035478 -268.055598) (xy 41.045384 -268.06271) (xy 41.066537 -268.078065) (xy 41.104836 -268.113637)
			(xy 41.137915 -268.154109) (xy 41.165153 -268.198722) (xy 41.186039 -268.246638) (xy 41.200181 -268.296959)
			(xy 41.207313 -268.348741) (xy 41.20769 -268.374876) (xy 41.207207 -268.402011) (xy 41.199508 -268.455732)
			(xy 41.184274 -268.507821) (xy 41.161814 -268.557226) (xy 41.132581 -268.60295) (xy 41.097165 -268.644071)
			(xy 41.05628 -268.67976) (xy 41.010751 -268.709296) (xy 40.961496 -268.732083) (xy 40.935656 -268.740382)
			(xy 40.9194 -268.745208) (xy 40.899334 -268.772132) (xy 40.899334 -270.616753) (xy 41.069457 -270.616753)
			(xy 41.069457 -270.562247) (xy 41.077215 -270.508295) (xy 41.092571 -270.455996) (xy 41.115215 -270.406415)
			(xy 41.144684 -270.360562) (xy 41.180379 -270.319369) (xy 41.221573 -270.283675) (xy 41.267428 -270.254208)
			(xy 41.317009 -270.231566) (xy 41.369308 -270.216212) (xy 41.423261 -270.208456) (xy 41.450514 -270.207994)
			(xy 41.477463 -270.208482) (xy 41.530822 -270.216082) (xy 41.582581 -270.231115) (xy 41.631709 -270.253282)
			(xy 41.67723 -270.28214) (xy 41.718237 -270.317117) (xy 41.753914 -270.357517) (xy 41.783551 -270.402534)
			(xy 41.806559 -270.451274) (xy 41.82248 -270.502767) (xy 41.827196 -270.529304) (xy 41.83003 -270.54387)
			(xy 41.84297 -270.570561) (xy 41.863029 -270.592413) (xy 41.888517 -270.607585) (xy 41.917289 -270.6148)
			(xy 41.94692 -270.613449) (xy 41.974916 -270.603647) (xy 41.987216 -270.595344) (xy 42.01183 -270.57815)
			(xy 42.065325 -270.550893) (xy 42.122429 -270.532353) (xy 42.181732 -270.522987) (xy 42.211752 -270.522446)
			(xy 42.239004 -270.522998) (xy 42.292953 -270.530748) (xy 42.345251 -270.546098) (xy 42.394831 -270.568735)
			(xy 42.440685 -270.598199) (xy 42.481878 -270.633888) (xy 42.517573 -270.675077) (xy 42.547041 -270.720927)
			(xy 42.569685 -270.770504) (xy 42.585041 -270.8228) (xy 42.592799 -270.876748) (xy 42.592799 -270.89989)
			(xy 84.898745 -270.89989) (xy 84.902751 -270.704835) (xy 84.914761 -270.510109) (xy 84.934756 -270.31604)
			(xy 84.962701 -270.122956) (xy 84.99855 -269.931181) (xy 85.042242 -269.741041) (xy 85.093703 -269.552854)
			(xy 85.152847 -269.366939) (xy 85.219574 -269.183608) (xy 85.293771 -269.003172) (xy 85.375313 -268.825934)
			(xy 85.464064 -268.652193) (xy 85.559872 -268.482242) (xy 85.662577 -268.316368) (xy 85.772005 -268.15485)
			(xy 85.887972 -267.997961) (xy 86.010283 -267.845966) (xy 86.13873 -267.69912) (xy 86.273098 -267.557671)
			(xy 86.41316 -267.421858) (xy 86.558679 -267.291909) (xy 86.709411 -267.168045) (xy 86.865101 -267.050473)
			(xy 87.025487 -266.939393) (xy 87.190298 -266.83499) (xy 87.359256 -266.737442) (xy 87.532077 -266.646913)
			(xy 87.708469 -266.563555) (xy 87.888134 -266.487509) (xy 88.070769 -266.418904) (xy 88.256068 -266.357854)
			(xy 88.443716 -266.304464) (xy 88.633398 -266.258822) (xy 88.824795 -266.221006) (xy 89.017582 -266.19108)
			(xy 89.211435 -266.169094) (xy 89.406028 -266.155085) (xy 89.601031 -266.149077) (xy 89.796117 -266.15108)
			(xy 89.990956 -266.161091) (xy 90.18522 -266.179092) (xy 90.378581 -266.205054) (xy 90.570714 -266.238932)
			(xy 90.761293 -266.280669) (xy 90.949998 -266.330196) (xy 91.136511 -266.387428) (xy 91.320517 -266.452269)
			(xy 91.501705 -266.52461) (xy 91.679771 -266.604328) (xy 91.854414 -266.69129) (xy 92.02534 -266.785349)
			(xy 92.192259 -266.886345) (xy 92.354892 -266.99411) (xy 92.512963 -267.10846) (xy 92.666206 -267.229203)
			(xy 92.814363 -267.356137) (xy 92.957184 -267.489045) (xy 93.094428 -267.627705) (xy 93.225864 -267.771883)
			(xy 93.351269 -267.921336) (xy 93.470433 -268.07581) (xy 93.583154 -268.235047) (xy 93.689243 -268.398778)
			(xy 93.788521 -268.566725) (xy 93.880819 -268.738608) (xy 93.965984 -268.914134) (xy 94.04387 -269.093009)
			(xy 94.114347 -269.274931) (xy 94.177295 -269.459593) (xy 94.23261 -269.646683) (xy 94.280196 -269.835887)
			(xy 94.319975 -270.026884) (xy 94.351879 -270.219354) (xy 94.375854 -270.412972) (xy 94.39186 -270.60741)
			(xy 94.399869 -270.802342) (xy 94.40037 -270.89989) (xy 94.399869 -270.997438) (xy 94.39186 -271.19237)
			(xy 94.375854 -271.386808) (xy 94.351879 -271.580426) (xy 94.319975 -271.772896) (xy 94.280196 -271.963893)
			(xy 94.23261 -272.153097) (xy 94.177295 -272.340187) (xy 94.114347 -272.524849) (xy 94.04387 -272.706771)
			(xy 93.965984 -272.885646) (xy 93.880819 -273.061172) (xy 93.788521 -273.233055) (xy 93.689243 -273.401002)
			(xy 93.583154 -273.564733) (xy 93.470433 -273.72397) (xy 93.351269 -273.878444) (xy 93.225864 -274.027897)
			(xy 93.094428 -274.172075) (xy 92.957184 -274.310735) (xy 92.814363 -274.443643) (xy 92.666206 -274.570577)
			(xy 92.512963 -274.69132) (xy 92.354892 -274.80567) (xy 92.192259 -274.913435) (xy 92.02534 -275.014431)
			(xy 91.854414 -275.10849) (xy 91.679771 -275.195452) (xy 91.501705 -275.27517) (xy 91.320517 -275.347511)
			(xy 91.136511 -275.412352) (xy 90.949998 -275.469584) (xy 90.761293 -275.519111) (xy 90.570714 -275.560848)
			(xy 90.378581 -275.594726) (xy 90.18522 -275.620688) (xy 89.990956 -275.638689) (xy 89.796117 -275.6487)
			(xy 89.601031 -275.650703) (xy 89.406028 -275.644695) (xy 89.211435 -275.630686) (xy 89.017582 -275.6087)
			(xy 88.824795 -275.578774) (xy 88.633398 -275.540958) (xy 88.443716 -275.495316) (xy 88.256068 -275.441926)
			(xy 88.070769 -275.380876) (xy 87.888134 -275.312271) (xy 87.708469 -275.236225) (xy 87.532077 -275.152867)
			(xy 87.359256 -275.062338) (xy 87.190298 -274.96479) (xy 87.025487 -274.860387) (xy 86.865101 -274.749307)
			(xy 86.709411 -274.631735) (xy 86.558679 -274.507871) (xy 86.41316 -274.377922) (xy 86.273098 -274.242109)
			(xy 86.13873 -274.10066) (xy 86.010283 -273.953814) (xy 85.887972 -273.801819) (xy 85.772005 -273.64493)
			(xy 85.662577 -273.483412) (xy 85.559872 -273.317538) (xy 85.464064 -273.147587) (xy 85.375313 -272.973846)
			(xy 85.293771 -272.796608) (xy 85.219574 -272.616172) (xy 85.152847 -272.432841) (xy 85.093703 -272.246926)
			(xy 85.042242 -272.058739) (xy 84.99855 -271.868599) (xy 84.962701 -271.676824) (xy 84.934756 -271.48374)
			(xy 84.914761 -271.289671) (xy 84.902751 -271.094945) (xy 84.898745 -270.89989) (xy 42.592799 -270.89989)
			(xy 42.592799 -270.931252) (xy 42.585041 -270.9852) (xy 42.569685 -271.037496) (xy 42.547041 -271.087073)
			(xy 42.517573 -271.132923) (xy 42.481878 -271.174112) (xy 42.440685 -271.209801) (xy 42.394831 -271.239265)
			(xy 42.345251 -271.261902) (xy 42.292953 -271.277252) (xy 42.239004 -271.285002) (xy 42.211752 -271.285462)
			(xy 42.184803 -271.28495) (xy 42.131443 -271.277358) (xy 42.079683 -271.262331) (xy 42.030553 -271.24017)
			(xy 41.98503 -271.211314) (xy 41.944022 -271.176339) (xy 41.908345 -271.135941) (xy 41.878708 -271.090923)
			(xy 41.855702 -271.042183) (xy 41.839784 -270.990689) (xy 41.83507 -270.964152) (xy 41.832258 -270.949578)
			(xy 41.819324 -270.922875) (xy 41.799264 -270.901013) (xy 41.773768 -270.885836) (xy 41.744988 -270.878623)
			(xy 41.715348 -270.879983) (xy 41.687349 -270.8898) (xy 41.67505 -270.898112) (xy 41.650442 -270.915315)
			(xy 41.596946 -270.942571) (xy 41.53984 -270.96111) (xy 41.480534 -270.970472) (xy 41.450514 -270.97101)
			(xy 41.423261 -270.970544) (xy 41.369308 -270.962788) (xy 41.317009 -270.947434) (xy 41.267428 -270.924792)
			(xy 41.221573 -270.895325) (xy 41.180379 -270.859631) (xy 41.144684 -270.818438) (xy 41.115215 -270.772585)
			(xy 41.092571 -270.723004) (xy 41.077215 -270.670705) (xy 41.069457 -270.616753) (xy 40.899334 -270.616753)
			(xy 40.899334 -272.14957) (xy 44.143688 -272.14957) (xy 44.147648 -272.100516) (xy 44.159425 -272.052732)
			(xy 44.178716 -272.007456) (xy 44.205019 -271.96586) (xy 44.237654 -271.929023) (xy 44.275775 -271.897898)
			(xy 44.318396 -271.873291) (xy 44.364412 -271.855839) (xy 44.412631 -271.845995) (xy 44.461806 -271.844014)
			(xy 44.510661 -271.849946) (xy 44.557932 -271.863638) (xy 44.602394 -271.884736) (xy 44.642897 -271.912692)
			(xy 44.67839 -271.946784) (xy 44.707955 -271.986128) (xy 44.730826 -272.029705) (xy 44.74641 -272.076386)
			(xy 44.754305 -272.124963) (xy 44.7548 -272.14957) (xy 46.043862 -272.14957) (xy 46.047822 -272.100516)
			(xy 46.059599 -272.052732) (xy 46.07889 -272.007456) (xy 46.105193 -271.96586) (xy 46.137828 -271.929023)
			(xy 46.175949 -271.897898) (xy 46.21857 -271.873291) (xy 46.264586 -271.855839) (xy 46.312805 -271.845995)
			(xy 46.36198 -271.844014) (xy 46.410835 -271.849946) (xy 46.458106 -271.863638) (xy 46.502568 -271.884736)
			(xy 46.543071 -271.912692) (xy 46.578564 -271.946784) (xy 46.608129 -271.986128) (xy 46.631 -272.029705)
			(xy 46.646584 -272.076386) (xy 46.654479 -272.124963) (xy 46.654974 -272.14957) (xy 47.943782 -272.14957)
			(xy 47.947742 -272.100516) (xy 47.959519 -272.052732) (xy 47.97881 -272.007456) (xy 48.005113 -271.96586)
			(xy 48.037748 -271.929023) (xy 48.075869 -271.897898) (xy 48.11849 -271.873291) (xy 48.164506 -271.855839)
			(xy 48.212725 -271.845995) (xy 48.2619 -271.844014) (xy 48.310755 -271.849946) (xy 48.358026 -271.863638)
			(xy 48.402488 -271.884736) (xy 48.442991 -271.912692) (xy 48.478484 -271.946784) (xy 48.508049 -271.986128)
			(xy 48.53092 -272.029705) (xy 48.546504 -272.076386) (xy 48.554399 -272.124963) (xy 48.554894 -272.14957)
			(xy 49.843702 -272.14957) (xy 49.847662 -272.100516) (xy 49.859439 -272.052732) (xy 49.87873 -272.007456)
			(xy 49.905033 -271.96586) (xy 49.937668 -271.929023) (xy 49.975789 -271.897898) (xy 50.01841 -271.873291)
			(xy 50.064426 -271.855839) (xy 50.112645 -271.845995) (xy 50.16182 -271.844014) (xy 50.210675 -271.849946)
			(xy 50.257946 -271.863638) (xy 50.302408 -271.884736) (xy 50.342911 -271.912692) (xy 50.378404 -271.946784)
			(xy 50.407969 -271.986128) (xy 50.43084 -272.029705) (xy 50.446424 -272.076386) (xy 50.454319 -272.124963)
			(xy 50.454814 -272.14957) (xy 51.743876 -272.14957) (xy 51.747836 -272.100516) (xy 51.759613 -272.052732)
			(xy 51.778904 -272.007456) (xy 51.805207 -271.96586) (xy 51.837842 -271.929023) (xy 51.875963 -271.897898)
			(xy 51.918584 -271.873291) (xy 51.9646 -271.855839) (xy 52.012819 -271.845995) (xy 52.061994 -271.844014)
			(xy 52.110849 -271.849946) (xy 52.15812 -271.863638) (xy 52.202582 -271.884736) (xy 52.243085 -271.912692)
			(xy 52.278578 -271.946784) (xy 52.308143 -271.986128) (xy 52.331014 -272.029705) (xy 52.346598 -272.076386)
			(xy 52.354493 -272.124963) (xy 52.354988 -272.14957) (xy 53.643796 -272.14957) (xy 53.647756 -272.100516)
			(xy 53.659533 -272.052732) (xy 53.678824 -272.007456) (xy 53.705127 -271.96586) (xy 53.737762 -271.929023)
			(xy 53.775883 -271.897898) (xy 53.818504 -271.873291) (xy 53.86452 -271.855839) (xy 53.912739 -271.845995)
			(xy 53.961914 -271.844014) (xy 54.010769 -271.849946) (xy 54.05804 -271.863638) (xy 54.102502 -271.884736)
			(xy 54.143005 -271.912692) (xy 54.178498 -271.946784) (xy 54.208063 -271.986128) (xy 54.230934 -272.029705)
			(xy 54.246518 -272.076386) (xy 54.254413 -272.124963) (xy 54.254908 -272.14957) (xy 55.543716 -272.14957)
			(xy 55.547676 -272.100516) (xy 55.559453 -272.052732) (xy 55.578744 -272.007456) (xy 55.605047 -271.96586)
			(xy 55.637682 -271.929023) (xy 55.675803 -271.897898) (xy 55.718424 -271.873291) (xy 55.76444 -271.855839)
			(xy 55.812659 -271.845995) (xy 55.861834 -271.844014) (xy 55.910689 -271.849946) (xy 55.95796 -271.863638)
			(xy 56.002422 -271.884736) (xy 56.042925 -271.912692) (xy 56.078418 -271.946784) (xy 56.107983 -271.986128)
			(xy 56.130854 -272.029705) (xy 56.146438 -272.076386) (xy 56.154333 -272.124963) (xy 56.154828 -272.14957)
			(xy 57.44389 -272.14957) (xy 57.44785 -272.100516) (xy 57.459627 -272.052732) (xy 57.478918 -272.007456)
			(xy 57.505221 -271.96586) (xy 57.537856 -271.929023) (xy 57.575977 -271.897898) (xy 57.618598 -271.873291)
			(xy 57.664614 -271.855839) (xy 57.712833 -271.845995) (xy 57.762008 -271.844014) (xy 57.810863 -271.849946)
			(xy 57.858134 -271.863638) (xy 57.902596 -271.884736) (xy 57.943099 -271.912692) (xy 57.978592 -271.946784)
			(xy 58.008157 -271.986128) (xy 58.031028 -272.029705) (xy 58.046612 -272.076386) (xy 58.054507 -272.124963)
			(xy 58.054997 -272.149316) (xy 59.34381 -272.149316) (xy 59.34777 -272.100262) (xy 59.359547 -272.052478)
			(xy 59.378838 -272.007202) (xy 59.405141 -271.965606) (xy 59.437776 -271.928769) (xy 59.475897 -271.897644)
			(xy 59.518518 -271.873037) (xy 59.564534 -271.855585) (xy 59.612753 -271.845741) (xy 59.661928 -271.84376)
			(xy 59.710783 -271.849692) (xy 59.758054 -271.863384) (xy 59.802516 -271.884482) (xy 59.843019 -271.912438)
			(xy 59.878512 -271.94653) (xy 59.908077 -271.985874) (xy 59.930948 -272.029451) (xy 59.946532 -272.076132)
			(xy 59.954427 -272.124709) (xy 59.954922 -272.149316) (xy 59.954917 -272.14957) (xy 61.24373 -272.14957)
			(xy 61.24769 -272.100516) (xy 61.259467 -272.052732) (xy 61.278758 -272.007456) (xy 61.305061 -271.96586)
			(xy 61.337696 -271.929023) (xy 61.375817 -271.897898) (xy 61.418438 -271.873291) (xy 61.464454 -271.855839)
			(xy 61.512673 -271.845995) (xy 61.561848 -271.844014) (xy 61.610703 -271.849946) (xy 61.657974 -271.863638)
			(xy 61.702436 -271.884736) (xy 61.742939 -271.912692) (xy 61.778432 -271.946784) (xy 61.807997 -271.986128)
			(xy 61.830868 -272.029705) (xy 61.846452 -272.076386) (xy 61.854347 -272.124963) (xy 61.854842 -272.14957)
			(xy 63.143904 -272.14957) (xy 63.147864 -272.100516) (xy 63.159641 -272.052732) (xy 63.178932 -272.007456)
			(xy 63.205235 -271.96586) (xy 63.23787 -271.929023) (xy 63.275991 -271.897898) (xy 63.318612 -271.873291)
			(xy 63.364628 -271.855839) (xy 63.412847 -271.845995) (xy 63.462022 -271.844014) (xy 63.510877 -271.849946)
			(xy 63.558148 -271.863638) (xy 63.60261 -271.884736) (xy 63.643113 -271.912692) (xy 63.678606 -271.946784)
			(xy 63.708171 -271.986128) (xy 63.731042 -272.029705) (xy 63.746626 -272.076386) (xy 63.754521 -272.124963)
			(xy 63.755016 -272.14957) (xy 65.043824 -272.14957) (xy 65.047784 -272.100516) (xy 65.059561 -272.052732)
			(xy 65.078852 -272.007456) (xy 65.105155 -271.96586) (xy 65.13779 -271.929023) (xy 65.175911 -271.897898)
			(xy 65.218532 -271.873291) (xy 65.264548 -271.855839) (xy 65.312767 -271.845995) (xy 65.361942 -271.844014)
			(xy 65.410797 -271.849946) (xy 65.458068 -271.863638) (xy 65.50253 -271.884736) (xy 65.543033 -271.912692)
			(xy 65.578526 -271.946784) (xy 65.608091 -271.986128) (xy 65.630962 -272.029705) (xy 65.646546 -272.076386)
			(xy 65.654441 -272.124963) (xy 65.654936 -272.14957) (xy 66.943744 -272.14957) (xy 66.947704 -272.100516)
			(xy 66.959481 -272.052732) (xy 66.978772 -272.007456) (xy 67.005075 -271.96586) (xy 67.03771 -271.929023)
			(xy 67.075831 -271.897898) (xy 67.118452 -271.873291) (xy 67.164468 -271.855839) (xy 67.212687 -271.845995)
			(xy 67.261862 -271.844014) (xy 67.310717 -271.849946) (xy 67.357988 -271.863638) (xy 67.40245 -271.884736)
			(xy 67.442953 -271.912692) (xy 67.478446 -271.946784) (xy 67.508011 -271.986128) (xy 67.530882 -272.029705)
			(xy 67.546466 -272.076386) (xy 67.554361 -272.124963) (xy 67.554856 -272.14957) (xy 68.843918 -272.14957)
			(xy 68.847878 -272.100516) (xy 68.859655 -272.052732) (xy 68.878946 -272.007456) (xy 68.905249 -271.96586)
			(xy 68.937884 -271.929023) (xy 68.976005 -271.897898) (xy 69.018626 -271.873291) (xy 69.064642 -271.855839)
			(xy 69.112861 -271.845995) (xy 69.162036 -271.844014) (xy 69.210891 -271.849946) (xy 69.258162 -271.863638)
			(xy 69.302624 -271.884736) (xy 69.343127 -271.912692) (xy 69.37862 -271.946784) (xy 69.408185 -271.986128)
			(xy 69.431056 -272.029705) (xy 69.44664 -272.076386) (xy 69.454535 -272.124963) (xy 69.45503 -272.14957)
			(xy 70.743838 -272.14957) (xy 70.747798 -272.100516) (xy 70.759575 -272.052732) (xy 70.778866 -272.007456)
			(xy 70.805169 -271.96586) (xy 70.837804 -271.929023) (xy 70.875925 -271.897898) (xy 70.918546 -271.873291)
			(xy 70.964562 -271.855839) (xy 71.012781 -271.845995) (xy 71.061956 -271.844014) (xy 71.110811 -271.849946)
			(xy 71.158082 -271.863638) (xy 71.202544 -271.884736) (xy 71.243047 -271.912692) (xy 71.27854 -271.946784)
			(xy 71.308105 -271.986128) (xy 71.330976 -272.029705) (xy 71.34656 -272.076386) (xy 71.354455 -272.124963)
			(xy 71.35495 -272.14957) (xy 72.643758 -272.14957) (xy 72.647718 -272.100516) (xy 72.659495 -272.052732)
			(xy 72.678786 -272.007456) (xy 72.705089 -271.96586) (xy 72.737724 -271.929023) (xy 72.775845 -271.897898)
			(xy 72.818466 -271.873291) (xy 72.864482 -271.855839) (xy 72.912701 -271.845995) (xy 72.961876 -271.844014)
			(xy 73.010731 -271.849946) (xy 73.058002 -271.863638) (xy 73.102464 -271.884736) (xy 73.142967 -271.912692)
			(xy 73.17846 -271.946784) (xy 73.208025 -271.986128) (xy 73.230896 -272.029705) (xy 73.24648 -272.076386)
			(xy 73.254375 -272.124963) (xy 73.25487 -272.14957) (xy 74.543932 -272.14957) (xy 74.547892 -272.100516)
			(xy 74.559669 -272.052732) (xy 74.57896 -272.007456) (xy 74.605263 -271.96586) (xy 74.637898 -271.929023)
			(xy 74.676019 -271.897898) (xy 74.71864 -271.873291) (xy 74.764656 -271.855839) (xy 74.812875 -271.845995)
			(xy 74.86205 -271.844014) (xy 74.910905 -271.849946) (xy 74.958176 -271.863638) (xy 75.002638 -271.884736)
			(xy 75.043141 -271.912692) (xy 75.078634 -271.946784) (xy 75.108199 -271.986128) (xy 75.13107 -272.029705)
			(xy 75.146654 -272.076386) (xy 75.154549 -272.124963) (xy 75.155044 -272.14957) (xy 76.444106 -272.14957)
			(xy 76.448066 -272.100516) (xy 76.459843 -272.052732) (xy 76.479134 -272.007456) (xy 76.505437 -271.96586)
			(xy 76.538072 -271.929023) (xy 76.576193 -271.897898) (xy 76.618814 -271.873291) (xy 76.66483 -271.855839)
			(xy 76.713049 -271.845995) (xy 76.762224 -271.844014) (xy 76.811079 -271.849946) (xy 76.85835 -271.863638)
			(xy 76.902812 -271.884736) (xy 76.943315 -271.912692) (xy 76.978808 -271.946784) (xy 77.008373 -271.986128)
			(xy 77.031244 -272.029705) (xy 77.046828 -272.076386) (xy 77.054723 -272.124963) (xy 77.055218 -272.14957)
			(xy 78.344026 -272.14957) (xy 78.347986 -272.100516) (xy 78.359763 -272.052732) (xy 78.379054 -272.007456)
			(xy 78.405357 -271.96586) (xy 78.437992 -271.929023) (xy 78.476113 -271.897898) (xy 78.518734 -271.873291)
			(xy 78.56475 -271.855839) (xy 78.612969 -271.845995) (xy 78.662144 -271.844014) (xy 78.710999 -271.849946)
			(xy 78.75827 -271.863638) (xy 78.802732 -271.884736) (xy 78.843235 -271.912692) (xy 78.878728 -271.946784)
			(xy 78.908293 -271.986128) (xy 78.931164 -272.029705) (xy 78.946748 -272.076386) (xy 78.954643 -272.124963)
			(xy 78.955138 -272.14957) (xy 80.243946 -272.14957) (xy 80.247906 -272.100516) (xy 80.259683 -272.052732)
			(xy 80.278974 -272.007456) (xy 80.305277 -271.96586) (xy 80.337912 -271.929023) (xy 80.376033 -271.897898)
			(xy 80.418654 -271.873291) (xy 80.46467 -271.855839) (xy 80.512889 -271.845995) (xy 80.562064 -271.844014)
			(xy 80.610919 -271.849946) (xy 80.65819 -271.863638) (xy 80.702652 -271.884736) (xy 80.743155 -271.912692)
			(xy 80.778648 -271.946784) (xy 80.808213 -271.986128) (xy 80.831084 -272.029705) (xy 80.846668 -272.076386)
			(xy 80.854563 -272.124963) (xy 80.855058 -272.14957) (xy 80.854563 -272.174177) (xy 80.846668 -272.222754)
			(xy 80.831084 -272.269435) (xy 80.808213 -272.313012) (xy 80.778648 -272.352356) (xy 80.743155 -272.386448)
			(xy 80.702652 -272.414404) (xy 80.65819 -272.435502) (xy 80.610919 -272.449194) (xy 80.562064 -272.455126)
			(xy 80.512889 -272.453145) (xy 80.46467 -272.443301) (xy 80.418654 -272.425849) (xy 80.376033 -272.401242)
			(xy 80.337912 -272.370117) (xy 80.305277 -272.33328) (xy 80.278974 -272.291684) (xy 80.259683 -272.246408)
			(xy 80.247906 -272.198624) (xy 80.243946 -272.14957) (xy 78.955138 -272.14957) (xy 78.954643 -272.174177)
			(xy 78.946748 -272.222754) (xy 78.931164 -272.269435) (xy 78.908293 -272.313012) (xy 78.878728 -272.352356)
			(xy 78.843235 -272.386448) (xy 78.802732 -272.414404) (xy 78.75827 -272.435502) (xy 78.710999 -272.449194)
			(xy 78.662144 -272.455126) (xy 78.612969 -272.453145) (xy 78.56475 -272.443301) (xy 78.518734 -272.425849)
			(xy 78.476113 -272.401242) (xy 78.437992 -272.370117) (xy 78.405357 -272.33328) (xy 78.379054 -272.291684)
			(xy 78.359763 -272.246408) (xy 78.347986 -272.198624) (xy 78.344026 -272.14957) (xy 77.055218 -272.14957)
			(xy 77.054723 -272.174177) (xy 77.046828 -272.222754) (xy 77.031244 -272.269435) (xy 77.008373 -272.313012)
			(xy 76.978808 -272.352356) (xy 76.943315 -272.386448) (xy 76.902812 -272.414404) (xy 76.85835 -272.435502)
			(xy 76.811079 -272.449194) (xy 76.762224 -272.455126) (xy 76.713049 -272.453145) (xy 76.66483 -272.443301)
			(xy 76.618814 -272.425849) (xy 76.576193 -272.401242) (xy 76.538072 -272.370117) (xy 76.505437 -272.33328)
			(xy 76.479134 -272.291684) (xy 76.459843 -272.246408) (xy 76.448066 -272.198624) (xy 76.444106 -272.14957)
			(xy 75.155044 -272.14957) (xy 75.154549 -272.174177) (xy 75.146654 -272.222754) (xy 75.13107 -272.269435)
			(xy 75.108199 -272.313012) (xy 75.078634 -272.352356) (xy 75.043141 -272.386448) (xy 75.002638 -272.414404)
			(xy 74.958176 -272.435502) (xy 74.910905 -272.449194) (xy 74.86205 -272.455126) (xy 74.812875 -272.453145)
			(xy 74.764656 -272.443301) (xy 74.71864 -272.425849) (xy 74.676019 -272.401242) (xy 74.637898 -272.370117)
			(xy 74.605263 -272.33328) (xy 74.57896 -272.291684) (xy 74.559669 -272.246408) (xy 74.547892 -272.198624)
			(xy 74.543932 -272.14957) (xy 73.25487 -272.14957) (xy 73.254375 -272.174177) (xy 73.24648 -272.222754)
			(xy 73.230896 -272.269435) (xy 73.208025 -272.313012) (xy 73.17846 -272.352356) (xy 73.142967 -272.386448)
			(xy 73.102464 -272.414404) (xy 73.058002 -272.435502) (xy 73.010731 -272.449194) (xy 72.961876 -272.455126)
			(xy 72.912701 -272.453145) (xy 72.864482 -272.443301) (xy 72.818466 -272.425849) (xy 72.775845 -272.401242)
			(xy 72.737724 -272.370117) (xy 72.705089 -272.33328) (xy 72.678786 -272.291684) (xy 72.659495 -272.246408)
			(xy 72.647718 -272.198624) (xy 72.643758 -272.14957) (xy 71.35495 -272.14957) (xy 71.354455 -272.174177)
			(xy 71.34656 -272.222754) (xy 71.330976 -272.269435) (xy 71.308105 -272.313012) (xy 71.27854 -272.352356)
			(xy 71.243047 -272.386448) (xy 71.202544 -272.414404) (xy 71.158082 -272.435502) (xy 71.110811 -272.449194)
			(xy 71.061956 -272.455126) (xy 71.012781 -272.453145) (xy 70.964562 -272.443301) (xy 70.918546 -272.425849)
			(xy 70.875925 -272.401242) (xy 70.837804 -272.370117) (xy 70.805169 -272.33328) (xy 70.778866 -272.291684)
			(xy 70.759575 -272.246408) (xy 70.747798 -272.198624) (xy 70.743838 -272.14957) (xy 69.45503 -272.14957)
			(xy 69.454535 -272.174177) (xy 69.44664 -272.222754) (xy 69.431056 -272.269435) (xy 69.408185 -272.313012)
			(xy 69.37862 -272.352356) (xy 69.343127 -272.386448) (xy 69.302624 -272.414404) (xy 69.258162 -272.435502)
			(xy 69.210891 -272.449194) (xy 69.162036 -272.455126) (xy 69.112861 -272.453145) (xy 69.064642 -272.443301)
			(xy 69.018626 -272.425849) (xy 68.976005 -272.401242) (xy 68.937884 -272.370117) (xy 68.905249 -272.33328)
			(xy 68.878946 -272.291684) (xy 68.859655 -272.246408) (xy 68.847878 -272.198624) (xy 68.843918 -272.14957)
			(xy 67.554856 -272.14957) (xy 67.554361 -272.174177) (xy 67.546466 -272.222754) (xy 67.530882 -272.269435)
			(xy 67.508011 -272.313012) (xy 67.478446 -272.352356) (xy 67.442953 -272.386448) (xy 67.40245 -272.414404)
			(xy 67.357988 -272.435502) (xy 67.310717 -272.449194) (xy 67.261862 -272.455126) (xy 67.212687 -272.453145)
			(xy 67.164468 -272.443301) (xy 67.118452 -272.425849) (xy 67.075831 -272.401242) (xy 67.03771 -272.370117)
			(xy 67.005075 -272.33328) (xy 66.978772 -272.291684) (xy 66.959481 -272.246408) (xy 66.947704 -272.198624)
			(xy 66.943744 -272.14957) (xy 65.654936 -272.14957) (xy 65.654441 -272.174177) (xy 65.646546 -272.222754)
			(xy 65.630962 -272.269435) (xy 65.608091 -272.313012) (xy 65.578526 -272.352356) (xy 65.543033 -272.386448)
			(xy 65.50253 -272.414404) (xy 65.458068 -272.435502) (xy 65.410797 -272.449194) (xy 65.361942 -272.455126)
			(xy 65.312767 -272.453145) (xy 65.264548 -272.443301) (xy 65.218532 -272.425849) (xy 65.175911 -272.401242)
			(xy 65.13779 -272.370117) (xy 65.105155 -272.33328) (xy 65.078852 -272.291684) (xy 65.059561 -272.246408)
			(xy 65.047784 -272.198624) (xy 65.043824 -272.14957) (xy 63.755016 -272.14957) (xy 63.754521 -272.174177)
			(xy 63.746626 -272.222754) (xy 63.731042 -272.269435) (xy 63.708171 -272.313012) (xy 63.678606 -272.352356)
			(xy 63.643113 -272.386448) (xy 63.60261 -272.414404) (xy 63.558148 -272.435502) (xy 63.510877 -272.449194)
			(xy 63.462022 -272.455126) (xy 63.412847 -272.453145) (xy 63.364628 -272.443301) (xy 63.318612 -272.425849)
			(xy 63.275991 -272.401242) (xy 63.23787 -272.370117) (xy 63.205235 -272.33328) (xy 63.178932 -272.291684)
			(xy 63.159641 -272.246408) (xy 63.147864 -272.198624) (xy 63.143904 -272.14957) (xy 61.854842 -272.14957)
			(xy 61.854347 -272.174177) (xy 61.846452 -272.222754) (xy 61.830868 -272.269435) (xy 61.807997 -272.313012)
			(xy 61.778432 -272.352356) (xy 61.742939 -272.386448) (xy 61.702436 -272.414404) (xy 61.657974 -272.435502)
			(xy 61.610703 -272.449194) (xy 61.561848 -272.455126) (xy 61.512673 -272.453145) (xy 61.464454 -272.443301)
			(xy 61.418438 -272.425849) (xy 61.375817 -272.401242) (xy 61.337696 -272.370117) (xy 61.305061 -272.33328)
			(xy 61.278758 -272.291684) (xy 61.259467 -272.246408) (xy 61.24769 -272.198624) (xy 61.24373 -272.14957)
			(xy 59.954917 -272.14957) (xy 59.954427 -272.173923) (xy 59.946532 -272.2225) (xy 59.930948 -272.269181)
			(xy 59.908077 -272.312758) (xy 59.878512 -272.352102) (xy 59.843019 -272.386194) (xy 59.802516 -272.41415)
			(xy 59.758054 -272.435248) (xy 59.710783 -272.44894) (xy 59.661928 -272.454872) (xy 59.612753 -272.452891)
			(xy 59.564534 -272.443047) (xy 59.518518 -272.425595) (xy 59.475897 -272.400988) (xy 59.437776 -272.369863)
			(xy 59.405141 -272.333026) (xy 59.378838 -272.29143) (xy 59.359547 -272.246154) (xy 59.34777 -272.19837)
			(xy 59.34381 -272.149316) (xy 58.054997 -272.149316) (xy 58.055002 -272.14957) (xy 58.054507 -272.174177)
			(xy 58.046612 -272.222754) (xy 58.031028 -272.269435) (xy 58.008157 -272.313012) (xy 57.978592 -272.352356)
			(xy 57.943099 -272.386448) (xy 57.902596 -272.414404) (xy 57.858134 -272.435502) (xy 57.810863 -272.449194)
			(xy 57.762008 -272.455126) (xy 57.712833 -272.453145) (xy 57.664614 -272.443301) (xy 57.618598 -272.425849)
			(xy 57.575977 -272.401242) (xy 57.537856 -272.370117) (xy 57.505221 -272.33328) (xy 57.478918 -272.291684)
			(xy 57.459627 -272.246408) (xy 57.44785 -272.198624) (xy 57.44389 -272.14957) (xy 56.154828 -272.14957)
			(xy 56.154333 -272.174177) (xy 56.146438 -272.222754) (xy 56.130854 -272.269435) (xy 56.107983 -272.313012)
			(xy 56.078418 -272.352356) (xy 56.042925 -272.386448) (xy 56.002422 -272.414404) (xy 55.95796 -272.435502)
			(xy 55.910689 -272.449194) (xy 55.861834 -272.455126) (xy 55.812659 -272.453145) (xy 55.76444 -272.443301)
			(xy 55.718424 -272.425849) (xy 55.675803 -272.401242) (xy 55.637682 -272.370117) (xy 55.605047 -272.33328)
			(xy 55.578744 -272.291684) (xy 55.559453 -272.246408) (xy 55.547676 -272.198624) (xy 55.543716 -272.14957)
			(xy 54.254908 -272.14957) (xy 54.254413 -272.174177) (xy 54.246518 -272.222754) (xy 54.230934 -272.269435)
			(xy 54.208063 -272.313012) (xy 54.178498 -272.352356) (xy 54.143005 -272.386448) (xy 54.102502 -272.414404)
			(xy 54.05804 -272.435502) (xy 54.010769 -272.449194) (xy 53.961914 -272.455126) (xy 53.912739 -272.453145)
			(xy 53.86452 -272.443301) (xy 53.818504 -272.425849) (xy 53.775883 -272.401242) (xy 53.737762 -272.370117)
			(xy 53.705127 -272.33328) (xy 53.678824 -272.291684) (xy 53.659533 -272.246408) (xy 53.647756 -272.198624)
			(xy 53.643796 -272.14957) (xy 52.354988 -272.14957) (xy 52.354493 -272.174177) (xy 52.346598 -272.222754)
			(xy 52.331014 -272.269435) (xy 52.308143 -272.313012) (xy 52.278578 -272.352356) (xy 52.243085 -272.386448)
			(xy 52.202582 -272.414404) (xy 52.15812 -272.435502) (xy 52.110849 -272.449194) (xy 52.061994 -272.455126)
			(xy 52.012819 -272.453145) (xy 51.9646 -272.443301) (xy 51.918584 -272.425849) (xy 51.875963 -272.401242)
			(xy 51.837842 -272.370117) (xy 51.805207 -272.33328) (xy 51.778904 -272.291684) (xy 51.759613 -272.246408)
			(xy 51.747836 -272.198624) (xy 51.743876 -272.14957) (xy 50.454814 -272.14957) (xy 50.454319 -272.174177)
			(xy 50.446424 -272.222754) (xy 50.43084 -272.269435) (xy 50.407969 -272.313012) (xy 50.378404 -272.352356)
			(xy 50.342911 -272.386448) (xy 50.302408 -272.414404) (xy 50.257946 -272.435502) (xy 50.210675 -272.449194)
			(xy 50.16182 -272.455126) (xy 50.112645 -272.453145) (xy 50.064426 -272.443301) (xy 50.01841 -272.425849)
			(xy 49.975789 -272.401242) (xy 49.937668 -272.370117) (xy 49.905033 -272.33328) (xy 49.87873 -272.291684)
			(xy 49.859439 -272.246408) (xy 49.847662 -272.198624) (xy 49.843702 -272.14957) (xy 48.554894 -272.14957)
			(xy 48.554399 -272.174177) (xy 48.546504 -272.222754) (xy 48.53092 -272.269435) (xy 48.508049 -272.313012)
			(xy 48.478484 -272.352356) (xy 48.442991 -272.386448) (xy 48.402488 -272.414404) (xy 48.358026 -272.435502)
			(xy 48.310755 -272.449194) (xy 48.2619 -272.455126) (xy 48.212725 -272.453145) (xy 48.164506 -272.443301)
			(xy 48.11849 -272.425849) (xy 48.075869 -272.401242) (xy 48.037748 -272.370117) (xy 48.005113 -272.33328)
			(xy 47.97881 -272.291684) (xy 47.959519 -272.246408) (xy 47.947742 -272.198624) (xy 47.943782 -272.14957)
			(xy 46.654974 -272.14957) (xy 46.654479 -272.174177) (xy 46.646584 -272.222754) (xy 46.631 -272.269435)
			(xy 46.608129 -272.313012) (xy 46.578564 -272.352356) (xy 46.543071 -272.386448) (xy 46.502568 -272.414404)
			(xy 46.458106 -272.435502) (xy 46.410835 -272.449194) (xy 46.36198 -272.455126) (xy 46.312805 -272.453145)
			(xy 46.264586 -272.443301) (xy 46.21857 -272.425849) (xy 46.175949 -272.401242) (xy 46.137828 -272.370117)
			(xy 46.105193 -272.33328) (xy 46.07889 -272.291684) (xy 46.059599 -272.246408) (xy 46.047822 -272.198624)
			(xy 46.043862 -272.14957) (xy 44.7548 -272.14957) (xy 44.754305 -272.174177) (xy 44.74641 -272.222754)
			(xy 44.730826 -272.269435) (xy 44.707955 -272.313012) (xy 44.67839 -272.352356) (xy 44.642897 -272.386448)
			(xy 44.602394 -272.414404) (xy 44.557932 -272.435502) (xy 44.510661 -272.449194) (xy 44.461806 -272.455126)
			(xy 44.412631 -272.453145) (xy 44.364412 -272.443301) (xy 44.318396 -272.425849) (xy 44.275775 -272.401242)
			(xy 44.237654 -272.370117) (xy 44.205019 -272.33328) (xy 44.178716 -272.291684) (xy 44.159425 -272.246408)
			(xy 44.147648 -272.198624) (xy 44.143688 -272.14957) (xy 40.899334 -272.14957) (xy 40.899334 -272.2372)
			(xy 40.9 -272.249227) (xy 40.910863 -272.270692) (xy 40.920162 -272.278348) (xy 40.996362 -272.333974)
			(xy 41.020238 -272.337784) (xy 41.031922 -272.333974) (xy 41.054563 -272.327199) (xy 41.101257 -272.319927)
			(xy 41.124886 -272.319496) (xy 41.150144 -272.319988) (xy 41.199972 -272.3283) (xy 41.247751 -272.344701)
			(xy 41.29218 -272.368743) (xy 41.332045 -272.399769) (xy 41.36626 -272.436935) (xy 41.39389 -272.479225)
			(xy 41.414183 -272.525486) (xy 41.426584 -272.574456) (xy 41.430756 -272.6248) (xy 41.430756 -272.624804)
			(xy 41.769042 -272.624804) (xy 41.773002 -272.57575) (xy 41.784779 -272.527966) (xy 41.80407 -272.48269)
			(xy 41.830373 -272.441094) (xy 41.863008 -272.404257) (xy 41.901129 -272.373132) (xy 41.94375 -272.348525)
			(xy 41.989766 -272.331073) (xy 42.037985 -272.321229) (xy 42.08716 -272.319248) (xy 42.136015 -272.32518)
			(xy 42.183286 -272.338872) (xy 42.227748 -272.35997) (xy 42.268251 -272.387926) (xy 42.303744 -272.422018)
			(xy 42.333309 -272.461362) (xy 42.35618 -272.504939) (xy 42.371764 -272.55162) (xy 42.379659 -272.600197)
			(xy 42.380154 -272.624804) (xy 42.379659 -272.649411) (xy 42.371764 -272.697988) (xy 42.35618 -272.744669)
			(xy 42.333309 -272.788246) (xy 42.303744 -272.82759) (xy 42.268251 -272.861682) (xy 42.227748 -272.889638)
			(xy 42.183286 -272.910736) (xy 42.136015 -272.924428) (xy 42.08716 -272.93036) (xy 42.037985 -272.928379)
			(xy 41.989766 -272.918535) (xy 41.94375 -272.901083) (xy 41.901129 -272.876476) (xy 41.863008 -272.845351)
			(xy 41.830373 -272.808514) (xy 41.80407 -272.766918) (xy 41.784779 -272.721642) (xy 41.773002 -272.673858)
			(xy 41.769042 -272.624804) (xy 41.430756 -272.624804) (xy 41.426584 -272.675144) (xy 41.414183 -272.724114)
			(xy 41.39389 -272.770375) (xy 41.36626 -272.812665) (xy 41.332045 -272.849831) (xy 41.29218 -272.880857)
			(xy 41.247751 -272.904899) (xy 41.199972 -272.9213) (xy 41.150144 -272.929612) (xy 41.124886 -272.930112)
			(xy 41.101259 -272.929665) (xy 41.054569 -272.922386) (xy 41.031922 -272.915634) (xy 41.020238 -272.911824)
			(xy 40.996362 -272.915634) (xy 40.920162 -272.97126) (xy 40.910818 -272.978881) (xy 40.899946 -273.000365)
			(xy 40.899334 -273.012408) (xy 40.899334 -273.099784) (xy 43.193982 -273.099784) (xy 43.197942 -273.05073)
			(xy 43.209719 -273.002946) (xy 43.22901 -272.95767) (xy 43.255313 -272.916074) (xy 43.287948 -272.879237)
			(xy 43.326069 -272.848112) (xy 43.36869 -272.823505) (xy 43.414706 -272.806053) (xy 43.462925 -272.796209)
			(xy 43.5121 -272.794228) (xy 43.560955 -272.80016) (xy 43.608226 -272.813852) (xy 43.652688 -272.83495)
			(xy 43.693191 -272.862906) (xy 43.728684 -272.896998) (xy 43.758249 -272.936342) (xy 43.78112 -272.979919)
			(xy 43.796704 -273.0266) (xy 43.804599 -273.075177) (xy 43.805094 -273.099784) (xy 43.804599 -273.124391)
			(xy 43.80442 -273.125492) (xy 44.123098 -273.125492) (xy 44.123098 -273.074076) (xy 44.131141 -273.023294)
			(xy 44.147029 -272.974395) (xy 44.170372 -272.928583) (xy 44.200593 -272.886987) (xy 44.236949 -272.850631)
			(xy 44.278545 -272.82041) (xy 44.324357 -272.797067) (xy 44.373256 -272.781179) (xy 44.424038 -272.773136)
			(xy 44.475454 -272.773136) (xy 44.526236 -272.781179) (xy 44.575135 -272.797067) (xy 44.620947 -272.82041)
			(xy 44.662543 -272.850631) (xy 44.698899 -272.886987) (xy 44.72912 -272.928583) (xy 44.752463 -272.974395)
			(xy 44.768351 -273.023294) (xy 44.776394 -273.074076) (xy 44.776898 -273.099784) (xy 45.094156 -273.099784)
			(xy 45.098116 -273.05073) (xy 45.109893 -273.002946) (xy 45.129184 -272.95767) (xy 45.155487 -272.916074)
			(xy 45.188122 -272.879237) (xy 45.226243 -272.848112) (xy 45.268864 -272.823505) (xy 45.31488 -272.806053)
			(xy 45.363099 -272.796209) (xy 45.412274 -272.794228) (xy 45.461129 -272.80016) (xy 45.5084 -272.813852)
			(xy 45.552862 -272.83495) (xy 45.593365 -272.862906) (xy 45.628858 -272.896998) (xy 45.658423 -272.936342)
			(xy 45.681294 -272.979919) (xy 45.696878 -273.0266) (xy 45.704773 -273.075177) (xy 45.705268 -273.099784)
			(xy 45.704773 -273.124391) (xy 45.704594 -273.125492) (xy 46.023272 -273.125492) (xy 46.023272 -273.074076)
			(xy 46.031315 -273.023294) (xy 46.047203 -272.974395) (xy 46.070546 -272.928583) (xy 46.100767 -272.886987)
			(xy 46.137123 -272.850631) (xy 46.178719 -272.82041) (xy 46.224531 -272.797067) (xy 46.27343 -272.781179)
			(xy 46.324212 -272.773136) (xy 46.375628 -272.773136) (xy 46.42641 -272.781179) (xy 46.475309 -272.797067)
			(xy 46.521121 -272.82041) (xy 46.562717 -272.850631) (xy 46.599073 -272.886987) (xy 46.629294 -272.928583)
			(xy 46.652637 -272.974395) (xy 46.668525 -273.023294) (xy 46.676568 -273.074076) (xy 46.677072 -273.099784)
			(xy 46.994076 -273.099784) (xy 46.998036 -273.05073) (xy 47.009813 -273.002946) (xy 47.029104 -272.95767)
			(xy 47.055407 -272.916074) (xy 47.088042 -272.879237) (xy 47.126163 -272.848112) (xy 47.168784 -272.823505)
			(xy 47.2148 -272.806053) (xy 47.263019 -272.796209) (xy 47.312194 -272.794228) (xy 47.361049 -272.80016)
			(xy 47.40832 -272.813852) (xy 47.452782 -272.83495) (xy 47.493285 -272.862906) (xy 47.528778 -272.896998)
			(xy 47.558343 -272.936342) (xy 47.581214 -272.979919) (xy 47.596798 -273.0266) (xy 47.604693 -273.075177)
			(xy 47.605188 -273.099784) (xy 47.604693 -273.124391) (xy 47.604514 -273.125492) (xy 47.923192 -273.125492)
			(xy 47.923192 -273.074076) (xy 47.931235 -273.023294) (xy 47.947123 -272.974395) (xy 47.970466 -272.928583)
			(xy 48.000687 -272.886987) (xy 48.037043 -272.850631) (xy 48.078639 -272.82041) (xy 48.124451 -272.797067)
			(xy 48.17335 -272.781179) (xy 48.224132 -272.773136) (xy 48.275548 -272.773136) (xy 48.32633 -272.781179)
			(xy 48.375229 -272.797067) (xy 48.421041 -272.82041) (xy 48.462637 -272.850631) (xy 48.498993 -272.886987)
			(xy 48.529214 -272.928583) (xy 48.552557 -272.974395) (xy 48.568445 -273.023294) (xy 48.576488 -273.074076)
			(xy 48.576992 -273.099784) (xy 48.893996 -273.099784) (xy 48.897956 -273.05073) (xy 48.909733 -273.002946)
			(xy 48.929024 -272.95767) (xy 48.955327 -272.916074) (xy 48.987962 -272.879237) (xy 49.026083 -272.848112)
			(xy 49.068704 -272.823505) (xy 49.11472 -272.806053) (xy 49.162939 -272.796209) (xy 49.212114 -272.794228)
			(xy 49.260969 -272.80016) (xy 49.30824 -272.813852) (xy 49.352702 -272.83495) (xy 49.393205 -272.862906)
			(xy 49.428698 -272.896998) (xy 49.458263 -272.936342) (xy 49.481134 -272.979919) (xy 49.496718 -273.0266)
			(xy 49.504613 -273.075177) (xy 49.505108 -273.099784) (xy 49.504613 -273.124391) (xy 49.504434 -273.125492)
			(xy 49.823112 -273.125492) (xy 49.823112 -273.074076) (xy 49.831155 -273.023294) (xy 49.847043 -272.974395)
			(xy 49.870386 -272.928583) (xy 49.900607 -272.886987) (xy 49.936963 -272.850631) (xy 49.978559 -272.82041)
			(xy 50.024371 -272.797067) (xy 50.07327 -272.781179) (xy 50.124052 -272.773136) (xy 50.175468 -272.773136)
			(xy 50.22625 -272.781179) (xy 50.275149 -272.797067) (xy 50.320961 -272.82041) (xy 50.362557 -272.850631)
			(xy 50.398913 -272.886987) (xy 50.429134 -272.928583) (xy 50.452477 -272.974395) (xy 50.468365 -273.023294)
			(xy 50.476408 -273.074076) (xy 50.476912 -273.099784) (xy 50.79417 -273.099784) (xy 50.79813 -273.05073)
			(xy 50.809907 -273.002946) (xy 50.829198 -272.95767) (xy 50.855501 -272.916074) (xy 50.888136 -272.879237)
			(xy 50.926257 -272.848112) (xy 50.968878 -272.823505) (xy 51.014894 -272.806053) (xy 51.063113 -272.796209)
			(xy 51.112288 -272.794228) (xy 51.161143 -272.80016) (xy 51.208414 -272.813852) (xy 51.252876 -272.83495)
			(xy 51.293379 -272.862906) (xy 51.328872 -272.896998) (xy 51.358437 -272.936342) (xy 51.381308 -272.979919)
			(xy 51.396892 -273.0266) (xy 51.404787 -273.075177) (xy 51.405282 -273.099784) (xy 51.404787 -273.124391)
			(xy 51.404608 -273.125492) (xy 51.723286 -273.125492) (xy 51.723286 -273.074076) (xy 51.731329 -273.023294)
			(xy 51.747217 -272.974395) (xy 51.77056 -272.928583) (xy 51.800781 -272.886987) (xy 51.837137 -272.850631)
			(xy 51.878733 -272.82041) (xy 51.924545 -272.797067) (xy 51.973444 -272.781179) (xy 52.024226 -272.773136)
			(xy 52.075642 -272.773136) (xy 52.126424 -272.781179) (xy 52.175323 -272.797067) (xy 52.221135 -272.82041)
			(xy 52.262731 -272.850631) (xy 52.299087 -272.886987) (xy 52.329308 -272.928583) (xy 52.352651 -272.974395)
			(xy 52.368539 -273.023294) (xy 52.376582 -273.074076) (xy 52.377086 -273.099784) (xy 52.69409 -273.099784)
			(xy 52.69805 -273.05073) (xy 52.709827 -273.002946) (xy 52.729118 -272.95767) (xy 52.755421 -272.916074)
			(xy 52.788056 -272.879237) (xy 52.826177 -272.848112) (xy 52.868798 -272.823505) (xy 52.914814 -272.806053)
			(xy 52.963033 -272.796209) (xy 53.012208 -272.794228) (xy 53.061063 -272.80016) (xy 53.108334 -272.813852)
			(xy 53.152796 -272.83495) (xy 53.193299 -272.862906) (xy 53.228792 -272.896998) (xy 53.258357 -272.936342)
			(xy 53.281228 -272.979919) (xy 53.296812 -273.0266) (xy 53.304707 -273.075177) (xy 53.305202 -273.099784)
			(xy 53.304707 -273.124391) (xy 53.304528 -273.125492) (xy 53.623206 -273.125492) (xy 53.623206 -273.074076)
			(xy 53.631249 -273.023294) (xy 53.647137 -272.974395) (xy 53.67048 -272.928583) (xy 53.700701 -272.886987)
			(xy 53.737057 -272.850631) (xy 53.778653 -272.82041) (xy 53.824465 -272.797067) (xy 53.873364 -272.781179)
			(xy 53.924146 -272.773136) (xy 53.975562 -272.773136) (xy 54.026344 -272.781179) (xy 54.075243 -272.797067)
			(xy 54.121055 -272.82041) (xy 54.162651 -272.850631) (xy 54.199007 -272.886987) (xy 54.229228 -272.928583)
			(xy 54.252571 -272.974395) (xy 54.268459 -273.023294) (xy 54.276502 -273.074076) (xy 54.277006 -273.099784)
			(xy 54.59401 -273.099784) (xy 54.59797 -273.05073) (xy 54.609747 -273.002946) (xy 54.629038 -272.95767)
			(xy 54.655341 -272.916074) (xy 54.687976 -272.879237) (xy 54.726097 -272.848112) (xy 54.768718 -272.823505)
			(xy 54.814734 -272.806053) (xy 54.862953 -272.796209) (xy 54.912128 -272.794228) (xy 54.960983 -272.80016)
			(xy 55.008254 -272.813852) (xy 55.052716 -272.83495) (xy 55.093219 -272.862906) (xy 55.128712 -272.896998)
			(xy 55.158277 -272.936342) (xy 55.181148 -272.979919) (xy 55.196732 -273.0266) (xy 55.204627 -273.075177)
			(xy 55.205122 -273.099784) (xy 55.204627 -273.124391) (xy 55.204448 -273.125492) (xy 55.523126 -273.125492)
			(xy 55.523126 -273.074076) (xy 55.531169 -273.023294) (xy 55.547057 -272.974395) (xy 55.5704 -272.928583)
			(xy 55.600621 -272.886987) (xy 55.636977 -272.850631) (xy 55.678573 -272.82041) (xy 55.724385 -272.797067)
			(xy 55.773284 -272.781179) (xy 55.824066 -272.773136) (xy 55.875482 -272.773136) (xy 55.926264 -272.781179)
			(xy 55.975163 -272.797067) (xy 56.020975 -272.82041) (xy 56.062571 -272.850631) (xy 56.098927 -272.886987)
			(xy 56.129148 -272.928583) (xy 56.152491 -272.974395) (xy 56.168379 -273.023294) (xy 56.176422 -273.074076)
			(xy 56.176926 -273.099784) (xy 56.494184 -273.099784) (xy 56.498144 -273.05073) (xy 56.509921 -273.002946)
			(xy 56.529212 -272.95767) (xy 56.555515 -272.916074) (xy 56.58815 -272.879237) (xy 56.626271 -272.848112)
			(xy 56.668892 -272.823505) (xy 56.714908 -272.806053) (xy 56.763127 -272.796209) (xy 56.812302 -272.794228)
			(xy 56.861157 -272.80016) (xy 56.908428 -272.813852) (xy 56.95289 -272.83495) (xy 56.993393 -272.862906)
			(xy 57.028886 -272.896998) (xy 57.058451 -272.936342) (xy 57.081322 -272.979919) (xy 57.096906 -273.0266)
			(xy 57.104801 -273.075177) (xy 57.105296 -273.099784) (xy 57.104801 -273.124391) (xy 57.104622 -273.125492)
			(xy 57.4233 -273.125492) (xy 57.4233 -273.074076) (xy 57.431343 -273.023294) (xy 57.447231 -272.974395)
			(xy 57.470574 -272.928583) (xy 57.500795 -272.886987) (xy 57.537151 -272.850631) (xy 57.578747 -272.82041)
			(xy 57.624559 -272.797067) (xy 57.673458 -272.781179) (xy 57.72424 -272.773136) (xy 57.775656 -272.773136)
			(xy 57.826438 -272.781179) (xy 57.875337 -272.797067) (xy 57.921149 -272.82041) (xy 57.962745 -272.850631)
			(xy 57.999101 -272.886987) (xy 58.029322 -272.928583) (xy 58.052665 -272.974395) (xy 58.068553 -273.023294)
			(xy 58.076596 -273.074076) (xy 58.0771 -273.099784) (xy 58.394104 -273.099784) (xy 58.398064 -273.05073)
			(xy 58.409841 -273.002946) (xy 58.429132 -272.95767) (xy 58.455435 -272.916074) (xy 58.48807 -272.879237)
			(xy 58.526191 -272.848112) (xy 58.568812 -272.823505) (xy 58.614828 -272.806053) (xy 58.663047 -272.796209)
			(xy 58.712222 -272.794228) (xy 58.761077 -272.80016) (xy 58.808348 -272.813852) (xy 58.85281 -272.83495)
			(xy 58.893313 -272.862906) (xy 58.928806 -272.896998) (xy 58.958371 -272.936342) (xy 58.981242 -272.979919)
			(xy 58.996826 -273.0266) (xy 59.004721 -273.075177) (xy 59.005216 -273.099784) (xy 59.004721 -273.124391)
			(xy 59.004583 -273.125238) (xy 59.322966 -273.125238) (xy 59.322966 -273.073822) (xy 59.331009 -273.02304)
			(xy 59.346897 -272.974141) (xy 59.37024 -272.928329) (xy 59.400461 -272.886733) (xy 59.436817 -272.850377)
			(xy 59.478413 -272.820156) (xy 59.524225 -272.796813) (xy 59.573124 -272.780925) (xy 59.623906 -272.772882)
			(xy 59.675322 -272.772882) (xy 59.726104 -272.780925) (xy 59.775003 -272.796813) (xy 59.820815 -272.820156)
			(xy 59.862411 -272.850377) (xy 59.898767 -272.886733) (xy 59.928988 -272.928329) (xy 59.952331 -272.974141)
			(xy 59.968219 -273.02304) (xy 59.976262 -273.073822) (xy 59.976766 -273.09953) (xy 59.976761 -273.099784)
			(xy 60.294024 -273.099784) (xy 60.297984 -273.05073) (xy 60.309761 -273.002946) (xy 60.329052 -272.95767)
			(xy 60.355355 -272.916074) (xy 60.38799 -272.879237) (xy 60.426111 -272.848112) (xy 60.468732 -272.823505)
			(xy 60.514748 -272.806053) (xy 60.562967 -272.796209) (xy 60.612142 -272.794228) (xy 60.660997 -272.80016)
			(xy 60.708268 -272.813852) (xy 60.75273 -272.83495) (xy 60.793233 -272.862906) (xy 60.828726 -272.896998)
			(xy 60.858291 -272.936342) (xy 60.881162 -272.979919) (xy 60.896746 -273.0266) (xy 60.904641 -273.075177)
			(xy 60.905136 -273.099784) (xy 60.904641 -273.124391) (xy 60.904462 -273.125492) (xy 61.222886 -273.125492)
			(xy 61.222886 -273.074076) (xy 61.230929 -273.023294) (xy 61.246817 -272.974395) (xy 61.27016 -272.928583)
			(xy 61.300381 -272.886987) (xy 61.336737 -272.850631) (xy 61.378333 -272.82041) (xy 61.424145 -272.797067)
			(xy 61.473044 -272.781179) (xy 61.523826 -272.773136) (xy 61.575242 -272.773136) (xy 61.626024 -272.781179)
			(xy 61.674923 -272.797067) (xy 61.720735 -272.82041) (xy 61.762331 -272.850631) (xy 61.798687 -272.886987)
			(xy 61.828908 -272.928583) (xy 61.852251 -272.974395) (xy 61.868139 -273.023294) (xy 61.876182 -273.074076)
			(xy 61.876686 -273.099784) (xy 62.193944 -273.099784) (xy 62.197904 -273.05073) (xy 62.209681 -273.002946)
			(xy 62.228972 -272.95767) (xy 62.255275 -272.916074) (xy 62.28791 -272.879237) (xy 62.326031 -272.848112)
			(xy 62.368652 -272.823505) (xy 62.414668 -272.806053) (xy 62.462887 -272.796209) (xy 62.512062 -272.794228)
			(xy 62.560917 -272.80016) (xy 62.608188 -272.813852) (xy 62.65265 -272.83495) (xy 62.693153 -272.862906)
			(xy 62.728646 -272.896998) (xy 62.758211 -272.936342) (xy 62.781082 -272.979919) (xy 62.796666 -273.0266)
			(xy 62.804561 -273.075177) (xy 62.805056 -273.099784) (xy 62.804561 -273.124391) (xy 62.804382 -273.125492)
			(xy 63.12306 -273.125492) (xy 63.12306 -273.074076) (xy 63.131103 -273.023294) (xy 63.146991 -272.974395)
			(xy 63.170334 -272.928583) (xy 63.200555 -272.886987) (xy 63.236911 -272.850631) (xy 63.278507 -272.82041)
			(xy 63.324319 -272.797067) (xy 63.373218 -272.781179) (xy 63.424 -272.773136) (xy 63.475416 -272.773136)
			(xy 63.526198 -272.781179) (xy 63.575097 -272.797067) (xy 63.620909 -272.82041) (xy 63.662505 -272.850631)
			(xy 63.698861 -272.886987) (xy 63.729082 -272.928583) (xy 63.752425 -272.974395) (xy 63.768313 -273.023294)
			(xy 63.776356 -273.074076) (xy 63.77686 -273.099784) (xy 64.094118 -273.099784) (xy 64.098078 -273.05073)
			(xy 64.109855 -273.002946) (xy 64.129146 -272.95767) (xy 64.155449 -272.916074) (xy 64.188084 -272.879237)
			(xy 64.226205 -272.848112) (xy 64.268826 -272.823505) (xy 64.314842 -272.806053) (xy 64.363061 -272.796209)
			(xy 64.412236 -272.794228) (xy 64.461091 -272.80016) (xy 64.508362 -272.813852) (xy 64.552824 -272.83495)
			(xy 64.593327 -272.862906) (xy 64.62882 -272.896998) (xy 64.658385 -272.936342) (xy 64.681256 -272.979919)
			(xy 64.69684 -273.0266) (xy 64.704735 -273.075177) (xy 64.70523 -273.099784) (xy 64.704735 -273.124391)
			(xy 64.704556 -273.125492) (xy 65.02298 -273.125492) (xy 65.02298 -273.074076) (xy 65.031023 -273.023294)
			(xy 65.046911 -272.974395) (xy 65.070254 -272.928583) (xy 65.100475 -272.886987) (xy 65.136831 -272.850631)
			(xy 65.178427 -272.82041) (xy 65.224239 -272.797067) (xy 65.273138 -272.781179) (xy 65.32392 -272.773136)
			(xy 65.375336 -272.773136) (xy 65.426118 -272.781179) (xy 65.475017 -272.797067) (xy 65.520829 -272.82041)
			(xy 65.562425 -272.850631) (xy 65.598781 -272.886987) (xy 65.629002 -272.928583) (xy 65.652345 -272.974395)
			(xy 65.668233 -273.023294) (xy 65.676276 -273.074076) (xy 65.67678 -273.099784) (xy 65.994038 -273.099784)
			(xy 65.997998 -273.05073) (xy 66.009775 -273.002946) (xy 66.029066 -272.95767) (xy 66.055369 -272.916074)
			(xy 66.088004 -272.879237) (xy 66.126125 -272.848112) (xy 66.168746 -272.823505) (xy 66.214762 -272.806053)
			(xy 66.262981 -272.796209) (xy 66.312156 -272.794228) (xy 66.361011 -272.80016) (xy 66.408282 -272.813852)
			(xy 66.452744 -272.83495) (xy 66.493247 -272.862906) (xy 66.52874 -272.896998) (xy 66.558305 -272.936342)
			(xy 66.581176 -272.979919) (xy 66.59676 -273.0266) (xy 66.604655 -273.075177) (xy 66.60515 -273.099784)
			(xy 66.604655 -273.124391) (xy 66.604476 -273.125492) (xy 66.9229 -273.125492) (xy 66.9229 -273.074076)
			(xy 66.930943 -273.023294) (xy 66.946831 -272.974395) (xy 66.970174 -272.928583) (xy 67.000395 -272.886987)
			(xy 67.036751 -272.850631) (xy 67.078347 -272.82041) (xy 67.124159 -272.797067) (xy 67.173058 -272.781179)
			(xy 67.22384 -272.773136) (xy 67.275256 -272.773136) (xy 67.326038 -272.781179) (xy 67.374937 -272.797067)
			(xy 67.420749 -272.82041) (xy 67.462345 -272.850631) (xy 67.498701 -272.886987) (xy 67.528922 -272.928583)
			(xy 67.552265 -272.974395) (xy 67.568153 -273.023294) (xy 67.576196 -273.074076) (xy 67.5767 -273.099784)
			(xy 67.893958 -273.099784) (xy 67.897918 -273.05073) (xy 67.909695 -273.002946) (xy 67.928986 -272.95767)
			(xy 67.955289 -272.916074) (xy 67.987924 -272.879237) (xy 68.026045 -272.848112) (xy 68.068666 -272.823505)
			(xy 68.114682 -272.806053) (xy 68.162901 -272.796209) (xy 68.212076 -272.794228) (xy 68.260931 -272.80016)
			(xy 68.308202 -272.813852) (xy 68.352664 -272.83495) (xy 68.393167 -272.862906) (xy 68.42866 -272.896998)
			(xy 68.458225 -272.936342) (xy 68.481096 -272.979919) (xy 68.49668 -273.0266) (xy 68.504575 -273.075177)
			(xy 68.50507 -273.099784) (xy 68.504575 -273.124391) (xy 68.504396 -273.125492) (xy 68.823074 -273.125492)
			(xy 68.823074 -273.074076) (xy 68.831117 -273.023294) (xy 68.847005 -272.974395) (xy 68.870348 -272.928583)
			(xy 68.900569 -272.886987) (xy 68.936925 -272.850631) (xy 68.978521 -272.82041) (xy 69.024333 -272.797067)
			(xy 69.073232 -272.781179) (xy 69.124014 -272.773136) (xy 69.17543 -272.773136) (xy 69.226212 -272.781179)
			(xy 69.275111 -272.797067) (xy 69.320923 -272.82041) (xy 69.362519 -272.850631) (xy 69.398875 -272.886987)
			(xy 69.429096 -272.928583) (xy 69.452439 -272.974395) (xy 69.468327 -273.023294) (xy 69.47637 -273.074076)
			(xy 69.476874 -273.099784) (xy 69.794132 -273.099784) (xy 69.798092 -273.05073) (xy 69.809869 -273.002946)
			(xy 69.82916 -272.95767) (xy 69.855463 -272.916074) (xy 69.888098 -272.879237) (xy 69.926219 -272.848112)
			(xy 69.96884 -272.823505) (xy 70.014856 -272.806053) (xy 70.063075 -272.796209) (xy 70.11225 -272.794228)
			(xy 70.161105 -272.80016) (xy 70.208376 -272.813852) (xy 70.252838 -272.83495) (xy 70.293341 -272.862906)
			(xy 70.328834 -272.896998) (xy 70.358399 -272.936342) (xy 70.38127 -272.979919) (xy 70.396854 -273.0266)
			(xy 70.404749 -273.075177) (xy 70.405244 -273.099784) (xy 70.404749 -273.124391) (xy 70.40457 -273.125492)
			(xy 70.722994 -273.125492) (xy 70.722994 -273.074076) (xy 70.731037 -273.023294) (xy 70.746925 -272.974395)
			(xy 70.770268 -272.928583) (xy 70.800489 -272.886987) (xy 70.836845 -272.850631) (xy 70.878441 -272.82041)
			(xy 70.924253 -272.797067) (xy 70.973152 -272.781179) (xy 71.023934 -272.773136) (xy 71.07535 -272.773136)
			(xy 71.126132 -272.781179) (xy 71.175031 -272.797067) (xy 71.220843 -272.82041) (xy 71.262439 -272.850631)
			(xy 71.298795 -272.886987) (xy 71.329016 -272.928583) (xy 71.352359 -272.974395) (xy 71.368247 -273.023294)
			(xy 71.37629 -273.074076) (xy 71.376794 -273.099784) (xy 71.694052 -273.099784) (xy 71.698012 -273.05073)
			(xy 71.709789 -273.002946) (xy 71.72908 -272.95767) (xy 71.755383 -272.916074) (xy 71.788018 -272.879237)
			(xy 71.826139 -272.848112) (xy 71.86876 -272.823505) (xy 71.914776 -272.806053) (xy 71.962995 -272.796209)
			(xy 72.01217 -272.794228) (xy 72.061025 -272.80016) (xy 72.108296 -272.813852) (xy 72.152758 -272.83495)
			(xy 72.193261 -272.862906) (xy 72.228754 -272.896998) (xy 72.258319 -272.936342) (xy 72.28119 -272.979919)
			(xy 72.296774 -273.0266) (xy 72.304669 -273.075177) (xy 72.305164 -273.099784) (xy 72.304669 -273.124391)
			(xy 72.30449 -273.125492) (xy 72.622914 -273.125492) (xy 72.622914 -273.074076) (xy 72.630957 -273.023294)
			(xy 72.646845 -272.974395) (xy 72.670188 -272.928583) (xy 72.700409 -272.886987) (xy 72.736765 -272.850631)
			(xy 72.778361 -272.82041) (xy 72.824173 -272.797067) (xy 72.873072 -272.781179) (xy 72.923854 -272.773136)
			(xy 72.97527 -272.773136) (xy 73.026052 -272.781179) (xy 73.074951 -272.797067) (xy 73.120763 -272.82041)
			(xy 73.162359 -272.850631) (xy 73.198715 -272.886987) (xy 73.228936 -272.928583) (xy 73.252279 -272.974395)
			(xy 73.268167 -273.023294) (xy 73.27621 -273.074076) (xy 73.276714 -273.099784) (xy 73.593972 -273.099784)
			(xy 73.597932 -273.05073) (xy 73.609709 -273.002946) (xy 73.629 -272.95767) (xy 73.655303 -272.916074)
			(xy 73.687938 -272.879237) (xy 73.726059 -272.848112) (xy 73.76868 -272.823505) (xy 73.814696 -272.806053)
			(xy 73.862915 -272.796209) (xy 73.91209 -272.794228) (xy 73.960945 -272.80016) (xy 74.008216 -272.813852)
			(xy 74.052678 -272.83495) (xy 74.093181 -272.862906) (xy 74.128674 -272.896998) (xy 74.158239 -272.936342)
			(xy 74.18111 -272.979919) (xy 74.196694 -273.0266) (xy 74.204589 -273.075177) (xy 74.205084 -273.099784)
			(xy 74.204589 -273.124391) (xy 74.20441 -273.125492) (xy 74.523088 -273.125492) (xy 74.523088 -273.074076)
			(xy 74.531131 -273.023294) (xy 74.547019 -272.974395) (xy 74.570362 -272.928583) (xy 74.600583 -272.886987)
			(xy 74.636939 -272.850631) (xy 74.678535 -272.82041) (xy 74.724347 -272.797067) (xy 74.773246 -272.781179)
			(xy 74.824028 -272.773136) (xy 74.875444 -272.773136) (xy 74.926226 -272.781179) (xy 74.975125 -272.797067)
			(xy 75.020937 -272.82041) (xy 75.062533 -272.850631) (xy 75.098889 -272.886987) (xy 75.12911 -272.928583)
			(xy 75.152453 -272.974395) (xy 75.168341 -273.023294) (xy 75.176384 -273.074076) (xy 75.176888 -273.099784)
			(xy 75.494146 -273.099784) (xy 75.498106 -273.05073) (xy 75.509883 -273.002946) (xy 75.529174 -272.95767)
			(xy 75.555477 -272.916074) (xy 75.588112 -272.879237) (xy 75.626233 -272.848112) (xy 75.668854 -272.823505)
			(xy 75.71487 -272.806053) (xy 75.763089 -272.796209) (xy 75.812264 -272.794228) (xy 75.861119 -272.80016)
			(xy 75.90839 -272.813852) (xy 75.952852 -272.83495) (xy 75.993355 -272.862906) (xy 76.028848 -272.896998)
			(xy 76.058413 -272.936342) (xy 76.081284 -272.979919) (xy 76.096868 -273.0266) (xy 76.104763 -273.075177)
			(xy 76.105258 -273.099784) (xy 76.104763 -273.124391) (xy 76.104584 -273.125492) (xy 76.423008 -273.125492)
			(xy 76.423008 -273.074076) (xy 76.431051 -273.023294) (xy 76.446939 -272.974395) (xy 76.470282 -272.928583)
			(xy 76.500503 -272.886987) (xy 76.536859 -272.850631) (xy 76.578455 -272.82041) (xy 76.624267 -272.797067)
			(xy 76.673166 -272.781179) (xy 76.723948 -272.773136) (xy 76.775364 -272.773136) (xy 76.826146 -272.781179)
			(xy 76.875045 -272.797067) (xy 76.920857 -272.82041) (xy 76.962453 -272.850631) (xy 76.998809 -272.886987)
			(xy 77.02903 -272.928583) (xy 77.052373 -272.974395) (xy 77.068261 -273.023294) (xy 77.076304 -273.074076)
			(xy 77.076808 -273.099784) (xy 77.39432 -273.099784) (xy 77.39828 -273.05073) (xy 77.410057 -273.002946)
			(xy 77.429348 -272.95767) (xy 77.455651 -272.916074) (xy 77.488286 -272.879237) (xy 77.526407 -272.848112)
			(xy 77.569028 -272.823505) (xy 77.615044 -272.806053) (xy 77.663263 -272.796209) (xy 77.712438 -272.794228)
			(xy 77.761293 -272.80016) (xy 77.808564 -272.813852) (xy 77.853026 -272.83495) (xy 77.893529 -272.862906)
			(xy 77.929022 -272.896998) (xy 77.958587 -272.936342) (xy 77.981458 -272.979919) (xy 77.997042 -273.0266)
			(xy 78.004937 -273.075177) (xy 78.005432 -273.099784) (xy 78.004937 -273.124391) (xy 78.004758 -273.125492)
			(xy 78.322928 -273.125492) (xy 78.322928 -273.074076) (xy 78.330971 -273.023294) (xy 78.346859 -272.974395)
			(xy 78.370202 -272.928583) (xy 78.400423 -272.886987) (xy 78.436779 -272.850631) (xy 78.478375 -272.82041)
			(xy 78.524187 -272.797067) (xy 78.573086 -272.781179) (xy 78.623868 -272.773136) (xy 78.675284 -272.773136)
			(xy 78.726066 -272.781179) (xy 78.774965 -272.797067) (xy 78.820777 -272.82041) (xy 78.862373 -272.850631)
			(xy 78.898729 -272.886987) (xy 78.92895 -272.928583) (xy 78.952293 -272.974395) (xy 78.968181 -273.023294)
			(xy 78.976224 -273.074076) (xy 78.976728 -273.099784) (xy 79.29424 -273.099784) (xy 79.2982 -273.05073)
			(xy 79.309977 -273.002946) (xy 79.329268 -272.95767) (xy 79.355571 -272.916074) (xy 79.388206 -272.879237)
			(xy 79.426327 -272.848112) (xy 79.468948 -272.823505) (xy 79.514964 -272.806053) (xy 79.563183 -272.796209)
			(xy 79.612358 -272.794228) (xy 79.661213 -272.80016) (xy 79.708484 -272.813852) (xy 79.752946 -272.83495)
			(xy 79.793449 -272.862906) (xy 79.828942 -272.896998) (xy 79.858507 -272.936342) (xy 79.881378 -272.979919)
			(xy 79.896962 -273.0266) (xy 79.904857 -273.075177) (xy 79.905352 -273.099784) (xy 79.904857 -273.124391)
			(xy 79.904678 -273.125492) (xy 80.222848 -273.125492) (xy 80.222848 -273.074076) (xy 80.230891 -273.023294)
			(xy 80.246779 -272.974395) (xy 80.270122 -272.928583) (xy 80.300343 -272.886987) (xy 80.336699 -272.850631)
			(xy 80.378295 -272.82041) (xy 80.424107 -272.797067) (xy 80.473006 -272.781179) (xy 80.523788 -272.773136)
			(xy 80.575204 -272.773136) (xy 80.625986 -272.781179) (xy 80.674885 -272.797067) (xy 80.720697 -272.82041)
			(xy 80.762293 -272.850631) (xy 80.798649 -272.886987) (xy 80.82887 -272.928583) (xy 80.852213 -272.974395)
			(xy 80.868101 -273.023294) (xy 80.876144 -273.074076) (xy 80.876648 -273.099784) (xy 81.19416 -273.099784)
			(xy 81.19812 -273.05073) (xy 81.209897 -273.002946) (xy 81.229188 -272.95767) (xy 81.255491 -272.916074)
			(xy 81.288126 -272.879237) (xy 81.326247 -272.848112) (xy 81.368868 -272.823505) (xy 81.414884 -272.806053)
			(xy 81.463103 -272.796209) (xy 81.512278 -272.794228) (xy 81.561133 -272.80016) (xy 81.608404 -272.813852)
			(xy 81.652866 -272.83495) (xy 81.693369 -272.862906) (xy 81.728862 -272.896998) (xy 81.758427 -272.936342)
			(xy 81.781298 -272.979919) (xy 81.796882 -273.0266) (xy 81.804777 -273.075177) (xy 81.805272 -273.099784)
			(xy 81.804777 -273.124391) (xy 81.796882 -273.172968) (xy 81.781298 -273.219649) (xy 81.758427 -273.263226)
			(xy 81.728862 -273.30257) (xy 81.693369 -273.336662) (xy 81.652866 -273.364618) (xy 81.608404 -273.385716)
			(xy 81.561133 -273.399408) (xy 81.512278 -273.40534) (xy 81.463103 -273.403359) (xy 81.414884 -273.393515)
			(xy 81.368868 -273.376063) (xy 81.326247 -273.351456) (xy 81.288126 -273.320331) (xy 81.255491 -273.283494)
			(xy 81.229188 -273.241898) (xy 81.209897 -273.196622) (xy 81.19812 -273.148838) (xy 81.19416 -273.099784)
			(xy 80.876648 -273.099784) (xy 80.876144 -273.125492) (xy 80.868101 -273.176274) (xy 80.852213 -273.225173)
			(xy 80.82887 -273.270985) (xy 80.798649 -273.312581) (xy 80.762293 -273.348937) (xy 80.720697 -273.379158)
			(xy 80.674885 -273.402501) (xy 80.625986 -273.418389) (xy 80.575204 -273.426432) (xy 80.523788 -273.426432)
			(xy 80.473006 -273.418389) (xy 80.424107 -273.402501) (xy 80.378295 -273.379158) (xy 80.336699 -273.348937)
			(xy 80.300343 -273.312581) (xy 80.270122 -273.270985) (xy 80.246779 -273.225173) (xy 80.230891 -273.176274)
			(xy 80.222848 -273.125492) (xy 79.904678 -273.125492) (xy 79.896962 -273.172968) (xy 79.881378 -273.219649)
			(xy 79.858507 -273.263226) (xy 79.828942 -273.30257) (xy 79.793449 -273.336662) (xy 79.752946 -273.364618)
			(xy 79.708484 -273.385716) (xy 79.661213 -273.399408) (xy 79.612358 -273.40534) (xy 79.563183 -273.403359)
			(xy 79.514964 -273.393515) (xy 79.468948 -273.376063) (xy 79.426327 -273.351456) (xy 79.388206 -273.320331)
			(xy 79.355571 -273.283494) (xy 79.329268 -273.241898) (xy 79.309977 -273.196622) (xy 79.2982 -273.148838)
			(xy 79.29424 -273.099784) (xy 78.976728 -273.099784) (xy 78.976224 -273.125492) (xy 78.968181 -273.176274)
			(xy 78.952293 -273.225173) (xy 78.92895 -273.270985) (xy 78.898729 -273.312581) (xy 78.862373 -273.348937)
			(xy 78.820777 -273.379158) (xy 78.774965 -273.402501) (xy 78.726066 -273.418389) (xy 78.675284 -273.426432)
			(xy 78.623868 -273.426432) (xy 78.573086 -273.418389) (xy 78.524187 -273.402501) (xy 78.478375 -273.379158)
			(xy 78.436779 -273.348937) (xy 78.400423 -273.312581) (xy 78.370202 -273.270985) (xy 78.346859 -273.225173)
			(xy 78.330971 -273.176274) (xy 78.322928 -273.125492) (xy 78.004758 -273.125492) (xy 77.997042 -273.172968)
			(xy 77.981458 -273.219649) (xy 77.958587 -273.263226) (xy 77.929022 -273.30257) (xy 77.893529 -273.336662)
			(xy 77.853026 -273.364618) (xy 77.808564 -273.385716) (xy 77.761293 -273.399408) (xy 77.712438 -273.40534)
			(xy 77.663263 -273.403359) (xy 77.615044 -273.393515) (xy 77.569028 -273.376063) (xy 77.526407 -273.351456)
			(xy 77.488286 -273.320331) (xy 77.455651 -273.283494) (xy 77.429348 -273.241898) (xy 77.410057 -273.196622)
			(xy 77.39828 -273.148838) (xy 77.39432 -273.099784) (xy 77.076808 -273.099784) (xy 77.076304 -273.125492)
			(xy 77.068261 -273.176274) (xy 77.052373 -273.225173) (xy 77.02903 -273.270985) (xy 76.998809 -273.312581)
			(xy 76.962453 -273.348937) (xy 76.920857 -273.379158) (xy 76.875045 -273.402501) (xy 76.826146 -273.418389)
			(xy 76.775364 -273.426432) (xy 76.723948 -273.426432) (xy 76.673166 -273.418389) (xy 76.624267 -273.402501)
			(xy 76.578455 -273.379158) (xy 76.536859 -273.348937) (xy 76.500503 -273.312581) (xy 76.470282 -273.270985)
			(xy 76.446939 -273.225173) (xy 76.431051 -273.176274) (xy 76.423008 -273.125492) (xy 76.104584 -273.125492)
			(xy 76.096868 -273.172968) (xy 76.081284 -273.219649) (xy 76.058413 -273.263226) (xy 76.028848 -273.30257)
			(xy 75.993355 -273.336662) (xy 75.952852 -273.364618) (xy 75.90839 -273.385716) (xy 75.861119 -273.399408)
			(xy 75.812264 -273.40534) (xy 75.763089 -273.403359) (xy 75.71487 -273.393515) (xy 75.668854 -273.376063)
			(xy 75.626233 -273.351456) (xy 75.588112 -273.320331) (xy 75.555477 -273.283494) (xy 75.529174 -273.241898)
			(xy 75.509883 -273.196622) (xy 75.498106 -273.148838) (xy 75.494146 -273.099784) (xy 75.176888 -273.099784)
			(xy 75.176384 -273.125492) (xy 75.168341 -273.176274) (xy 75.152453 -273.225173) (xy 75.12911 -273.270985)
			(xy 75.098889 -273.312581) (xy 75.062533 -273.348937) (xy 75.020937 -273.379158) (xy 74.975125 -273.402501)
			(xy 74.926226 -273.418389) (xy 74.875444 -273.426432) (xy 74.824028 -273.426432) (xy 74.773246 -273.418389)
			(xy 74.724347 -273.402501) (xy 74.678535 -273.379158) (xy 74.636939 -273.348937) (xy 74.600583 -273.312581)
			(xy 74.570362 -273.270985) (xy 74.547019 -273.225173) (xy 74.531131 -273.176274) (xy 74.523088 -273.125492)
			(xy 74.20441 -273.125492) (xy 74.196694 -273.172968) (xy 74.18111 -273.219649) (xy 74.158239 -273.263226)
			(xy 74.128674 -273.30257) (xy 74.093181 -273.336662) (xy 74.052678 -273.364618) (xy 74.008216 -273.385716)
			(xy 73.960945 -273.399408) (xy 73.91209 -273.40534) (xy 73.862915 -273.403359) (xy 73.814696 -273.393515)
			(xy 73.76868 -273.376063) (xy 73.726059 -273.351456) (xy 73.687938 -273.320331) (xy 73.655303 -273.283494)
			(xy 73.629 -273.241898) (xy 73.609709 -273.196622) (xy 73.597932 -273.148838) (xy 73.593972 -273.099784)
			(xy 73.276714 -273.099784) (xy 73.27621 -273.125492) (xy 73.268167 -273.176274) (xy 73.252279 -273.225173)
			(xy 73.228936 -273.270985) (xy 73.198715 -273.312581) (xy 73.162359 -273.348937) (xy 73.120763 -273.379158)
			(xy 73.074951 -273.402501) (xy 73.026052 -273.418389) (xy 72.97527 -273.426432) (xy 72.923854 -273.426432)
			(xy 72.873072 -273.418389) (xy 72.824173 -273.402501) (xy 72.778361 -273.379158) (xy 72.736765 -273.348937)
			(xy 72.700409 -273.312581) (xy 72.670188 -273.270985) (xy 72.646845 -273.225173) (xy 72.630957 -273.176274)
			(xy 72.622914 -273.125492) (xy 72.30449 -273.125492) (xy 72.296774 -273.172968) (xy 72.28119 -273.219649)
			(xy 72.258319 -273.263226) (xy 72.228754 -273.30257) (xy 72.193261 -273.336662) (xy 72.152758 -273.364618)
			(xy 72.108296 -273.385716) (xy 72.061025 -273.399408) (xy 72.01217 -273.40534) (xy 71.962995 -273.403359)
			(xy 71.914776 -273.393515) (xy 71.86876 -273.376063) (xy 71.826139 -273.351456) (xy 71.788018 -273.320331)
			(xy 71.755383 -273.283494) (xy 71.72908 -273.241898) (xy 71.709789 -273.196622) (xy 71.698012 -273.148838)
			(xy 71.694052 -273.099784) (xy 71.376794 -273.099784) (xy 71.37629 -273.125492) (xy 71.368247 -273.176274)
			(xy 71.352359 -273.225173) (xy 71.329016 -273.270985) (xy 71.298795 -273.312581) (xy 71.262439 -273.348937)
			(xy 71.220843 -273.379158) (xy 71.175031 -273.402501) (xy 71.126132 -273.418389) (xy 71.07535 -273.426432)
			(xy 71.023934 -273.426432) (xy 70.973152 -273.418389) (xy 70.924253 -273.402501) (xy 70.878441 -273.379158)
			(xy 70.836845 -273.348937) (xy 70.800489 -273.312581) (xy 70.770268 -273.270985) (xy 70.746925 -273.225173)
			(xy 70.731037 -273.176274) (xy 70.722994 -273.125492) (xy 70.40457 -273.125492) (xy 70.396854 -273.172968)
			(xy 70.38127 -273.219649) (xy 70.358399 -273.263226) (xy 70.328834 -273.30257) (xy 70.293341 -273.336662)
			(xy 70.252838 -273.364618) (xy 70.208376 -273.385716) (xy 70.161105 -273.399408) (xy 70.11225 -273.40534)
			(xy 70.063075 -273.403359) (xy 70.014856 -273.393515) (xy 69.96884 -273.376063) (xy 69.926219 -273.351456)
			(xy 69.888098 -273.320331) (xy 69.855463 -273.283494) (xy 69.82916 -273.241898) (xy 69.809869 -273.196622)
			(xy 69.798092 -273.148838) (xy 69.794132 -273.099784) (xy 69.476874 -273.099784) (xy 69.47637 -273.125492)
			(xy 69.468327 -273.176274) (xy 69.452439 -273.225173) (xy 69.429096 -273.270985) (xy 69.398875 -273.312581)
			(xy 69.362519 -273.348937) (xy 69.320923 -273.379158) (xy 69.275111 -273.402501) (xy 69.226212 -273.418389)
			(xy 69.17543 -273.426432) (xy 69.124014 -273.426432) (xy 69.073232 -273.418389) (xy 69.024333 -273.402501)
			(xy 68.978521 -273.379158) (xy 68.936925 -273.348937) (xy 68.900569 -273.312581) (xy 68.870348 -273.270985)
			(xy 68.847005 -273.225173) (xy 68.831117 -273.176274) (xy 68.823074 -273.125492) (xy 68.504396 -273.125492)
			(xy 68.49668 -273.172968) (xy 68.481096 -273.219649) (xy 68.458225 -273.263226) (xy 68.42866 -273.30257)
			(xy 68.393167 -273.336662) (xy 68.352664 -273.364618) (xy 68.308202 -273.385716) (xy 68.260931 -273.399408)
			(xy 68.212076 -273.40534) (xy 68.162901 -273.403359) (xy 68.114682 -273.393515) (xy 68.068666 -273.376063)
			(xy 68.026045 -273.351456) (xy 67.987924 -273.320331) (xy 67.955289 -273.283494) (xy 67.928986 -273.241898)
			(xy 67.909695 -273.196622) (xy 67.897918 -273.148838) (xy 67.893958 -273.099784) (xy 67.5767 -273.099784)
			(xy 67.576196 -273.125492) (xy 67.568153 -273.176274) (xy 67.552265 -273.225173) (xy 67.528922 -273.270985)
			(xy 67.498701 -273.312581) (xy 67.462345 -273.348937) (xy 67.420749 -273.379158) (xy 67.374937 -273.402501)
			(xy 67.326038 -273.418389) (xy 67.275256 -273.426432) (xy 67.22384 -273.426432) (xy 67.173058 -273.418389)
			(xy 67.124159 -273.402501) (xy 67.078347 -273.379158) (xy 67.036751 -273.348937) (xy 67.000395 -273.312581)
			(xy 66.970174 -273.270985) (xy 66.946831 -273.225173) (xy 66.930943 -273.176274) (xy 66.9229 -273.125492)
			(xy 66.604476 -273.125492) (xy 66.59676 -273.172968) (xy 66.581176 -273.219649) (xy 66.558305 -273.263226)
			(xy 66.52874 -273.30257) (xy 66.493247 -273.336662) (xy 66.452744 -273.364618) (xy 66.408282 -273.385716)
			(xy 66.361011 -273.399408) (xy 66.312156 -273.40534) (xy 66.262981 -273.403359) (xy 66.214762 -273.393515)
			(xy 66.168746 -273.376063) (xy 66.126125 -273.351456) (xy 66.088004 -273.320331) (xy 66.055369 -273.283494)
			(xy 66.029066 -273.241898) (xy 66.009775 -273.196622) (xy 65.997998 -273.148838) (xy 65.994038 -273.099784)
			(xy 65.67678 -273.099784) (xy 65.676276 -273.125492) (xy 65.668233 -273.176274) (xy 65.652345 -273.225173)
			(xy 65.629002 -273.270985) (xy 65.598781 -273.312581) (xy 65.562425 -273.348937) (xy 65.520829 -273.379158)
			(xy 65.475017 -273.402501) (xy 65.426118 -273.418389) (xy 65.375336 -273.426432) (xy 65.32392 -273.426432)
			(xy 65.273138 -273.418389) (xy 65.224239 -273.402501) (xy 65.178427 -273.379158) (xy 65.136831 -273.348937)
			(xy 65.100475 -273.312581) (xy 65.070254 -273.270985) (xy 65.046911 -273.225173) (xy 65.031023 -273.176274)
			(xy 65.02298 -273.125492) (xy 64.704556 -273.125492) (xy 64.69684 -273.172968) (xy 64.681256 -273.219649)
			(xy 64.658385 -273.263226) (xy 64.62882 -273.30257) (xy 64.593327 -273.336662) (xy 64.552824 -273.364618)
			(xy 64.508362 -273.385716) (xy 64.461091 -273.399408) (xy 64.412236 -273.40534) (xy 64.363061 -273.403359)
			(xy 64.314842 -273.393515) (xy 64.268826 -273.376063) (xy 64.226205 -273.351456) (xy 64.188084 -273.320331)
			(xy 64.155449 -273.283494) (xy 64.129146 -273.241898) (xy 64.109855 -273.196622) (xy 64.098078 -273.148838)
			(xy 64.094118 -273.099784) (xy 63.77686 -273.099784) (xy 63.776356 -273.125492) (xy 63.768313 -273.176274)
			(xy 63.752425 -273.225173) (xy 63.729082 -273.270985) (xy 63.698861 -273.312581) (xy 63.662505 -273.348937)
			(xy 63.620909 -273.379158) (xy 63.575097 -273.402501) (xy 63.526198 -273.418389) (xy 63.475416 -273.426432)
			(xy 63.424 -273.426432) (xy 63.373218 -273.418389) (xy 63.324319 -273.402501) (xy 63.278507 -273.379158)
			(xy 63.236911 -273.348937) (xy 63.200555 -273.312581) (xy 63.170334 -273.270985) (xy 63.146991 -273.225173)
			(xy 63.131103 -273.176274) (xy 63.12306 -273.125492) (xy 62.804382 -273.125492) (xy 62.796666 -273.172968)
			(xy 62.781082 -273.219649) (xy 62.758211 -273.263226) (xy 62.728646 -273.30257) (xy 62.693153 -273.336662)
			(xy 62.65265 -273.364618) (xy 62.608188 -273.385716) (xy 62.560917 -273.399408) (xy 62.512062 -273.40534)
			(xy 62.462887 -273.403359) (xy 62.414668 -273.393515) (xy 62.368652 -273.376063) (xy 62.326031 -273.351456)
			(xy 62.28791 -273.320331) (xy 62.255275 -273.283494) (xy 62.228972 -273.241898) (xy 62.209681 -273.196622)
			(xy 62.197904 -273.148838) (xy 62.193944 -273.099784) (xy 61.876686 -273.099784) (xy 61.876182 -273.125492)
			(xy 61.868139 -273.176274) (xy 61.852251 -273.225173) (xy 61.828908 -273.270985) (xy 61.798687 -273.312581)
			(xy 61.762331 -273.348937) (xy 61.720735 -273.379158) (xy 61.674923 -273.402501) (xy 61.626024 -273.418389)
			(xy 61.575242 -273.426432) (xy 61.523826 -273.426432) (xy 61.473044 -273.418389) (xy 61.424145 -273.402501)
			(xy 61.378333 -273.379158) (xy 61.336737 -273.348937) (xy 61.300381 -273.312581) (xy 61.27016 -273.270985)
			(xy 61.246817 -273.225173) (xy 61.230929 -273.176274) (xy 61.222886 -273.125492) (xy 60.904462 -273.125492)
			(xy 60.896746 -273.172968) (xy 60.881162 -273.219649) (xy 60.858291 -273.263226) (xy 60.828726 -273.30257)
			(xy 60.793233 -273.336662) (xy 60.75273 -273.364618) (xy 60.708268 -273.385716) (xy 60.660997 -273.399408)
			(xy 60.612142 -273.40534) (xy 60.562967 -273.403359) (xy 60.514748 -273.393515) (xy 60.468732 -273.376063)
			(xy 60.426111 -273.351456) (xy 60.38799 -273.320331) (xy 60.355355 -273.283494) (xy 60.329052 -273.241898)
			(xy 60.309761 -273.196622) (xy 60.297984 -273.148838) (xy 60.294024 -273.099784) (xy 59.976761 -273.099784)
			(xy 59.976262 -273.125238) (xy 59.968219 -273.17602) (xy 59.952331 -273.224919) (xy 59.928988 -273.270731)
			(xy 59.898767 -273.312327) (xy 59.862411 -273.348683) (xy 59.820815 -273.378904) (xy 59.775003 -273.402247)
			(xy 59.726104 -273.418135) (xy 59.675322 -273.426178) (xy 59.623906 -273.426178) (xy 59.573124 -273.418135)
			(xy 59.524225 -273.402247) (xy 59.478413 -273.378904) (xy 59.436817 -273.348683) (xy 59.400461 -273.312327)
			(xy 59.37024 -273.270731) (xy 59.346897 -273.224919) (xy 59.331009 -273.17602) (xy 59.322966 -273.125238)
			(xy 59.004583 -273.125238) (xy 58.996826 -273.172968) (xy 58.981242 -273.219649) (xy 58.958371 -273.263226)
			(xy 58.928806 -273.30257) (xy 58.893313 -273.336662) (xy 58.85281 -273.364618) (xy 58.808348 -273.385716)
			(xy 58.761077 -273.399408) (xy 58.712222 -273.40534) (xy 58.663047 -273.403359) (xy 58.614828 -273.393515)
			(xy 58.568812 -273.376063) (xy 58.526191 -273.351456) (xy 58.48807 -273.320331) (xy 58.455435 -273.283494)
			(xy 58.429132 -273.241898) (xy 58.409841 -273.196622) (xy 58.398064 -273.148838) (xy 58.394104 -273.099784)
			(xy 58.0771 -273.099784) (xy 58.076596 -273.125492) (xy 58.068553 -273.176274) (xy 58.052665 -273.225173)
			(xy 58.029322 -273.270985) (xy 57.999101 -273.312581) (xy 57.962745 -273.348937) (xy 57.921149 -273.379158)
			(xy 57.875337 -273.402501) (xy 57.826438 -273.418389) (xy 57.775656 -273.426432) (xy 57.72424 -273.426432)
			(xy 57.673458 -273.418389) (xy 57.624559 -273.402501) (xy 57.578747 -273.379158) (xy 57.537151 -273.348937)
			(xy 57.500795 -273.312581) (xy 57.470574 -273.270985) (xy 57.447231 -273.225173) (xy 57.431343 -273.176274)
			(xy 57.4233 -273.125492) (xy 57.104622 -273.125492) (xy 57.096906 -273.172968) (xy 57.081322 -273.219649)
			(xy 57.058451 -273.263226) (xy 57.028886 -273.30257) (xy 56.993393 -273.336662) (xy 56.95289 -273.364618)
			(xy 56.908428 -273.385716) (xy 56.861157 -273.399408) (xy 56.812302 -273.40534) (xy 56.763127 -273.403359)
			(xy 56.714908 -273.393515) (xy 56.668892 -273.376063) (xy 56.626271 -273.351456) (xy 56.58815 -273.320331)
			(xy 56.555515 -273.283494) (xy 56.529212 -273.241898) (xy 56.509921 -273.196622) (xy 56.498144 -273.148838)
			(xy 56.494184 -273.099784) (xy 56.176926 -273.099784) (xy 56.176422 -273.125492) (xy 56.168379 -273.176274)
			(xy 56.152491 -273.225173) (xy 56.129148 -273.270985) (xy 56.098927 -273.312581) (xy 56.062571 -273.348937)
			(xy 56.020975 -273.379158) (xy 55.975163 -273.402501) (xy 55.926264 -273.418389) (xy 55.875482 -273.426432)
			(xy 55.824066 -273.426432) (xy 55.773284 -273.418389) (xy 55.724385 -273.402501) (xy 55.678573 -273.379158)
			(xy 55.636977 -273.348937) (xy 55.600621 -273.312581) (xy 55.5704 -273.270985) (xy 55.547057 -273.225173)
			(xy 55.531169 -273.176274) (xy 55.523126 -273.125492) (xy 55.204448 -273.125492) (xy 55.196732 -273.172968)
			(xy 55.181148 -273.219649) (xy 55.158277 -273.263226) (xy 55.128712 -273.30257) (xy 55.093219 -273.336662)
			(xy 55.052716 -273.364618) (xy 55.008254 -273.385716) (xy 54.960983 -273.399408) (xy 54.912128 -273.40534)
			(xy 54.862953 -273.403359) (xy 54.814734 -273.393515) (xy 54.768718 -273.376063) (xy 54.726097 -273.351456)
			(xy 54.687976 -273.320331) (xy 54.655341 -273.283494) (xy 54.629038 -273.241898) (xy 54.609747 -273.196622)
			(xy 54.59797 -273.148838) (xy 54.59401 -273.099784) (xy 54.277006 -273.099784) (xy 54.276502 -273.125492)
			(xy 54.268459 -273.176274) (xy 54.252571 -273.225173) (xy 54.229228 -273.270985) (xy 54.199007 -273.312581)
			(xy 54.162651 -273.348937) (xy 54.121055 -273.379158) (xy 54.075243 -273.402501) (xy 54.026344 -273.418389)
			(xy 53.975562 -273.426432) (xy 53.924146 -273.426432) (xy 53.873364 -273.418389) (xy 53.824465 -273.402501)
			(xy 53.778653 -273.379158) (xy 53.737057 -273.348937) (xy 53.700701 -273.312581) (xy 53.67048 -273.270985)
			(xy 53.647137 -273.225173) (xy 53.631249 -273.176274) (xy 53.623206 -273.125492) (xy 53.304528 -273.125492)
			(xy 53.296812 -273.172968) (xy 53.281228 -273.219649) (xy 53.258357 -273.263226) (xy 53.228792 -273.30257)
			(xy 53.193299 -273.336662) (xy 53.152796 -273.364618) (xy 53.108334 -273.385716) (xy 53.061063 -273.399408)
			(xy 53.012208 -273.40534) (xy 52.963033 -273.403359) (xy 52.914814 -273.393515) (xy 52.868798 -273.376063)
			(xy 52.826177 -273.351456) (xy 52.788056 -273.320331) (xy 52.755421 -273.283494) (xy 52.729118 -273.241898)
			(xy 52.709827 -273.196622) (xy 52.69805 -273.148838) (xy 52.69409 -273.099784) (xy 52.377086 -273.099784)
			(xy 52.376582 -273.125492) (xy 52.368539 -273.176274) (xy 52.352651 -273.225173) (xy 52.329308 -273.270985)
			(xy 52.299087 -273.312581) (xy 52.262731 -273.348937) (xy 52.221135 -273.379158) (xy 52.175323 -273.402501)
			(xy 52.126424 -273.418389) (xy 52.075642 -273.426432) (xy 52.024226 -273.426432) (xy 51.973444 -273.418389)
			(xy 51.924545 -273.402501) (xy 51.878733 -273.379158) (xy 51.837137 -273.348937) (xy 51.800781 -273.312581)
			(xy 51.77056 -273.270985) (xy 51.747217 -273.225173) (xy 51.731329 -273.176274) (xy 51.723286 -273.125492)
			(xy 51.404608 -273.125492) (xy 51.396892 -273.172968) (xy 51.381308 -273.219649) (xy 51.358437 -273.263226)
			(xy 51.328872 -273.30257) (xy 51.293379 -273.336662) (xy 51.252876 -273.364618) (xy 51.208414 -273.385716)
			(xy 51.161143 -273.399408) (xy 51.112288 -273.40534) (xy 51.063113 -273.403359) (xy 51.014894 -273.393515)
			(xy 50.968878 -273.376063) (xy 50.926257 -273.351456) (xy 50.888136 -273.320331) (xy 50.855501 -273.283494)
			(xy 50.829198 -273.241898) (xy 50.809907 -273.196622) (xy 50.79813 -273.148838) (xy 50.79417 -273.099784)
			(xy 50.476912 -273.099784) (xy 50.476408 -273.125492) (xy 50.468365 -273.176274) (xy 50.452477 -273.225173)
			(xy 50.429134 -273.270985) (xy 50.398913 -273.312581) (xy 50.362557 -273.348937) (xy 50.320961 -273.379158)
			(xy 50.275149 -273.402501) (xy 50.22625 -273.418389) (xy 50.175468 -273.426432) (xy 50.124052 -273.426432)
			(xy 50.07327 -273.418389) (xy 50.024371 -273.402501) (xy 49.978559 -273.379158) (xy 49.936963 -273.348937)
			(xy 49.900607 -273.312581) (xy 49.870386 -273.270985) (xy 49.847043 -273.225173) (xy 49.831155 -273.176274)
			(xy 49.823112 -273.125492) (xy 49.504434 -273.125492) (xy 49.496718 -273.172968) (xy 49.481134 -273.219649)
			(xy 49.458263 -273.263226) (xy 49.428698 -273.30257) (xy 49.393205 -273.336662) (xy 49.352702 -273.364618)
			(xy 49.30824 -273.385716) (xy 49.260969 -273.399408) (xy 49.212114 -273.40534) (xy 49.162939 -273.403359)
			(xy 49.11472 -273.393515) (xy 49.068704 -273.376063) (xy 49.026083 -273.351456) (xy 48.987962 -273.320331)
			(xy 48.955327 -273.283494) (xy 48.929024 -273.241898) (xy 48.909733 -273.196622) (xy 48.897956 -273.148838)
			(xy 48.893996 -273.099784) (xy 48.576992 -273.099784) (xy 48.576488 -273.125492) (xy 48.568445 -273.176274)
			(xy 48.552557 -273.225173) (xy 48.529214 -273.270985) (xy 48.498993 -273.312581) (xy 48.462637 -273.348937)
			(xy 48.421041 -273.379158) (xy 48.375229 -273.402501) (xy 48.32633 -273.418389) (xy 48.275548 -273.426432)
			(xy 48.224132 -273.426432) (xy 48.17335 -273.418389) (xy 48.124451 -273.402501) (xy 48.078639 -273.379158)
			(xy 48.037043 -273.348937) (xy 48.000687 -273.312581) (xy 47.970466 -273.270985) (xy 47.947123 -273.225173)
			(xy 47.931235 -273.176274) (xy 47.923192 -273.125492) (xy 47.604514 -273.125492) (xy 47.596798 -273.172968)
			(xy 47.581214 -273.219649) (xy 47.558343 -273.263226) (xy 47.528778 -273.30257) (xy 47.493285 -273.336662)
			(xy 47.452782 -273.364618) (xy 47.40832 -273.385716) (xy 47.361049 -273.399408) (xy 47.312194 -273.40534)
			(xy 47.263019 -273.403359) (xy 47.2148 -273.393515) (xy 47.168784 -273.376063) (xy 47.126163 -273.351456)
			(xy 47.088042 -273.320331) (xy 47.055407 -273.283494) (xy 47.029104 -273.241898) (xy 47.009813 -273.196622)
			(xy 46.998036 -273.148838) (xy 46.994076 -273.099784) (xy 46.677072 -273.099784) (xy 46.676568 -273.125492)
			(xy 46.668525 -273.176274) (xy 46.652637 -273.225173) (xy 46.629294 -273.270985) (xy 46.599073 -273.312581)
			(xy 46.562717 -273.348937) (xy 46.521121 -273.379158) (xy 46.475309 -273.402501) (xy 46.42641 -273.418389)
			(xy 46.375628 -273.426432) (xy 46.324212 -273.426432) (xy 46.27343 -273.418389) (xy 46.224531 -273.402501)
			(xy 46.178719 -273.379158) (xy 46.137123 -273.348937) (xy 46.100767 -273.312581) (xy 46.070546 -273.270985)
			(xy 46.047203 -273.225173) (xy 46.031315 -273.176274) (xy 46.023272 -273.125492) (xy 45.704594 -273.125492)
			(xy 45.696878 -273.172968) (xy 45.681294 -273.219649) (xy 45.658423 -273.263226) (xy 45.628858 -273.30257)
			(xy 45.593365 -273.336662) (xy 45.552862 -273.364618) (xy 45.5084 -273.385716) (xy 45.461129 -273.399408)
			(xy 45.412274 -273.40534) (xy 45.363099 -273.403359) (xy 45.31488 -273.393515) (xy 45.268864 -273.376063)
			(xy 45.226243 -273.351456) (xy 45.188122 -273.320331) (xy 45.155487 -273.283494) (xy 45.129184 -273.241898)
			(xy 45.109893 -273.196622) (xy 45.098116 -273.148838) (xy 45.094156 -273.099784) (xy 44.776898 -273.099784)
			(xy 44.776394 -273.125492) (xy 44.768351 -273.176274) (xy 44.752463 -273.225173) (xy 44.72912 -273.270985)
			(xy 44.698899 -273.312581) (xy 44.662543 -273.348937) (xy 44.620947 -273.379158) (xy 44.575135 -273.402501)
			(xy 44.526236 -273.418389) (xy 44.475454 -273.426432) (xy 44.424038 -273.426432) (xy 44.373256 -273.418389)
			(xy 44.324357 -273.402501) (xy 44.278545 -273.379158) (xy 44.236949 -273.348937) (xy 44.200593 -273.312581)
			(xy 44.170372 -273.270985) (xy 44.147029 -273.225173) (xy 44.131141 -273.176274) (xy 44.123098 -273.125492)
			(xy 43.80442 -273.125492) (xy 43.796704 -273.172968) (xy 43.78112 -273.219649) (xy 43.758249 -273.263226)
			(xy 43.728684 -273.30257) (xy 43.693191 -273.336662) (xy 43.652688 -273.364618) (xy 43.608226 -273.385716)
			(xy 43.560955 -273.399408) (xy 43.5121 -273.40534) (xy 43.462925 -273.403359) (xy 43.414706 -273.393515)
			(xy 43.36869 -273.376063) (xy 43.326069 -273.351456) (xy 43.287948 -273.320331) (xy 43.255313 -273.283494)
			(xy 43.22901 -273.241898) (xy 43.209719 -273.196622) (xy 43.197942 -273.148838) (xy 43.193982 -273.099784)
			(xy 40.899334 -273.099784) (xy 40.899334 -273.18716) (xy 40.900012 -273.19918) (xy 40.91089 -273.220624)
			(xy 40.920162 -273.228308) (xy 40.996362 -273.283934) (xy 41.020238 -273.287744) (xy 41.031922 -273.283934)
			(xy 41.054563 -273.27716) (xy 41.101257 -273.269889) (xy 41.124886 -273.269456) (xy 41.150147 -273.269948)
			(xy 41.199982 -273.278261) (xy 41.247768 -273.294664) (xy 41.292202 -273.318709) (xy 41.332072 -273.34974)
			(xy 41.366291 -273.38691) (xy 41.393925 -273.429206) (xy 41.414221 -273.475473) (xy 41.426624 -273.52445)
			(xy 41.430793 -273.574764) (xy 41.769042 -273.574764) (xy 41.773002 -273.52571) (xy 41.784779 -273.477926)
			(xy 41.80407 -273.43265) (xy 41.830373 -273.391054) (xy 41.863008 -273.354217) (xy 41.901129 -273.323092)
			(xy 41.94375 -273.298485) (xy 41.989766 -273.281033) (xy 42.037985 -273.271189) (xy 42.08716 -273.269208)
			(xy 42.136015 -273.27514) (xy 42.183286 -273.288832) (xy 42.227748 -273.30993) (xy 42.268251 -273.337886)
			(xy 42.303744 -273.371978) (xy 42.333309 -273.411322) (xy 42.35618 -273.454899) (xy 42.371764 -273.50158)
			(xy 42.379659 -273.550157) (xy 42.380154 -273.574764) (xy 42.379659 -273.599371) (xy 42.371764 -273.647948)
			(xy 42.35618 -273.694629) (xy 42.333309 -273.738206) (xy 42.303744 -273.77755) (xy 42.268251 -273.811642)
			(xy 42.227748 -273.839598) (xy 42.183286 -273.860696) (xy 42.136015 -273.874388) (xy 42.08716 -273.88032)
			(xy 42.037985 -273.878339) (xy 41.989766 -273.868495) (xy 41.94375 -273.851043) (xy 41.901129 -273.826436)
			(xy 41.863008 -273.795311) (xy 41.830373 -273.758474) (xy 41.80407 -273.716878) (xy 41.784779 -273.671602)
			(xy 41.773002 -273.623818) (xy 41.769042 -273.574764) (xy 41.430793 -273.574764) (xy 41.430796 -273.5748)
			(xy 41.426624 -273.62515) (xy 41.414221 -273.674127) (xy 41.393925 -273.720394) (xy 41.366291 -273.76269)
			(xy 41.332072 -273.79986) (xy 41.292202 -273.830891) (xy 41.247768 -273.854936) (xy 41.199982 -273.871339)
			(xy 41.150147 -273.879652) (xy 41.124886 -273.880072) (xy 41.101259 -273.879624) (xy 41.054569 -273.872344)
			(xy 41.031922 -273.865594) (xy 41.020238 -273.861784) (xy 40.996362 -273.865594) (xy 40.920162 -273.92122)
			(xy 40.910828 -273.928845) (xy 40.899982 -273.950329) (xy 40.899334 -273.962368) (xy 40.899334 -274.137374)
			(xy 40.899994 -274.149404) (xy 40.910851 -274.170878) (xy 40.920162 -274.178522) (xy 40.996362 -274.234148)
			(xy 41.020238 -274.237958) (xy 41.031922 -274.234148) (xy 41.054563 -274.227374) (xy 41.101257 -274.220102)
			(xy 41.124886 -274.21967) (xy 41.150146 -274.220162) (xy 41.199978 -274.228475) (xy 41.247762 -274.244877)
			(xy 41.292194 -274.268921) (xy 41.332063 -274.29995) (xy 41.36628 -274.337119) (xy 41.393913 -274.379412)
			(xy 41.414208 -274.425677) (xy 41.42661 -274.474652) (xy 41.43078 -274.524978) (xy 41.769042 -274.524978)
			(xy 41.773002 -274.475924) (xy 41.784779 -274.42814) (xy 41.80407 -274.382864) (xy 41.830373 -274.341268)
			(xy 41.863008 -274.304431) (xy 41.901129 -274.273306) (xy 41.94375 -274.248699) (xy 41.989766 -274.231247)
			(xy 42.037985 -274.221403) (xy 42.08716 -274.219422) (xy 42.136015 -274.225354) (xy 42.183286 -274.239046)
			(xy 42.227748 -274.260144) (xy 42.268251 -274.2881) (xy 42.303744 -274.322192) (xy 42.333309 -274.361536)
			(xy 42.35618 -274.405113) (xy 42.371764 -274.451794) (xy 42.379659 -274.500371) (xy 42.379988 -274.516721)
			(xy 42.719059 -274.516721) (xy 42.724426 -274.467366) (xy 42.737708 -274.419529) (xy 42.758554 -274.374471)
			(xy 42.786415 -274.333379) (xy 42.820556 -274.297337) (xy 42.86008 -274.267292) (xy 42.903943 -274.244038)
			(xy 42.950991 -274.228187) (xy 42.999983 -274.220156) (xy 43.024806 -274.21967) (xy 43.038989 -274.219846)
			(xy 43.067229 -274.222519) (xy 43.081194 -274.225004) (xy 43.095159 -274.227177) (xy 43.123293 -274.224599)
			(xy 43.149643 -274.214409) (xy 43.172192 -274.197387) (xy 43.189212 -274.174838) (xy 43.1994 -274.148487)
			(xy 43.201977 -274.120353) (xy 43.199812 -274.106386) (xy 43.197327 -274.092357) (xy 43.194655 -274.06399)
			(xy 43.194478 -274.049744) (xy 43.19493 -274.024918) (xy 43.202956 -273.975921) (xy 43.218803 -273.928867)
			(xy 43.242055 -273.884996) (xy 43.272098 -273.845466) (xy 43.30814 -273.811317) (xy 43.349233 -273.783449)
			(xy 43.394293 -273.762597) (xy 43.442133 -273.74931) (xy 43.491492 -273.743937) (xy 43.54107 -273.746621)
			(xy 43.589561 -273.757291) (xy 43.635687 -273.775666) (xy 43.678232 -273.801261) (xy 43.716076 -273.833403)
			(xy 43.748221 -273.871243) (xy 43.77382 -273.913786) (xy 43.7922 -273.95991) (xy 43.802874 -274.0084)
			(xy 43.805563 -274.057978) (xy 43.803663 -274.075452) (xy 44.123098 -274.075452) (xy 44.123098 -274.024036)
			(xy 44.131141 -273.973254) (xy 44.147029 -273.924355) (xy 44.170372 -273.878543) (xy 44.200593 -273.836947)
			(xy 44.236949 -273.800591) (xy 44.278545 -273.77037) (xy 44.324357 -273.747027) (xy 44.373256 -273.731139)
			(xy 44.424038 -273.723096) (xy 44.475454 -273.723096) (xy 44.526236 -273.731139) (xy 44.575135 -273.747027)
			(xy 44.620947 -273.77037) (xy 44.662543 -273.800591) (xy 44.698899 -273.836947) (xy 44.72912 -273.878543)
			(xy 44.752463 -273.924355) (xy 44.768351 -273.973254) (xy 44.776394 -274.024036) (xy 44.776898 -274.049744)
			(xy 45.094156 -274.049744) (xy 45.098116 -274.00069) (xy 45.109893 -273.952906) (xy 45.129184 -273.90763)
			(xy 45.155487 -273.866034) (xy 45.188122 -273.829197) (xy 45.226243 -273.798072) (xy 45.268864 -273.773465)
			(xy 45.31488 -273.756013) (xy 45.363099 -273.746169) (xy 45.412274 -273.744188) (xy 45.461129 -273.75012)
			(xy 45.5084 -273.763812) (xy 45.552862 -273.78491) (xy 45.593365 -273.812866) (xy 45.628858 -273.846958)
			(xy 45.658423 -273.886302) (xy 45.681294 -273.929879) (xy 45.696878 -273.97656) (xy 45.704773 -274.025137)
			(xy 45.705268 -274.049744) (xy 45.704773 -274.074351) (xy 45.704594 -274.075452) (xy 46.023272 -274.075452)
			(xy 46.023272 -274.024036) (xy 46.031315 -273.973254) (xy 46.047203 -273.924355) (xy 46.070546 -273.878543)
			(xy 46.100767 -273.836947) (xy 46.137123 -273.800591) (xy 46.178719 -273.77037) (xy 46.224531 -273.747027)
			(xy 46.27343 -273.731139) (xy 46.324212 -273.723096) (xy 46.375628 -273.723096) (xy 46.42641 -273.731139)
			(xy 46.475309 -273.747027) (xy 46.521121 -273.77037) (xy 46.562717 -273.800591) (xy 46.599073 -273.836947)
			(xy 46.629294 -273.878543) (xy 46.652637 -273.924355) (xy 46.668525 -273.973254) (xy 46.676568 -274.024036)
			(xy 46.677072 -274.049744) (xy 46.994076 -274.049744) (xy 46.998036 -274.00069) (xy 47.009813 -273.952906)
			(xy 47.029104 -273.90763) (xy 47.055407 -273.866034) (xy 47.088042 -273.829197) (xy 47.126163 -273.798072)
			(xy 47.168784 -273.773465) (xy 47.2148 -273.756013) (xy 47.263019 -273.746169) (xy 47.312194 -273.744188)
			(xy 47.361049 -273.75012) (xy 47.40832 -273.763812) (xy 47.452782 -273.78491) (xy 47.493285 -273.812866)
			(xy 47.528778 -273.846958) (xy 47.558343 -273.886302) (xy 47.581214 -273.929879) (xy 47.596798 -273.97656)
			(xy 47.604693 -274.025137) (xy 47.605188 -274.049744) (xy 47.604693 -274.074351) (xy 47.604514 -274.075452)
			(xy 47.923192 -274.075452) (xy 47.923192 -274.024036) (xy 47.931235 -273.973254) (xy 47.947123 -273.924355)
			(xy 47.970466 -273.878543) (xy 48.000687 -273.836947) (xy 48.037043 -273.800591) (xy 48.078639 -273.77037)
			(xy 48.124451 -273.747027) (xy 48.17335 -273.731139) (xy 48.224132 -273.723096) (xy 48.275548 -273.723096)
			(xy 48.32633 -273.731139) (xy 48.375229 -273.747027) (xy 48.421041 -273.77037) (xy 48.462637 -273.800591)
			(xy 48.498993 -273.836947) (xy 48.529214 -273.878543) (xy 48.552557 -273.924355) (xy 48.568445 -273.973254)
			(xy 48.576488 -274.024036) (xy 48.576992 -274.049744) (xy 48.893996 -274.049744) (xy 48.897956 -274.00069)
			(xy 48.909733 -273.952906) (xy 48.929024 -273.90763) (xy 48.955327 -273.866034) (xy 48.987962 -273.829197)
			(xy 49.026083 -273.798072) (xy 49.068704 -273.773465) (xy 49.11472 -273.756013) (xy 49.162939 -273.746169)
			(xy 49.212114 -273.744188) (xy 49.260969 -273.75012) (xy 49.30824 -273.763812) (xy 49.352702 -273.78491)
			(xy 49.393205 -273.812866) (xy 49.428698 -273.846958) (xy 49.458263 -273.886302) (xy 49.481134 -273.929879)
			(xy 49.496718 -273.97656) (xy 49.504613 -274.025137) (xy 49.505108 -274.049744) (xy 49.504613 -274.074351)
			(xy 49.504434 -274.075452) (xy 49.823112 -274.075452) (xy 49.823112 -274.024036) (xy 49.831155 -273.973254)
			(xy 49.847043 -273.924355) (xy 49.870386 -273.878543) (xy 49.900607 -273.836947) (xy 49.936963 -273.800591)
			(xy 49.978559 -273.77037) (xy 50.024371 -273.747027) (xy 50.07327 -273.731139) (xy 50.124052 -273.723096)
			(xy 50.175468 -273.723096) (xy 50.22625 -273.731139) (xy 50.275149 -273.747027) (xy 50.320961 -273.77037)
			(xy 50.362557 -273.800591) (xy 50.398913 -273.836947) (xy 50.429134 -273.878543) (xy 50.452477 -273.924355)
			(xy 50.468365 -273.973254) (xy 50.476408 -274.024036) (xy 50.476912 -274.049744) (xy 50.79417 -274.049744)
			(xy 50.79813 -274.00069) (xy 50.809907 -273.952906) (xy 50.829198 -273.90763) (xy 50.855501 -273.866034)
			(xy 50.888136 -273.829197) (xy 50.926257 -273.798072) (xy 50.968878 -273.773465) (xy 51.014894 -273.756013)
			(xy 51.063113 -273.746169) (xy 51.112288 -273.744188) (xy 51.161143 -273.75012) (xy 51.208414 -273.763812)
			(xy 51.252876 -273.78491) (xy 51.293379 -273.812866) (xy 51.328872 -273.846958) (xy 51.358437 -273.886302)
			(xy 51.381308 -273.929879) (xy 51.396892 -273.97656) (xy 51.404787 -274.025137) (xy 51.405282 -274.049744)
			(xy 51.404787 -274.074351) (xy 51.404608 -274.075452) (xy 51.723286 -274.075452) (xy 51.723286 -274.024036)
			(xy 51.731329 -273.973254) (xy 51.747217 -273.924355) (xy 51.77056 -273.878543) (xy 51.800781 -273.836947)
			(xy 51.837137 -273.800591) (xy 51.878733 -273.77037) (xy 51.924545 -273.747027) (xy 51.973444 -273.731139)
			(xy 52.024226 -273.723096) (xy 52.075642 -273.723096) (xy 52.126424 -273.731139) (xy 52.175323 -273.747027)
			(xy 52.221135 -273.77037) (xy 52.262731 -273.800591) (xy 52.299087 -273.836947) (xy 52.329308 -273.878543)
			(xy 52.352651 -273.924355) (xy 52.368539 -273.973254) (xy 52.376582 -274.024036) (xy 52.377086 -274.049744)
			(xy 52.69409 -274.049744) (xy 52.69805 -274.00069) (xy 52.709827 -273.952906) (xy 52.729118 -273.90763)
			(xy 52.755421 -273.866034) (xy 52.788056 -273.829197) (xy 52.826177 -273.798072) (xy 52.868798 -273.773465)
			(xy 52.914814 -273.756013) (xy 52.963033 -273.746169) (xy 53.012208 -273.744188) (xy 53.061063 -273.75012)
			(xy 53.108334 -273.763812) (xy 53.152796 -273.78491) (xy 53.193299 -273.812866) (xy 53.228792 -273.846958)
			(xy 53.258357 -273.886302) (xy 53.281228 -273.929879) (xy 53.296812 -273.97656) (xy 53.304707 -274.025137)
			(xy 53.305202 -274.049744) (xy 53.304707 -274.074351) (xy 53.304528 -274.075452) (xy 53.623206 -274.075452)
			(xy 53.623206 -274.024036) (xy 53.631249 -273.973254) (xy 53.647137 -273.924355) (xy 53.67048 -273.878543)
			(xy 53.700701 -273.836947) (xy 53.737057 -273.800591) (xy 53.778653 -273.77037) (xy 53.824465 -273.747027)
			(xy 53.873364 -273.731139) (xy 53.924146 -273.723096) (xy 53.975562 -273.723096) (xy 54.026344 -273.731139)
			(xy 54.075243 -273.747027) (xy 54.121055 -273.77037) (xy 54.162651 -273.800591) (xy 54.199007 -273.836947)
			(xy 54.229228 -273.878543) (xy 54.252571 -273.924355) (xy 54.268459 -273.973254) (xy 54.276502 -274.024036)
			(xy 54.277006 -274.049744) (xy 54.59401 -274.049744) (xy 54.59797 -274.00069) (xy 54.609747 -273.952906)
			(xy 54.629038 -273.90763) (xy 54.655341 -273.866034) (xy 54.687976 -273.829197) (xy 54.726097 -273.798072)
			(xy 54.768718 -273.773465) (xy 54.814734 -273.756013) (xy 54.862953 -273.746169) (xy 54.912128 -273.744188)
			(xy 54.960983 -273.75012) (xy 55.008254 -273.763812) (xy 55.052716 -273.78491) (xy 55.093219 -273.812866)
			(xy 55.128712 -273.846958) (xy 55.158277 -273.886302) (xy 55.181148 -273.929879) (xy 55.196732 -273.97656)
			(xy 55.204627 -274.025137) (xy 55.205122 -274.049744) (xy 55.204627 -274.074351) (xy 55.204448 -274.075452)
			(xy 55.523126 -274.075452) (xy 55.523126 -274.024036) (xy 55.531169 -273.973254) (xy 55.547057 -273.924355)
			(xy 55.5704 -273.878543) (xy 55.600621 -273.836947) (xy 55.636977 -273.800591) (xy 55.678573 -273.77037)
			(xy 55.724385 -273.747027) (xy 55.773284 -273.731139) (xy 55.824066 -273.723096) (xy 55.875482 -273.723096)
			(xy 55.926264 -273.731139) (xy 55.975163 -273.747027) (xy 56.020975 -273.77037) (xy 56.062571 -273.800591)
			(xy 56.098927 -273.836947) (xy 56.129148 -273.878543) (xy 56.152491 -273.924355) (xy 56.168379 -273.973254)
			(xy 56.176422 -274.024036) (xy 56.176926 -274.049744) (xy 56.494184 -274.049744) (xy 56.498144 -274.00069)
			(xy 56.509921 -273.952906) (xy 56.529212 -273.90763) (xy 56.555515 -273.866034) (xy 56.58815 -273.829197)
			(xy 56.626271 -273.798072) (xy 56.668892 -273.773465) (xy 56.714908 -273.756013) (xy 56.763127 -273.746169)
			(xy 56.812302 -273.744188) (xy 56.861157 -273.75012) (xy 56.908428 -273.763812) (xy 56.95289 -273.78491)
			(xy 56.993393 -273.812866) (xy 57.028886 -273.846958) (xy 57.058451 -273.886302) (xy 57.081322 -273.929879)
			(xy 57.096906 -273.97656) (xy 57.104801 -274.025137) (xy 57.105296 -274.049744) (xy 57.104801 -274.074351)
			(xy 57.104622 -274.075452) (xy 57.4233 -274.075452) (xy 57.4233 -274.024036) (xy 57.431343 -273.973254)
			(xy 57.447231 -273.924355) (xy 57.470574 -273.878543) (xy 57.500795 -273.836947) (xy 57.537151 -273.800591)
			(xy 57.578747 -273.77037) (xy 57.624559 -273.747027) (xy 57.673458 -273.731139) (xy 57.72424 -273.723096)
			(xy 57.775656 -273.723096) (xy 57.826438 -273.731139) (xy 57.875337 -273.747027) (xy 57.921149 -273.77037)
			(xy 57.962745 -273.800591) (xy 57.999101 -273.836947) (xy 58.029322 -273.878543) (xy 58.052665 -273.924355)
			(xy 58.068553 -273.973254) (xy 58.076596 -274.024036) (xy 58.0771 -274.049744) (xy 58.394104 -274.049744)
			(xy 58.398064 -274.00069) (xy 58.409841 -273.952906) (xy 58.429132 -273.90763) (xy 58.455435 -273.866034)
			(xy 58.48807 -273.829197) (xy 58.526191 -273.798072) (xy 58.568812 -273.773465) (xy 58.614828 -273.756013)
			(xy 58.663047 -273.746169) (xy 58.712222 -273.744188) (xy 58.761077 -273.75012) (xy 58.808348 -273.763812)
			(xy 58.85281 -273.78491) (xy 58.893313 -273.812866) (xy 58.928806 -273.846958) (xy 58.958371 -273.886302)
			(xy 58.981242 -273.929879) (xy 58.996826 -273.97656) (xy 59.004721 -274.025137) (xy 59.005216 -274.049744)
			(xy 59.004721 -274.074351) (xy 59.004583 -274.075198) (xy 59.322966 -274.075198) (xy 59.322966 -274.023782)
			(xy 59.331009 -273.973) (xy 59.346897 -273.924101) (xy 59.37024 -273.878289) (xy 59.400461 -273.836693)
			(xy 59.436817 -273.800337) (xy 59.478413 -273.770116) (xy 59.524225 -273.746773) (xy 59.573124 -273.730885)
			(xy 59.623906 -273.722842) (xy 59.675322 -273.722842) (xy 59.726104 -273.730885) (xy 59.775003 -273.746773)
			(xy 59.820815 -273.770116) (xy 59.862411 -273.800337) (xy 59.898767 -273.836693) (xy 59.928988 -273.878289)
			(xy 59.952331 -273.924101) (xy 59.968219 -273.973) (xy 59.976262 -274.023782) (xy 59.976766 -274.04949)
			(xy 59.976761 -274.049744) (xy 60.294024 -274.049744) (xy 60.297984 -274.00069) (xy 60.309761 -273.952906)
			(xy 60.329052 -273.90763) (xy 60.355355 -273.866034) (xy 60.38799 -273.829197) (xy 60.426111 -273.798072)
			(xy 60.468732 -273.773465) (xy 60.514748 -273.756013) (xy 60.562967 -273.746169) (xy 60.612142 -273.744188)
			(xy 60.660997 -273.75012) (xy 60.708268 -273.763812) (xy 60.75273 -273.78491) (xy 60.793233 -273.812866)
			(xy 60.828726 -273.846958) (xy 60.858291 -273.886302) (xy 60.881162 -273.929879) (xy 60.896746 -273.97656)
			(xy 60.904641 -274.025137) (xy 60.905136 -274.049744) (xy 60.904641 -274.074351) (xy 60.904462 -274.075452)
			(xy 61.222886 -274.075452) (xy 61.222886 -274.024036) (xy 61.230929 -273.973254) (xy 61.246817 -273.924355)
			(xy 61.27016 -273.878543) (xy 61.300381 -273.836947) (xy 61.336737 -273.800591) (xy 61.378333 -273.77037)
			(xy 61.424145 -273.747027) (xy 61.473044 -273.731139) (xy 61.523826 -273.723096) (xy 61.575242 -273.723096)
			(xy 61.626024 -273.731139) (xy 61.674923 -273.747027) (xy 61.720735 -273.77037) (xy 61.762331 -273.800591)
			(xy 61.798687 -273.836947) (xy 61.828908 -273.878543) (xy 61.852251 -273.924355) (xy 61.868139 -273.973254)
			(xy 61.876182 -274.024036) (xy 61.876686 -274.049744) (xy 62.193944 -274.049744) (xy 62.197904 -274.00069)
			(xy 62.209681 -273.952906) (xy 62.228972 -273.90763) (xy 62.255275 -273.866034) (xy 62.28791 -273.829197)
			(xy 62.326031 -273.798072) (xy 62.368652 -273.773465) (xy 62.414668 -273.756013) (xy 62.462887 -273.746169)
			(xy 62.512062 -273.744188) (xy 62.560917 -273.75012) (xy 62.608188 -273.763812) (xy 62.65265 -273.78491)
			(xy 62.693153 -273.812866) (xy 62.728646 -273.846958) (xy 62.758211 -273.886302) (xy 62.781082 -273.929879)
			(xy 62.796666 -273.97656) (xy 62.804561 -274.025137) (xy 62.805056 -274.049744) (xy 62.804561 -274.074351)
			(xy 62.804382 -274.075452) (xy 63.12306 -274.075452) (xy 63.12306 -274.024036) (xy 63.131103 -273.973254)
			(xy 63.146991 -273.924355) (xy 63.170334 -273.878543) (xy 63.200555 -273.836947) (xy 63.236911 -273.800591)
			(xy 63.278507 -273.77037) (xy 63.324319 -273.747027) (xy 63.373218 -273.731139) (xy 63.424 -273.723096)
			(xy 63.475416 -273.723096) (xy 63.526198 -273.731139) (xy 63.575097 -273.747027) (xy 63.620909 -273.77037)
			(xy 63.662505 -273.800591) (xy 63.698861 -273.836947) (xy 63.729082 -273.878543) (xy 63.752425 -273.924355)
			(xy 63.768313 -273.973254) (xy 63.776356 -274.024036) (xy 63.77686 -274.049744) (xy 64.094118 -274.049744)
			(xy 64.098078 -274.00069) (xy 64.109855 -273.952906) (xy 64.129146 -273.90763) (xy 64.155449 -273.866034)
			(xy 64.188084 -273.829197) (xy 64.226205 -273.798072) (xy 64.268826 -273.773465) (xy 64.314842 -273.756013)
			(xy 64.363061 -273.746169) (xy 64.412236 -273.744188) (xy 64.461091 -273.75012) (xy 64.508362 -273.763812)
			(xy 64.552824 -273.78491) (xy 64.593327 -273.812866) (xy 64.62882 -273.846958) (xy 64.658385 -273.886302)
			(xy 64.681256 -273.929879) (xy 64.69684 -273.97656) (xy 64.704735 -274.025137) (xy 64.70523 -274.049744)
			(xy 64.704735 -274.074351) (xy 64.704556 -274.075452) (xy 65.02298 -274.075452) (xy 65.02298 -274.024036)
			(xy 65.031023 -273.973254) (xy 65.046911 -273.924355) (xy 65.070254 -273.878543) (xy 65.100475 -273.836947)
			(xy 65.136831 -273.800591) (xy 65.178427 -273.77037) (xy 65.224239 -273.747027) (xy 65.273138 -273.731139)
			(xy 65.32392 -273.723096) (xy 65.375336 -273.723096) (xy 65.426118 -273.731139) (xy 65.475017 -273.747027)
			(xy 65.520829 -273.77037) (xy 65.562425 -273.800591) (xy 65.598781 -273.836947) (xy 65.629002 -273.878543)
			(xy 65.652345 -273.924355) (xy 65.668233 -273.973254) (xy 65.676276 -274.024036) (xy 65.67678 -274.049744)
			(xy 65.994038 -274.049744) (xy 65.997998 -274.00069) (xy 66.009775 -273.952906) (xy 66.029066 -273.90763)
			(xy 66.055369 -273.866034) (xy 66.088004 -273.829197) (xy 66.126125 -273.798072) (xy 66.168746 -273.773465)
			(xy 66.214762 -273.756013) (xy 66.262981 -273.746169) (xy 66.312156 -273.744188) (xy 66.361011 -273.75012)
			(xy 66.408282 -273.763812) (xy 66.452744 -273.78491) (xy 66.493247 -273.812866) (xy 66.52874 -273.846958)
			(xy 66.558305 -273.886302) (xy 66.581176 -273.929879) (xy 66.59676 -273.97656) (xy 66.604655 -274.025137)
			(xy 66.60515 -274.049744) (xy 66.604655 -274.074351) (xy 66.604476 -274.075452) (xy 66.9229 -274.075452)
			(xy 66.9229 -274.024036) (xy 66.930943 -273.973254) (xy 66.946831 -273.924355) (xy 66.970174 -273.878543)
			(xy 67.000395 -273.836947) (xy 67.036751 -273.800591) (xy 67.078347 -273.77037) (xy 67.124159 -273.747027)
			(xy 67.173058 -273.731139) (xy 67.22384 -273.723096) (xy 67.275256 -273.723096) (xy 67.326038 -273.731139)
			(xy 67.374937 -273.747027) (xy 67.420749 -273.77037) (xy 67.462345 -273.800591) (xy 67.498701 -273.836947)
			(xy 67.528922 -273.878543) (xy 67.552265 -273.924355) (xy 67.568153 -273.973254) (xy 67.576196 -274.024036)
			(xy 67.5767 -274.049744) (xy 67.893958 -274.049744) (xy 67.897918 -274.00069) (xy 67.909695 -273.952906)
			(xy 67.928986 -273.90763) (xy 67.955289 -273.866034) (xy 67.987924 -273.829197) (xy 68.026045 -273.798072)
			(xy 68.068666 -273.773465) (xy 68.114682 -273.756013) (xy 68.162901 -273.746169) (xy 68.212076 -273.744188)
			(xy 68.260931 -273.75012) (xy 68.308202 -273.763812) (xy 68.352664 -273.78491) (xy 68.393167 -273.812866)
			(xy 68.42866 -273.846958) (xy 68.458225 -273.886302) (xy 68.481096 -273.929879) (xy 68.49668 -273.97656)
			(xy 68.504575 -274.025137) (xy 68.50507 -274.049744) (xy 68.504575 -274.074351) (xy 68.504396 -274.075452)
			(xy 68.823074 -274.075452) (xy 68.823074 -274.024036) (xy 68.831117 -273.973254) (xy 68.847005 -273.924355)
			(xy 68.870348 -273.878543) (xy 68.900569 -273.836947) (xy 68.936925 -273.800591) (xy 68.978521 -273.77037)
			(xy 69.024333 -273.747027) (xy 69.073232 -273.731139) (xy 69.124014 -273.723096) (xy 69.17543 -273.723096)
			(xy 69.226212 -273.731139) (xy 69.275111 -273.747027) (xy 69.320923 -273.77037) (xy 69.362519 -273.800591)
			(xy 69.398875 -273.836947) (xy 69.429096 -273.878543) (xy 69.452439 -273.924355) (xy 69.468327 -273.973254)
			(xy 69.47637 -274.024036) (xy 69.476874 -274.049744) (xy 69.794132 -274.049744) (xy 69.798092 -274.00069)
			(xy 69.809869 -273.952906) (xy 69.82916 -273.90763) (xy 69.855463 -273.866034) (xy 69.888098 -273.829197)
			(xy 69.926219 -273.798072) (xy 69.96884 -273.773465) (xy 70.014856 -273.756013) (xy 70.063075 -273.746169)
			(xy 70.11225 -273.744188) (xy 70.161105 -273.75012) (xy 70.208376 -273.763812) (xy 70.252838 -273.78491)
			(xy 70.293341 -273.812866) (xy 70.328834 -273.846958) (xy 70.358399 -273.886302) (xy 70.38127 -273.929879)
			(xy 70.396854 -273.97656) (xy 70.404749 -274.025137) (xy 70.405244 -274.049744) (xy 70.404749 -274.074351)
			(xy 70.40457 -274.075452) (xy 70.722994 -274.075452) (xy 70.722994 -274.024036) (xy 70.731037 -273.973254)
			(xy 70.746925 -273.924355) (xy 70.770268 -273.878543) (xy 70.800489 -273.836947) (xy 70.836845 -273.800591)
			(xy 70.878441 -273.77037) (xy 70.924253 -273.747027) (xy 70.973152 -273.731139) (xy 71.023934 -273.723096)
			(xy 71.07535 -273.723096) (xy 71.126132 -273.731139) (xy 71.175031 -273.747027) (xy 71.220843 -273.77037)
			(xy 71.262439 -273.800591) (xy 71.298795 -273.836947) (xy 71.329016 -273.878543) (xy 71.352359 -273.924355)
			(xy 71.368247 -273.973254) (xy 71.37629 -274.024036) (xy 71.376794 -274.049744) (xy 71.694052 -274.049744)
			(xy 71.698012 -274.00069) (xy 71.709789 -273.952906) (xy 71.72908 -273.90763) (xy 71.755383 -273.866034)
			(xy 71.788018 -273.829197) (xy 71.826139 -273.798072) (xy 71.86876 -273.773465) (xy 71.914776 -273.756013)
			(xy 71.962995 -273.746169) (xy 72.01217 -273.744188) (xy 72.061025 -273.75012) (xy 72.108296 -273.763812)
			(xy 72.152758 -273.78491) (xy 72.193261 -273.812866) (xy 72.228754 -273.846958) (xy 72.258319 -273.886302)
			(xy 72.28119 -273.929879) (xy 72.296774 -273.97656) (xy 72.304669 -274.025137) (xy 72.305164 -274.049744)
			(xy 72.304669 -274.074351) (xy 72.30449 -274.075452) (xy 72.622914 -274.075452) (xy 72.622914 -274.024036)
			(xy 72.630957 -273.973254) (xy 72.646845 -273.924355) (xy 72.670188 -273.878543) (xy 72.700409 -273.836947)
			(xy 72.736765 -273.800591) (xy 72.778361 -273.77037) (xy 72.824173 -273.747027) (xy 72.873072 -273.731139)
			(xy 72.923854 -273.723096) (xy 72.97527 -273.723096) (xy 73.026052 -273.731139) (xy 73.074951 -273.747027)
			(xy 73.120763 -273.77037) (xy 73.162359 -273.800591) (xy 73.198715 -273.836947) (xy 73.228936 -273.878543)
			(xy 73.252279 -273.924355) (xy 73.268167 -273.973254) (xy 73.27621 -274.024036) (xy 73.276714 -274.049744)
			(xy 73.593972 -274.049744) (xy 73.597932 -274.00069) (xy 73.609709 -273.952906) (xy 73.629 -273.90763)
			(xy 73.655303 -273.866034) (xy 73.687938 -273.829197) (xy 73.726059 -273.798072) (xy 73.76868 -273.773465)
			(xy 73.814696 -273.756013) (xy 73.862915 -273.746169) (xy 73.91209 -273.744188) (xy 73.960945 -273.75012)
			(xy 74.008216 -273.763812) (xy 74.052678 -273.78491) (xy 74.093181 -273.812866) (xy 74.128674 -273.846958)
			(xy 74.158239 -273.886302) (xy 74.18111 -273.929879) (xy 74.196694 -273.97656) (xy 74.204589 -274.025137)
			(xy 74.205084 -274.049744) (xy 74.204589 -274.074351) (xy 74.20441 -274.075452) (xy 74.523088 -274.075452)
			(xy 74.523088 -274.024036) (xy 74.531131 -273.973254) (xy 74.547019 -273.924355) (xy 74.570362 -273.878543)
			(xy 74.600583 -273.836947) (xy 74.636939 -273.800591) (xy 74.678535 -273.77037) (xy 74.724347 -273.747027)
			(xy 74.773246 -273.731139) (xy 74.824028 -273.723096) (xy 74.875444 -273.723096) (xy 74.926226 -273.731139)
			(xy 74.975125 -273.747027) (xy 75.020937 -273.77037) (xy 75.062533 -273.800591) (xy 75.098889 -273.836947)
			(xy 75.12911 -273.878543) (xy 75.152453 -273.924355) (xy 75.168341 -273.973254) (xy 75.176384 -274.024036)
			(xy 75.176888 -274.049744) (xy 75.4944 -274.049744) (xy 75.49836 -274.00069) (xy 75.510137 -273.952906)
			(xy 75.529428 -273.90763) (xy 75.555731 -273.866034) (xy 75.588366 -273.829197) (xy 75.626487 -273.798072)
			(xy 75.669108 -273.773465) (xy 75.715124 -273.756013) (xy 75.763343 -273.746169) (xy 75.812518 -273.744188)
			(xy 75.861373 -273.75012) (xy 75.908644 -273.763812) (xy 75.953106 -273.78491) (xy 75.993609 -273.812866)
			(xy 76.029102 -273.846958) (xy 76.058667 -273.886302) (xy 76.081538 -273.929879) (xy 76.097122 -273.97656)
			(xy 76.105017 -274.025137) (xy 76.105512 -274.049744) (xy 76.105017 -274.074351) (xy 76.104838 -274.075452)
			(xy 76.423008 -274.075452) (xy 76.423008 -274.024036) (xy 76.431051 -273.973254) (xy 76.446939 -273.924355)
			(xy 76.470282 -273.878543) (xy 76.500503 -273.836947) (xy 76.536859 -273.800591) (xy 76.578455 -273.77037)
			(xy 76.624267 -273.747027) (xy 76.673166 -273.731139) (xy 76.723948 -273.723096) (xy 76.775364 -273.723096)
			(xy 76.826146 -273.731139) (xy 76.875045 -273.747027) (xy 76.920857 -273.77037) (xy 76.962453 -273.800591)
			(xy 76.998809 -273.836947) (xy 77.02903 -273.878543) (xy 77.052373 -273.924355) (xy 77.068261 -273.973254)
			(xy 77.076304 -274.024036) (xy 77.076808 -274.049744) (xy 77.39432 -274.049744) (xy 77.39828 -274.00069)
			(xy 77.410057 -273.952906) (xy 77.429348 -273.90763) (xy 77.455651 -273.866034) (xy 77.488286 -273.829197)
			(xy 77.526407 -273.798072) (xy 77.569028 -273.773465) (xy 77.615044 -273.756013) (xy 77.663263 -273.746169)
			(xy 77.712438 -273.744188) (xy 77.761293 -273.75012) (xy 77.808564 -273.763812) (xy 77.853026 -273.78491)
			(xy 77.893529 -273.812866) (xy 77.929022 -273.846958) (xy 77.958587 -273.886302) (xy 77.981458 -273.929879)
			(xy 77.997042 -273.97656) (xy 78.004937 -274.025137) (xy 78.005432 -274.049744) (xy 78.004937 -274.074351)
			(xy 78.004758 -274.075452) (xy 78.322928 -274.075452) (xy 78.322928 -274.024036) (xy 78.330971 -273.973254)
			(xy 78.346859 -273.924355) (xy 78.370202 -273.878543) (xy 78.400423 -273.836947) (xy 78.436779 -273.800591)
			(xy 78.478375 -273.77037) (xy 78.524187 -273.747027) (xy 78.573086 -273.731139) (xy 78.623868 -273.723096)
			(xy 78.675284 -273.723096) (xy 78.726066 -273.731139) (xy 78.774965 -273.747027) (xy 78.820777 -273.77037)
			(xy 78.862373 -273.800591) (xy 78.898729 -273.836947) (xy 78.92895 -273.878543) (xy 78.952293 -273.924355)
			(xy 78.968181 -273.973254) (xy 78.976224 -274.024036) (xy 78.976728 -274.049744) (xy 79.29424 -274.049744)
			(xy 79.2982 -274.00069) (xy 79.309977 -273.952906) (xy 79.329268 -273.90763) (xy 79.355571 -273.866034)
			(xy 79.388206 -273.829197) (xy 79.426327 -273.798072) (xy 79.468948 -273.773465) (xy 79.514964 -273.756013)
			(xy 79.563183 -273.746169) (xy 79.612358 -273.744188) (xy 79.661213 -273.75012) (xy 79.708484 -273.763812)
			(xy 79.752946 -273.78491) (xy 79.793449 -273.812866) (xy 79.828942 -273.846958) (xy 79.858507 -273.886302)
			(xy 79.881378 -273.929879) (xy 79.896962 -273.97656) (xy 79.904857 -274.025137) (xy 79.905352 -274.049744)
			(xy 79.904857 -274.074351) (xy 79.904678 -274.075452) (xy 80.222848 -274.075452) (xy 80.222848 -274.024036)
			(xy 80.230891 -273.973254) (xy 80.246779 -273.924355) (xy 80.270122 -273.878543) (xy 80.300343 -273.836947)
			(xy 80.336699 -273.800591) (xy 80.378295 -273.77037) (xy 80.424107 -273.747027) (xy 80.473006 -273.731139)
			(xy 80.523788 -273.723096) (xy 80.575204 -273.723096) (xy 80.625986 -273.731139) (xy 80.674885 -273.747027)
			(xy 80.720697 -273.77037) (xy 80.762293 -273.800591) (xy 80.798649 -273.836947) (xy 80.82887 -273.878543)
			(xy 80.852213 -273.924355) (xy 80.868101 -273.973254) (xy 80.876144 -274.024036) (xy 80.876648 -274.049744)
			(xy 81.19416 -274.049744) (xy 81.19812 -274.00069) (xy 81.209897 -273.952906) (xy 81.229188 -273.90763)
			(xy 81.255491 -273.866034) (xy 81.288126 -273.829197) (xy 81.326247 -273.798072) (xy 81.368868 -273.773465)
			(xy 81.414884 -273.756013) (xy 81.463103 -273.746169) (xy 81.512278 -273.744188) (xy 81.561133 -273.75012)
			(xy 81.608404 -273.763812) (xy 81.652866 -273.78491) (xy 81.693369 -273.812866) (xy 81.728862 -273.846958)
			(xy 81.758427 -273.886302) (xy 81.781298 -273.929879) (xy 81.796882 -273.97656) (xy 81.804777 -274.025137)
			(xy 81.805272 -274.049744) (xy 82.14412 -274.049744) (xy 82.14808 -274.00069) (xy 82.159857 -273.952906)
			(xy 82.179148 -273.90763) (xy 82.205451 -273.866034) (xy 82.238086 -273.829197) (xy 82.276207 -273.798072)
			(xy 82.318828 -273.773465) (xy 82.364844 -273.756013) (xy 82.413063 -273.746169) (xy 82.462238 -273.744188)
			(xy 82.511093 -273.75012) (xy 82.558364 -273.763812) (xy 82.602826 -273.78491) (xy 82.643329 -273.812866)
			(xy 82.678822 -273.846958) (xy 82.708387 -273.886302) (xy 82.731258 -273.929879) (xy 82.746842 -273.97656)
			(xy 82.754737 -274.025137) (xy 82.755232 -274.049744) (xy 82.754737 -274.074351) (xy 82.746842 -274.122928)
			(xy 82.731258 -274.169609) (xy 82.708387 -274.213186) (xy 82.678822 -274.25253) (xy 82.643329 -274.286622)
			(xy 82.602826 -274.314578) (xy 82.558364 -274.335676) (xy 82.511093 -274.349368) (xy 82.462238 -274.3553)
			(xy 82.413063 -274.353319) (xy 82.364844 -274.343475) (xy 82.318828 -274.326023) (xy 82.276207 -274.301416)
			(xy 82.238086 -274.270291) (xy 82.205451 -274.233454) (xy 82.179148 -274.191858) (xy 82.159857 -274.146582)
			(xy 82.14808 -274.098798) (xy 82.14412 -274.049744) (xy 81.805272 -274.049744) (xy 81.804777 -274.074351)
			(xy 81.796882 -274.122928) (xy 81.781298 -274.169609) (xy 81.758427 -274.213186) (xy 81.728862 -274.25253)
			(xy 81.693369 -274.286622) (xy 81.652866 -274.314578) (xy 81.608404 -274.335676) (xy 81.561133 -274.349368)
			(xy 81.512278 -274.3553) (xy 81.463103 -274.353319) (xy 81.414884 -274.343475) (xy 81.368868 -274.326023)
			(xy 81.326247 -274.301416) (xy 81.288126 -274.270291) (xy 81.255491 -274.233454) (xy 81.229188 -274.191858)
			(xy 81.209897 -274.146582) (xy 81.19812 -274.098798) (xy 81.19416 -274.049744) (xy 80.876648 -274.049744)
			(xy 80.876144 -274.075452) (xy 80.868101 -274.126234) (xy 80.852213 -274.175133) (xy 80.82887 -274.220945)
			(xy 80.798649 -274.262541) (xy 80.762293 -274.298897) (xy 80.720697 -274.329118) (xy 80.674885 -274.352461)
			(xy 80.625986 -274.368349) (xy 80.575204 -274.376392) (xy 80.523788 -274.376392) (xy 80.473006 -274.368349)
			(xy 80.424107 -274.352461) (xy 80.378295 -274.329118) (xy 80.336699 -274.298897) (xy 80.300343 -274.262541)
			(xy 80.270122 -274.220945) (xy 80.246779 -274.175133) (xy 80.230891 -274.126234) (xy 80.222848 -274.075452)
			(xy 79.904678 -274.075452) (xy 79.896962 -274.122928) (xy 79.881378 -274.169609) (xy 79.858507 -274.213186)
			(xy 79.828942 -274.25253) (xy 79.793449 -274.286622) (xy 79.752946 -274.314578) (xy 79.708484 -274.335676)
			(xy 79.661213 -274.349368) (xy 79.612358 -274.3553) (xy 79.563183 -274.353319) (xy 79.514964 -274.343475)
			(xy 79.468948 -274.326023) (xy 79.426327 -274.301416) (xy 79.388206 -274.270291) (xy 79.355571 -274.233454)
			(xy 79.329268 -274.191858) (xy 79.309977 -274.146582) (xy 79.2982 -274.098798) (xy 79.29424 -274.049744)
			(xy 78.976728 -274.049744) (xy 78.976224 -274.075452) (xy 78.968181 -274.126234) (xy 78.952293 -274.175133)
			(xy 78.92895 -274.220945) (xy 78.898729 -274.262541) (xy 78.862373 -274.298897) (xy 78.820777 -274.329118)
			(xy 78.774965 -274.352461) (xy 78.726066 -274.368349) (xy 78.675284 -274.376392) (xy 78.623868 -274.376392)
			(xy 78.573086 -274.368349) (xy 78.524187 -274.352461) (xy 78.478375 -274.329118) (xy 78.436779 -274.298897)
			(xy 78.400423 -274.262541) (xy 78.370202 -274.220945) (xy 78.346859 -274.175133) (xy 78.330971 -274.126234)
			(xy 78.322928 -274.075452) (xy 78.004758 -274.075452) (xy 77.997042 -274.122928) (xy 77.981458 -274.169609)
			(xy 77.958587 -274.213186) (xy 77.929022 -274.25253) (xy 77.893529 -274.286622) (xy 77.853026 -274.314578)
			(xy 77.808564 -274.335676) (xy 77.761293 -274.349368) (xy 77.712438 -274.3553) (xy 77.663263 -274.353319)
			(xy 77.615044 -274.343475) (xy 77.569028 -274.326023) (xy 77.526407 -274.301416) (xy 77.488286 -274.270291)
			(xy 77.455651 -274.233454) (xy 77.429348 -274.191858) (xy 77.410057 -274.146582) (xy 77.39828 -274.098798)
			(xy 77.39432 -274.049744) (xy 77.076808 -274.049744) (xy 77.076304 -274.075452) (xy 77.068261 -274.126234)
			(xy 77.052373 -274.175133) (xy 77.02903 -274.220945) (xy 76.998809 -274.262541) (xy 76.962453 -274.298897)
			(xy 76.920857 -274.329118) (xy 76.875045 -274.352461) (xy 76.826146 -274.368349) (xy 76.775364 -274.376392)
			(xy 76.723948 -274.376392) (xy 76.673166 -274.368349) (xy 76.624267 -274.352461) (xy 76.578455 -274.329118)
			(xy 76.536859 -274.298897) (xy 76.500503 -274.262541) (xy 76.470282 -274.220945) (xy 76.446939 -274.175133)
			(xy 76.431051 -274.126234) (xy 76.423008 -274.075452) (xy 76.104838 -274.075452) (xy 76.097122 -274.122928)
			(xy 76.081538 -274.169609) (xy 76.058667 -274.213186) (xy 76.029102 -274.25253) (xy 75.993609 -274.286622)
			(xy 75.953106 -274.314578) (xy 75.908644 -274.335676) (xy 75.861373 -274.349368) (xy 75.812518 -274.3553)
			(xy 75.763343 -274.353319) (xy 75.715124 -274.343475) (xy 75.669108 -274.326023) (xy 75.626487 -274.301416)
			(xy 75.588366 -274.270291) (xy 75.555731 -274.233454) (xy 75.529428 -274.191858) (xy 75.510137 -274.146582)
			(xy 75.49836 -274.098798) (xy 75.4944 -274.049744) (xy 75.176888 -274.049744) (xy 75.176384 -274.075452)
			(xy 75.168341 -274.126234) (xy 75.152453 -274.175133) (xy 75.12911 -274.220945) (xy 75.098889 -274.262541)
			(xy 75.062533 -274.298897) (xy 75.020937 -274.329118) (xy 74.975125 -274.352461) (xy 74.926226 -274.368349)
			(xy 74.875444 -274.376392) (xy 74.824028 -274.376392) (xy 74.773246 -274.368349) (xy 74.724347 -274.352461)
			(xy 74.678535 -274.329118) (xy 74.636939 -274.298897) (xy 74.600583 -274.262541) (xy 74.570362 -274.220945)
			(xy 74.547019 -274.175133) (xy 74.531131 -274.126234) (xy 74.523088 -274.075452) (xy 74.20441 -274.075452)
			(xy 74.196694 -274.122928) (xy 74.18111 -274.169609) (xy 74.158239 -274.213186) (xy 74.128674 -274.25253)
			(xy 74.093181 -274.286622) (xy 74.052678 -274.314578) (xy 74.008216 -274.335676) (xy 73.960945 -274.349368)
			(xy 73.91209 -274.3553) (xy 73.862915 -274.353319) (xy 73.814696 -274.343475) (xy 73.76868 -274.326023)
			(xy 73.726059 -274.301416) (xy 73.687938 -274.270291) (xy 73.655303 -274.233454) (xy 73.629 -274.191858)
			(xy 73.609709 -274.146582) (xy 73.597932 -274.098798) (xy 73.593972 -274.049744) (xy 73.276714 -274.049744)
			(xy 73.27621 -274.075452) (xy 73.268167 -274.126234) (xy 73.252279 -274.175133) (xy 73.228936 -274.220945)
			(xy 73.198715 -274.262541) (xy 73.162359 -274.298897) (xy 73.120763 -274.329118) (xy 73.074951 -274.352461)
			(xy 73.026052 -274.368349) (xy 72.97527 -274.376392) (xy 72.923854 -274.376392) (xy 72.873072 -274.368349)
			(xy 72.824173 -274.352461) (xy 72.778361 -274.329118) (xy 72.736765 -274.298897) (xy 72.700409 -274.262541)
			(xy 72.670188 -274.220945) (xy 72.646845 -274.175133) (xy 72.630957 -274.126234) (xy 72.622914 -274.075452)
			(xy 72.30449 -274.075452) (xy 72.296774 -274.122928) (xy 72.28119 -274.169609) (xy 72.258319 -274.213186)
			(xy 72.228754 -274.25253) (xy 72.193261 -274.286622) (xy 72.152758 -274.314578) (xy 72.108296 -274.335676)
			(xy 72.061025 -274.349368) (xy 72.01217 -274.3553) (xy 71.962995 -274.353319) (xy 71.914776 -274.343475)
			(xy 71.86876 -274.326023) (xy 71.826139 -274.301416) (xy 71.788018 -274.270291) (xy 71.755383 -274.233454)
			(xy 71.72908 -274.191858) (xy 71.709789 -274.146582) (xy 71.698012 -274.098798) (xy 71.694052 -274.049744)
			(xy 71.376794 -274.049744) (xy 71.37629 -274.075452) (xy 71.368247 -274.126234) (xy 71.352359 -274.175133)
			(xy 71.329016 -274.220945) (xy 71.298795 -274.262541) (xy 71.262439 -274.298897) (xy 71.220843 -274.329118)
			(xy 71.175031 -274.352461) (xy 71.126132 -274.368349) (xy 71.07535 -274.376392) (xy 71.023934 -274.376392)
			(xy 70.973152 -274.368349) (xy 70.924253 -274.352461) (xy 70.878441 -274.329118) (xy 70.836845 -274.298897)
			(xy 70.800489 -274.262541) (xy 70.770268 -274.220945) (xy 70.746925 -274.175133) (xy 70.731037 -274.126234)
			(xy 70.722994 -274.075452) (xy 70.40457 -274.075452) (xy 70.396854 -274.122928) (xy 70.38127 -274.169609)
			(xy 70.358399 -274.213186) (xy 70.328834 -274.25253) (xy 70.293341 -274.286622) (xy 70.252838 -274.314578)
			(xy 70.208376 -274.335676) (xy 70.161105 -274.349368) (xy 70.11225 -274.3553) (xy 70.063075 -274.353319)
			(xy 70.014856 -274.343475) (xy 69.96884 -274.326023) (xy 69.926219 -274.301416) (xy 69.888098 -274.270291)
			(xy 69.855463 -274.233454) (xy 69.82916 -274.191858) (xy 69.809869 -274.146582) (xy 69.798092 -274.098798)
			(xy 69.794132 -274.049744) (xy 69.476874 -274.049744) (xy 69.47637 -274.075452) (xy 69.468327 -274.126234)
			(xy 69.452439 -274.175133) (xy 69.429096 -274.220945) (xy 69.398875 -274.262541) (xy 69.362519 -274.298897)
			(xy 69.320923 -274.329118) (xy 69.275111 -274.352461) (xy 69.226212 -274.368349) (xy 69.17543 -274.376392)
			(xy 69.124014 -274.376392) (xy 69.073232 -274.368349) (xy 69.024333 -274.352461) (xy 68.978521 -274.329118)
			(xy 68.936925 -274.298897) (xy 68.900569 -274.262541) (xy 68.870348 -274.220945) (xy 68.847005 -274.175133)
			(xy 68.831117 -274.126234) (xy 68.823074 -274.075452) (xy 68.504396 -274.075452) (xy 68.49668 -274.122928)
			(xy 68.481096 -274.169609) (xy 68.458225 -274.213186) (xy 68.42866 -274.25253) (xy 68.393167 -274.286622)
			(xy 68.352664 -274.314578) (xy 68.308202 -274.335676) (xy 68.260931 -274.349368) (xy 68.212076 -274.3553)
			(xy 68.162901 -274.353319) (xy 68.114682 -274.343475) (xy 68.068666 -274.326023) (xy 68.026045 -274.301416)
			(xy 67.987924 -274.270291) (xy 67.955289 -274.233454) (xy 67.928986 -274.191858) (xy 67.909695 -274.146582)
			(xy 67.897918 -274.098798) (xy 67.893958 -274.049744) (xy 67.5767 -274.049744) (xy 67.576196 -274.075452)
			(xy 67.568153 -274.126234) (xy 67.552265 -274.175133) (xy 67.528922 -274.220945) (xy 67.498701 -274.262541)
			(xy 67.462345 -274.298897) (xy 67.420749 -274.329118) (xy 67.374937 -274.352461) (xy 67.326038 -274.368349)
			(xy 67.275256 -274.376392) (xy 67.22384 -274.376392) (xy 67.173058 -274.368349) (xy 67.124159 -274.352461)
			(xy 67.078347 -274.329118) (xy 67.036751 -274.298897) (xy 67.000395 -274.262541) (xy 66.970174 -274.220945)
			(xy 66.946831 -274.175133) (xy 66.930943 -274.126234) (xy 66.9229 -274.075452) (xy 66.604476 -274.075452)
			(xy 66.59676 -274.122928) (xy 66.581176 -274.169609) (xy 66.558305 -274.213186) (xy 66.52874 -274.25253)
			(xy 66.493247 -274.286622) (xy 66.452744 -274.314578) (xy 66.408282 -274.335676) (xy 66.361011 -274.349368)
			(xy 66.312156 -274.3553) (xy 66.262981 -274.353319) (xy 66.214762 -274.343475) (xy 66.168746 -274.326023)
			(xy 66.126125 -274.301416) (xy 66.088004 -274.270291) (xy 66.055369 -274.233454) (xy 66.029066 -274.191858)
			(xy 66.009775 -274.146582) (xy 65.997998 -274.098798) (xy 65.994038 -274.049744) (xy 65.67678 -274.049744)
			(xy 65.676276 -274.075452) (xy 65.668233 -274.126234) (xy 65.652345 -274.175133) (xy 65.629002 -274.220945)
			(xy 65.598781 -274.262541) (xy 65.562425 -274.298897) (xy 65.520829 -274.329118) (xy 65.475017 -274.352461)
			(xy 65.426118 -274.368349) (xy 65.375336 -274.376392) (xy 65.32392 -274.376392) (xy 65.273138 -274.368349)
			(xy 65.224239 -274.352461) (xy 65.178427 -274.329118) (xy 65.136831 -274.298897) (xy 65.100475 -274.262541)
			(xy 65.070254 -274.220945) (xy 65.046911 -274.175133) (xy 65.031023 -274.126234) (xy 65.02298 -274.075452)
			(xy 64.704556 -274.075452) (xy 64.69684 -274.122928) (xy 64.681256 -274.169609) (xy 64.658385 -274.213186)
			(xy 64.62882 -274.25253) (xy 64.593327 -274.286622) (xy 64.552824 -274.314578) (xy 64.508362 -274.335676)
			(xy 64.461091 -274.349368) (xy 64.412236 -274.3553) (xy 64.363061 -274.353319) (xy 64.314842 -274.343475)
			(xy 64.268826 -274.326023) (xy 64.226205 -274.301416) (xy 64.188084 -274.270291) (xy 64.155449 -274.233454)
			(xy 64.129146 -274.191858) (xy 64.109855 -274.146582) (xy 64.098078 -274.098798) (xy 64.094118 -274.049744)
			(xy 63.77686 -274.049744) (xy 63.776356 -274.075452) (xy 63.768313 -274.126234) (xy 63.752425 -274.175133)
			(xy 63.729082 -274.220945) (xy 63.698861 -274.262541) (xy 63.662505 -274.298897) (xy 63.620909 -274.329118)
			(xy 63.575097 -274.352461) (xy 63.526198 -274.368349) (xy 63.475416 -274.376392) (xy 63.424 -274.376392)
			(xy 63.373218 -274.368349) (xy 63.324319 -274.352461) (xy 63.278507 -274.329118) (xy 63.236911 -274.298897)
			(xy 63.200555 -274.262541) (xy 63.170334 -274.220945) (xy 63.146991 -274.175133) (xy 63.131103 -274.126234)
			(xy 63.12306 -274.075452) (xy 62.804382 -274.075452) (xy 62.796666 -274.122928) (xy 62.781082 -274.169609)
			(xy 62.758211 -274.213186) (xy 62.728646 -274.25253) (xy 62.693153 -274.286622) (xy 62.65265 -274.314578)
			(xy 62.608188 -274.335676) (xy 62.560917 -274.349368) (xy 62.512062 -274.3553) (xy 62.462887 -274.353319)
			(xy 62.414668 -274.343475) (xy 62.368652 -274.326023) (xy 62.326031 -274.301416) (xy 62.28791 -274.270291)
			(xy 62.255275 -274.233454) (xy 62.228972 -274.191858) (xy 62.209681 -274.146582) (xy 62.197904 -274.098798)
			(xy 62.193944 -274.049744) (xy 61.876686 -274.049744) (xy 61.876182 -274.075452) (xy 61.868139 -274.126234)
			(xy 61.852251 -274.175133) (xy 61.828908 -274.220945) (xy 61.798687 -274.262541) (xy 61.762331 -274.298897)
			(xy 61.720735 -274.329118) (xy 61.674923 -274.352461) (xy 61.626024 -274.368349) (xy 61.575242 -274.376392)
			(xy 61.523826 -274.376392) (xy 61.473044 -274.368349) (xy 61.424145 -274.352461) (xy 61.378333 -274.329118)
			(xy 61.336737 -274.298897) (xy 61.300381 -274.262541) (xy 61.27016 -274.220945) (xy 61.246817 -274.175133)
			(xy 61.230929 -274.126234) (xy 61.222886 -274.075452) (xy 60.904462 -274.075452) (xy 60.896746 -274.122928)
			(xy 60.881162 -274.169609) (xy 60.858291 -274.213186) (xy 60.828726 -274.25253) (xy 60.793233 -274.286622)
			(xy 60.75273 -274.314578) (xy 60.708268 -274.335676) (xy 60.660997 -274.349368) (xy 60.612142 -274.3553)
			(xy 60.562967 -274.353319) (xy 60.514748 -274.343475) (xy 60.468732 -274.326023) (xy 60.426111 -274.301416)
			(xy 60.38799 -274.270291) (xy 60.355355 -274.233454) (xy 60.329052 -274.191858) (xy 60.309761 -274.146582)
			(xy 60.297984 -274.098798) (xy 60.294024 -274.049744) (xy 59.976761 -274.049744) (xy 59.976262 -274.075198)
			(xy 59.968219 -274.12598) (xy 59.952331 -274.174879) (xy 59.928988 -274.220691) (xy 59.898767 -274.262287)
			(xy 59.862411 -274.298643) (xy 59.820815 -274.328864) (xy 59.775003 -274.352207) (xy 59.726104 -274.368095)
			(xy 59.675322 -274.376138) (xy 59.623906 -274.376138) (xy 59.573124 -274.368095) (xy 59.524225 -274.352207)
			(xy 59.478413 -274.328864) (xy 59.436817 -274.298643) (xy 59.400461 -274.262287) (xy 59.37024 -274.220691)
			(xy 59.346897 -274.174879) (xy 59.331009 -274.12598) (xy 59.322966 -274.075198) (xy 59.004583 -274.075198)
			(xy 58.996826 -274.122928) (xy 58.981242 -274.169609) (xy 58.958371 -274.213186) (xy 58.928806 -274.25253)
			(xy 58.893313 -274.286622) (xy 58.85281 -274.314578) (xy 58.808348 -274.335676) (xy 58.761077 -274.349368)
			(xy 58.712222 -274.3553) (xy 58.663047 -274.353319) (xy 58.614828 -274.343475) (xy 58.568812 -274.326023)
			(xy 58.526191 -274.301416) (xy 58.48807 -274.270291) (xy 58.455435 -274.233454) (xy 58.429132 -274.191858)
			(xy 58.409841 -274.146582) (xy 58.398064 -274.098798) (xy 58.394104 -274.049744) (xy 58.0771 -274.049744)
			(xy 58.076596 -274.075452) (xy 58.068553 -274.126234) (xy 58.052665 -274.175133) (xy 58.029322 -274.220945)
			(xy 57.999101 -274.262541) (xy 57.962745 -274.298897) (xy 57.921149 -274.329118) (xy 57.875337 -274.352461)
			(xy 57.826438 -274.368349) (xy 57.775656 -274.376392) (xy 57.72424 -274.376392) (xy 57.673458 -274.368349)
			(xy 57.624559 -274.352461) (xy 57.578747 -274.329118) (xy 57.537151 -274.298897) (xy 57.500795 -274.262541)
			(xy 57.470574 -274.220945) (xy 57.447231 -274.175133) (xy 57.431343 -274.126234) (xy 57.4233 -274.075452)
			(xy 57.104622 -274.075452) (xy 57.096906 -274.122928) (xy 57.081322 -274.169609) (xy 57.058451 -274.213186)
			(xy 57.028886 -274.25253) (xy 56.993393 -274.286622) (xy 56.95289 -274.314578) (xy 56.908428 -274.335676)
			(xy 56.861157 -274.349368) (xy 56.812302 -274.3553) (xy 56.763127 -274.353319) (xy 56.714908 -274.343475)
			(xy 56.668892 -274.326023) (xy 56.626271 -274.301416) (xy 56.58815 -274.270291) (xy 56.555515 -274.233454)
			(xy 56.529212 -274.191858) (xy 56.509921 -274.146582) (xy 56.498144 -274.098798) (xy 56.494184 -274.049744)
			(xy 56.176926 -274.049744) (xy 56.176422 -274.075452) (xy 56.168379 -274.126234) (xy 56.152491 -274.175133)
			(xy 56.129148 -274.220945) (xy 56.098927 -274.262541) (xy 56.062571 -274.298897) (xy 56.020975 -274.329118)
			(xy 55.975163 -274.352461) (xy 55.926264 -274.368349) (xy 55.875482 -274.376392) (xy 55.824066 -274.376392)
			(xy 55.773284 -274.368349) (xy 55.724385 -274.352461) (xy 55.678573 -274.329118) (xy 55.636977 -274.298897)
			(xy 55.600621 -274.262541) (xy 55.5704 -274.220945) (xy 55.547057 -274.175133) (xy 55.531169 -274.126234)
			(xy 55.523126 -274.075452) (xy 55.204448 -274.075452) (xy 55.196732 -274.122928) (xy 55.181148 -274.169609)
			(xy 55.158277 -274.213186) (xy 55.128712 -274.25253) (xy 55.093219 -274.286622) (xy 55.052716 -274.314578)
			(xy 55.008254 -274.335676) (xy 54.960983 -274.349368) (xy 54.912128 -274.3553) (xy 54.862953 -274.353319)
			(xy 54.814734 -274.343475) (xy 54.768718 -274.326023) (xy 54.726097 -274.301416) (xy 54.687976 -274.270291)
			(xy 54.655341 -274.233454) (xy 54.629038 -274.191858) (xy 54.609747 -274.146582) (xy 54.59797 -274.098798)
			(xy 54.59401 -274.049744) (xy 54.277006 -274.049744) (xy 54.276502 -274.075452) (xy 54.268459 -274.126234)
			(xy 54.252571 -274.175133) (xy 54.229228 -274.220945) (xy 54.199007 -274.262541) (xy 54.162651 -274.298897)
			(xy 54.121055 -274.329118) (xy 54.075243 -274.352461) (xy 54.026344 -274.368349) (xy 53.975562 -274.376392)
			(xy 53.924146 -274.376392) (xy 53.873364 -274.368349) (xy 53.824465 -274.352461) (xy 53.778653 -274.329118)
			(xy 53.737057 -274.298897) (xy 53.700701 -274.262541) (xy 53.67048 -274.220945) (xy 53.647137 -274.175133)
			(xy 53.631249 -274.126234) (xy 53.623206 -274.075452) (xy 53.304528 -274.075452) (xy 53.296812 -274.122928)
			(xy 53.281228 -274.169609) (xy 53.258357 -274.213186) (xy 53.228792 -274.25253) (xy 53.193299 -274.286622)
			(xy 53.152796 -274.314578) (xy 53.108334 -274.335676) (xy 53.061063 -274.349368) (xy 53.012208 -274.3553)
			(xy 52.963033 -274.353319) (xy 52.914814 -274.343475) (xy 52.868798 -274.326023) (xy 52.826177 -274.301416)
			(xy 52.788056 -274.270291) (xy 52.755421 -274.233454) (xy 52.729118 -274.191858) (xy 52.709827 -274.146582)
			(xy 52.69805 -274.098798) (xy 52.69409 -274.049744) (xy 52.377086 -274.049744) (xy 52.376582 -274.075452)
			(xy 52.368539 -274.126234) (xy 52.352651 -274.175133) (xy 52.329308 -274.220945) (xy 52.299087 -274.262541)
			(xy 52.262731 -274.298897) (xy 52.221135 -274.329118) (xy 52.175323 -274.352461) (xy 52.126424 -274.368349)
			(xy 52.075642 -274.376392) (xy 52.024226 -274.376392) (xy 51.973444 -274.368349) (xy 51.924545 -274.352461)
			(xy 51.878733 -274.329118) (xy 51.837137 -274.298897) (xy 51.800781 -274.262541) (xy 51.77056 -274.220945)
			(xy 51.747217 -274.175133) (xy 51.731329 -274.126234) (xy 51.723286 -274.075452) (xy 51.404608 -274.075452)
			(xy 51.396892 -274.122928) (xy 51.381308 -274.169609) (xy 51.358437 -274.213186) (xy 51.328872 -274.25253)
			(xy 51.293379 -274.286622) (xy 51.252876 -274.314578) (xy 51.208414 -274.335676) (xy 51.161143 -274.349368)
			(xy 51.112288 -274.3553) (xy 51.063113 -274.353319) (xy 51.014894 -274.343475) (xy 50.968878 -274.326023)
			(xy 50.926257 -274.301416) (xy 50.888136 -274.270291) (xy 50.855501 -274.233454) (xy 50.829198 -274.191858)
			(xy 50.809907 -274.146582) (xy 50.79813 -274.098798) (xy 50.79417 -274.049744) (xy 50.476912 -274.049744)
			(xy 50.476408 -274.075452) (xy 50.468365 -274.126234) (xy 50.452477 -274.175133) (xy 50.429134 -274.220945)
			(xy 50.398913 -274.262541) (xy 50.362557 -274.298897) (xy 50.320961 -274.329118) (xy 50.275149 -274.352461)
			(xy 50.22625 -274.368349) (xy 50.175468 -274.376392) (xy 50.124052 -274.376392) (xy 50.07327 -274.368349)
			(xy 50.024371 -274.352461) (xy 49.978559 -274.329118) (xy 49.936963 -274.298897) (xy 49.900607 -274.262541)
			(xy 49.870386 -274.220945) (xy 49.847043 -274.175133) (xy 49.831155 -274.126234) (xy 49.823112 -274.075452)
			(xy 49.504434 -274.075452) (xy 49.496718 -274.122928) (xy 49.481134 -274.169609) (xy 49.458263 -274.213186)
			(xy 49.428698 -274.25253) (xy 49.393205 -274.286622) (xy 49.352702 -274.314578) (xy 49.30824 -274.335676)
			(xy 49.260969 -274.349368) (xy 49.212114 -274.3553) (xy 49.162939 -274.353319) (xy 49.11472 -274.343475)
			(xy 49.068704 -274.326023) (xy 49.026083 -274.301416) (xy 48.987962 -274.270291) (xy 48.955327 -274.233454)
			(xy 48.929024 -274.191858) (xy 48.909733 -274.146582) (xy 48.897956 -274.098798) (xy 48.893996 -274.049744)
			(xy 48.576992 -274.049744) (xy 48.576488 -274.075452) (xy 48.568445 -274.126234) (xy 48.552557 -274.175133)
			(xy 48.529214 -274.220945) (xy 48.498993 -274.262541) (xy 48.462637 -274.298897) (xy 48.421041 -274.329118)
			(xy 48.375229 -274.352461) (xy 48.32633 -274.368349) (xy 48.275548 -274.376392) (xy 48.224132 -274.376392)
			(xy 48.17335 -274.368349) (xy 48.124451 -274.352461) (xy 48.078639 -274.329118) (xy 48.037043 -274.298897)
			(xy 48.000687 -274.262541) (xy 47.970466 -274.220945) (xy 47.947123 -274.175133) (xy 47.931235 -274.126234)
			(xy 47.923192 -274.075452) (xy 47.604514 -274.075452) (xy 47.596798 -274.122928) (xy 47.581214 -274.169609)
			(xy 47.558343 -274.213186) (xy 47.528778 -274.25253) (xy 47.493285 -274.286622) (xy 47.452782 -274.314578)
			(xy 47.40832 -274.335676) (xy 47.361049 -274.349368) (xy 47.312194 -274.3553) (xy 47.263019 -274.353319)
			(xy 47.2148 -274.343475) (xy 47.168784 -274.326023) (xy 47.126163 -274.301416) (xy 47.088042 -274.270291)
			(xy 47.055407 -274.233454) (xy 47.029104 -274.191858) (xy 47.009813 -274.146582) (xy 46.998036 -274.098798)
			(xy 46.994076 -274.049744) (xy 46.677072 -274.049744) (xy 46.676568 -274.075452) (xy 46.668525 -274.126234)
			(xy 46.652637 -274.175133) (xy 46.629294 -274.220945) (xy 46.599073 -274.262541) (xy 46.562717 -274.298897)
			(xy 46.521121 -274.329118) (xy 46.475309 -274.352461) (xy 46.42641 -274.368349) (xy 46.375628 -274.376392)
			(xy 46.324212 -274.376392) (xy 46.27343 -274.368349) (xy 46.224531 -274.352461) (xy 46.178719 -274.329118)
			(xy 46.137123 -274.298897) (xy 46.100767 -274.262541) (xy 46.070546 -274.220945) (xy 46.047203 -274.175133)
			(xy 46.031315 -274.126234) (xy 46.023272 -274.075452) (xy 45.704594 -274.075452) (xy 45.696878 -274.122928)
			(xy 45.681294 -274.169609) (xy 45.658423 -274.213186) (xy 45.628858 -274.25253) (xy 45.593365 -274.286622)
			(xy 45.552862 -274.314578) (xy 45.5084 -274.335676) (xy 45.461129 -274.349368) (xy 45.412274 -274.3553)
			(xy 45.363099 -274.353319) (xy 45.31488 -274.343475) (xy 45.268864 -274.326023) (xy 45.226243 -274.301416)
			(xy 45.188122 -274.270291) (xy 45.155487 -274.233454) (xy 45.129184 -274.191858) (xy 45.109893 -274.146582)
			(xy 45.098116 -274.098798) (xy 45.094156 -274.049744) (xy 44.776898 -274.049744) (xy 44.776394 -274.075452)
			(xy 44.768351 -274.126234) (xy 44.752463 -274.175133) (xy 44.72912 -274.220945) (xy 44.698899 -274.262541)
			(xy 44.662543 -274.298897) (xy 44.620947 -274.329118) (xy 44.575135 -274.352461) (xy 44.526236 -274.368349)
			(xy 44.475454 -274.376392) (xy 44.424038 -274.376392) (xy 44.373256 -274.368349) (xy 44.324357 -274.352461)
			(xy 44.278545 -274.329118) (xy 44.236949 -274.298897) (xy 44.200593 -274.262541) (xy 44.170372 -274.220945)
			(xy 44.147029 -274.175133) (xy 44.131141 -274.126234) (xy 44.123098 -274.075452) (xy 43.803663 -274.075452)
			(xy 43.800196 -274.107338) (xy 43.786913 -274.155179) (xy 43.766065 -274.200241) (xy 43.738202 -274.241336)
			(xy 43.704056 -274.277382) (xy 43.664529 -274.307429) (xy 43.620661 -274.330685) (xy 43.573609 -274.346537)
			(xy 43.524611 -274.354568) (xy 43.499786 -274.355052) (xy 43.485603 -274.354877) (xy 43.457363 -274.352204)
			(xy 43.443398 -274.349718) (xy 43.429436 -274.34751) (xy 43.401297 -274.350091) (xy 43.374942 -274.360285)
			(xy 43.352391 -274.377312) (xy 43.33537 -274.399869) (xy 43.325184 -274.426227) (xy 43.322612 -274.454367)
			(xy 43.32478 -274.468336) (xy 43.327268 -274.482364) (xy 43.329938 -274.510732) (xy 43.330114 -274.524978)
			(xy 43.329646 -274.549801) (xy 43.321617 -274.598794) (xy 43.305768 -274.645842) (xy 43.282516 -274.689707)
			(xy 43.252474 -274.729232) (xy 43.216433 -274.763375) (xy 43.175343 -274.791238) (xy 43.130286 -274.812087)
			(xy 43.08245 -274.825371) (xy 43.033095 -274.83074) (xy 42.983522 -274.828055) (xy 42.935036 -274.817384)
			(xy 42.888915 -274.79901) (xy 42.846374 -274.773416) (xy 42.808535 -274.741276) (xy 42.776394 -274.703439)
			(xy 42.750797 -274.6609) (xy 42.732421 -274.61478) (xy 42.721747 -274.566294) (xy 42.719059 -274.516721)
			(xy 42.379988 -274.516721) (xy 42.380154 -274.524978) (xy 42.379659 -274.549585) (xy 42.371764 -274.598162)
			(xy 42.35618 -274.644843) (xy 42.333309 -274.68842) (xy 42.303744 -274.727764) (xy 42.268251 -274.761856)
			(xy 42.227748 -274.789812) (xy 42.183286 -274.81091) (xy 42.136015 -274.824602) (xy 42.08716 -274.830534)
			(xy 42.037985 -274.828553) (xy 41.989766 -274.818709) (xy 41.94375 -274.801257) (xy 41.901129 -274.77665)
			(xy 41.863008 -274.745525) (xy 41.830373 -274.708688) (xy 41.80407 -274.667092) (xy 41.784779 -274.621816)
			(xy 41.773002 -274.574032) (xy 41.769042 -274.524978) (xy 41.43078 -274.524978) (xy 41.430782 -274.525)
			(xy 41.42661 -274.575348) (xy 41.414208 -274.624323) (xy 41.393913 -274.670588) (xy 41.36628 -274.712881)
			(xy 41.332063 -274.75005) (xy 41.292194 -274.781079) (xy 41.247762 -274.805123) (xy 41.199978 -274.821525)
			(xy 41.150146 -274.829838) (xy 41.124886 -274.830286) (xy 41.101259 -274.829838) (xy 41.054569 -274.822559)
			(xy 41.031922 -274.815808) (xy 41.020238 -274.811998) (xy 40.996362 -274.815808) (xy 40.920162 -274.871434)
			(xy 40.910813 -274.879054) (xy 40.899931 -274.900537) (xy 40.899334 -274.912582) (xy 40.899334 -274.999958)
			(xy 44.143942 -274.999958) (xy 44.147902 -274.950904) (xy 44.159679 -274.90312) (xy 44.17897 -274.857844)
			(xy 44.205273 -274.816248) (xy 44.237908 -274.779411) (xy 44.276029 -274.748286) (xy 44.31865 -274.723679)
			(xy 44.364666 -274.706227) (xy 44.412885 -274.696383) (xy 44.46206 -274.694402) (xy 44.510915 -274.700334)
			(xy 44.558186 -274.714026) (xy 44.602648 -274.735124) (xy 44.643151 -274.76308) (xy 44.678644 -274.797172)
			(xy 44.708209 -274.836516) (xy 44.73108 -274.880093) (xy 44.746664 -274.926774) (xy 44.754559 -274.975351)
			(xy 44.755054 -274.999958) (xy 44.754559 -275.024565) (xy 44.75438 -275.025666) (xy 45.073312 -275.025666)
			(xy 45.073312 -274.97425) (xy 45.081355 -274.923468) (xy 45.097243 -274.874569) (xy 45.120586 -274.828757)
			(xy 45.150807 -274.787161) (xy 45.187163 -274.750805) (xy 45.228759 -274.720584) (xy 45.274571 -274.697241)
			(xy 45.32347 -274.681353) (xy 45.374252 -274.67331) (xy 45.425668 -274.67331) (xy 45.47645 -274.681353)
			(xy 45.525349 -274.697241) (xy 45.571161 -274.720584) (xy 45.612757 -274.750805) (xy 45.649113 -274.787161)
			(xy 45.679334 -274.828757) (xy 45.702677 -274.874569) (xy 45.718565 -274.923468) (xy 45.726608 -274.97425)
			(xy 45.727112 -274.999958) (xy 46.044116 -274.999958) (xy 46.048076 -274.950904) (xy 46.059853 -274.90312)
			(xy 46.079144 -274.857844) (xy 46.105447 -274.816248) (xy 46.138082 -274.779411) (xy 46.176203 -274.748286)
			(xy 46.218824 -274.723679) (xy 46.26484 -274.706227) (xy 46.313059 -274.696383) (xy 46.362234 -274.694402)
			(xy 46.411089 -274.700334) (xy 46.45836 -274.714026) (xy 46.502822 -274.735124) (xy 46.543325 -274.76308)
			(xy 46.578818 -274.797172) (xy 46.608383 -274.836516) (xy 46.631254 -274.880093) (xy 46.646838 -274.926774)
			(xy 46.654733 -274.975351) (xy 46.655228 -274.999958) (xy 46.654733 -275.024565) (xy 46.654554 -275.025666)
			(xy 46.973232 -275.025666) (xy 46.973232 -274.97425) (xy 46.981275 -274.923468) (xy 46.997163 -274.874569)
			(xy 47.020506 -274.828757) (xy 47.050727 -274.787161) (xy 47.087083 -274.750805) (xy 47.128679 -274.720584)
			(xy 47.174491 -274.697241) (xy 47.22339 -274.681353) (xy 47.274172 -274.67331) (xy 47.325588 -274.67331)
			(xy 47.37637 -274.681353) (xy 47.425269 -274.697241) (xy 47.471081 -274.720584) (xy 47.512677 -274.750805)
			(xy 47.549033 -274.787161) (xy 47.579254 -274.828757) (xy 47.602597 -274.874569) (xy 47.618485 -274.923468)
			(xy 47.626528 -274.97425) (xy 47.627032 -274.999958) (xy 47.944036 -274.999958) (xy 47.947996 -274.950904)
			(xy 47.959773 -274.90312) (xy 47.979064 -274.857844) (xy 48.005367 -274.816248) (xy 48.038002 -274.779411)
			(xy 48.076123 -274.748286) (xy 48.118744 -274.723679) (xy 48.16476 -274.706227) (xy 48.212979 -274.696383)
			(xy 48.262154 -274.694402) (xy 48.311009 -274.700334) (xy 48.35828 -274.714026) (xy 48.402742 -274.735124)
			(xy 48.443245 -274.76308) (xy 48.478738 -274.797172) (xy 48.508303 -274.836516) (xy 48.531174 -274.880093)
			(xy 48.546758 -274.926774) (xy 48.554653 -274.975351) (xy 48.555148 -274.999958) (xy 48.554653 -275.024565)
			(xy 48.554474 -275.025666) (xy 48.873152 -275.025666) (xy 48.873152 -274.97425) (xy 48.881195 -274.923468)
			(xy 48.897083 -274.874569) (xy 48.920426 -274.828757) (xy 48.950647 -274.787161) (xy 48.987003 -274.750805)
			(xy 49.028599 -274.720584) (xy 49.074411 -274.697241) (xy 49.12331 -274.681353) (xy 49.174092 -274.67331)
			(xy 49.225508 -274.67331) (xy 49.27629 -274.681353) (xy 49.325189 -274.697241) (xy 49.371001 -274.720584)
			(xy 49.412597 -274.750805) (xy 49.448953 -274.787161) (xy 49.479174 -274.828757) (xy 49.502517 -274.874569)
			(xy 49.518405 -274.923468) (xy 49.526448 -274.97425) (xy 49.526952 -274.999958) (xy 49.843956 -274.999958)
			(xy 49.847916 -274.950904) (xy 49.859693 -274.90312) (xy 49.878984 -274.857844) (xy 49.905287 -274.816248)
			(xy 49.937922 -274.779411) (xy 49.976043 -274.748286) (xy 50.018664 -274.723679) (xy 50.06468 -274.706227)
			(xy 50.112899 -274.696383) (xy 50.162074 -274.694402) (xy 50.210929 -274.700334) (xy 50.2582 -274.714026)
			(xy 50.302662 -274.735124) (xy 50.343165 -274.76308) (xy 50.378658 -274.797172) (xy 50.408223 -274.836516)
			(xy 50.431094 -274.880093) (xy 50.446678 -274.926774) (xy 50.454573 -274.975351) (xy 50.455068 -274.999958)
			(xy 50.454573 -275.024565) (xy 50.454394 -275.025666) (xy 50.773326 -275.025666) (xy 50.773326 -274.97425)
			(xy 50.781369 -274.923468) (xy 50.797257 -274.874569) (xy 50.8206 -274.828757) (xy 50.850821 -274.787161)
			(xy 50.887177 -274.750805) (xy 50.928773 -274.720584) (xy 50.974585 -274.697241) (xy 51.023484 -274.681353)
			(xy 51.074266 -274.67331) (xy 51.125682 -274.67331) (xy 51.176464 -274.681353) (xy 51.225363 -274.697241)
			(xy 51.271175 -274.720584) (xy 51.312771 -274.750805) (xy 51.349127 -274.787161) (xy 51.379348 -274.828757)
			(xy 51.402691 -274.874569) (xy 51.418579 -274.923468) (xy 51.426622 -274.97425) (xy 51.427126 -274.999958)
			(xy 51.74413 -274.999958) (xy 51.74809 -274.950904) (xy 51.759867 -274.90312) (xy 51.779158 -274.857844)
			(xy 51.805461 -274.816248) (xy 51.838096 -274.779411) (xy 51.876217 -274.748286) (xy 51.918838 -274.723679)
			(xy 51.964854 -274.706227) (xy 52.013073 -274.696383) (xy 52.062248 -274.694402) (xy 52.111103 -274.700334)
			(xy 52.158374 -274.714026) (xy 52.202836 -274.735124) (xy 52.243339 -274.76308) (xy 52.278832 -274.797172)
			(xy 52.308397 -274.836516) (xy 52.331268 -274.880093) (xy 52.346852 -274.926774) (xy 52.354747 -274.975351)
			(xy 52.355242 -274.999958) (xy 52.354747 -275.024565) (xy 52.354568 -275.025666) (xy 52.673246 -275.025666)
			(xy 52.673246 -274.97425) (xy 52.681289 -274.923468) (xy 52.697177 -274.874569) (xy 52.72052 -274.828757)
			(xy 52.750741 -274.787161) (xy 52.787097 -274.750805) (xy 52.828693 -274.720584) (xy 52.874505 -274.697241)
			(xy 52.923404 -274.681353) (xy 52.974186 -274.67331) (xy 53.025602 -274.67331) (xy 53.076384 -274.681353)
			(xy 53.125283 -274.697241) (xy 53.171095 -274.720584) (xy 53.212691 -274.750805) (xy 53.249047 -274.787161)
			(xy 53.279268 -274.828757) (xy 53.302611 -274.874569) (xy 53.318499 -274.923468) (xy 53.326542 -274.97425)
			(xy 53.327046 -274.999958) (xy 53.64405 -274.999958) (xy 53.64801 -274.950904) (xy 53.659787 -274.90312)
			(xy 53.679078 -274.857844) (xy 53.705381 -274.816248) (xy 53.738016 -274.779411) (xy 53.776137 -274.748286)
			(xy 53.818758 -274.723679) (xy 53.864774 -274.706227) (xy 53.912993 -274.696383) (xy 53.962168 -274.694402)
			(xy 54.011023 -274.700334) (xy 54.058294 -274.714026) (xy 54.102756 -274.735124) (xy 54.143259 -274.76308)
			(xy 54.178752 -274.797172) (xy 54.208317 -274.836516) (xy 54.231188 -274.880093) (xy 54.246772 -274.926774)
			(xy 54.254667 -274.975351) (xy 54.255162 -274.999958) (xy 54.254667 -275.024565) (xy 54.254488 -275.025666)
			(xy 54.573166 -275.025666) (xy 54.573166 -274.97425) (xy 54.581209 -274.923468) (xy 54.597097 -274.874569)
			(xy 54.62044 -274.828757) (xy 54.650661 -274.787161) (xy 54.687017 -274.750805) (xy 54.728613 -274.720584)
			(xy 54.774425 -274.697241) (xy 54.823324 -274.681353) (xy 54.874106 -274.67331) (xy 54.925522 -274.67331)
			(xy 54.976304 -274.681353) (xy 55.025203 -274.697241) (xy 55.071015 -274.720584) (xy 55.112611 -274.750805)
			(xy 55.148967 -274.787161) (xy 55.179188 -274.828757) (xy 55.202531 -274.874569) (xy 55.218419 -274.923468)
			(xy 55.226462 -274.97425) (xy 55.226966 -274.999958) (xy 55.54397 -274.999958) (xy 55.54793 -274.950904)
			(xy 55.559707 -274.90312) (xy 55.578998 -274.857844) (xy 55.605301 -274.816248) (xy 55.637936 -274.779411)
			(xy 55.676057 -274.748286) (xy 55.718678 -274.723679) (xy 55.764694 -274.706227) (xy 55.812913 -274.696383)
			(xy 55.862088 -274.694402) (xy 55.910943 -274.700334) (xy 55.958214 -274.714026) (xy 56.002676 -274.735124)
			(xy 56.043179 -274.76308) (xy 56.078672 -274.797172) (xy 56.108237 -274.836516) (xy 56.131108 -274.880093)
			(xy 56.146692 -274.926774) (xy 56.154587 -274.975351) (xy 56.155082 -274.999958) (xy 56.154587 -275.024565)
			(xy 56.154408 -275.025666) (xy 56.47334 -275.025666) (xy 56.47334 -274.97425) (xy 56.481383 -274.923468)
			(xy 56.497271 -274.874569) (xy 56.520614 -274.828757) (xy 56.550835 -274.787161) (xy 56.587191 -274.750805)
			(xy 56.628787 -274.720584) (xy 56.674599 -274.697241) (xy 56.723498 -274.681353) (xy 56.77428 -274.67331)
			(xy 56.825696 -274.67331) (xy 56.876478 -274.681353) (xy 56.925377 -274.697241) (xy 56.971189 -274.720584)
			(xy 57.012785 -274.750805) (xy 57.049141 -274.787161) (xy 57.079362 -274.828757) (xy 57.102705 -274.874569)
			(xy 57.118593 -274.923468) (xy 57.126636 -274.97425) (xy 57.12714 -274.999958) (xy 57.444144 -274.999958)
			(xy 57.448104 -274.950904) (xy 57.459881 -274.90312) (xy 57.479172 -274.857844) (xy 57.505475 -274.816248)
			(xy 57.53811 -274.779411) (xy 57.576231 -274.748286) (xy 57.618852 -274.723679) (xy 57.664868 -274.706227)
			(xy 57.713087 -274.696383) (xy 57.762262 -274.694402) (xy 57.811117 -274.700334) (xy 57.858388 -274.714026)
			(xy 57.90285 -274.735124) (xy 57.943353 -274.76308) (xy 57.978846 -274.797172) (xy 58.008411 -274.836516)
			(xy 58.031282 -274.880093) (xy 58.046866 -274.926774) (xy 58.054761 -274.975351) (xy 58.055256 -274.999958)
			(xy 58.054761 -275.024565) (xy 58.054582 -275.025666) (xy 58.37326 -275.025666) (xy 58.37326 -274.97425)
			(xy 58.381303 -274.923468) (xy 58.397191 -274.874569) (xy 58.420534 -274.828757) (xy 58.450755 -274.787161)
			(xy 58.487111 -274.750805) (xy 58.528707 -274.720584) (xy 58.574519 -274.697241) (xy 58.623418 -274.681353)
			(xy 58.6742 -274.67331) (xy 58.725616 -274.67331) (xy 58.776398 -274.681353) (xy 58.825297 -274.697241)
			(xy 58.871109 -274.720584) (xy 58.912705 -274.750805) (xy 58.949061 -274.787161) (xy 58.979282 -274.828757)
			(xy 59.002625 -274.874569) (xy 59.018513 -274.923468) (xy 59.026556 -274.97425) (xy 59.02706 -274.999958)
			(xy 59.344064 -274.999958) (xy 59.348024 -274.950904) (xy 59.359801 -274.90312) (xy 59.379092 -274.857844)
			(xy 59.405395 -274.816248) (xy 59.43803 -274.779411) (xy 59.476151 -274.748286) (xy 59.518772 -274.723679)
			(xy 59.564788 -274.706227) (xy 59.613007 -274.696383) (xy 59.662182 -274.694402) (xy 59.711037 -274.700334)
			(xy 59.758308 -274.714026) (xy 59.80277 -274.735124) (xy 59.843273 -274.76308) (xy 59.878766 -274.797172)
			(xy 59.908331 -274.836516) (xy 59.931202 -274.880093) (xy 59.946786 -274.926774) (xy 59.954681 -274.975351)
			(xy 59.955176 -274.999958) (xy 59.954681 -275.024565) (xy 59.954543 -275.025412) (xy 60.272926 -275.025412)
			(xy 60.272926 -274.973996) (xy 60.280969 -274.923214) (xy 60.296857 -274.874315) (xy 60.3202 -274.828503)
			(xy 60.350421 -274.786907) (xy 60.386777 -274.750551) (xy 60.428373 -274.72033) (xy 60.474185 -274.696987)
			(xy 60.523084 -274.681099) (xy 60.573866 -274.673056) (xy 60.625282 -274.673056) (xy 60.676064 -274.681099)
			(xy 60.724963 -274.696987) (xy 60.770775 -274.72033) (xy 60.812371 -274.750551) (xy 60.848727 -274.786907)
			(xy 60.878948 -274.828503) (xy 60.902291 -274.874315) (xy 60.918179 -274.923214) (xy 60.926222 -274.973996)
			(xy 60.926726 -274.999704) (xy 60.926721 -274.999958) (xy 61.243984 -274.999958) (xy 61.247944 -274.950904)
			(xy 61.259721 -274.90312) (xy 61.279012 -274.857844) (xy 61.305315 -274.816248) (xy 61.33795 -274.779411)
			(xy 61.376071 -274.748286) (xy 61.418692 -274.723679) (xy 61.464708 -274.706227) (xy 61.512927 -274.696383)
			(xy 61.562102 -274.694402) (xy 61.610957 -274.700334) (xy 61.658228 -274.714026) (xy 61.70269 -274.735124)
			(xy 61.743193 -274.76308) (xy 61.778686 -274.797172) (xy 61.808251 -274.836516) (xy 61.831122 -274.880093)
			(xy 61.846706 -274.926774) (xy 61.854601 -274.975351) (xy 61.855096 -274.999958) (xy 61.854601 -275.024565)
			(xy 61.854422 -275.025666) (xy 62.172846 -275.025666) (xy 62.172846 -274.97425) (xy 62.180889 -274.923468)
			(xy 62.196777 -274.874569) (xy 62.22012 -274.828757) (xy 62.250341 -274.787161) (xy 62.286697 -274.750805)
			(xy 62.328293 -274.720584) (xy 62.374105 -274.697241) (xy 62.423004 -274.681353) (xy 62.473786 -274.67331)
			(xy 62.525202 -274.67331) (xy 62.575984 -274.681353) (xy 62.624883 -274.697241) (xy 62.670695 -274.720584)
			(xy 62.712291 -274.750805) (xy 62.748647 -274.787161) (xy 62.778868 -274.828757) (xy 62.802211 -274.874569)
			(xy 62.818099 -274.923468) (xy 62.826142 -274.97425) (xy 62.826646 -274.999958) (xy 63.144158 -274.999958)
			(xy 63.148118 -274.950904) (xy 63.159895 -274.90312) (xy 63.179186 -274.857844) (xy 63.205489 -274.816248)
			(xy 63.238124 -274.779411) (xy 63.276245 -274.748286) (xy 63.318866 -274.723679) (xy 63.364882 -274.706227)
			(xy 63.413101 -274.696383) (xy 63.462276 -274.694402) (xy 63.511131 -274.700334) (xy 63.558402 -274.714026)
			(xy 63.602864 -274.735124) (xy 63.643367 -274.76308) (xy 63.67886 -274.797172) (xy 63.708425 -274.836516)
			(xy 63.731296 -274.880093) (xy 63.74688 -274.926774) (xy 63.754775 -274.975351) (xy 63.75527 -274.999958)
			(xy 63.754775 -275.024565) (xy 63.754637 -275.025412) (xy 64.07302 -275.025412) (xy 64.07302 -274.973996)
			(xy 64.081063 -274.923214) (xy 64.096951 -274.874315) (xy 64.120294 -274.828503) (xy 64.150515 -274.786907)
			(xy 64.186871 -274.750551) (xy 64.228467 -274.72033) (xy 64.274279 -274.696987) (xy 64.323178 -274.681099)
			(xy 64.37396 -274.673056) (xy 64.425376 -274.673056) (xy 64.476158 -274.681099) (xy 64.525057 -274.696987)
			(xy 64.570869 -274.72033) (xy 64.612465 -274.750551) (xy 64.648821 -274.786907) (xy 64.679042 -274.828503)
			(xy 64.702385 -274.874315) (xy 64.718273 -274.923214) (xy 64.726316 -274.973996) (xy 64.72682 -274.999704)
			(xy 64.726815 -274.999958) (xy 65.044078 -274.999958) (xy 65.048038 -274.950904) (xy 65.059815 -274.90312)
			(xy 65.079106 -274.857844) (xy 65.105409 -274.816248) (xy 65.138044 -274.779411) (xy 65.176165 -274.748286)
			(xy 65.218786 -274.723679) (xy 65.264802 -274.706227) (xy 65.313021 -274.696383) (xy 65.362196 -274.694402)
			(xy 65.411051 -274.700334) (xy 65.458322 -274.714026) (xy 65.502784 -274.735124) (xy 65.543287 -274.76308)
			(xy 65.57878 -274.797172) (xy 65.608345 -274.836516) (xy 65.631216 -274.880093) (xy 65.6468 -274.926774)
			(xy 65.654695 -274.975351) (xy 65.65519 -274.999958) (xy 65.654695 -275.024565) (xy 65.654516 -275.025666)
			(xy 65.97294 -275.025666) (xy 65.97294 -274.97425) (xy 65.980983 -274.923468) (xy 65.996871 -274.874569)
			(xy 66.020214 -274.828757) (xy 66.050435 -274.787161) (xy 66.086791 -274.750805) (xy 66.128387 -274.720584)
			(xy 66.174199 -274.697241) (xy 66.223098 -274.681353) (xy 66.27388 -274.67331) (xy 66.325296 -274.67331)
			(xy 66.376078 -274.681353) (xy 66.424977 -274.697241) (xy 66.470789 -274.720584) (xy 66.512385 -274.750805)
			(xy 66.548741 -274.787161) (xy 66.578962 -274.828757) (xy 66.602305 -274.874569) (xy 66.618193 -274.923468)
			(xy 66.626236 -274.97425) (xy 66.62674 -274.999958) (xy 66.943998 -274.999958) (xy 66.947958 -274.950904)
			(xy 66.959735 -274.90312) (xy 66.979026 -274.857844) (xy 67.005329 -274.816248) (xy 67.037964 -274.779411)
			(xy 67.076085 -274.748286) (xy 67.118706 -274.723679) (xy 67.164722 -274.706227) (xy 67.212941 -274.696383)
			(xy 67.262116 -274.694402) (xy 67.310971 -274.700334) (xy 67.358242 -274.714026) (xy 67.402704 -274.735124)
			(xy 67.443207 -274.76308) (xy 67.4787 -274.797172) (xy 67.508265 -274.836516) (xy 67.531136 -274.880093)
			(xy 67.54672 -274.926774) (xy 67.554615 -274.975351) (xy 67.55511 -274.999958) (xy 67.554615 -275.024565)
			(xy 67.554477 -275.025412) (xy 67.87286 -275.025412) (xy 67.87286 -274.973996) (xy 67.880903 -274.923214)
			(xy 67.896791 -274.874315) (xy 67.920134 -274.828503) (xy 67.950355 -274.786907) (xy 67.986711 -274.750551)
			(xy 68.028307 -274.72033) (xy 68.074119 -274.696987) (xy 68.123018 -274.681099) (xy 68.1738 -274.673056)
			(xy 68.225216 -274.673056) (xy 68.275998 -274.681099) (xy 68.324897 -274.696987) (xy 68.370709 -274.72033)
			(xy 68.412305 -274.750551) (xy 68.448661 -274.786907) (xy 68.478882 -274.828503) (xy 68.502225 -274.874315)
			(xy 68.518113 -274.923214) (xy 68.526156 -274.973996) (xy 68.52666 -274.999704) (xy 68.526655 -274.999958)
			(xy 68.844172 -274.999958) (xy 68.848132 -274.950904) (xy 68.859909 -274.90312) (xy 68.8792 -274.857844)
			(xy 68.905503 -274.816248) (xy 68.938138 -274.779411) (xy 68.976259 -274.748286) (xy 69.01888 -274.723679)
			(xy 69.064896 -274.706227) (xy 69.113115 -274.696383) (xy 69.16229 -274.694402) (xy 69.211145 -274.700334)
			(xy 69.258416 -274.714026) (xy 69.302878 -274.735124) (xy 69.343381 -274.76308) (xy 69.378874 -274.797172)
			(xy 69.408439 -274.836516) (xy 69.43131 -274.880093) (xy 69.446894 -274.926774) (xy 69.454789 -274.975351)
			(xy 69.455284 -274.999958) (xy 69.454789 -275.024565) (xy 69.45461 -275.025666) (xy 69.77278 -275.025666)
			(xy 69.77278 -274.97425) (xy 69.780823 -274.923468) (xy 69.796711 -274.874569) (xy 69.820054 -274.828757)
			(xy 69.850275 -274.787161) (xy 69.886631 -274.750805) (xy 69.928227 -274.720584) (xy 69.974039 -274.697241)
			(xy 70.022938 -274.681353) (xy 70.07372 -274.67331) (xy 70.125136 -274.67331) (xy 70.175918 -274.681353)
			(xy 70.224817 -274.697241) (xy 70.270629 -274.720584) (xy 70.312225 -274.750805) (xy 70.348581 -274.787161)
			(xy 70.378802 -274.828757) (xy 70.402145 -274.874569) (xy 70.418033 -274.923468) (xy 70.426076 -274.97425)
			(xy 70.42658 -274.999958) (xy 70.744092 -274.999958) (xy 70.748052 -274.950904) (xy 70.759829 -274.90312)
			(xy 70.77912 -274.857844) (xy 70.805423 -274.816248) (xy 70.838058 -274.779411) (xy 70.876179 -274.748286)
			(xy 70.9188 -274.723679) (xy 70.964816 -274.706227) (xy 71.013035 -274.696383) (xy 71.06221 -274.694402)
			(xy 71.111065 -274.700334) (xy 71.158336 -274.714026) (xy 71.202798 -274.735124) (xy 71.243301 -274.76308)
			(xy 71.278794 -274.797172) (xy 71.308359 -274.836516) (xy 71.33123 -274.880093) (xy 71.346814 -274.926774)
			(xy 71.354709 -274.975351) (xy 71.355204 -274.999958) (xy 71.354709 -275.024565) (xy 71.354571 -275.025412)
			(xy 71.672954 -275.025412) (xy 71.672954 -274.973996) (xy 71.680997 -274.923214) (xy 71.696885 -274.874315)
			(xy 71.720228 -274.828503) (xy 71.750449 -274.786907) (xy 71.786805 -274.750551) (xy 71.828401 -274.72033)
			(xy 71.874213 -274.696987) (xy 71.923112 -274.681099) (xy 71.973894 -274.673056) (xy 72.02531 -274.673056)
			(xy 72.076092 -274.681099) (xy 72.124991 -274.696987) (xy 72.170803 -274.72033) (xy 72.212399 -274.750551)
			(xy 72.248755 -274.786907) (xy 72.278976 -274.828503) (xy 72.302319 -274.874315) (xy 72.318207 -274.923214)
			(xy 72.32625 -274.973996) (xy 72.326754 -274.999704) (xy 72.326749 -274.999958) (xy 72.644012 -274.999958)
			(xy 72.647972 -274.950904) (xy 72.659749 -274.90312) (xy 72.67904 -274.857844) (xy 72.705343 -274.816248)
			(xy 72.737978 -274.779411) (xy 72.776099 -274.748286) (xy 72.81872 -274.723679) (xy 72.864736 -274.706227)
			(xy 72.912955 -274.696383) (xy 72.96213 -274.694402) (xy 73.010985 -274.700334) (xy 73.058256 -274.714026)
			(xy 73.102718 -274.735124) (xy 73.143221 -274.76308) (xy 73.178714 -274.797172) (xy 73.208279 -274.836516)
			(xy 73.23115 -274.880093) (xy 73.246734 -274.926774) (xy 73.254629 -274.975351) (xy 73.255124 -274.999958)
			(xy 73.254629 -275.024565) (xy 73.25445 -275.025666) (xy 73.572874 -275.025666) (xy 73.572874 -274.97425)
			(xy 73.580917 -274.923468) (xy 73.596805 -274.874569) (xy 73.620148 -274.828757) (xy 73.650369 -274.787161)
			(xy 73.686725 -274.750805) (xy 73.728321 -274.720584) (xy 73.774133 -274.697241) (xy 73.823032 -274.681353)
			(xy 73.873814 -274.67331) (xy 73.92523 -274.67331) (xy 73.976012 -274.681353) (xy 74.024911 -274.697241)
			(xy 74.070723 -274.720584) (xy 74.112319 -274.750805) (xy 74.148675 -274.787161) (xy 74.178896 -274.828757)
			(xy 74.202239 -274.874569) (xy 74.218127 -274.923468) (xy 74.22617 -274.97425) (xy 74.226674 -274.999958)
			(xy 74.543932 -274.999958) (xy 74.547892 -274.950904) (xy 74.559669 -274.90312) (xy 74.57896 -274.857844)
			(xy 74.605263 -274.816248) (xy 74.637898 -274.779411) (xy 74.676019 -274.748286) (xy 74.71864 -274.723679)
			(xy 74.764656 -274.706227) (xy 74.812875 -274.696383) (xy 74.86205 -274.694402) (xy 74.910905 -274.700334)
			(xy 74.958176 -274.714026) (xy 75.002638 -274.735124) (xy 75.043141 -274.76308) (xy 75.078634 -274.797172)
			(xy 75.108199 -274.836516) (xy 75.13107 -274.880093) (xy 75.146654 -274.926774) (xy 75.154549 -274.975351)
			(xy 75.155044 -274.999958) (xy 75.154549 -275.024565) (xy 75.154411 -275.025412) (xy 75.473048 -275.025412)
			(xy 75.473048 -274.973996) (xy 75.481091 -274.923214) (xy 75.496979 -274.874315) (xy 75.520322 -274.828503)
			(xy 75.550543 -274.786907) (xy 75.586899 -274.750551) (xy 75.628495 -274.72033) (xy 75.674307 -274.696987)
			(xy 75.723206 -274.681099) (xy 75.773988 -274.673056) (xy 75.825404 -274.673056) (xy 75.876186 -274.681099)
			(xy 75.925085 -274.696987) (xy 75.970897 -274.72033) (xy 76.012493 -274.750551) (xy 76.048849 -274.786907)
			(xy 76.07907 -274.828503) (xy 76.102413 -274.874315) (xy 76.118301 -274.923214) (xy 76.126344 -274.973996)
			(xy 76.126848 -274.999704) (xy 76.126843 -274.999958) (xy 76.443852 -274.999958) (xy 76.447812 -274.950904)
			(xy 76.459589 -274.90312) (xy 76.47888 -274.857844) (xy 76.505183 -274.816248) (xy 76.537818 -274.779411)
			(xy 76.575939 -274.748286) (xy 76.61856 -274.723679) (xy 76.664576 -274.706227) (xy 76.712795 -274.696383)
			(xy 76.76197 -274.694402) (xy 76.810825 -274.700334) (xy 76.858096 -274.714026) (xy 76.902558 -274.735124)
			(xy 76.943061 -274.76308) (xy 76.978554 -274.797172) (xy 77.008119 -274.836516) (xy 77.03099 -274.880093)
			(xy 77.046574 -274.926774) (xy 77.054469 -274.975351) (xy 77.054964 -274.999958) (xy 77.054469 -275.024565)
			(xy 77.05429 -275.025666) (xy 77.372968 -275.025666) (xy 77.372968 -274.97425) (xy 77.381011 -274.923468)
			(xy 77.396899 -274.874569) (xy 77.420242 -274.828757) (xy 77.450463 -274.787161) (xy 77.486819 -274.750805)
			(xy 77.528415 -274.720584) (xy 77.574227 -274.697241) (xy 77.623126 -274.681353) (xy 77.673908 -274.67331)
			(xy 77.725324 -274.67331) (xy 77.776106 -274.681353) (xy 77.825005 -274.697241) (xy 77.870817 -274.720584)
			(xy 77.912413 -274.750805) (xy 77.948769 -274.787161) (xy 77.97899 -274.828757) (xy 78.002333 -274.874569)
			(xy 78.018221 -274.923468) (xy 78.026264 -274.97425) (xy 78.026768 -274.999958) (xy 78.343772 -274.999958)
			(xy 78.347732 -274.950904) (xy 78.359509 -274.90312) (xy 78.3788 -274.857844) (xy 78.405103 -274.816248)
			(xy 78.437738 -274.779411) (xy 78.475859 -274.748286) (xy 78.51848 -274.723679) (xy 78.564496 -274.706227)
			(xy 78.612715 -274.696383) (xy 78.66189 -274.694402) (xy 78.710745 -274.700334) (xy 78.758016 -274.714026)
			(xy 78.802478 -274.735124) (xy 78.842981 -274.76308) (xy 78.878474 -274.797172) (xy 78.908039 -274.836516)
			(xy 78.93091 -274.880093) (xy 78.946494 -274.926774) (xy 78.954389 -274.975351) (xy 78.954884 -274.999958)
			(xy 78.954389 -275.024565) (xy 78.95421 -275.025666) (xy 79.272888 -275.025666) (xy 79.272888 -274.97425)
			(xy 79.280931 -274.923468) (xy 79.296819 -274.874569) (xy 79.320162 -274.828757) (xy 79.350383 -274.787161)
			(xy 79.386739 -274.750805) (xy 79.428335 -274.720584) (xy 79.474147 -274.697241) (xy 79.523046 -274.681353)
			(xy 79.573828 -274.67331) (xy 79.625244 -274.67331) (xy 79.676026 -274.681353) (xy 79.724925 -274.697241)
			(xy 79.770737 -274.720584) (xy 79.812333 -274.750805) (xy 79.848689 -274.787161) (xy 79.87891 -274.828757)
			(xy 79.902253 -274.874569) (xy 79.918141 -274.923468) (xy 79.926184 -274.97425) (xy 79.926688 -274.999958)
			(xy 80.243946 -274.999958) (xy 80.247906 -274.950904) (xy 80.259683 -274.90312) (xy 80.278974 -274.857844)
			(xy 80.305277 -274.816248) (xy 80.337912 -274.779411) (xy 80.376033 -274.748286) (xy 80.418654 -274.723679)
			(xy 80.46467 -274.706227) (xy 80.512889 -274.696383) (xy 80.562064 -274.694402) (xy 80.610919 -274.700334)
			(xy 80.65819 -274.714026) (xy 80.702652 -274.735124) (xy 80.743155 -274.76308) (xy 80.778648 -274.797172)
			(xy 80.808213 -274.836516) (xy 80.831084 -274.880093) (xy 80.846668 -274.926774) (xy 80.854563 -274.975351)
			(xy 80.855058 -274.999958) (xy 80.854563 -275.024565) (xy 80.854425 -275.025412) (xy 81.173316 -275.025412)
			(xy 81.173316 -274.973996) (xy 81.181359 -274.923214) (xy 81.197247 -274.874315) (xy 81.22059 -274.828503)
			(xy 81.250811 -274.786907) (xy 81.287167 -274.750551) (xy 81.328763 -274.72033) (xy 81.374575 -274.696987)
			(xy 81.423474 -274.681099) (xy 81.474256 -274.673056) (xy 81.525672 -274.673056) (xy 81.576454 -274.681099)
			(xy 81.625353 -274.696987) (xy 81.671165 -274.72033) (xy 81.712761 -274.750551) (xy 81.749117 -274.786907)
			(xy 81.779338 -274.828503) (xy 81.802681 -274.874315) (xy 81.818569 -274.923214) (xy 81.826612 -274.973996)
			(xy 81.827116 -274.999704) (xy 81.826612 -275.025412) (xy 82.123276 -275.025412) (xy 82.123276 -274.973996)
			(xy 82.131319 -274.923214) (xy 82.147207 -274.874315) (xy 82.17055 -274.828503) (xy 82.200771 -274.786907)
			(xy 82.237127 -274.750551) (xy 82.278723 -274.72033) (xy 82.324535 -274.696987) (xy 82.373434 -274.681099)
			(xy 82.424216 -274.673056) (xy 82.475632 -274.673056) (xy 82.526414 -274.681099) (xy 82.575313 -274.696987)
			(xy 82.621125 -274.72033) (xy 82.662721 -274.750551) (xy 82.699077 -274.786907) (xy 82.729298 -274.828503)
			(xy 82.752641 -274.874315) (xy 82.768529 -274.923214) (xy 82.776572 -274.973996) (xy 82.777076 -274.999704)
			(xy 82.777071 -274.999958) (xy 83.094334 -274.999958) (xy 83.098294 -274.950904) (xy 83.110071 -274.90312)
			(xy 83.129362 -274.857844) (xy 83.155665 -274.816248) (xy 83.1883 -274.779411) (xy 83.226421 -274.748286)
			(xy 83.269042 -274.723679) (xy 83.315058 -274.706227) (xy 83.363277 -274.696383) (xy 83.412452 -274.694402)
			(xy 83.461307 -274.700334) (xy 83.508578 -274.714026) (xy 83.55304 -274.735124) (xy 83.593543 -274.76308)
			(xy 83.629036 -274.797172) (xy 83.658601 -274.836516) (xy 83.681472 -274.880093) (xy 83.697056 -274.926774)
			(xy 83.704951 -274.975351) (xy 83.705446 -274.999958) (xy 83.704951 -275.024565) (xy 83.697056 -275.073142)
			(xy 83.681472 -275.119823) (xy 83.658601 -275.1634) (xy 83.629036 -275.202744) (xy 83.593543 -275.236836)
			(xy 83.55304 -275.264792) (xy 83.508578 -275.28589) (xy 83.461307 -275.299582) (xy 83.412452 -275.305514)
			(xy 83.363277 -275.303533) (xy 83.315058 -275.293689) (xy 83.269042 -275.276237) (xy 83.226421 -275.25163)
			(xy 83.1883 -275.220505) (xy 83.155665 -275.183668) (xy 83.129362 -275.142072) (xy 83.110071 -275.096796)
			(xy 83.098294 -275.049012) (xy 83.094334 -274.999958) (xy 82.777071 -274.999958) (xy 82.776572 -275.025412)
			(xy 82.768529 -275.076194) (xy 82.752641 -275.125093) (xy 82.729298 -275.170905) (xy 82.699077 -275.212501)
			(xy 82.662721 -275.248857) (xy 82.621125 -275.279078) (xy 82.575313 -275.302421) (xy 82.526414 -275.318309)
			(xy 82.475632 -275.326352) (xy 82.424216 -275.326352) (xy 82.373434 -275.318309) (xy 82.324535 -275.302421)
			(xy 82.278723 -275.279078) (xy 82.237127 -275.248857) (xy 82.200771 -275.212501) (xy 82.17055 -275.170905)
			(xy 82.147207 -275.125093) (xy 82.131319 -275.076194) (xy 82.123276 -275.025412) (xy 81.826612 -275.025412)
			(xy 81.818569 -275.076194) (xy 81.802681 -275.125093) (xy 81.779338 -275.170905) (xy 81.749117 -275.212501)
			(xy 81.712761 -275.248857) (xy 81.671165 -275.279078) (xy 81.625353 -275.302421) (xy 81.576454 -275.318309)
			(xy 81.525672 -275.326352) (xy 81.474256 -275.326352) (xy 81.423474 -275.318309) (xy 81.374575 -275.302421)
			(xy 81.328763 -275.279078) (xy 81.287167 -275.248857) (xy 81.250811 -275.212501) (xy 81.22059 -275.170905)
			(xy 81.197247 -275.125093) (xy 81.181359 -275.076194) (xy 81.173316 -275.025412) (xy 80.854425 -275.025412)
			(xy 80.846668 -275.073142) (xy 80.831084 -275.119823) (xy 80.808213 -275.1634) (xy 80.778648 -275.202744)
			(xy 80.743155 -275.236836) (xy 80.702652 -275.264792) (xy 80.65819 -275.28589) (xy 80.610919 -275.299582)
			(xy 80.562064 -275.305514) (xy 80.512889 -275.303533) (xy 80.46467 -275.293689) (xy 80.418654 -275.276237)
			(xy 80.376033 -275.25163) (xy 80.337912 -275.220505) (xy 80.305277 -275.183668) (xy 80.278974 -275.142072)
			(xy 80.259683 -275.096796) (xy 80.247906 -275.049012) (xy 80.243946 -274.999958) (xy 79.926688 -274.999958)
			(xy 79.926184 -275.025666) (xy 79.918141 -275.076448) (xy 79.902253 -275.125347) (xy 79.87891 -275.171159)
			(xy 79.848689 -275.212755) (xy 79.812333 -275.249111) (xy 79.770737 -275.279332) (xy 79.724925 -275.302675)
			(xy 79.676026 -275.318563) (xy 79.625244 -275.326606) (xy 79.573828 -275.326606) (xy 79.523046 -275.318563)
			(xy 79.474147 -275.302675) (xy 79.428335 -275.279332) (xy 79.386739 -275.249111) (xy 79.350383 -275.212755)
			(xy 79.320162 -275.171159) (xy 79.296819 -275.125347) (xy 79.280931 -275.076448) (xy 79.272888 -275.025666)
			(xy 78.95421 -275.025666) (xy 78.946494 -275.073142) (xy 78.93091 -275.119823) (xy 78.908039 -275.1634)
			(xy 78.878474 -275.202744) (xy 78.842981 -275.236836) (xy 78.802478 -275.264792) (xy 78.758016 -275.28589)
			(xy 78.710745 -275.299582) (xy 78.66189 -275.305514) (xy 78.612715 -275.303533) (xy 78.564496 -275.293689)
			(xy 78.51848 -275.276237) (xy 78.475859 -275.25163) (xy 78.437738 -275.220505) (xy 78.405103 -275.183668)
			(xy 78.3788 -275.142072) (xy 78.359509 -275.096796) (xy 78.347732 -275.049012) (xy 78.343772 -274.999958)
			(xy 78.026768 -274.999958) (xy 78.026264 -275.025666) (xy 78.018221 -275.076448) (xy 78.002333 -275.125347)
			(xy 77.97899 -275.171159) (xy 77.948769 -275.212755) (xy 77.912413 -275.249111) (xy 77.870817 -275.279332)
			(xy 77.825005 -275.302675) (xy 77.776106 -275.318563) (xy 77.725324 -275.326606) (xy 77.673908 -275.326606)
			(xy 77.623126 -275.318563) (xy 77.574227 -275.302675) (xy 77.528415 -275.279332) (xy 77.486819 -275.249111)
			(xy 77.450463 -275.212755) (xy 77.420242 -275.171159) (xy 77.396899 -275.125347) (xy 77.381011 -275.076448)
			(xy 77.372968 -275.025666) (xy 77.05429 -275.025666) (xy 77.046574 -275.073142) (xy 77.03099 -275.119823)
			(xy 77.008119 -275.1634) (xy 76.978554 -275.202744) (xy 76.943061 -275.236836) (xy 76.902558 -275.264792)
			(xy 76.858096 -275.28589) (xy 76.810825 -275.299582) (xy 76.76197 -275.305514) (xy 76.712795 -275.303533)
			(xy 76.664576 -275.293689) (xy 76.61856 -275.276237) (xy 76.575939 -275.25163) (xy 76.537818 -275.220505)
			(xy 76.505183 -275.183668) (xy 76.47888 -275.142072) (xy 76.459589 -275.096796) (xy 76.447812 -275.049012)
			(xy 76.443852 -274.999958) (xy 76.126843 -274.999958) (xy 76.126344 -275.025412) (xy 76.118301 -275.076194)
			(xy 76.102413 -275.125093) (xy 76.07907 -275.170905) (xy 76.048849 -275.212501) (xy 76.012493 -275.248857)
			(xy 75.970897 -275.279078) (xy 75.925085 -275.302421) (xy 75.876186 -275.318309) (xy 75.825404 -275.326352)
			(xy 75.773988 -275.326352) (xy 75.723206 -275.318309) (xy 75.674307 -275.302421) (xy 75.628495 -275.279078)
			(xy 75.586899 -275.248857) (xy 75.550543 -275.212501) (xy 75.520322 -275.170905) (xy 75.496979 -275.125093)
			(xy 75.481091 -275.076194) (xy 75.473048 -275.025412) (xy 75.154411 -275.025412) (xy 75.146654 -275.073142)
			(xy 75.13107 -275.119823) (xy 75.108199 -275.1634) (xy 75.078634 -275.202744) (xy 75.043141 -275.236836)
			(xy 75.002638 -275.264792) (xy 74.958176 -275.28589) (xy 74.910905 -275.299582) (xy 74.86205 -275.305514)
			(xy 74.812875 -275.303533) (xy 74.764656 -275.293689) (xy 74.71864 -275.276237) (xy 74.676019 -275.25163)
			(xy 74.637898 -275.220505) (xy 74.605263 -275.183668) (xy 74.57896 -275.142072) (xy 74.559669 -275.096796)
			(xy 74.547892 -275.049012) (xy 74.543932 -274.999958) (xy 74.226674 -274.999958) (xy 74.22617 -275.025666)
			(xy 74.218127 -275.076448) (xy 74.202239 -275.125347) (xy 74.178896 -275.171159) (xy 74.148675 -275.212755)
			(xy 74.112319 -275.249111) (xy 74.070723 -275.279332) (xy 74.024911 -275.302675) (xy 73.976012 -275.318563)
			(xy 73.92523 -275.326606) (xy 73.873814 -275.326606) (xy 73.823032 -275.318563) (xy 73.774133 -275.302675)
			(xy 73.728321 -275.279332) (xy 73.686725 -275.249111) (xy 73.650369 -275.212755) (xy 73.620148 -275.171159)
			(xy 73.596805 -275.125347) (xy 73.580917 -275.076448) (xy 73.572874 -275.025666) (xy 73.25445 -275.025666)
			(xy 73.246734 -275.073142) (xy 73.23115 -275.119823) (xy 73.208279 -275.1634) (xy 73.178714 -275.202744)
			(xy 73.143221 -275.236836) (xy 73.102718 -275.264792) (xy 73.058256 -275.28589) (xy 73.010985 -275.299582)
			(xy 72.96213 -275.305514) (xy 72.912955 -275.303533) (xy 72.864736 -275.293689) (xy 72.81872 -275.276237)
			(xy 72.776099 -275.25163) (xy 72.737978 -275.220505) (xy 72.705343 -275.183668) (xy 72.67904 -275.142072)
			(xy 72.659749 -275.096796) (xy 72.647972 -275.049012) (xy 72.644012 -274.999958) (xy 72.326749 -274.999958)
			(xy 72.32625 -275.025412) (xy 72.318207 -275.076194) (xy 72.302319 -275.125093) (xy 72.278976 -275.170905)
			(xy 72.248755 -275.212501) (xy 72.212399 -275.248857) (xy 72.170803 -275.279078) (xy 72.124991 -275.302421)
			(xy 72.076092 -275.318309) (xy 72.02531 -275.326352) (xy 71.973894 -275.326352) (xy 71.923112 -275.318309)
			(xy 71.874213 -275.302421) (xy 71.828401 -275.279078) (xy 71.786805 -275.248857) (xy 71.750449 -275.212501)
			(xy 71.720228 -275.170905) (xy 71.696885 -275.125093) (xy 71.680997 -275.076194) (xy 71.672954 -275.025412)
			(xy 71.354571 -275.025412) (xy 71.346814 -275.073142) (xy 71.33123 -275.119823) (xy 71.308359 -275.1634)
			(xy 71.278794 -275.202744) (xy 71.243301 -275.236836) (xy 71.202798 -275.264792) (xy 71.158336 -275.28589)
			(xy 71.111065 -275.299582) (xy 71.06221 -275.305514) (xy 71.013035 -275.303533) (xy 70.964816 -275.293689)
			(xy 70.9188 -275.276237) (xy 70.876179 -275.25163) (xy 70.838058 -275.220505) (xy 70.805423 -275.183668)
			(xy 70.77912 -275.142072) (xy 70.759829 -275.096796) (xy 70.748052 -275.049012) (xy 70.744092 -274.999958)
			(xy 70.42658 -274.999958) (xy 70.426076 -275.025666) (xy 70.418033 -275.076448) (xy 70.402145 -275.125347)
			(xy 70.378802 -275.171159) (xy 70.348581 -275.212755) (xy 70.312225 -275.249111) (xy 70.270629 -275.279332)
			(xy 70.224817 -275.302675) (xy 70.175918 -275.318563) (xy 70.125136 -275.326606) (xy 70.07372 -275.326606)
			(xy 70.022938 -275.318563) (xy 69.974039 -275.302675) (xy 69.928227 -275.279332) (xy 69.886631 -275.249111)
			(xy 69.850275 -275.212755) (xy 69.820054 -275.171159) (xy 69.796711 -275.125347) (xy 69.780823 -275.076448)
			(xy 69.77278 -275.025666) (xy 69.45461 -275.025666) (xy 69.446894 -275.073142) (xy 69.43131 -275.119823)
			(xy 69.408439 -275.1634) (xy 69.378874 -275.202744) (xy 69.343381 -275.236836) (xy 69.302878 -275.264792)
			(xy 69.258416 -275.28589) (xy 69.211145 -275.299582) (xy 69.16229 -275.305514) (xy 69.113115 -275.303533)
			(xy 69.064896 -275.293689) (xy 69.01888 -275.276237) (xy 68.976259 -275.25163) (xy 68.938138 -275.220505)
			(xy 68.905503 -275.183668) (xy 68.8792 -275.142072) (xy 68.859909 -275.096796) (xy 68.848132 -275.049012)
			(xy 68.844172 -274.999958) (xy 68.526655 -274.999958) (xy 68.526156 -275.025412) (xy 68.518113 -275.076194)
			(xy 68.502225 -275.125093) (xy 68.478882 -275.170905) (xy 68.448661 -275.212501) (xy 68.412305 -275.248857)
			(xy 68.370709 -275.279078) (xy 68.324897 -275.302421) (xy 68.275998 -275.318309) (xy 68.225216 -275.326352)
			(xy 68.1738 -275.326352) (xy 68.123018 -275.318309) (xy 68.074119 -275.302421) (xy 68.028307 -275.279078)
			(xy 67.986711 -275.248857) (xy 67.950355 -275.212501) (xy 67.920134 -275.170905) (xy 67.896791 -275.125093)
			(xy 67.880903 -275.076194) (xy 67.87286 -275.025412) (xy 67.554477 -275.025412) (xy 67.54672 -275.073142)
			(xy 67.531136 -275.119823) (xy 67.508265 -275.1634) (xy 67.4787 -275.202744) (xy 67.443207 -275.236836)
			(xy 67.402704 -275.264792) (xy 67.358242 -275.28589) (xy 67.310971 -275.299582) (xy 67.262116 -275.305514)
			(xy 67.212941 -275.303533) (xy 67.164722 -275.293689) (xy 67.118706 -275.276237) (xy 67.076085 -275.25163)
			(xy 67.037964 -275.220505) (xy 67.005329 -275.183668) (xy 66.979026 -275.142072) (xy 66.959735 -275.096796)
			(xy 66.947958 -275.049012) (xy 66.943998 -274.999958) (xy 66.62674 -274.999958) (xy 66.626236 -275.025666)
			(xy 66.618193 -275.076448) (xy 66.602305 -275.125347) (xy 66.578962 -275.171159) (xy 66.548741 -275.212755)
			(xy 66.512385 -275.249111) (xy 66.470789 -275.279332) (xy 66.424977 -275.302675) (xy 66.376078 -275.318563)
			(xy 66.325296 -275.326606) (xy 66.27388 -275.326606) (xy 66.223098 -275.318563) (xy 66.174199 -275.302675)
			(xy 66.128387 -275.279332) (xy 66.086791 -275.249111) (xy 66.050435 -275.212755) (xy 66.020214 -275.171159)
			(xy 65.996871 -275.125347) (xy 65.980983 -275.076448) (xy 65.97294 -275.025666) (xy 65.654516 -275.025666)
			(xy 65.6468 -275.073142) (xy 65.631216 -275.119823) (xy 65.608345 -275.1634) (xy 65.57878 -275.202744)
			(xy 65.543287 -275.236836) (xy 65.502784 -275.264792) (xy 65.458322 -275.28589) (xy 65.411051 -275.299582)
			(xy 65.362196 -275.305514) (xy 65.313021 -275.303533) (xy 65.264802 -275.293689) (xy 65.218786 -275.276237)
			(xy 65.176165 -275.25163) (xy 65.138044 -275.220505) (xy 65.105409 -275.183668) (xy 65.079106 -275.142072)
			(xy 65.059815 -275.096796) (xy 65.048038 -275.049012) (xy 65.044078 -274.999958) (xy 64.726815 -274.999958)
			(xy 64.726316 -275.025412) (xy 64.718273 -275.076194) (xy 64.702385 -275.125093) (xy 64.679042 -275.170905)
			(xy 64.648821 -275.212501) (xy 64.612465 -275.248857) (xy 64.570869 -275.279078) (xy 64.525057 -275.302421)
			(xy 64.476158 -275.318309) (xy 64.425376 -275.326352) (xy 64.37396 -275.326352) (xy 64.323178 -275.318309)
			(xy 64.274279 -275.302421) (xy 64.228467 -275.279078) (xy 64.186871 -275.248857) (xy 64.150515 -275.212501)
			(xy 64.120294 -275.170905) (xy 64.096951 -275.125093) (xy 64.081063 -275.076194) (xy 64.07302 -275.025412)
			(xy 63.754637 -275.025412) (xy 63.74688 -275.073142) (xy 63.731296 -275.119823) (xy 63.708425 -275.1634)
			(xy 63.67886 -275.202744) (xy 63.643367 -275.236836) (xy 63.602864 -275.264792) (xy 63.558402 -275.28589)
			(xy 63.511131 -275.299582) (xy 63.462276 -275.305514) (xy 63.413101 -275.303533) (xy 63.364882 -275.293689)
			(xy 63.318866 -275.276237) (xy 63.276245 -275.25163) (xy 63.238124 -275.220505) (xy 63.205489 -275.183668)
			(xy 63.179186 -275.142072) (xy 63.159895 -275.096796) (xy 63.148118 -275.049012) (xy 63.144158 -274.999958)
			(xy 62.826646 -274.999958) (xy 62.826142 -275.025666) (xy 62.818099 -275.076448) (xy 62.802211 -275.125347)
			(xy 62.778868 -275.171159) (xy 62.748647 -275.212755) (xy 62.712291 -275.249111) (xy 62.670695 -275.279332)
			(xy 62.624883 -275.302675) (xy 62.575984 -275.318563) (xy 62.525202 -275.326606) (xy 62.473786 -275.326606)
			(xy 62.423004 -275.318563) (xy 62.374105 -275.302675) (xy 62.328293 -275.279332) (xy 62.286697 -275.249111)
			(xy 62.250341 -275.212755) (xy 62.22012 -275.171159) (xy 62.196777 -275.125347) (xy 62.180889 -275.076448)
			(xy 62.172846 -275.025666) (xy 61.854422 -275.025666) (xy 61.846706 -275.073142) (xy 61.831122 -275.119823)
			(xy 61.808251 -275.1634) (xy 61.778686 -275.202744) (xy 61.743193 -275.236836) (xy 61.70269 -275.264792)
			(xy 61.658228 -275.28589) (xy 61.610957 -275.299582) (xy 61.562102 -275.305514) (xy 61.512927 -275.303533)
			(xy 61.464708 -275.293689) (xy 61.418692 -275.276237) (xy 61.376071 -275.25163) (xy 61.33795 -275.220505)
			(xy 61.305315 -275.183668) (xy 61.279012 -275.142072) (xy 61.259721 -275.096796) (xy 61.247944 -275.049012)
			(xy 61.243984 -274.999958) (xy 60.926721 -274.999958) (xy 60.926222 -275.025412) (xy 60.918179 -275.076194)
			(xy 60.902291 -275.125093) (xy 60.878948 -275.170905) (xy 60.848727 -275.212501) (xy 60.812371 -275.248857)
			(xy 60.770775 -275.279078) (xy 60.724963 -275.302421) (xy 60.676064 -275.318309) (xy 60.625282 -275.326352)
			(xy 60.573866 -275.326352) (xy 60.523084 -275.318309) (xy 60.474185 -275.302421) (xy 60.428373 -275.279078)
			(xy 60.386777 -275.248857) (xy 60.350421 -275.212501) (xy 60.3202 -275.170905) (xy 60.296857 -275.125093)
			(xy 60.280969 -275.076194) (xy 60.272926 -275.025412) (xy 59.954543 -275.025412) (xy 59.946786 -275.073142)
			(xy 59.931202 -275.119823) (xy 59.908331 -275.1634) (xy 59.878766 -275.202744) (xy 59.843273 -275.236836)
			(xy 59.80277 -275.264792) (xy 59.758308 -275.28589) (xy 59.711037 -275.299582) (xy 59.662182 -275.305514)
			(xy 59.613007 -275.303533) (xy 59.564788 -275.293689) (xy 59.518772 -275.276237) (xy 59.476151 -275.25163)
			(xy 59.43803 -275.220505) (xy 59.405395 -275.183668) (xy 59.379092 -275.142072) (xy 59.359801 -275.096796)
			(xy 59.348024 -275.049012) (xy 59.344064 -274.999958) (xy 59.02706 -274.999958) (xy 59.026556 -275.025666)
			(xy 59.018513 -275.076448) (xy 59.002625 -275.125347) (xy 58.979282 -275.171159) (xy 58.949061 -275.212755)
			(xy 58.912705 -275.249111) (xy 58.871109 -275.279332) (xy 58.825297 -275.302675) (xy 58.776398 -275.318563)
			(xy 58.725616 -275.326606) (xy 58.6742 -275.326606) (xy 58.623418 -275.318563) (xy 58.574519 -275.302675)
			(xy 58.528707 -275.279332) (xy 58.487111 -275.249111) (xy 58.450755 -275.212755) (xy 58.420534 -275.171159)
			(xy 58.397191 -275.125347) (xy 58.381303 -275.076448) (xy 58.37326 -275.025666) (xy 58.054582 -275.025666)
			(xy 58.046866 -275.073142) (xy 58.031282 -275.119823) (xy 58.008411 -275.1634) (xy 57.978846 -275.202744)
			(xy 57.943353 -275.236836) (xy 57.90285 -275.264792) (xy 57.858388 -275.28589) (xy 57.811117 -275.299582)
			(xy 57.762262 -275.305514) (xy 57.713087 -275.303533) (xy 57.664868 -275.293689) (xy 57.618852 -275.276237)
			(xy 57.576231 -275.25163) (xy 57.53811 -275.220505) (xy 57.505475 -275.183668) (xy 57.479172 -275.142072)
			(xy 57.459881 -275.096796) (xy 57.448104 -275.049012) (xy 57.444144 -274.999958) (xy 57.12714 -274.999958)
			(xy 57.126636 -275.025666) (xy 57.118593 -275.076448) (xy 57.102705 -275.125347) (xy 57.079362 -275.171159)
			(xy 57.049141 -275.212755) (xy 57.012785 -275.249111) (xy 56.971189 -275.279332) (xy 56.925377 -275.302675)
			(xy 56.876478 -275.318563) (xy 56.825696 -275.326606) (xy 56.77428 -275.326606) (xy 56.723498 -275.318563)
			(xy 56.674599 -275.302675) (xy 56.628787 -275.279332) (xy 56.587191 -275.249111) (xy 56.550835 -275.212755)
			(xy 56.520614 -275.171159) (xy 56.497271 -275.125347) (xy 56.481383 -275.076448) (xy 56.47334 -275.025666)
			(xy 56.154408 -275.025666) (xy 56.146692 -275.073142) (xy 56.131108 -275.119823) (xy 56.108237 -275.1634)
			(xy 56.078672 -275.202744) (xy 56.043179 -275.236836) (xy 56.002676 -275.264792) (xy 55.958214 -275.28589)
			(xy 55.910943 -275.299582) (xy 55.862088 -275.305514) (xy 55.812913 -275.303533) (xy 55.764694 -275.293689)
			(xy 55.718678 -275.276237) (xy 55.676057 -275.25163) (xy 55.637936 -275.220505) (xy 55.605301 -275.183668)
			(xy 55.578998 -275.142072) (xy 55.559707 -275.096796) (xy 55.54793 -275.049012) (xy 55.54397 -274.999958)
			(xy 55.226966 -274.999958) (xy 55.226462 -275.025666) (xy 55.218419 -275.076448) (xy 55.202531 -275.125347)
			(xy 55.179188 -275.171159) (xy 55.148967 -275.212755) (xy 55.112611 -275.249111) (xy 55.071015 -275.279332)
			(xy 55.025203 -275.302675) (xy 54.976304 -275.318563) (xy 54.925522 -275.326606) (xy 54.874106 -275.326606)
			(xy 54.823324 -275.318563) (xy 54.774425 -275.302675) (xy 54.728613 -275.279332) (xy 54.687017 -275.249111)
			(xy 54.650661 -275.212755) (xy 54.62044 -275.171159) (xy 54.597097 -275.125347) (xy 54.581209 -275.076448)
			(xy 54.573166 -275.025666) (xy 54.254488 -275.025666) (xy 54.246772 -275.073142) (xy 54.231188 -275.119823)
			(xy 54.208317 -275.1634) (xy 54.178752 -275.202744) (xy 54.143259 -275.236836) (xy 54.102756 -275.264792)
			(xy 54.058294 -275.28589) (xy 54.011023 -275.299582) (xy 53.962168 -275.305514) (xy 53.912993 -275.303533)
			(xy 53.864774 -275.293689) (xy 53.818758 -275.276237) (xy 53.776137 -275.25163) (xy 53.738016 -275.220505)
			(xy 53.705381 -275.183668) (xy 53.679078 -275.142072) (xy 53.659787 -275.096796) (xy 53.64801 -275.049012)
			(xy 53.64405 -274.999958) (xy 53.327046 -274.999958) (xy 53.326542 -275.025666) (xy 53.318499 -275.076448)
			(xy 53.302611 -275.125347) (xy 53.279268 -275.171159) (xy 53.249047 -275.212755) (xy 53.212691 -275.249111)
			(xy 53.171095 -275.279332) (xy 53.125283 -275.302675) (xy 53.076384 -275.318563) (xy 53.025602 -275.326606)
			(xy 52.974186 -275.326606) (xy 52.923404 -275.318563) (xy 52.874505 -275.302675) (xy 52.828693 -275.279332)
			(xy 52.787097 -275.249111) (xy 52.750741 -275.212755) (xy 52.72052 -275.171159) (xy 52.697177 -275.125347)
			(xy 52.681289 -275.076448) (xy 52.673246 -275.025666) (xy 52.354568 -275.025666) (xy 52.346852 -275.073142)
			(xy 52.331268 -275.119823) (xy 52.308397 -275.1634) (xy 52.278832 -275.202744) (xy 52.243339 -275.236836)
			(xy 52.202836 -275.264792) (xy 52.158374 -275.28589) (xy 52.111103 -275.299582) (xy 52.062248 -275.305514)
			(xy 52.013073 -275.303533) (xy 51.964854 -275.293689) (xy 51.918838 -275.276237) (xy 51.876217 -275.25163)
			(xy 51.838096 -275.220505) (xy 51.805461 -275.183668) (xy 51.779158 -275.142072) (xy 51.759867 -275.096796)
			(xy 51.74809 -275.049012) (xy 51.74413 -274.999958) (xy 51.427126 -274.999958) (xy 51.426622 -275.025666)
			(xy 51.418579 -275.076448) (xy 51.402691 -275.125347) (xy 51.379348 -275.171159) (xy 51.349127 -275.212755)
			(xy 51.312771 -275.249111) (xy 51.271175 -275.279332) (xy 51.225363 -275.302675) (xy 51.176464 -275.318563)
			(xy 51.125682 -275.326606) (xy 51.074266 -275.326606) (xy 51.023484 -275.318563) (xy 50.974585 -275.302675)
			(xy 50.928773 -275.279332) (xy 50.887177 -275.249111) (xy 50.850821 -275.212755) (xy 50.8206 -275.171159)
			(xy 50.797257 -275.125347) (xy 50.781369 -275.076448) (xy 50.773326 -275.025666) (xy 50.454394 -275.025666)
			(xy 50.446678 -275.073142) (xy 50.431094 -275.119823) (xy 50.408223 -275.1634) (xy 50.378658 -275.202744)
			(xy 50.343165 -275.236836) (xy 50.302662 -275.264792) (xy 50.2582 -275.28589) (xy 50.210929 -275.299582)
			(xy 50.162074 -275.305514) (xy 50.112899 -275.303533) (xy 50.06468 -275.293689) (xy 50.018664 -275.276237)
			(xy 49.976043 -275.25163) (xy 49.937922 -275.220505) (xy 49.905287 -275.183668) (xy 49.878984 -275.142072)
			(xy 49.859693 -275.096796) (xy 49.847916 -275.049012) (xy 49.843956 -274.999958) (xy 49.526952 -274.999958)
			(xy 49.526448 -275.025666) (xy 49.518405 -275.076448) (xy 49.502517 -275.125347) (xy 49.479174 -275.171159)
			(xy 49.448953 -275.212755) (xy 49.412597 -275.249111) (xy 49.371001 -275.279332) (xy 49.325189 -275.302675)
			(xy 49.27629 -275.318563) (xy 49.225508 -275.326606) (xy 49.174092 -275.326606) (xy 49.12331 -275.318563)
			(xy 49.074411 -275.302675) (xy 49.028599 -275.279332) (xy 48.987003 -275.249111) (xy 48.950647 -275.212755)
			(xy 48.920426 -275.171159) (xy 48.897083 -275.125347) (xy 48.881195 -275.076448) (xy 48.873152 -275.025666)
			(xy 48.554474 -275.025666) (xy 48.546758 -275.073142) (xy 48.531174 -275.119823) (xy 48.508303 -275.1634)
			(xy 48.478738 -275.202744) (xy 48.443245 -275.236836) (xy 48.402742 -275.264792) (xy 48.35828 -275.28589)
			(xy 48.311009 -275.299582) (xy 48.262154 -275.305514) (xy 48.212979 -275.303533) (xy 48.16476 -275.293689)
			(xy 48.118744 -275.276237) (xy 48.076123 -275.25163) (xy 48.038002 -275.220505) (xy 48.005367 -275.183668)
			(xy 47.979064 -275.142072) (xy 47.959773 -275.096796) (xy 47.947996 -275.049012) (xy 47.944036 -274.999958)
			(xy 47.627032 -274.999958) (xy 47.626528 -275.025666) (xy 47.618485 -275.076448) (xy 47.602597 -275.125347)
			(xy 47.579254 -275.171159) (xy 47.549033 -275.212755) (xy 47.512677 -275.249111) (xy 47.471081 -275.279332)
			(xy 47.425269 -275.302675) (xy 47.37637 -275.318563) (xy 47.325588 -275.326606) (xy 47.274172 -275.326606)
			(xy 47.22339 -275.318563) (xy 47.174491 -275.302675) (xy 47.128679 -275.279332) (xy 47.087083 -275.249111)
			(xy 47.050727 -275.212755) (xy 47.020506 -275.171159) (xy 46.997163 -275.125347) (xy 46.981275 -275.076448)
			(xy 46.973232 -275.025666) (xy 46.654554 -275.025666) (xy 46.646838 -275.073142) (xy 46.631254 -275.119823)
			(xy 46.608383 -275.1634) (xy 46.578818 -275.202744) (xy 46.543325 -275.236836) (xy 46.502822 -275.264792)
			(xy 46.45836 -275.28589) (xy 46.411089 -275.299582) (xy 46.362234 -275.305514) (xy 46.313059 -275.303533)
			(xy 46.26484 -275.293689) (xy 46.218824 -275.276237) (xy 46.176203 -275.25163) (xy 46.138082 -275.220505)
			(xy 46.105447 -275.183668) (xy 46.079144 -275.142072) (xy 46.059853 -275.096796) (xy 46.048076 -275.049012)
			(xy 46.044116 -274.999958) (xy 45.727112 -274.999958) (xy 45.726608 -275.025666) (xy 45.718565 -275.076448)
			(xy 45.702677 -275.125347) (xy 45.679334 -275.171159) (xy 45.649113 -275.212755) (xy 45.612757 -275.249111)
			(xy 45.571161 -275.279332) (xy 45.525349 -275.302675) (xy 45.47645 -275.318563) (xy 45.425668 -275.326606)
			(xy 45.374252 -275.326606) (xy 45.32347 -275.318563) (xy 45.274571 -275.302675) (xy 45.228759 -275.279332)
			(xy 45.187163 -275.249111) (xy 45.150807 -275.212755) (xy 45.120586 -275.171159) (xy 45.097243 -275.125347)
			(xy 45.081355 -275.076448) (xy 45.073312 -275.025666) (xy 44.75438 -275.025666) (xy 44.746664 -275.073142)
			(xy 44.73108 -275.119823) (xy 44.708209 -275.1634) (xy 44.678644 -275.202744) (xy 44.643151 -275.236836)
			(xy 44.602648 -275.264792) (xy 44.558186 -275.28589) (xy 44.510915 -275.299582) (xy 44.46206 -275.305514)
			(xy 44.412885 -275.303533) (xy 44.364666 -275.293689) (xy 44.31865 -275.276237) (xy 44.276029 -275.25163)
			(xy 44.237908 -275.220505) (xy 44.205273 -275.183668) (xy 44.17897 -275.142072) (xy 44.159679 -275.096796)
			(xy 44.147902 -275.049012) (xy 44.143942 -274.999958) (xy 40.899334 -274.999958) (xy 40.899334 -275.087334)
			(xy 40.900007 -275.099357) (xy 40.910878 -275.12081) (xy 40.920162 -275.128482) (xy 40.996362 -275.184108)
			(xy 41.020238 -275.187918) (xy 41.031922 -275.184108) (xy 41.054563 -275.177335) (xy 41.101257 -275.170064)
			(xy 41.124886 -275.16963) (xy 41.150141 -275.170121) (xy 41.199963 -275.178433) (xy 41.247738 -275.194832)
			(xy 41.292161 -275.218871) (xy 41.332022 -275.249894) (xy 41.366233 -275.287056) (xy 41.39386 -275.329341)
			(xy 41.414151 -275.375597) (xy 41.426551 -275.424562) (xy 41.430722 -275.4749) (xy 41.430719 -275.474938)
			(xy 41.769042 -275.474938) (xy 41.773002 -275.425884) (xy 41.784779 -275.3781) (xy 41.80407 -275.332824)
			(xy 41.830373 -275.291228) (xy 41.863008 -275.254391) (xy 41.901129 -275.223266) (xy 41.94375 -275.198659)
			(xy 41.989766 -275.181207) (xy 42.037985 -275.171363) (xy 42.08716 -275.169382) (xy 42.136015 -275.175314)
			(xy 42.183286 -275.189006) (xy 42.227748 -275.210104) (xy 42.268251 -275.23806) (xy 42.303744 -275.272152)
			(xy 42.333309 -275.311496) (xy 42.35618 -275.355073) (xy 42.371764 -275.401754) (xy 42.379659 -275.450331)
			(xy 42.380154 -275.474938) (xy 42.719002 -275.474938) (xy 42.722962 -275.425884) (xy 42.734739 -275.3781)
			(xy 42.75403 -275.332824) (xy 42.780333 -275.291228) (xy 42.812968 -275.254391) (xy 42.851089 -275.223266)
			(xy 42.89371 -275.198659) (xy 42.939726 -275.181207) (xy 42.987945 -275.171363) (xy 43.03712 -275.169382)
			(xy 43.085975 -275.175314) (xy 43.133246 -275.189006) (xy 43.177708 -275.210104) (xy 43.218211 -275.23806)
			(xy 43.253704 -275.272152) (xy 43.283269 -275.311496) (xy 43.30614 -275.355073) (xy 43.321724 -275.401754)
			(xy 43.329619 -275.450331) (xy 43.330114 -275.474938) (xy 43.329619 -275.499545) (xy 43.321724 -275.548122)
			(xy 43.30614 -275.594803) (xy 43.283269 -275.63838) (xy 43.253704 -275.677724) (xy 43.218211 -275.711816)
			(xy 43.177708 -275.739772) (xy 43.133246 -275.76087) (xy 43.085975 -275.774562) (xy 43.03712 -275.780494)
			(xy 42.987945 -275.778513) (xy 42.939726 -275.768669) (xy 42.89371 -275.751217) (xy 42.851089 -275.72661)
			(xy 42.812968 -275.695485) (xy 42.780333 -275.658648) (xy 42.75403 -275.617052) (xy 42.734739 -275.571776)
			(xy 42.722962 -275.523992) (xy 42.719002 -275.474938) (xy 42.380154 -275.474938) (xy 42.379659 -275.499545)
			(xy 42.371764 -275.548122) (xy 42.35618 -275.594803) (xy 42.333309 -275.63838) (xy 42.303744 -275.677724)
			(xy 42.268251 -275.711816) (xy 42.227748 -275.739772) (xy 42.183286 -275.76087) (xy 42.136015 -275.774562)
			(xy 42.08716 -275.780494) (xy 42.037985 -275.778513) (xy 41.989766 -275.768669) (xy 41.94375 -275.751217)
			(xy 41.901129 -275.72661) (xy 41.863008 -275.695485) (xy 41.830373 -275.658648) (xy 41.80407 -275.617052)
			(xy 41.784779 -275.571776) (xy 41.773002 -275.523992) (xy 41.769042 -275.474938) (xy 41.430719 -275.474938)
			(xy 41.426551 -275.525238) (xy 41.414151 -275.574203) (xy 41.39386 -275.620459) (xy 41.366233 -275.662744)
			(xy 41.332022 -275.699906) (xy 41.292161 -275.730929) (xy 41.247738 -275.754968) (xy 41.199963 -275.771367)
			(xy 41.150141 -275.779679) (xy 41.124886 -275.780246) (xy 41.101259 -275.779799) (xy 41.054568 -275.772521)
			(xy 41.031922 -275.765768) (xy 41.020238 -275.761958) (xy 40.996362 -275.765768) (xy 40.920162 -275.821394)
			(xy 40.910824 -275.829018) (xy 40.899967 -275.850502) (xy 40.899334 -275.862542) (xy 40.899334 -275.949918)
			(xy 44.143942 -275.949918) (xy 44.147902 -275.900864) (xy 44.159679 -275.85308) (xy 44.17897 -275.807804)
			(xy 44.205273 -275.766208) (xy 44.237908 -275.729371) (xy 44.276029 -275.698246) (xy 44.31865 -275.673639)
			(xy 44.364666 -275.656187) (xy 44.412885 -275.646343) (xy 44.46206 -275.644362) (xy 44.510915 -275.650294)
			(xy 44.558186 -275.663986) (xy 44.602648 -275.685084) (xy 44.643151 -275.71304) (xy 44.678644 -275.747132)
			(xy 44.708209 -275.786476) (xy 44.73108 -275.830053) (xy 44.746664 -275.876734) (xy 44.754559 -275.925311)
			(xy 44.755054 -275.949918) (xy 44.754559 -275.974525) (xy 44.75438 -275.975626) (xy 45.073312 -275.975626)
			(xy 45.073312 -275.92421) (xy 45.081355 -275.873428) (xy 45.097243 -275.824529) (xy 45.120586 -275.778717)
			(xy 45.150807 -275.737121) (xy 45.187163 -275.700765) (xy 45.228759 -275.670544) (xy 45.274571 -275.647201)
			(xy 45.32347 -275.631313) (xy 45.374252 -275.62327) (xy 45.425668 -275.62327) (xy 45.47645 -275.631313)
			(xy 45.525349 -275.647201) (xy 45.571161 -275.670544) (xy 45.612757 -275.700765) (xy 45.649113 -275.737121)
			(xy 45.679334 -275.778717) (xy 45.702677 -275.824529) (xy 45.718565 -275.873428) (xy 45.726608 -275.92421)
			(xy 45.727112 -275.949918) (xy 46.044116 -275.949918) (xy 46.048076 -275.900864) (xy 46.059853 -275.85308)
			(xy 46.079144 -275.807804) (xy 46.105447 -275.766208) (xy 46.138082 -275.729371) (xy 46.176203 -275.698246)
			(xy 46.218824 -275.673639) (xy 46.26484 -275.656187) (xy 46.313059 -275.646343) (xy 46.362234 -275.644362)
			(xy 46.411089 -275.650294) (xy 46.45836 -275.663986) (xy 46.502822 -275.685084) (xy 46.543325 -275.71304)
			(xy 46.578818 -275.747132) (xy 46.608383 -275.786476) (xy 46.631254 -275.830053) (xy 46.646838 -275.876734)
			(xy 46.654733 -275.925311) (xy 46.655228 -275.949918) (xy 46.654733 -275.974525) (xy 46.654554 -275.975626)
			(xy 46.973232 -275.975626) (xy 46.973232 -275.92421) (xy 46.981275 -275.873428) (xy 46.997163 -275.824529)
			(xy 47.020506 -275.778717) (xy 47.050727 -275.737121) (xy 47.087083 -275.700765) (xy 47.128679 -275.670544)
			(xy 47.174491 -275.647201) (xy 47.22339 -275.631313) (xy 47.274172 -275.62327) (xy 47.325588 -275.62327)
			(xy 47.37637 -275.631313) (xy 47.425269 -275.647201) (xy 47.471081 -275.670544) (xy 47.512677 -275.700765)
			(xy 47.549033 -275.737121) (xy 47.579254 -275.778717) (xy 47.602597 -275.824529) (xy 47.618485 -275.873428)
			(xy 47.626528 -275.92421) (xy 47.627032 -275.949918) (xy 47.944036 -275.949918) (xy 47.947996 -275.900864)
			(xy 47.959773 -275.85308) (xy 47.979064 -275.807804) (xy 48.005367 -275.766208) (xy 48.038002 -275.729371)
			(xy 48.076123 -275.698246) (xy 48.118744 -275.673639) (xy 48.16476 -275.656187) (xy 48.212979 -275.646343)
			(xy 48.262154 -275.644362) (xy 48.311009 -275.650294) (xy 48.35828 -275.663986) (xy 48.402742 -275.685084)
			(xy 48.443245 -275.71304) (xy 48.478738 -275.747132) (xy 48.508303 -275.786476) (xy 48.531174 -275.830053)
			(xy 48.546758 -275.876734) (xy 48.554653 -275.925311) (xy 48.555148 -275.949918) (xy 48.554653 -275.974525)
			(xy 48.554474 -275.975626) (xy 48.873152 -275.975626) (xy 48.873152 -275.92421) (xy 48.881195 -275.873428)
			(xy 48.897083 -275.824529) (xy 48.920426 -275.778717) (xy 48.950647 -275.737121) (xy 48.987003 -275.700765)
			(xy 49.028599 -275.670544) (xy 49.074411 -275.647201) (xy 49.12331 -275.631313) (xy 49.174092 -275.62327)
			(xy 49.225508 -275.62327) (xy 49.27629 -275.631313) (xy 49.325189 -275.647201) (xy 49.371001 -275.670544)
			(xy 49.412597 -275.700765) (xy 49.448953 -275.737121) (xy 49.479174 -275.778717) (xy 49.502517 -275.824529)
			(xy 49.518405 -275.873428) (xy 49.526448 -275.92421) (xy 49.526952 -275.949918) (xy 49.843956 -275.949918)
			(xy 49.847916 -275.900864) (xy 49.859693 -275.85308) (xy 49.878984 -275.807804) (xy 49.905287 -275.766208)
			(xy 49.937922 -275.729371) (xy 49.976043 -275.698246) (xy 50.018664 -275.673639) (xy 50.06468 -275.656187)
			(xy 50.112899 -275.646343) (xy 50.162074 -275.644362) (xy 50.210929 -275.650294) (xy 50.2582 -275.663986)
			(xy 50.302662 -275.685084) (xy 50.343165 -275.71304) (xy 50.378658 -275.747132) (xy 50.408223 -275.786476)
			(xy 50.431094 -275.830053) (xy 50.446678 -275.876734) (xy 50.454573 -275.925311) (xy 50.455068 -275.949918)
			(xy 50.454573 -275.974525) (xy 50.454394 -275.975626) (xy 50.773326 -275.975626) (xy 50.773326 -275.92421)
			(xy 50.781369 -275.873428) (xy 50.797257 -275.824529) (xy 50.8206 -275.778717) (xy 50.850821 -275.737121)
			(xy 50.887177 -275.700765) (xy 50.928773 -275.670544) (xy 50.974585 -275.647201) (xy 51.023484 -275.631313)
			(xy 51.074266 -275.62327) (xy 51.125682 -275.62327) (xy 51.176464 -275.631313) (xy 51.225363 -275.647201)
			(xy 51.271175 -275.670544) (xy 51.312771 -275.700765) (xy 51.349127 -275.737121) (xy 51.379348 -275.778717)
			(xy 51.402691 -275.824529) (xy 51.418579 -275.873428) (xy 51.426622 -275.92421) (xy 51.427126 -275.949918)
			(xy 51.74413 -275.949918) (xy 51.74809 -275.900864) (xy 51.759867 -275.85308) (xy 51.779158 -275.807804)
			(xy 51.805461 -275.766208) (xy 51.838096 -275.729371) (xy 51.876217 -275.698246) (xy 51.918838 -275.673639)
			(xy 51.964854 -275.656187) (xy 52.013073 -275.646343) (xy 52.062248 -275.644362) (xy 52.111103 -275.650294)
			(xy 52.158374 -275.663986) (xy 52.202836 -275.685084) (xy 52.243339 -275.71304) (xy 52.278832 -275.747132)
			(xy 52.308397 -275.786476) (xy 52.331268 -275.830053) (xy 52.346852 -275.876734) (xy 52.354747 -275.925311)
			(xy 52.355242 -275.949918) (xy 52.354747 -275.974525) (xy 52.354568 -275.975626) (xy 52.673246 -275.975626)
			(xy 52.673246 -275.92421) (xy 52.681289 -275.873428) (xy 52.697177 -275.824529) (xy 52.72052 -275.778717)
			(xy 52.750741 -275.737121) (xy 52.787097 -275.700765) (xy 52.828693 -275.670544) (xy 52.874505 -275.647201)
			(xy 52.923404 -275.631313) (xy 52.974186 -275.62327) (xy 53.025602 -275.62327) (xy 53.076384 -275.631313)
			(xy 53.125283 -275.647201) (xy 53.171095 -275.670544) (xy 53.212691 -275.700765) (xy 53.249047 -275.737121)
			(xy 53.279268 -275.778717) (xy 53.302611 -275.824529) (xy 53.318499 -275.873428) (xy 53.326542 -275.92421)
			(xy 53.327046 -275.949918) (xy 53.64405 -275.949918) (xy 53.64801 -275.900864) (xy 53.659787 -275.85308)
			(xy 53.679078 -275.807804) (xy 53.705381 -275.766208) (xy 53.738016 -275.729371) (xy 53.776137 -275.698246)
			(xy 53.818758 -275.673639) (xy 53.864774 -275.656187) (xy 53.912993 -275.646343) (xy 53.962168 -275.644362)
			(xy 54.011023 -275.650294) (xy 54.058294 -275.663986) (xy 54.102756 -275.685084) (xy 54.143259 -275.71304)
			(xy 54.178752 -275.747132) (xy 54.208317 -275.786476) (xy 54.231188 -275.830053) (xy 54.246772 -275.876734)
			(xy 54.254667 -275.925311) (xy 54.255162 -275.949918) (xy 54.254667 -275.974525) (xy 54.254488 -275.975626)
			(xy 54.573166 -275.975626) (xy 54.573166 -275.92421) (xy 54.581209 -275.873428) (xy 54.597097 -275.824529)
			(xy 54.62044 -275.778717) (xy 54.650661 -275.737121) (xy 54.687017 -275.700765) (xy 54.728613 -275.670544)
			(xy 54.774425 -275.647201) (xy 54.823324 -275.631313) (xy 54.874106 -275.62327) (xy 54.925522 -275.62327)
			(xy 54.976304 -275.631313) (xy 55.025203 -275.647201) (xy 55.071015 -275.670544) (xy 55.112611 -275.700765)
			(xy 55.148967 -275.737121) (xy 55.179188 -275.778717) (xy 55.202531 -275.824529) (xy 55.218419 -275.873428)
			(xy 55.226462 -275.92421) (xy 55.226966 -275.949918) (xy 55.54397 -275.949918) (xy 55.54793 -275.900864)
			(xy 55.559707 -275.85308) (xy 55.578998 -275.807804) (xy 55.605301 -275.766208) (xy 55.637936 -275.729371)
			(xy 55.676057 -275.698246) (xy 55.718678 -275.673639) (xy 55.764694 -275.656187) (xy 55.812913 -275.646343)
			(xy 55.862088 -275.644362) (xy 55.910943 -275.650294) (xy 55.958214 -275.663986) (xy 56.002676 -275.685084)
			(xy 56.043179 -275.71304) (xy 56.078672 -275.747132) (xy 56.108237 -275.786476) (xy 56.131108 -275.830053)
			(xy 56.146692 -275.876734) (xy 56.154587 -275.925311) (xy 56.155082 -275.949918) (xy 56.154587 -275.974525)
			(xy 56.154408 -275.975626) (xy 56.47334 -275.975626) (xy 56.47334 -275.92421) (xy 56.481383 -275.873428)
			(xy 56.497271 -275.824529) (xy 56.520614 -275.778717) (xy 56.550835 -275.737121) (xy 56.587191 -275.700765)
			(xy 56.628787 -275.670544) (xy 56.674599 -275.647201) (xy 56.723498 -275.631313) (xy 56.77428 -275.62327)
			(xy 56.825696 -275.62327) (xy 56.876478 -275.631313) (xy 56.925377 -275.647201) (xy 56.971189 -275.670544)
			(xy 57.012785 -275.700765) (xy 57.049141 -275.737121) (xy 57.079362 -275.778717) (xy 57.102705 -275.824529)
			(xy 57.118593 -275.873428) (xy 57.126636 -275.92421) (xy 57.12714 -275.949918) (xy 57.444144 -275.949918)
			(xy 57.448104 -275.900864) (xy 57.459881 -275.85308) (xy 57.479172 -275.807804) (xy 57.505475 -275.766208)
			(xy 57.53811 -275.729371) (xy 57.576231 -275.698246) (xy 57.618852 -275.673639) (xy 57.664868 -275.656187)
			(xy 57.713087 -275.646343) (xy 57.762262 -275.644362) (xy 57.811117 -275.650294) (xy 57.858388 -275.663986)
			(xy 57.90285 -275.685084) (xy 57.943353 -275.71304) (xy 57.978846 -275.747132) (xy 58.008411 -275.786476)
			(xy 58.031282 -275.830053) (xy 58.046866 -275.876734) (xy 58.054761 -275.925311) (xy 58.055256 -275.949918)
			(xy 58.054761 -275.974525) (xy 58.054582 -275.975626) (xy 58.37326 -275.975626) (xy 58.37326 -275.92421)
			(xy 58.381303 -275.873428) (xy 58.397191 -275.824529) (xy 58.420534 -275.778717) (xy 58.450755 -275.737121)
			(xy 58.487111 -275.700765) (xy 58.528707 -275.670544) (xy 58.574519 -275.647201) (xy 58.623418 -275.631313)
			(xy 58.6742 -275.62327) (xy 58.725616 -275.62327) (xy 58.776398 -275.631313) (xy 58.825297 -275.647201)
			(xy 58.871109 -275.670544) (xy 58.912705 -275.700765) (xy 58.949061 -275.737121) (xy 58.979282 -275.778717)
			(xy 59.002625 -275.824529) (xy 59.018513 -275.873428) (xy 59.026556 -275.92421) (xy 59.02706 -275.949918)
			(xy 59.344064 -275.949918) (xy 59.348024 -275.900864) (xy 59.359801 -275.85308) (xy 59.379092 -275.807804)
			(xy 59.405395 -275.766208) (xy 59.43803 -275.729371) (xy 59.476151 -275.698246) (xy 59.518772 -275.673639)
			(xy 59.564788 -275.656187) (xy 59.613007 -275.646343) (xy 59.662182 -275.644362) (xy 59.711037 -275.650294)
			(xy 59.758308 -275.663986) (xy 59.80277 -275.685084) (xy 59.843273 -275.71304) (xy 59.878766 -275.747132)
			(xy 59.908331 -275.786476) (xy 59.931202 -275.830053) (xy 59.946786 -275.876734) (xy 59.954681 -275.925311)
			(xy 59.955176 -275.949918) (xy 59.954681 -275.974525) (xy 59.954543 -275.975372) (xy 60.272926 -275.975372)
			(xy 60.272926 -275.923956) (xy 60.280969 -275.873174) (xy 60.296857 -275.824275) (xy 60.3202 -275.778463)
			(xy 60.350421 -275.736867) (xy 60.386777 -275.700511) (xy 60.428373 -275.67029) (xy 60.474185 -275.646947)
			(xy 60.523084 -275.631059) (xy 60.573866 -275.623016) (xy 60.625282 -275.623016) (xy 60.676064 -275.631059)
			(xy 60.724963 -275.646947) (xy 60.770775 -275.67029) (xy 60.812371 -275.700511) (xy 60.848727 -275.736867)
			(xy 60.878948 -275.778463) (xy 60.902291 -275.824275) (xy 60.918179 -275.873174) (xy 60.926222 -275.923956)
			(xy 60.926726 -275.949664) (xy 60.926721 -275.949918) (xy 61.243984 -275.949918) (xy 61.247944 -275.900864)
			(xy 61.259721 -275.85308) (xy 61.279012 -275.807804) (xy 61.305315 -275.766208) (xy 61.33795 -275.729371)
			(xy 61.376071 -275.698246) (xy 61.418692 -275.673639) (xy 61.464708 -275.656187) (xy 61.512927 -275.646343)
			(xy 61.562102 -275.644362) (xy 61.610957 -275.650294) (xy 61.658228 -275.663986) (xy 61.70269 -275.685084)
			(xy 61.743193 -275.71304) (xy 61.778686 -275.747132) (xy 61.808251 -275.786476) (xy 61.831122 -275.830053)
			(xy 61.846706 -275.876734) (xy 61.854601 -275.925311) (xy 61.855096 -275.949918) (xy 61.854601 -275.974525)
			(xy 61.854422 -275.975626) (xy 62.172846 -275.975626) (xy 62.172846 -275.92421) (xy 62.180889 -275.873428)
			(xy 62.196777 -275.824529) (xy 62.22012 -275.778717) (xy 62.250341 -275.737121) (xy 62.286697 -275.700765)
			(xy 62.328293 -275.670544) (xy 62.374105 -275.647201) (xy 62.423004 -275.631313) (xy 62.473786 -275.62327)
			(xy 62.525202 -275.62327) (xy 62.575984 -275.631313) (xy 62.624883 -275.647201) (xy 62.670695 -275.670544)
			(xy 62.712291 -275.700765) (xy 62.748647 -275.737121) (xy 62.778868 -275.778717) (xy 62.802211 -275.824529)
			(xy 62.818099 -275.873428) (xy 62.826142 -275.92421) (xy 62.826646 -275.949918) (xy 63.144158 -275.949918)
			(xy 63.148118 -275.900864) (xy 63.159895 -275.85308) (xy 63.179186 -275.807804) (xy 63.205489 -275.766208)
			(xy 63.238124 -275.729371) (xy 63.276245 -275.698246) (xy 63.318866 -275.673639) (xy 63.364882 -275.656187)
			(xy 63.413101 -275.646343) (xy 63.462276 -275.644362) (xy 63.511131 -275.650294) (xy 63.558402 -275.663986)
			(xy 63.602864 -275.685084) (xy 63.643367 -275.71304) (xy 63.67886 -275.747132) (xy 63.708425 -275.786476)
			(xy 63.731296 -275.830053) (xy 63.74688 -275.876734) (xy 63.754775 -275.925311) (xy 63.75527 -275.949918)
			(xy 63.754775 -275.974525) (xy 63.754637 -275.975372) (xy 64.07302 -275.975372) (xy 64.07302 -275.923956)
			(xy 64.081063 -275.873174) (xy 64.096951 -275.824275) (xy 64.120294 -275.778463) (xy 64.150515 -275.736867)
			(xy 64.186871 -275.700511) (xy 64.228467 -275.67029) (xy 64.274279 -275.646947) (xy 64.323178 -275.631059)
			(xy 64.37396 -275.623016) (xy 64.425376 -275.623016) (xy 64.476158 -275.631059) (xy 64.525057 -275.646947)
			(xy 64.570869 -275.67029) (xy 64.612465 -275.700511) (xy 64.648821 -275.736867) (xy 64.679042 -275.778463)
			(xy 64.702385 -275.824275) (xy 64.718273 -275.873174) (xy 64.726316 -275.923956) (xy 64.72682 -275.949664)
			(xy 64.726815 -275.949918) (xy 65.044078 -275.949918) (xy 65.048038 -275.900864) (xy 65.059815 -275.85308)
			(xy 65.079106 -275.807804) (xy 65.105409 -275.766208) (xy 65.138044 -275.729371) (xy 65.176165 -275.698246)
			(xy 65.218786 -275.673639) (xy 65.264802 -275.656187) (xy 65.313021 -275.646343) (xy 65.362196 -275.644362)
			(xy 65.411051 -275.650294) (xy 65.458322 -275.663986) (xy 65.502784 -275.685084) (xy 65.543287 -275.71304)
			(xy 65.57878 -275.747132) (xy 65.608345 -275.786476) (xy 65.631216 -275.830053) (xy 65.6468 -275.876734)
			(xy 65.654695 -275.925311) (xy 65.65519 -275.949918) (xy 65.654695 -275.974525) (xy 65.654516 -275.975626)
			(xy 65.97294 -275.975626) (xy 65.97294 -275.92421) (xy 65.980983 -275.873428) (xy 65.996871 -275.824529)
			(xy 66.020214 -275.778717) (xy 66.050435 -275.737121) (xy 66.086791 -275.700765) (xy 66.128387 -275.670544)
			(xy 66.174199 -275.647201) (xy 66.223098 -275.631313) (xy 66.27388 -275.62327) (xy 66.325296 -275.62327)
			(xy 66.376078 -275.631313) (xy 66.424977 -275.647201) (xy 66.470789 -275.670544) (xy 66.512385 -275.700765)
			(xy 66.548741 -275.737121) (xy 66.578962 -275.778717) (xy 66.602305 -275.824529) (xy 66.618193 -275.873428)
			(xy 66.626236 -275.92421) (xy 66.62674 -275.949918) (xy 66.943998 -275.949918) (xy 66.947958 -275.900864)
			(xy 66.959735 -275.85308) (xy 66.979026 -275.807804) (xy 67.005329 -275.766208) (xy 67.037964 -275.729371)
			(xy 67.076085 -275.698246) (xy 67.118706 -275.673639) (xy 67.164722 -275.656187) (xy 67.212941 -275.646343)
			(xy 67.262116 -275.644362) (xy 67.310971 -275.650294) (xy 67.358242 -275.663986) (xy 67.402704 -275.685084)
			(xy 67.443207 -275.71304) (xy 67.4787 -275.747132) (xy 67.508265 -275.786476) (xy 67.531136 -275.830053)
			(xy 67.54672 -275.876734) (xy 67.554615 -275.925311) (xy 67.55511 -275.949918) (xy 67.554615 -275.974525)
			(xy 67.554477 -275.975372) (xy 67.87286 -275.975372) (xy 67.87286 -275.923956) (xy 67.880903 -275.873174)
			(xy 67.896791 -275.824275) (xy 67.920134 -275.778463) (xy 67.950355 -275.736867) (xy 67.986711 -275.700511)
			(xy 68.028307 -275.67029) (xy 68.074119 -275.646947) (xy 68.123018 -275.631059) (xy 68.1738 -275.623016)
			(xy 68.225216 -275.623016) (xy 68.275998 -275.631059) (xy 68.324897 -275.646947) (xy 68.370709 -275.67029)
			(xy 68.412305 -275.700511) (xy 68.448661 -275.736867) (xy 68.478882 -275.778463) (xy 68.502225 -275.824275)
			(xy 68.518113 -275.873174) (xy 68.526156 -275.923956) (xy 68.52666 -275.949664) (xy 68.526655 -275.949918)
			(xy 68.844172 -275.949918) (xy 68.848132 -275.900864) (xy 68.859909 -275.85308) (xy 68.8792 -275.807804)
			(xy 68.905503 -275.766208) (xy 68.938138 -275.729371) (xy 68.976259 -275.698246) (xy 69.01888 -275.673639)
			(xy 69.064896 -275.656187) (xy 69.113115 -275.646343) (xy 69.16229 -275.644362) (xy 69.211145 -275.650294)
			(xy 69.258416 -275.663986) (xy 69.302878 -275.685084) (xy 69.343381 -275.71304) (xy 69.378874 -275.747132)
			(xy 69.408439 -275.786476) (xy 69.43131 -275.830053) (xy 69.446894 -275.876734) (xy 69.454789 -275.925311)
			(xy 69.455284 -275.949918) (xy 69.454789 -275.974525) (xy 69.45461 -275.975626) (xy 69.77278 -275.975626)
			(xy 69.77278 -275.92421) (xy 69.780823 -275.873428) (xy 69.796711 -275.824529) (xy 69.820054 -275.778717)
			(xy 69.850275 -275.737121) (xy 69.886631 -275.700765) (xy 69.928227 -275.670544) (xy 69.974039 -275.647201)
			(xy 70.022938 -275.631313) (xy 70.07372 -275.62327) (xy 70.125136 -275.62327) (xy 70.175918 -275.631313)
			(xy 70.224817 -275.647201) (xy 70.270629 -275.670544) (xy 70.312225 -275.700765) (xy 70.348581 -275.737121)
			(xy 70.378802 -275.778717) (xy 70.402145 -275.824529) (xy 70.418033 -275.873428) (xy 70.426076 -275.92421)
			(xy 70.42658 -275.949918) (xy 70.744092 -275.949918) (xy 70.748052 -275.900864) (xy 70.759829 -275.85308)
			(xy 70.77912 -275.807804) (xy 70.805423 -275.766208) (xy 70.838058 -275.729371) (xy 70.876179 -275.698246)
			(xy 70.9188 -275.673639) (xy 70.964816 -275.656187) (xy 71.013035 -275.646343) (xy 71.06221 -275.644362)
			(xy 71.111065 -275.650294) (xy 71.158336 -275.663986) (xy 71.202798 -275.685084) (xy 71.243301 -275.71304)
			(xy 71.278794 -275.747132) (xy 71.308359 -275.786476) (xy 71.33123 -275.830053) (xy 71.346814 -275.876734)
			(xy 71.354709 -275.925311) (xy 71.355204 -275.949918) (xy 71.354709 -275.974525) (xy 71.354571 -275.975372)
			(xy 71.672954 -275.975372) (xy 71.672954 -275.923956) (xy 71.680997 -275.873174) (xy 71.696885 -275.824275)
			(xy 71.720228 -275.778463) (xy 71.750449 -275.736867) (xy 71.786805 -275.700511) (xy 71.828401 -275.67029)
			(xy 71.874213 -275.646947) (xy 71.923112 -275.631059) (xy 71.973894 -275.623016) (xy 72.02531 -275.623016)
			(xy 72.076092 -275.631059) (xy 72.124991 -275.646947) (xy 72.170803 -275.67029) (xy 72.212399 -275.700511)
			(xy 72.248755 -275.736867) (xy 72.278976 -275.778463) (xy 72.302319 -275.824275) (xy 72.318207 -275.873174)
			(xy 72.32625 -275.923956) (xy 72.326754 -275.949664) (xy 72.326749 -275.949918) (xy 72.644012 -275.949918)
			(xy 72.647972 -275.900864) (xy 72.659749 -275.85308) (xy 72.67904 -275.807804) (xy 72.705343 -275.766208)
			(xy 72.737978 -275.729371) (xy 72.776099 -275.698246) (xy 72.81872 -275.673639) (xy 72.864736 -275.656187)
			(xy 72.912955 -275.646343) (xy 72.96213 -275.644362) (xy 73.010985 -275.650294) (xy 73.058256 -275.663986)
			(xy 73.102718 -275.685084) (xy 73.143221 -275.71304) (xy 73.178714 -275.747132) (xy 73.208279 -275.786476)
			(xy 73.23115 -275.830053) (xy 73.246734 -275.876734) (xy 73.254629 -275.925311) (xy 73.255124 -275.949918)
			(xy 73.254629 -275.974525) (xy 73.25445 -275.975626) (xy 73.572874 -275.975626) (xy 73.572874 -275.92421)
			(xy 73.580917 -275.873428) (xy 73.596805 -275.824529) (xy 73.620148 -275.778717) (xy 73.650369 -275.737121)
			(xy 73.686725 -275.700765) (xy 73.728321 -275.670544) (xy 73.774133 -275.647201) (xy 73.823032 -275.631313)
			(xy 73.873814 -275.62327) (xy 73.92523 -275.62327) (xy 73.976012 -275.631313) (xy 74.024911 -275.647201)
			(xy 74.070723 -275.670544) (xy 74.112319 -275.700765) (xy 74.148675 -275.737121) (xy 74.178896 -275.778717)
			(xy 74.202239 -275.824529) (xy 74.218127 -275.873428) (xy 74.22617 -275.92421) (xy 74.226674 -275.949918)
			(xy 74.544186 -275.949918) (xy 74.548146 -275.900864) (xy 74.559923 -275.85308) (xy 74.579214 -275.807804)
			(xy 74.605517 -275.766208) (xy 74.638152 -275.729371) (xy 74.676273 -275.698246) (xy 74.718894 -275.673639)
			(xy 74.76491 -275.656187) (xy 74.813129 -275.646343) (xy 74.862304 -275.644362) (xy 74.911159 -275.650294)
			(xy 74.95843 -275.663986) (xy 75.002892 -275.685084) (xy 75.043395 -275.71304) (xy 75.078888 -275.747132)
			(xy 75.108453 -275.786476) (xy 75.131324 -275.830053) (xy 75.146908 -275.876734) (xy 75.154803 -275.925311)
			(xy 75.155298 -275.949918) (xy 75.154803 -275.974525) (xy 75.154665 -275.975372) (xy 75.473048 -275.975372)
			(xy 75.473048 -275.923956) (xy 75.481091 -275.873174) (xy 75.496979 -275.824275) (xy 75.520322 -275.778463)
			(xy 75.550543 -275.736867) (xy 75.586899 -275.700511) (xy 75.628495 -275.67029) (xy 75.674307 -275.646947)
			(xy 75.723206 -275.631059) (xy 75.773988 -275.623016) (xy 75.825404 -275.623016) (xy 75.876186 -275.631059)
			(xy 75.925085 -275.646947) (xy 75.970897 -275.67029) (xy 76.012493 -275.700511) (xy 76.048849 -275.736867)
			(xy 76.07907 -275.778463) (xy 76.102413 -275.824275) (xy 76.118301 -275.873174) (xy 76.126344 -275.923956)
			(xy 76.126848 -275.949664) (xy 76.126843 -275.949918) (xy 76.444106 -275.949918) (xy 76.448066 -275.900864)
			(xy 76.459843 -275.85308) (xy 76.479134 -275.807804) (xy 76.505437 -275.766208) (xy 76.538072 -275.729371)
			(xy 76.576193 -275.698246) (xy 76.618814 -275.673639) (xy 76.66483 -275.656187) (xy 76.713049 -275.646343)
			(xy 76.762224 -275.644362) (xy 76.811079 -275.650294) (xy 76.85835 -275.663986) (xy 76.902812 -275.685084)
			(xy 76.943315 -275.71304) (xy 76.978808 -275.747132) (xy 77.008373 -275.786476) (xy 77.031244 -275.830053)
			(xy 77.046828 -275.876734) (xy 77.054723 -275.925311) (xy 77.055218 -275.949918) (xy 77.054723 -275.974525)
			(xy 77.054544 -275.975626) (xy 77.372968 -275.975626) (xy 77.372968 -275.92421) (xy 77.381011 -275.873428)
			(xy 77.396899 -275.824529) (xy 77.420242 -275.778717) (xy 77.450463 -275.737121) (xy 77.486819 -275.700765)
			(xy 77.528415 -275.670544) (xy 77.574227 -275.647201) (xy 77.623126 -275.631313) (xy 77.673908 -275.62327)
			(xy 77.725324 -275.62327) (xy 77.776106 -275.631313) (xy 77.825005 -275.647201) (xy 77.870817 -275.670544)
			(xy 77.912413 -275.700765) (xy 77.948769 -275.737121) (xy 77.97899 -275.778717) (xy 78.002333 -275.824529)
			(xy 78.018221 -275.873428) (xy 78.026264 -275.92421) (xy 78.026768 -275.949918) (xy 78.344026 -275.949918)
			(xy 78.347986 -275.900864) (xy 78.359763 -275.85308) (xy 78.379054 -275.807804) (xy 78.405357 -275.766208)
			(xy 78.437992 -275.729371) (xy 78.476113 -275.698246) (xy 78.518734 -275.673639) (xy 78.56475 -275.656187)
			(xy 78.612969 -275.646343) (xy 78.662144 -275.644362) (xy 78.710999 -275.650294) (xy 78.75827 -275.663986)
			(xy 78.802732 -275.685084) (xy 78.843235 -275.71304) (xy 78.878728 -275.747132) (xy 78.908293 -275.786476)
			(xy 78.931164 -275.830053) (xy 78.946748 -275.876734) (xy 78.954643 -275.925311) (xy 78.955138 -275.949918)
			(xy 78.954643 -275.974525) (xy 78.954464 -275.975626) (xy 79.272888 -275.975626) (xy 79.272888 -275.92421)
			(xy 79.280931 -275.873428) (xy 79.296819 -275.824529) (xy 79.320162 -275.778717) (xy 79.350383 -275.737121)
			(xy 79.386739 -275.700765) (xy 79.428335 -275.670544) (xy 79.474147 -275.647201) (xy 79.523046 -275.631313)
			(xy 79.573828 -275.62327) (xy 79.625244 -275.62327) (xy 79.676026 -275.631313) (xy 79.724925 -275.647201)
			(xy 79.770737 -275.670544) (xy 79.812333 -275.700765) (xy 79.848689 -275.737121) (xy 79.87891 -275.778717)
			(xy 79.902253 -275.824529) (xy 79.918141 -275.873428) (xy 79.926184 -275.92421) (xy 79.926688 -275.949918)
			(xy 80.2442 -275.949918) (xy 80.24816 -275.900864) (xy 80.259937 -275.85308) (xy 80.279228 -275.807804)
			(xy 80.305531 -275.766208) (xy 80.338166 -275.729371) (xy 80.376287 -275.698246) (xy 80.418908 -275.673639)
			(xy 80.464924 -275.656187) (xy 80.513143 -275.646343) (xy 80.562318 -275.644362) (xy 80.611173 -275.650294)
			(xy 80.658444 -275.663986) (xy 80.702906 -275.685084) (xy 80.743409 -275.71304) (xy 80.778902 -275.747132)
			(xy 80.808467 -275.786476) (xy 80.831338 -275.830053) (xy 80.846922 -275.876734) (xy 80.854817 -275.925311)
			(xy 80.855312 -275.949918) (xy 81.19416 -275.949918) (xy 81.19812 -275.900864) (xy 81.209897 -275.85308)
			(xy 81.229188 -275.807804) (xy 81.255491 -275.766208) (xy 81.288126 -275.729371) (xy 81.326247 -275.698246)
			(xy 81.368868 -275.673639) (xy 81.414884 -275.656187) (xy 81.463103 -275.646343) (xy 81.512278 -275.644362)
			(xy 81.561133 -275.650294) (xy 81.608404 -275.663986) (xy 81.652866 -275.685084) (xy 81.693369 -275.71304)
			(xy 81.728862 -275.747132) (xy 81.758427 -275.786476) (xy 81.781298 -275.830053) (xy 81.796882 -275.876734)
			(xy 81.804777 -275.925311) (xy 81.805272 -275.949918) (xy 82.14412 -275.949918) (xy 82.14808 -275.900864)
			(xy 82.159857 -275.85308) (xy 82.179148 -275.807804) (xy 82.205451 -275.766208) (xy 82.238086 -275.729371)
			(xy 82.276207 -275.698246) (xy 82.318828 -275.673639) (xy 82.364844 -275.656187) (xy 82.413063 -275.646343)
			(xy 82.462238 -275.644362) (xy 82.511093 -275.650294) (xy 82.558364 -275.663986) (xy 82.602826 -275.685084)
			(xy 82.643329 -275.71304) (xy 82.678822 -275.747132) (xy 82.708387 -275.786476) (xy 82.731258 -275.830053)
			(xy 82.746842 -275.876734) (xy 82.754737 -275.925311) (xy 82.755232 -275.949918) (xy 82.754737 -275.974525)
			(xy 82.746842 -276.023102) (xy 82.731258 -276.069783) (xy 82.708387 -276.11336) (xy 82.678822 -276.152704)
			(xy 82.643329 -276.186796) (xy 82.602826 -276.214752) (xy 82.558364 -276.23585) (xy 82.511093 -276.249542)
			(xy 82.462238 -276.255474) (xy 82.413063 -276.253493) (xy 82.364844 -276.243649) (xy 82.318828 -276.226197)
			(xy 82.276207 -276.20159) (xy 82.238086 -276.170465) (xy 82.205451 -276.133628) (xy 82.179148 -276.092032)
			(xy 82.159857 -276.046756) (xy 82.14808 -275.998972) (xy 82.14412 -275.949918) (xy 81.805272 -275.949918)
			(xy 81.804777 -275.974525) (xy 81.796882 -276.023102) (xy 81.781298 -276.069783) (xy 81.758427 -276.11336)
			(xy 81.728862 -276.152704) (xy 81.693369 -276.186796) (xy 81.652866 -276.214752) (xy 81.608404 -276.23585)
			(xy 81.561133 -276.249542) (xy 81.512278 -276.255474) (xy 81.463103 -276.253493) (xy 81.414884 -276.243649)
			(xy 81.368868 -276.226197) (xy 81.326247 -276.20159) (xy 81.288126 -276.170465) (xy 81.255491 -276.133628)
			(xy 81.229188 -276.092032) (xy 81.209897 -276.046756) (xy 81.19812 -275.998972) (xy 81.19416 -275.949918)
			(xy 80.855312 -275.949918) (xy 80.854817 -275.974525) (xy 80.846922 -276.023102) (xy 80.831338 -276.069783)
			(xy 80.808467 -276.11336) (xy 80.778902 -276.152704) (xy 80.743409 -276.186796) (xy 80.702906 -276.214752)
			(xy 80.658444 -276.23585) (xy 80.611173 -276.249542) (xy 80.562318 -276.255474) (xy 80.513143 -276.253493)
			(xy 80.464924 -276.243649) (xy 80.418908 -276.226197) (xy 80.376287 -276.20159) (xy 80.338166 -276.170465)
			(xy 80.305531 -276.133628) (xy 80.279228 -276.092032) (xy 80.259937 -276.046756) (xy 80.24816 -275.998972)
			(xy 80.2442 -275.949918) (xy 79.926688 -275.949918) (xy 79.926184 -275.975626) (xy 79.918141 -276.026408)
			(xy 79.902253 -276.075307) (xy 79.87891 -276.121119) (xy 79.848689 -276.162715) (xy 79.812333 -276.199071)
			(xy 79.770737 -276.229292) (xy 79.724925 -276.252635) (xy 79.676026 -276.268523) (xy 79.625244 -276.276566)
			(xy 79.573828 -276.276566) (xy 79.523046 -276.268523) (xy 79.474147 -276.252635) (xy 79.428335 -276.229292)
			(xy 79.386739 -276.199071) (xy 79.350383 -276.162715) (xy 79.320162 -276.121119) (xy 79.296819 -276.075307)
			(xy 79.280931 -276.026408) (xy 79.272888 -275.975626) (xy 78.954464 -275.975626) (xy 78.946748 -276.023102)
			(xy 78.931164 -276.069783) (xy 78.908293 -276.11336) (xy 78.878728 -276.152704) (xy 78.843235 -276.186796)
			(xy 78.802732 -276.214752) (xy 78.75827 -276.23585) (xy 78.710999 -276.249542) (xy 78.662144 -276.255474)
			(xy 78.612969 -276.253493) (xy 78.56475 -276.243649) (xy 78.518734 -276.226197) (xy 78.476113 -276.20159)
			(xy 78.437992 -276.170465) (xy 78.405357 -276.133628) (xy 78.379054 -276.092032) (xy 78.359763 -276.046756)
			(xy 78.347986 -275.998972) (xy 78.344026 -275.949918) (xy 78.026768 -275.949918) (xy 78.026264 -275.975626)
			(xy 78.018221 -276.026408) (xy 78.002333 -276.075307) (xy 77.97899 -276.121119) (xy 77.948769 -276.162715)
			(xy 77.912413 -276.199071) (xy 77.870817 -276.229292) (xy 77.825005 -276.252635) (xy 77.776106 -276.268523)
			(xy 77.725324 -276.276566) (xy 77.673908 -276.276566) (xy 77.623126 -276.268523) (xy 77.574227 -276.252635)
			(xy 77.528415 -276.229292) (xy 77.486819 -276.199071) (xy 77.450463 -276.162715) (xy 77.420242 -276.121119)
			(xy 77.396899 -276.075307) (xy 77.381011 -276.026408) (xy 77.372968 -275.975626) (xy 77.054544 -275.975626)
			(xy 77.046828 -276.023102) (xy 77.031244 -276.069783) (xy 77.008373 -276.11336) (xy 76.978808 -276.152704)
			(xy 76.943315 -276.186796) (xy 76.902812 -276.214752) (xy 76.85835 -276.23585) (xy 76.811079 -276.249542)
			(xy 76.762224 -276.255474) (xy 76.713049 -276.253493) (xy 76.66483 -276.243649) (xy 76.618814 -276.226197)
			(xy 76.576193 -276.20159) (xy 76.538072 -276.170465) (xy 76.505437 -276.133628) (xy 76.479134 -276.092032)
			(xy 76.459843 -276.046756) (xy 76.448066 -275.998972) (xy 76.444106 -275.949918) (xy 76.126843 -275.949918)
			(xy 76.126344 -275.975372) (xy 76.118301 -276.026154) (xy 76.102413 -276.075053) (xy 76.07907 -276.120865)
			(xy 76.048849 -276.162461) (xy 76.012493 -276.198817) (xy 75.970897 -276.229038) (xy 75.925085 -276.252381)
			(xy 75.876186 -276.268269) (xy 75.825404 -276.276312) (xy 75.773988 -276.276312) (xy 75.723206 -276.268269)
			(xy 75.674307 -276.252381) (xy 75.628495 -276.229038) (xy 75.586899 -276.198817) (xy 75.550543 -276.162461)
			(xy 75.520322 -276.120865) (xy 75.496979 -276.075053) (xy 75.481091 -276.026154) (xy 75.473048 -275.975372)
			(xy 75.154665 -275.975372) (xy 75.146908 -276.023102) (xy 75.131324 -276.069783) (xy 75.108453 -276.11336)
			(xy 75.078888 -276.152704) (xy 75.043395 -276.186796) (xy 75.002892 -276.214752) (xy 74.95843 -276.23585)
			(xy 74.911159 -276.249542) (xy 74.862304 -276.255474) (xy 74.813129 -276.253493) (xy 74.76491 -276.243649)
			(xy 74.718894 -276.226197) (xy 74.676273 -276.20159) (xy 74.638152 -276.170465) (xy 74.605517 -276.133628)
			(xy 74.579214 -276.092032) (xy 74.559923 -276.046756) (xy 74.548146 -275.998972) (xy 74.544186 -275.949918)
			(xy 74.226674 -275.949918) (xy 74.22617 -275.975626) (xy 74.218127 -276.026408) (xy 74.202239 -276.075307)
			(xy 74.178896 -276.121119) (xy 74.148675 -276.162715) (xy 74.112319 -276.199071) (xy 74.070723 -276.229292)
			(xy 74.024911 -276.252635) (xy 73.976012 -276.268523) (xy 73.92523 -276.276566) (xy 73.873814 -276.276566)
			(xy 73.823032 -276.268523) (xy 73.774133 -276.252635) (xy 73.728321 -276.229292) (xy 73.686725 -276.199071)
			(xy 73.650369 -276.162715) (xy 73.620148 -276.121119) (xy 73.596805 -276.075307) (xy 73.580917 -276.026408)
			(xy 73.572874 -275.975626) (xy 73.25445 -275.975626) (xy 73.246734 -276.023102) (xy 73.23115 -276.069783)
			(xy 73.208279 -276.11336) (xy 73.178714 -276.152704) (xy 73.143221 -276.186796) (xy 73.102718 -276.214752)
			(xy 73.058256 -276.23585) (xy 73.010985 -276.249542) (xy 72.96213 -276.255474) (xy 72.912955 -276.253493)
			(xy 72.864736 -276.243649) (xy 72.81872 -276.226197) (xy 72.776099 -276.20159) (xy 72.737978 -276.170465)
			(xy 72.705343 -276.133628) (xy 72.67904 -276.092032) (xy 72.659749 -276.046756) (xy 72.647972 -275.998972)
			(xy 72.644012 -275.949918) (xy 72.326749 -275.949918) (xy 72.32625 -275.975372) (xy 72.318207 -276.026154)
			(xy 72.302319 -276.075053) (xy 72.278976 -276.120865) (xy 72.248755 -276.162461) (xy 72.212399 -276.198817)
			(xy 72.170803 -276.229038) (xy 72.124991 -276.252381) (xy 72.076092 -276.268269) (xy 72.02531 -276.276312)
			(xy 71.973894 -276.276312) (xy 71.923112 -276.268269) (xy 71.874213 -276.252381) (xy 71.828401 -276.229038)
			(xy 71.786805 -276.198817) (xy 71.750449 -276.162461) (xy 71.720228 -276.120865) (xy 71.696885 -276.075053)
			(xy 71.680997 -276.026154) (xy 71.672954 -275.975372) (xy 71.354571 -275.975372) (xy 71.346814 -276.023102)
			(xy 71.33123 -276.069783) (xy 71.308359 -276.11336) (xy 71.278794 -276.152704) (xy 71.243301 -276.186796)
			(xy 71.202798 -276.214752) (xy 71.158336 -276.23585) (xy 71.111065 -276.249542) (xy 71.06221 -276.255474)
			(xy 71.013035 -276.253493) (xy 70.964816 -276.243649) (xy 70.9188 -276.226197) (xy 70.876179 -276.20159)
			(xy 70.838058 -276.170465) (xy 70.805423 -276.133628) (xy 70.77912 -276.092032) (xy 70.759829 -276.046756)
			(xy 70.748052 -275.998972) (xy 70.744092 -275.949918) (xy 70.42658 -275.949918) (xy 70.426076 -275.975626)
			(xy 70.418033 -276.026408) (xy 70.402145 -276.075307) (xy 70.378802 -276.121119) (xy 70.348581 -276.162715)
			(xy 70.312225 -276.199071) (xy 70.270629 -276.229292) (xy 70.224817 -276.252635) (xy 70.175918 -276.268523)
			(xy 70.125136 -276.276566) (xy 70.07372 -276.276566) (xy 70.022938 -276.268523) (xy 69.974039 -276.252635)
			(xy 69.928227 -276.229292) (xy 69.886631 -276.199071) (xy 69.850275 -276.162715) (xy 69.820054 -276.121119)
			(xy 69.796711 -276.075307) (xy 69.780823 -276.026408) (xy 69.77278 -275.975626) (xy 69.45461 -275.975626)
			(xy 69.446894 -276.023102) (xy 69.43131 -276.069783) (xy 69.408439 -276.11336) (xy 69.378874 -276.152704)
			(xy 69.343381 -276.186796) (xy 69.302878 -276.214752) (xy 69.258416 -276.23585) (xy 69.211145 -276.249542)
			(xy 69.16229 -276.255474) (xy 69.113115 -276.253493) (xy 69.064896 -276.243649) (xy 69.01888 -276.226197)
			(xy 68.976259 -276.20159) (xy 68.938138 -276.170465) (xy 68.905503 -276.133628) (xy 68.8792 -276.092032)
			(xy 68.859909 -276.046756) (xy 68.848132 -275.998972) (xy 68.844172 -275.949918) (xy 68.526655 -275.949918)
			(xy 68.526156 -275.975372) (xy 68.518113 -276.026154) (xy 68.502225 -276.075053) (xy 68.478882 -276.120865)
			(xy 68.448661 -276.162461) (xy 68.412305 -276.198817) (xy 68.370709 -276.229038) (xy 68.324897 -276.252381)
			(xy 68.275998 -276.268269) (xy 68.225216 -276.276312) (xy 68.1738 -276.276312) (xy 68.123018 -276.268269)
			(xy 68.074119 -276.252381) (xy 68.028307 -276.229038) (xy 67.986711 -276.198817) (xy 67.950355 -276.162461)
			(xy 67.920134 -276.120865) (xy 67.896791 -276.075053) (xy 67.880903 -276.026154) (xy 67.87286 -275.975372)
			(xy 67.554477 -275.975372) (xy 67.54672 -276.023102) (xy 67.531136 -276.069783) (xy 67.508265 -276.11336)
			(xy 67.4787 -276.152704) (xy 67.443207 -276.186796) (xy 67.402704 -276.214752) (xy 67.358242 -276.23585)
			(xy 67.310971 -276.249542) (xy 67.262116 -276.255474) (xy 67.212941 -276.253493) (xy 67.164722 -276.243649)
			(xy 67.118706 -276.226197) (xy 67.076085 -276.20159) (xy 67.037964 -276.170465) (xy 67.005329 -276.133628)
			(xy 66.979026 -276.092032) (xy 66.959735 -276.046756) (xy 66.947958 -275.998972) (xy 66.943998 -275.949918)
			(xy 66.62674 -275.949918) (xy 66.626236 -275.975626) (xy 66.618193 -276.026408) (xy 66.602305 -276.075307)
			(xy 66.578962 -276.121119) (xy 66.548741 -276.162715) (xy 66.512385 -276.199071) (xy 66.470789 -276.229292)
			(xy 66.424977 -276.252635) (xy 66.376078 -276.268523) (xy 66.325296 -276.276566) (xy 66.27388 -276.276566)
			(xy 66.223098 -276.268523) (xy 66.174199 -276.252635) (xy 66.128387 -276.229292) (xy 66.086791 -276.199071)
			(xy 66.050435 -276.162715) (xy 66.020214 -276.121119) (xy 65.996871 -276.075307) (xy 65.980983 -276.026408)
			(xy 65.97294 -275.975626) (xy 65.654516 -275.975626) (xy 65.6468 -276.023102) (xy 65.631216 -276.069783)
			(xy 65.608345 -276.11336) (xy 65.57878 -276.152704) (xy 65.543287 -276.186796) (xy 65.502784 -276.214752)
			(xy 65.458322 -276.23585) (xy 65.411051 -276.249542) (xy 65.362196 -276.255474) (xy 65.313021 -276.253493)
			(xy 65.264802 -276.243649) (xy 65.218786 -276.226197) (xy 65.176165 -276.20159) (xy 65.138044 -276.170465)
			(xy 65.105409 -276.133628) (xy 65.079106 -276.092032) (xy 65.059815 -276.046756) (xy 65.048038 -275.998972)
			(xy 65.044078 -275.949918) (xy 64.726815 -275.949918) (xy 64.726316 -275.975372) (xy 64.718273 -276.026154)
			(xy 64.702385 -276.075053) (xy 64.679042 -276.120865) (xy 64.648821 -276.162461) (xy 64.612465 -276.198817)
			(xy 64.570869 -276.229038) (xy 64.525057 -276.252381) (xy 64.476158 -276.268269) (xy 64.425376 -276.276312)
			(xy 64.37396 -276.276312) (xy 64.323178 -276.268269) (xy 64.274279 -276.252381) (xy 64.228467 -276.229038)
			(xy 64.186871 -276.198817) (xy 64.150515 -276.162461) (xy 64.120294 -276.120865) (xy 64.096951 -276.075053)
			(xy 64.081063 -276.026154) (xy 64.07302 -275.975372) (xy 63.754637 -275.975372) (xy 63.74688 -276.023102)
			(xy 63.731296 -276.069783) (xy 63.708425 -276.11336) (xy 63.67886 -276.152704) (xy 63.643367 -276.186796)
			(xy 63.602864 -276.214752) (xy 63.558402 -276.23585) (xy 63.511131 -276.249542) (xy 63.462276 -276.255474)
			(xy 63.413101 -276.253493) (xy 63.364882 -276.243649) (xy 63.318866 -276.226197) (xy 63.276245 -276.20159)
			(xy 63.238124 -276.170465) (xy 63.205489 -276.133628) (xy 63.179186 -276.092032) (xy 63.159895 -276.046756)
			(xy 63.148118 -275.998972) (xy 63.144158 -275.949918) (xy 62.826646 -275.949918) (xy 62.826142 -275.975626)
			(xy 62.818099 -276.026408) (xy 62.802211 -276.075307) (xy 62.778868 -276.121119) (xy 62.748647 -276.162715)
			(xy 62.712291 -276.199071) (xy 62.670695 -276.229292) (xy 62.624883 -276.252635) (xy 62.575984 -276.268523)
			(xy 62.525202 -276.276566) (xy 62.473786 -276.276566) (xy 62.423004 -276.268523) (xy 62.374105 -276.252635)
			(xy 62.328293 -276.229292) (xy 62.286697 -276.199071) (xy 62.250341 -276.162715) (xy 62.22012 -276.121119)
			(xy 62.196777 -276.075307) (xy 62.180889 -276.026408) (xy 62.172846 -275.975626) (xy 61.854422 -275.975626)
			(xy 61.846706 -276.023102) (xy 61.831122 -276.069783) (xy 61.808251 -276.11336) (xy 61.778686 -276.152704)
			(xy 61.743193 -276.186796) (xy 61.70269 -276.214752) (xy 61.658228 -276.23585) (xy 61.610957 -276.249542)
			(xy 61.562102 -276.255474) (xy 61.512927 -276.253493) (xy 61.464708 -276.243649) (xy 61.418692 -276.226197)
			(xy 61.376071 -276.20159) (xy 61.33795 -276.170465) (xy 61.305315 -276.133628) (xy 61.279012 -276.092032)
			(xy 61.259721 -276.046756) (xy 61.247944 -275.998972) (xy 61.243984 -275.949918) (xy 60.926721 -275.949918)
			(xy 60.926222 -275.975372) (xy 60.918179 -276.026154) (xy 60.902291 -276.075053) (xy 60.878948 -276.120865)
			(xy 60.848727 -276.162461) (xy 60.812371 -276.198817) (xy 60.770775 -276.229038) (xy 60.724963 -276.252381)
			(xy 60.676064 -276.268269) (xy 60.625282 -276.276312) (xy 60.573866 -276.276312) (xy 60.523084 -276.268269)
			(xy 60.474185 -276.252381) (xy 60.428373 -276.229038) (xy 60.386777 -276.198817) (xy 60.350421 -276.162461)
			(xy 60.3202 -276.120865) (xy 60.296857 -276.075053) (xy 60.280969 -276.026154) (xy 60.272926 -275.975372)
			(xy 59.954543 -275.975372) (xy 59.946786 -276.023102) (xy 59.931202 -276.069783) (xy 59.908331 -276.11336)
			(xy 59.878766 -276.152704) (xy 59.843273 -276.186796) (xy 59.80277 -276.214752) (xy 59.758308 -276.23585)
			(xy 59.711037 -276.249542) (xy 59.662182 -276.255474) (xy 59.613007 -276.253493) (xy 59.564788 -276.243649)
			(xy 59.518772 -276.226197) (xy 59.476151 -276.20159) (xy 59.43803 -276.170465) (xy 59.405395 -276.133628)
			(xy 59.379092 -276.092032) (xy 59.359801 -276.046756) (xy 59.348024 -275.998972) (xy 59.344064 -275.949918)
			(xy 59.02706 -275.949918) (xy 59.026556 -275.975626) (xy 59.018513 -276.026408) (xy 59.002625 -276.075307)
			(xy 58.979282 -276.121119) (xy 58.949061 -276.162715) (xy 58.912705 -276.199071) (xy 58.871109 -276.229292)
			(xy 58.825297 -276.252635) (xy 58.776398 -276.268523) (xy 58.725616 -276.276566) (xy 58.6742 -276.276566)
			(xy 58.623418 -276.268523) (xy 58.574519 -276.252635) (xy 58.528707 -276.229292) (xy 58.487111 -276.199071)
			(xy 58.450755 -276.162715) (xy 58.420534 -276.121119) (xy 58.397191 -276.075307) (xy 58.381303 -276.026408)
			(xy 58.37326 -275.975626) (xy 58.054582 -275.975626) (xy 58.046866 -276.023102) (xy 58.031282 -276.069783)
			(xy 58.008411 -276.11336) (xy 57.978846 -276.152704) (xy 57.943353 -276.186796) (xy 57.90285 -276.214752)
			(xy 57.858388 -276.23585) (xy 57.811117 -276.249542) (xy 57.762262 -276.255474) (xy 57.713087 -276.253493)
			(xy 57.664868 -276.243649) (xy 57.618852 -276.226197) (xy 57.576231 -276.20159) (xy 57.53811 -276.170465)
			(xy 57.505475 -276.133628) (xy 57.479172 -276.092032) (xy 57.459881 -276.046756) (xy 57.448104 -275.998972)
			(xy 57.444144 -275.949918) (xy 57.12714 -275.949918) (xy 57.126636 -275.975626) (xy 57.118593 -276.026408)
			(xy 57.102705 -276.075307) (xy 57.079362 -276.121119) (xy 57.049141 -276.162715) (xy 57.012785 -276.199071)
			(xy 56.971189 -276.229292) (xy 56.925377 -276.252635) (xy 56.876478 -276.268523) (xy 56.825696 -276.276566)
			(xy 56.77428 -276.276566) (xy 56.723498 -276.268523) (xy 56.674599 -276.252635) (xy 56.628787 -276.229292)
			(xy 56.587191 -276.199071) (xy 56.550835 -276.162715) (xy 56.520614 -276.121119) (xy 56.497271 -276.075307)
			(xy 56.481383 -276.026408) (xy 56.47334 -275.975626) (xy 56.154408 -275.975626) (xy 56.146692 -276.023102)
			(xy 56.131108 -276.069783) (xy 56.108237 -276.11336) (xy 56.078672 -276.152704) (xy 56.043179 -276.186796)
			(xy 56.002676 -276.214752) (xy 55.958214 -276.23585) (xy 55.910943 -276.249542) (xy 55.862088 -276.255474)
			(xy 55.812913 -276.253493) (xy 55.764694 -276.243649) (xy 55.718678 -276.226197) (xy 55.676057 -276.20159)
			(xy 55.637936 -276.170465) (xy 55.605301 -276.133628) (xy 55.578998 -276.092032) (xy 55.559707 -276.046756)
			(xy 55.54793 -275.998972) (xy 55.54397 -275.949918) (xy 55.226966 -275.949918) (xy 55.226462 -275.975626)
			(xy 55.218419 -276.026408) (xy 55.202531 -276.075307) (xy 55.179188 -276.121119) (xy 55.148967 -276.162715)
			(xy 55.112611 -276.199071) (xy 55.071015 -276.229292) (xy 55.025203 -276.252635) (xy 54.976304 -276.268523)
			(xy 54.925522 -276.276566) (xy 54.874106 -276.276566) (xy 54.823324 -276.268523) (xy 54.774425 -276.252635)
			(xy 54.728613 -276.229292) (xy 54.687017 -276.199071) (xy 54.650661 -276.162715) (xy 54.62044 -276.121119)
			(xy 54.597097 -276.075307) (xy 54.581209 -276.026408) (xy 54.573166 -275.975626) (xy 54.254488 -275.975626)
			(xy 54.246772 -276.023102) (xy 54.231188 -276.069783) (xy 54.208317 -276.11336) (xy 54.178752 -276.152704)
			(xy 54.143259 -276.186796) (xy 54.102756 -276.214752) (xy 54.058294 -276.23585) (xy 54.011023 -276.249542)
			(xy 53.962168 -276.255474) (xy 53.912993 -276.253493) (xy 53.864774 -276.243649) (xy 53.818758 -276.226197)
			(xy 53.776137 -276.20159) (xy 53.738016 -276.170465) (xy 53.705381 -276.133628) (xy 53.679078 -276.092032)
			(xy 53.659787 -276.046756) (xy 53.64801 -275.998972) (xy 53.64405 -275.949918) (xy 53.327046 -275.949918)
			(xy 53.326542 -275.975626) (xy 53.318499 -276.026408) (xy 53.302611 -276.075307) (xy 53.279268 -276.121119)
			(xy 53.249047 -276.162715) (xy 53.212691 -276.199071) (xy 53.171095 -276.229292) (xy 53.125283 -276.252635)
			(xy 53.076384 -276.268523) (xy 53.025602 -276.276566) (xy 52.974186 -276.276566) (xy 52.923404 -276.268523)
			(xy 52.874505 -276.252635) (xy 52.828693 -276.229292) (xy 52.787097 -276.199071) (xy 52.750741 -276.162715)
			(xy 52.72052 -276.121119) (xy 52.697177 -276.075307) (xy 52.681289 -276.026408) (xy 52.673246 -275.975626)
			(xy 52.354568 -275.975626) (xy 52.346852 -276.023102) (xy 52.331268 -276.069783) (xy 52.308397 -276.11336)
			(xy 52.278832 -276.152704) (xy 52.243339 -276.186796) (xy 52.202836 -276.214752) (xy 52.158374 -276.23585)
			(xy 52.111103 -276.249542) (xy 52.062248 -276.255474) (xy 52.013073 -276.253493) (xy 51.964854 -276.243649)
			(xy 51.918838 -276.226197) (xy 51.876217 -276.20159) (xy 51.838096 -276.170465) (xy 51.805461 -276.133628)
			(xy 51.779158 -276.092032) (xy 51.759867 -276.046756) (xy 51.74809 -275.998972) (xy 51.74413 -275.949918)
			(xy 51.427126 -275.949918) (xy 51.426622 -275.975626) (xy 51.418579 -276.026408) (xy 51.402691 -276.075307)
			(xy 51.379348 -276.121119) (xy 51.349127 -276.162715) (xy 51.312771 -276.199071) (xy 51.271175 -276.229292)
			(xy 51.225363 -276.252635) (xy 51.176464 -276.268523) (xy 51.125682 -276.276566) (xy 51.074266 -276.276566)
			(xy 51.023484 -276.268523) (xy 50.974585 -276.252635) (xy 50.928773 -276.229292) (xy 50.887177 -276.199071)
			(xy 50.850821 -276.162715) (xy 50.8206 -276.121119) (xy 50.797257 -276.075307) (xy 50.781369 -276.026408)
			(xy 50.773326 -275.975626) (xy 50.454394 -275.975626) (xy 50.446678 -276.023102) (xy 50.431094 -276.069783)
			(xy 50.408223 -276.11336) (xy 50.378658 -276.152704) (xy 50.343165 -276.186796) (xy 50.302662 -276.214752)
			(xy 50.2582 -276.23585) (xy 50.210929 -276.249542) (xy 50.162074 -276.255474) (xy 50.112899 -276.253493)
			(xy 50.06468 -276.243649) (xy 50.018664 -276.226197) (xy 49.976043 -276.20159) (xy 49.937922 -276.170465)
			(xy 49.905287 -276.133628) (xy 49.878984 -276.092032) (xy 49.859693 -276.046756) (xy 49.847916 -275.998972)
			(xy 49.843956 -275.949918) (xy 49.526952 -275.949918) (xy 49.526448 -275.975626) (xy 49.518405 -276.026408)
			(xy 49.502517 -276.075307) (xy 49.479174 -276.121119) (xy 49.448953 -276.162715) (xy 49.412597 -276.199071)
			(xy 49.371001 -276.229292) (xy 49.325189 -276.252635) (xy 49.27629 -276.268523) (xy 49.225508 -276.276566)
			(xy 49.174092 -276.276566) (xy 49.12331 -276.268523) (xy 49.074411 -276.252635) (xy 49.028599 -276.229292)
			(xy 48.987003 -276.199071) (xy 48.950647 -276.162715) (xy 48.920426 -276.121119) (xy 48.897083 -276.075307)
			(xy 48.881195 -276.026408) (xy 48.873152 -275.975626) (xy 48.554474 -275.975626) (xy 48.546758 -276.023102)
			(xy 48.531174 -276.069783) (xy 48.508303 -276.11336) (xy 48.478738 -276.152704) (xy 48.443245 -276.186796)
			(xy 48.402742 -276.214752) (xy 48.35828 -276.23585) (xy 48.311009 -276.249542) (xy 48.262154 -276.255474)
			(xy 48.212979 -276.253493) (xy 48.16476 -276.243649) (xy 48.118744 -276.226197) (xy 48.076123 -276.20159)
			(xy 48.038002 -276.170465) (xy 48.005367 -276.133628) (xy 47.979064 -276.092032) (xy 47.959773 -276.046756)
			(xy 47.947996 -275.998972) (xy 47.944036 -275.949918) (xy 47.627032 -275.949918) (xy 47.626528 -275.975626)
			(xy 47.618485 -276.026408) (xy 47.602597 -276.075307) (xy 47.579254 -276.121119) (xy 47.549033 -276.162715)
			(xy 47.512677 -276.199071) (xy 47.471081 -276.229292) (xy 47.425269 -276.252635) (xy 47.37637 -276.268523)
			(xy 47.325588 -276.276566) (xy 47.274172 -276.276566) (xy 47.22339 -276.268523) (xy 47.174491 -276.252635)
			(xy 47.128679 -276.229292) (xy 47.087083 -276.199071) (xy 47.050727 -276.162715) (xy 47.020506 -276.121119)
			(xy 46.997163 -276.075307) (xy 46.981275 -276.026408) (xy 46.973232 -275.975626) (xy 46.654554 -275.975626)
			(xy 46.646838 -276.023102) (xy 46.631254 -276.069783) (xy 46.608383 -276.11336) (xy 46.578818 -276.152704)
			(xy 46.543325 -276.186796) (xy 46.502822 -276.214752) (xy 46.45836 -276.23585) (xy 46.411089 -276.249542)
			(xy 46.362234 -276.255474) (xy 46.313059 -276.253493) (xy 46.26484 -276.243649) (xy 46.218824 -276.226197)
			(xy 46.176203 -276.20159) (xy 46.138082 -276.170465) (xy 46.105447 -276.133628) (xy 46.079144 -276.092032)
			(xy 46.059853 -276.046756) (xy 46.048076 -275.998972) (xy 46.044116 -275.949918) (xy 45.727112 -275.949918)
			(xy 45.726608 -275.975626) (xy 45.718565 -276.026408) (xy 45.702677 -276.075307) (xy 45.679334 -276.121119)
			(xy 45.649113 -276.162715) (xy 45.612757 -276.199071) (xy 45.571161 -276.229292) (xy 45.525349 -276.252635)
			(xy 45.47645 -276.268523) (xy 45.425668 -276.276566) (xy 45.374252 -276.276566) (xy 45.32347 -276.268523)
			(xy 45.274571 -276.252635) (xy 45.228759 -276.229292) (xy 45.187163 -276.199071) (xy 45.150807 -276.162715)
			(xy 45.120586 -276.121119) (xy 45.097243 -276.075307) (xy 45.081355 -276.026408) (xy 45.073312 -275.975626)
			(xy 44.75438 -275.975626) (xy 44.746664 -276.023102) (xy 44.73108 -276.069783) (xy 44.708209 -276.11336)
			(xy 44.678644 -276.152704) (xy 44.643151 -276.186796) (xy 44.602648 -276.214752) (xy 44.558186 -276.23585)
			(xy 44.510915 -276.249542) (xy 44.46206 -276.255474) (xy 44.412885 -276.253493) (xy 44.364666 -276.243649)
			(xy 44.31865 -276.226197) (xy 44.276029 -276.20159) (xy 44.237908 -276.170465) (xy 44.205273 -276.133628)
			(xy 44.17897 -276.092032) (xy 44.159679 -276.046756) (xy 44.147902 -275.998972) (xy 44.143942 -275.949918)
			(xy 40.899334 -275.949918) (xy 40.899334 -276.037294) (xy 40.899999 -276.049322) (xy 40.91086 -276.070789)
			(xy 40.920162 -276.078442) (xy 40.996362 -276.134068) (xy 41.020238 -276.137878) (xy 41.031922 -276.134068)
			(xy 41.054563 -276.127293) (xy 41.101257 -276.120021) (xy 41.124886 -276.11959) (xy 41.150145 -276.120082)
			(xy 41.199973 -276.128394) (xy 41.247754 -276.144796) (xy 41.292183 -276.168838) (xy 41.332049 -276.199865)
			(xy 41.366264 -276.237031) (xy 41.393895 -276.279322) (xy 41.414189 -276.325584) (xy 41.42659 -276.374555)
			(xy 41.430762 -276.424898) (xy 41.769042 -276.424898) (xy 41.773002 -276.375844) (xy 41.784779 -276.32806)
			(xy 41.80407 -276.282784) (xy 41.830373 -276.241188) (xy 41.863008 -276.204351) (xy 41.901129 -276.173226)
			(xy 41.94375 -276.148619) (xy 41.989766 -276.131167) (xy 42.037985 -276.121323) (xy 42.08716 -276.119342)
			(xy 42.136015 -276.125274) (xy 42.183286 -276.138966) (xy 42.227748 -276.160064) (xy 42.268251 -276.18802)
			(xy 42.303744 -276.222112) (xy 42.333309 -276.261456) (xy 42.35618 -276.305033) (xy 42.371764 -276.351714)
			(xy 42.379659 -276.400291) (xy 42.380154 -276.424898) (xy 42.379659 -276.449505) (xy 42.371764 -276.498082)
			(xy 42.35618 -276.544763) (xy 42.333309 -276.58834) (xy 42.303744 -276.627684) (xy 42.268251 -276.661776)
			(xy 42.227748 -276.689732) (xy 42.183286 -276.71083) (xy 42.136015 -276.724522) (xy 42.08716 -276.730454)
			(xy 42.037985 -276.728473) (xy 41.989766 -276.718629) (xy 41.94375 -276.701177) (xy 41.901129 -276.67657)
			(xy 41.863008 -276.645445) (xy 41.830373 -276.608608) (xy 41.80407 -276.567012) (xy 41.784779 -276.521736)
			(xy 41.773002 -276.473952) (xy 41.769042 -276.424898) (xy 41.430762 -276.424898) (xy 41.430762 -276.4249)
			(xy 41.42659 -276.475245) (xy 41.414189 -276.524216) (xy 41.393895 -276.570478) (xy 41.366264 -276.612769)
			(xy 41.332049 -276.649935) (xy 41.292183 -276.680962) (xy 41.247754 -276.705004) (xy 41.199973 -276.721406)
			(xy 41.150145 -276.729718) (xy 41.124886 -276.730206) (xy 41.101259 -276.729759) (xy 41.054569 -276.72248)
			(xy 41.031922 -276.715728) (xy 41.020238 -276.711918) (xy 40.996362 -276.715728) (xy 40.920162 -276.771354)
			(xy 40.910817 -276.778975) (xy 40.899943 -276.800459) (xy 40.899334 -276.812502) (xy 40.899334 -276.899878)
			(xy 43.193982 -276.899878) (xy 43.197942 -276.850824) (xy 43.209719 -276.80304) (xy 43.22901 -276.757764)
			(xy 43.255313 -276.716168) (xy 43.287948 -276.679331) (xy 43.326069 -276.648206) (xy 43.36869 -276.623599)
			(xy 43.414706 -276.606147) (xy 43.462925 -276.596303) (xy 43.5121 -276.594322) (xy 43.560955 -276.600254)
			(xy 43.608226 -276.613946) (xy 43.652688 -276.635044) (xy 43.693191 -276.663) (xy 43.728684 -276.697092)
			(xy 43.758249 -276.736436) (xy 43.78112 -276.780013) (xy 43.796704 -276.826694) (xy 43.804599 -276.875271)
			(xy 43.805094 -276.899878) (xy 44.143942 -276.899878) (xy 44.147902 -276.850824) (xy 44.159679 -276.80304)
			(xy 44.17897 -276.757764) (xy 44.205273 -276.716168) (xy 44.237908 -276.679331) (xy 44.276029 -276.648206)
			(xy 44.31865 -276.623599) (xy 44.364666 -276.606147) (xy 44.412885 -276.596303) (xy 44.46206 -276.594322)
			(xy 44.510915 -276.600254) (xy 44.558186 -276.613946) (xy 44.602648 -276.635044) (xy 44.643151 -276.663)
			(xy 44.678644 -276.697092) (xy 44.708209 -276.736436) (xy 44.73108 -276.780013) (xy 44.746664 -276.826694)
			(xy 44.754559 -276.875271) (xy 44.755054 -276.899878) (xy 45.094156 -276.899878) (xy 45.098116 -276.850824)
			(xy 45.109893 -276.80304) (xy 45.129184 -276.757764) (xy 45.155487 -276.716168) (xy 45.188122 -276.679331)
			(xy 45.226243 -276.648206) (xy 45.268864 -276.623599) (xy 45.31488 -276.606147) (xy 45.363099 -276.596303)
			(xy 45.412274 -276.594322) (xy 45.461129 -276.600254) (xy 45.5084 -276.613946) (xy 45.552862 -276.635044)
			(xy 45.593365 -276.663) (xy 45.628858 -276.697092) (xy 45.658423 -276.736436) (xy 45.681294 -276.780013)
			(xy 45.696878 -276.826694) (xy 45.704773 -276.875271) (xy 45.705268 -276.899878) (xy 46.044116 -276.899878)
			(xy 46.048076 -276.850824) (xy 46.059853 -276.80304) (xy 46.079144 -276.757764) (xy 46.105447 -276.716168)
			(xy 46.138082 -276.679331) (xy 46.176203 -276.648206) (xy 46.218824 -276.623599) (xy 46.26484 -276.606147)
			(xy 46.313059 -276.596303) (xy 46.362234 -276.594322) (xy 46.411089 -276.600254) (xy 46.45836 -276.613946)
			(xy 46.502822 -276.635044) (xy 46.543325 -276.663) (xy 46.578818 -276.697092) (xy 46.608383 -276.736436)
			(xy 46.631254 -276.780013) (xy 46.646838 -276.826694) (xy 46.654733 -276.875271) (xy 46.655228 -276.899878)
			(xy 46.994076 -276.899878) (xy 46.998036 -276.850824) (xy 47.009813 -276.80304) (xy 47.029104 -276.757764)
			(xy 47.055407 -276.716168) (xy 47.088042 -276.679331) (xy 47.126163 -276.648206) (xy 47.168784 -276.623599)
			(xy 47.2148 -276.606147) (xy 47.263019 -276.596303) (xy 47.312194 -276.594322) (xy 47.361049 -276.600254)
			(xy 47.40832 -276.613946) (xy 47.452782 -276.635044) (xy 47.493285 -276.663) (xy 47.528778 -276.697092)
			(xy 47.558343 -276.736436) (xy 47.581214 -276.780013) (xy 47.596798 -276.826694) (xy 47.604693 -276.875271)
			(xy 47.605188 -276.899878) (xy 47.944036 -276.899878) (xy 47.947996 -276.850824) (xy 47.959773 -276.80304)
			(xy 47.979064 -276.757764) (xy 48.005367 -276.716168) (xy 48.038002 -276.679331) (xy 48.076123 -276.648206)
			(xy 48.118744 -276.623599) (xy 48.16476 -276.606147) (xy 48.212979 -276.596303) (xy 48.262154 -276.594322)
			(xy 48.311009 -276.600254) (xy 48.35828 -276.613946) (xy 48.402742 -276.635044) (xy 48.443245 -276.663)
			(xy 48.478738 -276.697092) (xy 48.508303 -276.736436) (xy 48.531174 -276.780013) (xy 48.546758 -276.826694)
			(xy 48.554653 -276.875271) (xy 48.555148 -276.899878) (xy 48.893996 -276.899878) (xy 48.897956 -276.850824)
			(xy 48.909733 -276.80304) (xy 48.929024 -276.757764) (xy 48.955327 -276.716168) (xy 48.987962 -276.679331)
			(xy 49.026083 -276.648206) (xy 49.068704 -276.623599) (xy 49.11472 -276.606147) (xy 49.162939 -276.596303)
			(xy 49.212114 -276.594322) (xy 49.260969 -276.600254) (xy 49.30824 -276.613946) (xy 49.352702 -276.635044)
			(xy 49.393205 -276.663) (xy 49.428698 -276.697092) (xy 49.458263 -276.736436) (xy 49.481134 -276.780013)
			(xy 49.496718 -276.826694) (xy 49.504613 -276.875271) (xy 49.505108 -276.899878) (xy 49.843956 -276.899878)
			(xy 49.847916 -276.850824) (xy 49.859693 -276.80304) (xy 49.878984 -276.757764) (xy 49.905287 -276.716168)
			(xy 49.937922 -276.679331) (xy 49.976043 -276.648206) (xy 50.018664 -276.623599) (xy 50.06468 -276.606147)
			(xy 50.112899 -276.596303) (xy 50.162074 -276.594322) (xy 50.210929 -276.600254) (xy 50.2582 -276.613946)
			(xy 50.302662 -276.635044) (xy 50.343165 -276.663) (xy 50.378658 -276.697092) (xy 50.408223 -276.736436)
			(xy 50.431094 -276.780013) (xy 50.446678 -276.826694) (xy 50.454573 -276.875271) (xy 50.455068 -276.899878)
			(xy 50.79417 -276.899878) (xy 50.79813 -276.850824) (xy 50.809907 -276.80304) (xy 50.829198 -276.757764)
			(xy 50.855501 -276.716168) (xy 50.888136 -276.679331) (xy 50.926257 -276.648206) (xy 50.968878 -276.623599)
			(xy 51.014894 -276.606147) (xy 51.063113 -276.596303) (xy 51.112288 -276.594322) (xy 51.161143 -276.600254)
			(xy 51.208414 -276.613946) (xy 51.252876 -276.635044) (xy 51.293379 -276.663) (xy 51.328872 -276.697092)
			(xy 51.358437 -276.736436) (xy 51.381308 -276.780013) (xy 51.396892 -276.826694) (xy 51.404787 -276.875271)
			(xy 51.405282 -276.899878) (xy 51.74413 -276.899878) (xy 51.74809 -276.850824) (xy 51.759867 -276.80304)
			(xy 51.779158 -276.757764) (xy 51.805461 -276.716168) (xy 51.838096 -276.679331) (xy 51.876217 -276.648206)
			(xy 51.918838 -276.623599) (xy 51.964854 -276.606147) (xy 52.013073 -276.596303) (xy 52.062248 -276.594322)
			(xy 52.111103 -276.600254) (xy 52.158374 -276.613946) (xy 52.202836 -276.635044) (xy 52.243339 -276.663)
			(xy 52.278832 -276.697092) (xy 52.308397 -276.736436) (xy 52.331268 -276.780013) (xy 52.346852 -276.826694)
			(xy 52.354747 -276.875271) (xy 52.355242 -276.899878) (xy 52.69409 -276.899878) (xy 52.69805 -276.850824)
			(xy 52.709827 -276.80304) (xy 52.729118 -276.757764) (xy 52.755421 -276.716168) (xy 52.788056 -276.679331)
			(xy 52.826177 -276.648206) (xy 52.868798 -276.623599) (xy 52.914814 -276.606147) (xy 52.963033 -276.596303)
			(xy 53.012208 -276.594322) (xy 53.061063 -276.600254) (xy 53.108334 -276.613946) (xy 53.152796 -276.635044)
			(xy 53.193299 -276.663) (xy 53.228792 -276.697092) (xy 53.258357 -276.736436) (xy 53.281228 -276.780013)
			(xy 53.296812 -276.826694) (xy 53.304707 -276.875271) (xy 53.305202 -276.899878) (xy 53.64405 -276.899878)
			(xy 53.64801 -276.850824) (xy 53.659787 -276.80304) (xy 53.679078 -276.757764) (xy 53.705381 -276.716168)
			(xy 53.738016 -276.679331) (xy 53.776137 -276.648206) (xy 53.818758 -276.623599) (xy 53.864774 -276.606147)
			(xy 53.912993 -276.596303) (xy 53.962168 -276.594322) (xy 54.011023 -276.600254) (xy 54.058294 -276.613946)
			(xy 54.102756 -276.635044) (xy 54.143259 -276.663) (xy 54.178752 -276.697092) (xy 54.208317 -276.736436)
			(xy 54.231188 -276.780013) (xy 54.246772 -276.826694) (xy 54.254667 -276.875271) (xy 54.255162 -276.899878)
			(xy 54.59401 -276.899878) (xy 54.59797 -276.850824) (xy 54.609747 -276.80304) (xy 54.629038 -276.757764)
			(xy 54.655341 -276.716168) (xy 54.687976 -276.679331) (xy 54.726097 -276.648206) (xy 54.768718 -276.623599)
			(xy 54.814734 -276.606147) (xy 54.862953 -276.596303) (xy 54.912128 -276.594322) (xy 54.960983 -276.600254)
			(xy 55.008254 -276.613946) (xy 55.052716 -276.635044) (xy 55.093219 -276.663) (xy 55.128712 -276.697092)
			(xy 55.158277 -276.736436) (xy 55.181148 -276.780013) (xy 55.196732 -276.826694) (xy 55.204627 -276.875271)
			(xy 55.205122 -276.899878) (xy 55.54397 -276.899878) (xy 55.54793 -276.850824) (xy 55.559707 -276.80304)
			(xy 55.578998 -276.757764) (xy 55.605301 -276.716168) (xy 55.637936 -276.679331) (xy 55.676057 -276.648206)
			(xy 55.718678 -276.623599) (xy 55.764694 -276.606147) (xy 55.812913 -276.596303) (xy 55.862088 -276.594322)
			(xy 55.910943 -276.600254) (xy 55.958214 -276.613946) (xy 56.002676 -276.635044) (xy 56.043179 -276.663)
			(xy 56.078672 -276.697092) (xy 56.108237 -276.736436) (xy 56.131108 -276.780013) (xy 56.146692 -276.826694)
			(xy 56.154587 -276.875271) (xy 56.155082 -276.899878) (xy 56.494184 -276.899878) (xy 56.498144 -276.850824)
			(xy 56.509921 -276.80304) (xy 56.529212 -276.757764) (xy 56.555515 -276.716168) (xy 56.58815 -276.679331)
			(xy 56.626271 -276.648206) (xy 56.668892 -276.623599) (xy 56.714908 -276.606147) (xy 56.763127 -276.596303)
			(xy 56.812302 -276.594322) (xy 56.861157 -276.600254) (xy 56.908428 -276.613946) (xy 56.95289 -276.635044)
			(xy 56.993393 -276.663) (xy 57.028886 -276.697092) (xy 57.058451 -276.736436) (xy 57.081322 -276.780013)
			(xy 57.096906 -276.826694) (xy 57.104801 -276.875271) (xy 57.105296 -276.899878) (xy 57.444144 -276.899878)
			(xy 57.448104 -276.850824) (xy 57.459881 -276.80304) (xy 57.479172 -276.757764) (xy 57.505475 -276.716168)
			(xy 57.53811 -276.679331) (xy 57.576231 -276.648206) (xy 57.618852 -276.623599) (xy 57.664868 -276.606147)
			(xy 57.713087 -276.596303) (xy 57.762262 -276.594322) (xy 57.811117 -276.600254) (xy 57.858388 -276.613946)
			(xy 57.90285 -276.635044) (xy 57.943353 -276.663) (xy 57.978846 -276.697092) (xy 58.008411 -276.736436)
			(xy 58.031282 -276.780013) (xy 58.046866 -276.826694) (xy 58.054761 -276.875271) (xy 58.055256 -276.899878)
			(xy 58.394104 -276.899878) (xy 58.398064 -276.850824) (xy 58.409841 -276.80304) (xy 58.429132 -276.757764)
			(xy 58.455435 -276.716168) (xy 58.48807 -276.679331) (xy 58.526191 -276.648206) (xy 58.568812 -276.623599)
			(xy 58.614828 -276.606147) (xy 58.663047 -276.596303) (xy 58.712222 -276.594322) (xy 58.761077 -276.600254)
			(xy 58.808348 -276.613946) (xy 58.85281 -276.635044) (xy 58.893313 -276.663) (xy 58.928806 -276.697092)
			(xy 58.958371 -276.736436) (xy 58.981242 -276.780013) (xy 58.996826 -276.826694) (xy 59.004721 -276.875271)
			(xy 59.005216 -276.899878) (xy 59.344064 -276.899878) (xy 59.348024 -276.850824) (xy 59.359801 -276.80304)
			(xy 59.379092 -276.757764) (xy 59.405395 -276.716168) (xy 59.43803 -276.679331) (xy 59.476151 -276.648206)
			(xy 59.518772 -276.623599) (xy 59.564788 -276.606147) (xy 59.613007 -276.596303) (xy 59.662182 -276.594322)
			(xy 59.711037 -276.600254) (xy 59.758308 -276.613946) (xy 59.80277 -276.635044) (xy 59.843273 -276.663)
			(xy 59.878766 -276.697092) (xy 59.908331 -276.736436) (xy 59.931202 -276.780013) (xy 59.946786 -276.826694)
			(xy 59.954681 -276.875271) (xy 59.955176 -276.899878) (xy 60.294024 -276.899878) (xy 60.297984 -276.850824)
			(xy 60.309761 -276.80304) (xy 60.329052 -276.757764) (xy 60.355355 -276.716168) (xy 60.38799 -276.679331)
			(xy 60.426111 -276.648206) (xy 60.468732 -276.623599) (xy 60.514748 -276.606147) (xy 60.562967 -276.596303)
			(xy 60.612142 -276.594322) (xy 60.660997 -276.600254) (xy 60.708268 -276.613946) (xy 60.75273 -276.635044)
			(xy 60.793233 -276.663) (xy 60.828726 -276.697092) (xy 60.858291 -276.736436) (xy 60.881162 -276.780013)
			(xy 60.896746 -276.826694) (xy 60.904641 -276.875271) (xy 60.905136 -276.899878) (xy 61.243984 -276.899878)
			(xy 61.247944 -276.850824) (xy 61.259721 -276.80304) (xy 61.279012 -276.757764) (xy 61.305315 -276.716168)
			(xy 61.33795 -276.679331) (xy 61.376071 -276.648206) (xy 61.418692 -276.623599) (xy 61.464708 -276.606147)
			(xy 61.512927 -276.596303) (xy 61.562102 -276.594322) (xy 61.610957 -276.600254) (xy 61.658228 -276.613946)
			(xy 61.70269 -276.635044) (xy 61.743193 -276.663) (xy 61.778686 -276.697092) (xy 61.808251 -276.736436)
			(xy 61.831122 -276.780013) (xy 61.846706 -276.826694) (xy 61.854601 -276.875271) (xy 61.855096 -276.899878)
			(xy 62.193944 -276.899878) (xy 62.197904 -276.850824) (xy 62.209681 -276.80304) (xy 62.228972 -276.757764)
			(xy 62.255275 -276.716168) (xy 62.28791 -276.679331) (xy 62.326031 -276.648206) (xy 62.368652 -276.623599)
			(xy 62.414668 -276.606147) (xy 62.462887 -276.596303) (xy 62.512062 -276.594322) (xy 62.560917 -276.600254)
			(xy 62.608188 -276.613946) (xy 62.65265 -276.635044) (xy 62.693153 -276.663) (xy 62.728646 -276.697092)
			(xy 62.758211 -276.736436) (xy 62.781082 -276.780013) (xy 62.796666 -276.826694) (xy 62.804561 -276.875271)
			(xy 62.805056 -276.899878) (xy 63.144158 -276.899878) (xy 63.148118 -276.850824) (xy 63.159895 -276.80304)
			(xy 63.179186 -276.757764) (xy 63.205489 -276.716168) (xy 63.238124 -276.679331) (xy 63.276245 -276.648206)
			(xy 63.318866 -276.623599) (xy 63.364882 -276.606147) (xy 63.413101 -276.596303) (xy 63.462276 -276.594322)
			(xy 63.511131 -276.600254) (xy 63.558402 -276.613946) (xy 63.602864 -276.635044) (xy 63.643367 -276.663)
			(xy 63.67886 -276.697092) (xy 63.708425 -276.736436) (xy 63.731296 -276.780013) (xy 63.74688 -276.826694)
			(xy 63.754775 -276.875271) (xy 63.75527 -276.899878) (xy 64.094118 -276.899878) (xy 64.098078 -276.850824)
			(xy 64.109855 -276.80304) (xy 64.129146 -276.757764) (xy 64.155449 -276.716168) (xy 64.188084 -276.679331)
			(xy 64.226205 -276.648206) (xy 64.268826 -276.623599) (xy 64.314842 -276.606147) (xy 64.363061 -276.596303)
			(xy 64.412236 -276.594322) (xy 64.461091 -276.600254) (xy 64.508362 -276.613946) (xy 64.552824 -276.635044)
			(xy 64.593327 -276.663) (xy 64.62882 -276.697092) (xy 64.658385 -276.736436) (xy 64.681256 -276.780013)
			(xy 64.69684 -276.826694) (xy 64.704735 -276.875271) (xy 64.70523 -276.899878) (xy 65.044078 -276.899878)
			(xy 65.048038 -276.850824) (xy 65.059815 -276.80304) (xy 65.079106 -276.757764) (xy 65.105409 -276.716168)
			(xy 65.138044 -276.679331) (xy 65.176165 -276.648206) (xy 65.218786 -276.623599) (xy 65.264802 -276.606147)
			(xy 65.313021 -276.596303) (xy 65.362196 -276.594322) (xy 65.411051 -276.600254) (xy 65.458322 -276.613946)
			(xy 65.502784 -276.635044) (xy 65.543287 -276.663) (xy 65.57878 -276.697092) (xy 65.608345 -276.736436)
			(xy 65.631216 -276.780013) (xy 65.6468 -276.826694) (xy 65.654695 -276.875271) (xy 65.65519 -276.899878)
			(xy 65.994038 -276.899878) (xy 65.997998 -276.850824) (xy 66.009775 -276.80304) (xy 66.029066 -276.757764)
			(xy 66.055369 -276.716168) (xy 66.088004 -276.679331) (xy 66.126125 -276.648206) (xy 66.168746 -276.623599)
			(xy 66.214762 -276.606147) (xy 66.262981 -276.596303) (xy 66.312156 -276.594322) (xy 66.361011 -276.600254)
			(xy 66.408282 -276.613946) (xy 66.452744 -276.635044) (xy 66.493247 -276.663) (xy 66.52874 -276.697092)
			(xy 66.558305 -276.736436) (xy 66.581176 -276.780013) (xy 66.59676 -276.826694) (xy 66.604655 -276.875271)
			(xy 66.60515 -276.899878) (xy 66.943998 -276.899878) (xy 66.947958 -276.850824) (xy 66.959735 -276.80304)
			(xy 66.979026 -276.757764) (xy 67.005329 -276.716168) (xy 67.037964 -276.679331) (xy 67.076085 -276.648206)
			(xy 67.118706 -276.623599) (xy 67.164722 -276.606147) (xy 67.212941 -276.596303) (xy 67.262116 -276.594322)
			(xy 67.310971 -276.600254) (xy 67.358242 -276.613946) (xy 67.402704 -276.635044) (xy 67.443207 -276.663)
			(xy 67.4787 -276.697092) (xy 67.508265 -276.736436) (xy 67.531136 -276.780013) (xy 67.54672 -276.826694)
			(xy 67.554615 -276.875271) (xy 67.55511 -276.899878) (xy 67.893958 -276.899878) (xy 67.897918 -276.850824)
			(xy 67.909695 -276.80304) (xy 67.928986 -276.757764) (xy 67.955289 -276.716168) (xy 67.987924 -276.679331)
			(xy 68.026045 -276.648206) (xy 68.068666 -276.623599) (xy 68.114682 -276.606147) (xy 68.162901 -276.596303)
			(xy 68.212076 -276.594322) (xy 68.260931 -276.600254) (xy 68.308202 -276.613946) (xy 68.352664 -276.635044)
			(xy 68.393167 -276.663) (xy 68.42866 -276.697092) (xy 68.458225 -276.736436) (xy 68.481096 -276.780013)
			(xy 68.49668 -276.826694) (xy 68.504575 -276.875271) (xy 68.50507 -276.899878) (xy 68.844172 -276.899878)
			(xy 68.848132 -276.850824) (xy 68.859909 -276.80304) (xy 68.8792 -276.757764) (xy 68.905503 -276.716168)
			(xy 68.938138 -276.679331) (xy 68.976259 -276.648206) (xy 69.01888 -276.623599) (xy 69.064896 -276.606147)
			(xy 69.113115 -276.596303) (xy 69.16229 -276.594322) (xy 69.211145 -276.600254) (xy 69.258416 -276.613946)
			(xy 69.302878 -276.635044) (xy 69.343381 -276.663) (xy 69.378874 -276.697092) (xy 69.408439 -276.736436)
			(xy 69.43131 -276.780013) (xy 69.446894 -276.826694) (xy 69.454789 -276.875271) (xy 69.455284 -276.899878)
			(xy 69.794132 -276.899878) (xy 69.798092 -276.850824) (xy 69.809869 -276.80304) (xy 69.82916 -276.757764)
			(xy 69.855463 -276.716168) (xy 69.888098 -276.679331) (xy 69.926219 -276.648206) (xy 69.96884 -276.623599)
			(xy 70.014856 -276.606147) (xy 70.063075 -276.596303) (xy 70.11225 -276.594322) (xy 70.161105 -276.600254)
			(xy 70.208376 -276.613946) (xy 70.252838 -276.635044) (xy 70.293341 -276.663) (xy 70.328834 -276.697092)
			(xy 70.358399 -276.736436) (xy 70.38127 -276.780013) (xy 70.396854 -276.826694) (xy 70.404749 -276.875271)
			(xy 70.405244 -276.899878) (xy 70.744092 -276.899878) (xy 70.748052 -276.850824) (xy 70.759829 -276.80304)
			(xy 70.77912 -276.757764) (xy 70.805423 -276.716168) (xy 70.838058 -276.679331) (xy 70.876179 -276.648206)
			(xy 70.9188 -276.623599) (xy 70.964816 -276.606147) (xy 71.013035 -276.596303) (xy 71.06221 -276.594322)
			(xy 71.111065 -276.600254) (xy 71.158336 -276.613946) (xy 71.202798 -276.635044) (xy 71.243301 -276.663)
			(xy 71.278794 -276.697092) (xy 71.308359 -276.736436) (xy 71.33123 -276.780013) (xy 71.346814 -276.826694)
			(xy 71.354709 -276.875271) (xy 71.355204 -276.899878) (xy 71.694052 -276.899878) (xy 71.698012 -276.850824)
			(xy 71.709789 -276.80304) (xy 71.72908 -276.757764) (xy 71.755383 -276.716168) (xy 71.788018 -276.679331)
			(xy 71.826139 -276.648206) (xy 71.86876 -276.623599) (xy 71.914776 -276.606147) (xy 71.962995 -276.596303)
			(xy 72.01217 -276.594322) (xy 72.061025 -276.600254) (xy 72.108296 -276.613946) (xy 72.152758 -276.635044)
			(xy 72.193261 -276.663) (xy 72.228754 -276.697092) (xy 72.258319 -276.736436) (xy 72.28119 -276.780013)
			(xy 72.296774 -276.826694) (xy 72.304669 -276.875271) (xy 72.305164 -276.899878) (xy 72.644012 -276.899878)
			(xy 72.647972 -276.850824) (xy 72.659749 -276.80304) (xy 72.67904 -276.757764) (xy 72.705343 -276.716168)
			(xy 72.737978 -276.679331) (xy 72.776099 -276.648206) (xy 72.81872 -276.623599) (xy 72.864736 -276.606147)
			(xy 72.912955 -276.596303) (xy 72.96213 -276.594322) (xy 73.010985 -276.600254) (xy 73.058256 -276.613946)
			(xy 73.102718 -276.635044) (xy 73.143221 -276.663) (xy 73.178714 -276.697092) (xy 73.208279 -276.736436)
			(xy 73.23115 -276.780013) (xy 73.246734 -276.826694) (xy 73.254629 -276.875271) (xy 73.255124 -276.899878)
			(xy 73.593718 -276.899878) (xy 73.597678 -276.850824) (xy 73.609455 -276.80304) (xy 73.628746 -276.757764)
			(xy 73.655049 -276.716168) (xy 73.687684 -276.679331) (xy 73.725805 -276.648206) (xy 73.768426 -276.623599)
			(xy 73.814442 -276.606147) (xy 73.862661 -276.596303) (xy 73.911836 -276.594322) (xy 73.960691 -276.600254)
			(xy 74.007962 -276.613946) (xy 74.052424 -276.635044) (xy 74.092927 -276.663) (xy 74.12842 -276.697092)
			(xy 74.157985 -276.736436) (xy 74.180856 -276.780013) (xy 74.19644 -276.826694) (xy 74.204335 -276.875271)
			(xy 74.20483 -276.899878) (xy 74.543932 -276.899878) (xy 74.547892 -276.850824) (xy 74.559669 -276.80304)
			(xy 74.57896 -276.757764) (xy 74.605263 -276.716168) (xy 74.637898 -276.679331) (xy 74.676019 -276.648206)
			(xy 74.71864 -276.623599) (xy 74.764656 -276.606147) (xy 74.812875 -276.596303) (xy 74.86205 -276.594322)
			(xy 74.910905 -276.600254) (xy 74.958176 -276.613946) (xy 75.002638 -276.635044) (xy 75.043141 -276.663)
			(xy 75.078634 -276.697092) (xy 75.108199 -276.736436) (xy 75.13107 -276.780013) (xy 75.146654 -276.826694)
			(xy 75.154549 -276.875271) (xy 75.155044 -276.899878) (xy 75.493892 -276.899878) (xy 75.497852 -276.850824)
			(xy 75.509629 -276.80304) (xy 75.52892 -276.757764) (xy 75.555223 -276.716168) (xy 75.587858 -276.679331)
			(xy 75.625979 -276.648206) (xy 75.6686 -276.623599) (xy 75.714616 -276.606147) (xy 75.762835 -276.596303)
			(xy 75.81201 -276.594322) (xy 75.860865 -276.600254) (xy 75.908136 -276.613946) (xy 75.952598 -276.635044)
			(xy 75.993101 -276.663) (xy 76.028594 -276.697092) (xy 76.058159 -276.736436) (xy 76.08103 -276.780013)
			(xy 76.096614 -276.826694) (xy 76.104509 -276.875271) (xy 76.105004 -276.899878) (xy 76.443852 -276.899878)
			(xy 76.447812 -276.850824) (xy 76.459589 -276.80304) (xy 76.47888 -276.757764) (xy 76.505183 -276.716168)
			(xy 76.537818 -276.679331) (xy 76.575939 -276.648206) (xy 76.61856 -276.623599) (xy 76.664576 -276.606147)
			(xy 76.712795 -276.596303) (xy 76.76197 -276.594322) (xy 76.810825 -276.600254) (xy 76.858096 -276.613946)
			(xy 76.902558 -276.635044) (xy 76.943061 -276.663) (xy 76.978554 -276.697092) (xy 77.008119 -276.736436)
			(xy 77.03099 -276.780013) (xy 77.046574 -276.826694) (xy 77.054469 -276.875271) (xy 77.054964 -276.899878)
			(xy 77.393812 -276.899878) (xy 77.397772 -276.850824) (xy 77.409549 -276.80304) (xy 77.42884 -276.757764)
			(xy 77.455143 -276.716168) (xy 77.487778 -276.679331) (xy 77.525899 -276.648206) (xy 77.56852 -276.623599)
			(xy 77.614536 -276.606147) (xy 77.662755 -276.596303) (xy 77.71193 -276.594322) (xy 77.760785 -276.600254)
			(xy 77.808056 -276.613946) (xy 77.852518 -276.635044) (xy 77.893021 -276.663) (xy 77.928514 -276.697092)
			(xy 77.958079 -276.736436) (xy 77.98095 -276.780013) (xy 77.996534 -276.826694) (xy 78.004429 -276.875271)
			(xy 78.004924 -276.899878) (xy 78.343772 -276.899878) (xy 78.347732 -276.850824) (xy 78.359509 -276.80304)
			(xy 78.3788 -276.757764) (xy 78.405103 -276.716168) (xy 78.437738 -276.679331) (xy 78.475859 -276.648206)
			(xy 78.51848 -276.623599) (xy 78.564496 -276.606147) (xy 78.612715 -276.596303) (xy 78.66189 -276.594322)
			(xy 78.710745 -276.600254) (xy 78.758016 -276.613946) (xy 78.802478 -276.635044) (xy 78.842981 -276.663)
			(xy 78.878474 -276.697092) (xy 78.908039 -276.736436) (xy 78.93091 -276.780013) (xy 78.946494 -276.826694)
			(xy 78.954389 -276.875271) (xy 78.954884 -276.899878) (xy 79.293732 -276.899878) (xy 79.297692 -276.850824)
			(xy 79.309469 -276.80304) (xy 79.32876 -276.757764) (xy 79.355063 -276.716168) (xy 79.387698 -276.679331)
			(xy 79.425819 -276.648206) (xy 79.46844 -276.623599) (xy 79.514456 -276.606147) (xy 79.562675 -276.596303)
			(xy 79.61185 -276.594322) (xy 79.660705 -276.600254) (xy 79.707976 -276.613946) (xy 79.752438 -276.635044)
			(xy 79.792941 -276.663) (xy 79.828434 -276.697092) (xy 79.857999 -276.736436) (xy 79.88087 -276.780013)
			(xy 79.896454 -276.826694) (xy 79.904349 -276.875271) (xy 79.904844 -276.899878) (xy 80.243946 -276.899878)
			(xy 80.247906 -276.850824) (xy 80.259683 -276.80304) (xy 80.278974 -276.757764) (xy 80.305277 -276.716168)
			(xy 80.337912 -276.679331) (xy 80.376033 -276.648206) (xy 80.418654 -276.623599) (xy 80.46467 -276.606147)
			(xy 80.512889 -276.596303) (xy 80.562064 -276.594322) (xy 80.610919 -276.600254) (xy 80.65819 -276.613946)
			(xy 80.702652 -276.635044) (xy 80.743155 -276.663) (xy 80.778648 -276.697092) (xy 80.808213 -276.736436)
			(xy 80.831084 -276.780013) (xy 80.846668 -276.826694) (xy 80.854563 -276.875271) (xy 80.855058 -276.899878)
			(xy 80.854563 -276.924485) (xy 80.854384 -276.925586) (xy 81.173316 -276.925586) (xy 81.173316 -276.87417)
			(xy 81.181359 -276.823388) (xy 81.197247 -276.774489) (xy 81.22059 -276.728677) (xy 81.250811 -276.687081)
			(xy 81.287167 -276.650725) (xy 81.328763 -276.620504) (xy 81.374575 -276.597161) (xy 81.423474 -276.581273)
			(xy 81.474256 -276.57323) (xy 81.525672 -276.57323) (xy 81.576454 -276.581273) (xy 81.625353 -276.597161)
			(xy 81.671165 -276.620504) (xy 81.712761 -276.650725) (xy 81.749117 -276.687081) (xy 81.779338 -276.728677)
			(xy 81.802681 -276.774489) (xy 81.818569 -276.823388) (xy 81.826612 -276.87417) (xy 81.827116 -276.899878)
			(xy 81.826612 -276.925586) (xy 82.123276 -276.925586) (xy 82.123276 -276.87417) (xy 82.131319 -276.823388)
			(xy 82.147207 -276.774489) (xy 82.17055 -276.728677) (xy 82.200771 -276.687081) (xy 82.237127 -276.650725)
			(xy 82.278723 -276.620504) (xy 82.324535 -276.597161) (xy 82.373434 -276.581273) (xy 82.424216 -276.57323)
			(xy 82.475632 -276.57323) (xy 82.526414 -276.581273) (xy 82.575313 -276.597161) (xy 82.621125 -276.620504)
			(xy 82.662721 -276.650725) (xy 82.699077 -276.687081) (xy 82.729298 -276.728677) (xy 82.752641 -276.774489)
			(xy 82.768529 -276.823388) (xy 82.776572 -276.87417) (xy 82.777076 -276.899878) (xy 82.777071 -276.900132)
			(xy 83.094334 -276.900132) (xy 83.098294 -276.851078) (xy 83.110071 -276.803294) (xy 83.129362 -276.758018)
			(xy 83.155665 -276.716422) (xy 83.1883 -276.679585) (xy 83.226421 -276.64846) (xy 83.269042 -276.623853)
			(xy 83.315058 -276.606401) (xy 83.363277 -276.596557) (xy 83.412452 -276.594576) (xy 83.461307 -276.600508)
			(xy 83.508578 -276.6142) (xy 83.55304 -276.635298) (xy 83.593543 -276.663254) (xy 83.629036 -276.697346)
			(xy 83.658601 -276.73669) (xy 83.681472 -276.780267) (xy 83.697056 -276.826948) (xy 83.704951 -276.875525)
			(xy 83.705446 -276.900132) (xy 83.704951 -276.924739) (xy 83.697056 -276.973316) (xy 83.681472 -277.019997)
			(xy 83.658601 -277.063574) (xy 83.629036 -277.102918) (xy 83.593543 -277.13701) (xy 83.55304 -277.164966)
			(xy 83.508578 -277.186064) (xy 83.461307 -277.199756) (xy 83.412452 -277.205688) (xy 83.363277 -277.203707)
			(xy 83.315058 -277.193863) (xy 83.269042 -277.176411) (xy 83.226421 -277.151804) (xy 83.1883 -277.120679)
			(xy 83.155665 -277.083842) (xy 83.129362 -277.042246) (xy 83.110071 -276.99697) (xy 83.098294 -276.949186)
			(xy 83.094334 -276.900132) (xy 82.777071 -276.900132) (xy 82.776572 -276.925586) (xy 82.768529 -276.976368)
			(xy 82.752641 -277.025267) (xy 82.729298 -277.071079) (xy 82.699077 -277.112675) (xy 82.662721 -277.149031)
			(xy 82.621125 -277.179252) (xy 82.575313 -277.202595) (xy 82.526414 -277.218483) (xy 82.475632 -277.226526)
			(xy 82.424216 -277.226526) (xy 82.373434 -277.218483) (xy 82.324535 -277.202595) (xy 82.278723 -277.179252)
			(xy 82.237127 -277.149031) (xy 82.200771 -277.112675) (xy 82.17055 -277.071079) (xy 82.147207 -277.025267)
			(xy 82.131319 -276.976368) (xy 82.123276 -276.925586) (xy 81.826612 -276.925586) (xy 81.818569 -276.976368)
			(xy 81.802681 -277.025267) (xy 81.779338 -277.071079) (xy 81.749117 -277.112675) (xy 81.712761 -277.149031)
			(xy 81.671165 -277.179252) (xy 81.625353 -277.202595) (xy 81.576454 -277.218483) (xy 81.525672 -277.226526)
			(xy 81.474256 -277.226526) (xy 81.423474 -277.218483) (xy 81.374575 -277.202595) (xy 81.328763 -277.179252)
			(xy 81.287167 -277.149031) (xy 81.250811 -277.112675) (xy 81.22059 -277.071079) (xy 81.197247 -277.025267)
			(xy 81.181359 -276.976368) (xy 81.173316 -276.925586) (xy 80.854384 -276.925586) (xy 80.846668 -276.973062)
			(xy 80.831084 -277.019743) (xy 80.808213 -277.06332) (xy 80.778648 -277.102664) (xy 80.743155 -277.136756)
			(xy 80.702652 -277.164712) (xy 80.65819 -277.18581) (xy 80.610919 -277.199502) (xy 80.562064 -277.205434)
			(xy 80.512889 -277.203453) (xy 80.46467 -277.193609) (xy 80.418654 -277.176157) (xy 80.376033 -277.15155)
			(xy 80.337912 -277.120425) (xy 80.305277 -277.083588) (xy 80.278974 -277.041992) (xy 80.259683 -276.996716)
			(xy 80.247906 -276.948932) (xy 80.243946 -276.899878) (xy 79.904844 -276.899878) (xy 79.904349 -276.924485)
			(xy 79.896454 -276.973062) (xy 79.88087 -277.019743) (xy 79.857999 -277.06332) (xy 79.828434 -277.102664)
			(xy 79.792941 -277.136756) (xy 79.752438 -277.164712) (xy 79.707976 -277.18581) (xy 79.660705 -277.199502)
			(xy 79.61185 -277.205434) (xy 79.562675 -277.203453) (xy 79.514456 -277.193609) (xy 79.46844 -277.176157)
			(xy 79.425819 -277.15155) (xy 79.387698 -277.120425) (xy 79.355063 -277.083588) (xy 79.32876 -277.041992)
			(xy 79.309469 -276.996716) (xy 79.297692 -276.948932) (xy 79.293732 -276.899878) (xy 78.954884 -276.899878)
			(xy 78.954389 -276.924485) (xy 78.946494 -276.973062) (xy 78.93091 -277.019743) (xy 78.908039 -277.06332)
			(xy 78.878474 -277.102664) (xy 78.842981 -277.136756) (xy 78.802478 -277.164712) (xy 78.758016 -277.18581)
			(xy 78.710745 -277.199502) (xy 78.66189 -277.205434) (xy 78.612715 -277.203453) (xy 78.564496 -277.193609)
			(xy 78.51848 -277.176157) (xy 78.475859 -277.15155) (xy 78.437738 -277.120425) (xy 78.405103 -277.083588)
			(xy 78.3788 -277.041992) (xy 78.359509 -276.996716) (xy 78.347732 -276.948932) (xy 78.343772 -276.899878)
			(xy 78.004924 -276.899878) (xy 78.004429 -276.924485) (xy 77.996534 -276.973062) (xy 77.98095 -277.019743)
			(xy 77.958079 -277.06332) (xy 77.928514 -277.102664) (xy 77.893021 -277.136756) (xy 77.852518 -277.164712)
			(xy 77.808056 -277.18581) (xy 77.760785 -277.199502) (xy 77.71193 -277.205434) (xy 77.662755 -277.203453)
			(xy 77.614536 -277.193609) (xy 77.56852 -277.176157) (xy 77.525899 -277.15155) (xy 77.487778 -277.120425)
			(xy 77.455143 -277.083588) (xy 77.42884 -277.041992) (xy 77.409549 -276.996716) (xy 77.397772 -276.948932)
			(xy 77.393812 -276.899878) (xy 77.054964 -276.899878) (xy 77.054469 -276.924485) (xy 77.046574 -276.973062)
			(xy 77.03099 -277.019743) (xy 77.008119 -277.06332) (xy 76.978554 -277.102664) (xy 76.943061 -277.136756)
			(xy 76.902558 -277.164712) (xy 76.858096 -277.18581) (xy 76.810825 -277.199502) (xy 76.76197 -277.205434)
			(xy 76.712795 -277.203453) (xy 76.664576 -277.193609) (xy 76.61856 -277.176157) (xy 76.575939 -277.15155)
			(xy 76.537818 -277.120425) (xy 76.505183 -277.083588) (xy 76.47888 -277.041992) (xy 76.459589 -276.996716)
			(xy 76.447812 -276.948932) (xy 76.443852 -276.899878) (xy 76.105004 -276.899878) (xy 76.104509 -276.924485)
			(xy 76.096614 -276.973062) (xy 76.08103 -277.019743) (xy 76.058159 -277.06332) (xy 76.028594 -277.102664)
			(xy 75.993101 -277.136756) (xy 75.952598 -277.164712) (xy 75.908136 -277.18581) (xy 75.860865 -277.199502)
			(xy 75.81201 -277.205434) (xy 75.762835 -277.203453) (xy 75.714616 -277.193609) (xy 75.6686 -277.176157)
			(xy 75.625979 -277.15155) (xy 75.587858 -277.120425) (xy 75.555223 -277.083588) (xy 75.52892 -277.041992)
			(xy 75.509629 -276.996716) (xy 75.497852 -276.948932) (xy 75.493892 -276.899878) (xy 75.155044 -276.899878)
			(xy 75.154549 -276.924485) (xy 75.146654 -276.973062) (xy 75.13107 -277.019743) (xy 75.108199 -277.06332)
			(xy 75.078634 -277.102664) (xy 75.043141 -277.136756) (xy 75.002638 -277.164712) (xy 74.958176 -277.18581)
			(xy 74.910905 -277.199502) (xy 74.86205 -277.205434) (xy 74.812875 -277.203453) (xy 74.764656 -277.193609)
			(xy 74.71864 -277.176157) (xy 74.676019 -277.15155) (xy 74.637898 -277.120425) (xy 74.605263 -277.083588)
			(xy 74.57896 -277.041992) (xy 74.559669 -276.996716) (xy 74.547892 -276.948932) (xy 74.543932 -276.899878)
			(xy 74.20483 -276.899878) (xy 74.204335 -276.924485) (xy 74.19644 -276.973062) (xy 74.180856 -277.019743)
			(xy 74.157985 -277.06332) (xy 74.12842 -277.102664) (xy 74.092927 -277.136756) (xy 74.052424 -277.164712)
			(xy 74.007962 -277.18581) (xy 73.960691 -277.199502) (xy 73.911836 -277.205434) (xy 73.862661 -277.203453)
			(xy 73.814442 -277.193609) (xy 73.768426 -277.176157) (xy 73.725805 -277.15155) (xy 73.687684 -277.120425)
			(xy 73.655049 -277.083588) (xy 73.628746 -277.041992) (xy 73.609455 -276.996716) (xy 73.597678 -276.948932)
			(xy 73.593718 -276.899878) (xy 73.255124 -276.899878) (xy 73.254629 -276.924485) (xy 73.246734 -276.973062)
			(xy 73.23115 -277.019743) (xy 73.208279 -277.06332) (xy 73.178714 -277.102664) (xy 73.143221 -277.136756)
			(xy 73.102718 -277.164712) (xy 73.058256 -277.18581) (xy 73.010985 -277.199502) (xy 72.96213 -277.205434)
			(xy 72.912955 -277.203453) (xy 72.864736 -277.193609) (xy 72.81872 -277.176157) (xy 72.776099 -277.15155)
			(xy 72.737978 -277.120425) (xy 72.705343 -277.083588) (xy 72.67904 -277.041992) (xy 72.659749 -276.996716)
			(xy 72.647972 -276.948932) (xy 72.644012 -276.899878) (xy 72.305164 -276.899878) (xy 72.304669 -276.924485)
			(xy 72.296774 -276.973062) (xy 72.28119 -277.019743) (xy 72.258319 -277.06332) (xy 72.228754 -277.102664)
			(xy 72.193261 -277.136756) (xy 72.152758 -277.164712) (xy 72.108296 -277.18581) (xy 72.061025 -277.199502)
			(xy 72.01217 -277.205434) (xy 71.962995 -277.203453) (xy 71.914776 -277.193609) (xy 71.86876 -277.176157)
			(xy 71.826139 -277.15155) (xy 71.788018 -277.120425) (xy 71.755383 -277.083588) (xy 71.72908 -277.041992)
			(xy 71.709789 -276.996716) (xy 71.698012 -276.948932) (xy 71.694052 -276.899878) (xy 71.355204 -276.899878)
			(xy 71.354709 -276.924485) (xy 71.346814 -276.973062) (xy 71.33123 -277.019743) (xy 71.308359 -277.06332)
			(xy 71.278794 -277.102664) (xy 71.243301 -277.136756) (xy 71.202798 -277.164712) (xy 71.158336 -277.18581)
			(xy 71.111065 -277.199502) (xy 71.06221 -277.205434) (xy 71.013035 -277.203453) (xy 70.964816 -277.193609)
			(xy 70.9188 -277.176157) (xy 70.876179 -277.15155) (xy 70.838058 -277.120425) (xy 70.805423 -277.083588)
			(xy 70.77912 -277.041992) (xy 70.759829 -276.996716) (xy 70.748052 -276.948932) (xy 70.744092 -276.899878)
			(xy 70.405244 -276.899878) (xy 70.404749 -276.924485) (xy 70.396854 -276.973062) (xy 70.38127 -277.019743)
			(xy 70.358399 -277.06332) (xy 70.328834 -277.102664) (xy 70.293341 -277.136756) (xy 70.252838 -277.164712)
			(xy 70.208376 -277.18581) (xy 70.161105 -277.199502) (xy 70.11225 -277.205434) (xy 70.063075 -277.203453)
			(xy 70.014856 -277.193609) (xy 69.96884 -277.176157) (xy 69.926219 -277.15155) (xy 69.888098 -277.120425)
			(xy 69.855463 -277.083588) (xy 69.82916 -277.041992) (xy 69.809869 -276.996716) (xy 69.798092 -276.948932)
			(xy 69.794132 -276.899878) (xy 69.455284 -276.899878) (xy 69.454789 -276.924485) (xy 69.446894 -276.973062)
			(xy 69.43131 -277.019743) (xy 69.408439 -277.06332) (xy 69.378874 -277.102664) (xy 69.343381 -277.136756)
			(xy 69.302878 -277.164712) (xy 69.258416 -277.18581) (xy 69.211145 -277.199502) (xy 69.16229 -277.205434)
			(xy 69.113115 -277.203453) (xy 69.064896 -277.193609) (xy 69.01888 -277.176157) (xy 68.976259 -277.15155)
			(xy 68.938138 -277.120425) (xy 68.905503 -277.083588) (xy 68.8792 -277.041992) (xy 68.859909 -276.996716)
			(xy 68.848132 -276.948932) (xy 68.844172 -276.899878) (xy 68.50507 -276.899878) (xy 68.504575 -276.924485)
			(xy 68.49668 -276.973062) (xy 68.481096 -277.019743) (xy 68.458225 -277.06332) (xy 68.42866 -277.102664)
			(xy 68.393167 -277.136756) (xy 68.352664 -277.164712) (xy 68.308202 -277.18581) (xy 68.260931 -277.199502)
			(xy 68.212076 -277.205434) (xy 68.162901 -277.203453) (xy 68.114682 -277.193609) (xy 68.068666 -277.176157)
			(xy 68.026045 -277.15155) (xy 67.987924 -277.120425) (xy 67.955289 -277.083588) (xy 67.928986 -277.041992)
			(xy 67.909695 -276.996716) (xy 67.897918 -276.948932) (xy 67.893958 -276.899878) (xy 67.55511 -276.899878)
			(xy 67.554615 -276.924485) (xy 67.54672 -276.973062) (xy 67.531136 -277.019743) (xy 67.508265 -277.06332)
			(xy 67.4787 -277.102664) (xy 67.443207 -277.136756) (xy 67.402704 -277.164712) (xy 67.358242 -277.18581)
			(xy 67.310971 -277.199502) (xy 67.262116 -277.205434) (xy 67.212941 -277.203453) (xy 67.164722 -277.193609)
			(xy 67.118706 -277.176157) (xy 67.076085 -277.15155) (xy 67.037964 -277.120425) (xy 67.005329 -277.083588)
			(xy 66.979026 -277.041992) (xy 66.959735 -276.996716) (xy 66.947958 -276.948932) (xy 66.943998 -276.899878)
			(xy 66.60515 -276.899878) (xy 66.604655 -276.924485) (xy 66.59676 -276.973062) (xy 66.581176 -277.019743)
			(xy 66.558305 -277.06332) (xy 66.52874 -277.102664) (xy 66.493247 -277.136756) (xy 66.452744 -277.164712)
			(xy 66.408282 -277.18581) (xy 66.361011 -277.199502) (xy 66.312156 -277.205434) (xy 66.262981 -277.203453)
			(xy 66.214762 -277.193609) (xy 66.168746 -277.176157) (xy 66.126125 -277.15155) (xy 66.088004 -277.120425)
			(xy 66.055369 -277.083588) (xy 66.029066 -277.041992) (xy 66.009775 -276.996716) (xy 65.997998 -276.948932)
			(xy 65.994038 -276.899878) (xy 65.65519 -276.899878) (xy 65.654695 -276.924485) (xy 65.6468 -276.973062)
			(xy 65.631216 -277.019743) (xy 65.608345 -277.06332) (xy 65.57878 -277.102664) (xy 65.543287 -277.136756)
			(xy 65.502784 -277.164712) (xy 65.458322 -277.18581) (xy 65.411051 -277.199502) (xy 65.362196 -277.205434)
			(xy 65.313021 -277.203453) (xy 65.264802 -277.193609) (xy 65.218786 -277.176157) (xy 65.176165 -277.15155)
			(xy 65.138044 -277.120425) (xy 65.105409 -277.083588) (xy 65.079106 -277.041992) (xy 65.059815 -276.996716)
			(xy 65.048038 -276.948932) (xy 65.044078 -276.899878) (xy 64.70523 -276.899878) (xy 64.704735 -276.924485)
			(xy 64.69684 -276.973062) (xy 64.681256 -277.019743) (xy 64.658385 -277.06332) (xy 64.62882 -277.102664)
			(xy 64.593327 -277.136756) (xy 64.552824 -277.164712) (xy 64.508362 -277.18581) (xy 64.461091 -277.199502)
			(xy 64.412236 -277.205434) (xy 64.363061 -277.203453) (xy 64.314842 -277.193609) (xy 64.268826 -277.176157)
			(xy 64.226205 -277.15155) (xy 64.188084 -277.120425) (xy 64.155449 -277.083588) (xy 64.129146 -277.041992)
			(xy 64.109855 -276.996716) (xy 64.098078 -276.948932) (xy 64.094118 -276.899878) (xy 63.75527 -276.899878)
			(xy 63.754775 -276.924485) (xy 63.74688 -276.973062) (xy 63.731296 -277.019743) (xy 63.708425 -277.06332)
			(xy 63.67886 -277.102664) (xy 63.643367 -277.136756) (xy 63.602864 -277.164712) (xy 63.558402 -277.18581)
			(xy 63.511131 -277.199502) (xy 63.462276 -277.205434) (xy 63.413101 -277.203453) (xy 63.364882 -277.193609)
			(xy 63.318866 -277.176157) (xy 63.276245 -277.15155) (xy 63.238124 -277.120425) (xy 63.205489 -277.083588)
			(xy 63.179186 -277.041992) (xy 63.159895 -276.996716) (xy 63.148118 -276.948932) (xy 63.144158 -276.899878)
			(xy 62.805056 -276.899878) (xy 62.804561 -276.924485) (xy 62.796666 -276.973062) (xy 62.781082 -277.019743)
			(xy 62.758211 -277.06332) (xy 62.728646 -277.102664) (xy 62.693153 -277.136756) (xy 62.65265 -277.164712)
			(xy 62.608188 -277.18581) (xy 62.560917 -277.199502) (xy 62.512062 -277.205434) (xy 62.462887 -277.203453)
			(xy 62.414668 -277.193609) (xy 62.368652 -277.176157) (xy 62.326031 -277.15155) (xy 62.28791 -277.120425)
			(xy 62.255275 -277.083588) (xy 62.228972 -277.041992) (xy 62.209681 -276.996716) (xy 62.197904 -276.948932)
			(xy 62.193944 -276.899878) (xy 61.855096 -276.899878) (xy 61.854601 -276.924485) (xy 61.846706 -276.973062)
			(xy 61.831122 -277.019743) (xy 61.808251 -277.06332) (xy 61.778686 -277.102664) (xy 61.743193 -277.136756)
			(xy 61.70269 -277.164712) (xy 61.658228 -277.18581) (xy 61.610957 -277.199502) (xy 61.562102 -277.205434)
			(xy 61.512927 -277.203453) (xy 61.464708 -277.193609) (xy 61.418692 -277.176157) (xy 61.376071 -277.15155)
			(xy 61.33795 -277.120425) (xy 61.305315 -277.083588) (xy 61.279012 -277.041992) (xy 61.259721 -276.996716)
			(xy 61.247944 -276.948932) (xy 61.243984 -276.899878) (xy 60.905136 -276.899878) (xy 60.904641 -276.924485)
			(xy 60.896746 -276.973062) (xy 60.881162 -277.019743) (xy 60.858291 -277.06332) (xy 60.828726 -277.102664)
			(xy 60.793233 -277.136756) (xy 60.75273 -277.164712) (xy 60.708268 -277.18581) (xy 60.660997 -277.199502)
			(xy 60.612142 -277.205434) (xy 60.562967 -277.203453) (xy 60.514748 -277.193609) (xy 60.468732 -277.176157)
			(xy 60.426111 -277.15155) (xy 60.38799 -277.120425) (xy 60.355355 -277.083588) (xy 60.329052 -277.041992)
			(xy 60.309761 -276.996716) (xy 60.297984 -276.948932) (xy 60.294024 -276.899878) (xy 59.955176 -276.899878)
			(xy 59.954681 -276.924485) (xy 59.946786 -276.973062) (xy 59.931202 -277.019743) (xy 59.908331 -277.06332)
			(xy 59.878766 -277.102664) (xy 59.843273 -277.136756) (xy 59.80277 -277.164712) (xy 59.758308 -277.18581)
			(xy 59.711037 -277.199502) (xy 59.662182 -277.205434) (xy 59.613007 -277.203453) (xy 59.564788 -277.193609)
			(xy 59.518772 -277.176157) (xy 59.476151 -277.15155) (xy 59.43803 -277.120425) (xy 59.405395 -277.083588)
			(xy 59.379092 -277.041992) (xy 59.359801 -276.996716) (xy 59.348024 -276.948932) (xy 59.344064 -276.899878)
			(xy 59.005216 -276.899878) (xy 59.004721 -276.924485) (xy 58.996826 -276.973062) (xy 58.981242 -277.019743)
			(xy 58.958371 -277.06332) (xy 58.928806 -277.102664) (xy 58.893313 -277.136756) (xy 58.85281 -277.164712)
			(xy 58.808348 -277.18581) (xy 58.761077 -277.199502) (xy 58.712222 -277.205434) (xy 58.663047 -277.203453)
			(xy 58.614828 -277.193609) (xy 58.568812 -277.176157) (xy 58.526191 -277.15155) (xy 58.48807 -277.120425)
			(xy 58.455435 -277.083588) (xy 58.429132 -277.041992) (xy 58.409841 -276.996716) (xy 58.398064 -276.948932)
			(xy 58.394104 -276.899878) (xy 58.055256 -276.899878) (xy 58.054761 -276.924485) (xy 58.046866 -276.973062)
			(xy 58.031282 -277.019743) (xy 58.008411 -277.06332) (xy 57.978846 -277.102664) (xy 57.943353 -277.136756)
			(xy 57.90285 -277.164712) (xy 57.858388 -277.18581) (xy 57.811117 -277.199502) (xy 57.762262 -277.205434)
			(xy 57.713087 -277.203453) (xy 57.664868 -277.193609) (xy 57.618852 -277.176157) (xy 57.576231 -277.15155)
			(xy 57.53811 -277.120425) (xy 57.505475 -277.083588) (xy 57.479172 -277.041992) (xy 57.459881 -276.996716)
			(xy 57.448104 -276.948932) (xy 57.444144 -276.899878) (xy 57.105296 -276.899878) (xy 57.104801 -276.924485)
			(xy 57.096906 -276.973062) (xy 57.081322 -277.019743) (xy 57.058451 -277.06332) (xy 57.028886 -277.102664)
			(xy 56.993393 -277.136756) (xy 56.95289 -277.164712) (xy 56.908428 -277.18581) (xy 56.861157 -277.199502)
			(xy 56.812302 -277.205434) (xy 56.763127 -277.203453) (xy 56.714908 -277.193609) (xy 56.668892 -277.176157)
			(xy 56.626271 -277.15155) (xy 56.58815 -277.120425) (xy 56.555515 -277.083588) (xy 56.529212 -277.041992)
			(xy 56.509921 -276.996716) (xy 56.498144 -276.948932) (xy 56.494184 -276.899878) (xy 56.155082 -276.899878)
			(xy 56.154587 -276.924485) (xy 56.146692 -276.973062) (xy 56.131108 -277.019743) (xy 56.108237 -277.06332)
			(xy 56.078672 -277.102664) (xy 56.043179 -277.136756) (xy 56.002676 -277.164712) (xy 55.958214 -277.18581)
			(xy 55.910943 -277.199502) (xy 55.862088 -277.205434) (xy 55.812913 -277.203453) (xy 55.764694 -277.193609)
			(xy 55.718678 -277.176157) (xy 55.676057 -277.15155) (xy 55.637936 -277.120425) (xy 55.605301 -277.083588)
			(xy 55.578998 -277.041992) (xy 55.559707 -276.996716) (xy 55.54793 -276.948932) (xy 55.54397 -276.899878)
			(xy 55.205122 -276.899878) (xy 55.204627 -276.924485) (xy 55.196732 -276.973062) (xy 55.181148 -277.019743)
			(xy 55.158277 -277.06332) (xy 55.128712 -277.102664) (xy 55.093219 -277.136756) (xy 55.052716 -277.164712)
			(xy 55.008254 -277.18581) (xy 54.960983 -277.199502) (xy 54.912128 -277.205434) (xy 54.862953 -277.203453)
			(xy 54.814734 -277.193609) (xy 54.768718 -277.176157) (xy 54.726097 -277.15155) (xy 54.687976 -277.120425)
			(xy 54.655341 -277.083588) (xy 54.629038 -277.041992) (xy 54.609747 -276.996716) (xy 54.59797 -276.948932)
			(xy 54.59401 -276.899878) (xy 54.255162 -276.899878) (xy 54.254667 -276.924485) (xy 54.246772 -276.973062)
			(xy 54.231188 -277.019743) (xy 54.208317 -277.06332) (xy 54.178752 -277.102664) (xy 54.143259 -277.136756)
			(xy 54.102756 -277.164712) (xy 54.058294 -277.18581) (xy 54.011023 -277.199502) (xy 53.962168 -277.205434)
			(xy 53.912993 -277.203453) (xy 53.864774 -277.193609) (xy 53.818758 -277.176157) (xy 53.776137 -277.15155)
			(xy 53.738016 -277.120425) (xy 53.705381 -277.083588) (xy 53.679078 -277.041992) (xy 53.659787 -276.996716)
			(xy 53.64801 -276.948932) (xy 53.64405 -276.899878) (xy 53.305202 -276.899878) (xy 53.304707 -276.924485)
			(xy 53.296812 -276.973062) (xy 53.281228 -277.019743) (xy 53.258357 -277.06332) (xy 53.228792 -277.102664)
			(xy 53.193299 -277.136756) (xy 53.152796 -277.164712) (xy 53.108334 -277.18581) (xy 53.061063 -277.199502)
			(xy 53.012208 -277.205434) (xy 52.963033 -277.203453) (xy 52.914814 -277.193609) (xy 52.868798 -277.176157)
			(xy 52.826177 -277.15155) (xy 52.788056 -277.120425) (xy 52.755421 -277.083588) (xy 52.729118 -277.041992)
			(xy 52.709827 -276.996716) (xy 52.69805 -276.948932) (xy 52.69409 -276.899878) (xy 52.355242 -276.899878)
			(xy 52.354747 -276.924485) (xy 52.346852 -276.973062) (xy 52.331268 -277.019743) (xy 52.308397 -277.06332)
			(xy 52.278832 -277.102664) (xy 52.243339 -277.136756) (xy 52.202836 -277.164712) (xy 52.158374 -277.18581)
			(xy 52.111103 -277.199502) (xy 52.062248 -277.205434) (xy 52.013073 -277.203453) (xy 51.964854 -277.193609)
			(xy 51.918838 -277.176157) (xy 51.876217 -277.15155) (xy 51.838096 -277.120425) (xy 51.805461 -277.083588)
			(xy 51.779158 -277.041992) (xy 51.759867 -276.996716) (xy 51.74809 -276.948932) (xy 51.74413 -276.899878)
			(xy 51.405282 -276.899878) (xy 51.404787 -276.924485) (xy 51.396892 -276.973062) (xy 51.381308 -277.019743)
			(xy 51.358437 -277.06332) (xy 51.328872 -277.102664) (xy 51.293379 -277.136756) (xy 51.252876 -277.164712)
			(xy 51.208414 -277.18581) (xy 51.161143 -277.199502) (xy 51.112288 -277.205434) (xy 51.063113 -277.203453)
			(xy 51.014894 -277.193609) (xy 50.968878 -277.176157) (xy 50.926257 -277.15155) (xy 50.888136 -277.120425)
			(xy 50.855501 -277.083588) (xy 50.829198 -277.041992) (xy 50.809907 -276.996716) (xy 50.79813 -276.948932)
			(xy 50.79417 -276.899878) (xy 50.455068 -276.899878) (xy 50.454573 -276.924485) (xy 50.446678 -276.973062)
			(xy 50.431094 -277.019743) (xy 50.408223 -277.06332) (xy 50.378658 -277.102664) (xy 50.343165 -277.136756)
			(xy 50.302662 -277.164712) (xy 50.2582 -277.18581) (xy 50.210929 -277.199502) (xy 50.162074 -277.205434)
			(xy 50.112899 -277.203453) (xy 50.06468 -277.193609) (xy 50.018664 -277.176157) (xy 49.976043 -277.15155)
			(xy 49.937922 -277.120425) (xy 49.905287 -277.083588) (xy 49.878984 -277.041992) (xy 49.859693 -276.996716)
			(xy 49.847916 -276.948932) (xy 49.843956 -276.899878) (xy 49.505108 -276.899878) (xy 49.504613 -276.924485)
			(xy 49.496718 -276.973062) (xy 49.481134 -277.019743) (xy 49.458263 -277.06332) (xy 49.428698 -277.102664)
			(xy 49.393205 -277.136756) (xy 49.352702 -277.164712) (xy 49.30824 -277.18581) (xy 49.260969 -277.199502)
			(xy 49.212114 -277.205434) (xy 49.162939 -277.203453) (xy 49.11472 -277.193609) (xy 49.068704 -277.176157)
			(xy 49.026083 -277.15155) (xy 48.987962 -277.120425) (xy 48.955327 -277.083588) (xy 48.929024 -277.041992)
			(xy 48.909733 -276.996716) (xy 48.897956 -276.948932) (xy 48.893996 -276.899878) (xy 48.555148 -276.899878)
			(xy 48.554653 -276.924485) (xy 48.546758 -276.973062) (xy 48.531174 -277.019743) (xy 48.508303 -277.06332)
			(xy 48.478738 -277.102664) (xy 48.443245 -277.136756) (xy 48.402742 -277.164712) (xy 48.35828 -277.18581)
			(xy 48.311009 -277.199502) (xy 48.262154 -277.205434) (xy 48.212979 -277.203453) (xy 48.16476 -277.193609)
			(xy 48.118744 -277.176157) (xy 48.076123 -277.15155) (xy 48.038002 -277.120425) (xy 48.005367 -277.083588)
			(xy 47.979064 -277.041992) (xy 47.959773 -276.996716) (xy 47.947996 -276.948932) (xy 47.944036 -276.899878)
			(xy 47.605188 -276.899878) (xy 47.604693 -276.924485) (xy 47.596798 -276.973062) (xy 47.581214 -277.019743)
			(xy 47.558343 -277.06332) (xy 47.528778 -277.102664) (xy 47.493285 -277.136756) (xy 47.452782 -277.164712)
			(xy 47.40832 -277.18581) (xy 47.361049 -277.199502) (xy 47.312194 -277.205434) (xy 47.263019 -277.203453)
			(xy 47.2148 -277.193609) (xy 47.168784 -277.176157) (xy 47.126163 -277.15155) (xy 47.088042 -277.120425)
			(xy 47.055407 -277.083588) (xy 47.029104 -277.041992) (xy 47.009813 -276.996716) (xy 46.998036 -276.948932)
			(xy 46.994076 -276.899878) (xy 46.655228 -276.899878) (xy 46.654733 -276.924485) (xy 46.646838 -276.973062)
			(xy 46.631254 -277.019743) (xy 46.608383 -277.06332) (xy 46.578818 -277.102664) (xy 46.543325 -277.136756)
			(xy 46.502822 -277.164712) (xy 46.45836 -277.18581) (xy 46.411089 -277.199502) (xy 46.362234 -277.205434)
			(xy 46.313059 -277.203453) (xy 46.26484 -277.193609) (xy 46.218824 -277.176157) (xy 46.176203 -277.15155)
			(xy 46.138082 -277.120425) (xy 46.105447 -277.083588) (xy 46.079144 -277.041992) (xy 46.059853 -276.996716)
			(xy 46.048076 -276.948932) (xy 46.044116 -276.899878) (xy 45.705268 -276.899878) (xy 45.704773 -276.924485)
			(xy 45.696878 -276.973062) (xy 45.681294 -277.019743) (xy 45.658423 -277.06332) (xy 45.628858 -277.102664)
			(xy 45.593365 -277.136756) (xy 45.552862 -277.164712) (xy 45.5084 -277.18581) (xy 45.461129 -277.199502)
			(xy 45.412274 -277.205434) (xy 45.363099 -277.203453) (xy 45.31488 -277.193609) (xy 45.268864 -277.176157)
			(xy 45.226243 -277.15155) (xy 45.188122 -277.120425) (xy 45.155487 -277.083588) (xy 45.129184 -277.041992)
			(xy 45.109893 -276.996716) (xy 45.098116 -276.948932) (xy 45.094156 -276.899878) (xy 44.755054 -276.899878)
			(xy 44.754559 -276.924485) (xy 44.746664 -276.973062) (xy 44.73108 -277.019743) (xy 44.708209 -277.06332)
			(xy 44.678644 -277.102664) (xy 44.643151 -277.136756) (xy 44.602648 -277.164712) (xy 44.558186 -277.18581)
			(xy 44.510915 -277.199502) (xy 44.46206 -277.205434) (xy 44.412885 -277.203453) (xy 44.364666 -277.193609)
			(xy 44.31865 -277.176157) (xy 44.276029 -277.15155) (xy 44.237908 -277.120425) (xy 44.205273 -277.083588)
			(xy 44.17897 -277.041992) (xy 44.159679 -276.996716) (xy 44.147902 -276.948932) (xy 44.143942 -276.899878)
			(xy 43.805094 -276.899878) (xy 43.804599 -276.924485) (xy 43.796704 -276.973062) (xy 43.78112 -277.019743)
			(xy 43.758249 -277.06332) (xy 43.728684 -277.102664) (xy 43.693191 -277.136756) (xy 43.652688 -277.164712)
			(xy 43.608226 -277.18581) (xy 43.560955 -277.199502) (xy 43.5121 -277.205434) (xy 43.462925 -277.203453)
			(xy 43.414706 -277.193609) (xy 43.36869 -277.176157) (xy 43.326069 -277.15155) (xy 43.287948 -277.120425)
			(xy 43.255313 -277.083588) (xy 43.22901 -277.041992) (xy 43.209719 -276.996716) (xy 43.197942 -276.948932)
			(xy 43.193982 -276.899878) (xy 40.899334 -276.899878) (xy 40.899334 -276.987254) (xy 40.900011 -276.999275)
			(xy 40.910887 -277.020721) (xy 40.920162 -277.028402) (xy 40.996362 -277.084028) (xy 41.020238 -277.087838)
			(xy 41.031922 -277.084028) (xy 41.054563 -277.077254) (xy 41.101257 -277.069983) (xy 41.124886 -277.06955)
			(xy 41.150148 -277.070042) (xy 41.199983 -277.078356) (xy 41.24777 -277.094759) (xy 41.292205 -277.118804)
			(xy 41.332076 -277.149836) (xy 41.366296 -277.187006) (xy 41.393931 -277.229303) (xy 41.414226 -277.275571)
			(xy 41.42663 -277.324549) (xy 41.430799 -277.374858) (xy 41.769042 -277.374858) (xy 41.773002 -277.325804)
			(xy 41.784779 -277.27802) (xy 41.80407 -277.232744) (xy 41.830373 -277.191148) (xy 41.863008 -277.154311)
			(xy 41.901129 -277.123186) (xy 41.94375 -277.098579) (xy 41.989766 -277.081127) (xy 42.037985 -277.071283)
			(xy 42.08716 -277.069302) (xy 42.136015 -277.075234) (xy 42.183286 -277.088926) (xy 42.227748 -277.110024)
			(xy 42.268251 -277.13798) (xy 42.303744 -277.172072) (xy 42.333309 -277.211416) (xy 42.35618 -277.254993)
			(xy 42.371764 -277.301674) (xy 42.379659 -277.350251) (xy 42.380154 -277.374858) (xy 42.379659 -277.399465)
			(xy 42.371764 -277.448042) (xy 42.35618 -277.494723) (xy 42.333309 -277.5383) (xy 42.303744 -277.577644)
			(xy 42.268251 -277.611736) (xy 42.227748 -277.639692) (xy 42.183286 -277.66079) (xy 42.136015 -277.674482)
			(xy 42.08716 -277.680414) (xy 42.037985 -277.678433) (xy 41.989766 -277.668589) (xy 41.94375 -277.651137)
			(xy 41.901129 -277.62653) (xy 41.863008 -277.595405) (xy 41.830373 -277.558568) (xy 41.80407 -277.516972)
			(xy 41.784779 -277.471696) (xy 41.773002 -277.423912) (xy 41.769042 -277.374858) (xy 41.430799 -277.374858)
			(xy 41.430802 -277.3749) (xy 41.42663 -277.425251) (xy 41.414226 -277.474229) (xy 41.393931 -277.520497)
			(xy 41.366296 -277.562794) (xy 41.332076 -277.599964) (xy 41.292205 -277.630996) (xy 41.24777 -277.655041)
			(xy 41.199983 -277.671444) (xy 41.150148 -277.679758) (xy 41.124886 -277.680166) (xy 41.101259 -277.679718)
			(xy 41.054569 -277.672438) (xy 41.031922 -277.665688) (xy 41.020238 -277.661878) (xy 40.996362 -277.665688)
			(xy 40.920162 -277.721314) (xy 40.910827 -277.728939) (xy 40.899978 -277.750423) (xy 40.899334 -277.762462)
			(xy 40.899334 -277.849838) (xy 43.193982 -277.849838) (xy 43.197942 -277.800784) (xy 43.209719 -277.753)
			(xy 43.22901 -277.707724) (xy 43.255313 -277.666128) (xy 43.287948 -277.629291) (xy 43.326069 -277.598166)
			(xy 43.36869 -277.573559) (xy 43.414706 -277.556107) (xy 43.462925 -277.546263) (xy 43.5121 -277.544282)
			(xy 43.560955 -277.550214) (xy 43.608226 -277.563906) (xy 43.652688 -277.585004) (xy 43.693191 -277.61296)
			(xy 43.728684 -277.647052) (xy 43.758249 -277.686396) (xy 43.78112 -277.729973) (xy 43.796704 -277.776654)
			(xy 43.804599 -277.825231) (xy 43.805094 -277.849838) (xy 43.804599 -277.874445) (xy 43.80442 -277.875546)
			(xy 44.123098 -277.875546) (xy 44.123098 -277.82413) (xy 44.131141 -277.773348) (xy 44.147029 -277.724449)
			(xy 44.170372 -277.678637) (xy 44.200593 -277.637041) (xy 44.236949 -277.600685) (xy 44.278545 -277.570464)
			(xy 44.324357 -277.547121) (xy 44.373256 -277.531233) (xy 44.424038 -277.52319) (xy 44.475454 -277.52319)
			(xy 44.526236 -277.531233) (xy 44.575135 -277.547121) (xy 44.620947 -277.570464) (xy 44.662543 -277.600685)
			(xy 44.698899 -277.637041) (xy 44.72912 -277.678637) (xy 44.752463 -277.724449) (xy 44.768351 -277.773348)
			(xy 44.776394 -277.82413) (xy 44.776898 -277.849838) (xy 45.094156 -277.849838) (xy 45.098116 -277.800784)
			(xy 45.109893 -277.753) (xy 45.129184 -277.707724) (xy 45.155487 -277.666128) (xy 45.188122 -277.629291)
			(xy 45.226243 -277.598166) (xy 45.268864 -277.573559) (xy 45.31488 -277.556107) (xy 45.363099 -277.546263)
			(xy 45.412274 -277.544282) (xy 45.461129 -277.550214) (xy 45.5084 -277.563906) (xy 45.552862 -277.585004)
			(xy 45.593365 -277.61296) (xy 45.628858 -277.647052) (xy 45.658423 -277.686396) (xy 45.681294 -277.729973)
			(xy 45.696878 -277.776654) (xy 45.704773 -277.825231) (xy 45.705268 -277.849838) (xy 45.704773 -277.874445)
			(xy 45.704594 -277.875546) (xy 46.023272 -277.875546) (xy 46.023272 -277.82413) (xy 46.031315 -277.773348)
			(xy 46.047203 -277.724449) (xy 46.070546 -277.678637) (xy 46.100767 -277.637041) (xy 46.137123 -277.600685)
			(xy 46.178719 -277.570464) (xy 46.224531 -277.547121) (xy 46.27343 -277.531233) (xy 46.324212 -277.52319)
			(xy 46.375628 -277.52319) (xy 46.42641 -277.531233) (xy 46.475309 -277.547121) (xy 46.521121 -277.570464)
			(xy 46.562717 -277.600685) (xy 46.599073 -277.637041) (xy 46.629294 -277.678637) (xy 46.652637 -277.724449)
			(xy 46.668525 -277.773348) (xy 46.676568 -277.82413) (xy 46.677072 -277.849838) (xy 46.994076 -277.849838)
			(xy 46.998036 -277.800784) (xy 47.009813 -277.753) (xy 47.029104 -277.707724) (xy 47.055407 -277.666128)
			(xy 47.088042 -277.629291) (xy 47.126163 -277.598166) (xy 47.168784 -277.573559) (xy 47.2148 -277.556107)
			(xy 47.263019 -277.546263) (xy 47.312194 -277.544282) (xy 47.361049 -277.550214) (xy 47.40832 -277.563906)
			(xy 47.452782 -277.585004) (xy 47.493285 -277.61296) (xy 47.528778 -277.647052) (xy 47.558343 -277.686396)
			(xy 47.581214 -277.729973) (xy 47.596798 -277.776654) (xy 47.604693 -277.825231) (xy 47.605188 -277.849838)
			(xy 47.604693 -277.874445) (xy 47.604514 -277.875546) (xy 47.923192 -277.875546) (xy 47.923192 -277.82413)
			(xy 47.931235 -277.773348) (xy 47.947123 -277.724449) (xy 47.970466 -277.678637) (xy 48.000687 -277.637041)
			(xy 48.037043 -277.600685) (xy 48.078639 -277.570464) (xy 48.124451 -277.547121) (xy 48.17335 -277.531233)
			(xy 48.224132 -277.52319) (xy 48.275548 -277.52319) (xy 48.32633 -277.531233) (xy 48.375229 -277.547121)
			(xy 48.421041 -277.570464) (xy 48.462637 -277.600685) (xy 48.498993 -277.637041) (xy 48.529214 -277.678637)
			(xy 48.552557 -277.724449) (xy 48.568445 -277.773348) (xy 48.576488 -277.82413) (xy 48.576992 -277.849838)
			(xy 48.893996 -277.849838) (xy 48.897956 -277.800784) (xy 48.909733 -277.753) (xy 48.929024 -277.707724)
			(xy 48.955327 -277.666128) (xy 48.987962 -277.629291) (xy 49.026083 -277.598166) (xy 49.068704 -277.573559)
			(xy 49.11472 -277.556107) (xy 49.162939 -277.546263) (xy 49.212114 -277.544282) (xy 49.260969 -277.550214)
			(xy 49.30824 -277.563906) (xy 49.352702 -277.585004) (xy 49.393205 -277.61296) (xy 49.428698 -277.647052)
			(xy 49.458263 -277.686396) (xy 49.481134 -277.729973) (xy 49.496718 -277.776654) (xy 49.504613 -277.825231)
			(xy 49.505108 -277.849838) (xy 49.504613 -277.874445) (xy 49.504434 -277.875546) (xy 49.823112 -277.875546)
			(xy 49.823112 -277.82413) (xy 49.831155 -277.773348) (xy 49.847043 -277.724449) (xy 49.870386 -277.678637)
			(xy 49.900607 -277.637041) (xy 49.936963 -277.600685) (xy 49.978559 -277.570464) (xy 50.024371 -277.547121)
			(xy 50.07327 -277.531233) (xy 50.124052 -277.52319) (xy 50.175468 -277.52319) (xy 50.22625 -277.531233)
			(xy 50.275149 -277.547121) (xy 50.320961 -277.570464) (xy 50.362557 -277.600685) (xy 50.398913 -277.637041)
			(xy 50.429134 -277.678637) (xy 50.452477 -277.724449) (xy 50.468365 -277.773348) (xy 50.476408 -277.82413)
			(xy 50.476912 -277.849838) (xy 50.79417 -277.849838) (xy 50.79813 -277.800784) (xy 50.809907 -277.753)
			(xy 50.829198 -277.707724) (xy 50.855501 -277.666128) (xy 50.888136 -277.629291) (xy 50.926257 -277.598166)
			(xy 50.968878 -277.573559) (xy 51.014894 -277.556107) (xy 51.063113 -277.546263) (xy 51.112288 -277.544282)
			(xy 51.161143 -277.550214) (xy 51.208414 -277.563906) (xy 51.252876 -277.585004) (xy 51.293379 -277.61296)
			(xy 51.328872 -277.647052) (xy 51.358437 -277.686396) (xy 51.381308 -277.729973) (xy 51.396892 -277.776654)
			(xy 51.404787 -277.825231) (xy 51.405282 -277.849838) (xy 51.404787 -277.874445) (xy 51.404608 -277.875546)
			(xy 51.723286 -277.875546) (xy 51.723286 -277.82413) (xy 51.731329 -277.773348) (xy 51.747217 -277.724449)
			(xy 51.77056 -277.678637) (xy 51.800781 -277.637041) (xy 51.837137 -277.600685) (xy 51.878733 -277.570464)
			(xy 51.924545 -277.547121) (xy 51.973444 -277.531233) (xy 52.024226 -277.52319) (xy 52.075642 -277.52319)
			(xy 52.126424 -277.531233) (xy 52.175323 -277.547121) (xy 52.221135 -277.570464) (xy 52.262731 -277.600685)
			(xy 52.299087 -277.637041) (xy 52.329308 -277.678637) (xy 52.352651 -277.724449) (xy 52.368539 -277.773348)
			(xy 52.376582 -277.82413) (xy 52.377086 -277.849838) (xy 52.69409 -277.849838) (xy 52.69805 -277.800784)
			(xy 52.709827 -277.753) (xy 52.729118 -277.707724) (xy 52.755421 -277.666128) (xy 52.788056 -277.629291)
			(xy 52.826177 -277.598166) (xy 52.868798 -277.573559) (xy 52.914814 -277.556107) (xy 52.963033 -277.546263)
			(xy 53.012208 -277.544282) (xy 53.061063 -277.550214) (xy 53.108334 -277.563906) (xy 53.152796 -277.585004)
			(xy 53.193299 -277.61296) (xy 53.228792 -277.647052) (xy 53.258357 -277.686396) (xy 53.281228 -277.729973)
			(xy 53.296812 -277.776654) (xy 53.304707 -277.825231) (xy 53.305202 -277.849838) (xy 53.304707 -277.874445)
			(xy 53.304528 -277.875546) (xy 53.623206 -277.875546) (xy 53.623206 -277.82413) (xy 53.631249 -277.773348)
			(xy 53.647137 -277.724449) (xy 53.67048 -277.678637) (xy 53.700701 -277.637041) (xy 53.737057 -277.600685)
			(xy 53.778653 -277.570464) (xy 53.824465 -277.547121) (xy 53.873364 -277.531233) (xy 53.924146 -277.52319)
			(xy 53.975562 -277.52319) (xy 54.026344 -277.531233) (xy 54.075243 -277.547121) (xy 54.121055 -277.570464)
			(xy 54.162651 -277.600685) (xy 54.199007 -277.637041) (xy 54.229228 -277.678637) (xy 54.252571 -277.724449)
			(xy 54.268459 -277.773348) (xy 54.276502 -277.82413) (xy 54.277006 -277.849838) (xy 54.59401 -277.849838)
			(xy 54.59797 -277.800784) (xy 54.609747 -277.753) (xy 54.629038 -277.707724) (xy 54.655341 -277.666128)
			(xy 54.687976 -277.629291) (xy 54.726097 -277.598166) (xy 54.768718 -277.573559) (xy 54.814734 -277.556107)
			(xy 54.862953 -277.546263) (xy 54.912128 -277.544282) (xy 54.960983 -277.550214) (xy 55.008254 -277.563906)
			(xy 55.052716 -277.585004) (xy 55.093219 -277.61296) (xy 55.128712 -277.647052) (xy 55.158277 -277.686396)
			(xy 55.181148 -277.729973) (xy 55.196732 -277.776654) (xy 55.204627 -277.825231) (xy 55.205122 -277.849838)
			(xy 55.204627 -277.874445) (xy 55.204448 -277.875546) (xy 55.523126 -277.875546) (xy 55.523126 -277.82413)
			(xy 55.531169 -277.773348) (xy 55.547057 -277.724449) (xy 55.5704 -277.678637) (xy 55.600621 -277.637041)
			(xy 55.636977 -277.600685) (xy 55.678573 -277.570464) (xy 55.724385 -277.547121) (xy 55.773284 -277.531233)
			(xy 55.824066 -277.52319) (xy 55.875482 -277.52319) (xy 55.926264 -277.531233) (xy 55.975163 -277.547121)
			(xy 56.020975 -277.570464) (xy 56.062571 -277.600685) (xy 56.098927 -277.637041) (xy 56.129148 -277.678637)
			(xy 56.152491 -277.724449) (xy 56.168379 -277.773348) (xy 56.176422 -277.82413) (xy 56.176926 -277.849838)
			(xy 56.494184 -277.849838) (xy 56.498144 -277.800784) (xy 56.509921 -277.753) (xy 56.529212 -277.707724)
			(xy 56.555515 -277.666128) (xy 56.58815 -277.629291) (xy 56.626271 -277.598166) (xy 56.668892 -277.573559)
			(xy 56.714908 -277.556107) (xy 56.763127 -277.546263) (xy 56.812302 -277.544282) (xy 56.861157 -277.550214)
			(xy 56.908428 -277.563906) (xy 56.95289 -277.585004) (xy 56.993393 -277.61296) (xy 57.028886 -277.647052)
			(xy 57.058451 -277.686396) (xy 57.081322 -277.729973) (xy 57.096906 -277.776654) (xy 57.104801 -277.825231)
			(xy 57.105296 -277.849838) (xy 57.104801 -277.874445) (xy 57.104622 -277.875546) (xy 57.4233 -277.875546)
			(xy 57.4233 -277.82413) (xy 57.431343 -277.773348) (xy 57.447231 -277.724449) (xy 57.470574 -277.678637)
			(xy 57.500795 -277.637041) (xy 57.537151 -277.600685) (xy 57.578747 -277.570464) (xy 57.624559 -277.547121)
			(xy 57.673458 -277.531233) (xy 57.72424 -277.52319) (xy 57.775656 -277.52319) (xy 57.826438 -277.531233)
			(xy 57.875337 -277.547121) (xy 57.921149 -277.570464) (xy 57.962745 -277.600685) (xy 57.999101 -277.637041)
			(xy 58.029322 -277.678637) (xy 58.052665 -277.724449) (xy 58.068553 -277.773348) (xy 58.076596 -277.82413)
			(xy 58.0771 -277.849838) (xy 58.394104 -277.849838) (xy 58.398064 -277.800784) (xy 58.409841 -277.753)
			(xy 58.429132 -277.707724) (xy 58.455435 -277.666128) (xy 58.48807 -277.629291) (xy 58.526191 -277.598166)
			(xy 58.568812 -277.573559) (xy 58.614828 -277.556107) (xy 58.663047 -277.546263) (xy 58.712222 -277.544282)
			(xy 58.761077 -277.550214) (xy 58.808348 -277.563906) (xy 58.85281 -277.585004) (xy 58.893313 -277.61296)
			(xy 58.928806 -277.647052) (xy 58.958371 -277.686396) (xy 58.981242 -277.729973) (xy 58.996826 -277.776654)
			(xy 59.004721 -277.825231) (xy 59.005216 -277.849838) (xy 59.004721 -277.874445) (xy 59.004542 -277.875546)
			(xy 59.322966 -277.875546) (xy 59.322966 -277.82413) (xy 59.331009 -277.773348) (xy 59.346897 -277.724449)
			(xy 59.37024 -277.678637) (xy 59.400461 -277.637041) (xy 59.436817 -277.600685) (xy 59.478413 -277.570464)
			(xy 59.524225 -277.547121) (xy 59.573124 -277.531233) (xy 59.623906 -277.52319) (xy 59.675322 -277.52319)
			(xy 59.726104 -277.531233) (xy 59.775003 -277.547121) (xy 59.820815 -277.570464) (xy 59.862411 -277.600685)
			(xy 59.898767 -277.637041) (xy 59.928988 -277.678637) (xy 59.952331 -277.724449) (xy 59.968219 -277.773348)
			(xy 59.976262 -277.82413) (xy 59.976766 -277.849838) (xy 60.294024 -277.849838) (xy 60.297984 -277.800784)
			(xy 60.309761 -277.753) (xy 60.329052 -277.707724) (xy 60.355355 -277.666128) (xy 60.38799 -277.629291)
			(xy 60.426111 -277.598166) (xy 60.468732 -277.573559) (xy 60.514748 -277.556107) (xy 60.562967 -277.546263)
			(xy 60.612142 -277.544282) (xy 60.660997 -277.550214) (xy 60.708268 -277.563906) (xy 60.75273 -277.585004)
			(xy 60.793233 -277.61296) (xy 60.828726 -277.647052) (xy 60.858291 -277.686396) (xy 60.881162 -277.729973)
			(xy 60.896746 -277.776654) (xy 60.904641 -277.825231) (xy 60.905136 -277.849838) (xy 60.904641 -277.874445)
			(xy 60.904462 -277.875546) (xy 61.222886 -277.875546) (xy 61.222886 -277.82413) (xy 61.230929 -277.773348)
			(xy 61.246817 -277.724449) (xy 61.27016 -277.678637) (xy 61.300381 -277.637041) (xy 61.336737 -277.600685)
			(xy 61.378333 -277.570464) (xy 61.424145 -277.547121) (xy 61.473044 -277.531233) (xy 61.523826 -277.52319)
			(xy 61.575242 -277.52319) (xy 61.626024 -277.531233) (xy 61.674923 -277.547121) (xy 61.720735 -277.570464)
			(xy 61.762331 -277.600685) (xy 61.798687 -277.637041) (xy 61.828908 -277.678637) (xy 61.852251 -277.724449)
			(xy 61.868139 -277.773348) (xy 61.876182 -277.82413) (xy 61.876686 -277.849838) (xy 62.193944 -277.849838)
			(xy 62.197904 -277.800784) (xy 62.209681 -277.753) (xy 62.228972 -277.707724) (xy 62.255275 -277.666128)
			(xy 62.28791 -277.629291) (xy 62.326031 -277.598166) (xy 62.368652 -277.573559) (xy 62.414668 -277.556107)
			(xy 62.462887 -277.546263) (xy 62.512062 -277.544282) (xy 62.560917 -277.550214) (xy 62.608188 -277.563906)
			(xy 62.65265 -277.585004) (xy 62.693153 -277.61296) (xy 62.728646 -277.647052) (xy 62.758211 -277.686396)
			(xy 62.781082 -277.729973) (xy 62.796666 -277.776654) (xy 62.804561 -277.825231) (xy 62.805056 -277.849838)
			(xy 62.804561 -277.874445) (xy 62.804382 -277.875546) (xy 63.12306 -277.875546) (xy 63.12306 -277.82413)
			(xy 63.131103 -277.773348) (xy 63.146991 -277.724449) (xy 63.170334 -277.678637) (xy 63.200555 -277.637041)
			(xy 63.236911 -277.600685) (xy 63.278507 -277.570464) (xy 63.324319 -277.547121) (xy 63.373218 -277.531233)
			(xy 63.424 -277.52319) (xy 63.475416 -277.52319) (xy 63.526198 -277.531233) (xy 63.575097 -277.547121)
			(xy 63.620909 -277.570464) (xy 63.662505 -277.600685) (xy 63.698861 -277.637041) (xy 63.729082 -277.678637)
			(xy 63.752425 -277.724449) (xy 63.768313 -277.773348) (xy 63.776356 -277.82413) (xy 63.77686 -277.849838)
			(xy 64.094118 -277.849838) (xy 64.098078 -277.800784) (xy 64.109855 -277.753) (xy 64.129146 -277.707724)
			(xy 64.155449 -277.666128) (xy 64.188084 -277.629291) (xy 64.226205 -277.598166) (xy 64.268826 -277.573559)
			(xy 64.314842 -277.556107) (xy 64.363061 -277.546263) (xy 64.412236 -277.544282) (xy 64.461091 -277.550214)
			(xy 64.508362 -277.563906) (xy 64.552824 -277.585004) (xy 64.593327 -277.61296) (xy 64.62882 -277.647052)
			(xy 64.658385 -277.686396) (xy 64.681256 -277.729973) (xy 64.69684 -277.776654) (xy 64.704735 -277.825231)
			(xy 64.70523 -277.849838) (xy 64.704735 -277.874445) (xy 64.704556 -277.875546) (xy 65.02298 -277.875546)
			(xy 65.02298 -277.82413) (xy 65.031023 -277.773348) (xy 65.046911 -277.724449) (xy 65.070254 -277.678637)
			(xy 65.100475 -277.637041) (xy 65.136831 -277.600685) (xy 65.178427 -277.570464) (xy 65.224239 -277.547121)
			(xy 65.273138 -277.531233) (xy 65.32392 -277.52319) (xy 65.375336 -277.52319) (xy 65.426118 -277.531233)
			(xy 65.475017 -277.547121) (xy 65.520829 -277.570464) (xy 65.562425 -277.600685) (xy 65.598781 -277.637041)
			(xy 65.629002 -277.678637) (xy 65.652345 -277.724449) (xy 65.668233 -277.773348) (xy 65.676276 -277.82413)
			(xy 65.67678 -277.849838) (xy 65.994038 -277.849838) (xy 65.997998 -277.800784) (xy 66.009775 -277.753)
			(xy 66.029066 -277.707724) (xy 66.055369 -277.666128) (xy 66.088004 -277.629291) (xy 66.126125 -277.598166)
			(xy 66.168746 -277.573559) (xy 66.214762 -277.556107) (xy 66.262981 -277.546263) (xy 66.312156 -277.544282)
			(xy 66.361011 -277.550214) (xy 66.408282 -277.563906) (xy 66.452744 -277.585004) (xy 66.493247 -277.61296)
			(xy 66.52874 -277.647052) (xy 66.558305 -277.686396) (xy 66.581176 -277.729973) (xy 66.59676 -277.776654)
			(xy 66.604655 -277.825231) (xy 66.60515 -277.849838) (xy 66.604655 -277.874445) (xy 66.604476 -277.875546)
			(xy 66.9229 -277.875546) (xy 66.9229 -277.82413) (xy 66.930943 -277.773348) (xy 66.946831 -277.724449)
			(xy 66.970174 -277.678637) (xy 67.000395 -277.637041) (xy 67.036751 -277.600685) (xy 67.078347 -277.570464)
			(xy 67.124159 -277.547121) (xy 67.173058 -277.531233) (xy 67.22384 -277.52319) (xy 67.275256 -277.52319)
			(xy 67.326038 -277.531233) (xy 67.374937 -277.547121) (xy 67.420749 -277.570464) (xy 67.462345 -277.600685)
			(xy 67.498701 -277.637041) (xy 67.528922 -277.678637) (xy 67.552265 -277.724449) (xy 67.568153 -277.773348)
			(xy 67.576196 -277.82413) (xy 67.5767 -277.849838) (xy 67.893958 -277.849838) (xy 67.897918 -277.800784)
			(xy 67.909695 -277.753) (xy 67.928986 -277.707724) (xy 67.955289 -277.666128) (xy 67.987924 -277.629291)
			(xy 68.026045 -277.598166) (xy 68.068666 -277.573559) (xy 68.114682 -277.556107) (xy 68.162901 -277.546263)
			(xy 68.212076 -277.544282) (xy 68.260931 -277.550214) (xy 68.308202 -277.563906) (xy 68.352664 -277.585004)
			(xy 68.393167 -277.61296) (xy 68.42866 -277.647052) (xy 68.458225 -277.686396) (xy 68.481096 -277.729973)
			(xy 68.49668 -277.776654) (xy 68.504575 -277.825231) (xy 68.50507 -277.849838) (xy 68.504575 -277.874445)
			(xy 68.504396 -277.875546) (xy 68.823074 -277.875546) (xy 68.823074 -277.82413) (xy 68.831117 -277.773348)
			(xy 68.847005 -277.724449) (xy 68.870348 -277.678637) (xy 68.900569 -277.637041) (xy 68.936925 -277.600685)
			(xy 68.978521 -277.570464) (xy 69.024333 -277.547121) (xy 69.073232 -277.531233) (xy 69.124014 -277.52319)
			(xy 69.17543 -277.52319) (xy 69.226212 -277.531233) (xy 69.275111 -277.547121) (xy 69.320923 -277.570464)
			(xy 69.362519 -277.600685) (xy 69.398875 -277.637041) (xy 69.429096 -277.678637) (xy 69.452439 -277.724449)
			(xy 69.468327 -277.773348) (xy 69.47637 -277.82413) (xy 69.476874 -277.849838) (xy 69.794132 -277.849838)
			(xy 69.798092 -277.800784) (xy 69.809869 -277.753) (xy 69.82916 -277.707724) (xy 69.855463 -277.666128)
			(xy 69.888098 -277.629291) (xy 69.926219 -277.598166) (xy 69.96884 -277.573559) (xy 70.014856 -277.556107)
			(xy 70.063075 -277.546263) (xy 70.11225 -277.544282) (xy 70.161105 -277.550214) (xy 70.208376 -277.563906)
			(xy 70.252838 -277.585004) (xy 70.293341 -277.61296) (xy 70.328834 -277.647052) (xy 70.358399 -277.686396)
			(xy 70.38127 -277.729973) (xy 70.396854 -277.776654) (xy 70.404749 -277.825231) (xy 70.405244 -277.849838)
			(xy 70.404749 -277.874445) (xy 70.40457 -277.875546) (xy 70.722994 -277.875546) (xy 70.722994 -277.82413)
			(xy 70.731037 -277.773348) (xy 70.746925 -277.724449) (xy 70.770268 -277.678637) (xy 70.800489 -277.637041)
			(xy 70.836845 -277.600685) (xy 70.878441 -277.570464) (xy 70.924253 -277.547121) (xy 70.973152 -277.531233)
			(xy 71.023934 -277.52319) (xy 71.07535 -277.52319) (xy 71.126132 -277.531233) (xy 71.175031 -277.547121)
			(xy 71.220843 -277.570464) (xy 71.262439 -277.600685) (xy 71.298795 -277.637041) (xy 71.329016 -277.678637)
			(xy 71.352359 -277.724449) (xy 71.368247 -277.773348) (xy 71.37629 -277.82413) (xy 71.376794 -277.849838)
			(xy 71.694052 -277.849838) (xy 71.698012 -277.800784) (xy 71.709789 -277.753) (xy 71.72908 -277.707724)
			(xy 71.755383 -277.666128) (xy 71.788018 -277.629291) (xy 71.826139 -277.598166) (xy 71.86876 -277.573559)
			(xy 71.914776 -277.556107) (xy 71.962995 -277.546263) (xy 72.01217 -277.544282) (xy 72.061025 -277.550214)
			(xy 72.108296 -277.563906) (xy 72.152758 -277.585004) (xy 72.193261 -277.61296) (xy 72.228754 -277.647052)
			(xy 72.258319 -277.686396) (xy 72.28119 -277.729973) (xy 72.296774 -277.776654) (xy 72.304669 -277.825231)
			(xy 72.305164 -277.849838) (xy 72.304669 -277.874445) (xy 72.30449 -277.875546) (xy 72.622914 -277.875546)
			(xy 72.622914 -277.82413) (xy 72.630957 -277.773348) (xy 72.646845 -277.724449) (xy 72.670188 -277.678637)
			(xy 72.700409 -277.637041) (xy 72.736765 -277.600685) (xy 72.778361 -277.570464) (xy 72.824173 -277.547121)
			(xy 72.873072 -277.531233) (xy 72.923854 -277.52319) (xy 72.97527 -277.52319) (xy 73.026052 -277.531233)
			(xy 73.074951 -277.547121) (xy 73.120763 -277.570464) (xy 73.162359 -277.600685) (xy 73.198715 -277.637041)
			(xy 73.228936 -277.678637) (xy 73.252279 -277.724449) (xy 73.268167 -277.773348) (xy 73.27621 -277.82413)
			(xy 73.276714 -277.849838) (xy 73.593972 -277.849838) (xy 73.597932 -277.800784) (xy 73.609709 -277.753)
			(xy 73.629 -277.707724) (xy 73.655303 -277.666128) (xy 73.687938 -277.629291) (xy 73.726059 -277.598166)
			(xy 73.76868 -277.573559) (xy 73.814696 -277.556107) (xy 73.862915 -277.546263) (xy 73.91209 -277.544282)
			(xy 73.960945 -277.550214) (xy 74.008216 -277.563906) (xy 74.052678 -277.585004) (xy 74.093181 -277.61296)
			(xy 74.128674 -277.647052) (xy 74.158239 -277.686396) (xy 74.18111 -277.729973) (xy 74.196694 -277.776654)
			(xy 74.204589 -277.825231) (xy 74.205084 -277.849838) (xy 74.204589 -277.874445) (xy 74.20441 -277.875546)
			(xy 74.523088 -277.875546) (xy 74.523088 -277.82413) (xy 74.531131 -277.773348) (xy 74.547019 -277.724449)
			(xy 74.570362 -277.678637) (xy 74.600583 -277.637041) (xy 74.636939 -277.600685) (xy 74.678535 -277.570464)
			(xy 74.724347 -277.547121) (xy 74.773246 -277.531233) (xy 74.824028 -277.52319) (xy 74.875444 -277.52319)
			(xy 74.926226 -277.531233) (xy 74.975125 -277.547121) (xy 75.020937 -277.570464) (xy 75.062533 -277.600685)
			(xy 75.098889 -277.637041) (xy 75.12911 -277.678637) (xy 75.152453 -277.724449) (xy 75.168341 -277.773348)
			(xy 75.176384 -277.82413) (xy 75.176888 -277.849838) (xy 75.494146 -277.849838) (xy 75.498106 -277.800784)
			(xy 75.509883 -277.753) (xy 75.529174 -277.707724) (xy 75.555477 -277.666128) (xy 75.588112 -277.629291)
			(xy 75.626233 -277.598166) (xy 75.668854 -277.573559) (xy 75.71487 -277.556107) (xy 75.763089 -277.546263)
			(xy 75.812264 -277.544282) (xy 75.861119 -277.550214) (xy 75.90839 -277.563906) (xy 75.952852 -277.585004)
			(xy 75.993355 -277.61296) (xy 76.028848 -277.647052) (xy 76.058413 -277.686396) (xy 76.081284 -277.729973)
			(xy 76.096868 -277.776654) (xy 76.104763 -277.825231) (xy 76.105258 -277.849838) (xy 76.104763 -277.874445)
			(xy 76.104584 -277.875546) (xy 76.423008 -277.875546) (xy 76.423008 -277.82413) (xy 76.431051 -277.773348)
			(xy 76.446939 -277.724449) (xy 76.470282 -277.678637) (xy 76.500503 -277.637041) (xy 76.536859 -277.600685)
			(xy 76.578455 -277.570464) (xy 76.624267 -277.547121) (xy 76.673166 -277.531233) (xy 76.723948 -277.52319)
			(xy 76.775364 -277.52319) (xy 76.826146 -277.531233) (xy 76.875045 -277.547121) (xy 76.920857 -277.570464)
			(xy 76.962453 -277.600685) (xy 76.998809 -277.637041) (xy 77.02903 -277.678637) (xy 77.052373 -277.724449)
			(xy 77.068261 -277.773348) (xy 77.076304 -277.82413) (xy 77.076808 -277.849838) (xy 77.394066 -277.849838)
			(xy 77.398026 -277.800784) (xy 77.409803 -277.753) (xy 77.429094 -277.707724) (xy 77.455397 -277.666128)
			(xy 77.488032 -277.629291) (xy 77.526153 -277.598166) (xy 77.568774 -277.573559) (xy 77.61479 -277.556107)
			(xy 77.663009 -277.546263) (xy 77.712184 -277.544282) (xy 77.761039 -277.550214) (xy 77.80831 -277.563906)
			(xy 77.852772 -277.585004) (xy 77.893275 -277.61296) (xy 77.928768 -277.647052) (xy 77.958333 -277.686396)
			(xy 77.981204 -277.729973) (xy 77.996788 -277.776654) (xy 78.004683 -277.825231) (xy 78.005178 -277.849838)
			(xy 78.004683 -277.874445) (xy 78.004504 -277.875546) (xy 78.322928 -277.875546) (xy 78.322928 -277.82413)
			(xy 78.330971 -277.773348) (xy 78.346859 -277.724449) (xy 78.370202 -277.678637) (xy 78.400423 -277.637041)
			(xy 78.436779 -277.600685) (xy 78.478375 -277.570464) (xy 78.524187 -277.547121) (xy 78.573086 -277.531233)
			(xy 78.623868 -277.52319) (xy 78.675284 -277.52319) (xy 78.726066 -277.531233) (xy 78.774965 -277.547121)
			(xy 78.820777 -277.570464) (xy 78.862373 -277.600685) (xy 78.898729 -277.637041) (xy 78.92895 -277.678637)
			(xy 78.952293 -277.724449) (xy 78.968181 -277.773348) (xy 78.976224 -277.82413) (xy 78.976728 -277.849838)
			(xy 79.293986 -277.849838) (xy 79.297946 -277.800784) (xy 79.309723 -277.753) (xy 79.329014 -277.707724)
			(xy 79.355317 -277.666128) (xy 79.387952 -277.629291) (xy 79.426073 -277.598166) (xy 79.468694 -277.573559)
			(xy 79.51471 -277.556107) (xy 79.562929 -277.546263) (xy 79.612104 -277.544282) (xy 79.660959 -277.550214)
			(xy 79.70823 -277.563906) (xy 79.752692 -277.585004) (xy 79.793195 -277.61296) (xy 79.828688 -277.647052)
			(xy 79.858253 -277.686396) (xy 79.881124 -277.729973) (xy 79.896708 -277.776654) (xy 79.904603 -277.825231)
			(xy 79.905098 -277.849838) (xy 79.904603 -277.874445) (xy 79.904424 -277.875546) (xy 80.223102 -277.875546)
			(xy 80.223102 -277.82413) (xy 80.231145 -277.773348) (xy 80.247033 -277.724449) (xy 80.270376 -277.678637)
			(xy 80.300597 -277.637041) (xy 80.336953 -277.600685) (xy 80.378549 -277.570464) (xy 80.424361 -277.547121)
			(xy 80.47326 -277.531233) (xy 80.524042 -277.52319) (xy 80.575458 -277.52319) (xy 80.62624 -277.531233)
			(xy 80.675139 -277.547121) (xy 80.720951 -277.570464) (xy 80.762547 -277.600685) (xy 80.798903 -277.637041)
			(xy 80.829124 -277.678637) (xy 80.852467 -277.724449) (xy 80.868355 -277.773348) (xy 80.876398 -277.82413)
			(xy 80.876902 -277.849838) (xy 81.19416 -277.849838) (xy 81.19812 -277.800784) (xy 81.209897 -277.753)
			(xy 81.229188 -277.707724) (xy 81.255491 -277.666128) (xy 81.288126 -277.629291) (xy 81.326247 -277.598166)
			(xy 81.368868 -277.573559) (xy 81.414884 -277.556107) (xy 81.463103 -277.546263) (xy 81.512278 -277.544282)
			(xy 81.561133 -277.550214) (xy 81.608404 -277.563906) (xy 81.652866 -277.585004) (xy 81.693369 -277.61296)
			(xy 81.728862 -277.647052) (xy 81.758427 -277.686396) (xy 81.781298 -277.729973) (xy 81.796882 -277.776654)
			(xy 81.804777 -277.825231) (xy 81.805272 -277.849838) (xy 82.14412 -277.849838) (xy 82.14808 -277.800784)
			(xy 82.159857 -277.753) (xy 82.179148 -277.707724) (xy 82.205451 -277.666128) (xy 82.238086 -277.629291)
			(xy 82.276207 -277.598166) (xy 82.318828 -277.573559) (xy 82.364844 -277.556107) (xy 82.413063 -277.546263)
			(xy 82.462238 -277.544282) (xy 82.511093 -277.550214) (xy 82.558364 -277.563906) (xy 82.602826 -277.585004)
			(xy 82.643329 -277.61296) (xy 82.678822 -277.647052) (xy 82.708387 -277.686396) (xy 82.731258 -277.729973)
			(xy 82.746842 -277.776654) (xy 82.754737 -277.825231) (xy 82.755232 -277.849838) (xy 82.754737 -277.874445)
			(xy 82.746842 -277.923022) (xy 82.731258 -277.969703) (xy 82.708387 -278.01328) (xy 82.678822 -278.052624)
			(xy 82.643329 -278.086716) (xy 82.602826 -278.114672) (xy 82.558364 -278.13577) (xy 82.511093 -278.149462)
			(xy 82.462238 -278.155394) (xy 82.413063 -278.153413) (xy 82.364844 -278.143569) (xy 82.318828 -278.126117)
			(xy 82.276207 -278.10151) (xy 82.238086 -278.070385) (xy 82.205451 -278.033548) (xy 82.179148 -277.991952)
			(xy 82.159857 -277.946676) (xy 82.14808 -277.898892) (xy 82.14412 -277.849838) (xy 81.805272 -277.849838)
			(xy 81.804777 -277.874445) (xy 81.796882 -277.923022) (xy 81.781298 -277.969703) (xy 81.758427 -278.01328)
			(xy 81.728862 -278.052624) (xy 81.693369 -278.086716) (xy 81.652866 -278.114672) (xy 81.608404 -278.13577)
			(xy 81.561133 -278.149462) (xy 81.512278 -278.155394) (xy 81.463103 -278.153413) (xy 81.414884 -278.143569)
			(xy 81.368868 -278.126117) (xy 81.326247 -278.10151) (xy 81.288126 -278.070385) (xy 81.255491 -278.033548)
			(xy 81.229188 -277.991952) (xy 81.209897 -277.946676) (xy 81.19812 -277.898892) (xy 81.19416 -277.849838)
			(xy 80.876902 -277.849838) (xy 80.876398 -277.875546) (xy 80.868355 -277.926328) (xy 80.852467 -277.975227)
			(xy 80.829124 -278.021039) (xy 80.798903 -278.062635) (xy 80.762547 -278.098991) (xy 80.720951 -278.129212)
			(xy 80.675139 -278.152555) (xy 80.62624 -278.168443) (xy 80.575458 -278.176486) (xy 80.524042 -278.176486)
			(xy 80.47326 -278.168443) (xy 80.424361 -278.152555) (xy 80.378549 -278.129212) (xy 80.336953 -278.098991)
			(xy 80.300597 -278.062635) (xy 80.270376 -278.021039) (xy 80.247033 -277.975227) (xy 80.231145 -277.926328)
			(xy 80.223102 -277.875546) (xy 79.904424 -277.875546) (xy 79.896708 -277.923022) (xy 79.881124 -277.969703)
			(xy 79.858253 -278.01328) (xy 79.828688 -278.052624) (xy 79.793195 -278.086716) (xy 79.752692 -278.114672)
			(xy 79.70823 -278.13577) (xy 79.660959 -278.149462) (xy 79.612104 -278.155394) (xy 79.562929 -278.153413)
			(xy 79.51471 -278.143569) (xy 79.468694 -278.126117) (xy 79.426073 -278.10151) (xy 79.387952 -278.070385)
			(xy 79.355317 -278.033548) (xy 79.329014 -277.991952) (xy 79.309723 -277.946676) (xy 79.297946 -277.898892)
			(xy 79.293986 -277.849838) (xy 78.976728 -277.849838) (xy 78.976224 -277.875546) (xy 78.968181 -277.926328)
			(xy 78.952293 -277.975227) (xy 78.92895 -278.021039) (xy 78.898729 -278.062635) (xy 78.862373 -278.098991)
			(xy 78.820777 -278.129212) (xy 78.774965 -278.152555) (xy 78.726066 -278.168443) (xy 78.675284 -278.176486)
			(xy 78.623868 -278.176486) (xy 78.573086 -278.168443) (xy 78.524187 -278.152555) (xy 78.478375 -278.129212)
			(xy 78.436779 -278.098991) (xy 78.400423 -278.062635) (xy 78.370202 -278.021039) (xy 78.346859 -277.975227)
			(xy 78.330971 -277.926328) (xy 78.322928 -277.875546) (xy 78.004504 -277.875546) (xy 77.996788 -277.923022)
			(xy 77.981204 -277.969703) (xy 77.958333 -278.01328) (xy 77.928768 -278.052624) (xy 77.893275 -278.086716)
			(xy 77.852772 -278.114672) (xy 77.80831 -278.13577) (xy 77.761039 -278.149462) (xy 77.712184 -278.155394)
			(xy 77.663009 -278.153413) (xy 77.61479 -278.143569) (xy 77.568774 -278.126117) (xy 77.526153 -278.10151)
			(xy 77.488032 -278.070385) (xy 77.455397 -278.033548) (xy 77.429094 -277.991952) (xy 77.409803 -277.946676)
			(xy 77.398026 -277.898892) (xy 77.394066 -277.849838) (xy 77.076808 -277.849838) (xy 77.076304 -277.875546)
			(xy 77.068261 -277.926328) (xy 77.052373 -277.975227) (xy 77.02903 -278.021039) (xy 76.998809 -278.062635)
			(xy 76.962453 -278.098991) (xy 76.920857 -278.129212) (xy 76.875045 -278.152555) (xy 76.826146 -278.168443)
			(xy 76.775364 -278.176486) (xy 76.723948 -278.176486) (xy 76.673166 -278.168443) (xy 76.624267 -278.152555)
			(xy 76.578455 -278.129212) (xy 76.536859 -278.098991) (xy 76.500503 -278.062635) (xy 76.470282 -278.021039)
			(xy 76.446939 -277.975227) (xy 76.431051 -277.926328) (xy 76.423008 -277.875546) (xy 76.104584 -277.875546)
			(xy 76.096868 -277.923022) (xy 76.081284 -277.969703) (xy 76.058413 -278.01328) (xy 76.028848 -278.052624)
			(xy 75.993355 -278.086716) (xy 75.952852 -278.114672) (xy 75.90839 -278.13577) (xy 75.861119 -278.149462)
			(xy 75.812264 -278.155394) (xy 75.763089 -278.153413) (xy 75.71487 -278.143569) (xy 75.668854 -278.126117)
			(xy 75.626233 -278.10151) (xy 75.588112 -278.070385) (xy 75.555477 -278.033548) (xy 75.529174 -277.991952)
			(xy 75.509883 -277.946676) (xy 75.498106 -277.898892) (xy 75.494146 -277.849838) (xy 75.176888 -277.849838)
			(xy 75.176384 -277.875546) (xy 75.168341 -277.926328) (xy 75.152453 -277.975227) (xy 75.12911 -278.021039)
			(xy 75.098889 -278.062635) (xy 75.062533 -278.098991) (xy 75.020937 -278.129212) (xy 74.975125 -278.152555)
			(xy 74.926226 -278.168443) (xy 74.875444 -278.176486) (xy 74.824028 -278.176486) (xy 74.773246 -278.168443)
			(xy 74.724347 -278.152555) (xy 74.678535 -278.129212) (xy 74.636939 -278.098991) (xy 74.600583 -278.062635)
			(xy 74.570362 -278.021039) (xy 74.547019 -277.975227) (xy 74.531131 -277.926328) (xy 74.523088 -277.875546)
			(xy 74.20441 -277.875546) (xy 74.196694 -277.923022) (xy 74.18111 -277.969703) (xy 74.158239 -278.01328)
			(xy 74.128674 -278.052624) (xy 74.093181 -278.086716) (xy 74.052678 -278.114672) (xy 74.008216 -278.13577)
			(xy 73.960945 -278.149462) (xy 73.91209 -278.155394) (xy 73.862915 -278.153413) (xy 73.814696 -278.143569)
			(xy 73.76868 -278.126117) (xy 73.726059 -278.10151) (xy 73.687938 -278.070385) (xy 73.655303 -278.033548)
			(xy 73.629 -277.991952) (xy 73.609709 -277.946676) (xy 73.597932 -277.898892) (xy 73.593972 -277.849838)
			(xy 73.276714 -277.849838) (xy 73.27621 -277.875546) (xy 73.268167 -277.926328) (xy 73.252279 -277.975227)
			(xy 73.228936 -278.021039) (xy 73.198715 -278.062635) (xy 73.162359 -278.098991) (xy 73.120763 -278.129212)
			(xy 73.074951 -278.152555) (xy 73.026052 -278.168443) (xy 72.97527 -278.176486) (xy 72.923854 -278.176486)
			(xy 72.873072 -278.168443) (xy 72.824173 -278.152555) (xy 72.778361 -278.129212) (xy 72.736765 -278.098991)
			(xy 72.700409 -278.062635) (xy 72.670188 -278.021039) (xy 72.646845 -277.975227) (xy 72.630957 -277.926328)
			(xy 72.622914 -277.875546) (xy 72.30449 -277.875546) (xy 72.296774 -277.923022) (xy 72.28119 -277.969703)
			(xy 72.258319 -278.01328) (xy 72.228754 -278.052624) (xy 72.193261 -278.086716) (xy 72.152758 -278.114672)
			(xy 72.108296 -278.13577) (xy 72.061025 -278.149462) (xy 72.01217 -278.155394) (xy 71.962995 -278.153413)
			(xy 71.914776 -278.143569) (xy 71.86876 -278.126117) (xy 71.826139 -278.10151) (xy 71.788018 -278.070385)
			(xy 71.755383 -278.033548) (xy 71.72908 -277.991952) (xy 71.709789 -277.946676) (xy 71.698012 -277.898892)
			(xy 71.694052 -277.849838) (xy 71.376794 -277.849838) (xy 71.37629 -277.875546) (xy 71.368247 -277.926328)
			(xy 71.352359 -277.975227) (xy 71.329016 -278.021039) (xy 71.298795 -278.062635) (xy 71.262439 -278.098991)
			(xy 71.220843 -278.129212) (xy 71.175031 -278.152555) (xy 71.126132 -278.168443) (xy 71.07535 -278.176486)
			(xy 71.023934 -278.176486) (xy 70.973152 -278.168443) (xy 70.924253 -278.152555) (xy 70.878441 -278.129212)
			(xy 70.836845 -278.098991) (xy 70.800489 -278.062635) (xy 70.770268 -278.021039) (xy 70.746925 -277.975227)
			(xy 70.731037 -277.926328) (xy 70.722994 -277.875546) (xy 70.40457 -277.875546) (xy 70.396854 -277.923022)
			(xy 70.38127 -277.969703) (xy 70.358399 -278.01328) (xy 70.328834 -278.052624) (xy 70.293341 -278.086716)
			(xy 70.252838 -278.114672) (xy 70.208376 -278.13577) (xy 70.161105 -278.149462) (xy 70.11225 -278.155394)
			(xy 70.063075 -278.153413) (xy 70.014856 -278.143569) (xy 69.96884 -278.126117) (xy 69.926219 -278.10151)
			(xy 69.888098 -278.070385) (xy 69.855463 -278.033548) (xy 69.82916 -277.991952) (xy 69.809869 -277.946676)
			(xy 69.798092 -277.898892) (xy 69.794132 -277.849838) (xy 69.476874 -277.849838) (xy 69.47637 -277.875546)
			(xy 69.468327 -277.926328) (xy 69.452439 -277.975227) (xy 69.429096 -278.021039) (xy 69.398875 -278.062635)
			(xy 69.362519 -278.098991) (xy 69.320923 -278.129212) (xy 69.275111 -278.152555) (xy 69.226212 -278.168443)
			(xy 69.17543 -278.176486) (xy 69.124014 -278.176486) (xy 69.073232 -278.168443) (xy 69.024333 -278.152555)
			(xy 68.978521 -278.129212) (xy 68.936925 -278.098991) (xy 68.900569 -278.062635) (xy 68.870348 -278.021039)
			(xy 68.847005 -277.975227) (xy 68.831117 -277.926328) (xy 68.823074 -277.875546) (xy 68.504396 -277.875546)
			(xy 68.49668 -277.923022) (xy 68.481096 -277.969703) (xy 68.458225 -278.01328) (xy 68.42866 -278.052624)
			(xy 68.393167 -278.086716) (xy 68.352664 -278.114672) (xy 68.308202 -278.13577) (xy 68.260931 -278.149462)
			(xy 68.212076 -278.155394) (xy 68.162901 -278.153413) (xy 68.114682 -278.143569) (xy 68.068666 -278.126117)
			(xy 68.026045 -278.10151) (xy 67.987924 -278.070385) (xy 67.955289 -278.033548) (xy 67.928986 -277.991952)
			(xy 67.909695 -277.946676) (xy 67.897918 -277.898892) (xy 67.893958 -277.849838) (xy 67.5767 -277.849838)
			(xy 67.576196 -277.875546) (xy 67.568153 -277.926328) (xy 67.552265 -277.975227) (xy 67.528922 -278.021039)
			(xy 67.498701 -278.062635) (xy 67.462345 -278.098991) (xy 67.420749 -278.129212) (xy 67.374937 -278.152555)
			(xy 67.326038 -278.168443) (xy 67.275256 -278.176486) (xy 67.22384 -278.176486) (xy 67.173058 -278.168443)
			(xy 67.124159 -278.152555) (xy 67.078347 -278.129212) (xy 67.036751 -278.098991) (xy 67.000395 -278.062635)
			(xy 66.970174 -278.021039) (xy 66.946831 -277.975227) (xy 66.930943 -277.926328) (xy 66.9229 -277.875546)
			(xy 66.604476 -277.875546) (xy 66.59676 -277.923022) (xy 66.581176 -277.969703) (xy 66.558305 -278.01328)
			(xy 66.52874 -278.052624) (xy 66.493247 -278.086716) (xy 66.452744 -278.114672) (xy 66.408282 -278.13577)
			(xy 66.361011 -278.149462) (xy 66.312156 -278.155394) (xy 66.262981 -278.153413) (xy 66.214762 -278.143569)
			(xy 66.168746 -278.126117) (xy 66.126125 -278.10151) (xy 66.088004 -278.070385) (xy 66.055369 -278.033548)
			(xy 66.029066 -277.991952) (xy 66.009775 -277.946676) (xy 65.997998 -277.898892) (xy 65.994038 -277.849838)
			(xy 65.67678 -277.849838) (xy 65.676276 -277.875546) (xy 65.668233 -277.926328) (xy 65.652345 -277.975227)
			(xy 65.629002 -278.021039) (xy 65.598781 -278.062635) (xy 65.562425 -278.098991) (xy 65.520829 -278.129212)
			(xy 65.475017 -278.152555) (xy 65.426118 -278.168443) (xy 65.375336 -278.176486) (xy 65.32392 -278.176486)
			(xy 65.273138 -278.168443) (xy 65.224239 -278.152555) (xy 65.178427 -278.129212) (xy 65.136831 -278.098991)
			(xy 65.100475 -278.062635) (xy 65.070254 -278.021039) (xy 65.046911 -277.975227) (xy 65.031023 -277.926328)
			(xy 65.02298 -277.875546) (xy 64.704556 -277.875546) (xy 64.69684 -277.923022) (xy 64.681256 -277.969703)
			(xy 64.658385 -278.01328) (xy 64.62882 -278.052624) (xy 64.593327 -278.086716) (xy 64.552824 -278.114672)
			(xy 64.508362 -278.13577) (xy 64.461091 -278.149462) (xy 64.412236 -278.155394) (xy 64.363061 -278.153413)
			(xy 64.314842 -278.143569) (xy 64.268826 -278.126117) (xy 64.226205 -278.10151) (xy 64.188084 -278.070385)
			(xy 64.155449 -278.033548) (xy 64.129146 -277.991952) (xy 64.109855 -277.946676) (xy 64.098078 -277.898892)
			(xy 64.094118 -277.849838) (xy 63.77686 -277.849838) (xy 63.776356 -277.875546) (xy 63.768313 -277.926328)
			(xy 63.752425 -277.975227) (xy 63.729082 -278.021039) (xy 63.698861 -278.062635) (xy 63.662505 -278.098991)
			(xy 63.620909 -278.129212) (xy 63.575097 -278.152555) (xy 63.526198 -278.168443) (xy 63.475416 -278.176486)
			(xy 63.424 -278.176486) (xy 63.373218 -278.168443) (xy 63.324319 -278.152555) (xy 63.278507 -278.129212)
			(xy 63.236911 -278.098991) (xy 63.200555 -278.062635) (xy 63.170334 -278.021039) (xy 63.146991 -277.975227)
			(xy 63.131103 -277.926328) (xy 63.12306 -277.875546) (xy 62.804382 -277.875546) (xy 62.796666 -277.923022)
			(xy 62.781082 -277.969703) (xy 62.758211 -278.01328) (xy 62.728646 -278.052624) (xy 62.693153 -278.086716)
			(xy 62.65265 -278.114672) (xy 62.608188 -278.13577) (xy 62.560917 -278.149462) (xy 62.512062 -278.155394)
			(xy 62.462887 -278.153413) (xy 62.414668 -278.143569) (xy 62.368652 -278.126117) (xy 62.326031 -278.10151)
			(xy 62.28791 -278.070385) (xy 62.255275 -278.033548) (xy 62.228972 -277.991952) (xy 62.209681 -277.946676)
			(xy 62.197904 -277.898892) (xy 62.193944 -277.849838) (xy 61.876686 -277.849838) (xy 61.876182 -277.875546)
			(xy 61.868139 -277.926328) (xy 61.852251 -277.975227) (xy 61.828908 -278.021039) (xy 61.798687 -278.062635)
			(xy 61.762331 -278.098991) (xy 61.720735 -278.129212) (xy 61.674923 -278.152555) (xy 61.626024 -278.168443)
			(xy 61.575242 -278.176486) (xy 61.523826 -278.176486) (xy 61.473044 -278.168443) (xy 61.424145 -278.152555)
			(xy 61.378333 -278.129212) (xy 61.336737 -278.098991) (xy 61.300381 -278.062635) (xy 61.27016 -278.021039)
			(xy 61.246817 -277.975227) (xy 61.230929 -277.926328) (xy 61.222886 -277.875546) (xy 60.904462 -277.875546)
			(xy 60.896746 -277.923022) (xy 60.881162 -277.969703) (xy 60.858291 -278.01328) (xy 60.828726 -278.052624)
			(xy 60.793233 -278.086716) (xy 60.75273 -278.114672) (xy 60.708268 -278.13577) (xy 60.660997 -278.149462)
			(xy 60.612142 -278.155394) (xy 60.562967 -278.153413) (xy 60.514748 -278.143569) (xy 60.468732 -278.126117)
			(xy 60.426111 -278.10151) (xy 60.38799 -278.070385) (xy 60.355355 -278.033548) (xy 60.329052 -277.991952)
			(xy 60.309761 -277.946676) (xy 60.297984 -277.898892) (xy 60.294024 -277.849838) (xy 59.976766 -277.849838)
			(xy 59.976262 -277.875546) (xy 59.968219 -277.926328) (xy 59.952331 -277.975227) (xy 59.928988 -278.021039)
			(xy 59.898767 -278.062635) (xy 59.862411 -278.098991) (xy 59.820815 -278.129212) (xy 59.775003 -278.152555)
			(xy 59.726104 -278.168443) (xy 59.675322 -278.176486) (xy 59.623906 -278.176486) (xy 59.573124 -278.168443)
			(xy 59.524225 -278.152555) (xy 59.478413 -278.129212) (xy 59.436817 -278.098991) (xy 59.400461 -278.062635)
			(xy 59.37024 -278.021039) (xy 59.346897 -277.975227) (xy 59.331009 -277.926328) (xy 59.322966 -277.875546)
			(xy 59.004542 -277.875546) (xy 58.996826 -277.923022) (xy 58.981242 -277.969703) (xy 58.958371 -278.01328)
			(xy 58.928806 -278.052624) (xy 58.893313 -278.086716) (xy 58.85281 -278.114672) (xy 58.808348 -278.13577)
			(xy 58.761077 -278.149462) (xy 58.712222 -278.155394) (xy 58.663047 -278.153413) (xy 58.614828 -278.143569)
			(xy 58.568812 -278.126117) (xy 58.526191 -278.10151) (xy 58.48807 -278.070385) (xy 58.455435 -278.033548)
			(xy 58.429132 -277.991952) (xy 58.409841 -277.946676) (xy 58.398064 -277.898892) (xy 58.394104 -277.849838)
			(xy 58.0771 -277.849838) (xy 58.076596 -277.875546) (xy 58.068553 -277.926328) (xy 58.052665 -277.975227)
			(xy 58.029322 -278.021039) (xy 57.999101 -278.062635) (xy 57.962745 -278.098991) (xy 57.921149 -278.129212)
			(xy 57.875337 -278.152555) (xy 57.826438 -278.168443) (xy 57.775656 -278.176486) (xy 57.72424 -278.176486)
			(xy 57.673458 -278.168443) (xy 57.624559 -278.152555) (xy 57.578747 -278.129212) (xy 57.537151 -278.098991)
			(xy 57.500795 -278.062635) (xy 57.470574 -278.021039) (xy 57.447231 -277.975227) (xy 57.431343 -277.926328)
			(xy 57.4233 -277.875546) (xy 57.104622 -277.875546) (xy 57.096906 -277.923022) (xy 57.081322 -277.969703)
			(xy 57.058451 -278.01328) (xy 57.028886 -278.052624) (xy 56.993393 -278.086716) (xy 56.95289 -278.114672)
			(xy 56.908428 -278.13577) (xy 56.861157 -278.149462) (xy 56.812302 -278.155394) (xy 56.763127 -278.153413)
			(xy 56.714908 -278.143569) (xy 56.668892 -278.126117) (xy 56.626271 -278.10151) (xy 56.58815 -278.070385)
			(xy 56.555515 -278.033548) (xy 56.529212 -277.991952) (xy 56.509921 -277.946676) (xy 56.498144 -277.898892)
			(xy 56.494184 -277.849838) (xy 56.176926 -277.849838) (xy 56.176422 -277.875546) (xy 56.168379 -277.926328)
			(xy 56.152491 -277.975227) (xy 56.129148 -278.021039) (xy 56.098927 -278.062635) (xy 56.062571 -278.098991)
			(xy 56.020975 -278.129212) (xy 55.975163 -278.152555) (xy 55.926264 -278.168443) (xy 55.875482 -278.176486)
			(xy 55.824066 -278.176486) (xy 55.773284 -278.168443) (xy 55.724385 -278.152555) (xy 55.678573 -278.129212)
			(xy 55.636977 -278.098991) (xy 55.600621 -278.062635) (xy 55.5704 -278.021039) (xy 55.547057 -277.975227)
			(xy 55.531169 -277.926328) (xy 55.523126 -277.875546) (xy 55.204448 -277.875546) (xy 55.196732 -277.923022)
			(xy 55.181148 -277.969703) (xy 55.158277 -278.01328) (xy 55.128712 -278.052624) (xy 55.093219 -278.086716)
			(xy 55.052716 -278.114672) (xy 55.008254 -278.13577) (xy 54.960983 -278.149462) (xy 54.912128 -278.155394)
			(xy 54.862953 -278.153413) (xy 54.814734 -278.143569) (xy 54.768718 -278.126117) (xy 54.726097 -278.10151)
			(xy 54.687976 -278.070385) (xy 54.655341 -278.033548) (xy 54.629038 -277.991952) (xy 54.609747 -277.946676)
			(xy 54.59797 -277.898892) (xy 54.59401 -277.849838) (xy 54.277006 -277.849838) (xy 54.276502 -277.875546)
			(xy 54.268459 -277.926328) (xy 54.252571 -277.975227) (xy 54.229228 -278.021039) (xy 54.199007 -278.062635)
			(xy 54.162651 -278.098991) (xy 54.121055 -278.129212) (xy 54.075243 -278.152555) (xy 54.026344 -278.168443)
			(xy 53.975562 -278.176486) (xy 53.924146 -278.176486) (xy 53.873364 -278.168443) (xy 53.824465 -278.152555)
			(xy 53.778653 -278.129212) (xy 53.737057 -278.098991) (xy 53.700701 -278.062635) (xy 53.67048 -278.021039)
			(xy 53.647137 -277.975227) (xy 53.631249 -277.926328) (xy 53.623206 -277.875546) (xy 53.304528 -277.875546)
			(xy 53.296812 -277.923022) (xy 53.281228 -277.969703) (xy 53.258357 -278.01328) (xy 53.228792 -278.052624)
			(xy 53.193299 -278.086716) (xy 53.152796 -278.114672) (xy 53.108334 -278.13577) (xy 53.061063 -278.149462)
			(xy 53.012208 -278.155394) (xy 52.963033 -278.153413) (xy 52.914814 -278.143569) (xy 52.868798 -278.126117)
			(xy 52.826177 -278.10151) (xy 52.788056 -278.070385) (xy 52.755421 -278.033548) (xy 52.729118 -277.991952)
			(xy 52.709827 -277.946676) (xy 52.69805 -277.898892) (xy 52.69409 -277.849838) (xy 52.377086 -277.849838)
			(xy 52.376582 -277.875546) (xy 52.368539 -277.926328) (xy 52.352651 -277.975227) (xy 52.329308 -278.021039)
			(xy 52.299087 -278.062635) (xy 52.262731 -278.098991) (xy 52.221135 -278.129212) (xy 52.175323 -278.152555)
			(xy 52.126424 -278.168443) (xy 52.075642 -278.176486) (xy 52.024226 -278.176486) (xy 51.973444 -278.168443)
			(xy 51.924545 -278.152555) (xy 51.878733 -278.129212) (xy 51.837137 -278.098991) (xy 51.800781 -278.062635)
			(xy 51.77056 -278.021039) (xy 51.747217 -277.975227) (xy 51.731329 -277.926328) (xy 51.723286 -277.875546)
			(xy 51.404608 -277.875546) (xy 51.396892 -277.923022) (xy 51.381308 -277.969703) (xy 51.358437 -278.01328)
			(xy 51.328872 -278.052624) (xy 51.293379 -278.086716) (xy 51.252876 -278.114672) (xy 51.208414 -278.13577)
			(xy 51.161143 -278.149462) (xy 51.112288 -278.155394) (xy 51.063113 -278.153413) (xy 51.014894 -278.143569)
			(xy 50.968878 -278.126117) (xy 50.926257 -278.10151) (xy 50.888136 -278.070385) (xy 50.855501 -278.033548)
			(xy 50.829198 -277.991952) (xy 50.809907 -277.946676) (xy 50.79813 -277.898892) (xy 50.79417 -277.849838)
			(xy 50.476912 -277.849838) (xy 50.476408 -277.875546) (xy 50.468365 -277.926328) (xy 50.452477 -277.975227)
			(xy 50.429134 -278.021039) (xy 50.398913 -278.062635) (xy 50.362557 -278.098991) (xy 50.320961 -278.129212)
			(xy 50.275149 -278.152555) (xy 50.22625 -278.168443) (xy 50.175468 -278.176486) (xy 50.124052 -278.176486)
			(xy 50.07327 -278.168443) (xy 50.024371 -278.152555) (xy 49.978559 -278.129212) (xy 49.936963 -278.098991)
			(xy 49.900607 -278.062635) (xy 49.870386 -278.021039) (xy 49.847043 -277.975227) (xy 49.831155 -277.926328)
			(xy 49.823112 -277.875546) (xy 49.504434 -277.875546) (xy 49.496718 -277.923022) (xy 49.481134 -277.969703)
			(xy 49.458263 -278.01328) (xy 49.428698 -278.052624) (xy 49.393205 -278.086716) (xy 49.352702 -278.114672)
			(xy 49.30824 -278.13577) (xy 49.260969 -278.149462) (xy 49.212114 -278.155394) (xy 49.162939 -278.153413)
			(xy 49.11472 -278.143569) (xy 49.068704 -278.126117) (xy 49.026083 -278.10151) (xy 48.987962 -278.070385)
			(xy 48.955327 -278.033548) (xy 48.929024 -277.991952) (xy 48.909733 -277.946676) (xy 48.897956 -277.898892)
			(xy 48.893996 -277.849838) (xy 48.576992 -277.849838) (xy 48.576488 -277.875546) (xy 48.568445 -277.926328)
			(xy 48.552557 -277.975227) (xy 48.529214 -278.021039) (xy 48.498993 -278.062635) (xy 48.462637 -278.098991)
			(xy 48.421041 -278.129212) (xy 48.375229 -278.152555) (xy 48.32633 -278.168443) (xy 48.275548 -278.176486)
			(xy 48.224132 -278.176486) (xy 48.17335 -278.168443) (xy 48.124451 -278.152555) (xy 48.078639 -278.129212)
			(xy 48.037043 -278.098991) (xy 48.000687 -278.062635) (xy 47.970466 -278.021039) (xy 47.947123 -277.975227)
			(xy 47.931235 -277.926328) (xy 47.923192 -277.875546) (xy 47.604514 -277.875546) (xy 47.596798 -277.923022)
			(xy 47.581214 -277.969703) (xy 47.558343 -278.01328) (xy 47.528778 -278.052624) (xy 47.493285 -278.086716)
			(xy 47.452782 -278.114672) (xy 47.40832 -278.13577) (xy 47.361049 -278.149462) (xy 47.312194 -278.155394)
			(xy 47.263019 -278.153413) (xy 47.2148 -278.143569) (xy 47.168784 -278.126117) (xy 47.126163 -278.10151)
			(xy 47.088042 -278.070385) (xy 47.055407 -278.033548) (xy 47.029104 -277.991952) (xy 47.009813 -277.946676)
			(xy 46.998036 -277.898892) (xy 46.994076 -277.849838) (xy 46.677072 -277.849838) (xy 46.676568 -277.875546)
			(xy 46.668525 -277.926328) (xy 46.652637 -277.975227) (xy 46.629294 -278.021039) (xy 46.599073 -278.062635)
			(xy 46.562717 -278.098991) (xy 46.521121 -278.129212) (xy 46.475309 -278.152555) (xy 46.42641 -278.168443)
			(xy 46.375628 -278.176486) (xy 46.324212 -278.176486) (xy 46.27343 -278.168443) (xy 46.224531 -278.152555)
			(xy 46.178719 -278.129212) (xy 46.137123 -278.098991) (xy 46.100767 -278.062635) (xy 46.070546 -278.021039)
			(xy 46.047203 -277.975227) (xy 46.031315 -277.926328) (xy 46.023272 -277.875546) (xy 45.704594 -277.875546)
			(xy 45.696878 -277.923022) (xy 45.681294 -277.969703) (xy 45.658423 -278.01328) (xy 45.628858 -278.052624)
			(xy 45.593365 -278.086716) (xy 45.552862 -278.114672) (xy 45.5084 -278.13577) (xy 45.461129 -278.149462)
			(xy 45.412274 -278.155394) (xy 45.363099 -278.153413) (xy 45.31488 -278.143569) (xy 45.268864 -278.126117)
			(xy 45.226243 -278.10151) (xy 45.188122 -278.070385) (xy 45.155487 -278.033548) (xy 45.129184 -277.991952)
			(xy 45.109893 -277.946676) (xy 45.098116 -277.898892) (xy 45.094156 -277.849838) (xy 44.776898 -277.849838)
			(xy 44.776394 -277.875546) (xy 44.768351 -277.926328) (xy 44.752463 -277.975227) (xy 44.72912 -278.021039)
			(xy 44.698899 -278.062635) (xy 44.662543 -278.098991) (xy 44.620947 -278.129212) (xy 44.575135 -278.152555)
			(xy 44.526236 -278.168443) (xy 44.475454 -278.176486) (xy 44.424038 -278.176486) (xy 44.373256 -278.168443)
			(xy 44.324357 -278.152555) (xy 44.278545 -278.129212) (xy 44.236949 -278.098991) (xy 44.200593 -278.062635)
			(xy 44.170372 -278.021039) (xy 44.147029 -277.975227) (xy 44.131141 -277.926328) (xy 44.123098 -277.875546)
			(xy 43.80442 -277.875546) (xy 43.796704 -277.923022) (xy 43.78112 -277.969703) (xy 43.758249 -278.01328)
			(xy 43.728684 -278.052624) (xy 43.693191 -278.086716) (xy 43.652688 -278.114672) (xy 43.608226 -278.13577)
			(xy 43.560955 -278.149462) (xy 43.5121 -278.155394) (xy 43.462925 -278.153413) (xy 43.414706 -278.143569)
			(xy 43.36869 -278.126117) (xy 43.326069 -278.10151) (xy 43.287948 -278.070385) (xy 43.255313 -278.033548)
			(xy 43.22901 -277.991952) (xy 43.209719 -277.946676) (xy 43.197942 -277.898892) (xy 43.193982 -277.849838)
			(xy 40.899334 -277.849838) (xy 40.899334 -277.937214) (xy 40.900003 -277.94924) (xy 40.910869 -277.970699)
			(xy 40.920162 -277.978362) (xy 40.996362 -278.033988) (xy 41.020238 -278.037798) (xy 41.031922 -278.033988)
			(xy 41.054563 -278.027213) (xy 41.101257 -278.01994) (xy 41.124886 -278.01951) (xy 41.150143 -278.020002)
			(xy 41.199968 -278.028314) (xy 41.247746 -278.044714) (xy 41.292172 -278.068754) (xy 41.332036 -278.09978)
			(xy 41.366249 -278.136943) (xy 41.393878 -278.179231) (xy 41.41417 -278.22549) (xy 41.42657 -278.274459)
			(xy 41.430742 -278.3248) (xy 41.430741 -278.324818) (xy 41.769042 -278.324818) (xy 41.773002 -278.275764)
			(xy 41.784779 -278.22798) (xy 41.80407 -278.182704) (xy 41.830373 -278.141108) (xy 41.863008 -278.104271)
			(xy 41.901129 -278.073146) (xy 41.94375 -278.048539) (xy 41.989766 -278.031087) (xy 42.037985 -278.021243)
			(xy 42.08716 -278.019262) (xy 42.136015 -278.025194) (xy 42.183286 -278.038886) (xy 42.227748 -278.059984)
			(xy 42.268251 -278.08794) (xy 42.303744 -278.122032) (xy 42.333309 -278.161376) (xy 42.35618 -278.204953)
			(xy 42.371764 -278.251634) (xy 42.379659 -278.300211) (xy 42.380154 -278.324818) (xy 42.379659 -278.349425)
			(xy 42.371764 -278.398002) (xy 42.35618 -278.444683) (xy 42.333309 -278.48826) (xy 42.303744 -278.527604)
			(xy 42.268251 -278.561696) (xy 42.227748 -278.589652) (xy 42.183286 -278.61075) (xy 42.136015 -278.624442)
			(xy 42.08716 -278.630374) (xy 42.037985 -278.628393) (xy 41.989766 -278.618549) (xy 41.94375 -278.601097)
			(xy 41.901129 -278.57649) (xy 41.863008 -278.545365) (xy 41.830373 -278.508528) (xy 41.80407 -278.466932)
			(xy 41.784779 -278.421656) (xy 41.773002 -278.373872) (xy 41.769042 -278.324818) (xy 41.430741 -278.324818)
			(xy 41.42657 -278.375141) (xy 41.41417 -278.42411) (xy 41.393878 -278.470369) (xy 41.366249 -278.512657)
			(xy 41.332036 -278.54982) (xy 41.292172 -278.580846) (xy 41.247746 -278.604886) (xy 41.199968 -278.621286)
			(xy 41.150143 -278.629598) (xy 41.124886 -278.630126) (xy 41.101259 -278.629679) (xy 41.054568 -278.6224)
			(xy 41.031922 -278.615648) (xy 41.020238 -278.611838) (xy 40.996362 -278.615648) (xy 40.920162 -278.671274)
			(xy 40.91082 -278.678896) (xy 40.899955 -278.70038) (xy 40.899334 -278.712422) (xy 40.899334 -278.799798)
			(xy 43.193982 -278.799798) (xy 43.197942 -278.750744) (xy 43.209719 -278.70296) (xy 43.22901 -278.657684)
			(xy 43.255313 -278.616088) (xy 43.287948 -278.579251) (xy 43.326069 -278.548126) (xy 43.36869 -278.523519)
			(xy 43.414706 -278.506067) (xy 43.462925 -278.496223) (xy 43.5121 -278.494242) (xy 43.560955 -278.500174)
			(xy 43.608226 -278.513866) (xy 43.652688 -278.534964) (xy 43.693191 -278.56292) (xy 43.728684 -278.597012)
			(xy 43.758249 -278.636356) (xy 43.78112 -278.679933) (xy 43.796704 -278.726614) (xy 43.804599 -278.775191)
			(xy 43.805094 -278.799798) (xy 43.804599 -278.824405) (xy 43.80442 -278.825506) (xy 44.123098 -278.825506)
			(xy 44.123098 -278.77409) (xy 44.131141 -278.723308) (xy 44.147029 -278.674409) (xy 44.170372 -278.628597)
			(xy 44.200593 -278.587001) (xy 44.236949 -278.550645) (xy 44.278545 -278.520424) (xy 44.324357 -278.497081)
			(xy 44.373256 -278.481193) (xy 44.424038 -278.47315) (xy 44.475454 -278.47315) (xy 44.526236 -278.481193)
			(xy 44.575135 -278.497081) (xy 44.620947 -278.520424) (xy 44.662543 -278.550645) (xy 44.698899 -278.587001)
			(xy 44.72912 -278.628597) (xy 44.752463 -278.674409) (xy 44.768351 -278.723308) (xy 44.776394 -278.77409)
			(xy 44.776898 -278.799798) (xy 45.094156 -278.799798) (xy 45.098116 -278.750744) (xy 45.109893 -278.70296)
			(xy 45.129184 -278.657684) (xy 45.155487 -278.616088) (xy 45.188122 -278.579251) (xy 45.226243 -278.548126)
			(xy 45.268864 -278.523519) (xy 45.31488 -278.506067) (xy 45.363099 -278.496223) (xy 45.412274 -278.494242)
			(xy 45.461129 -278.500174) (xy 45.5084 -278.513866) (xy 45.552862 -278.534964) (xy 45.593365 -278.56292)
			(xy 45.628858 -278.597012) (xy 45.658423 -278.636356) (xy 45.681294 -278.679933) (xy 45.696878 -278.726614)
			(xy 45.704773 -278.775191) (xy 45.705268 -278.799798) (xy 45.704773 -278.824405) (xy 45.704594 -278.825506)
			(xy 46.023272 -278.825506) (xy 46.023272 -278.77409) (xy 46.031315 -278.723308) (xy 46.047203 -278.674409)
			(xy 46.070546 -278.628597) (xy 46.100767 -278.587001) (xy 46.137123 -278.550645) (xy 46.178719 -278.520424)
			(xy 46.224531 -278.497081) (xy 46.27343 -278.481193) (xy 46.324212 -278.47315) (xy 46.375628 -278.47315)
			(xy 46.42641 -278.481193) (xy 46.475309 -278.497081) (xy 46.521121 -278.520424) (xy 46.562717 -278.550645)
			(xy 46.599073 -278.587001) (xy 46.629294 -278.628597) (xy 46.652637 -278.674409) (xy 46.668525 -278.723308)
			(xy 46.676568 -278.77409) (xy 46.677072 -278.799798) (xy 46.994076 -278.799798) (xy 46.998036 -278.750744)
			(xy 47.009813 -278.70296) (xy 47.029104 -278.657684) (xy 47.055407 -278.616088) (xy 47.088042 -278.579251)
			(xy 47.126163 -278.548126) (xy 47.168784 -278.523519) (xy 47.2148 -278.506067) (xy 47.263019 -278.496223)
			(xy 47.312194 -278.494242) (xy 47.361049 -278.500174) (xy 47.40832 -278.513866) (xy 47.452782 -278.534964)
			(xy 47.493285 -278.56292) (xy 47.528778 -278.597012) (xy 47.558343 -278.636356) (xy 47.581214 -278.679933)
			(xy 47.596798 -278.726614) (xy 47.604693 -278.775191) (xy 47.605188 -278.799798) (xy 47.604693 -278.824405)
			(xy 47.604514 -278.825506) (xy 47.923192 -278.825506) (xy 47.923192 -278.77409) (xy 47.931235 -278.723308)
			(xy 47.947123 -278.674409) (xy 47.970466 -278.628597) (xy 48.000687 -278.587001) (xy 48.037043 -278.550645)
			(xy 48.078639 -278.520424) (xy 48.124451 -278.497081) (xy 48.17335 -278.481193) (xy 48.224132 -278.47315)
			(xy 48.275548 -278.47315) (xy 48.32633 -278.481193) (xy 48.375229 -278.497081) (xy 48.421041 -278.520424)
			(xy 48.462637 -278.550645) (xy 48.498993 -278.587001) (xy 48.529214 -278.628597) (xy 48.552557 -278.674409)
			(xy 48.568445 -278.723308) (xy 48.576488 -278.77409) (xy 48.576992 -278.799798) (xy 48.893996 -278.799798)
			(xy 48.897956 -278.750744) (xy 48.909733 -278.70296) (xy 48.929024 -278.657684) (xy 48.955327 -278.616088)
			(xy 48.987962 -278.579251) (xy 49.026083 -278.548126) (xy 49.068704 -278.523519) (xy 49.11472 -278.506067)
			(xy 49.162939 -278.496223) (xy 49.212114 -278.494242) (xy 49.260969 -278.500174) (xy 49.30824 -278.513866)
			(xy 49.352702 -278.534964) (xy 49.393205 -278.56292) (xy 49.428698 -278.597012) (xy 49.458263 -278.636356)
			(xy 49.481134 -278.679933) (xy 49.496718 -278.726614) (xy 49.504613 -278.775191) (xy 49.505108 -278.799798)
			(xy 49.504613 -278.824405) (xy 49.504434 -278.825506) (xy 49.823112 -278.825506) (xy 49.823112 -278.77409)
			(xy 49.831155 -278.723308) (xy 49.847043 -278.674409) (xy 49.870386 -278.628597) (xy 49.900607 -278.587001)
			(xy 49.936963 -278.550645) (xy 49.978559 -278.520424) (xy 50.024371 -278.497081) (xy 50.07327 -278.481193)
			(xy 50.124052 -278.47315) (xy 50.175468 -278.47315) (xy 50.22625 -278.481193) (xy 50.275149 -278.497081)
			(xy 50.320961 -278.520424) (xy 50.362557 -278.550645) (xy 50.398913 -278.587001) (xy 50.429134 -278.628597)
			(xy 50.452477 -278.674409) (xy 50.468365 -278.723308) (xy 50.476408 -278.77409) (xy 50.476912 -278.799798)
			(xy 50.79417 -278.799798) (xy 50.79813 -278.750744) (xy 50.809907 -278.70296) (xy 50.829198 -278.657684)
			(xy 50.855501 -278.616088) (xy 50.888136 -278.579251) (xy 50.926257 -278.548126) (xy 50.968878 -278.523519)
			(xy 51.014894 -278.506067) (xy 51.063113 -278.496223) (xy 51.112288 -278.494242) (xy 51.161143 -278.500174)
			(xy 51.208414 -278.513866) (xy 51.252876 -278.534964) (xy 51.293379 -278.56292) (xy 51.328872 -278.597012)
			(xy 51.358437 -278.636356) (xy 51.381308 -278.679933) (xy 51.396892 -278.726614) (xy 51.404787 -278.775191)
			(xy 51.405282 -278.799798) (xy 51.404787 -278.824405) (xy 51.404608 -278.825506) (xy 51.723286 -278.825506)
			(xy 51.723286 -278.77409) (xy 51.731329 -278.723308) (xy 51.747217 -278.674409) (xy 51.77056 -278.628597)
			(xy 51.800781 -278.587001) (xy 51.837137 -278.550645) (xy 51.878733 -278.520424) (xy 51.924545 -278.497081)
			(xy 51.973444 -278.481193) (xy 52.024226 -278.47315) (xy 52.075642 -278.47315) (xy 52.126424 -278.481193)
			(xy 52.175323 -278.497081) (xy 52.221135 -278.520424) (xy 52.262731 -278.550645) (xy 52.299087 -278.587001)
			(xy 52.329308 -278.628597) (xy 52.352651 -278.674409) (xy 52.368539 -278.723308) (xy 52.376582 -278.77409)
			(xy 52.377086 -278.799798) (xy 52.69409 -278.799798) (xy 52.69805 -278.750744) (xy 52.709827 -278.70296)
			(xy 52.729118 -278.657684) (xy 52.755421 -278.616088) (xy 52.788056 -278.579251) (xy 52.826177 -278.548126)
			(xy 52.868798 -278.523519) (xy 52.914814 -278.506067) (xy 52.963033 -278.496223) (xy 53.012208 -278.494242)
			(xy 53.061063 -278.500174) (xy 53.108334 -278.513866) (xy 53.152796 -278.534964) (xy 53.193299 -278.56292)
			(xy 53.228792 -278.597012) (xy 53.258357 -278.636356) (xy 53.281228 -278.679933) (xy 53.296812 -278.726614)
			(xy 53.304707 -278.775191) (xy 53.305202 -278.799798) (xy 53.304707 -278.824405) (xy 53.304528 -278.825506)
			(xy 53.623206 -278.825506) (xy 53.623206 -278.77409) (xy 53.631249 -278.723308) (xy 53.647137 -278.674409)
			(xy 53.67048 -278.628597) (xy 53.700701 -278.587001) (xy 53.737057 -278.550645) (xy 53.778653 -278.520424)
			(xy 53.824465 -278.497081) (xy 53.873364 -278.481193) (xy 53.924146 -278.47315) (xy 53.975562 -278.47315)
			(xy 54.026344 -278.481193) (xy 54.075243 -278.497081) (xy 54.121055 -278.520424) (xy 54.162651 -278.550645)
			(xy 54.199007 -278.587001) (xy 54.229228 -278.628597) (xy 54.252571 -278.674409) (xy 54.268459 -278.723308)
			(xy 54.276502 -278.77409) (xy 54.277006 -278.799798) (xy 54.59401 -278.799798) (xy 54.59797 -278.750744)
			(xy 54.609747 -278.70296) (xy 54.629038 -278.657684) (xy 54.655341 -278.616088) (xy 54.687976 -278.579251)
			(xy 54.726097 -278.548126) (xy 54.768718 -278.523519) (xy 54.814734 -278.506067) (xy 54.862953 -278.496223)
			(xy 54.912128 -278.494242) (xy 54.960983 -278.500174) (xy 55.008254 -278.513866) (xy 55.052716 -278.534964)
			(xy 55.093219 -278.56292) (xy 55.128712 -278.597012) (xy 55.158277 -278.636356) (xy 55.181148 -278.679933)
			(xy 55.196732 -278.726614) (xy 55.204627 -278.775191) (xy 55.205122 -278.799798) (xy 55.204627 -278.824405)
			(xy 55.204448 -278.825506) (xy 55.523126 -278.825506) (xy 55.523126 -278.77409) (xy 55.531169 -278.723308)
			(xy 55.547057 -278.674409) (xy 55.5704 -278.628597) (xy 55.600621 -278.587001) (xy 55.636977 -278.550645)
			(xy 55.678573 -278.520424) (xy 55.724385 -278.497081) (xy 55.773284 -278.481193) (xy 55.824066 -278.47315)
			(xy 55.875482 -278.47315) (xy 55.926264 -278.481193) (xy 55.975163 -278.497081) (xy 56.020975 -278.520424)
			(xy 56.062571 -278.550645) (xy 56.098927 -278.587001) (xy 56.129148 -278.628597) (xy 56.152491 -278.674409)
			(xy 56.168379 -278.723308) (xy 56.176422 -278.77409) (xy 56.176926 -278.799798) (xy 56.494184 -278.799798)
			(xy 56.498144 -278.750744) (xy 56.509921 -278.70296) (xy 56.529212 -278.657684) (xy 56.555515 -278.616088)
			(xy 56.58815 -278.579251) (xy 56.626271 -278.548126) (xy 56.668892 -278.523519) (xy 56.714908 -278.506067)
			(xy 56.763127 -278.496223) (xy 56.812302 -278.494242) (xy 56.861157 -278.500174) (xy 56.908428 -278.513866)
			(xy 56.95289 -278.534964) (xy 56.993393 -278.56292) (xy 57.028886 -278.597012) (xy 57.058451 -278.636356)
			(xy 57.081322 -278.679933) (xy 57.096906 -278.726614) (xy 57.104801 -278.775191) (xy 57.105296 -278.799798)
			(xy 57.104801 -278.824405) (xy 57.104622 -278.825506) (xy 57.4233 -278.825506) (xy 57.4233 -278.77409)
			(xy 57.431343 -278.723308) (xy 57.447231 -278.674409) (xy 57.470574 -278.628597) (xy 57.500795 -278.587001)
			(xy 57.537151 -278.550645) (xy 57.578747 -278.520424) (xy 57.624559 -278.497081) (xy 57.673458 -278.481193)
			(xy 57.72424 -278.47315) (xy 57.775656 -278.47315) (xy 57.826438 -278.481193) (xy 57.875337 -278.497081)
			(xy 57.921149 -278.520424) (xy 57.962745 -278.550645) (xy 57.999101 -278.587001) (xy 58.029322 -278.628597)
			(xy 58.052665 -278.674409) (xy 58.068553 -278.723308) (xy 58.076596 -278.77409) (xy 58.0771 -278.799798)
			(xy 58.394104 -278.799798) (xy 58.398064 -278.750744) (xy 58.409841 -278.70296) (xy 58.429132 -278.657684)
			(xy 58.455435 -278.616088) (xy 58.48807 -278.579251) (xy 58.526191 -278.548126) (xy 58.568812 -278.523519)
			(xy 58.614828 -278.506067) (xy 58.663047 -278.496223) (xy 58.712222 -278.494242) (xy 58.761077 -278.500174)
			(xy 58.808348 -278.513866) (xy 58.85281 -278.534964) (xy 58.893313 -278.56292) (xy 58.928806 -278.597012)
			(xy 58.958371 -278.636356) (xy 58.981242 -278.679933) (xy 58.996826 -278.726614) (xy 59.004721 -278.775191)
			(xy 59.005216 -278.799798) (xy 59.004721 -278.824405) (xy 59.004542 -278.825506) (xy 59.322966 -278.825506)
			(xy 59.322966 -278.77409) (xy 59.331009 -278.723308) (xy 59.346897 -278.674409) (xy 59.37024 -278.628597)
			(xy 59.400461 -278.587001) (xy 59.436817 -278.550645) (xy 59.478413 -278.520424) (xy 59.524225 -278.497081)
			(xy 59.573124 -278.481193) (xy 59.623906 -278.47315) (xy 59.675322 -278.47315) (xy 59.726104 -278.481193)
			(xy 59.775003 -278.497081) (xy 59.820815 -278.520424) (xy 59.862411 -278.550645) (xy 59.898767 -278.587001)
			(xy 59.928988 -278.628597) (xy 59.952331 -278.674409) (xy 59.968219 -278.723308) (xy 59.976262 -278.77409)
			(xy 59.976766 -278.799798) (xy 60.294024 -278.799798) (xy 60.297984 -278.750744) (xy 60.309761 -278.70296)
			(xy 60.329052 -278.657684) (xy 60.355355 -278.616088) (xy 60.38799 -278.579251) (xy 60.426111 -278.548126)
			(xy 60.468732 -278.523519) (xy 60.514748 -278.506067) (xy 60.562967 -278.496223) (xy 60.612142 -278.494242)
			(xy 60.660997 -278.500174) (xy 60.708268 -278.513866) (xy 60.75273 -278.534964) (xy 60.793233 -278.56292)
			(xy 60.828726 -278.597012) (xy 60.858291 -278.636356) (xy 60.881162 -278.679933) (xy 60.896746 -278.726614)
			(xy 60.904641 -278.775191) (xy 60.905136 -278.799798) (xy 60.904641 -278.824405) (xy 60.904462 -278.825506)
			(xy 61.222886 -278.825506) (xy 61.222886 -278.77409) (xy 61.230929 -278.723308) (xy 61.246817 -278.674409)
			(xy 61.27016 -278.628597) (xy 61.300381 -278.587001) (xy 61.336737 -278.550645) (xy 61.378333 -278.520424)
			(xy 61.424145 -278.497081) (xy 61.473044 -278.481193) (xy 61.523826 -278.47315) (xy 61.575242 -278.47315)
			(xy 61.626024 -278.481193) (xy 61.674923 -278.497081) (xy 61.720735 -278.520424) (xy 61.762331 -278.550645)
			(xy 61.798687 -278.587001) (xy 61.828908 -278.628597) (xy 61.852251 -278.674409) (xy 61.868139 -278.723308)
			(xy 61.876182 -278.77409) (xy 61.876686 -278.799798) (xy 62.193944 -278.799798) (xy 62.197904 -278.750744)
			(xy 62.209681 -278.70296) (xy 62.228972 -278.657684) (xy 62.255275 -278.616088) (xy 62.28791 -278.579251)
			(xy 62.326031 -278.548126) (xy 62.368652 -278.523519) (xy 62.414668 -278.506067) (xy 62.462887 -278.496223)
			(xy 62.512062 -278.494242) (xy 62.560917 -278.500174) (xy 62.608188 -278.513866) (xy 62.65265 -278.534964)
			(xy 62.693153 -278.56292) (xy 62.728646 -278.597012) (xy 62.758211 -278.636356) (xy 62.781082 -278.679933)
			(xy 62.796666 -278.726614) (xy 62.804561 -278.775191) (xy 62.805056 -278.799798) (xy 62.804561 -278.824405)
			(xy 62.804382 -278.825506) (xy 63.12306 -278.825506) (xy 63.12306 -278.77409) (xy 63.131103 -278.723308)
			(xy 63.146991 -278.674409) (xy 63.170334 -278.628597) (xy 63.200555 -278.587001) (xy 63.236911 -278.550645)
			(xy 63.278507 -278.520424) (xy 63.324319 -278.497081) (xy 63.373218 -278.481193) (xy 63.424 -278.47315)
			(xy 63.475416 -278.47315) (xy 63.526198 -278.481193) (xy 63.575097 -278.497081) (xy 63.620909 -278.520424)
			(xy 63.662505 -278.550645) (xy 63.698861 -278.587001) (xy 63.729082 -278.628597) (xy 63.752425 -278.674409)
			(xy 63.768313 -278.723308) (xy 63.776356 -278.77409) (xy 63.77686 -278.799798) (xy 64.094118 -278.799798)
			(xy 64.098078 -278.750744) (xy 64.109855 -278.70296) (xy 64.129146 -278.657684) (xy 64.155449 -278.616088)
			(xy 64.188084 -278.579251) (xy 64.226205 -278.548126) (xy 64.268826 -278.523519) (xy 64.314842 -278.506067)
			(xy 64.363061 -278.496223) (xy 64.412236 -278.494242) (xy 64.461091 -278.500174) (xy 64.508362 -278.513866)
			(xy 64.552824 -278.534964) (xy 64.593327 -278.56292) (xy 64.62882 -278.597012) (xy 64.658385 -278.636356)
			(xy 64.681256 -278.679933) (xy 64.69684 -278.726614) (xy 64.704735 -278.775191) (xy 64.70523 -278.799798)
			(xy 64.704735 -278.824405) (xy 64.704556 -278.825506) (xy 65.02298 -278.825506) (xy 65.02298 -278.77409)
			(xy 65.031023 -278.723308) (xy 65.046911 -278.674409) (xy 65.070254 -278.628597) (xy 65.100475 -278.587001)
			(xy 65.136831 -278.550645) (xy 65.178427 -278.520424) (xy 65.224239 -278.497081) (xy 65.273138 -278.481193)
			(xy 65.32392 -278.47315) (xy 65.375336 -278.47315) (xy 65.426118 -278.481193) (xy 65.475017 -278.497081)
			(xy 65.520829 -278.520424) (xy 65.562425 -278.550645) (xy 65.598781 -278.587001) (xy 65.629002 -278.628597)
			(xy 65.652345 -278.674409) (xy 65.668233 -278.723308) (xy 65.676276 -278.77409) (xy 65.67678 -278.799798)
			(xy 65.994038 -278.799798) (xy 65.997998 -278.750744) (xy 66.009775 -278.70296) (xy 66.029066 -278.657684)
			(xy 66.055369 -278.616088) (xy 66.088004 -278.579251) (xy 66.126125 -278.548126) (xy 66.168746 -278.523519)
			(xy 66.214762 -278.506067) (xy 66.262981 -278.496223) (xy 66.312156 -278.494242) (xy 66.361011 -278.500174)
			(xy 66.408282 -278.513866) (xy 66.452744 -278.534964) (xy 66.493247 -278.56292) (xy 66.52874 -278.597012)
			(xy 66.558305 -278.636356) (xy 66.581176 -278.679933) (xy 66.59676 -278.726614) (xy 66.604655 -278.775191)
			(xy 66.60515 -278.799798) (xy 66.604655 -278.824405) (xy 66.604476 -278.825506) (xy 66.9229 -278.825506)
			(xy 66.9229 -278.77409) (xy 66.930943 -278.723308) (xy 66.946831 -278.674409) (xy 66.970174 -278.628597)
			(xy 67.000395 -278.587001) (xy 67.036751 -278.550645) (xy 67.078347 -278.520424) (xy 67.124159 -278.497081)
			(xy 67.173058 -278.481193) (xy 67.22384 -278.47315) (xy 67.275256 -278.47315) (xy 67.326038 -278.481193)
			(xy 67.374937 -278.497081) (xy 67.420749 -278.520424) (xy 67.462345 -278.550645) (xy 67.498701 -278.587001)
			(xy 67.528922 -278.628597) (xy 67.552265 -278.674409) (xy 67.568153 -278.723308) (xy 67.576196 -278.77409)
			(xy 67.5767 -278.799798) (xy 67.893958 -278.799798) (xy 67.897918 -278.750744) (xy 67.909695 -278.70296)
			(xy 67.928986 -278.657684) (xy 67.955289 -278.616088) (xy 67.987924 -278.579251) (xy 68.026045 -278.548126)
			(xy 68.068666 -278.523519) (xy 68.114682 -278.506067) (xy 68.162901 -278.496223) (xy 68.212076 -278.494242)
			(xy 68.260931 -278.500174) (xy 68.308202 -278.513866) (xy 68.352664 -278.534964) (xy 68.393167 -278.56292)
			(xy 68.42866 -278.597012) (xy 68.458225 -278.636356) (xy 68.481096 -278.679933) (xy 68.49668 -278.726614)
			(xy 68.504575 -278.775191) (xy 68.50507 -278.799798) (xy 68.504575 -278.824405) (xy 68.504396 -278.825506)
			(xy 68.823074 -278.825506) (xy 68.823074 -278.77409) (xy 68.831117 -278.723308) (xy 68.847005 -278.674409)
			(xy 68.870348 -278.628597) (xy 68.900569 -278.587001) (xy 68.936925 -278.550645) (xy 68.978521 -278.520424)
			(xy 69.024333 -278.497081) (xy 69.073232 -278.481193) (xy 69.124014 -278.47315) (xy 69.17543 -278.47315)
			(xy 69.226212 -278.481193) (xy 69.275111 -278.497081) (xy 69.320923 -278.520424) (xy 69.362519 -278.550645)
			(xy 69.398875 -278.587001) (xy 69.429096 -278.628597) (xy 69.452439 -278.674409) (xy 69.468327 -278.723308)
			(xy 69.47637 -278.77409) (xy 69.476874 -278.799798) (xy 69.794132 -278.799798) (xy 69.798092 -278.750744)
			(xy 69.809869 -278.70296) (xy 69.82916 -278.657684) (xy 69.855463 -278.616088) (xy 69.888098 -278.579251)
			(xy 69.926219 -278.548126) (xy 69.96884 -278.523519) (xy 70.014856 -278.506067) (xy 70.063075 -278.496223)
			(xy 70.11225 -278.494242) (xy 70.161105 -278.500174) (xy 70.208376 -278.513866) (xy 70.252838 -278.534964)
			(xy 70.293341 -278.56292) (xy 70.328834 -278.597012) (xy 70.358399 -278.636356) (xy 70.38127 -278.679933)
			(xy 70.396854 -278.726614) (xy 70.404749 -278.775191) (xy 70.405244 -278.799798) (xy 70.404749 -278.824405)
			(xy 70.40457 -278.825506) (xy 70.722994 -278.825506) (xy 70.722994 -278.77409) (xy 70.731037 -278.723308)
			(xy 70.746925 -278.674409) (xy 70.770268 -278.628597) (xy 70.800489 -278.587001) (xy 70.836845 -278.550645)
			(xy 70.878441 -278.520424) (xy 70.924253 -278.497081) (xy 70.973152 -278.481193) (xy 71.023934 -278.47315)
			(xy 71.07535 -278.47315) (xy 71.126132 -278.481193) (xy 71.175031 -278.497081) (xy 71.220843 -278.520424)
			(xy 71.262439 -278.550645) (xy 71.298795 -278.587001) (xy 71.329016 -278.628597) (xy 71.352359 -278.674409)
			(xy 71.368247 -278.723308) (xy 71.37629 -278.77409) (xy 71.376794 -278.799798) (xy 71.694052 -278.799798)
			(xy 71.698012 -278.750744) (xy 71.709789 -278.70296) (xy 71.72908 -278.657684) (xy 71.755383 -278.616088)
			(xy 71.788018 -278.579251) (xy 71.826139 -278.548126) (xy 71.86876 -278.523519) (xy 71.914776 -278.506067)
			(xy 71.962995 -278.496223) (xy 72.01217 -278.494242) (xy 72.061025 -278.500174) (xy 72.108296 -278.513866)
			(xy 72.152758 -278.534964) (xy 72.193261 -278.56292) (xy 72.228754 -278.597012) (xy 72.258319 -278.636356)
			(xy 72.28119 -278.679933) (xy 72.296774 -278.726614) (xy 72.304669 -278.775191) (xy 72.305164 -278.799798)
			(xy 72.304669 -278.824405) (xy 72.30449 -278.825506) (xy 72.622914 -278.825506) (xy 72.622914 -278.77409)
			(xy 72.630957 -278.723308) (xy 72.646845 -278.674409) (xy 72.670188 -278.628597) (xy 72.700409 -278.587001)
			(xy 72.736765 -278.550645) (xy 72.778361 -278.520424) (xy 72.824173 -278.497081) (xy 72.873072 -278.481193)
			(xy 72.923854 -278.47315) (xy 72.97527 -278.47315) (xy 73.026052 -278.481193) (xy 73.074951 -278.497081)
			(xy 73.120763 -278.520424) (xy 73.162359 -278.550645) (xy 73.198715 -278.587001) (xy 73.228936 -278.628597)
			(xy 73.252279 -278.674409) (xy 73.268167 -278.723308) (xy 73.27621 -278.77409) (xy 73.276714 -278.799798)
			(xy 73.593972 -278.799798) (xy 73.597932 -278.750744) (xy 73.609709 -278.70296) (xy 73.629 -278.657684)
			(xy 73.655303 -278.616088) (xy 73.687938 -278.579251) (xy 73.726059 -278.548126) (xy 73.76868 -278.523519)
			(xy 73.814696 -278.506067) (xy 73.862915 -278.496223) (xy 73.91209 -278.494242) (xy 73.960945 -278.500174)
			(xy 74.008216 -278.513866) (xy 74.052678 -278.534964) (xy 74.093181 -278.56292) (xy 74.128674 -278.597012)
			(xy 74.158239 -278.636356) (xy 74.18111 -278.679933) (xy 74.196694 -278.726614) (xy 74.204589 -278.775191)
			(xy 74.205084 -278.799798) (xy 74.204589 -278.824405) (xy 74.20441 -278.825506) (xy 74.523088 -278.825506)
			(xy 74.523088 -278.77409) (xy 74.531131 -278.723308) (xy 74.547019 -278.674409) (xy 74.570362 -278.628597)
			(xy 74.600583 -278.587001) (xy 74.636939 -278.550645) (xy 74.678535 -278.520424) (xy 74.724347 -278.497081)
			(xy 74.773246 -278.481193) (xy 74.824028 -278.47315) (xy 74.875444 -278.47315) (xy 74.926226 -278.481193)
			(xy 74.975125 -278.497081) (xy 75.020937 -278.520424) (xy 75.062533 -278.550645) (xy 75.098889 -278.587001)
			(xy 75.12911 -278.628597) (xy 75.152453 -278.674409) (xy 75.168341 -278.723308) (xy 75.176384 -278.77409)
			(xy 75.176888 -278.799798) (xy 75.494146 -278.799798) (xy 75.498106 -278.750744) (xy 75.509883 -278.70296)
			(xy 75.529174 -278.657684) (xy 75.555477 -278.616088) (xy 75.588112 -278.579251) (xy 75.626233 -278.548126)
			(xy 75.668854 -278.523519) (xy 75.71487 -278.506067) (xy 75.763089 -278.496223) (xy 75.812264 -278.494242)
			(xy 75.861119 -278.500174) (xy 75.90839 -278.513866) (xy 75.952852 -278.534964) (xy 75.993355 -278.56292)
			(xy 76.028848 -278.597012) (xy 76.058413 -278.636356) (xy 76.081284 -278.679933) (xy 76.096868 -278.726614)
			(xy 76.104763 -278.775191) (xy 76.105258 -278.799798) (xy 76.104763 -278.824405) (xy 76.104584 -278.825506)
			(xy 76.423008 -278.825506) (xy 76.423008 -278.77409) (xy 76.431051 -278.723308) (xy 76.446939 -278.674409)
			(xy 76.470282 -278.628597) (xy 76.500503 -278.587001) (xy 76.536859 -278.550645) (xy 76.578455 -278.520424)
			(xy 76.624267 -278.497081) (xy 76.673166 -278.481193) (xy 76.723948 -278.47315) (xy 76.775364 -278.47315)
			(xy 76.826146 -278.481193) (xy 76.875045 -278.497081) (xy 76.920857 -278.520424) (xy 76.962453 -278.550645)
			(xy 76.998809 -278.587001) (xy 77.02903 -278.628597) (xy 77.052373 -278.674409) (xy 77.068261 -278.723308)
			(xy 77.076304 -278.77409) (xy 77.076808 -278.799798) (xy 77.394066 -278.799798) (xy 77.398026 -278.750744)
			(xy 77.409803 -278.70296) (xy 77.429094 -278.657684) (xy 77.455397 -278.616088) (xy 77.488032 -278.579251)
			(xy 77.526153 -278.548126) (xy 77.568774 -278.523519) (xy 77.61479 -278.506067) (xy 77.663009 -278.496223)
			(xy 77.712184 -278.494242) (xy 77.761039 -278.500174) (xy 77.80831 -278.513866) (xy 77.852772 -278.534964)
			(xy 77.893275 -278.56292) (xy 77.928768 -278.597012) (xy 77.958333 -278.636356) (xy 77.981204 -278.679933)
			(xy 77.996788 -278.726614) (xy 78.004683 -278.775191) (xy 78.005178 -278.799798) (xy 78.004683 -278.824405)
			(xy 78.004504 -278.825506) (xy 78.322928 -278.825506) (xy 78.322928 -278.77409) (xy 78.330971 -278.723308)
			(xy 78.346859 -278.674409) (xy 78.370202 -278.628597) (xy 78.400423 -278.587001) (xy 78.436779 -278.550645)
			(xy 78.478375 -278.520424) (xy 78.524187 -278.497081) (xy 78.573086 -278.481193) (xy 78.623868 -278.47315)
			(xy 78.675284 -278.47315) (xy 78.726066 -278.481193) (xy 78.774965 -278.497081) (xy 78.820777 -278.520424)
			(xy 78.862373 -278.550645) (xy 78.898729 -278.587001) (xy 78.92895 -278.628597) (xy 78.952293 -278.674409)
			(xy 78.968181 -278.723308) (xy 78.976224 -278.77409) (xy 78.976728 -278.799798) (xy 79.293986 -278.799798)
			(xy 79.297946 -278.750744) (xy 79.309723 -278.70296) (xy 79.329014 -278.657684) (xy 79.355317 -278.616088)
			(xy 79.387952 -278.579251) (xy 79.426073 -278.548126) (xy 79.468694 -278.523519) (xy 79.51471 -278.506067)
			(xy 79.562929 -278.496223) (xy 79.612104 -278.494242) (xy 79.660959 -278.500174) (xy 79.70823 -278.513866)
			(xy 79.752692 -278.534964) (xy 79.793195 -278.56292) (xy 79.828688 -278.597012) (xy 79.858253 -278.636356)
			(xy 79.881124 -278.679933) (xy 79.896708 -278.726614) (xy 79.904603 -278.775191) (xy 79.905098 -278.799798)
			(xy 79.904603 -278.824405) (xy 79.904424 -278.825506) (xy 80.223102 -278.825506) (xy 80.223102 -278.77409)
			(xy 80.231145 -278.723308) (xy 80.247033 -278.674409) (xy 80.270376 -278.628597) (xy 80.300597 -278.587001)
			(xy 80.336953 -278.550645) (xy 80.378549 -278.520424) (xy 80.424361 -278.497081) (xy 80.47326 -278.481193)
			(xy 80.524042 -278.47315) (xy 80.575458 -278.47315) (xy 80.62624 -278.481193) (xy 80.675139 -278.497081)
			(xy 80.720951 -278.520424) (xy 80.762547 -278.550645) (xy 80.798903 -278.587001) (xy 80.829124 -278.628597)
			(xy 80.852467 -278.674409) (xy 80.868355 -278.723308) (xy 80.876398 -278.77409) (xy 80.876902 -278.799798)
			(xy 81.19416 -278.799798) (xy 81.19812 -278.750744) (xy 81.209897 -278.70296) (xy 81.229188 -278.657684)
			(xy 81.255491 -278.616088) (xy 81.288126 -278.579251) (xy 81.326247 -278.548126) (xy 81.368868 -278.523519)
			(xy 81.414884 -278.506067) (xy 81.463103 -278.496223) (xy 81.512278 -278.494242) (xy 81.561133 -278.500174)
			(xy 81.608404 -278.513866) (xy 81.652866 -278.534964) (xy 81.693369 -278.56292) (xy 81.728862 -278.597012)
			(xy 81.758427 -278.636356) (xy 81.781298 -278.679933) (xy 81.796882 -278.726614) (xy 81.804777 -278.775191)
			(xy 81.805272 -278.799798) (xy 82.14412 -278.799798) (xy 82.14808 -278.750744) (xy 82.159857 -278.70296)
			(xy 82.179148 -278.657684) (xy 82.205451 -278.616088) (xy 82.238086 -278.579251) (xy 82.276207 -278.548126)
			(xy 82.318828 -278.523519) (xy 82.364844 -278.506067) (xy 82.413063 -278.496223) (xy 82.462238 -278.494242)
			(xy 82.511093 -278.500174) (xy 82.558364 -278.513866) (xy 82.602826 -278.534964) (xy 82.643329 -278.56292)
			(xy 82.678822 -278.597012) (xy 82.708387 -278.636356) (xy 82.731258 -278.679933) (xy 82.746842 -278.726614)
			(xy 82.754737 -278.775191) (xy 82.755232 -278.799798) (xy 82.754737 -278.824405) (xy 82.746842 -278.872982)
			(xy 82.731258 -278.919663) (xy 82.708387 -278.96324) (xy 82.678822 -279.002584) (xy 82.643329 -279.036676)
			(xy 82.602826 -279.064632) (xy 82.558364 -279.08573) (xy 82.511093 -279.099422) (xy 82.462238 -279.105354)
			(xy 82.413063 -279.103373) (xy 82.364844 -279.093529) (xy 82.318828 -279.076077) (xy 82.276207 -279.05147)
			(xy 82.238086 -279.020345) (xy 82.205451 -278.983508) (xy 82.179148 -278.941912) (xy 82.159857 -278.896636)
			(xy 82.14808 -278.848852) (xy 82.14412 -278.799798) (xy 81.805272 -278.799798) (xy 81.804777 -278.824405)
			(xy 81.796882 -278.872982) (xy 81.781298 -278.919663) (xy 81.758427 -278.96324) (xy 81.728862 -279.002584)
			(xy 81.693369 -279.036676) (xy 81.652866 -279.064632) (xy 81.608404 -279.08573) (xy 81.561133 -279.099422)
			(xy 81.512278 -279.105354) (xy 81.463103 -279.103373) (xy 81.414884 -279.093529) (xy 81.368868 -279.076077)
			(xy 81.326247 -279.05147) (xy 81.288126 -279.020345) (xy 81.255491 -278.983508) (xy 81.229188 -278.941912)
			(xy 81.209897 -278.896636) (xy 81.19812 -278.848852) (xy 81.19416 -278.799798) (xy 80.876902 -278.799798)
			(xy 80.876398 -278.825506) (xy 80.868355 -278.876288) (xy 80.852467 -278.925187) (xy 80.829124 -278.970999)
			(xy 80.798903 -279.012595) (xy 80.762547 -279.048951) (xy 80.720951 -279.079172) (xy 80.675139 -279.102515)
			(xy 80.62624 -279.118403) (xy 80.575458 -279.126446) (xy 80.524042 -279.126446) (xy 80.47326 -279.118403)
			(xy 80.424361 -279.102515) (xy 80.378549 -279.079172) (xy 80.336953 -279.048951) (xy 80.300597 -279.012595)
			(xy 80.270376 -278.970999) (xy 80.247033 -278.925187) (xy 80.231145 -278.876288) (xy 80.223102 -278.825506)
			(xy 79.904424 -278.825506) (xy 79.896708 -278.872982) (xy 79.881124 -278.919663) (xy 79.858253 -278.96324)
			(xy 79.828688 -279.002584) (xy 79.793195 -279.036676) (xy 79.752692 -279.064632) (xy 79.70823 -279.08573)
			(xy 79.660959 -279.099422) (xy 79.612104 -279.105354) (xy 79.562929 -279.103373) (xy 79.51471 -279.093529)
			(xy 79.468694 -279.076077) (xy 79.426073 -279.05147) (xy 79.387952 -279.020345) (xy 79.355317 -278.983508)
			(xy 79.329014 -278.941912) (xy 79.309723 -278.896636) (xy 79.297946 -278.848852) (xy 79.293986 -278.799798)
			(xy 78.976728 -278.799798) (xy 78.976224 -278.825506) (xy 78.968181 -278.876288) (xy 78.952293 -278.925187)
			(xy 78.92895 -278.970999) (xy 78.898729 -279.012595) (xy 78.862373 -279.048951) (xy 78.820777 -279.079172)
			(xy 78.774965 -279.102515) (xy 78.726066 -279.118403) (xy 78.675284 -279.126446) (xy 78.623868 -279.126446)
			(xy 78.573086 -279.118403) (xy 78.524187 -279.102515) (xy 78.478375 -279.079172) (xy 78.436779 -279.048951)
			(xy 78.400423 -279.012595) (xy 78.370202 -278.970999) (xy 78.346859 -278.925187) (xy 78.330971 -278.876288)
			(xy 78.322928 -278.825506) (xy 78.004504 -278.825506) (xy 77.996788 -278.872982) (xy 77.981204 -278.919663)
			(xy 77.958333 -278.96324) (xy 77.928768 -279.002584) (xy 77.893275 -279.036676) (xy 77.852772 -279.064632)
			(xy 77.80831 -279.08573) (xy 77.761039 -279.099422) (xy 77.712184 -279.105354) (xy 77.663009 -279.103373)
			(xy 77.61479 -279.093529) (xy 77.568774 -279.076077) (xy 77.526153 -279.05147) (xy 77.488032 -279.020345)
			(xy 77.455397 -278.983508) (xy 77.429094 -278.941912) (xy 77.409803 -278.896636) (xy 77.398026 -278.848852)
			(xy 77.394066 -278.799798) (xy 77.076808 -278.799798) (xy 77.076304 -278.825506) (xy 77.068261 -278.876288)
			(xy 77.052373 -278.925187) (xy 77.02903 -278.970999) (xy 76.998809 -279.012595) (xy 76.962453 -279.048951)
			(xy 76.920857 -279.079172) (xy 76.875045 -279.102515) (xy 76.826146 -279.118403) (xy 76.775364 -279.126446)
			(xy 76.723948 -279.126446) (xy 76.673166 -279.118403) (xy 76.624267 -279.102515) (xy 76.578455 -279.079172)
			(xy 76.536859 -279.048951) (xy 76.500503 -279.012595) (xy 76.470282 -278.970999) (xy 76.446939 -278.925187)
			(xy 76.431051 -278.876288) (xy 76.423008 -278.825506) (xy 76.104584 -278.825506) (xy 76.096868 -278.872982)
			(xy 76.081284 -278.919663) (xy 76.058413 -278.96324) (xy 76.028848 -279.002584) (xy 75.993355 -279.036676)
			(xy 75.952852 -279.064632) (xy 75.90839 -279.08573) (xy 75.861119 -279.099422) (xy 75.812264 -279.105354)
			(xy 75.763089 -279.103373) (xy 75.71487 -279.093529) (xy 75.668854 -279.076077) (xy 75.626233 -279.05147)
			(xy 75.588112 -279.020345) (xy 75.555477 -278.983508) (xy 75.529174 -278.941912) (xy 75.509883 -278.896636)
			(xy 75.498106 -278.848852) (xy 75.494146 -278.799798) (xy 75.176888 -278.799798) (xy 75.176384 -278.825506)
			(xy 75.168341 -278.876288) (xy 75.152453 -278.925187) (xy 75.12911 -278.970999) (xy 75.098889 -279.012595)
			(xy 75.062533 -279.048951) (xy 75.020937 -279.079172) (xy 74.975125 -279.102515) (xy 74.926226 -279.118403)
			(xy 74.875444 -279.126446) (xy 74.824028 -279.126446) (xy 74.773246 -279.118403) (xy 74.724347 -279.102515)
			(xy 74.678535 -279.079172) (xy 74.636939 -279.048951) (xy 74.600583 -279.012595) (xy 74.570362 -278.970999)
			(xy 74.547019 -278.925187) (xy 74.531131 -278.876288) (xy 74.523088 -278.825506) (xy 74.20441 -278.825506)
			(xy 74.196694 -278.872982) (xy 74.18111 -278.919663) (xy 74.158239 -278.96324) (xy 74.128674 -279.002584)
			(xy 74.093181 -279.036676) (xy 74.052678 -279.064632) (xy 74.008216 -279.08573) (xy 73.960945 -279.099422)
			(xy 73.91209 -279.105354) (xy 73.862915 -279.103373) (xy 73.814696 -279.093529) (xy 73.76868 -279.076077)
			(xy 73.726059 -279.05147) (xy 73.687938 -279.020345) (xy 73.655303 -278.983508) (xy 73.629 -278.941912)
			(xy 73.609709 -278.896636) (xy 73.597932 -278.848852) (xy 73.593972 -278.799798) (xy 73.276714 -278.799798)
			(xy 73.27621 -278.825506) (xy 73.268167 -278.876288) (xy 73.252279 -278.925187) (xy 73.228936 -278.970999)
			(xy 73.198715 -279.012595) (xy 73.162359 -279.048951) (xy 73.120763 -279.079172) (xy 73.074951 -279.102515)
			(xy 73.026052 -279.118403) (xy 72.97527 -279.126446) (xy 72.923854 -279.126446) (xy 72.873072 -279.118403)
			(xy 72.824173 -279.102515) (xy 72.778361 -279.079172) (xy 72.736765 -279.048951) (xy 72.700409 -279.012595)
			(xy 72.670188 -278.970999) (xy 72.646845 -278.925187) (xy 72.630957 -278.876288) (xy 72.622914 -278.825506)
			(xy 72.30449 -278.825506) (xy 72.296774 -278.872982) (xy 72.28119 -278.919663) (xy 72.258319 -278.96324)
			(xy 72.228754 -279.002584) (xy 72.193261 -279.036676) (xy 72.152758 -279.064632) (xy 72.108296 -279.08573)
			(xy 72.061025 -279.099422) (xy 72.01217 -279.105354) (xy 71.962995 -279.103373) (xy 71.914776 -279.093529)
			(xy 71.86876 -279.076077) (xy 71.826139 -279.05147) (xy 71.788018 -279.020345) (xy 71.755383 -278.983508)
			(xy 71.72908 -278.941912) (xy 71.709789 -278.896636) (xy 71.698012 -278.848852) (xy 71.694052 -278.799798)
			(xy 71.376794 -278.799798) (xy 71.37629 -278.825506) (xy 71.368247 -278.876288) (xy 71.352359 -278.925187)
			(xy 71.329016 -278.970999) (xy 71.298795 -279.012595) (xy 71.262439 -279.048951) (xy 71.220843 -279.079172)
			(xy 71.175031 -279.102515) (xy 71.126132 -279.118403) (xy 71.07535 -279.126446) (xy 71.023934 -279.126446)
			(xy 70.973152 -279.118403) (xy 70.924253 -279.102515) (xy 70.878441 -279.079172) (xy 70.836845 -279.048951)
			(xy 70.800489 -279.012595) (xy 70.770268 -278.970999) (xy 70.746925 -278.925187) (xy 70.731037 -278.876288)
			(xy 70.722994 -278.825506) (xy 70.40457 -278.825506) (xy 70.396854 -278.872982) (xy 70.38127 -278.919663)
			(xy 70.358399 -278.96324) (xy 70.328834 -279.002584) (xy 70.293341 -279.036676) (xy 70.252838 -279.064632)
			(xy 70.208376 -279.08573) (xy 70.161105 -279.099422) (xy 70.11225 -279.105354) (xy 70.063075 -279.103373)
			(xy 70.014856 -279.093529) (xy 69.96884 -279.076077) (xy 69.926219 -279.05147) (xy 69.888098 -279.020345)
			(xy 69.855463 -278.983508) (xy 69.82916 -278.941912) (xy 69.809869 -278.896636) (xy 69.798092 -278.848852)
			(xy 69.794132 -278.799798) (xy 69.476874 -278.799798) (xy 69.47637 -278.825506) (xy 69.468327 -278.876288)
			(xy 69.452439 -278.925187) (xy 69.429096 -278.970999) (xy 69.398875 -279.012595) (xy 69.362519 -279.048951)
			(xy 69.320923 -279.079172) (xy 69.275111 -279.102515) (xy 69.226212 -279.118403) (xy 69.17543 -279.126446)
			(xy 69.124014 -279.126446) (xy 69.073232 -279.118403) (xy 69.024333 -279.102515) (xy 68.978521 -279.079172)
			(xy 68.936925 -279.048951) (xy 68.900569 -279.012595) (xy 68.870348 -278.970999) (xy 68.847005 -278.925187)
			(xy 68.831117 -278.876288) (xy 68.823074 -278.825506) (xy 68.504396 -278.825506) (xy 68.49668 -278.872982)
			(xy 68.481096 -278.919663) (xy 68.458225 -278.96324) (xy 68.42866 -279.002584) (xy 68.393167 -279.036676)
			(xy 68.352664 -279.064632) (xy 68.308202 -279.08573) (xy 68.260931 -279.099422) (xy 68.212076 -279.105354)
			(xy 68.162901 -279.103373) (xy 68.114682 -279.093529) (xy 68.068666 -279.076077) (xy 68.026045 -279.05147)
			(xy 67.987924 -279.020345) (xy 67.955289 -278.983508) (xy 67.928986 -278.941912) (xy 67.909695 -278.896636)
			(xy 67.897918 -278.848852) (xy 67.893958 -278.799798) (xy 67.5767 -278.799798) (xy 67.576196 -278.825506)
			(xy 67.568153 -278.876288) (xy 67.552265 -278.925187) (xy 67.528922 -278.970999) (xy 67.498701 -279.012595)
			(xy 67.462345 -279.048951) (xy 67.420749 -279.079172) (xy 67.374937 -279.102515) (xy 67.326038 -279.118403)
			(xy 67.275256 -279.126446) (xy 67.22384 -279.126446) (xy 67.173058 -279.118403) (xy 67.124159 -279.102515)
			(xy 67.078347 -279.079172) (xy 67.036751 -279.048951) (xy 67.000395 -279.012595) (xy 66.970174 -278.970999)
			(xy 66.946831 -278.925187) (xy 66.930943 -278.876288) (xy 66.9229 -278.825506) (xy 66.604476 -278.825506)
			(xy 66.59676 -278.872982) (xy 66.581176 -278.919663) (xy 66.558305 -278.96324) (xy 66.52874 -279.002584)
			(xy 66.493247 -279.036676) (xy 66.452744 -279.064632) (xy 66.408282 -279.08573) (xy 66.361011 -279.099422)
			(xy 66.312156 -279.105354) (xy 66.262981 -279.103373) (xy 66.214762 -279.093529) (xy 66.168746 -279.076077)
			(xy 66.126125 -279.05147) (xy 66.088004 -279.020345) (xy 66.055369 -278.983508) (xy 66.029066 -278.941912)
			(xy 66.009775 -278.896636) (xy 65.997998 -278.848852) (xy 65.994038 -278.799798) (xy 65.67678 -278.799798)
			(xy 65.676276 -278.825506) (xy 65.668233 -278.876288) (xy 65.652345 -278.925187) (xy 65.629002 -278.970999)
			(xy 65.598781 -279.012595) (xy 65.562425 -279.048951) (xy 65.520829 -279.079172) (xy 65.475017 -279.102515)
			(xy 65.426118 -279.118403) (xy 65.375336 -279.126446) (xy 65.32392 -279.126446) (xy 65.273138 -279.118403)
			(xy 65.224239 -279.102515) (xy 65.178427 -279.079172) (xy 65.136831 -279.048951) (xy 65.100475 -279.012595)
			(xy 65.070254 -278.970999) (xy 65.046911 -278.925187) (xy 65.031023 -278.876288) (xy 65.02298 -278.825506)
			(xy 64.704556 -278.825506) (xy 64.69684 -278.872982) (xy 64.681256 -278.919663) (xy 64.658385 -278.96324)
			(xy 64.62882 -279.002584) (xy 64.593327 -279.036676) (xy 64.552824 -279.064632) (xy 64.508362 -279.08573)
			(xy 64.461091 -279.099422) (xy 64.412236 -279.105354) (xy 64.363061 -279.103373) (xy 64.314842 -279.093529)
			(xy 64.268826 -279.076077) (xy 64.226205 -279.05147) (xy 64.188084 -279.020345) (xy 64.155449 -278.983508)
			(xy 64.129146 -278.941912) (xy 64.109855 -278.896636) (xy 64.098078 -278.848852) (xy 64.094118 -278.799798)
			(xy 63.77686 -278.799798) (xy 63.776356 -278.825506) (xy 63.768313 -278.876288) (xy 63.752425 -278.925187)
			(xy 63.729082 -278.970999) (xy 63.698861 -279.012595) (xy 63.662505 -279.048951) (xy 63.620909 -279.079172)
			(xy 63.575097 -279.102515) (xy 63.526198 -279.118403) (xy 63.475416 -279.126446) (xy 63.424 -279.126446)
			(xy 63.373218 -279.118403) (xy 63.324319 -279.102515) (xy 63.278507 -279.079172) (xy 63.236911 -279.048951)
			(xy 63.200555 -279.012595) (xy 63.170334 -278.970999) (xy 63.146991 -278.925187) (xy 63.131103 -278.876288)
			(xy 63.12306 -278.825506) (xy 62.804382 -278.825506) (xy 62.796666 -278.872982) (xy 62.781082 -278.919663)
			(xy 62.758211 -278.96324) (xy 62.728646 -279.002584) (xy 62.693153 -279.036676) (xy 62.65265 -279.064632)
			(xy 62.608188 -279.08573) (xy 62.560917 -279.099422) (xy 62.512062 -279.105354) (xy 62.462887 -279.103373)
			(xy 62.414668 -279.093529) (xy 62.368652 -279.076077) (xy 62.326031 -279.05147) (xy 62.28791 -279.020345)
			(xy 62.255275 -278.983508) (xy 62.228972 -278.941912) (xy 62.209681 -278.896636) (xy 62.197904 -278.848852)
			(xy 62.193944 -278.799798) (xy 61.876686 -278.799798) (xy 61.876182 -278.825506) (xy 61.868139 -278.876288)
			(xy 61.852251 -278.925187) (xy 61.828908 -278.970999) (xy 61.798687 -279.012595) (xy 61.762331 -279.048951)
			(xy 61.720735 -279.079172) (xy 61.674923 -279.102515) (xy 61.626024 -279.118403) (xy 61.575242 -279.126446)
			(xy 61.523826 -279.126446) (xy 61.473044 -279.118403) (xy 61.424145 -279.102515) (xy 61.378333 -279.079172)
			(xy 61.336737 -279.048951) (xy 61.300381 -279.012595) (xy 61.27016 -278.970999) (xy 61.246817 -278.925187)
			(xy 61.230929 -278.876288) (xy 61.222886 -278.825506) (xy 60.904462 -278.825506) (xy 60.896746 -278.872982)
			(xy 60.881162 -278.919663) (xy 60.858291 -278.96324) (xy 60.828726 -279.002584) (xy 60.793233 -279.036676)
			(xy 60.75273 -279.064632) (xy 60.708268 -279.08573) (xy 60.660997 -279.099422) (xy 60.612142 -279.105354)
			(xy 60.562967 -279.103373) (xy 60.514748 -279.093529) (xy 60.468732 -279.076077) (xy 60.426111 -279.05147)
			(xy 60.38799 -279.020345) (xy 60.355355 -278.983508) (xy 60.329052 -278.941912) (xy 60.309761 -278.896636)
			(xy 60.297984 -278.848852) (xy 60.294024 -278.799798) (xy 59.976766 -278.799798) (xy 59.976262 -278.825506)
			(xy 59.968219 -278.876288) (xy 59.952331 -278.925187) (xy 59.928988 -278.970999) (xy 59.898767 -279.012595)
			(xy 59.862411 -279.048951) (xy 59.820815 -279.079172) (xy 59.775003 -279.102515) (xy 59.726104 -279.118403)
			(xy 59.675322 -279.126446) (xy 59.623906 -279.126446) (xy 59.573124 -279.118403) (xy 59.524225 -279.102515)
			(xy 59.478413 -279.079172) (xy 59.436817 -279.048951) (xy 59.400461 -279.012595) (xy 59.37024 -278.970999)
			(xy 59.346897 -278.925187) (xy 59.331009 -278.876288) (xy 59.322966 -278.825506) (xy 59.004542 -278.825506)
			(xy 58.996826 -278.872982) (xy 58.981242 -278.919663) (xy 58.958371 -278.96324) (xy 58.928806 -279.002584)
			(xy 58.893313 -279.036676) (xy 58.85281 -279.064632) (xy 58.808348 -279.08573) (xy 58.761077 -279.099422)
			(xy 58.712222 -279.105354) (xy 58.663047 -279.103373) (xy 58.614828 -279.093529) (xy 58.568812 -279.076077)
			(xy 58.526191 -279.05147) (xy 58.48807 -279.020345) (xy 58.455435 -278.983508) (xy 58.429132 -278.941912)
			(xy 58.409841 -278.896636) (xy 58.398064 -278.848852) (xy 58.394104 -278.799798) (xy 58.0771 -278.799798)
			(xy 58.076596 -278.825506) (xy 58.068553 -278.876288) (xy 58.052665 -278.925187) (xy 58.029322 -278.970999)
			(xy 57.999101 -279.012595) (xy 57.962745 -279.048951) (xy 57.921149 -279.079172) (xy 57.875337 -279.102515)
			(xy 57.826438 -279.118403) (xy 57.775656 -279.126446) (xy 57.72424 -279.126446) (xy 57.673458 -279.118403)
			(xy 57.624559 -279.102515) (xy 57.578747 -279.079172) (xy 57.537151 -279.048951) (xy 57.500795 -279.012595)
			(xy 57.470574 -278.970999) (xy 57.447231 -278.925187) (xy 57.431343 -278.876288) (xy 57.4233 -278.825506)
			(xy 57.104622 -278.825506) (xy 57.096906 -278.872982) (xy 57.081322 -278.919663) (xy 57.058451 -278.96324)
			(xy 57.028886 -279.002584) (xy 56.993393 -279.036676) (xy 56.95289 -279.064632) (xy 56.908428 -279.08573)
			(xy 56.861157 -279.099422) (xy 56.812302 -279.105354) (xy 56.763127 -279.103373) (xy 56.714908 -279.093529)
			(xy 56.668892 -279.076077) (xy 56.626271 -279.05147) (xy 56.58815 -279.020345) (xy 56.555515 -278.983508)
			(xy 56.529212 -278.941912) (xy 56.509921 -278.896636) (xy 56.498144 -278.848852) (xy 56.494184 -278.799798)
			(xy 56.176926 -278.799798) (xy 56.176422 -278.825506) (xy 56.168379 -278.876288) (xy 56.152491 -278.925187)
			(xy 56.129148 -278.970999) (xy 56.098927 -279.012595) (xy 56.062571 -279.048951) (xy 56.020975 -279.079172)
			(xy 55.975163 -279.102515) (xy 55.926264 -279.118403) (xy 55.875482 -279.126446) (xy 55.824066 -279.126446)
			(xy 55.773284 -279.118403) (xy 55.724385 -279.102515) (xy 55.678573 -279.079172) (xy 55.636977 -279.048951)
			(xy 55.600621 -279.012595) (xy 55.5704 -278.970999) (xy 55.547057 -278.925187) (xy 55.531169 -278.876288)
			(xy 55.523126 -278.825506) (xy 55.204448 -278.825506) (xy 55.196732 -278.872982) (xy 55.181148 -278.919663)
			(xy 55.158277 -278.96324) (xy 55.128712 -279.002584) (xy 55.093219 -279.036676) (xy 55.052716 -279.064632)
			(xy 55.008254 -279.08573) (xy 54.960983 -279.099422) (xy 54.912128 -279.105354) (xy 54.862953 -279.103373)
			(xy 54.814734 -279.093529) (xy 54.768718 -279.076077) (xy 54.726097 -279.05147) (xy 54.687976 -279.020345)
			(xy 54.655341 -278.983508) (xy 54.629038 -278.941912) (xy 54.609747 -278.896636) (xy 54.59797 -278.848852)
			(xy 54.59401 -278.799798) (xy 54.277006 -278.799798) (xy 54.276502 -278.825506) (xy 54.268459 -278.876288)
			(xy 54.252571 -278.925187) (xy 54.229228 -278.970999) (xy 54.199007 -279.012595) (xy 54.162651 -279.048951)
			(xy 54.121055 -279.079172) (xy 54.075243 -279.102515) (xy 54.026344 -279.118403) (xy 53.975562 -279.126446)
			(xy 53.924146 -279.126446) (xy 53.873364 -279.118403) (xy 53.824465 -279.102515) (xy 53.778653 -279.079172)
			(xy 53.737057 -279.048951) (xy 53.700701 -279.012595) (xy 53.67048 -278.970999) (xy 53.647137 -278.925187)
			(xy 53.631249 -278.876288) (xy 53.623206 -278.825506) (xy 53.304528 -278.825506) (xy 53.296812 -278.872982)
			(xy 53.281228 -278.919663) (xy 53.258357 -278.96324) (xy 53.228792 -279.002584) (xy 53.193299 -279.036676)
			(xy 53.152796 -279.064632) (xy 53.108334 -279.08573) (xy 53.061063 -279.099422) (xy 53.012208 -279.105354)
			(xy 52.963033 -279.103373) (xy 52.914814 -279.093529) (xy 52.868798 -279.076077) (xy 52.826177 -279.05147)
			(xy 52.788056 -279.020345) (xy 52.755421 -278.983508) (xy 52.729118 -278.941912) (xy 52.709827 -278.896636)
			(xy 52.69805 -278.848852) (xy 52.69409 -278.799798) (xy 52.377086 -278.799798) (xy 52.376582 -278.825506)
			(xy 52.368539 -278.876288) (xy 52.352651 -278.925187) (xy 52.329308 -278.970999) (xy 52.299087 -279.012595)
			(xy 52.262731 -279.048951) (xy 52.221135 -279.079172) (xy 52.175323 -279.102515) (xy 52.126424 -279.118403)
			(xy 52.075642 -279.126446) (xy 52.024226 -279.126446) (xy 51.973444 -279.118403) (xy 51.924545 -279.102515)
			(xy 51.878733 -279.079172) (xy 51.837137 -279.048951) (xy 51.800781 -279.012595) (xy 51.77056 -278.970999)
			(xy 51.747217 -278.925187) (xy 51.731329 -278.876288) (xy 51.723286 -278.825506) (xy 51.404608 -278.825506)
			(xy 51.396892 -278.872982) (xy 51.381308 -278.919663) (xy 51.358437 -278.96324) (xy 51.328872 -279.002584)
			(xy 51.293379 -279.036676) (xy 51.252876 -279.064632) (xy 51.208414 -279.08573) (xy 51.161143 -279.099422)
			(xy 51.112288 -279.105354) (xy 51.063113 -279.103373) (xy 51.014894 -279.093529) (xy 50.968878 -279.076077)
			(xy 50.926257 -279.05147) (xy 50.888136 -279.020345) (xy 50.855501 -278.983508) (xy 50.829198 -278.941912)
			(xy 50.809907 -278.896636) (xy 50.79813 -278.848852) (xy 50.79417 -278.799798) (xy 50.476912 -278.799798)
			(xy 50.476408 -278.825506) (xy 50.468365 -278.876288) (xy 50.452477 -278.925187) (xy 50.429134 -278.970999)
			(xy 50.398913 -279.012595) (xy 50.362557 -279.048951) (xy 50.320961 -279.079172) (xy 50.275149 -279.102515)
			(xy 50.22625 -279.118403) (xy 50.175468 -279.126446) (xy 50.124052 -279.126446) (xy 50.07327 -279.118403)
			(xy 50.024371 -279.102515) (xy 49.978559 -279.079172) (xy 49.936963 -279.048951) (xy 49.900607 -279.012595)
			(xy 49.870386 -278.970999) (xy 49.847043 -278.925187) (xy 49.831155 -278.876288) (xy 49.823112 -278.825506)
			(xy 49.504434 -278.825506) (xy 49.496718 -278.872982) (xy 49.481134 -278.919663) (xy 49.458263 -278.96324)
			(xy 49.428698 -279.002584) (xy 49.393205 -279.036676) (xy 49.352702 -279.064632) (xy 49.30824 -279.08573)
			(xy 49.260969 -279.099422) (xy 49.212114 -279.105354) (xy 49.162939 -279.103373) (xy 49.11472 -279.093529)
			(xy 49.068704 -279.076077) (xy 49.026083 -279.05147) (xy 48.987962 -279.020345) (xy 48.955327 -278.983508)
			(xy 48.929024 -278.941912) (xy 48.909733 -278.896636) (xy 48.897956 -278.848852) (xy 48.893996 -278.799798)
			(xy 48.576992 -278.799798) (xy 48.576488 -278.825506) (xy 48.568445 -278.876288) (xy 48.552557 -278.925187)
			(xy 48.529214 -278.970999) (xy 48.498993 -279.012595) (xy 48.462637 -279.048951) (xy 48.421041 -279.079172)
			(xy 48.375229 -279.102515) (xy 48.32633 -279.118403) (xy 48.275548 -279.126446) (xy 48.224132 -279.126446)
			(xy 48.17335 -279.118403) (xy 48.124451 -279.102515) (xy 48.078639 -279.079172) (xy 48.037043 -279.048951)
			(xy 48.000687 -279.012595) (xy 47.970466 -278.970999) (xy 47.947123 -278.925187) (xy 47.931235 -278.876288)
			(xy 47.923192 -278.825506) (xy 47.604514 -278.825506) (xy 47.596798 -278.872982) (xy 47.581214 -278.919663)
			(xy 47.558343 -278.96324) (xy 47.528778 -279.002584) (xy 47.493285 -279.036676) (xy 47.452782 -279.064632)
			(xy 47.40832 -279.08573) (xy 47.361049 -279.099422) (xy 47.312194 -279.105354) (xy 47.263019 -279.103373)
			(xy 47.2148 -279.093529) (xy 47.168784 -279.076077) (xy 47.126163 -279.05147) (xy 47.088042 -279.020345)
			(xy 47.055407 -278.983508) (xy 47.029104 -278.941912) (xy 47.009813 -278.896636) (xy 46.998036 -278.848852)
			(xy 46.994076 -278.799798) (xy 46.677072 -278.799798) (xy 46.676568 -278.825506) (xy 46.668525 -278.876288)
			(xy 46.652637 -278.925187) (xy 46.629294 -278.970999) (xy 46.599073 -279.012595) (xy 46.562717 -279.048951)
			(xy 46.521121 -279.079172) (xy 46.475309 -279.102515) (xy 46.42641 -279.118403) (xy 46.375628 -279.126446)
			(xy 46.324212 -279.126446) (xy 46.27343 -279.118403) (xy 46.224531 -279.102515) (xy 46.178719 -279.079172)
			(xy 46.137123 -279.048951) (xy 46.100767 -279.012595) (xy 46.070546 -278.970999) (xy 46.047203 -278.925187)
			(xy 46.031315 -278.876288) (xy 46.023272 -278.825506) (xy 45.704594 -278.825506) (xy 45.696878 -278.872982)
			(xy 45.681294 -278.919663) (xy 45.658423 -278.96324) (xy 45.628858 -279.002584) (xy 45.593365 -279.036676)
			(xy 45.552862 -279.064632) (xy 45.5084 -279.08573) (xy 45.461129 -279.099422) (xy 45.412274 -279.105354)
			(xy 45.363099 -279.103373) (xy 45.31488 -279.093529) (xy 45.268864 -279.076077) (xy 45.226243 -279.05147)
			(xy 45.188122 -279.020345) (xy 45.155487 -278.983508) (xy 45.129184 -278.941912) (xy 45.109893 -278.896636)
			(xy 45.098116 -278.848852) (xy 45.094156 -278.799798) (xy 44.776898 -278.799798) (xy 44.776394 -278.825506)
			(xy 44.768351 -278.876288) (xy 44.752463 -278.925187) (xy 44.72912 -278.970999) (xy 44.698899 -279.012595)
			(xy 44.662543 -279.048951) (xy 44.620947 -279.079172) (xy 44.575135 -279.102515) (xy 44.526236 -279.118403)
			(xy 44.475454 -279.126446) (xy 44.424038 -279.126446) (xy 44.373256 -279.118403) (xy 44.324357 -279.102515)
			(xy 44.278545 -279.079172) (xy 44.236949 -279.048951) (xy 44.200593 -279.012595) (xy 44.170372 -278.970999)
			(xy 44.147029 -278.925187) (xy 44.131141 -278.876288) (xy 44.123098 -278.825506) (xy 43.80442 -278.825506)
			(xy 43.796704 -278.872982) (xy 43.78112 -278.919663) (xy 43.758249 -278.96324) (xy 43.728684 -279.002584)
			(xy 43.693191 -279.036676) (xy 43.652688 -279.064632) (xy 43.608226 -279.08573) (xy 43.560955 -279.099422)
			(xy 43.5121 -279.105354) (xy 43.462925 -279.103373) (xy 43.414706 -279.093529) (xy 43.36869 -279.076077)
			(xy 43.326069 -279.05147) (xy 43.287948 -279.020345) (xy 43.255313 -278.983508) (xy 43.22901 -278.941912)
			(xy 43.209719 -278.896636) (xy 43.197942 -278.848852) (xy 43.193982 -278.799798) (xy 40.899334 -278.799798)
			(xy 40.899334 -278.887174) (xy 40.899994 -278.899204) (xy 40.910851 -278.920678) (xy 40.920162 -278.928322)
			(xy 40.996362 -278.983948) (xy 41.020238 -278.987758) (xy 41.031922 -278.983948) (xy 41.054563 -278.977174)
			(xy 41.101257 -278.969902) (xy 41.124886 -278.96947) (xy 41.150146 -278.969962) (xy 41.199978 -278.978275)
			(xy 41.247762 -278.994677) (xy 41.292194 -279.018721) (xy 41.332063 -279.04975) (xy 41.36628 -279.086919)
			(xy 41.393913 -279.129212) (xy 41.414208 -279.175477) (xy 41.42661 -279.224452) (xy 41.43078 -279.274778)
			(xy 41.769042 -279.274778) (xy 41.773002 -279.225724) (xy 41.784779 -279.17794) (xy 41.80407 -279.132664)
			(xy 41.830373 -279.091068) (xy 41.863008 -279.054231) (xy 41.901129 -279.023106) (xy 41.94375 -278.998499)
			(xy 41.989766 -278.981047) (xy 42.037985 -278.971203) (xy 42.08716 -278.969222) (xy 42.136015 -278.975154)
			(xy 42.183286 -278.988846) (xy 42.227748 -279.009944) (xy 42.268251 -279.0379) (xy 42.303744 -279.071992)
			(xy 42.333309 -279.111336) (xy 42.35618 -279.154913) (xy 42.371764 -279.201594) (xy 42.379659 -279.250171)
			(xy 42.380154 -279.274778) (xy 42.379659 -279.299385) (xy 42.371764 -279.347962) (xy 42.35618 -279.394643)
			(xy 42.333309 -279.43822) (xy 42.303744 -279.477564) (xy 42.268251 -279.511656) (xy 42.227748 -279.539612)
			(xy 42.183286 -279.56071) (xy 42.136015 -279.574402) (xy 42.08716 -279.580334) (xy 42.037985 -279.578353)
			(xy 41.989766 -279.568509) (xy 41.94375 -279.551057) (xy 41.901129 -279.52645) (xy 41.863008 -279.495325)
			(xy 41.830373 -279.458488) (xy 41.80407 -279.416892) (xy 41.784779 -279.371616) (xy 41.773002 -279.323832)
			(xy 41.769042 -279.274778) (xy 41.43078 -279.274778) (xy 41.430782 -279.2748) (xy 41.42661 -279.325148)
			(xy 41.414208 -279.374123) (xy 41.393913 -279.420388) (xy 41.36628 -279.462681) (xy 41.332063 -279.49985)
			(xy 41.292194 -279.530879) (xy 41.247762 -279.554923) (xy 41.199978 -279.571325) (xy 41.150146 -279.579638)
			(xy 41.124886 -279.580086) (xy 41.101259 -279.579638) (xy 41.054569 -279.572359) (xy 41.031922 -279.565608)
			(xy 41.020238 -279.561798) (xy 40.996362 -279.565608) (xy 40.920162 -279.621234) (xy 40.910813 -279.628854)
			(xy 40.899931 -279.650337) (xy 40.899334 -279.662382) (xy 40.899334 -279.749758) (xy 44.143942 -279.749758)
			(xy 44.147902 -279.700704) (xy 44.159679 -279.65292) (xy 44.17897 -279.607644) (xy 44.205273 -279.566048)
			(xy 44.237908 -279.529211) (xy 44.276029 -279.498086) (xy 44.31865 -279.473479) (xy 44.364666 -279.456027)
			(xy 44.412885 -279.446183) (xy 44.46206 -279.444202) (xy 44.510915 -279.450134) (xy 44.558186 -279.463826)
			(xy 44.602648 -279.484924) (xy 44.643151 -279.51288) (xy 44.678644 -279.546972) (xy 44.708209 -279.586316)
			(xy 44.73108 -279.629893) (xy 44.746664 -279.676574) (xy 44.754559 -279.725151) (xy 44.755054 -279.749758)
			(xy 44.754559 -279.774365) (xy 44.754421 -279.775212) (xy 45.073312 -279.775212) (xy 45.073312 -279.723796)
			(xy 45.081355 -279.673014) (xy 45.097243 -279.624115) (xy 45.120586 -279.578303) (xy 45.150807 -279.536707)
			(xy 45.187163 -279.500351) (xy 45.228759 -279.47013) (xy 45.274571 -279.446787) (xy 45.32347 -279.430899)
			(xy 45.374252 -279.422856) (xy 45.425668 -279.422856) (xy 45.47645 -279.430899) (xy 45.525349 -279.446787)
			(xy 45.571161 -279.47013) (xy 45.612757 -279.500351) (xy 45.649113 -279.536707) (xy 45.679334 -279.578303)
			(xy 45.702677 -279.624115) (xy 45.718565 -279.673014) (xy 45.726608 -279.723796) (xy 45.727112 -279.749504)
			(xy 45.727107 -279.749758) (xy 46.044116 -279.749758) (xy 46.048076 -279.700704) (xy 46.059853 -279.65292)
			(xy 46.079144 -279.607644) (xy 46.105447 -279.566048) (xy 46.138082 -279.529211) (xy 46.176203 -279.498086)
			(xy 46.218824 -279.473479) (xy 46.26484 -279.456027) (xy 46.313059 -279.446183) (xy 46.362234 -279.444202)
			(xy 46.411089 -279.450134) (xy 46.45836 -279.463826) (xy 46.502822 -279.484924) (xy 46.543325 -279.51288)
			(xy 46.578818 -279.546972) (xy 46.608383 -279.586316) (xy 46.631254 -279.629893) (xy 46.646838 -279.676574)
			(xy 46.654733 -279.725151) (xy 46.655228 -279.749758) (xy 46.654733 -279.774365) (xy 46.654595 -279.775212)
			(xy 46.973232 -279.775212) (xy 46.973232 -279.723796) (xy 46.981275 -279.673014) (xy 46.997163 -279.624115)
			(xy 47.020506 -279.578303) (xy 47.050727 -279.536707) (xy 47.087083 -279.500351) (xy 47.128679 -279.47013)
			(xy 47.174491 -279.446787) (xy 47.22339 -279.430899) (xy 47.274172 -279.422856) (xy 47.325588 -279.422856)
			(xy 47.37637 -279.430899) (xy 47.425269 -279.446787) (xy 47.471081 -279.47013) (xy 47.512677 -279.500351)
			(xy 47.549033 -279.536707) (xy 47.579254 -279.578303) (xy 47.602597 -279.624115) (xy 47.618485 -279.673014)
			(xy 47.626528 -279.723796) (xy 47.627032 -279.749504) (xy 47.627027 -279.749758) (xy 47.944036 -279.749758)
			(xy 47.947996 -279.700704) (xy 47.959773 -279.65292) (xy 47.979064 -279.607644) (xy 48.005367 -279.566048)
			(xy 48.038002 -279.529211) (xy 48.076123 -279.498086) (xy 48.118744 -279.473479) (xy 48.16476 -279.456027)
			(xy 48.212979 -279.446183) (xy 48.262154 -279.444202) (xy 48.311009 -279.450134) (xy 48.35828 -279.463826)
			(xy 48.402742 -279.484924) (xy 48.443245 -279.51288) (xy 48.478738 -279.546972) (xy 48.508303 -279.586316)
			(xy 48.531174 -279.629893) (xy 48.546758 -279.676574) (xy 48.554653 -279.725151) (xy 48.555148 -279.749758)
			(xy 48.554653 -279.774365) (xy 48.554515 -279.775212) (xy 48.873152 -279.775212) (xy 48.873152 -279.723796)
			(xy 48.881195 -279.673014) (xy 48.897083 -279.624115) (xy 48.920426 -279.578303) (xy 48.950647 -279.536707)
			(xy 48.987003 -279.500351) (xy 49.028599 -279.47013) (xy 49.074411 -279.446787) (xy 49.12331 -279.430899)
			(xy 49.174092 -279.422856) (xy 49.225508 -279.422856) (xy 49.27629 -279.430899) (xy 49.325189 -279.446787)
			(xy 49.371001 -279.47013) (xy 49.412597 -279.500351) (xy 49.448953 -279.536707) (xy 49.479174 -279.578303)
			(xy 49.502517 -279.624115) (xy 49.518405 -279.673014) (xy 49.526448 -279.723796) (xy 49.526952 -279.749504)
			(xy 49.526947 -279.749758) (xy 49.843956 -279.749758) (xy 49.847916 -279.700704) (xy 49.859693 -279.65292)
			(xy 49.878984 -279.607644) (xy 49.905287 -279.566048) (xy 49.937922 -279.529211) (xy 49.976043 -279.498086)
			(xy 50.018664 -279.473479) (xy 50.06468 -279.456027) (xy 50.112899 -279.446183) (xy 50.162074 -279.444202)
			(xy 50.210929 -279.450134) (xy 50.2582 -279.463826) (xy 50.302662 -279.484924) (xy 50.343165 -279.51288)
			(xy 50.378658 -279.546972) (xy 50.408223 -279.586316) (xy 50.431094 -279.629893) (xy 50.446678 -279.676574)
			(xy 50.454573 -279.725151) (xy 50.455068 -279.749758) (xy 50.454573 -279.774365) (xy 50.454435 -279.775212)
			(xy 50.773326 -279.775212) (xy 50.773326 -279.723796) (xy 50.781369 -279.673014) (xy 50.797257 -279.624115)
			(xy 50.8206 -279.578303) (xy 50.850821 -279.536707) (xy 50.887177 -279.500351) (xy 50.928773 -279.47013)
			(xy 50.974585 -279.446787) (xy 51.023484 -279.430899) (xy 51.074266 -279.422856) (xy 51.125682 -279.422856)
			(xy 51.176464 -279.430899) (xy 51.225363 -279.446787) (xy 51.271175 -279.47013) (xy 51.312771 -279.500351)
			(xy 51.349127 -279.536707) (xy 51.379348 -279.578303) (xy 51.402691 -279.624115) (xy 51.418579 -279.673014)
			(xy 51.426622 -279.723796) (xy 51.427126 -279.749504) (xy 51.427121 -279.749758) (xy 51.74413 -279.749758)
			(xy 51.74809 -279.700704) (xy 51.759867 -279.65292) (xy 51.779158 -279.607644) (xy 51.805461 -279.566048)
			(xy 51.838096 -279.529211) (xy 51.876217 -279.498086) (xy 51.918838 -279.473479) (xy 51.964854 -279.456027)
			(xy 52.013073 -279.446183) (xy 52.062248 -279.444202) (xy 52.111103 -279.450134) (xy 52.158374 -279.463826)
			(xy 52.202836 -279.484924) (xy 52.243339 -279.51288) (xy 52.278832 -279.546972) (xy 52.308397 -279.586316)
			(xy 52.331268 -279.629893) (xy 52.346852 -279.676574) (xy 52.354747 -279.725151) (xy 52.355242 -279.749758)
			(xy 52.354747 -279.774365) (xy 52.354609 -279.775212) (xy 52.673246 -279.775212) (xy 52.673246 -279.723796)
			(xy 52.681289 -279.673014) (xy 52.697177 -279.624115) (xy 52.72052 -279.578303) (xy 52.750741 -279.536707)
			(xy 52.787097 -279.500351) (xy 52.828693 -279.47013) (xy 52.874505 -279.446787) (xy 52.923404 -279.430899)
			(xy 52.974186 -279.422856) (xy 53.025602 -279.422856) (xy 53.076384 -279.430899) (xy 53.125283 -279.446787)
			(xy 53.171095 -279.47013) (xy 53.212691 -279.500351) (xy 53.249047 -279.536707) (xy 53.279268 -279.578303)
			(xy 53.302611 -279.624115) (xy 53.318499 -279.673014) (xy 53.326542 -279.723796) (xy 53.327046 -279.749504)
			(xy 53.327041 -279.749758) (xy 53.64405 -279.749758) (xy 53.64801 -279.700704) (xy 53.659787 -279.65292)
			(xy 53.679078 -279.607644) (xy 53.705381 -279.566048) (xy 53.738016 -279.529211) (xy 53.776137 -279.498086)
			(xy 53.818758 -279.473479) (xy 53.864774 -279.456027) (xy 53.912993 -279.446183) (xy 53.962168 -279.444202)
			(xy 54.011023 -279.450134) (xy 54.058294 -279.463826) (xy 54.102756 -279.484924) (xy 54.143259 -279.51288)
			(xy 54.178752 -279.546972) (xy 54.208317 -279.586316) (xy 54.231188 -279.629893) (xy 54.246772 -279.676574)
			(xy 54.254667 -279.725151) (xy 54.255162 -279.749758) (xy 54.254667 -279.774365) (xy 54.254529 -279.775212)
			(xy 54.573166 -279.775212) (xy 54.573166 -279.723796) (xy 54.581209 -279.673014) (xy 54.597097 -279.624115)
			(xy 54.62044 -279.578303) (xy 54.650661 -279.536707) (xy 54.687017 -279.500351) (xy 54.728613 -279.47013)
			(xy 54.774425 -279.446787) (xy 54.823324 -279.430899) (xy 54.874106 -279.422856) (xy 54.925522 -279.422856)
			(xy 54.976304 -279.430899) (xy 55.025203 -279.446787) (xy 55.071015 -279.47013) (xy 55.112611 -279.500351)
			(xy 55.148967 -279.536707) (xy 55.179188 -279.578303) (xy 55.202531 -279.624115) (xy 55.218419 -279.673014)
			(xy 55.226462 -279.723796) (xy 55.226966 -279.749504) (xy 55.226961 -279.749758) (xy 55.54397 -279.749758)
			(xy 55.54793 -279.700704) (xy 55.559707 -279.65292) (xy 55.578998 -279.607644) (xy 55.605301 -279.566048)
			(xy 55.637936 -279.529211) (xy 55.676057 -279.498086) (xy 55.718678 -279.473479) (xy 55.764694 -279.456027)
			(xy 55.812913 -279.446183) (xy 55.862088 -279.444202) (xy 55.910943 -279.450134) (xy 55.958214 -279.463826)
			(xy 56.002676 -279.484924) (xy 56.043179 -279.51288) (xy 56.078672 -279.546972) (xy 56.108237 -279.586316)
			(xy 56.131108 -279.629893) (xy 56.146692 -279.676574) (xy 56.154587 -279.725151) (xy 56.155082 -279.749758)
			(xy 56.154587 -279.774365) (xy 56.154449 -279.775212) (xy 56.473086 -279.775212) (xy 56.473086 -279.723796)
			(xy 56.481129 -279.673014) (xy 56.497017 -279.624115) (xy 56.52036 -279.578303) (xy 56.550581 -279.536707)
			(xy 56.586937 -279.500351) (xy 56.628533 -279.47013) (xy 56.674345 -279.446787) (xy 56.723244 -279.430899)
			(xy 56.774026 -279.422856) (xy 56.825442 -279.422856) (xy 56.876224 -279.430899) (xy 56.925123 -279.446787)
			(xy 56.970935 -279.47013) (xy 57.012531 -279.500351) (xy 57.048887 -279.536707) (xy 57.079108 -279.578303)
			(xy 57.102451 -279.624115) (xy 57.118339 -279.673014) (xy 57.126382 -279.723796) (xy 57.126886 -279.749504)
			(xy 57.126881 -279.749758) (xy 57.444144 -279.749758) (xy 57.448104 -279.700704) (xy 57.459881 -279.65292)
			(xy 57.479172 -279.607644) (xy 57.505475 -279.566048) (xy 57.53811 -279.529211) (xy 57.576231 -279.498086)
			(xy 57.618852 -279.473479) (xy 57.664868 -279.456027) (xy 57.713087 -279.446183) (xy 57.762262 -279.444202)
			(xy 57.811117 -279.450134) (xy 57.858388 -279.463826) (xy 57.90285 -279.484924) (xy 57.943353 -279.51288)
			(xy 57.978846 -279.546972) (xy 58.008411 -279.586316) (xy 58.031282 -279.629893) (xy 58.046866 -279.676574)
			(xy 58.054761 -279.725151) (xy 58.055256 -279.749758) (xy 58.054761 -279.774365) (xy 58.054623 -279.775212)
			(xy 58.37326 -279.775212) (xy 58.37326 -279.723796) (xy 58.381303 -279.673014) (xy 58.397191 -279.624115)
			(xy 58.420534 -279.578303) (xy 58.450755 -279.536707) (xy 58.487111 -279.500351) (xy 58.528707 -279.47013)
			(xy 58.574519 -279.446787) (xy 58.623418 -279.430899) (xy 58.6742 -279.422856) (xy 58.725616 -279.422856)
			(xy 58.776398 -279.430899) (xy 58.825297 -279.446787) (xy 58.871109 -279.47013) (xy 58.912705 -279.500351)
			(xy 58.949061 -279.536707) (xy 58.979282 -279.578303) (xy 59.002625 -279.624115) (xy 59.018513 -279.673014)
			(xy 59.026556 -279.723796) (xy 59.02706 -279.749504) (xy 59.027055 -279.749758) (xy 59.344064 -279.749758)
			(xy 59.348024 -279.700704) (xy 59.359801 -279.65292) (xy 59.379092 -279.607644) (xy 59.405395 -279.566048)
			(xy 59.43803 -279.529211) (xy 59.476151 -279.498086) (xy 59.518772 -279.473479) (xy 59.564788 -279.456027)
			(xy 59.613007 -279.446183) (xy 59.662182 -279.444202) (xy 59.711037 -279.450134) (xy 59.758308 -279.463826)
			(xy 59.80277 -279.484924) (xy 59.843273 -279.51288) (xy 59.878766 -279.546972) (xy 59.908331 -279.586316)
			(xy 59.931202 -279.629893) (xy 59.946786 -279.676574) (xy 59.954681 -279.725151) (xy 59.955176 -279.749758)
			(xy 59.954681 -279.774365) (xy 59.954543 -279.775212) (xy 60.27318 -279.775212) (xy 60.27318 -279.723796)
			(xy 60.281223 -279.673014) (xy 60.297111 -279.624115) (xy 60.320454 -279.578303) (xy 60.350675 -279.536707)
			(xy 60.387031 -279.500351) (xy 60.428627 -279.47013) (xy 60.474439 -279.446787) (xy 60.523338 -279.430899)
			(xy 60.57412 -279.422856) (xy 60.625536 -279.422856) (xy 60.676318 -279.430899) (xy 60.725217 -279.446787)
			(xy 60.771029 -279.47013) (xy 60.812625 -279.500351) (xy 60.848981 -279.536707) (xy 60.879202 -279.578303)
			(xy 60.902545 -279.624115) (xy 60.918433 -279.673014) (xy 60.926476 -279.723796) (xy 60.92698 -279.749504)
			(xy 60.926975 -279.749758) (xy 61.243984 -279.749758) (xy 61.247944 -279.700704) (xy 61.259721 -279.65292)
			(xy 61.279012 -279.607644) (xy 61.305315 -279.566048) (xy 61.33795 -279.529211) (xy 61.376071 -279.498086)
			(xy 61.418692 -279.473479) (xy 61.464708 -279.456027) (xy 61.512927 -279.446183) (xy 61.562102 -279.444202)
			(xy 61.610957 -279.450134) (xy 61.658228 -279.463826) (xy 61.70269 -279.484924) (xy 61.743193 -279.51288)
			(xy 61.778686 -279.546972) (xy 61.808251 -279.586316) (xy 61.831122 -279.629893) (xy 61.846706 -279.676574)
			(xy 61.854601 -279.725151) (xy 61.855096 -279.749758) (xy 61.854601 -279.774365) (xy 61.854463 -279.775212)
			(xy 62.1731 -279.775212) (xy 62.1731 -279.723796) (xy 62.181143 -279.673014) (xy 62.197031 -279.624115)
			(xy 62.220374 -279.578303) (xy 62.250595 -279.536707) (xy 62.286951 -279.500351) (xy 62.328547 -279.47013)
			(xy 62.374359 -279.446787) (xy 62.423258 -279.430899) (xy 62.47404 -279.422856) (xy 62.525456 -279.422856)
			(xy 62.576238 -279.430899) (xy 62.625137 -279.446787) (xy 62.670949 -279.47013) (xy 62.712545 -279.500351)
			(xy 62.748901 -279.536707) (xy 62.779122 -279.578303) (xy 62.802465 -279.624115) (xy 62.818353 -279.673014)
			(xy 62.826396 -279.723796) (xy 62.8269 -279.749504) (xy 62.826895 -279.749758) (xy 63.144158 -279.749758)
			(xy 63.148118 -279.700704) (xy 63.159895 -279.65292) (xy 63.179186 -279.607644) (xy 63.205489 -279.566048)
			(xy 63.238124 -279.529211) (xy 63.276245 -279.498086) (xy 63.318866 -279.473479) (xy 63.364882 -279.456027)
			(xy 63.413101 -279.446183) (xy 63.462276 -279.444202) (xy 63.511131 -279.450134) (xy 63.558402 -279.463826)
			(xy 63.602864 -279.484924) (xy 63.643367 -279.51288) (xy 63.67886 -279.546972) (xy 63.708425 -279.586316)
			(xy 63.731296 -279.629893) (xy 63.74688 -279.676574) (xy 63.754775 -279.725151) (xy 63.75527 -279.749758)
			(xy 63.754775 -279.774365) (xy 63.754637 -279.775212) (xy 64.073274 -279.775212) (xy 64.073274 -279.723796)
			(xy 64.081317 -279.673014) (xy 64.097205 -279.624115) (xy 64.120548 -279.578303) (xy 64.150769 -279.536707)
			(xy 64.187125 -279.500351) (xy 64.228721 -279.47013) (xy 64.274533 -279.446787) (xy 64.323432 -279.430899)
			(xy 64.374214 -279.422856) (xy 64.42563 -279.422856) (xy 64.476412 -279.430899) (xy 64.525311 -279.446787)
			(xy 64.571123 -279.47013) (xy 64.612719 -279.500351) (xy 64.649075 -279.536707) (xy 64.679296 -279.578303)
			(xy 64.702639 -279.624115) (xy 64.718527 -279.673014) (xy 64.72657 -279.723796) (xy 64.727074 -279.749504)
			(xy 64.727069 -279.749758) (xy 65.044078 -279.749758) (xy 65.048038 -279.700704) (xy 65.059815 -279.65292)
			(xy 65.079106 -279.607644) (xy 65.105409 -279.566048) (xy 65.138044 -279.529211) (xy 65.176165 -279.498086)
			(xy 65.218786 -279.473479) (xy 65.264802 -279.456027) (xy 65.313021 -279.446183) (xy 65.362196 -279.444202)
			(xy 65.411051 -279.450134) (xy 65.458322 -279.463826) (xy 65.502784 -279.484924) (xy 65.543287 -279.51288)
			(xy 65.57878 -279.546972) (xy 65.608345 -279.586316) (xy 65.631216 -279.629893) (xy 65.6468 -279.676574)
			(xy 65.654695 -279.725151) (xy 65.65519 -279.749758) (xy 65.654695 -279.774365) (xy 65.654557 -279.775212)
			(xy 65.973194 -279.775212) (xy 65.973194 -279.723796) (xy 65.981237 -279.673014) (xy 65.997125 -279.624115)
			(xy 66.020468 -279.578303) (xy 66.050689 -279.536707) (xy 66.087045 -279.500351) (xy 66.128641 -279.47013)
			(xy 66.174453 -279.446787) (xy 66.223352 -279.430899) (xy 66.274134 -279.422856) (xy 66.32555 -279.422856)
			(xy 66.376332 -279.430899) (xy 66.425231 -279.446787) (xy 66.471043 -279.47013) (xy 66.512639 -279.500351)
			(xy 66.548995 -279.536707) (xy 66.579216 -279.578303) (xy 66.602559 -279.624115) (xy 66.618447 -279.673014)
			(xy 66.62649 -279.723796) (xy 66.626994 -279.749504) (xy 66.626989 -279.749758) (xy 66.943998 -279.749758)
			(xy 66.947958 -279.700704) (xy 66.959735 -279.65292) (xy 66.979026 -279.607644) (xy 67.005329 -279.566048)
			(xy 67.037964 -279.529211) (xy 67.076085 -279.498086) (xy 67.118706 -279.473479) (xy 67.164722 -279.456027)
			(xy 67.212941 -279.446183) (xy 67.262116 -279.444202) (xy 67.310971 -279.450134) (xy 67.358242 -279.463826)
			(xy 67.402704 -279.484924) (xy 67.443207 -279.51288) (xy 67.4787 -279.546972) (xy 67.508265 -279.586316)
			(xy 67.531136 -279.629893) (xy 67.54672 -279.676574) (xy 67.554615 -279.725151) (xy 67.55511 -279.749758)
			(xy 67.554615 -279.774365) (xy 67.554477 -279.775212) (xy 67.873114 -279.775212) (xy 67.873114 -279.723796)
			(xy 67.881157 -279.673014) (xy 67.897045 -279.624115) (xy 67.920388 -279.578303) (xy 67.950609 -279.536707)
			(xy 67.986965 -279.500351) (xy 68.028561 -279.47013) (xy 68.074373 -279.446787) (xy 68.123272 -279.430899)
			(xy 68.174054 -279.422856) (xy 68.22547 -279.422856) (xy 68.276252 -279.430899) (xy 68.325151 -279.446787)
			(xy 68.370963 -279.47013) (xy 68.412559 -279.500351) (xy 68.448915 -279.536707) (xy 68.479136 -279.578303)
			(xy 68.502479 -279.624115) (xy 68.518367 -279.673014) (xy 68.52641 -279.723796) (xy 68.526914 -279.749504)
			(xy 68.526909 -279.749758) (xy 68.844172 -279.749758) (xy 68.848132 -279.700704) (xy 68.859909 -279.65292)
			(xy 68.8792 -279.607644) (xy 68.905503 -279.566048) (xy 68.938138 -279.529211) (xy 68.976259 -279.498086)
			(xy 69.01888 -279.473479) (xy 69.064896 -279.456027) (xy 69.113115 -279.446183) (xy 69.16229 -279.444202)
			(xy 69.211145 -279.450134) (xy 69.258416 -279.463826) (xy 69.302878 -279.484924) (xy 69.343381 -279.51288)
			(xy 69.378874 -279.546972) (xy 69.408439 -279.586316) (xy 69.43131 -279.629893) (xy 69.446894 -279.676574)
			(xy 69.454789 -279.725151) (xy 69.455284 -279.749758) (xy 69.454789 -279.774365) (xy 69.454651 -279.775212)
			(xy 69.773288 -279.775212) (xy 69.773288 -279.723796) (xy 69.781331 -279.673014) (xy 69.797219 -279.624115)
			(xy 69.820562 -279.578303) (xy 69.850783 -279.536707) (xy 69.887139 -279.500351) (xy 69.928735 -279.47013)
			(xy 69.974547 -279.446787) (xy 70.023446 -279.430899) (xy 70.074228 -279.422856) (xy 70.125644 -279.422856)
			(xy 70.176426 -279.430899) (xy 70.225325 -279.446787) (xy 70.271137 -279.47013) (xy 70.312733 -279.500351)
			(xy 70.349089 -279.536707) (xy 70.37931 -279.578303) (xy 70.402653 -279.624115) (xy 70.418541 -279.673014)
			(xy 70.426584 -279.723796) (xy 70.427088 -279.749504) (xy 70.427083 -279.749758) (xy 70.744092 -279.749758)
			(xy 70.748052 -279.700704) (xy 70.759829 -279.65292) (xy 70.77912 -279.607644) (xy 70.805423 -279.566048)
			(xy 70.838058 -279.529211) (xy 70.876179 -279.498086) (xy 70.9188 -279.473479) (xy 70.964816 -279.456027)
			(xy 71.013035 -279.446183) (xy 71.06221 -279.444202) (xy 71.111065 -279.450134) (xy 71.158336 -279.463826)
			(xy 71.202798 -279.484924) (xy 71.243301 -279.51288) (xy 71.278794 -279.546972) (xy 71.308359 -279.586316)
			(xy 71.33123 -279.629893) (xy 71.346814 -279.676574) (xy 71.354709 -279.725151) (xy 71.355204 -279.749758)
			(xy 71.354709 -279.774365) (xy 71.354571 -279.775212) (xy 71.673208 -279.775212) (xy 71.673208 -279.723796)
			(xy 71.681251 -279.673014) (xy 71.697139 -279.624115) (xy 71.720482 -279.578303) (xy 71.750703 -279.536707)
			(xy 71.787059 -279.500351) (xy 71.828655 -279.47013) (xy 71.874467 -279.446787) (xy 71.923366 -279.430899)
			(xy 71.974148 -279.422856) (xy 72.025564 -279.422856) (xy 72.076346 -279.430899) (xy 72.125245 -279.446787)
			(xy 72.171057 -279.47013) (xy 72.212653 -279.500351) (xy 72.249009 -279.536707) (xy 72.27923 -279.578303)
			(xy 72.302573 -279.624115) (xy 72.318461 -279.673014) (xy 72.326504 -279.723796) (xy 72.327008 -279.749504)
			(xy 72.327003 -279.749758) (xy 72.644012 -279.749758) (xy 72.647972 -279.700704) (xy 72.659749 -279.65292)
			(xy 72.67904 -279.607644) (xy 72.705343 -279.566048) (xy 72.737978 -279.529211) (xy 72.776099 -279.498086)
			(xy 72.81872 -279.473479) (xy 72.864736 -279.456027) (xy 72.912955 -279.446183) (xy 72.96213 -279.444202)
			(xy 73.010985 -279.450134) (xy 73.058256 -279.463826) (xy 73.102718 -279.484924) (xy 73.143221 -279.51288)
			(xy 73.178714 -279.546972) (xy 73.208279 -279.586316) (xy 73.23115 -279.629893) (xy 73.246734 -279.676574)
			(xy 73.254629 -279.725151) (xy 73.255124 -279.749758) (xy 73.254629 -279.774365) (xy 73.254491 -279.775212)
			(xy 73.573128 -279.775212) (xy 73.573128 -279.723796) (xy 73.581171 -279.673014) (xy 73.597059 -279.624115)
			(xy 73.620402 -279.578303) (xy 73.650623 -279.536707) (xy 73.686979 -279.500351) (xy 73.728575 -279.47013)
			(xy 73.774387 -279.446787) (xy 73.823286 -279.430899) (xy 73.874068 -279.422856) (xy 73.925484 -279.422856)
			(xy 73.976266 -279.430899) (xy 74.025165 -279.446787) (xy 74.070977 -279.47013) (xy 74.112573 -279.500351)
			(xy 74.148929 -279.536707) (xy 74.17915 -279.578303) (xy 74.202493 -279.624115) (xy 74.218381 -279.673014)
			(xy 74.226424 -279.723796) (xy 74.226928 -279.749504) (xy 74.226923 -279.749758) (xy 74.543932 -279.749758)
			(xy 74.547892 -279.700704) (xy 74.559669 -279.65292) (xy 74.57896 -279.607644) (xy 74.605263 -279.566048)
			(xy 74.637898 -279.529211) (xy 74.676019 -279.498086) (xy 74.71864 -279.473479) (xy 74.764656 -279.456027)
			(xy 74.812875 -279.446183) (xy 74.86205 -279.444202) (xy 74.910905 -279.450134) (xy 74.958176 -279.463826)
			(xy 75.002638 -279.484924) (xy 75.043141 -279.51288) (xy 75.078634 -279.546972) (xy 75.108199 -279.586316)
			(xy 75.13107 -279.629893) (xy 75.146654 -279.676574) (xy 75.154549 -279.725151) (xy 75.155044 -279.749758)
			(xy 75.154549 -279.774365) (xy 75.154411 -279.775212) (xy 75.473302 -279.775212) (xy 75.473302 -279.723796)
			(xy 75.481345 -279.673014) (xy 75.497233 -279.624115) (xy 75.520576 -279.578303) (xy 75.550797 -279.536707)
			(xy 75.587153 -279.500351) (xy 75.628749 -279.47013) (xy 75.674561 -279.446787) (xy 75.72346 -279.430899)
			(xy 75.774242 -279.422856) (xy 75.825658 -279.422856) (xy 75.87644 -279.430899) (xy 75.925339 -279.446787)
			(xy 75.971151 -279.47013) (xy 76.012747 -279.500351) (xy 76.049103 -279.536707) (xy 76.079324 -279.578303)
			(xy 76.102667 -279.624115) (xy 76.118555 -279.673014) (xy 76.126598 -279.723796) (xy 76.127102 -279.749504)
			(xy 76.127097 -279.749758) (xy 76.444106 -279.749758) (xy 76.448066 -279.700704) (xy 76.459843 -279.65292)
			(xy 76.479134 -279.607644) (xy 76.505437 -279.566048) (xy 76.538072 -279.529211) (xy 76.576193 -279.498086)
			(xy 76.618814 -279.473479) (xy 76.66483 -279.456027) (xy 76.713049 -279.446183) (xy 76.762224 -279.444202)
			(xy 76.811079 -279.450134) (xy 76.85835 -279.463826) (xy 76.902812 -279.484924) (xy 76.943315 -279.51288)
			(xy 76.978808 -279.546972) (xy 77.008373 -279.586316) (xy 77.031244 -279.629893) (xy 77.046828 -279.676574)
			(xy 77.054723 -279.725151) (xy 77.055218 -279.749758) (xy 77.054723 -279.774365) (xy 77.054585 -279.775212)
			(xy 77.373222 -279.775212) (xy 77.373222 -279.723796) (xy 77.381265 -279.673014) (xy 77.397153 -279.624115)
			(xy 77.420496 -279.578303) (xy 77.450717 -279.536707) (xy 77.487073 -279.500351) (xy 77.528669 -279.47013)
			(xy 77.574481 -279.446787) (xy 77.62338 -279.430899) (xy 77.674162 -279.422856) (xy 77.725578 -279.422856)
			(xy 77.77636 -279.430899) (xy 77.825259 -279.446787) (xy 77.871071 -279.47013) (xy 77.912667 -279.500351)
			(xy 77.949023 -279.536707) (xy 77.979244 -279.578303) (xy 78.002587 -279.624115) (xy 78.018475 -279.673014)
			(xy 78.026518 -279.723796) (xy 78.027022 -279.749504) (xy 78.027017 -279.749758) (xy 78.344026 -279.749758)
			(xy 78.347986 -279.700704) (xy 78.359763 -279.65292) (xy 78.379054 -279.607644) (xy 78.405357 -279.566048)
			(xy 78.437992 -279.529211) (xy 78.476113 -279.498086) (xy 78.518734 -279.473479) (xy 78.56475 -279.456027)
			(xy 78.612969 -279.446183) (xy 78.662144 -279.444202) (xy 78.710999 -279.450134) (xy 78.75827 -279.463826)
			(xy 78.802732 -279.484924) (xy 78.843235 -279.51288) (xy 78.878728 -279.546972) (xy 78.908293 -279.586316)
			(xy 78.931164 -279.629893) (xy 78.946748 -279.676574) (xy 78.954643 -279.725151) (xy 78.955138 -279.749758)
			(xy 78.954643 -279.774365) (xy 78.954464 -279.775466) (xy 79.273142 -279.775466) (xy 79.273142 -279.72405)
			(xy 79.281185 -279.673268) (xy 79.297073 -279.624369) (xy 79.320416 -279.578557) (xy 79.350637 -279.536961)
			(xy 79.386993 -279.500605) (xy 79.428589 -279.470384) (xy 79.474401 -279.447041) (xy 79.5233 -279.431153)
			(xy 79.574082 -279.42311) (xy 79.625498 -279.42311) (xy 79.67628 -279.431153) (xy 79.725179 -279.447041)
			(xy 79.770991 -279.470384) (xy 79.812587 -279.500605) (xy 79.848943 -279.536961) (xy 79.879164 -279.578557)
			(xy 79.902507 -279.624369) (xy 79.918395 -279.673268) (xy 79.926438 -279.72405) (xy 79.926942 -279.749758)
			(xy 80.243946 -279.749758) (xy 80.247906 -279.700704) (xy 80.259683 -279.65292) (xy 80.278974 -279.607644)
			(xy 80.305277 -279.566048) (xy 80.337912 -279.529211) (xy 80.376033 -279.498086) (xy 80.418654 -279.473479)
			(xy 80.46467 -279.456027) (xy 80.512889 -279.446183) (xy 80.562064 -279.444202) (xy 80.610919 -279.450134)
			(xy 80.65819 -279.463826) (xy 80.702652 -279.484924) (xy 80.743155 -279.51288) (xy 80.778648 -279.546972)
			(xy 80.808213 -279.586316) (xy 80.831084 -279.629893) (xy 80.846668 -279.676574) (xy 80.854563 -279.725151)
			(xy 80.855058 -279.749758) (xy 80.854563 -279.774365) (xy 80.854384 -279.775466) (xy 81.173316 -279.775466)
			(xy 81.173316 -279.72405) (xy 81.181359 -279.673268) (xy 81.197247 -279.624369) (xy 81.22059 -279.578557)
			(xy 81.250811 -279.536961) (xy 81.287167 -279.500605) (xy 81.328763 -279.470384) (xy 81.374575 -279.447041)
			(xy 81.423474 -279.431153) (xy 81.474256 -279.42311) (xy 81.525672 -279.42311) (xy 81.576454 -279.431153)
			(xy 81.625353 -279.447041) (xy 81.671165 -279.470384) (xy 81.712761 -279.500605) (xy 81.749117 -279.536961)
			(xy 81.779338 -279.578557) (xy 81.802681 -279.624369) (xy 81.818569 -279.673268) (xy 81.826612 -279.72405)
			(xy 81.827116 -279.749758) (xy 81.826612 -279.775466) (xy 82.123276 -279.775466) (xy 82.123276 -279.72405)
			(xy 82.131319 -279.673268) (xy 82.147207 -279.624369) (xy 82.17055 -279.578557) (xy 82.200771 -279.536961)
			(xy 82.237127 -279.500605) (xy 82.278723 -279.470384) (xy 82.324535 -279.447041) (xy 82.373434 -279.431153)
			(xy 82.424216 -279.42311) (xy 82.475632 -279.42311) (xy 82.526414 -279.431153) (xy 82.575313 -279.447041)
			(xy 82.621125 -279.470384) (xy 82.662721 -279.500605) (xy 82.699077 -279.536961) (xy 82.729298 -279.578557)
			(xy 82.752641 -279.624369) (xy 82.768529 -279.673268) (xy 82.776572 -279.72405) (xy 82.777076 -279.749758)
			(xy 82.777071 -279.750012) (xy 83.094334 -279.750012) (xy 83.098294 -279.700958) (xy 83.110071 -279.653174)
			(xy 83.129362 -279.607898) (xy 83.155665 -279.566302) (xy 83.1883 -279.529465) (xy 83.226421 -279.49834)
			(xy 83.269042 -279.473733) (xy 83.315058 -279.456281) (xy 83.363277 -279.446437) (xy 83.412452 -279.444456)
			(xy 83.461307 -279.450388) (xy 83.508578 -279.46408) (xy 83.55304 -279.485178) (xy 83.593543 -279.513134)
			(xy 83.629036 -279.547226) (xy 83.658601 -279.58657) (xy 83.681472 -279.630147) (xy 83.697056 -279.676828)
			(xy 83.704951 -279.725405) (xy 83.705446 -279.750012) (xy 83.704951 -279.774619) (xy 83.697056 -279.823196)
			(xy 83.681472 -279.869877) (xy 83.658601 -279.913454) (xy 83.629036 -279.952798) (xy 83.593543 -279.98689)
			(xy 83.55304 -280.014846) (xy 83.508578 -280.035944) (xy 83.461307 -280.049636) (xy 83.412452 -280.055568)
			(xy 83.363277 -280.053587) (xy 83.315058 -280.043743) (xy 83.269042 -280.026291) (xy 83.226421 -280.001684)
			(xy 83.1883 -279.970559) (xy 83.155665 -279.933722) (xy 83.129362 -279.892126) (xy 83.110071 -279.84685)
			(xy 83.098294 -279.799066) (xy 83.094334 -279.750012) (xy 82.777071 -279.750012) (xy 82.776572 -279.775466)
			(xy 82.768529 -279.826248) (xy 82.752641 -279.875147) (xy 82.729298 -279.920959) (xy 82.699077 -279.962555)
			(xy 82.662721 -279.998911) (xy 82.621125 -280.029132) (xy 82.575313 -280.052475) (xy 82.526414 -280.068363)
			(xy 82.475632 -280.076406) (xy 82.424216 -280.076406) (xy 82.373434 -280.068363) (xy 82.324535 -280.052475)
			(xy 82.278723 -280.029132) (xy 82.237127 -279.998911) (xy 82.200771 -279.962555) (xy 82.17055 -279.920959)
			(xy 82.147207 -279.875147) (xy 82.131319 -279.826248) (xy 82.123276 -279.775466) (xy 81.826612 -279.775466)
			(xy 81.818569 -279.826248) (xy 81.802681 -279.875147) (xy 81.779338 -279.920959) (xy 81.749117 -279.962555)
			(xy 81.712761 -279.998911) (xy 81.671165 -280.029132) (xy 81.625353 -280.052475) (xy 81.576454 -280.068363)
			(xy 81.525672 -280.076406) (xy 81.474256 -280.076406) (xy 81.423474 -280.068363) (xy 81.374575 -280.052475)
			(xy 81.328763 -280.029132) (xy 81.287167 -279.998911) (xy 81.250811 -279.962555) (xy 81.22059 -279.920959)
			(xy 81.197247 -279.875147) (xy 81.181359 -279.826248) (xy 81.173316 -279.775466) (xy 80.854384 -279.775466)
			(xy 80.846668 -279.822942) (xy 80.831084 -279.869623) (xy 80.808213 -279.9132) (xy 80.778648 -279.952544)
			(xy 80.743155 -279.986636) (xy 80.702652 -280.014592) (xy 80.65819 -280.03569) (xy 80.610919 -280.049382)
			(xy 80.562064 -280.055314) (xy 80.512889 -280.053333) (xy 80.46467 -280.043489) (xy 80.418654 -280.026037)
			(xy 80.376033 -280.00143) (xy 80.337912 -279.970305) (xy 80.305277 -279.933468) (xy 80.278974 -279.891872)
			(xy 80.259683 -279.846596) (xy 80.247906 -279.798812) (xy 80.243946 -279.749758) (xy 79.926942 -279.749758)
			(xy 79.926438 -279.775466) (xy 79.918395 -279.826248) (xy 79.902507 -279.875147) (xy 79.879164 -279.920959)
			(xy 79.848943 -279.962555) (xy 79.812587 -279.998911) (xy 79.770991 -280.029132) (xy 79.725179 -280.052475)
			(xy 79.67628 -280.068363) (xy 79.625498 -280.076406) (xy 79.574082 -280.076406) (xy 79.5233 -280.068363)
			(xy 79.474401 -280.052475) (xy 79.428589 -280.029132) (xy 79.386993 -279.998911) (xy 79.350637 -279.962555)
			(xy 79.320416 -279.920959) (xy 79.297073 -279.875147) (xy 79.281185 -279.826248) (xy 79.273142 -279.775466)
			(xy 78.954464 -279.775466) (xy 78.946748 -279.822942) (xy 78.931164 -279.869623) (xy 78.908293 -279.9132)
			(xy 78.878728 -279.952544) (xy 78.843235 -279.986636) (xy 78.802732 -280.014592) (xy 78.75827 -280.03569)
			(xy 78.710999 -280.049382) (xy 78.662144 -280.055314) (xy 78.612969 -280.053333) (xy 78.56475 -280.043489)
			(xy 78.518734 -280.026037) (xy 78.476113 -280.00143) (xy 78.437992 -279.970305) (xy 78.405357 -279.933468)
			(xy 78.379054 -279.891872) (xy 78.359763 -279.846596) (xy 78.347986 -279.798812) (xy 78.344026 -279.749758)
			(xy 78.027017 -279.749758) (xy 78.026518 -279.775212) (xy 78.018475 -279.825994) (xy 78.002587 -279.874893)
			(xy 77.979244 -279.920705) (xy 77.949023 -279.962301) (xy 77.912667 -279.998657) (xy 77.871071 -280.028878)
			(xy 77.825259 -280.052221) (xy 77.77636 -280.068109) (xy 77.725578 -280.076152) (xy 77.674162 -280.076152)
			(xy 77.62338 -280.068109) (xy 77.574481 -280.052221) (xy 77.528669 -280.028878) (xy 77.487073 -279.998657)
			(xy 77.450717 -279.962301) (xy 77.420496 -279.920705) (xy 77.397153 -279.874893) (xy 77.381265 -279.825994)
			(xy 77.373222 -279.775212) (xy 77.054585 -279.775212) (xy 77.046828 -279.822942) (xy 77.031244 -279.869623)
			(xy 77.008373 -279.9132) (xy 76.978808 -279.952544) (xy 76.943315 -279.986636) (xy 76.902812 -280.014592)
			(xy 76.85835 -280.03569) (xy 76.811079 -280.049382) (xy 76.762224 -280.055314) (xy 76.713049 -280.053333)
			(xy 76.66483 -280.043489) (xy 76.618814 -280.026037) (xy 76.576193 -280.00143) (xy 76.538072 -279.970305)
			(xy 76.505437 -279.933468) (xy 76.479134 -279.891872) (xy 76.459843 -279.846596) (xy 76.448066 -279.798812)
			(xy 76.444106 -279.749758) (xy 76.127097 -279.749758) (xy 76.126598 -279.775212) (xy 76.118555 -279.825994)
			(xy 76.102667 -279.874893) (xy 76.079324 -279.920705) (xy 76.049103 -279.962301) (xy 76.012747 -279.998657)
			(xy 75.971151 -280.028878) (xy 75.925339 -280.052221) (xy 75.87644 -280.068109) (xy 75.825658 -280.076152)
			(xy 75.774242 -280.076152) (xy 75.72346 -280.068109) (xy 75.674561 -280.052221) (xy 75.628749 -280.028878)
			(xy 75.587153 -279.998657) (xy 75.550797 -279.962301) (xy 75.520576 -279.920705) (xy 75.497233 -279.874893)
			(xy 75.481345 -279.825994) (xy 75.473302 -279.775212) (xy 75.154411 -279.775212) (xy 75.146654 -279.822942)
			(xy 75.13107 -279.869623) (xy 75.108199 -279.9132) (xy 75.078634 -279.952544) (xy 75.043141 -279.986636)
			(xy 75.002638 -280.014592) (xy 74.958176 -280.03569) (xy 74.910905 -280.049382) (xy 74.86205 -280.055314)
			(xy 74.812875 -280.053333) (xy 74.764656 -280.043489) (xy 74.71864 -280.026037) (xy 74.676019 -280.00143)
			(xy 74.637898 -279.970305) (xy 74.605263 -279.933468) (xy 74.57896 -279.891872) (xy 74.559669 -279.846596)
			(xy 74.547892 -279.798812) (xy 74.543932 -279.749758) (xy 74.226923 -279.749758) (xy 74.226424 -279.775212)
			(xy 74.218381 -279.825994) (xy 74.202493 -279.874893) (xy 74.17915 -279.920705) (xy 74.148929 -279.962301)
			(xy 74.112573 -279.998657) (xy 74.070977 -280.028878) (xy 74.025165 -280.052221) (xy 73.976266 -280.068109)
			(xy 73.925484 -280.076152) (xy 73.874068 -280.076152) (xy 73.823286 -280.068109) (xy 73.774387 -280.052221)
			(xy 73.728575 -280.028878) (xy 73.686979 -279.998657) (xy 73.650623 -279.962301) (xy 73.620402 -279.920705)
			(xy 73.597059 -279.874893) (xy 73.581171 -279.825994) (xy 73.573128 -279.775212) (xy 73.254491 -279.775212)
			(xy 73.246734 -279.822942) (xy 73.23115 -279.869623) (xy 73.208279 -279.9132) (xy 73.178714 -279.952544)
			(xy 73.143221 -279.986636) (xy 73.102718 -280.014592) (xy 73.058256 -280.03569) (xy 73.010985 -280.049382)
			(xy 72.96213 -280.055314) (xy 72.912955 -280.053333) (xy 72.864736 -280.043489) (xy 72.81872 -280.026037)
			(xy 72.776099 -280.00143) (xy 72.737978 -279.970305) (xy 72.705343 -279.933468) (xy 72.67904 -279.891872)
			(xy 72.659749 -279.846596) (xy 72.647972 -279.798812) (xy 72.644012 -279.749758) (xy 72.327003 -279.749758)
			(xy 72.326504 -279.775212) (xy 72.318461 -279.825994) (xy 72.302573 -279.874893) (xy 72.27923 -279.920705)
			(xy 72.249009 -279.962301) (xy 72.212653 -279.998657) (xy 72.171057 -280.028878) (xy 72.125245 -280.052221)
			(xy 72.076346 -280.068109) (xy 72.025564 -280.076152) (xy 71.974148 -280.076152) (xy 71.923366 -280.068109)
			(xy 71.874467 -280.052221) (xy 71.828655 -280.028878) (xy 71.787059 -279.998657) (xy 71.750703 -279.962301)
			(xy 71.720482 -279.920705) (xy 71.697139 -279.874893) (xy 71.681251 -279.825994) (xy 71.673208 -279.775212)
			(xy 71.354571 -279.775212) (xy 71.346814 -279.822942) (xy 71.33123 -279.869623) (xy 71.308359 -279.9132)
			(xy 71.278794 -279.952544) (xy 71.243301 -279.986636) (xy 71.202798 -280.014592) (xy 71.158336 -280.03569)
			(xy 71.111065 -280.049382) (xy 71.06221 -280.055314) (xy 71.013035 -280.053333) (xy 70.964816 -280.043489)
			(xy 70.9188 -280.026037) (xy 70.876179 -280.00143) (xy 70.838058 -279.970305) (xy 70.805423 -279.933468)
			(xy 70.77912 -279.891872) (xy 70.759829 -279.846596) (xy 70.748052 -279.798812) (xy 70.744092 -279.749758)
			(xy 70.427083 -279.749758) (xy 70.426584 -279.775212) (xy 70.418541 -279.825994) (xy 70.402653 -279.874893)
			(xy 70.37931 -279.920705) (xy 70.349089 -279.962301) (xy 70.312733 -279.998657) (xy 70.271137 -280.028878)
			(xy 70.225325 -280.052221) (xy 70.176426 -280.068109) (xy 70.125644 -280.076152) (xy 70.074228 -280.076152)
			(xy 70.023446 -280.068109) (xy 69.974547 -280.052221) (xy 69.928735 -280.028878) (xy 69.887139 -279.998657)
			(xy 69.850783 -279.962301) (xy 69.820562 -279.920705) (xy 69.797219 -279.874893) (xy 69.781331 -279.825994)
			(xy 69.773288 -279.775212) (xy 69.454651 -279.775212) (xy 69.446894 -279.822942) (xy 69.43131 -279.869623)
			(xy 69.408439 -279.9132) (xy 69.378874 -279.952544) (xy 69.343381 -279.986636) (xy 69.302878 -280.014592)
			(xy 69.258416 -280.03569) (xy 69.211145 -280.049382) (xy 69.16229 -280.055314) (xy 69.113115 -280.053333)
			(xy 69.064896 -280.043489) (xy 69.01888 -280.026037) (xy 68.976259 -280.00143) (xy 68.938138 -279.970305)
			(xy 68.905503 -279.933468) (xy 68.8792 -279.891872) (xy 68.859909 -279.846596) (xy 68.848132 -279.798812)
			(xy 68.844172 -279.749758) (xy 68.526909 -279.749758) (xy 68.52641 -279.775212) (xy 68.518367 -279.825994)
			(xy 68.502479 -279.874893) (xy 68.479136 -279.920705) (xy 68.448915 -279.962301) (xy 68.412559 -279.998657)
			(xy 68.370963 -280.028878) (xy 68.325151 -280.052221) (xy 68.276252 -280.068109) (xy 68.22547 -280.076152)
			(xy 68.174054 -280.076152) (xy 68.123272 -280.068109) (xy 68.074373 -280.052221) (xy 68.028561 -280.028878)
			(xy 67.986965 -279.998657) (xy 67.950609 -279.962301) (xy 67.920388 -279.920705) (xy 67.897045 -279.874893)
			(xy 67.881157 -279.825994) (xy 67.873114 -279.775212) (xy 67.554477 -279.775212) (xy 67.54672 -279.822942)
			(xy 67.531136 -279.869623) (xy 67.508265 -279.9132) (xy 67.4787 -279.952544) (xy 67.443207 -279.986636)
			(xy 67.402704 -280.014592) (xy 67.358242 -280.03569) (xy 67.310971 -280.049382) (xy 67.262116 -280.055314)
			(xy 67.212941 -280.053333) (xy 67.164722 -280.043489) (xy 67.118706 -280.026037) (xy 67.076085 -280.00143)
			(xy 67.037964 -279.970305) (xy 67.005329 -279.933468) (xy 66.979026 -279.891872) (xy 66.959735 -279.846596)
			(xy 66.947958 -279.798812) (xy 66.943998 -279.749758) (xy 66.626989 -279.749758) (xy 66.62649 -279.775212)
			(xy 66.618447 -279.825994) (xy 66.602559 -279.874893) (xy 66.579216 -279.920705) (xy 66.548995 -279.962301)
			(xy 66.512639 -279.998657) (xy 66.471043 -280.028878) (xy 66.425231 -280.052221) (xy 66.376332 -280.068109)
			(xy 66.32555 -280.076152) (xy 66.274134 -280.076152) (xy 66.223352 -280.068109) (xy 66.174453 -280.052221)
			(xy 66.128641 -280.028878) (xy 66.087045 -279.998657) (xy 66.050689 -279.962301) (xy 66.020468 -279.920705)
			(xy 65.997125 -279.874893) (xy 65.981237 -279.825994) (xy 65.973194 -279.775212) (xy 65.654557 -279.775212)
			(xy 65.6468 -279.822942) (xy 65.631216 -279.869623) (xy 65.608345 -279.9132) (xy 65.57878 -279.952544)
			(xy 65.543287 -279.986636) (xy 65.502784 -280.014592) (xy 65.458322 -280.03569) (xy 65.411051 -280.049382)
			(xy 65.362196 -280.055314) (xy 65.313021 -280.053333) (xy 65.264802 -280.043489) (xy 65.218786 -280.026037)
			(xy 65.176165 -280.00143) (xy 65.138044 -279.970305) (xy 65.105409 -279.933468) (xy 65.079106 -279.891872)
			(xy 65.059815 -279.846596) (xy 65.048038 -279.798812) (xy 65.044078 -279.749758) (xy 64.727069 -279.749758)
			(xy 64.72657 -279.775212) (xy 64.718527 -279.825994) (xy 64.702639 -279.874893) (xy 64.679296 -279.920705)
			(xy 64.649075 -279.962301) (xy 64.612719 -279.998657) (xy 64.571123 -280.028878) (xy 64.525311 -280.052221)
			(xy 64.476412 -280.068109) (xy 64.42563 -280.076152) (xy 64.374214 -280.076152) (xy 64.323432 -280.068109)
			(xy 64.274533 -280.052221) (xy 64.228721 -280.028878) (xy 64.187125 -279.998657) (xy 64.150769 -279.962301)
			(xy 64.120548 -279.920705) (xy 64.097205 -279.874893) (xy 64.081317 -279.825994) (xy 64.073274 -279.775212)
			(xy 63.754637 -279.775212) (xy 63.74688 -279.822942) (xy 63.731296 -279.869623) (xy 63.708425 -279.9132)
			(xy 63.67886 -279.952544) (xy 63.643367 -279.986636) (xy 63.602864 -280.014592) (xy 63.558402 -280.03569)
			(xy 63.511131 -280.049382) (xy 63.462276 -280.055314) (xy 63.413101 -280.053333) (xy 63.364882 -280.043489)
			(xy 63.318866 -280.026037) (xy 63.276245 -280.00143) (xy 63.238124 -279.970305) (xy 63.205489 -279.933468)
			(xy 63.179186 -279.891872) (xy 63.159895 -279.846596) (xy 63.148118 -279.798812) (xy 63.144158 -279.749758)
			(xy 62.826895 -279.749758) (xy 62.826396 -279.775212) (xy 62.818353 -279.825994) (xy 62.802465 -279.874893)
			(xy 62.779122 -279.920705) (xy 62.748901 -279.962301) (xy 62.712545 -279.998657) (xy 62.670949 -280.028878)
			(xy 62.625137 -280.052221) (xy 62.576238 -280.068109) (xy 62.525456 -280.076152) (xy 62.47404 -280.076152)
			(xy 62.423258 -280.068109) (xy 62.374359 -280.052221) (xy 62.328547 -280.028878) (xy 62.286951 -279.998657)
			(xy 62.250595 -279.962301) (xy 62.220374 -279.920705) (xy 62.197031 -279.874893) (xy 62.181143 -279.825994)
			(xy 62.1731 -279.775212) (xy 61.854463 -279.775212) (xy 61.846706 -279.822942) (xy 61.831122 -279.869623)
			(xy 61.808251 -279.9132) (xy 61.778686 -279.952544) (xy 61.743193 -279.986636) (xy 61.70269 -280.014592)
			(xy 61.658228 -280.03569) (xy 61.610957 -280.049382) (xy 61.562102 -280.055314) (xy 61.512927 -280.053333)
			(xy 61.464708 -280.043489) (xy 61.418692 -280.026037) (xy 61.376071 -280.00143) (xy 61.33795 -279.970305)
			(xy 61.305315 -279.933468) (xy 61.279012 -279.891872) (xy 61.259721 -279.846596) (xy 61.247944 -279.798812)
			(xy 61.243984 -279.749758) (xy 60.926975 -279.749758) (xy 60.926476 -279.775212) (xy 60.918433 -279.825994)
			(xy 60.902545 -279.874893) (xy 60.879202 -279.920705) (xy 60.848981 -279.962301) (xy 60.812625 -279.998657)
			(xy 60.771029 -280.028878) (xy 60.725217 -280.052221) (xy 60.676318 -280.068109) (xy 60.625536 -280.076152)
			(xy 60.57412 -280.076152) (xy 60.523338 -280.068109) (xy 60.474439 -280.052221) (xy 60.428627 -280.028878)
			(xy 60.387031 -279.998657) (xy 60.350675 -279.962301) (xy 60.320454 -279.920705) (xy 60.297111 -279.874893)
			(xy 60.281223 -279.825994) (xy 60.27318 -279.775212) (xy 59.954543 -279.775212) (xy 59.946786 -279.822942)
			(xy 59.931202 -279.869623) (xy 59.908331 -279.9132) (xy 59.878766 -279.952544) (xy 59.843273 -279.986636)
			(xy 59.80277 -280.014592) (xy 59.758308 -280.03569) (xy 59.711037 -280.049382) (xy 59.662182 -280.055314)
			(xy 59.613007 -280.053333) (xy 59.564788 -280.043489) (xy 59.518772 -280.026037) (xy 59.476151 -280.00143)
			(xy 59.43803 -279.970305) (xy 59.405395 -279.933468) (xy 59.379092 -279.891872) (xy 59.359801 -279.846596)
			(xy 59.348024 -279.798812) (xy 59.344064 -279.749758) (xy 59.027055 -279.749758) (xy 59.026556 -279.775212)
			(xy 59.018513 -279.825994) (xy 59.002625 -279.874893) (xy 58.979282 -279.920705) (xy 58.949061 -279.962301)
			(xy 58.912705 -279.998657) (xy 58.871109 -280.028878) (xy 58.825297 -280.052221) (xy 58.776398 -280.068109)
			(xy 58.725616 -280.076152) (xy 58.6742 -280.076152) (xy 58.623418 -280.068109) (xy 58.574519 -280.052221)
			(xy 58.528707 -280.028878) (xy 58.487111 -279.998657) (xy 58.450755 -279.962301) (xy 58.420534 -279.920705)
			(xy 58.397191 -279.874893) (xy 58.381303 -279.825994) (xy 58.37326 -279.775212) (xy 58.054623 -279.775212)
			(xy 58.046866 -279.822942) (xy 58.031282 -279.869623) (xy 58.008411 -279.9132) (xy 57.978846 -279.952544)
			(xy 57.943353 -279.986636) (xy 57.90285 -280.014592) (xy 57.858388 -280.03569) (xy 57.811117 -280.049382)
			(xy 57.762262 -280.055314) (xy 57.713087 -280.053333) (xy 57.664868 -280.043489) (xy 57.618852 -280.026037)
			(xy 57.576231 -280.00143) (xy 57.53811 -279.970305) (xy 57.505475 -279.933468) (xy 57.479172 -279.891872)
			(xy 57.459881 -279.846596) (xy 57.448104 -279.798812) (xy 57.444144 -279.749758) (xy 57.126881 -279.749758)
			(xy 57.126382 -279.775212) (xy 57.118339 -279.825994) (xy 57.102451 -279.874893) (xy 57.079108 -279.920705)
			(xy 57.048887 -279.962301) (xy 57.012531 -279.998657) (xy 56.970935 -280.028878) (xy 56.925123 -280.052221)
			(xy 56.876224 -280.068109) (xy 56.825442 -280.076152) (xy 56.774026 -280.076152) (xy 56.723244 -280.068109)
			(xy 56.674345 -280.052221) (xy 56.628533 -280.028878) (xy 56.586937 -279.998657) (xy 56.550581 -279.962301)
			(xy 56.52036 -279.920705) (xy 56.497017 -279.874893) (xy 56.481129 -279.825994) (xy 56.473086 -279.775212)
			(xy 56.154449 -279.775212) (xy 56.146692 -279.822942) (xy 56.131108 -279.869623) (xy 56.108237 -279.9132)
			(xy 56.078672 -279.952544) (xy 56.043179 -279.986636) (xy 56.002676 -280.014592) (xy 55.958214 -280.03569)
			(xy 55.910943 -280.049382) (xy 55.862088 -280.055314) (xy 55.812913 -280.053333) (xy 55.764694 -280.043489)
			(xy 55.718678 -280.026037) (xy 55.676057 -280.00143) (xy 55.637936 -279.970305) (xy 55.605301 -279.933468)
			(xy 55.578998 -279.891872) (xy 55.559707 -279.846596) (xy 55.54793 -279.798812) (xy 55.54397 -279.749758)
			(xy 55.226961 -279.749758) (xy 55.226462 -279.775212) (xy 55.218419 -279.825994) (xy 55.202531 -279.874893)
			(xy 55.179188 -279.920705) (xy 55.148967 -279.962301) (xy 55.112611 -279.998657) (xy 55.071015 -280.028878)
			(xy 55.025203 -280.052221) (xy 54.976304 -280.068109) (xy 54.925522 -280.076152) (xy 54.874106 -280.076152)
			(xy 54.823324 -280.068109) (xy 54.774425 -280.052221) (xy 54.728613 -280.028878) (xy 54.687017 -279.998657)
			(xy 54.650661 -279.962301) (xy 54.62044 -279.920705) (xy 54.597097 -279.874893) (xy 54.581209 -279.825994)
			(xy 54.573166 -279.775212) (xy 54.254529 -279.775212) (xy 54.246772 -279.822942) (xy 54.231188 -279.869623)
			(xy 54.208317 -279.9132) (xy 54.178752 -279.952544) (xy 54.143259 -279.986636) (xy 54.102756 -280.014592)
			(xy 54.058294 -280.03569) (xy 54.011023 -280.049382) (xy 53.962168 -280.055314) (xy 53.912993 -280.053333)
			(xy 53.864774 -280.043489) (xy 53.818758 -280.026037) (xy 53.776137 -280.00143) (xy 53.738016 -279.970305)
			(xy 53.705381 -279.933468) (xy 53.679078 -279.891872) (xy 53.659787 -279.846596) (xy 53.64801 -279.798812)
			(xy 53.64405 -279.749758) (xy 53.327041 -279.749758) (xy 53.326542 -279.775212) (xy 53.318499 -279.825994)
			(xy 53.302611 -279.874893) (xy 53.279268 -279.920705) (xy 53.249047 -279.962301) (xy 53.212691 -279.998657)
			(xy 53.171095 -280.028878) (xy 53.125283 -280.052221) (xy 53.076384 -280.068109) (xy 53.025602 -280.076152)
			(xy 52.974186 -280.076152) (xy 52.923404 -280.068109) (xy 52.874505 -280.052221) (xy 52.828693 -280.028878)
			(xy 52.787097 -279.998657) (xy 52.750741 -279.962301) (xy 52.72052 -279.920705) (xy 52.697177 -279.874893)
			(xy 52.681289 -279.825994) (xy 52.673246 -279.775212) (xy 52.354609 -279.775212) (xy 52.346852 -279.822942)
			(xy 52.331268 -279.869623) (xy 52.308397 -279.9132) (xy 52.278832 -279.952544) (xy 52.243339 -279.986636)
			(xy 52.202836 -280.014592) (xy 52.158374 -280.03569) (xy 52.111103 -280.049382) (xy 52.062248 -280.055314)
			(xy 52.013073 -280.053333) (xy 51.964854 -280.043489) (xy 51.918838 -280.026037) (xy 51.876217 -280.00143)
			(xy 51.838096 -279.970305) (xy 51.805461 -279.933468) (xy 51.779158 -279.891872) (xy 51.759867 -279.846596)
			(xy 51.74809 -279.798812) (xy 51.74413 -279.749758) (xy 51.427121 -279.749758) (xy 51.426622 -279.775212)
			(xy 51.418579 -279.825994) (xy 51.402691 -279.874893) (xy 51.379348 -279.920705) (xy 51.349127 -279.962301)
			(xy 51.312771 -279.998657) (xy 51.271175 -280.028878) (xy 51.225363 -280.052221) (xy 51.176464 -280.068109)
			(xy 51.125682 -280.076152) (xy 51.074266 -280.076152) (xy 51.023484 -280.068109) (xy 50.974585 -280.052221)
			(xy 50.928773 -280.028878) (xy 50.887177 -279.998657) (xy 50.850821 -279.962301) (xy 50.8206 -279.920705)
			(xy 50.797257 -279.874893) (xy 50.781369 -279.825994) (xy 50.773326 -279.775212) (xy 50.454435 -279.775212)
			(xy 50.446678 -279.822942) (xy 50.431094 -279.869623) (xy 50.408223 -279.9132) (xy 50.378658 -279.952544)
			(xy 50.343165 -279.986636) (xy 50.302662 -280.014592) (xy 50.2582 -280.03569) (xy 50.210929 -280.049382)
			(xy 50.162074 -280.055314) (xy 50.112899 -280.053333) (xy 50.06468 -280.043489) (xy 50.018664 -280.026037)
			(xy 49.976043 -280.00143) (xy 49.937922 -279.970305) (xy 49.905287 -279.933468) (xy 49.878984 -279.891872)
			(xy 49.859693 -279.846596) (xy 49.847916 -279.798812) (xy 49.843956 -279.749758) (xy 49.526947 -279.749758)
			(xy 49.526448 -279.775212) (xy 49.518405 -279.825994) (xy 49.502517 -279.874893) (xy 49.479174 -279.920705)
			(xy 49.448953 -279.962301) (xy 49.412597 -279.998657) (xy 49.371001 -280.028878) (xy 49.325189 -280.052221)
			(xy 49.27629 -280.068109) (xy 49.225508 -280.076152) (xy 49.174092 -280.076152) (xy 49.12331 -280.068109)
			(xy 49.074411 -280.052221) (xy 49.028599 -280.028878) (xy 48.987003 -279.998657) (xy 48.950647 -279.962301)
			(xy 48.920426 -279.920705) (xy 48.897083 -279.874893) (xy 48.881195 -279.825994) (xy 48.873152 -279.775212)
			(xy 48.554515 -279.775212) (xy 48.546758 -279.822942) (xy 48.531174 -279.869623) (xy 48.508303 -279.9132)
			(xy 48.478738 -279.952544) (xy 48.443245 -279.986636) (xy 48.402742 -280.014592) (xy 48.35828 -280.03569)
			(xy 48.311009 -280.049382) (xy 48.262154 -280.055314) (xy 48.212979 -280.053333) (xy 48.16476 -280.043489)
			(xy 48.118744 -280.026037) (xy 48.076123 -280.00143) (xy 48.038002 -279.970305) (xy 48.005367 -279.933468)
			(xy 47.979064 -279.891872) (xy 47.959773 -279.846596) (xy 47.947996 -279.798812) (xy 47.944036 -279.749758)
			(xy 47.627027 -279.749758) (xy 47.626528 -279.775212) (xy 47.618485 -279.825994) (xy 47.602597 -279.874893)
			(xy 47.579254 -279.920705) (xy 47.549033 -279.962301) (xy 47.512677 -279.998657) (xy 47.471081 -280.028878)
			(xy 47.425269 -280.052221) (xy 47.37637 -280.068109) (xy 47.325588 -280.076152) (xy 47.274172 -280.076152)
			(xy 47.22339 -280.068109) (xy 47.174491 -280.052221) (xy 47.128679 -280.028878) (xy 47.087083 -279.998657)
			(xy 47.050727 -279.962301) (xy 47.020506 -279.920705) (xy 46.997163 -279.874893) (xy 46.981275 -279.825994)
			(xy 46.973232 -279.775212) (xy 46.654595 -279.775212) (xy 46.646838 -279.822942) (xy 46.631254 -279.869623)
			(xy 46.608383 -279.9132) (xy 46.578818 -279.952544) (xy 46.543325 -279.986636) (xy 46.502822 -280.014592)
			(xy 46.45836 -280.03569) (xy 46.411089 -280.049382) (xy 46.362234 -280.055314) (xy 46.313059 -280.053333)
			(xy 46.26484 -280.043489) (xy 46.218824 -280.026037) (xy 46.176203 -280.00143) (xy 46.138082 -279.970305)
			(xy 46.105447 -279.933468) (xy 46.079144 -279.891872) (xy 46.059853 -279.846596) (xy 46.048076 -279.798812)
			(xy 46.044116 -279.749758) (xy 45.727107 -279.749758) (xy 45.726608 -279.775212) (xy 45.718565 -279.825994)
			(xy 45.702677 -279.874893) (xy 45.679334 -279.920705) (xy 45.649113 -279.962301) (xy 45.612757 -279.998657)
			(xy 45.571161 -280.028878) (xy 45.525349 -280.052221) (xy 45.47645 -280.068109) (xy 45.425668 -280.076152)
			(xy 45.374252 -280.076152) (xy 45.32347 -280.068109) (xy 45.274571 -280.052221) (xy 45.228759 -280.028878)
			(xy 45.187163 -279.998657) (xy 45.150807 -279.962301) (xy 45.120586 -279.920705) (xy 45.097243 -279.874893)
			(xy 45.081355 -279.825994) (xy 45.073312 -279.775212) (xy 44.754421 -279.775212) (xy 44.746664 -279.822942)
			(xy 44.73108 -279.869623) (xy 44.708209 -279.9132) (xy 44.678644 -279.952544) (xy 44.643151 -279.986636)
			(xy 44.602648 -280.014592) (xy 44.558186 -280.03569) (xy 44.510915 -280.049382) (xy 44.46206 -280.055314)
			(xy 44.412885 -280.053333) (xy 44.364666 -280.043489) (xy 44.31865 -280.026037) (xy 44.276029 -280.00143)
			(xy 44.237908 -279.970305) (xy 44.205273 -279.933468) (xy 44.17897 -279.891872) (xy 44.159679 -279.846596)
			(xy 44.147902 -279.798812) (xy 44.143942 -279.749758) (xy 40.899334 -279.749758) (xy 40.899334 -279.837134)
			(xy 40.900007 -279.849157) (xy 40.910878 -279.87061) (xy 40.920162 -279.878282) (xy 40.996362 -279.933908)
			(xy 41.020238 -279.937718) (xy 41.031922 -279.933908) (xy 41.054563 -279.927135) (xy 41.101257 -279.919864)
			(xy 41.124886 -279.91943) (xy 41.150141 -279.919921) (xy 41.199963 -279.928233) (xy 41.247738 -279.944632)
			(xy 41.292161 -279.968671) (xy 41.332022 -279.999694) (xy 41.366233 -280.036856) (xy 41.39386 -280.079141)
			(xy 41.414151 -280.125397) (xy 41.426551 -280.174362) (xy 41.430722 -280.2247) (xy 41.430719 -280.224738)
			(xy 41.769042 -280.224738) (xy 41.773002 -280.175684) (xy 41.784779 -280.1279) (xy 41.80407 -280.082624)
			(xy 41.830373 -280.041028) (xy 41.863008 -280.004191) (xy 41.901129 -279.973066) (xy 41.94375 -279.948459)
			(xy 41.989766 -279.931007) (xy 42.037985 -279.921163) (xy 42.08716 -279.919182) (xy 42.136015 -279.925114)
			(xy 42.183286 -279.938806) (xy 42.227748 -279.959904) (xy 42.268251 -279.98786) (xy 42.303744 -280.021952)
			(xy 42.333309 -280.061296) (xy 42.35618 -280.104873) (xy 42.371764 -280.151554) (xy 42.379659 -280.200131)
			(xy 42.380154 -280.224738) (xy 42.719002 -280.224738) (xy 42.722962 -280.175684) (xy 42.734739 -280.1279)
			(xy 42.75403 -280.082624) (xy 42.780333 -280.041028) (xy 42.812968 -280.004191) (xy 42.851089 -279.973066)
			(xy 42.89371 -279.948459) (xy 42.939726 -279.931007) (xy 42.987945 -279.921163) (xy 43.03712 -279.919182)
			(xy 43.085975 -279.925114) (xy 43.133246 -279.938806) (xy 43.177708 -279.959904) (xy 43.218211 -279.98786)
			(xy 43.253704 -280.021952) (xy 43.283269 -280.061296) (xy 43.30614 -280.104873) (xy 43.321724 -280.151554)
			(xy 43.329619 -280.200131) (xy 43.330114 -280.224738) (xy 43.329619 -280.249345) (xy 43.321724 -280.297922)
			(xy 43.30614 -280.344603) (xy 43.283269 -280.38818) (xy 43.253704 -280.427524) (xy 43.218211 -280.461616)
			(xy 43.177708 -280.489572) (xy 43.133246 -280.51067) (xy 43.085975 -280.524362) (xy 43.03712 -280.530294)
			(xy 42.987945 -280.528313) (xy 42.939726 -280.518469) (xy 42.89371 -280.501017) (xy 42.851089 -280.47641)
			(xy 42.812968 -280.445285) (xy 42.780333 -280.408448) (xy 42.75403 -280.366852) (xy 42.734739 -280.321576)
			(xy 42.722962 -280.273792) (xy 42.719002 -280.224738) (xy 42.380154 -280.224738) (xy 42.379659 -280.249345)
			(xy 42.371764 -280.297922) (xy 42.35618 -280.344603) (xy 42.333309 -280.38818) (xy 42.303744 -280.427524)
			(xy 42.268251 -280.461616) (xy 42.227748 -280.489572) (xy 42.183286 -280.51067) (xy 42.136015 -280.524362)
			(xy 42.08716 -280.530294) (xy 42.037985 -280.528313) (xy 41.989766 -280.518469) (xy 41.94375 -280.501017)
			(xy 41.901129 -280.47641) (xy 41.863008 -280.445285) (xy 41.830373 -280.408448) (xy 41.80407 -280.366852)
			(xy 41.784779 -280.321576) (xy 41.773002 -280.273792) (xy 41.769042 -280.224738) (xy 41.430719 -280.224738)
			(xy 41.426551 -280.275038) (xy 41.414151 -280.324003) (xy 41.39386 -280.370259) (xy 41.366233 -280.412544)
			(xy 41.332022 -280.449706) (xy 41.292161 -280.480729) (xy 41.247738 -280.504768) (xy 41.199963 -280.521167)
			(xy 41.150141 -280.529479) (xy 41.124886 -280.530046) (xy 41.101259 -280.529599) (xy 41.054568 -280.522321)
			(xy 41.031922 -280.515568) (xy 41.020238 -280.511758) (xy 40.996362 -280.515568) (xy 40.920162 -280.571194)
			(xy 40.910824 -280.578818) (xy 40.899967 -280.600302) (xy 40.899334 -280.612342) (xy 40.899334 -280.699718)
			(xy 44.143942 -280.699718) (xy 44.147902 -280.650664) (xy 44.159679 -280.60288) (xy 44.17897 -280.557604)
			(xy 44.205273 -280.516008) (xy 44.237908 -280.479171) (xy 44.276029 -280.448046) (xy 44.31865 -280.423439)
			(xy 44.364666 -280.405987) (xy 44.412885 -280.396143) (xy 44.46206 -280.394162) (xy 44.510915 -280.400094)
			(xy 44.558186 -280.413786) (xy 44.602648 -280.434884) (xy 44.643151 -280.46284) (xy 44.678644 -280.496932)
			(xy 44.708209 -280.536276) (xy 44.73108 -280.579853) (xy 44.746664 -280.626534) (xy 44.754559 -280.675111)
			(xy 44.755054 -280.699718) (xy 44.754559 -280.724325) (xy 44.75438 -280.725426) (xy 45.073312 -280.725426)
			(xy 45.073312 -280.67401) (xy 45.081355 -280.623228) (xy 45.097243 -280.574329) (xy 45.120586 -280.528517)
			(xy 45.150807 -280.486921) (xy 45.187163 -280.450565) (xy 45.228759 -280.420344) (xy 45.274571 -280.397001)
			(xy 45.32347 -280.381113) (xy 45.374252 -280.37307) (xy 45.425668 -280.37307) (xy 45.47645 -280.381113)
			(xy 45.525349 -280.397001) (xy 45.571161 -280.420344) (xy 45.612757 -280.450565) (xy 45.649113 -280.486921)
			(xy 45.679334 -280.528517) (xy 45.702677 -280.574329) (xy 45.718565 -280.623228) (xy 45.726608 -280.67401)
			(xy 45.727112 -280.699718) (xy 46.044116 -280.699718) (xy 46.048076 -280.650664) (xy 46.059853 -280.60288)
			(xy 46.079144 -280.557604) (xy 46.105447 -280.516008) (xy 46.138082 -280.479171) (xy 46.176203 -280.448046)
			(xy 46.218824 -280.423439) (xy 46.26484 -280.405987) (xy 46.313059 -280.396143) (xy 46.362234 -280.394162)
			(xy 46.411089 -280.400094) (xy 46.45836 -280.413786) (xy 46.502822 -280.434884) (xy 46.543325 -280.46284)
			(xy 46.578818 -280.496932) (xy 46.608383 -280.536276) (xy 46.631254 -280.579853) (xy 46.646838 -280.626534)
			(xy 46.654733 -280.675111) (xy 46.655228 -280.699718) (xy 46.654733 -280.724325) (xy 46.654554 -280.725426)
			(xy 46.973232 -280.725426) (xy 46.973232 -280.67401) (xy 46.981275 -280.623228) (xy 46.997163 -280.574329)
			(xy 47.020506 -280.528517) (xy 47.050727 -280.486921) (xy 47.087083 -280.450565) (xy 47.128679 -280.420344)
			(xy 47.174491 -280.397001) (xy 47.22339 -280.381113) (xy 47.274172 -280.37307) (xy 47.325588 -280.37307)
			(xy 47.37637 -280.381113) (xy 47.425269 -280.397001) (xy 47.471081 -280.420344) (xy 47.512677 -280.450565)
			(xy 47.549033 -280.486921) (xy 47.579254 -280.528517) (xy 47.602597 -280.574329) (xy 47.618485 -280.623228)
			(xy 47.626528 -280.67401) (xy 47.627032 -280.699718) (xy 47.944036 -280.699718) (xy 47.947996 -280.650664)
			(xy 47.959773 -280.60288) (xy 47.979064 -280.557604) (xy 48.005367 -280.516008) (xy 48.038002 -280.479171)
			(xy 48.076123 -280.448046) (xy 48.118744 -280.423439) (xy 48.16476 -280.405987) (xy 48.212979 -280.396143)
			(xy 48.262154 -280.394162) (xy 48.311009 -280.400094) (xy 48.35828 -280.413786) (xy 48.402742 -280.434884)
			(xy 48.443245 -280.46284) (xy 48.478738 -280.496932) (xy 48.508303 -280.536276) (xy 48.531174 -280.579853)
			(xy 48.546758 -280.626534) (xy 48.554653 -280.675111) (xy 48.555148 -280.699718) (xy 48.554653 -280.724325)
			(xy 48.554474 -280.725426) (xy 48.873152 -280.725426) (xy 48.873152 -280.67401) (xy 48.881195 -280.623228)
			(xy 48.897083 -280.574329) (xy 48.920426 -280.528517) (xy 48.950647 -280.486921) (xy 48.987003 -280.450565)
			(xy 49.028599 -280.420344) (xy 49.074411 -280.397001) (xy 49.12331 -280.381113) (xy 49.174092 -280.37307)
			(xy 49.225508 -280.37307) (xy 49.27629 -280.381113) (xy 49.325189 -280.397001) (xy 49.371001 -280.420344)
			(xy 49.412597 -280.450565) (xy 49.448953 -280.486921) (xy 49.479174 -280.528517) (xy 49.502517 -280.574329)
			(xy 49.518405 -280.623228) (xy 49.526448 -280.67401) (xy 49.526952 -280.699718) (xy 49.843956 -280.699718)
			(xy 49.847916 -280.650664) (xy 49.859693 -280.60288) (xy 49.878984 -280.557604) (xy 49.905287 -280.516008)
			(xy 49.937922 -280.479171) (xy 49.976043 -280.448046) (xy 50.018664 -280.423439) (xy 50.06468 -280.405987)
			(xy 50.112899 -280.396143) (xy 50.162074 -280.394162) (xy 50.210929 -280.400094) (xy 50.2582 -280.413786)
			(xy 50.302662 -280.434884) (xy 50.343165 -280.46284) (xy 50.378658 -280.496932) (xy 50.408223 -280.536276)
			(xy 50.431094 -280.579853) (xy 50.446678 -280.626534) (xy 50.454573 -280.675111) (xy 50.455068 -280.699718)
			(xy 50.454573 -280.724325) (xy 50.454394 -280.725426) (xy 50.773326 -280.725426) (xy 50.773326 -280.67401)
			(xy 50.781369 -280.623228) (xy 50.797257 -280.574329) (xy 50.8206 -280.528517) (xy 50.850821 -280.486921)
			(xy 50.887177 -280.450565) (xy 50.928773 -280.420344) (xy 50.974585 -280.397001) (xy 51.023484 -280.381113)
			(xy 51.074266 -280.37307) (xy 51.125682 -280.37307) (xy 51.176464 -280.381113) (xy 51.225363 -280.397001)
			(xy 51.271175 -280.420344) (xy 51.312771 -280.450565) (xy 51.349127 -280.486921) (xy 51.379348 -280.528517)
			(xy 51.402691 -280.574329) (xy 51.418579 -280.623228) (xy 51.426622 -280.67401) (xy 51.427126 -280.699718)
			(xy 51.74413 -280.699718) (xy 51.74809 -280.650664) (xy 51.759867 -280.60288) (xy 51.779158 -280.557604)
			(xy 51.805461 -280.516008) (xy 51.838096 -280.479171) (xy 51.876217 -280.448046) (xy 51.918838 -280.423439)
			(xy 51.964854 -280.405987) (xy 52.013073 -280.396143) (xy 52.062248 -280.394162) (xy 52.111103 -280.400094)
			(xy 52.158374 -280.413786) (xy 52.202836 -280.434884) (xy 52.243339 -280.46284) (xy 52.278832 -280.496932)
			(xy 52.308397 -280.536276) (xy 52.331268 -280.579853) (xy 52.346852 -280.626534) (xy 52.354747 -280.675111)
			(xy 52.355242 -280.699718) (xy 52.354747 -280.724325) (xy 52.354568 -280.725426) (xy 52.673246 -280.725426)
			(xy 52.673246 -280.67401) (xy 52.681289 -280.623228) (xy 52.697177 -280.574329) (xy 52.72052 -280.528517)
			(xy 52.750741 -280.486921) (xy 52.787097 -280.450565) (xy 52.828693 -280.420344) (xy 52.874505 -280.397001)
			(xy 52.923404 -280.381113) (xy 52.974186 -280.37307) (xy 53.025602 -280.37307) (xy 53.076384 -280.381113)
			(xy 53.125283 -280.397001) (xy 53.171095 -280.420344) (xy 53.212691 -280.450565) (xy 53.249047 -280.486921)
			(xy 53.279268 -280.528517) (xy 53.302611 -280.574329) (xy 53.318499 -280.623228) (xy 53.326542 -280.67401)
			(xy 53.327046 -280.699718) (xy 53.64405 -280.699718) (xy 53.64801 -280.650664) (xy 53.659787 -280.60288)
			(xy 53.679078 -280.557604) (xy 53.705381 -280.516008) (xy 53.738016 -280.479171) (xy 53.776137 -280.448046)
			(xy 53.818758 -280.423439) (xy 53.864774 -280.405987) (xy 53.912993 -280.396143) (xy 53.962168 -280.394162)
			(xy 54.011023 -280.400094) (xy 54.058294 -280.413786) (xy 54.102756 -280.434884) (xy 54.143259 -280.46284)
			(xy 54.178752 -280.496932) (xy 54.208317 -280.536276) (xy 54.231188 -280.579853) (xy 54.246772 -280.626534)
			(xy 54.254667 -280.675111) (xy 54.255162 -280.699718) (xy 54.254667 -280.724325) (xy 54.254488 -280.725426)
			(xy 54.573166 -280.725426) (xy 54.573166 -280.67401) (xy 54.581209 -280.623228) (xy 54.597097 -280.574329)
			(xy 54.62044 -280.528517) (xy 54.650661 -280.486921) (xy 54.687017 -280.450565) (xy 54.728613 -280.420344)
			(xy 54.774425 -280.397001) (xy 54.823324 -280.381113) (xy 54.874106 -280.37307) (xy 54.925522 -280.37307)
			(xy 54.976304 -280.381113) (xy 55.025203 -280.397001) (xy 55.071015 -280.420344) (xy 55.112611 -280.450565)
			(xy 55.148967 -280.486921) (xy 55.179188 -280.528517) (xy 55.202531 -280.574329) (xy 55.218419 -280.623228)
			(xy 55.226462 -280.67401) (xy 55.226966 -280.699718) (xy 55.54397 -280.699718) (xy 55.54793 -280.650664)
			(xy 55.559707 -280.60288) (xy 55.578998 -280.557604) (xy 55.605301 -280.516008) (xy 55.637936 -280.479171)
			(xy 55.676057 -280.448046) (xy 55.718678 -280.423439) (xy 55.764694 -280.405987) (xy 55.812913 -280.396143)
			(xy 55.862088 -280.394162) (xy 55.910943 -280.400094) (xy 55.958214 -280.413786) (xy 56.002676 -280.434884)
			(xy 56.043179 -280.46284) (xy 56.078672 -280.496932) (xy 56.108237 -280.536276) (xy 56.131108 -280.579853)
			(xy 56.146692 -280.626534) (xy 56.154587 -280.675111) (xy 56.155082 -280.699718) (xy 56.154587 -280.724325)
			(xy 56.154408 -280.725426) (xy 56.473086 -280.725426) (xy 56.473086 -280.67401) (xy 56.481129 -280.623228)
			(xy 56.497017 -280.574329) (xy 56.52036 -280.528517) (xy 56.550581 -280.486921) (xy 56.586937 -280.450565)
			(xy 56.628533 -280.420344) (xy 56.674345 -280.397001) (xy 56.723244 -280.381113) (xy 56.774026 -280.37307)
			(xy 56.825442 -280.37307) (xy 56.876224 -280.381113) (xy 56.925123 -280.397001) (xy 56.970935 -280.420344)
			(xy 57.012531 -280.450565) (xy 57.048887 -280.486921) (xy 57.079108 -280.528517) (xy 57.102451 -280.574329)
			(xy 57.118339 -280.623228) (xy 57.126382 -280.67401) (xy 57.126886 -280.699718) (xy 57.444144 -280.699718)
			(xy 57.448104 -280.650664) (xy 57.459881 -280.60288) (xy 57.479172 -280.557604) (xy 57.505475 -280.516008)
			(xy 57.53811 -280.479171) (xy 57.576231 -280.448046) (xy 57.618852 -280.423439) (xy 57.664868 -280.405987)
			(xy 57.713087 -280.396143) (xy 57.762262 -280.394162) (xy 57.811117 -280.400094) (xy 57.858388 -280.413786)
			(xy 57.90285 -280.434884) (xy 57.943353 -280.46284) (xy 57.978846 -280.496932) (xy 58.008411 -280.536276)
			(xy 58.031282 -280.579853) (xy 58.046866 -280.626534) (xy 58.054761 -280.675111) (xy 58.055256 -280.699718)
			(xy 58.054761 -280.724325) (xy 58.054582 -280.725426) (xy 58.37326 -280.725426) (xy 58.37326 -280.67401)
			(xy 58.381303 -280.623228) (xy 58.397191 -280.574329) (xy 58.420534 -280.528517) (xy 58.450755 -280.486921)
			(xy 58.487111 -280.450565) (xy 58.528707 -280.420344) (xy 58.574519 -280.397001) (xy 58.623418 -280.381113)
			(xy 58.6742 -280.37307) (xy 58.725616 -280.37307) (xy 58.776398 -280.381113) (xy 58.825297 -280.397001)
			(xy 58.871109 -280.420344) (xy 58.912705 -280.450565) (xy 58.949061 -280.486921) (xy 58.979282 -280.528517)
			(xy 59.002625 -280.574329) (xy 59.018513 -280.623228) (xy 59.026556 -280.67401) (xy 59.02706 -280.699718)
			(xy 59.344064 -280.699718) (xy 59.348024 -280.650664) (xy 59.359801 -280.60288) (xy 59.379092 -280.557604)
			(xy 59.405395 -280.516008) (xy 59.43803 -280.479171) (xy 59.476151 -280.448046) (xy 59.518772 -280.423439)
			(xy 59.564788 -280.405987) (xy 59.613007 -280.396143) (xy 59.662182 -280.394162) (xy 59.711037 -280.400094)
			(xy 59.758308 -280.413786) (xy 59.80277 -280.434884) (xy 59.843273 -280.46284) (xy 59.878766 -280.496932)
			(xy 59.908331 -280.536276) (xy 59.931202 -280.579853) (xy 59.946786 -280.626534) (xy 59.954681 -280.675111)
			(xy 59.955176 -280.699718) (xy 59.954681 -280.724325) (xy 59.954502 -280.725426) (xy 60.27318 -280.725426)
			(xy 60.27318 -280.67401) (xy 60.281223 -280.623228) (xy 60.297111 -280.574329) (xy 60.320454 -280.528517)
			(xy 60.350675 -280.486921) (xy 60.387031 -280.450565) (xy 60.428627 -280.420344) (xy 60.474439 -280.397001)
			(xy 60.523338 -280.381113) (xy 60.57412 -280.37307) (xy 60.625536 -280.37307) (xy 60.676318 -280.381113)
			(xy 60.725217 -280.397001) (xy 60.771029 -280.420344) (xy 60.812625 -280.450565) (xy 60.848981 -280.486921)
			(xy 60.879202 -280.528517) (xy 60.902545 -280.574329) (xy 60.918433 -280.623228) (xy 60.926476 -280.67401)
			(xy 60.92698 -280.699718) (xy 61.243984 -280.699718) (xy 61.247944 -280.650664) (xy 61.259721 -280.60288)
			(xy 61.279012 -280.557604) (xy 61.305315 -280.516008) (xy 61.33795 -280.479171) (xy 61.376071 -280.448046)
			(xy 61.418692 -280.423439) (xy 61.464708 -280.405987) (xy 61.512927 -280.396143) (xy 61.562102 -280.394162)
			(xy 61.610957 -280.400094) (xy 61.658228 -280.413786) (xy 61.70269 -280.434884) (xy 61.743193 -280.46284)
			(xy 61.778686 -280.496932) (xy 61.808251 -280.536276) (xy 61.831122 -280.579853) (xy 61.846706 -280.626534)
			(xy 61.854601 -280.675111) (xy 61.855096 -280.699718) (xy 61.854601 -280.724325) (xy 61.854422 -280.725426)
			(xy 62.1731 -280.725426) (xy 62.1731 -280.67401) (xy 62.181143 -280.623228) (xy 62.197031 -280.574329)
			(xy 62.220374 -280.528517) (xy 62.250595 -280.486921) (xy 62.286951 -280.450565) (xy 62.328547 -280.420344)
			(xy 62.374359 -280.397001) (xy 62.423258 -280.381113) (xy 62.47404 -280.37307) (xy 62.525456 -280.37307)
			(xy 62.576238 -280.381113) (xy 62.625137 -280.397001) (xy 62.670949 -280.420344) (xy 62.712545 -280.450565)
			(xy 62.748901 -280.486921) (xy 62.779122 -280.528517) (xy 62.802465 -280.574329) (xy 62.818353 -280.623228)
			(xy 62.826396 -280.67401) (xy 62.8269 -280.699718) (xy 63.144158 -280.699718) (xy 63.148118 -280.650664)
			(xy 63.159895 -280.60288) (xy 63.179186 -280.557604) (xy 63.205489 -280.516008) (xy 63.238124 -280.479171)
			(xy 63.276245 -280.448046) (xy 63.318866 -280.423439) (xy 63.364882 -280.405987) (xy 63.413101 -280.396143)
			(xy 63.462276 -280.394162) (xy 63.511131 -280.400094) (xy 63.558402 -280.413786) (xy 63.602864 -280.434884)
			(xy 63.643367 -280.46284) (xy 63.67886 -280.496932) (xy 63.708425 -280.536276) (xy 63.731296 -280.579853)
			(xy 63.74688 -280.626534) (xy 63.754775 -280.675111) (xy 63.75527 -280.699718) (xy 63.754775 -280.724325)
			(xy 63.754596 -280.725426) (xy 64.073274 -280.725426) (xy 64.073274 -280.67401) (xy 64.081317 -280.623228)
			(xy 64.097205 -280.574329) (xy 64.120548 -280.528517) (xy 64.150769 -280.486921) (xy 64.187125 -280.450565)
			(xy 64.228721 -280.420344) (xy 64.274533 -280.397001) (xy 64.323432 -280.381113) (xy 64.374214 -280.37307)
			(xy 64.42563 -280.37307) (xy 64.476412 -280.381113) (xy 64.525311 -280.397001) (xy 64.571123 -280.420344)
			(xy 64.612719 -280.450565) (xy 64.649075 -280.486921) (xy 64.679296 -280.528517) (xy 64.702639 -280.574329)
			(xy 64.718527 -280.623228) (xy 64.72657 -280.67401) (xy 64.727074 -280.699718) (xy 65.044078 -280.699718)
			(xy 65.048038 -280.650664) (xy 65.059815 -280.60288) (xy 65.079106 -280.557604) (xy 65.105409 -280.516008)
			(xy 65.138044 -280.479171) (xy 65.176165 -280.448046) (xy 65.218786 -280.423439) (xy 65.264802 -280.405987)
			(xy 65.313021 -280.396143) (xy 65.362196 -280.394162) (xy 65.411051 -280.400094) (xy 65.458322 -280.413786)
			(xy 65.502784 -280.434884) (xy 65.543287 -280.46284) (xy 65.57878 -280.496932) (xy 65.608345 -280.536276)
			(xy 65.631216 -280.579853) (xy 65.6468 -280.626534) (xy 65.654695 -280.675111) (xy 65.65519 -280.699718)
			(xy 65.654695 -280.724325) (xy 65.654516 -280.725426) (xy 65.973194 -280.725426) (xy 65.973194 -280.67401)
			(xy 65.981237 -280.623228) (xy 65.997125 -280.574329) (xy 66.020468 -280.528517) (xy 66.050689 -280.486921)
			(xy 66.087045 -280.450565) (xy 66.128641 -280.420344) (xy 66.174453 -280.397001) (xy 66.223352 -280.381113)
			(xy 66.274134 -280.37307) (xy 66.32555 -280.37307) (xy 66.376332 -280.381113) (xy 66.425231 -280.397001)
			(xy 66.471043 -280.420344) (xy 66.512639 -280.450565) (xy 66.548995 -280.486921) (xy 66.579216 -280.528517)
			(xy 66.602559 -280.574329) (xy 66.618447 -280.623228) (xy 66.62649 -280.67401) (xy 66.626994 -280.699718)
			(xy 66.943998 -280.699718) (xy 66.947958 -280.650664) (xy 66.959735 -280.60288) (xy 66.979026 -280.557604)
			(xy 67.005329 -280.516008) (xy 67.037964 -280.479171) (xy 67.076085 -280.448046) (xy 67.118706 -280.423439)
			(xy 67.164722 -280.405987) (xy 67.212941 -280.396143) (xy 67.262116 -280.394162) (xy 67.310971 -280.400094)
			(xy 67.358242 -280.413786) (xy 67.402704 -280.434884) (xy 67.443207 -280.46284) (xy 67.4787 -280.496932)
			(xy 67.508265 -280.536276) (xy 67.531136 -280.579853) (xy 67.54672 -280.626534) (xy 67.554615 -280.675111)
			(xy 67.55511 -280.699718) (xy 67.554615 -280.724325) (xy 67.554436 -280.725426) (xy 67.873114 -280.725426)
			(xy 67.873114 -280.67401) (xy 67.881157 -280.623228) (xy 67.897045 -280.574329) (xy 67.920388 -280.528517)
			(xy 67.950609 -280.486921) (xy 67.986965 -280.450565) (xy 68.028561 -280.420344) (xy 68.074373 -280.397001)
			(xy 68.123272 -280.381113) (xy 68.174054 -280.37307) (xy 68.22547 -280.37307) (xy 68.276252 -280.381113)
			(xy 68.325151 -280.397001) (xy 68.370963 -280.420344) (xy 68.412559 -280.450565) (xy 68.448915 -280.486921)
			(xy 68.479136 -280.528517) (xy 68.502479 -280.574329) (xy 68.518367 -280.623228) (xy 68.52641 -280.67401)
			(xy 68.526914 -280.699718) (xy 68.844172 -280.699718) (xy 68.848132 -280.650664) (xy 68.859909 -280.60288)
			(xy 68.8792 -280.557604) (xy 68.905503 -280.516008) (xy 68.938138 -280.479171) (xy 68.976259 -280.448046)
			(xy 69.01888 -280.423439) (xy 69.064896 -280.405987) (xy 69.113115 -280.396143) (xy 69.16229 -280.394162)
			(xy 69.211145 -280.400094) (xy 69.258416 -280.413786) (xy 69.302878 -280.434884) (xy 69.343381 -280.46284)
			(xy 69.378874 -280.496932) (xy 69.408439 -280.536276) (xy 69.43131 -280.579853) (xy 69.446894 -280.626534)
			(xy 69.454789 -280.675111) (xy 69.455284 -280.699718) (xy 69.454789 -280.724325) (xy 69.45461 -280.725426)
			(xy 69.773288 -280.725426) (xy 69.773288 -280.67401) (xy 69.781331 -280.623228) (xy 69.797219 -280.574329)
			(xy 69.820562 -280.528517) (xy 69.850783 -280.486921) (xy 69.887139 -280.450565) (xy 69.928735 -280.420344)
			(xy 69.974547 -280.397001) (xy 70.023446 -280.381113) (xy 70.074228 -280.37307) (xy 70.125644 -280.37307)
			(xy 70.176426 -280.381113) (xy 70.225325 -280.397001) (xy 70.271137 -280.420344) (xy 70.312733 -280.450565)
			(xy 70.349089 -280.486921) (xy 70.37931 -280.528517) (xy 70.402653 -280.574329) (xy 70.418541 -280.623228)
			(xy 70.426584 -280.67401) (xy 70.427088 -280.699718) (xy 70.744092 -280.699718) (xy 70.748052 -280.650664)
			(xy 70.759829 -280.60288) (xy 70.77912 -280.557604) (xy 70.805423 -280.516008) (xy 70.838058 -280.479171)
			(xy 70.876179 -280.448046) (xy 70.9188 -280.423439) (xy 70.964816 -280.405987) (xy 71.013035 -280.396143)
			(xy 71.06221 -280.394162) (xy 71.111065 -280.400094) (xy 71.158336 -280.413786) (xy 71.202798 -280.434884)
			(xy 71.243301 -280.46284) (xy 71.278794 -280.496932) (xy 71.308359 -280.536276) (xy 71.33123 -280.579853)
			(xy 71.346814 -280.626534) (xy 71.354709 -280.675111) (xy 71.355204 -280.699718) (xy 71.354709 -280.724325)
			(xy 71.35453 -280.725426) (xy 71.673208 -280.725426) (xy 71.673208 -280.67401) (xy 71.681251 -280.623228)
			(xy 71.697139 -280.574329) (xy 71.720482 -280.528517) (xy 71.750703 -280.486921) (xy 71.787059 -280.450565)
			(xy 71.828655 -280.420344) (xy 71.874467 -280.397001) (xy 71.923366 -280.381113) (xy 71.974148 -280.37307)
			(xy 72.025564 -280.37307) (xy 72.076346 -280.381113) (xy 72.125245 -280.397001) (xy 72.171057 -280.420344)
			(xy 72.212653 -280.450565) (xy 72.249009 -280.486921) (xy 72.27923 -280.528517) (xy 72.302573 -280.574329)
			(xy 72.318461 -280.623228) (xy 72.326504 -280.67401) (xy 72.327008 -280.699718) (xy 72.644012 -280.699718)
			(xy 72.647972 -280.650664) (xy 72.659749 -280.60288) (xy 72.67904 -280.557604) (xy 72.705343 -280.516008)
			(xy 72.737978 -280.479171) (xy 72.776099 -280.448046) (xy 72.81872 -280.423439) (xy 72.864736 -280.405987)
			(xy 72.912955 -280.396143) (xy 72.96213 -280.394162) (xy 73.010985 -280.400094) (xy 73.058256 -280.413786)
			(xy 73.102718 -280.434884) (xy 73.143221 -280.46284) (xy 73.178714 -280.496932) (xy 73.208279 -280.536276)
			(xy 73.23115 -280.579853) (xy 73.246734 -280.626534) (xy 73.254629 -280.675111) (xy 73.255124 -280.699718)
			(xy 73.254629 -280.724325) (xy 73.25445 -280.725426) (xy 73.573128 -280.725426) (xy 73.573128 -280.67401)
			(xy 73.581171 -280.623228) (xy 73.597059 -280.574329) (xy 73.620402 -280.528517) (xy 73.650623 -280.486921)
			(xy 73.686979 -280.450565) (xy 73.728575 -280.420344) (xy 73.774387 -280.397001) (xy 73.823286 -280.381113)
			(xy 73.874068 -280.37307) (xy 73.925484 -280.37307) (xy 73.976266 -280.381113) (xy 74.025165 -280.397001)
			(xy 74.070977 -280.420344) (xy 74.112573 -280.450565) (xy 74.148929 -280.486921) (xy 74.17915 -280.528517)
			(xy 74.202493 -280.574329) (xy 74.218381 -280.623228) (xy 74.226424 -280.67401) (xy 74.226928 -280.699718)
			(xy 74.544186 -280.699718) (xy 74.548146 -280.650664) (xy 74.559923 -280.60288) (xy 74.579214 -280.557604)
			(xy 74.605517 -280.516008) (xy 74.638152 -280.479171) (xy 74.676273 -280.448046) (xy 74.718894 -280.423439)
			(xy 74.76491 -280.405987) (xy 74.813129 -280.396143) (xy 74.862304 -280.394162) (xy 74.911159 -280.400094)
			(xy 74.95843 -280.413786) (xy 75.002892 -280.434884) (xy 75.043395 -280.46284) (xy 75.078888 -280.496932)
			(xy 75.108453 -280.536276) (xy 75.131324 -280.579853) (xy 75.146908 -280.626534) (xy 75.154803 -280.675111)
			(xy 75.155298 -280.699718) (xy 75.154803 -280.724325) (xy 75.154624 -280.725426) (xy 75.473302 -280.725426)
			(xy 75.473302 -280.67401) (xy 75.481345 -280.623228) (xy 75.497233 -280.574329) (xy 75.520576 -280.528517)
			(xy 75.550797 -280.486921) (xy 75.587153 -280.450565) (xy 75.628749 -280.420344) (xy 75.674561 -280.397001)
			(xy 75.72346 -280.381113) (xy 75.774242 -280.37307) (xy 75.825658 -280.37307) (xy 75.87644 -280.381113)
			(xy 75.925339 -280.397001) (xy 75.971151 -280.420344) (xy 76.012747 -280.450565) (xy 76.049103 -280.486921)
			(xy 76.079324 -280.528517) (xy 76.102667 -280.574329) (xy 76.118555 -280.623228) (xy 76.126598 -280.67401)
			(xy 76.127102 -280.699718) (xy 76.444106 -280.699718) (xy 76.448066 -280.650664) (xy 76.459843 -280.60288)
			(xy 76.479134 -280.557604) (xy 76.505437 -280.516008) (xy 76.538072 -280.479171) (xy 76.576193 -280.448046)
			(xy 76.618814 -280.423439) (xy 76.66483 -280.405987) (xy 76.713049 -280.396143) (xy 76.762224 -280.394162)
			(xy 76.811079 -280.400094) (xy 76.85835 -280.413786) (xy 76.902812 -280.434884) (xy 76.943315 -280.46284)
			(xy 76.978808 -280.496932) (xy 77.008373 -280.536276) (xy 77.031244 -280.579853) (xy 77.046828 -280.626534)
			(xy 77.054723 -280.675111) (xy 77.055218 -280.699718) (xy 77.054723 -280.724325) (xy 77.054544 -280.725426)
			(xy 77.373222 -280.725426) (xy 77.373222 -280.67401) (xy 77.381265 -280.623228) (xy 77.397153 -280.574329)
			(xy 77.420496 -280.528517) (xy 77.450717 -280.486921) (xy 77.487073 -280.450565) (xy 77.528669 -280.420344)
			(xy 77.574481 -280.397001) (xy 77.62338 -280.381113) (xy 77.674162 -280.37307) (xy 77.725578 -280.37307)
			(xy 77.77636 -280.381113) (xy 77.825259 -280.397001) (xy 77.871071 -280.420344) (xy 77.912667 -280.450565)
			(xy 77.949023 -280.486921) (xy 77.979244 -280.528517) (xy 78.002587 -280.574329) (xy 78.018475 -280.623228)
			(xy 78.026518 -280.67401) (xy 78.027022 -280.699718) (xy 78.344026 -280.699718) (xy 78.347986 -280.650664)
			(xy 78.359763 -280.60288) (xy 78.379054 -280.557604) (xy 78.405357 -280.516008) (xy 78.437992 -280.479171)
			(xy 78.476113 -280.448046) (xy 78.518734 -280.423439) (xy 78.56475 -280.405987) (xy 78.612969 -280.396143)
			(xy 78.662144 -280.394162) (xy 78.710999 -280.400094) (xy 78.75827 -280.413786) (xy 78.802732 -280.434884)
			(xy 78.843235 -280.46284) (xy 78.878728 -280.496932) (xy 78.908293 -280.536276) (xy 78.931164 -280.579853)
			(xy 78.946748 -280.626534) (xy 78.954643 -280.675111) (xy 78.955138 -280.699718) (xy 78.954643 -280.724325)
			(xy 78.954464 -280.725426) (xy 79.273142 -280.725426) (xy 79.273142 -280.67401) (xy 79.281185 -280.623228)
			(xy 79.297073 -280.574329) (xy 79.320416 -280.528517) (xy 79.350637 -280.486921) (xy 79.386993 -280.450565)
			(xy 79.428589 -280.420344) (xy 79.474401 -280.397001) (xy 79.5233 -280.381113) (xy 79.574082 -280.37307)
			(xy 79.625498 -280.37307) (xy 79.67628 -280.381113) (xy 79.725179 -280.397001) (xy 79.770991 -280.420344)
			(xy 79.812587 -280.450565) (xy 79.848943 -280.486921) (xy 79.879164 -280.528517) (xy 79.902507 -280.574329)
			(xy 79.918395 -280.623228) (xy 79.926438 -280.67401) (xy 79.926942 -280.699718) (xy 80.2442 -280.699718)
			(xy 80.24816 -280.650664) (xy 80.259937 -280.60288) (xy 80.279228 -280.557604) (xy 80.305531 -280.516008)
			(xy 80.338166 -280.479171) (xy 80.376287 -280.448046) (xy 80.418908 -280.423439) (xy 80.464924 -280.405987)
			(xy 80.513143 -280.396143) (xy 80.562318 -280.394162) (xy 80.611173 -280.400094) (xy 80.658444 -280.413786)
			(xy 80.702906 -280.434884) (xy 80.743409 -280.46284) (xy 80.778902 -280.496932) (xy 80.808467 -280.536276)
			(xy 80.831338 -280.579853) (xy 80.846922 -280.626534) (xy 80.854817 -280.675111) (xy 80.855312 -280.699718)
			(xy 81.19416 -280.699718) (xy 81.19812 -280.650664) (xy 81.209897 -280.60288) (xy 81.229188 -280.557604)
			(xy 81.255491 -280.516008) (xy 81.288126 -280.479171) (xy 81.326247 -280.448046) (xy 81.368868 -280.423439)
			(xy 81.414884 -280.405987) (xy 81.463103 -280.396143) (xy 81.512278 -280.394162) (xy 81.561133 -280.400094)
			(xy 81.608404 -280.413786) (xy 81.652866 -280.434884) (xy 81.693369 -280.46284) (xy 81.728862 -280.496932)
			(xy 81.758427 -280.536276) (xy 81.781298 -280.579853) (xy 81.796882 -280.626534) (xy 81.804777 -280.675111)
			(xy 81.805272 -280.699718) (xy 82.14412 -280.699718) (xy 82.14808 -280.650664) (xy 82.159857 -280.60288)
			(xy 82.179148 -280.557604) (xy 82.205451 -280.516008) (xy 82.238086 -280.479171) (xy 82.276207 -280.448046)
			(xy 82.318828 -280.423439) (xy 82.364844 -280.405987) (xy 82.413063 -280.396143) (xy 82.462238 -280.394162)
			(xy 82.511093 -280.400094) (xy 82.558364 -280.413786) (xy 82.602826 -280.434884) (xy 82.643329 -280.46284)
			(xy 82.678822 -280.496932) (xy 82.708387 -280.536276) (xy 82.731258 -280.579853) (xy 82.746842 -280.626534)
			(xy 82.754737 -280.675111) (xy 82.755232 -280.699718) (xy 82.754737 -280.724325) (xy 82.746842 -280.772902)
			(xy 82.731258 -280.819583) (xy 82.708387 -280.86316) (xy 82.678822 -280.902504) (xy 82.643329 -280.936596)
			(xy 82.602826 -280.964552) (xy 82.558364 -280.98565) (xy 82.511093 -280.999342) (xy 82.462238 -281.005274)
			(xy 82.413063 -281.003293) (xy 82.364844 -280.993449) (xy 82.318828 -280.975997) (xy 82.276207 -280.95139)
			(xy 82.238086 -280.920265) (xy 82.205451 -280.883428) (xy 82.179148 -280.841832) (xy 82.159857 -280.796556)
			(xy 82.14808 -280.748772) (xy 82.14412 -280.699718) (xy 81.805272 -280.699718) (xy 81.804777 -280.724325)
			(xy 81.796882 -280.772902) (xy 81.781298 -280.819583) (xy 81.758427 -280.86316) (xy 81.728862 -280.902504)
			(xy 81.693369 -280.936596) (xy 81.652866 -280.964552) (xy 81.608404 -280.98565) (xy 81.561133 -280.999342)
			(xy 81.512278 -281.005274) (xy 81.463103 -281.003293) (xy 81.414884 -280.993449) (xy 81.368868 -280.975997)
			(xy 81.326247 -280.95139) (xy 81.288126 -280.920265) (xy 81.255491 -280.883428) (xy 81.229188 -280.841832)
			(xy 81.209897 -280.796556) (xy 81.19812 -280.748772) (xy 81.19416 -280.699718) (xy 80.855312 -280.699718)
			(xy 80.854817 -280.724325) (xy 80.846922 -280.772902) (xy 80.831338 -280.819583) (xy 80.808467 -280.86316)
			(xy 80.778902 -280.902504) (xy 80.743409 -280.936596) (xy 80.702906 -280.964552) (xy 80.658444 -280.98565)
			(xy 80.611173 -280.999342) (xy 80.562318 -281.005274) (xy 80.513143 -281.003293) (xy 80.464924 -280.993449)
			(xy 80.418908 -280.975997) (xy 80.376287 -280.95139) (xy 80.338166 -280.920265) (xy 80.305531 -280.883428)
			(xy 80.279228 -280.841832) (xy 80.259937 -280.796556) (xy 80.24816 -280.748772) (xy 80.2442 -280.699718)
			(xy 79.926942 -280.699718) (xy 79.926438 -280.725426) (xy 79.918395 -280.776208) (xy 79.902507 -280.825107)
			(xy 79.879164 -280.870919) (xy 79.848943 -280.912515) (xy 79.812587 -280.948871) (xy 79.770991 -280.979092)
			(xy 79.725179 -281.002435) (xy 79.67628 -281.018323) (xy 79.625498 -281.026366) (xy 79.574082 -281.026366)
			(xy 79.5233 -281.018323) (xy 79.474401 -281.002435) (xy 79.428589 -280.979092) (xy 79.386993 -280.948871)
			(xy 79.350637 -280.912515) (xy 79.320416 -280.870919) (xy 79.297073 -280.825107) (xy 79.281185 -280.776208)
			(xy 79.273142 -280.725426) (xy 78.954464 -280.725426) (xy 78.946748 -280.772902) (xy 78.931164 -280.819583)
			(xy 78.908293 -280.86316) (xy 78.878728 -280.902504) (xy 78.843235 -280.936596) (xy 78.802732 -280.964552)
			(xy 78.75827 -280.98565) (xy 78.710999 -280.999342) (xy 78.662144 -281.005274) (xy 78.612969 -281.003293)
			(xy 78.56475 -280.993449) (xy 78.518734 -280.975997) (xy 78.476113 -280.95139) (xy 78.437992 -280.920265)
			(xy 78.405357 -280.883428) (xy 78.379054 -280.841832) (xy 78.359763 -280.796556) (xy 78.347986 -280.748772)
			(xy 78.344026 -280.699718) (xy 78.027022 -280.699718) (xy 78.026518 -280.725426) (xy 78.018475 -280.776208)
			(xy 78.002587 -280.825107) (xy 77.979244 -280.870919) (xy 77.949023 -280.912515) (xy 77.912667 -280.948871)
			(xy 77.871071 -280.979092) (xy 77.825259 -281.002435) (xy 77.77636 -281.018323) (xy 77.725578 -281.026366)
			(xy 77.674162 -281.026366) (xy 77.62338 -281.018323) (xy 77.574481 -281.002435) (xy 77.528669 -280.979092)
			(xy 77.487073 -280.948871) (xy 77.450717 -280.912515) (xy 77.420496 -280.870919) (xy 77.397153 -280.825107)
			(xy 77.381265 -280.776208) (xy 77.373222 -280.725426) (xy 77.054544 -280.725426) (xy 77.046828 -280.772902)
			(xy 77.031244 -280.819583) (xy 77.008373 -280.86316) (xy 76.978808 -280.902504) (xy 76.943315 -280.936596)
			(xy 76.902812 -280.964552) (xy 76.85835 -280.98565) (xy 76.811079 -280.999342) (xy 76.762224 -281.005274)
			(xy 76.713049 -281.003293) (xy 76.66483 -280.993449) (xy 76.618814 -280.975997) (xy 76.576193 -280.95139)
			(xy 76.538072 -280.920265) (xy 76.505437 -280.883428) (xy 76.479134 -280.841832) (xy 76.459843 -280.796556)
			(xy 76.448066 -280.748772) (xy 76.444106 -280.699718) (xy 76.127102 -280.699718) (xy 76.126598 -280.725426)
			(xy 76.118555 -280.776208) (xy 76.102667 -280.825107) (xy 76.079324 -280.870919) (xy 76.049103 -280.912515)
			(xy 76.012747 -280.948871) (xy 75.971151 -280.979092) (xy 75.925339 -281.002435) (xy 75.87644 -281.018323)
			(xy 75.825658 -281.026366) (xy 75.774242 -281.026366) (xy 75.72346 -281.018323) (xy 75.674561 -281.002435)
			(xy 75.628749 -280.979092) (xy 75.587153 -280.948871) (xy 75.550797 -280.912515) (xy 75.520576 -280.870919)
			(xy 75.497233 -280.825107) (xy 75.481345 -280.776208) (xy 75.473302 -280.725426) (xy 75.154624 -280.725426)
			(xy 75.146908 -280.772902) (xy 75.131324 -280.819583) (xy 75.108453 -280.86316) (xy 75.078888 -280.902504)
			(xy 75.043395 -280.936596) (xy 75.002892 -280.964552) (xy 74.95843 -280.98565) (xy 74.911159 -280.999342)
			(xy 74.862304 -281.005274) (xy 74.813129 -281.003293) (xy 74.76491 -280.993449) (xy 74.718894 -280.975997)
			(xy 74.676273 -280.95139) (xy 74.638152 -280.920265) (xy 74.605517 -280.883428) (xy 74.579214 -280.841832)
			(xy 74.559923 -280.796556) (xy 74.548146 -280.748772) (xy 74.544186 -280.699718) (xy 74.226928 -280.699718)
			(xy 74.226424 -280.725426) (xy 74.218381 -280.776208) (xy 74.202493 -280.825107) (xy 74.17915 -280.870919)
			(xy 74.148929 -280.912515) (xy 74.112573 -280.948871) (xy 74.070977 -280.979092) (xy 74.025165 -281.002435)
			(xy 73.976266 -281.018323) (xy 73.925484 -281.026366) (xy 73.874068 -281.026366) (xy 73.823286 -281.018323)
			(xy 73.774387 -281.002435) (xy 73.728575 -280.979092) (xy 73.686979 -280.948871) (xy 73.650623 -280.912515)
			(xy 73.620402 -280.870919) (xy 73.597059 -280.825107) (xy 73.581171 -280.776208) (xy 73.573128 -280.725426)
			(xy 73.25445 -280.725426) (xy 73.246734 -280.772902) (xy 73.23115 -280.819583) (xy 73.208279 -280.86316)
			(xy 73.178714 -280.902504) (xy 73.143221 -280.936596) (xy 73.102718 -280.964552) (xy 73.058256 -280.98565)
			(xy 73.010985 -280.999342) (xy 72.96213 -281.005274) (xy 72.912955 -281.003293) (xy 72.864736 -280.993449)
			(xy 72.81872 -280.975997) (xy 72.776099 -280.95139) (xy 72.737978 -280.920265) (xy 72.705343 -280.883428)
			(xy 72.67904 -280.841832) (xy 72.659749 -280.796556) (xy 72.647972 -280.748772) (xy 72.644012 -280.699718)
			(xy 72.327008 -280.699718) (xy 72.326504 -280.725426) (xy 72.318461 -280.776208) (xy 72.302573 -280.825107)
			(xy 72.27923 -280.870919) (xy 72.249009 -280.912515) (xy 72.212653 -280.948871) (xy 72.171057 -280.979092)
			(xy 72.125245 -281.002435) (xy 72.076346 -281.018323) (xy 72.025564 -281.026366) (xy 71.974148 -281.026366)
			(xy 71.923366 -281.018323) (xy 71.874467 -281.002435) (xy 71.828655 -280.979092) (xy 71.787059 -280.948871)
			(xy 71.750703 -280.912515) (xy 71.720482 -280.870919) (xy 71.697139 -280.825107) (xy 71.681251 -280.776208)
			(xy 71.673208 -280.725426) (xy 71.35453 -280.725426) (xy 71.346814 -280.772902) (xy 71.33123 -280.819583)
			(xy 71.308359 -280.86316) (xy 71.278794 -280.902504) (xy 71.243301 -280.936596) (xy 71.202798 -280.964552)
			(xy 71.158336 -280.98565) (xy 71.111065 -280.999342) (xy 71.06221 -281.005274) (xy 71.013035 -281.003293)
			(xy 70.964816 -280.993449) (xy 70.9188 -280.975997) (xy 70.876179 -280.95139) (xy 70.838058 -280.920265)
			(xy 70.805423 -280.883428) (xy 70.77912 -280.841832) (xy 70.759829 -280.796556) (xy 70.748052 -280.748772)
			(xy 70.744092 -280.699718) (xy 70.427088 -280.699718) (xy 70.426584 -280.725426) (xy 70.418541 -280.776208)
			(xy 70.402653 -280.825107) (xy 70.37931 -280.870919) (xy 70.349089 -280.912515) (xy 70.312733 -280.948871)
			(xy 70.271137 -280.979092) (xy 70.225325 -281.002435) (xy 70.176426 -281.018323) (xy 70.125644 -281.026366)
			(xy 70.074228 -281.026366) (xy 70.023446 -281.018323) (xy 69.974547 -281.002435) (xy 69.928735 -280.979092)
			(xy 69.887139 -280.948871) (xy 69.850783 -280.912515) (xy 69.820562 -280.870919) (xy 69.797219 -280.825107)
			(xy 69.781331 -280.776208) (xy 69.773288 -280.725426) (xy 69.45461 -280.725426) (xy 69.446894 -280.772902)
			(xy 69.43131 -280.819583) (xy 69.408439 -280.86316) (xy 69.378874 -280.902504) (xy 69.343381 -280.936596)
			(xy 69.302878 -280.964552) (xy 69.258416 -280.98565) (xy 69.211145 -280.999342) (xy 69.16229 -281.005274)
			(xy 69.113115 -281.003293) (xy 69.064896 -280.993449) (xy 69.01888 -280.975997) (xy 68.976259 -280.95139)
			(xy 68.938138 -280.920265) (xy 68.905503 -280.883428) (xy 68.8792 -280.841832) (xy 68.859909 -280.796556)
			(xy 68.848132 -280.748772) (xy 68.844172 -280.699718) (xy 68.526914 -280.699718) (xy 68.52641 -280.725426)
			(xy 68.518367 -280.776208) (xy 68.502479 -280.825107) (xy 68.479136 -280.870919) (xy 68.448915 -280.912515)
			(xy 68.412559 -280.948871) (xy 68.370963 -280.979092) (xy 68.325151 -281.002435) (xy 68.276252 -281.018323)
			(xy 68.22547 -281.026366) (xy 68.174054 -281.026366) (xy 68.123272 -281.018323) (xy 68.074373 -281.002435)
			(xy 68.028561 -280.979092) (xy 67.986965 -280.948871) (xy 67.950609 -280.912515) (xy 67.920388 -280.870919)
			(xy 67.897045 -280.825107) (xy 67.881157 -280.776208) (xy 67.873114 -280.725426) (xy 67.554436 -280.725426)
			(xy 67.54672 -280.772902) (xy 67.531136 -280.819583) (xy 67.508265 -280.86316) (xy 67.4787 -280.902504)
			(xy 67.443207 -280.936596) (xy 67.402704 -280.964552) (xy 67.358242 -280.98565) (xy 67.310971 -280.999342)
			(xy 67.262116 -281.005274) (xy 67.212941 -281.003293) (xy 67.164722 -280.993449) (xy 67.118706 -280.975997)
			(xy 67.076085 -280.95139) (xy 67.037964 -280.920265) (xy 67.005329 -280.883428) (xy 66.979026 -280.841832)
			(xy 66.959735 -280.796556) (xy 66.947958 -280.748772) (xy 66.943998 -280.699718) (xy 66.626994 -280.699718)
			(xy 66.62649 -280.725426) (xy 66.618447 -280.776208) (xy 66.602559 -280.825107) (xy 66.579216 -280.870919)
			(xy 66.548995 -280.912515) (xy 66.512639 -280.948871) (xy 66.471043 -280.979092) (xy 66.425231 -281.002435)
			(xy 66.376332 -281.018323) (xy 66.32555 -281.026366) (xy 66.274134 -281.026366) (xy 66.223352 -281.018323)
			(xy 66.174453 -281.002435) (xy 66.128641 -280.979092) (xy 66.087045 -280.948871) (xy 66.050689 -280.912515)
			(xy 66.020468 -280.870919) (xy 65.997125 -280.825107) (xy 65.981237 -280.776208) (xy 65.973194 -280.725426)
			(xy 65.654516 -280.725426) (xy 65.6468 -280.772902) (xy 65.631216 -280.819583) (xy 65.608345 -280.86316)
			(xy 65.57878 -280.902504) (xy 65.543287 -280.936596) (xy 65.502784 -280.964552) (xy 65.458322 -280.98565)
			(xy 65.411051 -280.999342) (xy 65.362196 -281.005274) (xy 65.313021 -281.003293) (xy 65.264802 -280.993449)
			(xy 65.218786 -280.975997) (xy 65.176165 -280.95139) (xy 65.138044 -280.920265) (xy 65.105409 -280.883428)
			(xy 65.079106 -280.841832) (xy 65.059815 -280.796556) (xy 65.048038 -280.748772) (xy 65.044078 -280.699718)
			(xy 64.727074 -280.699718) (xy 64.72657 -280.725426) (xy 64.718527 -280.776208) (xy 64.702639 -280.825107)
			(xy 64.679296 -280.870919) (xy 64.649075 -280.912515) (xy 64.612719 -280.948871) (xy 64.571123 -280.979092)
			(xy 64.525311 -281.002435) (xy 64.476412 -281.018323) (xy 64.42563 -281.026366) (xy 64.374214 -281.026366)
			(xy 64.323432 -281.018323) (xy 64.274533 -281.002435) (xy 64.228721 -280.979092) (xy 64.187125 -280.948871)
			(xy 64.150769 -280.912515) (xy 64.120548 -280.870919) (xy 64.097205 -280.825107) (xy 64.081317 -280.776208)
			(xy 64.073274 -280.725426) (xy 63.754596 -280.725426) (xy 63.74688 -280.772902) (xy 63.731296 -280.819583)
			(xy 63.708425 -280.86316) (xy 63.67886 -280.902504) (xy 63.643367 -280.936596) (xy 63.602864 -280.964552)
			(xy 63.558402 -280.98565) (xy 63.511131 -280.999342) (xy 63.462276 -281.005274) (xy 63.413101 -281.003293)
			(xy 63.364882 -280.993449) (xy 63.318866 -280.975997) (xy 63.276245 -280.95139) (xy 63.238124 -280.920265)
			(xy 63.205489 -280.883428) (xy 63.179186 -280.841832) (xy 63.159895 -280.796556) (xy 63.148118 -280.748772)
			(xy 63.144158 -280.699718) (xy 62.8269 -280.699718) (xy 62.826396 -280.725426) (xy 62.818353 -280.776208)
			(xy 62.802465 -280.825107) (xy 62.779122 -280.870919) (xy 62.748901 -280.912515) (xy 62.712545 -280.948871)
			(xy 62.670949 -280.979092) (xy 62.625137 -281.002435) (xy 62.576238 -281.018323) (xy 62.525456 -281.026366)
			(xy 62.47404 -281.026366) (xy 62.423258 -281.018323) (xy 62.374359 -281.002435) (xy 62.328547 -280.979092)
			(xy 62.286951 -280.948871) (xy 62.250595 -280.912515) (xy 62.220374 -280.870919) (xy 62.197031 -280.825107)
			(xy 62.181143 -280.776208) (xy 62.1731 -280.725426) (xy 61.854422 -280.725426) (xy 61.846706 -280.772902)
			(xy 61.831122 -280.819583) (xy 61.808251 -280.86316) (xy 61.778686 -280.902504) (xy 61.743193 -280.936596)
			(xy 61.70269 -280.964552) (xy 61.658228 -280.98565) (xy 61.610957 -280.999342) (xy 61.562102 -281.005274)
			(xy 61.512927 -281.003293) (xy 61.464708 -280.993449) (xy 61.418692 -280.975997) (xy 61.376071 -280.95139)
			(xy 61.33795 -280.920265) (xy 61.305315 -280.883428) (xy 61.279012 -280.841832) (xy 61.259721 -280.796556)
			(xy 61.247944 -280.748772) (xy 61.243984 -280.699718) (xy 60.92698 -280.699718) (xy 60.926476 -280.725426)
			(xy 60.918433 -280.776208) (xy 60.902545 -280.825107) (xy 60.879202 -280.870919) (xy 60.848981 -280.912515)
			(xy 60.812625 -280.948871) (xy 60.771029 -280.979092) (xy 60.725217 -281.002435) (xy 60.676318 -281.018323)
			(xy 60.625536 -281.026366) (xy 60.57412 -281.026366) (xy 60.523338 -281.018323) (xy 60.474439 -281.002435)
			(xy 60.428627 -280.979092) (xy 60.387031 -280.948871) (xy 60.350675 -280.912515) (xy 60.320454 -280.870919)
			(xy 60.297111 -280.825107) (xy 60.281223 -280.776208) (xy 60.27318 -280.725426) (xy 59.954502 -280.725426)
			(xy 59.946786 -280.772902) (xy 59.931202 -280.819583) (xy 59.908331 -280.86316) (xy 59.878766 -280.902504)
			(xy 59.843273 -280.936596) (xy 59.80277 -280.964552) (xy 59.758308 -280.98565) (xy 59.711037 -280.999342)
			(xy 59.662182 -281.005274) (xy 59.613007 -281.003293) (xy 59.564788 -280.993449) (xy 59.518772 -280.975997)
			(xy 59.476151 -280.95139) (xy 59.43803 -280.920265) (xy 59.405395 -280.883428) (xy 59.379092 -280.841832)
			(xy 59.359801 -280.796556) (xy 59.348024 -280.748772) (xy 59.344064 -280.699718) (xy 59.02706 -280.699718)
			(xy 59.026556 -280.725426) (xy 59.018513 -280.776208) (xy 59.002625 -280.825107) (xy 58.979282 -280.870919)
			(xy 58.949061 -280.912515) (xy 58.912705 -280.948871) (xy 58.871109 -280.979092) (xy 58.825297 -281.002435)
			(xy 58.776398 -281.018323) (xy 58.725616 -281.026366) (xy 58.6742 -281.026366) (xy 58.623418 -281.018323)
			(xy 58.574519 -281.002435) (xy 58.528707 -280.979092) (xy 58.487111 -280.948871) (xy 58.450755 -280.912515)
			(xy 58.420534 -280.870919) (xy 58.397191 -280.825107) (xy 58.381303 -280.776208) (xy 58.37326 -280.725426)
			(xy 58.054582 -280.725426) (xy 58.046866 -280.772902) (xy 58.031282 -280.819583) (xy 58.008411 -280.86316)
			(xy 57.978846 -280.902504) (xy 57.943353 -280.936596) (xy 57.90285 -280.964552) (xy 57.858388 -280.98565)
			(xy 57.811117 -280.999342) (xy 57.762262 -281.005274) (xy 57.713087 -281.003293) (xy 57.664868 -280.993449)
			(xy 57.618852 -280.975997) (xy 57.576231 -280.95139) (xy 57.53811 -280.920265) (xy 57.505475 -280.883428)
			(xy 57.479172 -280.841832) (xy 57.459881 -280.796556) (xy 57.448104 -280.748772) (xy 57.444144 -280.699718)
			(xy 57.126886 -280.699718) (xy 57.126382 -280.725426) (xy 57.118339 -280.776208) (xy 57.102451 -280.825107)
			(xy 57.079108 -280.870919) (xy 57.048887 -280.912515) (xy 57.012531 -280.948871) (xy 56.970935 -280.979092)
			(xy 56.925123 -281.002435) (xy 56.876224 -281.018323) (xy 56.825442 -281.026366) (xy 56.774026 -281.026366)
			(xy 56.723244 -281.018323) (xy 56.674345 -281.002435) (xy 56.628533 -280.979092) (xy 56.586937 -280.948871)
			(xy 56.550581 -280.912515) (xy 56.52036 -280.870919) (xy 56.497017 -280.825107) (xy 56.481129 -280.776208)
			(xy 56.473086 -280.725426) (xy 56.154408 -280.725426) (xy 56.146692 -280.772902) (xy 56.131108 -280.819583)
			(xy 56.108237 -280.86316) (xy 56.078672 -280.902504) (xy 56.043179 -280.936596) (xy 56.002676 -280.964552)
			(xy 55.958214 -280.98565) (xy 55.910943 -280.999342) (xy 55.862088 -281.005274) (xy 55.812913 -281.003293)
			(xy 55.764694 -280.993449) (xy 55.718678 -280.975997) (xy 55.676057 -280.95139) (xy 55.637936 -280.920265)
			(xy 55.605301 -280.883428) (xy 55.578998 -280.841832) (xy 55.559707 -280.796556) (xy 55.54793 -280.748772)
			(xy 55.54397 -280.699718) (xy 55.226966 -280.699718) (xy 55.226462 -280.725426) (xy 55.218419 -280.776208)
			(xy 55.202531 -280.825107) (xy 55.179188 -280.870919) (xy 55.148967 -280.912515) (xy 55.112611 -280.948871)
			(xy 55.071015 -280.979092) (xy 55.025203 -281.002435) (xy 54.976304 -281.018323) (xy 54.925522 -281.026366)
			(xy 54.874106 -281.026366) (xy 54.823324 -281.018323) (xy 54.774425 -281.002435) (xy 54.728613 -280.979092)
			(xy 54.687017 -280.948871) (xy 54.650661 -280.912515) (xy 54.62044 -280.870919) (xy 54.597097 -280.825107)
			(xy 54.581209 -280.776208) (xy 54.573166 -280.725426) (xy 54.254488 -280.725426) (xy 54.246772 -280.772902)
			(xy 54.231188 -280.819583) (xy 54.208317 -280.86316) (xy 54.178752 -280.902504) (xy 54.143259 -280.936596)
			(xy 54.102756 -280.964552) (xy 54.058294 -280.98565) (xy 54.011023 -280.999342) (xy 53.962168 -281.005274)
			(xy 53.912993 -281.003293) (xy 53.864774 -280.993449) (xy 53.818758 -280.975997) (xy 53.776137 -280.95139)
			(xy 53.738016 -280.920265) (xy 53.705381 -280.883428) (xy 53.679078 -280.841832) (xy 53.659787 -280.796556)
			(xy 53.64801 -280.748772) (xy 53.64405 -280.699718) (xy 53.327046 -280.699718) (xy 53.326542 -280.725426)
			(xy 53.318499 -280.776208) (xy 53.302611 -280.825107) (xy 53.279268 -280.870919) (xy 53.249047 -280.912515)
			(xy 53.212691 -280.948871) (xy 53.171095 -280.979092) (xy 53.125283 -281.002435) (xy 53.076384 -281.018323)
			(xy 53.025602 -281.026366) (xy 52.974186 -281.026366) (xy 52.923404 -281.018323) (xy 52.874505 -281.002435)
			(xy 52.828693 -280.979092) (xy 52.787097 -280.948871) (xy 52.750741 -280.912515) (xy 52.72052 -280.870919)
			(xy 52.697177 -280.825107) (xy 52.681289 -280.776208) (xy 52.673246 -280.725426) (xy 52.354568 -280.725426)
			(xy 52.346852 -280.772902) (xy 52.331268 -280.819583) (xy 52.308397 -280.86316) (xy 52.278832 -280.902504)
			(xy 52.243339 -280.936596) (xy 52.202836 -280.964552) (xy 52.158374 -280.98565) (xy 52.111103 -280.999342)
			(xy 52.062248 -281.005274) (xy 52.013073 -281.003293) (xy 51.964854 -280.993449) (xy 51.918838 -280.975997)
			(xy 51.876217 -280.95139) (xy 51.838096 -280.920265) (xy 51.805461 -280.883428) (xy 51.779158 -280.841832)
			(xy 51.759867 -280.796556) (xy 51.74809 -280.748772) (xy 51.74413 -280.699718) (xy 51.427126 -280.699718)
			(xy 51.426622 -280.725426) (xy 51.418579 -280.776208) (xy 51.402691 -280.825107) (xy 51.379348 -280.870919)
			(xy 51.349127 -280.912515) (xy 51.312771 -280.948871) (xy 51.271175 -280.979092) (xy 51.225363 -281.002435)
			(xy 51.176464 -281.018323) (xy 51.125682 -281.026366) (xy 51.074266 -281.026366) (xy 51.023484 -281.018323)
			(xy 50.974585 -281.002435) (xy 50.928773 -280.979092) (xy 50.887177 -280.948871) (xy 50.850821 -280.912515)
			(xy 50.8206 -280.870919) (xy 50.797257 -280.825107) (xy 50.781369 -280.776208) (xy 50.773326 -280.725426)
			(xy 50.454394 -280.725426) (xy 50.446678 -280.772902) (xy 50.431094 -280.819583) (xy 50.408223 -280.86316)
			(xy 50.378658 -280.902504) (xy 50.343165 -280.936596) (xy 50.302662 -280.964552) (xy 50.2582 -280.98565)
			(xy 50.210929 -280.999342) (xy 50.162074 -281.005274) (xy 50.112899 -281.003293) (xy 50.06468 -280.993449)
			(xy 50.018664 -280.975997) (xy 49.976043 -280.95139) (xy 49.937922 -280.920265) (xy 49.905287 -280.883428)
			(xy 49.878984 -280.841832) (xy 49.859693 -280.796556) (xy 49.847916 -280.748772) (xy 49.843956 -280.699718)
			(xy 49.526952 -280.699718) (xy 49.526448 -280.725426) (xy 49.518405 -280.776208) (xy 49.502517 -280.825107)
			(xy 49.479174 -280.870919) (xy 49.448953 -280.912515) (xy 49.412597 -280.948871) (xy 49.371001 -280.979092)
			(xy 49.325189 -281.002435) (xy 49.27629 -281.018323) (xy 49.225508 -281.026366) (xy 49.174092 -281.026366)
			(xy 49.12331 -281.018323) (xy 49.074411 -281.002435) (xy 49.028599 -280.979092) (xy 48.987003 -280.948871)
			(xy 48.950647 -280.912515) (xy 48.920426 -280.870919) (xy 48.897083 -280.825107) (xy 48.881195 -280.776208)
			(xy 48.873152 -280.725426) (xy 48.554474 -280.725426) (xy 48.546758 -280.772902) (xy 48.531174 -280.819583)
			(xy 48.508303 -280.86316) (xy 48.478738 -280.902504) (xy 48.443245 -280.936596) (xy 48.402742 -280.964552)
			(xy 48.35828 -280.98565) (xy 48.311009 -280.999342) (xy 48.262154 -281.005274) (xy 48.212979 -281.003293)
			(xy 48.16476 -280.993449) (xy 48.118744 -280.975997) (xy 48.076123 -280.95139) (xy 48.038002 -280.920265)
			(xy 48.005367 -280.883428) (xy 47.979064 -280.841832) (xy 47.959773 -280.796556) (xy 47.947996 -280.748772)
			(xy 47.944036 -280.699718) (xy 47.627032 -280.699718) (xy 47.626528 -280.725426) (xy 47.618485 -280.776208)
			(xy 47.602597 -280.825107) (xy 47.579254 -280.870919) (xy 47.549033 -280.912515) (xy 47.512677 -280.948871)
			(xy 47.471081 -280.979092) (xy 47.425269 -281.002435) (xy 47.37637 -281.018323) (xy 47.325588 -281.026366)
			(xy 47.274172 -281.026366) (xy 47.22339 -281.018323) (xy 47.174491 -281.002435) (xy 47.128679 -280.979092)
			(xy 47.087083 -280.948871) (xy 47.050727 -280.912515) (xy 47.020506 -280.870919) (xy 46.997163 -280.825107)
			(xy 46.981275 -280.776208) (xy 46.973232 -280.725426) (xy 46.654554 -280.725426) (xy 46.646838 -280.772902)
			(xy 46.631254 -280.819583) (xy 46.608383 -280.86316) (xy 46.578818 -280.902504) (xy 46.543325 -280.936596)
			(xy 46.502822 -280.964552) (xy 46.45836 -280.98565) (xy 46.411089 -280.999342) (xy 46.362234 -281.005274)
			(xy 46.313059 -281.003293) (xy 46.26484 -280.993449) (xy 46.218824 -280.975997) (xy 46.176203 -280.95139)
			(xy 46.138082 -280.920265) (xy 46.105447 -280.883428) (xy 46.079144 -280.841832) (xy 46.059853 -280.796556)
			(xy 46.048076 -280.748772) (xy 46.044116 -280.699718) (xy 45.727112 -280.699718) (xy 45.726608 -280.725426)
			(xy 45.718565 -280.776208) (xy 45.702677 -280.825107) (xy 45.679334 -280.870919) (xy 45.649113 -280.912515)
			(xy 45.612757 -280.948871) (xy 45.571161 -280.979092) (xy 45.525349 -281.002435) (xy 45.47645 -281.018323)
			(xy 45.425668 -281.026366) (xy 45.374252 -281.026366) (xy 45.32347 -281.018323) (xy 45.274571 -281.002435)
			(xy 45.228759 -280.979092) (xy 45.187163 -280.948871) (xy 45.150807 -280.912515) (xy 45.120586 -280.870919)
			(xy 45.097243 -280.825107) (xy 45.081355 -280.776208) (xy 45.073312 -280.725426) (xy 44.75438 -280.725426)
			(xy 44.746664 -280.772902) (xy 44.73108 -280.819583) (xy 44.708209 -280.86316) (xy 44.678644 -280.902504)
			(xy 44.643151 -280.936596) (xy 44.602648 -280.964552) (xy 44.558186 -280.98565) (xy 44.510915 -280.999342)
			(xy 44.46206 -281.005274) (xy 44.412885 -281.003293) (xy 44.364666 -280.993449) (xy 44.31865 -280.975997)
			(xy 44.276029 -280.95139) (xy 44.237908 -280.920265) (xy 44.205273 -280.883428) (xy 44.17897 -280.841832)
			(xy 44.159679 -280.796556) (xy 44.147902 -280.748772) (xy 44.143942 -280.699718) (xy 40.899334 -280.699718)
			(xy 40.899334 -280.787348) (xy 40.90001 -280.79937) (xy 40.910885 -280.820818) (xy 40.920162 -280.828496)
			(xy 40.996362 -280.884122) (xy 41.020238 -280.887932) (xy 41.031922 -280.884122) (xy 41.054563 -280.877348)
			(xy 41.101257 -280.870077) (xy 41.124886 -280.869644) (xy 41.150148 -280.870136) (xy 41.199985 -280.87845)
			(xy 41.247772 -280.894853) (xy 41.292208 -280.918899) (xy 41.33208 -280.949931) (xy 41.366301 -280.987103)
			(xy 41.393936 -281.0294) (xy 41.414232 -281.075669) (xy 41.426636 -281.124648) (xy 41.430804 -281.174952)
			(xy 41.769042 -281.174952) (xy 41.773002 -281.125898) (xy 41.784779 -281.078114) (xy 41.80407 -281.032838)
			(xy 41.830373 -280.991242) (xy 41.863008 -280.954405) (xy 41.901129 -280.92328) (xy 41.94375 -280.898673)
			(xy 41.989766 -280.881221) (xy 42.037985 -280.871377) (xy 42.08716 -280.869396) (xy 42.136015 -280.875328)
			(xy 42.183286 -280.88902) (xy 42.227748 -280.910118) (xy 42.268251 -280.938074) (xy 42.303744 -280.972166)
			(xy 42.333309 -281.01151) (xy 42.35618 -281.055087) (xy 42.371764 -281.101768) (xy 42.379659 -281.150345)
			(xy 42.380154 -281.174952) (xy 42.719002 -281.174952) (xy 42.722962 -281.125898) (xy 42.734739 -281.078114)
			(xy 42.75403 -281.032838) (xy 42.780333 -280.991242) (xy 42.812968 -280.954405) (xy 42.851089 -280.92328)
			(xy 42.89371 -280.898673) (xy 42.939726 -280.881221) (xy 42.987945 -280.871377) (xy 43.03712 -280.869396)
			(xy 43.085975 -280.875328) (xy 43.133246 -280.88902) (xy 43.177708 -280.910118) (xy 43.218211 -280.938074)
			(xy 43.253704 -280.972166) (xy 43.283269 -281.01151) (xy 43.30614 -281.055087) (xy 43.321724 -281.101768)
			(xy 43.329619 -281.150345) (xy 43.330114 -281.174952) (xy 43.329619 -281.199559) (xy 43.321724 -281.248136)
			(xy 43.30614 -281.294817) (xy 43.283269 -281.338394) (xy 43.253704 -281.377738) (xy 43.218211 -281.41183)
			(xy 43.177708 -281.439786) (xy 43.133246 -281.460884) (xy 43.085975 -281.474576) (xy 43.03712 -281.480508)
			(xy 42.987945 -281.478527) (xy 42.939726 -281.468683) (xy 42.89371 -281.451231) (xy 42.851089 -281.426624)
			(xy 42.812968 -281.395499) (xy 42.780333 -281.358662) (xy 42.75403 -281.317066) (xy 42.734739 -281.27179)
			(xy 42.722962 -281.224006) (xy 42.719002 -281.174952) (xy 42.380154 -281.174952) (xy 42.379659 -281.199559)
			(xy 42.371764 -281.248136) (xy 42.35618 -281.294817) (xy 42.333309 -281.338394) (xy 42.303744 -281.377738)
			(xy 42.268251 -281.41183) (xy 42.227748 -281.439786) (xy 42.183286 -281.460884) (xy 42.136015 -281.474576)
			(xy 42.08716 -281.480508) (xy 42.037985 -281.478527) (xy 41.989766 -281.468683) (xy 41.94375 -281.451231)
			(xy 41.901129 -281.426624) (xy 41.863008 -281.395499) (xy 41.830373 -281.358662) (xy 41.80407 -281.317066)
			(xy 41.784779 -281.27179) (xy 41.773002 -281.224006) (xy 41.769042 -281.174952) (xy 41.430804 -281.174952)
			(xy 41.430808 -281.175) (xy 41.426636 -281.225352) (xy 41.414232 -281.274331) (xy 41.393936 -281.3206)
			(xy 41.366301 -281.362897) (xy 41.33208 -281.400069) (xy 41.292208 -281.431101) (xy 41.247772 -281.455147)
			(xy 41.199985 -281.47155) (xy 41.150148 -281.479864) (xy 41.124886 -281.48026) (xy 41.101259 -281.479813)
			(xy 41.054568 -281.472535) (xy 41.031922 -281.465782) (xy 41.020238 -281.461972) (xy 40.996362 -281.465782)
			(xy 40.920162 -281.521408) (xy 40.910826 -281.529032) (xy 40.899975 -281.550517) (xy 40.899334 -281.562556)
			(xy 40.899334 -281.737308) (xy 40.900002 -281.749334) (xy 40.910867 -281.770796) (xy 40.920162 -281.778456)
			(xy 40.996362 -281.834082) (xy 41.020238 -281.837892) (xy 41.031922 -281.834082) (xy 41.054563 -281.827307)
			(xy 41.101257 -281.820035) (xy 41.124886 -281.819604) (xy 41.150143 -281.820096) (xy 41.19997 -281.828408)
			(xy 41.247748 -281.844808) (xy 41.292176 -281.868849) (xy 41.33204 -281.899875) (xy 41.366253 -281.93704)
			(xy 41.393883 -281.979329) (xy 41.414175 -282.025589) (xy 41.426576 -282.074558) (xy 41.430748 -282.1249)
			(xy 41.430747 -282.124912) (xy 41.769042 -282.124912) (xy 41.773002 -282.075858) (xy 41.784779 -282.028074)
			(xy 41.80407 -281.982798) (xy 41.830373 -281.941202) (xy 41.863008 -281.904365) (xy 41.901129 -281.87324)
			(xy 41.94375 -281.848633) (xy 41.989766 -281.831181) (xy 42.037985 -281.821337) (xy 42.08716 -281.819356)
			(xy 42.136015 -281.825288) (xy 42.183286 -281.83898) (xy 42.227748 -281.860078) (xy 42.268251 -281.888034)
			(xy 42.303744 -281.922126) (xy 42.333309 -281.96147) (xy 42.35618 -282.005047) (xy 42.371764 -282.051728)
			(xy 42.379659 -282.100305) (xy 42.380154 -282.124912) (xy 42.719002 -282.124912) (xy 42.722962 -282.075858)
			(xy 42.734739 -282.028074) (xy 42.75403 -281.982798) (xy 42.780333 -281.941202) (xy 42.812968 -281.904365)
			(xy 42.851089 -281.87324) (xy 42.89371 -281.848633) (xy 42.939726 -281.831181) (xy 42.987945 -281.821337)
			(xy 43.03712 -281.819356) (xy 43.085975 -281.825288) (xy 43.133246 -281.83898) (xy 43.177708 -281.860078)
			(xy 43.218211 -281.888034) (xy 43.253704 -281.922126) (xy 43.283269 -281.96147) (xy 43.30614 -282.005047)
			(xy 43.321724 -282.051728) (xy 43.329619 -282.100305) (xy 43.329948 -282.116638) (xy 43.669093 -282.116638)
			(xy 43.674456 -282.06729) (xy 43.687733 -282.01946) (xy 43.708572 -281.974408) (xy 43.736425 -281.933321)
			(xy 43.770558 -281.897281) (xy 43.810072 -281.867238) (xy 43.853925 -281.843983) (xy 43.900964 -281.828128)
			(xy 43.949947 -281.820093) (xy 43.974766 -281.819604) (xy 43.988949 -281.819785) (xy 44.017189 -281.822454)
			(xy 44.031154 -281.824938) (xy 44.045114 -281.827133) (xy 44.073246 -281.824541) (xy 44.099592 -281.814343)
			(xy 44.122137 -281.797318) (xy 44.139156 -281.774768) (xy 44.149347 -281.74842) (xy 44.151931 -281.720287)
			(xy 44.149772 -281.70632) (xy 44.147288 -281.692355) (xy 44.144621 -281.664115) (xy 44.144438 -281.649932)
			(xy 44.144843 -281.625109) (xy 44.15287 -281.576115) (xy 44.168717 -281.529066) (xy 44.191967 -281.4852)
			(xy 44.222007 -281.445674) (xy 44.258047 -281.411528) (xy 44.299135 -281.383662) (xy 44.344191 -281.362811)
			(xy 44.392026 -281.349524) (xy 44.441381 -281.34415) (xy 44.490955 -281.346832) (xy 44.539442 -281.357499)
			(xy 44.585564 -281.375869) (xy 44.628107 -281.401459) (xy 44.66595 -281.433595) (xy 44.698095 -281.471429)
			(xy 44.723696 -281.513966) (xy 44.742078 -281.560084) (xy 44.752757 -281.608568) (xy 44.755006 -281.649932)
			(xy 45.094156 -281.649932) (xy 45.098116 -281.600878) (xy 45.109893 -281.553094) (xy 45.129184 -281.507818)
			(xy 45.155487 -281.466222) (xy 45.188122 -281.429385) (xy 45.226243 -281.39826) (xy 45.268864 -281.373653)
			(xy 45.31488 -281.356201) (xy 45.363099 -281.346357) (xy 45.412274 -281.344376) (xy 45.461129 -281.350308)
			(xy 45.5084 -281.364) (xy 45.552862 -281.385098) (xy 45.593365 -281.413054) (xy 45.628858 -281.447146)
			(xy 45.658423 -281.48649) (xy 45.681294 -281.530067) (xy 45.696878 -281.576748) (xy 45.704773 -281.625325)
			(xy 45.705268 -281.649932) (xy 46.044116 -281.649932) (xy 46.048076 -281.600878) (xy 46.059853 -281.553094)
			(xy 46.079144 -281.507818) (xy 46.105447 -281.466222) (xy 46.138082 -281.429385) (xy 46.176203 -281.39826)
			(xy 46.218824 -281.373653) (xy 46.26484 -281.356201) (xy 46.313059 -281.346357) (xy 46.362234 -281.344376)
			(xy 46.411089 -281.350308) (xy 46.45836 -281.364) (xy 46.502822 -281.385098) (xy 46.543325 -281.413054)
			(xy 46.578818 -281.447146) (xy 46.608383 -281.48649) (xy 46.631254 -281.530067) (xy 46.646838 -281.576748)
			(xy 46.654733 -281.625325) (xy 46.655228 -281.649932) (xy 46.994076 -281.649932) (xy 46.998036 -281.600878)
			(xy 47.009813 -281.553094) (xy 47.029104 -281.507818) (xy 47.055407 -281.466222) (xy 47.088042 -281.429385)
			(xy 47.126163 -281.39826) (xy 47.168784 -281.373653) (xy 47.2148 -281.356201) (xy 47.263019 -281.346357)
			(xy 47.312194 -281.344376) (xy 47.361049 -281.350308) (xy 47.40832 -281.364) (xy 47.452782 -281.385098)
			(xy 47.493285 -281.413054) (xy 47.528778 -281.447146) (xy 47.558343 -281.48649) (xy 47.581214 -281.530067)
			(xy 47.596798 -281.576748) (xy 47.604693 -281.625325) (xy 47.605188 -281.649932) (xy 47.944036 -281.649932)
			(xy 47.947996 -281.600878) (xy 47.959773 -281.553094) (xy 47.979064 -281.507818) (xy 48.005367 -281.466222)
			(xy 48.038002 -281.429385) (xy 48.076123 -281.39826) (xy 48.118744 -281.373653) (xy 48.16476 -281.356201)
			(xy 48.212979 -281.346357) (xy 48.262154 -281.344376) (xy 48.311009 -281.350308) (xy 48.35828 -281.364)
			(xy 48.402742 -281.385098) (xy 48.443245 -281.413054) (xy 48.478738 -281.447146) (xy 48.508303 -281.48649)
			(xy 48.531174 -281.530067) (xy 48.546758 -281.576748) (xy 48.554653 -281.625325) (xy 48.555148 -281.649932)
			(xy 48.893996 -281.649932) (xy 48.897956 -281.600878) (xy 48.909733 -281.553094) (xy 48.929024 -281.507818)
			(xy 48.955327 -281.466222) (xy 48.987962 -281.429385) (xy 49.026083 -281.39826) (xy 49.068704 -281.373653)
			(xy 49.11472 -281.356201) (xy 49.162939 -281.346357) (xy 49.212114 -281.344376) (xy 49.260969 -281.350308)
			(xy 49.30824 -281.364) (xy 49.352702 -281.385098) (xy 49.393205 -281.413054) (xy 49.428698 -281.447146)
			(xy 49.458263 -281.48649) (xy 49.481134 -281.530067) (xy 49.496718 -281.576748) (xy 49.504613 -281.625325)
			(xy 49.505108 -281.649932) (xy 49.843956 -281.649932) (xy 49.847916 -281.600878) (xy 49.859693 -281.553094)
			(xy 49.878984 -281.507818) (xy 49.905287 -281.466222) (xy 49.937922 -281.429385) (xy 49.976043 -281.39826)
			(xy 50.018664 -281.373653) (xy 50.06468 -281.356201) (xy 50.112899 -281.346357) (xy 50.162074 -281.344376)
			(xy 50.210929 -281.350308) (xy 50.2582 -281.364) (xy 50.302662 -281.385098) (xy 50.343165 -281.413054)
			(xy 50.378658 -281.447146) (xy 50.408223 -281.48649) (xy 50.431094 -281.530067) (xy 50.446678 -281.576748)
			(xy 50.454573 -281.625325) (xy 50.455068 -281.649932) (xy 50.79417 -281.649932) (xy 50.79813 -281.600878)
			(xy 50.809907 -281.553094) (xy 50.829198 -281.507818) (xy 50.855501 -281.466222) (xy 50.888136 -281.429385)
			(xy 50.926257 -281.39826) (xy 50.968878 -281.373653) (xy 51.014894 -281.356201) (xy 51.063113 -281.346357)
			(xy 51.112288 -281.344376) (xy 51.161143 -281.350308) (xy 51.208414 -281.364) (xy 51.252876 -281.385098)
			(xy 51.293379 -281.413054) (xy 51.328872 -281.447146) (xy 51.358437 -281.48649) (xy 51.381308 -281.530067)
			(xy 51.396892 -281.576748) (xy 51.404787 -281.625325) (xy 51.405282 -281.649932) (xy 51.74413 -281.649932)
			(xy 51.74809 -281.600878) (xy 51.759867 -281.553094) (xy 51.779158 -281.507818) (xy 51.805461 -281.466222)
			(xy 51.838096 -281.429385) (xy 51.876217 -281.39826) (xy 51.918838 -281.373653) (xy 51.964854 -281.356201)
			(xy 52.013073 -281.346357) (xy 52.062248 -281.344376) (xy 52.111103 -281.350308) (xy 52.158374 -281.364)
			(xy 52.202836 -281.385098) (xy 52.243339 -281.413054) (xy 52.278832 -281.447146) (xy 52.308397 -281.48649)
			(xy 52.331268 -281.530067) (xy 52.346852 -281.576748) (xy 52.354747 -281.625325) (xy 52.355242 -281.649932)
			(xy 52.69409 -281.649932) (xy 52.69805 -281.600878) (xy 52.709827 -281.553094) (xy 52.729118 -281.507818)
			(xy 52.755421 -281.466222) (xy 52.788056 -281.429385) (xy 52.826177 -281.39826) (xy 52.868798 -281.373653)
			(xy 52.914814 -281.356201) (xy 52.963033 -281.346357) (xy 53.012208 -281.344376) (xy 53.061063 -281.350308)
			(xy 53.108334 -281.364) (xy 53.152796 -281.385098) (xy 53.193299 -281.413054) (xy 53.228792 -281.447146)
			(xy 53.258357 -281.48649) (xy 53.281228 -281.530067) (xy 53.296812 -281.576748) (xy 53.304707 -281.625325)
			(xy 53.305202 -281.649932) (xy 53.305037 -281.658139) (xy 53.644226 -281.658139) (xy 53.64692 -281.608578)
			(xy 53.657596 -281.560106) (xy 53.675973 -281.514) (xy 53.701568 -281.471475) (xy 53.733705 -281.43365)
			(xy 53.771538 -281.401522) (xy 53.81407 -281.375939) (xy 53.860181 -281.357573) (xy 53.908656 -281.346909)
			(xy 53.958217 -281.344228) (xy 54.007559 -281.3496) (xy 54.055382 -281.362884) (xy 54.100426 -281.38373)
			(xy 54.141504 -281.411589) (xy 54.177534 -281.445726) (xy 54.207567 -281.485242) (xy 54.230811 -281.529097)
			(xy 54.246654 -281.576134) (xy 54.254679 -281.625115) (xy 54.255162 -281.649932) (xy 54.254991 -281.664115)
			(xy 54.252315 -281.692355) (xy 54.249828 -281.70632) (xy 54.247542 -281.718766) (xy 54.254908 -281.742388)
			(xy 54.332378 -281.819858) (xy 54.356 -281.827224) (xy 54.368446 -281.824938) (xy 54.382412 -281.82246)
			(xy 54.410651 -281.819789) (xy 54.424834 -281.819604) (xy 54.439017 -281.819776) (xy 54.467257 -281.822451)
			(xy 54.481222 -281.824938) (xy 54.493668 -281.827224) (xy 54.51729 -281.819858) (xy 54.59476 -281.742388)
			(xy 54.602126 -281.718766) (xy 54.59984 -281.70632) (xy 54.597357 -281.692355) (xy 54.594689 -281.664115)
			(xy 54.594506 -281.649932) (xy 54.594943 -281.625108) (xy 54.60297 -281.576114) (xy 54.618818 -281.529064)
			(xy 54.642069 -281.485197) (xy 54.672111 -281.44567) (xy 54.708151 -281.411524) (xy 54.749242 -281.383659)
			(xy 54.794299 -281.362808) (xy 54.842135 -281.349522) (xy 54.891491 -281.34415) (xy 54.941066 -281.346834)
			(xy 54.989554 -281.357502) (xy 55.035677 -281.375875) (xy 55.07822 -281.401468) (xy 55.116062 -281.433606)
			(xy 55.148205 -281.471443) (xy 55.173804 -281.513982) (xy 55.192184 -281.560102) (xy 55.20286 -281.608588)
			(xy 55.205104 -281.649932) (xy 55.54397 -281.649932) (xy 55.54793 -281.600878) (xy 55.559707 -281.553094)
			(xy 55.578998 -281.507818) (xy 55.605301 -281.466222) (xy 55.637936 -281.429385) (xy 55.676057 -281.39826)
			(xy 55.718678 -281.373653) (xy 55.764694 -281.356201) (xy 55.812913 -281.346357) (xy 55.862088 -281.344376)
			(xy 55.910943 -281.350308) (xy 55.958214 -281.364) (xy 56.002676 -281.385098) (xy 56.043179 -281.413054)
			(xy 56.078672 -281.447146) (xy 56.108237 -281.48649) (xy 56.131108 -281.530067) (xy 56.146692 -281.576748)
			(xy 56.154587 -281.625325) (xy 56.155082 -281.649932) (xy 56.494184 -281.649932) (xy 56.498144 -281.600878)
			(xy 56.509921 -281.553094) (xy 56.529212 -281.507818) (xy 56.555515 -281.466222) (xy 56.58815 -281.429385)
			(xy 56.626271 -281.39826) (xy 56.668892 -281.373653) (xy 56.714908 -281.356201) (xy 56.763127 -281.346357)
			(xy 56.812302 -281.344376) (xy 56.861157 -281.350308) (xy 56.908428 -281.364) (xy 56.95289 -281.385098)
			(xy 56.993393 -281.413054) (xy 57.028886 -281.447146) (xy 57.058451 -281.48649) (xy 57.081322 -281.530067)
			(xy 57.096906 -281.576748) (xy 57.104801 -281.625325) (xy 57.105296 -281.649932) (xy 57.444144 -281.649932)
			(xy 57.448104 -281.600878) (xy 57.459881 -281.553094) (xy 57.479172 -281.507818) (xy 57.505475 -281.466222)
			(xy 57.53811 -281.429385) (xy 57.576231 -281.39826) (xy 57.618852 -281.373653) (xy 57.664868 -281.356201)
			(xy 57.713087 -281.346357) (xy 57.762262 -281.344376) (xy 57.811117 -281.350308) (xy 57.858388 -281.364)
			(xy 57.90285 -281.385098) (xy 57.943353 -281.413054) (xy 57.978846 -281.447146) (xy 58.008411 -281.48649)
			(xy 58.031282 -281.530067) (xy 58.046866 -281.576748) (xy 58.054761 -281.625325) (xy 58.055256 -281.649932)
			(xy 58.394104 -281.649932) (xy 58.398064 -281.600878) (xy 58.409841 -281.553094) (xy 58.429132 -281.507818)
			(xy 58.455435 -281.466222) (xy 58.48807 -281.429385) (xy 58.526191 -281.39826) (xy 58.568812 -281.373653)
			(xy 58.614828 -281.356201) (xy 58.663047 -281.346357) (xy 58.712222 -281.344376) (xy 58.761077 -281.350308)
			(xy 58.808348 -281.364) (xy 58.85281 -281.385098) (xy 58.893313 -281.413054) (xy 58.928806 -281.447146)
			(xy 58.958371 -281.48649) (xy 58.981242 -281.530067) (xy 58.996826 -281.576748) (xy 59.004721 -281.625325)
			(xy 59.005216 -281.649932) (xy 59.344064 -281.649932) (xy 59.348024 -281.600878) (xy 59.359801 -281.553094)
			(xy 59.379092 -281.507818) (xy 59.405395 -281.466222) (xy 59.43803 -281.429385) (xy 59.476151 -281.39826)
			(xy 59.518772 -281.373653) (xy 59.564788 -281.356201) (xy 59.613007 -281.346357) (xy 59.662182 -281.344376)
			(xy 59.711037 -281.350308) (xy 59.758308 -281.364) (xy 59.80277 -281.385098) (xy 59.843273 -281.413054)
			(xy 59.878766 -281.447146) (xy 59.908331 -281.48649) (xy 59.931202 -281.530067) (xy 59.946786 -281.576748)
			(xy 59.954681 -281.625325) (xy 59.955176 -281.649932) (xy 60.294024 -281.649932) (xy 60.297984 -281.600878)
			(xy 60.309761 -281.553094) (xy 60.329052 -281.507818) (xy 60.355355 -281.466222) (xy 60.38799 -281.429385)
			(xy 60.426111 -281.39826) (xy 60.468732 -281.373653) (xy 60.514748 -281.356201) (xy 60.562967 -281.346357)
			(xy 60.612142 -281.344376) (xy 60.660997 -281.350308) (xy 60.708268 -281.364) (xy 60.75273 -281.385098)
			(xy 60.793233 -281.413054) (xy 60.828726 -281.447146) (xy 60.858291 -281.48649) (xy 60.881162 -281.530067)
			(xy 60.896746 -281.576748) (xy 60.904641 -281.625325) (xy 60.905136 -281.649932) (xy 61.243984 -281.649932)
			(xy 61.247944 -281.600878) (xy 61.259721 -281.553094) (xy 61.279012 -281.507818) (xy 61.305315 -281.466222)
			(xy 61.33795 -281.429385) (xy 61.376071 -281.39826) (xy 61.418692 -281.373653) (xy 61.464708 -281.356201)
			(xy 61.512927 -281.346357) (xy 61.562102 -281.344376) (xy 61.610957 -281.350308) (xy 61.658228 -281.364)
			(xy 61.70269 -281.385098) (xy 61.743193 -281.413054) (xy 61.778686 -281.447146) (xy 61.808251 -281.48649)
			(xy 61.831122 -281.530067) (xy 61.846706 -281.576748) (xy 61.854601 -281.625325) (xy 61.855096 -281.649932)
			(xy 62.193944 -281.649932) (xy 62.197904 -281.600878) (xy 62.209681 -281.553094) (xy 62.228972 -281.507818)
			(xy 62.255275 -281.466222) (xy 62.28791 -281.429385) (xy 62.326031 -281.39826) (xy 62.368652 -281.373653)
			(xy 62.414668 -281.356201) (xy 62.462887 -281.346357) (xy 62.512062 -281.344376) (xy 62.560917 -281.350308)
			(xy 62.608188 -281.364) (xy 62.65265 -281.385098) (xy 62.693153 -281.413054) (xy 62.728646 -281.447146)
			(xy 62.758211 -281.48649) (xy 62.781082 -281.530067) (xy 62.796666 -281.576748) (xy 62.804561 -281.625325)
			(xy 62.805056 -281.649932) (xy 63.144158 -281.649932) (xy 63.148118 -281.600878) (xy 63.159895 -281.553094)
			(xy 63.179186 -281.507818) (xy 63.205489 -281.466222) (xy 63.238124 -281.429385) (xy 63.276245 -281.39826)
			(xy 63.318866 -281.373653) (xy 63.364882 -281.356201) (xy 63.413101 -281.346357) (xy 63.462276 -281.344376)
			(xy 63.511131 -281.350308) (xy 63.558402 -281.364) (xy 63.602864 -281.385098) (xy 63.643367 -281.413054)
			(xy 63.67886 -281.447146) (xy 63.708425 -281.48649) (xy 63.731296 -281.530067) (xy 63.74688 -281.576748)
			(xy 63.754775 -281.625325) (xy 63.75527 -281.649932) (xy 64.094118 -281.649932) (xy 64.098078 -281.600878)
			(xy 64.109855 -281.553094) (xy 64.129146 -281.507818) (xy 64.155449 -281.466222) (xy 64.188084 -281.429385)
			(xy 64.226205 -281.39826) (xy 64.268826 -281.373653) (xy 64.314842 -281.356201) (xy 64.363061 -281.346357)
			(xy 64.412236 -281.344376) (xy 64.461091 -281.350308) (xy 64.508362 -281.364) (xy 64.552824 -281.385098)
			(xy 64.593327 -281.413054) (xy 64.62882 -281.447146) (xy 64.658385 -281.48649) (xy 64.681256 -281.530067)
			(xy 64.69684 -281.576748) (xy 64.704735 -281.625325) (xy 64.70523 -281.649932) (xy 65.044078 -281.649932)
			(xy 65.048038 -281.600878) (xy 65.059815 -281.553094) (xy 65.079106 -281.507818) (xy 65.105409 -281.466222)
			(xy 65.138044 -281.429385) (xy 65.176165 -281.39826) (xy 65.218786 -281.373653) (xy 65.264802 -281.356201)
			(xy 65.313021 -281.346357) (xy 65.362196 -281.344376) (xy 65.411051 -281.350308) (xy 65.458322 -281.364)
			(xy 65.502784 -281.385098) (xy 65.543287 -281.413054) (xy 65.57878 -281.447146) (xy 65.608345 -281.48649)
			(xy 65.631216 -281.530067) (xy 65.6468 -281.576748) (xy 65.654695 -281.625325) (xy 65.65519 -281.649932)
			(xy 65.994038 -281.649932) (xy 65.997998 -281.600878) (xy 66.009775 -281.553094) (xy 66.029066 -281.507818)
			(xy 66.055369 -281.466222) (xy 66.088004 -281.429385) (xy 66.126125 -281.39826) (xy 66.168746 -281.373653)
			(xy 66.214762 -281.356201) (xy 66.262981 -281.346357) (xy 66.312156 -281.344376) (xy 66.361011 -281.350308)
			(xy 66.408282 -281.364) (xy 66.452744 -281.385098) (xy 66.493247 -281.413054) (xy 66.52874 -281.447146)
			(xy 66.558305 -281.48649) (xy 66.581176 -281.530067) (xy 66.59676 -281.576748) (xy 66.604655 -281.625325)
			(xy 66.60515 -281.649932) (xy 66.943998 -281.649932) (xy 66.947958 -281.600878) (xy 66.959735 -281.553094)
			(xy 66.979026 -281.507818) (xy 67.005329 -281.466222) (xy 67.037964 -281.429385) (xy 67.076085 -281.39826)
			(xy 67.118706 -281.373653) (xy 67.164722 -281.356201) (xy 67.212941 -281.346357) (xy 67.262116 -281.344376)
			(xy 67.310971 -281.350308) (xy 67.358242 -281.364) (xy 67.402704 -281.385098) (xy 67.443207 -281.413054)
			(xy 67.4787 -281.447146) (xy 67.508265 -281.48649) (xy 67.531136 -281.530067) (xy 67.54672 -281.576748)
			(xy 67.554615 -281.625325) (xy 67.55511 -281.649932) (xy 67.893958 -281.649932) (xy 67.897918 -281.600878)
			(xy 67.909695 -281.553094) (xy 67.928986 -281.507818) (xy 67.955289 -281.466222) (xy 67.987924 -281.429385)
			(xy 68.026045 -281.39826) (xy 68.068666 -281.373653) (xy 68.114682 -281.356201) (xy 68.162901 -281.346357)
			(xy 68.212076 -281.344376) (xy 68.260931 -281.350308) (xy 68.308202 -281.364) (xy 68.352664 -281.385098)
			(xy 68.393167 -281.413054) (xy 68.42866 -281.447146) (xy 68.458225 -281.48649) (xy 68.481096 -281.530067)
			(xy 68.49668 -281.576748) (xy 68.504575 -281.625325) (xy 68.50507 -281.649932) (xy 68.844172 -281.649932)
			(xy 68.848132 -281.600878) (xy 68.859909 -281.553094) (xy 68.8792 -281.507818) (xy 68.905503 -281.466222)
			(xy 68.938138 -281.429385) (xy 68.976259 -281.39826) (xy 69.01888 -281.373653) (xy 69.064896 -281.356201)
			(xy 69.113115 -281.346357) (xy 69.16229 -281.344376) (xy 69.211145 -281.350308) (xy 69.258416 -281.364)
			(xy 69.302878 -281.385098) (xy 69.343381 -281.413054) (xy 69.378874 -281.447146) (xy 69.408439 -281.48649)
			(xy 69.43131 -281.530067) (xy 69.446894 -281.576748) (xy 69.454789 -281.625325) (xy 69.455284 -281.649932)
			(xy 69.794132 -281.649932) (xy 69.798092 -281.600878) (xy 69.809869 -281.553094) (xy 69.82916 -281.507818)
			(xy 69.855463 -281.466222) (xy 69.888098 -281.429385) (xy 69.926219 -281.39826) (xy 69.96884 -281.373653)
			(xy 70.014856 -281.356201) (xy 70.063075 -281.346357) (xy 70.11225 -281.344376) (xy 70.161105 -281.350308)
			(xy 70.208376 -281.364) (xy 70.252838 -281.385098) (xy 70.293341 -281.413054) (xy 70.328834 -281.447146)
			(xy 70.358399 -281.48649) (xy 70.38127 -281.530067) (xy 70.396854 -281.576748) (xy 70.404749 -281.625325)
			(xy 70.405244 -281.649932) (xy 70.744092 -281.649932) (xy 70.748052 -281.600878) (xy 70.759829 -281.553094)
			(xy 70.77912 -281.507818) (xy 70.805423 -281.466222) (xy 70.838058 -281.429385) (xy 70.876179 -281.39826)
			(xy 70.9188 -281.373653) (xy 70.964816 -281.356201) (xy 71.013035 -281.346357) (xy 71.06221 -281.344376)
			(xy 71.111065 -281.350308) (xy 71.158336 -281.364) (xy 71.202798 -281.385098) (xy 71.243301 -281.413054)
			(xy 71.278794 -281.447146) (xy 71.308359 -281.48649) (xy 71.33123 -281.530067) (xy 71.346814 -281.576748)
			(xy 71.354709 -281.625325) (xy 71.355204 -281.649932) (xy 71.694052 -281.649932) (xy 71.698012 -281.600878)
			(xy 71.709789 -281.553094) (xy 71.72908 -281.507818) (xy 71.755383 -281.466222) (xy 71.788018 -281.429385)
			(xy 71.826139 -281.39826) (xy 71.86876 -281.373653) (xy 71.914776 -281.356201) (xy 71.962995 -281.346357)
			(xy 72.01217 -281.344376) (xy 72.061025 -281.350308) (xy 72.108296 -281.364) (xy 72.152758 -281.385098)
			(xy 72.193261 -281.413054) (xy 72.228754 -281.447146) (xy 72.258319 -281.48649) (xy 72.28119 -281.530067)
			(xy 72.296774 -281.576748) (xy 72.304669 -281.625325) (xy 72.305164 -281.649932) (xy 72.644012 -281.649932)
			(xy 72.647972 -281.600878) (xy 72.659749 -281.553094) (xy 72.67904 -281.507818) (xy 72.705343 -281.466222)
			(xy 72.737978 -281.429385) (xy 72.776099 -281.39826) (xy 72.81872 -281.373653) (xy 72.864736 -281.356201)
			(xy 72.912955 -281.346357) (xy 72.96213 -281.344376) (xy 73.010985 -281.350308) (xy 73.058256 -281.364)
			(xy 73.102718 -281.385098) (xy 73.143221 -281.413054) (xy 73.178714 -281.447146) (xy 73.208279 -281.48649)
			(xy 73.23115 -281.530067) (xy 73.246734 -281.576748) (xy 73.254629 -281.625325) (xy 73.255124 -281.649932)
			(xy 73.593972 -281.649932) (xy 73.597932 -281.600878) (xy 73.609709 -281.553094) (xy 73.629 -281.507818)
			(xy 73.655303 -281.466222) (xy 73.687938 -281.429385) (xy 73.726059 -281.39826) (xy 73.76868 -281.373653)
			(xy 73.814696 -281.356201) (xy 73.862915 -281.346357) (xy 73.91209 -281.344376) (xy 73.960945 -281.350308)
			(xy 74.008216 -281.364) (xy 74.052678 -281.385098) (xy 74.093181 -281.413054) (xy 74.128674 -281.447146)
			(xy 74.158239 -281.48649) (xy 74.18111 -281.530067) (xy 74.196694 -281.576748) (xy 74.204589 -281.625325)
			(xy 74.205084 -281.649932) (xy 74.544186 -281.649932) (xy 74.548146 -281.600878) (xy 74.559923 -281.553094)
			(xy 74.579214 -281.507818) (xy 74.605517 -281.466222) (xy 74.638152 -281.429385) (xy 74.676273 -281.39826)
			(xy 74.718894 -281.373653) (xy 74.76491 -281.356201) (xy 74.813129 -281.346357) (xy 74.862304 -281.344376)
			(xy 74.911159 -281.350308) (xy 74.95843 -281.364) (xy 75.002892 -281.385098) (xy 75.043395 -281.413054)
			(xy 75.078888 -281.447146) (xy 75.108453 -281.48649) (xy 75.131324 -281.530067) (xy 75.146908 -281.576748)
			(xy 75.154803 -281.625325) (xy 75.155298 -281.649932) (xy 75.494146 -281.649932) (xy 75.498106 -281.600878)
			(xy 75.509883 -281.553094) (xy 75.529174 -281.507818) (xy 75.555477 -281.466222) (xy 75.588112 -281.429385)
			(xy 75.626233 -281.39826) (xy 75.668854 -281.373653) (xy 75.71487 -281.356201) (xy 75.763089 -281.346357)
			(xy 75.812264 -281.344376) (xy 75.861119 -281.350308) (xy 75.90839 -281.364) (xy 75.952852 -281.385098)
			(xy 75.993355 -281.413054) (xy 76.028848 -281.447146) (xy 76.058413 -281.48649) (xy 76.081284 -281.530067)
			(xy 76.096868 -281.576748) (xy 76.104763 -281.625325) (xy 76.105258 -281.649932) (xy 76.444106 -281.649932)
			(xy 76.448066 -281.600878) (xy 76.459843 -281.553094) (xy 76.479134 -281.507818) (xy 76.505437 -281.466222)
			(xy 76.538072 -281.429385) (xy 76.576193 -281.39826) (xy 76.618814 -281.373653) (xy 76.66483 -281.356201)
			(xy 76.713049 -281.346357) (xy 76.762224 -281.344376) (xy 76.811079 -281.350308) (xy 76.85835 -281.364)
			(xy 76.902812 -281.385098) (xy 76.943315 -281.413054) (xy 76.978808 -281.447146) (xy 77.008373 -281.48649)
			(xy 77.031244 -281.530067) (xy 77.046828 -281.576748) (xy 77.054723 -281.625325) (xy 77.055213 -281.649678)
			(xy 77.393812 -281.649678) (xy 77.397772 -281.600624) (xy 77.409549 -281.55284) (xy 77.42884 -281.507564)
			(xy 77.455143 -281.465968) (xy 77.487778 -281.429131) (xy 77.525899 -281.398006) (xy 77.56852 -281.373399)
			(xy 77.614536 -281.355947) (xy 77.662755 -281.346103) (xy 77.71193 -281.344122) (xy 77.760785 -281.350054)
			(xy 77.808056 -281.363746) (xy 77.852518 -281.384844) (xy 77.893021 -281.4128) (xy 77.928514 -281.446892)
			(xy 77.958079 -281.486236) (xy 77.98095 -281.529813) (xy 77.996534 -281.576494) (xy 78.004429 -281.625071)
			(xy 78.004924 -281.649678) (xy 78.004919 -281.649932) (xy 78.343772 -281.649932) (xy 78.347732 -281.600878)
			(xy 78.359509 -281.553094) (xy 78.3788 -281.507818) (xy 78.405103 -281.466222) (xy 78.437738 -281.429385)
			(xy 78.475859 -281.39826) (xy 78.51848 -281.373653) (xy 78.564496 -281.356201) (xy 78.612715 -281.346357)
			(xy 78.66189 -281.344376) (xy 78.710745 -281.350308) (xy 78.758016 -281.364) (xy 78.802478 -281.385098)
			(xy 78.842981 -281.413054) (xy 78.878474 -281.447146) (xy 78.908039 -281.48649) (xy 78.93091 -281.530067)
			(xy 78.946494 -281.576748) (xy 78.954389 -281.625325) (xy 78.954884 -281.649932) (xy 79.293986 -281.649932)
			(xy 79.297946 -281.600878) (xy 79.309723 -281.553094) (xy 79.329014 -281.507818) (xy 79.355317 -281.466222)
			(xy 79.387952 -281.429385) (xy 79.426073 -281.39826) (xy 79.468694 -281.373653) (xy 79.51471 -281.356201)
			(xy 79.562929 -281.346357) (xy 79.612104 -281.344376) (xy 79.660959 -281.350308) (xy 79.70823 -281.364)
			(xy 79.752692 -281.385098) (xy 79.793195 -281.413054) (xy 79.828688 -281.447146) (xy 79.858253 -281.48649)
			(xy 79.881124 -281.530067) (xy 79.896708 -281.576748) (xy 79.904603 -281.625325) (xy 79.905098 -281.649932)
			(xy 80.243946 -281.649932) (xy 80.247906 -281.600878) (xy 80.259683 -281.553094) (xy 80.278974 -281.507818)
			(xy 80.305277 -281.466222) (xy 80.337912 -281.429385) (xy 80.376033 -281.39826) (xy 80.418654 -281.373653)
			(xy 80.46467 -281.356201) (xy 80.512889 -281.346357) (xy 80.562064 -281.344376) (xy 80.610919 -281.350308)
			(xy 80.65819 -281.364) (xy 80.702652 -281.385098) (xy 80.743155 -281.413054) (xy 80.778648 -281.447146)
			(xy 80.808213 -281.48649) (xy 80.831084 -281.530067) (xy 80.846668 -281.576748) (xy 80.854563 -281.625325)
			(xy 80.855058 -281.649932) (xy 80.854563 -281.674539) (xy 80.854384 -281.67564) (xy 81.173316 -281.67564)
			(xy 81.173316 -281.624224) (xy 81.181359 -281.573442) (xy 81.197247 -281.524543) (xy 81.22059 -281.478731)
			(xy 81.250811 -281.437135) (xy 81.287167 -281.400779) (xy 81.328763 -281.370558) (xy 81.374575 -281.347215)
			(xy 81.423474 -281.331327) (xy 81.474256 -281.323284) (xy 81.525672 -281.323284) (xy 81.576454 -281.331327)
			(xy 81.625353 -281.347215) (xy 81.671165 -281.370558) (xy 81.712761 -281.400779) (xy 81.749117 -281.437135)
			(xy 81.779338 -281.478731) (xy 81.802681 -281.524543) (xy 81.818569 -281.573442) (xy 81.826612 -281.624224)
			(xy 81.827116 -281.649932) (xy 81.826612 -281.67564) (xy 82.123276 -281.67564) (xy 82.123276 -281.624224)
			(xy 82.131319 -281.573442) (xy 82.147207 -281.524543) (xy 82.17055 -281.478731) (xy 82.200771 -281.437135)
			(xy 82.237127 -281.400779) (xy 82.278723 -281.370558) (xy 82.324535 -281.347215) (xy 82.373434 -281.331327)
			(xy 82.424216 -281.323284) (xy 82.475632 -281.323284) (xy 82.526414 -281.331327) (xy 82.575313 -281.347215)
			(xy 82.621125 -281.370558) (xy 82.662721 -281.400779) (xy 82.699077 -281.437135) (xy 82.729298 -281.478731)
			(xy 82.752641 -281.524543) (xy 82.768529 -281.573442) (xy 82.776572 -281.624224) (xy 82.777076 -281.649932)
			(xy 82.777071 -281.650186) (xy 83.094334 -281.650186) (xy 83.098294 -281.601132) (xy 83.110071 -281.553348)
			(xy 83.129362 -281.508072) (xy 83.155665 -281.466476) (xy 83.1883 -281.429639) (xy 83.226421 -281.398514)
			(xy 83.269042 -281.373907) (xy 83.315058 -281.356455) (xy 83.363277 -281.346611) (xy 83.412452 -281.34463)
			(xy 83.461307 -281.350562) (xy 83.508578 -281.364254) (xy 83.55304 -281.385352) (xy 83.593543 -281.413308)
			(xy 83.629036 -281.4474) (xy 83.658601 -281.486744) (xy 83.681472 -281.530321) (xy 83.697056 -281.577002)
			(xy 83.704951 -281.625579) (xy 83.705446 -281.650186) (xy 83.704951 -281.674793) (xy 83.697056 -281.72337)
			(xy 83.681472 -281.770051) (xy 83.658601 -281.813628) (xy 83.629036 -281.852972) (xy 83.593543 -281.887064)
			(xy 83.55304 -281.91502) (xy 83.508578 -281.936118) (xy 83.461307 -281.94981) (xy 83.412452 -281.955742)
			(xy 83.363277 -281.953761) (xy 83.315058 -281.943917) (xy 83.269042 -281.926465) (xy 83.226421 -281.901858)
			(xy 83.1883 -281.870733) (xy 83.155665 -281.833896) (xy 83.129362 -281.7923) (xy 83.110071 -281.747024)
			(xy 83.098294 -281.69924) (xy 83.094334 -281.650186) (xy 82.777071 -281.650186) (xy 82.776572 -281.67564)
			(xy 82.768529 -281.726422) (xy 82.752641 -281.775321) (xy 82.729298 -281.821133) (xy 82.699077 -281.862729)
			(xy 82.662721 -281.899085) (xy 82.621125 -281.929306) (xy 82.575313 -281.952649) (xy 82.526414 -281.968537)
			(xy 82.475632 -281.97658) (xy 82.424216 -281.97658) (xy 82.373434 -281.968537) (xy 82.324535 -281.952649)
			(xy 82.278723 -281.929306) (xy 82.237127 -281.899085) (xy 82.200771 -281.862729) (xy 82.17055 -281.821133)
			(xy 82.147207 -281.775321) (xy 82.131319 -281.726422) (xy 82.123276 -281.67564) (xy 81.826612 -281.67564)
			(xy 81.818569 -281.726422) (xy 81.802681 -281.775321) (xy 81.779338 -281.821133) (xy 81.749117 -281.862729)
			(xy 81.712761 -281.899085) (xy 81.671165 -281.929306) (xy 81.625353 -281.952649) (xy 81.576454 -281.968537)
			(xy 81.525672 -281.97658) (xy 81.474256 -281.97658) (xy 81.423474 -281.968537) (xy 81.374575 -281.952649)
			(xy 81.328763 -281.929306) (xy 81.287167 -281.899085) (xy 81.250811 -281.862729) (xy 81.22059 -281.821133)
			(xy 81.197247 -281.775321) (xy 81.181359 -281.726422) (xy 81.173316 -281.67564) (xy 80.854384 -281.67564)
			(xy 80.846668 -281.723116) (xy 80.831084 -281.769797) (xy 80.808213 -281.813374) (xy 80.778648 -281.852718)
			(xy 80.743155 -281.88681) (xy 80.702652 -281.914766) (xy 80.65819 -281.935864) (xy 80.610919 -281.949556)
			(xy 80.562064 -281.955488) (xy 80.512889 -281.953507) (xy 80.46467 -281.943663) (xy 80.418654 -281.926211)
			(xy 80.376033 -281.901604) (xy 80.337912 -281.870479) (xy 80.305277 -281.833642) (xy 80.278974 -281.792046)
			(xy 80.259683 -281.74677) (xy 80.247906 -281.698986) (xy 80.243946 -281.649932) (xy 79.905098 -281.649932)
			(xy 79.904603 -281.674539) (xy 79.896708 -281.723116) (xy 79.881124 -281.769797) (xy 79.858253 -281.813374)
			(xy 79.828688 -281.852718) (xy 79.793195 -281.88681) (xy 79.752692 -281.914766) (xy 79.70823 -281.935864)
			(xy 79.660959 -281.949556) (xy 79.612104 -281.955488) (xy 79.562929 -281.953507) (xy 79.51471 -281.943663)
			(xy 79.468694 -281.926211) (xy 79.426073 -281.901604) (xy 79.387952 -281.870479) (xy 79.355317 -281.833642)
			(xy 79.329014 -281.792046) (xy 79.309723 -281.74677) (xy 79.297946 -281.698986) (xy 79.293986 -281.649932)
			(xy 78.954884 -281.649932) (xy 78.954389 -281.674539) (xy 78.946494 -281.723116) (xy 78.93091 -281.769797)
			(xy 78.908039 -281.813374) (xy 78.878474 -281.852718) (xy 78.842981 -281.88681) (xy 78.802478 -281.914766)
			(xy 78.758016 -281.935864) (xy 78.710745 -281.949556) (xy 78.66189 -281.955488) (xy 78.612715 -281.953507)
			(xy 78.564496 -281.943663) (xy 78.51848 -281.926211) (xy 78.475859 -281.901604) (xy 78.437738 -281.870479)
			(xy 78.405103 -281.833642) (xy 78.3788 -281.792046) (xy 78.359509 -281.74677) (xy 78.347732 -281.698986)
			(xy 78.343772 -281.649932) (xy 78.004919 -281.649932) (xy 78.004429 -281.674285) (xy 77.996534 -281.722862)
			(xy 77.98095 -281.769543) (xy 77.958079 -281.81312) (xy 77.928514 -281.852464) (xy 77.893021 -281.886556)
			(xy 77.852518 -281.914512) (xy 77.808056 -281.93561) (xy 77.760785 -281.949302) (xy 77.71193 -281.955234)
			(xy 77.662755 -281.953253) (xy 77.614536 -281.943409) (xy 77.56852 -281.925957) (xy 77.525899 -281.90135)
			(xy 77.487778 -281.870225) (xy 77.455143 -281.833388) (xy 77.42884 -281.791792) (xy 77.409549 -281.746516)
			(xy 77.397772 -281.698732) (xy 77.393812 -281.649678) (xy 77.055213 -281.649678) (xy 77.055218 -281.649932)
			(xy 77.054723 -281.674539) (xy 77.046828 -281.723116) (xy 77.031244 -281.769797) (xy 77.008373 -281.813374)
			(xy 76.978808 -281.852718) (xy 76.943315 -281.88681) (xy 76.902812 -281.914766) (xy 76.85835 -281.935864)
			(xy 76.811079 -281.949556) (xy 76.762224 -281.955488) (xy 76.713049 -281.953507) (xy 76.66483 -281.943663)
			(xy 76.618814 -281.926211) (xy 76.576193 -281.901604) (xy 76.538072 -281.870479) (xy 76.505437 -281.833642)
			(xy 76.479134 -281.792046) (xy 76.459843 -281.74677) (xy 76.448066 -281.698986) (xy 76.444106 -281.649932)
			(xy 76.105258 -281.649932) (xy 76.104763 -281.674539) (xy 76.096868 -281.723116) (xy 76.081284 -281.769797)
			(xy 76.058413 -281.813374) (xy 76.028848 -281.852718) (xy 75.993355 -281.88681) (xy 75.952852 -281.914766)
			(xy 75.90839 -281.935864) (xy 75.861119 -281.949556) (xy 75.812264 -281.955488) (xy 75.763089 -281.953507)
			(xy 75.71487 -281.943663) (xy 75.668854 -281.926211) (xy 75.626233 -281.901604) (xy 75.588112 -281.870479)
			(xy 75.555477 -281.833642) (xy 75.529174 -281.792046) (xy 75.509883 -281.74677) (xy 75.498106 -281.698986)
			(xy 75.494146 -281.649932) (xy 75.155298 -281.649932) (xy 75.154803 -281.674539) (xy 75.146908 -281.723116)
			(xy 75.131324 -281.769797) (xy 75.108453 -281.813374) (xy 75.078888 -281.852718) (xy 75.043395 -281.88681)
			(xy 75.002892 -281.914766) (xy 74.95843 -281.935864) (xy 74.911159 -281.949556) (xy 74.862304 -281.955488)
			(xy 74.813129 -281.953507) (xy 74.76491 -281.943663) (xy 74.718894 -281.926211) (xy 74.676273 -281.901604)
			(xy 74.638152 -281.870479) (xy 74.605517 -281.833642) (xy 74.579214 -281.792046) (xy 74.559923 -281.74677)
			(xy 74.548146 -281.698986) (xy 74.544186 -281.649932) (xy 74.205084 -281.649932) (xy 74.204589 -281.674539)
			(xy 74.196694 -281.723116) (xy 74.18111 -281.769797) (xy 74.158239 -281.813374) (xy 74.128674 -281.852718)
			(xy 74.093181 -281.88681) (xy 74.052678 -281.914766) (xy 74.008216 -281.935864) (xy 73.960945 -281.949556)
			(xy 73.91209 -281.955488) (xy 73.862915 -281.953507) (xy 73.814696 -281.943663) (xy 73.76868 -281.926211)
			(xy 73.726059 -281.901604) (xy 73.687938 -281.870479) (xy 73.655303 -281.833642) (xy 73.629 -281.792046)
			(xy 73.609709 -281.74677) (xy 73.597932 -281.698986) (xy 73.593972 -281.649932) (xy 73.255124 -281.649932)
			(xy 73.254629 -281.674539) (xy 73.246734 -281.723116) (xy 73.23115 -281.769797) (xy 73.208279 -281.813374)
			(xy 73.178714 -281.852718) (xy 73.143221 -281.88681) (xy 73.102718 -281.914766) (xy 73.058256 -281.935864)
			(xy 73.010985 -281.949556) (xy 72.96213 -281.955488) (xy 72.912955 -281.953507) (xy 72.864736 -281.943663)
			(xy 72.81872 -281.926211) (xy 72.776099 -281.901604) (xy 72.737978 -281.870479) (xy 72.705343 -281.833642)
			(xy 72.67904 -281.792046) (xy 72.659749 -281.74677) (xy 72.647972 -281.698986) (xy 72.644012 -281.649932)
			(xy 72.305164 -281.649932) (xy 72.304669 -281.674539) (xy 72.296774 -281.723116) (xy 72.28119 -281.769797)
			(xy 72.258319 -281.813374) (xy 72.228754 -281.852718) (xy 72.193261 -281.88681) (xy 72.152758 -281.914766)
			(xy 72.108296 -281.935864) (xy 72.061025 -281.949556) (xy 72.01217 -281.955488) (xy 71.962995 -281.953507)
			(xy 71.914776 -281.943663) (xy 71.86876 -281.926211) (xy 71.826139 -281.901604) (xy 71.788018 -281.870479)
			(xy 71.755383 -281.833642) (xy 71.72908 -281.792046) (xy 71.709789 -281.74677) (xy 71.698012 -281.698986)
			(xy 71.694052 -281.649932) (xy 71.355204 -281.649932) (xy 71.354709 -281.674539) (xy 71.346814 -281.723116)
			(xy 71.33123 -281.769797) (xy 71.308359 -281.813374) (xy 71.278794 -281.852718) (xy 71.243301 -281.88681)
			(xy 71.202798 -281.914766) (xy 71.158336 -281.935864) (xy 71.111065 -281.949556) (xy 71.06221 -281.955488)
			(xy 71.013035 -281.953507) (xy 70.964816 -281.943663) (xy 70.9188 -281.926211) (xy 70.876179 -281.901604)
			(xy 70.838058 -281.870479) (xy 70.805423 -281.833642) (xy 70.77912 -281.792046) (xy 70.759829 -281.74677)
			(xy 70.748052 -281.698986) (xy 70.744092 -281.649932) (xy 70.405244 -281.649932) (xy 70.404749 -281.674539)
			(xy 70.396854 -281.723116) (xy 70.38127 -281.769797) (xy 70.358399 -281.813374) (xy 70.328834 -281.852718)
			(xy 70.293341 -281.88681) (xy 70.252838 -281.914766) (xy 70.208376 -281.935864) (xy 70.161105 -281.949556)
			(xy 70.11225 -281.955488) (xy 70.063075 -281.953507) (xy 70.014856 -281.943663) (xy 69.96884 -281.926211)
			(xy 69.926219 -281.901604) (xy 69.888098 -281.870479) (xy 69.855463 -281.833642) (xy 69.82916 -281.792046)
			(xy 69.809869 -281.74677) (xy 69.798092 -281.698986) (xy 69.794132 -281.649932) (xy 69.455284 -281.649932)
			(xy 69.454789 -281.674539) (xy 69.446894 -281.723116) (xy 69.43131 -281.769797) (xy 69.408439 -281.813374)
			(xy 69.378874 -281.852718) (xy 69.343381 -281.88681) (xy 69.302878 -281.914766) (xy 69.258416 -281.935864)
			(xy 69.211145 -281.949556) (xy 69.16229 -281.955488) (xy 69.113115 -281.953507) (xy 69.064896 -281.943663)
			(xy 69.01888 -281.926211) (xy 68.976259 -281.901604) (xy 68.938138 -281.870479) (xy 68.905503 -281.833642)
			(xy 68.8792 -281.792046) (xy 68.859909 -281.74677) (xy 68.848132 -281.698986) (xy 68.844172 -281.649932)
			(xy 68.50507 -281.649932) (xy 68.504575 -281.674539) (xy 68.49668 -281.723116) (xy 68.481096 -281.769797)
			(xy 68.458225 -281.813374) (xy 68.42866 -281.852718) (xy 68.393167 -281.88681) (xy 68.352664 -281.914766)
			(xy 68.308202 -281.935864) (xy 68.260931 -281.949556) (xy 68.212076 -281.955488) (xy 68.162901 -281.953507)
			(xy 68.114682 -281.943663) (xy 68.068666 -281.926211) (xy 68.026045 -281.901604) (xy 67.987924 -281.870479)
			(xy 67.955289 -281.833642) (xy 67.928986 -281.792046) (xy 67.909695 -281.74677) (xy 67.897918 -281.698986)
			(xy 67.893958 -281.649932) (xy 67.55511 -281.649932) (xy 67.554615 -281.674539) (xy 67.54672 -281.723116)
			(xy 67.531136 -281.769797) (xy 67.508265 -281.813374) (xy 67.4787 -281.852718) (xy 67.443207 -281.88681)
			(xy 67.402704 -281.914766) (xy 67.358242 -281.935864) (xy 67.310971 -281.949556) (xy 67.262116 -281.955488)
			(xy 67.212941 -281.953507) (xy 67.164722 -281.943663) (xy 67.118706 -281.926211) (xy 67.076085 -281.901604)
			(xy 67.037964 -281.870479) (xy 67.005329 -281.833642) (xy 66.979026 -281.792046) (xy 66.959735 -281.74677)
			(xy 66.947958 -281.698986) (xy 66.943998 -281.649932) (xy 66.60515 -281.649932) (xy 66.604655 -281.674539)
			(xy 66.59676 -281.723116) (xy 66.581176 -281.769797) (xy 66.558305 -281.813374) (xy 66.52874 -281.852718)
			(xy 66.493247 -281.88681) (xy 66.452744 -281.914766) (xy 66.408282 -281.935864) (xy 66.361011 -281.949556)
			(xy 66.312156 -281.955488) (xy 66.262981 -281.953507) (xy 66.214762 -281.943663) (xy 66.168746 -281.926211)
			(xy 66.126125 -281.901604) (xy 66.088004 -281.870479) (xy 66.055369 -281.833642) (xy 66.029066 -281.792046)
			(xy 66.009775 -281.74677) (xy 65.997998 -281.698986) (xy 65.994038 -281.649932) (xy 65.65519 -281.649932)
			(xy 65.654695 -281.674539) (xy 65.6468 -281.723116) (xy 65.631216 -281.769797) (xy 65.608345 -281.813374)
			(xy 65.57878 -281.852718) (xy 65.543287 -281.88681) (xy 65.502784 -281.914766) (xy 65.458322 -281.935864)
			(xy 65.411051 -281.949556) (xy 65.362196 -281.955488) (xy 65.313021 -281.953507) (xy 65.264802 -281.943663)
			(xy 65.218786 -281.926211) (xy 65.176165 -281.901604) (xy 65.138044 -281.870479) (xy 65.105409 -281.833642)
			(xy 65.079106 -281.792046) (xy 65.059815 -281.74677) (xy 65.048038 -281.698986) (xy 65.044078 -281.649932)
			(xy 64.70523 -281.649932) (xy 64.704735 -281.674539) (xy 64.69684 -281.723116) (xy 64.681256 -281.769797)
			(xy 64.658385 -281.813374) (xy 64.62882 -281.852718) (xy 64.593327 -281.88681) (xy 64.552824 -281.914766)
			(xy 64.508362 -281.935864) (xy 64.461091 -281.949556) (xy 64.412236 -281.955488) (xy 64.363061 -281.953507)
			(xy 64.314842 -281.943663) (xy 64.268826 -281.926211) (xy 64.226205 -281.901604) (xy 64.188084 -281.870479)
			(xy 64.155449 -281.833642) (xy 64.129146 -281.792046) (xy 64.109855 -281.74677) (xy 64.098078 -281.698986)
			(xy 64.094118 -281.649932) (xy 63.75527 -281.649932) (xy 63.754775 -281.674539) (xy 63.74688 -281.723116)
			(xy 63.731296 -281.769797) (xy 63.708425 -281.813374) (xy 63.67886 -281.852718) (xy 63.643367 -281.88681)
			(xy 63.602864 -281.914766) (xy 63.558402 -281.935864) (xy 63.511131 -281.949556) (xy 63.462276 -281.955488)
			(xy 63.413101 -281.953507) (xy 63.364882 -281.943663) (xy 63.318866 -281.926211) (xy 63.276245 -281.901604)
			(xy 63.238124 -281.870479) (xy 63.205489 -281.833642) (xy 63.179186 -281.792046) (xy 63.159895 -281.74677)
			(xy 63.148118 -281.698986) (xy 63.144158 -281.649932) (xy 62.805056 -281.649932) (xy 62.804561 -281.674539)
			(xy 62.796666 -281.723116) (xy 62.781082 -281.769797) (xy 62.758211 -281.813374) (xy 62.728646 -281.852718)
			(xy 62.693153 -281.88681) (xy 62.65265 -281.914766) (xy 62.608188 -281.935864) (xy 62.560917 -281.949556)
			(xy 62.512062 -281.955488) (xy 62.462887 -281.953507) (xy 62.414668 -281.943663) (xy 62.368652 -281.926211)
			(xy 62.326031 -281.901604) (xy 62.28791 -281.870479) (xy 62.255275 -281.833642) (xy 62.228972 -281.792046)
			(xy 62.209681 -281.74677) (xy 62.197904 -281.698986) (xy 62.193944 -281.649932) (xy 61.855096 -281.649932)
			(xy 61.854601 -281.674539) (xy 61.846706 -281.723116) (xy 61.831122 -281.769797) (xy 61.808251 -281.813374)
			(xy 61.778686 -281.852718) (xy 61.743193 -281.88681) (xy 61.70269 -281.914766) (xy 61.658228 -281.935864)
			(xy 61.610957 -281.949556) (xy 61.562102 -281.955488) (xy 61.512927 -281.953507) (xy 61.464708 -281.943663)
			(xy 61.418692 -281.926211) (xy 61.376071 -281.901604) (xy 61.33795 -281.870479) (xy 61.305315 -281.833642)
			(xy 61.279012 -281.792046) (xy 61.259721 -281.74677) (xy 61.247944 -281.698986) (xy 61.243984 -281.649932)
			(xy 60.905136 -281.649932) (xy 60.904641 -281.674539) (xy 60.896746 -281.723116) (xy 60.881162 -281.769797)
			(xy 60.858291 -281.813374) (xy 60.828726 -281.852718) (xy 60.793233 -281.88681) (xy 60.75273 -281.914766)
			(xy 60.708268 -281.935864) (xy 60.660997 -281.949556) (xy 60.612142 -281.955488) (xy 60.562967 -281.953507)
			(xy 60.514748 -281.943663) (xy 60.468732 -281.926211) (xy 60.426111 -281.901604) (xy 60.38799 -281.870479)
			(xy 60.355355 -281.833642) (xy 60.329052 -281.792046) (xy 60.309761 -281.74677) (xy 60.297984 -281.698986)
			(xy 60.294024 -281.649932) (xy 59.955176 -281.649932) (xy 59.954681 -281.674539) (xy 59.946786 -281.723116)
			(xy 59.931202 -281.769797) (xy 59.908331 -281.813374) (xy 59.878766 -281.852718) (xy 59.843273 -281.88681)
			(xy 59.80277 -281.914766) (xy 59.758308 -281.935864) (xy 59.711037 -281.949556) (xy 59.662182 -281.955488)
			(xy 59.613007 -281.953507) (xy 59.564788 -281.943663) (xy 59.518772 -281.926211) (xy 59.476151 -281.901604)
			(xy 59.43803 -281.870479) (xy 59.405395 -281.833642) (xy 59.379092 -281.792046) (xy 59.359801 -281.74677)
			(xy 59.348024 -281.698986) (xy 59.344064 -281.649932) (xy 59.005216 -281.649932) (xy 59.004721 -281.674539)
			(xy 58.996826 -281.723116) (xy 58.981242 -281.769797) (xy 58.958371 -281.813374) (xy 58.928806 -281.852718)
			(xy 58.893313 -281.88681) (xy 58.85281 -281.914766) (xy 58.808348 -281.935864) (xy 58.761077 -281.949556)
			(xy 58.712222 -281.955488) (xy 58.663047 -281.953507) (xy 58.614828 -281.943663) (xy 58.568812 -281.926211)
			(xy 58.526191 -281.901604) (xy 58.48807 -281.870479) (xy 58.455435 -281.833642) (xy 58.429132 -281.792046)
			(xy 58.409841 -281.74677) (xy 58.398064 -281.698986) (xy 58.394104 -281.649932) (xy 58.055256 -281.649932)
			(xy 58.054761 -281.674539) (xy 58.046866 -281.723116) (xy 58.031282 -281.769797) (xy 58.008411 -281.813374)
			(xy 57.978846 -281.852718) (xy 57.943353 -281.88681) (xy 57.90285 -281.914766) (xy 57.858388 -281.935864)
			(xy 57.811117 -281.949556) (xy 57.762262 -281.955488) (xy 57.713087 -281.953507) (xy 57.664868 -281.943663)
			(xy 57.618852 -281.926211) (xy 57.576231 -281.901604) (xy 57.53811 -281.870479) (xy 57.505475 -281.833642)
			(xy 57.479172 -281.792046) (xy 57.459881 -281.74677) (xy 57.448104 -281.698986) (xy 57.444144 -281.649932)
			(xy 57.105296 -281.649932) (xy 57.104801 -281.674539) (xy 57.096906 -281.723116) (xy 57.081322 -281.769797)
			(xy 57.058451 -281.813374) (xy 57.028886 -281.852718) (xy 56.993393 -281.88681) (xy 56.95289 -281.914766)
			(xy 56.908428 -281.935864) (xy 56.861157 -281.949556) (xy 56.812302 -281.955488) (xy 56.763127 -281.953507)
			(xy 56.714908 -281.943663) (xy 56.668892 -281.926211) (xy 56.626271 -281.901604) (xy 56.58815 -281.870479)
			(xy 56.555515 -281.833642) (xy 56.529212 -281.792046) (xy 56.509921 -281.74677) (xy 56.498144 -281.698986)
			(xy 56.494184 -281.649932) (xy 56.155082 -281.649932) (xy 56.154587 -281.674539) (xy 56.146692 -281.723116)
			(xy 56.131108 -281.769797) (xy 56.108237 -281.813374) (xy 56.078672 -281.852718) (xy 56.043179 -281.88681)
			(xy 56.002676 -281.914766) (xy 55.958214 -281.935864) (xy 55.910943 -281.949556) (xy 55.862088 -281.955488)
			(xy 55.812913 -281.953507) (xy 55.764694 -281.943663) (xy 55.718678 -281.926211) (xy 55.676057 -281.901604)
			(xy 55.637936 -281.870479) (xy 55.605301 -281.833642) (xy 55.578998 -281.792046) (xy 55.559707 -281.74677)
			(xy 55.54793 -281.698986) (xy 55.54397 -281.649932) (xy 55.205104 -281.649932) (xy 55.205551 -281.658163)
			(xy 55.200187 -281.707519) (xy 55.186908 -281.755358) (xy 55.166064 -281.800418) (xy 55.138205 -281.841513)
			(xy 55.104064 -281.877558) (xy 55.064542 -281.907606) (xy 55.020679 -281.930864) (xy 54.973631 -281.946718)
			(xy 54.924638 -281.954753) (xy 54.899814 -281.95524) (xy 54.885631 -281.955061) (xy 54.857391 -281.95239)
			(xy 54.843426 -281.949906) (xy 54.83098 -281.94762) (xy 54.807358 -281.954986) (xy 54.729888 -282.032456)
			(xy 54.722522 -282.056078) (xy 54.724808 -282.068524) (xy 54.727284 -282.08249) (xy 54.729956 -282.110729)
			(xy 54.730142 -282.124912) (xy 54.72962 -282.150167) (xy 54.721307 -282.199989) (xy 54.704906 -282.247763)
			(xy 54.680865 -282.292186) (xy 54.649841 -282.332046) (xy 54.612679 -282.366256) (xy 54.570393 -282.393882)
			(xy 54.524137 -282.414172) (xy 54.475172 -282.426572) (xy 54.424834 -282.430743) (xy 54.374496 -282.426572)
			(xy 54.325531 -282.414172) (xy 54.279275 -282.393882) (xy 54.236989 -282.366256) (xy 54.199827 -282.332046)
			(xy 54.168803 -282.292186) (xy 54.144762 -282.247763) (xy 54.128361 -282.199989) (xy 54.120048 -282.150167)
			(xy 54.119526 -282.124912) (xy 54.119704 -282.110729) (xy 54.122375 -282.082489) (xy 54.12486 -282.068524)
			(xy 54.127146 -282.056078) (xy 54.11978 -282.032456) (xy 54.04231 -281.954986) (xy 54.018688 -281.94762)
			(xy 54.006242 -281.949906) (xy 53.992277 -281.952387) (xy 53.964037 -281.955056) (xy 53.949854 -281.95524)
			(xy 53.925037 -281.954673) (xy 53.876058 -281.946635) (xy 53.829025 -281.93078) (xy 53.785177 -281.907525)
			(xy 53.745668 -281.877482) (xy 53.71154 -281.841444) (xy 53.683692 -281.800358) (xy 53.662857 -281.755309)
			(xy 53.649586 -281.707483) (xy 53.644226 -281.658139) (xy 53.305037 -281.658139) (xy 53.304707 -281.674539)
			(xy 53.296812 -281.723116) (xy 53.281228 -281.769797) (xy 53.258357 -281.813374) (xy 53.228792 -281.852718)
			(xy 53.193299 -281.88681) (xy 53.152796 -281.914766) (xy 53.108334 -281.935864) (xy 53.061063 -281.949556)
			(xy 53.012208 -281.955488) (xy 52.963033 -281.953507) (xy 52.914814 -281.943663) (xy 52.868798 -281.926211)
			(xy 52.826177 -281.901604) (xy 52.788056 -281.870479) (xy 52.755421 -281.833642) (xy 52.729118 -281.792046)
			(xy 52.709827 -281.74677) (xy 52.69805 -281.698986) (xy 52.69409 -281.649932) (xy 52.355242 -281.649932)
			(xy 52.354747 -281.674539) (xy 52.346852 -281.723116) (xy 52.331268 -281.769797) (xy 52.308397 -281.813374)
			(xy 52.278832 -281.852718) (xy 52.243339 -281.88681) (xy 52.202836 -281.914766) (xy 52.158374 -281.935864)
			(xy 52.111103 -281.949556) (xy 52.062248 -281.955488) (xy 52.013073 -281.953507) (xy 51.964854 -281.943663)
			(xy 51.918838 -281.926211) (xy 51.876217 -281.901604) (xy 51.838096 -281.870479) (xy 51.805461 -281.833642)
			(xy 51.779158 -281.792046) (xy 51.759867 -281.74677) (xy 51.74809 -281.698986) (xy 51.74413 -281.649932)
			(xy 51.405282 -281.649932) (xy 51.404787 -281.674539) (xy 51.396892 -281.723116) (xy 51.381308 -281.769797)
			(xy 51.358437 -281.813374) (xy 51.328872 -281.852718) (xy 51.293379 -281.88681) (xy 51.252876 -281.914766)
			(xy 51.208414 -281.935864) (xy 51.161143 -281.949556) (xy 51.112288 -281.955488) (xy 51.063113 -281.953507)
			(xy 51.014894 -281.943663) (xy 50.968878 -281.926211) (xy 50.926257 -281.901604) (xy 50.888136 -281.870479)
			(xy 50.855501 -281.833642) (xy 50.829198 -281.792046) (xy 50.809907 -281.74677) (xy 50.79813 -281.698986)
			(xy 50.79417 -281.649932) (xy 50.455068 -281.649932) (xy 50.454573 -281.674539) (xy 50.446678 -281.723116)
			(xy 50.431094 -281.769797) (xy 50.408223 -281.813374) (xy 50.378658 -281.852718) (xy 50.343165 -281.88681)
			(xy 50.302662 -281.914766) (xy 50.2582 -281.935864) (xy 50.210929 -281.949556) (xy 50.162074 -281.955488)
			(xy 50.112899 -281.953507) (xy 50.06468 -281.943663) (xy 50.018664 -281.926211) (xy 49.976043 -281.901604)
			(xy 49.937922 -281.870479) (xy 49.905287 -281.833642) (xy 49.878984 -281.792046) (xy 49.859693 -281.74677)
			(xy 49.847916 -281.698986) (xy 49.843956 -281.649932) (xy 49.505108 -281.649932) (xy 49.504613 -281.674539)
			(xy 49.496718 -281.723116) (xy 49.481134 -281.769797) (xy 49.458263 -281.813374) (xy 49.428698 -281.852718)
			(xy 49.393205 -281.88681) (xy 49.352702 -281.914766) (xy 49.30824 -281.935864) (xy 49.260969 -281.949556)
			(xy 49.212114 -281.955488) (xy 49.162939 -281.953507) (xy 49.11472 -281.943663) (xy 49.068704 -281.926211)
			(xy 49.026083 -281.901604) (xy 48.987962 -281.870479) (xy 48.955327 -281.833642) (xy 48.929024 -281.792046)
			(xy 48.909733 -281.74677) (xy 48.897956 -281.698986) (xy 48.893996 -281.649932) (xy 48.555148 -281.649932)
			(xy 48.554653 -281.674539) (xy 48.546758 -281.723116) (xy 48.531174 -281.769797) (xy 48.508303 -281.813374)
			(xy 48.478738 -281.852718) (xy 48.443245 -281.88681) (xy 48.402742 -281.914766) (xy 48.35828 -281.935864)
			(xy 48.311009 -281.949556) (xy 48.262154 -281.955488) (xy 48.212979 -281.953507) (xy 48.16476 -281.943663)
			(xy 48.118744 -281.926211) (xy 48.076123 -281.901604) (xy 48.038002 -281.870479) (xy 48.005367 -281.833642)
			(xy 47.979064 -281.792046) (xy 47.959773 -281.74677) (xy 47.947996 -281.698986) (xy 47.944036 -281.649932)
			(xy 47.605188 -281.649932) (xy 47.604693 -281.674539) (xy 47.596798 -281.723116) (xy 47.581214 -281.769797)
			(xy 47.558343 -281.813374) (xy 47.528778 -281.852718) (xy 47.493285 -281.88681) (xy 47.452782 -281.914766)
			(xy 47.40832 -281.935864) (xy 47.361049 -281.949556) (xy 47.312194 -281.955488) (xy 47.263019 -281.953507)
			(xy 47.2148 -281.943663) (xy 47.168784 -281.926211) (xy 47.126163 -281.901604) (xy 47.088042 -281.870479)
			(xy 47.055407 -281.833642) (xy 47.029104 -281.792046) (xy 47.009813 -281.74677) (xy 46.998036 -281.698986)
			(xy 46.994076 -281.649932) (xy 46.655228 -281.649932) (xy 46.654733 -281.674539) (xy 46.646838 -281.723116)
			(xy 46.631254 -281.769797) (xy 46.608383 -281.813374) (xy 46.578818 -281.852718) (xy 46.543325 -281.88681)
			(xy 46.502822 -281.914766) (xy 46.45836 -281.935864) (xy 46.411089 -281.949556) (xy 46.362234 -281.955488)
			(xy 46.313059 -281.953507) (xy 46.26484 -281.943663) (xy 46.218824 -281.926211) (xy 46.176203 -281.901604)
			(xy 46.138082 -281.870479) (xy 46.105447 -281.833642) (xy 46.079144 -281.792046) (xy 46.059853 -281.74677)
			(xy 46.048076 -281.698986) (xy 46.044116 -281.649932) (xy 45.705268 -281.649932) (xy 45.704773 -281.674539)
			(xy 45.696878 -281.723116) (xy 45.681294 -281.769797) (xy 45.658423 -281.813374) (xy 45.628858 -281.852718)
			(xy 45.593365 -281.88681) (xy 45.552862 -281.914766) (xy 45.5084 -281.935864) (xy 45.461129 -281.949556)
			(xy 45.412274 -281.955488) (xy 45.363099 -281.953507) (xy 45.31488 -281.943663) (xy 45.268864 -281.926211)
			(xy 45.226243 -281.901604) (xy 45.188122 -281.870479) (xy 45.155487 -281.833642) (xy 45.129184 -281.792046)
			(xy 45.109893 -281.74677) (xy 45.098116 -281.698986) (xy 45.094156 -281.649932) (xy 44.755006 -281.649932)
			(xy 44.755452 -281.658141) (xy 44.750091 -281.707497) (xy 44.736816 -281.755336) (xy 44.715976 -281.800397)
			(xy 44.688121 -281.841492) (xy 44.653984 -281.87754) (xy 44.614465 -281.907591) (xy 44.570606 -281.930852)
			(xy 44.52356 -281.946711) (xy 44.474569 -281.95475) (xy 44.449746 -281.95524) (xy 44.435563 -281.955056)
			(xy 44.407323 -281.952389) (xy 44.393358 -281.949906) (xy 44.379401 -281.947672) (xy 44.35126 -281.950261)
			(xy 44.324907 -281.960462) (xy 44.302357 -281.977494) (xy 44.285336 -282.000053) (xy 44.275149 -282.026412)
			(xy 44.272574 -282.054554) (xy 44.27474 -282.068524) (xy 44.277215 -282.08249) (xy 44.279888 -282.11073)
			(xy 44.280074 -282.124912) (xy 44.279609 -282.149731) (xy 44.271577 -282.198715) (xy 44.255726 -282.245754)
			(xy 44.232474 -282.28961) (xy 44.202434 -282.329126) (xy 44.166396 -282.363261) (xy 44.125311 -282.391117)
			(xy 44.08026 -282.41196) (xy 44.032432 -282.42524) (xy 43.983084 -282.430607) (xy 43.933519 -282.42792)
			(xy 43.885041 -282.41725) (xy 43.838928 -282.398878) (xy 43.796395 -282.373288) (xy 43.758561 -282.341154)
			(xy 43.726425 -282.303323) (xy 43.700832 -282.260792) (xy 43.682456 -282.21468) (xy 43.671783 -282.166203)
			(xy 43.669093 -282.116638) (xy 43.329948 -282.116638) (xy 43.330114 -282.124912) (xy 43.329619 -282.149519)
			(xy 43.321724 -282.198096) (xy 43.30614 -282.244777) (xy 43.283269 -282.288354) (xy 43.253704 -282.327698)
			(xy 43.218211 -282.36179) (xy 43.177708 -282.389746) (xy 43.133246 -282.410844) (xy 43.085975 -282.424536)
			(xy 43.03712 -282.430468) (xy 42.987945 -282.428487) (xy 42.939726 -282.418643) (xy 42.89371 -282.401191)
			(xy 42.851089 -282.376584) (xy 42.812968 -282.345459) (xy 42.780333 -282.308622) (xy 42.75403 -282.267026)
			(xy 42.734739 -282.22175) (xy 42.722962 -282.173966) (xy 42.719002 -282.124912) (xy 42.380154 -282.124912)
			(xy 42.379659 -282.149519) (xy 42.371764 -282.198096) (xy 42.35618 -282.244777) (xy 42.333309 -282.288354)
			(xy 42.303744 -282.327698) (xy 42.268251 -282.36179) (xy 42.227748 -282.389746) (xy 42.183286 -282.410844)
			(xy 42.136015 -282.424536) (xy 42.08716 -282.430468) (xy 42.037985 -282.428487) (xy 41.989766 -282.418643)
			(xy 41.94375 -282.401191) (xy 41.901129 -282.376584) (xy 41.863008 -282.345459) (xy 41.830373 -282.308622)
			(xy 41.80407 -282.267026) (xy 41.784779 -282.22175) (xy 41.773002 -282.173966) (xy 41.769042 -282.124912)
			(xy 41.430747 -282.124912) (xy 41.426576 -282.175242) (xy 41.414175 -282.224211) (xy 41.393883 -282.270471)
			(xy 41.366253 -282.31276) (xy 41.33204 -282.349925) (xy 41.292176 -282.380951) (xy 41.247748 -282.404992)
			(xy 41.19997 -282.421392) (xy 41.150143 -282.429704) (xy 41.124886 -282.43022) (xy 41.101259 -282.429773)
			(xy 41.054568 -282.422494) (xy 41.031922 -282.415742) (xy 41.020238 -282.411932) (xy 40.996362 -282.415742)
			(xy 40.920162 -282.471368) (xy 40.910819 -282.47899) (xy 40.899951 -282.500474) (xy 40.899334 -282.512516)
			(xy 40.899334 -282.687268) (xy 40.900014 -282.699287) (xy 40.910894 -282.720728) (xy 40.920162 -282.728416)
			(xy 40.996362 -282.784042) (xy 41.020238 -282.787852) (xy 41.031922 -282.784042) (xy 41.054563 -282.777268)
			(xy 41.101257 -282.769997) (xy 41.124886 -282.769564) (xy 41.150147 -282.770056) (xy 41.19998 -282.778369)
			(xy 41.247764 -282.794772) (xy 41.292197 -282.818816) (xy 41.332067 -282.849846) (xy 41.366285 -282.887015)
			(xy 41.393918 -282.92931) (xy 41.414213 -282.975576) (xy 41.426616 -283.024551) (xy 41.430786 -283.074872)
			(xy 41.769042 -283.074872) (xy 41.773002 -283.025818) (xy 41.784779 -282.978034) (xy 41.80407 -282.932758)
			(xy 41.830373 -282.891162) (xy 41.863008 -282.854325) (xy 41.901129 -282.8232) (xy 41.94375 -282.798593)
			(xy 41.989766 -282.781141) (xy 42.037985 -282.771297) (xy 42.08716 -282.769316) (xy 42.136015 -282.775248)
			(xy 42.183286 -282.78894) (xy 42.227748 -282.810038) (xy 42.268251 -282.837994) (xy 42.303744 -282.872086)
			(xy 42.333309 -282.91143) (xy 42.35618 -282.955007) (xy 42.371764 -283.001688) (xy 42.379659 -283.050265)
			(xy 42.379988 -283.06664) (xy 44.619253 -283.06664) (xy 44.624617 -283.017284) (xy 44.637895 -282.969446)
			(xy 44.658738 -282.924387) (xy 44.686596 -282.883293) (xy 44.720735 -282.847248) (xy 44.760256 -282.8172)
			(xy 44.804118 -282.793942) (xy 44.851165 -282.778087) (xy 44.900157 -282.770052) (xy 44.92498 -282.769564)
			(xy 44.939163 -282.769744) (xy 44.967403 -282.772414) (xy 44.981368 -282.774898) (xy 44.993814 -282.777184)
			(xy 45.017436 -282.769818) (xy 45.094906 -282.692348) (xy 45.102272 -282.668726) (xy 45.099986 -282.65628)
			(xy 45.097511 -282.642314) (xy 45.094838 -282.614074) (xy 45.094652 -282.599892) (xy 45.095174 -282.574637)
			(xy 45.103487 -282.524815) (xy 45.119888 -282.477041) (xy 45.143929 -282.432618) (xy 45.174953 -282.392758)
			(xy 45.212115 -282.358548) (xy 45.254401 -282.330922) (xy 45.300657 -282.310632) (xy 45.349622 -282.298232)
			(xy 45.39996 -282.294061) (xy 45.450298 -282.298232) (xy 45.499263 -282.310632) (xy 45.545519 -282.330922)
			(xy 45.587805 -282.358548) (xy 45.624967 -282.392758) (xy 45.655991 -282.432618) (xy 45.680032 -282.477041)
			(xy 45.696433 -282.524815) (xy 45.704746 -282.574637) (xy 45.705268 -282.599892) (xy 45.705091 -282.614075)
			(xy 45.702419 -282.642315) (xy 45.699934 -282.65628) (xy 45.697648 -282.668726) (xy 45.705014 -282.692348)
			(xy 45.782484 -282.769818) (xy 45.806106 -282.777184) (xy 45.818552 -282.774898) (xy 45.832517 -282.772418)
			(xy 45.860757 -282.769749) (xy 45.87494 -282.769564) (xy 45.889123 -282.769736) (xy 45.917363 -282.772411)
			(xy 45.931328 -282.774898) (xy 45.943774 -282.777184) (xy 45.967396 -282.769818) (xy 46.044866 -282.692348)
			(xy 46.052232 -282.668726) (xy 46.049946 -282.65628) (xy 46.047471 -282.642314) (xy 46.044798 -282.614074)
			(xy 46.044612 -282.599892) (xy 46.045134 -282.574637) (xy 46.053447 -282.524815) (xy 46.069848 -282.477041)
			(xy 46.093889 -282.432618) (xy 46.124913 -282.392758) (xy 46.162075 -282.358548) (xy 46.204361 -282.330922)
			(xy 46.250617 -282.310632) (xy 46.299582 -282.298232) (xy 46.34992 -282.294061) (xy 46.400258 -282.298232)
			(xy 46.449223 -282.310632) (xy 46.495479 -282.330922) (xy 46.537765 -282.358548) (xy 46.574927 -282.392758)
			(xy 46.605951 -282.432618) (xy 46.629992 -282.477041) (xy 46.646393 -282.524815) (xy 46.654706 -282.574637)
			(xy 46.655228 -282.599892) (xy 73.593972 -282.599892) (xy 73.597932 -282.550838) (xy 73.609709 -282.503054)
			(xy 73.629 -282.457778) (xy 73.655303 -282.416182) (xy 73.687938 -282.379345) (xy 73.726059 -282.34822)
			(xy 73.76868 -282.323613) (xy 73.814696 -282.306161) (xy 73.862915 -282.296317) (xy 73.91209 -282.294336)
			(xy 73.960945 -282.300268) (xy 74.008216 -282.31396) (xy 74.052678 -282.335058) (xy 74.093181 -282.363014)
			(xy 74.128674 -282.397106) (xy 74.158239 -282.43645) (xy 74.18111 -282.480027) (xy 74.196694 -282.526708)
			(xy 74.204589 -282.575285) (xy 74.205084 -282.599892) (xy 74.543932 -282.599892) (xy 74.547892 -282.550838)
			(xy 74.559669 -282.503054) (xy 74.57896 -282.457778) (xy 74.605263 -282.416182) (xy 74.637898 -282.379345)
			(xy 74.676019 -282.34822) (xy 74.71864 -282.323613) (xy 74.764656 -282.306161) (xy 74.812875 -282.296317)
			(xy 74.86205 -282.294336) (xy 74.910905 -282.300268) (xy 74.958176 -282.31396) (xy 75.002638 -282.335058)
			(xy 75.043141 -282.363014) (xy 75.078634 -282.397106) (xy 75.108199 -282.43645) (xy 75.13107 -282.480027)
			(xy 75.146654 -282.526708) (xy 75.154549 -282.575285) (xy 75.155044 -282.599892) (xy 75.494146 -282.599892)
			(xy 75.498106 -282.550838) (xy 75.509883 -282.503054) (xy 75.529174 -282.457778) (xy 75.555477 -282.416182)
			(xy 75.588112 -282.379345) (xy 75.626233 -282.34822) (xy 75.668854 -282.323613) (xy 75.71487 -282.306161)
			(xy 75.763089 -282.296317) (xy 75.812264 -282.294336) (xy 75.861119 -282.300268) (xy 75.90839 -282.31396)
			(xy 75.952852 -282.335058) (xy 75.993355 -282.363014) (xy 76.028848 -282.397106) (xy 76.058413 -282.43645)
			(xy 76.081284 -282.480027) (xy 76.096868 -282.526708) (xy 76.104763 -282.575285) (xy 76.105258 -282.599892)
			(xy 76.104763 -282.624499) (xy 76.104584 -282.6256) (xy 76.423262 -282.6256) (xy 76.423262 -282.574184)
			(xy 76.431305 -282.523402) (xy 76.447193 -282.474503) (xy 76.470536 -282.428691) (xy 76.500757 -282.387095)
			(xy 76.537113 -282.350739) (xy 76.578709 -282.320518) (xy 76.624521 -282.297175) (xy 76.67342 -282.281287)
			(xy 76.724202 -282.273244) (xy 76.775618 -282.273244) (xy 76.8264 -282.281287) (xy 76.875299 -282.297175)
			(xy 76.921111 -282.320518) (xy 76.962707 -282.350739) (xy 76.999063 -282.387095) (xy 77.029284 -282.428691)
			(xy 77.052627 -282.474503) (xy 77.068515 -282.523402) (xy 77.076558 -282.574184) (xy 77.077062 -282.599892)
			(xy 77.076558 -282.6256) (xy 77.373222 -282.6256) (xy 77.373222 -282.574184) (xy 77.381265 -282.523402)
			(xy 77.397153 -282.474503) (xy 77.420496 -282.428691) (xy 77.450717 -282.387095) (xy 77.487073 -282.350739)
			(xy 77.528669 -282.320518) (xy 77.574481 -282.297175) (xy 77.62338 -282.281287) (xy 77.674162 -282.273244)
			(xy 77.725578 -282.273244) (xy 77.77636 -282.281287) (xy 77.825259 -282.297175) (xy 77.871071 -282.320518)
			(xy 77.912667 -282.350739) (xy 77.949023 -282.387095) (xy 77.979244 -282.428691) (xy 78.002587 -282.474503)
			(xy 78.018475 -282.523402) (xy 78.026518 -282.574184) (xy 78.027022 -282.599892) (xy 78.344026 -282.599892)
			(xy 78.347986 -282.550838) (xy 78.359763 -282.503054) (xy 78.379054 -282.457778) (xy 78.405357 -282.416182)
			(xy 78.437992 -282.379345) (xy 78.476113 -282.34822) (xy 78.518734 -282.323613) (xy 78.56475 -282.306161)
			(xy 78.612969 -282.296317) (xy 78.662144 -282.294336) (xy 78.710999 -282.300268) (xy 78.75827 -282.31396)
			(xy 78.802732 -282.335058) (xy 78.843235 -282.363014) (xy 78.878728 -282.397106) (xy 78.908293 -282.43645)
			(xy 78.931164 -282.480027) (xy 78.946748 -282.526708) (xy 78.954643 -282.575285) (xy 78.955138 -282.599892)
			(xy 78.954643 -282.624499) (xy 78.954464 -282.6256) (xy 79.273142 -282.6256) (xy 79.273142 -282.574184)
			(xy 79.281185 -282.523402) (xy 79.297073 -282.474503) (xy 79.320416 -282.428691) (xy 79.350637 -282.387095)
			(xy 79.386993 -282.350739) (xy 79.428589 -282.320518) (xy 79.474401 -282.297175) (xy 79.5233 -282.281287)
			(xy 79.574082 -282.273244) (xy 79.625498 -282.273244) (xy 79.67628 -282.281287) (xy 79.725179 -282.297175)
			(xy 79.770991 -282.320518) (xy 79.812587 -282.350739) (xy 79.848943 -282.387095) (xy 79.879164 -282.428691)
			(xy 79.902507 -282.474503) (xy 79.918395 -282.523402) (xy 79.926438 -282.574184) (xy 79.926942 -282.599892)
			(xy 79.926438 -282.6256) (xy 80.223102 -282.6256) (xy 80.223102 -282.574184) (xy 80.231145 -282.523402)
			(xy 80.247033 -282.474503) (xy 80.270376 -282.428691) (xy 80.300597 -282.387095) (xy 80.336953 -282.350739)
			(xy 80.378549 -282.320518) (xy 80.424361 -282.297175) (xy 80.47326 -282.281287) (xy 80.524042 -282.273244)
			(xy 80.575458 -282.273244) (xy 80.62624 -282.281287) (xy 80.675139 -282.297175) (xy 80.720951 -282.320518)
			(xy 80.762547 -282.350739) (xy 80.798903 -282.387095) (xy 80.829124 -282.428691) (xy 80.852467 -282.474503)
			(xy 80.868355 -282.523402) (xy 80.876398 -282.574184) (xy 80.876902 -282.599892) (xy 81.19416 -282.599892)
			(xy 81.19812 -282.550838) (xy 81.209897 -282.503054) (xy 81.229188 -282.457778) (xy 81.255491 -282.416182)
			(xy 81.288126 -282.379345) (xy 81.326247 -282.34822) (xy 81.368868 -282.323613) (xy 81.414884 -282.306161)
			(xy 81.463103 -282.296317) (xy 81.512278 -282.294336) (xy 81.561133 -282.300268) (xy 81.608404 -282.31396)
			(xy 81.652866 -282.335058) (xy 81.693369 -282.363014) (xy 81.728862 -282.397106) (xy 81.758427 -282.43645)
			(xy 81.781298 -282.480027) (xy 81.796882 -282.526708) (xy 81.804777 -282.575285) (xy 81.805272 -282.599892)
			(xy 82.14412 -282.599892) (xy 82.14808 -282.550838) (xy 82.159857 -282.503054) (xy 82.179148 -282.457778)
			(xy 82.205451 -282.416182) (xy 82.238086 -282.379345) (xy 82.276207 -282.34822) (xy 82.318828 -282.323613)
			(xy 82.364844 -282.306161) (xy 82.413063 -282.296317) (xy 82.462238 -282.294336) (xy 82.511093 -282.300268)
			(xy 82.558364 -282.31396) (xy 82.602826 -282.335058) (xy 82.643329 -282.363014) (xy 82.678822 -282.397106)
			(xy 82.708387 -282.43645) (xy 82.731258 -282.480027) (xy 82.746842 -282.526708) (xy 82.754737 -282.575285)
			(xy 82.755232 -282.599892) (xy 82.754737 -282.624499) (xy 82.746842 -282.673076) (xy 82.731258 -282.719757)
			(xy 82.708387 -282.763334) (xy 82.678822 -282.802678) (xy 82.643329 -282.83677) (xy 82.602826 -282.864726)
			(xy 82.558364 -282.885824) (xy 82.511093 -282.899516) (xy 82.462238 -282.905448) (xy 82.413063 -282.903467)
			(xy 82.364844 -282.893623) (xy 82.318828 -282.876171) (xy 82.276207 -282.851564) (xy 82.238086 -282.820439)
			(xy 82.205451 -282.783602) (xy 82.179148 -282.742006) (xy 82.159857 -282.69673) (xy 82.14808 -282.648946)
			(xy 82.14412 -282.599892) (xy 81.805272 -282.599892) (xy 81.804777 -282.624499) (xy 81.796882 -282.673076)
			(xy 81.781298 -282.719757) (xy 81.758427 -282.763334) (xy 81.728862 -282.802678) (xy 81.693369 -282.83677)
			(xy 81.652866 -282.864726) (xy 81.608404 -282.885824) (xy 81.561133 -282.899516) (xy 81.512278 -282.905448)
			(xy 81.463103 -282.903467) (xy 81.414884 -282.893623) (xy 81.368868 -282.876171) (xy 81.326247 -282.851564)
			(xy 81.288126 -282.820439) (xy 81.255491 -282.783602) (xy 81.229188 -282.742006) (xy 81.209897 -282.69673)
			(xy 81.19812 -282.648946) (xy 81.19416 -282.599892) (xy 80.876902 -282.599892) (xy 80.876398 -282.6256)
			(xy 80.868355 -282.676382) (xy 80.852467 -282.725281) (xy 80.829124 -282.771093) (xy 80.798903 -282.812689)
			(xy 80.762547 -282.849045) (xy 80.720951 -282.879266) (xy 80.675139 -282.902609) (xy 80.62624 -282.918497)
			(xy 80.575458 -282.92654) (xy 80.524042 -282.92654) (xy 80.47326 -282.918497) (xy 80.424361 -282.902609)
			(xy 80.378549 -282.879266) (xy 80.336953 -282.849045) (xy 80.300597 -282.812689) (xy 80.270376 -282.771093)
			(xy 80.247033 -282.725281) (xy 80.231145 -282.676382) (xy 80.223102 -282.6256) (xy 79.926438 -282.6256)
			(xy 79.918395 -282.676382) (xy 79.902507 -282.725281) (xy 79.879164 -282.771093) (xy 79.848943 -282.812689)
			(xy 79.812587 -282.849045) (xy 79.770991 -282.879266) (xy 79.725179 -282.902609) (xy 79.67628 -282.918497)
			(xy 79.625498 -282.92654) (xy 79.574082 -282.92654) (xy 79.5233 -282.918497) (xy 79.474401 -282.902609)
			(xy 79.428589 -282.879266) (xy 79.386993 -282.849045) (xy 79.350637 -282.812689) (xy 79.320416 -282.771093)
			(xy 79.297073 -282.725281) (xy 79.281185 -282.676382) (xy 79.273142 -282.6256) (xy 78.954464 -282.6256)
			(xy 78.946748 -282.673076) (xy 78.931164 -282.719757) (xy 78.908293 -282.763334) (xy 78.878728 -282.802678)
			(xy 78.843235 -282.83677) (xy 78.802732 -282.864726) (xy 78.75827 -282.885824) (xy 78.710999 -282.899516)
			(xy 78.662144 -282.905448) (xy 78.612969 -282.903467) (xy 78.56475 -282.893623) (xy 78.518734 -282.876171)
			(xy 78.476113 -282.851564) (xy 78.437992 -282.820439) (xy 78.405357 -282.783602) (xy 78.379054 -282.742006)
			(xy 78.359763 -282.69673) (xy 78.347986 -282.648946) (xy 78.344026 -282.599892) (xy 78.027022 -282.599892)
			(xy 78.026518 -282.6256) (xy 78.018475 -282.676382) (xy 78.002587 -282.725281) (xy 77.979244 -282.771093)
			(xy 77.949023 -282.812689) (xy 77.912667 -282.849045) (xy 77.871071 -282.879266) (xy 77.825259 -282.902609)
			(xy 77.77636 -282.918497) (xy 77.725578 -282.92654) (xy 77.674162 -282.92654) (xy 77.62338 -282.918497)
			(xy 77.574481 -282.902609) (xy 77.528669 -282.879266) (xy 77.487073 -282.849045) (xy 77.450717 -282.812689)
			(xy 77.420496 -282.771093) (xy 77.397153 -282.725281) (xy 77.381265 -282.676382) (xy 77.373222 -282.6256)
			(xy 77.076558 -282.6256) (xy 77.068515 -282.676382) (xy 77.052627 -282.725281) (xy 77.029284 -282.771093)
			(xy 76.999063 -282.812689) (xy 76.962707 -282.849045) (xy 76.921111 -282.879266) (xy 76.875299 -282.902609)
			(xy 76.8264 -282.918497) (xy 76.775618 -282.92654) (xy 76.724202 -282.92654) (xy 76.67342 -282.918497)
			(xy 76.624521 -282.902609) (xy 76.578709 -282.879266) (xy 76.537113 -282.849045) (xy 76.500757 -282.812689)
			(xy 76.470536 -282.771093) (xy 76.447193 -282.725281) (xy 76.431305 -282.676382) (xy 76.423262 -282.6256)
			(xy 76.104584 -282.6256) (xy 76.096868 -282.673076) (xy 76.081284 -282.719757) (xy 76.058413 -282.763334)
			(xy 76.028848 -282.802678) (xy 75.993355 -282.83677) (xy 75.952852 -282.864726) (xy 75.90839 -282.885824)
			(xy 75.861119 -282.899516) (xy 75.812264 -282.905448) (xy 75.763089 -282.903467) (xy 75.71487 -282.893623)
			(xy 75.668854 -282.876171) (xy 75.626233 -282.851564) (xy 75.588112 -282.820439) (xy 75.555477 -282.783602)
			(xy 75.529174 -282.742006) (xy 75.509883 -282.69673) (xy 75.498106 -282.648946) (xy 75.494146 -282.599892)
			(xy 75.155044 -282.599892) (xy 75.154549 -282.624499) (xy 75.146654 -282.673076) (xy 75.13107 -282.719757)
			(xy 75.108199 -282.763334) (xy 75.078634 -282.802678) (xy 75.043141 -282.83677) (xy 75.002638 -282.864726)
			(xy 74.958176 -282.885824) (xy 74.910905 -282.899516) (xy 74.86205 -282.905448) (xy 74.812875 -282.903467)
			(xy 74.764656 -282.893623) (xy 74.71864 -282.876171) (xy 74.676019 -282.851564) (xy 74.637898 -282.820439)
			(xy 74.605263 -282.783602) (xy 74.57896 -282.742006) (xy 74.559669 -282.69673) (xy 74.547892 -282.648946)
			(xy 74.543932 -282.599892) (xy 74.205084 -282.599892) (xy 74.204589 -282.624499) (xy 74.196694 -282.673076)
			(xy 74.18111 -282.719757) (xy 74.158239 -282.763334) (xy 74.128674 -282.802678) (xy 74.093181 -282.83677)
			(xy 74.052678 -282.864726) (xy 74.008216 -282.885824) (xy 73.960945 -282.899516) (xy 73.91209 -282.905448)
			(xy 73.862915 -282.903467) (xy 73.814696 -282.893623) (xy 73.76868 -282.876171) (xy 73.726059 -282.851564)
			(xy 73.687938 -282.820439) (xy 73.655303 -282.783602) (xy 73.629 -282.742006) (xy 73.609709 -282.69673)
			(xy 73.597932 -282.648946) (xy 73.593972 -282.599892) (xy 46.655228 -282.599892) (xy 46.65505 -282.614075)
			(xy 46.652379 -282.642315) (xy 46.649894 -282.65628) (xy 46.647608 -282.668726) (xy 46.654974 -282.692348)
			(xy 46.732444 -282.769818) (xy 46.756066 -282.777184) (xy 46.768512 -282.774898) (xy 46.782478 -282.772424)
			(xy 46.810718 -282.769751) (xy 46.8249 -282.769564) (xy 46.849721 -282.770078) (xy 46.89871 -282.778109)
			(xy 46.945754 -282.793961) (xy 46.989614 -282.817214) (xy 47.029133 -282.847257) (xy 47.063272 -282.883298)
			(xy 47.09113 -282.924387) (xy 47.111974 -282.969442) (xy 47.125253 -283.017276) (xy 47.130619 -283.066627)
			(xy 47.130172 -283.074872) (xy 47.469056 -283.074872) (xy 47.473016 -283.025818) (xy 47.484793 -282.978034)
			(xy 47.504084 -282.932758) (xy 47.530387 -282.891162) (xy 47.563022 -282.854325) (xy 47.601143 -282.8232)
			(xy 47.643764 -282.798593) (xy 47.68978 -282.781141) (xy 47.737999 -282.771297) (xy 47.787174 -282.769316)
			(xy 47.836029 -282.775248) (xy 47.8833 -282.78894) (xy 47.927762 -282.810038) (xy 47.968265 -282.837994)
			(xy 48.003758 -282.872086) (xy 48.033323 -282.91143) (xy 48.056194 -282.955007) (xy 48.071778 -283.001688)
			(xy 48.079673 -283.050265) (xy 48.080168 -283.074872) (xy 48.419016 -283.074872) (xy 48.422976 -283.025818)
			(xy 48.434753 -282.978034) (xy 48.454044 -282.932758) (xy 48.480347 -282.891162) (xy 48.512982 -282.854325)
			(xy 48.551103 -282.8232) (xy 48.593724 -282.798593) (xy 48.63974 -282.781141) (xy 48.687959 -282.771297)
			(xy 48.737134 -282.769316) (xy 48.785989 -282.775248) (xy 48.83326 -282.78894) (xy 48.877722 -282.810038)
			(xy 48.918225 -282.837994) (xy 48.953718 -282.872086) (xy 48.983283 -282.91143) (xy 49.006154 -282.955007)
			(xy 49.021738 -283.001688) (xy 49.029633 -283.050265) (xy 49.030128 -283.074872) (xy 49.368976 -283.074872)
			(xy 49.372936 -283.025818) (xy 49.384713 -282.978034) (xy 49.404004 -282.932758) (xy 49.430307 -282.891162)
			(xy 49.462942 -282.854325) (xy 49.501063 -282.8232) (xy 49.543684 -282.798593) (xy 49.5897 -282.781141)
			(xy 49.637919 -282.771297) (xy 49.687094 -282.769316) (xy 49.735949 -282.775248) (xy 49.78322 -282.78894)
			(xy 49.827682 -282.810038) (xy 49.868185 -282.837994) (xy 49.903678 -282.872086) (xy 49.933243 -282.91143)
			(xy 49.956114 -282.955007) (xy 49.971698 -283.001688) (xy 49.979593 -283.050265) (xy 49.980088 -283.074872)
			(xy 50.31919 -283.074872) (xy 50.32315 -283.025818) (xy 50.334927 -282.978034) (xy 50.354218 -282.932758)
			(xy 50.380521 -282.891162) (xy 50.413156 -282.854325) (xy 50.451277 -282.8232) (xy 50.493898 -282.798593)
			(xy 50.539914 -282.781141) (xy 50.588133 -282.771297) (xy 50.637308 -282.769316) (xy 50.686163 -282.775248)
			(xy 50.733434 -282.78894) (xy 50.777896 -282.810038) (xy 50.818399 -282.837994) (xy 50.853892 -282.872086)
			(xy 50.883457 -282.91143) (xy 50.906328 -282.955007) (xy 50.921912 -283.001688) (xy 50.929807 -283.050265)
			(xy 50.930302 -283.074872) (xy 51.26915 -283.074872) (xy 51.27311 -283.025818) (xy 51.284887 -282.978034)
			(xy 51.304178 -282.932758) (xy 51.330481 -282.891162) (xy 51.363116 -282.854325) (xy 51.401237 -282.8232)
			(xy 51.443858 -282.798593) (xy 51.489874 -282.781141) (xy 51.538093 -282.771297) (xy 51.587268 -282.769316)
			(xy 51.636123 -282.775248) (xy 51.683394 -282.78894) (xy 51.727856 -282.810038) (xy 51.768359 -282.837994)
			(xy 51.803852 -282.872086) (xy 51.833417 -282.91143) (xy 51.856288 -282.955007) (xy 51.871872 -283.001688)
			(xy 51.879767 -283.050265) (xy 51.880262 -283.074872) (xy 52.21911 -283.074872) (xy 52.22307 -283.025818)
			(xy 52.234847 -282.978034) (xy 52.254138 -282.932758) (xy 52.280441 -282.891162) (xy 52.313076 -282.854325)
			(xy 52.351197 -282.8232) (xy 52.393818 -282.798593) (xy 52.439834 -282.781141) (xy 52.488053 -282.771297)
			(xy 52.537228 -282.769316) (xy 52.586083 -282.775248) (xy 52.633354 -282.78894) (xy 52.677816 -282.810038)
			(xy 52.718319 -282.837994) (xy 52.753812 -282.872086) (xy 52.783377 -282.91143) (xy 52.806248 -282.955007)
			(xy 52.821832 -283.001688) (xy 52.829727 -283.050265) (xy 52.830222 -283.074872) (xy 53.16907 -283.074872)
			(xy 53.17303 -283.025818) (xy 53.184807 -282.978034) (xy 53.204098 -282.932758) (xy 53.230401 -282.891162)
			(xy 53.263036 -282.854325) (xy 53.301157 -282.8232) (xy 53.343778 -282.798593) (xy 53.389794 -282.781141)
			(xy 53.438013 -282.771297) (xy 53.487188 -282.769316) (xy 53.536043 -282.775248) (xy 53.583314 -282.78894)
			(xy 53.627776 -282.810038) (xy 53.668279 -282.837994) (xy 53.703772 -282.872086) (xy 53.733337 -282.91143)
			(xy 53.756208 -282.955007) (xy 53.771792 -283.001688) (xy 53.779687 -283.050265) (xy 53.780182 -283.074872)
			(xy 54.11903 -283.074872) (xy 54.12299 -283.025818) (xy 54.134767 -282.978034) (xy 54.154058 -282.932758)
			(xy 54.180361 -282.891162) (xy 54.212996 -282.854325) (xy 54.251117 -282.8232) (xy 54.293738 -282.798593)
			(xy 54.339754 -282.781141) (xy 54.387973 -282.771297) (xy 54.437148 -282.769316) (xy 54.486003 -282.775248)
			(xy 54.533274 -282.78894) (xy 54.577736 -282.810038) (xy 54.618239 -282.837994) (xy 54.653732 -282.872086)
			(xy 54.683297 -282.91143) (xy 54.706168 -282.955007) (xy 54.721752 -283.001688) (xy 54.729647 -283.050265)
			(xy 54.730142 -283.074872) (xy 55.06899 -283.074872) (xy 55.07295 -283.025818) (xy 55.084727 -282.978034)
			(xy 55.104018 -282.932758) (xy 55.130321 -282.891162) (xy 55.162956 -282.854325) (xy 55.201077 -282.8232)
			(xy 55.243698 -282.798593) (xy 55.289714 -282.781141) (xy 55.337933 -282.771297) (xy 55.387108 -282.769316)
			(xy 55.435963 -282.775248) (xy 55.483234 -282.78894) (xy 55.527696 -282.810038) (xy 55.568199 -282.837994)
			(xy 55.603692 -282.872086) (xy 55.633257 -282.91143) (xy 55.656128 -282.955007) (xy 55.671712 -283.001688)
			(xy 55.679607 -283.050265) (xy 55.680102 -283.074872) (xy 56.019204 -283.074872) (xy 56.023164 -283.025818)
			(xy 56.034941 -282.978034) (xy 56.054232 -282.932758) (xy 56.080535 -282.891162) (xy 56.11317 -282.854325)
			(xy 56.151291 -282.8232) (xy 56.193912 -282.798593) (xy 56.239928 -282.781141) (xy 56.288147 -282.771297)
			(xy 56.337322 -282.769316) (xy 56.386177 -282.775248) (xy 56.433448 -282.78894) (xy 56.47791 -282.810038)
			(xy 56.518413 -282.837994) (xy 56.553906 -282.872086) (xy 56.583471 -282.91143) (xy 56.606342 -282.955007)
			(xy 56.621926 -283.001688) (xy 56.629821 -283.050265) (xy 56.630316 -283.074872) (xy 56.969164 -283.074872)
			(xy 56.973124 -283.025818) (xy 56.984901 -282.978034) (xy 57.004192 -282.932758) (xy 57.030495 -282.891162)
			(xy 57.06313 -282.854325) (xy 57.101251 -282.8232) (xy 57.143872 -282.798593) (xy 57.189888 -282.781141)
			(xy 57.238107 -282.771297) (xy 57.287282 -282.769316) (xy 57.336137 -282.775248) (xy 57.383408 -282.78894)
			(xy 57.42787 -282.810038) (xy 57.468373 -282.837994) (xy 57.503866 -282.872086) (xy 57.533431 -282.91143)
			(xy 57.556302 -282.955007) (xy 57.571886 -283.001688) (xy 57.579781 -283.050265) (xy 57.580276 -283.074872)
			(xy 57.919124 -283.074872) (xy 57.923084 -283.025818) (xy 57.934861 -282.978034) (xy 57.954152 -282.932758)
			(xy 57.980455 -282.891162) (xy 58.01309 -282.854325) (xy 58.051211 -282.8232) (xy 58.093832 -282.798593)
			(xy 58.139848 -282.781141) (xy 58.188067 -282.771297) (xy 58.237242 -282.769316) (xy 58.286097 -282.775248)
			(xy 58.333368 -282.78894) (xy 58.37783 -282.810038) (xy 58.418333 -282.837994) (xy 58.453826 -282.872086)
			(xy 58.483391 -282.91143) (xy 58.506262 -282.955007) (xy 58.521846 -283.001688) (xy 58.529741 -283.050265)
			(xy 58.530236 -283.074872) (xy 59.819044 -283.074872) (xy 59.823004 -283.025818) (xy 59.834781 -282.978034)
			(xy 59.854072 -282.932758) (xy 59.880375 -282.891162) (xy 59.91301 -282.854325) (xy 59.951131 -282.8232)
			(xy 59.993752 -282.798593) (xy 60.039768 -282.781141) (xy 60.087987 -282.771297) (xy 60.137162 -282.769316)
			(xy 60.186017 -282.775248) (xy 60.233288 -282.78894) (xy 60.27775 -282.810038) (xy 60.318253 -282.837994)
			(xy 60.353746 -282.872086) (xy 60.383311 -282.91143) (xy 60.406182 -282.955007) (xy 60.421766 -283.001688)
			(xy 60.429661 -283.050265) (xy 60.430156 -283.074872) (xy 60.769004 -283.074872) (xy 60.772964 -283.025818)
			(xy 60.784741 -282.978034) (xy 60.804032 -282.932758) (xy 60.830335 -282.891162) (xy 60.86297 -282.854325)
			(xy 60.901091 -282.8232) (xy 60.943712 -282.798593) (xy 60.989728 -282.781141) (xy 61.037947 -282.771297)
			(xy 61.087122 -282.769316) (xy 61.135977 -282.775248) (xy 61.183248 -282.78894) (xy 61.22771 -282.810038)
			(xy 61.268213 -282.837994) (xy 61.303706 -282.872086) (xy 61.333271 -282.91143) (xy 61.356142 -282.955007)
			(xy 61.371726 -283.001688) (xy 61.379621 -283.050265) (xy 61.380116 -283.074872) (xy 61.718964 -283.074872)
			(xy 61.722924 -283.025818) (xy 61.734701 -282.978034) (xy 61.753992 -282.932758) (xy 61.780295 -282.891162)
			(xy 61.81293 -282.854325) (xy 61.851051 -282.8232) (xy 61.893672 -282.798593) (xy 61.939688 -282.781141)
			(xy 61.987907 -282.771297) (xy 62.037082 -282.769316) (xy 62.085937 -282.775248) (xy 62.133208 -282.78894)
			(xy 62.17767 -282.810038) (xy 62.218173 -282.837994) (xy 62.253666 -282.872086) (xy 62.283231 -282.91143)
			(xy 62.306102 -282.955007) (xy 62.321686 -283.001688) (xy 62.329581 -283.050265) (xy 62.330076 -283.074872)
			(xy 62.669178 -283.074872) (xy 62.673138 -283.025818) (xy 62.684915 -282.978034) (xy 62.704206 -282.932758)
			(xy 62.730509 -282.891162) (xy 62.763144 -282.854325) (xy 62.801265 -282.8232) (xy 62.843886 -282.798593)
			(xy 62.889902 -282.781141) (xy 62.938121 -282.771297) (xy 62.987296 -282.769316) (xy 63.036151 -282.775248)
			(xy 63.083422 -282.78894) (xy 63.127884 -282.810038) (xy 63.168387 -282.837994) (xy 63.20388 -282.872086)
			(xy 63.233445 -282.91143) (xy 63.256316 -282.955007) (xy 63.2719 -283.001688) (xy 63.279795 -283.050265)
			(xy 63.28029 -283.074872) (xy 63.619138 -283.074872) (xy 63.623098 -283.025818) (xy 63.634875 -282.978034)
			(xy 63.654166 -282.932758) (xy 63.680469 -282.891162) (xy 63.713104 -282.854325) (xy 63.751225 -282.8232)
			(xy 63.793846 -282.798593) (xy 63.839862 -282.781141) (xy 63.888081 -282.771297) (xy 63.937256 -282.769316)
			(xy 63.986111 -282.775248) (xy 64.033382 -282.78894) (xy 64.077844 -282.810038) (xy 64.118347 -282.837994)
			(xy 64.15384 -282.872086) (xy 64.183405 -282.91143) (xy 64.206276 -282.955007) (xy 64.22186 -283.001688)
			(xy 64.229755 -283.050265) (xy 64.23025 -283.074872) (xy 64.569098 -283.074872) (xy 64.573058 -283.025818)
			(xy 64.584835 -282.978034) (xy 64.604126 -282.932758) (xy 64.630429 -282.891162) (xy 64.663064 -282.854325)
			(xy 64.701185 -282.8232) (xy 64.743806 -282.798593) (xy 64.789822 -282.781141) (xy 64.838041 -282.771297)
			(xy 64.887216 -282.769316) (xy 64.936071 -282.775248) (xy 64.983342 -282.78894) (xy 65.027804 -282.810038)
			(xy 65.068307 -282.837994) (xy 65.1038 -282.872086) (xy 65.133365 -282.91143) (xy 65.156236 -282.955007)
			(xy 65.17182 -283.001688) (xy 65.179715 -283.050265) (xy 65.18021 -283.074872) (xy 65.519058 -283.074872)
			(xy 65.523018 -283.025818) (xy 65.534795 -282.978034) (xy 65.554086 -282.932758) (xy 65.580389 -282.891162)
			(xy 65.613024 -282.854325) (xy 65.651145 -282.8232) (xy 65.693766 -282.798593) (xy 65.739782 -282.781141)
			(xy 65.788001 -282.771297) (xy 65.837176 -282.769316) (xy 65.886031 -282.775248) (xy 65.933302 -282.78894)
			(xy 65.977764 -282.810038) (xy 66.018267 -282.837994) (xy 66.05376 -282.872086) (xy 66.083325 -282.91143)
			(xy 66.106196 -282.955007) (xy 66.12178 -283.001688) (xy 66.129675 -283.050265) (xy 66.13017 -283.074872)
			(xy 66.469018 -283.074872) (xy 66.472978 -283.025818) (xy 66.484755 -282.978034) (xy 66.504046 -282.932758)
			(xy 66.530349 -282.891162) (xy 66.562984 -282.854325) (xy 66.601105 -282.8232) (xy 66.643726 -282.798593)
			(xy 66.689742 -282.781141) (xy 66.737961 -282.771297) (xy 66.787136 -282.769316) (xy 66.835991 -282.775248)
			(xy 66.883262 -282.78894) (xy 66.927724 -282.810038) (xy 66.968227 -282.837994) (xy 67.00372 -282.872086)
			(xy 67.033285 -282.91143) (xy 67.056156 -282.955007) (xy 67.07174 -283.001688) (xy 67.079635 -283.050265)
			(xy 67.08013 -283.074872) (xy 68.368938 -283.074872) (xy 68.372898 -283.025818) (xy 68.384675 -282.978034)
			(xy 68.403966 -282.932758) (xy 68.430269 -282.891162) (xy 68.462904 -282.854325) (xy 68.501025 -282.8232)
			(xy 68.543646 -282.798593) (xy 68.589662 -282.781141) (xy 68.637881 -282.771297) (xy 68.687056 -282.769316)
			(xy 68.735911 -282.775248) (xy 68.783182 -282.78894) (xy 68.827644 -282.810038) (xy 68.868147 -282.837994)
			(xy 68.90364 -282.872086) (xy 68.933205 -282.91143) (xy 68.956076 -282.955007) (xy 68.97166 -283.001688)
			(xy 68.979555 -283.050265) (xy 68.98005 -283.074872) (xy 69.319152 -283.074872) (xy 69.323112 -283.025818)
			(xy 69.334889 -282.978034) (xy 69.35418 -282.932758) (xy 69.380483 -282.891162) (xy 69.413118 -282.854325)
			(xy 69.451239 -282.8232) (xy 69.49386 -282.798593) (xy 69.539876 -282.781141) (xy 69.588095 -282.771297)
			(xy 69.63727 -282.769316) (xy 69.686125 -282.775248) (xy 69.733396 -282.78894) (xy 69.777858 -282.810038)
			(xy 69.818361 -282.837994) (xy 69.853854 -282.872086) (xy 69.883419 -282.91143) (xy 69.90629 -282.955007)
			(xy 69.921874 -283.001688) (xy 69.929769 -283.050265) (xy 69.930264 -283.074872) (xy 70.269112 -283.074872)
			(xy 70.273072 -283.025818) (xy 70.284849 -282.978034) (xy 70.30414 -282.932758) (xy 70.330443 -282.891162)
			(xy 70.363078 -282.854325) (xy 70.401199 -282.8232) (xy 70.44382 -282.798593) (xy 70.489836 -282.781141)
			(xy 70.538055 -282.771297) (xy 70.58723 -282.769316) (xy 70.636085 -282.775248) (xy 70.683356 -282.78894)
			(xy 70.727818 -282.810038) (xy 70.768321 -282.837994) (xy 70.803814 -282.872086) (xy 70.833379 -282.91143)
			(xy 70.85625 -282.955007) (xy 70.871834 -283.001688) (xy 70.879729 -283.050265) (xy 70.880224 -283.074872)
			(xy 71.219072 -283.074872) (xy 71.223032 -283.025818) (xy 71.234809 -282.978034) (xy 71.2541 -282.932758)
			(xy 71.280403 -282.891162) (xy 71.313038 -282.854325) (xy 71.351159 -282.8232) (xy 71.39378 -282.798593)
			(xy 71.439796 -282.781141) (xy 71.488015 -282.771297) (xy 71.53719 -282.769316) (xy 71.586045 -282.775248)
			(xy 71.633316 -282.78894) (xy 71.677778 -282.810038) (xy 71.718281 -282.837994) (xy 71.753774 -282.872086)
			(xy 71.783339 -282.91143) (xy 71.80621 -282.955007) (xy 71.821794 -283.001688) (xy 71.829689 -283.050265)
			(xy 71.830184 -283.074872) (xy 72.169032 -283.074872) (xy 72.172992 -283.025818) (xy 72.184769 -282.978034)
			(xy 72.20406 -282.932758) (xy 72.230363 -282.891162) (xy 72.262998 -282.854325) (xy 72.301119 -282.8232)
			(xy 72.34374 -282.798593) (xy 72.389756 -282.781141) (xy 72.437975 -282.771297) (xy 72.48715 -282.769316)
			(xy 72.536005 -282.775248) (xy 72.583276 -282.78894) (xy 72.627738 -282.810038) (xy 72.668241 -282.837994)
			(xy 72.703734 -282.872086) (xy 72.733299 -282.91143) (xy 72.75617 -282.955007) (xy 72.771754 -283.001688)
			(xy 72.779649 -283.050265) (xy 72.780144 -283.074872) (xy 72.779649 -283.099479) (xy 72.771754 -283.148056)
			(xy 72.75617 -283.194737) (xy 72.733299 -283.238314) (xy 72.703734 -283.277658) (xy 72.668241 -283.31175)
			(xy 72.627738 -283.339706) (xy 72.583276 -283.360804) (xy 72.536005 -283.374496) (xy 72.48715 -283.380428)
			(xy 72.437975 -283.378447) (xy 72.389756 -283.368603) (xy 72.34374 -283.351151) (xy 72.301119 -283.326544)
			(xy 72.262998 -283.295419) (xy 72.230363 -283.258582) (xy 72.20406 -283.216986) (xy 72.184769 -283.17171)
			(xy 72.172992 -283.123926) (xy 72.169032 -283.074872) (xy 71.830184 -283.074872) (xy 71.829689 -283.099479)
			(xy 71.821794 -283.148056) (xy 71.80621 -283.194737) (xy 71.783339 -283.238314) (xy 71.753774 -283.277658)
			(xy 71.718281 -283.31175) (xy 71.677778 -283.339706) (xy 71.633316 -283.360804) (xy 71.586045 -283.374496)
			(xy 71.53719 -283.380428) (xy 71.488015 -283.378447) (xy 71.439796 -283.368603) (xy 71.39378 -283.351151)
			(xy 71.351159 -283.326544) (xy 71.313038 -283.295419) (xy 71.280403 -283.258582) (xy 71.2541 -283.216986)
			(xy 71.234809 -283.17171) (xy 71.223032 -283.123926) (xy 71.219072 -283.074872) (xy 70.880224 -283.074872)
			(xy 70.879729 -283.099479) (xy 70.871834 -283.148056) (xy 70.85625 -283.194737) (xy 70.833379 -283.238314)
			(xy 70.803814 -283.277658) (xy 70.768321 -283.31175) (xy 70.727818 -283.339706) (xy 70.683356 -283.360804)
			(xy 70.636085 -283.374496) (xy 70.58723 -283.380428) (xy 70.538055 -283.378447) (xy 70.489836 -283.368603)
			(xy 70.44382 -283.351151) (xy 70.401199 -283.326544) (xy 70.363078 -283.295419) (xy 70.330443 -283.258582)
			(xy 70.30414 -283.216986) (xy 70.284849 -283.17171) (xy 70.273072 -283.123926) (xy 70.269112 -283.074872)
			(xy 69.930264 -283.074872) (xy 69.929769 -283.099479) (xy 69.921874 -283.148056) (xy 69.90629 -283.194737)
			(xy 69.883419 -283.238314) (xy 69.853854 -283.277658) (xy 69.818361 -283.31175) (xy 69.777858 -283.339706)
			(xy 69.733396 -283.360804) (xy 69.686125 -283.374496) (xy 69.63727 -283.380428) (xy 69.588095 -283.378447)
			(xy 69.539876 -283.368603) (xy 69.49386 -283.351151) (xy 69.451239 -283.326544) (xy 69.413118 -283.295419)
			(xy 69.380483 -283.258582) (xy 69.35418 -283.216986) (xy 69.334889 -283.17171) (xy 69.323112 -283.123926)
			(xy 69.319152 -283.074872) (xy 68.98005 -283.074872) (xy 68.979555 -283.099479) (xy 68.97166 -283.148056)
			(xy 68.956076 -283.194737) (xy 68.933205 -283.238314) (xy 68.90364 -283.277658) (xy 68.868147 -283.31175)
			(xy 68.827644 -283.339706) (xy 68.783182 -283.360804) (xy 68.735911 -283.374496) (xy 68.687056 -283.380428)
			(xy 68.637881 -283.378447) (xy 68.589662 -283.368603) (xy 68.543646 -283.351151) (xy 68.501025 -283.326544)
			(xy 68.462904 -283.295419) (xy 68.430269 -283.258582) (xy 68.403966 -283.216986) (xy 68.384675 -283.17171)
			(xy 68.372898 -283.123926) (xy 68.368938 -283.074872) (xy 67.08013 -283.074872) (xy 67.079635 -283.099479)
			(xy 67.07174 -283.148056) (xy 67.056156 -283.194737) (xy 67.033285 -283.238314) (xy 67.00372 -283.277658)
			(xy 66.968227 -283.31175) (xy 66.927724 -283.339706) (xy 66.883262 -283.360804) (xy 66.835991 -283.374496)
			(xy 66.787136 -283.380428) (xy 66.737961 -283.378447) (xy 66.689742 -283.368603) (xy 66.643726 -283.351151)
			(xy 66.601105 -283.326544) (xy 66.562984 -283.295419) (xy 66.530349 -283.258582) (xy 66.504046 -283.216986)
			(xy 66.484755 -283.17171) (xy 66.472978 -283.123926) (xy 66.469018 -283.074872) (xy 66.13017 -283.074872)
			(xy 66.129675 -283.099479) (xy 66.12178 -283.148056) (xy 66.106196 -283.194737) (xy 66.083325 -283.238314)
			(xy 66.05376 -283.277658) (xy 66.018267 -283.31175) (xy 65.977764 -283.339706) (xy 65.933302 -283.360804)
			(xy 65.886031 -283.374496) (xy 65.837176 -283.380428) (xy 65.788001 -283.378447) (xy 65.739782 -283.368603)
			(xy 65.693766 -283.351151) (xy 65.651145 -283.326544) (xy 65.613024 -283.295419) (xy 65.580389 -283.258582)
			(xy 65.554086 -283.216986) (xy 65.534795 -283.17171) (xy 65.523018 -283.123926) (xy 65.519058 -283.074872)
			(xy 65.18021 -283.074872) (xy 65.179715 -283.099479) (xy 65.17182 -283.148056) (xy 65.156236 -283.194737)
			(xy 65.133365 -283.238314) (xy 65.1038 -283.277658) (xy 65.068307 -283.31175) (xy 65.027804 -283.339706)
			(xy 64.983342 -283.360804) (xy 64.936071 -283.374496) (xy 64.887216 -283.380428) (xy 64.838041 -283.378447)
			(xy 64.789822 -283.368603) (xy 64.743806 -283.351151) (xy 64.701185 -283.326544) (xy 64.663064 -283.295419)
			(xy 64.630429 -283.258582) (xy 64.604126 -283.216986) (xy 64.584835 -283.17171) (xy 64.573058 -283.123926)
			(xy 64.569098 -283.074872) (xy 64.23025 -283.074872) (xy 64.229755 -283.099479) (xy 64.22186 -283.148056)
			(xy 64.206276 -283.194737) (xy 64.183405 -283.238314) (xy 64.15384 -283.277658) (xy 64.118347 -283.31175)
			(xy 64.077844 -283.339706) (xy 64.033382 -283.360804) (xy 63.986111 -283.374496) (xy 63.937256 -283.380428)
			(xy 63.888081 -283.378447) (xy 63.839862 -283.368603) (xy 63.793846 -283.351151) (xy 63.751225 -283.326544)
			(xy 63.713104 -283.295419) (xy 63.680469 -283.258582) (xy 63.654166 -283.216986) (xy 63.634875 -283.17171)
			(xy 63.623098 -283.123926) (xy 63.619138 -283.074872) (xy 63.28029 -283.074872) (xy 63.279795 -283.099479)
			(xy 63.2719 -283.148056) (xy 63.256316 -283.194737) (xy 63.233445 -283.238314) (xy 63.20388 -283.277658)
			(xy 63.168387 -283.31175) (xy 63.127884 -283.339706) (xy 63.083422 -283.360804) (xy 63.036151 -283.374496)
			(xy 62.987296 -283.380428) (xy 62.938121 -283.378447) (xy 62.889902 -283.368603) (xy 62.843886 -283.351151)
			(xy 62.801265 -283.326544) (xy 62.763144 -283.295419) (xy 62.730509 -283.258582) (xy 62.704206 -283.216986)
			(xy 62.684915 -283.17171) (xy 62.673138 -283.123926) (xy 62.669178 -283.074872) (xy 62.330076 -283.074872)
			(xy 62.329581 -283.099479) (xy 62.321686 -283.148056) (xy 62.306102 -283.194737) (xy 62.283231 -283.238314)
			(xy 62.253666 -283.277658) (xy 62.218173 -283.31175) (xy 62.17767 -283.339706) (xy 62.133208 -283.360804)
			(xy 62.085937 -283.374496) (xy 62.037082 -283.380428) (xy 61.987907 -283.378447) (xy 61.939688 -283.368603)
			(xy 61.893672 -283.351151) (xy 61.851051 -283.326544) (xy 61.81293 -283.295419) (xy 61.780295 -283.258582)
			(xy 61.753992 -283.216986) (xy 61.734701 -283.17171) (xy 61.722924 -283.123926) (xy 61.718964 -283.074872)
			(xy 61.380116 -283.074872) (xy 61.379621 -283.099479) (xy 61.371726 -283.148056) (xy 61.356142 -283.194737)
			(xy 61.333271 -283.238314) (xy 61.303706 -283.277658) (xy 61.268213 -283.31175) (xy 61.22771 -283.339706)
			(xy 61.183248 -283.360804) (xy 61.135977 -283.374496) (xy 61.087122 -283.380428) (xy 61.037947 -283.378447)
			(xy 60.989728 -283.368603) (xy 60.943712 -283.351151) (xy 60.901091 -283.326544) (xy 60.86297 -283.295419)
			(xy 60.830335 -283.258582) (xy 60.804032 -283.216986) (xy 60.784741 -283.17171) (xy 60.772964 -283.123926)
			(xy 60.769004 -283.074872) (xy 60.430156 -283.074872) (xy 60.429661 -283.099479) (xy 60.421766 -283.148056)
			(xy 60.406182 -283.194737) (xy 60.383311 -283.238314) (xy 60.353746 -283.277658) (xy 60.318253 -283.31175)
			(xy 60.27775 -283.339706) (xy 60.233288 -283.360804) (xy 60.186017 -283.374496) (xy 60.137162 -283.380428)
			(xy 60.087987 -283.378447) (xy 60.039768 -283.368603) (xy 59.993752 -283.351151) (xy 59.951131 -283.326544)
			(xy 59.91301 -283.295419) (xy 59.880375 -283.258582) (xy 59.854072 -283.216986) (xy 59.834781 -283.17171)
			(xy 59.823004 -283.123926) (xy 59.819044 -283.074872) (xy 58.530236 -283.074872) (xy 58.529741 -283.099479)
			(xy 58.521846 -283.148056) (xy 58.506262 -283.194737) (xy 58.483391 -283.238314) (xy 58.453826 -283.277658)
			(xy 58.418333 -283.31175) (xy 58.37783 -283.339706) (xy 58.333368 -283.360804) (xy 58.286097 -283.374496)
			(xy 58.237242 -283.380428) (xy 58.188067 -283.378447) (xy 58.139848 -283.368603) (xy 58.093832 -283.351151)
			(xy 58.051211 -283.326544) (xy 58.01309 -283.295419) (xy 57.980455 -283.258582) (xy 57.954152 -283.216986)
			(xy 57.934861 -283.17171) (xy 57.923084 -283.123926) (xy 57.919124 -283.074872) (xy 57.580276 -283.074872)
			(xy 57.579781 -283.099479) (xy 57.571886 -283.148056) (xy 57.556302 -283.194737) (xy 57.533431 -283.238314)
			(xy 57.503866 -283.277658) (xy 57.468373 -283.31175) (xy 57.42787 -283.339706) (xy 57.383408 -283.360804)
			(xy 57.336137 -283.374496) (xy 57.287282 -283.380428) (xy 57.238107 -283.378447) (xy 57.189888 -283.368603)
			(xy 57.143872 -283.351151) (xy 57.101251 -283.326544) (xy 57.06313 -283.295419) (xy 57.030495 -283.258582)
			(xy 57.004192 -283.216986) (xy 56.984901 -283.17171) (xy 56.973124 -283.123926) (xy 56.969164 -283.074872)
			(xy 56.630316 -283.074872) (xy 56.629821 -283.099479) (xy 56.621926 -283.148056) (xy 56.606342 -283.194737)
			(xy 56.583471 -283.238314) (xy 56.553906 -283.277658) (xy 56.518413 -283.31175) (xy 56.47791 -283.339706)
			(xy 56.433448 -283.360804) (xy 56.386177 -283.374496) (xy 56.337322 -283.380428) (xy 56.288147 -283.378447)
			(xy 56.239928 -283.368603) (xy 56.193912 -283.351151) (xy 56.151291 -283.326544) (xy 56.11317 -283.295419)
			(xy 56.080535 -283.258582) (xy 56.054232 -283.216986) (xy 56.034941 -283.17171) (xy 56.023164 -283.123926)
			(xy 56.019204 -283.074872) (xy 55.680102 -283.074872) (xy 55.679607 -283.099479) (xy 55.671712 -283.148056)
			(xy 55.656128 -283.194737) (xy 55.633257 -283.238314) (xy 55.603692 -283.277658) (xy 55.568199 -283.31175)
			(xy 55.527696 -283.339706) (xy 55.483234 -283.360804) (xy 55.435963 -283.374496) (xy 55.387108 -283.380428)
			(xy 55.337933 -283.378447) (xy 55.289714 -283.368603) (xy 55.243698 -283.351151) (xy 55.201077 -283.326544)
			(xy 55.162956 -283.295419) (xy 55.130321 -283.258582) (xy 55.104018 -283.216986) (xy 55.084727 -283.17171)
			(xy 55.07295 -283.123926) (xy 55.06899 -283.074872) (xy 54.730142 -283.074872) (xy 54.729647 -283.099479)
			(xy 54.721752 -283.148056) (xy 54.706168 -283.194737) (xy 54.683297 -283.238314) (xy 54.653732 -283.277658)
			(xy 54.618239 -283.31175) (xy 54.577736 -283.339706) (xy 54.533274 -283.360804) (xy 54.486003 -283.374496)
			(xy 54.437148 -283.380428) (xy 54.387973 -283.378447) (xy 54.339754 -283.368603) (xy 54.293738 -283.351151)
			(xy 54.251117 -283.326544) (xy 54.212996 -283.295419) (xy 54.180361 -283.258582) (xy 54.154058 -283.216986)
			(xy 54.134767 -283.17171) (xy 54.12299 -283.123926) (xy 54.11903 -283.074872) (xy 53.780182 -283.074872)
			(xy 53.779687 -283.099479) (xy 53.771792 -283.148056) (xy 53.756208 -283.194737) (xy 53.733337 -283.238314)
			(xy 53.703772 -283.277658) (xy 53.668279 -283.31175) (xy 53.627776 -283.339706) (xy 53.583314 -283.360804)
			(xy 53.536043 -283.374496) (xy 53.487188 -283.380428) (xy 53.438013 -283.378447) (xy 53.389794 -283.368603)
			(xy 53.343778 -283.351151) (xy 53.301157 -283.326544) (xy 53.263036 -283.295419) (xy 53.230401 -283.258582)
			(xy 53.204098 -283.216986) (xy 53.184807 -283.17171) (xy 53.17303 -283.123926) (xy 53.16907 -283.074872)
			(xy 52.830222 -283.074872) (xy 52.829727 -283.099479) (xy 52.821832 -283.148056) (xy 52.806248 -283.194737)
			(xy 52.783377 -283.238314) (xy 52.753812 -283.277658) (xy 52.718319 -283.31175) (xy 52.677816 -283.339706)
			(xy 52.633354 -283.360804) (xy 52.586083 -283.374496) (xy 52.537228 -283.380428) (xy 52.488053 -283.378447)
			(xy 52.439834 -283.368603) (xy 52.393818 -283.351151) (xy 52.351197 -283.326544) (xy 52.313076 -283.295419)
			(xy 52.280441 -283.258582) (xy 52.254138 -283.216986) (xy 52.234847 -283.17171) (xy 52.22307 -283.123926)
			(xy 52.21911 -283.074872) (xy 51.880262 -283.074872) (xy 51.879767 -283.099479) (xy 51.871872 -283.148056)
			(xy 51.856288 -283.194737) (xy 51.833417 -283.238314) (xy 51.803852 -283.277658) (xy 51.768359 -283.31175)
			(xy 51.727856 -283.339706) (xy 51.683394 -283.360804) (xy 51.636123 -283.374496) (xy 51.587268 -283.380428)
			(xy 51.538093 -283.378447) (xy 51.489874 -283.368603) (xy 51.443858 -283.351151) (xy 51.401237 -283.326544)
			(xy 51.363116 -283.295419) (xy 51.330481 -283.258582) (xy 51.304178 -283.216986) (xy 51.284887 -283.17171)
			(xy 51.27311 -283.123926) (xy 51.26915 -283.074872) (xy 50.930302 -283.074872) (xy 50.929807 -283.099479)
			(xy 50.921912 -283.148056) (xy 50.906328 -283.194737) (xy 50.883457 -283.238314) (xy 50.853892 -283.277658)
			(xy 50.818399 -283.31175) (xy 50.777896 -283.339706) (xy 50.733434 -283.360804) (xy 50.686163 -283.374496)
			(xy 50.637308 -283.380428) (xy 50.588133 -283.378447) (xy 50.539914 -283.368603) (xy 50.493898 -283.351151)
			(xy 50.451277 -283.326544) (xy 50.413156 -283.295419) (xy 50.380521 -283.258582) (xy 50.354218 -283.216986)
			(xy 50.334927 -283.17171) (xy 50.32315 -283.123926) (xy 50.31919 -283.074872) (xy 49.980088 -283.074872)
			(xy 49.979593 -283.099479) (xy 49.971698 -283.148056) (xy 49.956114 -283.194737) (xy 49.933243 -283.238314)
			(xy 49.903678 -283.277658) (xy 49.868185 -283.31175) (xy 49.827682 -283.339706) (xy 49.78322 -283.360804)
			(xy 49.735949 -283.374496) (xy 49.687094 -283.380428) (xy 49.637919 -283.378447) (xy 49.5897 -283.368603)
			(xy 49.543684 -283.351151) (xy 49.501063 -283.326544) (xy 49.462942 -283.295419) (xy 49.430307 -283.258582)
			(xy 49.404004 -283.216986) (xy 49.384713 -283.17171) (xy 49.372936 -283.123926) (xy 49.368976 -283.074872)
			(xy 49.030128 -283.074872) (xy 49.029633 -283.099479) (xy 49.021738 -283.148056) (xy 49.006154 -283.194737)
			(xy 48.983283 -283.238314) (xy 48.953718 -283.277658) (xy 48.918225 -283.31175) (xy 48.877722 -283.339706)
			(xy 48.83326 -283.360804) (xy 48.785989 -283.374496) (xy 48.737134 -283.380428) (xy 48.687959 -283.378447)
			(xy 48.63974 -283.368603) (xy 48.593724 -283.351151) (xy 48.551103 -283.326544) (xy 48.512982 -283.295419)
			(xy 48.480347 -283.258582) (xy 48.454044 -283.216986) (xy 48.434753 -283.17171) (xy 48.422976 -283.123926)
			(xy 48.419016 -283.074872) (xy 48.080168 -283.074872) (xy 48.079673 -283.099479) (xy 48.071778 -283.148056)
			(xy 48.056194 -283.194737) (xy 48.033323 -283.238314) (xy 48.003758 -283.277658) (xy 47.968265 -283.31175)
			(xy 47.927762 -283.339706) (xy 47.8833 -283.360804) (xy 47.836029 -283.374496) (xy 47.787174 -283.380428)
			(xy 47.737999 -283.378447) (xy 47.68978 -283.368603) (xy 47.643764 -283.351151) (xy 47.601143 -283.326544)
			(xy 47.563022 -283.295419) (xy 47.530387 -283.258582) (xy 47.504084 -283.216986) (xy 47.484793 -283.17171)
			(xy 47.473016 -283.123926) (xy 47.469056 -283.074872) (xy 47.130172 -283.074872) (xy 47.12793 -283.116197)
			(xy 47.117257 -283.164679) (xy 47.09888 -283.210795) (xy 47.073285 -283.253331) (xy 47.041145 -283.291165)
			(xy 47.003308 -283.323301) (xy 46.96077 -283.348893) (xy 46.914652 -283.367265) (xy 46.866169 -283.377934)
			(xy 46.816599 -283.380618) (xy 46.767248 -283.375248) (xy 46.719416 -283.361964) (xy 46.674363 -283.341116)
			(xy 46.633276 -283.313255) (xy 46.597238 -283.279113) (xy 46.567199 -283.23959) (xy 46.54395 -283.195728)
			(xy 46.528103 -283.148683) (xy 46.520076 -283.099693) (xy 46.519592 -283.074872) (xy 46.519765 -283.060689)
			(xy 46.522439 -283.032449) (xy 46.524926 -283.018484) (xy 46.527212 -283.006038) (xy 46.519846 -282.982416)
			(xy 46.442376 -282.904946) (xy 46.418754 -282.89758) (xy 46.406308 -282.899866) (xy 46.392341 -282.902337)
			(xy 46.364102 -282.905013) (xy 46.34992 -282.9052) (xy 46.335737 -282.905021) (xy 46.307497 -282.90235)
			(xy 46.293532 -282.899866) (xy 46.281086 -282.89758) (xy 46.257464 -282.904946) (xy 46.179994 -282.982416)
			(xy 46.172628 -283.006038) (xy 46.174914 -283.018484) (xy 46.177398 -283.032449) (xy 46.180065 -283.060689)
			(xy 46.180248 -283.074872) (xy 46.179726 -283.100127) (xy 46.171413 -283.149949) (xy 46.155012 -283.197723)
			(xy 46.130971 -283.242146) (xy 46.099947 -283.282006) (xy 46.062785 -283.316216) (xy 46.020499 -283.343842)
			(xy 45.974243 -283.364132) (xy 45.925278 -283.376532) (xy 45.87494 -283.380703) (xy 45.824602 -283.376532)
			(xy 45.775637 -283.364132) (xy 45.729381 -283.343842) (xy 45.687095 -283.316216) (xy 45.649933 -283.282006)
			(xy 45.618909 -283.242146) (xy 45.594868 -283.197723) (xy 45.578467 -283.149949) (xy 45.570154 -283.100127)
			(xy 45.569632 -283.074872) (xy 45.569804 -283.060689) (xy 45.572479 -283.032449) (xy 45.574966 -283.018484)
			(xy 45.577252 -283.006038) (xy 45.569886 -282.982416) (xy 45.492416 -282.904946) (xy 45.468794 -282.89758)
			(xy 45.456348 -282.899866) (xy 45.442383 -282.902345) (xy 45.414143 -282.905015) (xy 45.39996 -282.9052)
			(xy 45.385777 -282.905029) (xy 45.357537 -282.902353) (xy 45.343572 -282.899866) (xy 45.331126 -282.89758)
			(xy 45.307504 -282.904946) (xy 45.230034 -282.982416) (xy 45.222668 -283.006038) (xy 45.224954 -283.018484)
			(xy 45.227438 -283.032449) (xy 45.230105 -283.060689) (xy 45.230288 -283.074872) (xy 45.229852 -283.099695)
			(xy 45.221825 -283.148689) (xy 45.205977 -283.195738) (xy 45.182726 -283.239603) (xy 45.152685 -283.279129)
			(xy 45.116644 -283.313274) (xy 45.075555 -283.341139) (xy 45.030499 -283.361988) (xy 44.982663 -283.375274)
			(xy 44.933308 -283.380646) (xy 44.883734 -283.377962) (xy 44.835247 -283.367294) (xy 44.789125 -283.348922)
			(xy 44.746583 -283.323329) (xy 44.708742 -283.291192) (xy 44.676599 -283.253356) (xy 44.651 -283.210818)
			(xy 44.63262 -283.164699) (xy 44.621944 -283.116214) (xy 44.619253 -283.06664) (xy 42.379988 -283.06664)
			(xy 42.380154 -283.074872) (xy 42.379659 -283.099479) (xy 42.371764 -283.148056) (xy 42.35618 -283.194737)
			(xy 42.333309 -283.238314) (xy 42.303744 -283.277658) (xy 42.268251 -283.31175) (xy 42.227748 -283.339706)
			(xy 42.183286 -283.360804) (xy 42.136015 -283.374496) (xy 42.08716 -283.380428) (xy 42.037985 -283.378447)
			(xy 41.989766 -283.368603) (xy 41.94375 -283.351151) (xy 41.901129 -283.326544) (xy 41.863008 -283.295419)
			(xy 41.830373 -283.258582) (xy 41.80407 -283.216986) (xy 41.784779 -283.17171) (xy 41.773002 -283.123926)
			(xy 41.769042 -283.074872) (xy 41.430786 -283.074872) (xy 41.430788 -283.0749) (xy 41.426616 -283.125249)
			(xy 41.414213 -283.174224) (xy 41.393918 -283.22049) (xy 41.366285 -283.262785) (xy 41.332067 -283.299954)
			(xy 41.292197 -283.330984) (xy 41.247764 -283.355028) (xy 41.19998 -283.371431) (xy 41.150147 -283.379744)
			(xy 41.124886 -283.38018) (xy 41.101259 -283.379732) (xy 41.054569 -283.372452) (xy 41.031922 -283.365702)
			(xy 41.020238 -283.361892) (xy 40.996362 -283.365702) (xy 40.920162 -283.421328) (xy 40.910812 -283.428947)
			(xy 40.899927 -283.450431) (xy 40.899334 -283.462476) (xy 40.899334 -283.549852) (xy 73.593972 -283.549852)
			(xy 73.597932 -283.500798) (xy 73.609709 -283.453014) (xy 73.629 -283.407738) (xy 73.655303 -283.366142)
			(xy 73.687938 -283.329305) (xy 73.726059 -283.29818) (xy 73.76868 -283.273573) (xy 73.814696 -283.256121)
			(xy 73.862915 -283.246277) (xy 73.91209 -283.244296) (xy 73.960945 -283.250228) (xy 74.008216 -283.26392)
			(xy 74.052678 -283.285018) (xy 74.093181 -283.312974) (xy 74.128674 -283.347066) (xy 74.158239 -283.38641)
			(xy 74.18111 -283.429987) (xy 74.196694 -283.476668) (xy 74.204589 -283.525245) (xy 74.205084 -283.549852)
			(xy 74.204589 -283.574459) (xy 74.20441 -283.57556) (xy 74.523088 -283.57556) (xy 74.523088 -283.524144)
			(xy 74.531131 -283.473362) (xy 74.547019 -283.424463) (xy 74.570362 -283.378651) (xy 74.600583 -283.337055)
			(xy 74.636939 -283.300699) (xy 74.678535 -283.270478) (xy 74.724347 -283.247135) (xy 74.773246 -283.231247)
			(xy 74.824028 -283.223204) (xy 74.875444 -283.223204) (xy 74.926226 -283.231247) (xy 74.975125 -283.247135)
			(xy 75.020937 -283.270478) (xy 75.062533 -283.300699) (xy 75.098889 -283.337055) (xy 75.12911 -283.378651)
			(xy 75.152453 -283.424463) (xy 75.168341 -283.473362) (xy 75.176384 -283.524144) (xy 75.176888 -283.549852)
			(xy 75.176384 -283.57556) (xy 75.473302 -283.57556) (xy 75.473302 -283.524144) (xy 75.481345 -283.473362)
			(xy 75.497233 -283.424463) (xy 75.520576 -283.378651) (xy 75.550797 -283.337055) (xy 75.587153 -283.300699)
			(xy 75.628749 -283.270478) (xy 75.674561 -283.247135) (xy 75.72346 -283.231247) (xy 75.774242 -283.223204)
			(xy 75.825658 -283.223204) (xy 75.87644 -283.231247) (xy 75.925339 -283.247135) (xy 75.971151 -283.270478)
			(xy 76.012747 -283.300699) (xy 76.049103 -283.337055) (xy 76.079324 -283.378651) (xy 76.102667 -283.424463)
			(xy 76.118555 -283.473362) (xy 76.126598 -283.524144) (xy 76.127102 -283.549852) (xy 76.444106 -283.549852)
			(xy 76.448066 -283.500798) (xy 76.459843 -283.453014) (xy 76.479134 -283.407738) (xy 76.505437 -283.366142)
			(xy 76.538072 -283.329305) (xy 76.576193 -283.29818) (xy 76.618814 -283.273573) (xy 76.66483 -283.256121)
			(xy 76.713049 -283.246277) (xy 76.762224 -283.244296) (xy 76.811079 -283.250228) (xy 76.85835 -283.26392)
			(xy 76.902812 -283.285018) (xy 76.943315 -283.312974) (xy 76.978808 -283.347066) (xy 77.008373 -283.38641)
			(xy 77.031244 -283.429987) (xy 77.046828 -283.476668) (xy 77.054723 -283.525245) (xy 77.055218 -283.549852)
			(xy 77.394066 -283.549852) (xy 77.398026 -283.500798) (xy 77.409803 -283.453014) (xy 77.429094 -283.407738)
			(xy 77.455397 -283.366142) (xy 77.488032 -283.329305) (xy 77.526153 -283.29818) (xy 77.568774 -283.273573)
			(xy 77.61479 -283.256121) (xy 77.663009 -283.246277) (xy 77.712184 -283.244296) (xy 77.761039 -283.250228)
			(xy 77.80831 -283.26392) (xy 77.852772 -283.285018) (xy 77.893275 -283.312974) (xy 77.928768 -283.347066)
			(xy 77.958333 -283.38641) (xy 77.981204 -283.429987) (xy 77.996788 -283.476668) (xy 78.004683 -283.525245)
			(xy 78.005178 -283.549852) (xy 78.344026 -283.549852) (xy 78.347986 -283.500798) (xy 78.359763 -283.453014)
			(xy 78.379054 -283.407738) (xy 78.405357 -283.366142) (xy 78.437992 -283.329305) (xy 78.476113 -283.29818)
			(xy 78.518734 -283.273573) (xy 78.56475 -283.256121) (xy 78.612969 -283.246277) (xy 78.662144 -283.244296)
			(xy 78.710999 -283.250228) (xy 78.75827 -283.26392) (xy 78.802732 -283.285018) (xy 78.843235 -283.312974)
			(xy 78.878728 -283.347066) (xy 78.908293 -283.38641) (xy 78.931164 -283.429987) (xy 78.946748 -283.476668)
			(xy 78.954643 -283.525245) (xy 78.955138 -283.549852) (xy 79.293986 -283.549852) (xy 79.297946 -283.500798)
			(xy 79.309723 -283.453014) (xy 79.329014 -283.407738) (xy 79.355317 -283.366142) (xy 79.387952 -283.329305)
			(xy 79.426073 -283.29818) (xy 79.468694 -283.273573) (xy 79.51471 -283.256121) (xy 79.562929 -283.246277)
			(xy 79.612104 -283.244296) (xy 79.660959 -283.250228) (xy 79.70823 -283.26392) (xy 79.752692 -283.285018)
			(xy 79.793195 -283.312974) (xy 79.828688 -283.347066) (xy 79.858253 -283.38641) (xy 79.881124 -283.429987)
			(xy 79.896708 -283.476668) (xy 79.904603 -283.525245) (xy 79.905098 -283.549852) (xy 80.243946 -283.549852)
			(xy 80.247906 -283.500798) (xy 80.259683 -283.453014) (xy 80.278974 -283.407738) (xy 80.305277 -283.366142)
			(xy 80.337912 -283.329305) (xy 80.376033 -283.29818) (xy 80.418654 -283.273573) (xy 80.46467 -283.256121)
			(xy 80.512889 -283.246277) (xy 80.562064 -283.244296) (xy 80.610919 -283.250228) (xy 80.65819 -283.26392)
			(xy 80.702652 -283.285018) (xy 80.743155 -283.312974) (xy 80.778648 -283.347066) (xy 80.808213 -283.38641)
			(xy 80.831084 -283.429987) (xy 80.846668 -283.476668) (xy 80.854563 -283.525245) (xy 80.855058 -283.549852)
			(xy 80.854563 -283.574459) (xy 80.854384 -283.57556) (xy 81.173316 -283.57556) (xy 81.173316 -283.524144)
			(xy 81.181359 -283.473362) (xy 81.197247 -283.424463) (xy 81.22059 -283.378651) (xy 81.250811 -283.337055)
			(xy 81.287167 -283.300699) (xy 81.328763 -283.270478) (xy 81.374575 -283.247135) (xy 81.423474 -283.231247)
			(xy 81.474256 -283.223204) (xy 81.525672 -283.223204) (xy 81.576454 -283.231247) (xy 81.625353 -283.247135)
			(xy 81.671165 -283.270478) (xy 81.712761 -283.300699) (xy 81.749117 -283.337055) (xy 81.779338 -283.378651)
			(xy 81.802681 -283.424463) (xy 81.818569 -283.473362) (xy 81.826612 -283.524144) (xy 81.827116 -283.549852)
			(xy 81.826612 -283.57556) (xy 82.123276 -283.57556) (xy 82.123276 -283.524144) (xy 82.131319 -283.473362)
			(xy 82.147207 -283.424463) (xy 82.17055 -283.378651) (xy 82.200771 -283.337055) (xy 82.237127 -283.300699)
			(xy 82.278723 -283.270478) (xy 82.324535 -283.247135) (xy 82.373434 -283.231247) (xy 82.424216 -283.223204)
			(xy 82.475632 -283.223204) (xy 82.526414 -283.231247) (xy 82.575313 -283.247135) (xy 82.621125 -283.270478)
			(xy 82.662721 -283.300699) (xy 82.699077 -283.337055) (xy 82.729298 -283.378651) (xy 82.752641 -283.424463)
			(xy 82.768529 -283.473362) (xy 82.776572 -283.524144) (xy 82.777076 -283.549852) (xy 82.777071 -283.550106)
			(xy 83.094334 -283.550106) (xy 83.098294 -283.501052) (xy 83.110071 -283.453268) (xy 83.129362 -283.407992)
			(xy 83.155665 -283.366396) (xy 83.1883 -283.329559) (xy 83.226421 -283.298434) (xy 83.269042 -283.273827)
			(xy 83.315058 -283.256375) (xy 83.363277 -283.246531) (xy 83.412452 -283.24455) (xy 83.461307 -283.250482)
			(xy 83.508578 -283.264174) (xy 83.55304 -283.285272) (xy 83.593543 -283.313228) (xy 83.629036 -283.34732)
			(xy 83.658601 -283.386664) (xy 83.681472 -283.430241) (xy 83.697056 -283.476922) (xy 83.704951 -283.525499)
			(xy 83.705446 -283.550106) (xy 83.704951 -283.574713) (xy 83.697056 -283.62329) (xy 83.681472 -283.669971)
			(xy 83.658601 -283.713548) (xy 83.629036 -283.752892) (xy 83.593543 -283.786984) (xy 83.55304 -283.81494)
			(xy 83.508578 -283.836038) (xy 83.461307 -283.84973) (xy 83.412452 -283.855662) (xy 83.363277 -283.853681)
			(xy 83.315058 -283.843837) (xy 83.269042 -283.826385) (xy 83.226421 -283.801778) (xy 83.1883 -283.770653)
			(xy 83.155665 -283.733816) (xy 83.129362 -283.69222) (xy 83.110071 -283.646944) (xy 83.098294 -283.59916)
			(xy 83.094334 -283.550106) (xy 82.777071 -283.550106) (xy 82.776572 -283.57556) (xy 82.768529 -283.626342)
			(xy 82.752641 -283.675241) (xy 82.729298 -283.721053) (xy 82.699077 -283.762649) (xy 82.662721 -283.799005)
			(xy 82.621125 -283.829226) (xy 82.575313 -283.852569) (xy 82.526414 -283.868457) (xy 82.475632 -283.8765)
			(xy 82.424216 -283.8765) (xy 82.373434 -283.868457) (xy 82.324535 -283.852569) (xy 82.278723 -283.829226)
			(xy 82.237127 -283.799005) (xy 82.200771 -283.762649) (xy 82.17055 -283.721053) (xy 82.147207 -283.675241)
			(xy 82.131319 -283.626342) (xy 82.123276 -283.57556) (xy 81.826612 -283.57556) (xy 81.818569 -283.626342)
			(xy 81.802681 -283.675241) (xy 81.779338 -283.721053) (xy 81.749117 -283.762649) (xy 81.712761 -283.799005)
			(xy 81.671165 -283.829226) (xy 81.625353 -283.852569) (xy 81.576454 -283.868457) (xy 81.525672 -283.8765)
			(xy 81.474256 -283.8765) (xy 81.423474 -283.868457) (xy 81.374575 -283.852569) (xy 81.328763 -283.829226)
			(xy 81.287167 -283.799005) (xy 81.250811 -283.762649) (xy 81.22059 -283.721053) (xy 81.197247 -283.675241)
			(xy 81.181359 -283.626342) (xy 81.173316 -283.57556) (xy 80.854384 -283.57556) (xy 80.846668 -283.623036)
			(xy 80.831084 -283.669717) (xy 80.808213 -283.713294) (xy 80.778648 -283.752638) (xy 80.743155 -283.78673)
			(xy 80.702652 -283.814686) (xy 80.65819 -283.835784) (xy 80.610919 -283.849476) (xy 80.562064 -283.855408)
			(xy 80.512889 -283.853427) (xy 80.46467 -283.843583) (xy 80.418654 -283.826131) (xy 80.376033 -283.801524)
			(xy 80.337912 -283.770399) (xy 80.305277 -283.733562) (xy 80.278974 -283.691966) (xy 80.259683 -283.64669)
			(xy 80.247906 -283.598906) (xy 80.243946 -283.549852) (xy 79.905098 -283.549852) (xy 79.904603 -283.574459)
			(xy 79.896708 -283.623036) (xy 79.881124 -283.669717) (xy 79.858253 -283.713294) (xy 79.828688 -283.752638)
			(xy 79.793195 -283.78673) (xy 79.752692 -283.814686) (xy 79.70823 -283.835784) (xy 79.660959 -283.849476)
			(xy 79.612104 -283.855408) (xy 79.562929 -283.853427) (xy 79.51471 -283.843583) (xy 79.468694 -283.826131)
			(xy 79.426073 -283.801524) (xy 79.387952 -283.770399) (xy 79.355317 -283.733562) (xy 79.329014 -283.691966)
			(xy 79.309723 -283.64669) (xy 79.297946 -283.598906) (xy 79.293986 -283.549852) (xy 78.955138 -283.549852)
			(xy 78.954643 -283.574459) (xy 78.946748 -283.623036) (xy 78.931164 -283.669717) (xy 78.908293 -283.713294)
			(xy 78.878728 -283.752638) (xy 78.843235 -283.78673) (xy 78.802732 -283.814686) (xy 78.75827 -283.835784)
			(xy 78.710999 -283.849476) (xy 78.662144 -283.855408) (xy 78.612969 -283.853427) (xy 78.56475 -283.843583)
			(xy 78.518734 -283.826131) (xy 78.476113 -283.801524) (xy 78.437992 -283.770399) (xy 78.405357 -283.733562)
			(xy 78.379054 -283.691966) (xy 78.359763 -283.64669) (xy 78.347986 -283.598906) (xy 78.344026 -283.549852)
			(xy 78.005178 -283.549852) (xy 78.004683 -283.574459) (xy 77.996788 -283.623036) (xy 77.981204 -283.669717)
			(xy 77.958333 -283.713294) (xy 77.928768 -283.752638) (xy 77.893275 -283.78673) (xy 77.852772 -283.814686)
			(xy 77.80831 -283.835784) (xy 77.761039 -283.849476) (xy 77.712184 -283.855408) (xy 77.663009 -283.853427)
			(xy 77.61479 -283.843583) (xy 77.568774 -283.826131) (xy 77.526153 -283.801524) (xy 77.488032 -283.770399)
			(xy 77.455397 -283.733562) (xy 77.429094 -283.691966) (xy 77.409803 -283.64669) (xy 77.398026 -283.598906)
			(xy 77.394066 -283.549852) (xy 77.055218 -283.549852) (xy 77.054723 -283.574459) (xy 77.046828 -283.623036)
			(xy 77.031244 -283.669717) (xy 77.008373 -283.713294) (xy 76.978808 -283.752638) (xy 76.943315 -283.78673)
			(xy 76.902812 -283.814686) (xy 76.85835 -283.835784) (xy 76.811079 -283.849476) (xy 76.762224 -283.855408)
			(xy 76.713049 -283.853427) (xy 76.66483 -283.843583) (xy 76.618814 -283.826131) (xy 76.576193 -283.801524)
			(xy 76.538072 -283.770399) (xy 76.505437 -283.733562) (xy 76.479134 -283.691966) (xy 76.459843 -283.64669)
			(xy 76.448066 -283.598906) (xy 76.444106 -283.549852) (xy 76.127102 -283.549852) (xy 76.126598 -283.57556)
			(xy 76.118555 -283.626342) (xy 76.102667 -283.675241) (xy 76.079324 -283.721053) (xy 76.049103 -283.762649)
			(xy 76.012747 -283.799005) (xy 75.971151 -283.829226) (xy 75.925339 -283.852569) (xy 75.87644 -283.868457)
			(xy 75.825658 -283.8765) (xy 75.774242 -283.8765) (xy 75.72346 -283.868457) (xy 75.674561 -283.852569)
			(xy 75.628749 -283.829226) (xy 75.587153 -283.799005) (xy 75.550797 -283.762649) (xy 75.520576 -283.721053)
			(xy 75.497233 -283.675241) (xy 75.481345 -283.626342) (xy 75.473302 -283.57556) (xy 75.176384 -283.57556)
			(xy 75.168341 -283.626342) (xy 75.152453 -283.675241) (xy 75.12911 -283.721053) (xy 75.098889 -283.762649)
			(xy 75.062533 -283.799005) (xy 75.020937 -283.829226) (xy 74.975125 -283.852569) (xy 74.926226 -283.868457)
			(xy 74.875444 -283.8765) (xy 74.824028 -283.8765) (xy 74.773246 -283.868457) (xy 74.724347 -283.852569)
			(xy 74.678535 -283.829226) (xy 74.636939 -283.799005) (xy 74.600583 -283.762649) (xy 74.570362 -283.721053)
			(xy 74.547019 -283.675241) (xy 74.531131 -283.626342) (xy 74.523088 -283.57556) (xy 74.20441 -283.57556)
			(xy 74.196694 -283.623036) (xy 74.18111 -283.669717) (xy 74.158239 -283.713294) (xy 74.128674 -283.752638)
			(xy 74.093181 -283.78673) (xy 74.052678 -283.814686) (xy 74.008216 -283.835784) (xy 73.960945 -283.849476)
			(xy 73.91209 -283.855408) (xy 73.862915 -283.853427) (xy 73.814696 -283.843583) (xy 73.76868 -283.826131)
			(xy 73.726059 -283.801524) (xy 73.687938 -283.770399) (xy 73.655303 -283.733562) (xy 73.629 -283.691966)
			(xy 73.609709 -283.64669) (xy 73.597932 -283.598906) (xy 73.593972 -283.549852) (xy 40.899334 -283.549852)
			(xy 40.899334 -284.024832) (xy 44.619176 -284.024832) (xy 44.623136 -283.975778) (xy 44.634913 -283.927994)
			(xy 44.654204 -283.882718) (xy 44.680507 -283.841122) (xy 44.713142 -283.804285) (xy 44.751263 -283.77316)
			(xy 44.793884 -283.748553) (xy 44.8399 -283.731101) (xy 44.888119 -283.721257) (xy 44.937294 -283.719276)
			(xy 44.986149 -283.725208) (xy 45.03342 -283.7389) (xy 45.077882 -283.759998) (xy 45.118385 -283.787954)
			(xy 45.153878 -283.822046) (xy 45.183443 -283.86139) (xy 45.206314 -283.904967) (xy 45.221898 -283.951648)
			(xy 45.229793 -284.000225) (xy 45.230288 -284.024832) (xy 45.569136 -284.024832) (xy 45.573096 -283.975778)
			(xy 45.584873 -283.927994) (xy 45.604164 -283.882718) (xy 45.630467 -283.841122) (xy 45.663102 -283.804285)
			(xy 45.701223 -283.77316) (xy 45.743844 -283.748553) (xy 45.78986 -283.731101) (xy 45.838079 -283.721257)
			(xy 45.887254 -283.719276) (xy 45.936109 -283.725208) (xy 45.98338 -283.7389) (xy 46.027842 -283.759998)
			(xy 46.068345 -283.787954) (xy 46.103838 -283.822046) (xy 46.133403 -283.86139) (xy 46.156274 -283.904967)
			(xy 46.171858 -283.951648) (xy 46.179753 -284.000225) (xy 46.180248 -284.024832) (xy 46.519096 -284.024832)
			(xy 46.523056 -283.975778) (xy 46.534833 -283.927994) (xy 46.554124 -283.882718) (xy 46.580427 -283.841122)
			(xy 46.613062 -283.804285) (xy 46.651183 -283.77316) (xy 46.693804 -283.748553) (xy 46.73982 -283.731101)
			(xy 46.788039 -283.721257) (xy 46.837214 -283.719276) (xy 46.886069 -283.725208) (xy 46.93334 -283.7389)
			(xy 46.977802 -283.759998) (xy 47.018305 -283.787954) (xy 47.053798 -283.822046) (xy 47.083363 -283.86139)
			(xy 47.106234 -283.904967) (xy 47.121818 -283.951648) (xy 47.129713 -284.000225) (xy 47.130208 -284.024832)
			(xy 47.469056 -284.024832) (xy 47.473016 -283.975778) (xy 47.484793 -283.927994) (xy 47.504084 -283.882718)
			(xy 47.530387 -283.841122) (xy 47.563022 -283.804285) (xy 47.601143 -283.77316) (xy 47.643764 -283.748553)
			(xy 47.68978 -283.731101) (xy 47.737999 -283.721257) (xy 47.787174 -283.719276) (xy 47.836029 -283.725208)
			(xy 47.8833 -283.7389) (xy 47.927762 -283.759998) (xy 47.968265 -283.787954) (xy 48.003758 -283.822046)
			(xy 48.033323 -283.86139) (xy 48.056194 -283.904967) (xy 48.071778 -283.951648) (xy 48.079673 -284.000225)
			(xy 48.080168 -284.024832) (xy 48.419016 -284.024832) (xy 48.422976 -283.975778) (xy 48.434753 -283.927994)
			(xy 48.454044 -283.882718) (xy 48.480347 -283.841122) (xy 48.512982 -283.804285) (xy 48.551103 -283.77316)
			(xy 48.593724 -283.748553) (xy 48.63974 -283.731101) (xy 48.687959 -283.721257) (xy 48.737134 -283.719276)
			(xy 48.785989 -283.725208) (xy 48.83326 -283.7389) (xy 48.877722 -283.759998) (xy 48.918225 -283.787954)
			(xy 48.953718 -283.822046) (xy 48.983283 -283.86139) (xy 49.006154 -283.904967) (xy 49.021738 -283.951648)
			(xy 49.029633 -284.000225) (xy 49.030128 -284.024832) (xy 49.368976 -284.024832) (xy 49.372936 -283.975778)
			(xy 49.384713 -283.927994) (xy 49.404004 -283.882718) (xy 49.430307 -283.841122) (xy 49.462942 -283.804285)
			(xy 49.501063 -283.77316) (xy 49.543684 -283.748553) (xy 49.5897 -283.731101) (xy 49.637919 -283.721257)
			(xy 49.687094 -283.719276) (xy 49.735949 -283.725208) (xy 49.78322 -283.7389) (xy 49.827682 -283.759998)
			(xy 49.868185 -283.787954) (xy 49.903678 -283.822046) (xy 49.933243 -283.86139) (xy 49.956114 -283.904967)
			(xy 49.971698 -283.951648) (xy 49.979593 -284.000225) (xy 49.980088 -284.024832) (xy 50.31919 -284.024832)
			(xy 50.32315 -283.975778) (xy 50.334927 -283.927994) (xy 50.354218 -283.882718) (xy 50.380521 -283.841122)
			(xy 50.413156 -283.804285) (xy 50.451277 -283.77316) (xy 50.493898 -283.748553) (xy 50.539914 -283.731101)
			(xy 50.588133 -283.721257) (xy 50.637308 -283.719276) (xy 50.686163 -283.725208) (xy 50.733434 -283.7389)
			(xy 50.777896 -283.759998) (xy 50.818399 -283.787954) (xy 50.853892 -283.822046) (xy 50.883457 -283.86139)
			(xy 50.906328 -283.904967) (xy 50.921912 -283.951648) (xy 50.929807 -284.000225) (xy 50.930302 -284.024832)
			(xy 51.26915 -284.024832) (xy 51.27311 -283.975778) (xy 51.284887 -283.927994) (xy 51.304178 -283.882718)
			(xy 51.330481 -283.841122) (xy 51.363116 -283.804285) (xy 51.401237 -283.77316) (xy 51.443858 -283.748553)
			(xy 51.489874 -283.731101) (xy 51.538093 -283.721257) (xy 51.587268 -283.719276) (xy 51.636123 -283.725208)
			(xy 51.683394 -283.7389) (xy 51.727856 -283.759998) (xy 51.768359 -283.787954) (xy 51.803852 -283.822046)
			(xy 51.833417 -283.86139) (xy 51.856288 -283.904967) (xy 51.871872 -283.951648) (xy 51.879767 -284.000225)
			(xy 51.880262 -284.024832) (xy 52.21911 -284.024832) (xy 52.22307 -283.975778) (xy 52.234847 -283.927994)
			(xy 52.254138 -283.882718) (xy 52.280441 -283.841122) (xy 52.313076 -283.804285) (xy 52.351197 -283.77316)
			(xy 52.393818 -283.748553) (xy 52.439834 -283.731101) (xy 52.488053 -283.721257) (xy 52.537228 -283.719276)
			(xy 52.586083 -283.725208) (xy 52.633354 -283.7389) (xy 52.677816 -283.759998) (xy 52.718319 -283.787954)
			(xy 52.753812 -283.822046) (xy 52.783377 -283.86139) (xy 52.806248 -283.904967) (xy 52.821832 -283.951648)
			(xy 52.829727 -284.000225) (xy 52.830222 -284.024832) (xy 53.16907 -284.024832) (xy 53.17303 -283.975778)
			(xy 53.184807 -283.927994) (xy 53.204098 -283.882718) (xy 53.230401 -283.841122) (xy 53.263036 -283.804285)
			(xy 53.301157 -283.77316) (xy 53.343778 -283.748553) (xy 53.389794 -283.731101) (xy 53.438013 -283.721257)
			(xy 53.487188 -283.719276) (xy 53.536043 -283.725208) (xy 53.583314 -283.7389) (xy 53.627776 -283.759998)
			(xy 53.668279 -283.787954) (xy 53.703772 -283.822046) (xy 53.733337 -283.86139) (xy 53.756208 -283.904967)
			(xy 53.771792 -283.951648) (xy 53.779687 -284.000225) (xy 53.780182 -284.024832) (xy 54.11903 -284.024832)
			(xy 54.12299 -283.975778) (xy 54.134767 -283.927994) (xy 54.154058 -283.882718) (xy 54.180361 -283.841122)
			(xy 54.212996 -283.804285) (xy 54.251117 -283.77316) (xy 54.293738 -283.748553) (xy 54.339754 -283.731101)
			(xy 54.387973 -283.721257) (xy 54.437148 -283.719276) (xy 54.486003 -283.725208) (xy 54.533274 -283.7389)
			(xy 54.577736 -283.759998) (xy 54.618239 -283.787954) (xy 54.653732 -283.822046) (xy 54.683297 -283.86139)
			(xy 54.706168 -283.904967) (xy 54.721752 -283.951648) (xy 54.729647 -284.000225) (xy 54.730142 -284.024832)
			(xy 55.06899 -284.024832) (xy 55.07295 -283.975778) (xy 55.084727 -283.927994) (xy 55.104018 -283.882718)
			(xy 55.130321 -283.841122) (xy 55.162956 -283.804285) (xy 55.201077 -283.77316) (xy 55.243698 -283.748553)
			(xy 55.289714 -283.731101) (xy 55.337933 -283.721257) (xy 55.387108 -283.719276) (xy 55.435963 -283.725208)
			(xy 55.483234 -283.7389) (xy 55.527696 -283.759998) (xy 55.568199 -283.787954) (xy 55.603692 -283.822046)
			(xy 55.633257 -283.86139) (xy 55.656128 -283.904967) (xy 55.671712 -283.951648) (xy 55.679607 -284.000225)
			(xy 55.680102 -284.024832) (xy 56.01895 -284.024832) (xy 56.02291 -283.975778) (xy 56.034687 -283.927994)
			(xy 56.053978 -283.882718) (xy 56.080281 -283.841122) (xy 56.112916 -283.804285) (xy 56.151037 -283.77316)
			(xy 56.193658 -283.748553) (xy 56.239674 -283.731101) (xy 56.287893 -283.721257) (xy 56.337068 -283.719276)
			(xy 56.385923 -283.725208) (xy 56.433194 -283.7389) (xy 56.477656 -283.759998) (xy 56.518159 -283.787954)
			(xy 56.553652 -283.822046) (xy 56.583217 -283.86139) (xy 56.606088 -283.904967) (xy 56.621672 -283.951648)
			(xy 56.629567 -284.000225) (xy 56.630062 -284.024832) (xy 56.969164 -284.024832) (xy 56.973124 -283.975778)
			(xy 56.984901 -283.927994) (xy 57.004192 -283.882718) (xy 57.030495 -283.841122) (xy 57.06313 -283.804285)
			(xy 57.101251 -283.77316) (xy 57.143872 -283.748553) (xy 57.189888 -283.731101) (xy 57.238107 -283.721257)
			(xy 57.287282 -283.719276) (xy 57.336137 -283.725208) (xy 57.383408 -283.7389) (xy 57.42787 -283.759998)
			(xy 57.468373 -283.787954) (xy 57.503866 -283.822046) (xy 57.533431 -283.86139) (xy 57.556302 -283.904967)
			(xy 57.571886 -283.951648) (xy 57.579781 -284.000225) (xy 57.580276 -284.024832) (xy 57.919124 -284.024832)
			(xy 57.923084 -283.975778) (xy 57.934861 -283.927994) (xy 57.954152 -283.882718) (xy 57.980455 -283.841122)
			(xy 58.01309 -283.804285) (xy 58.051211 -283.77316) (xy 58.093832 -283.748553) (xy 58.139848 -283.731101)
			(xy 58.188067 -283.721257) (xy 58.237242 -283.719276) (xy 58.286097 -283.725208) (xy 58.333368 -283.7389)
			(xy 58.37783 -283.759998) (xy 58.418333 -283.787954) (xy 58.453826 -283.822046) (xy 58.483391 -283.86139)
			(xy 58.506262 -283.904967) (xy 58.521846 -283.951648) (xy 58.529741 -284.000225) (xy 58.530236 -284.024832)
			(xy 59.819044 -284.024832) (xy 59.823004 -283.975778) (xy 59.834781 -283.927994) (xy 59.854072 -283.882718)
			(xy 59.880375 -283.841122) (xy 59.91301 -283.804285) (xy 59.951131 -283.77316) (xy 59.993752 -283.748553)
			(xy 60.039768 -283.731101) (xy 60.087987 -283.721257) (xy 60.137162 -283.719276) (xy 60.186017 -283.725208)
			(xy 60.233288 -283.7389) (xy 60.27775 -283.759998) (xy 60.318253 -283.787954) (xy 60.353746 -283.822046)
			(xy 60.383311 -283.86139) (xy 60.406182 -283.904967) (xy 60.421766 -283.951648) (xy 60.429661 -284.000225)
			(xy 60.430156 -284.024832) (xy 60.769004 -284.024832) (xy 60.772964 -283.975778) (xy 60.784741 -283.927994)
			(xy 60.804032 -283.882718) (xy 60.830335 -283.841122) (xy 60.86297 -283.804285) (xy 60.901091 -283.77316)
			(xy 60.943712 -283.748553) (xy 60.989728 -283.731101) (xy 61.037947 -283.721257) (xy 61.087122 -283.719276)
			(xy 61.135977 -283.725208) (xy 61.183248 -283.7389) (xy 61.22771 -283.759998) (xy 61.268213 -283.787954)
			(xy 61.303706 -283.822046) (xy 61.333271 -283.86139) (xy 61.356142 -283.904967) (xy 61.371726 -283.951648)
			(xy 61.379621 -284.000225) (xy 61.380116 -284.024832) (xy 61.718964 -284.024832) (xy 61.722924 -283.975778)
			(xy 61.734701 -283.927994) (xy 61.753992 -283.882718) (xy 61.780295 -283.841122) (xy 61.81293 -283.804285)
			(xy 61.851051 -283.77316) (xy 61.893672 -283.748553) (xy 61.939688 -283.731101) (xy 61.987907 -283.721257)
			(xy 62.037082 -283.719276) (xy 62.085937 -283.725208) (xy 62.133208 -283.7389) (xy 62.17767 -283.759998)
			(xy 62.218173 -283.787954) (xy 62.253666 -283.822046) (xy 62.283231 -283.86139) (xy 62.306102 -283.904967)
			(xy 62.321686 -283.951648) (xy 62.329581 -284.000225) (xy 62.330076 -284.024832) (xy 62.669178 -284.024832)
			(xy 62.673138 -283.975778) (xy 62.684915 -283.927994) (xy 62.704206 -283.882718) (xy 62.730509 -283.841122)
			(xy 62.763144 -283.804285) (xy 62.801265 -283.77316) (xy 62.843886 -283.748553) (xy 62.889902 -283.731101)
			(xy 62.938121 -283.721257) (xy 62.987296 -283.719276) (xy 63.036151 -283.725208) (xy 63.083422 -283.7389)
			(xy 63.127884 -283.759998) (xy 63.168387 -283.787954) (xy 63.20388 -283.822046) (xy 63.233445 -283.86139)
			(xy 63.256316 -283.904967) (xy 63.2719 -283.951648) (xy 63.279795 -284.000225) (xy 63.28029 -284.024832)
			(xy 63.619138 -284.024832) (xy 63.623098 -283.975778) (xy 63.634875 -283.927994) (xy 63.654166 -283.882718)
			(xy 63.680469 -283.841122) (xy 63.713104 -283.804285) (xy 63.751225 -283.77316) (xy 63.793846 -283.748553)
			(xy 63.839862 -283.731101) (xy 63.888081 -283.721257) (xy 63.937256 -283.719276) (xy 63.986111 -283.725208)
			(xy 64.033382 -283.7389) (xy 64.077844 -283.759998) (xy 64.118347 -283.787954) (xy 64.15384 -283.822046)
			(xy 64.183405 -283.86139) (xy 64.206276 -283.904967) (xy 64.22186 -283.951648) (xy 64.229755 -284.000225)
			(xy 64.23025 -284.024832) (xy 64.569098 -284.024832) (xy 64.573058 -283.975778) (xy 64.584835 -283.927994)
			(xy 64.604126 -283.882718) (xy 64.630429 -283.841122) (xy 64.663064 -283.804285) (xy 64.701185 -283.77316)
			(xy 64.743806 -283.748553) (xy 64.789822 -283.731101) (xy 64.838041 -283.721257) (xy 64.887216 -283.719276)
			(xy 64.936071 -283.725208) (xy 64.983342 -283.7389) (xy 65.027804 -283.759998) (xy 65.068307 -283.787954)
			(xy 65.1038 -283.822046) (xy 65.133365 -283.86139) (xy 65.156236 -283.904967) (xy 65.17182 -283.951648)
			(xy 65.179715 -284.000225) (xy 65.18021 -284.024832) (xy 65.519058 -284.024832) (xy 65.523018 -283.975778)
			(xy 65.534795 -283.927994) (xy 65.554086 -283.882718) (xy 65.580389 -283.841122) (xy 65.613024 -283.804285)
			(xy 65.651145 -283.77316) (xy 65.693766 -283.748553) (xy 65.739782 -283.731101) (xy 65.788001 -283.721257)
			(xy 65.837176 -283.719276) (xy 65.886031 -283.725208) (xy 65.933302 -283.7389) (xy 65.977764 -283.759998)
			(xy 66.018267 -283.787954) (xy 66.05376 -283.822046) (xy 66.083325 -283.86139) (xy 66.106196 -283.904967)
			(xy 66.12178 -283.951648) (xy 66.129675 -284.000225) (xy 66.13017 -284.024832) (xy 66.469018 -284.024832)
			(xy 66.472978 -283.975778) (xy 66.484755 -283.927994) (xy 66.504046 -283.882718) (xy 66.530349 -283.841122)
			(xy 66.562984 -283.804285) (xy 66.601105 -283.77316) (xy 66.643726 -283.748553) (xy 66.689742 -283.731101)
			(xy 66.737961 -283.721257) (xy 66.787136 -283.719276) (xy 66.835991 -283.725208) (xy 66.883262 -283.7389)
			(xy 66.927724 -283.759998) (xy 66.968227 -283.787954) (xy 67.00372 -283.822046) (xy 67.033285 -283.86139)
			(xy 67.056156 -283.904967) (xy 67.07174 -283.951648) (xy 67.079635 -284.000225) (xy 67.08013 -284.024832)
			(xy 68.368938 -284.024832) (xy 68.372898 -283.975778) (xy 68.384675 -283.927994) (xy 68.403966 -283.882718)
			(xy 68.430269 -283.841122) (xy 68.462904 -283.804285) (xy 68.501025 -283.77316) (xy 68.543646 -283.748553)
			(xy 68.589662 -283.731101) (xy 68.637881 -283.721257) (xy 68.687056 -283.719276) (xy 68.735911 -283.725208)
			(xy 68.783182 -283.7389) (xy 68.827644 -283.759998) (xy 68.868147 -283.787954) (xy 68.90364 -283.822046)
			(xy 68.933205 -283.86139) (xy 68.956076 -283.904967) (xy 68.97166 -283.951648) (xy 68.979555 -284.000225)
			(xy 68.98005 -284.024832) (xy 69.319152 -284.024832) (xy 69.323112 -283.975778) (xy 69.334889 -283.927994)
			(xy 69.35418 -283.882718) (xy 69.380483 -283.841122) (xy 69.413118 -283.804285) (xy 69.451239 -283.77316)
			(xy 69.49386 -283.748553) (xy 69.539876 -283.731101) (xy 69.588095 -283.721257) (xy 69.63727 -283.719276)
			(xy 69.686125 -283.725208) (xy 69.733396 -283.7389) (xy 69.777858 -283.759998) (xy 69.818361 -283.787954)
			(xy 69.853854 -283.822046) (xy 69.883419 -283.86139) (xy 69.90629 -283.904967) (xy 69.921874 -283.951648)
			(xy 69.929769 -284.000225) (xy 69.930264 -284.024832) (xy 70.269112 -284.024832) (xy 70.273072 -283.975778)
			(xy 70.284849 -283.927994) (xy 70.30414 -283.882718) (xy 70.330443 -283.841122) (xy 70.363078 -283.804285)
			(xy 70.401199 -283.77316) (xy 70.44382 -283.748553) (xy 70.489836 -283.731101) (xy 70.538055 -283.721257)
			(xy 70.58723 -283.719276) (xy 70.636085 -283.725208) (xy 70.683356 -283.7389) (xy 70.727818 -283.759998)
			(xy 70.768321 -283.787954) (xy 70.803814 -283.822046) (xy 70.833379 -283.86139) (xy 70.85625 -283.904967)
			(xy 70.871834 -283.951648) (xy 70.879729 -284.000225) (xy 70.880224 -284.024832) (xy 70.879729 -284.049439)
			(xy 70.871834 -284.098016) (xy 70.85625 -284.144697) (xy 70.833379 -284.188274) (xy 70.803814 -284.227618)
			(xy 70.768321 -284.26171) (xy 70.727818 -284.289666) (xy 70.683356 -284.310764) (xy 70.636085 -284.324456)
			(xy 70.58723 -284.330388) (xy 70.538055 -284.328407) (xy 70.489836 -284.318563) (xy 70.44382 -284.301111)
			(xy 70.401199 -284.276504) (xy 70.363078 -284.245379) (xy 70.330443 -284.208542) (xy 70.30414 -284.166946)
			(xy 70.284849 -284.12167) (xy 70.273072 -284.073886) (xy 70.269112 -284.024832) (xy 69.930264 -284.024832)
			(xy 69.929769 -284.049439) (xy 69.921874 -284.098016) (xy 69.90629 -284.144697) (xy 69.883419 -284.188274)
			(xy 69.853854 -284.227618) (xy 69.818361 -284.26171) (xy 69.777858 -284.289666) (xy 69.733396 -284.310764)
			(xy 69.686125 -284.324456) (xy 69.63727 -284.330388) (xy 69.588095 -284.328407) (xy 69.539876 -284.318563)
			(xy 69.49386 -284.301111) (xy 69.451239 -284.276504) (xy 69.413118 -284.245379) (xy 69.380483 -284.208542)
			(xy 69.35418 -284.166946) (xy 69.334889 -284.12167) (xy 69.323112 -284.073886) (xy 69.319152 -284.024832)
			(xy 68.98005 -284.024832) (xy 68.979555 -284.049439) (xy 68.97166 -284.098016) (xy 68.956076 -284.144697)
			(xy 68.933205 -284.188274) (xy 68.90364 -284.227618) (xy 68.868147 -284.26171) (xy 68.827644 -284.289666)
			(xy 68.783182 -284.310764) (xy 68.735911 -284.324456) (xy 68.687056 -284.330388) (xy 68.637881 -284.328407)
			(xy 68.589662 -284.318563) (xy 68.543646 -284.301111) (xy 68.501025 -284.276504) (xy 68.462904 -284.245379)
			(xy 68.430269 -284.208542) (xy 68.403966 -284.166946) (xy 68.384675 -284.12167) (xy 68.372898 -284.073886)
			(xy 68.368938 -284.024832) (xy 67.08013 -284.024832) (xy 67.079635 -284.049439) (xy 67.07174 -284.098016)
			(xy 67.056156 -284.144697) (xy 67.033285 -284.188274) (xy 67.00372 -284.227618) (xy 66.968227 -284.26171)
			(xy 66.927724 -284.289666) (xy 66.883262 -284.310764) (xy 66.835991 -284.324456) (xy 66.787136 -284.330388)
			(xy 66.737961 -284.328407) (xy 66.689742 -284.318563) (xy 66.643726 -284.301111) (xy 66.601105 -284.276504)
			(xy 66.562984 -284.245379) (xy 66.530349 -284.208542) (xy 66.504046 -284.166946) (xy 66.484755 -284.12167)
			(xy 66.472978 -284.073886) (xy 66.469018 -284.024832) (xy 66.13017 -284.024832) (xy 66.129675 -284.049439)
			(xy 66.12178 -284.098016) (xy 66.106196 -284.144697) (xy 66.083325 -284.188274) (xy 66.05376 -284.227618)
			(xy 66.018267 -284.26171) (xy 65.977764 -284.289666) (xy 65.933302 -284.310764) (xy 65.886031 -284.324456)
			(xy 65.837176 -284.330388) (xy 65.788001 -284.328407) (xy 65.739782 -284.318563) (xy 65.693766 -284.301111)
			(xy 65.651145 -284.276504) (xy 65.613024 -284.245379) (xy 65.580389 -284.208542) (xy 65.554086 -284.166946)
			(xy 65.534795 -284.12167) (xy 65.523018 -284.073886) (xy 65.519058 -284.024832) (xy 65.18021 -284.024832)
			(xy 65.179715 -284.049439) (xy 65.17182 -284.098016) (xy 65.156236 -284.144697) (xy 65.133365 -284.188274)
			(xy 65.1038 -284.227618) (xy 65.068307 -284.26171) (xy 65.027804 -284.289666) (xy 64.983342 -284.310764)
			(xy 64.936071 -284.324456) (xy 64.887216 -284.330388) (xy 64.838041 -284.328407) (xy 64.789822 -284.318563)
			(xy 64.743806 -284.301111) (xy 64.701185 -284.276504) (xy 64.663064 -284.245379) (xy 64.630429 -284.208542)
			(xy 64.604126 -284.166946) (xy 64.584835 -284.12167) (xy 64.573058 -284.073886) (xy 64.569098 -284.024832)
			(xy 64.23025 -284.024832) (xy 64.229755 -284.049439) (xy 64.22186 -284.098016) (xy 64.206276 -284.144697)
			(xy 64.183405 -284.188274) (xy 64.15384 -284.227618) (xy 64.118347 -284.26171) (xy 64.077844 -284.289666)
			(xy 64.033382 -284.310764) (xy 63.986111 -284.324456) (xy 63.937256 -284.330388) (xy 63.888081 -284.328407)
			(xy 63.839862 -284.318563) (xy 63.793846 -284.301111) (xy 63.751225 -284.276504) (xy 63.713104 -284.245379)
			(xy 63.680469 -284.208542) (xy 63.654166 -284.166946) (xy 63.634875 -284.12167) (xy 63.623098 -284.073886)
			(xy 63.619138 -284.024832) (xy 63.28029 -284.024832) (xy 63.279795 -284.049439) (xy 63.2719 -284.098016)
			(xy 63.256316 -284.144697) (xy 63.233445 -284.188274) (xy 63.20388 -284.227618) (xy 63.168387 -284.26171)
			(xy 63.127884 -284.289666) (xy 63.083422 -284.310764) (xy 63.036151 -284.324456) (xy 62.987296 -284.330388)
			(xy 62.938121 -284.328407) (xy 62.889902 -284.318563) (xy 62.843886 -284.301111) (xy 62.801265 -284.276504)
			(xy 62.763144 -284.245379) (xy 62.730509 -284.208542) (xy 62.704206 -284.166946) (xy 62.684915 -284.12167)
			(xy 62.673138 -284.073886) (xy 62.669178 -284.024832) (xy 62.330076 -284.024832) (xy 62.329581 -284.049439)
			(xy 62.321686 -284.098016) (xy 62.306102 -284.144697) (xy 62.283231 -284.188274) (xy 62.253666 -284.227618)
			(xy 62.218173 -284.26171) (xy 62.17767 -284.289666) (xy 62.133208 -284.310764) (xy 62.085937 -284.324456)
			(xy 62.037082 -284.330388) (xy 61.987907 -284.328407) (xy 61.939688 -284.318563) (xy 61.893672 -284.301111)
			(xy 61.851051 -284.276504) (xy 61.81293 -284.245379) (xy 61.780295 -284.208542) (xy 61.753992 -284.166946)
			(xy 61.734701 -284.12167) (xy 61.722924 -284.073886) (xy 61.718964 -284.024832) (xy 61.380116 -284.024832)
			(xy 61.379621 -284.049439) (xy 61.371726 -284.098016) (xy 61.356142 -284.144697) (xy 61.333271 -284.188274)
			(xy 61.303706 -284.227618) (xy 61.268213 -284.26171) (xy 61.22771 -284.289666) (xy 61.183248 -284.310764)
			(xy 61.135977 -284.324456) (xy 61.087122 -284.330388) (xy 61.037947 -284.328407) (xy 60.989728 -284.318563)
			(xy 60.943712 -284.301111) (xy 60.901091 -284.276504) (xy 60.86297 -284.245379) (xy 60.830335 -284.208542)
			(xy 60.804032 -284.166946) (xy 60.784741 -284.12167) (xy 60.772964 -284.073886) (xy 60.769004 -284.024832)
			(xy 60.430156 -284.024832) (xy 60.429661 -284.049439) (xy 60.421766 -284.098016) (xy 60.406182 -284.144697)
			(xy 60.383311 -284.188274) (xy 60.353746 -284.227618) (xy 60.318253 -284.26171) (xy 60.27775 -284.289666)
			(xy 60.233288 -284.310764) (xy 60.186017 -284.324456) (xy 60.137162 -284.330388) (xy 60.087987 -284.328407)
			(xy 60.039768 -284.318563) (xy 59.993752 -284.301111) (xy 59.951131 -284.276504) (xy 59.91301 -284.245379)
			(xy 59.880375 -284.208542) (xy 59.854072 -284.166946) (xy 59.834781 -284.12167) (xy 59.823004 -284.073886)
			(xy 59.819044 -284.024832) (xy 58.530236 -284.024832) (xy 58.529741 -284.049439) (xy 58.521846 -284.098016)
			(xy 58.506262 -284.144697) (xy 58.483391 -284.188274) (xy 58.453826 -284.227618) (xy 58.418333 -284.26171)
			(xy 58.37783 -284.289666) (xy 58.333368 -284.310764) (xy 58.286097 -284.324456) (xy 58.237242 -284.330388)
			(xy 58.188067 -284.328407) (xy 58.139848 -284.318563) (xy 58.093832 -284.301111) (xy 58.051211 -284.276504)
			(xy 58.01309 -284.245379) (xy 57.980455 -284.208542) (xy 57.954152 -284.166946) (xy 57.934861 -284.12167)
			(xy 57.923084 -284.073886) (xy 57.919124 -284.024832) (xy 57.580276 -284.024832) (xy 57.579781 -284.049439)
			(xy 57.571886 -284.098016) (xy 57.556302 -284.144697) (xy 57.533431 -284.188274) (xy 57.503866 -284.227618)
			(xy 57.468373 -284.26171) (xy 57.42787 -284.289666) (xy 57.383408 -284.310764) (xy 57.336137 -284.324456)
			(xy 57.287282 -284.330388) (xy 57.238107 -284.328407) (xy 57.189888 -284.318563) (xy 57.143872 -284.301111)
			(xy 57.101251 -284.276504) (xy 57.06313 -284.245379) (xy 57.030495 -284.208542) (xy 57.004192 -284.166946)
			(xy 56.984901 -284.12167) (xy 56.973124 -284.073886) (xy 56.969164 -284.024832) (xy 56.630062 -284.024832)
			(xy 56.629567 -284.049439) (xy 56.621672 -284.098016) (xy 56.606088 -284.144697) (xy 56.583217 -284.188274)
			(xy 56.553652 -284.227618) (xy 56.518159 -284.26171) (xy 56.477656 -284.289666) (xy 56.433194 -284.310764)
			(xy 56.385923 -284.324456) (xy 56.337068 -284.330388) (xy 56.287893 -284.328407) (xy 56.239674 -284.318563)
			(xy 56.193658 -284.301111) (xy 56.151037 -284.276504) (xy 56.112916 -284.245379) (xy 56.080281 -284.208542)
			(xy 56.053978 -284.166946) (xy 56.034687 -284.12167) (xy 56.02291 -284.073886) (xy 56.01895 -284.024832)
			(xy 55.680102 -284.024832) (xy 55.679607 -284.049439) (xy 55.671712 -284.098016) (xy 55.656128 -284.144697)
			(xy 55.633257 -284.188274) (xy 55.603692 -284.227618) (xy 55.568199 -284.26171) (xy 55.527696 -284.289666)
			(xy 55.483234 -284.310764) (xy 55.435963 -284.324456) (xy 55.387108 -284.330388) (xy 55.337933 -284.328407)
			(xy 55.289714 -284.318563) (xy 55.243698 -284.301111) (xy 55.201077 -284.276504) (xy 55.162956 -284.245379)
			(xy 55.130321 -284.208542) (xy 55.104018 -284.166946) (xy 55.084727 -284.12167) (xy 55.07295 -284.073886)
			(xy 55.06899 -284.024832) (xy 54.730142 -284.024832) (xy 54.729647 -284.049439) (xy 54.721752 -284.098016)
			(xy 54.706168 -284.144697) (xy 54.683297 -284.188274) (xy 54.653732 -284.227618) (xy 54.618239 -284.26171)
			(xy 54.577736 -284.289666) (xy 54.533274 -284.310764) (xy 54.486003 -284.324456) (xy 54.437148 -284.330388)
			(xy 54.387973 -284.328407) (xy 54.339754 -284.318563) (xy 54.293738 -284.301111) (xy 54.251117 -284.276504)
			(xy 54.212996 -284.245379) (xy 54.180361 -284.208542) (xy 54.154058 -284.166946) (xy 54.134767 -284.12167)
			(xy 54.12299 -284.073886) (xy 54.11903 -284.024832) (xy 53.780182 -284.024832) (xy 53.779687 -284.049439)
			(xy 53.771792 -284.098016) (xy 53.756208 -284.144697) (xy 53.733337 -284.188274) (xy 53.703772 -284.227618)
			(xy 53.668279 -284.26171) (xy 53.627776 -284.289666) (xy 53.583314 -284.310764) (xy 53.536043 -284.324456)
			(xy 53.487188 -284.330388) (xy 53.438013 -284.328407) (xy 53.389794 -284.318563) (xy 53.343778 -284.301111)
			(xy 53.301157 -284.276504) (xy 53.263036 -284.245379) (xy 53.230401 -284.208542) (xy 53.204098 -284.166946)
			(xy 53.184807 -284.12167) (xy 53.17303 -284.073886) (xy 53.16907 -284.024832) (xy 52.830222 -284.024832)
			(xy 52.829727 -284.049439) (xy 52.821832 -284.098016) (xy 52.806248 -284.144697) (xy 52.783377 -284.188274)
			(xy 52.753812 -284.227618) (xy 52.718319 -284.26171) (xy 52.677816 -284.289666) (xy 52.633354 -284.310764)
			(xy 52.586083 -284.324456) (xy 52.537228 -284.330388) (xy 52.488053 -284.328407) (xy 52.439834 -284.318563)
			(xy 52.393818 -284.301111) (xy 52.351197 -284.276504) (xy 52.313076 -284.245379) (xy 52.280441 -284.208542)
			(xy 52.254138 -284.166946) (xy 52.234847 -284.12167) (xy 52.22307 -284.073886) (xy 52.21911 -284.024832)
			(xy 51.880262 -284.024832) (xy 51.879767 -284.049439) (xy 51.871872 -284.098016) (xy 51.856288 -284.144697)
			(xy 51.833417 -284.188274) (xy 51.803852 -284.227618) (xy 51.768359 -284.26171) (xy 51.727856 -284.289666)
			(xy 51.683394 -284.310764) (xy 51.636123 -284.324456) (xy 51.587268 -284.330388) (xy 51.538093 -284.328407)
			(xy 51.489874 -284.318563) (xy 51.443858 -284.301111) (xy 51.401237 -284.276504) (xy 51.363116 -284.245379)
			(xy 51.330481 -284.208542) (xy 51.304178 -284.166946) (xy 51.284887 -284.12167) (xy 51.27311 -284.073886)
			(xy 51.26915 -284.024832) (xy 50.930302 -284.024832) (xy 50.929807 -284.049439) (xy 50.921912 -284.098016)
			(xy 50.906328 -284.144697) (xy 50.883457 -284.188274) (xy 50.853892 -284.227618) (xy 50.818399 -284.26171)
			(xy 50.777896 -284.289666) (xy 50.733434 -284.310764) (xy 50.686163 -284.324456) (xy 50.637308 -284.330388)
			(xy 50.588133 -284.328407) (xy 50.539914 -284.318563) (xy 50.493898 -284.301111) (xy 50.451277 -284.276504)
			(xy 50.413156 -284.245379) (xy 50.380521 -284.208542) (xy 50.354218 -284.166946) (xy 50.334927 -284.12167)
			(xy 50.32315 -284.073886) (xy 50.31919 -284.024832) (xy 49.980088 -284.024832) (xy 49.979593 -284.049439)
			(xy 49.971698 -284.098016) (xy 49.956114 -284.144697) (xy 49.933243 -284.188274) (xy 49.903678 -284.227618)
			(xy 49.868185 -284.26171) (xy 49.827682 -284.289666) (xy 49.78322 -284.310764) (xy 49.735949 -284.324456)
			(xy 49.687094 -284.330388) (xy 49.637919 -284.328407) (xy 49.5897 -284.318563) (xy 49.543684 -284.301111)
			(xy 49.501063 -284.276504) (xy 49.462942 -284.245379) (xy 49.430307 -284.208542) (xy 49.404004 -284.166946)
			(xy 49.384713 -284.12167) (xy 49.372936 -284.073886) (xy 49.368976 -284.024832) (xy 49.030128 -284.024832)
			(xy 49.029633 -284.049439) (xy 49.021738 -284.098016) (xy 49.006154 -284.144697) (xy 48.983283 -284.188274)
			(xy 48.953718 -284.227618) (xy 48.918225 -284.26171) (xy 48.877722 -284.289666) (xy 48.83326 -284.310764)
			(xy 48.785989 -284.324456) (xy 48.737134 -284.330388) (xy 48.687959 -284.328407) (xy 48.63974 -284.318563)
			(xy 48.593724 -284.301111) (xy 48.551103 -284.276504) (xy 48.512982 -284.245379) (xy 48.480347 -284.208542)
			(xy 48.454044 -284.166946) (xy 48.434753 -284.12167) (xy 48.422976 -284.073886) (xy 48.419016 -284.024832)
			(xy 48.080168 -284.024832) (xy 48.079673 -284.049439) (xy 48.071778 -284.098016) (xy 48.056194 -284.144697)
			(xy 48.033323 -284.188274) (xy 48.003758 -284.227618) (xy 47.968265 -284.26171) (xy 47.927762 -284.289666)
			(xy 47.8833 -284.310764) (xy 47.836029 -284.324456) (xy 47.787174 -284.330388) (xy 47.737999 -284.328407)
			(xy 47.68978 -284.318563) (xy 47.643764 -284.301111) (xy 47.601143 -284.276504) (xy 47.563022 -284.245379)
			(xy 47.530387 -284.208542) (xy 47.504084 -284.166946) (xy 47.484793 -284.12167) (xy 47.473016 -284.073886)
			(xy 47.469056 -284.024832) (xy 47.130208 -284.024832) (xy 47.129713 -284.049439) (xy 47.121818 -284.098016)
			(xy 47.106234 -284.144697) (xy 47.083363 -284.188274) (xy 47.053798 -284.227618) (xy 47.018305 -284.26171)
			(xy 46.977802 -284.289666) (xy 46.93334 -284.310764) (xy 46.886069 -284.324456) (xy 46.837214 -284.330388)
			(xy 46.788039 -284.328407) (xy 46.73982 -284.318563) (xy 46.693804 -284.301111) (xy 46.651183 -284.276504)
			(xy 46.613062 -284.245379) (xy 46.580427 -284.208542) (xy 46.554124 -284.166946) (xy 46.534833 -284.12167)
			(xy 46.523056 -284.073886) (xy 46.519096 -284.024832) (xy 46.180248 -284.024832) (xy 46.179753 -284.049439)
			(xy 46.171858 -284.098016) (xy 46.156274 -284.144697) (xy 46.133403 -284.188274) (xy 46.103838 -284.227618)
			(xy 46.068345 -284.26171) (xy 46.027842 -284.289666) (xy 45.98338 -284.310764) (xy 45.936109 -284.324456)
			(xy 45.887254 -284.330388) (xy 45.838079 -284.328407) (xy 45.78986 -284.318563) (xy 45.743844 -284.301111)
			(xy 45.701223 -284.276504) (xy 45.663102 -284.245379) (xy 45.630467 -284.208542) (xy 45.604164 -284.166946)
			(xy 45.584873 -284.12167) (xy 45.573096 -284.073886) (xy 45.569136 -284.024832) (xy 45.230288 -284.024832)
			(xy 45.229793 -284.049439) (xy 45.221898 -284.098016) (xy 45.206314 -284.144697) (xy 45.183443 -284.188274)
			(xy 45.153878 -284.227618) (xy 45.118385 -284.26171) (xy 45.077882 -284.289666) (xy 45.03342 -284.310764)
			(xy 44.986149 -284.324456) (xy 44.937294 -284.330388) (xy 44.888119 -284.328407) (xy 44.8399 -284.318563)
			(xy 44.793884 -284.301111) (xy 44.751263 -284.276504) (xy 44.713142 -284.245379) (xy 44.680507 -284.208542)
			(xy 44.654204 -284.166946) (xy 44.634913 -284.12167) (xy 44.623136 -284.073886) (xy 44.619176 -284.024832)
			(xy 40.899334 -284.024832) (xy 40.899334 -284.499812) (xy 73.593972 -284.499812) (xy 73.597932 -284.450758)
			(xy 73.609709 -284.402974) (xy 73.629 -284.357698) (xy 73.655303 -284.316102) (xy 73.687938 -284.279265)
			(xy 73.726059 -284.24814) (xy 73.76868 -284.223533) (xy 73.814696 -284.206081) (xy 73.862915 -284.196237)
			(xy 73.91209 -284.194256) (xy 73.960945 -284.200188) (xy 74.008216 -284.21388) (xy 74.052678 -284.234978)
			(xy 74.093181 -284.262934) (xy 74.128674 -284.297026) (xy 74.158239 -284.33637) (xy 74.18111 -284.379947)
			(xy 74.196694 -284.426628) (xy 74.204589 -284.475205) (xy 74.205084 -284.499812) (xy 74.543932 -284.499812)
			(xy 74.547892 -284.450758) (xy 74.559669 -284.402974) (xy 74.57896 -284.357698) (xy 74.605263 -284.316102)
			(xy 74.637898 -284.279265) (xy 74.676019 -284.24814) (xy 74.71864 -284.223533) (xy 74.764656 -284.206081)
			(xy 74.812875 -284.196237) (xy 74.86205 -284.194256) (xy 74.910905 -284.200188) (xy 74.958176 -284.21388)
			(xy 75.002638 -284.234978) (xy 75.043141 -284.262934) (xy 75.078634 -284.297026) (xy 75.108199 -284.33637)
			(xy 75.13107 -284.379947) (xy 75.146654 -284.426628) (xy 75.154549 -284.475205) (xy 75.155044 -284.499812)
			(xy 75.494146 -284.499812) (xy 75.498106 -284.450758) (xy 75.509883 -284.402974) (xy 75.529174 -284.357698)
			(xy 75.555477 -284.316102) (xy 75.588112 -284.279265) (xy 75.626233 -284.24814) (xy 75.668854 -284.223533)
			(xy 75.71487 -284.206081) (xy 75.763089 -284.196237) (xy 75.812264 -284.194256) (xy 75.861119 -284.200188)
			(xy 75.90839 -284.21388) (xy 75.952852 -284.234978) (xy 75.993355 -284.262934) (xy 76.028848 -284.297026)
			(xy 76.058413 -284.33637) (xy 76.081284 -284.379947) (xy 76.096868 -284.426628) (xy 76.104763 -284.475205)
			(xy 76.105258 -284.499812) (xy 76.104763 -284.524419) (xy 76.104584 -284.52552) (xy 76.423262 -284.52552)
			(xy 76.423262 -284.474104) (xy 76.431305 -284.423322) (xy 76.447193 -284.374423) (xy 76.470536 -284.328611)
			(xy 76.500757 -284.287015) (xy 76.537113 -284.250659) (xy 76.578709 -284.220438) (xy 76.624521 -284.197095)
			(xy 76.67342 -284.181207) (xy 76.724202 -284.173164) (xy 76.775618 -284.173164) (xy 76.8264 -284.181207)
			(xy 76.875299 -284.197095) (xy 76.921111 -284.220438) (xy 76.962707 -284.250659) (xy 76.999063 -284.287015)
			(xy 77.029284 -284.328611) (xy 77.052627 -284.374423) (xy 77.068515 -284.423322) (xy 77.076558 -284.474104)
			(xy 77.077062 -284.499812) (xy 77.076558 -284.52552) (xy 77.373222 -284.52552) (xy 77.373222 -284.474104)
			(xy 77.381265 -284.423322) (xy 77.397153 -284.374423) (xy 77.420496 -284.328611) (xy 77.450717 -284.287015)
			(xy 77.487073 -284.250659) (xy 77.528669 -284.220438) (xy 77.574481 -284.197095) (xy 77.62338 -284.181207)
			(xy 77.674162 -284.173164) (xy 77.725578 -284.173164) (xy 77.77636 -284.181207) (xy 77.825259 -284.197095)
			(xy 77.871071 -284.220438) (xy 77.912667 -284.250659) (xy 77.949023 -284.287015) (xy 77.979244 -284.328611)
			(xy 78.002587 -284.374423) (xy 78.018475 -284.423322) (xy 78.026518 -284.474104) (xy 78.027022 -284.499812)
			(xy 78.344026 -284.499812) (xy 78.347986 -284.450758) (xy 78.359763 -284.402974) (xy 78.379054 -284.357698)
			(xy 78.405357 -284.316102) (xy 78.437992 -284.279265) (xy 78.476113 -284.24814) (xy 78.518734 -284.223533)
			(xy 78.56475 -284.206081) (xy 78.612969 -284.196237) (xy 78.662144 -284.194256) (xy 78.710999 -284.200188)
			(xy 78.75827 -284.21388) (xy 78.802732 -284.234978) (xy 78.843235 -284.262934) (xy 78.878728 -284.297026)
			(xy 78.908293 -284.33637) (xy 78.931164 -284.379947) (xy 78.946748 -284.426628) (xy 78.954643 -284.475205)
			(xy 78.955138 -284.499812) (xy 78.954643 -284.524419) (xy 78.954464 -284.52552) (xy 79.273142 -284.52552)
			(xy 79.273142 -284.474104) (xy 79.281185 -284.423322) (xy 79.297073 -284.374423) (xy 79.320416 -284.328611)
			(xy 79.350637 -284.287015) (xy 79.386993 -284.250659) (xy 79.428589 -284.220438) (xy 79.474401 -284.197095)
			(xy 79.5233 -284.181207) (xy 79.574082 -284.173164) (xy 79.625498 -284.173164) (xy 79.67628 -284.181207)
			(xy 79.725179 -284.197095) (xy 79.770991 -284.220438) (xy 79.812587 -284.250659) (xy 79.848943 -284.287015)
			(xy 79.879164 -284.328611) (xy 79.902507 -284.374423) (xy 79.918395 -284.423322) (xy 79.926438 -284.474104)
			(xy 79.926942 -284.499812) (xy 79.926438 -284.52552) (xy 80.223102 -284.52552) (xy 80.223102 -284.474104)
			(xy 80.231145 -284.423322) (xy 80.247033 -284.374423) (xy 80.270376 -284.328611) (xy 80.300597 -284.287015)
			(xy 80.336953 -284.250659) (xy 80.378549 -284.220438) (xy 80.424361 -284.197095) (xy 80.47326 -284.181207)
			(xy 80.524042 -284.173164) (xy 80.575458 -284.173164) (xy 80.62624 -284.181207) (xy 80.675139 -284.197095)
			(xy 80.720951 -284.220438) (xy 80.762547 -284.250659) (xy 80.798903 -284.287015) (xy 80.829124 -284.328611)
			(xy 80.852467 -284.374423) (xy 80.868355 -284.423322) (xy 80.876398 -284.474104) (xy 80.876902 -284.499812)
			(xy 81.19416 -284.499812) (xy 81.19812 -284.450758) (xy 81.209897 -284.402974) (xy 81.229188 -284.357698)
			(xy 81.255491 -284.316102) (xy 81.288126 -284.279265) (xy 81.326247 -284.24814) (xy 81.368868 -284.223533)
			(xy 81.414884 -284.206081) (xy 81.463103 -284.196237) (xy 81.512278 -284.194256) (xy 81.561133 -284.200188)
			(xy 81.608404 -284.21388) (xy 81.652866 -284.234978) (xy 81.693369 -284.262934) (xy 81.728862 -284.297026)
			(xy 81.758427 -284.33637) (xy 81.781298 -284.379947) (xy 81.796882 -284.426628) (xy 81.804777 -284.475205)
			(xy 81.805272 -284.499812) (xy 82.14412 -284.499812) (xy 82.14808 -284.450758) (xy 82.159857 -284.402974)
			(xy 82.179148 -284.357698) (xy 82.205451 -284.316102) (xy 82.238086 -284.279265) (xy 82.276207 -284.24814)
			(xy 82.318828 -284.223533) (xy 82.364844 -284.206081) (xy 82.413063 -284.196237) (xy 82.462238 -284.194256)
			(xy 82.511093 -284.200188) (xy 82.558364 -284.21388) (xy 82.602826 -284.234978) (xy 82.643329 -284.262934)
			(xy 82.678822 -284.297026) (xy 82.708387 -284.33637) (xy 82.731258 -284.379947) (xy 82.746842 -284.426628)
			(xy 82.754737 -284.475205) (xy 82.755232 -284.499812) (xy 82.754737 -284.524419) (xy 82.746842 -284.572996)
			(xy 82.731258 -284.619677) (xy 82.708387 -284.663254) (xy 82.678822 -284.702598) (xy 82.643329 -284.73669)
			(xy 82.602826 -284.764646) (xy 82.558364 -284.785744) (xy 82.511093 -284.799436) (xy 82.462238 -284.805368)
			(xy 82.413063 -284.803387) (xy 82.364844 -284.793543) (xy 82.318828 -284.776091) (xy 82.276207 -284.751484)
			(xy 82.238086 -284.720359) (xy 82.205451 -284.683522) (xy 82.179148 -284.641926) (xy 82.159857 -284.59665)
			(xy 82.14808 -284.548866) (xy 82.14412 -284.499812) (xy 81.805272 -284.499812) (xy 81.804777 -284.524419)
			(xy 81.796882 -284.572996) (xy 81.781298 -284.619677) (xy 81.758427 -284.663254) (xy 81.728862 -284.702598)
			(xy 81.693369 -284.73669) (xy 81.652866 -284.764646) (xy 81.608404 -284.785744) (xy 81.561133 -284.799436)
			(xy 81.512278 -284.805368) (xy 81.463103 -284.803387) (xy 81.414884 -284.793543) (xy 81.368868 -284.776091)
			(xy 81.326247 -284.751484) (xy 81.288126 -284.720359) (xy 81.255491 -284.683522) (xy 81.229188 -284.641926)
			(xy 81.209897 -284.59665) (xy 81.19812 -284.548866) (xy 81.19416 -284.499812) (xy 80.876902 -284.499812)
			(xy 80.876398 -284.52552) (xy 80.868355 -284.576302) (xy 80.852467 -284.625201) (xy 80.829124 -284.671013)
			(xy 80.798903 -284.712609) (xy 80.762547 -284.748965) (xy 80.720951 -284.779186) (xy 80.675139 -284.802529)
			(xy 80.62624 -284.818417) (xy 80.575458 -284.82646) (xy 80.524042 -284.82646) (xy 80.47326 -284.818417)
			(xy 80.424361 -284.802529) (xy 80.378549 -284.779186) (xy 80.336953 -284.748965) (xy 80.300597 -284.712609)
			(xy 80.270376 -284.671013) (xy 80.247033 -284.625201) (xy 80.231145 -284.576302) (xy 80.223102 -284.52552)
			(xy 79.926438 -284.52552) (xy 79.918395 -284.576302) (xy 79.902507 -284.625201) (xy 79.879164 -284.671013)
			(xy 79.848943 -284.712609) (xy 79.812587 -284.748965) (xy 79.770991 -284.779186) (xy 79.725179 -284.802529)
			(xy 79.67628 -284.818417) (xy 79.625498 -284.82646) (xy 79.574082 -284.82646) (xy 79.5233 -284.818417)
			(xy 79.474401 -284.802529) (xy 79.428589 -284.779186) (xy 79.386993 -284.748965) (xy 79.350637 -284.712609)
			(xy 79.320416 -284.671013) (xy 79.297073 -284.625201) (xy 79.281185 -284.576302) (xy 79.273142 -284.52552)
			(xy 78.954464 -284.52552) (xy 78.946748 -284.572996) (xy 78.931164 -284.619677) (xy 78.908293 -284.663254)
			(xy 78.878728 -284.702598) (xy 78.843235 -284.73669) (xy 78.802732 -284.764646) (xy 78.75827 -284.785744)
			(xy 78.710999 -284.799436) (xy 78.662144 -284.805368) (xy 78.612969 -284.803387) (xy 78.56475 -284.793543)
			(xy 78.518734 -284.776091) (xy 78.476113 -284.751484) (xy 78.437992 -284.720359) (xy 78.405357 -284.683522)
			(xy 78.379054 -284.641926) (xy 78.359763 -284.59665) (xy 78.347986 -284.548866) (xy 78.344026 -284.499812)
			(xy 78.027022 -284.499812) (xy 78.026518 -284.52552) (xy 78.018475 -284.576302) (xy 78.002587 -284.625201)
			(xy 77.979244 -284.671013) (xy 77.949023 -284.712609) (xy 77.912667 -284.748965) (xy 77.871071 -284.779186)
			(xy 77.825259 -284.802529) (xy 77.77636 -284.818417) (xy 77.725578 -284.82646) (xy 77.674162 -284.82646)
			(xy 77.62338 -284.818417) (xy 77.574481 -284.802529) (xy 77.528669 -284.779186) (xy 77.487073 -284.748965)
			(xy 77.450717 -284.712609) (xy 77.420496 -284.671013) (xy 77.397153 -284.625201) (xy 77.381265 -284.576302)
			(xy 77.373222 -284.52552) (xy 77.076558 -284.52552) (xy 77.068515 -284.576302) (xy 77.052627 -284.625201)
			(xy 77.029284 -284.671013) (xy 76.999063 -284.712609) (xy 76.962707 -284.748965) (xy 76.921111 -284.779186)
			(xy 76.875299 -284.802529) (xy 76.8264 -284.818417) (xy 76.775618 -284.82646) (xy 76.724202 -284.82646)
			(xy 76.67342 -284.818417) (xy 76.624521 -284.802529) (xy 76.578709 -284.779186) (xy 76.537113 -284.748965)
			(xy 76.500757 -284.712609) (xy 76.470536 -284.671013) (xy 76.447193 -284.625201) (xy 76.431305 -284.576302)
			(xy 76.423262 -284.52552) (xy 76.104584 -284.52552) (xy 76.096868 -284.572996) (xy 76.081284 -284.619677)
			(xy 76.058413 -284.663254) (xy 76.028848 -284.702598) (xy 75.993355 -284.73669) (xy 75.952852 -284.764646)
			(xy 75.90839 -284.785744) (xy 75.861119 -284.799436) (xy 75.812264 -284.805368) (xy 75.763089 -284.803387)
			(xy 75.71487 -284.793543) (xy 75.668854 -284.776091) (xy 75.626233 -284.751484) (xy 75.588112 -284.720359)
			(xy 75.555477 -284.683522) (xy 75.529174 -284.641926) (xy 75.509883 -284.59665) (xy 75.498106 -284.548866)
			(xy 75.494146 -284.499812) (xy 75.155044 -284.499812) (xy 75.154549 -284.524419) (xy 75.146654 -284.572996)
			(xy 75.13107 -284.619677) (xy 75.108199 -284.663254) (xy 75.078634 -284.702598) (xy 75.043141 -284.73669)
			(xy 75.002638 -284.764646) (xy 74.958176 -284.785744) (xy 74.910905 -284.799436) (xy 74.86205 -284.805368)
			(xy 74.812875 -284.803387) (xy 74.764656 -284.793543) (xy 74.71864 -284.776091) (xy 74.676019 -284.751484)
			(xy 74.637898 -284.720359) (xy 74.605263 -284.683522) (xy 74.57896 -284.641926) (xy 74.559669 -284.59665)
			(xy 74.547892 -284.548866) (xy 74.543932 -284.499812) (xy 74.205084 -284.499812) (xy 74.204589 -284.524419)
			(xy 74.196694 -284.572996) (xy 74.18111 -284.619677) (xy 74.158239 -284.663254) (xy 74.128674 -284.702598)
			(xy 74.093181 -284.73669) (xy 74.052678 -284.764646) (xy 74.008216 -284.785744) (xy 73.960945 -284.799436)
			(xy 73.91209 -284.805368) (xy 73.862915 -284.803387) (xy 73.814696 -284.793543) (xy 73.76868 -284.776091)
			(xy 73.726059 -284.751484) (xy 73.687938 -284.720359) (xy 73.655303 -284.683522) (xy 73.629 -284.641926)
			(xy 73.609709 -284.59665) (xy 73.597932 -284.548866) (xy 73.593972 -284.499812) (xy 40.899334 -284.499812)
			(xy 40.899334 -284.974792) (xy 42.719002 -284.974792) (xy 42.722962 -284.925738) (xy 42.734739 -284.877954)
			(xy 42.75403 -284.832678) (xy 42.780333 -284.791082) (xy 42.812968 -284.754245) (xy 42.851089 -284.72312)
			(xy 42.89371 -284.698513) (xy 42.939726 -284.681061) (xy 42.987945 -284.671217) (xy 43.03712 -284.669236)
			(xy 43.085975 -284.675168) (xy 43.133246 -284.68886) (xy 43.177708 -284.709958) (xy 43.218211 -284.737914)
			(xy 43.253704 -284.772006) (xy 43.283269 -284.81135) (xy 43.30614 -284.854927) (xy 43.321724 -284.901608)
			(xy 43.329619 -284.950185) (xy 43.330114 -284.974792) (xy 44.619176 -284.974792) (xy 44.623136 -284.925738)
			(xy 44.634913 -284.877954) (xy 44.654204 -284.832678) (xy 44.680507 -284.791082) (xy 44.713142 -284.754245)
			(xy 44.751263 -284.72312) (xy 44.793884 -284.698513) (xy 44.8399 -284.681061) (xy 44.888119 -284.671217)
			(xy 44.937294 -284.669236) (xy 44.986149 -284.675168) (xy 45.03342 -284.68886) (xy 45.077882 -284.709958)
			(xy 45.118385 -284.737914) (xy 45.153878 -284.772006) (xy 45.183443 -284.81135) (xy 45.206314 -284.854927)
			(xy 45.221898 -284.901608) (xy 45.229793 -284.950185) (xy 45.230288 -284.974792) (xy 45.569136 -284.974792)
			(xy 45.573096 -284.925738) (xy 45.584873 -284.877954) (xy 45.604164 -284.832678) (xy 45.630467 -284.791082)
			(xy 45.663102 -284.754245) (xy 45.701223 -284.72312) (xy 45.743844 -284.698513) (xy 45.78986 -284.681061)
			(xy 45.838079 -284.671217) (xy 45.887254 -284.669236) (xy 45.936109 -284.675168) (xy 45.98338 -284.68886)
			(xy 46.027842 -284.709958) (xy 46.068345 -284.737914) (xy 46.103838 -284.772006) (xy 46.133403 -284.81135)
			(xy 46.156274 -284.854927) (xy 46.171858 -284.901608) (xy 46.179753 -284.950185) (xy 46.180248 -284.974792)
			(xy 46.519096 -284.974792) (xy 46.523056 -284.925738) (xy 46.534833 -284.877954) (xy 46.554124 -284.832678)
			(xy 46.580427 -284.791082) (xy 46.613062 -284.754245) (xy 46.651183 -284.72312) (xy 46.693804 -284.698513)
			(xy 46.73982 -284.681061) (xy 46.788039 -284.671217) (xy 46.837214 -284.669236) (xy 46.886069 -284.675168)
			(xy 46.93334 -284.68886) (xy 46.977802 -284.709958) (xy 47.018305 -284.737914) (xy 47.053798 -284.772006)
			(xy 47.083363 -284.81135) (xy 47.106234 -284.854927) (xy 47.121818 -284.901608) (xy 47.129713 -284.950185)
			(xy 47.130208 -284.974792) (xy 47.469056 -284.974792) (xy 47.473016 -284.925738) (xy 47.484793 -284.877954)
			(xy 47.504084 -284.832678) (xy 47.530387 -284.791082) (xy 47.563022 -284.754245) (xy 47.601143 -284.72312)
			(xy 47.643764 -284.698513) (xy 47.68978 -284.681061) (xy 47.737999 -284.671217) (xy 47.787174 -284.669236)
			(xy 47.836029 -284.675168) (xy 47.8833 -284.68886) (xy 47.927762 -284.709958) (xy 47.968265 -284.737914)
			(xy 48.003758 -284.772006) (xy 48.033323 -284.81135) (xy 48.056194 -284.854927) (xy 48.071778 -284.901608)
			(xy 48.079673 -284.950185) (xy 48.080168 -284.974792) (xy 48.419016 -284.974792) (xy 48.422976 -284.925738)
			(xy 48.434753 -284.877954) (xy 48.454044 -284.832678) (xy 48.480347 -284.791082) (xy 48.512982 -284.754245)
			(xy 48.551103 -284.72312) (xy 48.593724 -284.698513) (xy 48.63974 -284.681061) (xy 48.687959 -284.671217)
			(xy 48.737134 -284.669236) (xy 48.785989 -284.675168) (xy 48.83326 -284.68886) (xy 48.877722 -284.709958)
			(xy 48.918225 -284.737914) (xy 48.953718 -284.772006) (xy 48.983283 -284.81135) (xy 49.006154 -284.854927)
			(xy 49.021738 -284.901608) (xy 49.029633 -284.950185) (xy 49.030128 -284.974792) (xy 49.368976 -284.974792)
			(xy 49.372936 -284.925738) (xy 49.384713 -284.877954) (xy 49.404004 -284.832678) (xy 49.430307 -284.791082)
			(xy 49.462942 -284.754245) (xy 49.501063 -284.72312) (xy 49.543684 -284.698513) (xy 49.5897 -284.681061)
			(xy 49.637919 -284.671217) (xy 49.687094 -284.669236) (xy 49.735949 -284.675168) (xy 49.78322 -284.68886)
			(xy 49.827682 -284.709958) (xy 49.868185 -284.737914) (xy 49.903678 -284.772006) (xy 49.933243 -284.81135)
			(xy 49.956114 -284.854927) (xy 49.971698 -284.901608) (xy 49.979593 -284.950185) (xy 49.980088 -284.974792)
			(xy 50.31919 -284.974792) (xy 50.32315 -284.925738) (xy 50.334927 -284.877954) (xy 50.354218 -284.832678)
			(xy 50.380521 -284.791082) (xy 50.413156 -284.754245) (xy 50.451277 -284.72312) (xy 50.493898 -284.698513)
			(xy 50.539914 -284.681061) (xy 50.588133 -284.671217) (xy 50.637308 -284.669236) (xy 50.686163 -284.675168)
			(xy 50.733434 -284.68886) (xy 50.777896 -284.709958) (xy 50.818399 -284.737914) (xy 50.853892 -284.772006)
			(xy 50.883457 -284.81135) (xy 50.906328 -284.854927) (xy 50.921912 -284.901608) (xy 50.929807 -284.950185)
			(xy 50.930302 -284.974792) (xy 51.26915 -284.974792) (xy 51.27311 -284.925738) (xy 51.284887 -284.877954)
			(xy 51.304178 -284.832678) (xy 51.330481 -284.791082) (xy 51.363116 -284.754245) (xy 51.401237 -284.72312)
			(xy 51.443858 -284.698513) (xy 51.489874 -284.681061) (xy 51.538093 -284.671217) (xy 51.587268 -284.669236)
			(xy 51.636123 -284.675168) (xy 51.683394 -284.68886) (xy 51.727856 -284.709958) (xy 51.768359 -284.737914)
			(xy 51.803852 -284.772006) (xy 51.833417 -284.81135) (xy 51.856288 -284.854927) (xy 51.871872 -284.901608)
			(xy 51.879767 -284.950185) (xy 51.880262 -284.974792) (xy 52.21911 -284.974792) (xy 52.22307 -284.925738)
			(xy 52.234847 -284.877954) (xy 52.254138 -284.832678) (xy 52.280441 -284.791082) (xy 52.313076 -284.754245)
			(xy 52.351197 -284.72312) (xy 52.393818 -284.698513) (xy 52.439834 -284.681061) (xy 52.488053 -284.671217)
			(xy 52.537228 -284.669236) (xy 52.586083 -284.675168) (xy 52.633354 -284.68886) (xy 52.677816 -284.709958)
			(xy 52.718319 -284.737914) (xy 52.753812 -284.772006) (xy 52.783377 -284.81135) (xy 52.806248 -284.854927)
			(xy 52.821832 -284.901608) (xy 52.829727 -284.950185) (xy 52.830222 -284.974792) (xy 53.16907 -284.974792)
			(xy 53.17303 -284.925738) (xy 53.184807 -284.877954) (xy 53.204098 -284.832678) (xy 53.230401 -284.791082)
			(xy 53.263036 -284.754245) (xy 53.301157 -284.72312) (xy 53.343778 -284.698513) (xy 53.389794 -284.681061)
			(xy 53.438013 -284.671217) (xy 53.487188 -284.669236) (xy 53.536043 -284.675168) (xy 53.583314 -284.68886)
			(xy 53.627776 -284.709958) (xy 53.668279 -284.737914) (xy 53.703772 -284.772006) (xy 53.733337 -284.81135)
			(xy 53.756208 -284.854927) (xy 53.771792 -284.901608) (xy 53.779687 -284.950185) (xy 53.780182 -284.974792)
			(xy 54.11903 -284.974792) (xy 54.12299 -284.925738) (xy 54.134767 -284.877954) (xy 54.154058 -284.832678)
			(xy 54.180361 -284.791082) (xy 54.212996 -284.754245) (xy 54.251117 -284.72312) (xy 54.293738 -284.698513)
			(xy 54.339754 -284.681061) (xy 54.387973 -284.671217) (xy 54.437148 -284.669236) (xy 54.486003 -284.675168)
			(xy 54.533274 -284.68886) (xy 54.577736 -284.709958) (xy 54.618239 -284.737914) (xy 54.653732 -284.772006)
			(xy 54.683297 -284.81135) (xy 54.706168 -284.854927) (xy 54.721752 -284.901608) (xy 54.729647 -284.950185)
			(xy 54.730142 -284.974792) (xy 55.06899 -284.974792) (xy 55.07295 -284.925738) (xy 55.084727 -284.877954)
			(xy 55.104018 -284.832678) (xy 55.130321 -284.791082) (xy 55.162956 -284.754245) (xy 55.201077 -284.72312)
			(xy 55.243698 -284.698513) (xy 55.289714 -284.681061) (xy 55.337933 -284.671217) (xy 55.387108 -284.669236)
			(xy 55.435963 -284.675168) (xy 55.483234 -284.68886) (xy 55.527696 -284.709958) (xy 55.568199 -284.737914)
			(xy 55.603692 -284.772006) (xy 55.633257 -284.81135) (xy 55.656128 -284.854927) (xy 55.671712 -284.901608)
			(xy 55.679607 -284.950185) (xy 55.680102 -284.974792) (xy 56.01895 -284.974792) (xy 56.02291 -284.925738)
			(xy 56.034687 -284.877954) (xy 56.053978 -284.832678) (xy 56.080281 -284.791082) (xy 56.112916 -284.754245)
			(xy 56.151037 -284.72312) (xy 56.193658 -284.698513) (xy 56.239674 -284.681061) (xy 56.287893 -284.671217)
			(xy 56.337068 -284.669236) (xy 56.385923 -284.675168) (xy 56.433194 -284.68886) (xy 56.477656 -284.709958)
			(xy 56.518159 -284.737914) (xy 56.553652 -284.772006) (xy 56.583217 -284.81135) (xy 56.606088 -284.854927)
			(xy 56.621672 -284.901608) (xy 56.629567 -284.950185) (xy 56.630062 -284.974792) (xy 56.969164 -284.974792)
			(xy 56.973124 -284.925738) (xy 56.984901 -284.877954) (xy 57.004192 -284.832678) (xy 57.030495 -284.791082)
			(xy 57.06313 -284.754245) (xy 57.101251 -284.72312) (xy 57.143872 -284.698513) (xy 57.189888 -284.681061)
			(xy 57.238107 -284.671217) (xy 57.287282 -284.669236) (xy 57.336137 -284.675168) (xy 57.383408 -284.68886)
			(xy 57.42787 -284.709958) (xy 57.468373 -284.737914) (xy 57.503866 -284.772006) (xy 57.533431 -284.81135)
			(xy 57.556302 -284.854927) (xy 57.571886 -284.901608) (xy 57.579781 -284.950185) (xy 57.580276 -284.974792)
			(xy 57.919124 -284.974792) (xy 57.923084 -284.925738) (xy 57.934861 -284.877954) (xy 57.954152 -284.832678)
			(xy 57.980455 -284.791082) (xy 58.01309 -284.754245) (xy 58.051211 -284.72312) (xy 58.093832 -284.698513)
			(xy 58.139848 -284.681061) (xy 58.188067 -284.671217) (xy 58.237242 -284.669236) (xy 58.286097 -284.675168)
			(xy 58.333368 -284.68886) (xy 58.37783 -284.709958) (xy 58.418333 -284.737914) (xy 58.453826 -284.772006)
			(xy 58.483391 -284.81135) (xy 58.506262 -284.854927) (xy 58.521846 -284.901608) (xy 58.529741 -284.950185)
			(xy 58.530236 -284.974792) (xy 59.819044 -284.974792) (xy 59.823004 -284.925738) (xy 59.834781 -284.877954)
			(xy 59.854072 -284.832678) (xy 59.880375 -284.791082) (xy 59.91301 -284.754245) (xy 59.951131 -284.72312)
			(xy 59.993752 -284.698513) (xy 60.039768 -284.681061) (xy 60.087987 -284.671217) (xy 60.137162 -284.669236)
			(xy 60.186017 -284.675168) (xy 60.233288 -284.68886) (xy 60.27775 -284.709958) (xy 60.318253 -284.737914)
			(xy 60.353746 -284.772006) (xy 60.383311 -284.81135) (xy 60.406182 -284.854927) (xy 60.421766 -284.901608)
			(xy 60.429661 -284.950185) (xy 60.430156 -284.974792) (xy 60.769004 -284.974792) (xy 60.772964 -284.925738)
			(xy 60.784741 -284.877954) (xy 60.804032 -284.832678) (xy 60.830335 -284.791082) (xy 60.86297 -284.754245)
			(xy 60.901091 -284.72312) (xy 60.943712 -284.698513) (xy 60.989728 -284.681061) (xy 61.037947 -284.671217)
			(xy 61.087122 -284.669236) (xy 61.135977 -284.675168) (xy 61.183248 -284.68886) (xy 61.22771 -284.709958)
			(xy 61.268213 -284.737914) (xy 61.303706 -284.772006) (xy 61.333271 -284.81135) (xy 61.356142 -284.854927)
			(xy 61.371726 -284.901608) (xy 61.379621 -284.950185) (xy 61.380116 -284.974792) (xy 61.718964 -284.974792)
			(xy 61.722924 -284.925738) (xy 61.734701 -284.877954) (xy 61.753992 -284.832678) (xy 61.780295 -284.791082)
			(xy 61.81293 -284.754245) (xy 61.851051 -284.72312) (xy 61.893672 -284.698513) (xy 61.939688 -284.681061)
			(xy 61.987907 -284.671217) (xy 62.037082 -284.669236) (xy 62.085937 -284.675168) (xy 62.133208 -284.68886)
			(xy 62.17767 -284.709958) (xy 62.218173 -284.737914) (xy 62.253666 -284.772006) (xy 62.283231 -284.81135)
			(xy 62.306102 -284.854927) (xy 62.321686 -284.901608) (xy 62.329581 -284.950185) (xy 62.330076 -284.974792)
			(xy 62.669178 -284.974792) (xy 62.673138 -284.925738) (xy 62.684915 -284.877954) (xy 62.704206 -284.832678)
			(xy 62.730509 -284.791082) (xy 62.763144 -284.754245) (xy 62.801265 -284.72312) (xy 62.843886 -284.698513)
			(xy 62.889902 -284.681061) (xy 62.938121 -284.671217) (xy 62.987296 -284.669236) (xy 63.036151 -284.675168)
			(xy 63.083422 -284.68886) (xy 63.127884 -284.709958) (xy 63.168387 -284.737914) (xy 63.20388 -284.772006)
			(xy 63.233445 -284.81135) (xy 63.256316 -284.854927) (xy 63.2719 -284.901608) (xy 63.279795 -284.950185)
			(xy 63.28029 -284.974792) (xy 63.619138 -284.974792) (xy 63.623098 -284.925738) (xy 63.634875 -284.877954)
			(xy 63.654166 -284.832678) (xy 63.680469 -284.791082) (xy 63.713104 -284.754245) (xy 63.751225 -284.72312)
			(xy 63.793846 -284.698513) (xy 63.839862 -284.681061) (xy 63.888081 -284.671217) (xy 63.937256 -284.669236)
			(xy 63.986111 -284.675168) (xy 64.033382 -284.68886) (xy 64.077844 -284.709958) (xy 64.118347 -284.737914)
			(xy 64.15384 -284.772006) (xy 64.183405 -284.81135) (xy 64.206276 -284.854927) (xy 64.22186 -284.901608)
			(xy 64.229755 -284.950185) (xy 64.23025 -284.974792) (xy 64.569098 -284.974792) (xy 64.573058 -284.925738)
			(xy 64.584835 -284.877954) (xy 64.604126 -284.832678) (xy 64.630429 -284.791082) (xy 64.663064 -284.754245)
			(xy 64.701185 -284.72312) (xy 64.743806 -284.698513) (xy 64.789822 -284.681061) (xy 64.838041 -284.671217)
			(xy 64.887216 -284.669236) (xy 64.936071 -284.675168) (xy 64.983342 -284.68886) (xy 65.027804 -284.709958)
			(xy 65.068307 -284.737914) (xy 65.1038 -284.772006) (xy 65.133365 -284.81135) (xy 65.156236 -284.854927)
			(xy 65.17182 -284.901608) (xy 65.179715 -284.950185) (xy 65.18021 -284.974792) (xy 65.519058 -284.974792)
			(xy 65.523018 -284.925738) (xy 65.534795 -284.877954) (xy 65.554086 -284.832678) (xy 65.580389 -284.791082)
			(xy 65.613024 -284.754245) (xy 65.651145 -284.72312) (xy 65.693766 -284.698513) (xy 65.739782 -284.681061)
			(xy 65.788001 -284.671217) (xy 65.837176 -284.669236) (xy 65.886031 -284.675168) (xy 65.933302 -284.68886)
			(xy 65.977764 -284.709958) (xy 66.018267 -284.737914) (xy 66.05376 -284.772006) (xy 66.083325 -284.81135)
			(xy 66.106196 -284.854927) (xy 66.12178 -284.901608) (xy 66.129675 -284.950185) (xy 66.13017 -284.974792)
			(xy 66.469018 -284.974792) (xy 66.472978 -284.925738) (xy 66.484755 -284.877954) (xy 66.504046 -284.832678)
			(xy 66.530349 -284.791082) (xy 66.562984 -284.754245) (xy 66.601105 -284.72312) (xy 66.643726 -284.698513)
			(xy 66.689742 -284.681061) (xy 66.737961 -284.671217) (xy 66.787136 -284.669236) (xy 66.835991 -284.675168)
			(xy 66.883262 -284.68886) (xy 66.927724 -284.709958) (xy 66.968227 -284.737914) (xy 67.00372 -284.772006)
			(xy 67.033285 -284.81135) (xy 67.056156 -284.854927) (xy 67.07174 -284.901608) (xy 67.079635 -284.950185)
			(xy 67.08013 -284.974792) (xy 67.418978 -284.974792) (xy 67.422938 -284.925738) (xy 67.434715 -284.877954)
			(xy 67.454006 -284.832678) (xy 67.480309 -284.791082) (xy 67.512944 -284.754245) (xy 67.551065 -284.72312)
			(xy 67.593686 -284.698513) (xy 67.639702 -284.681061) (xy 67.687921 -284.671217) (xy 67.737096 -284.669236)
			(xy 67.785951 -284.675168) (xy 67.833222 -284.68886) (xy 67.877684 -284.709958) (xy 67.918187 -284.737914)
			(xy 67.95368 -284.772006) (xy 67.983245 -284.81135) (xy 68.006116 -284.854927) (xy 68.0217 -284.901608)
			(xy 68.029595 -284.950185) (xy 68.03009 -284.974792) (xy 68.368938 -284.974792) (xy 68.372898 -284.925738)
			(xy 68.384675 -284.877954) (xy 68.403966 -284.832678) (xy 68.430269 -284.791082) (xy 68.462904 -284.754245)
			(xy 68.501025 -284.72312) (xy 68.543646 -284.698513) (xy 68.589662 -284.681061) (xy 68.637881 -284.671217)
			(xy 68.687056 -284.669236) (xy 68.735911 -284.675168) (xy 68.783182 -284.68886) (xy 68.827644 -284.709958)
			(xy 68.868147 -284.737914) (xy 68.90364 -284.772006) (xy 68.933205 -284.81135) (xy 68.956076 -284.854927)
			(xy 68.97166 -284.901608) (xy 68.979555 -284.950185) (xy 68.98005 -284.974792) (xy 69.319152 -284.974792)
			(xy 69.323112 -284.925738) (xy 69.334889 -284.877954) (xy 69.35418 -284.832678) (xy 69.380483 -284.791082)
			(xy 69.413118 -284.754245) (xy 69.451239 -284.72312) (xy 69.49386 -284.698513) (xy 69.539876 -284.681061)
			(xy 69.588095 -284.671217) (xy 69.63727 -284.669236) (xy 69.686125 -284.675168) (xy 69.733396 -284.68886)
			(xy 69.777858 -284.709958) (xy 69.818361 -284.737914) (xy 69.853854 -284.772006) (xy 69.883419 -284.81135)
			(xy 69.90629 -284.854927) (xy 69.921874 -284.901608) (xy 69.929769 -284.950185) (xy 69.930264 -284.974792)
			(xy 70.269112 -284.974792) (xy 70.273072 -284.925738) (xy 70.284849 -284.877954) (xy 70.30414 -284.832678)
			(xy 70.330443 -284.791082) (xy 70.363078 -284.754245) (xy 70.401199 -284.72312) (xy 70.44382 -284.698513)
			(xy 70.489836 -284.681061) (xy 70.538055 -284.671217) (xy 70.58723 -284.669236) (xy 70.636085 -284.675168)
			(xy 70.683356 -284.68886) (xy 70.727818 -284.709958) (xy 70.768321 -284.737914) (xy 70.803814 -284.772006)
			(xy 70.833379 -284.81135) (xy 70.85625 -284.854927) (xy 70.871834 -284.901608) (xy 70.879729 -284.950185)
			(xy 70.880224 -284.974792) (xy 70.879729 -284.999399) (xy 70.871834 -285.047976) (xy 70.85625 -285.094657)
			(xy 70.833379 -285.138234) (xy 70.803814 -285.177578) (xy 70.768321 -285.21167) (xy 70.727818 -285.239626)
			(xy 70.683356 -285.260724) (xy 70.636085 -285.274416) (xy 70.58723 -285.280348) (xy 70.538055 -285.278367)
			(xy 70.489836 -285.268523) (xy 70.44382 -285.251071) (xy 70.401199 -285.226464) (xy 70.363078 -285.195339)
			(xy 70.330443 -285.158502) (xy 70.30414 -285.116906) (xy 70.284849 -285.07163) (xy 70.273072 -285.023846)
			(xy 70.269112 -284.974792) (xy 69.930264 -284.974792) (xy 69.929769 -284.999399) (xy 69.921874 -285.047976)
			(xy 69.90629 -285.094657) (xy 69.883419 -285.138234) (xy 69.853854 -285.177578) (xy 69.818361 -285.21167)
			(xy 69.777858 -285.239626) (xy 69.733396 -285.260724) (xy 69.686125 -285.274416) (xy 69.63727 -285.280348)
			(xy 69.588095 -285.278367) (xy 69.539876 -285.268523) (xy 69.49386 -285.251071) (xy 69.451239 -285.226464)
			(xy 69.413118 -285.195339) (xy 69.380483 -285.158502) (xy 69.35418 -285.116906) (xy 69.334889 -285.07163)
			(xy 69.323112 -285.023846) (xy 69.319152 -284.974792) (xy 68.98005 -284.974792) (xy 68.979555 -284.999399)
			(xy 68.97166 -285.047976) (xy 68.956076 -285.094657) (xy 68.933205 -285.138234) (xy 68.90364 -285.177578)
			(xy 68.868147 -285.21167) (xy 68.827644 -285.239626) (xy 68.783182 -285.260724) (xy 68.735911 -285.274416)
			(xy 68.687056 -285.280348) (xy 68.637881 -285.278367) (xy 68.589662 -285.268523) (xy 68.543646 -285.251071)
			(xy 68.501025 -285.226464) (xy 68.462904 -285.195339) (xy 68.430269 -285.158502) (xy 68.403966 -285.116906)
			(xy 68.384675 -285.07163) (xy 68.372898 -285.023846) (xy 68.368938 -284.974792) (xy 68.03009 -284.974792)
			(xy 68.029595 -284.999399) (xy 68.0217 -285.047976) (xy 68.006116 -285.094657) (xy 67.983245 -285.138234)
			(xy 67.95368 -285.177578) (xy 67.918187 -285.21167) (xy 67.877684 -285.239626) (xy 67.833222 -285.260724)
			(xy 67.785951 -285.274416) (xy 67.737096 -285.280348) (xy 67.687921 -285.278367) (xy 67.639702 -285.268523)
			(xy 67.593686 -285.251071) (xy 67.551065 -285.226464) (xy 67.512944 -285.195339) (xy 67.480309 -285.158502)
			(xy 67.454006 -285.116906) (xy 67.434715 -285.07163) (xy 67.422938 -285.023846) (xy 67.418978 -284.974792)
			(xy 67.08013 -284.974792) (xy 67.079635 -284.999399) (xy 67.07174 -285.047976) (xy 67.056156 -285.094657)
			(xy 67.033285 -285.138234) (xy 67.00372 -285.177578) (xy 66.968227 -285.21167) (xy 66.927724 -285.239626)
			(xy 66.883262 -285.260724) (xy 66.835991 -285.274416) (xy 66.787136 -285.280348) (xy 66.737961 -285.278367)
			(xy 66.689742 -285.268523) (xy 66.643726 -285.251071) (xy 66.601105 -285.226464) (xy 66.562984 -285.195339)
			(xy 66.530349 -285.158502) (xy 66.504046 -285.116906) (xy 66.484755 -285.07163) (xy 66.472978 -285.023846)
			(xy 66.469018 -284.974792) (xy 66.13017 -284.974792) (xy 66.129675 -284.999399) (xy 66.12178 -285.047976)
			(xy 66.106196 -285.094657) (xy 66.083325 -285.138234) (xy 66.05376 -285.177578) (xy 66.018267 -285.21167)
			(xy 65.977764 -285.239626) (xy 65.933302 -285.260724) (xy 65.886031 -285.274416) (xy 65.837176 -285.280348)
			(xy 65.788001 -285.278367) (xy 65.739782 -285.268523) (xy 65.693766 -285.251071) (xy 65.651145 -285.226464)
			(xy 65.613024 -285.195339) (xy 65.580389 -285.158502) (xy 65.554086 -285.116906) (xy 65.534795 -285.07163)
			(xy 65.523018 -285.023846) (xy 65.519058 -284.974792) (xy 65.18021 -284.974792) (xy 65.179715 -284.999399)
			(xy 65.17182 -285.047976) (xy 65.156236 -285.094657) (xy 65.133365 -285.138234) (xy 65.1038 -285.177578)
			(xy 65.068307 -285.21167) (xy 65.027804 -285.239626) (xy 64.983342 -285.260724) (xy 64.936071 -285.274416)
			(xy 64.887216 -285.280348) (xy 64.838041 -285.278367) (xy 64.789822 -285.268523) (xy 64.743806 -285.251071)
			(xy 64.701185 -285.226464) (xy 64.663064 -285.195339) (xy 64.630429 -285.158502) (xy 64.604126 -285.116906)
			(xy 64.584835 -285.07163) (xy 64.573058 -285.023846) (xy 64.569098 -284.974792) (xy 64.23025 -284.974792)
			(xy 64.229755 -284.999399) (xy 64.22186 -285.047976) (xy 64.206276 -285.094657) (xy 64.183405 -285.138234)
			(xy 64.15384 -285.177578) (xy 64.118347 -285.21167) (xy 64.077844 -285.239626) (xy 64.033382 -285.260724)
			(xy 63.986111 -285.274416) (xy 63.937256 -285.280348) (xy 63.888081 -285.278367) (xy 63.839862 -285.268523)
			(xy 63.793846 -285.251071) (xy 63.751225 -285.226464) (xy 63.713104 -285.195339) (xy 63.680469 -285.158502)
			(xy 63.654166 -285.116906) (xy 63.634875 -285.07163) (xy 63.623098 -285.023846) (xy 63.619138 -284.974792)
			(xy 63.28029 -284.974792) (xy 63.279795 -284.999399) (xy 63.2719 -285.047976) (xy 63.256316 -285.094657)
			(xy 63.233445 -285.138234) (xy 63.20388 -285.177578) (xy 63.168387 -285.21167) (xy 63.127884 -285.239626)
			(xy 63.083422 -285.260724) (xy 63.036151 -285.274416) (xy 62.987296 -285.280348) (xy 62.938121 -285.278367)
			(xy 62.889902 -285.268523) (xy 62.843886 -285.251071) (xy 62.801265 -285.226464) (xy 62.763144 -285.195339)
			(xy 62.730509 -285.158502) (xy 62.704206 -285.116906) (xy 62.684915 -285.07163) (xy 62.673138 -285.023846)
			(xy 62.669178 -284.974792) (xy 62.330076 -284.974792) (xy 62.329581 -284.999399) (xy 62.321686 -285.047976)
			(xy 62.306102 -285.094657) (xy 62.283231 -285.138234) (xy 62.253666 -285.177578) (xy 62.218173 -285.21167)
			(xy 62.17767 -285.239626) (xy 62.133208 -285.260724) (xy 62.085937 -285.274416) (xy 62.037082 -285.280348)
			(xy 61.987907 -285.278367) (xy 61.939688 -285.268523) (xy 61.893672 -285.251071) (xy 61.851051 -285.226464)
			(xy 61.81293 -285.195339) (xy 61.780295 -285.158502) (xy 61.753992 -285.116906) (xy 61.734701 -285.07163)
			(xy 61.722924 -285.023846) (xy 61.718964 -284.974792) (xy 61.380116 -284.974792) (xy 61.379621 -284.999399)
			(xy 61.371726 -285.047976) (xy 61.356142 -285.094657) (xy 61.333271 -285.138234) (xy 61.303706 -285.177578)
			(xy 61.268213 -285.21167) (xy 61.22771 -285.239626) (xy 61.183248 -285.260724) (xy 61.135977 -285.274416)
			(xy 61.087122 -285.280348) (xy 61.037947 -285.278367) (xy 60.989728 -285.268523) (xy 60.943712 -285.251071)
			(xy 60.901091 -285.226464) (xy 60.86297 -285.195339) (xy 60.830335 -285.158502) (xy 60.804032 -285.116906)
			(xy 60.784741 -285.07163) (xy 60.772964 -285.023846) (xy 60.769004 -284.974792) (xy 60.430156 -284.974792)
			(xy 60.429661 -284.999399) (xy 60.421766 -285.047976) (xy 60.406182 -285.094657) (xy 60.383311 -285.138234)
			(xy 60.353746 -285.177578) (xy 60.318253 -285.21167) (xy 60.27775 -285.239626) (xy 60.233288 -285.260724)
			(xy 60.186017 -285.274416) (xy 60.137162 -285.280348) (xy 60.087987 -285.278367) (xy 60.039768 -285.268523)
			(xy 59.993752 -285.251071) (xy 59.951131 -285.226464) (xy 59.91301 -285.195339) (xy 59.880375 -285.158502)
			(xy 59.854072 -285.116906) (xy 59.834781 -285.07163) (xy 59.823004 -285.023846) (xy 59.819044 -284.974792)
			(xy 58.530236 -284.974792) (xy 58.529741 -284.999399) (xy 58.521846 -285.047976) (xy 58.506262 -285.094657)
			(xy 58.483391 -285.138234) (xy 58.453826 -285.177578) (xy 58.418333 -285.21167) (xy 58.37783 -285.239626)
			(xy 58.333368 -285.260724) (xy 58.286097 -285.274416) (xy 58.237242 -285.280348) (xy 58.188067 -285.278367)
			(xy 58.139848 -285.268523) (xy 58.093832 -285.251071) (xy 58.051211 -285.226464) (xy 58.01309 -285.195339)
			(xy 57.980455 -285.158502) (xy 57.954152 -285.116906) (xy 57.934861 -285.07163) (xy 57.923084 -285.023846)
			(xy 57.919124 -284.974792) (xy 57.580276 -284.974792) (xy 57.579781 -284.999399) (xy 57.571886 -285.047976)
			(xy 57.556302 -285.094657) (xy 57.533431 -285.138234) (xy 57.503866 -285.177578) (xy 57.468373 -285.21167)
			(xy 57.42787 -285.239626) (xy 57.383408 -285.260724) (xy 57.336137 -285.274416) (xy 57.287282 -285.280348)
			(xy 57.238107 -285.278367) (xy 57.189888 -285.268523) (xy 57.143872 -285.251071) (xy 57.101251 -285.226464)
			(xy 57.06313 -285.195339) (xy 57.030495 -285.158502) (xy 57.004192 -285.116906) (xy 56.984901 -285.07163)
			(xy 56.973124 -285.023846) (xy 56.969164 -284.974792) (xy 56.630062 -284.974792) (xy 56.629567 -284.999399)
			(xy 56.621672 -285.047976) (xy 56.606088 -285.094657) (xy 56.583217 -285.138234) (xy 56.553652 -285.177578)
			(xy 56.518159 -285.21167) (xy 56.477656 -285.239626) (xy 56.433194 -285.260724) (xy 56.385923 -285.274416)
			(xy 56.337068 -285.280348) (xy 56.287893 -285.278367) (xy 56.239674 -285.268523) (xy 56.193658 -285.251071)
			(xy 56.151037 -285.226464) (xy 56.112916 -285.195339) (xy 56.080281 -285.158502) (xy 56.053978 -285.116906)
			(xy 56.034687 -285.07163) (xy 56.02291 -285.023846) (xy 56.01895 -284.974792) (xy 55.680102 -284.974792)
			(xy 55.679607 -284.999399) (xy 55.671712 -285.047976) (xy 55.656128 -285.094657) (xy 55.633257 -285.138234)
			(xy 55.603692 -285.177578) (xy 55.568199 -285.21167) (xy 55.527696 -285.239626) (xy 55.483234 -285.260724)
			(xy 55.435963 -285.274416) (xy 55.387108 -285.280348) (xy 55.337933 -285.278367) (xy 55.289714 -285.268523)
			(xy 55.243698 -285.251071) (xy 55.201077 -285.226464) (xy 55.162956 -285.195339) (xy 55.130321 -285.158502)
			(xy 55.104018 -285.116906) (xy 55.084727 -285.07163) (xy 55.07295 -285.023846) (xy 55.06899 -284.974792)
			(xy 54.730142 -284.974792) (xy 54.729647 -284.999399) (xy 54.721752 -285.047976) (xy 54.706168 -285.094657)
			(xy 54.683297 -285.138234) (xy 54.653732 -285.177578) (xy 54.618239 -285.21167) (xy 54.577736 -285.239626)
			(xy 54.533274 -285.260724) (xy 54.486003 -285.274416) (xy 54.437148 -285.280348) (xy 54.387973 -285.278367)
			(xy 54.339754 -285.268523) (xy 54.293738 -285.251071) (xy 54.251117 -285.226464) (xy 54.212996 -285.195339)
			(xy 54.180361 -285.158502) (xy 54.154058 -285.116906) (xy 54.134767 -285.07163) (xy 54.12299 -285.023846)
			(xy 54.11903 -284.974792) (xy 53.780182 -284.974792) (xy 53.779687 -284.999399) (xy 53.771792 -285.047976)
			(xy 53.756208 -285.094657) (xy 53.733337 -285.138234) (xy 53.703772 -285.177578) (xy 53.668279 -285.21167)
			(xy 53.627776 -285.239626) (xy 53.583314 -285.260724) (xy 53.536043 -285.274416) (xy 53.487188 -285.280348)
			(xy 53.438013 -285.278367) (xy 53.389794 -285.268523) (xy 53.343778 -285.251071) (xy 53.301157 -285.226464)
			(xy 53.263036 -285.195339) (xy 53.230401 -285.158502) (xy 53.204098 -285.116906) (xy 53.184807 -285.07163)
			(xy 53.17303 -285.023846) (xy 53.16907 -284.974792) (xy 52.830222 -284.974792) (xy 52.829727 -284.999399)
			(xy 52.821832 -285.047976) (xy 52.806248 -285.094657) (xy 52.783377 -285.138234) (xy 52.753812 -285.177578)
			(xy 52.718319 -285.21167) (xy 52.677816 -285.239626) (xy 52.633354 -285.260724) (xy 52.586083 -285.274416)
			(xy 52.537228 -285.280348) (xy 52.488053 -285.278367) (xy 52.439834 -285.268523) (xy 52.393818 -285.251071)
			(xy 52.351197 -285.226464) (xy 52.313076 -285.195339) (xy 52.280441 -285.158502) (xy 52.254138 -285.116906)
			(xy 52.234847 -285.07163) (xy 52.22307 -285.023846) (xy 52.21911 -284.974792) (xy 51.880262 -284.974792)
			(xy 51.879767 -284.999399) (xy 51.871872 -285.047976) (xy 51.856288 -285.094657) (xy 51.833417 -285.138234)
			(xy 51.803852 -285.177578) (xy 51.768359 -285.21167) (xy 51.727856 -285.239626) (xy 51.683394 -285.260724)
			(xy 51.636123 -285.274416) (xy 51.587268 -285.280348) (xy 51.538093 -285.278367) (xy 51.489874 -285.268523)
			(xy 51.443858 -285.251071) (xy 51.401237 -285.226464) (xy 51.363116 -285.195339) (xy 51.330481 -285.158502)
			(xy 51.304178 -285.116906) (xy 51.284887 -285.07163) (xy 51.27311 -285.023846) (xy 51.26915 -284.974792)
			(xy 50.930302 -284.974792) (xy 50.929807 -284.999399) (xy 50.921912 -285.047976) (xy 50.906328 -285.094657)
			(xy 50.883457 -285.138234) (xy 50.853892 -285.177578) (xy 50.818399 -285.21167) (xy 50.777896 -285.239626)
			(xy 50.733434 -285.260724) (xy 50.686163 -285.274416) (xy 50.637308 -285.280348) (xy 50.588133 -285.278367)
			(xy 50.539914 -285.268523) (xy 50.493898 -285.251071) (xy 50.451277 -285.226464) (xy 50.413156 -285.195339)
			(xy 50.380521 -285.158502) (xy 50.354218 -285.116906) (xy 50.334927 -285.07163) (xy 50.32315 -285.023846)
			(xy 50.31919 -284.974792) (xy 49.980088 -284.974792) (xy 49.979593 -284.999399) (xy 49.971698 -285.047976)
			(xy 49.956114 -285.094657) (xy 49.933243 -285.138234) (xy 49.903678 -285.177578) (xy 49.868185 -285.21167)
			(xy 49.827682 -285.239626) (xy 49.78322 -285.260724) (xy 49.735949 -285.274416) (xy 49.687094 -285.280348)
			(xy 49.637919 -285.278367) (xy 49.5897 -285.268523) (xy 49.543684 -285.251071) (xy 49.501063 -285.226464)
			(xy 49.462942 -285.195339) (xy 49.430307 -285.158502) (xy 49.404004 -285.116906) (xy 49.384713 -285.07163)
			(xy 49.372936 -285.023846) (xy 49.368976 -284.974792) (xy 49.030128 -284.974792) (xy 49.029633 -284.999399)
			(xy 49.021738 -285.047976) (xy 49.006154 -285.094657) (xy 48.983283 -285.138234) (xy 48.953718 -285.177578)
			(xy 48.918225 -285.21167) (xy 48.877722 -285.239626) (xy 48.83326 -285.260724) (xy 48.785989 -285.274416)
			(xy 48.737134 -285.280348) (xy 48.687959 -285.278367) (xy 48.63974 -285.268523) (xy 48.593724 -285.251071)
			(xy 48.551103 -285.226464) (xy 48.512982 -285.195339) (xy 48.480347 -285.158502) (xy 48.454044 -285.116906)
			(xy 48.434753 -285.07163) (xy 48.422976 -285.023846) (xy 48.419016 -284.974792) (xy 48.080168 -284.974792)
			(xy 48.079673 -284.999399) (xy 48.071778 -285.047976) (xy 48.056194 -285.094657) (xy 48.033323 -285.138234)
			(xy 48.003758 -285.177578) (xy 47.968265 -285.21167) (xy 47.927762 -285.239626) (xy 47.8833 -285.260724)
			(xy 47.836029 -285.274416) (xy 47.787174 -285.280348) (xy 47.737999 -285.278367) (xy 47.68978 -285.268523)
			(xy 47.643764 -285.251071) (xy 47.601143 -285.226464) (xy 47.563022 -285.195339) (xy 47.530387 -285.158502)
			(xy 47.504084 -285.116906) (xy 47.484793 -285.07163) (xy 47.473016 -285.023846) (xy 47.469056 -284.974792)
			(xy 47.130208 -284.974792) (xy 47.129713 -284.999399) (xy 47.121818 -285.047976) (xy 47.106234 -285.094657)
			(xy 47.083363 -285.138234) (xy 47.053798 -285.177578) (xy 47.018305 -285.21167) (xy 46.977802 -285.239626)
			(xy 46.93334 -285.260724) (xy 46.886069 -285.274416) (xy 46.837214 -285.280348) (xy 46.788039 -285.278367)
			(xy 46.73982 -285.268523) (xy 46.693804 -285.251071) (xy 46.651183 -285.226464) (xy 46.613062 -285.195339)
			(xy 46.580427 -285.158502) (xy 46.554124 -285.116906) (xy 46.534833 -285.07163) (xy 46.523056 -285.023846)
			(xy 46.519096 -284.974792) (xy 46.180248 -284.974792) (xy 46.179753 -284.999399) (xy 46.171858 -285.047976)
			(xy 46.156274 -285.094657) (xy 46.133403 -285.138234) (xy 46.103838 -285.177578) (xy 46.068345 -285.21167)
			(xy 46.027842 -285.239626) (xy 45.98338 -285.260724) (xy 45.936109 -285.274416) (xy 45.887254 -285.280348)
			(xy 45.838079 -285.278367) (xy 45.78986 -285.268523) (xy 45.743844 -285.251071) (xy 45.701223 -285.226464)
			(xy 45.663102 -285.195339) (xy 45.630467 -285.158502) (xy 45.604164 -285.116906) (xy 45.584873 -285.07163)
			(xy 45.573096 -285.023846) (xy 45.569136 -284.974792) (xy 45.230288 -284.974792) (xy 45.229793 -284.999399)
			(xy 45.221898 -285.047976) (xy 45.206314 -285.094657) (xy 45.183443 -285.138234) (xy 45.153878 -285.177578)
			(xy 45.118385 -285.21167) (xy 45.077882 -285.239626) (xy 45.03342 -285.260724) (xy 44.986149 -285.274416)
			(xy 44.937294 -285.280348) (xy 44.888119 -285.278367) (xy 44.8399 -285.268523) (xy 44.793884 -285.251071)
			(xy 44.751263 -285.226464) (xy 44.713142 -285.195339) (xy 44.680507 -285.158502) (xy 44.654204 -285.116906)
			(xy 44.634913 -285.07163) (xy 44.623136 -285.023846) (xy 44.619176 -284.974792) (xy 43.330114 -284.974792)
			(xy 43.329619 -284.999399) (xy 43.321724 -285.047976) (xy 43.30614 -285.094657) (xy 43.283269 -285.138234)
			(xy 43.253704 -285.177578) (xy 43.218211 -285.21167) (xy 43.177708 -285.239626) (xy 43.133246 -285.260724)
			(xy 43.085975 -285.274416) (xy 43.03712 -285.280348) (xy 42.987945 -285.278367) (xy 42.939726 -285.268523)
			(xy 42.89371 -285.251071) (xy 42.851089 -285.226464) (xy 42.812968 -285.195339) (xy 42.780333 -285.158502)
			(xy 42.75403 -285.116906) (xy 42.734739 -285.07163) (xy 42.722962 -285.023846) (xy 42.719002 -284.974792)
			(xy 40.899334 -284.974792) (xy 40.899334 -285.325566) (xy 40.89977 -285.33563) (xy 40.907505 -285.354214)
			(xy 40.91432 -285.361634) (xy 41.17086 -285.618174) (xy 41.183306 -285.624778) (xy 41.190418 -285.626556)
			(xy 41.213943 -285.632186) (xy 41.258966 -285.649863) (xy 41.300641 -285.674415) (xy 41.337925 -285.705229)
			(xy 41.369887 -285.741534) (xy 41.395727 -285.782423) (xy 41.414799 -285.826874) (xy 41.426627 -285.873775)
			(xy 41.429178 -285.897828) (xy 41.42994 -285.906972) (xy 41.437306 -285.922974) (xy 41.514268 -285.999682)
			(xy 41.521616 -286.006484) (xy 41.540079 -286.014194) (xy 41.550082 -286.014668) (xy 44.518072 -286.014668)
			(xy 44.527857 -286.014217) (xy 44.546009 -286.006899) (xy 44.553378 -286.000444) (xy 44.611544 -285.944056)
			(xy 44.619418 -285.926022) (xy 44.619672 -285.916116) (xy 44.620858 -285.891328) (xy 44.630261 -285.842604)
			(xy 44.647417 -285.796041) (xy 44.671875 -285.752864) (xy 44.702992 -285.714208) (xy 44.739947 -285.681091)
			(xy 44.781771 -285.654384) (xy 44.827362 -285.634789) (xy 44.87552 -285.622823) (xy 44.92498 -285.618798)
			(xy 44.97444 -285.622823) (xy 45.022598 -285.634789) (xy 45.068189 -285.654384) (xy 45.110013 -285.681091)
			(xy 45.146968 -285.714208) (xy 45.178085 -285.752864) (xy 45.202543 -285.796041) (xy 45.219699 -285.842604)
			(xy 45.229102 -285.891328) (xy 45.230288 -285.916116) (xy 45.230542 -285.926022) (xy 45.238416 -285.944056)
			(xy 45.296582 -286.000444) (xy 45.303935 -286.00692) (xy 45.322098 -286.014222) (xy 45.331888 -286.014668)
			(xy 45.468032 -286.014668) (xy 45.47782 -286.014224) (xy 45.495982 -286.006916) (xy 45.503338 -286.000444)
			(xy 45.561504 -285.944056) (xy 45.569378 -285.926022) (xy 45.569632 -285.916116) (xy 45.570818 -285.891328)
			(xy 45.580221 -285.842604) (xy 45.597377 -285.796041) (xy 45.621835 -285.752864) (xy 45.652952 -285.714208)
			(xy 45.689907 -285.681091) (xy 45.731731 -285.654384) (xy 45.777322 -285.634789) (xy 45.82548 -285.622823)
			(xy 45.87494 -285.618798) (xy 45.9244 -285.622823) (xy 45.972558 -285.634789) (xy 46.018149 -285.654384)
			(xy 46.059973 -285.681091) (xy 46.096928 -285.714208) (xy 46.128045 -285.752864) (xy 46.152503 -285.796041)
			(xy 46.169659 -285.842604) (xy 46.179062 -285.891328) (xy 46.180248 -285.916116) (xy 46.180502 -285.926022)
			(xy 46.188376 -285.944056) (xy 46.246542 -286.000444) (xy 46.253893 -286.006926) (xy 46.272056 -286.014243)
			(xy 46.281848 -286.014668) (xy 46.417992 -286.014668) (xy 46.427776 -286.014214) (xy 46.445922 -286.00689)
			(xy 46.453298 -286.000444) (xy 46.511464 -285.944056) (xy 46.519338 -285.926022) (xy 46.519592 -285.916116)
			(xy 46.520778 -285.891328) (xy 46.530181 -285.842604) (xy 46.547337 -285.796041) (xy 46.571795 -285.752864)
			(xy 46.602912 -285.714208) (xy 46.639867 -285.681091) (xy 46.681691 -285.654384) (xy 46.727282 -285.634789)
			(xy 46.77544 -285.622823) (xy 46.8249 -285.618798) (xy 46.87436 -285.622823) (xy 46.922518 -285.634789)
			(xy 46.968109 -285.654384) (xy 47.009933 -285.681091) (xy 47.046888 -285.714208) (xy 47.078005 -285.752864)
			(xy 47.102463 -285.796041) (xy 47.119619 -285.842604) (xy 47.129022 -285.891328) (xy 47.130208 -285.916116)
			(xy 47.130462 -285.926022) (xy 47.138336 -285.944056) (xy 47.196502 -286.000444) (xy 47.203851 -286.006932)
			(xy 47.222014 -286.014263) (xy 47.231808 -286.014668) (xy 47.367952 -286.014668) (xy 47.377739 -286.014221)
			(xy 47.395896 -286.006907) (xy 47.403258 -286.000444) (xy 47.461424 -285.944056) (xy 47.469298 -285.926022)
			(xy 47.469552 -285.916116) (xy 47.470738 -285.891328) (xy 47.480141 -285.842604) (xy 47.497297 -285.796041)
			(xy 47.521755 -285.752864) (xy 47.552872 -285.714208) (xy 47.589827 -285.681091) (xy 47.631651 -285.654384)
			(xy 47.677242 -285.634789) (xy 47.7254 -285.622823) (xy 47.77486 -285.618798) (xy 47.82432 -285.622823)
			(xy 47.872478 -285.634789) (xy 47.918069 -285.654384) (xy 47.959893 -285.681091) (xy 47.996848 -285.714208)
			(xy 48.027965 -285.752864) (xy 48.052423 -285.796041) (xy 48.069579 -285.842604) (xy 48.078982 -285.891328)
			(xy 48.080168 -285.916116) (xy 48.080422 -285.926022) (xy 48.088296 -285.944056) (xy 48.146462 -286.000444)
			(xy 48.153814 -286.006923) (xy 48.171977 -286.014232) (xy 48.181768 -286.014668) (xy 48.317912 -286.014668)
			(xy 48.327702 -286.014228) (xy 48.345869 -286.006924) (xy 48.353218 -286.000444) (xy 48.411384 -285.944056)
			(xy 48.419258 -285.926022) (xy 48.419512 -285.916116) (xy 48.420698 -285.891328) (xy 48.430101 -285.842604)
			(xy 48.447257 -285.796041) (xy 48.471715 -285.752864) (xy 48.502832 -285.714208) (xy 48.539787 -285.681091)
			(xy 48.581611 -285.654384) (xy 48.627202 -285.634789) (xy 48.67536 -285.622823) (xy 48.72482 -285.618798)
			(xy 48.77428 -285.622823) (xy 48.822438 -285.634789) (xy 48.868029 -285.654384) (xy 48.909853 -285.681091)
			(xy 48.946808 -285.714208) (xy 48.977925 -285.752864) (xy 49.002383 -285.796041) (xy 49.019539 -285.842604)
			(xy 49.028942 -285.891328) (xy 49.030128 -285.916116) (xy 49.030382 -285.926022) (xy 49.038256 -285.944056)
			(xy 49.096422 -286.000444) (xy 49.103772 -286.006929) (xy 49.121935 -286.014253) (xy 49.131728 -286.014668)
			(xy 49.267872 -286.014668) (xy 49.277657 -286.014217) (xy 49.295809 -286.006899) (xy 49.303178 -286.000444)
			(xy 49.361344 -285.944056) (xy 49.369218 -285.926022) (xy 49.369472 -285.916116) (xy 49.370658 -285.891328)
			(xy 49.380061 -285.842604) (xy 49.397217 -285.796041) (xy 49.421675 -285.752864) (xy 49.452792 -285.714208)
			(xy 49.489747 -285.681091) (xy 49.531571 -285.654384) (xy 49.577162 -285.634789) (xy 49.62532 -285.622823)
			(xy 49.67478 -285.618798) (xy 49.72424 -285.622823) (xy 49.772398 -285.634789) (xy 49.817989 -285.654384)
			(xy 49.859813 -285.681091) (xy 49.896768 -285.714208) (xy 49.927885 -285.752864) (xy 49.952343 -285.796041)
			(xy 49.969499 -285.842604) (xy 49.978902 -285.891328) (xy 49.980088 -285.916116) (xy 49.980342 -285.926022)
			(xy 49.988216 -285.944056) (xy 50.046382 -286.000444) (xy 50.053735 -286.00692) (xy 50.071898 -286.014222)
			(xy 50.081688 -286.014668) (xy 50.218086 -286.014668) (xy 50.22787 -286.014215) (xy 50.246018 -286.006892)
			(xy 50.253392 -286.000444) (xy 50.311558 -285.944056) (xy 50.319432 -285.926022) (xy 50.319686 -285.916116)
			(xy 50.320872 -285.891328) (xy 50.330275 -285.842604) (xy 50.347431 -285.796041) (xy 50.371889 -285.752864)
			(xy 50.403006 -285.714208) (xy 50.439961 -285.681091) (xy 50.481785 -285.654384) (xy 50.527376 -285.634789)
			(xy 50.575534 -285.622823) (xy 50.624994 -285.618798) (xy 50.674454 -285.622823) (xy 50.722612 -285.634789)
			(xy 50.768203 -285.654384) (xy 50.810027 -285.681091) (xy 50.846982 -285.714208) (xy 50.878099 -285.752864)
			(xy 50.902557 -285.796041) (xy 50.919713 -285.842604) (xy 50.929116 -285.891328) (xy 50.930302 -285.916116)
			(xy 50.930556 -285.926022) (xy 50.93843 -285.944056) (xy 50.996596 -286.000444) (xy 51.003945 -286.006933)
			(xy 51.022108 -286.014266) (xy 51.031902 -286.014668) (xy 51.168046 -286.014668) (xy 51.177833 -286.014222)
			(xy 51.195992 -286.00691) (xy 51.203352 -286.000444) (xy 51.261518 -285.944056) (xy 51.269392 -285.926022)
			(xy 51.269646 -285.916116) (xy 51.270832 -285.891328) (xy 51.280235 -285.842604) (xy 51.297391 -285.796041)
			(xy 51.321849 -285.752864) (xy 51.352966 -285.714208) (xy 51.389921 -285.681091) (xy 51.431745 -285.654384)
			(xy 51.477336 -285.634789) (xy 51.525494 -285.622823) (xy 51.574954 -285.618798) (xy 51.624414 -285.622823)
			(xy 51.672572 -285.634789) (xy 51.718163 -285.654384) (xy 51.759987 -285.681091) (xy 51.796942 -285.714208)
			(xy 51.828059 -285.752864) (xy 51.852517 -285.796041) (xy 51.869673 -285.842604) (xy 51.879076 -285.891328)
			(xy 51.880262 -285.916116) (xy 51.880516 -285.926022) (xy 51.88839 -285.944056) (xy 51.946556 -286.000444)
			(xy 51.953908 -286.006924) (xy 51.972071 -286.014235) (xy 51.981862 -286.014668) (xy 52.118006 -286.014668)
			(xy 52.127796 -286.014229) (xy 52.145965 -286.006927) (xy 52.153312 -286.000444) (xy 52.211478 -285.944056)
			(xy 52.219352 -285.926022) (xy 52.219606 -285.916116) (xy 52.220792 -285.891328) (xy 52.230195 -285.842604)
			(xy 52.247351 -285.796041) (xy 52.271809 -285.752864) (xy 52.302926 -285.714208) (xy 52.339881 -285.681091)
			(xy 52.381705 -285.654384) (xy 52.427296 -285.634789) (xy 52.475454 -285.622823) (xy 52.524914 -285.618798)
			(xy 52.574374 -285.622823) (xy 52.622532 -285.634789) (xy 52.668123 -285.654384) (xy 52.709947 -285.681091)
			(xy 52.746902 -285.714208) (xy 52.778019 -285.752864) (xy 52.802477 -285.796041) (xy 52.819633 -285.842604)
			(xy 52.829036 -285.891328) (xy 52.830222 -285.916116) (xy 52.830476 -285.926022) (xy 52.83835 -285.944056)
			(xy 52.896516 -286.000444) (xy 52.903866 -286.00693) (xy 52.922029 -286.014256) (xy 52.931822 -286.014668)
			(xy 53.067966 -286.014668) (xy 53.077752 -286.014218) (xy 53.095905 -286.006901) (xy 53.103272 -286.000444)
			(xy 53.161438 -285.944056) (xy 53.169312 -285.926022) (xy 53.169566 -285.916116) (xy 53.170752 -285.891328)
			(xy 53.180155 -285.842604) (xy 53.197311 -285.796041) (xy 53.221769 -285.752864) (xy 53.252886 -285.714208)
			(xy 53.289841 -285.681091) (xy 53.331665 -285.654384) (xy 53.377256 -285.634789) (xy 53.425414 -285.622823)
			(xy 53.474874 -285.618798) (xy 53.524334 -285.622823) (xy 53.572492 -285.634789) (xy 53.618083 -285.654384)
			(xy 53.659907 -285.681091) (xy 53.696862 -285.714208) (xy 53.727979 -285.752864) (xy 53.752437 -285.796041)
			(xy 53.769593 -285.842604) (xy 53.778996 -285.891328) (xy 53.780182 -285.916116) (xy 53.780436 -285.926022)
			(xy 53.78831 -285.944056) (xy 53.846476 -286.000444) (xy 53.853829 -286.006921) (xy 53.871992 -286.014225)
			(xy 53.881782 -286.014668) (xy 54.017926 -286.014668) (xy 54.027715 -286.014225) (xy 54.045878 -286.006918)
			(xy 54.053232 -286.000444) (xy 54.111398 -285.944056) (xy 54.119272 -285.926022) (xy 54.119526 -285.916116)
			(xy 54.120712 -285.891328) (xy 54.130115 -285.842604) (xy 54.147271 -285.796041) (xy 54.171729 -285.752864)
			(xy 54.202846 -285.714208) (xy 54.239801 -285.681091) (xy 54.281625 -285.654384) (xy 54.327216 -285.634789)
			(xy 54.375374 -285.622823) (xy 54.424834 -285.618798) (xy 54.474294 -285.622823) (xy 54.522452 -285.634789)
			(xy 54.568043 -285.654384) (xy 54.609867 -285.681091) (xy 54.646822 -285.714208) (xy 54.677939 -285.752864)
			(xy 54.702397 -285.796041) (xy 54.719553 -285.842604) (xy 54.728956 -285.891328) (xy 54.730142 -285.916116)
			(xy 54.730396 -285.926022) (xy 54.73827 -285.944056) (xy 54.796436 -286.000444) (xy 54.803787 -286.006927)
			(xy 54.82195 -286.014246) (xy 54.831742 -286.014668) (xy 54.967886 -286.014668) (xy 54.97767 -286.014215)
			(xy 54.995818 -286.006892) (xy 55.003192 -286.000444) (xy 55.061358 -285.944056) (xy 55.069232 -285.926022)
			(xy 55.069486 -285.916116) (xy 55.070672 -285.891328) (xy 55.080075 -285.842604) (xy 55.097231 -285.796041)
			(xy 55.121689 -285.752864) (xy 55.152806 -285.714208) (xy 55.189761 -285.681091) (xy 55.231585 -285.654384)
			(xy 55.277176 -285.634789) (xy 55.325334 -285.622823) (xy 55.374794 -285.618798) (xy 55.424254 -285.622823)
			(xy 55.472412 -285.634789) (xy 55.518003 -285.654384) (xy 55.559827 -285.681091) (xy 55.596782 -285.714208)
			(xy 55.627899 -285.752864) (xy 55.652357 -285.796041) (xy 55.669513 -285.842604) (xy 55.678916 -285.891328)
			(xy 55.680102 -285.916116) (xy 55.680356 -285.926022) (xy 55.68823 -285.944056) (xy 55.746396 -286.000444)
			(xy 55.753745 -286.006933) (xy 55.771908 -286.014266) (xy 55.781702 -286.014668) (xy 55.917846 -286.014668)
			(xy 55.927633 -286.014222) (xy 55.945792 -286.00691) (xy 55.953152 -286.000444) (xy 56.011318 -285.944056)
			(xy 56.019192 -285.926022) (xy 56.019446 -285.916116) (xy 56.020632 -285.891328) (xy 56.030035 -285.842604)
			(xy 56.047191 -285.796041) (xy 56.071649 -285.752864) (xy 56.102766 -285.714208) (xy 56.139721 -285.681091)
			(xy 56.181545 -285.654384) (xy 56.227136 -285.634789) (xy 56.275294 -285.622823) (xy 56.324754 -285.618798)
			(xy 56.374214 -285.622823) (xy 56.422372 -285.634789) (xy 56.467963 -285.654384) (xy 56.509787 -285.681091)
			(xy 56.546742 -285.714208) (xy 56.577859 -285.752864) (xy 56.602317 -285.796041) (xy 56.619473 -285.842604)
			(xy 56.628876 -285.891328) (xy 56.630062 -285.916116) (xy 56.630316 -285.926022) (xy 56.63819 -285.944056)
			(xy 56.696356 -286.000444) (xy 56.703708 -286.006924) (xy 56.721871 -286.014235) (xy 56.731662 -286.014668)
			(xy 56.86806 -286.014668) (xy 56.877846 -286.014219) (xy 56.896001 -286.006904) (xy 56.903366 -286.000444)
			(xy 56.961532 -285.944056) (xy 56.969406 -285.926022) (xy 56.96966 -285.916116) (xy 56.970846 -285.891328)
			(xy 56.980249 -285.842604) (xy 56.997405 -285.796041) (xy 57.021863 -285.752864) (xy 57.05298 -285.714208)
			(xy 57.089935 -285.681091) (xy 57.131759 -285.654384) (xy 57.17735 -285.634789) (xy 57.225508 -285.622823)
			(xy 57.274968 -285.618798) (xy 57.324428 -285.622823) (xy 57.372586 -285.634789) (xy 57.418177 -285.654384)
			(xy 57.460001 -285.681091) (xy 57.496956 -285.714208) (xy 57.528073 -285.752864) (xy 57.552531 -285.796041)
			(xy 57.569687 -285.842604) (xy 57.57909 -285.891328) (xy 57.580276 -285.916116) (xy 57.58053 -285.926022)
			(xy 57.588404 -285.944056) (xy 57.64657 -286.000444) (xy 57.653923 -286.006922) (xy 57.672086 -286.014228)
			(xy 57.681876 -286.014668) (xy 57.81802 -286.014668) (xy 57.827809 -286.014226) (xy 57.845974 -286.006921)
			(xy 57.853326 -286.000444) (xy 57.911492 -285.944056) (xy 57.919366 -285.926022) (xy 57.91962 -285.916116)
			(xy 57.920806 -285.891328) (xy 57.930209 -285.842604) (xy 57.947365 -285.796041) (xy 57.971823 -285.752864)
			(xy 58.00294 -285.714208) (xy 58.039895 -285.681091) (xy 58.081719 -285.654384) (xy 58.12731 -285.634789)
			(xy 58.175468 -285.622823) (xy 58.224928 -285.618798) (xy 58.274388 -285.622823) (xy 58.322546 -285.634789)
			(xy 58.368137 -285.654384) (xy 58.409961 -285.681091) (xy 58.446916 -285.714208) (xy 58.478033 -285.752864)
			(xy 58.502491 -285.796041) (xy 58.519647 -285.842604) (xy 58.52905 -285.891328) (xy 58.530236 -285.916116)
			(xy 58.53049 -285.926022) (xy 58.538364 -285.944056) (xy 58.59653 -286.000444) (xy 58.603881 -286.006928)
			(xy 58.622043 -286.014249) (xy 58.631836 -286.014668) (xy 59.71794 -286.014668) (xy 59.727728 -286.014223)
			(xy 59.745887 -286.006912) (xy 59.753246 -286.000444) (xy 59.811412 -285.944056) (xy 59.819286 -285.926022)
			(xy 59.81954 -285.916116) (xy 59.820726 -285.891328) (xy 59.830129 -285.842604) (xy 59.847285 -285.796041)
			(xy 59.871743 -285.752864) (xy 59.90286 -285.714208) (xy 59.939815 -285.681091) (xy 59.981639 -285.654384)
			(xy 60.02723 -285.634789) (xy 60.075388 -285.622823) (xy 60.124848 -285.618798) (xy 60.174308 -285.622823)
			(xy 60.222466 -285.634789) (xy 60.268057 -285.654384) (xy 60.309881 -285.681091) (xy 60.346836 -285.714208)
			(xy 60.377953 -285.752864) (xy 60.402411 -285.796041) (xy 60.419567 -285.842604) (xy 60.42897 -285.891328)
			(xy 60.430156 -285.916116) (xy 60.43041 -285.926022) (xy 60.438284 -285.944056) (xy 60.49645 -286.000444)
			(xy 60.503801 -286.006925) (xy 60.521965 -286.014239) (xy 60.531756 -286.014668) (xy 60.6679 -286.014668)
			(xy 60.677691 -286.01423) (xy 60.695861 -286.00693) (xy 60.703206 -286.000444) (xy 60.761372 -285.944056)
			(xy 60.769246 -285.926022) (xy 60.7695 -285.916116) (xy 60.770686 -285.891328) (xy 60.780089 -285.842604)
			(xy 60.797245 -285.796041) (xy 60.821703 -285.752864) (xy 60.85282 -285.714208) (xy 60.889775 -285.681091)
			(xy 60.931599 -285.654384) (xy 60.97719 -285.634789) (xy 61.025348 -285.622823) (xy 61.074808 -285.618798)
			(xy 61.124268 -285.622823) (xy 61.172426 -285.634789) (xy 61.218017 -285.654384) (xy 61.259841 -285.681091)
			(xy 61.296796 -285.714208) (xy 61.327913 -285.752864) (xy 61.352371 -285.796041) (xy 61.369527 -285.842604)
			(xy 61.37893 -285.891328) (xy 61.380116 -285.916116) (xy 61.38037 -285.926022) (xy 61.388244 -285.944056)
			(xy 61.44641 -286.000444) (xy 61.45376 -286.006931) (xy 61.471922 -286.014259) (xy 61.481716 -286.014668)
			(xy 61.61786 -286.014668) (xy 61.627646 -286.014219) (xy 61.645801 -286.006904) (xy 61.653166 -286.000444)
			(xy 61.711332 -285.944056) (xy 61.719206 -285.926022) (xy 61.71946 -285.916116) (xy 61.720646 -285.891328)
			(xy 61.730049 -285.842604) (xy 61.747205 -285.796041) (xy 61.771663 -285.752864) (xy 61.80278 -285.714208)
			(xy 61.839735 -285.681091) (xy 61.881559 -285.654384) (xy 61.92715 -285.634789) (xy 61.975308 -285.622823)
			(xy 62.024768 -285.618798) (xy 62.074228 -285.622823) (xy 62.122386 -285.634789) (xy 62.167977 -285.654384)
			(xy 62.209801 -285.681091) (xy 62.246756 -285.714208) (xy 62.277873 -285.752864) (xy 62.302331 -285.796041)
			(xy 62.319487 -285.842604) (xy 62.32889 -285.891328) (xy 62.330076 -285.916116) (xy 62.33033 -285.926022)
			(xy 62.338204 -285.944056) (xy 62.39637 -286.000444) (xy 62.403723 -286.006922) (xy 62.421886 -286.014228)
			(xy 62.431676 -286.014668) (xy 62.568074 -286.014668) (xy 62.577859 -286.014217) (xy 62.59601 -286.006898)
			(xy 62.60338 -286.000444) (xy 62.661546 -285.944056) (xy 62.66942 -285.926022) (xy 62.669674 -285.916116)
			(xy 62.67086 -285.891328) (xy 62.680263 -285.842604) (xy 62.697419 -285.796041) (xy 62.721877 -285.752864)
			(xy 62.752994 -285.714208) (xy 62.789949 -285.681091) (xy 62.831773 -285.654384) (xy 62.877364 -285.634789)
			(xy 62.925522 -285.622823) (xy 62.974982 -285.618798) (xy 63.024442 -285.622823) (xy 63.0726 -285.634789)
			(xy 63.118191 -285.654384) (xy 63.160015 -285.681091) (xy 63.19697 -285.714208) (xy 63.228087 -285.752864)
			(xy 63.252545 -285.796041) (xy 63.269701 -285.842604) (xy 63.279104 -285.891328) (xy 63.28029 -285.916116)
			(xy 63.280544 -285.926022) (xy 63.288418 -285.944056) (xy 63.346584 -286.000444) (xy 63.353937 -286.00692)
			(xy 63.3721 -286.014221) (xy 63.38189 -286.014668) (xy 63.518034 -286.014668) (xy 63.527822 -286.014224)
			(xy 63.545983 -286.006915) (xy 63.55334 -286.000444) (xy 63.611506 -285.944056) (xy 63.61938 -285.926022)
			(xy 63.619634 -285.916116) (xy 63.62082 -285.891328) (xy 63.630223 -285.842604) (xy 63.647379 -285.796041)
			(xy 63.671837 -285.752864) (xy 63.702954 -285.714208) (xy 63.739909 -285.681091) (xy 63.781733 -285.654384)
			(xy 63.827324 -285.634789) (xy 63.875482 -285.622823) (xy 63.924942 -285.618798) (xy 63.974402 -285.622823)
			(xy 64.02256 -285.634789) (xy 64.068151 -285.654384) (xy 64.109975 -285.681091) (xy 64.14693 -285.714208)
			(xy 64.178047 -285.752864) (xy 64.202505 -285.796041) (xy 64.219661 -285.842604) (xy 64.229064 -285.891328)
			(xy 64.23025 -285.916116) (xy 64.230504 -285.926022) (xy 64.238378 -285.944056) (xy 64.296544 -286.000444)
			(xy 64.303895 -286.006926) (xy 64.322058 -286.014242) (xy 64.33185 -286.014668) (xy 64.467994 -286.014668)
			(xy 64.477777 -286.014213) (xy 64.495924 -286.006889) (xy 64.5033 -286.000444) (xy 64.561466 -285.944056)
			(xy 64.56934 -285.926022) (xy 64.569594 -285.916116) (xy 64.57078 -285.891328) (xy 64.580183 -285.842604)
			(xy 64.597339 -285.796041) (xy 64.621797 -285.752864) (xy 64.652914 -285.714208) (xy 64.689869 -285.681091)
			(xy 64.731693 -285.654384) (xy 64.777284 -285.634789) (xy 64.825442 -285.622823) (xy 64.874902 -285.618798)
			(xy 64.924362 -285.622823) (xy 64.97252 -285.634789) (xy 65.018111 -285.654384) (xy 65.059935 -285.681091)
			(xy 65.09689 -285.714208) (xy 65.128007 -285.752864) (xy 65.152465 -285.796041) (xy 65.169621 -285.842604)
			(xy 65.179024 -285.891328) (xy 65.18021 -285.916116) (xy 65.180464 -285.926022) (xy 65.188338 -285.944056)
			(xy 65.246504 -286.000444) (xy 65.253853 -286.006932) (xy 65.272016 -286.014262) (xy 65.28181 -286.014668)
			(xy 65.417954 -286.014668) (xy 65.427741 -286.01422) (xy 65.445897 -286.006906) (xy 65.45326 -286.000444)
			(xy 65.511426 -285.944056) (xy 65.5193 -285.926022) (xy 65.519554 -285.916116) (xy 65.52074 -285.891328)
			(xy 65.530143 -285.842604) (xy 65.547299 -285.796041) (xy 65.571757 -285.752864) (xy 65.602874 -285.714208)
			(xy 65.639829 -285.681091) (xy 65.681653 -285.654384) (xy 65.727244 -285.634789) (xy 65.775402 -285.622823)
			(xy 65.824862 -285.618798) (xy 65.874322 -285.622823) (xy 65.92248 -285.634789) (xy 65.968071 -285.654384)
			(xy 66.009895 -285.681091) (xy 66.04685 -285.714208) (xy 66.077967 -285.752864) (xy 66.102425 -285.796041)
			(xy 66.119581 -285.842604) (xy 66.128984 -285.891328) (xy 66.13017 -285.916116) (xy 66.130424 -285.926022)
			(xy 66.138298 -285.944056) (xy 66.196464 -286.000444) (xy 66.203816 -286.006923) (xy 66.221979 -286.014231)
			(xy 66.23177 -286.014668) (xy 66.367914 -286.014668) (xy 66.377704 -286.014228) (xy 66.39587 -286.006924)
			(xy 66.40322 -286.000444) (xy 66.461386 -285.944056) (xy 66.46926 -285.926022) (xy 66.469514 -285.916116)
			(xy 66.4707 -285.891328) (xy 66.480103 -285.842604) (xy 66.497259 -285.796041) (xy 66.521717 -285.752864)
			(xy 66.552834 -285.714208) (xy 66.589789 -285.681091) (xy 66.631613 -285.654384) (xy 66.677204 -285.634789)
			(xy 66.725362 -285.622823) (xy 66.774822 -285.618798) (xy 66.824282 -285.622823) (xy 66.87244 -285.634789)
			(xy 66.918031 -285.654384) (xy 66.959855 -285.681091) (xy 66.99681 -285.714208) (xy 67.027927 -285.752864)
			(xy 67.052385 -285.796041) (xy 67.069541 -285.842604) (xy 67.078944 -285.891328) (xy 67.08013 -285.916116)
			(xy 67.080384 -285.926022) (xy 67.088258 -285.944056) (xy 67.146424 -286.000444) (xy 67.153774 -286.006929)
			(xy 67.171937 -286.014252) (xy 67.18173 -286.014668) (xy 67.317874 -286.014668) (xy 67.327659 -286.014217)
			(xy 67.34581 -286.006898) (xy 67.35318 -286.000444) (xy 67.411346 -285.944056) (xy 67.41922 -285.926022)
			(xy 67.419474 -285.916116) (xy 67.42066 -285.891328) (xy 67.430063 -285.842604) (xy 67.447219 -285.796041)
			(xy 67.471677 -285.752864) (xy 67.502794 -285.714208) (xy 67.539749 -285.681091) (xy 67.581573 -285.654384)
			(xy 67.627164 -285.634789) (xy 67.675322 -285.622823) (xy 67.724782 -285.618798) (xy 67.774242 -285.622823)
			(xy 67.8224 -285.634789) (xy 67.867991 -285.654384) (xy 67.909815 -285.681091) (xy 67.94677 -285.714208)
			(xy 67.977887 -285.752864) (xy 68.002345 -285.796041) (xy 68.019501 -285.842604) (xy 68.028904 -285.891328)
			(xy 68.03009 -285.916116) (xy 68.030344 -285.926022) (xy 68.038218 -285.944056) (xy 68.096384 -286.000444)
			(xy 68.103737 -286.00692) (xy 68.1219 -286.014221) (xy 68.13169 -286.014668) (xy 68.267834 -286.014668)
			(xy 68.277622 -286.014224) (xy 68.295783 -286.006915) (xy 68.30314 -286.000444) (xy 68.361306 -285.944056)
			(xy 68.36918 -285.926022) (xy 68.369434 -285.916116) (xy 68.37062 -285.891328) (xy 68.380023 -285.842604)
			(xy 68.397179 -285.796041) (xy 68.421637 -285.752864) (xy 68.452754 -285.714208) (xy 68.489709 -285.681091)
			(xy 68.531533 -285.654384) (xy 68.577124 -285.634789) (xy 68.625282 -285.622823) (xy 68.674742 -285.618798)
			(xy 68.724202 -285.622823) (xy 68.77236 -285.634789) (xy 68.817951 -285.654384) (xy 68.859775 -285.681091)
			(xy 68.89673 -285.714208) (xy 68.927847 -285.752864) (xy 68.952305 -285.796041) (xy 68.969461 -285.842604)
			(xy 68.978864 -285.891328) (xy 68.98005 -285.916116) (xy 68.980304 -285.926022) (xy 68.988178 -285.944056)
			(xy 69.046344 -286.000444) (xy 69.053695 -286.006926) (xy 69.071858 -286.014242) (xy 69.08165 -286.014668)
			(xy 69.218048 -286.014668) (xy 69.227835 -286.014221) (xy 69.245993 -286.006909) (xy 69.253354 -286.000444)
			(xy 69.31152 -285.944056) (xy 69.319394 -285.926022) (xy 69.319648 -285.916116) (xy 69.320834 -285.891328)
			(xy 69.330237 -285.842604) (xy 69.347393 -285.796041) (xy 69.371851 -285.752864) (xy 69.402968 -285.714208)
			(xy 69.439923 -285.681091) (xy 69.481747 -285.654384) (xy 69.527338 -285.634789) (xy 69.575496 -285.622823)
			(xy 69.624956 -285.618798) (xy 69.674416 -285.622823) (xy 69.722574 -285.634789) (xy 69.768165 -285.654384)
			(xy 69.809989 -285.681091) (xy 69.846944 -285.714208) (xy 69.878061 -285.752864) (xy 69.902519 -285.796041)
			(xy 69.919675 -285.842604) (xy 69.929078 -285.891328) (xy 69.930264 -285.916116) (xy 69.930518 -285.926022)
			(xy 69.938392 -285.944056) (xy 69.996558 -286.000444) (xy 70.00391 -286.006924) (xy 70.022073 -286.014234)
			(xy 70.031864 -286.014668) (xy 70.168008 -286.014668) (xy 70.177798 -286.014229) (xy 70.195966 -286.006926)
			(xy 70.203314 -286.000444) (xy 70.26148 -285.944056) (xy 70.269354 -285.926022) (xy 70.269608 -285.916116)
			(xy 70.270794 -285.891328) (xy 70.280197 -285.842604) (xy 70.297353 -285.796041) (xy 70.321811 -285.752864)
			(xy 70.352928 -285.714208) (xy 70.389883 -285.681091) (xy 70.431707 -285.654384) (xy 70.477298 -285.634789)
			(xy 70.525456 -285.622823) (xy 70.574916 -285.618798) (xy 70.624376 -285.622823) (xy 70.672534 -285.634789)
			(xy 70.718125 -285.654384) (xy 70.759949 -285.681091) (xy 70.796904 -285.714208) (xy 70.828021 -285.752864)
			(xy 70.852479 -285.796041) (xy 70.869635 -285.842604) (xy 70.879038 -285.891328) (xy 70.880224 -285.916116)
			(xy 70.880478 -285.926022) (xy 70.888352 -285.944056) (xy 70.946518 -286.000444) (xy 70.953868 -286.00693)
			(xy 70.972031 -286.014255) (xy 70.981824 -286.014668) (xy 73.017888 -286.014668) (xy 73.027672 -286.014214)
			(xy 73.04582 -286.006892) (xy 73.053194 -286.000444) (xy 73.11136 -285.944056) (xy 73.119234 -285.926022)
			(xy 73.119488 -285.916116) (xy 73.120655 -285.892142) (xy 73.129535 -285.844975) (xy 73.145681 -285.799776)
			(xy 73.168695 -285.757658) (xy 73.198012 -285.719656) (xy 73.23291 -285.686705) (xy 73.272531 -285.659617)
			(xy 73.3159 -285.639057) (xy 73.361951 -285.625531) (xy 73.40955 -285.619372) (xy 73.457527 -285.620731)
			(xy 73.481184 -285.624778) (xy 73.49363 -285.627064) (xy 73.517252 -285.619698) (xy 73.594722 -285.542228)
			(xy 73.602088 -285.518606) (xy 73.599802 -285.50616) (xy 73.597318 -285.492195) (xy 73.594649 -285.463955)
			(xy 73.594468 -285.449772) (xy 73.59499 -285.424517) (xy 73.603303 -285.374695) (xy 73.619704 -285.326921)
			(xy 73.643745 -285.282498) (xy 73.674769 -285.242638) (xy 73.711931 -285.208428) (xy 73.754217 -285.180802)
			(xy 73.800473 -285.160512) (xy 73.849438 -285.148112) (xy 73.899776 -285.143941) (xy 73.950114 -285.148112)
			(xy 73.999079 -285.160512) (xy 74.045335 -285.180802) (xy 74.087621 -285.208428) (xy 74.124783 -285.242638)
			(xy 74.155807 -285.282498) (xy 74.179848 -285.326921) (xy 74.196249 -285.374695) (xy 74.204562 -285.424517)
			(xy 74.205084 -285.449772) (xy 74.204985 -285.458876) (xy 74.20384 -285.477049) (xy 74.202798 -285.486094)
			(xy 74.201528 -285.498286) (xy 74.209402 -285.520638) (xy 74.285856 -285.593536) (xy 74.308462 -285.600648)
			(xy 74.3204 -285.598616) (xy 74.333888 -285.596484) (xy 74.361101 -285.594192) (xy 74.374756 -285.594044)
			(xy 74.42327 -285.594044) (xy 74.43393 -285.593589) (xy 74.4534 -285.584907) (xy 74.460862 -285.57728)
			(xy 74.518774 -285.513526) (xy 74.525378 -285.493206) (xy 74.524362 -285.482284) (xy 74.522584 -285.449772)
			(xy 74.523088 -285.424064) (xy 74.531131 -285.373282) (xy 74.547019 -285.324383) (xy 74.570362 -285.278571)
			(xy 74.600583 -285.236975) (xy 74.636939 -285.200619) (xy 74.678535 -285.170398) (xy 74.724347 -285.147055)
			(xy 74.773246 -285.131167) (xy 74.824028 -285.123124) (xy 74.875444 -285.123124) (xy 74.926226 -285.131167)
			(xy 74.975125 -285.147055) (xy 75.020937 -285.170398) (xy 75.062533 -285.200619) (xy 75.098889 -285.236975)
			(xy 75.12911 -285.278571) (xy 75.152453 -285.324383) (xy 75.168341 -285.373282) (xy 75.176384 -285.424064)
			(xy 75.176888 -285.449772) (xy 75.17511 -285.482284) (xy 75.174094 -285.493206) (xy 75.180698 -285.513526)
			(xy 75.23861 -285.57728) (xy 75.246156 -285.584785) (xy 75.265576 -285.593438) (xy 75.276202 -285.594044)
			(xy 75.324716 -285.594044) (xy 75.334134 -285.594079) (xy 75.352941 -285.595095) (xy 75.362308 -285.596076)
			(xy 75.373738 -285.5976) (xy 75.395582 -285.58998) (xy 75.468226 -285.51759) (xy 75.4761 -285.496)
			(xy 75.47483 -285.48457) (xy 75.473052 -285.449772) (xy 75.473556 -285.424084) (xy 75.481593 -285.373341)
			(xy 75.497469 -285.32448) (xy 75.520793 -285.278704) (xy 75.55099 -285.23714) (xy 75.587318 -285.200812)
			(xy 75.628882 -285.170615) (xy 75.674658 -285.147291) (xy 75.723519 -285.131415) (xy 75.774262 -285.123378)
			(xy 75.825638 -285.123378) (xy 75.876381 -285.131415) (xy 75.925242 -285.147291) (xy 75.971018 -285.170615)
			(xy 76.012582 -285.200812) (xy 76.04891 -285.23714) (xy 76.079107 -285.278704) (xy 76.102431 -285.32448)
			(xy 76.118307 -285.373341) (xy 76.126344 -285.424084) (xy 76.126848 -285.449772) (xy 76.126722 -285.463491)
			(xy 76.124437 -285.490834) (xy 76.122276 -285.504382) (xy 76.120498 -285.51632) (xy 76.127356 -285.53918)
			(xy 76.201016 -285.615634) (xy 76.223622 -285.623508) (xy 76.23556 -285.621984) (xy 76.259483 -285.619346)
			(xy 76.307591 -285.620742) (xy 76.331318 -285.624778) (xy 76.343764 -285.627064) (xy 76.367386 -285.619698)
			(xy 76.444856 -285.542228) (xy 76.452222 -285.518606) (xy 76.449936 -285.50616) (xy 76.447452 -285.492195)
			(xy 76.444782 -285.463955) (xy 76.444602 -285.449772) (xy 76.445124 -285.424517) (xy 76.453437 -285.374695)
			(xy 76.469838 -285.326921) (xy 76.493879 -285.282498) (xy 76.524903 -285.242638) (xy 76.562065 -285.208428)
			(xy 76.604351 -285.180802) (xy 76.650607 -285.160512) (xy 76.699572 -285.148112) (xy 76.74991 -285.143941)
			(xy 76.800248 -285.148112) (xy 76.849213 -285.160512) (xy 76.895469 -285.180802) (xy 76.937755 -285.208428)
			(xy 76.974917 -285.242638) (xy 77.005941 -285.282498) (xy 77.029982 -285.326921) (xy 77.046383 -285.374695)
			(xy 77.054696 -285.424517) (xy 77.055218 -285.449772) (xy 77.055033 -285.463955) (xy 77.052362 -285.492194)
			(xy 77.049884 -285.50616) (xy 77.047598 -285.518606) (xy 77.054964 -285.542228) (xy 77.132434 -285.619698)
			(xy 77.156056 -285.627064) (xy 77.168502 -285.624778) (xy 77.196509 -285.620149) (xy 77.253271 -285.620149)
			(xy 77.281278 -285.624778) (xy 77.293724 -285.627064) (xy 77.317346 -285.619698) (xy 77.394816 -285.542228)
			(xy 77.402182 -285.518606) (xy 77.399896 -285.50616) (xy 77.397412 -285.492195) (xy 77.394743 -285.463955)
			(xy 77.394562 -285.449772) (xy 77.395084 -285.424517) (xy 77.403397 -285.374695) (xy 77.419798 -285.326921)
			(xy 77.443839 -285.282498) (xy 77.474863 -285.242638) (xy 77.512025 -285.208428) (xy 77.554311 -285.180802)
			(xy 77.600567 -285.160512) (xy 77.649532 -285.148112) (xy 77.69987 -285.143941) (xy 77.750208 -285.148112)
			(xy 77.799173 -285.160512) (xy 77.845429 -285.180802) (xy 77.887715 -285.208428) (xy 77.924877 -285.242638)
			(xy 77.955901 -285.282498) (xy 77.979942 -285.326921) (xy 77.996343 -285.374695) (xy 78.004656 -285.424517)
			(xy 78.005178 -285.449772) (xy 78.004993 -285.463955) (xy 78.002322 -285.492194) (xy 77.999844 -285.50616)
			(xy 77.997558 -285.518606) (xy 78.004924 -285.542228) (xy 78.082394 -285.619698) (xy 78.106016 -285.627064)
			(xy 78.118462 -285.624778) (xy 78.146469 -285.620149) (xy 78.203231 -285.620149) (xy 78.231238 -285.624778)
			(xy 78.243684 -285.627064) (xy 78.267306 -285.619698) (xy 78.344776 -285.542228) (xy 78.352142 -285.518606)
			(xy 78.349856 -285.50616) (xy 78.347372 -285.492195) (xy 78.344702 -285.463955) (xy 78.344522 -285.449772)
			(xy 78.345044 -285.424517) (xy 78.353357 -285.374695) (xy 78.369758 -285.326921) (xy 78.393799 -285.282498)
			(xy 78.424823 -285.242638) (xy 78.461985 -285.208428) (xy 78.504271 -285.180802) (xy 78.550527 -285.160512)
			(xy 78.599492 -285.148112) (xy 78.64983 -285.143941) (xy 78.700168 -285.148112) (xy 78.749133 -285.160512)
			(xy 78.795389 -285.180802) (xy 78.837675 -285.208428) (xy 78.874837 -285.242638) (xy 78.905861 -285.282498)
			(xy 78.929902 -285.326921) (xy 78.946303 -285.374695) (xy 78.954616 -285.424517) (xy 78.955138 -285.449772)
			(xy 78.954953 -285.463955) (xy 78.952282 -285.492194) (xy 78.949804 -285.50616) (xy 78.947518 -285.518606)
			(xy 78.954884 -285.542228) (xy 79.032354 -285.619698) (xy 79.055976 -285.627064) (xy 79.068422 -285.624778)
			(xy 79.096429 -285.620149) (xy 79.153191 -285.620149) (xy 79.181198 -285.624778) (xy 79.193644 -285.627064)
			(xy 79.217266 -285.619698) (xy 79.294736 -285.542228) (xy 79.302102 -285.518606) (xy 79.299816 -285.50616)
			(xy 79.297332 -285.492195) (xy 79.294663 -285.463955) (xy 79.294482 -285.449772) (xy 79.295004 -285.424517)
			(xy 79.303317 -285.374695) (xy 79.319718 -285.326921) (xy 79.343759 -285.282498) (xy 79.374783 -285.242638)
			(xy 79.411945 -285.208428) (xy 79.454231 -285.180802) (xy 79.500487 -285.160512) (xy 79.549452 -285.148112)
			(xy 79.59979 -285.143941) (xy 79.650128 -285.148112) (xy 79.699093 -285.160512) (xy 79.745349 -285.180802)
			(xy 79.787635 -285.208428) (xy 79.824797 -285.242638) (xy 79.855821 -285.282498) (xy 79.879862 -285.326921)
			(xy 79.896263 -285.374695) (xy 79.904576 -285.424517) (xy 79.905098 -285.449772) (xy 79.904999 -285.458876)
			(xy 79.903854 -285.477049) (xy 79.902812 -285.486094) (xy 79.901542 -285.498286) (xy 79.909416 -285.520638)
			(xy 79.98587 -285.593536) (xy 80.008476 -285.600648) (xy 80.020414 -285.598616) (xy 80.033902 -285.596484)
			(xy 80.061115 -285.594194) (xy 80.07477 -285.594044) (xy 80.145128 -285.594044) (xy 80.155818 -285.593478)
			(xy 80.175366 -285.584811) (xy 80.182974 -285.57728) (xy 80.240632 -285.513018) (xy 80.247236 -285.492698)
			(xy 80.24622 -285.481776) (xy 80.244442 -285.449772) (xy 80.244964 -285.424517) (xy 80.253277 -285.374695)
			(xy 80.269678 -285.326921) (xy 80.293719 -285.282498) (xy 80.324743 -285.242638) (xy 80.361905 -285.208428)
			(xy 80.404191 -285.180802) (xy 80.450447 -285.160512) (xy 80.499412 -285.148112) (xy 80.54975 -285.143941)
			(xy 80.600088 -285.148112) (xy 80.649053 -285.160512) (xy 80.695309 -285.180802) (xy 80.737595 -285.208428)
			(xy 80.774757 -285.242638) (xy 80.805781 -285.282498) (xy 80.829822 -285.326921) (xy 80.846223 -285.374695)
			(xy 80.854536 -285.424517) (xy 80.855058 -285.449772) (xy 80.85328 -285.481776) (xy 80.852264 -285.492698)
			(xy 80.858868 -285.513018) (xy 80.916526 -285.57728) (xy 80.924046 -285.584933) (xy 80.94365 -285.593603)
			(xy 80.954372 -285.594044) (xy 81.02473 -285.594044) (xy 81.034148 -285.59408) (xy 81.052955 -285.595096)
			(xy 81.062322 -285.596076) (xy 81.073752 -285.5976) (xy 81.095596 -285.58998) (xy 81.16824 -285.51759)
			(xy 81.176114 -285.496) (xy 81.174844 -285.48457) (xy 81.172812 -285.449772) (xy 81.173316 -285.424064)
			(xy 81.181359 -285.373282) (xy 81.197247 -285.324383) (xy 81.22059 -285.278571) (xy 81.250811 -285.236975)
			(xy 81.287167 -285.200619) (xy 81.328763 -285.170398) (xy 81.374575 -285.147055) (xy 81.423474 -285.131167)
			(xy 81.474256 -285.123124) (xy 81.525672 -285.123124) (xy 81.576454 -285.131167) (xy 81.625353 -285.147055)
			(xy 81.671165 -285.170398) (xy 81.712761 -285.200619) (xy 81.749117 -285.236975) (xy 81.779338 -285.278571)
			(xy 81.802681 -285.324383) (xy 81.818569 -285.373282) (xy 81.826612 -285.424064) (xy 81.827116 -285.449772)
			(xy 81.826922 -285.463495) (xy 81.824503 -285.490837) (xy 81.82229 -285.504382) (xy 81.820512 -285.51632)
			(xy 81.82737 -285.53918) (xy 81.90103 -285.615634) (xy 81.923636 -285.623508) (xy 81.935574 -285.621984)
			(xy 81.955197 -285.619746) (xy 81.994691 -285.619746) (xy 82.014314 -285.621984) (xy 82.026252 -285.623508)
			(xy 82.048858 -285.615634) (xy 82.122518 -285.53918) (xy 82.129376 -285.51632) (xy 82.127598 -285.504382)
			(xy 82.125396 -285.490835) (xy 82.122978 -285.463495) (xy 82.122772 -285.449772) (xy 82.123276 -285.424064)
			(xy 82.131319 -285.373282) (xy 82.147207 -285.324383) (xy 82.17055 -285.278571) (xy 82.200771 -285.236975)
			(xy 82.237127 -285.200619) (xy 82.278723 -285.170398) (xy 82.324535 -285.147055) (xy 82.373434 -285.131167)
			(xy 82.424216 -285.123124) (xy 82.475632 -285.123124) (xy 82.526414 -285.131167) (xy 82.575313 -285.147055)
			(xy 82.621125 -285.170398) (xy 82.662721 -285.200619) (xy 82.699077 -285.236975) (xy 82.729298 -285.278571)
			(xy 82.752641 -285.324383) (xy 82.768529 -285.373282) (xy 82.776572 -285.424064) (xy 82.777076 -285.449772)
			(xy 82.776882 -285.463495) (xy 82.774463 -285.490837) (xy 82.77225 -285.504382) (xy 82.770472 -285.51632)
			(xy 82.77733 -285.53918) (xy 82.85099 -285.615634) (xy 82.873596 -285.623508) (xy 82.885534 -285.621984)
			(xy 82.909457 -285.619352) (xy 82.957562 -285.620759) (xy 82.981292 -285.624778) (xy 82.993992 -285.627064)
			(xy 83.017614 -285.619698) (xy 83.095084 -285.542482) (xy 83.10245 -285.51886) (xy 83.100164 -285.50616)
			(xy 83.097689 -285.492258) (xy 83.095021 -285.464145) (xy 83.09483 -285.450026) (xy 83.095314 -285.425208)
			(xy 83.103339 -285.376226) (xy 83.119184 -285.329188) (xy 83.142429 -285.285333) (xy 83.172464 -285.245816)
			(xy 83.208496 -285.211679) (xy 83.249575 -285.18382) (xy 83.294621 -285.162975) (xy 83.342446 -285.149691)
			(xy 83.391789 -285.14432) (xy 83.441352 -285.147002) (xy 83.489828 -285.157667) (xy 83.535939 -285.176035)
			(xy 83.578472 -285.20162) (xy 83.616306 -285.233749) (xy 83.648443 -285.271576) (xy 83.674037 -285.314103)
			(xy 83.692414 -285.360211) (xy 83.703089 -285.408685) (xy 83.705782 -285.458247) (xy 83.700421 -285.507591)
			(xy 83.687147 -285.555419) (xy 83.666311 -285.600469) (xy 83.638462 -285.641554) (xy 83.604332 -285.677593)
			(xy 83.564821 -285.707636) (xy 83.520971 -285.730891) (xy 83.473936 -285.746745) (xy 83.424955 -285.754781)
			(xy 83.400138 -285.755334) (xy 83.385955 -285.755149) (xy 83.357715 -285.752479) (xy 83.34375 -285.75)
			(xy 83.33105 -285.747714) (xy 83.307428 -285.75508) (xy 83.229958 -285.832296) (xy 83.222846 -285.855918)
			(xy 83.225132 -285.868618) (xy 83.227217 -285.880391) (xy 83.229764 -285.904168) (xy 83.230212 -285.916116)
			(xy 83.230466 -285.926022) (xy 83.23834 -285.944056) (xy 83.296506 -286.000444) (xy 83.303855 -286.006932)
			(xy 83.322018 -286.014261) (xy 83.331812 -286.014668) (xy 98.314256 -286.014668) (xy 98.324281 -286.014255)
			(xy 98.342807 -286.006592) (xy 98.356985 -285.992417) (xy 98.364653 -285.973893) (xy 98.365056 -285.963868)
			(xy 98.365056 -269.543784) (xy 98.365484 -269.533716) (xy 98.373208 -269.515121) (xy 98.380042 -269.507716)
			(xy 101.720904 -266.166854) (xy 101.7283 -266.160002) (xy 101.746899 -266.152261) (xy 101.756972 -266.151868)
			(xy 113.768124 -266.151868) (xy 113.779537 -266.151398) (xy 113.800146 -266.1416) (xy 113.807748 -266.133072)
			(xy 113.864644 -266.062714) (xy 113.869978 -266.040362) (xy 113.867692 -266.029186) (xy 113.863787 -266.009607)
			(xy 113.859587 -265.969901) (xy 113.85931 -265.949938) (xy 113.859796 -265.922687) (xy 113.867552 -265.868739)
			(xy 113.882907 -265.816444) (xy 113.905549 -265.766867) (xy 113.935015 -265.721017) (xy 113.970706 -265.679826)
			(xy 114.011897 -265.644135) (xy 114.057747 -265.614669) (xy 114.107324 -265.592027) (xy 114.159619 -265.576672)
			(xy 114.213567 -265.568916) (xy 114.268069 -265.568916) (xy 114.322017 -265.576672) (xy 114.374312 -265.592027)
			(xy 114.423889 -265.614669) (xy 114.469739 -265.644135) (xy 114.51093 -265.679826) (xy 114.546621 -265.721017)
			(xy 114.576087 -265.766867) (xy 114.598729 -265.816444) (xy 114.614084 -265.868739) (xy 114.62184 -265.922687)
			(xy 114.622326 -265.949938) (xy 114.622061 -265.969902) (xy 114.61786 -266.009608) (xy 114.613944 -266.029186)
			(xy 114.611658 -266.040362) (xy 114.616992 -266.062714) (xy 114.673888 -266.133072) (xy 114.681554 -266.141514)
			(xy 114.702125 -266.151285) (xy 114.713512 -266.151868) (xy 119.196358 -266.151868) (xy 119.204995 -266.151528)
			(xy 119.22128 -266.145772) (xy 119.234706 -266.134906) (xy 119.239538 -266.127738) (xy 119.292116 -266.042902)
			(xy 119.293132 -266.01674) (xy 119.28729 -266.004802) (xy 119.27456 -265.978169) (xy 119.256569 -265.92195)
			(xy 119.247471 -265.863628) (xy 119.246904 -265.834114) (xy 119.24739 -265.806863) (xy 119.255146 -265.752915)
			(xy 119.270501 -265.70062) (xy 119.293143 -265.651043) (xy 119.322609 -265.605193) (xy 119.3583 -265.564002)
			(xy 119.399491 -265.528311) (xy 119.445341 -265.498845) (xy 119.494918 -265.476203) (xy 119.547213 -265.460848)
			(xy 119.601161 -265.453092) (xy 119.655663 -265.453092) (xy 119.709611 -265.460848) (xy 119.761906 -265.476203)
			(xy 119.811483 -265.498845) (xy 119.857333 -265.528311) (xy 119.898524 -265.564002) (xy 119.934215 -265.605193)
			(xy 119.963681 -265.651043) (xy 119.986323 -265.70062) (xy 120.001678 -265.752915) (xy 120.009434 -265.806863)
			(xy 120.00992 -265.834114) (xy 120.009349 -265.863627) (xy 120.006259 -265.88339) (xy 157.279592 -265.88339)
			(xy 157.283663 -265.827768) (xy 157.295789 -265.773331) (xy 157.315712 -265.72124) (xy 157.343008 -265.672605)
			(xy 157.377094 -265.628462) (xy 157.417243 -265.589753) (xy 157.462601 -265.557302) (xy 157.512201 -265.531801)
			(xy 157.564985 -265.513794) (xy 157.619828 -265.503664) (xy 157.675562 -265.501627) (xy 157.730999 -265.507727)
			(xy 157.784956 -265.521833) (xy 157.836285 -265.543645) (xy 157.883891 -265.572699) (xy 157.926759 -265.608374)
			(xy 157.963976 -265.649911) (xy 157.994749 -265.696424) (xy 158.018421 -265.746921) (xy 158.034489 -265.800328)
			(xy 158.042609 -265.855504) (xy 158.043118 -265.88339) (xy 158.042609 -265.911276) (xy 158.034489 -265.966452)
			(xy 158.020658 -266.012422) (xy 273.142454 -266.012422) (xy 273.146525 -265.9568) (xy 273.158651 -265.902363)
			(xy 273.178574 -265.850272) (xy 273.20587 -265.801637) (xy 273.239956 -265.757494) (xy 273.280105 -265.718785)
			(xy 273.325463 -265.686334) (xy 273.375063 -265.660833) (xy 273.427847 -265.642826) (xy 273.48269 -265.632696)
			(xy 273.538424 -265.630659) (xy 273.593861 -265.636759) (xy 273.647818 -265.650865) (xy 273.699147 -265.672677)
			(xy 273.746753 -265.701731) (xy 273.789621 -265.737406) (xy 273.826838 -265.778943) (xy 273.857611 -265.825456)
			(xy 273.881283 -265.875953) (xy 273.897351 -265.92936) (xy 273.900379 -265.949938) (xy 346.058996 -265.949938)
			(xy 346.063067 -265.894316) (xy 346.075193 -265.839879) (xy 346.095116 -265.787788) (xy 346.122412 -265.739153)
			(xy 346.156498 -265.69501) (xy 346.196647 -265.656301) (xy 346.242005 -265.62385) (xy 346.291605 -265.598349)
			(xy 346.344389 -265.580342) (xy 346.399232 -265.570212) (xy 346.454966 -265.568175) (xy 346.510403 -265.574275)
			(xy 346.56436 -265.588381) (xy 346.615689 -265.610193) (xy 346.663295 -265.639247) (xy 346.706163 -265.674922)
			(xy 346.74338 -265.716459) (xy 346.774153 -265.762972) (xy 346.797825 -265.813469) (xy 346.804036 -265.834114)
			(xy 351.44659 -265.834114) (xy 351.450661 -265.778492) (xy 351.462787 -265.724055) (xy 351.48271 -265.671964)
			(xy 351.510006 -265.623329) (xy 351.544092 -265.579186) (xy 351.584241 -265.540477) (xy 351.629599 -265.508026)
			(xy 351.679199 -265.482525) (xy 351.731983 -265.464518) (xy 351.786826 -265.454388) (xy 351.84256 -265.452351)
			(xy 351.897997 -265.458451) (xy 351.951954 -265.472557) (xy 352.003283 -265.494369) (xy 352.050889 -265.523423)
			(xy 352.093757 -265.559098) (xy 352.130974 -265.600635) (xy 352.161747 -265.647148) (xy 352.185419 -265.697645)
			(xy 352.197514 -265.737848) (xy 388.73252 -265.737848) (xy 388.736591 -265.682226) (xy 388.748717 -265.627789)
			(xy 388.76864 -265.575698) (xy 388.795936 -265.527063) (xy 388.830022 -265.48292) (xy 388.870171 -265.444211)
			(xy 388.915529 -265.41176) (xy 388.965129 -265.386259) (xy 389.017913 -265.368252) (xy 389.072756 -265.358122)
			(xy 389.12849 -265.356085) (xy 389.183927 -265.362185) (xy 389.237884 -265.376291) (xy 389.289213 -265.398103)
			(xy 389.336819 -265.427157) (xy 389.379687 -265.462832) (xy 389.416904 -265.504369) (xy 389.447677 -265.550882)
			(xy 389.471349 -265.601379) (xy 389.487417 -265.654786) (xy 389.495537 -265.709962) (xy 389.496046 -265.737848)
			(xy 389.495537 -265.765734) (xy 389.487417 -265.82091) (xy 389.471349 -265.874317) (xy 389.447677 -265.924814)
			(xy 389.416904 -265.971327) (xy 389.379687 -266.012864) (xy 389.336819 -266.048539) (xy 389.289213 -266.077593)
			(xy 389.237884 -266.099405) (xy 389.183927 -266.113511) (xy 389.12849 -266.119611) (xy 389.072756 -266.117574)
			(xy 389.017913 -266.107444) (xy 388.965129 -266.089437) (xy 388.915529 -266.063936) (xy 388.870171 -266.031485)
			(xy 388.830022 -265.992776) (xy 388.795936 -265.948633) (xy 388.76864 -265.899998) (xy 388.748717 -265.847907)
			(xy 388.736591 -265.79347) (xy 388.73252 -265.737848) (xy 352.197514 -265.737848) (xy 352.201487 -265.751052)
			(xy 352.209607 -265.806228) (xy 352.210116 -265.834114) (xy 352.209607 -265.862) (xy 352.201487 -265.917176)
			(xy 352.185419 -265.970583) (xy 352.161747 -266.02108) (xy 352.130974 -266.067593) (xy 352.093757 -266.10913)
			(xy 352.050889 -266.144805) (xy 352.003283 -266.173859) (xy 351.951954 -266.195671) (xy 351.897997 -266.209777)
			(xy 351.84256 -266.215877) (xy 351.786826 -266.21384) (xy 351.731983 -266.20371) (xy 351.679199 -266.185703)
			(xy 351.629599 -266.160202) (xy 351.584241 -266.127751) (xy 351.544092 -266.089042) (xy 351.510006 -266.044899)
			(xy 351.48271 -265.996264) (xy 351.462787 -265.944173) (xy 351.450661 -265.889736) (xy 351.44659 -265.834114)
			(xy 346.804036 -265.834114) (xy 346.813893 -265.866876) (xy 346.822013 -265.922052) (xy 346.822522 -265.949938)
			(xy 346.822013 -265.977824) (xy 346.813893 -266.033) (xy 346.797825 -266.086407) (xy 346.774153 -266.136904)
			(xy 346.74338 -266.183417) (xy 346.706163 -266.224954) (xy 346.663295 -266.260629) (xy 346.615689 -266.289683)
			(xy 346.56436 -266.311495) (xy 346.510403 -266.325601) (xy 346.454966 -266.331701) (xy 346.399232 -266.329664)
			(xy 346.344389 -266.319534) (xy 346.291605 -266.301527) (xy 346.242005 -266.276026) (xy 346.196647 -266.243575)
			(xy 346.156498 -266.204866) (xy 346.122412 -266.160723) (xy 346.095116 -266.112088) (xy 346.075193 -266.059997)
			(xy 346.063067 -266.00556) (xy 346.058996 -265.949938) (xy 273.900379 -265.949938) (xy 273.905471 -265.984536)
			(xy 273.90598 -266.012422) (xy 273.905471 -266.040308) (xy 273.897351 -266.095484) (xy 273.881283 -266.148891)
			(xy 273.857611 -266.199388) (xy 273.826838 -266.245901) (xy 273.789621 -266.287438) (xy 273.746753 -266.323113)
			(xy 273.699147 -266.352167) (xy 273.647818 -266.373979) (xy 273.593861 -266.388085) (xy 273.538424 -266.394185)
			(xy 273.48269 -266.392148) (xy 273.427847 -266.382018) (xy 273.375063 -266.364011) (xy 273.325463 -266.33851)
			(xy 273.280105 -266.306059) (xy 273.239956 -266.26735) (xy 273.20587 -266.223207) (xy 273.178574 -266.174572)
			(xy 273.158651 -266.122481) (xy 273.146525 -266.068044) (xy 273.142454 -266.012422) (xy 158.020658 -266.012422)
			(xy 158.018421 -266.019859) (xy 157.994749 -266.070356) (xy 157.963976 -266.116869) (xy 157.926759 -266.158406)
			(xy 157.883891 -266.194081) (xy 157.836285 -266.223135) (xy 157.784956 -266.244947) (xy 157.730999 -266.259053)
			(xy 157.675562 -266.265153) (xy 157.619828 -266.263116) (xy 157.564985 -266.252986) (xy 157.512201 -266.234979)
			(xy 157.462601 -266.209478) (xy 157.417243 -266.177027) (xy 157.377094 -266.138318) (xy 157.343008 -266.094175)
			(xy 157.315712 -266.04554) (xy 157.295789 -265.993449) (xy 157.283663 -265.939012) (xy 157.279592 -265.88339)
			(xy 120.006259 -265.88339) (xy 120.000231 -265.921945) (xy 119.982261 -265.978169) (xy 119.969534 -266.004802)
			(xy 119.963692 -266.01674) (xy 119.964708 -266.042902) (xy 120.017286 -266.127738) (xy 120.02212 -266.134898)
			(xy 120.035562 -266.14573) (xy 120.051835 -266.151494) (xy 120.060466 -266.151868) (xy 133.618986 -266.151868)
			(xy 133.629036 -266.152375) (xy 133.647596 -266.160097) (xy 133.655054 -266.166854) (xy 134.719314 -267.231114)
			(xy 134.72287 -267.234416) (xy 134.729881 -267.239823) (xy 134.746533 -267.245806) (xy 134.755382 -267.2461)
			(xy 134.972044 -267.2461) (xy 134.99601 -267.246594) (xy 135.043347 -267.254128) (xy 135.088928 -267.268958)
			(xy 135.131635 -267.290721) (xy 135.170423 -267.318882) (xy 135.18769 -267.335508) (xy 136.056116 -268.203934)
			(xy 136.072768 -268.221184) (xy 136.10098 -268.259951) (xy 136.122769 -268.302658) (xy 136.137596 -268.348253)
			(xy 136.145097 -268.395607) (xy 136.145524 -268.41958) (xy 136.145524 -268.636242) (xy 136.145911 -268.645072)
			(xy 136.151894 -268.66169) (xy 136.157208 -268.668754) (xy 136.158732 -268.670532) (xy 136.934194 -269.445994)
			(xy 136.941042 -269.453392) (xy 136.94878 -269.47199) (xy 136.94918 -269.482062) (xy 136.94918 -270.89989)
			(xy 140.998709 -270.89989) (xy 141.002715 -270.704835) (xy 141.014725 -270.510109) (xy 141.03472 -270.31604)
			(xy 141.062665 -270.122956) (xy 141.098514 -269.931181) (xy 141.142206 -269.741041) (xy 141.193667 -269.552854)
			(xy 141.252811 -269.366939) (xy 141.319538 -269.183608) (xy 141.393735 -269.003172) (xy 141.475277 -268.825934)
			(xy 141.564028 -268.652193) (xy 141.659836 -268.482242) (xy 141.762541 -268.316368) (xy 141.871969 -268.15485)
			(xy 141.987936 -267.997961) (xy 142.110247 -267.845966) (xy 142.238694 -267.69912) (xy 142.373062 -267.557671)
			(xy 142.513124 -267.421858) (xy 142.658643 -267.291909) (xy 142.809375 -267.168045) (xy 142.965065 -267.050473)
			(xy 143.125451 -266.939393) (xy 143.290262 -266.83499) (xy 143.45922 -266.737442) (xy 143.632041 -266.646913)
			(xy 143.808433 -266.563555) (xy 143.988098 -266.487509) (xy 144.170733 -266.418904) (xy 144.356032 -266.357854)
			(xy 144.54368 -266.304464) (xy 144.733362 -266.258822) (xy 144.924759 -266.221006) (xy 145.117546 -266.19108)
			(xy 145.311399 -266.169094) (xy 145.505992 -266.155085) (xy 145.700995 -266.149077) (xy 145.896081 -266.15108)
			(xy 146.09092 -266.161091) (xy 146.285184 -266.179092) (xy 146.478545 -266.205054) (xy 146.670678 -266.238932)
			(xy 146.861257 -266.280669) (xy 147.049962 -266.330196) (xy 147.236475 -266.387428) (xy 147.420481 -266.452269)
			(xy 147.584818 -266.517882) (xy 156.497018 -266.517882) (xy 156.501089 -266.46226) (xy 156.513215 -266.407823)
			(xy 156.533138 -266.355732) (xy 156.560434 -266.307097) (xy 156.59452 -266.262954) (xy 156.634669 -266.224245)
			(xy 156.680027 -266.191794) (xy 156.729627 -266.166293) (xy 156.782411 -266.148286) (xy 156.837254 -266.138156)
			(xy 156.892988 -266.136119) (xy 156.948425 -266.142219) (xy 157.002382 -266.156325) (xy 157.053711 -266.178137)
			(xy 157.101317 -266.207191) (xy 157.144185 -266.242866) (xy 157.181402 -266.284403) (xy 157.212175 -266.330916)
			(xy 157.235847 -266.381413) (xy 157.251915 -266.43482) (xy 157.260035 -266.489996) (xy 157.260544 -266.517882)
			(xy 157.260035 -266.545768) (xy 157.251915 -266.600944) (xy 157.235847 -266.654351) (xy 157.212175 -266.704848)
			(xy 157.181402 -266.751361) (xy 157.144185 -266.792898) (xy 157.101317 -266.828573) (xy 157.053711 -266.857627)
			(xy 157.002382 -266.879439) (xy 156.948425 -266.893545) (xy 156.892988 -266.899645) (xy 156.837254 -266.897608)
			(xy 156.782411 -266.887478) (xy 156.729627 -266.869471) (xy 156.680027 -266.84397) (xy 156.634669 -266.811519)
			(xy 156.59452 -266.77281) (xy 156.560434 -266.728667) (xy 156.533138 -266.680032) (xy 156.513215 -266.627941)
			(xy 156.501089 -266.573504) (xy 156.497018 -266.517882) (xy 147.584818 -266.517882) (xy 147.601669 -266.52461)
			(xy 147.779735 -266.604328) (xy 147.954378 -266.69129) (xy 148.125304 -266.785349) (xy 148.292223 -266.886345)
			(xy 148.408507 -266.963398) (xy 154.756102 -266.963398) (xy 154.760173 -266.907776) (xy 154.772299 -266.853339)
			(xy 154.792222 -266.801248) (xy 154.819518 -266.752613) (xy 154.853604 -266.70847) (xy 154.893753 -266.669761)
			(xy 154.939111 -266.63731) (xy 154.988711 -266.611809) (xy 155.041495 -266.593802) (xy 155.096338 -266.583672)
			(xy 155.152072 -266.581635) (xy 155.207509 -266.587735) (xy 155.261466 -266.601841) (xy 155.312795 -266.623653)
			(xy 155.360401 -266.652707) (xy 155.403269 -266.688382) (xy 155.440486 -266.729919) (xy 155.471259 -266.776432)
			(xy 155.494931 -266.826929) (xy 155.510999 -266.880336) (xy 155.519119 -266.935512) (xy 155.519628 -266.963398)
			(xy 155.519119 -266.991284) (xy 155.510999 -267.04646) (xy 155.494931 -267.099867) (xy 155.471259 -267.150364)
			(xy 155.440486 -267.196877) (xy 155.403269 -267.238414) (xy 155.360401 -267.274089) (xy 155.312795 -267.303143)
			(xy 155.261466 -267.324955) (xy 155.207509 -267.339061) (xy 155.152072 -267.345161) (xy 155.096338 -267.343124)
			(xy 155.041495 -267.332994) (xy 154.988711 -267.314987) (xy 154.939111 -267.289486) (xy 154.893753 -267.257035)
			(xy 154.853604 -267.218326) (xy 154.819518 -267.174183) (xy 154.792222 -267.125548) (xy 154.772299 -267.073457)
			(xy 154.760173 -267.01902) (xy 154.756102 -266.963398) (xy 148.408507 -266.963398) (xy 148.454856 -266.99411)
			(xy 148.612927 -267.10846) (xy 148.76617 -267.229203) (xy 148.914327 -267.356137) (xy 149.057148 -267.489045)
			(xy 149.145272 -267.578078) (xy 152.95321 -267.578078) (xy 152.957281 -267.522456) (xy 152.969407 -267.468019)
			(xy 152.98933 -267.415928) (xy 153.016626 -267.367293) (xy 153.050712 -267.32315) (xy 153.090861 -267.284441)
			(xy 153.136219 -267.25199) (xy 153.185819 -267.226489) (xy 153.238603 -267.208482) (xy 153.293446 -267.198352)
			(xy 153.34918 -267.196315) (xy 153.404617 -267.202415) (xy 153.458574 -267.216521) (xy 153.509903 -267.238333)
			(xy 153.557509 -267.267387) (xy 153.600377 -267.303062) (xy 153.637594 -267.344599) (xy 153.668367 -267.391112)
			(xy 153.692039 -267.441609) (xy 153.708107 -267.495016) (xy 153.716227 -267.550192) (xy 153.716736 -267.578078)
			(xy 153.716227 -267.605964) (xy 153.708107 -267.66114) (xy 153.692039 -267.714547) (xy 153.668367 -267.765044)
			(xy 153.637594 -267.811557) (xy 153.600377 -267.853094) (xy 153.557509 -267.888769) (xy 153.509903 -267.917823)
			(xy 153.458574 -267.939635) (xy 153.404617 -267.953741) (xy 153.34918 -267.959841) (xy 153.293446 -267.957804)
			(xy 153.238603 -267.947674) (xy 153.185819 -267.929667) (xy 153.136219 -267.904166) (xy 153.090861 -267.871715)
			(xy 153.050712 -267.833006) (xy 153.016626 -267.788863) (xy 152.98933 -267.740228) (xy 152.969407 -267.688137)
			(xy 152.957281 -267.6337) (xy 152.95321 -267.578078) (xy 149.145272 -267.578078) (xy 149.194392 -267.627705)
			(xy 149.325828 -267.771883) (xy 149.451233 -267.921336) (xy 149.570397 -268.07581) (xy 149.683118 -268.235047)
			(xy 149.750514 -268.339062) (xy 156.865826 -268.339062) (xy 156.869897 -268.28344) (xy 156.882023 -268.229003)
			(xy 156.901946 -268.176912) (xy 156.929242 -268.128277) (xy 156.963328 -268.084134) (xy 157.003477 -268.045425)
			(xy 157.048835 -268.012974) (xy 157.098435 -267.987473) (xy 157.151219 -267.969466) (xy 157.206062 -267.959336)
			(xy 157.261796 -267.957299) (xy 157.317233 -267.963399) (xy 157.37119 -267.977505) (xy 157.422519 -267.999317)
			(xy 157.470125 -268.028371) (xy 157.512993 -268.064046) (xy 157.55021 -268.105583) (xy 157.580983 -268.152096)
			(xy 157.604655 -268.202593) (xy 157.620723 -268.256) (xy 157.628843 -268.311176) (xy 157.629352 -268.339062)
			(xy 157.628843 -268.366948) (xy 157.620723 -268.422124) (xy 157.604655 -268.475531) (xy 157.580983 -268.526028)
			(xy 157.55021 -268.572541) (xy 157.512993 -268.614078) (xy 157.470125 -268.649753) (xy 157.422519 -268.678807)
			(xy 157.37119 -268.700619) (xy 157.317233 -268.714725) (xy 157.261796 -268.720825) (xy 157.206062 -268.718788)
			(xy 157.151219 -268.708658) (xy 157.098435 -268.690651) (xy 157.048835 -268.66515) (xy 157.003477 -268.632699)
			(xy 156.963328 -268.59399) (xy 156.929242 -268.549847) (xy 156.901946 -268.501212) (xy 156.882023 -268.449121)
			(xy 156.869897 -268.394684) (xy 156.865826 -268.339062) (xy 149.750514 -268.339062) (xy 149.789207 -268.398778)
			(xy 149.888485 -268.566725) (xy 149.980783 -268.738608) (xy 150.065948 -268.914134) (xy 150.143834 -269.093009)
			(xy 150.214311 -269.274931) (xy 150.277259 -269.459593) (xy 150.332574 -269.646683) (xy 150.38016 -269.835887)
			(xy 150.411635 -269.987014) (xy 155.308552 -269.987014) (xy 155.312623 -269.931392) (xy 155.324749 -269.876955)
			(xy 155.344672 -269.824864) (xy 155.371968 -269.776229) (xy 155.406054 -269.732086) (xy 155.446203 -269.693377)
			(xy 155.491561 -269.660926) (xy 155.541161 -269.635425) (xy 155.593945 -269.617418) (xy 155.648788 -269.607288)
			(xy 155.704522 -269.605251) (xy 155.759959 -269.611351) (xy 155.813916 -269.625457) (xy 155.865245 -269.647269)
			(xy 155.912851 -269.676323) (xy 155.955719 -269.711998) (xy 155.992936 -269.753535) (xy 156.023709 -269.800048)
			(xy 156.047381 -269.850545) (xy 156.063449 -269.903952) (xy 156.071569 -269.959128) (xy 156.072078 -269.987014)
			(xy 156.071569 -270.0149) (xy 156.063449 -270.070076) (xy 156.047381 -270.123483) (xy 156.023709 -270.17398)
			(xy 155.992936 -270.220493) (xy 155.955719 -270.26203) (xy 155.912851 -270.297705) (xy 155.865245 -270.326759)
			(xy 155.813916 -270.348571) (xy 155.759959 -270.362677) (xy 155.704522 -270.368777) (xy 155.648788 -270.36674)
			(xy 155.593945 -270.35661) (xy 155.541161 -270.338603) (xy 155.491561 -270.313102) (xy 155.446203 -270.280651)
			(xy 155.406054 -270.241942) (xy 155.371968 -270.197799) (xy 155.344672 -270.149164) (xy 155.324749 -270.097073)
			(xy 155.312623 -270.042636) (xy 155.308552 -269.987014) (xy 150.411635 -269.987014) (xy 150.419939 -270.026884)
			(xy 150.451843 -270.219354) (xy 150.475818 -270.412972) (xy 150.491824 -270.60741) (xy 150.499833 -270.802342)
			(xy 150.500334 -270.89989) (xy 200.998589 -270.89989) (xy 201.002595 -270.704835) (xy 201.014605 -270.510109)
			(xy 201.0346 -270.31604) (xy 201.062545 -270.122956) (xy 201.098394 -269.931181) (xy 201.142086 -269.741041)
			(xy 201.193547 -269.552854) (xy 201.252691 -269.366939) (xy 201.319418 -269.183608) (xy 201.393615 -269.003172)
			(xy 201.475157 -268.825934) (xy 201.563908 -268.652193) (xy 201.659716 -268.482242) (xy 201.762421 -268.316368)
			(xy 201.871849 -268.15485) (xy 201.987816 -267.997961) (xy 202.110127 -267.845966) (xy 202.238574 -267.69912)
			(xy 202.372942 -267.557671) (xy 202.513004 -267.421858) (xy 202.658523 -267.291909) (xy 202.809255 -267.168045)
			(xy 202.964945 -267.050473) (xy 203.125331 -266.939393) (xy 203.290142 -266.83499) (xy 203.4591 -266.737442)
			(xy 203.631921 -266.646913) (xy 203.808313 -266.563555) (xy 203.987978 -266.487509) (xy 204.170613 -266.418904)
			(xy 204.355912 -266.357854) (xy 204.54356 -266.304464) (xy 204.733242 -266.258822) (xy 204.924639 -266.221006)
			(xy 205.117426 -266.19108) (xy 205.311279 -266.169094) (xy 205.505872 -266.155085) (xy 205.700875 -266.149077)
			(xy 205.895961 -266.15108) (xy 206.0908 -266.161091) (xy 206.285064 -266.179092) (xy 206.478425 -266.205054)
			(xy 206.670558 -266.238932) (xy 206.861137 -266.280669) (xy 207.049842 -266.330196) (xy 207.236355 -266.387428)
			(xy 207.420361 -266.452269) (xy 207.601549 -266.52461) (xy 207.779615 -266.604328) (xy 207.954258 -266.69129)
			(xy 208.125184 -266.785349) (xy 208.292103 -266.886345) (xy 208.454736 -266.99411) (xy 208.612807 -267.10846)
			(xy 208.76605 -267.229203) (xy 208.914207 -267.356137) (xy 209.057028 -267.489045) (xy 209.194272 -267.627705)
			(xy 209.325708 -267.771883) (xy 209.451113 -267.921336) (xy 209.570277 -268.07581) (xy 209.682998 -268.235047)
			(xy 209.789087 -268.398778) (xy 209.888365 -268.566725) (xy 209.980663 -268.738608) (xy 210.065828 -268.914134)
			(xy 210.143714 -269.093009) (xy 210.214191 -269.274931) (xy 210.277139 -269.459593) (xy 210.332454 -269.646683)
			(xy 210.38004 -269.835887) (xy 210.419819 -270.026884) (xy 210.451723 -270.219354) (xy 210.475698 -270.412972)
			(xy 210.491704 -270.60741) (xy 210.499713 -270.802342) (xy 210.500214 -270.89989) (xy 257.098807 -270.89989)
			(xy 257.102813 -270.704835) (xy 257.114823 -270.510109) (xy 257.134818 -270.31604) (xy 257.162763 -270.122956)
			(xy 257.198612 -269.931181) (xy 257.242304 -269.741041) (xy 257.293765 -269.552854) (xy 257.352909 -269.366939)
			(xy 257.419636 -269.183608) (xy 257.493833 -269.003172) (xy 257.575375 -268.825934) (xy 257.664126 -268.652193)
			(xy 257.759934 -268.482242) (xy 257.862639 -268.316368) (xy 257.972067 -268.15485) (xy 258.088034 -267.997961)
			(xy 258.210345 -267.845966) (xy 258.338792 -267.69912) (xy 258.47316 -267.557671) (xy 258.613222 -267.421858)
			(xy 258.758741 -267.291909) (xy 258.909473 -267.168045) (xy 259.065163 -267.050473) (xy 259.225549 -266.939393)
			(xy 259.39036 -266.83499) (xy 259.559318 -266.737442) (xy 259.732139 -266.646913) (xy 259.908531 -266.563555)
			(xy 260.088196 -266.487509) (xy 260.270831 -266.418904) (xy 260.45613 -266.357854) (xy 260.643778 -266.304464)
			(xy 260.83346 -266.258822) (xy 261.024857 -266.221006) (xy 261.217644 -266.19108) (xy 261.411497 -266.169094)
			(xy 261.60609 -266.155085) (xy 261.801093 -266.149077) (xy 261.996179 -266.15108) (xy 262.191018 -266.161091)
			(xy 262.385282 -266.179092) (xy 262.578643 -266.205054) (xy 262.770776 -266.238932) (xy 262.961355 -266.280669)
			(xy 263.15006 -266.330196) (xy 263.336573 -266.387428) (xy 263.520579 -266.452269) (xy 263.701767 -266.52461)
			(xy 263.879833 -266.604328) (xy 264.054476 -266.69129) (xy 264.225402 -266.785349) (xy 264.286264 -266.822174)
			(xy 268.90218 -266.822174) (xy 268.902666 -266.794923) (xy 268.910422 -266.740975) (xy 268.925777 -266.68868)
			(xy 268.948419 -266.639103) (xy 268.977885 -266.593253) (xy 269.013576 -266.552062) (xy 269.054767 -266.516371)
			(xy 269.100617 -266.486905) (xy 269.150194 -266.464263) (xy 269.202489 -266.448908) (xy 269.256437 -266.441152)
			(xy 269.310939 -266.441152) (xy 269.364887 -266.448908) (xy 269.417182 -266.464263) (xy 269.466759 -266.486905)
			(xy 269.512609 -266.516371) (xy 269.5538 -266.552062) (xy 269.589491 -266.593253) (xy 269.618957 -266.639103)
			(xy 269.641599 -266.68868) (xy 269.656954 -266.740975) (xy 269.66471 -266.794923) (xy 269.665196 -266.822174)
			(xy 269.664723 -266.849884) (xy 269.65669 -266.90472) (xy 269.640803 -266.957815) (xy 269.638202 -266.963398)
			(xy 270.855946 -266.963398) (xy 270.860017 -266.907776) (xy 270.872143 -266.853339) (xy 270.892066 -266.801248)
			(xy 270.919362 -266.752613) (xy 270.953448 -266.70847) (xy 270.993597 -266.669761) (xy 271.038955 -266.63731)
			(xy 271.088555 -266.611809) (xy 271.141339 -266.593802) (xy 271.196182 -266.583672) (xy 271.251916 -266.581635)
			(xy 271.307353 -266.587735) (xy 271.36131 -266.601841) (xy 271.412639 -266.623653) (xy 271.460245 -266.652707)
			(xy 271.503113 -266.688382) (xy 271.54033 -266.729919) (xy 271.571103 -266.776432) (xy 271.594775 -266.826929)
			(xy 271.595026 -266.827762) (xy 271.740374 -266.827762) (xy 271.744445 -266.77214) (xy 271.756571 -266.717703)
			(xy 271.776494 -266.665612) (xy 271.80379 -266.616977) (xy 271.837876 -266.572834) (xy 271.878025 -266.534125)
			(xy 271.923383 -266.501674) (xy 271.972983 -266.476173) (xy 272.025767 -266.458166) (xy 272.08061 -266.448036)
			(xy 272.136344 -266.445999) (xy 272.191781 -266.452099) (xy 272.245738 -266.466205) (xy 272.297067 -266.488017)
			(xy 272.344673 -266.517071) (xy 272.387541 -266.552746) (xy 272.424758 -266.594283) (xy 272.455531 -266.640796)
			(xy 272.479203 -266.691293) (xy 272.495271 -266.7447) (xy 272.503391 -266.799876) (xy 272.5039 -266.827762)
			(xy 272.503391 -266.855648) (xy 272.495271 -266.910824) (xy 272.479203 -266.964231) (xy 272.455531 -267.014728)
			(xy 272.424758 -267.061241) (xy 272.387541 -267.102778) (xy 272.344673 -267.138453) (xy 272.297067 -267.167507)
			(xy 272.245738 -267.189319) (xy 272.191781 -267.203425) (xy 272.136344 -267.209525) (xy 272.08061 -267.207488)
			(xy 272.025767 -267.197358) (xy 271.972983 -267.179351) (xy 271.923383 -267.15385) (xy 271.878025 -267.121399)
			(xy 271.837876 -267.08269) (xy 271.80379 -267.038547) (xy 271.776494 -266.989912) (xy 271.756571 -266.937821)
			(xy 271.744445 -266.883384) (xy 271.740374 -266.827762) (xy 271.595026 -266.827762) (xy 271.610843 -266.880336)
			(xy 271.618963 -266.935512) (xy 271.619472 -266.963398) (xy 271.618963 -266.991284) (xy 271.610843 -267.04646)
			(xy 271.594775 -267.099867) (xy 271.571103 -267.150364) (xy 271.54033 -267.196877) (xy 271.503113 -267.238414)
			(xy 271.460245 -267.274089) (xy 271.412639 -267.303143) (xy 271.36131 -267.324955) (xy 271.307353 -267.339061)
			(xy 271.251916 -267.345161) (xy 271.196182 -267.343124) (xy 271.141339 -267.332994) (xy 271.088555 -267.314987)
			(xy 271.038955 -267.289486) (xy 270.993597 -267.257035) (xy 270.953448 -267.218326) (xy 270.919362 -267.174183)
			(xy 270.892066 -267.125548) (xy 270.872143 -267.073457) (xy 270.860017 -267.01902) (xy 270.855946 -266.963398)
			(xy 269.638202 -266.963398) (xy 269.617398 -267.008051) (xy 269.586966 -267.054369) (xy 269.56893 -267.075412)
			(xy 269.560331 -267.085734) (xy 269.548359 -267.109773) (xy 269.543065 -267.136103) (xy 269.544816 -267.162901)
			(xy 269.55349 -267.188318) (xy 269.568488 -267.210596) (xy 269.588773 -267.228196) (xy 269.60068 -267.234416)
			(xy 269.624563 -267.246491) (xy 269.669059 -267.276219) (xy 269.708964 -267.311875) (xy 269.743492 -267.352759)
			(xy 269.771965 -267.398068) (xy 269.793826 -267.446913) (xy 269.808643 -267.498334) (xy 269.816127 -267.551321)
			(xy 269.81658 -267.578078) (xy 269.816094 -267.605329) (xy 269.808338 -267.659277) (xy 269.792983 -267.711572)
			(xy 269.770341 -267.761149) (xy 269.740875 -267.806999) (xy 269.705184 -267.84819) (xy 269.663993 -267.883881)
			(xy 269.618143 -267.913347) (xy 269.568566 -267.935989) (xy 269.516271 -267.951344) (xy 269.462323 -267.9591)
			(xy 269.407821 -267.9591) (xy 269.353873 -267.951344) (xy 269.301578 -267.935989) (xy 269.252001 -267.913347)
			(xy 269.206151 -267.883881) (xy 269.16496 -267.84819) (xy 269.129269 -267.806999) (xy 269.099803 -267.761149)
			(xy 269.077161 -267.711572) (xy 269.061806 -267.659277) (xy 269.05405 -267.605329) (xy 269.053564 -267.578078)
			(xy 269.054078 -267.550369) (xy 269.062103 -267.495536) (xy 269.07798 -267.442442) (xy 269.101377 -267.392205)
			(xy 269.131798 -267.345885) (xy 269.14983 -267.32484) (xy 269.158498 -267.31457) (xy 269.170472 -267.290516)
			(xy 269.175762 -267.264173) (xy 269.174003 -267.237361) (xy 269.165315 -267.211935) (xy 269.150301 -267.189652)
			(xy 269.129997 -267.172053) (xy 269.11808 -267.165836) (xy 269.094169 -267.153815) (xy 269.049672 -267.124079)
			(xy 269.00977 -267.088414) (xy 268.975245 -267.047522) (xy 268.946775 -267.002205) (xy 268.924919 -266.953353)
			(xy 268.910107 -266.901926) (xy 268.90263 -266.848933) (xy 268.90218 -266.822174) (xy 264.286264 -266.822174)
			(xy 264.392321 -266.886345) (xy 264.554954 -266.99411) (xy 264.713025 -267.10846) (xy 264.866268 -267.229203)
			(xy 265.014425 -267.356137) (xy 265.157246 -267.489045) (xy 265.29449 -267.627705) (xy 265.425926 -267.771883)
			(xy 265.551331 -267.921336) (xy 265.670495 -268.07581) (xy 265.783216 -268.235047) (xy 265.889305 -268.398778)
			(xy 265.988583 -268.566725) (xy 266.080881 -268.738608) (xy 266.094491 -268.766658) (xy 271.815721 -268.766658)
			(xy 271.815721 -268.712146) (xy 271.823479 -268.658189) (xy 271.838837 -268.605885) (xy 271.861482 -268.556299)
			(xy 271.890954 -268.510441) (xy 271.926652 -268.469244) (xy 271.96785 -268.433547) (xy 272.01371 -268.404076)
			(xy 272.063296 -268.381432) (xy 272.1156 -268.366076) (xy 272.169558 -268.35832) (xy 272.196814 -268.357858)
			(xy 272.222265 -268.358291) (xy 272.272712 -268.365091) (xy 272.321805 -268.378542) (xy 272.345404 -268.388084)
			(xy 272.358518 -268.393175) (xy 272.386414 -268.396718) (xy 272.414218 -268.392512) (xy 272.439817 -268.380875)
			(xy 272.461267 -268.362692) (xy 272.476939 -268.339344) (xy 272.485642 -268.312605) (xy 272.486715 -268.284505)
			(xy 272.483834 -268.270736) (xy 272.478981 -268.24896) (xy 272.473764 -268.204651) (xy 272.47342 -268.182344)
			(xy 272.473808 -268.155088) (xy 272.48156 -268.101129) (xy 272.496912 -268.048823) (xy 272.519551 -267.999234)
			(xy 272.549018 -267.953372) (xy 272.584712 -267.91217) (xy 272.625906 -267.876468) (xy 272.671761 -267.846991)
			(xy 272.721345 -267.824341) (xy 272.773648 -267.808977) (xy 272.827605 -267.801214) (xy 272.882118 -267.801208)
			(xy 272.936076 -267.808961) (xy 272.988382 -267.824314) (xy 273.037971 -267.846954) (xy 273.083832 -267.876421)
			(xy 273.125033 -267.912116) (xy 273.160735 -267.95331) (xy 273.190211 -267.999166) (xy 273.212861 -268.04875)
			(xy 273.228224 -268.101053) (xy 273.235987 -268.15501) (xy 273.235991 -268.209523) (xy 273.228238 -268.263481)
			(xy 273.212885 -268.315787) (xy 273.190243 -268.365375) (xy 273.160775 -268.411237) (xy 273.125081 -268.452437)
			(xy 273.083886 -268.488139) (xy 273.038029 -268.517614) (xy 272.988445 -268.540263) (xy 272.936141 -268.555625)
			(xy 272.882184 -268.563387) (xy 272.854928 -268.563852) (xy 272.829477 -268.563405) (xy 272.779031 -268.55661)
			(xy 272.729937 -268.543165) (xy 272.706338 -268.533626) (xy 272.693217 -268.528571) (xy 272.665332 -268.525047)
			(xy 272.637544 -268.529263) (xy 272.611959 -268.540898) (xy 272.590519 -268.559071) (xy 272.574848 -268.582403)
			(xy 272.566135 -268.609124) (xy 272.565041 -268.637209) (xy 272.567908 -268.650974) (xy 272.572763 -268.672749)
			(xy 272.577979 -268.717059) (xy 272.578322 -268.739366) (xy 272.577881 -268.766622) (xy 272.570128 -268.82058)
			(xy 272.554775 -268.872885) (xy 272.532133 -268.922473) (xy 272.502665 -268.968334) (xy 272.46697 -269.009534)
			(xy 272.425775 -269.045234) (xy 272.379919 -269.074708) (xy 272.330334 -269.097356) (xy 272.278031 -269.112717)
			(xy 272.224074 -269.120478) (xy 272.169562 -269.12048) (xy 272.115604 -269.112725) (xy 272.0633 -269.097369)
			(xy 272.013713 -269.074726) (xy 271.967854 -269.045256) (xy 271.926655 -269.009559) (xy 271.890956 -268.968362)
			(xy 271.861484 -268.922505) (xy 271.838838 -268.872919) (xy 271.823479 -268.820615) (xy 271.815721 -268.766658)
			(xy 266.094491 -268.766658) (xy 266.166046 -268.914134) (xy 266.243932 -269.093009) (xy 266.314409 -269.274931)
			(xy 266.377357 -269.459593) (xy 266.432672 -269.646683) (xy 266.480258 -269.835887) (xy 266.520037 -270.026884)
			(xy 266.551941 -270.219354) (xy 266.575916 -270.412972) (xy 266.591922 -270.60741) (xy 266.599931 -270.802342)
			(xy 266.600432 -270.89989) (xy 317.098687 -270.89989) (xy 317.102693 -270.704835) (xy 317.114703 -270.510109)
			(xy 317.134698 -270.31604) (xy 317.162643 -270.122956) (xy 317.198492 -269.931181) (xy 317.242184 -269.741041)
			(xy 317.293645 -269.552854) (xy 317.352789 -269.366939) (xy 317.419516 -269.183608) (xy 317.493713 -269.003172)
			(xy 317.575255 -268.825934) (xy 317.664006 -268.652193) (xy 317.759814 -268.482242) (xy 317.862519 -268.316368)
			(xy 317.971947 -268.15485) (xy 318.087914 -267.997961) (xy 318.210225 -267.845966) (xy 318.338672 -267.69912)
			(xy 318.47304 -267.557671) (xy 318.613102 -267.421858) (xy 318.758621 -267.291909) (xy 318.909353 -267.168045)
			(xy 319.065043 -267.050473) (xy 319.225429 -266.939393) (xy 319.39024 -266.83499) (xy 319.559198 -266.737442)
			(xy 319.732019 -266.646913) (xy 319.908411 -266.563555) (xy 320.088076 -266.487509) (xy 320.270711 -266.418904)
			(xy 320.45601 -266.357854) (xy 320.643658 -266.304464) (xy 320.83334 -266.258822) (xy 321.024737 -266.221006)
			(xy 321.217524 -266.19108) (xy 321.411377 -266.169094) (xy 321.60597 -266.155085) (xy 321.800973 -266.149077)
			(xy 321.996059 -266.15108) (xy 322.190898 -266.161091) (xy 322.385162 -266.179092) (xy 322.578523 -266.205054)
			(xy 322.770656 -266.238932) (xy 322.961235 -266.280669) (xy 323.14994 -266.330196) (xy 323.336453 -266.387428)
			(xy 323.520459 -266.452269) (xy 323.701647 -266.52461) (xy 323.879713 -266.604328) (xy 324.054356 -266.69129)
			(xy 324.225282 -266.785349) (xy 324.392201 -266.886345) (xy 324.554834 -266.99411) (xy 324.712905 -267.10846)
			(xy 324.866148 -267.229203) (xy 325.014305 -267.356137) (xy 325.157126 -267.489045) (xy 325.29437 -267.627705)
			(xy 325.425806 -267.771883) (xy 325.551211 -267.921336) (xy 325.670375 -268.07581) (xy 325.783096 -268.235047)
			(xy 325.889185 -268.398778) (xy 325.988463 -268.566725) (xy 326.080761 -268.738608) (xy 326.165926 -268.914134)
			(xy 326.243812 -269.093009) (xy 326.314289 -269.274931) (xy 326.377237 -269.459593) (xy 326.432552 -269.646683)
			(xy 326.480138 -269.835887) (xy 326.519917 -270.026884) (xy 326.551821 -270.219354) (xy 326.575796 -270.412972)
			(xy 326.591802 -270.60741) (xy 326.599811 -270.802342) (xy 326.600312 -270.89989) (xy 326.599811 -270.997438)
			(xy 326.591802 -271.19237) (xy 326.575796 -271.386808) (xy 326.551821 -271.580426) (xy 326.519917 -271.772896)
			(xy 326.480138 -271.963893) (xy 326.432552 -272.153097) (xy 326.377237 -272.340187) (xy 326.314289 -272.524849)
			(xy 326.243812 -272.706771) (xy 326.165926 -272.885646) (xy 326.080761 -273.061172) (xy 325.988463 -273.233055)
			(xy 325.889185 -273.401002) (xy 325.783096 -273.564733) (xy 325.670375 -273.72397) (xy 325.551211 -273.878444)
			(xy 325.425806 -274.027897) (xy 325.29437 -274.172075) (xy 325.157126 -274.310735) (xy 325.014305 -274.443643)
			(xy 324.866148 -274.570577) (xy 324.712905 -274.69132) (xy 324.554834 -274.80567) (xy 324.392201 -274.913435)
			(xy 324.225282 -275.014431) (xy 324.054356 -275.10849) (xy 323.879713 -275.195452) (xy 323.701647 -275.27517)
			(xy 323.520459 -275.347511) (xy 323.336453 -275.412352) (xy 323.14994 -275.469584) (xy 322.961235 -275.519111)
			(xy 322.770656 -275.560848) (xy 322.578523 -275.594726) (xy 322.385162 -275.620688) (xy 322.190898 -275.638689)
			(xy 321.996059 -275.6487) (xy 321.800973 -275.650703) (xy 321.60597 -275.644695) (xy 321.411377 -275.630686)
			(xy 321.217524 -275.6087) (xy 321.024737 -275.578774) (xy 320.83334 -275.540958) (xy 320.643658 -275.495316)
			(xy 320.45601 -275.441926) (xy 320.270711 -275.380876) (xy 320.088076 -275.312271) (xy 319.908411 -275.236225)
			(xy 319.732019 -275.152867) (xy 319.559198 -275.062338) (xy 319.39024 -274.96479) (xy 319.225429 -274.860387)
			(xy 319.065043 -274.749307) (xy 318.909353 -274.631735) (xy 318.758621 -274.507871) (xy 318.613102 -274.377922)
			(xy 318.47304 -274.242109) (xy 318.338672 -274.10066) (xy 318.210225 -273.953814) (xy 318.087914 -273.801819)
			(xy 317.971947 -273.64493) (xy 317.862519 -273.483412) (xy 317.759814 -273.317538) (xy 317.664006 -273.147587)
			(xy 317.575255 -272.973846) (xy 317.493713 -272.796608) (xy 317.419516 -272.616172) (xy 317.352789 -272.432841)
			(xy 317.293645 -272.246926) (xy 317.242184 -272.058739) (xy 317.198492 -271.868599) (xy 317.162643 -271.676824)
			(xy 317.134698 -271.48374) (xy 317.114703 -271.289671) (xy 317.102693 -271.094945) (xy 317.098687 -270.89989)
			(xy 266.600432 -270.89989) (xy 266.599931 -270.997438) (xy 266.591922 -271.19237) (xy 266.575916 -271.386808)
			(xy 266.551941 -271.580426) (xy 266.520037 -271.772896) (xy 266.51269 -271.808173) (xy 272.60549 -271.808173)
			(xy 272.60549 -271.754875) (xy 272.613433 -271.702171) (xy 272.629143 -271.651241) (xy 272.652269 -271.60322)
			(xy 272.682293 -271.559183) (xy 272.718545 -271.520112) (xy 272.760216 -271.486881) (xy 272.806374 -271.460232)
			(xy 272.855988 -271.44076) (xy 272.90795 -271.4289) (xy 272.9611 -271.424917) (xy 273.01425 -271.4289)
			(xy 273.066212 -271.44076) (xy 273.115826 -271.460232) (xy 273.161984 -271.486881) (xy 273.203655 -271.520112)
			(xy 273.239907 -271.559183) (xy 273.269931 -271.60322) (xy 273.293057 -271.651241) (xy 273.308767 -271.702171)
			(xy 273.31671 -271.754875) (xy 273.317208 -271.781524) (xy 273.31671 -271.808173) (xy 273.308767 -271.860877)
			(xy 273.293057 -271.911807) (xy 273.269931 -271.959828) (xy 273.239907 -272.003865) (xy 273.203655 -272.042936)
			(xy 273.161984 -272.076167) (xy 273.115826 -272.102816) (xy 273.066212 -272.122288) (xy 273.01425 -272.134148)
			(xy 272.9611 -272.138132) (xy 272.90795 -272.134148) (xy 272.855988 -272.122288) (xy 272.806374 -272.102816)
			(xy 272.760216 -272.076167) (xy 272.718545 -272.042936) (xy 272.682293 -272.003865) (xy 272.652269 -271.959828)
			(xy 272.629143 -271.911807) (xy 272.613433 -271.860877) (xy 272.60549 -271.808173) (xy 266.51269 -271.808173)
			(xy 266.480258 -271.963893) (xy 266.433559 -272.14957) (xy 276.34363 -272.14957) (xy 276.34759 -272.100516)
			(xy 276.359367 -272.052732) (xy 276.378658 -272.007456) (xy 276.404961 -271.96586) (xy 276.437596 -271.929023)
			(xy 276.475717 -271.897898) (xy 276.518338 -271.873291) (xy 276.564354 -271.855839) (xy 276.612573 -271.845995)
			(xy 276.661748 -271.844014) (xy 276.710603 -271.849946) (xy 276.757874 -271.863638) (xy 276.802336 -271.884736)
			(xy 276.842839 -271.912692) (xy 276.878332 -271.946784) (xy 276.907897 -271.986128) (xy 276.930768 -272.029705)
			(xy 276.946352 -272.076386) (xy 276.954247 -272.124963) (xy 276.954742 -272.14957) (xy 278.243804 -272.14957)
			(xy 278.247764 -272.100516) (xy 278.259541 -272.052732) (xy 278.278832 -272.007456) (xy 278.305135 -271.96586)
			(xy 278.33777 -271.929023) (xy 278.375891 -271.897898) (xy 278.418512 -271.873291) (xy 278.464528 -271.855839)
			(xy 278.512747 -271.845995) (xy 278.561922 -271.844014) (xy 278.610777 -271.849946) (xy 278.658048 -271.863638)
			(xy 278.70251 -271.884736) (xy 278.743013 -271.912692) (xy 278.778506 -271.946784) (xy 278.808071 -271.986128)
			(xy 278.830942 -272.029705) (xy 278.846526 -272.076386) (xy 278.854421 -272.124963) (xy 278.854916 -272.14957)
			(xy 280.143724 -272.14957) (xy 280.147684 -272.100516) (xy 280.159461 -272.052732) (xy 280.178752 -272.007456)
			(xy 280.205055 -271.96586) (xy 280.23769 -271.929023) (xy 280.275811 -271.897898) (xy 280.318432 -271.873291)
			(xy 280.364448 -271.855839) (xy 280.412667 -271.845995) (xy 280.461842 -271.844014) (xy 280.510697 -271.849946)
			(xy 280.557968 -271.863638) (xy 280.60243 -271.884736) (xy 280.642933 -271.912692) (xy 280.678426 -271.946784)
			(xy 280.707991 -271.986128) (xy 280.730862 -272.029705) (xy 280.746446 -272.076386) (xy 280.754341 -272.124963)
			(xy 280.754836 -272.14957) (xy 282.043644 -272.14957) (xy 282.047604 -272.100516) (xy 282.059381 -272.052732)
			(xy 282.078672 -272.007456) (xy 282.104975 -271.96586) (xy 282.13761 -271.929023) (xy 282.175731 -271.897898)
			(xy 282.218352 -271.873291) (xy 282.264368 -271.855839) (xy 282.312587 -271.845995) (xy 282.361762 -271.844014)
			(xy 282.410617 -271.849946) (xy 282.457888 -271.863638) (xy 282.50235 -271.884736) (xy 282.542853 -271.912692)
			(xy 282.578346 -271.946784) (xy 282.607911 -271.986128) (xy 282.630782 -272.029705) (xy 282.646366 -272.076386)
			(xy 282.654261 -272.124963) (xy 282.654756 -272.14957) (xy 283.943818 -272.14957) (xy 283.947778 -272.100516)
			(xy 283.959555 -272.052732) (xy 283.978846 -272.007456) (xy 284.005149 -271.96586) (xy 284.037784 -271.929023)
			(xy 284.075905 -271.897898) (xy 284.118526 -271.873291) (xy 284.164542 -271.855839) (xy 284.212761 -271.845995)
			(xy 284.261936 -271.844014) (xy 284.310791 -271.849946) (xy 284.358062 -271.863638) (xy 284.402524 -271.884736)
			(xy 284.443027 -271.912692) (xy 284.47852 -271.946784) (xy 284.508085 -271.986128) (xy 284.530956 -272.029705)
			(xy 284.54654 -272.076386) (xy 284.554435 -272.124963) (xy 284.55493 -272.14957) (xy 285.843738 -272.14957)
			(xy 285.847698 -272.100516) (xy 285.859475 -272.052732) (xy 285.878766 -272.007456) (xy 285.905069 -271.96586)
			(xy 285.937704 -271.929023) (xy 285.975825 -271.897898) (xy 286.018446 -271.873291) (xy 286.064462 -271.855839)
			(xy 286.112681 -271.845995) (xy 286.161856 -271.844014) (xy 286.210711 -271.849946) (xy 286.257982 -271.863638)
			(xy 286.302444 -271.884736) (xy 286.342947 -271.912692) (xy 286.37844 -271.946784) (xy 286.408005 -271.986128)
			(xy 286.430876 -272.029705) (xy 286.44646 -272.076386) (xy 286.454355 -272.124963) (xy 286.45485 -272.14957)
			(xy 287.743658 -272.14957) (xy 287.747618 -272.100516) (xy 287.759395 -272.052732) (xy 287.778686 -272.007456)
			(xy 287.804989 -271.96586) (xy 287.837624 -271.929023) (xy 287.875745 -271.897898) (xy 287.918366 -271.873291)
			(xy 287.964382 -271.855839) (xy 288.012601 -271.845995) (xy 288.061776 -271.844014) (xy 288.110631 -271.849946)
			(xy 288.157902 -271.863638) (xy 288.202364 -271.884736) (xy 288.242867 -271.912692) (xy 288.27836 -271.946784)
			(xy 288.307925 -271.986128) (xy 288.330796 -272.029705) (xy 288.34638 -272.076386) (xy 288.354275 -272.124963)
			(xy 288.35477 -272.14957) (xy 289.643832 -272.14957) (xy 289.647792 -272.100516) (xy 289.659569 -272.052732)
			(xy 289.67886 -272.007456) (xy 289.705163 -271.96586) (xy 289.737798 -271.929023) (xy 289.775919 -271.897898)
			(xy 289.81854 -271.873291) (xy 289.864556 -271.855839) (xy 289.912775 -271.845995) (xy 289.96195 -271.844014)
			(xy 290.010805 -271.849946) (xy 290.058076 -271.863638) (xy 290.102538 -271.884736) (xy 290.143041 -271.912692)
			(xy 290.178534 -271.946784) (xy 290.208099 -271.986128) (xy 290.23097 -272.029705) (xy 290.246554 -272.076386)
			(xy 290.254449 -272.124963) (xy 290.254939 -272.149316) (xy 291.543752 -272.149316) (xy 291.547712 -272.100262)
			(xy 291.559489 -272.052478) (xy 291.57878 -272.007202) (xy 291.605083 -271.965606) (xy 291.637718 -271.928769)
			(xy 291.675839 -271.897644) (xy 291.71846 -271.873037) (xy 291.764476 -271.855585) (xy 291.812695 -271.845741)
			(xy 291.86187 -271.84376) (xy 291.910725 -271.849692) (xy 291.957996 -271.863384) (xy 292.002458 -271.884482)
			(xy 292.042961 -271.912438) (xy 292.078454 -271.94653) (xy 292.108019 -271.985874) (xy 292.13089 -272.029451)
			(xy 292.146474 -272.076132) (xy 292.154369 -272.124709) (xy 292.154864 -272.149316) (xy 292.154859 -272.14957)
			(xy 293.443672 -272.14957) (xy 293.447632 -272.100516) (xy 293.459409 -272.052732) (xy 293.4787 -272.007456)
			(xy 293.505003 -271.96586) (xy 293.537638 -271.929023) (xy 293.575759 -271.897898) (xy 293.61838 -271.873291)
			(xy 293.664396 -271.855839) (xy 293.712615 -271.845995) (xy 293.76179 -271.844014) (xy 293.810645 -271.849946)
			(xy 293.857916 -271.863638) (xy 293.902378 -271.884736) (xy 293.942881 -271.912692) (xy 293.978374 -271.946784)
			(xy 294.007939 -271.986128) (xy 294.03081 -272.029705) (xy 294.046394 -272.076386) (xy 294.054289 -272.124963)
			(xy 294.054784 -272.14957) (xy 295.343846 -272.14957) (xy 295.347806 -272.100516) (xy 295.359583 -272.052732)
			(xy 295.378874 -272.007456) (xy 295.405177 -271.96586) (xy 295.437812 -271.929023) (xy 295.475933 -271.897898)
			(xy 295.518554 -271.873291) (xy 295.56457 -271.855839) (xy 295.612789 -271.845995) (xy 295.661964 -271.844014)
			(xy 295.710819 -271.849946) (xy 295.75809 -271.863638) (xy 295.802552 -271.884736) (xy 295.843055 -271.912692)
			(xy 295.878548 -271.946784) (xy 295.908113 -271.986128) (xy 295.930984 -272.029705) (xy 295.946568 -272.076386)
			(xy 295.954463 -272.124963) (xy 295.954958 -272.14957) (xy 297.243766 -272.14957) (xy 297.247726 -272.100516)
			(xy 297.259503 -272.052732) (xy 297.278794 -272.007456) (xy 297.305097 -271.96586) (xy 297.337732 -271.929023)
			(xy 297.375853 -271.897898) (xy 297.418474 -271.873291) (xy 297.46449 -271.855839) (xy 297.512709 -271.845995)
			(xy 297.561884 -271.844014) (xy 297.610739 -271.849946) (xy 297.65801 -271.863638) (xy 297.702472 -271.884736)
			(xy 297.742975 -271.912692) (xy 297.778468 -271.946784) (xy 297.808033 -271.986128) (xy 297.830904 -272.029705)
			(xy 297.846488 -272.076386) (xy 297.854383 -272.124963) (xy 297.854878 -272.14957) (xy 299.143686 -272.14957)
			(xy 299.147646 -272.100516) (xy 299.159423 -272.052732) (xy 299.178714 -272.007456) (xy 299.205017 -271.96586)
			(xy 299.237652 -271.929023) (xy 299.275773 -271.897898) (xy 299.318394 -271.873291) (xy 299.36441 -271.855839)
			(xy 299.412629 -271.845995) (xy 299.461804 -271.844014) (xy 299.510659 -271.849946) (xy 299.55793 -271.863638)
			(xy 299.602392 -271.884736) (xy 299.642895 -271.912692) (xy 299.678388 -271.946784) (xy 299.707953 -271.986128)
			(xy 299.730824 -272.029705) (xy 299.746408 -272.076386) (xy 299.754303 -272.124963) (xy 299.754798 -272.14957)
			(xy 301.04386 -272.14957) (xy 301.04782 -272.100516) (xy 301.059597 -272.052732) (xy 301.078888 -272.007456)
			(xy 301.105191 -271.96586) (xy 301.137826 -271.929023) (xy 301.175947 -271.897898) (xy 301.218568 -271.873291)
			(xy 301.264584 -271.855839) (xy 301.312803 -271.845995) (xy 301.361978 -271.844014) (xy 301.410833 -271.849946)
			(xy 301.458104 -271.863638) (xy 301.502566 -271.884736) (xy 301.543069 -271.912692) (xy 301.578562 -271.946784)
			(xy 301.608127 -271.986128) (xy 301.630998 -272.029705) (xy 301.646582 -272.076386) (xy 301.654477 -272.124963)
			(xy 301.654972 -272.14957) (xy 302.94378 -272.14957) (xy 302.94774 -272.100516) (xy 302.959517 -272.052732)
			(xy 302.978808 -272.007456) (xy 303.005111 -271.96586) (xy 303.037746 -271.929023) (xy 303.075867 -271.897898)
			(xy 303.118488 -271.873291) (xy 303.164504 -271.855839) (xy 303.212723 -271.845995) (xy 303.261898 -271.844014)
			(xy 303.310753 -271.849946) (xy 303.358024 -271.863638) (xy 303.402486 -271.884736) (xy 303.442989 -271.912692)
			(xy 303.478482 -271.946784) (xy 303.508047 -271.986128) (xy 303.530918 -272.029705) (xy 303.546502 -272.076386)
			(xy 303.554397 -272.124963) (xy 303.554892 -272.14957) (xy 304.8437 -272.14957) (xy 304.84766 -272.100516)
			(xy 304.859437 -272.052732) (xy 304.878728 -272.007456) (xy 304.905031 -271.96586) (xy 304.937666 -271.929023)
			(xy 304.975787 -271.897898) (xy 305.018408 -271.873291) (xy 305.064424 -271.855839) (xy 305.112643 -271.845995)
			(xy 305.161818 -271.844014) (xy 305.210673 -271.849946) (xy 305.257944 -271.863638) (xy 305.302406 -271.884736)
			(xy 305.342909 -271.912692) (xy 305.378402 -271.946784) (xy 305.407967 -271.986128) (xy 305.430838 -272.029705)
			(xy 305.446422 -272.076386) (xy 305.454317 -272.124963) (xy 305.454812 -272.14957) (xy 306.743874 -272.14957)
			(xy 306.747834 -272.100516) (xy 306.759611 -272.052732) (xy 306.778902 -272.007456) (xy 306.805205 -271.96586)
			(xy 306.83784 -271.929023) (xy 306.875961 -271.897898) (xy 306.918582 -271.873291) (xy 306.964598 -271.855839)
			(xy 307.012817 -271.845995) (xy 307.061992 -271.844014) (xy 307.110847 -271.849946) (xy 307.158118 -271.863638)
			(xy 307.20258 -271.884736) (xy 307.243083 -271.912692) (xy 307.278576 -271.946784) (xy 307.308141 -271.986128)
			(xy 307.331012 -272.029705) (xy 307.346596 -272.076386) (xy 307.354491 -272.124963) (xy 307.354986 -272.14957)
			(xy 308.644048 -272.14957) (xy 308.648008 -272.100516) (xy 308.659785 -272.052732) (xy 308.679076 -272.007456)
			(xy 308.705379 -271.96586) (xy 308.738014 -271.929023) (xy 308.776135 -271.897898) (xy 308.818756 -271.873291)
			(xy 308.864772 -271.855839) (xy 308.912991 -271.845995) (xy 308.962166 -271.844014) (xy 309.011021 -271.849946)
			(xy 309.058292 -271.863638) (xy 309.102754 -271.884736) (xy 309.143257 -271.912692) (xy 309.17875 -271.946784)
			(xy 309.208315 -271.986128) (xy 309.231186 -272.029705) (xy 309.24677 -272.076386) (xy 309.254665 -272.124963)
			(xy 309.25516 -272.14957) (xy 310.543968 -272.14957) (xy 310.547928 -272.100516) (xy 310.559705 -272.052732)
			(xy 310.578996 -272.007456) (xy 310.605299 -271.96586) (xy 310.637934 -271.929023) (xy 310.676055 -271.897898)
			(xy 310.718676 -271.873291) (xy 310.764692 -271.855839) (xy 310.812911 -271.845995) (xy 310.862086 -271.844014)
			(xy 310.910941 -271.849946) (xy 310.958212 -271.863638) (xy 311.002674 -271.884736) (xy 311.043177 -271.912692)
			(xy 311.07867 -271.946784) (xy 311.108235 -271.986128) (xy 311.131106 -272.029705) (xy 311.14669 -272.076386)
			(xy 311.154585 -272.124963) (xy 311.15508 -272.14957) (xy 312.443888 -272.14957) (xy 312.447848 -272.100516)
			(xy 312.459625 -272.052732) (xy 312.478916 -272.007456) (xy 312.505219 -271.96586) (xy 312.537854 -271.929023)
			(xy 312.575975 -271.897898) (xy 312.618596 -271.873291) (xy 312.664612 -271.855839) (xy 312.712831 -271.845995)
			(xy 312.762006 -271.844014) (xy 312.810861 -271.849946) (xy 312.858132 -271.863638) (xy 312.902594 -271.884736)
			(xy 312.943097 -271.912692) (xy 312.97859 -271.946784) (xy 313.008155 -271.986128) (xy 313.031026 -272.029705)
			(xy 313.04661 -272.076386) (xy 313.054505 -272.124963) (xy 313.055 -272.14957) (xy 313.054505 -272.174177)
			(xy 313.04661 -272.222754) (xy 313.031026 -272.269435) (xy 313.008155 -272.313012) (xy 312.97859 -272.352356)
			(xy 312.943097 -272.386448) (xy 312.902594 -272.414404) (xy 312.858132 -272.435502) (xy 312.810861 -272.449194)
			(xy 312.762006 -272.455126) (xy 312.712831 -272.453145) (xy 312.664612 -272.443301) (xy 312.618596 -272.425849)
			(xy 312.575975 -272.401242) (xy 312.537854 -272.370117) (xy 312.505219 -272.33328) (xy 312.478916 -272.291684)
			(xy 312.459625 -272.246408) (xy 312.447848 -272.198624) (xy 312.443888 -272.14957) (xy 311.15508 -272.14957)
			(xy 311.154585 -272.174177) (xy 311.14669 -272.222754) (xy 311.131106 -272.269435) (xy 311.108235 -272.313012)
			(xy 311.07867 -272.352356) (xy 311.043177 -272.386448) (xy 311.002674 -272.414404) (xy 310.958212 -272.435502)
			(xy 310.910941 -272.449194) (xy 310.862086 -272.455126) (xy 310.812911 -272.453145) (xy 310.764692 -272.443301)
			(xy 310.718676 -272.425849) (xy 310.676055 -272.401242) (xy 310.637934 -272.370117) (xy 310.605299 -272.33328)
			(xy 310.578996 -272.291684) (xy 310.559705 -272.246408) (xy 310.547928 -272.198624) (xy 310.543968 -272.14957)
			(xy 309.25516 -272.14957) (xy 309.254665 -272.174177) (xy 309.24677 -272.222754) (xy 309.231186 -272.269435)
			(xy 309.208315 -272.313012) (xy 309.17875 -272.352356) (xy 309.143257 -272.386448) (xy 309.102754 -272.414404)
			(xy 309.058292 -272.435502) (xy 309.011021 -272.449194) (xy 308.962166 -272.455126) (xy 308.912991 -272.453145)
			(xy 308.864772 -272.443301) (xy 308.818756 -272.425849) (xy 308.776135 -272.401242) (xy 308.738014 -272.370117)
			(xy 308.705379 -272.33328) (xy 308.679076 -272.291684) (xy 308.659785 -272.246408) (xy 308.648008 -272.198624)
			(xy 308.644048 -272.14957) (xy 307.354986 -272.14957) (xy 307.354491 -272.174177) (xy 307.346596 -272.222754)
			(xy 307.331012 -272.269435) (xy 307.308141 -272.313012) (xy 307.278576 -272.352356) (xy 307.243083 -272.386448)
			(xy 307.20258 -272.414404) (xy 307.158118 -272.435502) (xy 307.110847 -272.449194) (xy 307.061992 -272.455126)
			(xy 307.012817 -272.453145) (xy 306.964598 -272.443301) (xy 306.918582 -272.425849) (xy 306.875961 -272.401242)
			(xy 306.83784 -272.370117) (xy 306.805205 -272.33328) (xy 306.778902 -272.291684) (xy 306.759611 -272.246408)
			(xy 306.747834 -272.198624) (xy 306.743874 -272.14957) (xy 305.454812 -272.14957) (xy 305.454317 -272.174177)
			(xy 305.446422 -272.222754) (xy 305.430838 -272.269435) (xy 305.407967 -272.313012) (xy 305.378402 -272.352356)
			(xy 305.342909 -272.386448) (xy 305.302406 -272.414404) (xy 305.257944 -272.435502) (xy 305.210673 -272.449194)
			(xy 305.161818 -272.455126) (xy 305.112643 -272.453145) (xy 305.064424 -272.443301) (xy 305.018408 -272.425849)
			(xy 304.975787 -272.401242) (xy 304.937666 -272.370117) (xy 304.905031 -272.33328) (xy 304.878728 -272.291684)
			(xy 304.859437 -272.246408) (xy 304.84766 -272.198624) (xy 304.8437 -272.14957) (xy 303.554892 -272.14957)
			(xy 303.554397 -272.174177) (xy 303.546502 -272.222754) (xy 303.530918 -272.269435) (xy 303.508047 -272.313012)
			(xy 303.478482 -272.352356) (xy 303.442989 -272.386448) (xy 303.402486 -272.414404) (xy 303.358024 -272.435502)
			(xy 303.310753 -272.449194) (xy 303.261898 -272.455126) (xy 303.212723 -272.453145) (xy 303.164504 -272.443301)
			(xy 303.118488 -272.425849) (xy 303.075867 -272.401242) (xy 303.037746 -272.370117) (xy 303.005111 -272.33328)
			(xy 302.978808 -272.291684) (xy 302.959517 -272.246408) (xy 302.94774 -272.198624) (xy 302.94378 -272.14957)
			(xy 301.654972 -272.14957) (xy 301.654477 -272.174177) (xy 301.646582 -272.222754) (xy 301.630998 -272.269435)
			(xy 301.608127 -272.313012) (xy 301.578562 -272.352356) (xy 301.543069 -272.386448) (xy 301.502566 -272.414404)
			(xy 301.458104 -272.435502) (xy 301.410833 -272.449194) (xy 301.361978 -272.455126) (xy 301.312803 -272.453145)
			(xy 301.264584 -272.443301) (xy 301.218568 -272.425849) (xy 301.175947 -272.401242) (xy 301.137826 -272.370117)
			(xy 301.105191 -272.33328) (xy 301.078888 -272.291684) (xy 301.059597 -272.246408) (xy 301.04782 -272.198624)
			(xy 301.04386 -272.14957) (xy 299.754798 -272.14957) (xy 299.754303 -272.174177) (xy 299.746408 -272.222754)
			(xy 299.730824 -272.269435) (xy 299.707953 -272.313012) (xy 299.678388 -272.352356) (xy 299.642895 -272.386448)
			(xy 299.602392 -272.414404) (xy 299.55793 -272.435502) (xy 299.510659 -272.449194) (xy 299.461804 -272.455126)
			(xy 299.412629 -272.453145) (xy 299.36441 -272.443301) (xy 299.318394 -272.425849) (xy 299.275773 -272.401242)
			(xy 299.237652 -272.370117) (xy 299.205017 -272.33328) (xy 299.178714 -272.291684) (xy 299.159423 -272.246408)
			(xy 299.147646 -272.198624) (xy 299.143686 -272.14957) (xy 297.854878 -272.14957) (xy 297.854383 -272.174177)
			(xy 297.846488 -272.222754) (xy 297.830904 -272.269435) (xy 297.808033 -272.313012) (xy 297.778468 -272.352356)
			(xy 297.742975 -272.386448) (xy 297.702472 -272.414404) (xy 297.65801 -272.435502) (xy 297.610739 -272.449194)
			(xy 297.561884 -272.455126) (xy 297.512709 -272.453145) (xy 297.46449 -272.443301) (xy 297.418474 -272.425849)
			(xy 297.375853 -272.401242) (xy 297.337732 -272.370117) (xy 297.305097 -272.33328) (xy 297.278794 -272.291684)
			(xy 297.259503 -272.246408) (xy 297.247726 -272.198624) (xy 297.243766 -272.14957) (xy 295.954958 -272.14957)
			(xy 295.954463 -272.174177) (xy 295.946568 -272.222754) (xy 295.930984 -272.269435) (xy 295.908113 -272.313012)
			(xy 295.878548 -272.352356) (xy 295.843055 -272.386448) (xy 295.802552 -272.414404) (xy 295.75809 -272.435502)
			(xy 295.710819 -272.449194) (xy 295.661964 -272.455126) (xy 295.612789 -272.453145) (xy 295.56457 -272.443301)
			(xy 295.518554 -272.425849) (xy 295.475933 -272.401242) (xy 295.437812 -272.370117) (xy 295.405177 -272.33328)
			(xy 295.378874 -272.291684) (xy 295.359583 -272.246408) (xy 295.347806 -272.198624) (xy 295.343846 -272.14957)
			(xy 294.054784 -272.14957) (xy 294.054289 -272.174177) (xy 294.046394 -272.222754) (xy 294.03081 -272.269435)
			(xy 294.007939 -272.313012) (xy 293.978374 -272.352356) (xy 293.942881 -272.386448) (xy 293.902378 -272.414404)
			(xy 293.857916 -272.435502) (xy 293.810645 -272.449194) (xy 293.76179 -272.455126) (xy 293.712615 -272.453145)
			(xy 293.664396 -272.443301) (xy 293.61838 -272.425849) (xy 293.575759 -272.401242) (xy 293.537638 -272.370117)
			(xy 293.505003 -272.33328) (xy 293.4787 -272.291684) (xy 293.459409 -272.246408) (xy 293.447632 -272.198624)
			(xy 293.443672 -272.14957) (xy 292.154859 -272.14957) (xy 292.154369 -272.173923) (xy 292.146474 -272.2225)
			(xy 292.13089 -272.269181) (xy 292.108019 -272.312758) (xy 292.078454 -272.352102) (xy 292.042961 -272.386194)
			(xy 292.002458 -272.41415) (xy 291.957996 -272.435248) (xy 291.910725 -272.44894) (xy 291.86187 -272.454872)
			(xy 291.812695 -272.452891) (xy 291.764476 -272.443047) (xy 291.71846 -272.425595) (xy 291.675839 -272.400988)
			(xy 291.637718 -272.369863) (xy 291.605083 -272.333026) (xy 291.57878 -272.29143) (xy 291.559489 -272.246154)
			(xy 291.547712 -272.19837) (xy 291.543752 -272.149316) (xy 290.254939 -272.149316) (xy 290.254944 -272.14957)
			(xy 290.254449 -272.174177) (xy 290.246554 -272.222754) (xy 290.23097 -272.269435) (xy 290.208099 -272.313012)
			(xy 290.178534 -272.352356) (xy 290.143041 -272.386448) (xy 290.102538 -272.414404) (xy 290.058076 -272.435502)
			(xy 290.010805 -272.449194) (xy 289.96195 -272.455126) (xy 289.912775 -272.453145) (xy 289.864556 -272.443301)
			(xy 289.81854 -272.425849) (xy 289.775919 -272.401242) (xy 289.737798 -272.370117) (xy 289.705163 -272.33328)
			(xy 289.67886 -272.291684) (xy 289.659569 -272.246408) (xy 289.647792 -272.198624) (xy 289.643832 -272.14957)
			(xy 288.35477 -272.14957) (xy 288.354275 -272.174177) (xy 288.34638 -272.222754) (xy 288.330796 -272.269435)
			(xy 288.307925 -272.313012) (xy 288.27836 -272.352356) (xy 288.242867 -272.386448) (xy 288.202364 -272.414404)
			(xy 288.157902 -272.435502) (xy 288.110631 -272.449194) (xy 288.061776 -272.455126) (xy 288.012601 -272.453145)
			(xy 287.964382 -272.443301) (xy 287.918366 -272.425849) (xy 287.875745 -272.401242) (xy 287.837624 -272.370117)
			(xy 287.804989 -272.33328) (xy 287.778686 -272.291684) (xy 287.759395 -272.246408) (xy 287.747618 -272.198624)
			(xy 287.743658 -272.14957) (xy 286.45485 -272.14957) (xy 286.454355 -272.174177) (xy 286.44646 -272.222754)
			(xy 286.430876 -272.269435) (xy 286.408005 -272.313012) (xy 286.37844 -272.352356) (xy 286.342947 -272.386448)
			(xy 286.302444 -272.414404) (xy 286.257982 -272.435502) (xy 286.210711 -272.449194) (xy 286.161856 -272.455126)
			(xy 286.112681 -272.453145) (xy 286.064462 -272.443301) (xy 286.018446 -272.425849) (xy 285.975825 -272.401242)
			(xy 285.937704 -272.370117) (xy 285.905069 -272.33328) (xy 285.878766 -272.291684) (xy 285.859475 -272.246408)
			(xy 285.847698 -272.198624) (xy 285.843738 -272.14957) (xy 284.55493 -272.14957) (xy 284.554435 -272.174177)
			(xy 284.54654 -272.222754) (xy 284.530956 -272.269435) (xy 284.508085 -272.313012) (xy 284.47852 -272.352356)
			(xy 284.443027 -272.386448) (xy 284.402524 -272.414404) (xy 284.358062 -272.435502) (xy 284.310791 -272.449194)
			(xy 284.261936 -272.455126) (xy 284.212761 -272.453145) (xy 284.164542 -272.443301) (xy 284.118526 -272.425849)
			(xy 284.075905 -272.401242) (xy 284.037784 -272.370117) (xy 284.005149 -272.33328) (xy 283.978846 -272.291684)
			(xy 283.959555 -272.246408) (xy 283.947778 -272.198624) (xy 283.943818 -272.14957) (xy 282.654756 -272.14957)
			(xy 282.654261 -272.174177) (xy 282.646366 -272.222754) (xy 282.630782 -272.269435) (xy 282.607911 -272.313012)
			(xy 282.578346 -272.352356) (xy 282.542853 -272.386448) (xy 282.50235 -272.414404) (xy 282.457888 -272.435502)
			(xy 282.410617 -272.449194) (xy 282.361762 -272.455126) (xy 282.312587 -272.453145) (xy 282.264368 -272.443301)
			(xy 282.218352 -272.425849) (xy 282.175731 -272.401242) (xy 282.13761 -272.370117) (xy 282.104975 -272.33328)
			(xy 282.078672 -272.291684) (xy 282.059381 -272.246408) (xy 282.047604 -272.198624) (xy 282.043644 -272.14957)
			(xy 280.754836 -272.14957) (xy 280.754341 -272.174177) (xy 280.746446 -272.222754) (xy 280.730862 -272.269435)
			(xy 280.707991 -272.313012) (xy 280.678426 -272.352356) (xy 280.642933 -272.386448) (xy 280.60243 -272.414404)
			(xy 280.557968 -272.435502) (xy 280.510697 -272.449194) (xy 280.461842 -272.455126) (xy 280.412667 -272.453145)
			(xy 280.364448 -272.443301) (xy 280.318432 -272.425849) (xy 280.275811 -272.401242) (xy 280.23769 -272.370117)
			(xy 280.205055 -272.33328) (xy 280.178752 -272.291684) (xy 280.159461 -272.246408) (xy 280.147684 -272.198624)
			(xy 280.143724 -272.14957) (xy 278.854916 -272.14957) (xy 278.854421 -272.174177) (xy 278.846526 -272.222754)
			(xy 278.830942 -272.269435) (xy 278.808071 -272.313012) (xy 278.778506 -272.352356) (xy 278.743013 -272.386448)
			(xy 278.70251 -272.414404) (xy 278.658048 -272.435502) (xy 278.610777 -272.449194) (xy 278.561922 -272.455126)
			(xy 278.512747 -272.453145) (xy 278.464528 -272.443301) (xy 278.418512 -272.425849) (xy 278.375891 -272.401242)
			(xy 278.33777 -272.370117) (xy 278.305135 -272.33328) (xy 278.278832 -272.291684) (xy 278.259541 -272.246408)
			(xy 278.247764 -272.198624) (xy 278.243804 -272.14957) (xy 276.954742 -272.14957) (xy 276.954247 -272.174177)
			(xy 276.946352 -272.222754) (xy 276.930768 -272.269435) (xy 276.907897 -272.313012) (xy 276.878332 -272.352356)
			(xy 276.842839 -272.386448) (xy 276.802336 -272.414404) (xy 276.757874 -272.435502) (xy 276.710603 -272.449194)
			(xy 276.661748 -272.455126) (xy 276.612573 -272.453145) (xy 276.564354 -272.443301) (xy 276.518338 -272.425849)
			(xy 276.475717 -272.401242) (xy 276.437596 -272.370117) (xy 276.404961 -272.33328) (xy 276.378658 -272.291684)
			(xy 276.359367 -272.246408) (xy 276.34759 -272.198624) (xy 276.34363 -272.14957) (xy 266.433559 -272.14957)
			(xy 266.432672 -272.153097) (xy 266.377357 -272.340187) (xy 266.314409 -272.524849) (xy 266.275686 -272.624804)
			(xy 270.169144 -272.624804) (xy 270.173104 -272.57575) (xy 270.184881 -272.527966) (xy 270.204172 -272.48269)
			(xy 270.230475 -272.441094) (xy 270.26311 -272.404257) (xy 270.301231 -272.373132) (xy 270.343852 -272.348525)
			(xy 270.389868 -272.331073) (xy 270.438087 -272.321229) (xy 270.487262 -272.319248) (xy 270.536117 -272.32518)
			(xy 270.583388 -272.338872) (xy 270.62785 -272.35997) (xy 270.668353 -272.387926) (xy 270.703846 -272.422018)
			(xy 270.733411 -272.461362) (xy 270.756282 -272.504939) (xy 270.771866 -272.55162) (xy 270.779761 -272.600197)
			(xy 270.780256 -272.624804) (xy 271.119104 -272.624804) (xy 271.123064 -272.57575) (xy 271.134841 -272.527966)
			(xy 271.154132 -272.48269) (xy 271.180435 -272.441094) (xy 271.21307 -272.404257) (xy 271.251191 -272.373132)
			(xy 271.293812 -272.348525) (xy 271.339828 -272.331073) (xy 271.388047 -272.321229) (xy 271.437222 -272.319248)
			(xy 271.486077 -272.32518) (xy 271.533348 -272.338872) (xy 271.57781 -272.35997) (xy 271.618313 -272.387926)
			(xy 271.653806 -272.422018) (xy 271.683371 -272.461362) (xy 271.706242 -272.504939) (xy 271.721826 -272.55162)
			(xy 271.729721 -272.600197) (xy 271.730216 -272.624804) (xy 272.069064 -272.624804) (xy 272.073024 -272.57575)
			(xy 272.084801 -272.527966) (xy 272.104092 -272.48269) (xy 272.130395 -272.441094) (xy 272.16303 -272.404257)
			(xy 272.201151 -272.373132) (xy 272.243772 -272.348525) (xy 272.289788 -272.331073) (xy 272.338007 -272.321229)
			(xy 272.387182 -272.319248) (xy 272.436037 -272.32518) (xy 272.483308 -272.338872) (xy 272.52777 -272.35997)
			(xy 272.568273 -272.387926) (xy 272.603766 -272.422018) (xy 272.633331 -272.461362) (xy 272.656202 -272.504939)
			(xy 272.671786 -272.55162) (xy 272.679681 -272.600197) (xy 272.680176 -272.624804) (xy 273.019024 -272.624804)
			(xy 273.022984 -272.57575) (xy 273.034761 -272.527966) (xy 273.054052 -272.48269) (xy 273.080355 -272.441094)
			(xy 273.11299 -272.404257) (xy 273.151111 -272.373132) (xy 273.193732 -272.348525) (xy 273.239748 -272.331073)
			(xy 273.287967 -272.321229) (xy 273.337142 -272.319248) (xy 273.385997 -272.32518) (xy 273.433268 -272.338872)
			(xy 273.47773 -272.35997) (xy 273.518233 -272.387926) (xy 273.553726 -272.422018) (xy 273.583291 -272.461362)
			(xy 273.606162 -272.504939) (xy 273.621746 -272.55162) (xy 273.629641 -272.600197) (xy 273.630136 -272.624804)
			(xy 273.968984 -272.624804) (xy 273.972944 -272.57575) (xy 273.984721 -272.527966) (xy 274.004012 -272.48269)
			(xy 274.030315 -272.441094) (xy 274.06295 -272.404257) (xy 274.101071 -272.373132) (xy 274.143692 -272.348525)
			(xy 274.189708 -272.331073) (xy 274.237927 -272.321229) (xy 274.287102 -272.319248) (xy 274.335957 -272.32518)
			(xy 274.383228 -272.338872) (xy 274.42769 -272.35997) (xy 274.468193 -272.387926) (xy 274.503686 -272.422018)
			(xy 274.533251 -272.461362) (xy 274.556122 -272.504939) (xy 274.571706 -272.55162) (xy 274.579601 -272.600197)
			(xy 274.580096 -272.624804) (xy 274.918944 -272.624804) (xy 274.922904 -272.57575) (xy 274.934681 -272.527966)
			(xy 274.953972 -272.48269) (xy 274.980275 -272.441094) (xy 275.01291 -272.404257) (xy 275.051031 -272.373132)
			(xy 275.093652 -272.348525) (xy 275.139668 -272.331073) (xy 275.187887 -272.321229) (xy 275.237062 -272.319248)
			(xy 275.285917 -272.32518) (xy 275.333188 -272.338872) (xy 275.37765 -272.35997) (xy 275.418153 -272.387926)
			(xy 275.453646 -272.422018) (xy 275.483211 -272.461362) (xy 275.506082 -272.504939) (xy 275.521666 -272.55162)
			(xy 275.529561 -272.600197) (xy 275.530056 -272.624804) (xy 275.529561 -272.649411) (xy 275.521666 -272.697988)
			(xy 275.506082 -272.744669) (xy 275.483211 -272.788246) (xy 275.453646 -272.82759) (xy 275.418153 -272.861682)
			(xy 275.37765 -272.889638) (xy 275.333188 -272.910736) (xy 275.285917 -272.924428) (xy 275.237062 -272.93036)
			(xy 275.187887 -272.928379) (xy 275.139668 -272.918535) (xy 275.093652 -272.901083) (xy 275.051031 -272.876476)
			(xy 275.01291 -272.845351) (xy 274.980275 -272.808514) (xy 274.953972 -272.766918) (xy 274.934681 -272.721642)
			(xy 274.922904 -272.673858) (xy 274.918944 -272.624804) (xy 274.580096 -272.624804) (xy 274.579601 -272.649411)
			(xy 274.571706 -272.697988) (xy 274.556122 -272.744669) (xy 274.533251 -272.788246) (xy 274.503686 -272.82759)
			(xy 274.468193 -272.861682) (xy 274.42769 -272.889638) (xy 274.383228 -272.910736) (xy 274.335957 -272.924428)
			(xy 274.287102 -272.93036) (xy 274.237927 -272.928379) (xy 274.189708 -272.918535) (xy 274.143692 -272.901083)
			(xy 274.101071 -272.876476) (xy 274.06295 -272.845351) (xy 274.030315 -272.808514) (xy 274.004012 -272.766918)
			(xy 273.984721 -272.721642) (xy 273.972944 -272.673858) (xy 273.968984 -272.624804) (xy 273.630136 -272.624804)
			(xy 273.629641 -272.649411) (xy 273.621746 -272.697988) (xy 273.606162 -272.744669) (xy 273.583291 -272.788246)
			(xy 273.553726 -272.82759) (xy 273.518233 -272.861682) (xy 273.47773 -272.889638) (xy 273.433268 -272.910736)
			(xy 273.385997 -272.924428) (xy 273.337142 -272.93036) (xy 273.287967 -272.928379) (xy 273.239748 -272.918535)
			(xy 273.193732 -272.901083) (xy 273.151111 -272.876476) (xy 273.11299 -272.845351) (xy 273.080355 -272.808514)
			(xy 273.054052 -272.766918) (xy 273.034761 -272.721642) (xy 273.022984 -272.673858) (xy 273.019024 -272.624804)
			(xy 272.680176 -272.624804) (xy 272.679681 -272.649411) (xy 272.671786 -272.697988) (xy 272.656202 -272.744669)
			(xy 272.633331 -272.788246) (xy 272.603766 -272.82759) (xy 272.568273 -272.861682) (xy 272.52777 -272.889638)
			(xy 272.483308 -272.910736) (xy 272.436037 -272.924428) (xy 272.387182 -272.93036) (xy 272.338007 -272.928379)
			(xy 272.289788 -272.918535) (xy 272.243772 -272.901083) (xy 272.201151 -272.876476) (xy 272.16303 -272.845351)
			(xy 272.130395 -272.808514) (xy 272.104092 -272.766918) (xy 272.084801 -272.721642) (xy 272.073024 -272.673858)
			(xy 272.069064 -272.624804) (xy 271.730216 -272.624804) (xy 271.729721 -272.649411) (xy 271.721826 -272.697988)
			(xy 271.706242 -272.744669) (xy 271.683371 -272.788246) (xy 271.653806 -272.82759) (xy 271.618313 -272.861682)
			(xy 271.57781 -272.889638) (xy 271.533348 -272.910736) (xy 271.486077 -272.924428) (xy 271.437222 -272.93036)
			(xy 271.388047 -272.928379) (xy 271.339828 -272.918535) (xy 271.293812 -272.901083) (xy 271.251191 -272.876476)
			(xy 271.21307 -272.845351) (xy 271.180435 -272.808514) (xy 271.154132 -272.766918) (xy 271.134841 -272.721642)
			(xy 271.123064 -272.673858) (xy 271.119104 -272.624804) (xy 270.780256 -272.624804) (xy 270.779761 -272.649411)
			(xy 270.771866 -272.697988) (xy 270.756282 -272.744669) (xy 270.733411 -272.788246) (xy 270.703846 -272.82759)
			(xy 270.668353 -272.861682) (xy 270.62785 -272.889638) (xy 270.583388 -272.910736) (xy 270.536117 -272.924428)
			(xy 270.487262 -272.93036) (xy 270.438087 -272.928379) (xy 270.389868 -272.918535) (xy 270.343852 -272.901083)
			(xy 270.301231 -272.876476) (xy 270.26311 -272.845351) (xy 270.230475 -272.808514) (xy 270.204172 -272.766918)
			(xy 270.184881 -272.721642) (xy 270.173104 -272.673858) (xy 270.169144 -272.624804) (xy 266.275686 -272.624804)
			(xy 266.243932 -272.706771) (xy 266.166046 -272.885646) (xy 266.080881 -273.061172) (xy 266.046342 -273.125492)
			(xy 276.32304 -273.125492) (xy 276.32304 -273.074076) (xy 276.331083 -273.023294) (xy 276.346971 -272.974395)
			(xy 276.370314 -272.928583) (xy 276.400535 -272.886987) (xy 276.436891 -272.850631) (xy 276.478487 -272.82041)
			(xy 276.524299 -272.797067) (xy 276.573198 -272.781179) (xy 276.62398 -272.773136) (xy 276.675396 -272.773136)
			(xy 276.726178 -272.781179) (xy 276.775077 -272.797067) (xy 276.820889 -272.82041) (xy 276.862485 -272.850631)
			(xy 276.898841 -272.886987) (xy 276.929062 -272.928583) (xy 276.952405 -272.974395) (xy 276.968293 -273.023294)
			(xy 276.976336 -273.074076) (xy 276.97684 -273.099784) (xy 277.294098 -273.099784) (xy 277.298058 -273.05073)
			(xy 277.309835 -273.002946) (xy 277.329126 -272.95767) (xy 277.355429 -272.916074) (xy 277.388064 -272.879237)
			(xy 277.426185 -272.848112) (xy 277.468806 -272.823505) (xy 277.514822 -272.806053) (xy 277.563041 -272.796209)
			(xy 277.612216 -272.794228) (xy 277.661071 -272.80016) (xy 277.708342 -272.813852) (xy 277.752804 -272.83495)
			(xy 277.793307 -272.862906) (xy 277.8288 -272.896998) (xy 277.858365 -272.936342) (xy 277.881236 -272.979919)
			(xy 277.89682 -273.0266) (xy 277.904715 -273.075177) (xy 277.90521 -273.099784) (xy 277.904715 -273.124391)
			(xy 277.904536 -273.125492) (xy 278.223214 -273.125492) (xy 278.223214 -273.074076) (xy 278.231257 -273.023294)
			(xy 278.247145 -272.974395) (xy 278.270488 -272.928583) (xy 278.300709 -272.886987) (xy 278.337065 -272.850631)
			(xy 278.378661 -272.82041) (xy 278.424473 -272.797067) (xy 278.473372 -272.781179) (xy 278.524154 -272.773136)
			(xy 278.57557 -272.773136) (xy 278.626352 -272.781179) (xy 278.675251 -272.797067) (xy 278.721063 -272.82041)
			(xy 278.762659 -272.850631) (xy 278.799015 -272.886987) (xy 278.829236 -272.928583) (xy 278.852579 -272.974395)
			(xy 278.868467 -273.023294) (xy 278.87651 -273.074076) (xy 278.877014 -273.099784) (xy 279.194018 -273.099784)
			(xy 279.197978 -273.05073) (xy 279.209755 -273.002946) (xy 279.229046 -272.95767) (xy 279.255349 -272.916074)
			(xy 279.287984 -272.879237) (xy 279.326105 -272.848112) (xy 279.368726 -272.823505) (xy 279.414742 -272.806053)
			(xy 279.462961 -272.796209) (xy 279.512136 -272.794228) (xy 279.560991 -272.80016) (xy 279.608262 -272.813852)
			(xy 279.652724 -272.83495) (xy 279.693227 -272.862906) (xy 279.72872 -272.896998) (xy 279.758285 -272.936342)
			(xy 279.781156 -272.979919) (xy 279.79674 -273.0266) (xy 279.804635 -273.075177) (xy 279.80513 -273.099784)
			(xy 279.804635 -273.124391) (xy 279.804456 -273.125492) (xy 280.123134 -273.125492) (xy 280.123134 -273.074076)
			(xy 280.131177 -273.023294) (xy 280.147065 -272.974395) (xy 280.170408 -272.928583) (xy 280.200629 -272.886987)
			(xy 280.236985 -272.850631) (xy 280.278581 -272.82041) (xy 280.324393 -272.797067) (xy 280.373292 -272.781179)
			(xy 280.424074 -272.773136) (xy 280.47549 -272.773136) (xy 280.526272 -272.781179) (xy 280.575171 -272.797067)
			(xy 280.620983 -272.82041) (xy 280.662579 -272.850631) (xy 280.698935 -272.886987) (xy 280.729156 -272.928583)
			(xy 280.752499 -272.974395) (xy 280.768387 -273.023294) (xy 280.77643 -273.074076) (xy 280.776934 -273.099784)
			(xy 281.093938 -273.099784) (xy 281.097898 -273.05073) (xy 281.109675 -273.002946) (xy 281.128966 -272.95767)
			(xy 281.155269 -272.916074) (xy 281.187904 -272.879237) (xy 281.226025 -272.848112) (xy 281.268646 -272.823505)
			(xy 281.314662 -272.806053) (xy 281.362881 -272.796209) (xy 281.412056 -272.794228) (xy 281.460911 -272.80016)
			(xy 281.508182 -272.813852) (xy 281.552644 -272.83495) (xy 281.593147 -272.862906) (xy 281.62864 -272.896998)
			(xy 281.658205 -272.936342) (xy 281.681076 -272.979919) (xy 281.69666 -273.0266) (xy 281.704555 -273.075177)
			(xy 281.70505 -273.099784) (xy 281.704555 -273.124391) (xy 281.704376 -273.125492) (xy 282.023054 -273.125492)
			(xy 282.023054 -273.074076) (xy 282.031097 -273.023294) (xy 282.046985 -272.974395) (xy 282.070328 -272.928583)
			(xy 282.100549 -272.886987) (xy 282.136905 -272.850631) (xy 282.178501 -272.82041) (xy 282.224313 -272.797067)
			(xy 282.273212 -272.781179) (xy 282.323994 -272.773136) (xy 282.37541 -272.773136) (xy 282.426192 -272.781179)
			(xy 282.475091 -272.797067) (xy 282.520903 -272.82041) (xy 282.562499 -272.850631) (xy 282.598855 -272.886987)
			(xy 282.629076 -272.928583) (xy 282.652419 -272.974395) (xy 282.668307 -273.023294) (xy 282.67635 -273.074076)
			(xy 282.676854 -273.099784) (xy 282.994112 -273.099784) (xy 282.998072 -273.05073) (xy 283.009849 -273.002946)
			(xy 283.02914 -272.95767) (xy 283.055443 -272.916074) (xy 283.088078 -272.879237) (xy 283.126199 -272.848112)
			(xy 283.16882 -272.823505) (xy 283.214836 -272.806053) (xy 283.263055 -272.796209) (xy 283.31223 -272.794228)
			(xy 283.361085 -272.80016) (xy 283.408356 -272.813852) (xy 283.452818 -272.83495) (xy 283.493321 -272.862906)
			(xy 283.528814 -272.896998) (xy 283.558379 -272.936342) (xy 283.58125 -272.979919) (xy 283.596834 -273.0266)
			(xy 283.604729 -273.075177) (xy 283.605224 -273.099784) (xy 283.604729 -273.124391) (xy 283.60455 -273.125492)
			(xy 283.923228 -273.125492) (xy 283.923228 -273.074076) (xy 283.931271 -273.023294) (xy 283.947159 -272.974395)
			(xy 283.970502 -272.928583) (xy 284.000723 -272.886987) (xy 284.037079 -272.850631) (xy 284.078675 -272.82041)
			(xy 284.124487 -272.797067) (xy 284.173386 -272.781179) (xy 284.224168 -272.773136) (xy 284.275584 -272.773136)
			(xy 284.326366 -272.781179) (xy 284.375265 -272.797067) (xy 284.421077 -272.82041) (xy 284.462673 -272.850631)
			(xy 284.499029 -272.886987) (xy 284.52925 -272.928583) (xy 284.552593 -272.974395) (xy 284.568481 -273.023294)
			(xy 284.576524 -273.074076) (xy 284.577028 -273.099784) (xy 284.894032 -273.099784) (xy 284.897992 -273.05073)
			(xy 284.909769 -273.002946) (xy 284.92906 -272.95767) (xy 284.955363 -272.916074) (xy 284.987998 -272.879237)
			(xy 285.026119 -272.848112) (xy 285.06874 -272.823505) (xy 285.114756 -272.806053) (xy 285.162975 -272.796209)
			(xy 285.21215 -272.794228) (xy 285.261005 -272.80016) (xy 285.308276 -272.813852) (xy 285.352738 -272.83495)
			(xy 285.393241 -272.862906) (xy 285.428734 -272.896998) (xy 285.458299 -272.936342) (xy 285.48117 -272.979919)
			(xy 285.496754 -273.0266) (xy 285.504649 -273.075177) (xy 285.505144 -273.099784) (xy 285.504649 -273.124391)
			(xy 285.50447 -273.125492) (xy 285.823148 -273.125492) (xy 285.823148 -273.074076) (xy 285.831191 -273.023294)
			(xy 285.847079 -272.974395) (xy 285.870422 -272.928583) (xy 285.900643 -272.886987) (xy 285.936999 -272.850631)
			(xy 285.978595 -272.82041) (xy 286.024407 -272.797067) (xy 286.073306 -272.781179) (xy 286.124088 -272.773136)
			(xy 286.175504 -272.773136) (xy 286.226286 -272.781179) (xy 286.275185 -272.797067) (xy 286.320997 -272.82041)
			(xy 286.362593 -272.850631) (xy 286.398949 -272.886987) (xy 286.42917 -272.928583) (xy 286.452513 -272.974395)
			(xy 286.468401 -273.023294) (xy 286.476444 -273.074076) (xy 286.476948 -273.099784) (xy 286.793952 -273.099784)
			(xy 286.797912 -273.05073) (xy 286.809689 -273.002946) (xy 286.82898 -272.95767) (xy 286.855283 -272.916074)
			(xy 286.887918 -272.879237) (xy 286.926039 -272.848112) (xy 286.96866 -272.823505) (xy 287.014676 -272.806053)
			(xy 287.062895 -272.796209) (xy 287.11207 -272.794228) (xy 287.160925 -272.80016) (xy 287.208196 -272.813852)
			(xy 287.252658 -272.83495) (xy 287.293161 -272.862906) (xy 287.328654 -272.896998) (xy 287.358219 -272.936342)
			(xy 287.38109 -272.979919) (xy 287.396674 -273.0266) (xy 287.404569 -273.075177) (xy 287.405064 -273.099784)
			(xy 287.404569 -273.124391) (xy 287.40439 -273.125492) (xy 287.723068 -273.125492) (xy 287.723068 -273.074076)
			(xy 287.731111 -273.023294) (xy 287.746999 -272.974395) (xy 287.770342 -272.928583) (xy 287.800563 -272.886987)
			(xy 287.836919 -272.850631) (xy 287.878515 -272.82041) (xy 287.924327 -272.797067) (xy 287.973226 -272.781179)
			(xy 288.024008 -272.773136) (xy 288.075424 -272.773136) (xy 288.126206 -272.781179) (xy 288.175105 -272.797067)
			(xy 288.220917 -272.82041) (xy 288.262513 -272.850631) (xy 288.298869 -272.886987) (xy 288.32909 -272.928583)
			(xy 288.352433 -272.974395) (xy 288.368321 -273.023294) (xy 288.376364 -273.074076) (xy 288.376868 -273.099784)
			(xy 288.694126 -273.099784) (xy 288.698086 -273.05073) (xy 288.709863 -273.002946) (xy 288.729154 -272.95767)
			(xy 288.755457 -272.916074) (xy 288.788092 -272.879237) (xy 288.826213 -272.848112) (xy 288.868834 -272.823505)
			(xy 288.91485 -272.806053) (xy 288.963069 -272.796209) (xy 289.012244 -272.794228) (xy 289.061099 -272.80016)
			(xy 289.10837 -272.813852) (xy 289.152832 -272.83495) (xy 289.193335 -272.862906) (xy 289.228828 -272.896998)
			(xy 289.258393 -272.936342) (xy 289.281264 -272.979919) (xy 289.296848 -273.0266) (xy 289.304743 -273.075177)
			(xy 289.305238 -273.099784) (xy 289.304743 -273.124391) (xy 289.304564 -273.125492) (xy 289.623242 -273.125492)
			(xy 289.623242 -273.074076) (xy 289.631285 -273.023294) (xy 289.647173 -272.974395) (xy 289.670516 -272.928583)
			(xy 289.700737 -272.886987) (xy 289.737093 -272.850631) (xy 289.778689 -272.82041) (xy 289.824501 -272.797067)
			(xy 289.8734 -272.781179) (xy 289.924182 -272.773136) (xy 289.975598 -272.773136) (xy 290.02638 -272.781179)
			(xy 290.075279 -272.797067) (xy 290.121091 -272.82041) (xy 290.162687 -272.850631) (xy 290.199043 -272.886987)
			(xy 290.229264 -272.928583) (xy 290.252607 -272.974395) (xy 290.268495 -273.023294) (xy 290.276538 -273.074076)
			(xy 290.277042 -273.099784) (xy 290.594046 -273.099784) (xy 290.598006 -273.05073) (xy 290.609783 -273.002946)
			(xy 290.629074 -272.95767) (xy 290.655377 -272.916074) (xy 290.688012 -272.879237) (xy 290.726133 -272.848112)
			(xy 290.768754 -272.823505) (xy 290.81477 -272.806053) (xy 290.862989 -272.796209) (xy 290.912164 -272.794228)
			(xy 290.961019 -272.80016) (xy 291.00829 -272.813852) (xy 291.052752 -272.83495) (xy 291.093255 -272.862906)
			(xy 291.128748 -272.896998) (xy 291.158313 -272.936342) (xy 291.181184 -272.979919) (xy 291.196768 -273.0266)
			(xy 291.204663 -273.075177) (xy 291.205158 -273.099784) (xy 291.204663 -273.124391) (xy 291.204525 -273.125238)
			(xy 291.522908 -273.125238) (xy 291.522908 -273.073822) (xy 291.530951 -273.02304) (xy 291.546839 -272.974141)
			(xy 291.570182 -272.928329) (xy 291.600403 -272.886733) (xy 291.636759 -272.850377) (xy 291.678355 -272.820156)
			(xy 291.724167 -272.796813) (xy 291.773066 -272.780925) (xy 291.823848 -272.772882) (xy 291.875264 -272.772882)
			(xy 291.926046 -272.780925) (xy 291.974945 -272.796813) (xy 292.020757 -272.820156) (xy 292.062353 -272.850377)
			(xy 292.098709 -272.886733) (xy 292.12893 -272.928329) (xy 292.152273 -272.974141) (xy 292.168161 -273.02304)
			(xy 292.176204 -273.073822) (xy 292.176708 -273.09953) (xy 292.176703 -273.099784) (xy 292.493966 -273.099784)
			(xy 292.497926 -273.05073) (xy 292.509703 -273.002946) (xy 292.528994 -272.95767) (xy 292.555297 -272.916074)
			(xy 292.587932 -272.879237) (xy 292.626053 -272.848112) (xy 292.668674 -272.823505) (xy 292.71469 -272.806053)
			(xy 292.762909 -272.796209) (xy 292.812084 -272.794228) (xy 292.860939 -272.80016) (xy 292.90821 -272.813852)
			(xy 292.952672 -272.83495) (xy 292.993175 -272.862906) (xy 293.028668 -272.896998) (xy 293.058233 -272.936342)
			(xy 293.081104 -272.979919) (xy 293.096688 -273.0266) (xy 293.104583 -273.075177) (xy 293.105078 -273.099784)
			(xy 293.104583 -273.124391) (xy 293.104404 -273.125492) (xy 293.422828 -273.125492) (xy 293.422828 -273.074076)
			(xy 293.430871 -273.023294) (xy 293.446759 -272.974395) (xy 293.470102 -272.928583) (xy 293.500323 -272.886987)
			(xy 293.536679 -272.850631) (xy 293.578275 -272.82041) (xy 293.624087 -272.797067) (xy 293.672986 -272.781179)
			(xy 293.723768 -272.773136) (xy 293.775184 -272.773136) (xy 293.825966 -272.781179) (xy 293.874865 -272.797067)
			(xy 293.920677 -272.82041) (xy 293.962273 -272.850631) (xy 293.998629 -272.886987) (xy 294.02885 -272.928583)
			(xy 294.052193 -272.974395) (xy 294.068081 -273.023294) (xy 294.076124 -273.074076) (xy 294.076628 -273.099784)
			(xy 294.393886 -273.099784) (xy 294.397846 -273.05073) (xy 294.409623 -273.002946) (xy 294.428914 -272.95767)
			(xy 294.455217 -272.916074) (xy 294.487852 -272.879237) (xy 294.525973 -272.848112) (xy 294.568594 -272.823505)
			(xy 294.61461 -272.806053) (xy 294.662829 -272.796209) (xy 294.712004 -272.794228) (xy 294.760859 -272.80016)
			(xy 294.80813 -272.813852) (xy 294.852592 -272.83495) (xy 294.893095 -272.862906) (xy 294.928588 -272.896998)
			(xy 294.958153 -272.936342) (xy 294.981024 -272.979919) (xy 294.996608 -273.0266) (xy 295.004503 -273.075177)
			(xy 295.004998 -273.099784) (xy 295.004503 -273.124391) (xy 295.004324 -273.125492) (xy 295.323002 -273.125492)
			(xy 295.323002 -273.074076) (xy 295.331045 -273.023294) (xy 295.346933 -272.974395) (xy 295.370276 -272.928583)
			(xy 295.400497 -272.886987) (xy 295.436853 -272.850631) (xy 295.478449 -272.82041) (xy 295.524261 -272.797067)
			(xy 295.57316 -272.781179) (xy 295.623942 -272.773136) (xy 295.675358 -272.773136) (xy 295.72614 -272.781179)
			(xy 295.775039 -272.797067) (xy 295.820851 -272.82041) (xy 295.862447 -272.850631) (xy 295.898803 -272.886987)
			(xy 295.929024 -272.928583) (xy 295.952367 -272.974395) (xy 295.968255 -273.023294) (xy 295.976298 -273.074076)
			(xy 295.976802 -273.099784) (xy 296.29406 -273.099784) (xy 296.29802 -273.05073) (xy 296.309797 -273.002946)
			(xy 296.329088 -272.95767) (xy 296.355391 -272.916074) (xy 296.388026 -272.879237) (xy 296.426147 -272.848112)
			(xy 296.468768 -272.823505) (xy 296.514784 -272.806053) (xy 296.563003 -272.796209) (xy 296.612178 -272.794228)
			(xy 296.661033 -272.80016) (xy 296.708304 -272.813852) (xy 296.752766 -272.83495) (xy 296.793269 -272.862906)
			(xy 296.828762 -272.896998) (xy 296.858327 -272.936342) (xy 296.881198 -272.979919) (xy 296.896782 -273.0266)
			(xy 296.904677 -273.075177) (xy 296.905172 -273.099784) (xy 296.904677 -273.124391) (xy 296.904498 -273.125492)
			(xy 297.222922 -273.125492) (xy 297.222922 -273.074076) (xy 297.230965 -273.023294) (xy 297.246853 -272.974395)
			(xy 297.270196 -272.928583) (xy 297.300417 -272.886987) (xy 297.336773 -272.850631) (xy 297.378369 -272.82041)
			(xy 297.424181 -272.797067) (xy 297.47308 -272.781179) (xy 297.523862 -272.773136) (xy 297.575278 -272.773136)
			(xy 297.62606 -272.781179) (xy 297.674959 -272.797067) (xy 297.720771 -272.82041) (xy 297.762367 -272.850631)
			(xy 297.798723 -272.886987) (xy 297.828944 -272.928583) (xy 297.852287 -272.974395) (xy 297.868175 -273.023294)
			(xy 297.876218 -273.074076) (xy 297.876722 -273.099784) (xy 298.19398 -273.099784) (xy 298.19794 -273.05073)
			(xy 298.209717 -273.002946) (xy 298.229008 -272.95767) (xy 298.255311 -272.916074) (xy 298.287946 -272.879237)
			(xy 298.326067 -272.848112) (xy 298.368688 -272.823505) (xy 298.414704 -272.806053) (xy 298.462923 -272.796209)
			(xy 298.512098 -272.794228) (xy 298.560953 -272.80016) (xy 298.608224 -272.813852) (xy 298.652686 -272.83495)
			(xy 298.693189 -272.862906) (xy 298.728682 -272.896998) (xy 298.758247 -272.936342) (xy 298.781118 -272.979919)
			(xy 298.796702 -273.0266) (xy 298.804597 -273.075177) (xy 298.805092 -273.099784) (xy 298.804597 -273.124391)
			(xy 298.804418 -273.125492) (xy 299.122842 -273.125492) (xy 299.122842 -273.074076) (xy 299.130885 -273.023294)
			(xy 299.146773 -272.974395) (xy 299.170116 -272.928583) (xy 299.200337 -272.886987) (xy 299.236693 -272.850631)
			(xy 299.278289 -272.82041) (xy 299.324101 -272.797067) (xy 299.373 -272.781179) (xy 299.423782 -272.773136)
			(xy 299.475198 -272.773136) (xy 299.52598 -272.781179) (xy 299.574879 -272.797067) (xy 299.620691 -272.82041)
			(xy 299.662287 -272.850631) (xy 299.698643 -272.886987) (xy 299.728864 -272.928583) (xy 299.752207 -272.974395)
			(xy 299.768095 -273.023294) (xy 299.776138 -273.074076) (xy 299.776642 -273.099784) (xy 300.0939 -273.099784)
			(xy 300.09786 -273.05073) (xy 300.109637 -273.002946) (xy 300.128928 -272.95767) (xy 300.155231 -272.916074)
			(xy 300.187866 -272.879237) (xy 300.225987 -272.848112) (xy 300.268608 -272.823505) (xy 300.314624 -272.806053)
			(xy 300.362843 -272.796209) (xy 300.412018 -272.794228) (xy 300.460873 -272.80016) (xy 300.508144 -272.813852)
			(xy 300.552606 -272.83495) (xy 300.593109 -272.862906) (xy 300.628602 -272.896998) (xy 300.658167 -272.936342)
			(xy 300.681038 -272.979919) (xy 300.696622 -273.0266) (xy 300.704517 -273.075177) (xy 300.705012 -273.099784)
			(xy 300.704517 -273.124391) (xy 300.704338 -273.125492) (xy 301.023016 -273.125492) (xy 301.023016 -273.074076)
			(xy 301.031059 -273.023294) (xy 301.046947 -272.974395) (xy 301.07029 -272.928583) (xy 301.100511 -272.886987)
			(xy 301.136867 -272.850631) (xy 301.178463 -272.82041) (xy 301.224275 -272.797067) (xy 301.273174 -272.781179)
			(xy 301.323956 -272.773136) (xy 301.375372 -272.773136) (xy 301.426154 -272.781179) (xy 301.475053 -272.797067)
			(xy 301.520865 -272.82041) (xy 301.562461 -272.850631) (xy 301.598817 -272.886987) (xy 301.629038 -272.928583)
			(xy 301.652381 -272.974395) (xy 301.668269 -273.023294) (xy 301.676312 -273.074076) (xy 301.676816 -273.099784)
			(xy 301.994074 -273.099784) (xy 301.998034 -273.05073) (xy 302.009811 -273.002946) (xy 302.029102 -272.95767)
			(xy 302.055405 -272.916074) (xy 302.08804 -272.879237) (xy 302.126161 -272.848112) (xy 302.168782 -272.823505)
			(xy 302.214798 -272.806053) (xy 302.263017 -272.796209) (xy 302.312192 -272.794228) (xy 302.361047 -272.80016)
			(xy 302.408318 -272.813852) (xy 302.45278 -272.83495) (xy 302.493283 -272.862906) (xy 302.528776 -272.896998)
			(xy 302.558341 -272.936342) (xy 302.581212 -272.979919) (xy 302.596796 -273.0266) (xy 302.604691 -273.075177)
			(xy 302.605186 -273.099784) (xy 302.604691 -273.124391) (xy 302.604512 -273.125492) (xy 302.922936 -273.125492)
			(xy 302.922936 -273.074076) (xy 302.930979 -273.023294) (xy 302.946867 -272.974395) (xy 302.97021 -272.928583)
			(xy 303.000431 -272.886987) (xy 303.036787 -272.850631) (xy 303.078383 -272.82041) (xy 303.124195 -272.797067)
			(xy 303.173094 -272.781179) (xy 303.223876 -272.773136) (xy 303.275292 -272.773136) (xy 303.326074 -272.781179)
			(xy 303.374973 -272.797067) (xy 303.420785 -272.82041) (xy 303.462381 -272.850631) (xy 303.498737 -272.886987)
			(xy 303.528958 -272.928583) (xy 303.552301 -272.974395) (xy 303.568189 -273.023294) (xy 303.576232 -273.074076)
			(xy 303.576736 -273.099784) (xy 303.893994 -273.099784) (xy 303.897954 -273.05073) (xy 303.909731 -273.002946)
			(xy 303.929022 -272.95767) (xy 303.955325 -272.916074) (xy 303.98796 -272.879237) (xy 304.026081 -272.848112)
			(xy 304.068702 -272.823505) (xy 304.114718 -272.806053) (xy 304.162937 -272.796209) (xy 304.212112 -272.794228)
			(xy 304.260967 -272.80016) (xy 304.308238 -272.813852) (xy 304.3527 -272.83495) (xy 304.393203 -272.862906)
			(xy 304.428696 -272.896998) (xy 304.458261 -272.936342) (xy 304.481132 -272.979919) (xy 304.496716 -273.0266)
			(xy 304.504611 -273.075177) (xy 304.505106 -273.099784) (xy 304.504611 -273.124391) (xy 304.504432 -273.125492)
			(xy 304.822856 -273.125492) (xy 304.822856 -273.074076) (xy 304.830899 -273.023294) (xy 304.846787 -272.974395)
			(xy 304.87013 -272.928583) (xy 304.900351 -272.886987) (xy 304.936707 -272.850631) (xy 304.978303 -272.82041)
			(xy 305.024115 -272.797067) (xy 305.073014 -272.781179) (xy 305.123796 -272.773136) (xy 305.175212 -272.773136)
			(xy 305.225994 -272.781179) (xy 305.274893 -272.797067) (xy 305.320705 -272.82041) (xy 305.362301 -272.850631)
			(xy 305.398657 -272.886987) (xy 305.428878 -272.928583) (xy 305.452221 -272.974395) (xy 305.468109 -273.023294)
			(xy 305.476152 -273.074076) (xy 305.476656 -273.099784) (xy 305.793914 -273.099784) (xy 305.797874 -273.05073)
			(xy 305.809651 -273.002946) (xy 305.828942 -272.95767) (xy 305.855245 -272.916074) (xy 305.88788 -272.879237)
			(xy 305.926001 -272.848112) (xy 305.968622 -272.823505) (xy 306.014638 -272.806053) (xy 306.062857 -272.796209)
			(xy 306.112032 -272.794228) (xy 306.160887 -272.80016) (xy 306.208158 -272.813852) (xy 306.25262 -272.83495)
			(xy 306.293123 -272.862906) (xy 306.328616 -272.896998) (xy 306.358181 -272.936342) (xy 306.381052 -272.979919)
			(xy 306.396636 -273.0266) (xy 306.404531 -273.075177) (xy 306.405026 -273.099784) (xy 306.404531 -273.124391)
			(xy 306.404352 -273.125492) (xy 306.72303 -273.125492) (xy 306.72303 -273.074076) (xy 306.731073 -273.023294)
			(xy 306.746961 -272.974395) (xy 306.770304 -272.928583) (xy 306.800525 -272.886987) (xy 306.836881 -272.850631)
			(xy 306.878477 -272.82041) (xy 306.924289 -272.797067) (xy 306.973188 -272.781179) (xy 307.02397 -272.773136)
			(xy 307.075386 -272.773136) (xy 307.126168 -272.781179) (xy 307.175067 -272.797067) (xy 307.220879 -272.82041)
			(xy 307.262475 -272.850631) (xy 307.298831 -272.886987) (xy 307.329052 -272.928583) (xy 307.352395 -272.974395)
			(xy 307.368283 -273.023294) (xy 307.376326 -273.074076) (xy 307.37683 -273.099784) (xy 307.694088 -273.099784)
			(xy 307.698048 -273.05073) (xy 307.709825 -273.002946) (xy 307.729116 -272.95767) (xy 307.755419 -272.916074)
			(xy 307.788054 -272.879237) (xy 307.826175 -272.848112) (xy 307.868796 -272.823505) (xy 307.914812 -272.806053)
			(xy 307.963031 -272.796209) (xy 308.012206 -272.794228) (xy 308.061061 -272.80016) (xy 308.108332 -272.813852)
			(xy 308.152794 -272.83495) (xy 308.193297 -272.862906) (xy 308.22879 -272.896998) (xy 308.258355 -272.936342)
			(xy 308.281226 -272.979919) (xy 308.29681 -273.0266) (xy 308.304705 -273.075177) (xy 308.3052 -273.099784)
			(xy 308.304705 -273.124391) (xy 308.304526 -273.125492) (xy 308.62295 -273.125492) (xy 308.62295 -273.074076)
			(xy 308.630993 -273.023294) (xy 308.646881 -272.974395) (xy 308.670224 -272.928583) (xy 308.700445 -272.886987)
			(xy 308.736801 -272.850631) (xy 308.778397 -272.82041) (xy 308.824209 -272.797067) (xy 308.873108 -272.781179)
			(xy 308.92389 -272.773136) (xy 308.975306 -272.773136) (xy 309.026088 -272.781179) (xy 309.074987 -272.797067)
			(xy 309.120799 -272.82041) (xy 309.162395 -272.850631) (xy 309.198751 -272.886987) (xy 309.228972 -272.928583)
			(xy 309.252315 -272.974395) (xy 309.268203 -273.023294) (xy 309.276246 -273.074076) (xy 309.27675 -273.099784)
			(xy 309.594262 -273.099784) (xy 309.598222 -273.05073) (xy 309.609999 -273.002946) (xy 309.62929 -272.95767)
			(xy 309.655593 -272.916074) (xy 309.688228 -272.879237) (xy 309.726349 -272.848112) (xy 309.76897 -272.823505)
			(xy 309.814986 -272.806053) (xy 309.863205 -272.796209) (xy 309.91238 -272.794228) (xy 309.961235 -272.80016)
			(xy 310.008506 -272.813852) (xy 310.052968 -272.83495) (xy 310.093471 -272.862906) (xy 310.128964 -272.896998)
			(xy 310.158529 -272.936342) (xy 310.1814 -272.979919) (xy 310.196984 -273.0266) (xy 310.204879 -273.075177)
			(xy 310.205374 -273.099784) (xy 310.204879 -273.124391) (xy 310.2047 -273.125492) (xy 310.52287 -273.125492)
			(xy 310.52287 -273.074076) (xy 310.530913 -273.023294) (xy 310.546801 -272.974395) (xy 310.570144 -272.928583)
			(xy 310.600365 -272.886987) (xy 310.636721 -272.850631) (xy 310.678317 -272.82041) (xy 310.724129 -272.797067)
			(xy 310.773028 -272.781179) (xy 310.82381 -272.773136) (xy 310.875226 -272.773136) (xy 310.926008 -272.781179)
			(xy 310.974907 -272.797067) (xy 311.020719 -272.82041) (xy 311.062315 -272.850631) (xy 311.098671 -272.886987)
			(xy 311.128892 -272.928583) (xy 311.152235 -272.974395) (xy 311.168123 -273.023294) (xy 311.176166 -273.074076)
			(xy 311.17667 -273.099784) (xy 311.494182 -273.099784) (xy 311.498142 -273.05073) (xy 311.509919 -273.002946)
			(xy 311.52921 -272.95767) (xy 311.555513 -272.916074) (xy 311.588148 -272.879237) (xy 311.626269 -272.848112)
			(xy 311.66889 -272.823505) (xy 311.714906 -272.806053) (xy 311.763125 -272.796209) (xy 311.8123 -272.794228)
			(xy 311.861155 -272.80016) (xy 311.908426 -272.813852) (xy 311.952888 -272.83495) (xy 311.993391 -272.862906)
			(xy 312.028884 -272.896998) (xy 312.058449 -272.936342) (xy 312.08132 -272.979919) (xy 312.096904 -273.0266)
			(xy 312.104799 -273.075177) (xy 312.105294 -273.099784) (xy 312.104799 -273.124391) (xy 312.10462 -273.125492)
			(xy 312.42279 -273.125492) (xy 312.42279 -273.074076) (xy 312.430833 -273.023294) (xy 312.446721 -272.974395)
			(xy 312.470064 -272.928583) (xy 312.500285 -272.886987) (xy 312.536641 -272.850631) (xy 312.578237 -272.82041)
			(xy 312.624049 -272.797067) (xy 312.672948 -272.781179) (xy 312.72373 -272.773136) (xy 312.775146 -272.773136)
			(xy 312.825928 -272.781179) (xy 312.874827 -272.797067) (xy 312.920639 -272.82041) (xy 312.962235 -272.850631)
			(xy 312.998591 -272.886987) (xy 313.028812 -272.928583) (xy 313.052155 -272.974395) (xy 313.068043 -273.023294)
			(xy 313.076086 -273.074076) (xy 313.07659 -273.099784) (xy 313.394102 -273.099784) (xy 313.398062 -273.05073)
			(xy 313.409839 -273.002946) (xy 313.42913 -272.95767) (xy 313.455433 -272.916074) (xy 313.488068 -272.879237)
			(xy 313.526189 -272.848112) (xy 313.56881 -272.823505) (xy 313.614826 -272.806053) (xy 313.663045 -272.796209)
			(xy 313.71222 -272.794228) (xy 313.761075 -272.80016) (xy 313.808346 -272.813852) (xy 313.852808 -272.83495)
			(xy 313.893311 -272.862906) (xy 313.928804 -272.896998) (xy 313.958369 -272.936342) (xy 313.98124 -272.979919)
			(xy 313.996824 -273.0266) (xy 314.004719 -273.075177) (xy 314.005214 -273.099784) (xy 314.004719 -273.124391)
			(xy 313.996824 -273.172968) (xy 313.98124 -273.219649) (xy 313.958369 -273.263226) (xy 313.928804 -273.30257)
			(xy 313.893311 -273.336662) (xy 313.852808 -273.364618) (xy 313.808346 -273.385716) (xy 313.761075 -273.399408)
			(xy 313.71222 -273.40534) (xy 313.663045 -273.403359) (xy 313.614826 -273.393515) (xy 313.56881 -273.376063)
			(xy 313.526189 -273.351456) (xy 313.488068 -273.320331) (xy 313.455433 -273.283494) (xy 313.42913 -273.241898)
			(xy 313.409839 -273.196622) (xy 313.398062 -273.148838) (xy 313.394102 -273.099784) (xy 313.07659 -273.099784)
			(xy 313.076086 -273.125492) (xy 313.068043 -273.176274) (xy 313.052155 -273.225173) (xy 313.028812 -273.270985)
			(xy 312.998591 -273.312581) (xy 312.962235 -273.348937) (xy 312.920639 -273.379158) (xy 312.874827 -273.402501)
			(xy 312.825928 -273.418389) (xy 312.775146 -273.426432) (xy 312.72373 -273.426432) (xy 312.672948 -273.418389)
			(xy 312.624049 -273.402501) (xy 312.578237 -273.379158) (xy 312.536641 -273.348937) (xy 312.500285 -273.312581)
			(xy 312.470064 -273.270985) (xy 312.446721 -273.225173) (xy 312.430833 -273.176274) (xy 312.42279 -273.125492)
			(xy 312.10462 -273.125492) (xy 312.096904 -273.172968) (xy 312.08132 -273.219649) (xy 312.058449 -273.263226)
			(xy 312.028884 -273.30257) (xy 311.993391 -273.336662) (xy 311.952888 -273.364618) (xy 311.908426 -273.385716)
			(xy 311.861155 -273.399408) (xy 311.8123 -273.40534) (xy 311.763125 -273.403359) (xy 311.714906 -273.393515)
			(xy 311.66889 -273.376063) (xy 311.626269 -273.351456) (xy 311.588148 -273.320331) (xy 311.555513 -273.283494)
			(xy 311.52921 -273.241898) (xy 311.509919 -273.196622) (xy 311.498142 -273.148838) (xy 311.494182 -273.099784)
			(xy 311.17667 -273.099784) (xy 311.176166 -273.125492) (xy 311.168123 -273.176274) (xy 311.152235 -273.225173)
			(xy 311.128892 -273.270985) (xy 311.098671 -273.312581) (xy 311.062315 -273.348937) (xy 311.020719 -273.379158)
			(xy 310.974907 -273.402501) (xy 310.926008 -273.418389) (xy 310.875226 -273.426432) (xy 310.82381 -273.426432)
			(xy 310.773028 -273.418389) (xy 310.724129 -273.402501) (xy 310.678317 -273.379158) (xy 310.636721 -273.348937)
			(xy 310.600365 -273.312581) (xy 310.570144 -273.270985) (xy 310.546801 -273.225173) (xy 310.530913 -273.176274)
			(xy 310.52287 -273.125492) (xy 310.2047 -273.125492) (xy 310.196984 -273.172968) (xy 310.1814 -273.219649)
			(xy 310.158529 -273.263226) (xy 310.128964 -273.30257) (xy 310.093471 -273.336662) (xy 310.052968 -273.364618)
			(xy 310.008506 -273.385716) (xy 309.961235 -273.399408) (xy 309.91238 -273.40534) (xy 309.863205 -273.403359)
			(xy 309.814986 -273.393515) (xy 309.76897 -273.376063) (xy 309.726349 -273.351456) (xy 309.688228 -273.320331)
			(xy 309.655593 -273.283494) (xy 309.62929 -273.241898) (xy 309.609999 -273.196622) (xy 309.598222 -273.148838)
			(xy 309.594262 -273.099784) (xy 309.27675 -273.099784) (xy 309.276246 -273.125492) (xy 309.268203 -273.176274)
			(xy 309.252315 -273.225173) (xy 309.228972 -273.270985) (xy 309.198751 -273.312581) (xy 309.162395 -273.348937)
			(xy 309.120799 -273.379158) (xy 309.074987 -273.402501) (xy 309.026088 -273.418389) (xy 308.975306 -273.426432)
			(xy 308.92389 -273.426432) (xy 308.873108 -273.418389) (xy 308.824209 -273.402501) (xy 308.778397 -273.379158)
			(xy 308.736801 -273.348937) (xy 308.700445 -273.312581) (xy 308.670224 -273.270985) (xy 308.646881 -273.225173)
			(xy 308.630993 -273.176274) (xy 308.62295 -273.125492) (xy 308.304526 -273.125492) (xy 308.29681 -273.172968)
			(xy 308.281226 -273.219649) (xy 308.258355 -273.263226) (xy 308.22879 -273.30257) (xy 308.193297 -273.336662)
			(xy 308.152794 -273.364618) (xy 308.108332 -273.385716) (xy 308.061061 -273.399408) (xy 308.012206 -273.40534)
			(xy 307.963031 -273.403359) (xy 307.914812 -273.393515) (xy 307.868796 -273.376063) (xy 307.826175 -273.351456)
			(xy 307.788054 -273.320331) (xy 307.755419 -273.283494) (xy 307.729116 -273.241898) (xy 307.709825 -273.196622)
			(xy 307.698048 -273.148838) (xy 307.694088 -273.099784) (xy 307.37683 -273.099784) (xy 307.376326 -273.125492)
			(xy 307.368283 -273.176274) (xy 307.352395 -273.225173) (xy 307.329052 -273.270985) (xy 307.298831 -273.312581)
			(xy 307.262475 -273.348937) (xy 307.220879 -273.379158) (xy 307.175067 -273.402501) (xy 307.126168 -273.418389)
			(xy 307.075386 -273.426432) (xy 307.02397 -273.426432) (xy 306.973188 -273.418389) (xy 306.924289 -273.402501)
			(xy 306.878477 -273.379158) (xy 306.836881 -273.348937) (xy 306.800525 -273.312581) (xy 306.770304 -273.270985)
			(xy 306.746961 -273.225173) (xy 306.731073 -273.176274) (xy 306.72303 -273.125492) (xy 306.404352 -273.125492)
			(xy 306.396636 -273.172968) (xy 306.381052 -273.219649) (xy 306.358181 -273.263226) (xy 306.328616 -273.30257)
			(xy 306.293123 -273.336662) (xy 306.25262 -273.364618) (xy 306.208158 -273.385716) (xy 306.160887 -273.399408)
			(xy 306.112032 -273.40534) (xy 306.062857 -273.403359) (xy 306.014638 -273.393515) (xy 305.968622 -273.376063)
			(xy 305.926001 -273.351456) (xy 305.88788 -273.320331) (xy 305.855245 -273.283494) (xy 305.828942 -273.241898)
			(xy 305.809651 -273.196622) (xy 305.797874 -273.148838) (xy 305.793914 -273.099784) (xy 305.476656 -273.099784)
			(xy 305.476152 -273.125492) (xy 305.468109 -273.176274) (xy 305.452221 -273.225173) (xy 305.428878 -273.270985)
			(xy 305.398657 -273.312581) (xy 305.362301 -273.348937) (xy 305.320705 -273.379158) (xy 305.274893 -273.402501)
			(xy 305.225994 -273.418389) (xy 305.175212 -273.426432) (xy 305.123796 -273.426432) (xy 305.073014 -273.418389)
			(xy 305.024115 -273.402501) (xy 304.978303 -273.379158) (xy 304.936707 -273.348937) (xy 304.900351 -273.312581)
			(xy 304.87013 -273.270985) (xy 304.846787 -273.225173) (xy 304.830899 -273.176274) (xy 304.822856 -273.125492)
			(xy 304.504432 -273.125492) (xy 304.496716 -273.172968) (xy 304.481132 -273.219649) (xy 304.458261 -273.263226)
			(xy 304.428696 -273.30257) (xy 304.393203 -273.336662) (xy 304.3527 -273.364618) (xy 304.308238 -273.385716)
			(xy 304.260967 -273.399408) (xy 304.212112 -273.40534) (xy 304.162937 -273.403359) (xy 304.114718 -273.393515)
			(xy 304.068702 -273.376063) (xy 304.026081 -273.351456) (xy 303.98796 -273.320331) (xy 303.955325 -273.283494)
			(xy 303.929022 -273.241898) (xy 303.909731 -273.196622) (xy 303.897954 -273.148838) (xy 303.893994 -273.099784)
			(xy 303.576736 -273.099784) (xy 303.576232 -273.125492) (xy 303.568189 -273.176274) (xy 303.552301 -273.225173)
			(xy 303.528958 -273.270985) (xy 303.498737 -273.312581) (xy 303.462381 -273.348937) (xy 303.420785 -273.379158)
			(xy 303.374973 -273.402501) (xy 303.326074 -273.418389) (xy 303.275292 -273.426432) (xy 303.223876 -273.426432)
			(xy 303.173094 -273.418389) (xy 303.124195 -273.402501) (xy 303.078383 -273.379158) (xy 303.036787 -273.348937)
			(xy 303.000431 -273.312581) (xy 302.97021 -273.270985) (xy 302.946867 -273.225173) (xy 302.930979 -273.176274)
			(xy 302.922936 -273.125492) (xy 302.604512 -273.125492) (xy 302.596796 -273.172968) (xy 302.581212 -273.219649)
			(xy 302.558341 -273.263226) (xy 302.528776 -273.30257) (xy 302.493283 -273.336662) (xy 302.45278 -273.364618)
			(xy 302.408318 -273.385716) (xy 302.361047 -273.399408) (xy 302.312192 -273.40534) (xy 302.263017 -273.403359)
			(xy 302.214798 -273.393515) (xy 302.168782 -273.376063) (xy 302.126161 -273.351456) (xy 302.08804 -273.320331)
			(xy 302.055405 -273.283494) (xy 302.029102 -273.241898) (xy 302.009811 -273.196622) (xy 301.998034 -273.148838)
			(xy 301.994074 -273.099784) (xy 301.676816 -273.099784) (xy 301.676312 -273.125492) (xy 301.668269 -273.176274)
			(xy 301.652381 -273.225173) (xy 301.629038 -273.270985) (xy 301.598817 -273.312581) (xy 301.562461 -273.348937)
			(xy 301.520865 -273.379158) (xy 301.475053 -273.402501) (xy 301.426154 -273.418389) (xy 301.375372 -273.426432)
			(xy 301.323956 -273.426432) (xy 301.273174 -273.418389) (xy 301.224275 -273.402501) (xy 301.178463 -273.379158)
			(xy 301.136867 -273.348937) (xy 301.100511 -273.312581) (xy 301.07029 -273.270985) (xy 301.046947 -273.225173)
			(xy 301.031059 -273.176274) (xy 301.023016 -273.125492) (xy 300.704338 -273.125492) (xy 300.696622 -273.172968)
			(xy 300.681038 -273.219649) (xy 300.658167 -273.263226) (xy 300.628602 -273.30257) (xy 300.593109 -273.336662)
			(xy 300.552606 -273.364618) (xy 300.508144 -273.385716) (xy 300.460873 -273.399408) (xy 300.412018 -273.40534)
			(xy 300.362843 -273.403359) (xy 300.314624 -273.393515) (xy 300.268608 -273.376063) (xy 300.225987 -273.351456)
			(xy 300.187866 -273.320331) (xy 300.155231 -273.283494) (xy 300.128928 -273.241898) (xy 300.109637 -273.196622)
			(xy 300.09786 -273.148838) (xy 300.0939 -273.099784) (xy 299.776642 -273.099784) (xy 299.776138 -273.125492)
			(xy 299.768095 -273.176274) (xy 299.752207 -273.225173) (xy 299.728864 -273.270985) (xy 299.698643 -273.312581)
			(xy 299.662287 -273.348937) (xy 299.620691 -273.379158) (xy 299.574879 -273.402501) (xy 299.52598 -273.418389)
			(xy 299.475198 -273.426432) (xy 299.423782 -273.426432) (xy 299.373 -273.418389) (xy 299.324101 -273.402501)
			(xy 299.278289 -273.379158) (xy 299.236693 -273.348937) (xy 299.200337 -273.312581) (xy 299.170116 -273.270985)
			(xy 299.146773 -273.225173) (xy 299.130885 -273.176274) (xy 299.122842 -273.125492) (xy 298.804418 -273.125492)
			(xy 298.796702 -273.172968) (xy 298.781118 -273.219649) (xy 298.758247 -273.263226) (xy 298.728682 -273.30257)
			(xy 298.693189 -273.336662) (xy 298.652686 -273.364618) (xy 298.608224 -273.385716) (xy 298.560953 -273.399408)
			(xy 298.512098 -273.40534) (xy 298.462923 -273.403359) (xy 298.414704 -273.393515) (xy 298.368688 -273.376063)
			(xy 298.326067 -273.351456) (xy 298.287946 -273.320331) (xy 298.255311 -273.283494) (xy 298.229008 -273.241898)
			(xy 298.209717 -273.196622) (xy 298.19794 -273.148838) (xy 298.19398 -273.099784) (xy 297.876722 -273.099784)
			(xy 297.876218 -273.125492) (xy 297.868175 -273.176274) (xy 297.852287 -273.225173) (xy 297.828944 -273.270985)
			(xy 297.798723 -273.312581) (xy 297.762367 -273.348937) (xy 297.720771 -273.379158) (xy 297.674959 -273.402501)
			(xy 297.62606 -273.418389) (xy 297.575278 -273.426432) (xy 297.523862 -273.426432) (xy 297.47308 -273.418389)
			(xy 297.424181 -273.402501) (xy 297.378369 -273.379158) (xy 297.336773 -273.348937) (xy 297.300417 -273.312581)
			(xy 297.270196 -273.270985) (xy 297.246853 -273.225173) (xy 297.230965 -273.176274) (xy 297.222922 -273.125492)
			(xy 296.904498 -273.125492) (xy 296.896782 -273.172968) (xy 296.881198 -273.219649) (xy 296.858327 -273.263226)
			(xy 296.828762 -273.30257) (xy 296.793269 -273.336662) (xy 296.752766 -273.364618) (xy 296.708304 -273.385716)
			(xy 296.661033 -273.399408) (xy 296.612178 -273.40534) (xy 296.563003 -273.403359) (xy 296.514784 -273.393515)
			(xy 296.468768 -273.376063) (xy 296.426147 -273.351456) (xy 296.388026 -273.320331) (xy 296.355391 -273.283494)
			(xy 296.329088 -273.241898) (xy 296.309797 -273.196622) (xy 296.29802 -273.148838) (xy 296.29406 -273.099784)
			(xy 295.976802 -273.099784) (xy 295.976298 -273.125492) (xy 295.968255 -273.176274) (xy 295.952367 -273.225173)
			(xy 295.929024 -273.270985) (xy 295.898803 -273.312581) (xy 295.862447 -273.348937) (xy 295.820851 -273.379158)
			(xy 295.775039 -273.402501) (xy 295.72614 -273.418389) (xy 295.675358 -273.426432) (xy 295.623942 -273.426432)
			(xy 295.57316 -273.418389) (xy 295.524261 -273.402501) (xy 295.478449 -273.379158) (xy 295.436853 -273.348937)
			(xy 295.400497 -273.312581) (xy 295.370276 -273.270985) (xy 295.346933 -273.225173) (xy 295.331045 -273.176274)
			(xy 295.323002 -273.125492) (xy 295.004324 -273.125492) (xy 294.996608 -273.172968) (xy 294.981024 -273.219649)
			(xy 294.958153 -273.263226) (xy 294.928588 -273.30257) (xy 294.893095 -273.336662) (xy 294.852592 -273.364618)
			(xy 294.80813 -273.385716) (xy 294.760859 -273.399408) (xy 294.712004 -273.40534) (xy 294.662829 -273.403359)
			(xy 294.61461 -273.393515) (xy 294.568594 -273.376063) (xy 294.525973 -273.351456) (xy 294.487852 -273.320331)
			(xy 294.455217 -273.283494) (xy 294.428914 -273.241898) (xy 294.409623 -273.196622) (xy 294.397846 -273.148838)
			(xy 294.393886 -273.099784) (xy 294.076628 -273.099784) (xy 294.076124 -273.125492) (xy 294.068081 -273.176274)
			(xy 294.052193 -273.225173) (xy 294.02885 -273.270985) (xy 293.998629 -273.312581) (xy 293.962273 -273.348937)
			(xy 293.920677 -273.379158) (xy 293.874865 -273.402501) (xy 293.825966 -273.418389) (xy 293.775184 -273.426432)
			(xy 293.723768 -273.426432) (xy 293.672986 -273.418389) (xy 293.624087 -273.402501) (xy 293.578275 -273.379158)
			(xy 293.536679 -273.348937) (xy 293.500323 -273.312581) (xy 293.470102 -273.270985) (xy 293.446759 -273.225173)
			(xy 293.430871 -273.176274) (xy 293.422828 -273.125492) (xy 293.104404 -273.125492) (xy 293.096688 -273.172968)
			(xy 293.081104 -273.219649) (xy 293.058233 -273.263226) (xy 293.028668 -273.30257) (xy 292.993175 -273.336662)
			(xy 292.952672 -273.364618) (xy 292.90821 -273.385716) (xy 292.860939 -273.399408) (xy 292.812084 -273.40534)
			(xy 292.762909 -273.403359) (xy 292.71469 -273.393515) (xy 292.668674 -273.376063) (xy 292.626053 -273.351456)
			(xy 292.587932 -273.320331) (xy 292.555297 -273.283494) (xy 292.528994 -273.241898) (xy 292.509703 -273.196622)
			(xy 292.497926 -273.148838) (xy 292.493966 -273.099784) (xy 292.176703 -273.099784) (xy 292.176204 -273.125238)
			(xy 292.168161 -273.17602) (xy 292.152273 -273.224919) (xy 292.12893 -273.270731) (xy 292.098709 -273.312327)
			(xy 292.062353 -273.348683) (xy 292.020757 -273.378904) (xy 291.974945 -273.402247) (xy 291.926046 -273.418135)
			(xy 291.875264 -273.426178) (xy 291.823848 -273.426178) (xy 291.773066 -273.418135) (xy 291.724167 -273.402247)
			(xy 291.678355 -273.378904) (xy 291.636759 -273.348683) (xy 291.600403 -273.312327) (xy 291.570182 -273.270731)
			(xy 291.546839 -273.224919) (xy 291.530951 -273.17602) (xy 291.522908 -273.125238) (xy 291.204525 -273.125238)
			(xy 291.196768 -273.172968) (xy 291.181184 -273.219649) (xy 291.158313 -273.263226) (xy 291.128748 -273.30257)
			(xy 291.093255 -273.336662) (xy 291.052752 -273.364618) (xy 291.00829 -273.385716) (xy 290.961019 -273.399408)
			(xy 290.912164 -273.40534) (xy 290.862989 -273.403359) (xy 290.81477 -273.393515) (xy 290.768754 -273.376063)
			(xy 290.726133 -273.351456) (xy 290.688012 -273.320331) (xy 290.655377 -273.283494) (xy 290.629074 -273.241898)
			(xy 290.609783 -273.196622) (xy 290.598006 -273.148838) (xy 290.594046 -273.099784) (xy 290.277042 -273.099784)
			(xy 290.276538 -273.125492) (xy 290.268495 -273.176274) (xy 290.252607 -273.225173) (xy 290.229264 -273.270985)
			(xy 290.199043 -273.312581) (xy 290.162687 -273.348937) (xy 290.121091 -273.379158) (xy 290.075279 -273.402501)
			(xy 290.02638 -273.418389) (xy 289.975598 -273.426432) (xy 289.924182 -273.426432) (xy 289.8734 -273.418389)
			(xy 289.824501 -273.402501) (xy 289.778689 -273.379158) (xy 289.737093 -273.348937) (xy 289.700737 -273.312581)
			(xy 289.670516 -273.270985) (xy 289.647173 -273.225173) (xy 289.631285 -273.176274) (xy 289.623242 -273.125492)
			(xy 289.304564 -273.125492) (xy 289.296848 -273.172968) (xy 289.281264 -273.219649) (xy 289.258393 -273.263226)
			(xy 289.228828 -273.30257) (xy 289.193335 -273.336662) (xy 289.152832 -273.364618) (xy 289.10837 -273.385716)
			(xy 289.061099 -273.399408) (xy 289.012244 -273.40534) (xy 288.963069 -273.403359) (xy 288.91485 -273.393515)
			(xy 288.868834 -273.376063) (xy 288.826213 -273.351456) (xy 288.788092 -273.320331) (xy 288.755457 -273.283494)
			(xy 288.729154 -273.241898) (xy 288.709863 -273.196622) (xy 288.698086 -273.148838) (xy 288.694126 -273.099784)
			(xy 288.376868 -273.099784) (xy 288.376364 -273.125492) (xy 288.368321 -273.176274) (xy 288.352433 -273.225173)
			(xy 288.32909 -273.270985) (xy 288.298869 -273.312581) (xy 288.262513 -273.348937) (xy 288.220917 -273.379158)
			(xy 288.175105 -273.402501) (xy 288.126206 -273.418389) (xy 288.075424 -273.426432) (xy 288.024008 -273.426432)
			(xy 287.973226 -273.418389) (xy 287.924327 -273.402501) (xy 287.878515 -273.379158) (xy 287.836919 -273.348937)
			(xy 287.800563 -273.312581) (xy 287.770342 -273.270985) (xy 287.746999 -273.225173) (xy 287.731111 -273.176274)
			(xy 287.723068 -273.125492) (xy 287.40439 -273.125492) (xy 287.396674 -273.172968) (xy 287.38109 -273.219649)
			(xy 287.358219 -273.263226) (xy 287.328654 -273.30257) (xy 287.293161 -273.336662) (xy 287.252658 -273.364618)
			(xy 287.208196 -273.385716) (xy 287.160925 -273.399408) (xy 287.11207 -273.40534) (xy 287.062895 -273.403359)
			(xy 287.014676 -273.393515) (xy 286.96866 -273.376063) (xy 286.926039 -273.351456) (xy 286.887918 -273.320331)
			(xy 286.855283 -273.283494) (xy 286.82898 -273.241898) (xy 286.809689 -273.196622) (xy 286.797912 -273.148838)
			(xy 286.793952 -273.099784) (xy 286.476948 -273.099784) (xy 286.476444 -273.125492) (xy 286.468401 -273.176274)
			(xy 286.452513 -273.225173) (xy 286.42917 -273.270985) (xy 286.398949 -273.312581) (xy 286.362593 -273.348937)
			(xy 286.320997 -273.379158) (xy 286.275185 -273.402501) (xy 286.226286 -273.418389) (xy 286.175504 -273.426432)
			(xy 286.124088 -273.426432) (xy 286.073306 -273.418389) (xy 286.024407 -273.402501) (xy 285.978595 -273.379158)
			(xy 285.936999 -273.348937) (xy 285.900643 -273.312581) (xy 285.870422 -273.270985) (xy 285.847079 -273.225173)
			(xy 285.831191 -273.176274) (xy 285.823148 -273.125492) (xy 285.50447 -273.125492) (xy 285.496754 -273.172968)
			(xy 285.48117 -273.219649) (xy 285.458299 -273.263226) (xy 285.428734 -273.30257) (xy 285.393241 -273.336662)
			(xy 285.352738 -273.364618) (xy 285.308276 -273.385716) (xy 285.261005 -273.399408) (xy 285.21215 -273.40534)
			(xy 285.162975 -273.403359) (xy 285.114756 -273.393515) (xy 285.06874 -273.376063) (xy 285.026119 -273.351456)
			(xy 284.987998 -273.320331) (xy 284.955363 -273.283494) (xy 284.92906 -273.241898) (xy 284.909769 -273.196622)
			(xy 284.897992 -273.148838) (xy 284.894032 -273.099784) (xy 284.577028 -273.099784) (xy 284.576524 -273.125492)
			(xy 284.568481 -273.176274) (xy 284.552593 -273.225173) (xy 284.52925 -273.270985) (xy 284.499029 -273.312581)
			(xy 284.462673 -273.348937) (xy 284.421077 -273.379158) (xy 284.375265 -273.402501) (xy 284.326366 -273.418389)
			(xy 284.275584 -273.426432) (xy 284.224168 -273.426432) (xy 284.173386 -273.418389) (xy 284.124487 -273.402501)
			(xy 284.078675 -273.379158) (xy 284.037079 -273.348937) (xy 284.000723 -273.312581) (xy 283.970502 -273.270985)
			(xy 283.947159 -273.225173) (xy 283.931271 -273.176274) (xy 283.923228 -273.125492) (xy 283.60455 -273.125492)
			(xy 283.596834 -273.172968) (xy 283.58125 -273.219649) (xy 283.558379 -273.263226) (xy 283.528814 -273.30257)
			(xy 283.493321 -273.336662) (xy 283.452818 -273.364618) (xy 283.408356 -273.385716) (xy 283.361085 -273.399408)
			(xy 283.31223 -273.40534) (xy 283.263055 -273.403359) (xy 283.214836 -273.393515) (xy 283.16882 -273.376063)
			(xy 283.126199 -273.351456) (xy 283.088078 -273.320331) (xy 283.055443 -273.283494) (xy 283.02914 -273.241898)
			(xy 283.009849 -273.196622) (xy 282.998072 -273.148838) (xy 282.994112 -273.099784) (xy 282.676854 -273.099784)
			(xy 282.67635 -273.125492) (xy 282.668307 -273.176274) (xy 282.652419 -273.225173) (xy 282.629076 -273.270985)
			(xy 282.598855 -273.312581) (xy 282.562499 -273.348937) (xy 282.520903 -273.379158) (xy 282.475091 -273.402501)
			(xy 282.426192 -273.418389) (xy 282.37541 -273.426432) (xy 282.323994 -273.426432) (xy 282.273212 -273.418389)
			(xy 282.224313 -273.402501) (xy 282.178501 -273.379158) (xy 282.136905 -273.348937) (xy 282.100549 -273.312581)
			(xy 282.070328 -273.270985) (xy 282.046985 -273.225173) (xy 282.031097 -273.176274) (xy 282.023054 -273.125492)
			(xy 281.704376 -273.125492) (xy 281.69666 -273.172968) (xy 281.681076 -273.219649) (xy 281.658205 -273.263226)
			(xy 281.62864 -273.30257) (xy 281.593147 -273.336662) (xy 281.552644 -273.364618) (xy 281.508182 -273.385716)
			(xy 281.460911 -273.399408) (xy 281.412056 -273.40534) (xy 281.362881 -273.403359) (xy 281.314662 -273.393515)
			(xy 281.268646 -273.376063) (xy 281.226025 -273.351456) (xy 281.187904 -273.320331) (xy 281.155269 -273.283494)
			(xy 281.128966 -273.241898) (xy 281.109675 -273.196622) (xy 281.097898 -273.148838) (xy 281.093938 -273.099784)
			(xy 280.776934 -273.099784) (xy 280.77643 -273.125492) (xy 280.768387 -273.176274) (xy 280.752499 -273.225173)
			(xy 280.729156 -273.270985) (xy 280.698935 -273.312581) (xy 280.662579 -273.348937) (xy 280.620983 -273.379158)
			(xy 280.575171 -273.402501) (xy 280.526272 -273.418389) (xy 280.47549 -273.426432) (xy 280.424074 -273.426432)
			(xy 280.373292 -273.418389) (xy 280.324393 -273.402501) (xy 280.278581 -273.379158) (xy 280.236985 -273.348937)
			(xy 280.200629 -273.312581) (xy 280.170408 -273.270985) (xy 280.147065 -273.225173) (xy 280.131177 -273.176274)
			(xy 280.123134 -273.125492) (xy 279.804456 -273.125492) (xy 279.79674 -273.172968) (xy 279.781156 -273.219649)
			(xy 279.758285 -273.263226) (xy 279.72872 -273.30257) (xy 279.693227 -273.336662) (xy 279.652724 -273.364618)
			(xy 279.608262 -273.385716) (xy 279.560991 -273.399408) (xy 279.512136 -273.40534) (xy 279.462961 -273.403359)
			(xy 279.414742 -273.393515) (xy 279.368726 -273.376063) (xy 279.326105 -273.351456) (xy 279.287984 -273.320331)
			(xy 279.255349 -273.283494) (xy 279.229046 -273.241898) (xy 279.209755 -273.196622) (xy 279.197978 -273.148838)
			(xy 279.194018 -273.099784) (xy 278.877014 -273.099784) (xy 278.87651 -273.125492) (xy 278.868467 -273.176274)
			(xy 278.852579 -273.225173) (xy 278.829236 -273.270985) (xy 278.799015 -273.312581) (xy 278.762659 -273.348937)
			(xy 278.721063 -273.379158) (xy 278.675251 -273.402501) (xy 278.626352 -273.418389) (xy 278.57557 -273.426432)
			(xy 278.524154 -273.426432) (xy 278.473372 -273.418389) (xy 278.424473 -273.402501) (xy 278.378661 -273.379158)
			(xy 278.337065 -273.348937) (xy 278.300709 -273.312581) (xy 278.270488 -273.270985) (xy 278.247145 -273.225173)
			(xy 278.231257 -273.176274) (xy 278.223214 -273.125492) (xy 277.904536 -273.125492) (xy 277.89682 -273.172968)
			(xy 277.881236 -273.219649) (xy 277.858365 -273.263226) (xy 277.8288 -273.30257) (xy 277.793307 -273.336662)
			(xy 277.752804 -273.364618) (xy 277.708342 -273.385716) (xy 277.661071 -273.399408) (xy 277.612216 -273.40534)
			(xy 277.563041 -273.403359) (xy 277.514822 -273.393515) (xy 277.468806 -273.376063) (xy 277.426185 -273.351456)
			(xy 277.388064 -273.320331) (xy 277.355429 -273.283494) (xy 277.329126 -273.241898) (xy 277.309835 -273.196622)
			(xy 277.298058 -273.148838) (xy 277.294098 -273.099784) (xy 276.97684 -273.099784) (xy 276.976336 -273.125492)
			(xy 276.968293 -273.176274) (xy 276.952405 -273.225173) (xy 276.929062 -273.270985) (xy 276.898841 -273.312581)
			(xy 276.862485 -273.348937) (xy 276.820889 -273.379158) (xy 276.775077 -273.402501) (xy 276.726178 -273.418389)
			(xy 276.675396 -273.426432) (xy 276.62398 -273.426432) (xy 276.573198 -273.418389) (xy 276.524299 -273.402501)
			(xy 276.478487 -273.379158) (xy 276.436891 -273.348937) (xy 276.400535 -273.312581) (xy 276.370314 -273.270985)
			(xy 276.346971 -273.225173) (xy 276.331083 -273.176274) (xy 276.32304 -273.125492) (xy 266.046342 -273.125492)
			(xy 265.988583 -273.233055) (xy 265.889305 -273.401002) (xy 265.783216 -273.564733) (xy 265.776115 -273.574764)
			(xy 269.21893 -273.574764) (xy 269.22289 -273.52571) (xy 269.234667 -273.477926) (xy 269.253958 -273.43265)
			(xy 269.280261 -273.391054) (xy 269.312896 -273.354217) (xy 269.351017 -273.323092) (xy 269.393638 -273.298485)
			(xy 269.439654 -273.281033) (xy 269.487873 -273.271189) (xy 269.537048 -273.269208) (xy 269.585903 -273.27514)
			(xy 269.633174 -273.288832) (xy 269.677636 -273.30993) (xy 269.718139 -273.337886) (xy 269.753632 -273.371978)
			(xy 269.783197 -273.411322) (xy 269.806068 -273.454899) (xy 269.821652 -273.50158) (xy 269.829547 -273.550157)
			(xy 269.830042 -273.574764) (xy 270.16889 -273.574764) (xy 270.17285 -273.52571) (xy 270.184627 -273.477926)
			(xy 270.203918 -273.43265) (xy 270.230221 -273.391054) (xy 270.262856 -273.354217) (xy 270.300977 -273.323092)
			(xy 270.343598 -273.298485) (xy 270.389614 -273.281033) (xy 270.437833 -273.271189) (xy 270.487008 -273.269208)
			(xy 270.535863 -273.27514) (xy 270.583134 -273.288832) (xy 270.627596 -273.30993) (xy 270.668099 -273.337886)
			(xy 270.703592 -273.371978) (xy 270.733157 -273.411322) (xy 270.756028 -273.454899) (xy 270.771612 -273.50158)
			(xy 270.779507 -273.550157) (xy 270.780002 -273.574764) (xy 271.119104 -273.574764) (xy 271.123064 -273.52571)
			(xy 271.134841 -273.477926) (xy 271.154132 -273.43265) (xy 271.180435 -273.391054) (xy 271.21307 -273.354217)
			(xy 271.251191 -273.323092) (xy 271.293812 -273.298485) (xy 271.339828 -273.281033) (xy 271.388047 -273.271189)
			(xy 271.437222 -273.269208) (xy 271.486077 -273.27514) (xy 271.533348 -273.288832) (xy 271.57781 -273.30993)
			(xy 271.618313 -273.337886) (xy 271.653806 -273.371978) (xy 271.683371 -273.411322) (xy 271.706242 -273.454899)
			(xy 271.721826 -273.50158) (xy 271.729721 -273.550157) (xy 271.730216 -273.574764) (xy 272.069064 -273.574764)
			(xy 272.073024 -273.52571) (xy 272.084801 -273.477926) (xy 272.104092 -273.43265) (xy 272.130395 -273.391054)
			(xy 272.16303 -273.354217) (xy 272.201151 -273.323092) (xy 272.243772 -273.298485) (xy 272.289788 -273.281033)
			(xy 272.338007 -273.271189) (xy 272.387182 -273.269208) (xy 272.436037 -273.27514) (xy 272.483308 -273.288832)
			(xy 272.52777 -273.30993) (xy 272.568273 -273.337886) (xy 272.603766 -273.371978) (xy 272.633331 -273.411322)
			(xy 272.656202 -273.454899) (xy 272.671786 -273.50158) (xy 272.679681 -273.550157) (xy 272.680176 -273.574764)
			(xy 273.019024 -273.574764) (xy 273.022984 -273.52571) (xy 273.034761 -273.477926) (xy 273.054052 -273.43265)
			(xy 273.080355 -273.391054) (xy 273.11299 -273.354217) (xy 273.151111 -273.323092) (xy 273.193732 -273.298485)
			(xy 273.239748 -273.281033) (xy 273.287967 -273.271189) (xy 273.337142 -273.269208) (xy 273.385997 -273.27514)
			(xy 273.433268 -273.288832) (xy 273.47773 -273.30993) (xy 273.518233 -273.337886) (xy 273.553726 -273.371978)
			(xy 273.583291 -273.411322) (xy 273.606162 -273.454899) (xy 273.621746 -273.50158) (xy 273.629641 -273.550157)
			(xy 273.630136 -273.574764) (xy 273.968984 -273.574764) (xy 273.972944 -273.52571) (xy 273.984721 -273.477926)
			(xy 274.004012 -273.43265) (xy 274.030315 -273.391054) (xy 274.06295 -273.354217) (xy 274.101071 -273.323092)
			(xy 274.143692 -273.298485) (xy 274.189708 -273.281033) (xy 274.237927 -273.271189) (xy 274.287102 -273.269208)
			(xy 274.335957 -273.27514) (xy 274.383228 -273.288832) (xy 274.42769 -273.30993) (xy 274.468193 -273.337886)
			(xy 274.503686 -273.371978) (xy 274.533251 -273.411322) (xy 274.556122 -273.454899) (xy 274.571706 -273.50158)
			(xy 274.579601 -273.550157) (xy 274.580096 -273.574764) (xy 274.918944 -273.574764) (xy 274.922904 -273.52571)
			(xy 274.934681 -273.477926) (xy 274.953972 -273.43265) (xy 274.980275 -273.391054) (xy 275.01291 -273.354217)
			(xy 275.051031 -273.323092) (xy 275.093652 -273.298485) (xy 275.139668 -273.281033) (xy 275.187887 -273.271189)
			(xy 275.237062 -273.269208) (xy 275.285917 -273.27514) (xy 275.333188 -273.288832) (xy 275.37765 -273.30993)
			(xy 275.418153 -273.337886) (xy 275.453646 -273.371978) (xy 275.483211 -273.411322) (xy 275.506082 -273.454899)
			(xy 275.521666 -273.50158) (xy 275.529561 -273.550157) (xy 275.530056 -273.574764) (xy 275.529561 -273.599371)
			(xy 275.521666 -273.647948) (xy 275.506082 -273.694629) (xy 275.483211 -273.738206) (xy 275.453646 -273.77755)
			(xy 275.418153 -273.811642) (xy 275.37765 -273.839598) (xy 275.333188 -273.860696) (xy 275.285917 -273.874388)
			(xy 275.237062 -273.88032) (xy 275.187887 -273.878339) (xy 275.139668 -273.868495) (xy 275.093652 -273.851043)
			(xy 275.051031 -273.826436) (xy 275.01291 -273.795311) (xy 274.980275 -273.758474) (xy 274.953972 -273.716878)
			(xy 274.934681 -273.671602) (xy 274.922904 -273.623818) (xy 274.918944 -273.574764) (xy 274.580096 -273.574764)
			(xy 274.579601 -273.599371) (xy 274.571706 -273.647948) (xy 274.556122 -273.694629) (xy 274.533251 -273.738206)
			(xy 274.503686 -273.77755) (xy 274.468193 -273.811642) (xy 274.42769 -273.839598) (xy 274.383228 -273.860696)
			(xy 274.335957 -273.874388) (xy 274.287102 -273.88032) (xy 274.237927 -273.878339) (xy 274.189708 -273.868495)
			(xy 274.143692 -273.851043) (xy 274.101071 -273.826436) (xy 274.06295 -273.795311) (xy 274.030315 -273.758474)
			(xy 274.004012 -273.716878) (xy 273.984721 -273.671602) (xy 273.972944 -273.623818) (xy 273.968984 -273.574764)
			(xy 273.630136 -273.574764) (xy 273.629641 -273.599371) (xy 273.621746 -273.647948) (xy 273.606162 -273.694629)
			(xy 273.583291 -273.738206) (xy 273.553726 -273.77755) (xy 273.518233 -273.811642) (xy 273.47773 -273.839598)
			(xy 273.433268 -273.860696) (xy 273.385997 -273.874388) (xy 273.337142 -273.88032) (xy 273.287967 -273.878339)
			(xy 273.239748 -273.868495) (xy 273.193732 -273.851043) (xy 273.151111 -273.826436) (xy 273.11299 -273.795311)
			(xy 273.080355 -273.758474) (xy 273.054052 -273.716878) (xy 273.034761 -273.671602) (xy 273.022984 -273.623818)
			(xy 273.019024 -273.574764) (xy 272.680176 -273.574764) (xy 272.679681 -273.599371) (xy 272.671786 -273.647948)
			(xy 272.656202 -273.694629) (xy 272.633331 -273.738206) (xy 272.603766 -273.77755) (xy 272.568273 -273.811642)
			(xy 272.52777 -273.839598) (xy 272.483308 -273.860696) (xy 272.436037 -273.874388) (xy 272.387182 -273.88032)
			(xy 272.338007 -273.878339) (xy 272.289788 -273.868495) (xy 272.243772 -273.851043) (xy 272.201151 -273.826436)
			(xy 272.16303 -273.795311) (xy 272.130395 -273.758474) (xy 272.104092 -273.716878) (xy 272.084801 -273.671602)
			(xy 272.073024 -273.623818) (xy 272.069064 -273.574764) (xy 271.730216 -273.574764) (xy 271.729721 -273.599371)
			(xy 271.721826 -273.647948) (xy 271.706242 -273.694629) (xy 271.683371 -273.738206) (xy 271.653806 -273.77755)
			(xy 271.618313 -273.811642) (xy 271.57781 -273.839598) (xy 271.533348 -273.860696) (xy 271.486077 -273.874388)
			(xy 271.437222 -273.88032) (xy 271.388047 -273.878339) (xy 271.339828 -273.868495) (xy 271.293812 -273.851043)
			(xy 271.251191 -273.826436) (xy 271.21307 -273.795311) (xy 271.180435 -273.758474) (xy 271.154132 -273.716878)
			(xy 271.134841 -273.671602) (xy 271.123064 -273.623818) (xy 271.119104 -273.574764) (xy 270.780002 -273.574764)
			(xy 270.779507 -273.599371) (xy 270.771612 -273.647948) (xy 270.756028 -273.694629) (xy 270.733157 -273.738206)
			(xy 270.703592 -273.77755) (xy 270.668099 -273.811642) (xy 270.627596 -273.839598) (xy 270.583134 -273.860696)
			(xy 270.535863 -273.874388) (xy 270.487008 -273.88032) (xy 270.437833 -273.878339) (xy 270.389614 -273.868495)
			(xy 270.343598 -273.851043) (xy 270.300977 -273.826436) (xy 270.262856 -273.795311) (xy 270.230221 -273.758474)
			(xy 270.203918 -273.716878) (xy 270.184627 -273.671602) (xy 270.17285 -273.623818) (xy 270.16889 -273.574764)
			(xy 269.830042 -273.574764) (xy 269.829547 -273.599371) (xy 269.821652 -273.647948) (xy 269.806068 -273.694629)
			(xy 269.783197 -273.738206) (xy 269.753632 -273.77755) (xy 269.718139 -273.811642) (xy 269.677636 -273.839598)
			(xy 269.633174 -273.860696) (xy 269.585903 -273.874388) (xy 269.537048 -273.88032) (xy 269.487873 -273.878339)
			(xy 269.439654 -273.868495) (xy 269.393638 -273.851043) (xy 269.351017 -273.826436) (xy 269.312896 -273.795311)
			(xy 269.280261 -273.758474) (xy 269.253958 -273.716878) (xy 269.234667 -273.671602) (xy 269.22289 -273.623818)
			(xy 269.21893 -273.574764) (xy 265.776115 -273.574764) (xy 265.670495 -273.72397) (xy 265.551331 -273.878444)
			(xy 265.425926 -274.027897) (xy 265.382574 -274.075452) (xy 276.32304 -274.075452) (xy 276.32304 -274.024036)
			(xy 276.331083 -273.973254) (xy 276.346971 -273.924355) (xy 276.370314 -273.878543) (xy 276.400535 -273.836947)
			(xy 276.436891 -273.800591) (xy 276.478487 -273.77037) (xy 276.524299 -273.747027) (xy 276.573198 -273.731139)
			(xy 276.62398 -273.723096) (xy 276.675396 -273.723096) (xy 276.726178 -273.731139) (xy 276.775077 -273.747027)
			(xy 276.820889 -273.77037) (xy 276.862485 -273.800591) (xy 276.898841 -273.836947) (xy 276.929062 -273.878543)
			(xy 276.952405 -273.924355) (xy 276.968293 -273.973254) (xy 276.976336 -274.024036) (xy 276.97684 -274.049744)
			(xy 277.294098 -274.049744) (xy 277.298058 -274.00069) (xy 277.309835 -273.952906) (xy 277.329126 -273.90763)
			(xy 277.355429 -273.866034) (xy 277.388064 -273.829197) (xy 277.426185 -273.798072) (xy 277.468806 -273.773465)
			(xy 277.514822 -273.756013) (xy 277.563041 -273.746169) (xy 277.612216 -273.744188) (xy 277.661071 -273.75012)
			(xy 277.708342 -273.763812) (xy 277.752804 -273.78491) (xy 277.793307 -273.812866) (xy 277.8288 -273.846958)
			(xy 277.858365 -273.886302) (xy 277.881236 -273.929879) (xy 277.89682 -273.97656) (xy 277.904715 -274.025137)
			(xy 277.90521 -274.049744) (xy 277.904715 -274.074351) (xy 277.904536 -274.075452) (xy 278.223214 -274.075452)
			(xy 278.223214 -274.024036) (xy 278.231257 -273.973254) (xy 278.247145 -273.924355) (xy 278.270488 -273.878543)
			(xy 278.300709 -273.836947) (xy 278.337065 -273.800591) (xy 278.378661 -273.77037) (xy 278.424473 -273.747027)
			(xy 278.473372 -273.731139) (xy 278.524154 -273.723096) (xy 278.57557 -273.723096) (xy 278.626352 -273.731139)
			(xy 278.675251 -273.747027) (xy 278.721063 -273.77037) (xy 278.762659 -273.800591) (xy 278.799015 -273.836947)
			(xy 278.829236 -273.878543) (xy 278.852579 -273.924355) (xy 278.868467 -273.973254) (xy 278.87651 -274.024036)
			(xy 278.877014 -274.049744) (xy 279.194018 -274.049744) (xy 279.197978 -274.00069) (xy 279.209755 -273.952906)
			(xy 279.229046 -273.90763) (xy 279.255349 -273.866034) (xy 279.287984 -273.829197) (xy 279.326105 -273.798072)
			(xy 279.368726 -273.773465) (xy 279.414742 -273.756013) (xy 279.462961 -273.746169) (xy 279.512136 -273.744188)
			(xy 279.560991 -273.75012) (xy 279.608262 -273.763812) (xy 279.652724 -273.78491) (xy 279.693227 -273.812866)
			(xy 279.72872 -273.846958) (xy 279.758285 -273.886302) (xy 279.781156 -273.929879) (xy 279.79674 -273.97656)
			(xy 279.804635 -274.025137) (xy 279.80513 -274.049744) (xy 279.804635 -274.074351) (xy 279.804456 -274.075452)
			(xy 280.123134 -274.075452) (xy 280.123134 -274.024036) (xy 280.131177 -273.973254) (xy 280.147065 -273.924355)
			(xy 280.170408 -273.878543) (xy 280.200629 -273.836947) (xy 280.236985 -273.800591) (xy 280.278581 -273.77037)
			(xy 280.324393 -273.747027) (xy 280.373292 -273.731139) (xy 280.424074 -273.723096) (xy 280.47549 -273.723096)
			(xy 280.526272 -273.731139) (xy 280.575171 -273.747027) (xy 280.620983 -273.77037) (xy 280.662579 -273.800591)
			(xy 280.698935 -273.836947) (xy 280.729156 -273.878543) (xy 280.752499 -273.924355) (xy 280.768387 -273.973254)
			(xy 280.77643 -274.024036) (xy 280.776934 -274.049744) (xy 281.093938 -274.049744) (xy 281.097898 -274.00069)
			(xy 281.109675 -273.952906) (xy 281.128966 -273.90763) (xy 281.155269 -273.866034) (xy 281.187904 -273.829197)
			(xy 281.226025 -273.798072) (xy 281.268646 -273.773465) (xy 281.314662 -273.756013) (xy 281.362881 -273.746169)
			(xy 281.412056 -273.744188) (xy 281.460911 -273.75012) (xy 281.508182 -273.763812) (xy 281.552644 -273.78491)
			(xy 281.593147 -273.812866) (xy 281.62864 -273.846958) (xy 281.658205 -273.886302) (xy 281.681076 -273.929879)
			(xy 281.69666 -273.97656) (xy 281.704555 -274.025137) (xy 281.70505 -274.049744) (xy 281.704555 -274.074351)
			(xy 281.704376 -274.075452) (xy 282.023054 -274.075452) (xy 282.023054 -274.024036) (xy 282.031097 -273.973254)
			(xy 282.046985 -273.924355) (xy 282.070328 -273.878543) (xy 282.100549 -273.836947) (xy 282.136905 -273.800591)
			(xy 282.178501 -273.77037) (xy 282.224313 -273.747027) (xy 282.273212 -273.731139) (xy 282.323994 -273.723096)
			(xy 282.37541 -273.723096) (xy 282.426192 -273.731139) (xy 282.475091 -273.747027) (xy 282.520903 -273.77037)
			(xy 282.562499 -273.800591) (xy 282.598855 -273.836947) (xy 282.629076 -273.878543) (xy 282.652419 -273.924355)
			(xy 282.668307 -273.973254) (xy 282.67635 -274.024036) (xy 282.676854 -274.049744) (xy 282.994112 -274.049744)
			(xy 282.998072 -274.00069) (xy 283.009849 -273.952906) (xy 283.02914 -273.90763) (xy 283.055443 -273.866034)
			(xy 283.088078 -273.829197) (xy 283.126199 -273.798072) (xy 283.16882 -273.773465) (xy 283.214836 -273.756013)
			(xy 283.263055 -273.746169) (xy 283.31223 -273.744188) (xy 283.361085 -273.75012) (xy 283.408356 -273.763812)
			(xy 283.452818 -273.78491) (xy 283.493321 -273.812866) (xy 283.528814 -273.846958) (xy 283.558379 -273.886302)
			(xy 283.58125 -273.929879) (xy 283.596834 -273.97656) (xy 283.604729 -274.025137) (xy 283.605224 -274.049744)
			(xy 283.604729 -274.074351) (xy 283.60455 -274.075452) (xy 283.923228 -274.075452) (xy 283.923228 -274.024036)
			(xy 283.931271 -273.973254) (xy 283.947159 -273.924355) (xy 283.970502 -273.878543) (xy 284.000723 -273.836947)
			(xy 284.037079 -273.800591) (xy 284.078675 -273.77037) (xy 284.124487 -273.747027) (xy 284.173386 -273.731139)
			(xy 284.224168 -273.723096) (xy 284.275584 -273.723096) (xy 284.326366 -273.731139) (xy 284.375265 -273.747027)
			(xy 284.421077 -273.77037) (xy 284.462673 -273.800591) (xy 284.499029 -273.836947) (xy 284.52925 -273.878543)
			(xy 284.552593 -273.924355) (xy 284.568481 -273.973254) (xy 284.576524 -274.024036) (xy 284.577028 -274.049744)
			(xy 284.894032 -274.049744) (xy 284.897992 -274.00069) (xy 284.909769 -273.952906) (xy 284.92906 -273.90763)
			(xy 284.955363 -273.866034) (xy 284.987998 -273.829197) (xy 285.026119 -273.798072) (xy 285.06874 -273.773465)
			(xy 285.114756 -273.756013) (xy 285.162975 -273.746169) (xy 285.21215 -273.744188) (xy 285.261005 -273.75012)
			(xy 285.308276 -273.763812) (xy 285.352738 -273.78491) (xy 285.393241 -273.812866) (xy 285.428734 -273.846958)
			(xy 285.458299 -273.886302) (xy 285.48117 -273.929879) (xy 285.496754 -273.97656) (xy 285.504649 -274.025137)
			(xy 285.505144 -274.049744) (xy 285.504649 -274.074351) (xy 285.50447 -274.075452) (xy 285.823148 -274.075452)
			(xy 285.823148 -274.024036) (xy 285.831191 -273.973254) (xy 285.847079 -273.924355) (xy 285.870422 -273.878543)
			(xy 285.900643 -273.836947) (xy 285.936999 -273.800591) (xy 285.978595 -273.77037) (xy 286.024407 -273.747027)
			(xy 286.073306 -273.731139) (xy 286.124088 -273.723096) (xy 286.175504 -273.723096) (xy 286.226286 -273.731139)
			(xy 286.275185 -273.747027) (xy 286.320997 -273.77037) (xy 286.362593 -273.800591) (xy 286.398949 -273.836947)
			(xy 286.42917 -273.878543) (xy 286.452513 -273.924355) (xy 286.468401 -273.973254) (xy 286.476444 -274.024036)
			(xy 286.476948 -274.049744) (xy 286.793952 -274.049744) (xy 286.797912 -274.00069) (xy 286.809689 -273.952906)
			(xy 286.82898 -273.90763) (xy 286.855283 -273.866034) (xy 286.887918 -273.829197) (xy 286.926039 -273.798072)
			(xy 286.96866 -273.773465) (xy 287.014676 -273.756013) (xy 287.062895 -273.746169) (xy 287.11207 -273.744188)
			(xy 287.160925 -273.75012) (xy 287.208196 -273.763812) (xy 287.252658 -273.78491) (xy 287.293161 -273.812866)
			(xy 287.328654 -273.846958) (xy 287.358219 -273.886302) (xy 287.38109 -273.929879) (xy 287.396674 -273.97656)
			(xy 287.404569 -274.025137) (xy 287.405064 -274.049744) (xy 287.404569 -274.074351) (xy 287.40439 -274.075452)
			(xy 287.723068 -274.075452) (xy 287.723068 -274.024036) (xy 287.731111 -273.973254) (xy 287.746999 -273.924355)
			(xy 287.770342 -273.878543) (xy 287.800563 -273.836947) (xy 287.836919 -273.800591) (xy 287.878515 -273.77037)
			(xy 287.924327 -273.747027) (xy 287.973226 -273.731139) (xy 288.024008 -273.723096) (xy 288.075424 -273.723096)
			(xy 288.126206 -273.731139) (xy 288.175105 -273.747027) (xy 288.220917 -273.77037) (xy 288.262513 -273.800591)
			(xy 288.298869 -273.836947) (xy 288.32909 -273.878543) (xy 288.352433 -273.924355) (xy 288.368321 -273.973254)
			(xy 288.376364 -274.024036) (xy 288.376868 -274.049744) (xy 288.694126 -274.049744) (xy 288.698086 -274.00069)
			(xy 288.709863 -273.952906) (xy 288.729154 -273.90763) (xy 288.755457 -273.866034) (xy 288.788092 -273.829197)
			(xy 288.826213 -273.798072) (xy 288.868834 -273.773465) (xy 288.91485 -273.756013) (xy 288.963069 -273.746169)
			(xy 289.012244 -273.744188) (xy 289.061099 -273.75012) (xy 289.10837 -273.763812) (xy 289.152832 -273.78491)
			(xy 289.193335 -273.812866) (xy 289.228828 -273.846958) (xy 289.258393 -273.886302) (xy 289.281264 -273.929879)
			(xy 289.296848 -273.97656) (xy 289.304743 -274.025137) (xy 289.305238 -274.049744) (xy 289.304743 -274.074351)
			(xy 289.304564 -274.075452) (xy 289.623242 -274.075452) (xy 289.623242 -274.024036) (xy 289.631285 -273.973254)
			(xy 289.647173 -273.924355) (xy 289.670516 -273.878543) (xy 289.700737 -273.836947) (xy 289.737093 -273.800591)
			(xy 289.778689 -273.77037) (xy 289.824501 -273.747027) (xy 289.8734 -273.731139) (xy 289.924182 -273.723096)
			(xy 289.975598 -273.723096) (xy 290.02638 -273.731139) (xy 290.075279 -273.747027) (xy 290.121091 -273.77037)
			(xy 290.162687 -273.800591) (xy 290.199043 -273.836947) (xy 290.229264 -273.878543) (xy 290.252607 -273.924355)
			(xy 290.268495 -273.973254) (xy 290.276538 -274.024036) (xy 290.277042 -274.049744) (xy 290.594046 -274.049744)
			(xy 290.598006 -274.00069) (xy 290.609783 -273.952906) (xy 290.629074 -273.90763) (xy 290.655377 -273.866034)
			(xy 290.688012 -273.829197) (xy 290.726133 -273.798072) (xy 290.768754 -273.773465) (xy 290.81477 -273.756013)
			(xy 290.862989 -273.746169) (xy 290.912164 -273.744188) (xy 290.961019 -273.75012) (xy 291.00829 -273.763812)
			(xy 291.052752 -273.78491) (xy 291.093255 -273.812866) (xy 291.128748 -273.846958) (xy 291.158313 -273.886302)
			(xy 291.181184 -273.929879) (xy 291.196768 -273.97656) (xy 291.204663 -274.025137) (xy 291.205158 -274.049744)
			(xy 291.204663 -274.074351) (xy 291.204525 -274.075198) (xy 291.522908 -274.075198) (xy 291.522908 -274.023782)
			(xy 291.530951 -273.973) (xy 291.546839 -273.924101) (xy 291.570182 -273.878289) (xy 291.600403 -273.836693)
			(xy 291.636759 -273.800337) (xy 291.678355 -273.770116) (xy 291.724167 -273.746773) (xy 291.773066 -273.730885)
			(xy 291.823848 -273.722842) (xy 291.875264 -273.722842) (xy 291.926046 -273.730885) (xy 291.974945 -273.746773)
			(xy 292.020757 -273.770116) (xy 292.062353 -273.800337) (xy 292.098709 -273.836693) (xy 292.12893 -273.878289)
			(xy 292.152273 -273.924101) (xy 292.168161 -273.973) (xy 292.176204 -274.023782) (xy 292.176708 -274.04949)
			(xy 292.176703 -274.049744) (xy 292.493966 -274.049744) (xy 292.497926 -274.00069) (xy 292.509703 -273.952906)
			(xy 292.528994 -273.90763) (xy 292.555297 -273.866034) (xy 292.587932 -273.829197) (xy 292.626053 -273.798072)
			(xy 292.668674 -273.773465) (xy 292.71469 -273.756013) (xy 292.762909 -273.746169) (xy 292.812084 -273.744188)
			(xy 292.860939 -273.75012) (xy 292.90821 -273.763812) (xy 292.952672 -273.78491) (xy 292.993175 -273.812866)
			(xy 293.028668 -273.846958) (xy 293.058233 -273.886302) (xy 293.081104 -273.929879) (xy 293.096688 -273.97656)
			(xy 293.104583 -274.025137) (xy 293.105078 -274.049744) (xy 293.104583 -274.074351) (xy 293.104404 -274.075452)
			(xy 293.422828 -274.075452) (xy 293.422828 -274.024036) (xy 293.430871 -273.973254) (xy 293.446759 -273.924355)
			(xy 293.470102 -273.878543) (xy 293.500323 -273.836947) (xy 293.536679 -273.800591) (xy 293.578275 -273.77037)
			(xy 293.624087 -273.747027) (xy 293.672986 -273.731139) (xy 293.723768 -273.723096) (xy 293.775184 -273.723096)
			(xy 293.825966 -273.731139) (xy 293.874865 -273.747027) (xy 293.920677 -273.77037) (xy 293.962273 -273.800591)
			(xy 293.998629 -273.836947) (xy 294.02885 -273.878543) (xy 294.052193 -273.924355) (xy 294.068081 -273.973254)
			(xy 294.076124 -274.024036) (xy 294.076628 -274.049744) (xy 294.393886 -274.049744) (xy 294.397846 -274.00069)
			(xy 294.409623 -273.952906) (xy 294.428914 -273.90763) (xy 294.455217 -273.866034) (xy 294.487852 -273.829197)
			(xy 294.525973 -273.798072) (xy 294.568594 -273.773465) (xy 294.61461 -273.756013) (xy 294.662829 -273.746169)
			(xy 294.712004 -273.744188) (xy 294.760859 -273.75012) (xy 294.80813 -273.763812) (xy 294.852592 -273.78491)
			(xy 294.893095 -273.812866) (xy 294.928588 -273.846958) (xy 294.958153 -273.886302) (xy 294.981024 -273.929879)
			(xy 294.996608 -273.97656) (xy 295.004503 -274.025137) (xy 295.004998 -274.049744) (xy 295.004503 -274.074351)
			(xy 295.004324 -274.075452) (xy 295.323002 -274.075452) (xy 295.323002 -274.024036) (xy 295.331045 -273.973254)
			(xy 295.346933 -273.924355) (xy 295.370276 -273.878543) (xy 295.400497 -273.836947) (xy 295.436853 -273.800591)
			(xy 295.478449 -273.77037) (xy 295.524261 -273.747027) (xy 295.57316 -273.731139) (xy 295.623942 -273.723096)
			(xy 295.675358 -273.723096) (xy 295.72614 -273.731139) (xy 295.775039 -273.747027) (xy 295.820851 -273.77037)
			(xy 295.862447 -273.800591) (xy 295.898803 -273.836947) (xy 295.929024 -273.878543) (xy 295.952367 -273.924355)
			(xy 295.968255 -273.973254) (xy 295.976298 -274.024036) (xy 295.976802 -274.049744) (xy 296.29406 -274.049744)
			(xy 296.29802 -274.00069) (xy 296.309797 -273.952906) (xy 296.329088 -273.90763) (xy 296.355391 -273.866034)
			(xy 296.388026 -273.829197) (xy 296.426147 -273.798072) (xy 296.468768 -273.773465) (xy 296.514784 -273.756013)
			(xy 296.563003 -273.746169) (xy 296.612178 -273.744188) (xy 296.661033 -273.75012) (xy 296.708304 -273.763812)
			(xy 296.752766 -273.78491) (xy 296.793269 -273.812866) (xy 296.828762 -273.846958) (xy 296.858327 -273.886302)
			(xy 296.881198 -273.929879) (xy 296.896782 -273.97656) (xy 296.904677 -274.025137) (xy 296.905172 -274.049744)
			(xy 296.904677 -274.074351) (xy 296.904498 -274.075452) (xy 297.222922 -274.075452) (xy 297.222922 -274.024036)
			(xy 297.230965 -273.973254) (xy 297.246853 -273.924355) (xy 297.270196 -273.878543) (xy 297.300417 -273.836947)
			(xy 297.336773 -273.800591) (xy 297.378369 -273.77037) (xy 297.424181 -273.747027) (xy 297.47308 -273.731139)
			(xy 297.523862 -273.723096) (xy 297.575278 -273.723096) (xy 297.62606 -273.731139) (xy 297.674959 -273.747027)
			(xy 297.720771 -273.77037) (xy 297.762367 -273.800591) (xy 297.798723 -273.836947) (xy 297.828944 -273.878543)
			(xy 297.852287 -273.924355) (xy 297.868175 -273.973254) (xy 297.876218 -274.024036) (xy 297.876722 -274.049744)
			(xy 298.19398 -274.049744) (xy 298.19794 -274.00069) (xy 298.209717 -273.952906) (xy 298.229008 -273.90763)
			(xy 298.255311 -273.866034) (xy 298.287946 -273.829197) (xy 298.326067 -273.798072) (xy 298.368688 -273.773465)
			(xy 298.414704 -273.756013) (xy 298.462923 -273.746169) (xy 298.512098 -273.744188) (xy 298.560953 -273.75012)
			(xy 298.608224 -273.763812) (xy 298.652686 -273.78491) (xy 298.693189 -273.812866) (xy 298.728682 -273.846958)
			(xy 298.758247 -273.886302) (xy 298.781118 -273.929879) (xy 298.796702 -273.97656) (xy 298.804597 -274.025137)
			(xy 298.805092 -274.049744) (xy 298.804597 -274.074351) (xy 298.804418 -274.075452) (xy 299.122842 -274.075452)
			(xy 299.122842 -274.024036) (xy 299.130885 -273.973254) (xy 299.146773 -273.924355) (xy 299.170116 -273.878543)
			(xy 299.200337 -273.836947) (xy 299.236693 -273.800591) (xy 299.278289 -273.77037) (xy 299.324101 -273.747027)
			(xy 299.373 -273.731139) (xy 299.423782 -273.723096) (xy 299.475198 -273.723096) (xy 299.52598 -273.731139)
			(xy 299.574879 -273.747027) (xy 299.620691 -273.77037) (xy 299.662287 -273.800591) (xy 299.698643 -273.836947)
			(xy 299.728864 -273.878543) (xy 299.752207 -273.924355) (xy 299.768095 -273.973254) (xy 299.776138 -274.024036)
			(xy 299.776642 -274.049744) (xy 300.0939 -274.049744) (xy 300.09786 -274.00069) (xy 300.109637 -273.952906)
			(xy 300.128928 -273.90763) (xy 300.155231 -273.866034) (xy 300.187866 -273.829197) (xy 300.225987 -273.798072)
			(xy 300.268608 -273.773465) (xy 300.314624 -273.756013) (xy 300.362843 -273.746169) (xy 300.412018 -273.744188)
			(xy 300.460873 -273.75012) (xy 300.508144 -273.763812) (xy 300.552606 -273.78491) (xy 300.593109 -273.812866)
			(xy 300.628602 -273.846958) (xy 300.658167 -273.886302) (xy 300.681038 -273.929879) (xy 300.696622 -273.97656)
			(xy 300.704517 -274.025137) (xy 300.705012 -274.049744) (xy 300.704517 -274.074351) (xy 300.704338 -274.075452)
			(xy 301.023016 -274.075452) (xy 301.023016 -274.024036) (xy 301.031059 -273.973254) (xy 301.046947 -273.924355)
			(xy 301.07029 -273.878543) (xy 301.100511 -273.836947) (xy 301.136867 -273.800591) (xy 301.178463 -273.77037)
			(xy 301.224275 -273.747027) (xy 301.273174 -273.731139) (xy 301.323956 -273.723096) (xy 301.375372 -273.723096)
			(xy 301.426154 -273.731139) (xy 301.475053 -273.747027) (xy 301.520865 -273.77037) (xy 301.562461 -273.800591)
			(xy 301.598817 -273.836947) (xy 301.629038 -273.878543) (xy 301.652381 -273.924355) (xy 301.668269 -273.973254)
			(xy 301.676312 -274.024036) (xy 301.676816 -274.049744) (xy 301.994074 -274.049744) (xy 301.998034 -274.00069)
			(xy 302.009811 -273.952906) (xy 302.029102 -273.90763) (xy 302.055405 -273.866034) (xy 302.08804 -273.829197)
			(xy 302.126161 -273.798072) (xy 302.168782 -273.773465) (xy 302.214798 -273.756013) (xy 302.263017 -273.746169)
			(xy 302.312192 -273.744188) (xy 302.361047 -273.75012) (xy 302.408318 -273.763812) (xy 302.45278 -273.78491)
			(xy 302.493283 -273.812866) (xy 302.528776 -273.846958) (xy 302.558341 -273.886302) (xy 302.581212 -273.929879)
			(xy 302.596796 -273.97656) (xy 302.604691 -274.025137) (xy 302.605186 -274.049744) (xy 302.604691 -274.074351)
			(xy 302.604512 -274.075452) (xy 302.922936 -274.075452) (xy 302.922936 -274.024036) (xy 302.930979 -273.973254)
			(xy 302.946867 -273.924355) (xy 302.97021 -273.878543) (xy 303.000431 -273.836947) (xy 303.036787 -273.800591)
			(xy 303.078383 -273.77037) (xy 303.124195 -273.747027) (xy 303.173094 -273.731139) (xy 303.223876 -273.723096)
			(xy 303.275292 -273.723096) (xy 303.326074 -273.731139) (xy 303.374973 -273.747027) (xy 303.420785 -273.77037)
			(xy 303.462381 -273.800591) (xy 303.498737 -273.836947) (xy 303.528958 -273.878543) (xy 303.552301 -273.924355)
			(xy 303.568189 -273.973254) (xy 303.576232 -274.024036) (xy 303.576736 -274.049744) (xy 303.893994 -274.049744)
			(xy 303.897954 -274.00069) (xy 303.909731 -273.952906) (xy 303.929022 -273.90763) (xy 303.955325 -273.866034)
			(xy 303.98796 -273.829197) (xy 304.026081 -273.798072) (xy 304.068702 -273.773465) (xy 304.114718 -273.756013)
			(xy 304.162937 -273.746169) (xy 304.212112 -273.744188) (xy 304.260967 -273.75012) (xy 304.308238 -273.763812)
			(xy 304.3527 -273.78491) (xy 304.393203 -273.812866) (xy 304.428696 -273.846958) (xy 304.458261 -273.886302)
			(xy 304.481132 -273.929879) (xy 304.496716 -273.97656) (xy 304.504611 -274.025137) (xy 304.505106 -274.049744)
			(xy 304.504611 -274.074351) (xy 304.504432 -274.075452) (xy 304.822856 -274.075452) (xy 304.822856 -274.024036)
			(xy 304.830899 -273.973254) (xy 304.846787 -273.924355) (xy 304.87013 -273.878543) (xy 304.900351 -273.836947)
			(xy 304.936707 -273.800591) (xy 304.978303 -273.77037) (xy 305.024115 -273.747027) (xy 305.073014 -273.731139)
			(xy 305.123796 -273.723096) (xy 305.175212 -273.723096) (xy 305.225994 -273.731139) (xy 305.274893 -273.747027)
			(xy 305.320705 -273.77037) (xy 305.362301 -273.800591) (xy 305.398657 -273.836947) (xy 305.428878 -273.878543)
			(xy 305.452221 -273.924355) (xy 305.468109 -273.973254) (xy 305.476152 -274.024036) (xy 305.476656 -274.049744)
			(xy 305.793914 -274.049744) (xy 305.797874 -274.00069) (xy 305.809651 -273.952906) (xy 305.828942 -273.90763)
			(xy 305.855245 -273.866034) (xy 305.88788 -273.829197) (xy 305.926001 -273.798072) (xy 305.968622 -273.773465)
			(xy 306.014638 -273.756013) (xy 306.062857 -273.746169) (xy 306.112032 -273.744188) (xy 306.160887 -273.75012)
			(xy 306.208158 -273.763812) (xy 306.25262 -273.78491) (xy 306.293123 -273.812866) (xy 306.328616 -273.846958)
			(xy 306.358181 -273.886302) (xy 306.381052 -273.929879) (xy 306.396636 -273.97656) (xy 306.404531 -274.025137)
			(xy 306.405026 -274.049744) (xy 306.404531 -274.074351) (xy 306.404352 -274.075452) (xy 306.72303 -274.075452)
			(xy 306.72303 -274.024036) (xy 306.731073 -273.973254) (xy 306.746961 -273.924355) (xy 306.770304 -273.878543)
			(xy 306.800525 -273.836947) (xy 306.836881 -273.800591) (xy 306.878477 -273.77037) (xy 306.924289 -273.747027)
			(xy 306.973188 -273.731139) (xy 307.02397 -273.723096) (xy 307.075386 -273.723096) (xy 307.126168 -273.731139)
			(xy 307.175067 -273.747027) (xy 307.220879 -273.77037) (xy 307.262475 -273.800591) (xy 307.298831 -273.836947)
			(xy 307.329052 -273.878543) (xy 307.352395 -273.924355) (xy 307.368283 -273.973254) (xy 307.376326 -274.024036)
			(xy 307.37683 -274.049744) (xy 307.694342 -274.049744) (xy 307.698302 -274.00069) (xy 307.710079 -273.952906)
			(xy 307.72937 -273.90763) (xy 307.755673 -273.866034) (xy 307.788308 -273.829197) (xy 307.826429 -273.798072)
			(xy 307.86905 -273.773465) (xy 307.915066 -273.756013) (xy 307.963285 -273.746169) (xy 308.01246 -273.744188)
			(xy 308.061315 -273.75012) (xy 308.108586 -273.763812) (xy 308.153048 -273.78491) (xy 308.193551 -273.812866)
			(xy 308.229044 -273.846958) (xy 308.258609 -273.886302) (xy 308.28148 -273.929879) (xy 308.297064 -273.97656)
			(xy 308.304959 -274.025137) (xy 308.305454 -274.049744) (xy 308.304959 -274.074351) (xy 308.30478 -274.075452)
			(xy 308.62295 -274.075452) (xy 308.62295 -274.024036) (xy 308.630993 -273.973254) (xy 308.646881 -273.924355)
			(xy 308.670224 -273.878543) (xy 308.700445 -273.836947) (xy 308.736801 -273.800591) (xy 308.778397 -273.77037)
			(xy 308.824209 -273.747027) (xy 308.873108 -273.731139) (xy 308.92389 -273.723096) (xy 308.975306 -273.723096)
			(xy 309.026088 -273.731139) (xy 309.074987 -273.747027) (xy 309.120799 -273.77037) (xy 309.162395 -273.800591)
			(xy 309.198751 -273.836947) (xy 309.228972 -273.878543) (xy 309.252315 -273.924355) (xy 309.268203 -273.973254)
			(xy 309.276246 -274.024036) (xy 309.27675 -274.049744) (xy 309.594262 -274.049744) (xy 309.598222 -274.00069)
			(xy 309.609999 -273.952906) (xy 309.62929 -273.90763) (xy 309.655593 -273.866034) (xy 309.688228 -273.829197)
			(xy 309.726349 -273.798072) (xy 309.76897 -273.773465) (xy 309.814986 -273.756013) (xy 309.863205 -273.746169)
			(xy 309.91238 -273.744188) (xy 309.961235 -273.75012) (xy 310.008506 -273.763812) (xy 310.052968 -273.78491)
			(xy 310.093471 -273.812866) (xy 310.128964 -273.846958) (xy 310.158529 -273.886302) (xy 310.1814 -273.929879)
			(xy 310.196984 -273.97656) (xy 310.204879 -274.025137) (xy 310.205374 -274.049744) (xy 310.204879 -274.074351)
			(xy 310.2047 -274.075452) (xy 310.52287 -274.075452) (xy 310.52287 -274.024036) (xy 310.530913 -273.973254)
			(xy 310.546801 -273.924355) (xy 310.570144 -273.878543) (xy 310.600365 -273.836947) (xy 310.636721 -273.800591)
			(xy 310.678317 -273.77037) (xy 310.724129 -273.747027) (xy 310.773028 -273.731139) (xy 310.82381 -273.723096)
			(xy 310.875226 -273.723096) (xy 310.926008 -273.731139) (xy 310.974907 -273.747027) (xy 311.020719 -273.77037)
			(xy 311.062315 -273.800591) (xy 311.098671 -273.836947) (xy 311.128892 -273.878543) (xy 311.152235 -273.924355)
			(xy 311.168123 -273.973254) (xy 311.176166 -274.024036) (xy 311.17667 -274.049744) (xy 311.494182 -274.049744)
			(xy 311.498142 -274.00069) (xy 311.509919 -273.952906) (xy 311.52921 -273.90763) (xy 311.555513 -273.866034)
			(xy 311.588148 -273.829197) (xy 311.626269 -273.798072) (xy 311.66889 -273.773465) (xy 311.714906 -273.756013)
			(xy 311.763125 -273.746169) (xy 311.8123 -273.744188) (xy 311.861155 -273.75012) (xy 311.908426 -273.763812)
			(xy 311.952888 -273.78491) (xy 311.993391 -273.812866) (xy 312.028884 -273.846958) (xy 312.058449 -273.886302)
			(xy 312.08132 -273.929879) (xy 312.096904 -273.97656) (xy 312.104799 -274.025137) (xy 312.105294 -274.049744)
			(xy 312.104799 -274.074351) (xy 312.10462 -274.075452) (xy 312.42279 -274.075452) (xy 312.42279 -274.024036)
			(xy 312.430833 -273.973254) (xy 312.446721 -273.924355) (xy 312.470064 -273.878543) (xy 312.500285 -273.836947)
			(xy 312.536641 -273.800591) (xy 312.578237 -273.77037) (xy 312.624049 -273.747027) (xy 312.672948 -273.731139)
			(xy 312.72373 -273.723096) (xy 312.775146 -273.723096) (xy 312.825928 -273.731139) (xy 312.874827 -273.747027)
			(xy 312.920639 -273.77037) (xy 312.962235 -273.800591) (xy 312.998591 -273.836947) (xy 313.028812 -273.878543)
			(xy 313.052155 -273.924355) (xy 313.068043 -273.973254) (xy 313.076086 -274.024036) (xy 313.07659 -274.049744)
			(xy 313.394102 -274.049744) (xy 313.398062 -274.00069) (xy 313.409839 -273.952906) (xy 313.42913 -273.90763)
			(xy 313.455433 -273.866034) (xy 313.488068 -273.829197) (xy 313.526189 -273.798072) (xy 313.56881 -273.773465)
			(xy 313.614826 -273.756013) (xy 313.663045 -273.746169) (xy 313.71222 -273.744188) (xy 313.761075 -273.75012)
			(xy 313.808346 -273.763812) (xy 313.852808 -273.78491) (xy 313.893311 -273.812866) (xy 313.928804 -273.846958)
			(xy 313.958369 -273.886302) (xy 313.98124 -273.929879) (xy 313.996824 -273.97656) (xy 314.004719 -274.025137)
			(xy 314.005214 -274.049744) (xy 314.344062 -274.049744) (xy 314.348022 -274.00069) (xy 314.359799 -273.952906)
			(xy 314.37909 -273.90763) (xy 314.405393 -273.866034) (xy 314.438028 -273.829197) (xy 314.476149 -273.798072)
			(xy 314.51877 -273.773465) (xy 314.564786 -273.756013) (xy 314.613005 -273.746169) (xy 314.66218 -273.744188)
			(xy 314.711035 -273.75012) (xy 314.758306 -273.763812) (xy 314.802768 -273.78491) (xy 314.843271 -273.812866)
			(xy 314.878764 -273.846958) (xy 314.908329 -273.886302) (xy 314.9312 -273.929879) (xy 314.946784 -273.97656)
			(xy 314.954679 -274.025137) (xy 314.955174 -274.049744) (xy 314.954679 -274.074351) (xy 314.946784 -274.122928)
			(xy 314.9312 -274.169609) (xy 314.908329 -274.213186) (xy 314.878764 -274.25253) (xy 314.843271 -274.286622)
			(xy 314.802768 -274.314578) (xy 314.758306 -274.335676) (xy 314.711035 -274.349368) (xy 314.66218 -274.3553)
			(xy 314.613005 -274.353319) (xy 314.564786 -274.343475) (xy 314.51877 -274.326023) (xy 314.476149 -274.301416)
			(xy 314.438028 -274.270291) (xy 314.405393 -274.233454) (xy 314.37909 -274.191858) (xy 314.359799 -274.146582)
			(xy 314.348022 -274.098798) (xy 314.344062 -274.049744) (xy 314.005214 -274.049744) (xy 314.004719 -274.074351)
			(xy 313.996824 -274.122928) (xy 313.98124 -274.169609) (xy 313.958369 -274.213186) (xy 313.928804 -274.25253)
			(xy 313.893311 -274.286622) (xy 313.852808 -274.314578) (xy 313.808346 -274.335676) (xy 313.761075 -274.349368)
			(xy 313.71222 -274.3553) (xy 313.663045 -274.353319) (xy 313.614826 -274.343475) (xy 313.56881 -274.326023)
			(xy 313.526189 -274.301416) (xy 313.488068 -274.270291) (xy 313.455433 -274.233454) (xy 313.42913 -274.191858)
			(xy 313.409839 -274.146582) (xy 313.398062 -274.098798) (xy 313.394102 -274.049744) (xy 313.07659 -274.049744)
			(xy 313.076086 -274.075452) (xy 313.068043 -274.126234) (xy 313.052155 -274.175133) (xy 313.028812 -274.220945)
			(xy 312.998591 -274.262541) (xy 312.962235 -274.298897) (xy 312.920639 -274.329118) (xy 312.874827 -274.352461)
			(xy 312.825928 -274.368349) (xy 312.775146 -274.376392) (xy 312.72373 -274.376392) (xy 312.672948 -274.368349)
			(xy 312.624049 -274.352461) (xy 312.578237 -274.329118) (xy 312.536641 -274.298897) (xy 312.500285 -274.262541)
			(xy 312.470064 -274.220945) (xy 312.446721 -274.175133) (xy 312.430833 -274.126234) (xy 312.42279 -274.075452)
			(xy 312.10462 -274.075452) (xy 312.096904 -274.122928) (xy 312.08132 -274.169609) (xy 312.058449 -274.213186)
			(xy 312.028884 -274.25253) (xy 311.993391 -274.286622) (xy 311.952888 -274.314578) (xy 311.908426 -274.335676)
			(xy 311.861155 -274.349368) (xy 311.8123 -274.3553) (xy 311.763125 -274.353319) (xy 311.714906 -274.343475)
			(xy 311.66889 -274.326023) (xy 311.626269 -274.301416) (xy 311.588148 -274.270291) (xy 311.555513 -274.233454)
			(xy 311.52921 -274.191858) (xy 311.509919 -274.146582) (xy 311.498142 -274.098798) (xy 311.494182 -274.049744)
			(xy 311.17667 -274.049744) (xy 311.176166 -274.075452) (xy 311.168123 -274.126234) (xy 311.152235 -274.175133)
			(xy 311.128892 -274.220945) (xy 311.098671 -274.262541) (xy 311.062315 -274.298897) (xy 311.020719 -274.329118)
			(xy 310.974907 -274.352461) (xy 310.926008 -274.368349) (xy 310.875226 -274.376392) (xy 310.82381 -274.376392)
			(xy 310.773028 -274.368349) (xy 310.724129 -274.352461) (xy 310.678317 -274.329118) (xy 310.636721 -274.298897)
			(xy 310.600365 -274.262541) (xy 310.570144 -274.220945) (xy 310.546801 -274.175133) (xy 310.530913 -274.126234)
			(xy 310.52287 -274.075452) (xy 310.2047 -274.075452) (xy 310.196984 -274.122928) (xy 310.1814 -274.169609)
			(xy 310.158529 -274.213186) (xy 310.128964 -274.25253) (xy 310.093471 -274.286622) (xy 310.052968 -274.314578)
			(xy 310.008506 -274.335676) (xy 309.961235 -274.349368) (xy 309.91238 -274.3553) (xy 309.863205 -274.353319)
			(xy 309.814986 -274.343475) (xy 309.76897 -274.326023) (xy 309.726349 -274.301416) (xy 309.688228 -274.270291)
			(xy 309.655593 -274.233454) (xy 309.62929 -274.191858) (xy 309.609999 -274.146582) (xy 309.598222 -274.098798)
			(xy 309.594262 -274.049744) (xy 309.27675 -274.049744) (xy 309.276246 -274.075452) (xy 309.268203 -274.126234)
			(xy 309.252315 -274.175133) (xy 309.228972 -274.220945) (xy 309.198751 -274.262541) (xy 309.162395 -274.298897)
			(xy 309.120799 -274.329118) (xy 309.074987 -274.352461) (xy 309.026088 -274.368349) (xy 308.975306 -274.376392)
			(xy 308.92389 -274.376392) (xy 308.873108 -274.368349) (xy 308.824209 -274.352461) (xy 308.778397 -274.329118)
			(xy 308.736801 -274.298897) (xy 308.700445 -274.262541) (xy 308.670224 -274.220945) (xy 308.646881 -274.175133)
			(xy 308.630993 -274.126234) (xy 308.62295 -274.075452) (xy 308.30478 -274.075452) (xy 308.297064 -274.122928)
			(xy 308.28148 -274.169609) (xy 308.258609 -274.213186) (xy 308.229044 -274.25253) (xy 308.193551 -274.286622)
			(xy 308.153048 -274.314578) (xy 308.108586 -274.335676) (xy 308.061315 -274.349368) (xy 308.01246 -274.3553)
			(xy 307.963285 -274.353319) (xy 307.915066 -274.343475) (xy 307.86905 -274.326023) (xy 307.826429 -274.301416)
			(xy 307.788308 -274.270291) (xy 307.755673 -274.233454) (xy 307.72937 -274.191858) (xy 307.710079 -274.146582)
			(xy 307.698302 -274.098798) (xy 307.694342 -274.049744) (xy 307.37683 -274.049744) (xy 307.376326 -274.075452)
			(xy 307.368283 -274.126234) (xy 307.352395 -274.175133) (xy 307.329052 -274.220945) (xy 307.298831 -274.262541)
			(xy 307.262475 -274.298897) (xy 307.220879 -274.329118) (xy 307.175067 -274.352461) (xy 307.126168 -274.368349)
			(xy 307.075386 -274.376392) (xy 307.02397 -274.376392) (xy 306.973188 -274.368349) (xy 306.924289 -274.352461)
			(xy 306.878477 -274.329118) (xy 306.836881 -274.298897) (xy 306.800525 -274.262541) (xy 306.770304 -274.220945)
			(xy 306.746961 -274.175133) (xy 306.731073 -274.126234) (xy 306.72303 -274.075452) (xy 306.404352 -274.075452)
			(xy 306.396636 -274.122928) (xy 306.381052 -274.169609) (xy 306.358181 -274.213186) (xy 306.328616 -274.25253)
			(xy 306.293123 -274.286622) (xy 306.25262 -274.314578) (xy 306.208158 -274.335676) (xy 306.160887 -274.349368)
			(xy 306.112032 -274.3553) (xy 306.062857 -274.353319) (xy 306.014638 -274.343475) (xy 305.968622 -274.326023)
			(xy 305.926001 -274.301416) (xy 305.88788 -274.270291) (xy 305.855245 -274.233454) (xy 305.828942 -274.191858)
			(xy 305.809651 -274.146582) (xy 305.797874 -274.098798) (xy 305.793914 -274.049744) (xy 305.476656 -274.049744)
			(xy 305.476152 -274.075452) (xy 305.468109 -274.126234) (xy 305.452221 -274.175133) (xy 305.428878 -274.220945)
			(xy 305.398657 -274.262541) (xy 305.362301 -274.298897) (xy 305.320705 -274.329118) (xy 305.274893 -274.352461)
			(xy 305.225994 -274.368349) (xy 305.175212 -274.376392) (xy 305.123796 -274.376392) (xy 305.073014 -274.368349)
			(xy 305.024115 -274.352461) (xy 304.978303 -274.329118) (xy 304.936707 -274.298897) (xy 304.900351 -274.262541)
			(xy 304.87013 -274.220945) (xy 304.846787 -274.175133) (xy 304.830899 -274.126234) (xy 304.822856 -274.075452)
			(xy 304.504432 -274.075452) (xy 304.496716 -274.122928) (xy 304.481132 -274.169609) (xy 304.458261 -274.213186)
			(xy 304.428696 -274.25253) (xy 304.393203 -274.286622) (xy 304.3527 -274.314578) (xy 304.308238 -274.335676)
			(xy 304.260967 -274.349368) (xy 304.212112 -274.3553) (xy 304.162937 -274.353319) (xy 304.114718 -274.343475)
			(xy 304.068702 -274.326023) (xy 304.026081 -274.301416) (xy 303.98796 -274.270291) (xy 303.955325 -274.233454)
			(xy 303.929022 -274.191858) (xy 303.909731 -274.146582) (xy 303.897954 -274.098798) (xy 303.893994 -274.049744)
			(xy 303.576736 -274.049744) (xy 303.576232 -274.075452) (xy 303.568189 -274.126234) (xy 303.552301 -274.175133)
			(xy 303.528958 -274.220945) (xy 303.498737 -274.262541) (xy 303.462381 -274.298897) (xy 303.420785 -274.329118)
			(xy 303.374973 -274.352461) (xy 303.326074 -274.368349) (xy 303.275292 -274.376392) (xy 303.223876 -274.376392)
			(xy 303.173094 -274.368349) (xy 303.124195 -274.352461) (xy 303.078383 -274.329118) (xy 303.036787 -274.298897)
			(xy 303.000431 -274.262541) (xy 302.97021 -274.220945) (xy 302.946867 -274.175133) (xy 302.930979 -274.126234)
			(xy 302.922936 -274.075452) (xy 302.604512 -274.075452) (xy 302.596796 -274.122928) (xy 302.581212 -274.169609)
			(xy 302.558341 -274.213186) (xy 302.528776 -274.25253) (xy 302.493283 -274.286622) (xy 302.45278 -274.314578)
			(xy 302.408318 -274.335676) (xy 302.361047 -274.349368) (xy 302.312192 -274.3553) (xy 302.263017 -274.353319)
			(xy 302.214798 -274.343475) (xy 302.168782 -274.326023) (xy 302.126161 -274.301416) (xy 302.08804 -274.270291)
			(xy 302.055405 -274.233454) (xy 302.029102 -274.191858) (xy 302.009811 -274.146582) (xy 301.998034 -274.098798)
			(xy 301.994074 -274.049744) (xy 301.676816 -274.049744) (xy 301.676312 -274.075452) (xy 301.668269 -274.126234)
			(xy 301.652381 -274.175133) (xy 301.629038 -274.220945) (xy 301.598817 -274.262541) (xy 301.562461 -274.298897)
			(xy 301.520865 -274.329118) (xy 301.475053 -274.352461) (xy 301.426154 -274.368349) (xy 301.375372 -274.376392)
			(xy 301.323956 -274.376392) (xy 301.273174 -274.368349) (xy 301.224275 -274.352461) (xy 301.178463 -274.329118)
			(xy 301.136867 -274.298897) (xy 301.100511 -274.262541) (xy 301.07029 -274.220945) (xy 301.046947 -274.175133)
			(xy 301.031059 -274.126234) (xy 301.023016 -274.075452) (xy 300.704338 -274.075452) (xy 300.696622 -274.122928)
			(xy 300.681038 -274.169609) (xy 300.658167 -274.213186) (xy 300.628602 -274.25253) (xy 300.593109 -274.286622)
			(xy 300.552606 -274.314578) (xy 300.508144 -274.335676) (xy 300.460873 -274.349368) (xy 300.412018 -274.3553)
			(xy 300.362843 -274.353319) (xy 300.314624 -274.343475) (xy 300.268608 -274.326023) (xy 300.225987 -274.301416)
			(xy 300.187866 -274.270291) (xy 300.155231 -274.233454) (xy 300.128928 -274.191858) (xy 300.109637 -274.146582)
			(xy 300.09786 -274.098798) (xy 300.0939 -274.049744) (xy 299.776642 -274.049744) (xy 299.776138 -274.075452)
			(xy 299.768095 -274.126234) (xy 299.752207 -274.175133) (xy 299.728864 -274.220945) (xy 299.698643 -274.262541)
			(xy 299.662287 -274.298897) (xy 299.620691 -274.329118) (xy 299.574879 -274.352461) (xy 299.52598 -274.368349)
			(xy 299.475198 -274.376392) (xy 299.423782 -274.376392) (xy 299.373 -274.368349) (xy 299.324101 -274.352461)
			(xy 299.278289 -274.329118) (xy 299.236693 -274.298897) (xy 299.200337 -274.262541) (xy 299.170116 -274.220945)
			(xy 299.146773 -274.175133) (xy 299.130885 -274.126234) (xy 299.122842 -274.075452) (xy 298.804418 -274.075452)
			(xy 298.796702 -274.122928) (xy 298.781118 -274.169609) (xy 298.758247 -274.213186) (xy 298.728682 -274.25253)
			(xy 298.693189 -274.286622) (xy 298.652686 -274.314578) (xy 298.608224 -274.335676) (xy 298.560953 -274.349368)
			(xy 298.512098 -274.3553) (xy 298.462923 -274.353319) (xy 298.414704 -274.343475) (xy 298.368688 -274.326023)
			(xy 298.326067 -274.301416) (xy 298.287946 -274.270291) (xy 298.255311 -274.233454) (xy 298.229008 -274.191858)
			(xy 298.209717 -274.146582) (xy 298.19794 -274.098798) (xy 298.19398 -274.049744) (xy 297.876722 -274.049744)
			(xy 297.876218 -274.075452) (xy 297.868175 -274.126234) (xy 297.852287 -274.175133) (xy 297.828944 -274.220945)
			(xy 297.798723 -274.262541) (xy 297.762367 -274.298897) (xy 297.720771 -274.329118) (xy 297.674959 -274.352461)
			(xy 297.62606 -274.368349) (xy 297.575278 -274.376392) (xy 297.523862 -274.376392) (xy 297.47308 -274.368349)
			(xy 297.424181 -274.352461) (xy 297.378369 -274.329118) (xy 297.336773 -274.298897) (xy 297.300417 -274.262541)
			(xy 297.270196 -274.220945) (xy 297.246853 -274.175133) (xy 297.230965 -274.126234) (xy 297.222922 -274.075452)
			(xy 296.904498 -274.075452) (xy 296.896782 -274.122928) (xy 296.881198 -274.169609) (xy 296.858327 -274.213186)
			(xy 296.828762 -274.25253) (xy 296.793269 -274.286622) (xy 296.752766 -274.314578) (xy 296.708304 -274.335676)
			(xy 296.661033 -274.349368) (xy 296.612178 -274.3553) (xy 296.563003 -274.353319) (xy 296.514784 -274.343475)
			(xy 296.468768 -274.326023) (xy 296.426147 -274.301416) (xy 296.388026 -274.270291) (xy 296.355391 -274.233454)
			(xy 296.329088 -274.191858) (xy 296.309797 -274.146582) (xy 296.29802 -274.098798) (xy 296.29406 -274.049744)
			(xy 295.976802 -274.049744) (xy 295.976298 -274.075452) (xy 295.968255 -274.126234) (xy 295.952367 -274.175133)
			(xy 295.929024 -274.220945) (xy 295.898803 -274.262541) (xy 295.862447 -274.298897) (xy 295.820851 -274.329118)
			(xy 295.775039 -274.352461) (xy 295.72614 -274.368349) (xy 295.675358 -274.376392) (xy 295.623942 -274.376392)
			(xy 295.57316 -274.368349) (xy 295.524261 -274.352461) (xy 295.478449 -274.329118) (xy 295.436853 -274.298897)
			(xy 295.400497 -274.262541) (xy 295.370276 -274.220945) (xy 295.346933 -274.175133) (xy 295.331045 -274.126234)
			(xy 295.323002 -274.075452) (xy 295.004324 -274.075452) (xy 294.996608 -274.122928) (xy 294.981024 -274.169609)
			(xy 294.958153 -274.213186) (xy 294.928588 -274.25253) (xy 294.893095 -274.286622) (xy 294.852592 -274.314578)
			(xy 294.80813 -274.335676) (xy 294.760859 -274.349368) (xy 294.712004 -274.3553) (xy 294.662829 -274.353319)
			(xy 294.61461 -274.343475) (xy 294.568594 -274.326023) (xy 294.525973 -274.301416) (xy 294.487852 -274.270291)
			(xy 294.455217 -274.233454) (xy 294.428914 -274.191858) (xy 294.409623 -274.146582) (xy 294.397846 -274.098798)
			(xy 294.393886 -274.049744) (xy 294.076628 -274.049744) (xy 294.076124 -274.075452) (xy 294.068081 -274.126234)
			(xy 294.052193 -274.175133) (xy 294.02885 -274.220945) (xy 293.998629 -274.262541) (xy 293.962273 -274.298897)
			(xy 293.920677 -274.329118) (xy 293.874865 -274.352461) (xy 293.825966 -274.368349) (xy 293.775184 -274.376392)
			(xy 293.723768 -274.376392) (xy 293.672986 -274.368349) (xy 293.624087 -274.352461) (xy 293.578275 -274.329118)
			(xy 293.536679 -274.298897) (xy 293.500323 -274.262541) (xy 293.470102 -274.220945) (xy 293.446759 -274.175133)
			(xy 293.430871 -274.126234) (xy 293.422828 -274.075452) (xy 293.104404 -274.075452) (xy 293.096688 -274.122928)
			(xy 293.081104 -274.169609) (xy 293.058233 -274.213186) (xy 293.028668 -274.25253) (xy 292.993175 -274.286622)
			(xy 292.952672 -274.314578) (xy 292.90821 -274.335676) (xy 292.860939 -274.349368) (xy 292.812084 -274.3553)
			(xy 292.762909 -274.353319) (xy 292.71469 -274.343475) (xy 292.668674 -274.326023) (xy 292.626053 -274.301416)
			(xy 292.587932 -274.270291) (xy 292.555297 -274.233454) (xy 292.528994 -274.191858) (xy 292.509703 -274.146582)
			(xy 292.497926 -274.098798) (xy 292.493966 -274.049744) (xy 292.176703 -274.049744) (xy 292.176204 -274.075198)
			(xy 292.168161 -274.12598) (xy 292.152273 -274.174879) (xy 292.12893 -274.220691) (xy 292.098709 -274.262287)
			(xy 292.062353 -274.298643) (xy 292.020757 -274.328864) (xy 291.974945 -274.352207) (xy 291.926046 -274.368095)
			(xy 291.875264 -274.376138) (xy 291.823848 -274.376138) (xy 291.773066 -274.368095) (xy 291.724167 -274.352207)
			(xy 291.678355 -274.328864) (xy 291.636759 -274.298643) (xy 291.600403 -274.262287) (xy 291.570182 -274.220691)
			(xy 291.546839 -274.174879) (xy 291.530951 -274.12598) (xy 291.522908 -274.075198) (xy 291.204525 -274.075198)
			(xy 291.196768 -274.122928) (xy 291.181184 -274.169609) (xy 291.158313 -274.213186) (xy 291.128748 -274.25253)
			(xy 291.093255 -274.286622) (xy 291.052752 -274.314578) (xy 291.00829 -274.335676) (xy 290.961019 -274.349368)
			(xy 290.912164 -274.3553) (xy 290.862989 -274.353319) (xy 290.81477 -274.343475) (xy 290.768754 -274.326023)
			(xy 290.726133 -274.301416) (xy 290.688012 -274.270291) (xy 290.655377 -274.233454) (xy 290.629074 -274.191858)
			(xy 290.609783 -274.146582) (xy 290.598006 -274.098798) (xy 290.594046 -274.049744) (xy 290.277042 -274.049744)
			(xy 290.276538 -274.075452) (xy 290.268495 -274.126234) (xy 290.252607 -274.175133) (xy 290.229264 -274.220945)
			(xy 290.199043 -274.262541) (xy 290.162687 -274.298897) (xy 290.121091 -274.329118) (xy 290.075279 -274.352461)
			(xy 290.02638 -274.368349) (xy 289.975598 -274.376392) (xy 289.924182 -274.376392) (xy 289.8734 -274.368349)
			(xy 289.824501 -274.352461) (xy 289.778689 -274.329118) (xy 289.737093 -274.298897) (xy 289.700737 -274.262541)
			(xy 289.670516 -274.220945) (xy 289.647173 -274.175133) (xy 289.631285 -274.126234) (xy 289.623242 -274.075452)
			(xy 289.304564 -274.075452) (xy 289.296848 -274.122928) (xy 289.281264 -274.169609) (xy 289.258393 -274.213186)
			(xy 289.228828 -274.25253) (xy 289.193335 -274.286622) (xy 289.152832 -274.314578) (xy 289.10837 -274.335676)
			(xy 289.061099 -274.349368) (xy 289.012244 -274.3553) (xy 288.963069 -274.353319) (xy 288.91485 -274.343475)
			(xy 288.868834 -274.326023) (xy 288.826213 -274.301416) (xy 288.788092 -274.270291) (xy 288.755457 -274.233454)
			(xy 288.729154 -274.191858) (xy 288.709863 -274.146582) (xy 288.698086 -274.098798) (xy 288.694126 -274.049744)
			(xy 288.376868 -274.049744) (xy 288.376364 -274.075452) (xy 288.368321 -274.126234) (xy 288.352433 -274.175133)
			(xy 288.32909 -274.220945) (xy 288.298869 -274.262541) (xy 288.262513 -274.298897) (xy 288.220917 -274.329118)
			(xy 288.175105 -274.352461) (xy 288.126206 -274.368349) (xy 288.075424 -274.376392) (xy 288.024008 -274.376392)
			(xy 287.973226 -274.368349) (xy 287.924327 -274.352461) (xy 287.878515 -274.329118) (xy 287.836919 -274.298897)
			(xy 287.800563 -274.262541) (xy 287.770342 -274.220945) (xy 287.746999 -274.175133) (xy 287.731111 -274.126234)
			(xy 287.723068 -274.075452) (xy 287.40439 -274.075452) (xy 287.396674 -274.122928) (xy 287.38109 -274.169609)
			(xy 287.358219 -274.213186) (xy 287.328654 -274.25253) (xy 287.293161 -274.286622) (xy 287.252658 -274.314578)
			(xy 287.208196 -274.335676) (xy 287.160925 -274.349368) (xy 287.11207 -274.3553) (xy 287.062895 -274.353319)
			(xy 287.014676 -274.343475) (xy 286.96866 -274.326023) (xy 286.926039 -274.301416) (xy 286.887918 -274.270291)
			(xy 286.855283 -274.233454) (xy 286.82898 -274.191858) (xy 286.809689 -274.146582) (xy 286.797912 -274.098798)
			(xy 286.793952 -274.049744) (xy 286.476948 -274.049744) (xy 286.476444 -274.075452) (xy 286.468401 -274.126234)
			(xy 286.452513 -274.175133) (xy 286.42917 -274.220945) (xy 286.398949 -274.262541) (xy 286.362593 -274.298897)
			(xy 286.320997 -274.329118) (xy 286.275185 -274.352461) (xy 286.226286 -274.368349) (xy 286.175504 -274.376392)
			(xy 286.124088 -274.376392) (xy 286.073306 -274.368349) (xy 286.024407 -274.352461) (xy 285.978595 -274.329118)
			(xy 285.936999 -274.298897) (xy 285.900643 -274.262541) (xy 285.870422 -274.220945) (xy 285.847079 -274.175133)
			(xy 285.831191 -274.126234) (xy 285.823148 -274.075452) (xy 285.50447 -274.075452) (xy 285.496754 -274.122928)
			(xy 285.48117 -274.169609) (xy 285.458299 -274.213186) (xy 285.428734 -274.25253) (xy 285.393241 -274.286622)
			(xy 285.352738 -274.314578) (xy 285.308276 -274.335676) (xy 285.261005 -274.349368) (xy 285.21215 -274.3553)
			(xy 285.162975 -274.353319) (xy 285.114756 -274.343475) (xy 285.06874 -274.326023) (xy 285.026119 -274.301416)
			(xy 284.987998 -274.270291) (xy 284.955363 -274.233454) (xy 284.92906 -274.191858) (xy 284.909769 -274.146582)
			(xy 284.897992 -274.098798) (xy 284.894032 -274.049744) (xy 284.577028 -274.049744) (xy 284.576524 -274.075452)
			(xy 284.568481 -274.126234) (xy 284.552593 -274.175133) (xy 284.52925 -274.220945) (xy 284.499029 -274.262541)
			(xy 284.462673 -274.298897) (xy 284.421077 -274.329118) (xy 284.375265 -274.352461) (xy 284.326366 -274.368349)
			(xy 284.275584 -274.376392) (xy 284.224168 -274.376392) (xy 284.173386 -274.368349) (xy 284.124487 -274.352461)
			(xy 284.078675 -274.329118) (xy 284.037079 -274.298897) (xy 284.000723 -274.262541) (xy 283.970502 -274.220945)
			(xy 283.947159 -274.175133) (xy 283.931271 -274.126234) (xy 283.923228 -274.075452) (xy 283.60455 -274.075452)
			(xy 283.596834 -274.122928) (xy 283.58125 -274.169609) (xy 283.558379 -274.213186) (xy 283.528814 -274.25253)
			(xy 283.493321 -274.286622) (xy 283.452818 -274.314578) (xy 283.408356 -274.335676) (xy 283.361085 -274.349368)
			(xy 283.31223 -274.3553) (xy 283.263055 -274.353319) (xy 283.214836 -274.343475) (xy 283.16882 -274.326023)
			(xy 283.126199 -274.301416) (xy 283.088078 -274.270291) (xy 283.055443 -274.233454) (xy 283.02914 -274.191858)
			(xy 283.009849 -274.146582) (xy 282.998072 -274.098798) (xy 282.994112 -274.049744) (xy 282.676854 -274.049744)
			(xy 282.67635 -274.075452) (xy 282.668307 -274.126234) (xy 282.652419 -274.175133) (xy 282.629076 -274.220945)
			(xy 282.598855 -274.262541) (xy 282.562499 -274.298897) (xy 282.520903 -274.329118) (xy 282.475091 -274.352461)
			(xy 282.426192 -274.368349) (xy 282.37541 -274.376392) (xy 282.323994 -274.376392) (xy 282.273212 -274.368349)
			(xy 282.224313 -274.352461) (xy 282.178501 -274.329118) (xy 282.136905 -274.298897) (xy 282.100549 -274.262541)
			(xy 282.070328 -274.220945) (xy 282.046985 -274.175133) (xy 282.031097 -274.126234) (xy 282.023054 -274.075452)
			(xy 281.704376 -274.075452) (xy 281.69666 -274.122928) (xy 281.681076 -274.169609) (xy 281.658205 -274.213186)
			(xy 281.62864 -274.25253) (xy 281.593147 -274.286622) (xy 281.552644 -274.314578) (xy 281.508182 -274.335676)
			(xy 281.460911 -274.349368) (xy 281.412056 -274.3553) (xy 281.362881 -274.353319) (xy 281.314662 -274.343475)
			(xy 281.268646 -274.326023) (xy 281.226025 -274.301416) (xy 281.187904 -274.270291) (xy 281.155269 -274.233454)
			(xy 281.128966 -274.191858) (xy 281.109675 -274.146582) (xy 281.097898 -274.098798) (xy 281.093938 -274.049744)
			(xy 280.776934 -274.049744) (xy 280.77643 -274.075452) (xy 280.768387 -274.126234) (xy 280.752499 -274.175133)
			(xy 280.729156 -274.220945) (xy 280.698935 -274.262541) (xy 280.662579 -274.298897) (xy 280.620983 -274.329118)
			(xy 280.575171 -274.352461) (xy 280.526272 -274.368349) (xy 280.47549 -274.376392) (xy 280.424074 -274.376392)
			(xy 280.373292 -274.368349) (xy 280.324393 -274.352461) (xy 280.278581 -274.329118) (xy 280.236985 -274.298897)
			(xy 280.200629 -274.262541) (xy 280.170408 -274.220945) (xy 280.147065 -274.175133) (xy 280.131177 -274.126234)
			(xy 280.123134 -274.075452) (xy 279.804456 -274.075452) (xy 279.79674 -274.122928) (xy 279.781156 -274.169609)
			(xy 279.758285 -274.213186) (xy 279.72872 -274.25253) (xy 279.693227 -274.286622) (xy 279.652724 -274.314578)
			(xy 279.608262 -274.335676) (xy 279.560991 -274.349368) (xy 279.512136 -274.3553) (xy 279.462961 -274.353319)
			(xy 279.414742 -274.343475) (xy 279.368726 -274.326023) (xy 279.326105 -274.301416) (xy 279.287984 -274.270291)
			(xy 279.255349 -274.233454) (xy 279.229046 -274.191858) (xy 279.209755 -274.146582) (xy 279.197978 -274.098798)
			(xy 279.194018 -274.049744) (xy 278.877014 -274.049744) (xy 278.87651 -274.075452) (xy 278.868467 -274.126234)
			(xy 278.852579 -274.175133) (xy 278.829236 -274.220945) (xy 278.799015 -274.262541) (xy 278.762659 -274.298897)
			(xy 278.721063 -274.329118) (xy 278.675251 -274.352461) (xy 278.626352 -274.368349) (xy 278.57557 -274.376392)
			(xy 278.524154 -274.376392) (xy 278.473372 -274.368349) (xy 278.424473 -274.352461) (xy 278.378661 -274.329118)
			(xy 278.337065 -274.298897) (xy 278.300709 -274.262541) (xy 278.270488 -274.220945) (xy 278.247145 -274.175133)
			(xy 278.231257 -274.126234) (xy 278.223214 -274.075452) (xy 277.904536 -274.075452) (xy 277.89682 -274.122928)
			(xy 277.881236 -274.169609) (xy 277.858365 -274.213186) (xy 277.8288 -274.25253) (xy 277.793307 -274.286622)
			(xy 277.752804 -274.314578) (xy 277.708342 -274.335676) (xy 277.661071 -274.349368) (xy 277.612216 -274.3553)
			(xy 277.563041 -274.353319) (xy 277.514822 -274.343475) (xy 277.468806 -274.326023) (xy 277.426185 -274.301416)
			(xy 277.388064 -274.270291) (xy 277.355429 -274.233454) (xy 277.329126 -274.191858) (xy 277.309835 -274.146582)
			(xy 277.298058 -274.098798) (xy 277.294098 -274.049744) (xy 276.97684 -274.049744) (xy 276.976336 -274.075452)
			(xy 276.968293 -274.126234) (xy 276.952405 -274.175133) (xy 276.929062 -274.220945) (xy 276.898841 -274.262541)
			(xy 276.862485 -274.298897) (xy 276.820889 -274.329118) (xy 276.775077 -274.352461) (xy 276.726178 -274.368349)
			(xy 276.675396 -274.376392) (xy 276.62398 -274.376392) (xy 276.573198 -274.368349) (xy 276.524299 -274.352461)
			(xy 276.478487 -274.329118) (xy 276.436891 -274.298897) (xy 276.400535 -274.262541) (xy 276.370314 -274.220945)
			(xy 276.346971 -274.175133) (xy 276.331083 -274.126234) (xy 276.32304 -274.075452) (xy 265.382574 -274.075452)
			(xy 265.29449 -274.172075) (xy 265.157246 -274.310735) (xy 265.014425 -274.443643) (xy 264.919787 -274.524724)
			(xy 269.21893 -274.524724) (xy 269.22289 -274.47567) (xy 269.234667 -274.427886) (xy 269.253958 -274.38261)
			(xy 269.280261 -274.341014) (xy 269.312896 -274.304177) (xy 269.351017 -274.273052) (xy 269.393638 -274.248445)
			(xy 269.439654 -274.230993) (xy 269.487873 -274.221149) (xy 269.537048 -274.219168) (xy 269.585903 -274.2251)
			(xy 269.633174 -274.238792) (xy 269.677636 -274.25989) (xy 269.718139 -274.287846) (xy 269.753632 -274.321938)
			(xy 269.783197 -274.361282) (xy 269.806068 -274.404859) (xy 269.821652 -274.45154) (xy 269.829547 -274.500117)
			(xy 269.830042 -274.524724) (xy 269.830037 -274.524978) (xy 270.169144 -274.524978) (xy 270.173104 -274.475924)
			(xy 270.184881 -274.42814) (xy 270.204172 -274.382864) (xy 270.230475 -274.341268) (xy 270.26311 -274.304431)
			(xy 270.301231 -274.273306) (xy 270.343852 -274.248699) (xy 270.389868 -274.231247) (xy 270.438087 -274.221403)
			(xy 270.487262 -274.219422) (xy 270.536117 -274.225354) (xy 270.583388 -274.239046) (xy 270.62785 -274.260144)
			(xy 270.668353 -274.2881) (xy 270.703846 -274.322192) (xy 270.733411 -274.361536) (xy 270.756282 -274.405113)
			(xy 270.771866 -274.451794) (xy 270.779761 -274.500371) (xy 270.780256 -274.524978) (xy 271.119104 -274.524978)
			(xy 271.123064 -274.475924) (xy 271.134841 -274.42814) (xy 271.154132 -274.382864) (xy 271.180435 -274.341268)
			(xy 271.21307 -274.304431) (xy 271.251191 -274.273306) (xy 271.293812 -274.248699) (xy 271.339828 -274.231247)
			(xy 271.388047 -274.221403) (xy 271.437222 -274.219422) (xy 271.486077 -274.225354) (xy 271.533348 -274.239046)
			(xy 271.57781 -274.260144) (xy 271.618313 -274.2881) (xy 271.653806 -274.322192) (xy 271.683371 -274.361536)
			(xy 271.706242 -274.405113) (xy 271.721826 -274.451794) (xy 271.729721 -274.500371) (xy 271.730216 -274.524978)
			(xy 272.069064 -274.524978) (xy 272.073024 -274.475924) (xy 272.084801 -274.42814) (xy 272.104092 -274.382864)
			(xy 272.130395 -274.341268) (xy 272.16303 -274.304431) (xy 272.201151 -274.273306) (xy 272.243772 -274.248699)
			(xy 272.289788 -274.231247) (xy 272.338007 -274.221403) (xy 272.387182 -274.219422) (xy 272.436037 -274.225354)
			(xy 272.483308 -274.239046) (xy 272.52777 -274.260144) (xy 272.568273 -274.2881) (xy 272.603766 -274.322192)
			(xy 272.633331 -274.361536) (xy 272.656202 -274.405113) (xy 272.671786 -274.451794) (xy 272.679681 -274.500371)
			(xy 272.680176 -274.524978) (xy 273.019024 -274.524978) (xy 273.022984 -274.475924) (xy 273.034761 -274.42814)
			(xy 273.054052 -274.382864) (xy 273.080355 -274.341268) (xy 273.11299 -274.304431) (xy 273.151111 -274.273306)
			(xy 273.193732 -274.248699) (xy 273.239748 -274.231247) (xy 273.287967 -274.221403) (xy 273.337142 -274.219422)
			(xy 273.385997 -274.225354) (xy 273.433268 -274.239046) (xy 273.47773 -274.260144) (xy 273.518233 -274.2881)
			(xy 273.553726 -274.322192) (xy 273.583291 -274.361536) (xy 273.606162 -274.405113) (xy 273.621746 -274.451794)
			(xy 273.629641 -274.500371) (xy 273.630136 -274.524978) (xy 273.968984 -274.524978) (xy 273.972944 -274.475924)
			(xy 273.984721 -274.42814) (xy 274.004012 -274.382864) (xy 274.030315 -274.341268) (xy 274.06295 -274.304431)
			(xy 274.101071 -274.273306) (xy 274.143692 -274.248699) (xy 274.189708 -274.231247) (xy 274.237927 -274.221403)
			(xy 274.287102 -274.219422) (xy 274.335957 -274.225354) (xy 274.383228 -274.239046) (xy 274.42769 -274.260144)
			(xy 274.468193 -274.2881) (xy 274.503686 -274.322192) (xy 274.533251 -274.361536) (xy 274.556122 -274.405113)
			(xy 274.571706 -274.451794) (xy 274.579601 -274.500371) (xy 274.580096 -274.524978) (xy 274.918944 -274.524978)
			(xy 274.922904 -274.475924) (xy 274.934681 -274.42814) (xy 274.953972 -274.382864) (xy 274.980275 -274.341268)
			(xy 275.01291 -274.304431) (xy 275.051031 -274.273306) (xy 275.093652 -274.248699) (xy 275.139668 -274.231247)
			(xy 275.187887 -274.221403) (xy 275.237062 -274.219422) (xy 275.285917 -274.225354) (xy 275.333188 -274.239046)
			(xy 275.37765 -274.260144) (xy 275.418153 -274.2881) (xy 275.453646 -274.322192) (xy 275.483211 -274.361536)
			(xy 275.506082 -274.405113) (xy 275.521666 -274.451794) (xy 275.529561 -274.500371) (xy 275.530056 -274.524978)
			(xy 275.529561 -274.549585) (xy 275.521666 -274.598162) (xy 275.506082 -274.644843) (xy 275.483211 -274.68842)
			(xy 275.453646 -274.727764) (xy 275.418153 -274.761856) (xy 275.37765 -274.789812) (xy 275.333188 -274.81091)
			(xy 275.285917 -274.824602) (xy 275.237062 -274.830534) (xy 275.187887 -274.828553) (xy 275.139668 -274.818709)
			(xy 275.093652 -274.801257) (xy 275.051031 -274.77665) (xy 275.01291 -274.745525) (xy 274.980275 -274.708688)
			(xy 274.953972 -274.667092) (xy 274.934681 -274.621816) (xy 274.922904 -274.574032) (xy 274.918944 -274.524978)
			(xy 274.580096 -274.524978) (xy 274.579601 -274.549585) (xy 274.571706 -274.598162) (xy 274.556122 -274.644843)
			(xy 274.533251 -274.68842) (xy 274.503686 -274.727764) (xy 274.468193 -274.761856) (xy 274.42769 -274.789812)
			(xy 274.383228 -274.81091) (xy 274.335957 -274.824602) (xy 274.287102 -274.830534) (xy 274.237927 -274.828553)
			(xy 274.189708 -274.818709) (xy 274.143692 -274.801257) (xy 274.101071 -274.77665) (xy 274.06295 -274.745525)
			(xy 274.030315 -274.708688) (xy 274.004012 -274.667092) (xy 273.984721 -274.621816) (xy 273.972944 -274.574032)
			(xy 273.968984 -274.524978) (xy 273.630136 -274.524978) (xy 273.629641 -274.549585) (xy 273.621746 -274.598162)
			(xy 273.606162 -274.644843) (xy 273.583291 -274.68842) (xy 273.553726 -274.727764) (xy 273.518233 -274.761856)
			(xy 273.47773 -274.789812) (xy 273.433268 -274.81091) (xy 273.385997 -274.824602) (xy 273.337142 -274.830534)
			(xy 273.287967 -274.828553) (xy 273.239748 -274.818709) (xy 273.193732 -274.801257) (xy 273.151111 -274.77665)
			(xy 273.11299 -274.745525) (xy 273.080355 -274.708688) (xy 273.054052 -274.667092) (xy 273.034761 -274.621816)
			(xy 273.022984 -274.574032) (xy 273.019024 -274.524978) (xy 272.680176 -274.524978) (xy 272.679681 -274.549585)
			(xy 272.671786 -274.598162) (xy 272.656202 -274.644843) (xy 272.633331 -274.68842) (xy 272.603766 -274.727764)
			(xy 272.568273 -274.761856) (xy 272.52777 -274.789812) (xy 272.483308 -274.81091) (xy 272.436037 -274.824602)
			(xy 272.387182 -274.830534) (xy 272.338007 -274.828553) (xy 272.289788 -274.818709) (xy 272.243772 -274.801257)
			(xy 272.201151 -274.77665) (xy 272.16303 -274.745525) (xy 272.130395 -274.708688) (xy 272.104092 -274.667092)
			(xy 272.084801 -274.621816) (xy 272.073024 -274.574032) (xy 272.069064 -274.524978) (xy 271.730216 -274.524978)
			(xy 271.729721 -274.549585) (xy 271.721826 -274.598162) (xy 271.706242 -274.644843) (xy 271.683371 -274.68842)
			(xy 271.653806 -274.727764) (xy 271.618313 -274.761856) (xy 271.57781 -274.789812) (xy 271.533348 -274.81091)
			(xy 271.486077 -274.824602) (xy 271.437222 -274.830534) (xy 271.388047 -274.828553) (xy 271.339828 -274.818709)
			(xy 271.293812 -274.801257) (xy 271.251191 -274.77665) (xy 271.21307 -274.745525) (xy 271.180435 -274.708688)
			(xy 271.154132 -274.667092) (xy 271.134841 -274.621816) (xy 271.123064 -274.574032) (xy 271.119104 -274.524978)
			(xy 270.780256 -274.524978) (xy 270.779761 -274.549585) (xy 270.771866 -274.598162) (xy 270.756282 -274.644843)
			(xy 270.733411 -274.68842) (xy 270.703846 -274.727764) (xy 270.668353 -274.761856) (xy 270.62785 -274.789812)
			(xy 270.583388 -274.81091) (xy 270.536117 -274.824602) (xy 270.487262 -274.830534) (xy 270.438087 -274.828553)
			(xy 270.389868 -274.818709) (xy 270.343852 -274.801257) (xy 270.301231 -274.77665) (xy 270.26311 -274.745525)
			(xy 270.230475 -274.708688) (xy 270.204172 -274.667092) (xy 270.184881 -274.621816) (xy 270.173104 -274.574032)
			(xy 270.169144 -274.524978) (xy 269.830037 -274.524978) (xy 269.829547 -274.549331) (xy 269.821652 -274.597908)
			(xy 269.806068 -274.644589) (xy 269.783197 -274.688166) (xy 269.753632 -274.72751) (xy 269.718139 -274.761602)
			(xy 269.677636 -274.789558) (xy 269.633174 -274.810656) (xy 269.585903 -274.824348) (xy 269.537048 -274.83028)
			(xy 269.487873 -274.828299) (xy 269.439654 -274.818455) (xy 269.393638 -274.801003) (xy 269.351017 -274.776396)
			(xy 269.312896 -274.745271) (xy 269.280261 -274.708434) (xy 269.253958 -274.666838) (xy 269.234667 -274.621562)
			(xy 269.22289 -274.573778) (xy 269.21893 -274.524724) (xy 264.919787 -274.524724) (xy 264.866268 -274.570577)
			(xy 264.713025 -274.69132) (xy 264.554954 -274.80567) (xy 264.392321 -274.913435) (xy 264.249322 -274.999958)
			(xy 276.343884 -274.999958) (xy 276.347844 -274.950904) (xy 276.359621 -274.90312) (xy 276.378912 -274.857844)
			(xy 276.405215 -274.816248) (xy 276.43785 -274.779411) (xy 276.475971 -274.748286) (xy 276.518592 -274.723679)
			(xy 276.564608 -274.706227) (xy 276.612827 -274.696383) (xy 276.662002 -274.694402) (xy 276.710857 -274.700334)
			(xy 276.758128 -274.714026) (xy 276.80259 -274.735124) (xy 276.843093 -274.76308) (xy 276.878586 -274.797172)
			(xy 276.908151 -274.836516) (xy 276.931022 -274.880093) (xy 276.946606 -274.926774) (xy 276.954501 -274.975351)
			(xy 276.954996 -274.999958) (xy 276.954501 -275.024565) (xy 276.954322 -275.025666) (xy 277.273254 -275.025666)
			(xy 277.273254 -274.97425) (xy 277.281297 -274.923468) (xy 277.297185 -274.874569) (xy 277.320528 -274.828757)
			(xy 277.350749 -274.787161) (xy 277.387105 -274.750805) (xy 277.428701 -274.720584) (xy 277.474513 -274.697241)
			(xy 277.523412 -274.681353) (xy 277.574194 -274.67331) (xy 277.62561 -274.67331) (xy 277.676392 -274.681353)
			(xy 277.725291 -274.697241) (xy 277.771103 -274.720584) (xy 277.812699 -274.750805) (xy 277.849055 -274.787161)
			(xy 277.879276 -274.828757) (xy 277.902619 -274.874569) (xy 277.918507 -274.923468) (xy 277.92655 -274.97425)
			(xy 277.927054 -274.999958) (xy 278.244058 -274.999958) (xy 278.248018 -274.950904) (xy 278.259795 -274.90312)
			(xy 278.279086 -274.857844) (xy 278.305389 -274.816248) (xy 278.338024 -274.779411) (xy 278.376145 -274.748286)
			(xy 278.418766 -274.723679) (xy 278.464782 -274.706227) (xy 278.513001 -274.696383) (xy 278.562176 -274.694402)
			(xy 278.611031 -274.700334) (xy 278.658302 -274.714026) (xy 278.702764 -274.735124) (xy 278.743267 -274.76308)
			(xy 278.77876 -274.797172) (xy 278.808325 -274.836516) (xy 278.831196 -274.880093) (xy 278.84678 -274.926774)
			(xy 278.854675 -274.975351) (xy 278.85517 -274.999958) (xy 278.854675 -275.024565) (xy 278.854496 -275.025666)
			(xy 279.173174 -275.025666) (xy 279.173174 -274.97425) (xy 279.181217 -274.923468) (xy 279.197105 -274.874569)
			(xy 279.220448 -274.828757) (xy 279.250669 -274.787161) (xy 279.287025 -274.750805) (xy 279.328621 -274.720584)
			(xy 279.374433 -274.697241) (xy 279.423332 -274.681353) (xy 279.474114 -274.67331) (xy 279.52553 -274.67331)
			(xy 279.576312 -274.681353) (xy 279.625211 -274.697241) (xy 279.671023 -274.720584) (xy 279.712619 -274.750805)
			(xy 279.748975 -274.787161) (xy 279.779196 -274.828757) (xy 279.802539 -274.874569) (xy 279.818427 -274.923468)
			(xy 279.82647 -274.97425) (xy 279.826974 -274.999958) (xy 280.143978 -274.999958) (xy 280.147938 -274.950904)
			(xy 280.159715 -274.90312) (xy 280.179006 -274.857844) (xy 280.205309 -274.816248) (xy 280.237944 -274.779411)
			(xy 280.276065 -274.748286) (xy 280.318686 -274.723679) (xy 280.364702 -274.706227) (xy 280.412921 -274.696383)
			(xy 280.462096 -274.694402) (xy 280.510951 -274.700334) (xy 280.558222 -274.714026) (xy 280.602684 -274.735124)
			(xy 280.643187 -274.76308) (xy 280.67868 -274.797172) (xy 280.708245 -274.836516) (xy 280.731116 -274.880093)
			(xy 280.7467 -274.926774) (xy 280.754595 -274.975351) (xy 280.75509 -274.999958) (xy 280.754595 -275.024565)
			(xy 280.754416 -275.025666) (xy 281.073094 -275.025666) (xy 281.073094 -274.97425) (xy 281.081137 -274.923468)
			(xy 281.097025 -274.874569) (xy 281.120368 -274.828757) (xy 281.150589 -274.787161) (xy 281.186945 -274.750805)
			(xy 281.228541 -274.720584) (xy 281.274353 -274.697241) (xy 281.323252 -274.681353) (xy 281.374034 -274.67331)
			(xy 281.42545 -274.67331) (xy 281.476232 -274.681353) (xy 281.525131 -274.697241) (xy 281.570943 -274.720584)
			(xy 281.612539 -274.750805) (xy 281.648895 -274.787161) (xy 281.679116 -274.828757) (xy 281.702459 -274.874569)
			(xy 281.718347 -274.923468) (xy 281.72639 -274.97425) (xy 281.726894 -274.999958) (xy 282.043898 -274.999958)
			(xy 282.047858 -274.950904) (xy 282.059635 -274.90312) (xy 282.078926 -274.857844) (xy 282.105229 -274.816248)
			(xy 282.137864 -274.779411) (xy 282.175985 -274.748286) (xy 282.218606 -274.723679) (xy 282.264622 -274.706227)
			(xy 282.312841 -274.696383) (xy 282.362016 -274.694402) (xy 282.410871 -274.700334) (xy 282.458142 -274.714026)
			(xy 282.502604 -274.735124) (xy 282.543107 -274.76308) (xy 282.5786 -274.797172) (xy 282.608165 -274.836516)
			(xy 282.631036 -274.880093) (xy 282.64662 -274.926774) (xy 282.654515 -274.975351) (xy 282.65501 -274.999958)
			(xy 282.654515 -275.024565) (xy 282.654336 -275.025666) (xy 282.973268 -275.025666) (xy 282.973268 -274.97425)
			(xy 282.981311 -274.923468) (xy 282.997199 -274.874569) (xy 283.020542 -274.828757) (xy 283.050763 -274.787161)
			(xy 283.087119 -274.750805) (xy 283.128715 -274.720584) (xy 283.174527 -274.697241) (xy 283.223426 -274.681353)
			(xy 283.274208 -274.67331) (xy 283.325624 -274.67331) (xy 283.376406 -274.681353) (xy 283.425305 -274.697241)
			(xy 283.471117 -274.720584) (xy 283.512713 -274.750805) (xy 283.549069 -274.787161) (xy 283.57929 -274.828757)
			(xy 283.602633 -274.874569) (xy 283.618521 -274.923468) (xy 283.626564 -274.97425) (xy 283.627068 -274.999958)
			(xy 283.944072 -274.999958) (xy 283.948032 -274.950904) (xy 283.959809 -274.90312) (xy 283.9791 -274.857844)
			(xy 284.005403 -274.816248) (xy 284.038038 -274.779411) (xy 284.076159 -274.748286) (xy 284.11878 -274.723679)
			(xy 284.164796 -274.706227) (xy 284.213015 -274.696383) (xy 284.26219 -274.694402) (xy 284.311045 -274.700334)
			(xy 284.358316 -274.714026) (xy 284.402778 -274.735124) (xy 284.443281 -274.76308) (xy 284.478774 -274.797172)
			(xy 284.508339 -274.836516) (xy 284.53121 -274.880093) (xy 284.546794 -274.926774) (xy 284.554689 -274.975351)
			(xy 284.555184 -274.999958) (xy 284.554689 -275.024565) (xy 284.55451 -275.025666) (xy 284.873188 -275.025666)
			(xy 284.873188 -274.97425) (xy 284.881231 -274.923468) (xy 284.897119 -274.874569) (xy 284.920462 -274.828757)
			(xy 284.950683 -274.787161) (xy 284.987039 -274.750805) (xy 285.028635 -274.720584) (xy 285.074447 -274.697241)
			(xy 285.123346 -274.681353) (xy 285.174128 -274.67331) (xy 285.225544 -274.67331) (xy 285.276326 -274.681353)
			(xy 285.325225 -274.697241) (xy 285.371037 -274.720584) (xy 285.412633 -274.750805) (xy 285.448989 -274.787161)
			(xy 285.47921 -274.828757) (xy 285.502553 -274.874569) (xy 285.518441 -274.923468) (xy 285.526484 -274.97425)
			(xy 285.526988 -274.999958) (xy 285.843992 -274.999958) (xy 285.847952 -274.950904) (xy 285.859729 -274.90312)
			(xy 285.87902 -274.857844) (xy 285.905323 -274.816248) (xy 285.937958 -274.779411) (xy 285.976079 -274.748286)
			(xy 286.0187 -274.723679) (xy 286.064716 -274.706227) (xy 286.112935 -274.696383) (xy 286.16211 -274.694402)
			(xy 286.210965 -274.700334) (xy 286.258236 -274.714026) (xy 286.302698 -274.735124) (xy 286.343201 -274.76308)
			(xy 286.378694 -274.797172) (xy 286.408259 -274.836516) (xy 286.43113 -274.880093) (xy 286.446714 -274.926774)
			(xy 286.454609 -274.975351) (xy 286.455104 -274.999958) (xy 286.454609 -275.024565) (xy 286.45443 -275.025666)
			(xy 286.773108 -275.025666) (xy 286.773108 -274.97425) (xy 286.781151 -274.923468) (xy 286.797039 -274.874569)
			(xy 286.820382 -274.828757) (xy 286.850603 -274.787161) (xy 286.886959 -274.750805) (xy 286.928555 -274.720584)
			(xy 286.974367 -274.697241) (xy 287.023266 -274.681353) (xy 287.074048 -274.67331) (xy 287.125464 -274.67331)
			(xy 287.176246 -274.681353) (xy 287.225145 -274.697241) (xy 287.270957 -274.720584) (xy 287.312553 -274.750805)
			(xy 287.348909 -274.787161) (xy 287.37913 -274.828757) (xy 287.402473 -274.874569) (xy 287.418361 -274.923468)
			(xy 287.426404 -274.97425) (xy 287.426908 -274.999958) (xy 287.743912 -274.999958) (xy 287.747872 -274.950904)
			(xy 287.759649 -274.90312) (xy 287.77894 -274.857844) (xy 287.805243 -274.816248) (xy 287.837878 -274.779411)
			(xy 287.875999 -274.748286) (xy 287.91862 -274.723679) (xy 287.964636 -274.706227) (xy 288.012855 -274.696383)
			(xy 288.06203 -274.694402) (xy 288.110885 -274.700334) (xy 288.158156 -274.714026) (xy 288.202618 -274.735124)
			(xy 288.243121 -274.76308) (xy 288.278614 -274.797172) (xy 288.308179 -274.836516) (xy 288.33105 -274.880093)
			(xy 288.346634 -274.926774) (xy 288.354529 -274.975351) (xy 288.355024 -274.999958) (xy 288.354529 -275.024565)
			(xy 288.35435 -275.025666) (xy 288.673282 -275.025666) (xy 288.673282 -274.97425) (xy 288.681325 -274.923468)
			(xy 288.697213 -274.874569) (xy 288.720556 -274.828757) (xy 288.750777 -274.787161) (xy 288.787133 -274.750805)
			(xy 288.828729 -274.720584) (xy 288.874541 -274.697241) (xy 288.92344 -274.681353) (xy 288.974222 -274.67331)
			(xy 289.025638 -274.67331) (xy 289.07642 -274.681353) (xy 289.125319 -274.697241) (xy 289.171131 -274.720584)
			(xy 289.212727 -274.750805) (xy 289.249083 -274.787161) (xy 289.279304 -274.828757) (xy 289.302647 -274.874569)
			(xy 289.318535 -274.923468) (xy 289.326578 -274.97425) (xy 289.327082 -274.999958) (xy 289.644086 -274.999958)
			(xy 289.648046 -274.950904) (xy 289.659823 -274.90312) (xy 289.679114 -274.857844) (xy 289.705417 -274.816248)
			(xy 289.738052 -274.779411) (xy 289.776173 -274.748286) (xy 289.818794 -274.723679) (xy 289.86481 -274.706227)
			(xy 289.913029 -274.696383) (xy 289.962204 -274.694402) (xy 290.011059 -274.700334) (xy 290.05833 -274.714026)
			(xy 290.102792 -274.735124) (xy 290.143295 -274.76308) (xy 290.178788 -274.797172) (xy 290.208353 -274.836516)
			(xy 290.231224 -274.880093) (xy 290.246808 -274.926774) (xy 290.254703 -274.975351) (xy 290.255198 -274.999958)
			(xy 290.254703 -275.024565) (xy 290.254524 -275.025666) (xy 290.573202 -275.025666) (xy 290.573202 -274.97425)
			(xy 290.581245 -274.923468) (xy 290.597133 -274.874569) (xy 290.620476 -274.828757) (xy 290.650697 -274.787161)
			(xy 290.687053 -274.750805) (xy 290.728649 -274.720584) (xy 290.774461 -274.697241) (xy 290.82336 -274.681353)
			(xy 290.874142 -274.67331) (xy 290.925558 -274.67331) (xy 290.97634 -274.681353) (xy 291.025239 -274.697241)
			(xy 291.071051 -274.720584) (xy 291.112647 -274.750805) (xy 291.149003 -274.787161) (xy 291.179224 -274.828757)
			(xy 291.202567 -274.874569) (xy 291.218455 -274.923468) (xy 291.226498 -274.97425) (xy 291.227002 -274.999958)
			(xy 291.544006 -274.999958) (xy 291.547966 -274.950904) (xy 291.559743 -274.90312) (xy 291.579034 -274.857844)
			(xy 291.605337 -274.816248) (xy 291.637972 -274.779411) (xy 291.676093 -274.748286) (xy 291.718714 -274.723679)
			(xy 291.76473 -274.706227) (xy 291.812949 -274.696383) (xy 291.862124 -274.694402) (xy 291.910979 -274.700334)
			(xy 291.95825 -274.714026) (xy 292.002712 -274.735124) (xy 292.043215 -274.76308) (xy 292.078708 -274.797172)
			(xy 292.108273 -274.836516) (xy 292.131144 -274.880093) (xy 292.146728 -274.926774) (xy 292.154623 -274.975351)
			(xy 292.155118 -274.999958) (xy 292.154623 -275.024565) (xy 292.154485 -275.025412) (xy 292.472868 -275.025412)
			(xy 292.472868 -274.973996) (xy 292.480911 -274.923214) (xy 292.496799 -274.874315) (xy 292.520142 -274.828503)
			(xy 292.550363 -274.786907) (xy 292.586719 -274.750551) (xy 292.628315 -274.72033) (xy 292.674127 -274.696987)
			(xy 292.723026 -274.681099) (xy 292.773808 -274.673056) (xy 292.825224 -274.673056) (xy 292.876006 -274.681099)
			(xy 292.924905 -274.696987) (xy 292.970717 -274.72033) (xy 293.012313 -274.750551) (xy 293.048669 -274.786907)
			(xy 293.07889 -274.828503) (xy 293.102233 -274.874315) (xy 293.118121 -274.923214) (xy 293.126164 -274.973996)
			(xy 293.126668 -274.999704) (xy 293.126663 -274.999958) (xy 293.443926 -274.999958) (xy 293.447886 -274.950904)
			(xy 293.459663 -274.90312) (xy 293.478954 -274.857844) (xy 293.505257 -274.816248) (xy 293.537892 -274.779411)
			(xy 293.576013 -274.748286) (xy 293.618634 -274.723679) (xy 293.66465 -274.706227) (xy 293.712869 -274.696383)
			(xy 293.762044 -274.694402) (xy 293.810899 -274.700334) (xy 293.85817 -274.714026) (xy 293.902632 -274.735124)
			(xy 293.943135 -274.76308) (xy 293.978628 -274.797172) (xy 294.008193 -274.836516) (xy 294.031064 -274.880093)
			(xy 294.046648 -274.926774) (xy 294.054543 -274.975351) (xy 294.055038 -274.999958) (xy 294.054543 -275.024565)
			(xy 294.054364 -275.025666) (xy 294.372788 -275.025666) (xy 294.372788 -274.97425) (xy 294.380831 -274.923468)
			(xy 294.396719 -274.874569) (xy 294.420062 -274.828757) (xy 294.450283 -274.787161) (xy 294.486639 -274.750805)
			(xy 294.528235 -274.720584) (xy 294.574047 -274.697241) (xy 294.622946 -274.681353) (xy 294.673728 -274.67331)
			(xy 294.725144 -274.67331) (xy 294.775926 -274.681353) (xy 294.824825 -274.697241) (xy 294.870637 -274.720584)
			(xy 294.912233 -274.750805) (xy 294.948589 -274.787161) (xy 294.97881 -274.828757) (xy 295.002153 -274.874569)
			(xy 295.018041 -274.923468) (xy 295.026084 -274.97425) (xy 295.026588 -274.999958) (xy 295.3441 -274.999958)
			(xy 295.34806 -274.950904) (xy 295.359837 -274.90312) (xy 295.379128 -274.857844) (xy 295.405431 -274.816248)
			(xy 295.438066 -274.779411) (xy 295.476187 -274.748286) (xy 295.518808 -274.723679) (xy 295.564824 -274.706227)
			(xy 295.613043 -274.696383) (xy 295.662218 -274.694402) (xy 295.711073 -274.700334) (xy 295.758344 -274.714026)
			(xy 295.802806 -274.735124) (xy 295.843309 -274.76308) (xy 295.878802 -274.797172) (xy 295.908367 -274.836516)
			(xy 295.931238 -274.880093) (xy 295.946822 -274.926774) (xy 295.954717 -274.975351) (xy 295.955212 -274.999958)
			(xy 295.954717 -275.024565) (xy 295.954579 -275.025412) (xy 296.272962 -275.025412) (xy 296.272962 -274.973996)
			(xy 296.281005 -274.923214) (xy 296.296893 -274.874315) (xy 296.320236 -274.828503) (xy 296.350457 -274.786907)
			(xy 296.386813 -274.750551) (xy 296.428409 -274.72033) (xy 296.474221 -274.696987) (xy 296.52312 -274.681099)
			(xy 296.573902 -274.673056) (xy 296.625318 -274.673056) (xy 296.6761 -274.681099) (xy 296.724999 -274.696987)
			(xy 296.770811 -274.72033) (xy 296.812407 -274.750551) (xy 296.848763 -274.786907) (xy 296.878984 -274.828503)
			(xy 296.902327 -274.874315) (xy 296.918215 -274.923214) (xy 296.926258 -274.973996) (xy 296.926762 -274.999704)
			(xy 296.926757 -274.999958) (xy 297.24402 -274.999958) (xy 297.24798 -274.950904) (xy 297.259757 -274.90312)
			(xy 297.279048 -274.857844) (xy 297.305351 -274.816248) (xy 297.337986 -274.779411) (xy 297.376107 -274.748286)
			(xy 297.418728 -274.723679) (xy 297.464744 -274.706227) (xy 297.512963 -274.696383) (xy 297.562138 -274.694402)
			(xy 297.610993 -274.700334) (xy 297.658264 -274.714026) (xy 297.702726 -274.735124) (xy 297.743229 -274.76308)
			(xy 297.778722 -274.797172) (xy 297.808287 -274.836516) (xy 297.831158 -274.880093) (xy 297.846742 -274.926774)
			(xy 297.854637 -274.975351) (xy 297.855132 -274.999958) (xy 297.854637 -275.024565) (xy 297.854458 -275.025666)
			(xy 298.172882 -275.025666) (xy 298.172882 -274.97425) (xy 298.180925 -274.923468) (xy 298.196813 -274.874569)
			(xy 298.220156 -274.828757) (xy 298.250377 -274.787161) (xy 298.286733 -274.750805) (xy 298.328329 -274.720584)
			(xy 298.374141 -274.697241) (xy 298.42304 -274.681353) (xy 298.473822 -274.67331) (xy 298.525238 -274.67331)
			(xy 298.57602 -274.681353) (xy 298.624919 -274.697241) (xy 298.670731 -274.720584) (xy 298.712327 -274.750805)
			(xy 298.748683 -274.787161) (xy 298.778904 -274.828757) (xy 298.802247 -274.874569) (xy 298.818135 -274.923468)
			(xy 298.826178 -274.97425) (xy 298.826682 -274.999958) (xy 299.14394 -274.999958) (xy 299.1479 -274.950904)
			(xy 299.159677 -274.90312) (xy 299.178968 -274.857844) (xy 299.205271 -274.816248) (xy 299.237906 -274.779411)
			(xy 299.276027 -274.748286) (xy 299.318648 -274.723679) (xy 299.364664 -274.706227) (xy 299.412883 -274.696383)
			(xy 299.462058 -274.694402) (xy 299.510913 -274.700334) (xy 299.558184 -274.714026) (xy 299.602646 -274.735124)
			(xy 299.643149 -274.76308) (xy 299.678642 -274.797172) (xy 299.708207 -274.836516) (xy 299.731078 -274.880093)
			(xy 299.746662 -274.926774) (xy 299.754557 -274.975351) (xy 299.755052 -274.999958) (xy 299.754557 -275.024565)
			(xy 299.754419 -275.025412) (xy 300.072802 -275.025412) (xy 300.072802 -274.973996) (xy 300.080845 -274.923214)
			(xy 300.096733 -274.874315) (xy 300.120076 -274.828503) (xy 300.150297 -274.786907) (xy 300.186653 -274.750551)
			(xy 300.228249 -274.72033) (xy 300.274061 -274.696987) (xy 300.32296 -274.681099) (xy 300.373742 -274.673056)
			(xy 300.425158 -274.673056) (xy 300.47594 -274.681099) (xy 300.524839 -274.696987) (xy 300.570651 -274.72033)
			(xy 300.612247 -274.750551) (xy 300.648603 -274.786907) (xy 300.678824 -274.828503) (xy 300.702167 -274.874315)
			(xy 300.718055 -274.923214) (xy 300.726098 -274.973996) (xy 300.726602 -274.999704) (xy 300.726597 -274.999958)
			(xy 301.044114 -274.999958) (xy 301.048074 -274.950904) (xy 301.059851 -274.90312) (xy 301.079142 -274.857844)
			(xy 301.105445 -274.816248) (xy 301.13808 -274.779411) (xy 301.176201 -274.748286) (xy 301.218822 -274.723679)
			(xy 301.264838 -274.706227) (xy 301.313057 -274.696383) (xy 301.362232 -274.694402) (xy 301.411087 -274.700334)
			(xy 301.458358 -274.714026) (xy 301.50282 -274.735124) (xy 301.543323 -274.76308) (xy 301.578816 -274.797172)
			(xy 301.608381 -274.836516) (xy 301.631252 -274.880093) (xy 301.646836 -274.926774) (xy 301.654731 -274.975351)
			(xy 301.655226 -274.999958) (xy 301.654731 -275.024565) (xy 301.654552 -275.025666) (xy 301.972722 -275.025666)
			(xy 301.972722 -274.97425) (xy 301.980765 -274.923468) (xy 301.996653 -274.874569) (xy 302.019996 -274.828757)
			(xy 302.050217 -274.787161) (xy 302.086573 -274.750805) (xy 302.128169 -274.720584) (xy 302.173981 -274.697241)
			(xy 302.22288 -274.681353) (xy 302.273662 -274.67331) (xy 302.325078 -274.67331) (xy 302.37586 -274.681353)
			(xy 302.424759 -274.697241) (xy 302.470571 -274.720584) (xy 302.512167 -274.750805) (xy 302.548523 -274.787161)
			(xy 302.578744 -274.828757) (xy 302.602087 -274.874569) (xy 302.617975 -274.923468) (xy 302.626018 -274.97425)
			(xy 302.626522 -274.999958) (xy 302.944034 -274.999958) (xy 302.947994 -274.950904) (xy 302.959771 -274.90312)
			(xy 302.979062 -274.857844) (xy 303.005365 -274.816248) (xy 303.038 -274.779411) (xy 303.076121 -274.748286)
			(xy 303.118742 -274.723679) (xy 303.164758 -274.706227) (xy 303.212977 -274.696383) (xy 303.262152 -274.694402)
			(xy 303.311007 -274.700334) (xy 303.358278 -274.714026) (xy 303.40274 -274.735124) (xy 303.443243 -274.76308)
			(xy 303.478736 -274.797172) (xy 303.508301 -274.836516) (xy 303.531172 -274.880093) (xy 303.546756 -274.926774)
			(xy 303.554651 -274.975351) (xy 303.555146 -274.999958) (xy 303.554651 -275.024565) (xy 303.554513 -275.025412)
			(xy 303.872896 -275.025412) (xy 303.872896 -274.973996) (xy 303.880939 -274.923214) (xy 303.896827 -274.874315)
			(xy 303.92017 -274.828503) (xy 303.950391 -274.786907) (xy 303.986747 -274.750551) (xy 304.028343 -274.72033)
			(xy 304.074155 -274.696987) (xy 304.123054 -274.681099) (xy 304.173836 -274.673056) (xy 304.225252 -274.673056)
			(xy 304.276034 -274.681099) (xy 304.324933 -274.696987) (xy 304.370745 -274.72033) (xy 304.412341 -274.750551)
			(xy 304.448697 -274.786907) (xy 304.478918 -274.828503) (xy 304.502261 -274.874315) (xy 304.518149 -274.923214)
			(xy 304.526192 -274.973996) (xy 304.526696 -274.999704) (xy 304.526691 -274.999958) (xy 304.843954 -274.999958)
			(xy 304.847914 -274.950904) (xy 304.859691 -274.90312) (xy 304.878982 -274.857844) (xy 304.905285 -274.816248)
			(xy 304.93792 -274.779411) (xy 304.976041 -274.748286) (xy 305.018662 -274.723679) (xy 305.064678 -274.706227)
			(xy 305.112897 -274.696383) (xy 305.162072 -274.694402) (xy 305.210927 -274.700334) (xy 305.258198 -274.714026)
			(xy 305.30266 -274.735124) (xy 305.343163 -274.76308) (xy 305.378656 -274.797172) (xy 305.408221 -274.836516)
			(xy 305.431092 -274.880093) (xy 305.446676 -274.926774) (xy 305.454571 -274.975351) (xy 305.455066 -274.999958)
			(xy 305.454571 -275.024565) (xy 305.454392 -275.025666) (xy 305.772816 -275.025666) (xy 305.772816 -274.97425)
			(xy 305.780859 -274.923468) (xy 305.796747 -274.874569) (xy 305.82009 -274.828757) (xy 305.850311 -274.787161)
			(xy 305.886667 -274.750805) (xy 305.928263 -274.720584) (xy 305.974075 -274.697241) (xy 306.022974 -274.681353)
			(xy 306.073756 -274.67331) (xy 306.125172 -274.67331) (xy 306.175954 -274.681353) (xy 306.224853 -274.697241)
			(xy 306.270665 -274.720584) (xy 306.312261 -274.750805) (xy 306.348617 -274.787161) (xy 306.378838 -274.828757)
			(xy 306.402181 -274.874569) (xy 306.418069 -274.923468) (xy 306.426112 -274.97425) (xy 306.426616 -274.999958)
			(xy 306.743874 -274.999958) (xy 306.747834 -274.950904) (xy 306.759611 -274.90312) (xy 306.778902 -274.857844)
			(xy 306.805205 -274.816248) (xy 306.83784 -274.779411) (xy 306.875961 -274.748286) (xy 306.918582 -274.723679)
			(xy 306.964598 -274.706227) (xy 307.012817 -274.696383) (xy 307.061992 -274.694402) (xy 307.110847 -274.700334)
			(xy 307.158118 -274.714026) (xy 307.20258 -274.735124) (xy 307.243083 -274.76308) (xy 307.278576 -274.797172)
			(xy 307.308141 -274.836516) (xy 307.331012 -274.880093) (xy 307.346596 -274.926774) (xy 307.354491 -274.975351)
			(xy 307.354986 -274.999958) (xy 307.354491 -275.024565) (xy 307.354353 -275.025412) (xy 307.67299 -275.025412)
			(xy 307.67299 -274.973996) (xy 307.681033 -274.923214) (xy 307.696921 -274.874315) (xy 307.720264 -274.828503)
			(xy 307.750485 -274.786907) (xy 307.786841 -274.750551) (xy 307.828437 -274.72033) (xy 307.874249 -274.696987)
			(xy 307.923148 -274.681099) (xy 307.97393 -274.673056) (xy 308.025346 -274.673056) (xy 308.076128 -274.681099)
			(xy 308.125027 -274.696987) (xy 308.170839 -274.72033) (xy 308.212435 -274.750551) (xy 308.248791 -274.786907)
			(xy 308.279012 -274.828503) (xy 308.302355 -274.874315) (xy 308.318243 -274.923214) (xy 308.326286 -274.973996)
			(xy 308.32679 -274.999704) (xy 308.326785 -274.999958) (xy 308.643794 -274.999958) (xy 308.647754 -274.950904)
			(xy 308.659531 -274.90312) (xy 308.678822 -274.857844) (xy 308.705125 -274.816248) (xy 308.73776 -274.779411)
			(xy 308.775881 -274.748286) (xy 308.818502 -274.723679) (xy 308.864518 -274.706227) (xy 308.912737 -274.696383)
			(xy 308.961912 -274.694402) (xy 309.010767 -274.700334) (xy 309.058038 -274.714026) (xy 309.1025 -274.735124)
			(xy 309.143003 -274.76308) (xy 309.178496 -274.797172) (xy 309.208061 -274.836516) (xy 309.230932 -274.880093)
			(xy 309.246516 -274.926774) (xy 309.254411 -274.975351) (xy 309.254906 -274.999958) (xy 309.254411 -275.024565)
			(xy 309.254232 -275.025666) (xy 309.57291 -275.025666) (xy 309.57291 -274.97425) (xy 309.580953 -274.923468)
			(xy 309.596841 -274.874569) (xy 309.620184 -274.828757) (xy 309.650405 -274.787161) (xy 309.686761 -274.750805)
			(xy 309.728357 -274.720584) (xy 309.774169 -274.697241) (xy 309.823068 -274.681353) (xy 309.87385 -274.67331)
			(xy 309.925266 -274.67331) (xy 309.976048 -274.681353) (xy 310.024947 -274.697241) (xy 310.070759 -274.720584)
			(xy 310.112355 -274.750805) (xy 310.148711 -274.787161) (xy 310.178932 -274.828757) (xy 310.202275 -274.874569)
			(xy 310.218163 -274.923468) (xy 310.226206 -274.97425) (xy 310.22671 -274.999958) (xy 310.543714 -274.999958)
			(xy 310.547674 -274.950904) (xy 310.559451 -274.90312) (xy 310.578742 -274.857844) (xy 310.605045 -274.816248)
			(xy 310.63768 -274.779411) (xy 310.675801 -274.748286) (xy 310.718422 -274.723679) (xy 310.764438 -274.706227)
			(xy 310.812657 -274.696383) (xy 310.861832 -274.694402) (xy 310.910687 -274.700334) (xy 310.957958 -274.714026)
			(xy 311.00242 -274.735124) (xy 311.042923 -274.76308) (xy 311.078416 -274.797172) (xy 311.107981 -274.836516)
			(xy 311.130852 -274.880093) (xy 311.146436 -274.926774) (xy 311.154331 -274.975351) (xy 311.154826 -274.999958)
			(xy 311.154331 -275.024565) (xy 311.154152 -275.025666) (xy 311.47283 -275.025666) (xy 311.47283 -274.97425)
			(xy 311.480873 -274.923468) (xy 311.496761 -274.874569) (xy 311.520104 -274.828757) (xy 311.550325 -274.787161)
			(xy 311.586681 -274.750805) (xy 311.628277 -274.720584) (xy 311.674089 -274.697241) (xy 311.722988 -274.681353)
			(xy 311.77377 -274.67331) (xy 311.825186 -274.67331) (xy 311.875968 -274.681353) (xy 311.924867 -274.697241)
			(xy 311.970679 -274.720584) (xy 312.012275 -274.750805) (xy 312.048631 -274.787161) (xy 312.078852 -274.828757)
			(xy 312.102195 -274.874569) (xy 312.118083 -274.923468) (xy 312.126126 -274.97425) (xy 312.12663 -274.999958)
			(xy 312.443888 -274.999958) (xy 312.447848 -274.950904) (xy 312.459625 -274.90312) (xy 312.478916 -274.857844)
			(xy 312.505219 -274.816248) (xy 312.537854 -274.779411) (xy 312.575975 -274.748286) (xy 312.618596 -274.723679)
			(xy 312.664612 -274.706227) (xy 312.712831 -274.696383) (xy 312.762006 -274.694402) (xy 312.810861 -274.700334)
			(xy 312.858132 -274.714026) (xy 312.902594 -274.735124) (xy 312.943097 -274.76308) (xy 312.97859 -274.797172)
			(xy 313.008155 -274.836516) (xy 313.031026 -274.880093) (xy 313.04661 -274.926774) (xy 313.054505 -274.975351)
			(xy 313.055 -274.999958) (xy 313.054505 -275.024565) (xy 313.054367 -275.025412) (xy 313.373258 -275.025412)
			(xy 313.373258 -274.973996) (xy 313.381301 -274.923214) (xy 313.397189 -274.874315) (xy 313.420532 -274.828503)
			(xy 313.450753 -274.786907) (xy 313.487109 -274.750551) (xy 313.528705 -274.72033) (xy 313.574517 -274.696987)
			(xy 313.623416 -274.681099) (xy 313.674198 -274.673056) (xy 313.725614 -274.673056) (xy 313.776396 -274.681099)
			(xy 313.825295 -274.696987) (xy 313.871107 -274.72033) (xy 313.912703 -274.750551) (xy 313.949059 -274.786907)
			(xy 313.97928 -274.828503) (xy 314.002623 -274.874315) (xy 314.018511 -274.923214) (xy 314.026554 -274.973996)
			(xy 314.027058 -274.999704) (xy 314.026554 -275.025412) (xy 314.323218 -275.025412) (xy 314.323218 -274.973996)
			(xy 314.331261 -274.923214) (xy 314.347149 -274.874315) (xy 314.370492 -274.828503) (xy 314.400713 -274.786907)
			(xy 314.437069 -274.750551) (xy 314.478665 -274.72033) (xy 314.524477 -274.696987) (xy 314.573376 -274.681099)
			(xy 314.624158 -274.673056) (xy 314.675574 -274.673056) (xy 314.726356 -274.681099) (xy 314.775255 -274.696987)
			(xy 314.821067 -274.72033) (xy 314.862663 -274.750551) (xy 314.899019 -274.786907) (xy 314.92924 -274.828503)
			(xy 314.952583 -274.874315) (xy 314.968471 -274.923214) (xy 314.976514 -274.973996) (xy 314.977018 -274.999704)
			(xy 314.977013 -274.999958) (xy 315.294276 -274.999958) (xy 315.298236 -274.950904) (xy 315.310013 -274.90312)
			(xy 315.329304 -274.857844) (xy 315.355607 -274.816248) (xy 315.388242 -274.779411) (xy 315.426363 -274.748286)
			(xy 315.468984 -274.723679) (xy 315.515 -274.706227) (xy 315.563219 -274.696383) (xy 315.612394 -274.694402)
			(xy 315.661249 -274.700334) (xy 315.70852 -274.714026) (xy 315.752982 -274.735124) (xy 315.793485 -274.76308)
			(xy 315.828978 -274.797172) (xy 315.858543 -274.836516) (xy 315.881414 -274.880093) (xy 315.896998 -274.926774)
			(xy 315.904893 -274.975351) (xy 315.905388 -274.999958) (xy 315.904893 -275.024565) (xy 315.896998 -275.073142)
			(xy 315.881414 -275.119823) (xy 315.858543 -275.1634) (xy 315.828978 -275.202744) (xy 315.793485 -275.236836)
			(xy 315.752982 -275.264792) (xy 315.70852 -275.28589) (xy 315.661249 -275.299582) (xy 315.612394 -275.305514)
			(xy 315.563219 -275.303533) (xy 315.515 -275.293689) (xy 315.468984 -275.276237) (xy 315.426363 -275.25163)
			(xy 315.388242 -275.220505) (xy 315.355607 -275.183668) (xy 315.329304 -275.142072) (xy 315.310013 -275.096796)
			(xy 315.298236 -275.049012) (xy 315.294276 -274.999958) (xy 314.977013 -274.999958) (xy 314.976514 -275.025412)
			(xy 314.968471 -275.076194) (xy 314.952583 -275.125093) (xy 314.92924 -275.170905) (xy 314.899019 -275.212501)
			(xy 314.862663 -275.248857) (xy 314.821067 -275.279078) (xy 314.775255 -275.302421) (xy 314.726356 -275.318309)
			(xy 314.675574 -275.326352) (xy 314.624158 -275.326352) (xy 314.573376 -275.318309) (xy 314.524477 -275.302421)
			(xy 314.478665 -275.279078) (xy 314.437069 -275.248857) (xy 314.400713 -275.212501) (xy 314.370492 -275.170905)
			(xy 314.347149 -275.125093) (xy 314.331261 -275.076194) (xy 314.323218 -275.025412) (xy 314.026554 -275.025412)
			(xy 314.018511 -275.076194) (xy 314.002623 -275.125093) (xy 313.97928 -275.170905) (xy 313.949059 -275.212501)
			(xy 313.912703 -275.248857) (xy 313.871107 -275.279078) (xy 313.825295 -275.302421) (xy 313.776396 -275.318309)
			(xy 313.725614 -275.326352) (xy 313.674198 -275.326352) (xy 313.623416 -275.318309) (xy 313.574517 -275.302421)
			(xy 313.528705 -275.279078) (xy 313.487109 -275.248857) (xy 313.450753 -275.212501) (xy 313.420532 -275.170905)
			(xy 313.397189 -275.125093) (xy 313.381301 -275.076194) (xy 313.373258 -275.025412) (xy 313.054367 -275.025412)
			(xy 313.04661 -275.073142) (xy 313.031026 -275.119823) (xy 313.008155 -275.1634) (xy 312.97859 -275.202744)
			(xy 312.943097 -275.236836) (xy 312.902594 -275.264792) (xy 312.858132 -275.28589) (xy 312.810861 -275.299582)
			(xy 312.762006 -275.305514) (xy 312.712831 -275.303533) (xy 312.664612 -275.293689) (xy 312.618596 -275.276237)
			(xy 312.575975 -275.25163) (xy 312.537854 -275.220505) (xy 312.505219 -275.183668) (xy 312.478916 -275.142072)
			(xy 312.459625 -275.096796) (xy 312.447848 -275.049012) (xy 312.443888 -274.999958) (xy 312.12663 -274.999958)
			(xy 312.126126 -275.025666) (xy 312.118083 -275.076448) (xy 312.102195 -275.125347) (xy 312.078852 -275.171159)
			(xy 312.048631 -275.212755) (xy 312.012275 -275.249111) (xy 311.970679 -275.279332) (xy 311.924867 -275.302675)
			(xy 311.875968 -275.318563) (xy 311.825186 -275.326606) (xy 311.77377 -275.326606) (xy 311.722988 -275.318563)
			(xy 311.674089 -275.302675) (xy 311.628277 -275.279332) (xy 311.586681 -275.249111) (xy 311.550325 -275.212755)
			(xy 311.520104 -275.171159) (xy 311.496761 -275.125347) (xy 311.480873 -275.076448) (xy 311.47283 -275.025666)
			(xy 311.154152 -275.025666) (xy 311.146436 -275.073142) (xy 311.130852 -275.119823) (xy 311.107981 -275.1634)
			(xy 311.078416 -275.202744) (xy 311.042923 -275.236836) (xy 311.00242 -275.264792) (xy 310.957958 -275.28589)
			(xy 310.910687 -275.299582) (xy 310.861832 -275.305514) (xy 310.812657 -275.303533) (xy 310.764438 -275.293689)
			(xy 310.718422 -275.276237) (xy 310.675801 -275.25163) (xy 310.63768 -275.220505) (xy 310.605045 -275.183668)
			(xy 310.578742 -275.142072) (xy 310.559451 -275.096796) (xy 310.547674 -275.049012) (xy 310.543714 -274.999958)
			(xy 310.22671 -274.999958) (xy 310.226206 -275.025666) (xy 310.218163 -275.076448) (xy 310.202275 -275.125347)
			(xy 310.178932 -275.171159) (xy 310.148711 -275.212755) (xy 310.112355 -275.249111) (xy 310.070759 -275.279332)
			(xy 310.024947 -275.302675) (xy 309.976048 -275.318563) (xy 309.925266 -275.326606) (xy 309.87385 -275.326606)
			(xy 309.823068 -275.318563) (xy 309.774169 -275.302675) (xy 309.728357 -275.279332) (xy 309.686761 -275.249111)
			(xy 309.650405 -275.212755) (xy 309.620184 -275.171159) (xy 309.596841 -275.125347) (xy 309.580953 -275.076448)
			(xy 309.57291 -275.025666) (xy 309.254232 -275.025666) (xy 309.246516 -275.073142) (xy 309.230932 -275.119823)
			(xy 309.208061 -275.1634) (xy 309.178496 -275.202744) (xy 309.143003 -275.236836) (xy 309.1025 -275.264792)
			(xy 309.058038 -275.28589) (xy 309.010767 -275.299582) (xy 308.961912 -275.305514) (xy 308.912737 -275.303533)
			(xy 308.864518 -275.293689) (xy 308.818502 -275.276237) (xy 308.775881 -275.25163) (xy 308.73776 -275.220505)
			(xy 308.705125 -275.183668) (xy 308.678822 -275.142072) (xy 308.659531 -275.096796) (xy 308.647754 -275.049012)
			(xy 308.643794 -274.999958) (xy 308.326785 -274.999958) (xy 308.326286 -275.025412) (xy 308.318243 -275.076194)
			(xy 308.302355 -275.125093) (xy 308.279012 -275.170905) (xy 308.248791 -275.212501) (xy 308.212435 -275.248857)
			(xy 308.170839 -275.279078) (xy 308.125027 -275.302421) (xy 308.076128 -275.318309) (xy 308.025346 -275.326352)
			(xy 307.97393 -275.326352) (xy 307.923148 -275.318309) (xy 307.874249 -275.302421) (xy 307.828437 -275.279078)
			(xy 307.786841 -275.248857) (xy 307.750485 -275.212501) (xy 307.720264 -275.170905) (xy 307.696921 -275.125093)
			(xy 307.681033 -275.076194) (xy 307.67299 -275.025412) (xy 307.354353 -275.025412) (xy 307.346596 -275.073142)
			(xy 307.331012 -275.119823) (xy 307.308141 -275.1634) (xy 307.278576 -275.202744) (xy 307.243083 -275.236836)
			(xy 307.20258 -275.264792) (xy 307.158118 -275.28589) (xy 307.110847 -275.299582) (xy 307.061992 -275.305514)
			(xy 307.012817 -275.303533) (xy 306.964598 -275.293689) (xy 306.918582 -275.276237) (xy 306.875961 -275.25163)
			(xy 306.83784 -275.220505) (xy 306.805205 -275.183668) (xy 306.778902 -275.142072) (xy 306.759611 -275.096796)
			(xy 306.747834 -275.049012) (xy 306.743874 -274.999958) (xy 306.426616 -274.999958) (xy 306.426112 -275.025666)
			(xy 306.418069 -275.076448) (xy 306.402181 -275.125347) (xy 306.378838 -275.171159) (xy 306.348617 -275.212755)
			(xy 306.312261 -275.249111) (xy 306.270665 -275.279332) (xy 306.224853 -275.302675) (xy 306.175954 -275.318563)
			(xy 306.125172 -275.326606) (xy 306.073756 -275.326606) (xy 306.022974 -275.318563) (xy 305.974075 -275.302675)
			(xy 305.928263 -275.279332) (xy 305.886667 -275.249111) (xy 305.850311 -275.212755) (xy 305.82009 -275.171159)
			(xy 305.796747 -275.125347) (xy 305.780859 -275.076448) (xy 305.772816 -275.025666) (xy 305.454392 -275.025666)
			(xy 305.446676 -275.073142) (xy 305.431092 -275.119823) (xy 305.408221 -275.1634) (xy 305.378656 -275.202744)
			(xy 305.343163 -275.236836) (xy 305.30266 -275.264792) (xy 305.258198 -275.28589) (xy 305.210927 -275.299582)
			(xy 305.162072 -275.305514) (xy 305.112897 -275.303533) (xy 305.064678 -275.293689) (xy 305.018662 -275.276237)
			(xy 304.976041 -275.25163) (xy 304.93792 -275.220505) (xy 304.905285 -275.183668) (xy 304.878982 -275.142072)
			(xy 304.859691 -275.096796) (xy 304.847914 -275.049012) (xy 304.843954 -274.999958) (xy 304.526691 -274.999958)
			(xy 304.526192 -275.025412) (xy 304.518149 -275.076194) (xy 304.502261 -275.125093) (xy 304.478918 -275.170905)
			(xy 304.448697 -275.212501) (xy 304.412341 -275.248857) (xy 304.370745 -275.279078) (xy 304.324933 -275.302421)
			(xy 304.276034 -275.318309) (xy 304.225252 -275.326352) (xy 304.173836 -275.326352) (xy 304.123054 -275.318309)
			(xy 304.074155 -275.302421) (xy 304.028343 -275.279078) (xy 303.986747 -275.248857) (xy 303.950391 -275.212501)
			(xy 303.92017 -275.170905) (xy 303.896827 -275.125093) (xy 303.880939 -275.076194) (xy 303.872896 -275.025412)
			(xy 303.554513 -275.025412) (xy 303.546756 -275.073142) (xy 303.531172 -275.119823) (xy 303.508301 -275.1634)
			(xy 303.478736 -275.202744) (xy 303.443243 -275.236836) (xy 303.40274 -275.264792) (xy 303.358278 -275.28589)
			(xy 303.311007 -275.299582) (xy 303.262152 -275.305514) (xy 303.212977 -275.303533) (xy 303.164758 -275.293689)
			(xy 303.118742 -275.276237) (xy 303.076121 -275.25163) (xy 303.038 -275.220505) (xy 303.005365 -275.183668)
			(xy 302.979062 -275.142072) (xy 302.959771 -275.096796) (xy 302.947994 -275.049012) (xy 302.944034 -274.999958)
			(xy 302.626522 -274.999958) (xy 302.626018 -275.025666) (xy 302.617975 -275.076448) (xy 302.602087 -275.125347)
			(xy 302.578744 -275.171159) (xy 302.548523 -275.212755) (xy 302.512167 -275.249111) (xy 302.470571 -275.279332)
			(xy 302.424759 -275.302675) (xy 302.37586 -275.318563) (xy 302.325078 -275.326606) (xy 302.273662 -275.326606)
			(xy 302.22288 -275.318563) (xy 302.173981 -275.302675) (xy 302.128169 -275.279332) (xy 302.086573 -275.249111)
			(xy 302.050217 -275.212755) (xy 302.019996 -275.171159) (xy 301.996653 -275.125347) (xy 301.980765 -275.076448)
			(xy 301.972722 -275.025666) (xy 301.654552 -275.025666) (xy 301.646836 -275.073142) (xy 301.631252 -275.119823)
			(xy 301.608381 -275.1634) (xy 301.578816 -275.202744) (xy 301.543323 -275.236836) (xy 301.50282 -275.264792)
			(xy 301.458358 -275.28589) (xy 301.411087 -275.299582) (xy 301.362232 -275.305514) (xy 301.313057 -275.303533)
			(xy 301.264838 -275.293689) (xy 301.218822 -275.276237) (xy 301.176201 -275.25163) (xy 301.13808 -275.220505)
			(xy 301.105445 -275.183668) (xy 301.079142 -275.142072) (xy 301.059851 -275.096796) (xy 301.048074 -275.049012)
			(xy 301.044114 -274.999958) (xy 300.726597 -274.999958) (xy 300.726098 -275.025412) (xy 300.718055 -275.076194)
			(xy 300.702167 -275.125093) (xy 300.678824 -275.170905) (xy 300.648603 -275.212501) (xy 300.612247 -275.248857)
			(xy 300.570651 -275.279078) (xy 300.524839 -275.302421) (xy 300.47594 -275.318309) (xy 300.425158 -275.326352)
			(xy 300.373742 -275.326352) (xy 300.32296 -275.318309) (xy 300.274061 -275.302421) (xy 300.228249 -275.279078)
			(xy 300.186653 -275.248857) (xy 300.150297 -275.212501) (xy 300.120076 -275.170905) (xy 300.096733 -275.125093)
			(xy 300.080845 -275.076194) (xy 300.072802 -275.025412) (xy 299.754419 -275.025412) (xy 299.746662 -275.073142)
			(xy 299.731078 -275.119823) (xy 299.708207 -275.1634) (xy 299.678642 -275.202744) (xy 299.643149 -275.236836)
			(xy 299.602646 -275.264792) (xy 299.558184 -275.28589) (xy 299.510913 -275.299582) (xy 299.462058 -275.305514)
			(xy 299.412883 -275.303533) (xy 299.364664 -275.293689) (xy 299.318648 -275.276237) (xy 299.276027 -275.25163)
			(xy 299.237906 -275.220505) (xy 299.205271 -275.183668) (xy 299.178968 -275.142072) (xy 299.159677 -275.096796)
			(xy 299.1479 -275.049012) (xy 299.14394 -274.999958) (xy 298.826682 -274.999958) (xy 298.826178 -275.025666)
			(xy 298.818135 -275.076448) (xy 298.802247 -275.125347) (xy 298.778904 -275.171159) (xy 298.748683 -275.212755)
			(xy 298.712327 -275.249111) (xy 298.670731 -275.279332) (xy 298.624919 -275.302675) (xy 298.57602 -275.318563)
			(xy 298.525238 -275.326606) (xy 298.473822 -275.326606) (xy 298.42304 -275.318563) (xy 298.374141 -275.302675)
			(xy 298.328329 -275.279332) (xy 298.286733 -275.249111) (xy 298.250377 -275.212755) (xy 298.220156 -275.171159)
			(xy 298.196813 -275.125347) (xy 298.180925 -275.076448) (xy 298.172882 -275.025666) (xy 297.854458 -275.025666)
			(xy 297.846742 -275.073142) (xy 297.831158 -275.119823) (xy 297.808287 -275.1634) (xy 297.778722 -275.202744)
			(xy 297.743229 -275.236836) (xy 297.702726 -275.264792) (xy 297.658264 -275.28589) (xy 297.610993 -275.299582)
			(xy 297.562138 -275.305514) (xy 297.512963 -275.303533) (xy 297.464744 -275.293689) (xy 297.418728 -275.276237)
			(xy 297.376107 -275.25163) (xy 297.337986 -275.220505) (xy 297.305351 -275.183668) (xy 297.279048 -275.142072)
			(xy 297.259757 -275.096796) (xy 297.24798 -275.049012) (xy 297.24402 -274.999958) (xy 296.926757 -274.999958)
			(xy 296.926258 -275.025412) (xy 296.918215 -275.076194) (xy 296.902327 -275.125093) (xy 296.878984 -275.170905)
			(xy 296.848763 -275.212501) (xy 296.812407 -275.248857) (xy 296.770811 -275.279078) (xy 296.724999 -275.302421)
			(xy 296.6761 -275.318309) (xy 296.625318 -275.326352) (xy 296.573902 -275.326352) (xy 296.52312 -275.318309)
			(xy 296.474221 -275.302421) (xy 296.428409 -275.279078) (xy 296.386813 -275.248857) (xy 296.350457 -275.212501)
			(xy 296.320236 -275.170905) (xy 296.296893 -275.125093) (xy 296.281005 -275.076194) (xy 296.272962 -275.025412)
			(xy 295.954579 -275.025412) (xy 295.946822 -275.073142) (xy 295.931238 -275.119823) (xy 295.908367 -275.1634)
			(xy 295.878802 -275.202744) (xy 295.843309 -275.236836) (xy 295.802806 -275.264792) (xy 295.758344 -275.28589)
			(xy 295.711073 -275.299582) (xy 295.662218 -275.305514) (xy 295.613043 -275.303533) (xy 295.564824 -275.293689)
			(xy 295.518808 -275.276237) (xy 295.476187 -275.25163) (xy 295.438066 -275.220505) (xy 295.405431 -275.183668)
			(xy 295.379128 -275.142072) (xy 295.359837 -275.096796) (xy 295.34806 -275.049012) (xy 295.3441 -274.999958)
			(xy 295.026588 -274.999958) (xy 295.026084 -275.025666) (xy 295.018041 -275.076448) (xy 295.002153 -275.125347)
			(xy 294.97881 -275.171159) (xy 294.948589 -275.212755) (xy 294.912233 -275.249111) (xy 294.870637 -275.279332)
			(xy 294.824825 -275.302675) (xy 294.775926 -275.318563) (xy 294.725144 -275.326606) (xy 294.673728 -275.326606)
			(xy 294.622946 -275.318563) (xy 294.574047 -275.302675) (xy 294.528235 -275.279332) (xy 294.486639 -275.249111)
			(xy 294.450283 -275.212755) (xy 294.420062 -275.171159) (xy 294.396719 -275.125347) (xy 294.380831 -275.076448)
			(xy 294.372788 -275.025666) (xy 294.054364 -275.025666) (xy 294.046648 -275.073142) (xy 294.031064 -275.119823)
			(xy 294.008193 -275.1634) (xy 293.978628 -275.202744) (xy 293.943135 -275.236836) (xy 293.902632 -275.264792)
			(xy 293.85817 -275.28589) (xy 293.810899 -275.299582) (xy 293.762044 -275.305514) (xy 293.712869 -275.303533)
			(xy 293.66465 -275.293689) (xy 293.618634 -275.276237) (xy 293.576013 -275.25163) (xy 293.537892 -275.220505)
			(xy 293.505257 -275.183668) (xy 293.478954 -275.142072) (xy 293.459663 -275.096796) (xy 293.447886 -275.049012)
			(xy 293.443926 -274.999958) (xy 293.126663 -274.999958) (xy 293.126164 -275.025412) (xy 293.118121 -275.076194)
			(xy 293.102233 -275.125093) (xy 293.07889 -275.170905) (xy 293.048669 -275.212501) (xy 293.012313 -275.248857)
			(xy 292.970717 -275.279078) (xy 292.924905 -275.302421) (xy 292.876006 -275.318309) (xy 292.825224 -275.326352)
			(xy 292.773808 -275.326352) (xy 292.723026 -275.318309) (xy 292.674127 -275.302421) (xy 292.628315 -275.279078)
			(xy 292.586719 -275.248857) (xy 292.550363 -275.212501) (xy 292.520142 -275.170905) (xy 292.496799 -275.125093)
			(xy 292.480911 -275.076194) (xy 292.472868 -275.025412) (xy 292.154485 -275.025412) (xy 292.146728 -275.073142)
			(xy 292.131144 -275.119823) (xy 292.108273 -275.1634) (xy 292.078708 -275.202744) (xy 292.043215 -275.236836)
			(xy 292.002712 -275.264792) (xy 291.95825 -275.28589) (xy 291.910979 -275.299582) (xy 291.862124 -275.305514)
			(xy 291.812949 -275.303533) (xy 291.76473 -275.293689) (xy 291.718714 -275.276237) (xy 291.676093 -275.25163)
			(xy 291.637972 -275.220505) (xy 291.605337 -275.183668) (xy 291.579034 -275.142072) (xy 291.559743 -275.096796)
			(xy 291.547966 -275.049012) (xy 291.544006 -274.999958) (xy 291.227002 -274.999958) (xy 291.226498 -275.025666)
			(xy 291.218455 -275.076448) (xy 291.202567 -275.125347) (xy 291.179224 -275.171159) (xy 291.149003 -275.212755)
			(xy 291.112647 -275.249111) (xy 291.071051 -275.279332) (xy 291.025239 -275.302675) (xy 290.97634 -275.318563)
			(xy 290.925558 -275.326606) (xy 290.874142 -275.326606) (xy 290.82336 -275.318563) (xy 290.774461 -275.302675)
			(xy 290.728649 -275.279332) (xy 290.687053 -275.249111) (xy 290.650697 -275.212755) (xy 290.620476 -275.171159)
			(xy 290.597133 -275.125347) (xy 290.581245 -275.076448) (xy 290.573202 -275.025666) (xy 290.254524 -275.025666)
			(xy 290.246808 -275.073142) (xy 290.231224 -275.119823) (xy 290.208353 -275.1634) (xy 290.178788 -275.202744)
			(xy 290.143295 -275.236836) (xy 290.102792 -275.264792) (xy 290.05833 -275.28589) (xy 290.011059 -275.299582)
			(xy 289.962204 -275.305514) (xy 289.913029 -275.303533) (xy 289.86481 -275.293689) (xy 289.818794 -275.276237)
			(xy 289.776173 -275.25163) (xy 289.738052 -275.220505) (xy 289.705417 -275.183668) (xy 289.679114 -275.142072)
			(xy 289.659823 -275.096796) (xy 289.648046 -275.049012) (xy 289.644086 -274.999958) (xy 289.327082 -274.999958)
			(xy 289.326578 -275.025666) (xy 289.318535 -275.076448) (xy 289.302647 -275.125347) (xy 289.279304 -275.171159)
			(xy 289.249083 -275.212755) (xy 289.212727 -275.249111) (xy 289.171131 -275.279332) (xy 289.125319 -275.302675)
			(xy 289.07642 -275.318563) (xy 289.025638 -275.326606) (xy 288.974222 -275.326606) (xy 288.92344 -275.318563)
			(xy 288.874541 -275.302675) (xy 288.828729 -275.279332) (xy 288.787133 -275.249111) (xy 288.750777 -275.212755)
			(xy 288.720556 -275.171159) (xy 288.697213 -275.125347) (xy 288.681325 -275.076448) (xy 288.673282 -275.025666)
			(xy 288.35435 -275.025666) (xy 288.346634 -275.073142) (xy 288.33105 -275.119823) (xy 288.308179 -275.1634)
			(xy 288.278614 -275.202744) (xy 288.243121 -275.236836) (xy 288.202618 -275.264792) (xy 288.158156 -275.28589)
			(xy 288.110885 -275.299582) (xy 288.06203 -275.305514) (xy 288.012855 -275.303533) (xy 287.964636 -275.293689)
			(xy 287.91862 -275.276237) (xy 287.875999 -275.25163) (xy 287.837878 -275.220505) (xy 287.805243 -275.183668)
			(xy 287.77894 -275.142072) (xy 287.759649 -275.096796) (xy 287.747872 -275.049012) (xy 287.743912 -274.999958)
			(xy 287.426908 -274.999958) (xy 287.426404 -275.025666) (xy 287.418361 -275.076448) (xy 287.402473 -275.125347)
			(xy 287.37913 -275.171159) (xy 287.348909 -275.212755) (xy 287.312553 -275.249111) (xy 287.270957 -275.279332)
			(xy 287.225145 -275.302675) (xy 287.176246 -275.318563) (xy 287.125464 -275.326606) (xy 287.074048 -275.326606)
			(xy 287.023266 -275.318563) (xy 286.974367 -275.302675) (xy 286.928555 -275.279332) (xy 286.886959 -275.249111)
			(xy 286.850603 -275.212755) (xy 286.820382 -275.171159) (xy 286.797039 -275.125347) (xy 286.781151 -275.076448)
			(xy 286.773108 -275.025666) (xy 286.45443 -275.025666) (xy 286.446714 -275.073142) (xy 286.43113 -275.119823)
			(xy 286.408259 -275.1634) (xy 286.378694 -275.202744) (xy 286.343201 -275.236836) (xy 286.302698 -275.264792)
			(xy 286.258236 -275.28589) (xy 286.210965 -275.299582) (xy 286.16211 -275.305514) (xy 286.112935 -275.303533)
			(xy 286.064716 -275.293689) (xy 286.0187 -275.276237) (xy 285.976079 -275.25163) (xy 285.937958 -275.220505)
			(xy 285.905323 -275.183668) (xy 285.87902 -275.142072) (xy 285.859729 -275.096796) (xy 285.847952 -275.049012)
			(xy 285.843992 -274.999958) (xy 285.526988 -274.999958) (xy 285.526484 -275.025666) (xy 285.518441 -275.076448)
			(xy 285.502553 -275.125347) (xy 285.47921 -275.171159) (xy 285.448989 -275.212755) (xy 285.412633 -275.249111)
			(xy 285.371037 -275.279332) (xy 285.325225 -275.302675) (xy 285.276326 -275.318563) (xy 285.225544 -275.326606)
			(xy 285.174128 -275.326606) (xy 285.123346 -275.318563) (xy 285.074447 -275.302675) (xy 285.028635 -275.279332)
			(xy 284.987039 -275.249111) (xy 284.950683 -275.212755) (xy 284.920462 -275.171159) (xy 284.897119 -275.125347)
			(xy 284.881231 -275.076448) (xy 284.873188 -275.025666) (xy 284.55451 -275.025666) (xy 284.546794 -275.073142)
			(xy 284.53121 -275.119823) (xy 284.508339 -275.1634) (xy 284.478774 -275.202744) (xy 284.443281 -275.236836)
			(xy 284.402778 -275.264792) (xy 284.358316 -275.28589) (xy 284.311045 -275.299582) (xy 284.26219 -275.305514)
			(xy 284.213015 -275.303533) (xy 284.164796 -275.293689) (xy 284.11878 -275.276237) (xy 284.076159 -275.25163)
			(xy 284.038038 -275.220505) (xy 284.005403 -275.183668) (xy 283.9791 -275.142072) (xy 283.959809 -275.096796)
			(xy 283.948032 -275.049012) (xy 283.944072 -274.999958) (xy 283.627068 -274.999958) (xy 283.626564 -275.025666)
			(xy 283.618521 -275.076448) (xy 283.602633 -275.125347) (xy 283.57929 -275.171159) (xy 283.549069 -275.212755)
			(xy 283.512713 -275.249111) (xy 283.471117 -275.279332) (xy 283.425305 -275.302675) (xy 283.376406 -275.318563)
			(xy 283.325624 -275.326606) (xy 283.274208 -275.326606) (xy 283.223426 -275.318563) (xy 283.174527 -275.302675)
			(xy 283.128715 -275.279332) (xy 283.087119 -275.249111) (xy 283.050763 -275.212755) (xy 283.020542 -275.171159)
			(xy 282.997199 -275.125347) (xy 282.981311 -275.076448) (xy 282.973268 -275.025666) (xy 282.654336 -275.025666)
			(xy 282.64662 -275.073142) (xy 282.631036 -275.119823) (xy 282.608165 -275.1634) (xy 282.5786 -275.202744)
			(xy 282.543107 -275.236836) (xy 282.502604 -275.264792) (xy 282.458142 -275.28589) (xy 282.410871 -275.299582)
			(xy 282.362016 -275.305514) (xy 282.312841 -275.303533) (xy 282.264622 -275.293689) (xy 282.218606 -275.276237)
			(xy 282.175985 -275.25163) (xy 282.137864 -275.220505) (xy 282.105229 -275.183668) (xy 282.078926 -275.142072)
			(xy 282.059635 -275.096796) (xy 282.047858 -275.049012) (xy 282.043898 -274.999958) (xy 281.726894 -274.999958)
			(xy 281.72639 -275.025666) (xy 281.718347 -275.076448) (xy 281.702459 -275.125347) (xy 281.679116 -275.171159)
			(xy 281.648895 -275.212755) (xy 281.612539 -275.249111) (xy 281.570943 -275.279332) (xy 281.525131 -275.302675)
			(xy 281.476232 -275.318563) (xy 281.42545 -275.326606) (xy 281.374034 -275.326606) (xy 281.323252 -275.318563)
			(xy 281.274353 -275.302675) (xy 281.228541 -275.279332) (xy 281.186945 -275.249111) (xy 281.150589 -275.212755)
			(xy 281.120368 -275.171159) (xy 281.097025 -275.125347) (xy 281.081137 -275.076448) (xy 281.073094 -275.025666)
			(xy 280.754416 -275.025666) (xy 280.7467 -275.073142) (xy 280.731116 -275.119823) (xy 280.708245 -275.1634)
			(xy 280.67868 -275.202744) (xy 280.643187 -275.236836) (xy 280.602684 -275.264792) (xy 280.558222 -275.28589)
			(xy 280.510951 -275.299582) (xy 280.462096 -275.305514) (xy 280.412921 -275.303533) (xy 280.364702 -275.293689)
			(xy 280.318686 -275.276237) (xy 280.276065 -275.25163) (xy 280.237944 -275.220505) (xy 280.205309 -275.183668)
			(xy 280.179006 -275.142072) (xy 280.159715 -275.096796) (xy 280.147938 -275.049012) (xy 280.143978 -274.999958)
			(xy 279.826974 -274.999958) (xy 279.82647 -275.025666) (xy 279.818427 -275.076448) (xy 279.802539 -275.125347)
			(xy 279.779196 -275.171159) (xy 279.748975 -275.212755) (xy 279.712619 -275.249111) (xy 279.671023 -275.279332)
			(xy 279.625211 -275.302675) (xy 279.576312 -275.318563) (xy 279.52553 -275.326606) (xy 279.474114 -275.326606)
			(xy 279.423332 -275.318563) (xy 279.374433 -275.302675) (xy 279.328621 -275.279332) (xy 279.287025 -275.249111)
			(xy 279.250669 -275.212755) (xy 279.220448 -275.171159) (xy 279.197105 -275.125347) (xy 279.181217 -275.076448)
			(xy 279.173174 -275.025666) (xy 278.854496 -275.025666) (xy 278.84678 -275.073142) (xy 278.831196 -275.119823)
			(xy 278.808325 -275.1634) (xy 278.77876 -275.202744) (xy 278.743267 -275.236836) (xy 278.702764 -275.264792)
			(xy 278.658302 -275.28589) (xy 278.611031 -275.299582) (xy 278.562176 -275.305514) (xy 278.513001 -275.303533)
			(xy 278.464782 -275.293689) (xy 278.418766 -275.276237) (xy 278.376145 -275.25163) (xy 278.338024 -275.220505)
			(xy 278.305389 -275.183668) (xy 278.279086 -275.142072) (xy 278.259795 -275.096796) (xy 278.248018 -275.049012)
			(xy 278.244058 -274.999958) (xy 277.927054 -274.999958) (xy 277.92655 -275.025666) (xy 277.918507 -275.076448)
			(xy 277.902619 -275.125347) (xy 277.879276 -275.171159) (xy 277.849055 -275.212755) (xy 277.812699 -275.249111)
			(xy 277.771103 -275.279332) (xy 277.725291 -275.302675) (xy 277.676392 -275.318563) (xy 277.62561 -275.326606)
			(xy 277.574194 -275.326606) (xy 277.523412 -275.318563) (xy 277.474513 -275.302675) (xy 277.428701 -275.279332)
			(xy 277.387105 -275.249111) (xy 277.350749 -275.212755) (xy 277.320528 -275.171159) (xy 277.297185 -275.125347)
			(xy 277.281297 -275.076448) (xy 277.273254 -275.025666) (xy 276.954322 -275.025666) (xy 276.946606 -275.073142)
			(xy 276.931022 -275.119823) (xy 276.908151 -275.1634) (xy 276.878586 -275.202744) (xy 276.843093 -275.236836)
			(xy 276.80259 -275.264792) (xy 276.758128 -275.28589) (xy 276.710857 -275.299582) (xy 276.662002 -275.305514)
			(xy 276.612827 -275.303533) (xy 276.564608 -275.293689) (xy 276.518592 -275.276237) (xy 276.475971 -275.25163)
			(xy 276.43785 -275.220505) (xy 276.405215 -275.183668) (xy 276.378912 -275.142072) (xy 276.359621 -275.096796)
			(xy 276.347844 -275.049012) (xy 276.343884 -274.999958) (xy 264.249322 -274.999958) (xy 264.225402 -275.014431)
			(xy 264.054476 -275.10849) (xy 263.879833 -275.195452) (xy 263.701767 -275.27517) (xy 263.520579 -275.347511)
			(xy 263.336573 -275.412352) (xy 263.15006 -275.469584) (xy 263.12966 -275.474938) (xy 268.26897 -275.474938)
			(xy 268.27293 -275.425884) (xy 268.284707 -275.3781) (xy 268.303998 -275.332824) (xy 268.330301 -275.291228)
			(xy 268.362936 -275.254391) (xy 268.401057 -275.223266) (xy 268.443678 -275.198659) (xy 268.489694 -275.181207)
			(xy 268.537913 -275.171363) (xy 268.587088 -275.169382) (xy 268.635943 -275.175314) (xy 268.683214 -275.189006)
			(xy 268.727676 -275.210104) (xy 268.768179 -275.23806) (xy 268.803672 -275.272152) (xy 268.833237 -275.311496)
			(xy 268.856108 -275.355073) (xy 268.871692 -275.401754) (xy 268.879587 -275.450331) (xy 268.880082 -275.474938)
			(xy 269.21893 -275.474938) (xy 269.22289 -275.425884) (xy 269.234667 -275.3781) (xy 269.253958 -275.332824)
			(xy 269.280261 -275.291228) (xy 269.312896 -275.254391) (xy 269.351017 -275.223266) (xy 269.393638 -275.198659)
			(xy 269.439654 -275.181207) (xy 269.487873 -275.171363) (xy 269.537048 -275.169382) (xy 269.585903 -275.175314)
			(xy 269.633174 -275.189006) (xy 269.677636 -275.210104) (xy 269.718139 -275.23806) (xy 269.753632 -275.272152)
			(xy 269.783197 -275.311496) (xy 269.806068 -275.355073) (xy 269.821652 -275.401754) (xy 269.829547 -275.450331)
			(xy 269.830042 -275.474938) (xy 270.169144 -275.474938) (xy 270.173104 -275.425884) (xy 270.184881 -275.3781)
			(xy 270.204172 -275.332824) (xy 270.230475 -275.291228) (xy 270.26311 -275.254391) (xy 270.301231 -275.223266)
			(xy 270.343852 -275.198659) (xy 270.389868 -275.181207) (xy 270.438087 -275.171363) (xy 270.487262 -275.169382)
			(xy 270.536117 -275.175314) (xy 270.583388 -275.189006) (xy 270.62785 -275.210104) (xy 270.668353 -275.23806)
			(xy 270.703846 -275.272152) (xy 270.733411 -275.311496) (xy 270.756282 -275.355073) (xy 270.771866 -275.401754)
			(xy 270.779761 -275.450331) (xy 270.780256 -275.474938) (xy 271.119104 -275.474938) (xy 271.123064 -275.425884)
			(xy 271.134841 -275.3781) (xy 271.154132 -275.332824) (xy 271.180435 -275.291228) (xy 271.21307 -275.254391)
			(xy 271.251191 -275.223266) (xy 271.293812 -275.198659) (xy 271.339828 -275.181207) (xy 271.388047 -275.171363)
			(xy 271.437222 -275.169382) (xy 271.486077 -275.175314) (xy 271.533348 -275.189006) (xy 271.57781 -275.210104)
			(xy 271.618313 -275.23806) (xy 271.653806 -275.272152) (xy 271.683371 -275.311496) (xy 271.706242 -275.355073)
			(xy 271.721826 -275.401754) (xy 271.729721 -275.450331) (xy 271.730216 -275.474938) (xy 272.069064 -275.474938)
			(xy 272.073024 -275.425884) (xy 272.084801 -275.3781) (xy 272.104092 -275.332824) (xy 272.130395 -275.291228)
			(xy 272.16303 -275.254391) (xy 272.201151 -275.223266) (xy 272.243772 -275.198659) (xy 272.289788 -275.181207)
			(xy 272.338007 -275.171363) (xy 272.387182 -275.169382) (xy 272.436037 -275.175314) (xy 272.483308 -275.189006)
			(xy 272.52777 -275.210104) (xy 272.568273 -275.23806) (xy 272.603766 -275.272152) (xy 272.633331 -275.311496)
			(xy 272.656202 -275.355073) (xy 272.671786 -275.401754) (xy 272.679681 -275.450331) (xy 272.680176 -275.474938)
			(xy 273.019024 -275.474938) (xy 273.022984 -275.425884) (xy 273.034761 -275.3781) (xy 273.054052 -275.332824)
			(xy 273.080355 -275.291228) (xy 273.11299 -275.254391) (xy 273.151111 -275.223266) (xy 273.193732 -275.198659)
			(xy 273.239748 -275.181207) (xy 273.287967 -275.171363) (xy 273.337142 -275.169382) (xy 273.385997 -275.175314)
			(xy 273.433268 -275.189006) (xy 273.47773 -275.210104) (xy 273.518233 -275.23806) (xy 273.553726 -275.272152)
			(xy 273.583291 -275.311496) (xy 273.606162 -275.355073) (xy 273.621746 -275.401754) (xy 273.629641 -275.450331)
			(xy 273.630136 -275.474938) (xy 273.968984 -275.474938) (xy 273.972944 -275.425884) (xy 273.984721 -275.3781)
			(xy 274.004012 -275.332824) (xy 274.030315 -275.291228) (xy 274.06295 -275.254391) (xy 274.101071 -275.223266)
			(xy 274.143692 -275.198659) (xy 274.189708 -275.181207) (xy 274.237927 -275.171363) (xy 274.287102 -275.169382)
			(xy 274.335957 -275.175314) (xy 274.383228 -275.189006) (xy 274.42769 -275.210104) (xy 274.468193 -275.23806)
			(xy 274.503686 -275.272152) (xy 274.533251 -275.311496) (xy 274.556122 -275.355073) (xy 274.571706 -275.401754)
			(xy 274.579601 -275.450331) (xy 274.580096 -275.474938) (xy 274.918944 -275.474938) (xy 274.922904 -275.425884)
			(xy 274.934681 -275.3781) (xy 274.953972 -275.332824) (xy 274.980275 -275.291228) (xy 275.01291 -275.254391)
			(xy 275.051031 -275.223266) (xy 275.093652 -275.198659) (xy 275.139668 -275.181207) (xy 275.187887 -275.171363)
			(xy 275.237062 -275.169382) (xy 275.285917 -275.175314) (xy 275.333188 -275.189006) (xy 275.37765 -275.210104)
			(xy 275.418153 -275.23806) (xy 275.453646 -275.272152) (xy 275.483211 -275.311496) (xy 275.506082 -275.355073)
			(xy 275.521666 -275.401754) (xy 275.529561 -275.450331) (xy 275.530056 -275.474938) (xy 275.529561 -275.499545)
			(xy 275.521666 -275.548122) (xy 275.506082 -275.594803) (xy 275.483211 -275.63838) (xy 275.453646 -275.677724)
			(xy 275.418153 -275.711816) (xy 275.37765 -275.739772) (xy 275.333188 -275.76087) (xy 275.285917 -275.774562)
			(xy 275.237062 -275.780494) (xy 275.187887 -275.778513) (xy 275.139668 -275.768669) (xy 275.093652 -275.751217)
			(xy 275.051031 -275.72661) (xy 275.01291 -275.695485) (xy 274.980275 -275.658648) (xy 274.953972 -275.617052)
			(xy 274.934681 -275.571776) (xy 274.922904 -275.523992) (xy 274.918944 -275.474938) (xy 274.580096 -275.474938)
			(xy 274.579601 -275.499545) (xy 274.571706 -275.548122) (xy 274.556122 -275.594803) (xy 274.533251 -275.63838)
			(xy 274.503686 -275.677724) (xy 274.468193 -275.711816) (xy 274.42769 -275.739772) (xy 274.383228 -275.76087)
			(xy 274.335957 -275.774562) (xy 274.287102 -275.780494) (xy 274.237927 -275.778513) (xy 274.189708 -275.768669)
			(xy 274.143692 -275.751217) (xy 274.101071 -275.72661) (xy 274.06295 -275.695485) (xy 274.030315 -275.658648)
			(xy 274.004012 -275.617052) (xy 273.984721 -275.571776) (xy 273.972944 -275.523992) (xy 273.968984 -275.474938)
			(xy 273.630136 -275.474938) (xy 273.629641 -275.499545) (xy 273.621746 -275.548122) (xy 273.606162 -275.594803)
			(xy 273.583291 -275.63838) (xy 273.553726 -275.677724) (xy 273.518233 -275.711816) (xy 273.47773 -275.739772)
			(xy 273.433268 -275.76087) (xy 273.385997 -275.774562) (xy 273.337142 -275.780494) (xy 273.287967 -275.778513)
			(xy 273.239748 -275.768669) (xy 273.193732 -275.751217) (xy 273.151111 -275.72661) (xy 273.11299 -275.695485)
			(xy 273.080355 -275.658648) (xy 273.054052 -275.617052) (xy 273.034761 -275.571776) (xy 273.022984 -275.523992)
			(xy 273.019024 -275.474938) (xy 272.680176 -275.474938) (xy 272.679681 -275.499545) (xy 272.671786 -275.548122)
			(xy 272.656202 -275.594803) (xy 272.633331 -275.63838) (xy 272.603766 -275.677724) (xy 272.568273 -275.711816)
			(xy 272.52777 -275.739772) (xy 272.483308 -275.76087) (xy 272.436037 -275.774562) (xy 272.387182 -275.780494)
			(xy 272.338007 -275.778513) (xy 272.289788 -275.768669) (xy 272.243772 -275.751217) (xy 272.201151 -275.72661)
			(xy 272.16303 -275.695485) (xy 272.130395 -275.658648) (xy 272.104092 -275.617052) (xy 272.084801 -275.571776)
			(xy 272.073024 -275.523992) (xy 272.069064 -275.474938) (xy 271.730216 -275.474938) (xy 271.729721 -275.499545)
			(xy 271.721826 -275.548122) (xy 271.706242 -275.594803) (xy 271.683371 -275.63838) (xy 271.653806 -275.677724)
			(xy 271.618313 -275.711816) (xy 271.57781 -275.739772) (xy 271.533348 -275.76087) (xy 271.486077 -275.774562)
			(xy 271.437222 -275.780494) (xy 271.388047 -275.778513) (xy 271.339828 -275.768669) (xy 271.293812 -275.751217)
			(xy 271.251191 -275.72661) (xy 271.21307 -275.695485) (xy 271.180435 -275.658648) (xy 271.154132 -275.617052)
			(xy 271.134841 -275.571776) (xy 271.123064 -275.523992) (xy 271.119104 -275.474938) (xy 270.780256 -275.474938)
			(xy 270.779761 -275.499545) (xy 270.771866 -275.548122) (xy 270.756282 -275.594803) (xy 270.733411 -275.63838)
			(xy 270.703846 -275.677724) (xy 270.668353 -275.711816) (xy 270.62785 -275.739772) (xy 270.583388 -275.76087)
			(xy 270.536117 -275.774562) (xy 270.487262 -275.780494) (xy 270.438087 -275.778513) (xy 270.389868 -275.768669)
			(xy 270.343852 -275.751217) (xy 270.301231 -275.72661) (xy 270.26311 -275.695485) (xy 270.230475 -275.658648)
			(xy 270.204172 -275.617052) (xy 270.184881 -275.571776) (xy 270.173104 -275.523992) (xy 270.169144 -275.474938)
			(xy 269.830042 -275.474938) (xy 269.829547 -275.499545) (xy 269.821652 -275.548122) (xy 269.806068 -275.594803)
			(xy 269.783197 -275.63838) (xy 269.753632 -275.677724) (xy 269.718139 -275.711816) (xy 269.677636 -275.739772)
			(xy 269.633174 -275.76087) (xy 269.585903 -275.774562) (xy 269.537048 -275.780494) (xy 269.487873 -275.778513)
			(xy 269.439654 -275.768669) (xy 269.393638 -275.751217) (xy 269.351017 -275.72661) (xy 269.312896 -275.695485)
			(xy 269.280261 -275.658648) (xy 269.253958 -275.617052) (xy 269.234667 -275.571776) (xy 269.22289 -275.523992)
			(xy 269.21893 -275.474938) (xy 268.880082 -275.474938) (xy 268.879587 -275.499545) (xy 268.871692 -275.548122)
			(xy 268.856108 -275.594803) (xy 268.833237 -275.63838) (xy 268.803672 -275.677724) (xy 268.768179 -275.711816)
			(xy 268.727676 -275.739772) (xy 268.683214 -275.76087) (xy 268.635943 -275.774562) (xy 268.587088 -275.780494)
			(xy 268.537913 -275.778513) (xy 268.489694 -275.768669) (xy 268.443678 -275.751217) (xy 268.401057 -275.72661)
			(xy 268.362936 -275.695485) (xy 268.330301 -275.658648) (xy 268.303998 -275.617052) (xy 268.284707 -275.571776)
			(xy 268.27293 -275.523992) (xy 268.26897 -275.474938) (xy 263.12966 -275.474938) (xy 262.961355 -275.519111)
			(xy 262.770776 -275.560848) (xy 262.578643 -275.594726) (xy 262.385282 -275.620688) (xy 262.191018 -275.638689)
			(xy 261.996179 -275.6487) (xy 261.801093 -275.650703) (xy 261.60609 -275.644695) (xy 261.411497 -275.630686)
			(xy 261.217644 -275.6087) (xy 261.024857 -275.578774) (xy 260.83346 -275.540958) (xy 260.643778 -275.495316)
			(xy 260.45613 -275.441926) (xy 260.270831 -275.380876) (xy 260.088196 -275.312271) (xy 259.908531 -275.236225)
			(xy 259.732139 -275.152867) (xy 259.559318 -275.062338) (xy 259.39036 -274.96479) (xy 259.225549 -274.860387)
			(xy 259.065163 -274.749307) (xy 258.909473 -274.631735) (xy 258.758741 -274.507871) (xy 258.613222 -274.377922)
			(xy 258.47316 -274.242109) (xy 258.338792 -274.10066) (xy 258.210345 -273.953814) (xy 258.088034 -273.801819)
			(xy 257.972067 -273.64493) (xy 257.862639 -273.483412) (xy 257.759934 -273.317538) (xy 257.664126 -273.147587)
			(xy 257.575375 -272.973846) (xy 257.493833 -272.796608) (xy 257.419636 -272.616172) (xy 257.352909 -272.432841)
			(xy 257.293765 -272.246926) (xy 257.242304 -272.058739) (xy 257.198612 -271.868599) (xy 257.162763 -271.676824)
			(xy 257.134818 -271.48374) (xy 257.114823 -271.289671) (xy 257.102813 -271.094945) (xy 257.098807 -270.89989)
			(xy 210.500214 -270.89989) (xy 210.499713 -270.997438) (xy 210.491704 -271.19237) (xy 210.475698 -271.386808)
			(xy 210.451723 -271.580426) (xy 210.419819 -271.772896) (xy 210.38004 -271.963893) (xy 210.332454 -272.153097)
			(xy 210.277139 -272.340187) (xy 210.214191 -272.524849) (xy 210.143714 -272.706771) (xy 210.09336 -272.822416)
			(xy 220.248988 -272.822416) (xy 220.249466 -272.795046) (xy 220.257282 -272.740868) (xy 220.272768 -272.688365)
			(xy 220.295607 -272.638618) (xy 220.325328 -272.59265) (xy 220.342968 -272.571718) (xy 220.349064 -272.564606)
			(xy 220.355414 -272.547588) (xy 220.355414 -272.462244) (xy 220.349064 -272.445226) (xy 220.342968 -272.438114)
			(xy 220.325317 -272.417192) (xy 220.295608 -272.371216) (xy 220.272775 -272.321466) (xy 220.257287 -272.268963)
			(xy 220.249461 -272.214786) (xy 220.248988 -272.187416) (xy 220.24947 -272.160164) (xy 220.257225 -272.106214)
			(xy 220.272579 -272.053916) (xy 220.295219 -272.004337) (xy 220.324685 -271.958484) (xy 220.360377 -271.917291)
			(xy 220.401568 -271.881597) (xy 220.447419 -271.852129) (xy 220.496998 -271.829486) (xy 220.549294 -271.814129)
			(xy 220.603244 -271.806372) (xy 220.630496 -271.805908) (xy 220.659235 -271.806432) (xy 220.716062 -271.815054)
			(xy 220.770953 -271.832104) (xy 220.822665 -271.857196) (xy 220.870027 -271.889761) (xy 220.891354 -271.909032)
			(xy 220.898466 -271.915636) (xy 220.915992 -271.922748) (xy 221.0054 -271.922748) (xy 221.022926 -271.915636)
			(xy 221.030038 -271.909032) (xy 221.051365 -271.889762) (xy 221.098728 -271.857197) (xy 221.150439 -271.832106)
			(xy 221.20533 -271.815056) (xy 221.262157 -271.806434) (xy 221.319635 -271.806434) (xy 221.376462 -271.815056)
			(xy 221.431353 -271.832106) (xy 221.483064 -271.857197) (xy 221.530427 -271.889762) (xy 221.551754 -271.909032)
			(xy 221.558866 -271.915636) (xy 221.576392 -271.922748) (xy 221.6658 -271.922748) (xy 221.683326 -271.915636)
			(xy 221.690438 -271.909032) (xy 221.711765 -271.889762) (xy 221.759128 -271.857197) (xy 221.810839 -271.832106)
			(xy 221.86573 -271.815056) (xy 221.922557 -271.806434) (xy 221.980035 -271.806434) (xy 222.036862 -271.815056)
			(xy 222.091753 -271.832106) (xy 222.143464 -271.857197) (xy 222.190827 -271.889762) (xy 222.212154 -271.909032)
			(xy 222.219266 -271.915636) (xy 222.236792 -271.922748) (xy 222.3262 -271.922748) (xy 222.343726 -271.915636)
			(xy 222.350838 -271.909032) (xy 222.372166 -271.889762) (xy 222.419528 -271.857196) (xy 222.471239 -271.832103)
			(xy 222.52613 -271.815053) (xy 222.582957 -271.806429) (xy 222.611696 -271.805908) (xy 222.638949 -271.806359)
			(xy 222.692902 -271.814116) (xy 222.745201 -271.829472) (xy 222.794782 -271.852115) (xy 222.840636 -271.881585)
			(xy 222.881829 -271.91728) (xy 222.917523 -271.958474) (xy 222.94699 -272.004329) (xy 222.969632 -272.053911)
			(xy 222.984987 -272.10621) (xy 222.992742 -272.160163) (xy 222.993204 -272.187416) (xy 222.992746 -272.214787)
			(xy 222.984926 -272.268966) (xy 222.969435 -272.321469) (xy 222.946592 -272.371216) (xy 222.916866 -272.417182)
			(xy 222.899224 -272.438114) (xy 222.893128 -272.445226) (xy 222.886778 -272.462244) (xy 222.886778 -272.547588)
			(xy 222.893128 -272.564606) (xy 222.899224 -272.571718) (xy 222.916842 -272.592667) (xy 222.946556 -272.638636)
			(xy 222.969396 -272.688379) (xy 222.984892 -272.740876) (xy 222.992726 -272.795048) (xy 222.993204 -272.822416)
			(xy 223.844358 -272.822416) (xy 223.844819 -272.795045) (xy 223.852636 -272.740866) (xy 223.868126 -272.688362)
			(xy 223.890969 -272.638615) (xy 223.920695 -272.592649) (xy 223.938338 -272.571718) (xy 223.944434 -272.564606)
			(xy 223.950784 -272.547588) (xy 223.950784 -272.462244) (xy 223.944434 -272.445226) (xy 223.938338 -272.438114)
			(xy 223.920698 -272.417183) (xy 223.890985 -272.37121) (xy 223.868149 -272.321463) (xy 223.852658 -272.268962)
			(xy 223.844831 -272.214785) (xy 223.844358 -272.187416) (xy 223.844893 -272.160167) (xy 223.852646 -272.106223)
			(xy 223.867998 -272.053931) (xy 223.890635 -272.004356) (xy 223.920096 -271.958507) (xy 223.955782 -271.917318)
			(xy 223.996967 -271.881626) (xy 224.042812 -271.852159) (xy 224.092384 -271.829515) (xy 224.144674 -271.814157)
			(xy 224.198617 -271.806397) (xy 224.225866 -271.805908) (xy 224.254607 -271.806389) (xy 224.311436 -271.815022)
			(xy 224.366327 -271.832082) (xy 224.418038 -271.857183) (xy 224.465399 -271.889757) (xy 224.486724 -271.909032)
			(xy 224.493836 -271.915636) (xy 224.511362 -271.922748) (xy 224.60077 -271.922748) (xy 224.618296 -271.915636)
			(xy 224.625408 -271.909032) (xy 224.646735 -271.889762) (xy 224.694098 -271.857197) (xy 224.745809 -271.832106)
			(xy 224.8007 -271.815056) (xy 224.857527 -271.806434) (xy 224.915005 -271.806434) (xy 224.971832 -271.815056)
			(xy 225.026723 -271.832106) (xy 225.078434 -271.857197) (xy 225.125797 -271.889762) (xy 225.147124 -271.909032)
			(xy 225.154236 -271.915636) (xy 225.171762 -271.922748) (xy 225.26117 -271.922748) (xy 225.278696 -271.915636)
			(xy 225.285808 -271.909032) (xy 225.307135 -271.889762) (xy 225.354498 -271.857197) (xy 225.406209 -271.832106)
			(xy 225.4611 -271.815056) (xy 225.517927 -271.806434) (xy 225.575405 -271.806434) (xy 225.632232 -271.815056)
			(xy 225.687123 -271.832106) (xy 225.738834 -271.857197) (xy 225.786197 -271.889762) (xy 225.807524 -271.909032)
			(xy 225.814636 -271.915636) (xy 225.832162 -271.922748) (xy 225.92157 -271.922748) (xy 225.939096 -271.915636)
			(xy 225.946208 -271.909032) (xy 225.967548 -271.889776) (xy 226.014907 -271.857208) (xy 226.066615 -271.832113)
			(xy 226.121503 -271.815059) (xy 226.178328 -271.806431) (xy 226.207066 -271.805908) (xy 226.234319 -271.806387)
			(xy 226.28827 -271.81414) (xy 226.340568 -271.829492) (xy 226.39015 -271.852132) (xy 226.436004 -271.881598)
			(xy 226.477197 -271.91729) (xy 226.512891 -271.958482) (xy 226.542359 -272.004335) (xy 226.565001 -272.053915)
			(xy 226.580356 -272.106212) (xy 226.588112 -272.160163) (xy 226.588574 -272.187416) (xy 226.588124 -272.214787)
			(xy 226.580303 -272.268967) (xy 226.564811 -272.32147) (xy 226.541965 -272.371217) (xy 226.512237 -272.417183)
			(xy 226.494594 -272.438114) (xy 226.488498 -272.445226) (xy 226.482148 -272.462244) (xy 226.482148 -272.547588)
			(xy 226.488498 -272.564606) (xy 226.494594 -272.571718) (xy 226.512207 -272.592671) (xy 226.541923 -272.638638)
			(xy 226.564764 -272.68838) (xy 226.580261 -272.740876) (xy 226.588096 -272.795048) (xy 226.588574 -272.822416)
			(xy 226.588273 -272.842228) (xy 236.419898 -272.842228) (xy 236.420381 -272.814858) (xy 236.428195 -272.76068)
			(xy 236.44368 -272.708177) (xy 236.466518 -272.65843) (xy 236.496239 -272.612462) (xy 236.513878 -272.59153)
			(xy 236.519974 -272.584418) (xy 236.526324 -272.5674) (xy 236.526324 -272.482056) (xy 236.519974 -272.465038)
			(xy 236.513878 -272.457926) (xy 236.496234 -272.436998) (xy 236.466524 -272.391024) (xy 236.443689 -272.341275)
			(xy 236.428199 -272.288774) (xy 236.420372 -272.234597) (xy 236.419898 -272.207228) (xy 236.420381 -272.179976)
			(xy 236.428135 -272.126025) (xy 236.443487 -272.073727) (xy 236.466127 -272.024147) (xy 236.495593 -271.978293)
			(xy 236.531284 -271.9371) (xy 236.572476 -271.901406) (xy 236.618327 -271.871938) (xy 236.667907 -271.849295)
			(xy 236.720204 -271.833939) (xy 236.774154 -271.826183) (xy 236.801406 -271.82572) (xy 236.830144 -271.826261)
			(xy 236.88697 -271.834883) (xy 236.941859 -271.85193) (xy 236.993571 -271.877017) (xy 237.040936 -271.909576)
			(xy 237.062264 -271.928844) (xy 237.069376 -271.935448) (xy 237.086902 -271.94256) (xy 237.17631 -271.94256)
			(xy 237.193836 -271.935448) (xy 237.200948 -271.928844) (xy 237.222275 -271.909574) (xy 237.269638 -271.877009)
			(xy 237.321349 -271.851918) (xy 237.37624 -271.834868) (xy 237.433067 -271.826246) (xy 237.490545 -271.826246)
			(xy 237.547372 -271.834868) (xy 237.602263 -271.851918) (xy 237.653974 -271.877009) (xy 237.701337 -271.909574)
			(xy 237.722664 -271.928844) (xy 237.729776 -271.935448) (xy 237.747302 -271.94256) (xy 237.83671 -271.94256)
			(xy 237.854236 -271.935448) (xy 237.861348 -271.928844) (xy 237.882675 -271.909574) (xy 237.930038 -271.877009)
			(xy 237.981749 -271.851918) (xy 238.03664 -271.834868) (xy 238.093467 -271.826246) (xy 238.150945 -271.826246)
			(xy 238.207772 -271.834868) (xy 238.262663 -271.851918) (xy 238.314374 -271.877009) (xy 238.361737 -271.909574)
			(xy 238.383064 -271.928844) (xy 238.390176 -271.935448) (xy 238.407702 -271.94256) (xy 238.49711 -271.94256)
			(xy 238.514636 -271.935448) (xy 238.521748 -271.928844) (xy 238.543073 -271.909571) (xy 238.590436 -271.877005)
			(xy 238.642148 -271.851913) (xy 238.697039 -271.834863) (xy 238.753867 -271.826241) (xy 238.782606 -271.82572)
			(xy 238.80986 -271.82615) (xy 238.863814 -271.833908) (xy 238.916114 -271.849267) (xy 238.965696 -271.871912)
			(xy 239.01155 -271.901383) (xy 239.052744 -271.93708) (xy 239.088437 -271.978277) (xy 239.117905 -272.024134)
			(xy 239.140545 -272.073718) (xy 239.155899 -272.126019) (xy 239.163653 -272.179974) (xy 239.164114 -272.207228)
			(xy 239.163661 -272.234599) (xy 239.155839 -272.288778) (xy 239.140347 -272.341281) (xy 239.117503 -272.391028)
			(xy 239.087776 -272.436994) (xy 239.070134 -272.457926) (xy 239.064038 -272.465038) (xy 239.057688 -272.482056)
			(xy 239.057688 -272.5674) (xy 239.064038 -272.584418) (xy 239.070134 -272.59153) (xy 239.087759 -272.612473)
			(xy 239.117472 -272.658444) (xy 239.14031 -272.708188) (xy 239.155804 -272.760686) (xy 239.163637 -272.81486)
			(xy 239.163769 -272.822416) (xy 240.094516 -272.822416) (xy 240.094988 -272.795046) (xy 240.102803 -272.740867)
			(xy 240.118291 -272.688364) (xy 240.141132 -272.638617) (xy 240.170855 -272.59265) (xy 240.188496 -272.571718)
			(xy 240.194592 -272.564606) (xy 240.200942 -272.547588) (xy 240.200942 -272.462244) (xy 240.194592 -272.445226)
			(xy 240.188496 -272.438114) (xy 240.170849 -272.417188) (xy 240.141139 -272.371213) (xy 240.118304 -272.321464)
			(xy 240.102815 -272.268962) (xy 240.094989 -272.214786) (xy 240.094516 -272.187416) (xy 240.09497 -272.160162)
			(xy 240.102726 -272.10621) (xy 240.118081 -272.05391) (xy 240.140723 -272.004329) (xy 240.170192 -271.958474)
			(xy 240.205887 -271.917281) (xy 240.247081 -271.881587) (xy 240.292936 -271.852119) (xy 240.342518 -271.829478)
			(xy 240.394818 -271.814124) (xy 240.44877 -271.80637) (xy 240.476024 -271.805908) (xy 240.504764 -271.806415)
			(xy 240.561592 -271.815041) (xy 240.616483 -271.832095) (xy 240.668194 -271.857191) (xy 240.715556 -271.889759)
			(xy 240.736882 -271.909032) (xy 240.743994 -271.915636) (xy 240.76152 -271.922748) (xy 240.850928 -271.922748)
			(xy 240.868454 -271.915636) (xy 240.875566 -271.909032) (xy 240.896893 -271.889762) (xy 240.944256 -271.857197)
			(xy 240.995967 -271.832106) (xy 241.050858 -271.815056) (xy 241.107685 -271.806434) (xy 241.165163 -271.806434)
			(xy 241.22199 -271.815056) (xy 241.276881 -271.832106) (xy 241.328592 -271.857197) (xy 241.375955 -271.889762)
			(xy 241.397282 -271.909032) (xy 241.404394 -271.915636) (xy 241.42192 -271.922748) (xy 241.511328 -271.922748)
			(xy 241.528854 -271.915636) (xy 241.535966 -271.909032) (xy 241.557293 -271.889762) (xy 241.604656 -271.857197)
			(xy 241.656367 -271.832106) (xy 241.711258 -271.815056) (xy 241.768085 -271.806434) (xy 241.825563 -271.806434)
			(xy 241.88239 -271.815056) (xy 241.937281 -271.832106) (xy 241.988992 -271.857197) (xy 242.036355 -271.889762)
			(xy 242.057682 -271.909032) (xy 242.064794 -271.915636) (xy 242.08232 -271.922748) (xy 242.171728 -271.922748)
			(xy 242.189254 -271.915636) (xy 242.196366 -271.909032) (xy 242.217682 -271.889749) (xy 242.265047 -271.857185)
			(xy 242.316762 -271.832095) (xy 242.371655 -271.815047) (xy 242.428484 -271.806427) (xy 242.457224 -271.805908)
			(xy 242.484477 -271.806356) (xy 242.538427 -271.814116) (xy 242.590723 -271.829475) (xy 242.640301 -271.85212)
			(xy 242.686152 -271.88159) (xy 242.727343 -271.917286) (xy 242.763034 -271.95848) (xy 242.792499 -272.004334)
			(xy 242.815139 -272.053915) (xy 242.830493 -272.106213) (xy 242.838247 -272.160163) (xy 242.838732 -272.187416)
			(xy 242.838292 -272.214787) (xy 242.83047 -272.268968) (xy 242.814976 -272.321472) (xy 242.792128 -272.371219)
			(xy 242.762397 -272.417184) (xy 242.744752 -272.438114) (xy 242.738656 -272.445226) (xy 242.732306 -272.462244)
			(xy 242.732306 -272.547588) (xy 242.738656 -272.564606) (xy 242.744752 -272.571718) (xy 242.762359 -272.592676)
			(xy 242.792077 -272.638641) (xy 242.81492 -272.688382) (xy 242.830418 -272.740877) (xy 242.838254 -272.795048)
			(xy 242.838732 -272.822416) (xy 242.838237 -272.849667) (xy 242.830479 -272.903613) (xy 242.815123 -272.955906)
			(xy 242.792482 -273.005482) (xy 242.763016 -273.051331) (xy 242.727326 -273.09252) (xy 242.686137 -273.128211)
			(xy 242.640289 -273.157678) (xy 242.590713 -273.18032) (xy 242.538421 -273.195677) (xy 242.484475 -273.203437)
			(xy 242.457224 -273.203924) (xy 242.428486 -273.203379) (xy 242.37166 -273.194761) (xy 242.31677 -273.177715)
			(xy 242.265057 -273.152629) (xy 242.217694 -273.120068) (xy 242.196366 -273.1008) (xy 242.189254 -273.094196)
			(xy 242.171728 -273.087084) (xy 242.08232 -273.087084) (xy 242.064794 -273.094196) (xy 242.057682 -273.1008)
			(xy 242.036355 -273.12007) (xy 241.988992 -273.152635) (xy 241.937281 -273.177726) (xy 241.88239 -273.194776)
			(xy 241.825563 -273.203398) (xy 241.768085 -273.203398) (xy 241.711258 -273.194776) (xy 241.656367 -273.177726)
			(xy 241.604656 -273.152635) (xy 241.557293 -273.12007) (xy 241.535966 -273.1008) (xy 241.528854 -273.094196)
			(xy 241.511328 -273.087084) (xy 241.42192 -273.087084) (xy 241.404394 -273.094196) (xy 241.397282 -273.1008)
			(xy 241.375955 -273.12007) (xy 241.328592 -273.152635) (xy 241.276881 -273.177726) (xy 241.22199 -273.194776)
			(xy 241.165163 -273.203398) (xy 241.107685 -273.203398) (xy 241.050858 -273.194776) (xy 240.995967 -273.177726)
			(xy 240.944256 -273.152635) (xy 240.896893 -273.12007) (xy 240.875566 -273.1008) (xy 240.868454 -273.094196)
			(xy 240.850928 -273.087084) (xy 240.76152 -273.087084) (xy 240.743994 -273.094196) (xy 240.736882 -273.1008)
			(xy 240.715536 -273.120049) (xy 240.66818 -273.15262) (xy 240.616473 -273.177718) (xy 240.561586 -273.194773)
			(xy 240.504762 -273.203401) (xy 240.476024 -273.203924) (xy 240.448772 -273.203422) (xy 240.394824 -273.195669)
			(xy 240.342528 -273.180317) (xy 240.292949 -273.157678) (xy 240.247096 -273.128214) (xy 240.205904 -273.092525)
			(xy 240.17021 -273.051336) (xy 240.140741 -273.005487) (xy 240.118097 -272.95591) (xy 240.102739 -272.903615)
			(xy 240.09498 -272.849667) (xy 240.094516 -272.822416) (xy 239.163769 -272.822416) (xy 239.164114 -272.842228)
			(xy 239.163648 -272.86948) (xy 239.155888 -272.923428) (xy 239.14053 -272.975723) (xy 239.117886 -273.025299)
			(xy 239.088417 -273.071149) (xy 239.052724 -273.112339) (xy 239.011532 -273.14803) (xy 238.96568 -273.177496)
			(xy 238.916102 -273.200137) (xy 238.863806 -273.215493) (xy 238.809858 -273.22325) (xy 238.782606 -273.223736)
			(xy 238.753868 -273.223199) (xy 238.697041 -273.214578) (xy 238.642151 -273.197531) (xy 238.590439 -273.172442)
			(xy 238.543076 -273.139881) (xy 238.521748 -273.120612) (xy 238.514636 -273.114008) (xy 238.49711 -273.106896)
			(xy 238.407702 -273.106896) (xy 238.390176 -273.114008) (xy 238.383064 -273.120612) (xy 238.361737 -273.139882)
			(xy 238.314374 -273.172447) (xy 238.262663 -273.197538) (xy 238.207772 -273.214588) (xy 238.150945 -273.22321)
			(xy 238.093467 -273.22321) (xy 238.03664 -273.214588) (xy 237.981749 -273.197538) (xy 237.930038 -273.172447)
			(xy 237.882675 -273.139882) (xy 237.861348 -273.120612) (xy 237.854236 -273.114008) (xy 237.83671 -273.106896)
			(xy 237.747302 -273.106896) (xy 237.729776 -273.114008) (xy 237.722664 -273.120612) (xy 237.701337 -273.139882)
			(xy 237.653974 -273.172447) (xy 237.602263 -273.197538) (xy 237.547372 -273.214588) (xy 237.490545 -273.22321)
			(xy 237.433067 -273.22321) (xy 237.37624 -273.214588) (xy 237.321349 -273.197538) (xy 237.269638 -273.172447)
			(xy 237.222275 -273.139882) (xy 237.200948 -273.120612) (xy 237.193836 -273.114008) (xy 237.17631 -273.106896)
			(xy 237.086902 -273.106896) (xy 237.069376 -273.114008) (xy 237.062264 -273.120612) (xy 237.040927 -273.139872)
			(xy 236.993569 -273.172441) (xy 236.94186 -273.197537) (xy 236.886971 -273.21459) (xy 236.830144 -273.223214)
			(xy 236.801406 -273.223736) (xy 236.774156 -273.223217) (xy 236.720211 -273.215462) (xy 236.667919 -273.200109)
			(xy 236.618343 -273.17747) (xy 236.572494 -273.148007) (xy 236.531305 -273.112319) (xy 236.495613 -273.071133)
			(xy 236.466146 -273.025287) (xy 236.443503 -272.975713) (xy 236.428145 -272.923422) (xy 236.420386 -272.869478)
			(xy 236.419898 -272.842228) (xy 226.588273 -272.842228) (xy 226.58816 -272.849671) (xy 226.5804 -272.903625)
			(xy 226.56504 -272.955926) (xy 226.542393 -273.005509) (xy 226.51292 -273.051363) (xy 226.477221 -273.092557)
			(xy 226.436023 -273.12825) (xy 226.390165 -273.157717) (xy 226.340579 -273.180358) (xy 226.288276 -273.195711)
			(xy 226.234321 -273.203463) (xy 226.207066 -273.203924) (xy 226.178327 -273.203415) (xy 226.121499 -273.194787)
			(xy 226.066608 -273.177734) (xy 226.014897 -273.152639) (xy 225.967535 -273.120072) (xy 225.946208 -273.1008)
			(xy 225.939096 -273.094196) (xy 225.92157 -273.087084) (xy 225.832162 -273.087084) (xy 225.814636 -273.094196)
			(xy 225.807524 -273.1008) (xy 225.786197 -273.12007) (xy 225.738834 -273.152635) (xy 225.687123 -273.177726)
			(xy 225.632232 -273.194776) (xy 225.575405 -273.203398) (xy 225.517927 -273.203398) (xy 225.4611 -273.194776)
			(xy 225.406209 -273.177726) (xy 225.354498 -273.152635) (xy 225.307135 -273.12007) (xy 225.285808 -273.1008)
			(xy 225.278696 -273.094196) (xy 225.26117 -273.087084) (xy 225.171762 -273.087084) (xy 225.154236 -273.094196)
			(xy 225.147124 -273.1008) (xy 225.125797 -273.12007) (xy 225.078434 -273.152635) (xy 225.026723 -273.177726)
			(xy 224.971832 -273.194776) (xy 224.915005 -273.203398) (xy 224.857527 -273.203398) (xy 224.8007 -273.194776)
			(xy 224.745809 -273.177726) (xy 224.694098 -273.152635) (xy 224.646735 -273.12007) (xy 224.625408 -273.1008)
			(xy 224.618296 -273.094196) (xy 224.60077 -273.087084) (xy 224.511362 -273.087084) (xy 224.493836 -273.094196)
			(xy 224.486724 -273.1008) (xy 224.465401 -273.120076) (xy 224.418039 -273.152644) (xy 224.366327 -273.177736)
			(xy 224.311434 -273.194785) (xy 224.254606 -273.203405) (xy 224.225866 -273.203924) (xy 224.198615 -273.203454)
			(xy 224.144667 -273.195693) (xy 224.092373 -273.180335) (xy 224.042797 -273.157691) (xy 223.996947 -273.128222)
			(xy 223.955758 -273.092529) (xy 223.920067 -273.051338) (xy 223.890601 -273.005487) (xy 223.867959 -272.95591)
			(xy 223.852603 -272.903615) (xy 223.844845 -272.849667) (xy 223.844358 -272.822416) (xy 222.993204 -272.822416)
			(xy 222.992737 -272.849668) (xy 222.984978 -272.903616) (xy 222.969621 -272.955912) (xy 222.946978 -273.005489)
			(xy 222.917509 -273.05134) (xy 222.881816 -273.09253) (xy 222.840624 -273.128221) (xy 222.794772 -273.157687)
			(xy 222.745193 -273.180328) (xy 222.692897 -273.195683) (xy 222.638948 -273.203439) (xy 222.611696 -273.203924)
			(xy 222.582957 -273.203396) (xy 222.52613 -273.194774) (xy 222.47124 -273.177724) (xy 222.419528 -273.152634)
			(xy 222.372165 -273.12007) (xy 222.350838 -273.1008) (xy 222.343726 -273.094196) (xy 222.3262 -273.087084)
			(xy 222.236792 -273.087084) (xy 222.219266 -273.094196) (xy 222.212154 -273.1008) (xy 222.190827 -273.12007)
			(xy 222.143464 -273.152635) (xy 222.091753 -273.177726) (xy 222.036862 -273.194776) (xy 221.980035 -273.203398)
			(xy 221.922557 -273.203398) (xy 221.86573 -273.194776) (xy 221.810839 -273.177726) (xy 221.759128 -273.152635)
			(xy 221.711765 -273.12007) (xy 221.690438 -273.1008) (xy 221.683326 -273.094196) (xy 221.6658 -273.087084)
			(xy 221.576392 -273.087084) (xy 221.558866 -273.094196) (xy 221.551754 -273.1008) (xy 221.530427 -273.12007)
			(xy 221.483064 -273.152635) (xy 221.431353 -273.177726) (xy 221.376462 -273.194776) (xy 221.319635 -273.203398)
			(xy 221.262157 -273.203398) (xy 221.20533 -273.194776) (xy 221.150439 -273.177726) (xy 221.098728 -273.152635)
			(xy 221.051365 -273.12007) (xy 221.030038 -273.1008) (xy 221.022926 -273.094196) (xy 221.0054 -273.087084)
			(xy 220.915992 -273.087084) (xy 220.898466 -273.094196) (xy 220.891354 -273.1008) (xy 220.870019 -273.120062)
			(xy 220.82266 -273.152632) (xy 220.770951 -273.177727) (xy 220.716061 -273.194779) (xy 220.659235 -273.203403)
			(xy 220.630496 -273.203924) (xy 220.603245 -273.203426) (xy 220.549299 -273.195669) (xy 220.497005 -273.180315)
			(xy 220.447429 -273.157674) (xy 220.40158 -273.128209) (xy 220.36039 -273.092519) (xy 220.324698 -273.05133)
			(xy 220.295232 -273.005481) (xy 220.27259 -272.955906) (xy 220.257233 -272.903613) (xy 220.249475 -272.849667)
			(xy 220.248988 -272.822416) (xy 210.09336 -272.822416) (xy 210.065828 -272.885646) (xy 209.980663 -273.061172)
			(xy 209.888365 -273.233055) (xy 209.789087 -273.401002) (xy 209.682998 -273.564733) (xy 209.570277 -273.72397)
			(xy 209.49414 -273.822668) (xy 227.662992 -273.822668) (xy 227.667063 -273.767046) (xy 227.679189 -273.712609)
			(xy 227.699112 -273.660518) (xy 227.726408 -273.611883) (xy 227.760494 -273.56774) (xy 227.800643 -273.529031)
			(xy 227.846001 -273.49658) (xy 227.895601 -273.471079) (xy 227.948385 -273.453072) (xy 228.003228 -273.442942)
			(xy 228.058962 -273.440905) (xy 228.114399 -273.447005) (xy 228.168356 -273.461111) (xy 228.219685 -273.482923)
			(xy 228.267291 -273.511977) (xy 228.310159 -273.547652) (xy 228.347376 -273.589189) (xy 228.378149 -273.635702)
			(xy 228.401821 -273.686199) (xy 228.417889 -273.739606) (xy 228.426009 -273.794782) (xy 228.426518 -273.822668)
			(xy 228.426393 -273.829526) (xy 228.564946 -273.829526) (xy 228.569017 -273.773904) (xy 228.581143 -273.719467)
			(xy 228.601066 -273.667376) (xy 228.628362 -273.618741) (xy 228.662448 -273.574598) (xy 228.702597 -273.535889)
			(xy 228.747955 -273.503438) (xy 228.797555 -273.477937) (xy 228.850339 -273.45993) (xy 228.905182 -273.4498)
			(xy 228.960916 -273.447763) (xy 229.016353 -273.453863) (xy 229.07031 -273.467969) (xy 229.078351 -273.471386)
			(xy 232.53395 -273.471386) (xy 232.538021 -273.415764) (xy 232.550147 -273.361327) (xy 232.57007 -273.309236)
			(xy 232.597366 -273.260601) (xy 232.631452 -273.216458) (xy 232.671601 -273.177749) (xy 232.716959 -273.145298)
			(xy 232.766559 -273.119797) (xy 232.819343 -273.10179) (xy 232.874186 -273.09166) (xy 232.92992 -273.089623)
			(xy 232.985357 -273.095723) (xy 233.039314 -273.109829) (xy 233.090643 -273.131641) (xy 233.138249 -273.160695)
			(xy 233.181117 -273.19637) (xy 233.218334 -273.237907) (xy 233.249107 -273.28442) (xy 233.272779 -273.334917)
			(xy 233.288847 -273.388324) (xy 233.296967 -273.4435) (xy 233.297476 -273.471386) (xy 248.784108 -273.471386)
			(xy 248.788179 -273.415764) (xy 248.800305 -273.361327) (xy 248.820228 -273.309236) (xy 248.847524 -273.260601)
			(xy 248.88161 -273.216458) (xy 248.921759 -273.177749) (xy 248.967117 -273.145298) (xy 249.016717 -273.119797)
			(xy 249.069501 -273.10179) (xy 249.124344 -273.09166) (xy 249.180078 -273.089623) (xy 249.235515 -273.095723)
			(xy 249.289472 -273.109829) (xy 249.340801 -273.131641) (xy 249.388407 -273.160695) (xy 249.431275 -273.19637)
			(xy 249.468492 -273.237907) (xy 249.499265 -273.28442) (xy 249.522937 -273.334917) (xy 249.539005 -273.388324)
			(xy 249.547125 -273.4435) (xy 249.547634 -273.471386) (xy 249.547125 -273.499272) (xy 249.539005 -273.554448)
			(xy 249.522937 -273.607855) (xy 249.499265 -273.658352) (xy 249.468492 -273.704865) (xy 249.431275 -273.746402)
			(xy 249.388407 -273.782077) (xy 249.340801 -273.811131) (xy 249.289472 -273.832943) (xy 249.235515 -273.847049)
			(xy 249.180078 -273.853149) (xy 249.124344 -273.851112) (xy 249.069501 -273.840982) (xy 249.016717 -273.822975)
			(xy 248.967117 -273.797474) (xy 248.921759 -273.765023) (xy 248.88161 -273.726314) (xy 248.847524 -273.682171)
			(xy 248.820228 -273.633536) (xy 248.800305 -273.581445) (xy 248.788179 -273.527008) (xy 248.784108 -273.471386)
			(xy 233.297476 -273.471386) (xy 233.296967 -273.499272) (xy 233.288847 -273.554448) (xy 233.272779 -273.607855)
			(xy 233.249107 -273.658352) (xy 233.218334 -273.704865) (xy 233.181117 -273.746402) (xy 233.138249 -273.782077)
			(xy 233.090643 -273.811131) (xy 233.039314 -273.832943) (xy 232.985357 -273.847049) (xy 232.92992 -273.853149)
			(xy 232.874186 -273.851112) (xy 232.819343 -273.840982) (xy 232.766559 -273.822975) (xy 232.716959 -273.797474)
			(xy 232.671601 -273.765023) (xy 232.631452 -273.726314) (xy 232.597366 -273.682171) (xy 232.57007 -273.633536)
			(xy 232.550147 -273.581445) (xy 232.538021 -273.527008) (xy 232.53395 -273.471386) (xy 229.078351 -273.471386)
			(xy 229.121639 -273.489781) (xy 229.169245 -273.518835) (xy 229.212113 -273.55451) (xy 229.24933 -273.596047)
			(xy 229.280103 -273.64256) (xy 229.303775 -273.693057) (xy 229.319843 -273.746464) (xy 229.327963 -273.80164)
			(xy 229.328472 -273.829526) (xy 229.327963 -273.857412) (xy 229.319843 -273.912588) (xy 229.303775 -273.965995)
			(xy 229.295592 -273.98345) (xy 249.491246 -273.98345) (xy 249.491732 -273.956199) (xy 249.499488 -273.902251)
			(xy 249.514843 -273.849956) (xy 249.537485 -273.800379) (xy 249.566951 -273.754529) (xy 249.602642 -273.713338)
			(xy 249.643833 -273.677647) (xy 249.689683 -273.648181) (xy 249.73926 -273.625539) (xy 249.791555 -273.610184)
			(xy 249.845503 -273.602428) (xy 249.900005 -273.602428) (xy 249.953953 -273.610184) (xy 250.006248 -273.625539)
			(xy 250.055825 -273.648181) (xy 250.101675 -273.677647) (xy 250.142866 -273.713338) (xy 250.178557 -273.754529)
			(xy 250.208023 -273.800379) (xy 250.230665 -273.849956) (xy 250.24602 -273.902251) (xy 250.253776 -273.956199)
			(xy 250.254262 -273.98345) (xy 250.253689 -274.014423) (xy 250.243735 -274.075562) (xy 250.23445 -274.105116)
			(xy 250.231148 -274.114768) (xy 250.232418 -274.134326) (xy 250.272042 -274.216368) (xy 250.286774 -274.229576)
			(xy 250.296172 -274.233132) (xy 250.323475 -274.243568) (xy 250.374805 -274.271521) (xy 250.421269 -274.306979)
			(xy 250.461779 -274.349111) (xy 250.495386 -274.39693) (xy 250.521304 -274.449317) (xy 250.538925 -274.505046)
			(xy 250.547838 -274.56281) (xy 250.548394 -274.592034) (xy 250.547908 -274.619285) (xy 250.540152 -274.673233)
			(xy 250.524797 -274.725528) (xy 250.502155 -274.775105) (xy 250.472689 -274.820955) (xy 250.436998 -274.862146)
			(xy 250.395807 -274.897837) (xy 250.349957 -274.927303) (xy 250.30038 -274.949945) (xy 250.248085 -274.9653)
			(xy 250.194137 -274.973056) (xy 250.139635 -274.973056) (xy 250.085687 -274.9653) (xy 250.033392 -274.949945)
			(xy 249.983815 -274.927303) (xy 249.937965 -274.897837) (xy 249.896774 -274.862146) (xy 249.861083 -274.820955)
			(xy 249.831617 -274.775105) (xy 249.808975 -274.725528) (xy 249.79362 -274.673233) (xy 249.785864 -274.619285)
			(xy 249.785378 -274.592034) (xy 249.785945 -274.561061) (xy 249.795903 -274.499922) (xy 249.80519 -274.470368)
			(xy 249.808492 -274.460716) (xy 249.807222 -274.441158) (xy 249.767598 -274.359116) (xy 249.752866 -274.345908)
			(xy 249.743468 -274.342352) (xy 249.716146 -274.331963) (xy 249.664817 -274.304001) (xy 249.618355 -274.268534)
			(xy 249.577848 -274.226395) (xy 249.544243 -274.17857) (xy 249.518329 -274.126177) (xy 249.50071 -274.070444)
			(xy 249.4918 -274.012676) (xy 249.491246 -273.98345) (xy 229.295592 -273.98345) (xy 229.280103 -274.016492)
			(xy 229.24933 -274.063005) (xy 229.212113 -274.104542) (xy 229.169245 -274.140217) (xy 229.121639 -274.169271)
			(xy 229.07031 -274.191083) (xy 229.016353 -274.205189) (xy 228.960916 -274.211289) (xy 228.905182 -274.209252)
			(xy 228.850339 -274.199122) (xy 228.797555 -274.181115) (xy 228.747955 -274.155614) (xy 228.702597 -274.123163)
			(xy 228.662448 -274.084454) (xy 228.628362 -274.040311) (xy 228.601066 -273.991676) (xy 228.581143 -273.939585)
			(xy 228.569017 -273.885148) (xy 228.564946 -273.829526) (xy 228.426393 -273.829526) (xy 228.426009 -273.850554)
			(xy 228.417889 -273.90573) (xy 228.401821 -273.959137) (xy 228.378149 -274.009634) (xy 228.347376 -274.056147)
			(xy 228.310159 -274.097684) (xy 228.267291 -274.133359) (xy 228.219685 -274.162413) (xy 228.168356 -274.184225)
			(xy 228.114399 -274.198331) (xy 228.058962 -274.204431) (xy 228.003228 -274.202394) (xy 227.948385 -274.192264)
			(xy 227.895601 -274.174257) (xy 227.846001 -274.148756) (xy 227.800643 -274.116305) (xy 227.760494 -274.077596)
			(xy 227.726408 -274.033453) (xy 227.699112 -273.984818) (xy 227.679189 -273.932727) (xy 227.667063 -273.87829)
			(xy 227.662992 -273.822668) (xy 209.49414 -273.822668) (xy 209.451113 -273.878444) (xy 209.325708 -274.027897)
			(xy 209.194272 -274.172075) (xy 209.057028 -274.310735) (xy 208.914207 -274.443643) (xy 208.76605 -274.570577)
			(xy 208.687239 -274.632674) (xy 226.694998 -274.632674) (xy 226.699069 -274.577052) (xy 226.711195 -274.522615)
			(xy 226.731118 -274.470524) (xy 226.758414 -274.421889) (xy 226.7925 -274.377746) (xy 226.832649 -274.339037)
			(xy 226.878007 -274.306586) (xy 226.927607 -274.281085) (xy 226.980391 -274.263078) (xy 227.035234 -274.252948)
			(xy 227.090968 -274.250911) (xy 227.146405 -274.257011) (xy 227.200362 -274.271117) (xy 227.251691 -274.292929)
			(xy 227.299297 -274.321983) (xy 227.342165 -274.357658) (xy 227.379382 -274.399195) (xy 227.410155 -274.445708)
			(xy 227.433827 -274.496205) (xy 227.449895 -274.549612) (xy 227.458015 -274.604788) (xy 227.458524 -274.632674)
			(xy 227.458015 -274.66056) (xy 227.449895 -274.715736) (xy 227.434154 -274.768056) (xy 228.824788 -274.768056)
			(xy 228.828859 -274.712434) (xy 228.840985 -274.657997) (xy 228.860908 -274.605906) (xy 228.888204 -274.557271)
			(xy 228.92229 -274.513128) (xy 228.962439 -274.474419) (xy 229.007797 -274.441968) (xy 229.057397 -274.416467)
			(xy 229.110181 -274.39846) (xy 229.165024 -274.38833) (xy 229.220758 -274.386293) (xy 229.276195 -274.392393)
			(xy 229.330152 -274.406499) (xy 229.381481 -274.428311) (xy 229.429087 -274.457365) (xy 229.465161 -274.487386)
			(xy 232.472228 -274.487386) (xy 232.476299 -274.431764) (xy 232.488425 -274.377327) (xy 232.508348 -274.325236)
			(xy 232.535644 -274.276601) (xy 232.56973 -274.232458) (xy 232.609879 -274.193749) (xy 232.655237 -274.161298)
			(xy 232.704837 -274.135797) (xy 232.757621 -274.11779) (xy 232.812464 -274.10766) (xy 232.868198 -274.105623)
			(xy 232.923635 -274.111723) (xy 232.977592 -274.125829) (xy 233.028921 -274.147641) (xy 233.076527 -274.176695)
			(xy 233.119395 -274.21237) (xy 233.156612 -274.253907) (xy 233.187385 -274.30042) (xy 233.211057 -274.350917)
			(xy 233.227125 -274.404324) (xy 233.235245 -274.4595) (xy 233.235754 -274.487386) (xy 233.235245 -274.515272)
			(xy 233.227125 -274.570448) (xy 233.211057 -274.623855) (xy 233.206923 -274.632674) (xy 242.945156 -274.632674)
			(xy 242.949227 -274.577052) (xy 242.961353 -274.522615) (xy 242.981276 -274.470524) (xy 243.008572 -274.421889)
			(xy 243.042658 -274.377746) (xy 243.082807 -274.339037) (xy 243.128165 -274.306586) (xy 243.177765 -274.281085)
			(xy 243.230549 -274.263078) (xy 243.285392 -274.252948) (xy 243.341126 -274.250911) (xy 243.396563 -274.257011)
			(xy 243.45052 -274.271117) (xy 243.501849 -274.292929) (xy 243.549455 -274.321983) (xy 243.592323 -274.357658)
			(xy 243.62954 -274.399195) (xy 243.660313 -274.445708) (xy 243.683985 -274.496205) (xy 243.700053 -274.549612)
			(xy 243.708173 -274.604788) (xy 243.708682 -274.632674) (xy 243.708173 -274.66056) (xy 243.700053 -274.715736)
			(xy 243.684312 -274.768056) (xy 245.074946 -274.768056) (xy 245.079017 -274.712434) (xy 245.091143 -274.657997)
			(xy 245.111066 -274.605906) (xy 245.138362 -274.557271) (xy 245.172448 -274.513128) (xy 245.212597 -274.474419)
			(xy 245.257955 -274.441968) (xy 245.307555 -274.416467) (xy 245.360339 -274.39846) (xy 245.415182 -274.38833)
			(xy 245.470916 -274.386293) (xy 245.526353 -274.392393) (xy 245.58031 -274.406499) (xy 245.631639 -274.428311)
			(xy 245.679245 -274.457365) (xy 245.715319 -274.487386) (xy 248.722386 -274.487386) (xy 248.726457 -274.431764)
			(xy 248.738583 -274.377327) (xy 248.758506 -274.325236) (xy 248.785802 -274.276601) (xy 248.819888 -274.232458)
			(xy 248.860037 -274.193749) (xy 248.905395 -274.161298) (xy 248.954995 -274.135797) (xy 249.007779 -274.11779)
			(xy 249.062622 -274.10766) (xy 249.118356 -274.105623) (xy 249.173793 -274.111723) (xy 249.22775 -274.125829)
			(xy 249.279079 -274.147641) (xy 249.326685 -274.176695) (xy 249.369553 -274.21237) (xy 249.40677 -274.253907)
			(xy 249.437543 -274.30042) (xy 249.461215 -274.350917) (xy 249.477283 -274.404324) (xy 249.485403 -274.4595)
			(xy 249.485912 -274.487386) (xy 249.485403 -274.515272) (xy 249.477283 -274.570448) (xy 249.461215 -274.623855)
			(xy 249.437543 -274.674352) (xy 249.40677 -274.720865) (xy 249.369553 -274.762402) (xy 249.326685 -274.798077)
			(xy 249.279079 -274.827131) (xy 249.22775 -274.848943) (xy 249.173793 -274.863049) (xy 249.118356 -274.869149)
			(xy 249.062622 -274.867112) (xy 249.007779 -274.856982) (xy 248.954995 -274.838975) (xy 248.905395 -274.813474)
			(xy 248.860037 -274.781023) (xy 248.819888 -274.742314) (xy 248.785802 -274.698171) (xy 248.758506 -274.649536)
			(xy 248.738583 -274.597445) (xy 248.726457 -274.543008) (xy 248.722386 -274.487386) (xy 245.715319 -274.487386)
			(xy 245.722113 -274.49304) (xy 245.75933 -274.534577) (xy 245.790103 -274.58109) (xy 245.813775 -274.631587)
			(xy 245.829843 -274.684994) (xy 245.837963 -274.74017) (xy 245.838472 -274.768056) (xy 245.837963 -274.795942)
			(xy 245.829843 -274.851118) (xy 245.813775 -274.904525) (xy 245.790103 -274.955022) (xy 245.75933 -275.001535)
			(xy 245.722113 -275.043072) (xy 245.679245 -275.078747) (xy 245.631639 -275.107801) (xy 245.58031 -275.129613)
			(xy 245.526353 -275.143719) (xy 245.470916 -275.149819) (xy 245.415182 -275.147782) (xy 245.360339 -275.137652)
			(xy 245.307555 -275.119645) (xy 245.257955 -275.094144) (xy 245.212597 -275.061693) (xy 245.172448 -275.022984)
			(xy 245.138362 -274.978841) (xy 245.111066 -274.930206) (xy 245.091143 -274.878115) (xy 245.079017 -274.823678)
			(xy 245.074946 -274.768056) (xy 243.684312 -274.768056) (xy 243.683985 -274.769143) (xy 243.660313 -274.81964)
			(xy 243.62954 -274.866153) (xy 243.592323 -274.90769) (xy 243.549455 -274.943365) (xy 243.501849 -274.972419)
			(xy 243.45052 -274.994231) (xy 243.396563 -275.008337) (xy 243.341126 -275.014437) (xy 243.285392 -275.0124)
			(xy 243.230549 -275.00227) (xy 243.177765 -274.984263) (xy 243.128165 -274.958762) (xy 243.082807 -274.926311)
			(xy 243.042658 -274.887602) (xy 243.008572 -274.843459) (xy 242.981276 -274.794824) (xy 242.961353 -274.742733)
			(xy 242.949227 -274.688296) (xy 242.945156 -274.632674) (xy 233.206923 -274.632674) (xy 233.187385 -274.674352)
			(xy 233.156612 -274.720865) (xy 233.119395 -274.762402) (xy 233.076527 -274.798077) (xy 233.028921 -274.827131)
			(xy 232.977592 -274.848943) (xy 232.923635 -274.863049) (xy 232.868198 -274.869149) (xy 232.812464 -274.867112)
			(xy 232.757621 -274.856982) (xy 232.704837 -274.838975) (xy 232.655237 -274.813474) (xy 232.609879 -274.781023)
			(xy 232.56973 -274.742314) (xy 232.535644 -274.698171) (xy 232.508348 -274.649536) (xy 232.488425 -274.597445)
			(xy 232.476299 -274.543008) (xy 232.472228 -274.487386) (xy 229.465161 -274.487386) (xy 229.471955 -274.49304)
			(xy 229.509172 -274.534577) (xy 229.539945 -274.58109) (xy 229.563617 -274.631587) (xy 229.579685 -274.684994)
			(xy 229.587805 -274.74017) (xy 229.588314 -274.768056) (xy 229.587805 -274.795942) (xy 229.579685 -274.851118)
			(xy 229.563617 -274.904525) (xy 229.539945 -274.955022) (xy 229.509172 -275.001535) (xy 229.471955 -275.043072)
			(xy 229.429087 -275.078747) (xy 229.381481 -275.107801) (xy 229.330152 -275.129613) (xy 229.276195 -275.143719)
			(xy 229.220758 -275.149819) (xy 229.165024 -275.147782) (xy 229.110181 -275.137652) (xy 229.057397 -275.119645)
			(xy 229.007797 -275.094144) (xy 228.962439 -275.061693) (xy 228.92229 -275.022984) (xy 228.888204 -274.978841)
			(xy 228.860908 -274.930206) (xy 228.840985 -274.878115) (xy 228.828859 -274.823678) (xy 228.824788 -274.768056)
			(xy 227.434154 -274.768056) (xy 227.433827 -274.769143) (xy 227.410155 -274.81964) (xy 227.379382 -274.866153)
			(xy 227.342165 -274.90769) (xy 227.299297 -274.943365) (xy 227.251691 -274.972419) (xy 227.200362 -274.994231)
			(xy 227.146405 -275.008337) (xy 227.090968 -275.014437) (xy 227.035234 -275.0124) (xy 226.980391 -275.00227)
			(xy 226.927607 -274.984263) (xy 226.878007 -274.958762) (xy 226.832649 -274.926311) (xy 226.7925 -274.887602)
			(xy 226.758414 -274.843459) (xy 226.731118 -274.794824) (xy 226.711195 -274.742733) (xy 226.699069 -274.688296)
			(xy 226.694998 -274.632674) (xy 208.687239 -274.632674) (xy 208.612807 -274.69132) (xy 208.454736 -274.80567)
			(xy 208.292103 -274.913435) (xy 208.125184 -275.014431) (xy 207.954258 -275.10849) (xy 207.779615 -275.195452)
			(xy 207.601549 -275.27517) (xy 207.420361 -275.347511) (xy 207.236355 -275.412352) (xy 207.049842 -275.469584)
			(xy 206.861137 -275.519111) (xy 206.800201 -275.532456) (xy 223.168119 -275.532456) (xy 223.168119 -275.477944)
			(xy 223.175877 -275.423987) (xy 223.191235 -275.371684) (xy 223.21388 -275.322098) (xy 223.243352 -275.27624)
			(xy 223.27905 -275.235043) (xy 223.320248 -275.199346) (xy 223.366107 -275.169876) (xy 223.415693 -275.147231)
			(xy 223.467997 -275.131875) (xy 223.521954 -275.124118) (xy 223.54921 -275.123656) (xy 223.576581 -275.124103)
			(xy 223.630762 -275.131923) (xy 223.683265 -275.147416) (xy 223.733012 -275.170262) (xy 223.778977 -275.199992)
			(xy 223.799908 -275.217636) (xy 223.80702 -275.223732) (xy 223.824038 -275.230082) (xy 223.909382 -275.230082)
			(xy 223.9264 -275.223732) (xy 223.933512 -275.217636) (xy 223.954471 -275.20003) (xy 224.000436 -275.170312)
			(xy 224.050176 -275.147469) (xy 224.102671 -275.13197) (xy 224.156843 -275.124134) (xy 224.18421 -275.123656)
			(xy 224.211458 -275.124215) (xy 224.2654 -275.131972) (xy 224.317688 -275.147326) (xy 224.367259 -275.169966)
			(xy 224.413104 -275.19943) (xy 224.419458 -275.204936) (xy 230.320594 -275.204936) (xy 230.324665 -275.149314)
			(xy 230.336791 -275.094877) (xy 230.356714 -275.042786) (xy 230.38401 -274.994151) (xy 230.418096 -274.950008)
			(xy 230.458245 -274.911299) (xy 230.503603 -274.878848) (xy 230.553203 -274.853347) (xy 230.605987 -274.83534)
			(xy 230.66083 -274.82521) (xy 230.716564 -274.823173) (xy 230.772001 -274.829273) (xy 230.825958 -274.843379)
			(xy 230.877287 -274.865191) (xy 230.924893 -274.894245) (xy 230.967761 -274.92992) (xy 231.004978 -274.971457)
			(xy 231.035751 -275.01797) (xy 231.059423 -275.068467) (xy 231.075491 -275.121874) (xy 231.083611 -275.17705)
			(xy 231.08412 -275.204936) (xy 231.083611 -275.232822) (xy 231.075491 -275.287998) (xy 231.059423 -275.341405)
			(xy 231.035751 -275.391902) (xy 231.004978 -275.438415) (xy 230.967761 -275.479952) (xy 230.939602 -275.503386)
			(xy 232.472228 -275.503386) (xy 232.476299 -275.447764) (xy 232.488425 -275.393327) (xy 232.508348 -275.341236)
			(xy 232.535644 -275.292601) (xy 232.56973 -275.248458) (xy 232.609879 -275.209749) (xy 232.655237 -275.177298)
			(xy 232.704837 -275.151797) (xy 232.757621 -275.13379) (xy 232.812464 -275.12366) (xy 232.868198 -275.121623)
			(xy 232.923635 -275.127723) (xy 232.977592 -275.141829) (xy 233.028921 -275.163641) (xy 233.076527 -275.192695)
			(xy 233.119395 -275.22837) (xy 233.156612 -275.269907) (xy 233.187385 -275.31642) (xy 233.211057 -275.366917)
			(xy 233.227125 -275.420324) (xy 233.235245 -275.4755) (xy 233.235754 -275.503386) (xy 233.235245 -275.531272)
			(xy 233.235071 -275.532452) (xy 239.418342 -275.532452) (xy 239.418342 -275.477948) (xy 239.426098 -275.423998)
			(xy 239.441453 -275.3717) (xy 239.464094 -275.322121) (xy 239.49356 -275.276268) (xy 239.529252 -275.235074)
			(xy 239.570442 -275.199379) (xy 239.616293 -275.169909) (xy 239.66587 -275.147264) (xy 239.718166 -275.131905)
			(xy 239.772116 -275.124144) (xy 239.799368 -275.123656) (xy 239.826738 -275.124127) (xy 239.880918 -275.131942)
			(xy 239.933421 -275.147429) (xy 239.983168 -275.17027) (xy 240.029135 -275.199994) (xy 240.050066 -275.217636)
			(xy 240.057178 -275.223732) (xy 240.074196 -275.230082) (xy 240.15954 -275.230082) (xy 240.176558 -275.223732)
			(xy 240.18367 -275.217636) (xy 240.204607 -275.200003) (xy 240.250578 -275.170289) (xy 240.300324 -275.147451)
			(xy 240.352824 -275.131959) (xy 240.406999 -275.12413) (xy 240.434368 -275.123656) (xy 240.46162 -275.124189)
			(xy 240.515569 -275.131942) (xy 240.567866 -275.147293) (xy 240.617445 -275.169932) (xy 240.663298 -275.199396)
			(xy 240.669692 -275.204936) (xy 246.570752 -275.204936) (xy 246.574823 -275.149314) (xy 246.586949 -275.094877)
			(xy 246.606872 -275.042786) (xy 246.634168 -274.994151) (xy 246.668254 -274.950008) (xy 246.708403 -274.911299)
			(xy 246.753761 -274.878848) (xy 246.803361 -274.853347) (xy 246.856145 -274.83534) (xy 246.910988 -274.82521)
			(xy 246.966722 -274.823173) (xy 247.022159 -274.829273) (xy 247.076116 -274.843379) (xy 247.127445 -274.865191)
			(xy 247.175051 -274.894245) (xy 247.217919 -274.92992) (xy 247.255136 -274.971457) (xy 247.285909 -275.01797)
			(xy 247.309581 -275.068467) (xy 247.325649 -275.121874) (xy 247.333769 -275.17705) (xy 247.334278 -275.204936)
			(xy 247.333769 -275.232822) (xy 247.325649 -275.287998) (xy 247.309581 -275.341405) (xy 247.285909 -275.391902)
			(xy 247.255136 -275.438415) (xy 247.217919 -275.479952) (xy 247.18976 -275.503386) (xy 248.722386 -275.503386)
			(xy 248.726457 -275.447764) (xy 248.738583 -275.393327) (xy 248.758506 -275.341236) (xy 248.785802 -275.292601)
			(xy 248.819888 -275.248458) (xy 248.860037 -275.209749) (xy 248.905395 -275.177298) (xy 248.954995 -275.151797)
			(xy 249.007779 -275.13379) (xy 249.062622 -275.12366) (xy 249.118356 -275.121623) (xy 249.173793 -275.127723)
			(xy 249.22775 -275.141829) (xy 249.279079 -275.163641) (xy 249.326685 -275.192695) (xy 249.369553 -275.22837)
			(xy 249.40677 -275.269907) (xy 249.437543 -275.31642) (xy 249.461215 -275.366917) (xy 249.477283 -275.420324)
			(xy 249.485403 -275.4755) (xy 249.485912 -275.503386) (xy 249.485403 -275.531272) (xy 249.477283 -275.586448)
			(xy 249.461215 -275.639855) (xy 249.437543 -275.690352) (xy 249.40677 -275.736865) (xy 249.369553 -275.778402)
			(xy 249.326685 -275.814077) (xy 249.279079 -275.843131) (xy 249.22775 -275.864943) (xy 249.173793 -275.879049)
			(xy 249.118356 -275.885149) (xy 249.062622 -275.883112) (xy 249.007779 -275.872982) (xy 248.954995 -275.854975)
			(xy 248.905395 -275.829474) (xy 248.860037 -275.797023) (xy 248.819888 -275.758314) (xy 248.785802 -275.714171)
			(xy 248.758506 -275.665536) (xy 248.738583 -275.613445) (xy 248.726457 -275.559008) (xy 248.722386 -275.503386)
			(xy 247.18976 -275.503386) (xy 247.175051 -275.515627) (xy 247.127445 -275.544681) (xy 247.076116 -275.566493)
			(xy 247.022159 -275.580599) (xy 246.966722 -275.586699) (xy 246.910988 -275.584662) (xy 246.856145 -275.574532)
			(xy 246.803361 -275.556525) (xy 246.753761 -275.531024) (xy 246.708403 -275.498573) (xy 246.668254 -275.459864)
			(xy 246.634168 -275.415721) (xy 246.606872 -275.367086) (xy 246.586949 -275.314995) (xy 246.574823 -275.260558)
			(xy 246.570752 -275.204936) (xy 240.669692 -275.204936) (xy 240.704491 -275.235087) (xy 240.740184 -275.276276)
			(xy 240.769653 -275.322127) (xy 240.792295 -275.371704) (xy 240.807652 -275.424) (xy 240.815409 -275.477948)
			(xy 240.815409 -275.532452) (xy 240.807652 -275.5864) (xy 240.792295 -275.638696) (xy 240.769653 -275.688273)
			(xy 240.740184 -275.734124) (xy 240.704491 -275.775313) (xy 240.663298 -275.811004) (xy 240.617445 -275.840468)
			(xy 240.567866 -275.863107) (xy 240.515569 -275.878458) (xy 240.46162 -275.886211) (xy 240.434368 -275.886672)
			(xy 240.406997 -275.886232) (xy 240.352816 -275.878409) (xy 240.300313 -275.862914) (xy 240.250566 -275.840066)
			(xy 240.204601 -275.810336) (xy 240.18367 -275.792692) (xy 240.176558 -275.786596) (xy 240.15954 -275.780246)
			(xy 240.074196 -275.780246) (xy 240.057178 -275.786596) (xy 240.050066 -275.792692) (xy 240.029119 -275.810312)
			(xy 239.98315 -275.840027) (xy 239.933407 -275.862867) (xy 239.880909 -275.878362) (xy 239.826736 -275.886195)
			(xy 239.799368 -275.886672) (xy 239.772116 -275.886256) (xy 239.718166 -275.878495) (xy 239.66587 -275.863136)
			(xy 239.616293 -275.840491) (xy 239.570442 -275.811021) (xy 239.529252 -275.775326) (xy 239.49356 -275.734132)
			(xy 239.464094 -275.688279) (xy 239.441453 -275.638699) (xy 239.426098 -275.586402) (xy 239.418342 -275.532452)
			(xy 233.235071 -275.532452) (xy 233.227125 -275.586448) (xy 233.211057 -275.639855) (xy 233.187385 -275.690352)
			(xy 233.156612 -275.736865) (xy 233.119395 -275.778402) (xy 233.076527 -275.814077) (xy 233.028921 -275.843131)
			(xy 232.977592 -275.864943) (xy 232.923635 -275.879049) (xy 232.868198 -275.885149) (xy 232.812464 -275.883112)
			(xy 232.757621 -275.872982) (xy 232.704837 -275.854975) (xy 232.655237 -275.829474) (xy 232.609879 -275.797023)
			(xy 232.56973 -275.758314) (xy 232.535644 -275.714171) (xy 232.508348 -275.665536) (xy 232.488425 -275.613445)
			(xy 232.476299 -275.559008) (xy 232.472228 -275.503386) (xy 230.939602 -275.503386) (xy 230.924893 -275.515627)
			(xy 230.877287 -275.544681) (xy 230.825958 -275.566493) (xy 230.772001 -275.580599) (xy 230.716564 -275.586699)
			(xy 230.66083 -275.584662) (xy 230.605987 -275.574532) (xy 230.553203 -275.556525) (xy 230.503603 -275.531024)
			(xy 230.458245 -275.498573) (xy 230.418096 -275.459864) (xy 230.38401 -275.415721) (xy 230.356714 -275.367086)
			(xy 230.336791 -275.314995) (xy 230.324665 -275.260558) (xy 230.320594 -275.204936) (xy 224.419458 -275.204936)
			(xy 224.454289 -275.235118) (xy 224.489976 -275.276304) (xy 224.519439 -275.322149) (xy 224.542077 -275.371721)
			(xy 224.55743 -275.42401) (xy 224.565186 -275.477952) (xy 224.565186 -275.532448) (xy 224.55743 -275.58639)
			(xy 224.542077 -275.638679) (xy 224.519439 -275.688251) (xy 224.489976 -275.734096) (xy 224.454289 -275.775282)
			(xy 224.413104 -275.81097) (xy 224.367259 -275.840434) (xy 224.317688 -275.863074) (xy 224.2654 -275.878428)
			(xy 224.211458 -275.886185) (xy 224.18421 -275.886672) (xy 224.15684 -275.886207) (xy 224.10266 -275.87839)
			(xy 224.050157 -275.862901) (xy 224.00041 -275.840059) (xy 223.954443 -275.810334) (xy 223.933512 -275.792692)
			(xy 223.9264 -275.786596) (xy 223.909382 -275.780246) (xy 223.824038 -275.780246) (xy 223.80702 -275.786596)
			(xy 223.799908 -275.792692) (xy 223.778983 -275.81034) (xy 223.733008 -275.84005) (xy 223.683259 -275.862885)
			(xy 223.630757 -275.878374) (xy 223.57658 -275.886199) (xy 223.54921 -275.886672) (xy 223.521954 -275.886282)
			(xy 223.467997 -275.878525) (xy 223.415693 -275.863169) (xy 223.366107 -275.840524) (xy 223.320248 -275.811054)
			(xy 223.27905 -275.775357) (xy 223.243352 -275.73416) (xy 223.21388 -275.688302) (xy 223.191235 -275.638716)
			(xy 223.175877 -275.586413) (xy 223.168119 -275.532456) (xy 206.800201 -275.532456) (xy 206.670558 -275.560848)
			(xy 206.478425 -275.594726) (xy 206.285064 -275.620688) (xy 206.0908 -275.638689) (xy 205.895961 -275.6487)
			(xy 205.700875 -275.650703) (xy 205.505872 -275.644695) (xy 205.311279 -275.630686) (xy 205.117426 -275.6087)
			(xy 204.924639 -275.578774) (xy 204.733242 -275.540958) (xy 204.54356 -275.495316) (xy 204.355912 -275.441926)
			(xy 204.170613 -275.380876) (xy 203.987978 -275.312271) (xy 203.808313 -275.236225) (xy 203.631921 -275.152867)
			(xy 203.4591 -275.062338) (xy 203.290142 -274.96479) (xy 203.125331 -274.860387) (xy 202.964945 -274.749307)
			(xy 202.809255 -274.631735) (xy 202.658523 -274.507871) (xy 202.513004 -274.377922) (xy 202.372942 -274.242109)
			(xy 202.238574 -274.10066) (xy 202.110127 -273.953814) (xy 201.987816 -273.801819) (xy 201.871849 -273.64493)
			(xy 201.762421 -273.483412) (xy 201.659716 -273.317538) (xy 201.563908 -273.147587) (xy 201.475157 -272.973846)
			(xy 201.393615 -272.796608) (xy 201.319418 -272.616172) (xy 201.252691 -272.432841) (xy 201.193547 -272.246926)
			(xy 201.142086 -272.058739) (xy 201.098394 -271.868599) (xy 201.062545 -271.676824) (xy 201.0346 -271.48374)
			(xy 201.014605 -271.289671) (xy 201.002595 -271.094945) (xy 200.998589 -270.89989) (xy 150.500334 -270.89989)
			(xy 150.499833 -270.997438) (xy 150.491824 -271.19237) (xy 150.475818 -271.386808) (xy 150.451843 -271.580426)
			(xy 150.419939 -271.772896) (xy 150.38016 -271.963893) (xy 150.333461 -272.14957) (xy 160.243786 -272.14957)
			(xy 160.247746 -272.100516) (xy 160.259523 -272.052732) (xy 160.278814 -272.007456) (xy 160.305117 -271.96586)
			(xy 160.337752 -271.929023) (xy 160.375873 -271.897898) (xy 160.418494 -271.873291) (xy 160.46451 -271.855839)
			(xy 160.512729 -271.845995) (xy 160.561904 -271.844014) (xy 160.610759 -271.849946) (xy 160.65803 -271.863638)
			(xy 160.702492 -271.884736) (xy 160.742995 -271.912692) (xy 160.778488 -271.946784) (xy 160.808053 -271.986128)
			(xy 160.830924 -272.029705) (xy 160.846508 -272.076386) (xy 160.854403 -272.124963) (xy 160.854898 -272.14957)
			(xy 162.14396 -272.14957) (xy 162.14792 -272.100516) (xy 162.159697 -272.052732) (xy 162.178988 -272.007456)
			(xy 162.205291 -271.96586) (xy 162.237926 -271.929023) (xy 162.276047 -271.897898) (xy 162.318668 -271.873291)
			(xy 162.364684 -271.855839) (xy 162.412903 -271.845995) (xy 162.462078 -271.844014) (xy 162.510933 -271.849946)
			(xy 162.558204 -271.863638) (xy 162.602666 -271.884736) (xy 162.643169 -271.912692) (xy 162.678662 -271.946784)
			(xy 162.708227 -271.986128) (xy 162.731098 -272.029705) (xy 162.746682 -272.076386) (xy 162.754577 -272.124963)
			(xy 162.755072 -272.14957) (xy 164.04388 -272.14957) (xy 164.04784 -272.100516) (xy 164.059617 -272.052732)
			(xy 164.078908 -272.007456) (xy 164.105211 -271.96586) (xy 164.137846 -271.929023) (xy 164.175967 -271.897898)
			(xy 164.218588 -271.873291) (xy 164.264604 -271.855839) (xy 164.312823 -271.845995) (xy 164.361998 -271.844014)
			(xy 164.410853 -271.849946) (xy 164.458124 -271.863638) (xy 164.502586 -271.884736) (xy 164.543089 -271.912692)
			(xy 164.578582 -271.946784) (xy 164.608147 -271.986128) (xy 164.631018 -272.029705) (xy 164.646602 -272.076386)
			(xy 164.654497 -272.124963) (xy 164.654992 -272.14957) (xy 165.9438 -272.14957) (xy 165.94776 -272.100516)
			(xy 165.959537 -272.052732) (xy 165.978828 -272.007456) (xy 166.005131 -271.96586) (xy 166.037766 -271.929023)
			(xy 166.075887 -271.897898) (xy 166.118508 -271.873291) (xy 166.164524 -271.855839) (xy 166.212743 -271.845995)
			(xy 166.261918 -271.844014) (xy 166.310773 -271.849946) (xy 166.358044 -271.863638) (xy 166.402506 -271.884736)
			(xy 166.443009 -271.912692) (xy 166.478502 -271.946784) (xy 166.508067 -271.986128) (xy 166.530938 -272.029705)
			(xy 166.546522 -272.076386) (xy 166.554417 -272.124963) (xy 166.554912 -272.14957) (xy 167.843974 -272.14957)
			(xy 167.847934 -272.100516) (xy 167.859711 -272.052732) (xy 167.879002 -272.007456) (xy 167.905305 -271.96586)
			(xy 167.93794 -271.929023) (xy 167.976061 -271.897898) (xy 168.018682 -271.873291) (xy 168.064698 -271.855839)
			(xy 168.112917 -271.845995) (xy 168.162092 -271.844014) (xy 168.210947 -271.849946) (xy 168.258218 -271.863638)
			(xy 168.30268 -271.884736) (xy 168.343183 -271.912692) (xy 168.378676 -271.946784) (xy 168.408241 -271.986128)
			(xy 168.431112 -272.029705) (xy 168.446696 -272.076386) (xy 168.454591 -272.124963) (xy 168.455086 -272.14957)
			(xy 169.743894 -272.14957) (xy 169.747854 -272.100516) (xy 169.759631 -272.052732) (xy 169.778922 -272.007456)
			(xy 169.805225 -271.96586) (xy 169.83786 -271.929023) (xy 169.875981 -271.897898) (xy 169.918602 -271.873291)
			(xy 169.964618 -271.855839) (xy 170.012837 -271.845995) (xy 170.062012 -271.844014) (xy 170.110867 -271.849946)
			(xy 170.158138 -271.863638) (xy 170.2026 -271.884736) (xy 170.243103 -271.912692) (xy 170.278596 -271.946784)
			(xy 170.308161 -271.986128) (xy 170.331032 -272.029705) (xy 170.346616 -272.076386) (xy 170.354511 -272.124963)
			(xy 170.355006 -272.14957) (xy 171.643814 -272.14957) (xy 171.647774 -272.100516) (xy 171.659551 -272.052732)
			(xy 171.678842 -272.007456) (xy 171.705145 -271.96586) (xy 171.73778 -271.929023) (xy 171.775901 -271.897898)
			(xy 171.818522 -271.873291) (xy 171.864538 -271.855839) (xy 171.912757 -271.845995) (xy 171.961932 -271.844014)
			(xy 172.010787 -271.849946) (xy 172.058058 -271.863638) (xy 172.10252 -271.884736) (xy 172.143023 -271.912692)
			(xy 172.178516 -271.946784) (xy 172.208081 -271.986128) (xy 172.230952 -272.029705) (xy 172.246536 -272.076386)
			(xy 172.254431 -272.124963) (xy 172.254926 -272.14957) (xy 173.543988 -272.14957) (xy 173.547948 -272.100516)
			(xy 173.559725 -272.052732) (xy 173.579016 -272.007456) (xy 173.605319 -271.96586) (xy 173.637954 -271.929023)
			(xy 173.676075 -271.897898) (xy 173.718696 -271.873291) (xy 173.764712 -271.855839) (xy 173.812931 -271.845995)
			(xy 173.862106 -271.844014) (xy 173.910961 -271.849946) (xy 173.958232 -271.863638) (xy 174.002694 -271.884736)
			(xy 174.043197 -271.912692) (xy 174.07869 -271.946784) (xy 174.108255 -271.986128) (xy 174.131126 -272.029705)
			(xy 174.14671 -272.076386) (xy 174.154605 -272.124963) (xy 174.155095 -272.149316) (xy 175.443908 -272.149316)
			(xy 175.447868 -272.100262) (xy 175.459645 -272.052478) (xy 175.478936 -272.007202) (xy 175.505239 -271.965606)
			(xy 175.537874 -271.928769) (xy 175.575995 -271.897644) (xy 175.618616 -271.873037) (xy 175.664632 -271.855585)
			(xy 175.712851 -271.845741) (xy 175.762026 -271.84376) (xy 175.810881 -271.849692) (xy 175.858152 -271.863384)
			(xy 175.902614 -271.884482) (xy 175.943117 -271.912438) (xy 175.97861 -271.94653) (xy 176.008175 -271.985874)
			(xy 176.031046 -272.029451) (xy 176.04663 -272.076132) (xy 176.054525 -272.124709) (xy 176.05502 -272.149316)
			(xy 176.055015 -272.14957) (xy 177.343828 -272.14957) (xy 177.347788 -272.100516) (xy 177.359565 -272.052732)
			(xy 177.378856 -272.007456) (xy 177.405159 -271.96586) (xy 177.437794 -271.929023) (xy 177.475915 -271.897898)
			(xy 177.518536 -271.873291) (xy 177.564552 -271.855839) (xy 177.612771 -271.845995) (xy 177.661946 -271.844014)
			(xy 177.710801 -271.849946) (xy 177.758072 -271.863638) (xy 177.802534 -271.884736) (xy 177.843037 -271.912692)
			(xy 177.87853 -271.946784) (xy 177.908095 -271.986128) (xy 177.930966 -272.029705) (xy 177.94655 -272.076386)
			(xy 177.954445 -272.124963) (xy 177.95494 -272.14957) (xy 179.244002 -272.14957) (xy 179.247962 -272.100516)
			(xy 179.259739 -272.052732) (xy 179.27903 -272.007456) (xy 179.305333 -271.96586) (xy 179.337968 -271.929023)
			(xy 179.376089 -271.897898) (xy 179.41871 -271.873291) (xy 179.464726 -271.855839) (xy 179.512945 -271.845995)
			(xy 179.56212 -271.844014) (xy 179.610975 -271.849946) (xy 179.658246 -271.863638) (xy 179.702708 -271.884736)
			(xy 179.743211 -271.912692) (xy 179.778704 -271.946784) (xy 179.808269 -271.986128) (xy 179.83114 -272.029705)
			(xy 179.846724 -272.076386) (xy 179.854619 -272.124963) (xy 179.855114 -272.14957) (xy 181.143922 -272.14957)
			(xy 181.147882 -272.100516) (xy 181.159659 -272.052732) (xy 181.17895 -272.007456) (xy 181.205253 -271.96586)
			(xy 181.237888 -271.929023) (xy 181.276009 -271.897898) (xy 181.31863 -271.873291) (xy 181.364646 -271.855839)
			(xy 181.412865 -271.845995) (xy 181.46204 -271.844014) (xy 181.510895 -271.849946) (xy 181.558166 -271.863638)
			(xy 181.602628 -271.884736) (xy 181.643131 -271.912692) (xy 181.678624 -271.946784) (xy 181.708189 -271.986128)
			(xy 181.73106 -272.029705) (xy 181.746644 -272.076386) (xy 181.754539 -272.124963) (xy 181.755034 -272.14957)
			(xy 183.043842 -272.14957) (xy 183.047802 -272.100516) (xy 183.059579 -272.052732) (xy 183.07887 -272.007456)
			(xy 183.105173 -271.96586) (xy 183.137808 -271.929023) (xy 183.175929 -271.897898) (xy 183.21855 -271.873291)
			(xy 183.264566 -271.855839) (xy 183.312785 -271.845995) (xy 183.36196 -271.844014) (xy 183.410815 -271.849946)
			(xy 183.458086 -271.863638) (xy 183.502548 -271.884736) (xy 183.543051 -271.912692) (xy 183.578544 -271.946784)
			(xy 183.608109 -271.986128) (xy 183.63098 -272.029705) (xy 183.646564 -272.076386) (xy 183.654459 -272.124963)
			(xy 183.654954 -272.14957) (xy 184.944016 -272.14957) (xy 184.947976 -272.100516) (xy 184.959753 -272.052732)
			(xy 184.979044 -272.007456) (xy 185.005347 -271.96586) (xy 185.037982 -271.929023) (xy 185.076103 -271.897898)
			(xy 185.118724 -271.873291) (xy 185.16474 -271.855839) (xy 185.212959 -271.845995) (xy 185.262134 -271.844014)
			(xy 185.310989 -271.849946) (xy 185.35826 -271.863638) (xy 185.402722 -271.884736) (xy 185.443225 -271.912692)
			(xy 185.478718 -271.946784) (xy 185.508283 -271.986128) (xy 185.531154 -272.029705) (xy 185.546738 -272.076386)
			(xy 185.554633 -272.124963) (xy 185.555128 -272.14957) (xy 186.843936 -272.14957) (xy 186.847896 -272.100516)
			(xy 186.859673 -272.052732) (xy 186.878964 -272.007456) (xy 186.905267 -271.96586) (xy 186.937902 -271.929023)
			(xy 186.976023 -271.897898) (xy 187.018644 -271.873291) (xy 187.06466 -271.855839) (xy 187.112879 -271.845995)
			(xy 187.162054 -271.844014) (xy 187.210909 -271.849946) (xy 187.25818 -271.863638) (xy 187.302642 -271.884736)
			(xy 187.343145 -271.912692) (xy 187.378638 -271.946784) (xy 187.408203 -271.986128) (xy 187.431074 -272.029705)
			(xy 187.446658 -272.076386) (xy 187.454553 -272.124963) (xy 187.455048 -272.14957) (xy 188.743856 -272.14957)
			(xy 188.747816 -272.100516) (xy 188.759593 -272.052732) (xy 188.778884 -272.007456) (xy 188.805187 -271.96586)
			(xy 188.837822 -271.929023) (xy 188.875943 -271.897898) (xy 188.918564 -271.873291) (xy 188.96458 -271.855839)
			(xy 189.012799 -271.845995) (xy 189.061974 -271.844014) (xy 189.110829 -271.849946) (xy 189.1581 -271.863638)
			(xy 189.202562 -271.884736) (xy 189.243065 -271.912692) (xy 189.278558 -271.946784) (xy 189.308123 -271.986128)
			(xy 189.330994 -272.029705) (xy 189.346578 -272.076386) (xy 189.354473 -272.124963) (xy 189.354968 -272.14957)
			(xy 190.64403 -272.14957) (xy 190.64799 -272.100516) (xy 190.659767 -272.052732) (xy 190.679058 -272.007456)
			(xy 190.705361 -271.96586) (xy 190.737996 -271.929023) (xy 190.776117 -271.897898) (xy 190.818738 -271.873291)
			(xy 190.864754 -271.855839) (xy 190.912973 -271.845995) (xy 190.962148 -271.844014) (xy 191.011003 -271.849946)
			(xy 191.058274 -271.863638) (xy 191.102736 -271.884736) (xy 191.143239 -271.912692) (xy 191.178732 -271.946784)
			(xy 191.208297 -271.986128) (xy 191.231168 -272.029705) (xy 191.246752 -272.076386) (xy 191.254647 -272.124963)
			(xy 191.255142 -272.14957) (xy 192.544204 -272.14957) (xy 192.548164 -272.100516) (xy 192.559941 -272.052732)
			(xy 192.579232 -272.007456) (xy 192.605535 -271.96586) (xy 192.63817 -271.929023) (xy 192.676291 -271.897898)
			(xy 192.718912 -271.873291) (xy 192.764928 -271.855839) (xy 192.813147 -271.845995) (xy 192.862322 -271.844014)
			(xy 192.911177 -271.849946) (xy 192.958448 -271.863638) (xy 193.00291 -271.884736) (xy 193.043413 -271.912692)
			(xy 193.078906 -271.946784) (xy 193.108471 -271.986128) (xy 193.131342 -272.029705) (xy 193.146926 -272.076386)
			(xy 193.154821 -272.124963) (xy 193.155316 -272.14957) (xy 194.444124 -272.14957) (xy 194.448084 -272.100516)
			(xy 194.459861 -272.052732) (xy 194.479152 -272.007456) (xy 194.505455 -271.96586) (xy 194.53809 -271.929023)
			(xy 194.576211 -271.897898) (xy 194.618832 -271.873291) (xy 194.664848 -271.855839) (xy 194.713067 -271.845995)
			(xy 194.762242 -271.844014) (xy 194.811097 -271.849946) (xy 194.858368 -271.863638) (xy 194.90283 -271.884736)
			(xy 194.943333 -271.912692) (xy 194.978826 -271.946784) (xy 195.008391 -271.986128) (xy 195.031262 -272.029705)
			(xy 195.046846 -272.076386) (xy 195.054741 -272.124963) (xy 195.055236 -272.14957) (xy 196.344044 -272.14957)
			(xy 196.348004 -272.100516) (xy 196.359781 -272.052732) (xy 196.379072 -272.007456) (xy 196.405375 -271.96586)
			(xy 196.43801 -271.929023) (xy 196.476131 -271.897898) (xy 196.518752 -271.873291) (xy 196.564768 -271.855839)
			(xy 196.612987 -271.845995) (xy 196.662162 -271.844014) (xy 196.711017 -271.849946) (xy 196.758288 -271.863638)
			(xy 196.80275 -271.884736) (xy 196.843253 -271.912692) (xy 196.878746 -271.946784) (xy 196.908311 -271.986128)
			(xy 196.931182 -272.029705) (xy 196.946766 -272.076386) (xy 196.954661 -272.124963) (xy 196.955156 -272.14957)
			(xy 196.954661 -272.174177) (xy 196.946766 -272.222754) (xy 196.931182 -272.269435) (xy 196.908311 -272.313012)
			(xy 196.878746 -272.352356) (xy 196.843253 -272.386448) (xy 196.80275 -272.414404) (xy 196.758288 -272.435502)
			(xy 196.711017 -272.449194) (xy 196.662162 -272.455126) (xy 196.612987 -272.453145) (xy 196.564768 -272.443301)
			(xy 196.518752 -272.425849) (xy 196.476131 -272.401242) (xy 196.43801 -272.370117) (xy 196.405375 -272.33328)
			(xy 196.379072 -272.291684) (xy 196.359781 -272.246408) (xy 196.348004 -272.198624) (xy 196.344044 -272.14957)
			(xy 195.055236 -272.14957) (xy 195.054741 -272.174177) (xy 195.046846 -272.222754) (xy 195.031262 -272.269435)
			(xy 195.008391 -272.313012) (xy 194.978826 -272.352356) (xy 194.943333 -272.386448) (xy 194.90283 -272.414404)
			(xy 194.858368 -272.435502) (xy 194.811097 -272.449194) (xy 194.762242 -272.455126) (xy 194.713067 -272.453145)
			(xy 194.664848 -272.443301) (xy 194.618832 -272.425849) (xy 194.576211 -272.401242) (xy 194.53809 -272.370117)
			(xy 194.505455 -272.33328) (xy 194.479152 -272.291684) (xy 194.459861 -272.246408) (xy 194.448084 -272.198624)
			(xy 194.444124 -272.14957) (xy 193.155316 -272.14957) (xy 193.154821 -272.174177) (xy 193.146926 -272.222754)
			(xy 193.131342 -272.269435) (xy 193.108471 -272.313012) (xy 193.078906 -272.352356) (xy 193.043413 -272.386448)
			(xy 193.00291 -272.414404) (xy 192.958448 -272.435502) (xy 192.911177 -272.449194) (xy 192.862322 -272.455126)
			(xy 192.813147 -272.453145) (xy 192.764928 -272.443301) (xy 192.718912 -272.425849) (xy 192.676291 -272.401242)
			(xy 192.63817 -272.370117) (xy 192.605535 -272.33328) (xy 192.579232 -272.291684) (xy 192.559941 -272.246408)
			(xy 192.548164 -272.198624) (xy 192.544204 -272.14957) (xy 191.255142 -272.14957) (xy 191.254647 -272.174177)
			(xy 191.246752 -272.222754) (xy 191.231168 -272.269435) (xy 191.208297 -272.313012) (xy 191.178732 -272.352356)
			(xy 191.143239 -272.386448) (xy 191.102736 -272.414404) (xy 191.058274 -272.435502) (xy 191.011003 -272.449194)
			(xy 190.962148 -272.455126) (xy 190.912973 -272.453145) (xy 190.864754 -272.443301) (xy 190.818738 -272.425849)
			(xy 190.776117 -272.401242) (xy 190.737996 -272.370117) (xy 190.705361 -272.33328) (xy 190.679058 -272.291684)
			(xy 190.659767 -272.246408) (xy 190.64799 -272.198624) (xy 190.64403 -272.14957) (xy 189.354968 -272.14957)
			(xy 189.354473 -272.174177) (xy 189.346578 -272.222754) (xy 189.330994 -272.269435) (xy 189.308123 -272.313012)
			(xy 189.278558 -272.352356) (xy 189.243065 -272.386448) (xy 189.202562 -272.414404) (xy 189.1581 -272.435502)
			(xy 189.110829 -272.449194) (xy 189.061974 -272.455126) (xy 189.012799 -272.453145) (xy 188.96458 -272.443301)
			(xy 188.918564 -272.425849) (xy 188.875943 -272.401242) (xy 188.837822 -272.370117) (xy 188.805187 -272.33328)
			(xy 188.778884 -272.291684) (xy 188.759593 -272.246408) (xy 188.747816 -272.198624) (xy 188.743856 -272.14957)
			(xy 187.455048 -272.14957) (xy 187.454553 -272.174177) (xy 187.446658 -272.222754) (xy 187.431074 -272.269435)
			(xy 187.408203 -272.313012) (xy 187.378638 -272.352356) (xy 187.343145 -272.386448) (xy 187.302642 -272.414404)
			(xy 187.25818 -272.435502) (xy 187.210909 -272.449194) (xy 187.162054 -272.455126) (xy 187.112879 -272.453145)
			(xy 187.06466 -272.443301) (xy 187.018644 -272.425849) (xy 186.976023 -272.401242) (xy 186.937902 -272.370117)
			(xy 186.905267 -272.33328) (xy 186.878964 -272.291684) (xy 186.859673 -272.246408) (xy 186.847896 -272.198624)
			(xy 186.843936 -272.14957) (xy 185.555128 -272.14957) (xy 185.554633 -272.174177) (xy 185.546738 -272.222754)
			(xy 185.531154 -272.269435) (xy 185.508283 -272.313012) (xy 185.478718 -272.352356) (xy 185.443225 -272.386448)
			(xy 185.402722 -272.414404) (xy 185.35826 -272.435502) (xy 185.310989 -272.449194) (xy 185.262134 -272.455126)
			(xy 185.212959 -272.453145) (xy 185.16474 -272.443301) (xy 185.118724 -272.425849) (xy 185.076103 -272.401242)
			(xy 185.037982 -272.370117) (xy 185.005347 -272.33328) (xy 184.979044 -272.291684) (xy 184.959753 -272.246408)
			(xy 184.947976 -272.198624) (xy 184.944016 -272.14957) (xy 183.654954 -272.14957) (xy 183.654459 -272.174177)
			(xy 183.646564 -272.222754) (xy 183.63098 -272.269435) (xy 183.608109 -272.313012) (xy 183.578544 -272.352356)
			(xy 183.543051 -272.386448) (xy 183.502548 -272.414404) (xy 183.458086 -272.435502) (xy 183.410815 -272.449194)
			(xy 183.36196 -272.455126) (xy 183.312785 -272.453145) (xy 183.264566 -272.443301) (xy 183.21855 -272.425849)
			(xy 183.175929 -272.401242) (xy 183.137808 -272.370117) (xy 183.105173 -272.33328) (xy 183.07887 -272.291684)
			(xy 183.059579 -272.246408) (xy 183.047802 -272.198624) (xy 183.043842 -272.14957) (xy 181.755034 -272.14957)
			(xy 181.754539 -272.174177) (xy 181.746644 -272.222754) (xy 181.73106 -272.269435) (xy 181.708189 -272.313012)
			(xy 181.678624 -272.352356) (xy 181.643131 -272.386448) (xy 181.602628 -272.414404) (xy 181.558166 -272.435502)
			(xy 181.510895 -272.449194) (xy 181.46204 -272.455126) (xy 181.412865 -272.453145) (xy 181.364646 -272.443301)
			(xy 181.31863 -272.425849) (xy 181.276009 -272.401242) (xy 181.237888 -272.370117) (xy 181.205253 -272.33328)
			(xy 181.17895 -272.291684) (xy 181.159659 -272.246408) (xy 181.147882 -272.198624) (xy 181.143922 -272.14957)
			(xy 179.855114 -272.14957) (xy 179.854619 -272.174177) (xy 179.846724 -272.222754) (xy 179.83114 -272.269435)
			(xy 179.808269 -272.313012) (xy 179.778704 -272.352356) (xy 179.743211 -272.386448) (xy 179.702708 -272.414404)
			(xy 179.658246 -272.435502) (xy 179.610975 -272.449194) (xy 179.56212 -272.455126) (xy 179.512945 -272.453145)
			(xy 179.464726 -272.443301) (xy 179.41871 -272.425849) (xy 179.376089 -272.401242) (xy 179.337968 -272.370117)
			(xy 179.305333 -272.33328) (xy 179.27903 -272.291684) (xy 179.259739 -272.246408) (xy 179.247962 -272.198624)
			(xy 179.244002 -272.14957) (xy 177.95494 -272.14957) (xy 177.954445 -272.174177) (xy 177.94655 -272.222754)
			(xy 177.930966 -272.269435) (xy 177.908095 -272.313012) (xy 177.87853 -272.352356) (xy 177.843037 -272.386448)
			(xy 177.802534 -272.414404) (xy 177.758072 -272.435502) (xy 177.710801 -272.449194) (xy 177.661946 -272.455126)
			(xy 177.612771 -272.453145) (xy 177.564552 -272.443301) (xy 177.518536 -272.425849) (xy 177.475915 -272.401242)
			(xy 177.437794 -272.370117) (xy 177.405159 -272.33328) (xy 177.378856 -272.291684) (xy 177.359565 -272.246408)
			(xy 177.347788 -272.198624) (xy 177.343828 -272.14957) (xy 176.055015 -272.14957) (xy 176.054525 -272.173923)
			(xy 176.04663 -272.2225) (xy 176.031046 -272.269181) (xy 176.008175 -272.312758) (xy 175.97861 -272.352102)
			(xy 175.943117 -272.386194) (xy 175.902614 -272.41415) (xy 175.858152 -272.435248) (xy 175.810881 -272.44894)
			(xy 175.762026 -272.454872) (xy 175.712851 -272.452891) (xy 175.664632 -272.443047) (xy 175.618616 -272.425595)
			(xy 175.575995 -272.400988) (xy 175.537874 -272.369863) (xy 175.505239 -272.333026) (xy 175.478936 -272.29143)
			(xy 175.459645 -272.246154) (xy 175.447868 -272.19837) (xy 175.443908 -272.149316) (xy 174.155095 -272.149316)
			(xy 174.1551 -272.14957) (xy 174.154605 -272.174177) (xy 174.14671 -272.222754) (xy 174.131126 -272.269435)
			(xy 174.108255 -272.313012) (xy 174.07869 -272.352356) (xy 174.043197 -272.386448) (xy 174.002694 -272.414404)
			(xy 173.958232 -272.435502) (xy 173.910961 -272.449194) (xy 173.862106 -272.455126) (xy 173.812931 -272.453145)
			(xy 173.764712 -272.443301) (xy 173.718696 -272.425849) (xy 173.676075 -272.401242) (xy 173.637954 -272.370117)
			(xy 173.605319 -272.33328) (xy 173.579016 -272.291684) (xy 173.559725 -272.246408) (xy 173.547948 -272.198624)
			(xy 173.543988 -272.14957) (xy 172.254926 -272.14957) (xy 172.254431 -272.174177) (xy 172.246536 -272.222754)
			(xy 172.230952 -272.269435) (xy 172.208081 -272.313012) (xy 172.178516 -272.352356) (xy 172.143023 -272.386448)
			(xy 172.10252 -272.414404) (xy 172.058058 -272.435502) (xy 172.010787 -272.449194) (xy 171.961932 -272.455126)
			(xy 171.912757 -272.453145) (xy 171.864538 -272.443301) (xy 171.818522 -272.425849) (xy 171.775901 -272.401242)
			(xy 171.73778 -272.370117) (xy 171.705145 -272.33328) (xy 171.678842 -272.291684) (xy 171.659551 -272.246408)
			(xy 171.647774 -272.198624) (xy 171.643814 -272.14957) (xy 170.355006 -272.14957) (xy 170.354511 -272.174177)
			(xy 170.346616 -272.222754) (xy 170.331032 -272.269435) (xy 170.308161 -272.313012) (xy 170.278596 -272.352356)
			(xy 170.243103 -272.386448) (xy 170.2026 -272.414404) (xy 170.158138 -272.435502) (xy 170.110867 -272.449194)
			(xy 170.062012 -272.455126) (xy 170.012837 -272.453145) (xy 169.964618 -272.443301) (xy 169.918602 -272.425849)
			(xy 169.875981 -272.401242) (xy 169.83786 -272.370117) (xy 169.805225 -272.33328) (xy 169.778922 -272.291684)
			(xy 169.759631 -272.246408) (xy 169.747854 -272.198624) (xy 169.743894 -272.14957) (xy 168.455086 -272.14957)
			(xy 168.454591 -272.174177) (xy 168.446696 -272.222754) (xy 168.431112 -272.269435) (xy 168.408241 -272.313012)
			(xy 168.378676 -272.352356) (xy 168.343183 -272.386448) (xy 168.30268 -272.414404) (xy 168.258218 -272.435502)
			(xy 168.210947 -272.449194) (xy 168.162092 -272.455126) (xy 168.112917 -272.453145) (xy 168.064698 -272.443301)
			(xy 168.018682 -272.425849) (xy 167.976061 -272.401242) (xy 167.93794 -272.370117) (xy 167.905305 -272.33328)
			(xy 167.879002 -272.291684) (xy 167.859711 -272.246408) (xy 167.847934 -272.198624) (xy 167.843974 -272.14957)
			(xy 166.554912 -272.14957) (xy 166.554417 -272.174177) (xy 166.546522 -272.222754) (xy 166.530938 -272.269435)
			(xy 166.508067 -272.313012) (xy 166.478502 -272.352356) (xy 166.443009 -272.386448) (xy 166.402506 -272.414404)
			(xy 166.358044 -272.435502) (xy 166.310773 -272.449194) (xy 166.261918 -272.455126) (xy 166.212743 -272.453145)
			(xy 166.164524 -272.443301) (xy 166.118508 -272.425849) (xy 166.075887 -272.401242) (xy 166.037766 -272.370117)
			(xy 166.005131 -272.33328) (xy 165.978828 -272.291684) (xy 165.959537 -272.246408) (xy 165.94776 -272.198624)
			(xy 165.9438 -272.14957) (xy 164.654992 -272.14957) (xy 164.654497 -272.174177) (xy 164.646602 -272.222754)
			(xy 164.631018 -272.269435) (xy 164.608147 -272.313012) (xy 164.578582 -272.352356) (xy 164.543089 -272.386448)
			(xy 164.502586 -272.414404) (xy 164.458124 -272.435502) (xy 164.410853 -272.449194) (xy 164.361998 -272.455126)
			(xy 164.312823 -272.453145) (xy 164.264604 -272.443301) (xy 164.218588 -272.425849) (xy 164.175967 -272.401242)
			(xy 164.137846 -272.370117) (xy 164.105211 -272.33328) (xy 164.078908 -272.291684) (xy 164.059617 -272.246408)
			(xy 164.04784 -272.198624) (xy 164.04388 -272.14957) (xy 162.755072 -272.14957) (xy 162.754577 -272.174177)
			(xy 162.746682 -272.222754) (xy 162.731098 -272.269435) (xy 162.708227 -272.313012) (xy 162.678662 -272.352356)
			(xy 162.643169 -272.386448) (xy 162.602666 -272.414404) (xy 162.558204 -272.435502) (xy 162.510933 -272.449194)
			(xy 162.462078 -272.455126) (xy 162.412903 -272.453145) (xy 162.364684 -272.443301) (xy 162.318668 -272.425849)
			(xy 162.276047 -272.401242) (xy 162.237926 -272.370117) (xy 162.205291 -272.33328) (xy 162.178988 -272.291684)
			(xy 162.159697 -272.246408) (xy 162.14792 -272.198624) (xy 162.14396 -272.14957) (xy 160.854898 -272.14957)
			(xy 160.854403 -272.174177) (xy 160.846508 -272.222754) (xy 160.830924 -272.269435) (xy 160.808053 -272.313012)
			(xy 160.778488 -272.352356) (xy 160.742995 -272.386448) (xy 160.702492 -272.414404) (xy 160.65803 -272.435502)
			(xy 160.610759 -272.449194) (xy 160.561904 -272.455126) (xy 160.512729 -272.453145) (xy 160.46451 -272.443301)
			(xy 160.418494 -272.425849) (xy 160.375873 -272.401242) (xy 160.337752 -272.370117) (xy 160.305117 -272.33328)
			(xy 160.278814 -272.291684) (xy 160.259523 -272.246408) (xy 160.247746 -272.198624) (xy 160.243786 -272.14957)
			(xy 150.333461 -272.14957) (xy 150.332574 -272.153097) (xy 150.277259 -272.340187) (xy 150.214311 -272.524849)
			(xy 150.175588 -272.624804) (xy 154.0693 -272.624804) (xy 154.07326 -272.57575) (xy 154.085037 -272.527966)
			(xy 154.104328 -272.48269) (xy 154.130631 -272.441094) (xy 154.163266 -272.404257) (xy 154.201387 -272.373132)
			(xy 154.244008 -272.348525) (xy 154.290024 -272.331073) (xy 154.338243 -272.321229) (xy 154.387418 -272.319248)
			(xy 154.436273 -272.32518) (xy 154.483544 -272.338872) (xy 154.528006 -272.35997) (xy 154.568509 -272.387926)
			(xy 154.604002 -272.422018) (xy 154.633567 -272.461362) (xy 154.656438 -272.504939) (xy 154.672022 -272.55162)
			(xy 154.679917 -272.600197) (xy 154.680412 -272.624804) (xy 155.01926 -272.624804) (xy 155.02322 -272.57575)
			(xy 155.034997 -272.527966) (xy 155.054288 -272.48269) (xy 155.080591 -272.441094) (xy 155.113226 -272.404257)
			(xy 155.151347 -272.373132) (xy 155.193968 -272.348525) (xy 155.239984 -272.331073) (xy 155.288203 -272.321229)
			(xy 155.337378 -272.319248) (xy 155.386233 -272.32518) (xy 155.433504 -272.338872) (xy 155.477966 -272.35997)
			(xy 155.518469 -272.387926) (xy 155.553962 -272.422018) (xy 155.583527 -272.461362) (xy 155.606398 -272.504939)
			(xy 155.621982 -272.55162) (xy 155.629877 -272.600197) (xy 155.630372 -272.624804) (xy 155.96922 -272.624804)
			(xy 155.97318 -272.57575) (xy 155.984957 -272.527966) (xy 156.004248 -272.48269) (xy 156.030551 -272.441094)
			(xy 156.063186 -272.404257) (xy 156.101307 -272.373132) (xy 156.143928 -272.348525) (xy 156.189944 -272.331073)
			(xy 156.238163 -272.321229) (xy 156.287338 -272.319248) (xy 156.336193 -272.32518) (xy 156.383464 -272.338872)
			(xy 156.427926 -272.35997) (xy 156.468429 -272.387926) (xy 156.503922 -272.422018) (xy 156.533487 -272.461362)
			(xy 156.556358 -272.504939) (xy 156.571942 -272.55162) (xy 156.579837 -272.600197) (xy 156.580332 -272.624804)
			(xy 156.91918 -272.624804) (xy 156.92314 -272.57575) (xy 156.934917 -272.527966) (xy 156.954208 -272.48269)
			(xy 156.980511 -272.441094) (xy 157.013146 -272.404257) (xy 157.051267 -272.373132) (xy 157.093888 -272.348525)
			(xy 157.139904 -272.331073) (xy 157.188123 -272.321229) (xy 157.237298 -272.319248) (xy 157.286153 -272.32518)
			(xy 157.333424 -272.338872) (xy 157.377886 -272.35997) (xy 157.418389 -272.387926) (xy 157.453882 -272.422018)
			(xy 157.483447 -272.461362) (xy 157.506318 -272.504939) (xy 157.521902 -272.55162) (xy 157.529797 -272.600197)
			(xy 157.530292 -272.624804) (xy 157.86914 -272.624804) (xy 157.8731 -272.57575) (xy 157.884877 -272.527966)
			(xy 157.904168 -272.48269) (xy 157.930471 -272.441094) (xy 157.963106 -272.404257) (xy 158.001227 -272.373132)
			(xy 158.043848 -272.348525) (xy 158.089864 -272.331073) (xy 158.138083 -272.321229) (xy 158.187258 -272.319248)
			(xy 158.236113 -272.32518) (xy 158.283384 -272.338872) (xy 158.327846 -272.35997) (xy 158.368349 -272.387926)
			(xy 158.403842 -272.422018) (xy 158.433407 -272.461362) (xy 158.456278 -272.504939) (xy 158.471862 -272.55162)
			(xy 158.479757 -272.600197) (xy 158.480252 -272.624804) (xy 158.479757 -272.649411) (xy 158.471862 -272.697988)
			(xy 158.456278 -272.744669) (xy 158.433407 -272.788246) (xy 158.403842 -272.82759) (xy 158.368349 -272.861682)
			(xy 158.327846 -272.889638) (xy 158.283384 -272.910736) (xy 158.236113 -272.924428) (xy 158.187258 -272.93036)
			(xy 158.138083 -272.928379) (xy 158.089864 -272.918535) (xy 158.043848 -272.901083) (xy 158.001227 -272.876476)
			(xy 157.963106 -272.845351) (xy 157.930471 -272.808514) (xy 157.904168 -272.766918) (xy 157.884877 -272.721642)
			(xy 157.8731 -272.673858) (xy 157.86914 -272.624804) (xy 157.530292 -272.624804) (xy 157.529797 -272.649411)
			(xy 157.521902 -272.697988) (xy 157.506318 -272.744669) (xy 157.483447 -272.788246) (xy 157.453882 -272.82759)
			(xy 157.418389 -272.861682) (xy 157.377886 -272.889638) (xy 157.333424 -272.910736) (xy 157.286153 -272.924428)
			(xy 157.237298 -272.93036) (xy 157.188123 -272.928379) (xy 157.139904 -272.918535) (xy 157.093888 -272.901083)
			(xy 157.051267 -272.876476) (xy 157.013146 -272.845351) (xy 156.980511 -272.808514) (xy 156.954208 -272.766918)
			(xy 156.934917 -272.721642) (xy 156.92314 -272.673858) (xy 156.91918 -272.624804) (xy 156.580332 -272.624804)
			(xy 156.579837 -272.649411) (xy 156.571942 -272.697988) (xy 156.556358 -272.744669) (xy 156.533487 -272.788246)
			(xy 156.503922 -272.82759) (xy 156.468429 -272.861682) (xy 156.427926 -272.889638) (xy 156.383464 -272.910736)
			(xy 156.336193 -272.924428) (xy 156.287338 -272.93036) (xy 156.238163 -272.928379) (xy 156.189944 -272.918535)
			(xy 156.143928 -272.901083) (xy 156.101307 -272.876476) (xy 156.063186 -272.845351) (xy 156.030551 -272.808514)
			(xy 156.004248 -272.766918) (xy 155.984957 -272.721642) (xy 155.97318 -272.673858) (xy 155.96922 -272.624804)
			(xy 155.630372 -272.624804) (xy 155.629877 -272.649411) (xy 155.621982 -272.697988) (xy 155.606398 -272.744669)
			(xy 155.583527 -272.788246) (xy 155.553962 -272.82759) (xy 155.518469 -272.861682) (xy 155.477966 -272.889638)
			(xy 155.433504 -272.910736) (xy 155.386233 -272.924428) (xy 155.337378 -272.93036) (xy 155.288203 -272.928379)
			(xy 155.239984 -272.918535) (xy 155.193968 -272.901083) (xy 155.151347 -272.876476) (xy 155.113226 -272.845351)
			(xy 155.080591 -272.808514) (xy 155.054288 -272.766918) (xy 155.034997 -272.721642) (xy 155.02322 -272.673858)
			(xy 155.01926 -272.624804) (xy 154.680412 -272.624804) (xy 154.679917 -272.649411) (xy 154.672022 -272.697988)
			(xy 154.656438 -272.744669) (xy 154.633567 -272.788246) (xy 154.604002 -272.82759) (xy 154.568509 -272.861682)
			(xy 154.528006 -272.889638) (xy 154.483544 -272.910736) (xy 154.436273 -272.924428) (xy 154.387418 -272.93036)
			(xy 154.338243 -272.928379) (xy 154.290024 -272.918535) (xy 154.244008 -272.901083) (xy 154.201387 -272.876476)
			(xy 154.163266 -272.845351) (xy 154.130631 -272.808514) (xy 154.104328 -272.766918) (xy 154.085037 -272.721642)
			(xy 154.07326 -272.673858) (xy 154.0693 -272.624804) (xy 150.175588 -272.624804) (xy 150.143834 -272.706771)
			(xy 150.065948 -272.885646) (xy 149.980783 -273.061172) (xy 149.888485 -273.233055) (xy 149.789207 -273.401002)
			(xy 149.683118 -273.564733) (xy 149.676017 -273.574764) (xy 153.119086 -273.574764) (xy 153.123046 -273.52571)
			(xy 153.134823 -273.477926) (xy 153.154114 -273.43265) (xy 153.180417 -273.391054) (xy 153.213052 -273.354217)
			(xy 153.251173 -273.323092) (xy 153.293794 -273.298485) (xy 153.33981 -273.281033) (xy 153.388029 -273.271189)
			(xy 153.437204 -273.269208) (xy 153.486059 -273.27514) (xy 153.53333 -273.288832) (xy 153.577792 -273.30993)
			(xy 153.618295 -273.337886) (xy 153.653788 -273.371978) (xy 153.683353 -273.411322) (xy 153.706224 -273.454899)
			(xy 153.721808 -273.50158) (xy 153.729703 -273.550157) (xy 153.730198 -273.574764) (xy 154.069046 -273.574764)
			(xy 154.073006 -273.52571) (xy 154.084783 -273.477926) (xy 154.104074 -273.43265) (xy 154.130377 -273.391054)
			(xy 154.163012 -273.354217) (xy 154.201133 -273.323092) (xy 154.243754 -273.298485) (xy 154.28977 -273.281033)
			(xy 154.337989 -273.271189) (xy 154.387164 -273.269208) (xy 154.436019 -273.27514) (xy 154.48329 -273.288832)
			(xy 154.527752 -273.30993) (xy 154.568255 -273.337886) (xy 154.603748 -273.371978) (xy 154.633313 -273.411322)
			(xy 154.656184 -273.454899) (xy 154.671768 -273.50158) (xy 154.679663 -273.550157) (xy 154.680158 -273.574764)
			(xy 155.01926 -273.574764) (xy 155.02322 -273.52571) (xy 155.034997 -273.477926) (xy 155.054288 -273.43265)
			(xy 155.080591 -273.391054) (xy 155.113226 -273.354217) (xy 155.151347 -273.323092) (xy 155.193968 -273.298485)
			(xy 155.239984 -273.281033) (xy 155.288203 -273.271189) (xy 155.337378 -273.269208) (xy 155.386233 -273.27514)
			(xy 155.433504 -273.288832) (xy 155.477966 -273.30993) (xy 155.518469 -273.337886) (xy 155.553962 -273.371978)
			(xy 155.583527 -273.411322) (xy 155.606398 -273.454899) (xy 155.621982 -273.50158) (xy 155.629877 -273.550157)
			(xy 155.630372 -273.574764) (xy 155.96922 -273.574764) (xy 155.97318 -273.52571) (xy 155.984957 -273.477926)
			(xy 156.004248 -273.43265) (xy 156.030551 -273.391054) (xy 156.063186 -273.354217) (xy 156.101307 -273.323092)
			(xy 156.143928 -273.298485) (xy 156.189944 -273.281033) (xy 156.238163 -273.271189) (xy 156.287338 -273.269208)
			(xy 156.336193 -273.27514) (xy 156.383464 -273.288832) (xy 156.427926 -273.30993) (xy 156.468429 -273.337886)
			(xy 156.503922 -273.371978) (xy 156.533487 -273.411322) (xy 156.556358 -273.454899) (xy 156.571942 -273.50158)
			(xy 156.579837 -273.550157) (xy 156.580332 -273.574764) (xy 156.91918 -273.574764) (xy 156.92314 -273.52571)
			(xy 156.934917 -273.477926) (xy 156.954208 -273.43265) (xy 156.980511 -273.391054) (xy 157.013146 -273.354217)
			(xy 157.051267 -273.323092) (xy 157.093888 -273.298485) (xy 157.139904 -273.281033) (xy 157.188123 -273.271189)
			(xy 157.237298 -273.269208) (xy 157.286153 -273.27514) (xy 157.333424 -273.288832) (xy 157.377886 -273.30993)
			(xy 157.418389 -273.337886) (xy 157.453882 -273.371978) (xy 157.483447 -273.411322) (xy 157.506318 -273.454899)
			(xy 157.521902 -273.50158) (xy 157.529797 -273.550157) (xy 157.530292 -273.574764) (xy 157.86914 -273.574764)
			(xy 157.8731 -273.52571) (xy 157.884877 -273.477926) (xy 157.904168 -273.43265) (xy 157.930471 -273.391054)
			(xy 157.963106 -273.354217) (xy 158.001227 -273.323092) (xy 158.043848 -273.298485) (xy 158.089864 -273.281033)
			(xy 158.138083 -273.271189) (xy 158.187258 -273.269208) (xy 158.236113 -273.27514) (xy 158.283384 -273.288832)
			(xy 158.327846 -273.30993) (xy 158.368349 -273.337886) (xy 158.403842 -273.371978) (xy 158.433407 -273.411322)
			(xy 158.456278 -273.454899) (xy 158.471862 -273.50158) (xy 158.479757 -273.550157) (xy 158.480252 -273.574764)
			(xy 158.480251 -273.5748) (xy 158.819004 -273.5748) (xy 158.823176 -273.524451) (xy 158.835579 -273.475475)
			(xy 158.855873 -273.429208) (xy 158.883506 -273.386913) (xy 158.917724 -273.349744) (xy 158.957593 -273.318713)
			(xy 159.002026 -273.294667) (xy 159.04981 -273.278264) (xy 159.099643 -273.269948) (xy 159.124904 -273.269456)
			(xy 159.139087 -273.269633) (xy 159.167327 -273.272305) (xy 159.181292 -273.27479) (xy 159.193738 -273.277076)
			(xy 159.21736 -273.26971) (xy 159.29483 -273.19224) (xy 159.302196 -273.168618) (xy 159.29991 -273.156172)
			(xy 159.297434 -273.142206) (xy 159.294762 -273.113967) (xy 159.294576 -273.099784) (xy 159.294751 -273.085601)
			(xy 159.297424 -273.057361) (xy 159.29991 -273.043396) (xy 159.302196 -273.03095) (xy 159.29483 -273.007328)
			(xy 159.21736 -272.929858) (xy 159.193738 -272.922492) (xy 159.181292 -272.924778) (xy 159.167326 -272.927251)
			(xy 159.139086 -272.929925) (xy 159.124904 -272.930112) (xy 159.100083 -272.929626) (xy 159.051094 -272.921596)
			(xy 159.00405 -272.905745) (xy 158.96019 -272.882493) (xy 158.920669 -272.852451) (xy 158.88653 -272.816411)
			(xy 158.858671 -272.775322) (xy 158.837826 -272.730268) (xy 158.824545 -272.682435) (xy 158.819177 -272.633083)
			(xy 158.821865 -272.583513) (xy 158.832536 -272.535031) (xy 158.850911 -272.488914) (xy 158.876504 -272.446378)
			(xy 158.908642 -272.408542) (xy 158.946478 -272.376404) (xy 158.989014 -272.350811) (xy 159.035131 -272.332436)
			(xy 159.083613 -272.321765) (xy 159.133183 -272.319077) (xy 159.182535 -272.324445) (xy 159.230368 -272.337726)
			(xy 159.275422 -272.358571) (xy 159.316511 -272.38643) (xy 159.352551 -272.420569) (xy 159.382593 -272.46009)
			(xy 159.405845 -272.50395) (xy 159.421696 -272.550994) (xy 159.429726 -272.599983) (xy 159.430212 -272.624804)
			(xy 159.430036 -272.638987) (xy 159.427363 -272.667227) (xy 159.424878 -272.681192) (xy 159.422592 -272.693638)
			(xy 159.429958 -272.71726) (xy 159.507428 -272.79473) (xy 159.53105 -272.802096) (xy 159.543496 -272.79981)
			(xy 159.557463 -272.797338) (xy 159.585702 -272.794663) (xy 159.599884 -272.794476) (xy 159.625141 -272.794999)
			(xy 159.674967 -272.803311) (xy 159.722745 -272.819711) (xy 159.767172 -272.843752) (xy 159.807036 -272.874778)
			(xy 159.84125 -272.911941) (xy 159.868879 -272.95423) (xy 159.889171 -273.000489) (xy 159.901572 -273.049458)
			(xy 159.905744 -273.0998) (xy 159.903615 -273.125492) (xy 160.223196 -273.125492) (xy 160.223196 -273.074076)
			(xy 160.231239 -273.023294) (xy 160.247127 -272.974395) (xy 160.27047 -272.928583) (xy 160.300691 -272.886987)
			(xy 160.337047 -272.850631) (xy 160.378643 -272.82041) (xy 160.424455 -272.797067) (xy 160.473354 -272.781179)
			(xy 160.524136 -272.773136) (xy 160.575552 -272.773136) (xy 160.626334 -272.781179) (xy 160.675233 -272.797067)
			(xy 160.721045 -272.82041) (xy 160.762641 -272.850631) (xy 160.798997 -272.886987) (xy 160.829218 -272.928583)
			(xy 160.852561 -272.974395) (xy 160.868449 -273.023294) (xy 160.876492 -273.074076) (xy 160.876996 -273.099784)
			(xy 161.194254 -273.099784) (xy 161.198214 -273.05073) (xy 161.209991 -273.002946) (xy 161.229282 -272.95767)
			(xy 161.255585 -272.916074) (xy 161.28822 -272.879237) (xy 161.326341 -272.848112) (xy 161.368962 -272.823505)
			(xy 161.414978 -272.806053) (xy 161.463197 -272.796209) (xy 161.512372 -272.794228) (xy 161.561227 -272.80016)
			(xy 161.608498 -272.813852) (xy 161.65296 -272.83495) (xy 161.693463 -272.862906) (xy 161.728956 -272.896998)
			(xy 161.758521 -272.936342) (xy 161.781392 -272.979919) (xy 161.796976 -273.0266) (xy 161.804871 -273.075177)
			(xy 161.805366 -273.099784) (xy 161.804871 -273.124391) (xy 161.804692 -273.125492) (xy 162.12337 -273.125492)
			(xy 162.12337 -273.074076) (xy 162.131413 -273.023294) (xy 162.147301 -272.974395) (xy 162.170644 -272.928583)
			(xy 162.200865 -272.886987) (xy 162.237221 -272.850631) (xy 162.278817 -272.82041) (xy 162.324629 -272.797067)
			(xy 162.373528 -272.781179) (xy 162.42431 -272.773136) (xy 162.475726 -272.773136) (xy 162.526508 -272.781179)
			(xy 162.575407 -272.797067) (xy 162.621219 -272.82041) (xy 162.662815 -272.850631) (xy 162.699171 -272.886987)
			(xy 162.729392 -272.928583) (xy 162.752735 -272.974395) (xy 162.768623 -273.023294) (xy 162.776666 -273.074076)
			(xy 162.77717 -273.099784) (xy 163.094174 -273.099784) (xy 163.098134 -273.05073) (xy 163.109911 -273.002946)
			(xy 163.129202 -272.95767) (xy 163.155505 -272.916074) (xy 163.18814 -272.879237) (xy 163.226261 -272.848112)
			(xy 163.268882 -272.823505) (xy 163.314898 -272.806053) (xy 163.363117 -272.796209) (xy 163.412292 -272.794228)
			(xy 163.461147 -272.80016) (xy 163.508418 -272.813852) (xy 163.55288 -272.83495) (xy 163.593383 -272.862906)
			(xy 163.628876 -272.896998) (xy 163.658441 -272.936342) (xy 163.681312 -272.979919) (xy 163.696896 -273.0266)
			(xy 163.704791 -273.075177) (xy 163.705286 -273.099784) (xy 163.704791 -273.124391) (xy 163.704612 -273.125492)
			(xy 164.02329 -273.125492) (xy 164.02329 -273.074076) (xy 164.031333 -273.023294) (xy 164.047221 -272.974395)
			(xy 164.070564 -272.928583) (xy 164.100785 -272.886987) (xy 164.137141 -272.850631) (xy 164.178737 -272.82041)
			(xy 164.224549 -272.797067) (xy 164.273448 -272.781179) (xy 164.32423 -272.773136) (xy 164.375646 -272.773136)
			(xy 164.426428 -272.781179) (xy 164.475327 -272.797067) (xy 164.521139 -272.82041) (xy 164.562735 -272.850631)
			(xy 164.599091 -272.886987) (xy 164.629312 -272.928583) (xy 164.652655 -272.974395) (xy 164.668543 -273.023294)
			(xy 164.676586 -273.074076) (xy 164.67709 -273.099784) (xy 164.994094 -273.099784) (xy 164.998054 -273.05073)
			(xy 165.009831 -273.002946) (xy 165.029122 -272.95767) (xy 165.055425 -272.916074) (xy 165.08806 -272.879237)
			(xy 165.126181 -272.848112) (xy 165.168802 -272.823505) (xy 165.214818 -272.806053) (xy 165.263037 -272.796209)
			(xy 165.312212 -272.794228) (xy 165.361067 -272.80016) (xy 165.408338 -272.813852) (xy 165.4528 -272.83495)
			(xy 165.493303 -272.862906) (xy 165.528796 -272.896998) (xy 165.558361 -272.936342) (xy 165.581232 -272.979919)
			(xy 165.596816 -273.0266) (xy 165.604711 -273.075177) (xy 165.605206 -273.099784) (xy 165.604711 -273.124391)
			(xy 165.604532 -273.125492) (xy 165.92321 -273.125492) (xy 165.92321 -273.074076) (xy 165.931253 -273.023294)
			(xy 165.947141 -272.974395) (xy 165.970484 -272.928583) (xy 166.000705 -272.886987) (xy 166.037061 -272.850631)
			(xy 166.078657 -272.82041) (xy 166.124469 -272.797067) (xy 166.173368 -272.781179) (xy 166.22415 -272.773136)
			(xy 166.275566 -272.773136) (xy 166.326348 -272.781179) (xy 166.375247 -272.797067) (xy 166.421059 -272.82041)
			(xy 166.462655 -272.850631) (xy 166.499011 -272.886987) (xy 166.529232 -272.928583) (xy 166.552575 -272.974395)
			(xy 166.568463 -273.023294) (xy 166.576506 -273.074076) (xy 166.57701 -273.099784) (xy 166.894268 -273.099784)
			(xy 166.898228 -273.05073) (xy 166.910005 -273.002946) (xy 166.929296 -272.95767) (xy 166.955599 -272.916074)
			(xy 166.988234 -272.879237) (xy 167.026355 -272.848112) (xy 167.068976 -272.823505) (xy 167.114992 -272.806053)
			(xy 167.163211 -272.796209) (xy 167.212386 -272.794228) (xy 167.261241 -272.80016) (xy 167.308512 -272.813852)
			(xy 167.352974 -272.83495) (xy 167.393477 -272.862906) (xy 167.42897 -272.896998) (xy 167.458535 -272.936342)
			(xy 167.481406 -272.979919) (xy 167.49699 -273.0266) (xy 167.504885 -273.075177) (xy 167.50538 -273.099784)
			(xy 167.504885 -273.124391) (xy 167.504706 -273.125492) (xy 167.823384 -273.125492) (xy 167.823384 -273.074076)
			(xy 167.831427 -273.023294) (xy 167.847315 -272.974395) (xy 167.870658 -272.928583) (xy 167.900879 -272.886987)
			(xy 167.937235 -272.850631) (xy 167.978831 -272.82041) (xy 168.024643 -272.797067) (xy 168.073542 -272.781179)
			(xy 168.124324 -272.773136) (xy 168.17574 -272.773136) (xy 168.226522 -272.781179) (xy 168.275421 -272.797067)
			(xy 168.321233 -272.82041) (xy 168.362829 -272.850631) (xy 168.399185 -272.886987) (xy 168.429406 -272.928583)
			(xy 168.452749 -272.974395) (xy 168.468637 -273.023294) (xy 168.47668 -273.074076) (xy 168.477184 -273.099784)
			(xy 168.794188 -273.099784) (xy 168.798148 -273.05073) (xy 168.809925 -273.002946) (xy 168.829216 -272.95767)
			(xy 168.855519 -272.916074) (xy 168.888154 -272.879237) (xy 168.926275 -272.848112) (xy 168.968896 -272.823505)
			(xy 169.014912 -272.806053) (xy 169.063131 -272.796209) (xy 169.112306 -272.794228) (xy 169.161161 -272.80016)
			(xy 169.208432 -272.813852) (xy 169.252894 -272.83495) (xy 169.293397 -272.862906) (xy 169.32889 -272.896998)
			(xy 169.358455 -272.936342) (xy 169.381326 -272.979919) (xy 169.39691 -273.0266) (xy 169.404805 -273.075177)
			(xy 169.4053 -273.099784) (xy 169.404805 -273.124391) (xy 169.404626 -273.125492) (xy 169.723304 -273.125492)
			(xy 169.723304 -273.074076) (xy 169.731347 -273.023294) (xy 169.747235 -272.974395) (xy 169.770578 -272.928583)
			(xy 169.800799 -272.886987) (xy 169.837155 -272.850631) (xy 169.878751 -272.82041) (xy 169.924563 -272.797067)
			(xy 169.973462 -272.781179) (xy 170.024244 -272.773136) (xy 170.07566 -272.773136) (xy 170.126442 -272.781179)
			(xy 170.175341 -272.797067) (xy 170.221153 -272.82041) (xy 170.262749 -272.850631) (xy 170.299105 -272.886987)
			(xy 170.329326 -272.928583) (xy 170.352669 -272.974395) (xy 170.368557 -273.023294) (xy 170.3766 -273.074076)
			(xy 170.377104 -273.099784) (xy 170.694108 -273.099784) (xy 170.698068 -273.05073) (xy 170.709845 -273.002946)
			(xy 170.729136 -272.95767) (xy 170.755439 -272.916074) (xy 170.788074 -272.879237) (xy 170.826195 -272.848112)
			(xy 170.868816 -272.823505) (xy 170.914832 -272.806053) (xy 170.963051 -272.796209) (xy 171.012226 -272.794228)
			(xy 171.061081 -272.80016) (xy 171.108352 -272.813852) (xy 171.152814 -272.83495) (xy 171.193317 -272.862906)
			(xy 171.22881 -272.896998) (xy 171.258375 -272.936342) (xy 171.281246 -272.979919) (xy 171.29683 -273.0266)
			(xy 171.304725 -273.075177) (xy 171.30522 -273.099784) (xy 171.304725 -273.124391) (xy 171.304546 -273.125492)
			(xy 171.623224 -273.125492) (xy 171.623224 -273.074076) (xy 171.631267 -273.023294) (xy 171.647155 -272.974395)
			(xy 171.670498 -272.928583) (xy 171.700719 -272.886987) (xy 171.737075 -272.850631) (xy 171.778671 -272.82041)
			(xy 171.824483 -272.797067) (xy 171.873382 -272.781179) (xy 171.924164 -272.773136) (xy 171.97558 -272.773136)
			(xy 172.026362 -272.781179) (xy 172.075261 -272.797067) (xy 172.121073 -272.82041) (xy 172.162669 -272.850631)
			(xy 172.199025 -272.886987) (xy 172.229246 -272.928583) (xy 172.252589 -272.974395) (xy 172.268477 -273.023294)
			(xy 172.27652 -273.074076) (xy 172.277024 -273.099784) (xy 172.594282 -273.099784) (xy 172.598242 -273.05073)
			(xy 172.610019 -273.002946) (xy 172.62931 -272.95767) (xy 172.655613 -272.916074) (xy 172.688248 -272.879237)
			(xy 172.726369 -272.848112) (xy 172.76899 -272.823505) (xy 172.815006 -272.806053) (xy 172.863225 -272.796209)
			(xy 172.9124 -272.794228) (xy 172.961255 -272.80016) (xy 173.008526 -272.813852) (xy 173.052988 -272.83495)
			(xy 173.093491 -272.862906) (xy 173.128984 -272.896998) (xy 173.158549 -272.936342) (xy 173.18142 -272.979919)
			(xy 173.197004 -273.0266) (xy 173.204899 -273.075177) (xy 173.205394 -273.099784) (xy 173.204899 -273.124391)
			(xy 173.20472 -273.125492) (xy 173.523398 -273.125492) (xy 173.523398 -273.074076) (xy 173.531441 -273.023294)
			(xy 173.547329 -272.974395) (xy 173.570672 -272.928583) (xy 173.600893 -272.886987) (xy 173.637249 -272.850631)
			(xy 173.678845 -272.82041) (xy 173.724657 -272.797067) (xy 173.773556 -272.781179) (xy 173.824338 -272.773136)
			(xy 173.875754 -272.773136) (xy 173.926536 -272.781179) (xy 173.975435 -272.797067) (xy 174.021247 -272.82041)
			(xy 174.062843 -272.850631) (xy 174.099199 -272.886987) (xy 174.12942 -272.928583) (xy 174.152763 -272.974395)
			(xy 174.168651 -273.023294) (xy 174.176694 -273.074076) (xy 174.177198 -273.099784) (xy 174.494202 -273.099784)
			(xy 174.498162 -273.05073) (xy 174.509939 -273.002946) (xy 174.52923 -272.95767) (xy 174.555533 -272.916074)
			(xy 174.588168 -272.879237) (xy 174.626289 -272.848112) (xy 174.66891 -272.823505) (xy 174.714926 -272.806053)
			(xy 174.763145 -272.796209) (xy 174.81232 -272.794228) (xy 174.861175 -272.80016) (xy 174.908446 -272.813852)
			(xy 174.952908 -272.83495) (xy 174.993411 -272.862906) (xy 175.028904 -272.896998) (xy 175.058469 -272.936342)
			(xy 175.08134 -272.979919) (xy 175.096924 -273.0266) (xy 175.104819 -273.075177) (xy 175.105314 -273.099784)
			(xy 175.104819 -273.124391) (xy 175.104681 -273.125238) (xy 175.423064 -273.125238) (xy 175.423064 -273.073822)
			(xy 175.431107 -273.02304) (xy 175.446995 -272.974141) (xy 175.470338 -272.928329) (xy 175.500559 -272.886733)
			(xy 175.536915 -272.850377) (xy 175.578511 -272.820156) (xy 175.624323 -272.796813) (xy 175.673222 -272.780925)
			(xy 175.724004 -272.772882) (xy 175.77542 -272.772882) (xy 175.826202 -272.780925) (xy 175.875101 -272.796813)
			(xy 175.920913 -272.820156) (xy 175.962509 -272.850377) (xy 175.998865 -272.886733) (xy 176.029086 -272.928329)
			(xy 176.052429 -272.974141) (xy 176.068317 -273.02304) (xy 176.07636 -273.073822) (xy 176.076864 -273.09953)
			(xy 176.076859 -273.099784) (xy 176.394122 -273.099784) (xy 176.398082 -273.05073) (xy 176.409859 -273.002946)
			(xy 176.42915 -272.95767) (xy 176.455453 -272.916074) (xy 176.488088 -272.879237) (xy 176.526209 -272.848112)
			(xy 176.56883 -272.823505) (xy 176.614846 -272.806053) (xy 176.663065 -272.796209) (xy 176.71224 -272.794228)
			(xy 176.761095 -272.80016) (xy 176.808366 -272.813852) (xy 176.852828 -272.83495) (xy 176.893331 -272.862906)
			(xy 176.928824 -272.896998) (xy 176.958389 -272.936342) (xy 176.98126 -272.979919) (xy 176.996844 -273.0266)
			(xy 177.004739 -273.075177) (xy 177.005234 -273.099784) (xy 177.004739 -273.124391) (xy 177.00456 -273.125492)
			(xy 177.322984 -273.125492) (xy 177.322984 -273.074076) (xy 177.331027 -273.023294) (xy 177.346915 -272.974395)
			(xy 177.370258 -272.928583) (xy 177.400479 -272.886987) (xy 177.436835 -272.850631) (xy 177.478431 -272.82041)
			(xy 177.524243 -272.797067) (xy 177.573142 -272.781179) (xy 177.623924 -272.773136) (xy 177.67534 -272.773136)
			(xy 177.726122 -272.781179) (xy 177.775021 -272.797067) (xy 177.820833 -272.82041) (xy 177.862429 -272.850631)
			(xy 177.898785 -272.886987) (xy 177.929006 -272.928583) (xy 177.952349 -272.974395) (xy 177.968237 -273.023294)
			(xy 177.97628 -273.074076) (xy 177.976784 -273.099784) (xy 178.294042 -273.099784) (xy 178.298002 -273.05073)
			(xy 178.309779 -273.002946) (xy 178.32907 -272.95767) (xy 178.355373 -272.916074) (xy 178.388008 -272.879237)
			(xy 178.426129 -272.848112) (xy 178.46875 -272.823505) (xy 178.514766 -272.806053) (xy 178.562985 -272.796209)
			(xy 178.61216 -272.794228) (xy 178.661015 -272.80016) (xy 178.708286 -272.813852) (xy 178.752748 -272.83495)
			(xy 178.793251 -272.862906) (xy 178.828744 -272.896998) (xy 178.858309 -272.936342) (xy 178.88118 -272.979919)
			(xy 178.896764 -273.0266) (xy 178.904659 -273.075177) (xy 178.905154 -273.099784) (xy 178.904659 -273.124391)
			(xy 178.90448 -273.125492) (xy 179.223158 -273.125492) (xy 179.223158 -273.074076) (xy 179.231201 -273.023294)
			(xy 179.247089 -272.974395) (xy 179.270432 -272.928583) (xy 179.300653 -272.886987) (xy 179.337009 -272.850631)
			(xy 179.378605 -272.82041) (xy 179.424417 -272.797067) (xy 179.473316 -272.781179) (xy 179.524098 -272.773136)
			(xy 179.575514 -272.773136) (xy 179.626296 -272.781179) (xy 179.675195 -272.797067) (xy 179.721007 -272.82041)
			(xy 179.762603 -272.850631) (xy 179.798959 -272.886987) (xy 179.82918 -272.928583) (xy 179.852523 -272.974395)
			(xy 179.868411 -273.023294) (xy 179.876454 -273.074076) (xy 179.876958 -273.099784) (xy 180.194216 -273.099784)
			(xy 180.198176 -273.05073) (xy 180.209953 -273.002946) (xy 180.229244 -272.95767) (xy 180.255547 -272.916074)
			(xy 180.288182 -272.879237) (xy 180.326303 -272.848112) (xy 180.368924 -272.823505) (xy 180.41494 -272.806053)
			(xy 180.463159 -272.796209) (xy 180.512334 -272.794228) (xy 180.561189 -272.80016) (xy 180.60846 -272.813852)
			(xy 180.652922 -272.83495) (xy 180.693425 -272.862906) (xy 180.728918 -272.896998) (xy 180.758483 -272.936342)
			(xy 180.781354 -272.979919) (xy 180.796938 -273.0266) (xy 180.804833 -273.075177) (xy 180.805328 -273.099784)
			(xy 180.804833 -273.124391) (xy 180.804654 -273.125492) (xy 181.123078 -273.125492) (xy 181.123078 -273.074076)
			(xy 181.131121 -273.023294) (xy 181.147009 -272.974395) (xy 181.170352 -272.928583) (xy 181.200573 -272.886987)
			(xy 181.236929 -272.850631) (xy 181.278525 -272.82041) (xy 181.324337 -272.797067) (xy 181.373236 -272.781179)
			(xy 181.424018 -272.773136) (xy 181.475434 -272.773136) (xy 181.526216 -272.781179) (xy 181.575115 -272.797067)
			(xy 181.620927 -272.82041) (xy 181.662523 -272.850631) (xy 181.698879 -272.886987) (xy 181.7291 -272.928583)
			(xy 181.752443 -272.974395) (xy 181.768331 -273.023294) (xy 181.776374 -273.074076) (xy 181.776878 -273.099784)
			(xy 182.094136 -273.099784) (xy 182.098096 -273.05073) (xy 182.109873 -273.002946) (xy 182.129164 -272.95767)
			(xy 182.155467 -272.916074) (xy 182.188102 -272.879237) (xy 182.226223 -272.848112) (xy 182.268844 -272.823505)
			(xy 182.31486 -272.806053) (xy 182.363079 -272.796209) (xy 182.412254 -272.794228) (xy 182.461109 -272.80016)
			(xy 182.50838 -272.813852) (xy 182.552842 -272.83495) (xy 182.593345 -272.862906) (xy 182.628838 -272.896998)
			(xy 182.658403 -272.936342) (xy 182.681274 -272.979919) (xy 182.696858 -273.0266) (xy 182.704753 -273.075177)
			(xy 182.705248 -273.099784) (xy 182.704753 -273.124391) (xy 182.704574 -273.125492) (xy 183.022998 -273.125492)
			(xy 183.022998 -273.074076) (xy 183.031041 -273.023294) (xy 183.046929 -272.974395) (xy 183.070272 -272.928583)
			(xy 183.100493 -272.886987) (xy 183.136849 -272.850631) (xy 183.178445 -272.82041) (xy 183.224257 -272.797067)
			(xy 183.273156 -272.781179) (xy 183.323938 -272.773136) (xy 183.375354 -272.773136) (xy 183.426136 -272.781179)
			(xy 183.475035 -272.797067) (xy 183.520847 -272.82041) (xy 183.562443 -272.850631) (xy 183.598799 -272.886987)
			(xy 183.62902 -272.928583) (xy 183.652363 -272.974395) (xy 183.668251 -273.023294) (xy 183.676294 -273.074076)
			(xy 183.676798 -273.099784) (xy 183.994056 -273.099784) (xy 183.998016 -273.05073) (xy 184.009793 -273.002946)
			(xy 184.029084 -272.95767) (xy 184.055387 -272.916074) (xy 184.088022 -272.879237) (xy 184.126143 -272.848112)
			(xy 184.168764 -272.823505) (xy 184.21478 -272.806053) (xy 184.262999 -272.796209) (xy 184.312174 -272.794228)
			(xy 184.361029 -272.80016) (xy 184.4083 -272.813852) (xy 184.452762 -272.83495) (xy 184.493265 -272.862906)
			(xy 184.528758 -272.896998) (xy 184.558323 -272.936342) (xy 184.581194 -272.979919) (xy 184.596778 -273.0266)
			(xy 184.604673 -273.075177) (xy 184.605168 -273.099784) (xy 184.604673 -273.124391) (xy 184.604494 -273.125492)
			(xy 184.923172 -273.125492) (xy 184.923172 -273.074076) (xy 184.931215 -273.023294) (xy 184.947103 -272.974395)
			(xy 184.970446 -272.928583) (xy 185.000667 -272.886987) (xy 185.037023 -272.850631) (xy 185.078619 -272.82041)
			(xy 185.124431 -272.797067) (xy 185.17333 -272.781179) (xy 185.224112 -272.773136) (xy 185.275528 -272.773136)
			(xy 185.32631 -272.781179) (xy 185.375209 -272.797067) (xy 185.421021 -272.82041) (xy 185.462617 -272.850631)
			(xy 185.498973 -272.886987) (xy 185.529194 -272.928583) (xy 185.552537 -272.974395) (xy 185.568425 -273.023294)
			(xy 185.576468 -273.074076) (xy 185.576972 -273.099784) (xy 185.89423 -273.099784) (xy 185.89819 -273.05073)
			(xy 185.909967 -273.002946) (xy 185.929258 -272.95767) (xy 185.955561 -272.916074) (xy 185.988196 -272.879237)
			(xy 186.026317 -272.848112) (xy 186.068938 -272.823505) (xy 186.114954 -272.806053) (xy 186.163173 -272.796209)
			(xy 186.212348 -272.794228) (xy 186.261203 -272.80016) (xy 186.308474 -272.813852) (xy 186.352936 -272.83495)
			(xy 186.393439 -272.862906) (xy 186.428932 -272.896998) (xy 186.458497 -272.936342) (xy 186.481368 -272.979919)
			(xy 186.496952 -273.0266) (xy 186.504847 -273.075177) (xy 186.505342 -273.099784) (xy 186.504847 -273.124391)
			(xy 186.504668 -273.125492) (xy 186.823092 -273.125492) (xy 186.823092 -273.074076) (xy 186.831135 -273.023294)
			(xy 186.847023 -272.974395) (xy 186.870366 -272.928583) (xy 186.900587 -272.886987) (xy 186.936943 -272.850631)
			(xy 186.978539 -272.82041) (xy 187.024351 -272.797067) (xy 187.07325 -272.781179) (xy 187.124032 -272.773136)
			(xy 187.175448 -272.773136) (xy 187.22623 -272.781179) (xy 187.275129 -272.797067) (xy 187.320941 -272.82041)
			(xy 187.362537 -272.850631) (xy 187.398893 -272.886987) (xy 187.429114 -272.928583) (xy 187.452457 -272.974395)
			(xy 187.468345 -273.023294) (xy 187.476388 -273.074076) (xy 187.476892 -273.099784) (xy 187.79415 -273.099784)
			(xy 187.79811 -273.05073) (xy 187.809887 -273.002946) (xy 187.829178 -272.95767) (xy 187.855481 -272.916074)
			(xy 187.888116 -272.879237) (xy 187.926237 -272.848112) (xy 187.968858 -272.823505) (xy 188.014874 -272.806053)
			(xy 188.063093 -272.796209) (xy 188.112268 -272.794228) (xy 188.161123 -272.80016) (xy 188.208394 -272.813852)
			(xy 188.252856 -272.83495) (xy 188.293359 -272.862906) (xy 188.328852 -272.896998) (xy 188.358417 -272.936342)
			(xy 188.381288 -272.979919) (xy 188.396872 -273.0266) (xy 188.404767 -273.075177) (xy 188.405262 -273.099784)
			(xy 188.404767 -273.124391) (xy 188.404588 -273.125492) (xy 188.723012 -273.125492) (xy 188.723012 -273.074076)
			(xy 188.731055 -273.023294) (xy 188.746943 -272.974395) (xy 188.770286 -272.928583) (xy 188.800507 -272.886987)
			(xy 188.836863 -272.850631) (xy 188.878459 -272.82041) (xy 188.924271 -272.797067) (xy 188.97317 -272.781179)
			(xy 189.023952 -272.773136) (xy 189.075368 -272.773136) (xy 189.12615 -272.781179) (xy 189.175049 -272.797067)
			(xy 189.220861 -272.82041) (xy 189.262457 -272.850631) (xy 189.298813 -272.886987) (xy 189.329034 -272.928583)
			(xy 189.352377 -272.974395) (xy 189.368265 -273.023294) (xy 189.376308 -273.074076) (xy 189.376812 -273.099784)
			(xy 189.69407 -273.099784) (xy 189.69803 -273.05073) (xy 189.709807 -273.002946) (xy 189.729098 -272.95767)
			(xy 189.755401 -272.916074) (xy 189.788036 -272.879237) (xy 189.826157 -272.848112) (xy 189.868778 -272.823505)
			(xy 189.914794 -272.806053) (xy 189.963013 -272.796209) (xy 190.012188 -272.794228) (xy 190.061043 -272.80016)
			(xy 190.108314 -272.813852) (xy 190.152776 -272.83495) (xy 190.193279 -272.862906) (xy 190.228772 -272.896998)
			(xy 190.258337 -272.936342) (xy 190.281208 -272.979919) (xy 190.296792 -273.0266) (xy 190.304687 -273.075177)
			(xy 190.305182 -273.099784) (xy 190.304687 -273.124391) (xy 190.304508 -273.125492) (xy 190.623186 -273.125492)
			(xy 190.623186 -273.074076) (xy 190.631229 -273.023294) (xy 190.647117 -272.974395) (xy 190.67046 -272.928583)
			(xy 190.700681 -272.886987) (xy 190.737037 -272.850631) (xy 190.778633 -272.82041) (xy 190.824445 -272.797067)
			(xy 190.873344 -272.781179) (xy 190.924126 -272.773136) (xy 190.975542 -272.773136) (xy 191.026324 -272.781179)
			(xy 191.075223 -272.797067) (xy 191.121035 -272.82041) (xy 191.162631 -272.850631) (xy 191.198987 -272.886987)
			(xy 191.229208 -272.928583) (xy 191.252551 -272.974395) (xy 191.268439 -273.023294) (xy 191.276482 -273.074076)
			(xy 191.276986 -273.099784) (xy 191.594244 -273.099784) (xy 191.598204 -273.05073) (xy 191.609981 -273.002946)
			(xy 191.629272 -272.95767) (xy 191.655575 -272.916074) (xy 191.68821 -272.879237) (xy 191.726331 -272.848112)
			(xy 191.768952 -272.823505) (xy 191.814968 -272.806053) (xy 191.863187 -272.796209) (xy 191.912362 -272.794228)
			(xy 191.961217 -272.80016) (xy 192.008488 -272.813852) (xy 192.05295 -272.83495) (xy 192.093453 -272.862906)
			(xy 192.128946 -272.896998) (xy 192.158511 -272.936342) (xy 192.181382 -272.979919) (xy 192.196966 -273.0266)
			(xy 192.204861 -273.075177) (xy 192.205356 -273.099784) (xy 192.204861 -273.124391) (xy 192.204682 -273.125492)
			(xy 192.523106 -273.125492) (xy 192.523106 -273.074076) (xy 192.531149 -273.023294) (xy 192.547037 -272.974395)
			(xy 192.57038 -272.928583) (xy 192.600601 -272.886987) (xy 192.636957 -272.850631) (xy 192.678553 -272.82041)
			(xy 192.724365 -272.797067) (xy 192.773264 -272.781179) (xy 192.824046 -272.773136) (xy 192.875462 -272.773136)
			(xy 192.926244 -272.781179) (xy 192.975143 -272.797067) (xy 193.020955 -272.82041) (xy 193.062551 -272.850631)
			(xy 193.098907 -272.886987) (xy 193.129128 -272.928583) (xy 193.152471 -272.974395) (xy 193.168359 -273.023294)
			(xy 193.176402 -273.074076) (xy 193.176906 -273.099784) (xy 193.494418 -273.099784) (xy 193.498378 -273.05073)
			(xy 193.510155 -273.002946) (xy 193.529446 -272.95767) (xy 193.555749 -272.916074) (xy 193.588384 -272.879237)
			(xy 193.626505 -272.848112) (xy 193.669126 -272.823505) (xy 193.715142 -272.806053) (xy 193.763361 -272.796209)
			(xy 193.812536 -272.794228) (xy 193.861391 -272.80016) (xy 193.908662 -272.813852) (xy 193.953124 -272.83495)
			(xy 193.993627 -272.862906) (xy 194.02912 -272.896998) (xy 194.058685 -272.936342) (xy 194.081556 -272.979919)
			(xy 194.09714 -273.0266) (xy 194.105035 -273.075177) (xy 194.10553 -273.099784) (xy 194.105035 -273.124391)
			(xy 194.104856 -273.125492) (xy 194.423026 -273.125492) (xy 194.423026 -273.074076) (xy 194.431069 -273.023294)
			(xy 194.446957 -272.974395) (xy 194.4703 -272.928583) (xy 194.500521 -272.886987) (xy 194.536877 -272.850631)
			(xy 194.578473 -272.82041) (xy 194.624285 -272.797067) (xy 194.673184 -272.781179) (xy 194.723966 -272.773136)
			(xy 194.775382 -272.773136) (xy 194.826164 -272.781179) (xy 194.875063 -272.797067) (xy 194.920875 -272.82041)
			(xy 194.962471 -272.850631) (xy 194.998827 -272.886987) (xy 195.029048 -272.928583) (xy 195.052391 -272.974395)
			(xy 195.068279 -273.023294) (xy 195.076322 -273.074076) (xy 195.076826 -273.099784) (xy 195.394338 -273.099784)
			(xy 195.398298 -273.05073) (xy 195.410075 -273.002946) (xy 195.429366 -272.95767) (xy 195.455669 -272.916074)
			(xy 195.488304 -272.879237) (xy 195.526425 -272.848112) (xy 195.569046 -272.823505) (xy 195.615062 -272.806053)
			(xy 195.663281 -272.796209) (xy 195.712456 -272.794228) (xy 195.761311 -272.80016) (xy 195.808582 -272.813852)
			(xy 195.853044 -272.83495) (xy 195.893547 -272.862906) (xy 195.92904 -272.896998) (xy 195.958605 -272.936342)
			(xy 195.981476 -272.979919) (xy 195.99706 -273.0266) (xy 196.004955 -273.075177) (xy 196.00545 -273.099784)
			(xy 196.004955 -273.124391) (xy 196.004776 -273.125492) (xy 196.322946 -273.125492) (xy 196.322946 -273.074076)
			(xy 196.330989 -273.023294) (xy 196.346877 -272.974395) (xy 196.37022 -272.928583) (xy 196.400441 -272.886987)
			(xy 196.436797 -272.850631) (xy 196.478393 -272.82041) (xy 196.524205 -272.797067) (xy 196.573104 -272.781179)
			(xy 196.623886 -272.773136) (xy 196.675302 -272.773136) (xy 196.726084 -272.781179) (xy 196.774983 -272.797067)
			(xy 196.820795 -272.82041) (xy 196.862391 -272.850631) (xy 196.898747 -272.886987) (xy 196.928968 -272.928583)
			(xy 196.952311 -272.974395) (xy 196.968199 -273.023294) (xy 196.976242 -273.074076) (xy 196.976746 -273.099784)
			(xy 197.294258 -273.099784) (xy 197.298218 -273.05073) (xy 197.309995 -273.002946) (xy 197.329286 -272.95767)
			(xy 197.355589 -272.916074) (xy 197.388224 -272.879237) (xy 197.426345 -272.848112) (xy 197.468966 -272.823505)
			(xy 197.514982 -272.806053) (xy 197.563201 -272.796209) (xy 197.612376 -272.794228) (xy 197.661231 -272.80016)
			(xy 197.708502 -272.813852) (xy 197.752964 -272.83495) (xy 197.793467 -272.862906) (xy 197.82896 -272.896998)
			(xy 197.858525 -272.936342) (xy 197.881396 -272.979919) (xy 197.89698 -273.0266) (xy 197.904875 -273.075177)
			(xy 197.90537 -273.099784) (xy 197.904875 -273.124391) (xy 197.89698 -273.172968) (xy 197.881396 -273.219649)
			(xy 197.858525 -273.263226) (xy 197.82896 -273.30257) (xy 197.793467 -273.336662) (xy 197.752964 -273.364618)
			(xy 197.708502 -273.385716) (xy 197.661231 -273.399408) (xy 197.612376 -273.40534) (xy 197.563201 -273.403359)
			(xy 197.514982 -273.393515) (xy 197.468966 -273.376063) (xy 197.426345 -273.351456) (xy 197.388224 -273.320331)
			(xy 197.355589 -273.283494) (xy 197.329286 -273.241898) (xy 197.309995 -273.196622) (xy 197.298218 -273.148838)
			(xy 197.294258 -273.099784) (xy 196.976746 -273.099784) (xy 196.976242 -273.125492) (xy 196.968199 -273.176274)
			(xy 196.952311 -273.225173) (xy 196.928968 -273.270985) (xy 196.898747 -273.312581) (xy 196.862391 -273.348937)
			(xy 196.820795 -273.379158) (xy 196.774983 -273.402501) (xy 196.726084 -273.418389) (xy 196.675302 -273.426432)
			(xy 196.623886 -273.426432) (xy 196.573104 -273.418389) (xy 196.524205 -273.402501) (xy 196.478393 -273.379158)
			(xy 196.436797 -273.348937) (xy 196.400441 -273.312581) (xy 196.37022 -273.270985) (xy 196.346877 -273.225173)
			(xy 196.330989 -273.176274) (xy 196.322946 -273.125492) (xy 196.004776 -273.125492) (xy 195.99706 -273.172968)
			(xy 195.981476 -273.219649) (xy 195.958605 -273.263226) (xy 195.92904 -273.30257) (xy 195.893547 -273.336662)
			(xy 195.853044 -273.364618) (xy 195.808582 -273.385716) (xy 195.761311 -273.399408) (xy 195.712456 -273.40534)
			(xy 195.663281 -273.403359) (xy 195.615062 -273.393515) (xy 195.569046 -273.376063) (xy 195.526425 -273.351456)
			(xy 195.488304 -273.320331) (xy 195.455669 -273.283494) (xy 195.429366 -273.241898) (xy 195.410075 -273.196622)
			(xy 195.398298 -273.148838) (xy 195.394338 -273.099784) (xy 195.076826 -273.099784) (xy 195.076322 -273.125492)
			(xy 195.068279 -273.176274) (xy 195.052391 -273.225173) (xy 195.029048 -273.270985) (xy 194.998827 -273.312581)
			(xy 194.962471 -273.348937) (xy 194.920875 -273.379158) (xy 194.875063 -273.402501) (xy 194.826164 -273.418389)
			(xy 194.775382 -273.426432) (xy 194.723966 -273.426432) (xy 194.673184 -273.418389) (xy 194.624285 -273.402501)
			(xy 194.578473 -273.379158) (xy 194.536877 -273.348937) (xy 194.500521 -273.312581) (xy 194.4703 -273.270985)
			(xy 194.446957 -273.225173) (xy 194.431069 -273.176274) (xy 194.423026 -273.125492) (xy 194.104856 -273.125492)
			(xy 194.09714 -273.172968) (xy 194.081556 -273.219649) (xy 194.058685 -273.263226) (xy 194.02912 -273.30257)
			(xy 193.993627 -273.336662) (xy 193.953124 -273.364618) (xy 193.908662 -273.385716) (xy 193.861391 -273.399408)
			(xy 193.812536 -273.40534) (xy 193.763361 -273.403359) (xy 193.715142 -273.393515) (xy 193.669126 -273.376063)
			(xy 193.626505 -273.351456) (xy 193.588384 -273.320331) (xy 193.555749 -273.283494) (xy 193.529446 -273.241898)
			(xy 193.510155 -273.196622) (xy 193.498378 -273.148838) (xy 193.494418 -273.099784) (xy 193.176906 -273.099784)
			(xy 193.176402 -273.125492) (xy 193.168359 -273.176274) (xy 193.152471 -273.225173) (xy 193.129128 -273.270985)
			(xy 193.098907 -273.312581) (xy 193.062551 -273.348937) (xy 193.020955 -273.379158) (xy 192.975143 -273.402501)
			(xy 192.926244 -273.418389) (xy 192.875462 -273.426432) (xy 192.824046 -273.426432) (xy 192.773264 -273.418389)
			(xy 192.724365 -273.402501) (xy 192.678553 -273.379158) (xy 192.636957 -273.348937) (xy 192.600601 -273.312581)
			(xy 192.57038 -273.270985) (xy 192.547037 -273.225173) (xy 192.531149 -273.176274) (xy 192.523106 -273.125492)
			(xy 192.204682 -273.125492) (xy 192.196966 -273.172968) (xy 192.181382 -273.219649) (xy 192.158511 -273.263226)
			(xy 192.128946 -273.30257) (xy 192.093453 -273.336662) (xy 192.05295 -273.364618) (xy 192.008488 -273.385716)
			(xy 191.961217 -273.399408) (xy 191.912362 -273.40534) (xy 191.863187 -273.403359) (xy 191.814968 -273.393515)
			(xy 191.768952 -273.376063) (xy 191.726331 -273.351456) (xy 191.68821 -273.320331) (xy 191.655575 -273.283494)
			(xy 191.629272 -273.241898) (xy 191.609981 -273.196622) (xy 191.598204 -273.148838) (xy 191.594244 -273.099784)
			(xy 191.276986 -273.099784) (xy 191.276482 -273.125492) (xy 191.268439 -273.176274) (xy 191.252551 -273.225173)
			(xy 191.229208 -273.270985) (xy 191.198987 -273.312581) (xy 191.162631 -273.348937) (xy 191.121035 -273.379158)
			(xy 191.075223 -273.402501) (xy 191.026324 -273.418389) (xy 190.975542 -273.426432) (xy 190.924126 -273.426432)
			(xy 190.873344 -273.418389) (xy 190.824445 -273.402501) (xy 190.778633 -273.379158) (xy 190.737037 -273.348937)
			(xy 190.700681 -273.312581) (xy 190.67046 -273.270985) (xy 190.647117 -273.225173) (xy 190.631229 -273.176274)
			(xy 190.623186 -273.125492) (xy 190.304508 -273.125492) (xy 190.296792 -273.172968) (xy 190.281208 -273.219649)
			(xy 190.258337 -273.263226) (xy 190.228772 -273.30257) (xy 190.193279 -273.336662) (xy 190.152776 -273.364618)
			(xy 190.108314 -273.385716) (xy 190.061043 -273.399408) (xy 190.012188 -273.40534) (xy 189.963013 -273.403359)
			(xy 189.914794 -273.393515) (xy 189.868778 -273.376063) (xy 189.826157 -273.351456) (xy 189.788036 -273.320331)
			(xy 189.755401 -273.283494) (xy 189.729098 -273.241898) (xy 189.709807 -273.196622) (xy 189.69803 -273.148838)
			(xy 189.69407 -273.099784) (xy 189.376812 -273.099784) (xy 189.376308 -273.125492) (xy 189.368265 -273.176274)
			(xy 189.352377 -273.225173) (xy 189.329034 -273.270985) (xy 189.298813 -273.312581) (xy 189.262457 -273.348937)
			(xy 189.220861 -273.379158) (xy 189.175049 -273.402501) (xy 189.12615 -273.418389) (xy 189.075368 -273.426432)
			(xy 189.023952 -273.426432) (xy 188.97317 -273.418389) (xy 188.924271 -273.402501) (xy 188.878459 -273.379158)
			(xy 188.836863 -273.348937) (xy 188.800507 -273.312581) (xy 188.770286 -273.270985) (xy 188.746943 -273.225173)
			(xy 188.731055 -273.176274) (xy 188.723012 -273.125492) (xy 188.404588 -273.125492) (xy 188.396872 -273.172968)
			(xy 188.381288 -273.219649) (xy 188.358417 -273.263226) (xy 188.328852 -273.30257) (xy 188.293359 -273.336662)
			(xy 188.252856 -273.364618) (xy 188.208394 -273.385716) (xy 188.161123 -273.399408) (xy 188.112268 -273.40534)
			(xy 188.063093 -273.403359) (xy 188.014874 -273.393515) (xy 187.968858 -273.376063) (xy 187.926237 -273.351456)
			(xy 187.888116 -273.320331) (xy 187.855481 -273.283494) (xy 187.829178 -273.241898) (xy 187.809887 -273.196622)
			(xy 187.79811 -273.148838) (xy 187.79415 -273.099784) (xy 187.476892 -273.099784) (xy 187.476388 -273.125492)
			(xy 187.468345 -273.176274) (xy 187.452457 -273.225173) (xy 187.429114 -273.270985) (xy 187.398893 -273.312581)
			(xy 187.362537 -273.348937) (xy 187.320941 -273.379158) (xy 187.275129 -273.402501) (xy 187.22623 -273.418389)
			(xy 187.175448 -273.426432) (xy 187.124032 -273.426432) (xy 187.07325 -273.418389) (xy 187.024351 -273.402501)
			(xy 186.978539 -273.379158) (xy 186.936943 -273.348937) (xy 186.900587 -273.312581) (xy 186.870366 -273.270985)
			(xy 186.847023 -273.225173) (xy 186.831135 -273.176274) (xy 186.823092 -273.125492) (xy 186.504668 -273.125492)
			(xy 186.496952 -273.172968) (xy 186.481368 -273.219649) (xy 186.458497 -273.263226) (xy 186.428932 -273.30257)
			(xy 186.393439 -273.336662) (xy 186.352936 -273.364618) (xy 186.308474 -273.385716) (xy 186.261203 -273.399408)
			(xy 186.212348 -273.40534) (xy 186.163173 -273.403359) (xy 186.114954 -273.393515) (xy 186.068938 -273.376063)
			(xy 186.026317 -273.351456) (xy 185.988196 -273.320331) (xy 185.955561 -273.283494) (xy 185.929258 -273.241898)
			(xy 185.909967 -273.196622) (xy 185.89819 -273.148838) (xy 185.89423 -273.099784) (xy 185.576972 -273.099784)
			(xy 185.576468 -273.125492) (xy 185.568425 -273.176274) (xy 185.552537 -273.225173) (xy 185.529194 -273.270985)
			(xy 185.498973 -273.312581) (xy 185.462617 -273.348937) (xy 185.421021 -273.379158) (xy 185.375209 -273.402501)
			(xy 185.32631 -273.418389) (xy 185.275528 -273.426432) (xy 185.224112 -273.426432) (xy 185.17333 -273.418389)
			(xy 185.124431 -273.402501) (xy 185.078619 -273.379158) (xy 185.037023 -273.348937) (xy 185.000667 -273.312581)
			(xy 184.970446 -273.270985) (xy 184.947103 -273.225173) (xy 184.931215 -273.176274) (xy 184.923172 -273.125492)
			(xy 184.604494 -273.125492) (xy 184.596778 -273.172968) (xy 184.581194 -273.219649) (xy 184.558323 -273.263226)
			(xy 184.528758 -273.30257) (xy 184.493265 -273.336662) (xy 184.452762 -273.364618) (xy 184.4083 -273.385716)
			(xy 184.361029 -273.399408) (xy 184.312174 -273.40534) (xy 184.262999 -273.403359) (xy 184.21478 -273.393515)
			(xy 184.168764 -273.376063) (xy 184.126143 -273.351456) (xy 184.088022 -273.320331) (xy 184.055387 -273.283494)
			(xy 184.029084 -273.241898) (xy 184.009793 -273.196622) (xy 183.998016 -273.148838) (xy 183.994056 -273.099784)
			(xy 183.676798 -273.099784) (xy 183.676294 -273.125492) (xy 183.668251 -273.176274) (xy 183.652363 -273.225173)
			(xy 183.62902 -273.270985) (xy 183.598799 -273.312581) (xy 183.562443 -273.348937) (xy 183.520847 -273.379158)
			(xy 183.475035 -273.402501) (xy 183.426136 -273.418389) (xy 183.375354 -273.426432) (xy 183.323938 -273.426432)
			(xy 183.273156 -273.418389) (xy 183.224257 -273.402501) (xy 183.178445 -273.379158) (xy 183.136849 -273.348937)
			(xy 183.100493 -273.312581) (xy 183.070272 -273.270985) (xy 183.046929 -273.225173) (xy 183.031041 -273.176274)
			(xy 183.022998 -273.125492) (xy 182.704574 -273.125492) (xy 182.696858 -273.172968) (xy 182.681274 -273.219649)
			(xy 182.658403 -273.263226) (xy 182.628838 -273.30257) (xy 182.593345 -273.336662) (xy 182.552842 -273.364618)
			(xy 182.50838 -273.385716) (xy 182.461109 -273.399408) (xy 182.412254 -273.40534) (xy 182.363079 -273.403359)
			(xy 182.31486 -273.393515) (xy 182.268844 -273.376063) (xy 182.226223 -273.351456) (xy 182.188102 -273.320331)
			(xy 182.155467 -273.283494) (xy 182.129164 -273.241898) (xy 182.109873 -273.196622) (xy 182.098096 -273.148838)
			(xy 182.094136 -273.099784) (xy 181.776878 -273.099784) (xy 181.776374 -273.125492) (xy 181.768331 -273.176274)
			(xy 181.752443 -273.225173) (xy 181.7291 -273.270985) (xy 181.698879 -273.312581) (xy 181.662523 -273.348937)
			(xy 181.620927 -273.379158) (xy 181.575115 -273.402501) (xy 181.526216 -273.418389) (xy 181.475434 -273.426432)
			(xy 181.424018 -273.426432) (xy 181.373236 -273.418389) (xy 181.324337 -273.402501) (xy 181.278525 -273.379158)
			(xy 181.236929 -273.348937) (xy 181.200573 -273.312581) (xy 181.170352 -273.270985) (xy 181.147009 -273.225173)
			(xy 181.131121 -273.176274) (xy 181.123078 -273.125492) (xy 180.804654 -273.125492) (xy 180.796938 -273.172968)
			(xy 180.781354 -273.219649) (xy 180.758483 -273.263226) (xy 180.728918 -273.30257) (xy 180.693425 -273.336662)
			(xy 180.652922 -273.364618) (xy 180.60846 -273.385716) (xy 180.561189 -273.399408) (xy 180.512334 -273.40534)
			(xy 180.463159 -273.403359) (xy 180.41494 -273.393515) (xy 180.368924 -273.376063) (xy 180.326303 -273.351456)
			(xy 180.288182 -273.320331) (xy 180.255547 -273.283494) (xy 180.229244 -273.241898) (xy 180.209953 -273.196622)
			(xy 180.198176 -273.148838) (xy 180.194216 -273.099784) (xy 179.876958 -273.099784) (xy 179.876454 -273.125492)
			(xy 179.868411 -273.176274) (xy 179.852523 -273.225173) (xy 179.82918 -273.270985) (xy 179.798959 -273.312581)
			(xy 179.762603 -273.348937) (xy 179.721007 -273.379158) (xy 179.675195 -273.402501) (xy 179.626296 -273.418389)
			(xy 179.575514 -273.426432) (xy 179.524098 -273.426432) (xy 179.473316 -273.418389) (xy 179.424417 -273.402501)
			(xy 179.378605 -273.379158) (xy 179.337009 -273.348937) (xy 179.300653 -273.312581) (xy 179.270432 -273.270985)
			(xy 179.247089 -273.225173) (xy 179.231201 -273.176274) (xy 179.223158 -273.125492) (xy 178.90448 -273.125492)
			(xy 178.896764 -273.172968) (xy 178.88118 -273.219649) (xy 178.858309 -273.263226) (xy 178.828744 -273.30257)
			(xy 178.793251 -273.336662) (xy 178.752748 -273.364618) (xy 178.708286 -273.385716) (xy 178.661015 -273.399408)
			(xy 178.61216 -273.40534) (xy 178.562985 -273.403359) (xy 178.514766 -273.393515) (xy 178.46875 -273.376063)
			(xy 178.426129 -273.351456) (xy 178.388008 -273.320331) (xy 178.355373 -273.283494) (xy 178.32907 -273.241898)
			(xy 178.309779 -273.196622) (xy 178.298002 -273.148838) (xy 178.294042 -273.099784) (xy 177.976784 -273.099784)
			(xy 177.97628 -273.125492) (xy 177.968237 -273.176274) (xy 177.952349 -273.225173) (xy 177.929006 -273.270985)
			(xy 177.898785 -273.312581) (xy 177.862429 -273.348937) (xy 177.820833 -273.379158) (xy 177.775021 -273.402501)
			(xy 177.726122 -273.418389) (xy 177.67534 -273.426432) (xy 177.623924 -273.426432) (xy 177.573142 -273.418389)
			(xy 177.524243 -273.402501) (xy 177.478431 -273.379158) (xy 177.436835 -273.348937) (xy 177.400479 -273.312581)
			(xy 177.370258 -273.270985) (xy 177.346915 -273.225173) (xy 177.331027 -273.176274) (xy 177.322984 -273.125492)
			(xy 177.00456 -273.125492) (xy 176.996844 -273.172968) (xy 176.98126 -273.219649) (xy 176.958389 -273.263226)
			(xy 176.928824 -273.30257) (xy 176.893331 -273.336662) (xy 176.852828 -273.364618) (xy 176.808366 -273.385716)
			(xy 176.761095 -273.399408) (xy 176.71224 -273.40534) (xy 176.663065 -273.403359) (xy 176.614846 -273.393515)
			(xy 176.56883 -273.376063) (xy 176.526209 -273.351456) (xy 176.488088 -273.320331) (xy 176.455453 -273.283494)
			(xy 176.42915 -273.241898) (xy 176.409859 -273.196622) (xy 176.398082 -273.148838) (xy 176.394122 -273.099784)
			(xy 176.076859 -273.099784) (xy 176.07636 -273.125238) (xy 176.068317 -273.17602) (xy 176.052429 -273.224919)
			(xy 176.029086 -273.270731) (xy 175.998865 -273.312327) (xy 175.962509 -273.348683) (xy 175.920913 -273.378904)
			(xy 175.875101 -273.402247) (xy 175.826202 -273.418135) (xy 175.77542 -273.426178) (xy 175.724004 -273.426178)
			(xy 175.673222 -273.418135) (xy 175.624323 -273.402247) (xy 175.578511 -273.378904) (xy 175.536915 -273.348683)
			(xy 175.500559 -273.312327) (xy 175.470338 -273.270731) (xy 175.446995 -273.224919) (xy 175.431107 -273.17602)
			(xy 175.423064 -273.125238) (xy 175.104681 -273.125238) (xy 175.096924 -273.172968) (xy 175.08134 -273.219649)
			(xy 175.058469 -273.263226) (xy 175.028904 -273.30257) (xy 174.993411 -273.336662) (xy 174.952908 -273.364618)
			(xy 174.908446 -273.385716) (xy 174.861175 -273.399408) (xy 174.81232 -273.40534) (xy 174.763145 -273.403359)
			(xy 174.714926 -273.393515) (xy 174.66891 -273.376063) (xy 174.626289 -273.351456) (xy 174.588168 -273.320331)
			(xy 174.555533 -273.283494) (xy 174.52923 -273.241898) (xy 174.509939 -273.196622) (xy 174.498162 -273.148838)
			(xy 174.494202 -273.099784) (xy 174.177198 -273.099784) (xy 174.176694 -273.125492) (xy 174.168651 -273.176274)
			(xy 174.152763 -273.225173) (xy 174.12942 -273.270985) (xy 174.099199 -273.312581) (xy 174.062843 -273.348937)
			(xy 174.021247 -273.379158) (xy 173.975435 -273.402501) (xy 173.926536 -273.418389) (xy 173.875754 -273.426432)
			(xy 173.824338 -273.426432) (xy 173.773556 -273.418389) (xy 173.724657 -273.402501) (xy 173.678845 -273.379158)
			(xy 173.637249 -273.348937) (xy 173.600893 -273.312581) (xy 173.570672 -273.270985) (xy 173.547329 -273.225173)
			(xy 173.531441 -273.176274) (xy 173.523398 -273.125492) (xy 173.20472 -273.125492) (xy 173.197004 -273.172968)
			(xy 173.18142 -273.219649) (xy 173.158549 -273.263226) (xy 173.128984 -273.30257) (xy 173.093491 -273.336662)
			(xy 173.052988 -273.364618) (xy 173.008526 -273.385716) (xy 172.961255 -273.399408) (xy 172.9124 -273.40534)
			(xy 172.863225 -273.403359) (xy 172.815006 -273.393515) (xy 172.76899 -273.376063) (xy 172.726369 -273.351456)
			(xy 172.688248 -273.320331) (xy 172.655613 -273.283494) (xy 172.62931 -273.241898) (xy 172.610019 -273.196622)
			(xy 172.598242 -273.148838) (xy 172.594282 -273.099784) (xy 172.277024 -273.099784) (xy 172.27652 -273.125492)
			(xy 172.268477 -273.176274) (xy 172.252589 -273.225173) (xy 172.229246 -273.270985) (xy 172.199025 -273.312581)
			(xy 172.162669 -273.348937) (xy 172.121073 -273.379158) (xy 172.075261 -273.402501) (xy 172.026362 -273.418389)
			(xy 171.97558 -273.426432) (xy 171.924164 -273.426432) (xy 171.873382 -273.418389) (xy 171.824483 -273.402501)
			(xy 171.778671 -273.379158) (xy 171.737075 -273.348937) (xy 171.700719 -273.312581) (xy 171.670498 -273.270985)
			(xy 171.647155 -273.225173) (xy 171.631267 -273.176274) (xy 171.623224 -273.125492) (xy 171.304546 -273.125492)
			(xy 171.29683 -273.172968) (xy 171.281246 -273.219649) (xy 171.258375 -273.263226) (xy 171.22881 -273.30257)
			(xy 171.193317 -273.336662) (xy 171.152814 -273.364618) (xy 171.108352 -273.385716) (xy 171.061081 -273.399408)
			(xy 171.012226 -273.40534) (xy 170.963051 -273.403359) (xy 170.914832 -273.393515) (xy 170.868816 -273.376063)
			(xy 170.826195 -273.351456) (xy 170.788074 -273.320331) (xy 170.755439 -273.283494) (xy 170.729136 -273.241898)
			(xy 170.709845 -273.196622) (xy 170.698068 -273.148838) (xy 170.694108 -273.099784) (xy 170.377104 -273.099784)
			(xy 170.3766 -273.125492) (xy 170.368557 -273.176274) (xy 170.352669 -273.225173) (xy 170.329326 -273.270985)
			(xy 170.299105 -273.312581) (xy 170.262749 -273.348937) (xy 170.221153 -273.379158) (xy 170.175341 -273.402501)
			(xy 170.126442 -273.418389) (xy 170.07566 -273.426432) (xy 170.024244 -273.426432) (xy 169.973462 -273.418389)
			(xy 169.924563 -273.402501) (xy 169.878751 -273.379158) (xy 169.837155 -273.348937) (xy 169.800799 -273.312581)
			(xy 169.770578 -273.270985) (xy 169.747235 -273.225173) (xy 169.731347 -273.176274) (xy 169.723304 -273.125492)
			(xy 169.404626 -273.125492) (xy 169.39691 -273.172968) (xy 169.381326 -273.219649) (xy 169.358455 -273.263226)
			(xy 169.32889 -273.30257) (xy 169.293397 -273.336662) (xy 169.252894 -273.364618) (xy 169.208432 -273.385716)
			(xy 169.161161 -273.399408) (xy 169.112306 -273.40534) (xy 169.063131 -273.403359) (xy 169.014912 -273.393515)
			(xy 168.968896 -273.376063) (xy 168.926275 -273.351456) (xy 168.888154 -273.320331) (xy 168.855519 -273.283494)
			(xy 168.829216 -273.241898) (xy 168.809925 -273.196622) (xy 168.798148 -273.148838) (xy 168.794188 -273.099784)
			(xy 168.477184 -273.099784) (xy 168.47668 -273.125492) (xy 168.468637 -273.176274) (xy 168.452749 -273.225173)
			(xy 168.429406 -273.270985) (xy 168.399185 -273.312581) (xy 168.362829 -273.348937) (xy 168.321233 -273.379158)
			(xy 168.275421 -273.402501) (xy 168.226522 -273.418389) (xy 168.17574 -273.426432) (xy 168.124324 -273.426432)
			(xy 168.073542 -273.418389) (xy 168.024643 -273.402501) (xy 167.978831 -273.379158) (xy 167.937235 -273.348937)
			(xy 167.900879 -273.312581) (xy 167.870658 -273.270985) (xy 167.847315 -273.225173) (xy 167.831427 -273.176274)
			(xy 167.823384 -273.125492) (xy 167.504706 -273.125492) (xy 167.49699 -273.172968) (xy 167.481406 -273.219649)
			(xy 167.458535 -273.263226) (xy 167.42897 -273.30257) (xy 167.393477 -273.336662) (xy 167.352974 -273.364618)
			(xy 167.308512 -273.385716) (xy 167.261241 -273.399408) (xy 167.212386 -273.40534) (xy 167.163211 -273.403359)
			(xy 167.114992 -273.393515) (xy 167.068976 -273.376063) (xy 167.026355 -273.351456) (xy 166.988234 -273.320331)
			(xy 166.955599 -273.283494) (xy 166.929296 -273.241898) (xy 166.910005 -273.196622) (xy 166.898228 -273.148838)
			(xy 166.894268 -273.099784) (xy 166.57701 -273.099784) (xy 166.576506 -273.125492) (xy 166.568463 -273.176274)
			(xy 166.552575 -273.225173) (xy 166.529232 -273.270985) (xy 166.499011 -273.312581) (xy 166.462655 -273.348937)
			(xy 166.421059 -273.379158) (xy 166.375247 -273.402501) (xy 166.326348 -273.418389) (xy 166.275566 -273.426432)
			(xy 166.22415 -273.426432) (xy 166.173368 -273.418389) (xy 166.124469 -273.402501) (xy 166.078657 -273.379158)
			(xy 166.037061 -273.348937) (xy 166.000705 -273.312581) (xy 165.970484 -273.270985) (xy 165.947141 -273.225173)
			(xy 165.931253 -273.176274) (xy 165.92321 -273.125492) (xy 165.604532 -273.125492) (xy 165.596816 -273.172968)
			(xy 165.581232 -273.219649) (xy 165.558361 -273.263226) (xy 165.528796 -273.30257) (xy 165.493303 -273.336662)
			(xy 165.4528 -273.364618) (xy 165.408338 -273.385716) (xy 165.361067 -273.399408) (xy 165.312212 -273.40534)
			(xy 165.263037 -273.403359) (xy 165.214818 -273.393515) (xy 165.168802 -273.376063) (xy 165.126181 -273.351456)
			(xy 165.08806 -273.320331) (xy 165.055425 -273.283494) (xy 165.029122 -273.241898) (xy 165.009831 -273.196622)
			(xy 164.998054 -273.148838) (xy 164.994094 -273.099784) (xy 164.67709 -273.099784) (xy 164.676586 -273.125492)
			(xy 164.668543 -273.176274) (xy 164.652655 -273.225173) (xy 164.629312 -273.270985) (xy 164.599091 -273.312581)
			(xy 164.562735 -273.348937) (xy 164.521139 -273.379158) (xy 164.475327 -273.402501) (xy 164.426428 -273.418389)
			(xy 164.375646 -273.426432) (xy 164.32423 -273.426432) (xy 164.273448 -273.418389) (xy 164.224549 -273.402501)
			(xy 164.178737 -273.379158) (xy 164.137141 -273.348937) (xy 164.100785 -273.312581) (xy 164.070564 -273.270985)
			(xy 164.047221 -273.225173) (xy 164.031333 -273.176274) (xy 164.02329 -273.125492) (xy 163.704612 -273.125492)
			(xy 163.696896 -273.172968) (xy 163.681312 -273.219649) (xy 163.658441 -273.263226) (xy 163.628876 -273.30257)
			(xy 163.593383 -273.336662) (xy 163.55288 -273.364618) (xy 163.508418 -273.385716) (xy 163.461147 -273.399408)
			(xy 163.412292 -273.40534) (xy 163.363117 -273.403359) (xy 163.314898 -273.393515) (xy 163.268882 -273.376063)
			(xy 163.226261 -273.351456) (xy 163.18814 -273.320331) (xy 163.155505 -273.283494) (xy 163.129202 -273.241898)
			(xy 163.109911 -273.196622) (xy 163.098134 -273.148838) (xy 163.094174 -273.099784) (xy 162.77717 -273.099784)
			(xy 162.776666 -273.125492) (xy 162.768623 -273.176274) (xy 162.752735 -273.225173) (xy 162.729392 -273.270985)
			(xy 162.699171 -273.312581) (xy 162.662815 -273.348937) (xy 162.621219 -273.379158) (xy 162.575407 -273.402501)
			(xy 162.526508 -273.418389) (xy 162.475726 -273.426432) (xy 162.42431 -273.426432) (xy 162.373528 -273.418389)
			(xy 162.324629 -273.402501) (xy 162.278817 -273.379158) (xy 162.237221 -273.348937) (xy 162.200865 -273.312581)
			(xy 162.170644 -273.270985) (xy 162.147301 -273.225173) (xy 162.131413 -273.176274) (xy 162.12337 -273.125492)
			(xy 161.804692 -273.125492) (xy 161.796976 -273.172968) (xy 161.781392 -273.219649) (xy 161.758521 -273.263226)
			(xy 161.728956 -273.30257) (xy 161.693463 -273.336662) (xy 161.65296 -273.364618) (xy 161.608498 -273.385716)
			(xy 161.561227 -273.399408) (xy 161.512372 -273.40534) (xy 161.463197 -273.403359) (xy 161.414978 -273.393515)
			(xy 161.368962 -273.376063) (xy 161.326341 -273.351456) (xy 161.28822 -273.320331) (xy 161.255585 -273.283494)
			(xy 161.229282 -273.241898) (xy 161.209991 -273.196622) (xy 161.198214 -273.148838) (xy 161.194254 -273.099784)
			(xy 160.876996 -273.099784) (xy 160.876492 -273.125492) (xy 160.868449 -273.176274) (xy 160.852561 -273.225173)
			(xy 160.829218 -273.270985) (xy 160.798997 -273.312581) (xy 160.762641 -273.348937) (xy 160.721045 -273.379158)
			(xy 160.675233 -273.402501) (xy 160.626334 -273.418389) (xy 160.575552 -273.426432) (xy 160.524136 -273.426432)
			(xy 160.473354 -273.418389) (xy 160.424455 -273.402501) (xy 160.378643 -273.379158) (xy 160.337047 -273.348937)
			(xy 160.300691 -273.312581) (xy 160.27047 -273.270985) (xy 160.247127 -273.225173) (xy 160.231239 -273.176274)
			(xy 160.223196 -273.125492) (xy 159.903615 -273.125492) (xy 159.901572 -273.150142) (xy 159.889171 -273.199111)
			(xy 159.868879 -273.24537) (xy 159.84125 -273.287659) (xy 159.807036 -273.324822) (xy 159.767172 -273.355848)
			(xy 159.722745 -273.379889) (xy 159.674967 -273.396289) (xy 159.625141 -273.404601) (xy 159.599884 -273.405092)
			(xy 159.585701 -273.404918) (xy 159.557461 -273.402244) (xy 159.543496 -273.399758) (xy 159.53105 -273.397472)
			(xy 159.507428 -273.404838) (xy 159.429958 -273.482308) (xy 159.422592 -273.50593) (xy 159.424878 -273.518376)
			(xy 159.427361 -273.532341) (xy 159.430028 -273.560581) (xy 159.430212 -273.574764) (xy 159.43003 -273.588947)
			(xy 159.427362 -273.617187) (xy 159.424878 -273.631152) (xy 159.422592 -273.643598) (xy 159.429958 -273.66722)
			(xy 159.507428 -273.74469) (xy 159.53105 -273.752056) (xy 159.543496 -273.74977) (xy 159.557463 -273.747298)
			(xy 159.585702 -273.744623) (xy 159.599884 -273.744436) (xy 159.625146 -273.74484) (xy 159.674982 -273.753153)
			(xy 159.722769 -273.769557) (xy 159.767205 -273.793602) (xy 159.807077 -273.824633) (xy 159.841297 -273.861805)
			(xy 159.868932 -273.904101) (xy 159.889228 -273.95037) (xy 159.901632 -273.999348) (xy 159.905804 -274.0497)
			(xy 159.90367 -274.075452) (xy 160.223196 -274.075452) (xy 160.223196 -274.024036) (xy 160.231239 -273.973254)
			(xy 160.247127 -273.924355) (xy 160.27047 -273.878543) (xy 160.300691 -273.836947) (xy 160.337047 -273.800591)
			(xy 160.378643 -273.77037) (xy 160.424455 -273.747027) (xy 160.473354 -273.731139) (xy 160.524136 -273.723096)
			(xy 160.575552 -273.723096) (xy 160.626334 -273.731139) (xy 160.675233 -273.747027) (xy 160.721045 -273.77037)
			(xy 160.762641 -273.800591) (xy 160.798997 -273.836947) (xy 160.829218 -273.878543) (xy 160.852561 -273.924355)
			(xy 160.868449 -273.973254) (xy 160.876492 -274.024036) (xy 160.876996 -274.049744) (xy 161.194254 -274.049744)
			(xy 161.198214 -274.00069) (xy 161.209991 -273.952906) (xy 161.229282 -273.90763) (xy 161.255585 -273.866034)
			(xy 161.28822 -273.829197) (xy 161.326341 -273.798072) (xy 161.368962 -273.773465) (xy 161.414978 -273.756013)
			(xy 161.463197 -273.746169) (xy 161.512372 -273.744188) (xy 161.561227 -273.75012) (xy 161.608498 -273.763812)
			(xy 161.65296 -273.78491) (xy 161.693463 -273.812866) (xy 161.728956 -273.846958) (xy 161.758521 -273.886302)
			(xy 161.781392 -273.929879) (xy 161.796976 -273.97656) (xy 161.804871 -274.025137) (xy 161.805366 -274.049744)
			(xy 161.804871 -274.074351) (xy 161.804692 -274.075452) (xy 162.12337 -274.075452) (xy 162.12337 -274.024036)
			(xy 162.131413 -273.973254) (xy 162.147301 -273.924355) (xy 162.170644 -273.878543) (xy 162.200865 -273.836947)
			(xy 162.237221 -273.800591) (xy 162.278817 -273.77037) (xy 162.324629 -273.747027) (xy 162.373528 -273.731139)
			(xy 162.42431 -273.723096) (xy 162.475726 -273.723096) (xy 162.526508 -273.731139) (xy 162.575407 -273.747027)
			(xy 162.621219 -273.77037) (xy 162.662815 -273.800591) (xy 162.699171 -273.836947) (xy 162.729392 -273.878543)
			(xy 162.752735 -273.924355) (xy 162.768623 -273.973254) (xy 162.776666 -274.024036) (xy 162.77717 -274.049744)
			(xy 163.094174 -274.049744) (xy 163.098134 -274.00069) (xy 163.109911 -273.952906) (xy 163.129202 -273.90763)
			(xy 163.155505 -273.866034) (xy 163.18814 -273.829197) (xy 163.226261 -273.798072) (xy 163.268882 -273.773465)
			(xy 163.314898 -273.756013) (xy 163.363117 -273.746169) (xy 163.412292 -273.744188) (xy 163.461147 -273.75012)
			(xy 163.508418 -273.763812) (xy 163.55288 -273.78491) (xy 163.593383 -273.812866) (xy 163.628876 -273.846958)
			(xy 163.658441 -273.886302) (xy 163.681312 -273.929879) (xy 163.696896 -273.97656) (xy 163.704791 -274.025137)
			(xy 163.705286 -274.049744) (xy 163.704791 -274.074351) (xy 163.704612 -274.075452) (xy 164.02329 -274.075452)
			(xy 164.02329 -274.024036) (xy 164.031333 -273.973254) (xy 164.047221 -273.924355) (xy 164.070564 -273.878543)
			(xy 164.100785 -273.836947) (xy 164.137141 -273.800591) (xy 164.178737 -273.77037) (xy 164.224549 -273.747027)
			(xy 164.273448 -273.731139) (xy 164.32423 -273.723096) (xy 164.375646 -273.723096) (xy 164.426428 -273.731139)
			(xy 164.475327 -273.747027) (xy 164.521139 -273.77037) (xy 164.562735 -273.800591) (xy 164.599091 -273.836947)
			(xy 164.629312 -273.878543) (xy 164.652655 -273.924355) (xy 164.668543 -273.973254) (xy 164.676586 -274.024036)
			(xy 164.67709 -274.049744) (xy 164.994094 -274.049744) (xy 164.998054 -274.00069) (xy 165.009831 -273.952906)
			(xy 165.029122 -273.90763) (xy 165.055425 -273.866034) (xy 165.08806 -273.829197) (xy 165.126181 -273.798072)
			(xy 165.168802 -273.773465) (xy 165.214818 -273.756013) (xy 165.263037 -273.746169) (xy 165.312212 -273.744188)
			(xy 165.361067 -273.75012) (xy 165.408338 -273.763812) (xy 165.4528 -273.78491) (xy 165.493303 -273.812866)
			(xy 165.528796 -273.846958) (xy 165.558361 -273.886302) (xy 165.581232 -273.929879) (xy 165.596816 -273.97656)
			(xy 165.604711 -274.025137) (xy 165.605206 -274.049744) (xy 165.604711 -274.074351) (xy 165.604532 -274.075452)
			(xy 165.92321 -274.075452) (xy 165.92321 -274.024036) (xy 165.931253 -273.973254) (xy 165.947141 -273.924355)
			(xy 165.970484 -273.878543) (xy 166.000705 -273.836947) (xy 166.037061 -273.800591) (xy 166.078657 -273.77037)
			(xy 166.124469 -273.747027) (xy 166.173368 -273.731139) (xy 166.22415 -273.723096) (xy 166.275566 -273.723096)
			(xy 166.326348 -273.731139) (xy 166.375247 -273.747027) (xy 166.421059 -273.77037) (xy 166.462655 -273.800591)
			(xy 166.499011 -273.836947) (xy 166.529232 -273.878543) (xy 166.552575 -273.924355) (xy 166.568463 -273.973254)
			(xy 166.576506 -274.024036) (xy 166.57701 -274.049744) (xy 166.894268 -274.049744) (xy 166.898228 -274.00069)
			(xy 166.910005 -273.952906) (xy 166.929296 -273.90763) (xy 166.955599 -273.866034) (xy 166.988234 -273.829197)
			(xy 167.026355 -273.798072) (xy 167.068976 -273.773465) (xy 167.114992 -273.756013) (xy 167.163211 -273.746169)
			(xy 167.212386 -273.744188) (xy 167.261241 -273.75012) (xy 167.308512 -273.763812) (xy 167.352974 -273.78491)
			(xy 167.393477 -273.812866) (xy 167.42897 -273.846958) (xy 167.458535 -273.886302) (xy 167.481406 -273.929879)
			(xy 167.49699 -273.97656) (xy 167.504885 -274.025137) (xy 167.50538 -274.049744) (xy 167.504885 -274.074351)
			(xy 167.504706 -274.075452) (xy 167.823384 -274.075452) (xy 167.823384 -274.024036) (xy 167.831427 -273.973254)
			(xy 167.847315 -273.924355) (xy 167.870658 -273.878543) (xy 167.900879 -273.836947) (xy 167.937235 -273.800591)
			(xy 167.978831 -273.77037) (xy 168.024643 -273.747027) (xy 168.073542 -273.731139) (xy 168.124324 -273.723096)
			(xy 168.17574 -273.723096) (xy 168.226522 -273.731139) (xy 168.275421 -273.747027) (xy 168.321233 -273.77037)
			(xy 168.362829 -273.800591) (xy 168.399185 -273.836947) (xy 168.429406 -273.878543) (xy 168.452749 -273.924355)
			(xy 168.468637 -273.973254) (xy 168.47668 -274.024036) (xy 168.477184 -274.049744) (xy 168.794188 -274.049744)
			(xy 168.798148 -274.00069) (xy 168.809925 -273.952906) (xy 168.829216 -273.90763) (xy 168.855519 -273.866034)
			(xy 168.888154 -273.829197) (xy 168.926275 -273.798072) (xy 168.968896 -273.773465) (xy 169.014912 -273.756013)
			(xy 169.063131 -273.746169) (xy 169.112306 -273.744188) (xy 169.161161 -273.75012) (xy 169.208432 -273.763812)
			(xy 169.252894 -273.78491) (xy 169.293397 -273.812866) (xy 169.32889 -273.846958) (xy 169.358455 -273.886302)
			(xy 169.381326 -273.929879) (xy 169.39691 -273.97656) (xy 169.404805 -274.025137) (xy 169.4053 -274.049744)
			(xy 169.404805 -274.074351) (xy 169.404626 -274.075452) (xy 169.723304 -274.075452) (xy 169.723304 -274.024036)
			(xy 169.731347 -273.973254) (xy 169.747235 -273.924355) (xy 169.770578 -273.878543) (xy 169.800799 -273.836947)
			(xy 169.837155 -273.800591) (xy 169.878751 -273.77037) (xy 169.924563 -273.747027) (xy 169.973462 -273.731139)
			(xy 170.024244 -273.723096) (xy 170.07566 -273.723096) (xy 170.126442 -273.731139) (xy 170.175341 -273.747027)
			(xy 170.221153 -273.77037) (xy 170.262749 -273.800591) (xy 170.299105 -273.836947) (xy 170.329326 -273.878543)
			(xy 170.352669 -273.924355) (xy 170.368557 -273.973254) (xy 170.3766 -274.024036) (xy 170.377104 -274.049744)
			(xy 170.694108 -274.049744) (xy 170.698068 -274.00069) (xy 170.709845 -273.952906) (xy 170.729136 -273.90763)
			(xy 170.755439 -273.866034) (xy 170.788074 -273.829197) (xy 170.826195 -273.798072) (xy 170.868816 -273.773465)
			(xy 170.914832 -273.756013) (xy 170.963051 -273.746169) (xy 171.012226 -273.744188) (xy 171.061081 -273.75012)
			(xy 171.108352 -273.763812) (xy 171.152814 -273.78491) (xy 171.193317 -273.812866) (xy 171.22881 -273.846958)
			(xy 171.258375 -273.886302) (xy 171.281246 -273.929879) (xy 171.29683 -273.97656) (xy 171.304725 -274.025137)
			(xy 171.30522 -274.049744) (xy 171.304725 -274.074351) (xy 171.304546 -274.075452) (xy 171.623224 -274.075452)
			(xy 171.623224 -274.024036) (xy 171.631267 -273.973254) (xy 171.647155 -273.924355) (xy 171.670498 -273.878543)
			(xy 171.700719 -273.836947) (xy 171.737075 -273.800591) (xy 171.778671 -273.77037) (xy 171.824483 -273.747027)
			(xy 171.873382 -273.731139) (xy 171.924164 -273.723096) (xy 171.97558 -273.723096) (xy 172.026362 -273.731139)
			(xy 172.075261 -273.747027) (xy 172.121073 -273.77037) (xy 172.162669 -273.800591) (xy 172.199025 -273.836947)
			(xy 172.229246 -273.878543) (xy 172.252589 -273.924355) (xy 172.268477 -273.973254) (xy 172.27652 -274.024036)
			(xy 172.277024 -274.049744) (xy 172.594282 -274.049744) (xy 172.598242 -274.00069) (xy 172.610019 -273.952906)
			(xy 172.62931 -273.90763) (xy 172.655613 -273.866034) (xy 172.688248 -273.829197) (xy 172.726369 -273.798072)
			(xy 172.76899 -273.773465) (xy 172.815006 -273.756013) (xy 172.863225 -273.746169) (xy 172.9124 -273.744188)
			(xy 172.961255 -273.75012) (xy 173.008526 -273.763812) (xy 173.052988 -273.78491) (xy 173.093491 -273.812866)
			(xy 173.128984 -273.846958) (xy 173.158549 -273.886302) (xy 173.18142 -273.929879) (xy 173.197004 -273.97656)
			(xy 173.204899 -274.025137) (xy 173.205394 -274.049744) (xy 173.204899 -274.074351) (xy 173.20472 -274.075452)
			(xy 173.523398 -274.075452) (xy 173.523398 -274.024036) (xy 173.531441 -273.973254) (xy 173.547329 -273.924355)
			(xy 173.570672 -273.878543) (xy 173.600893 -273.836947) (xy 173.637249 -273.800591) (xy 173.678845 -273.77037)
			(xy 173.724657 -273.747027) (xy 173.773556 -273.731139) (xy 173.824338 -273.723096) (xy 173.875754 -273.723096)
			(xy 173.926536 -273.731139) (xy 173.975435 -273.747027) (xy 174.021247 -273.77037) (xy 174.062843 -273.800591)
			(xy 174.099199 -273.836947) (xy 174.12942 -273.878543) (xy 174.152763 -273.924355) (xy 174.168651 -273.973254)
			(xy 174.176694 -274.024036) (xy 174.177198 -274.049744) (xy 174.494202 -274.049744) (xy 174.498162 -274.00069)
			(xy 174.509939 -273.952906) (xy 174.52923 -273.90763) (xy 174.555533 -273.866034) (xy 174.588168 -273.829197)
			(xy 174.626289 -273.798072) (xy 174.66891 -273.773465) (xy 174.714926 -273.756013) (xy 174.763145 -273.746169)
			(xy 174.81232 -273.744188) (xy 174.861175 -273.75012) (xy 174.908446 -273.763812) (xy 174.952908 -273.78491)
			(xy 174.993411 -273.812866) (xy 175.028904 -273.846958) (xy 175.058469 -273.886302) (xy 175.08134 -273.929879)
			(xy 175.096924 -273.97656) (xy 175.104819 -274.025137) (xy 175.105314 -274.049744) (xy 175.104819 -274.074351)
			(xy 175.104681 -274.075198) (xy 175.423064 -274.075198) (xy 175.423064 -274.023782) (xy 175.431107 -273.973)
			(xy 175.446995 -273.924101) (xy 175.470338 -273.878289) (xy 175.500559 -273.836693) (xy 175.536915 -273.800337)
			(xy 175.578511 -273.770116) (xy 175.624323 -273.746773) (xy 175.673222 -273.730885) (xy 175.724004 -273.722842)
			(xy 175.77542 -273.722842) (xy 175.826202 -273.730885) (xy 175.875101 -273.746773) (xy 175.920913 -273.770116)
			(xy 175.962509 -273.800337) (xy 175.998865 -273.836693) (xy 176.029086 -273.878289) (xy 176.052429 -273.924101)
			(xy 176.068317 -273.973) (xy 176.07636 -274.023782) (xy 176.076864 -274.04949) (xy 176.076859 -274.049744)
			(xy 176.394122 -274.049744) (xy 176.398082 -274.00069) (xy 176.409859 -273.952906) (xy 176.42915 -273.90763)
			(xy 176.455453 -273.866034) (xy 176.488088 -273.829197) (xy 176.526209 -273.798072) (xy 176.56883 -273.773465)
			(xy 176.614846 -273.756013) (xy 176.663065 -273.746169) (xy 176.71224 -273.744188) (xy 176.761095 -273.75012)
			(xy 176.808366 -273.763812) (xy 176.852828 -273.78491) (xy 176.893331 -273.812866) (xy 176.928824 -273.846958)
			(xy 176.958389 -273.886302) (xy 176.98126 -273.929879) (xy 176.996844 -273.97656) (xy 177.004739 -274.025137)
			(xy 177.005234 -274.049744) (xy 177.004739 -274.074351) (xy 177.00456 -274.075452) (xy 177.322984 -274.075452)
			(xy 177.322984 -274.024036) (xy 177.331027 -273.973254) (xy 177.346915 -273.924355) (xy 177.370258 -273.878543)
			(xy 177.400479 -273.836947) (xy 177.436835 -273.800591) (xy 177.478431 -273.77037) (xy 177.524243 -273.747027)
			(xy 177.573142 -273.731139) (xy 177.623924 -273.723096) (xy 177.67534 -273.723096) (xy 177.726122 -273.731139)
			(xy 177.775021 -273.747027) (xy 177.820833 -273.77037) (xy 177.862429 -273.800591) (xy 177.898785 -273.836947)
			(xy 177.929006 -273.878543) (xy 177.952349 -273.924355) (xy 177.968237 -273.973254) (xy 177.97628 -274.024036)
			(xy 177.976784 -274.049744) (xy 178.294042 -274.049744) (xy 178.298002 -274.00069) (xy 178.309779 -273.952906)
			(xy 178.32907 -273.90763) (xy 178.355373 -273.866034) (xy 178.388008 -273.829197) (xy 178.426129 -273.798072)
			(xy 178.46875 -273.773465) (xy 178.514766 -273.756013) (xy 178.562985 -273.746169) (xy 178.61216 -273.744188)
			(xy 178.661015 -273.75012) (xy 178.708286 -273.763812) (xy 178.752748 -273.78491) (xy 178.793251 -273.812866)
			(xy 178.828744 -273.846958) (xy 178.858309 -273.886302) (xy 178.88118 -273.929879) (xy 178.896764 -273.97656)
			(xy 178.904659 -274.025137) (xy 178.905154 -274.049744) (xy 178.904659 -274.074351) (xy 178.90448 -274.075452)
			(xy 179.223158 -274.075452) (xy 179.223158 -274.024036) (xy 179.231201 -273.973254) (xy 179.247089 -273.924355)
			(xy 179.270432 -273.878543) (xy 179.300653 -273.836947) (xy 179.337009 -273.800591) (xy 179.378605 -273.77037)
			(xy 179.424417 -273.747027) (xy 179.473316 -273.731139) (xy 179.524098 -273.723096) (xy 179.575514 -273.723096)
			(xy 179.626296 -273.731139) (xy 179.675195 -273.747027) (xy 179.721007 -273.77037) (xy 179.762603 -273.800591)
			(xy 179.798959 -273.836947) (xy 179.82918 -273.878543) (xy 179.852523 -273.924355) (xy 179.868411 -273.973254)
			(xy 179.876454 -274.024036) (xy 179.876958 -274.049744) (xy 180.194216 -274.049744) (xy 180.198176 -274.00069)
			(xy 180.209953 -273.952906) (xy 180.229244 -273.90763) (xy 180.255547 -273.866034) (xy 180.288182 -273.829197)
			(xy 180.326303 -273.798072) (xy 180.368924 -273.773465) (xy 180.41494 -273.756013) (xy 180.463159 -273.746169)
			(xy 180.512334 -273.744188) (xy 180.561189 -273.75012) (xy 180.60846 -273.763812) (xy 180.652922 -273.78491)
			(xy 180.693425 -273.812866) (xy 180.728918 -273.846958) (xy 180.758483 -273.886302) (xy 180.781354 -273.929879)
			(xy 180.796938 -273.97656) (xy 180.804833 -274.025137) (xy 180.805328 -274.049744) (xy 180.804833 -274.074351)
			(xy 180.804654 -274.075452) (xy 181.123078 -274.075452) (xy 181.123078 -274.024036) (xy 181.131121 -273.973254)
			(xy 181.147009 -273.924355) (xy 181.170352 -273.878543) (xy 181.200573 -273.836947) (xy 181.236929 -273.800591)
			(xy 181.278525 -273.77037) (xy 181.324337 -273.747027) (xy 181.373236 -273.731139) (xy 181.424018 -273.723096)
			(xy 181.475434 -273.723096) (xy 181.526216 -273.731139) (xy 181.575115 -273.747027) (xy 181.620927 -273.77037)
			(xy 181.662523 -273.800591) (xy 181.698879 -273.836947) (xy 181.7291 -273.878543) (xy 181.752443 -273.924355)
			(xy 181.768331 -273.973254) (xy 181.776374 -274.024036) (xy 181.776878 -274.049744) (xy 182.094136 -274.049744)
			(xy 182.098096 -274.00069) (xy 182.109873 -273.952906) (xy 182.129164 -273.90763) (xy 182.155467 -273.866034)
			(xy 182.188102 -273.829197) (xy 182.226223 -273.798072) (xy 182.268844 -273.773465) (xy 182.31486 -273.756013)
			(xy 182.363079 -273.746169) (xy 182.412254 -273.744188) (xy 182.461109 -273.75012) (xy 182.50838 -273.763812)
			(xy 182.552842 -273.78491) (xy 182.593345 -273.812866) (xy 182.628838 -273.846958) (xy 182.658403 -273.886302)
			(xy 182.681274 -273.929879) (xy 182.696858 -273.97656) (xy 182.704753 -274.025137) (xy 182.705248 -274.049744)
			(xy 182.704753 -274.074351) (xy 182.704574 -274.075452) (xy 183.022998 -274.075452) (xy 183.022998 -274.024036)
			(xy 183.031041 -273.973254) (xy 183.046929 -273.924355) (xy 183.070272 -273.878543) (xy 183.100493 -273.836947)
			(xy 183.136849 -273.800591) (xy 183.178445 -273.77037) (xy 183.224257 -273.747027) (xy 183.273156 -273.731139)
			(xy 183.323938 -273.723096) (xy 183.375354 -273.723096) (xy 183.426136 -273.731139) (xy 183.475035 -273.747027)
			(xy 183.520847 -273.77037) (xy 183.562443 -273.800591) (xy 183.598799 -273.836947) (xy 183.62902 -273.878543)
			(xy 183.652363 -273.924355) (xy 183.668251 -273.973254) (xy 183.676294 -274.024036) (xy 183.676798 -274.049744)
			(xy 183.994056 -274.049744) (xy 183.998016 -274.00069) (xy 184.009793 -273.952906) (xy 184.029084 -273.90763)
			(xy 184.055387 -273.866034) (xy 184.088022 -273.829197) (xy 184.126143 -273.798072) (xy 184.168764 -273.773465)
			(xy 184.21478 -273.756013) (xy 184.262999 -273.746169) (xy 184.312174 -273.744188) (xy 184.361029 -273.75012)
			(xy 184.4083 -273.763812) (xy 184.452762 -273.78491) (xy 184.493265 -273.812866) (xy 184.528758 -273.846958)
			(xy 184.558323 -273.886302) (xy 184.581194 -273.929879) (xy 184.596778 -273.97656) (xy 184.604673 -274.025137)
			(xy 184.605168 -274.049744) (xy 184.604673 -274.074351) (xy 184.604494 -274.075452) (xy 184.923172 -274.075452)
			(xy 184.923172 -274.024036) (xy 184.931215 -273.973254) (xy 184.947103 -273.924355) (xy 184.970446 -273.878543)
			(xy 185.000667 -273.836947) (xy 185.037023 -273.800591) (xy 185.078619 -273.77037) (xy 185.124431 -273.747027)
			(xy 185.17333 -273.731139) (xy 185.224112 -273.723096) (xy 185.275528 -273.723096) (xy 185.32631 -273.731139)
			(xy 185.375209 -273.747027) (xy 185.421021 -273.77037) (xy 185.462617 -273.800591) (xy 185.498973 -273.836947)
			(xy 185.529194 -273.878543) (xy 185.552537 -273.924355) (xy 185.568425 -273.973254) (xy 185.576468 -274.024036)
			(xy 185.576972 -274.049744) (xy 185.89423 -274.049744) (xy 185.89819 -274.00069) (xy 185.909967 -273.952906)
			(xy 185.929258 -273.90763) (xy 185.955561 -273.866034) (xy 185.988196 -273.829197) (xy 186.026317 -273.798072)
			(xy 186.068938 -273.773465) (xy 186.114954 -273.756013) (xy 186.163173 -273.746169) (xy 186.212348 -273.744188)
			(xy 186.261203 -273.75012) (xy 186.308474 -273.763812) (xy 186.352936 -273.78491) (xy 186.393439 -273.812866)
			(xy 186.428932 -273.846958) (xy 186.458497 -273.886302) (xy 186.481368 -273.929879) (xy 186.496952 -273.97656)
			(xy 186.504847 -274.025137) (xy 186.505342 -274.049744) (xy 186.504847 -274.074351) (xy 186.504668 -274.075452)
			(xy 186.823092 -274.075452) (xy 186.823092 -274.024036) (xy 186.831135 -273.973254) (xy 186.847023 -273.924355)
			(xy 186.870366 -273.878543) (xy 186.900587 -273.836947) (xy 186.936943 -273.800591) (xy 186.978539 -273.77037)
			(xy 187.024351 -273.747027) (xy 187.07325 -273.731139) (xy 187.124032 -273.723096) (xy 187.175448 -273.723096)
			(xy 187.22623 -273.731139) (xy 187.275129 -273.747027) (xy 187.320941 -273.77037) (xy 187.362537 -273.800591)
			(xy 187.398893 -273.836947) (xy 187.429114 -273.878543) (xy 187.452457 -273.924355) (xy 187.468345 -273.973254)
			(xy 187.476388 -274.024036) (xy 187.476892 -274.049744) (xy 187.79415 -274.049744) (xy 187.79811 -274.00069)
			(xy 187.809887 -273.952906) (xy 187.829178 -273.90763) (xy 187.855481 -273.866034) (xy 187.888116 -273.829197)
			(xy 187.926237 -273.798072) (xy 187.968858 -273.773465) (xy 188.014874 -273.756013) (xy 188.063093 -273.746169)
			(xy 188.112268 -273.744188) (xy 188.161123 -273.75012) (xy 188.208394 -273.763812) (xy 188.252856 -273.78491)
			(xy 188.293359 -273.812866) (xy 188.328852 -273.846958) (xy 188.358417 -273.886302) (xy 188.381288 -273.929879)
			(xy 188.396872 -273.97656) (xy 188.404767 -274.025137) (xy 188.405262 -274.049744) (xy 188.404767 -274.074351)
			(xy 188.404588 -274.075452) (xy 188.723012 -274.075452) (xy 188.723012 -274.024036) (xy 188.731055 -273.973254)
			(xy 188.746943 -273.924355) (xy 188.770286 -273.878543) (xy 188.800507 -273.836947) (xy 188.836863 -273.800591)
			(xy 188.878459 -273.77037) (xy 188.924271 -273.747027) (xy 188.97317 -273.731139) (xy 189.023952 -273.723096)
			(xy 189.075368 -273.723096) (xy 189.12615 -273.731139) (xy 189.175049 -273.747027) (xy 189.220861 -273.77037)
			(xy 189.262457 -273.800591) (xy 189.298813 -273.836947) (xy 189.329034 -273.878543) (xy 189.352377 -273.924355)
			(xy 189.368265 -273.973254) (xy 189.376308 -274.024036) (xy 189.376812 -274.049744) (xy 189.69407 -274.049744)
			(xy 189.69803 -274.00069) (xy 189.709807 -273.952906) (xy 189.729098 -273.90763) (xy 189.755401 -273.866034)
			(xy 189.788036 -273.829197) (xy 189.826157 -273.798072) (xy 189.868778 -273.773465) (xy 189.914794 -273.756013)
			(xy 189.963013 -273.746169) (xy 190.012188 -273.744188) (xy 190.061043 -273.75012) (xy 190.108314 -273.763812)
			(xy 190.152776 -273.78491) (xy 190.193279 -273.812866) (xy 190.228772 -273.846958) (xy 190.258337 -273.886302)
			(xy 190.281208 -273.929879) (xy 190.296792 -273.97656) (xy 190.304687 -274.025137) (xy 190.305182 -274.049744)
			(xy 190.304687 -274.074351) (xy 190.304508 -274.075452) (xy 190.623186 -274.075452) (xy 190.623186 -274.024036)
			(xy 190.631229 -273.973254) (xy 190.647117 -273.924355) (xy 190.67046 -273.878543) (xy 190.700681 -273.836947)
			(xy 190.737037 -273.800591) (xy 190.778633 -273.77037) (xy 190.824445 -273.747027) (xy 190.873344 -273.731139)
			(xy 190.924126 -273.723096) (xy 190.975542 -273.723096) (xy 191.026324 -273.731139) (xy 191.075223 -273.747027)
			(xy 191.121035 -273.77037) (xy 191.162631 -273.800591) (xy 191.198987 -273.836947) (xy 191.229208 -273.878543)
			(xy 191.252551 -273.924355) (xy 191.268439 -273.973254) (xy 191.276482 -274.024036) (xy 191.276986 -274.049744)
			(xy 191.594498 -274.049744) (xy 191.598458 -274.00069) (xy 191.610235 -273.952906) (xy 191.629526 -273.90763)
			(xy 191.655829 -273.866034) (xy 191.688464 -273.829197) (xy 191.726585 -273.798072) (xy 191.769206 -273.773465)
			(xy 191.815222 -273.756013) (xy 191.863441 -273.746169) (xy 191.912616 -273.744188) (xy 191.961471 -273.75012)
			(xy 192.008742 -273.763812) (xy 192.053204 -273.78491) (xy 192.093707 -273.812866) (xy 192.1292 -273.846958)
			(xy 192.158765 -273.886302) (xy 192.181636 -273.929879) (xy 192.19722 -273.97656) (xy 192.205115 -274.025137)
			(xy 192.20561 -274.049744) (xy 192.205115 -274.074351) (xy 192.204936 -274.075452) (xy 192.523106 -274.075452)
			(xy 192.523106 -274.024036) (xy 192.531149 -273.973254) (xy 192.547037 -273.924355) (xy 192.57038 -273.878543)
			(xy 192.600601 -273.836947) (xy 192.636957 -273.800591) (xy 192.678553 -273.77037) (xy 192.724365 -273.747027)
			(xy 192.773264 -273.731139) (xy 192.824046 -273.723096) (xy 192.875462 -273.723096) (xy 192.926244 -273.731139)
			(xy 192.975143 -273.747027) (xy 193.020955 -273.77037) (xy 193.062551 -273.800591) (xy 193.098907 -273.836947)
			(xy 193.129128 -273.878543) (xy 193.152471 -273.924355) (xy 193.168359 -273.973254) (xy 193.176402 -274.024036)
			(xy 193.176906 -274.049744) (xy 193.494418 -274.049744) (xy 193.498378 -274.00069) (xy 193.510155 -273.952906)
			(xy 193.529446 -273.90763) (xy 193.555749 -273.866034) (xy 193.588384 -273.829197) (xy 193.626505 -273.798072)
			(xy 193.669126 -273.773465) (xy 193.715142 -273.756013) (xy 193.763361 -273.746169) (xy 193.812536 -273.744188)
			(xy 193.861391 -273.75012) (xy 193.908662 -273.763812) (xy 193.953124 -273.78491) (xy 193.993627 -273.812866)
			(xy 194.02912 -273.846958) (xy 194.058685 -273.886302) (xy 194.081556 -273.929879) (xy 194.09714 -273.97656)
			(xy 194.105035 -274.025137) (xy 194.10553 -274.049744) (xy 194.105035 -274.074351) (xy 194.104856 -274.075452)
			(xy 194.423026 -274.075452) (xy 194.423026 -274.024036) (xy 194.431069 -273.973254) (xy 194.446957 -273.924355)
			(xy 194.4703 -273.878543) (xy 194.500521 -273.836947) (xy 194.536877 -273.800591) (xy 194.578473 -273.77037)
			(xy 194.624285 -273.747027) (xy 194.673184 -273.731139) (xy 194.723966 -273.723096) (xy 194.775382 -273.723096)
			(xy 194.826164 -273.731139) (xy 194.875063 -273.747027) (xy 194.920875 -273.77037) (xy 194.962471 -273.800591)
			(xy 194.998827 -273.836947) (xy 195.029048 -273.878543) (xy 195.052391 -273.924355) (xy 195.068279 -273.973254)
			(xy 195.076322 -274.024036) (xy 195.076826 -274.049744) (xy 195.394338 -274.049744) (xy 195.398298 -274.00069)
			(xy 195.410075 -273.952906) (xy 195.429366 -273.90763) (xy 195.455669 -273.866034) (xy 195.488304 -273.829197)
			(xy 195.526425 -273.798072) (xy 195.569046 -273.773465) (xy 195.615062 -273.756013) (xy 195.663281 -273.746169)
			(xy 195.712456 -273.744188) (xy 195.761311 -273.75012) (xy 195.808582 -273.763812) (xy 195.853044 -273.78491)
			(xy 195.893547 -273.812866) (xy 195.92904 -273.846958) (xy 195.958605 -273.886302) (xy 195.981476 -273.929879)
			(xy 195.99706 -273.97656) (xy 196.004955 -274.025137) (xy 196.00545 -274.049744) (xy 196.004955 -274.074351)
			(xy 196.004776 -274.075452) (xy 196.322946 -274.075452) (xy 196.322946 -274.024036) (xy 196.330989 -273.973254)
			(xy 196.346877 -273.924355) (xy 196.37022 -273.878543) (xy 196.400441 -273.836947) (xy 196.436797 -273.800591)
			(xy 196.478393 -273.77037) (xy 196.524205 -273.747027) (xy 196.573104 -273.731139) (xy 196.623886 -273.723096)
			(xy 196.675302 -273.723096) (xy 196.726084 -273.731139) (xy 196.774983 -273.747027) (xy 196.820795 -273.77037)
			(xy 196.862391 -273.800591) (xy 196.898747 -273.836947) (xy 196.928968 -273.878543) (xy 196.952311 -273.924355)
			(xy 196.968199 -273.973254) (xy 196.976242 -274.024036) (xy 196.976746 -274.049744) (xy 197.294258 -274.049744)
			(xy 197.298218 -274.00069) (xy 197.309995 -273.952906) (xy 197.329286 -273.90763) (xy 197.355589 -273.866034)
			(xy 197.388224 -273.829197) (xy 197.426345 -273.798072) (xy 197.468966 -273.773465) (xy 197.514982 -273.756013)
			(xy 197.563201 -273.746169) (xy 197.612376 -273.744188) (xy 197.661231 -273.75012) (xy 197.708502 -273.763812)
			(xy 197.752964 -273.78491) (xy 197.793467 -273.812866) (xy 197.82896 -273.846958) (xy 197.858525 -273.886302)
			(xy 197.881396 -273.929879) (xy 197.89698 -273.97656) (xy 197.904875 -274.025137) (xy 197.90537 -274.049744)
			(xy 198.244218 -274.049744) (xy 198.248178 -274.00069) (xy 198.259955 -273.952906) (xy 198.279246 -273.90763)
			(xy 198.305549 -273.866034) (xy 198.338184 -273.829197) (xy 198.376305 -273.798072) (xy 198.418926 -273.773465)
			(xy 198.464942 -273.756013) (xy 198.513161 -273.746169) (xy 198.562336 -273.744188) (xy 198.611191 -273.75012)
			(xy 198.658462 -273.763812) (xy 198.702924 -273.78491) (xy 198.743427 -273.812866) (xy 198.77892 -273.846958)
			(xy 198.808485 -273.886302) (xy 198.831356 -273.929879) (xy 198.84694 -273.97656) (xy 198.854835 -274.025137)
			(xy 198.85533 -274.049744) (xy 198.854835 -274.074351) (xy 198.84694 -274.122928) (xy 198.831356 -274.169609)
			(xy 198.808485 -274.213186) (xy 198.77892 -274.25253) (xy 198.743427 -274.286622) (xy 198.702924 -274.314578)
			(xy 198.658462 -274.335676) (xy 198.611191 -274.349368) (xy 198.562336 -274.3553) (xy 198.513161 -274.353319)
			(xy 198.464942 -274.343475) (xy 198.418926 -274.326023) (xy 198.376305 -274.301416) (xy 198.338184 -274.270291)
			(xy 198.305549 -274.233454) (xy 198.279246 -274.191858) (xy 198.259955 -274.146582) (xy 198.248178 -274.098798)
			(xy 198.244218 -274.049744) (xy 197.90537 -274.049744) (xy 197.904875 -274.074351) (xy 197.89698 -274.122928)
			(xy 197.881396 -274.169609) (xy 197.858525 -274.213186) (xy 197.82896 -274.25253) (xy 197.793467 -274.286622)
			(xy 197.752964 -274.314578) (xy 197.708502 -274.335676) (xy 197.661231 -274.349368) (xy 197.612376 -274.3553)
			(xy 197.563201 -274.353319) (xy 197.514982 -274.343475) (xy 197.468966 -274.326023) (xy 197.426345 -274.301416)
			(xy 197.388224 -274.270291) (xy 197.355589 -274.233454) (xy 197.329286 -274.191858) (xy 197.309995 -274.146582)
			(xy 197.298218 -274.098798) (xy 197.294258 -274.049744) (xy 196.976746 -274.049744) (xy 196.976242 -274.075452)
			(xy 196.968199 -274.126234) (xy 196.952311 -274.175133) (xy 196.928968 -274.220945) (xy 196.898747 -274.262541)
			(xy 196.862391 -274.298897) (xy 196.820795 -274.329118) (xy 196.774983 -274.352461) (xy 196.726084 -274.368349)
			(xy 196.675302 -274.376392) (xy 196.623886 -274.376392) (xy 196.573104 -274.368349) (xy 196.524205 -274.352461)
			(xy 196.478393 -274.329118) (xy 196.436797 -274.298897) (xy 196.400441 -274.262541) (xy 196.37022 -274.220945)
			(xy 196.346877 -274.175133) (xy 196.330989 -274.126234) (xy 196.322946 -274.075452) (xy 196.004776 -274.075452)
			(xy 195.99706 -274.122928) (xy 195.981476 -274.169609) (xy 195.958605 -274.213186) (xy 195.92904 -274.25253)
			(xy 195.893547 -274.286622) (xy 195.853044 -274.314578) (xy 195.808582 -274.335676) (xy 195.761311 -274.349368)
			(xy 195.712456 -274.3553) (xy 195.663281 -274.353319) (xy 195.615062 -274.343475) (xy 195.569046 -274.326023)
			(xy 195.526425 -274.301416) (xy 195.488304 -274.270291) (xy 195.455669 -274.233454) (xy 195.429366 -274.191858)
			(xy 195.410075 -274.146582) (xy 195.398298 -274.098798) (xy 195.394338 -274.049744) (xy 195.076826 -274.049744)
			(xy 195.076322 -274.075452) (xy 195.068279 -274.126234) (xy 195.052391 -274.175133) (xy 195.029048 -274.220945)
			(xy 194.998827 -274.262541) (xy 194.962471 -274.298897) (xy 194.920875 -274.329118) (xy 194.875063 -274.352461)
			(xy 194.826164 -274.368349) (xy 194.775382 -274.376392) (xy 194.723966 -274.376392) (xy 194.673184 -274.368349)
			(xy 194.624285 -274.352461) (xy 194.578473 -274.329118) (xy 194.536877 -274.298897) (xy 194.500521 -274.262541)
			(xy 194.4703 -274.220945) (xy 194.446957 -274.175133) (xy 194.431069 -274.126234) (xy 194.423026 -274.075452)
			(xy 194.104856 -274.075452) (xy 194.09714 -274.122928) (xy 194.081556 -274.169609) (xy 194.058685 -274.213186)
			(xy 194.02912 -274.25253) (xy 193.993627 -274.286622) (xy 193.953124 -274.314578) (xy 193.908662 -274.335676)
			(xy 193.861391 -274.349368) (xy 193.812536 -274.3553) (xy 193.763361 -274.353319) (xy 193.715142 -274.343475)
			(xy 193.669126 -274.326023) (xy 193.626505 -274.301416) (xy 193.588384 -274.270291) (xy 193.555749 -274.233454)
			(xy 193.529446 -274.191858) (xy 193.510155 -274.146582) (xy 193.498378 -274.098798) (xy 193.494418 -274.049744)
			(xy 193.176906 -274.049744) (xy 193.176402 -274.075452) (xy 193.168359 -274.126234) (xy 193.152471 -274.175133)
			(xy 193.129128 -274.220945) (xy 193.098907 -274.262541) (xy 193.062551 -274.298897) (xy 193.020955 -274.329118)
			(xy 192.975143 -274.352461) (xy 192.926244 -274.368349) (xy 192.875462 -274.376392) (xy 192.824046 -274.376392)
			(xy 192.773264 -274.368349) (xy 192.724365 -274.352461) (xy 192.678553 -274.329118) (xy 192.636957 -274.298897)
			(xy 192.600601 -274.262541) (xy 192.57038 -274.220945) (xy 192.547037 -274.175133) (xy 192.531149 -274.126234)
			(xy 192.523106 -274.075452) (xy 192.204936 -274.075452) (xy 192.19722 -274.122928) (xy 192.181636 -274.169609)
			(xy 192.158765 -274.213186) (xy 192.1292 -274.25253) (xy 192.093707 -274.286622) (xy 192.053204 -274.314578)
			(xy 192.008742 -274.335676) (xy 191.961471 -274.349368) (xy 191.912616 -274.3553) (xy 191.863441 -274.353319)
			(xy 191.815222 -274.343475) (xy 191.769206 -274.326023) (xy 191.726585 -274.301416) (xy 191.688464 -274.270291)
			(xy 191.655829 -274.233454) (xy 191.629526 -274.191858) (xy 191.610235 -274.146582) (xy 191.598458 -274.098798)
			(xy 191.594498 -274.049744) (xy 191.276986 -274.049744) (xy 191.276482 -274.075452) (xy 191.268439 -274.126234)
			(xy 191.252551 -274.175133) (xy 191.229208 -274.220945) (xy 191.198987 -274.262541) (xy 191.162631 -274.298897)
			(xy 191.121035 -274.329118) (xy 191.075223 -274.352461) (xy 191.026324 -274.368349) (xy 190.975542 -274.376392)
			(xy 190.924126 -274.376392) (xy 190.873344 -274.368349) (xy 190.824445 -274.352461) (xy 190.778633 -274.329118)
			(xy 190.737037 -274.298897) (xy 190.700681 -274.262541) (xy 190.67046 -274.220945) (xy 190.647117 -274.175133)
			(xy 190.631229 -274.126234) (xy 190.623186 -274.075452) (xy 190.304508 -274.075452) (xy 190.296792 -274.122928)
			(xy 190.281208 -274.169609) (xy 190.258337 -274.213186) (xy 190.228772 -274.25253) (xy 190.193279 -274.286622)
			(xy 190.152776 -274.314578) (xy 190.108314 -274.335676) (xy 190.061043 -274.349368) (xy 190.012188 -274.3553)
			(xy 189.963013 -274.353319) (xy 189.914794 -274.343475) (xy 189.868778 -274.326023) (xy 189.826157 -274.301416)
			(xy 189.788036 -274.270291) (xy 189.755401 -274.233454) (xy 189.729098 -274.191858) (xy 189.709807 -274.146582)
			(xy 189.69803 -274.098798) (xy 189.69407 -274.049744) (xy 189.376812 -274.049744) (xy 189.376308 -274.075452)
			(xy 189.368265 -274.126234) (xy 189.352377 -274.175133) (xy 189.329034 -274.220945) (xy 189.298813 -274.262541)
			(xy 189.262457 -274.298897) (xy 189.220861 -274.329118) (xy 189.175049 -274.352461) (xy 189.12615 -274.368349)
			(xy 189.075368 -274.376392) (xy 189.023952 -274.376392) (xy 188.97317 -274.368349) (xy 188.924271 -274.352461)
			(xy 188.878459 -274.329118) (xy 188.836863 -274.298897) (xy 188.800507 -274.262541) (xy 188.770286 -274.220945)
			(xy 188.746943 -274.175133) (xy 188.731055 -274.126234) (xy 188.723012 -274.075452) (xy 188.404588 -274.075452)
			(xy 188.396872 -274.122928) (xy 188.381288 -274.169609) (xy 188.358417 -274.213186) (xy 188.328852 -274.25253)
			(xy 188.293359 -274.286622) (xy 188.252856 -274.314578) (xy 188.208394 -274.335676) (xy 188.161123 -274.349368)
			(xy 188.112268 -274.3553) (xy 188.063093 -274.353319) (xy 188.014874 -274.343475) (xy 187.968858 -274.326023)
			(xy 187.926237 -274.301416) (xy 187.888116 -274.270291) (xy 187.855481 -274.233454) (xy 187.829178 -274.191858)
			(xy 187.809887 -274.146582) (xy 187.79811 -274.098798) (xy 187.79415 -274.049744) (xy 187.476892 -274.049744)
			(xy 187.476388 -274.075452) (xy 187.468345 -274.126234) (xy 187.452457 -274.175133) (xy 187.429114 -274.220945)
			(xy 187.398893 -274.262541) (xy 187.362537 -274.298897) (xy 187.320941 -274.329118) (xy 187.275129 -274.352461)
			(xy 187.22623 -274.368349) (xy 187.175448 -274.376392) (xy 187.124032 -274.376392) (xy 187.07325 -274.368349)
			(xy 187.024351 -274.352461) (xy 186.978539 -274.329118) (xy 186.936943 -274.298897) (xy 186.900587 -274.262541)
			(xy 186.870366 -274.220945) (xy 186.847023 -274.175133) (xy 186.831135 -274.126234) (xy 186.823092 -274.075452)
			(xy 186.504668 -274.075452) (xy 186.496952 -274.122928) (xy 186.481368 -274.169609) (xy 186.458497 -274.213186)
			(xy 186.428932 -274.25253) (xy 186.393439 -274.286622) (xy 186.352936 -274.314578) (xy 186.308474 -274.335676)
			(xy 186.261203 -274.349368) (xy 186.212348 -274.3553) (xy 186.163173 -274.353319) (xy 186.114954 -274.343475)
			(xy 186.068938 -274.326023) (xy 186.026317 -274.301416) (xy 185.988196 -274.270291) (xy 185.955561 -274.233454)
			(xy 185.929258 -274.191858) (xy 185.909967 -274.146582) (xy 185.89819 -274.098798) (xy 185.89423 -274.049744)
			(xy 185.576972 -274.049744) (xy 185.576468 -274.075452) (xy 185.568425 -274.126234) (xy 185.552537 -274.175133)
			(xy 185.529194 -274.220945) (xy 185.498973 -274.262541) (xy 185.462617 -274.298897) (xy 185.421021 -274.329118)
			(xy 185.375209 -274.352461) (xy 185.32631 -274.368349) (xy 185.275528 -274.376392) (xy 185.224112 -274.376392)
			(xy 185.17333 -274.368349) (xy 185.124431 -274.352461) (xy 185.078619 -274.329118) (xy 185.037023 -274.298897)
			(xy 185.000667 -274.262541) (xy 184.970446 -274.220945) (xy 184.947103 -274.175133) (xy 184.931215 -274.126234)
			(xy 184.923172 -274.075452) (xy 184.604494 -274.075452) (xy 184.596778 -274.122928) (xy 184.581194 -274.169609)
			(xy 184.558323 -274.213186) (xy 184.528758 -274.25253) (xy 184.493265 -274.286622) (xy 184.452762 -274.314578)
			(xy 184.4083 -274.335676) (xy 184.361029 -274.349368) (xy 184.312174 -274.3553) (xy 184.262999 -274.353319)
			(xy 184.21478 -274.343475) (xy 184.168764 -274.326023) (xy 184.126143 -274.301416) (xy 184.088022 -274.270291)
			(xy 184.055387 -274.233454) (xy 184.029084 -274.191858) (xy 184.009793 -274.146582) (xy 183.998016 -274.098798)
			(xy 183.994056 -274.049744) (xy 183.676798 -274.049744) (xy 183.676294 -274.075452) (xy 183.668251 -274.126234)
			(xy 183.652363 -274.175133) (xy 183.62902 -274.220945) (xy 183.598799 -274.262541) (xy 183.562443 -274.298897)
			(xy 183.520847 -274.329118) (xy 183.475035 -274.352461) (xy 183.426136 -274.368349) (xy 183.375354 -274.376392)
			(xy 183.323938 -274.376392) (xy 183.273156 -274.368349) (xy 183.224257 -274.352461) (xy 183.178445 -274.329118)
			(xy 183.136849 -274.298897) (xy 183.100493 -274.262541) (xy 183.070272 -274.220945) (xy 183.046929 -274.175133)
			(xy 183.031041 -274.126234) (xy 183.022998 -274.075452) (xy 182.704574 -274.075452) (xy 182.696858 -274.122928)
			(xy 182.681274 -274.169609) (xy 182.658403 -274.213186) (xy 182.628838 -274.25253) (xy 182.593345 -274.286622)
			(xy 182.552842 -274.314578) (xy 182.50838 -274.335676) (xy 182.461109 -274.349368) (xy 182.412254 -274.3553)
			(xy 182.363079 -274.353319) (xy 182.31486 -274.343475) (xy 182.268844 -274.326023) (xy 182.226223 -274.301416)
			(xy 182.188102 -274.270291) (xy 182.155467 -274.233454) (xy 182.129164 -274.191858) (xy 182.109873 -274.146582)
			(xy 182.098096 -274.098798) (xy 182.094136 -274.049744) (xy 181.776878 -274.049744) (xy 181.776374 -274.075452)
			(xy 181.768331 -274.126234) (xy 181.752443 -274.175133) (xy 181.7291 -274.220945) (xy 181.698879 -274.262541)
			(xy 181.662523 -274.298897) (xy 181.620927 -274.329118) (xy 181.575115 -274.352461) (xy 181.526216 -274.368349)
			(xy 181.475434 -274.376392) (xy 181.424018 -274.376392) (xy 181.373236 -274.368349) (xy 181.324337 -274.352461)
			(xy 181.278525 -274.329118) (xy 181.236929 -274.298897) (xy 181.200573 -274.262541) (xy 181.170352 -274.220945)
			(xy 181.147009 -274.175133) (xy 181.131121 -274.126234) (xy 181.123078 -274.075452) (xy 180.804654 -274.075452)
			(xy 180.796938 -274.122928) (xy 180.781354 -274.169609) (xy 180.758483 -274.213186) (xy 180.728918 -274.25253)
			(xy 180.693425 -274.286622) (xy 180.652922 -274.314578) (xy 180.60846 -274.335676) (xy 180.561189 -274.349368)
			(xy 180.512334 -274.3553) (xy 180.463159 -274.353319) (xy 180.41494 -274.343475) (xy 180.368924 -274.326023)
			(xy 180.326303 -274.301416) (xy 180.288182 -274.270291) (xy 180.255547 -274.233454) (xy 180.229244 -274.191858)
			(xy 180.209953 -274.146582) (xy 180.198176 -274.098798) (xy 180.194216 -274.049744) (xy 179.876958 -274.049744)
			(xy 179.876454 -274.075452) (xy 179.868411 -274.126234) (xy 179.852523 -274.175133) (xy 179.82918 -274.220945)
			(xy 179.798959 -274.262541) (xy 179.762603 -274.298897) (xy 179.721007 -274.329118) (xy 179.675195 -274.352461)
			(xy 179.626296 -274.368349) (xy 179.575514 -274.376392) (xy 179.524098 -274.376392) (xy 179.473316 -274.368349)
			(xy 179.424417 -274.352461) (xy 179.378605 -274.329118) (xy 179.337009 -274.298897) (xy 179.300653 -274.262541)
			(xy 179.270432 -274.220945) (xy 179.247089 -274.175133) (xy 179.231201 -274.126234) (xy 179.223158 -274.075452)
			(xy 178.90448 -274.075452) (xy 178.896764 -274.122928) (xy 178.88118 -274.169609) (xy 178.858309 -274.213186)
			(xy 178.828744 -274.25253) (xy 178.793251 -274.286622) (xy 178.752748 -274.314578) (xy 178.708286 -274.335676)
			(xy 178.661015 -274.349368) (xy 178.61216 -274.3553) (xy 178.562985 -274.353319) (xy 178.514766 -274.343475)
			(xy 178.46875 -274.326023) (xy 178.426129 -274.301416) (xy 178.388008 -274.270291) (xy 178.355373 -274.233454)
			(xy 178.32907 -274.191858) (xy 178.309779 -274.146582) (xy 178.298002 -274.098798) (xy 178.294042 -274.049744)
			(xy 177.976784 -274.049744) (xy 177.97628 -274.075452) (xy 177.968237 -274.126234) (xy 177.952349 -274.175133)
			(xy 177.929006 -274.220945) (xy 177.898785 -274.262541) (xy 177.862429 -274.298897) (xy 177.820833 -274.329118)
			(xy 177.775021 -274.352461) (xy 177.726122 -274.368349) (xy 177.67534 -274.376392) (xy 177.623924 -274.376392)
			(xy 177.573142 -274.368349) (xy 177.524243 -274.352461) (xy 177.478431 -274.329118) (xy 177.436835 -274.298897)
			(xy 177.400479 -274.262541) (xy 177.370258 -274.220945) (xy 177.346915 -274.175133) (xy 177.331027 -274.126234)
			(xy 177.322984 -274.075452) (xy 177.00456 -274.075452) (xy 176.996844 -274.122928) (xy 176.98126 -274.169609)
			(xy 176.958389 -274.213186) (xy 176.928824 -274.25253) (xy 176.893331 -274.286622) (xy 176.852828 -274.314578)
			(xy 176.808366 -274.335676) (xy 176.761095 -274.349368) (xy 176.71224 -274.3553) (xy 176.663065 -274.353319)
			(xy 176.614846 -274.343475) (xy 176.56883 -274.326023) (xy 176.526209 -274.301416) (xy 176.488088 -274.270291)
			(xy 176.455453 -274.233454) (xy 176.42915 -274.191858) (xy 176.409859 -274.146582) (xy 176.398082 -274.098798)
			(xy 176.394122 -274.049744) (xy 176.076859 -274.049744) (xy 176.07636 -274.075198) (xy 176.068317 -274.12598)
			(xy 176.052429 -274.174879) (xy 176.029086 -274.220691) (xy 175.998865 -274.262287) (xy 175.962509 -274.298643)
			(xy 175.920913 -274.328864) (xy 175.875101 -274.352207) (xy 175.826202 -274.368095) (xy 175.77542 -274.376138)
			(xy 175.724004 -274.376138) (xy 175.673222 -274.368095) (xy 175.624323 -274.352207) (xy 175.578511 -274.328864)
			(xy 175.536915 -274.298643) (xy 175.500559 -274.262287) (xy 175.470338 -274.220691) (xy 175.446995 -274.174879)
			(xy 175.431107 -274.12598) (xy 175.423064 -274.075198) (xy 175.104681 -274.075198) (xy 175.096924 -274.122928)
			(xy 175.08134 -274.169609) (xy 175.058469 -274.213186) (xy 175.028904 -274.25253) (xy 174.993411 -274.286622)
			(xy 174.952908 -274.314578) (xy 174.908446 -274.335676) (xy 174.861175 -274.349368) (xy 174.81232 -274.3553)
			(xy 174.763145 -274.353319) (xy 174.714926 -274.343475) (xy 174.66891 -274.326023) (xy 174.626289 -274.301416)
			(xy 174.588168 -274.270291) (xy 174.555533 -274.233454) (xy 174.52923 -274.191858) (xy 174.509939 -274.146582)
			(xy 174.498162 -274.098798) (xy 174.494202 -274.049744) (xy 174.177198 -274.049744) (xy 174.176694 -274.075452)
			(xy 174.168651 -274.126234) (xy 174.152763 -274.175133) (xy 174.12942 -274.220945) (xy 174.099199 -274.262541)
			(xy 174.062843 -274.298897) (xy 174.021247 -274.329118) (xy 173.975435 -274.352461) (xy 173.926536 -274.368349)
			(xy 173.875754 -274.376392) (xy 173.824338 -274.376392) (xy 173.773556 -274.368349) (xy 173.724657 -274.352461)
			(xy 173.678845 -274.329118) (xy 173.637249 -274.298897) (xy 173.600893 -274.262541) (xy 173.570672 -274.220945)
			(xy 173.547329 -274.175133) (xy 173.531441 -274.126234) (xy 173.523398 -274.075452) (xy 173.20472 -274.075452)
			(xy 173.197004 -274.122928) (xy 173.18142 -274.169609) (xy 173.158549 -274.213186) (xy 173.128984 -274.25253)
			(xy 173.093491 -274.286622) (xy 173.052988 -274.314578) (xy 173.008526 -274.335676) (xy 172.961255 -274.349368)
			(xy 172.9124 -274.3553) (xy 172.863225 -274.353319) (xy 172.815006 -274.343475) (xy 172.76899 -274.326023)
			(xy 172.726369 -274.301416) (xy 172.688248 -274.270291) (xy 172.655613 -274.233454) (xy 172.62931 -274.191858)
			(xy 172.610019 -274.146582) (xy 172.598242 -274.098798) (xy 172.594282 -274.049744) (xy 172.277024 -274.049744)
			(xy 172.27652 -274.075452) (xy 172.268477 -274.126234) (xy 172.252589 -274.175133) (xy 172.229246 -274.220945)
			(xy 172.199025 -274.262541) (xy 172.162669 -274.298897) (xy 172.121073 -274.329118) (xy 172.075261 -274.352461)
			(xy 172.026362 -274.368349) (xy 171.97558 -274.376392) (xy 171.924164 -274.376392) (xy 171.873382 -274.368349)
			(xy 171.824483 -274.352461) (xy 171.778671 -274.329118) (xy 171.737075 -274.298897) (xy 171.700719 -274.262541)
			(xy 171.670498 -274.220945) (xy 171.647155 -274.175133) (xy 171.631267 -274.126234) (xy 171.623224 -274.075452)
			(xy 171.304546 -274.075452) (xy 171.29683 -274.122928) (xy 171.281246 -274.169609) (xy 171.258375 -274.213186)
			(xy 171.22881 -274.25253) (xy 171.193317 -274.286622) (xy 171.152814 -274.314578) (xy 171.108352 -274.335676)
			(xy 171.061081 -274.349368) (xy 171.012226 -274.3553) (xy 170.963051 -274.353319) (xy 170.914832 -274.343475)
			(xy 170.868816 -274.326023) (xy 170.826195 -274.301416) (xy 170.788074 -274.270291) (xy 170.755439 -274.233454)
			(xy 170.729136 -274.191858) (xy 170.709845 -274.146582) (xy 170.698068 -274.098798) (xy 170.694108 -274.049744)
			(xy 170.377104 -274.049744) (xy 170.3766 -274.075452) (xy 170.368557 -274.126234) (xy 170.352669 -274.175133)
			(xy 170.329326 -274.220945) (xy 170.299105 -274.262541) (xy 170.262749 -274.298897) (xy 170.221153 -274.329118)
			(xy 170.175341 -274.352461) (xy 170.126442 -274.368349) (xy 170.07566 -274.376392) (xy 170.024244 -274.376392)
			(xy 169.973462 -274.368349) (xy 169.924563 -274.352461) (xy 169.878751 -274.329118) (xy 169.837155 -274.298897)
			(xy 169.800799 -274.262541) (xy 169.770578 -274.220945) (xy 169.747235 -274.175133) (xy 169.731347 -274.126234)
			(xy 169.723304 -274.075452) (xy 169.404626 -274.075452) (xy 169.39691 -274.122928) (xy 169.381326 -274.169609)
			(xy 169.358455 -274.213186) (xy 169.32889 -274.25253) (xy 169.293397 -274.286622) (xy 169.252894 -274.314578)
			(xy 169.208432 -274.335676) (xy 169.161161 -274.349368) (xy 169.112306 -274.3553) (xy 169.063131 -274.353319)
			(xy 169.014912 -274.343475) (xy 168.968896 -274.326023) (xy 168.926275 -274.301416) (xy 168.888154 -274.270291)
			(xy 168.855519 -274.233454) (xy 168.829216 -274.191858) (xy 168.809925 -274.146582) (xy 168.798148 -274.098798)
			(xy 168.794188 -274.049744) (xy 168.477184 -274.049744) (xy 168.47668 -274.075452) (xy 168.468637 -274.126234)
			(xy 168.452749 -274.175133) (xy 168.429406 -274.220945) (xy 168.399185 -274.262541) (xy 168.362829 -274.298897)
			(xy 168.321233 -274.329118) (xy 168.275421 -274.352461) (xy 168.226522 -274.368349) (xy 168.17574 -274.376392)
			(xy 168.124324 -274.376392) (xy 168.073542 -274.368349) (xy 168.024643 -274.352461) (xy 167.978831 -274.329118)
			(xy 167.937235 -274.298897) (xy 167.900879 -274.262541) (xy 167.870658 -274.220945) (xy 167.847315 -274.175133)
			(xy 167.831427 -274.126234) (xy 167.823384 -274.075452) (xy 167.504706 -274.075452) (xy 167.49699 -274.122928)
			(xy 167.481406 -274.169609) (xy 167.458535 -274.213186) (xy 167.42897 -274.25253) (xy 167.393477 -274.286622)
			(xy 167.352974 -274.314578) (xy 167.308512 -274.335676) (xy 167.261241 -274.349368) (xy 167.212386 -274.3553)
			(xy 167.163211 -274.353319) (xy 167.114992 -274.343475) (xy 167.068976 -274.326023) (xy 167.026355 -274.301416)
			(xy 166.988234 -274.270291) (xy 166.955599 -274.233454) (xy 166.929296 -274.191858) (xy 166.910005 -274.146582)
			(xy 166.898228 -274.098798) (xy 166.894268 -274.049744) (xy 166.57701 -274.049744) (xy 166.576506 -274.075452)
			(xy 166.568463 -274.126234) (xy 166.552575 -274.175133) (xy 166.529232 -274.220945) (xy 166.499011 -274.262541)
			(xy 166.462655 -274.298897) (xy 166.421059 -274.329118) (xy 166.375247 -274.352461) (xy 166.326348 -274.368349)
			(xy 166.275566 -274.376392) (xy 166.22415 -274.376392) (xy 166.173368 -274.368349) (xy 166.124469 -274.352461)
			(xy 166.078657 -274.329118) (xy 166.037061 -274.298897) (xy 166.000705 -274.262541) (xy 165.970484 -274.220945)
			(xy 165.947141 -274.175133) (xy 165.931253 -274.126234) (xy 165.92321 -274.075452) (xy 165.604532 -274.075452)
			(xy 165.596816 -274.122928) (xy 165.581232 -274.169609) (xy 165.558361 -274.213186) (xy 165.528796 -274.25253)
			(xy 165.493303 -274.286622) (xy 165.4528 -274.314578) (xy 165.408338 -274.335676) (xy 165.361067 -274.349368)
			(xy 165.312212 -274.3553) (xy 165.263037 -274.353319) (xy 165.214818 -274.343475) (xy 165.168802 -274.326023)
			(xy 165.126181 -274.301416) (xy 165.08806 -274.270291) (xy 165.055425 -274.233454) (xy 165.029122 -274.191858)
			(xy 165.009831 -274.146582) (xy 164.998054 -274.098798) (xy 164.994094 -274.049744) (xy 164.67709 -274.049744)
			(xy 164.676586 -274.075452) (xy 164.668543 -274.126234) (xy 164.652655 -274.175133) (xy 164.629312 -274.220945)
			(xy 164.599091 -274.262541) (xy 164.562735 -274.298897) (xy 164.521139 -274.329118) (xy 164.475327 -274.352461)
			(xy 164.426428 -274.368349) (xy 164.375646 -274.376392) (xy 164.32423 -274.376392) (xy 164.273448 -274.368349)
			(xy 164.224549 -274.352461) (xy 164.178737 -274.329118) (xy 164.137141 -274.298897) (xy 164.100785 -274.262541)
			(xy 164.070564 -274.220945) (xy 164.047221 -274.175133) (xy 164.031333 -274.126234) (xy 164.02329 -274.075452)
			(xy 163.704612 -274.075452) (xy 163.696896 -274.122928) (xy 163.681312 -274.169609) (xy 163.658441 -274.213186)
			(xy 163.628876 -274.25253) (xy 163.593383 -274.286622) (xy 163.55288 -274.314578) (xy 163.508418 -274.335676)
			(xy 163.461147 -274.349368) (xy 163.412292 -274.3553) (xy 163.363117 -274.353319) (xy 163.314898 -274.343475)
			(xy 163.268882 -274.326023) (xy 163.226261 -274.301416) (xy 163.18814 -274.270291) (xy 163.155505 -274.233454)
			(xy 163.129202 -274.191858) (xy 163.109911 -274.146582) (xy 163.098134 -274.098798) (xy 163.094174 -274.049744)
			(xy 162.77717 -274.049744) (xy 162.776666 -274.075452) (xy 162.768623 -274.126234) (xy 162.752735 -274.175133)
			(xy 162.729392 -274.220945) (xy 162.699171 -274.262541) (xy 162.662815 -274.298897) (xy 162.621219 -274.329118)
			(xy 162.575407 -274.352461) (xy 162.526508 -274.368349) (xy 162.475726 -274.376392) (xy 162.42431 -274.376392)
			(xy 162.373528 -274.368349) (xy 162.324629 -274.352461) (xy 162.278817 -274.329118) (xy 162.237221 -274.298897)
			(xy 162.200865 -274.262541) (xy 162.170644 -274.220945) (xy 162.147301 -274.175133) (xy 162.131413 -274.126234)
			(xy 162.12337 -274.075452) (xy 161.804692 -274.075452) (xy 161.796976 -274.122928) (xy 161.781392 -274.169609)
			(xy 161.758521 -274.213186) (xy 161.728956 -274.25253) (xy 161.693463 -274.286622) (xy 161.65296 -274.314578)
			(xy 161.608498 -274.335676) (xy 161.561227 -274.349368) (xy 161.512372 -274.3553) (xy 161.463197 -274.353319)
			(xy 161.414978 -274.343475) (xy 161.368962 -274.326023) (xy 161.326341 -274.301416) (xy 161.28822 -274.270291)
			(xy 161.255585 -274.233454) (xy 161.229282 -274.191858) (xy 161.209991 -274.146582) (xy 161.198214 -274.098798)
			(xy 161.194254 -274.049744) (xy 160.876996 -274.049744) (xy 160.876492 -274.075452) (xy 160.868449 -274.126234)
			(xy 160.852561 -274.175133) (xy 160.829218 -274.220945) (xy 160.798997 -274.262541) (xy 160.762641 -274.298897)
			(xy 160.721045 -274.329118) (xy 160.675233 -274.352461) (xy 160.626334 -274.368349) (xy 160.575552 -274.376392)
			(xy 160.524136 -274.376392) (xy 160.473354 -274.368349) (xy 160.424455 -274.352461) (xy 160.378643 -274.329118)
			(xy 160.337047 -274.298897) (xy 160.300691 -274.262541) (xy 160.27047 -274.220945) (xy 160.247127 -274.175133)
			(xy 160.231239 -274.126234) (xy 160.223196 -274.075452) (xy 159.90367 -274.075452) (xy 159.901632 -274.100052)
			(xy 159.889228 -274.14903) (xy 159.868932 -274.195299) (xy 159.841297 -274.237595) (xy 159.807077 -274.274767)
			(xy 159.767205 -274.305798) (xy 159.722769 -274.329843) (xy 159.674982 -274.346247) (xy 159.625146 -274.35456)
			(xy 159.599884 -274.355052) (xy 159.585701 -274.354877) (xy 159.557461 -274.352204) (xy 159.543496 -274.349718)
			(xy 159.53105 -274.347432) (xy 159.507174 -274.354798) (xy 159.429958 -274.432014) (xy 159.422592 -274.456144)
			(xy 159.424878 -274.468336) (xy 159.427366 -274.482364) (xy 159.430036 -274.510732) (xy 159.430212 -274.524978)
			(xy 159.429746 -274.549801) (xy 159.421717 -274.598794) (xy 159.405868 -274.645842) (xy 159.382616 -274.689707)
			(xy 159.352574 -274.729231) (xy 159.316533 -274.763375) (xy 159.275443 -274.791238) (xy 159.230387 -274.812086)
			(xy 159.182551 -274.825371) (xy 159.133196 -274.83074) (xy 159.083622 -274.828055) (xy 159.035136 -274.817384)
			(xy 158.989016 -274.79901) (xy 158.946475 -274.773416) (xy 158.908636 -274.741277) (xy 158.876494 -274.70344)
			(xy 158.850898 -274.660901) (xy 158.832521 -274.614781) (xy 158.821848 -274.566296) (xy 158.819159 -274.516722)
			(xy 158.824526 -274.467367) (xy 158.837807 -274.41953) (xy 158.858653 -274.374472) (xy 158.886513 -274.333381)
			(xy 158.920655 -274.297338) (xy 158.960178 -274.267293) (xy 159.004041 -274.244039) (xy 159.051089 -274.228187)
			(xy 159.100081 -274.220156) (xy 159.124904 -274.21967) (xy 159.139087 -274.219846) (xy 159.167327 -274.222519)
			(xy 159.181292 -274.225004) (xy 159.193738 -274.22729) (xy 159.217614 -274.219924) (xy 159.29483 -274.142708)
			(xy 159.302196 -274.118578) (xy 159.29991 -274.106386) (xy 159.297425 -274.092357) (xy 159.294753 -274.06399)
			(xy 159.294576 -274.049744) (xy 159.294759 -274.035561) (xy 159.297427 -274.007321) (xy 159.29991 -273.993356)
			(xy 159.302196 -273.98091) (xy 159.29483 -273.957288) (xy 159.21736 -273.879818) (xy 159.193738 -273.872452)
			(xy 159.181292 -273.874738) (xy 159.167326 -273.877211) (xy 159.139086 -273.879885) (xy 159.124904 -273.880072)
			(xy 159.099643 -273.879652) (xy 159.04981 -273.871336) (xy 159.002026 -273.854933) (xy 158.957593 -273.830887)
			(xy 158.917724 -273.799856) (xy 158.883506 -273.762687) (xy 158.855873 -273.720392) (xy 158.835579 -273.674125)
			(xy 158.823176 -273.625149) (xy 158.819004 -273.5748) (xy 158.480251 -273.5748) (xy 158.479757 -273.599371)
			(xy 158.471862 -273.647948) (xy 158.456278 -273.694629) (xy 158.433407 -273.738206) (xy 158.403842 -273.77755)
			(xy 158.368349 -273.811642) (xy 158.327846 -273.839598) (xy 158.283384 -273.860696) (xy 158.236113 -273.874388)
			(xy 158.187258 -273.88032) (xy 158.138083 -273.878339) (xy 158.089864 -273.868495) (xy 158.043848 -273.851043)
			(xy 158.001227 -273.826436) (xy 157.963106 -273.795311) (xy 157.930471 -273.758474) (xy 157.904168 -273.716878)
			(xy 157.884877 -273.671602) (xy 157.8731 -273.623818) (xy 157.86914 -273.574764) (xy 157.530292 -273.574764)
			(xy 157.529797 -273.599371) (xy 157.521902 -273.647948) (xy 157.506318 -273.694629) (xy 157.483447 -273.738206)
			(xy 157.453882 -273.77755) (xy 157.418389 -273.811642) (xy 157.377886 -273.839598) (xy 157.333424 -273.860696)
			(xy 157.286153 -273.874388) (xy 157.237298 -273.88032) (xy 157.188123 -273.878339) (xy 157.139904 -273.868495)
			(xy 157.093888 -273.851043) (xy 157.051267 -273.826436) (xy 157.013146 -273.795311) (xy 156.980511 -273.758474)
			(xy 156.954208 -273.716878) (xy 156.934917 -273.671602) (xy 156.92314 -273.623818) (xy 156.91918 -273.574764)
			(xy 156.580332 -273.574764) (xy 156.579837 -273.599371) (xy 156.571942 -273.647948) (xy 156.556358 -273.694629)
			(xy 156.533487 -273.738206) (xy 156.503922 -273.77755) (xy 156.468429 -273.811642) (xy 156.427926 -273.839598)
			(xy 156.383464 -273.860696) (xy 156.336193 -273.874388) (xy 156.287338 -273.88032) (xy 156.238163 -273.878339)
			(xy 156.189944 -273.868495) (xy 156.143928 -273.851043) (xy 156.101307 -273.826436) (xy 156.063186 -273.795311)
			(xy 156.030551 -273.758474) (xy 156.004248 -273.716878) (xy 155.984957 -273.671602) (xy 155.97318 -273.623818)
			(xy 155.96922 -273.574764) (xy 155.630372 -273.574764) (xy 155.629877 -273.599371) (xy 155.621982 -273.647948)
			(xy 155.606398 -273.694629) (xy 155.583527 -273.738206) (xy 155.553962 -273.77755) (xy 155.518469 -273.811642)
			(xy 155.477966 -273.839598) (xy 155.433504 -273.860696) (xy 155.386233 -273.874388) (xy 155.337378 -273.88032)
			(xy 155.288203 -273.878339) (xy 155.239984 -273.868495) (xy 155.193968 -273.851043) (xy 155.151347 -273.826436)
			(xy 155.113226 -273.795311) (xy 155.080591 -273.758474) (xy 155.054288 -273.716878) (xy 155.034997 -273.671602)
			(xy 155.02322 -273.623818) (xy 155.01926 -273.574764) (xy 154.680158 -273.574764) (xy 154.679663 -273.599371)
			(xy 154.671768 -273.647948) (xy 154.656184 -273.694629) (xy 154.633313 -273.738206) (xy 154.603748 -273.77755)
			(xy 154.568255 -273.811642) (xy 154.527752 -273.839598) (xy 154.48329 -273.860696) (xy 154.436019 -273.874388)
			(xy 154.387164 -273.88032) (xy 154.337989 -273.878339) (xy 154.28977 -273.868495) (xy 154.243754 -273.851043)
			(xy 154.201133 -273.826436) (xy 154.163012 -273.795311) (xy 154.130377 -273.758474) (xy 154.104074 -273.716878)
			(xy 154.084783 -273.671602) (xy 154.073006 -273.623818) (xy 154.069046 -273.574764) (xy 153.730198 -273.574764)
			(xy 153.729703 -273.599371) (xy 153.721808 -273.647948) (xy 153.706224 -273.694629) (xy 153.683353 -273.738206)
			(xy 153.653788 -273.77755) (xy 153.618295 -273.811642) (xy 153.577792 -273.839598) (xy 153.53333 -273.860696)
			(xy 153.486059 -273.874388) (xy 153.437204 -273.88032) (xy 153.388029 -273.878339) (xy 153.33981 -273.868495)
			(xy 153.293794 -273.851043) (xy 153.251173 -273.826436) (xy 153.213052 -273.795311) (xy 153.180417 -273.758474)
			(xy 153.154114 -273.716878) (xy 153.134823 -273.671602) (xy 153.123046 -273.623818) (xy 153.119086 -273.574764)
			(xy 149.676017 -273.574764) (xy 149.570397 -273.72397) (xy 149.451233 -273.878444) (xy 149.325828 -274.027897)
			(xy 149.194392 -274.172075) (xy 149.057148 -274.310735) (xy 148.914327 -274.443643) (xy 148.819689 -274.524724)
			(xy 153.119086 -274.524724) (xy 153.123046 -274.47567) (xy 153.134823 -274.427886) (xy 153.154114 -274.38261)
			(xy 153.180417 -274.341014) (xy 153.213052 -274.304177) (xy 153.251173 -274.273052) (xy 153.293794 -274.248445)
			(xy 153.33981 -274.230993) (xy 153.388029 -274.221149) (xy 153.437204 -274.219168) (xy 153.486059 -274.2251)
			(xy 153.53333 -274.238792) (xy 153.577792 -274.25989) (xy 153.618295 -274.287846) (xy 153.653788 -274.321938)
			(xy 153.683353 -274.361282) (xy 153.706224 -274.404859) (xy 153.721808 -274.45154) (xy 153.729703 -274.500117)
			(xy 153.730198 -274.524724) (xy 153.730193 -274.524978) (xy 154.0693 -274.524978) (xy 154.07326 -274.475924)
			(xy 154.085037 -274.42814) (xy 154.104328 -274.382864) (xy 154.130631 -274.341268) (xy 154.163266 -274.304431)
			(xy 154.201387 -274.273306) (xy 154.244008 -274.248699) (xy 154.290024 -274.231247) (xy 154.338243 -274.221403)
			(xy 154.387418 -274.219422) (xy 154.436273 -274.225354) (xy 154.483544 -274.239046) (xy 154.528006 -274.260144)
			(xy 154.568509 -274.2881) (xy 154.604002 -274.322192) (xy 154.633567 -274.361536) (xy 154.656438 -274.405113)
			(xy 154.672022 -274.451794) (xy 154.679917 -274.500371) (xy 154.680412 -274.524978) (xy 155.01926 -274.524978)
			(xy 155.02322 -274.475924) (xy 155.034997 -274.42814) (xy 155.054288 -274.382864) (xy 155.080591 -274.341268)
			(xy 155.113226 -274.304431) (xy 155.151347 -274.273306) (xy 155.193968 -274.248699) (xy 155.239984 -274.231247)
			(xy 155.288203 -274.221403) (xy 155.337378 -274.219422) (xy 155.386233 -274.225354) (xy 155.433504 -274.239046)
			(xy 155.477966 -274.260144) (xy 155.518469 -274.2881) (xy 155.553962 -274.322192) (xy 155.583527 -274.361536)
			(xy 155.606398 -274.405113) (xy 155.621982 -274.451794) (xy 155.629877 -274.500371) (xy 155.630372 -274.524978)
			(xy 155.96922 -274.524978) (xy 155.97318 -274.475924) (xy 155.984957 -274.42814) (xy 156.004248 -274.382864)
			(xy 156.030551 -274.341268) (xy 156.063186 -274.304431) (xy 156.101307 -274.273306) (xy 156.143928 -274.248699)
			(xy 156.189944 -274.231247) (xy 156.238163 -274.221403) (xy 156.287338 -274.219422) (xy 156.336193 -274.225354)
			(xy 156.383464 -274.239046) (xy 156.427926 -274.260144) (xy 156.468429 -274.2881) (xy 156.503922 -274.322192)
			(xy 156.533487 -274.361536) (xy 156.556358 -274.405113) (xy 156.571942 -274.451794) (xy 156.579837 -274.500371)
			(xy 156.580332 -274.524978) (xy 156.91918 -274.524978) (xy 156.92314 -274.475924) (xy 156.934917 -274.42814)
			(xy 156.954208 -274.382864) (xy 156.980511 -274.341268) (xy 157.013146 -274.304431) (xy 157.051267 -274.273306)
			(xy 157.093888 -274.248699) (xy 157.139904 -274.231247) (xy 157.188123 -274.221403) (xy 157.237298 -274.219422)
			(xy 157.286153 -274.225354) (xy 157.333424 -274.239046) (xy 157.377886 -274.260144) (xy 157.418389 -274.2881)
			(xy 157.453882 -274.322192) (xy 157.483447 -274.361536) (xy 157.506318 -274.405113) (xy 157.521902 -274.451794)
			(xy 157.529797 -274.500371) (xy 157.530292 -274.524978) (xy 157.86914 -274.524978) (xy 157.8731 -274.475924)
			(xy 157.884877 -274.42814) (xy 157.904168 -274.382864) (xy 157.930471 -274.341268) (xy 157.963106 -274.304431)
			(xy 158.001227 -274.273306) (xy 158.043848 -274.248699) (xy 158.089864 -274.231247) (xy 158.138083 -274.221403)
			(xy 158.187258 -274.219422) (xy 158.236113 -274.225354) (xy 158.283384 -274.239046) (xy 158.327846 -274.260144)
			(xy 158.368349 -274.2881) (xy 158.403842 -274.322192) (xy 158.433407 -274.361536) (xy 158.456278 -274.405113)
			(xy 158.471862 -274.451794) (xy 158.479757 -274.500371) (xy 158.480252 -274.524978) (xy 158.479757 -274.549585)
			(xy 158.471862 -274.598162) (xy 158.456278 -274.644843) (xy 158.433407 -274.68842) (xy 158.403842 -274.727764)
			(xy 158.368349 -274.761856) (xy 158.327846 -274.789812) (xy 158.283384 -274.81091) (xy 158.236113 -274.824602)
			(xy 158.187258 -274.830534) (xy 158.138083 -274.828553) (xy 158.089864 -274.818709) (xy 158.043848 -274.801257)
			(xy 158.001227 -274.77665) (xy 157.963106 -274.745525) (xy 157.930471 -274.708688) (xy 157.904168 -274.667092)
			(xy 157.884877 -274.621816) (xy 157.8731 -274.574032) (xy 157.86914 -274.524978) (xy 157.530292 -274.524978)
			(xy 157.529797 -274.549585) (xy 157.521902 -274.598162) (xy 157.506318 -274.644843) (xy 157.483447 -274.68842)
			(xy 157.453882 -274.727764) (xy 157.418389 -274.761856) (xy 157.377886 -274.789812) (xy 157.333424 -274.81091)
			(xy 157.286153 -274.824602) (xy 157.237298 -274.830534) (xy 157.188123 -274.828553) (xy 157.139904 -274.818709)
			(xy 157.093888 -274.801257) (xy 157.051267 -274.77665) (xy 157.013146 -274.745525) (xy 156.980511 -274.708688)
			(xy 156.954208 -274.667092) (xy 156.934917 -274.621816) (xy 156.92314 -274.574032) (xy 156.91918 -274.524978)
			(xy 156.580332 -274.524978) (xy 156.579837 -274.549585) (xy 156.571942 -274.598162) (xy 156.556358 -274.644843)
			(xy 156.533487 -274.68842) (xy 156.503922 -274.727764) (xy 156.468429 -274.761856) (xy 156.427926 -274.789812)
			(xy 156.383464 -274.81091) (xy 156.336193 -274.824602) (xy 156.287338 -274.830534) (xy 156.238163 -274.828553)
			(xy 156.189944 -274.818709) (xy 156.143928 -274.801257) (xy 156.101307 -274.77665) (xy 156.063186 -274.745525)
			(xy 156.030551 -274.708688) (xy 156.004248 -274.667092) (xy 155.984957 -274.621816) (xy 155.97318 -274.574032)
			(xy 155.96922 -274.524978) (xy 155.630372 -274.524978) (xy 155.629877 -274.549585) (xy 155.621982 -274.598162)
			(xy 155.606398 -274.644843) (xy 155.583527 -274.68842) (xy 155.553962 -274.727764) (xy 155.518469 -274.761856)
			(xy 155.477966 -274.789812) (xy 155.433504 -274.81091) (xy 155.386233 -274.824602) (xy 155.337378 -274.830534)
			(xy 155.288203 -274.828553) (xy 155.239984 -274.818709) (xy 155.193968 -274.801257) (xy 155.151347 -274.77665)
			(xy 155.113226 -274.745525) (xy 155.080591 -274.708688) (xy 155.054288 -274.667092) (xy 155.034997 -274.621816)
			(xy 155.02322 -274.574032) (xy 155.01926 -274.524978) (xy 154.680412 -274.524978) (xy 154.679917 -274.549585)
			(xy 154.672022 -274.598162) (xy 154.656438 -274.644843) (xy 154.633567 -274.68842) (xy 154.604002 -274.727764)
			(xy 154.568509 -274.761856) (xy 154.528006 -274.789812) (xy 154.483544 -274.81091) (xy 154.436273 -274.824602)
			(xy 154.387418 -274.830534) (xy 154.338243 -274.828553) (xy 154.290024 -274.818709) (xy 154.244008 -274.801257)
			(xy 154.201387 -274.77665) (xy 154.163266 -274.745525) (xy 154.130631 -274.708688) (xy 154.104328 -274.667092)
			(xy 154.085037 -274.621816) (xy 154.07326 -274.574032) (xy 154.0693 -274.524978) (xy 153.730193 -274.524978)
			(xy 153.729703 -274.549331) (xy 153.721808 -274.597908) (xy 153.706224 -274.644589) (xy 153.683353 -274.688166)
			(xy 153.653788 -274.72751) (xy 153.618295 -274.761602) (xy 153.577792 -274.789558) (xy 153.53333 -274.810656)
			(xy 153.486059 -274.824348) (xy 153.437204 -274.83028) (xy 153.388029 -274.828299) (xy 153.33981 -274.818455)
			(xy 153.293794 -274.801003) (xy 153.251173 -274.776396) (xy 153.213052 -274.745271) (xy 153.180417 -274.708434)
			(xy 153.154114 -274.666838) (xy 153.134823 -274.621562) (xy 153.123046 -274.573778) (xy 153.119086 -274.524724)
			(xy 148.819689 -274.524724) (xy 148.76617 -274.570577) (xy 148.612927 -274.69132) (xy 148.454856 -274.80567)
			(xy 148.292223 -274.913435) (xy 148.149224 -274.999958) (xy 160.24404 -274.999958) (xy 160.248 -274.950904)
			(xy 160.259777 -274.90312) (xy 160.279068 -274.857844) (xy 160.305371 -274.816248) (xy 160.338006 -274.779411)
			(xy 160.376127 -274.748286) (xy 160.418748 -274.723679) (xy 160.464764 -274.706227) (xy 160.512983 -274.696383)
			(xy 160.562158 -274.694402) (xy 160.611013 -274.700334) (xy 160.658284 -274.714026) (xy 160.702746 -274.735124)
			(xy 160.743249 -274.76308) (xy 160.778742 -274.797172) (xy 160.808307 -274.836516) (xy 160.831178 -274.880093)
			(xy 160.846762 -274.926774) (xy 160.854657 -274.975351) (xy 160.855152 -274.999958) (xy 160.854657 -275.024565)
			(xy 160.854478 -275.025666) (xy 161.17341 -275.025666) (xy 161.17341 -274.97425) (xy 161.181453 -274.923468)
			(xy 161.197341 -274.874569) (xy 161.220684 -274.828757) (xy 161.250905 -274.787161) (xy 161.287261 -274.750805)
			(xy 161.328857 -274.720584) (xy 161.374669 -274.697241) (xy 161.423568 -274.681353) (xy 161.47435 -274.67331)
			(xy 161.525766 -274.67331) (xy 161.576548 -274.681353) (xy 161.625447 -274.697241) (xy 161.671259 -274.720584)
			(xy 161.712855 -274.750805) (xy 161.749211 -274.787161) (xy 161.779432 -274.828757) (xy 161.802775 -274.874569)
			(xy 161.818663 -274.923468) (xy 161.826706 -274.97425) (xy 161.82721 -274.999958) (xy 162.144214 -274.999958)
			(xy 162.148174 -274.950904) (xy 162.159951 -274.90312) (xy 162.179242 -274.857844) (xy 162.205545 -274.816248)
			(xy 162.23818 -274.779411) (xy 162.276301 -274.748286) (xy 162.318922 -274.723679) (xy 162.364938 -274.706227)
			(xy 162.413157 -274.696383) (xy 162.462332 -274.694402) (xy 162.511187 -274.700334) (xy 162.558458 -274.714026)
			(xy 162.60292 -274.735124) (xy 162.643423 -274.76308) (xy 162.678916 -274.797172) (xy 162.708481 -274.836516)
			(xy 162.731352 -274.880093) (xy 162.746936 -274.926774) (xy 162.754831 -274.975351) (xy 162.755326 -274.999958)
			(xy 162.754831 -275.024565) (xy 162.754652 -275.025666) (xy 163.07333 -275.025666) (xy 163.07333 -274.97425)
			(xy 163.081373 -274.923468) (xy 163.097261 -274.874569) (xy 163.120604 -274.828757) (xy 163.150825 -274.787161)
			(xy 163.187181 -274.750805) (xy 163.228777 -274.720584) (xy 163.274589 -274.697241) (xy 163.323488 -274.681353)
			(xy 163.37427 -274.67331) (xy 163.425686 -274.67331) (xy 163.476468 -274.681353) (xy 163.525367 -274.697241)
			(xy 163.571179 -274.720584) (xy 163.612775 -274.750805) (xy 163.649131 -274.787161) (xy 163.679352 -274.828757)
			(xy 163.702695 -274.874569) (xy 163.718583 -274.923468) (xy 163.726626 -274.97425) (xy 163.72713 -274.999958)
			(xy 164.044134 -274.999958) (xy 164.048094 -274.950904) (xy 164.059871 -274.90312) (xy 164.079162 -274.857844)
			(xy 164.105465 -274.816248) (xy 164.1381 -274.779411) (xy 164.176221 -274.748286) (xy 164.218842 -274.723679)
			(xy 164.264858 -274.706227) (xy 164.313077 -274.696383) (xy 164.362252 -274.694402) (xy 164.411107 -274.700334)
			(xy 164.458378 -274.714026) (xy 164.50284 -274.735124) (xy 164.543343 -274.76308) (xy 164.578836 -274.797172)
			(xy 164.608401 -274.836516) (xy 164.631272 -274.880093) (xy 164.646856 -274.926774) (xy 164.654751 -274.975351)
			(xy 164.655246 -274.999958) (xy 164.654751 -275.024565) (xy 164.654572 -275.025666) (xy 164.97325 -275.025666)
			(xy 164.97325 -274.97425) (xy 164.981293 -274.923468) (xy 164.997181 -274.874569) (xy 165.020524 -274.828757)
			(xy 165.050745 -274.787161) (xy 165.087101 -274.750805) (xy 165.128697 -274.720584) (xy 165.174509 -274.697241)
			(xy 165.223408 -274.681353) (xy 165.27419 -274.67331) (xy 165.325606 -274.67331) (xy 165.376388 -274.681353)
			(xy 165.425287 -274.697241) (xy 165.471099 -274.720584) (xy 165.512695 -274.750805) (xy 165.549051 -274.787161)
			(xy 165.579272 -274.828757) (xy 165.602615 -274.874569) (xy 165.618503 -274.923468) (xy 165.626546 -274.97425)
			(xy 165.62705 -274.999958) (xy 165.944054 -274.999958) (xy 165.948014 -274.950904) (xy 165.959791 -274.90312)
			(xy 165.979082 -274.857844) (xy 166.005385 -274.816248) (xy 166.03802 -274.779411) (xy 166.076141 -274.748286)
			(xy 166.118762 -274.723679) (xy 166.164778 -274.706227) (xy 166.212997 -274.696383) (xy 166.262172 -274.694402)
			(xy 166.311027 -274.700334) (xy 166.358298 -274.714026) (xy 166.40276 -274.735124) (xy 166.443263 -274.76308)
			(xy 166.478756 -274.797172) (xy 166.508321 -274.836516) (xy 166.531192 -274.880093) (xy 166.546776 -274.926774)
			(xy 166.554671 -274.975351) (xy 166.555166 -274.999958) (xy 166.554671 -275.024565) (xy 166.554492 -275.025666)
			(xy 166.873424 -275.025666) (xy 166.873424 -274.97425) (xy 166.881467 -274.923468) (xy 166.897355 -274.874569)
			(xy 166.920698 -274.828757) (xy 166.950919 -274.787161) (xy 166.987275 -274.750805) (xy 167.028871 -274.720584)
			(xy 167.074683 -274.697241) (xy 167.123582 -274.681353) (xy 167.174364 -274.67331) (xy 167.22578 -274.67331)
			(xy 167.276562 -274.681353) (xy 167.325461 -274.697241) (xy 167.371273 -274.720584) (xy 167.412869 -274.750805)
			(xy 167.449225 -274.787161) (xy 167.479446 -274.828757) (xy 167.502789 -274.874569) (xy 167.518677 -274.923468)
			(xy 167.52672 -274.97425) (xy 167.527224 -274.999958) (xy 167.844228 -274.999958) (xy 167.848188 -274.950904)
			(xy 167.859965 -274.90312) (xy 167.879256 -274.857844) (xy 167.905559 -274.816248) (xy 167.938194 -274.779411)
			(xy 167.976315 -274.748286) (xy 168.018936 -274.723679) (xy 168.064952 -274.706227) (xy 168.113171 -274.696383)
			(xy 168.162346 -274.694402) (xy 168.211201 -274.700334) (xy 168.258472 -274.714026) (xy 168.302934 -274.735124)
			(xy 168.343437 -274.76308) (xy 168.37893 -274.797172) (xy 168.408495 -274.836516) (xy 168.431366 -274.880093)
			(xy 168.44695 -274.926774) (xy 168.454845 -274.975351) (xy 168.45534 -274.999958) (xy 168.454845 -275.024565)
			(xy 168.454666 -275.025666) (xy 168.773344 -275.025666) (xy 168.773344 -274.97425) (xy 168.781387 -274.923468)
			(xy 168.797275 -274.874569) (xy 168.820618 -274.828757) (xy 168.850839 -274.787161) (xy 168.887195 -274.750805)
			(xy 168.928791 -274.720584) (xy 168.974603 -274.697241) (xy 169.023502 -274.681353) (xy 169.074284 -274.67331)
			(xy 169.1257 -274.67331) (xy 169.176482 -274.681353) (xy 169.225381 -274.697241) (xy 169.271193 -274.720584)
			(xy 169.312789 -274.750805) (xy 169.349145 -274.787161) (xy 169.379366 -274.828757) (xy 169.402709 -274.874569)
			(xy 169.418597 -274.923468) (xy 169.42664 -274.97425) (xy 169.427144 -274.999958) (xy 169.744148 -274.999958)
			(xy 169.748108 -274.950904) (xy 169.759885 -274.90312) (xy 169.779176 -274.857844) (xy 169.805479 -274.816248)
			(xy 169.838114 -274.779411) (xy 169.876235 -274.748286) (xy 169.918856 -274.723679) (xy 169.964872 -274.706227)
			(xy 170.013091 -274.696383) (xy 170.062266 -274.694402) (xy 170.111121 -274.700334) (xy 170.158392 -274.714026)
			(xy 170.202854 -274.735124) (xy 170.243357 -274.76308) (xy 170.27885 -274.797172) (xy 170.308415 -274.836516)
			(xy 170.331286 -274.880093) (xy 170.34687 -274.926774) (xy 170.354765 -274.975351) (xy 170.35526 -274.999958)
			(xy 170.354765 -275.024565) (xy 170.354586 -275.025666) (xy 170.673264 -275.025666) (xy 170.673264 -274.97425)
			(xy 170.681307 -274.923468) (xy 170.697195 -274.874569) (xy 170.720538 -274.828757) (xy 170.750759 -274.787161)
			(xy 170.787115 -274.750805) (xy 170.828711 -274.720584) (xy 170.874523 -274.697241) (xy 170.923422 -274.681353)
			(xy 170.974204 -274.67331) (xy 171.02562 -274.67331) (xy 171.076402 -274.681353) (xy 171.125301 -274.697241)
			(xy 171.171113 -274.720584) (xy 171.212709 -274.750805) (xy 171.249065 -274.787161) (xy 171.279286 -274.828757)
			(xy 171.302629 -274.874569) (xy 171.318517 -274.923468) (xy 171.32656 -274.97425) (xy 171.327064 -274.999958)
			(xy 171.644068 -274.999958) (xy 171.648028 -274.950904) (xy 171.659805 -274.90312) (xy 171.679096 -274.857844)
			(xy 171.705399 -274.816248) (xy 171.738034 -274.779411) (xy 171.776155 -274.748286) (xy 171.818776 -274.723679)
			(xy 171.864792 -274.706227) (xy 171.913011 -274.696383) (xy 171.962186 -274.694402) (xy 172.011041 -274.700334)
			(xy 172.058312 -274.714026) (xy 172.102774 -274.735124) (xy 172.143277 -274.76308) (xy 172.17877 -274.797172)
			(xy 172.208335 -274.836516) (xy 172.231206 -274.880093) (xy 172.24679 -274.926774) (xy 172.254685 -274.975351)
			(xy 172.25518 -274.999958) (xy 172.254685 -275.024565) (xy 172.254506 -275.025666) (xy 172.573438 -275.025666)
			(xy 172.573438 -274.97425) (xy 172.581481 -274.923468) (xy 172.597369 -274.874569) (xy 172.620712 -274.828757)
			(xy 172.650933 -274.787161) (xy 172.687289 -274.750805) (xy 172.728885 -274.720584) (xy 172.774697 -274.697241)
			(xy 172.823596 -274.681353) (xy 172.874378 -274.67331) (xy 172.925794 -274.67331) (xy 172.976576 -274.681353)
			(xy 173.025475 -274.697241) (xy 173.071287 -274.720584) (xy 173.112883 -274.750805) (xy 173.149239 -274.787161)
			(xy 173.17946 -274.828757) (xy 173.202803 -274.874569) (xy 173.218691 -274.923468) (xy 173.226734 -274.97425)
			(xy 173.227238 -274.999958) (xy 173.544242 -274.999958) (xy 173.548202 -274.950904) (xy 173.559979 -274.90312)
			(xy 173.57927 -274.857844) (xy 173.605573 -274.816248) (xy 173.638208 -274.779411) (xy 173.676329 -274.748286)
			(xy 173.71895 -274.723679) (xy 173.764966 -274.706227) (xy 173.813185 -274.696383) (xy 173.86236 -274.694402)
			(xy 173.911215 -274.700334) (xy 173.958486 -274.714026) (xy 174.002948 -274.735124) (xy 174.043451 -274.76308)
			(xy 174.078944 -274.797172) (xy 174.108509 -274.836516) (xy 174.13138 -274.880093) (xy 174.146964 -274.926774)
			(xy 174.154859 -274.975351) (xy 174.155354 -274.999958) (xy 174.154859 -275.024565) (xy 174.15468 -275.025666)
			(xy 174.473358 -275.025666) (xy 174.473358 -274.97425) (xy 174.481401 -274.923468) (xy 174.497289 -274.874569)
			(xy 174.520632 -274.828757) (xy 174.550853 -274.787161) (xy 174.587209 -274.750805) (xy 174.628805 -274.720584)
			(xy 174.674617 -274.697241) (xy 174.723516 -274.681353) (xy 174.774298 -274.67331) (xy 174.825714 -274.67331)
			(xy 174.876496 -274.681353) (xy 174.925395 -274.697241) (xy 174.971207 -274.720584) (xy 175.012803 -274.750805)
			(xy 175.049159 -274.787161) (xy 175.07938 -274.828757) (xy 175.102723 -274.874569) (xy 175.118611 -274.923468)
			(xy 175.126654 -274.97425) (xy 175.127158 -274.999958) (xy 175.444162 -274.999958) (xy 175.448122 -274.950904)
			(xy 175.459899 -274.90312) (xy 175.47919 -274.857844) (xy 175.505493 -274.816248) (xy 175.538128 -274.779411)
			(xy 175.576249 -274.748286) (xy 175.61887 -274.723679) (xy 175.664886 -274.706227) (xy 175.713105 -274.696383)
			(xy 175.76228 -274.694402) (xy 175.811135 -274.700334) (xy 175.858406 -274.714026) (xy 175.902868 -274.735124)
			(xy 175.943371 -274.76308) (xy 175.978864 -274.797172) (xy 176.008429 -274.836516) (xy 176.0313 -274.880093)
			(xy 176.046884 -274.926774) (xy 176.054779 -274.975351) (xy 176.055274 -274.999958) (xy 176.054779 -275.024565)
			(xy 176.054641 -275.025412) (xy 176.373024 -275.025412) (xy 176.373024 -274.973996) (xy 176.381067 -274.923214)
			(xy 176.396955 -274.874315) (xy 176.420298 -274.828503) (xy 176.450519 -274.786907) (xy 176.486875 -274.750551)
			(xy 176.528471 -274.72033) (xy 176.574283 -274.696987) (xy 176.623182 -274.681099) (xy 176.673964 -274.673056)
			(xy 176.72538 -274.673056) (xy 176.776162 -274.681099) (xy 176.825061 -274.696987) (xy 176.870873 -274.72033)
			(xy 176.912469 -274.750551) (xy 176.948825 -274.786907) (xy 176.979046 -274.828503) (xy 177.002389 -274.874315)
			(xy 177.018277 -274.923214) (xy 177.02632 -274.973996) (xy 177.026824 -274.999704) (xy 177.026819 -274.999958)
			(xy 177.344082 -274.999958) (xy 177.348042 -274.950904) (xy 177.359819 -274.90312) (xy 177.37911 -274.857844)
			(xy 177.405413 -274.816248) (xy 177.438048 -274.779411) (xy 177.476169 -274.748286) (xy 177.51879 -274.723679)
			(xy 177.564806 -274.706227) (xy 177.613025 -274.696383) (xy 177.6622 -274.694402) (xy 177.711055 -274.700334)
			(xy 177.758326 -274.714026) (xy 177.802788 -274.735124) (xy 177.843291 -274.76308) (xy 177.878784 -274.797172)
			(xy 177.908349 -274.836516) (xy 177.93122 -274.880093) (xy 177.946804 -274.926774) (xy 177.954699 -274.975351)
			(xy 177.955194 -274.999958) (xy 177.954699 -275.024565) (xy 177.95452 -275.025666) (xy 178.272944 -275.025666)
			(xy 178.272944 -274.97425) (xy 178.280987 -274.923468) (xy 178.296875 -274.874569) (xy 178.320218 -274.828757)
			(xy 178.350439 -274.787161) (xy 178.386795 -274.750805) (xy 178.428391 -274.720584) (xy 178.474203 -274.697241)
			(xy 178.523102 -274.681353) (xy 178.573884 -274.67331) (xy 178.6253 -274.67331) (xy 178.676082 -274.681353)
			(xy 178.724981 -274.697241) (xy 178.770793 -274.720584) (xy 178.812389 -274.750805) (xy 178.848745 -274.787161)
			(xy 178.878966 -274.828757) (xy 178.902309 -274.874569) (xy 178.918197 -274.923468) (xy 178.92624 -274.97425)
			(xy 178.926744 -274.999958) (xy 179.244256 -274.999958) (xy 179.248216 -274.950904) (xy 179.259993 -274.90312)
			(xy 179.279284 -274.857844) (xy 179.305587 -274.816248) (xy 179.338222 -274.779411) (xy 179.376343 -274.748286)
			(xy 179.418964 -274.723679) (xy 179.46498 -274.706227) (xy 179.513199 -274.696383) (xy 179.562374 -274.694402)
			(xy 179.611229 -274.700334) (xy 179.6585 -274.714026) (xy 179.702962 -274.735124) (xy 179.743465 -274.76308)
			(xy 179.778958 -274.797172) (xy 179.808523 -274.836516) (xy 179.831394 -274.880093) (xy 179.846978 -274.926774)
			(xy 179.854873 -274.975351) (xy 179.855368 -274.999958) (xy 179.854873 -275.024565) (xy 179.854735 -275.025412)
			(xy 180.173118 -275.025412) (xy 180.173118 -274.973996) (xy 180.181161 -274.923214) (xy 180.197049 -274.874315)
			(xy 180.220392 -274.828503) (xy 180.250613 -274.786907) (xy 180.286969 -274.750551) (xy 180.328565 -274.72033)
			(xy 180.374377 -274.696987) (xy 180.423276 -274.681099) (xy 180.474058 -274.673056) (xy 180.525474 -274.673056)
			(xy 180.576256 -274.681099) (xy 180.625155 -274.696987) (xy 180.670967 -274.72033) (xy 180.712563 -274.750551)
			(xy 180.748919 -274.786907) (xy 180.77914 -274.828503) (xy 180.802483 -274.874315) (xy 180.818371 -274.923214)
			(xy 180.826414 -274.973996) (xy 180.826918 -274.999704) (xy 180.826913 -274.999958) (xy 181.144176 -274.999958)
			(xy 181.148136 -274.950904) (xy 181.159913 -274.90312) (xy 181.179204 -274.857844) (xy 181.205507 -274.816248)
			(xy 181.238142 -274.779411) (xy 181.276263 -274.748286) (xy 181.318884 -274.723679) (xy 181.3649 -274.706227)
			(xy 181.413119 -274.696383) (xy 181.462294 -274.694402) (xy 181.511149 -274.700334) (xy 181.55842 -274.714026)
			(xy 181.602882 -274.735124) (xy 181.643385 -274.76308) (xy 181.678878 -274.797172) (xy 181.708443 -274.836516)
			(xy 181.731314 -274.880093) (xy 181.746898 -274.926774) (xy 181.754793 -274.975351) (xy 181.755288 -274.999958)
			(xy 181.754793 -275.024565) (xy 181.754614 -275.025666) (xy 182.073038 -275.025666) (xy 182.073038 -274.97425)
			(xy 182.081081 -274.923468) (xy 182.096969 -274.874569) (xy 182.120312 -274.828757) (xy 182.150533 -274.787161)
			(xy 182.186889 -274.750805) (xy 182.228485 -274.720584) (xy 182.274297 -274.697241) (xy 182.323196 -274.681353)
			(xy 182.373978 -274.67331) (xy 182.425394 -274.67331) (xy 182.476176 -274.681353) (xy 182.525075 -274.697241)
			(xy 182.570887 -274.720584) (xy 182.612483 -274.750805) (xy 182.648839 -274.787161) (xy 182.67906 -274.828757)
			(xy 182.702403 -274.874569) (xy 182.718291 -274.923468) (xy 182.726334 -274.97425) (xy 182.726838 -274.999958)
			(xy 183.044096 -274.999958) (xy 183.048056 -274.950904) (xy 183.059833 -274.90312) (xy 183.079124 -274.857844)
			(xy 183.105427 -274.816248) (xy 183.138062 -274.779411) (xy 183.176183 -274.748286) (xy 183.218804 -274.723679)
			(xy 183.26482 -274.706227) (xy 183.313039 -274.696383) (xy 183.362214 -274.694402) (xy 183.411069 -274.700334)
			(xy 183.45834 -274.714026) (xy 183.502802 -274.735124) (xy 183.543305 -274.76308) (xy 183.578798 -274.797172)
			(xy 183.608363 -274.836516) (xy 183.631234 -274.880093) (xy 183.646818 -274.926774) (xy 183.654713 -274.975351)
			(xy 183.655208 -274.999958) (xy 183.654713 -275.024565) (xy 183.654575 -275.025412) (xy 183.972958 -275.025412)
			(xy 183.972958 -274.973996) (xy 183.981001 -274.923214) (xy 183.996889 -274.874315) (xy 184.020232 -274.828503)
			(xy 184.050453 -274.786907) (xy 184.086809 -274.750551) (xy 184.128405 -274.72033) (xy 184.174217 -274.696987)
			(xy 184.223116 -274.681099) (xy 184.273898 -274.673056) (xy 184.325314 -274.673056) (xy 184.376096 -274.681099)
			(xy 184.424995 -274.696987) (xy 184.470807 -274.72033) (xy 184.512403 -274.750551) (xy 184.548759 -274.786907)
			(xy 184.57898 -274.828503) (xy 184.602323 -274.874315) (xy 184.618211 -274.923214) (xy 184.626254 -274.973996)
			(xy 184.626758 -274.999704) (xy 184.626753 -274.999958) (xy 184.94427 -274.999958) (xy 184.94823 -274.950904)
			(xy 184.960007 -274.90312) (xy 184.979298 -274.857844) (xy 185.005601 -274.816248) (xy 185.038236 -274.779411)
			(xy 185.076357 -274.748286) (xy 185.118978 -274.723679) (xy 185.164994 -274.706227) (xy 185.213213 -274.696383)
			(xy 185.262388 -274.694402) (xy 185.311243 -274.700334) (xy 185.358514 -274.714026) (xy 185.402976 -274.735124)
			(xy 185.443479 -274.76308) (xy 185.478972 -274.797172) (xy 185.508537 -274.836516) (xy 185.531408 -274.880093)
			(xy 185.546992 -274.926774) (xy 185.554887 -274.975351) (xy 185.555382 -274.999958) (xy 185.554887 -275.024565)
			(xy 185.554708 -275.025666) (xy 185.872878 -275.025666) (xy 185.872878 -274.97425) (xy 185.880921 -274.923468)
			(xy 185.896809 -274.874569) (xy 185.920152 -274.828757) (xy 185.950373 -274.787161) (xy 185.986729 -274.750805)
			(xy 186.028325 -274.720584) (xy 186.074137 -274.697241) (xy 186.123036 -274.681353) (xy 186.173818 -274.67331)
			(xy 186.225234 -274.67331) (xy 186.276016 -274.681353) (xy 186.324915 -274.697241) (xy 186.370727 -274.720584)
			(xy 186.412323 -274.750805) (xy 186.448679 -274.787161) (xy 186.4789 -274.828757) (xy 186.502243 -274.874569)
			(xy 186.518131 -274.923468) (xy 186.526174 -274.97425) (xy 186.526678 -274.999958) (xy 186.84419 -274.999958)
			(xy 186.84815 -274.950904) (xy 186.859927 -274.90312) (xy 186.879218 -274.857844) (xy 186.905521 -274.816248)
			(xy 186.938156 -274.779411) (xy 186.976277 -274.748286) (xy 187.018898 -274.723679) (xy 187.064914 -274.706227)
			(xy 187.113133 -274.696383) (xy 187.162308 -274.694402) (xy 187.211163 -274.700334) (xy 187.258434 -274.714026)
			(xy 187.302896 -274.735124) (xy 187.343399 -274.76308) (xy 187.378892 -274.797172) (xy 187.408457 -274.836516)
			(xy 187.431328 -274.880093) (xy 187.446912 -274.926774) (xy 187.454807 -274.975351) (xy 187.455302 -274.999958)
			(xy 187.454807 -275.024565) (xy 187.454669 -275.025412) (xy 187.773052 -275.025412) (xy 187.773052 -274.973996)
			(xy 187.781095 -274.923214) (xy 187.796983 -274.874315) (xy 187.820326 -274.828503) (xy 187.850547 -274.786907)
			(xy 187.886903 -274.750551) (xy 187.928499 -274.72033) (xy 187.974311 -274.696987) (xy 188.02321 -274.681099)
			(xy 188.073992 -274.673056) (xy 188.125408 -274.673056) (xy 188.17619 -274.681099) (xy 188.225089 -274.696987)
			(xy 188.270901 -274.72033) (xy 188.312497 -274.750551) (xy 188.348853 -274.786907) (xy 188.379074 -274.828503)
			(xy 188.402417 -274.874315) (xy 188.418305 -274.923214) (xy 188.426348 -274.973996) (xy 188.426852 -274.999704)
			(xy 188.426847 -274.999958) (xy 188.74411 -274.999958) (xy 188.74807 -274.950904) (xy 188.759847 -274.90312)
			(xy 188.779138 -274.857844) (xy 188.805441 -274.816248) (xy 188.838076 -274.779411) (xy 188.876197 -274.748286)
			(xy 188.918818 -274.723679) (xy 188.964834 -274.706227) (xy 189.013053 -274.696383) (xy 189.062228 -274.694402)
			(xy 189.111083 -274.700334) (xy 189.158354 -274.714026) (xy 189.202816 -274.735124) (xy 189.243319 -274.76308)
			(xy 189.278812 -274.797172) (xy 189.308377 -274.836516) (xy 189.331248 -274.880093) (xy 189.346832 -274.926774)
			(xy 189.354727 -274.975351) (xy 189.355222 -274.999958) (xy 189.354727 -275.024565) (xy 189.354548 -275.025666)
			(xy 189.672972 -275.025666) (xy 189.672972 -274.97425) (xy 189.681015 -274.923468) (xy 189.696903 -274.874569)
			(xy 189.720246 -274.828757) (xy 189.750467 -274.787161) (xy 189.786823 -274.750805) (xy 189.828419 -274.720584)
			(xy 189.874231 -274.697241) (xy 189.92313 -274.681353) (xy 189.973912 -274.67331) (xy 190.025328 -274.67331)
			(xy 190.07611 -274.681353) (xy 190.125009 -274.697241) (xy 190.170821 -274.720584) (xy 190.212417 -274.750805)
			(xy 190.248773 -274.787161) (xy 190.278994 -274.828757) (xy 190.302337 -274.874569) (xy 190.318225 -274.923468)
			(xy 190.326268 -274.97425) (xy 190.326772 -274.999958) (xy 190.64403 -274.999958) (xy 190.64799 -274.950904)
			(xy 190.659767 -274.90312) (xy 190.679058 -274.857844) (xy 190.705361 -274.816248) (xy 190.737996 -274.779411)
			(xy 190.776117 -274.748286) (xy 190.818738 -274.723679) (xy 190.864754 -274.706227) (xy 190.912973 -274.696383)
			(xy 190.962148 -274.694402) (xy 191.011003 -274.700334) (xy 191.058274 -274.714026) (xy 191.102736 -274.735124)
			(xy 191.143239 -274.76308) (xy 191.178732 -274.797172) (xy 191.208297 -274.836516) (xy 191.231168 -274.880093)
			(xy 191.246752 -274.926774) (xy 191.254647 -274.975351) (xy 191.255142 -274.999958) (xy 191.254647 -275.024565)
			(xy 191.254509 -275.025412) (xy 191.573146 -275.025412) (xy 191.573146 -274.973996) (xy 191.581189 -274.923214)
			(xy 191.597077 -274.874315) (xy 191.62042 -274.828503) (xy 191.650641 -274.786907) (xy 191.686997 -274.750551)
			(xy 191.728593 -274.72033) (xy 191.774405 -274.696987) (xy 191.823304 -274.681099) (xy 191.874086 -274.673056)
			(xy 191.925502 -274.673056) (xy 191.976284 -274.681099) (xy 192.025183 -274.696987) (xy 192.070995 -274.72033)
			(xy 192.112591 -274.750551) (xy 192.148947 -274.786907) (xy 192.179168 -274.828503) (xy 192.202511 -274.874315)
			(xy 192.218399 -274.923214) (xy 192.226442 -274.973996) (xy 192.226946 -274.999704) (xy 192.226941 -274.999958)
			(xy 192.54395 -274.999958) (xy 192.54791 -274.950904) (xy 192.559687 -274.90312) (xy 192.578978 -274.857844)
			(xy 192.605281 -274.816248) (xy 192.637916 -274.779411) (xy 192.676037 -274.748286) (xy 192.718658 -274.723679)
			(xy 192.764674 -274.706227) (xy 192.812893 -274.696383) (xy 192.862068 -274.694402) (xy 192.910923 -274.700334)
			(xy 192.958194 -274.714026) (xy 193.002656 -274.735124) (xy 193.043159 -274.76308) (xy 193.078652 -274.797172)
			(xy 193.108217 -274.836516) (xy 193.131088 -274.880093) (xy 193.146672 -274.926774) (xy 193.154567 -274.975351)
			(xy 193.155062 -274.999958) (xy 193.154567 -275.024565) (xy 193.154388 -275.025666) (xy 193.473066 -275.025666)
			(xy 193.473066 -274.97425) (xy 193.481109 -274.923468) (xy 193.496997 -274.874569) (xy 193.52034 -274.828757)
			(xy 193.550561 -274.787161) (xy 193.586917 -274.750805) (xy 193.628513 -274.720584) (xy 193.674325 -274.697241)
			(xy 193.723224 -274.681353) (xy 193.774006 -274.67331) (xy 193.825422 -274.67331) (xy 193.876204 -274.681353)
			(xy 193.925103 -274.697241) (xy 193.970915 -274.720584) (xy 194.012511 -274.750805) (xy 194.048867 -274.787161)
			(xy 194.079088 -274.828757) (xy 194.102431 -274.874569) (xy 194.118319 -274.923468) (xy 194.126362 -274.97425)
			(xy 194.126866 -274.999958) (xy 194.44387 -274.999958) (xy 194.44783 -274.950904) (xy 194.459607 -274.90312)
			(xy 194.478898 -274.857844) (xy 194.505201 -274.816248) (xy 194.537836 -274.779411) (xy 194.575957 -274.748286)
			(xy 194.618578 -274.723679) (xy 194.664594 -274.706227) (xy 194.712813 -274.696383) (xy 194.761988 -274.694402)
			(xy 194.810843 -274.700334) (xy 194.858114 -274.714026) (xy 194.902576 -274.735124) (xy 194.943079 -274.76308)
			(xy 194.978572 -274.797172) (xy 195.008137 -274.836516) (xy 195.031008 -274.880093) (xy 195.046592 -274.926774)
			(xy 195.054487 -274.975351) (xy 195.054982 -274.999958) (xy 195.054487 -275.024565) (xy 195.054308 -275.025666)
			(xy 195.372986 -275.025666) (xy 195.372986 -274.97425) (xy 195.381029 -274.923468) (xy 195.396917 -274.874569)
			(xy 195.42026 -274.828757) (xy 195.450481 -274.787161) (xy 195.486837 -274.750805) (xy 195.528433 -274.720584)
			(xy 195.574245 -274.697241) (xy 195.623144 -274.681353) (xy 195.673926 -274.67331) (xy 195.725342 -274.67331)
			(xy 195.776124 -274.681353) (xy 195.825023 -274.697241) (xy 195.870835 -274.720584) (xy 195.912431 -274.750805)
			(xy 195.948787 -274.787161) (xy 195.979008 -274.828757) (xy 196.002351 -274.874569) (xy 196.018239 -274.923468)
			(xy 196.026282 -274.97425) (xy 196.026786 -274.999958) (xy 196.344044 -274.999958) (xy 196.348004 -274.950904)
			(xy 196.359781 -274.90312) (xy 196.379072 -274.857844) (xy 196.405375 -274.816248) (xy 196.43801 -274.779411)
			(xy 196.476131 -274.748286) (xy 196.518752 -274.723679) (xy 196.564768 -274.706227) (xy 196.612987 -274.696383)
			(xy 196.662162 -274.694402) (xy 196.711017 -274.700334) (xy 196.758288 -274.714026) (xy 196.80275 -274.735124)
			(xy 196.843253 -274.76308) (xy 196.878746 -274.797172) (xy 196.908311 -274.836516) (xy 196.931182 -274.880093)
			(xy 196.946766 -274.926774) (xy 196.954661 -274.975351) (xy 196.955156 -274.999958) (xy 196.954661 -275.024565)
			(xy 196.954523 -275.025412) (xy 197.273414 -275.025412) (xy 197.273414 -274.973996) (xy 197.281457 -274.923214)
			(xy 197.297345 -274.874315) (xy 197.320688 -274.828503) (xy 197.350909 -274.786907) (xy 197.387265 -274.750551)
			(xy 197.428861 -274.72033) (xy 197.474673 -274.696987) (xy 197.523572 -274.681099) (xy 197.574354 -274.673056)
			(xy 197.62577 -274.673056) (xy 197.676552 -274.681099) (xy 197.725451 -274.696987) (xy 197.771263 -274.72033)
			(xy 197.812859 -274.750551) (xy 197.849215 -274.786907) (xy 197.879436 -274.828503) (xy 197.902779 -274.874315)
			(xy 197.918667 -274.923214) (xy 197.92671 -274.973996) (xy 197.927214 -274.999704) (xy 197.92671 -275.025412)
			(xy 198.223374 -275.025412) (xy 198.223374 -274.973996) (xy 198.231417 -274.923214) (xy 198.247305 -274.874315)
			(xy 198.270648 -274.828503) (xy 198.300869 -274.786907) (xy 198.337225 -274.750551) (xy 198.378821 -274.72033)
			(xy 198.424633 -274.696987) (xy 198.473532 -274.681099) (xy 198.524314 -274.673056) (xy 198.57573 -274.673056)
			(xy 198.626512 -274.681099) (xy 198.675411 -274.696987) (xy 198.721223 -274.72033) (xy 198.762819 -274.750551)
			(xy 198.799175 -274.786907) (xy 198.829396 -274.828503) (xy 198.852739 -274.874315) (xy 198.868627 -274.923214)
			(xy 198.87667 -274.973996) (xy 198.877174 -274.999704) (xy 198.877169 -274.999958) (xy 199.194432 -274.999958)
			(xy 199.198392 -274.950904) (xy 199.210169 -274.90312) (xy 199.22946 -274.857844) (xy 199.255763 -274.816248)
			(xy 199.288398 -274.779411) (xy 199.326519 -274.748286) (xy 199.36914 -274.723679) (xy 199.415156 -274.706227)
			(xy 199.463375 -274.696383) (xy 199.51255 -274.694402) (xy 199.561405 -274.700334) (xy 199.608676 -274.714026)
			(xy 199.653138 -274.735124) (xy 199.693641 -274.76308) (xy 199.729134 -274.797172) (xy 199.758699 -274.836516)
			(xy 199.78157 -274.880093) (xy 199.797154 -274.926774) (xy 199.805049 -274.975351) (xy 199.805544 -274.999958)
			(xy 199.805049 -275.024565) (xy 199.797154 -275.073142) (xy 199.78157 -275.119823) (xy 199.758699 -275.1634)
			(xy 199.729134 -275.202744) (xy 199.693641 -275.236836) (xy 199.653138 -275.264792) (xy 199.608676 -275.28589)
			(xy 199.561405 -275.299582) (xy 199.51255 -275.305514) (xy 199.463375 -275.303533) (xy 199.415156 -275.293689)
			(xy 199.36914 -275.276237) (xy 199.326519 -275.25163) (xy 199.288398 -275.220505) (xy 199.255763 -275.183668)
			(xy 199.22946 -275.142072) (xy 199.210169 -275.096796) (xy 199.198392 -275.049012) (xy 199.194432 -274.999958)
			(xy 198.877169 -274.999958) (xy 198.87667 -275.025412) (xy 198.868627 -275.076194) (xy 198.852739 -275.125093)
			(xy 198.829396 -275.170905) (xy 198.799175 -275.212501) (xy 198.762819 -275.248857) (xy 198.721223 -275.279078)
			(xy 198.675411 -275.302421) (xy 198.626512 -275.318309) (xy 198.57573 -275.326352) (xy 198.524314 -275.326352)
			(xy 198.473532 -275.318309) (xy 198.424633 -275.302421) (xy 198.378821 -275.279078) (xy 198.337225 -275.248857)
			(xy 198.300869 -275.212501) (xy 198.270648 -275.170905) (xy 198.247305 -275.125093) (xy 198.231417 -275.076194)
			(xy 198.223374 -275.025412) (xy 197.92671 -275.025412) (xy 197.918667 -275.076194) (xy 197.902779 -275.125093)
			(xy 197.879436 -275.170905) (xy 197.849215 -275.212501) (xy 197.812859 -275.248857) (xy 197.771263 -275.279078)
			(xy 197.725451 -275.302421) (xy 197.676552 -275.318309) (xy 197.62577 -275.326352) (xy 197.574354 -275.326352)
			(xy 197.523572 -275.318309) (xy 197.474673 -275.302421) (xy 197.428861 -275.279078) (xy 197.387265 -275.248857)
			(xy 197.350909 -275.212501) (xy 197.320688 -275.170905) (xy 197.297345 -275.125093) (xy 197.281457 -275.076194)
			(xy 197.273414 -275.025412) (xy 196.954523 -275.025412) (xy 196.946766 -275.073142) (xy 196.931182 -275.119823)
			(xy 196.908311 -275.1634) (xy 196.878746 -275.202744) (xy 196.843253 -275.236836) (xy 196.80275 -275.264792)
			(xy 196.758288 -275.28589) (xy 196.711017 -275.299582) (xy 196.662162 -275.305514) (xy 196.612987 -275.303533)
			(xy 196.564768 -275.293689) (xy 196.518752 -275.276237) (xy 196.476131 -275.25163) (xy 196.43801 -275.220505)
			(xy 196.405375 -275.183668) (xy 196.379072 -275.142072) (xy 196.359781 -275.096796) (xy 196.348004 -275.049012)
			(xy 196.344044 -274.999958) (xy 196.026786 -274.999958) (xy 196.026282 -275.025666) (xy 196.018239 -275.076448)
			(xy 196.002351 -275.125347) (xy 195.979008 -275.171159) (xy 195.948787 -275.212755) (xy 195.912431 -275.249111)
			(xy 195.870835 -275.279332) (xy 195.825023 -275.302675) (xy 195.776124 -275.318563) (xy 195.725342 -275.326606)
			(xy 195.673926 -275.326606) (xy 195.623144 -275.318563) (xy 195.574245 -275.302675) (xy 195.528433 -275.279332)
			(xy 195.486837 -275.249111) (xy 195.450481 -275.212755) (xy 195.42026 -275.171159) (xy 195.396917 -275.125347)
			(xy 195.381029 -275.076448) (xy 195.372986 -275.025666) (xy 195.054308 -275.025666) (xy 195.046592 -275.073142)
			(xy 195.031008 -275.119823) (xy 195.008137 -275.1634) (xy 194.978572 -275.202744) (xy 194.943079 -275.236836)
			(xy 194.902576 -275.264792) (xy 194.858114 -275.28589) (xy 194.810843 -275.299582) (xy 194.761988 -275.305514)
			(xy 194.712813 -275.303533) (xy 194.664594 -275.293689) (xy 194.618578 -275.276237) (xy 194.575957 -275.25163)
			(xy 194.537836 -275.220505) (xy 194.505201 -275.183668) (xy 194.478898 -275.142072) (xy 194.459607 -275.096796)
			(xy 194.44783 -275.049012) (xy 194.44387 -274.999958) (xy 194.126866 -274.999958) (xy 194.126362 -275.025666)
			(xy 194.118319 -275.076448) (xy 194.102431 -275.125347) (xy 194.079088 -275.171159) (xy 194.048867 -275.212755)
			(xy 194.012511 -275.249111) (xy 193.970915 -275.279332) (xy 193.925103 -275.302675) (xy 193.876204 -275.318563)
			(xy 193.825422 -275.326606) (xy 193.774006 -275.326606) (xy 193.723224 -275.318563) (xy 193.674325 -275.302675)
			(xy 193.628513 -275.279332) (xy 193.586917 -275.249111) (xy 193.550561 -275.212755) (xy 193.52034 -275.171159)
			(xy 193.496997 -275.125347) (xy 193.481109 -275.076448) (xy 193.473066 -275.025666) (xy 193.154388 -275.025666)
			(xy 193.146672 -275.073142) (xy 193.131088 -275.119823) (xy 193.108217 -275.1634) (xy 193.078652 -275.202744)
			(xy 193.043159 -275.236836) (xy 193.002656 -275.264792) (xy 192.958194 -275.28589) (xy 192.910923 -275.299582)
			(xy 192.862068 -275.305514) (xy 192.812893 -275.303533) (xy 192.764674 -275.293689) (xy 192.718658 -275.276237)
			(xy 192.676037 -275.25163) (xy 192.637916 -275.220505) (xy 192.605281 -275.183668) (xy 192.578978 -275.142072)
			(xy 192.559687 -275.096796) (xy 192.54791 -275.049012) (xy 192.54395 -274.999958) (xy 192.226941 -274.999958)
			(xy 192.226442 -275.025412) (xy 192.218399 -275.076194) (xy 192.202511 -275.125093) (xy 192.179168 -275.170905)
			(xy 192.148947 -275.212501) (xy 192.112591 -275.248857) (xy 192.070995 -275.279078) (xy 192.025183 -275.302421)
			(xy 191.976284 -275.318309) (xy 191.925502 -275.326352) (xy 191.874086 -275.326352) (xy 191.823304 -275.318309)
			(xy 191.774405 -275.302421) (xy 191.728593 -275.279078) (xy 191.686997 -275.248857) (xy 191.650641 -275.212501)
			(xy 191.62042 -275.170905) (xy 191.597077 -275.125093) (xy 191.581189 -275.076194) (xy 191.573146 -275.025412)
			(xy 191.254509 -275.025412) (xy 191.246752 -275.073142) (xy 191.231168 -275.119823) (xy 191.208297 -275.1634)
			(xy 191.178732 -275.202744) (xy 191.143239 -275.236836) (xy 191.102736 -275.264792) (xy 191.058274 -275.28589)
			(xy 191.011003 -275.299582) (xy 190.962148 -275.305514) (xy 190.912973 -275.303533) (xy 190.864754 -275.293689)
			(xy 190.818738 -275.276237) (xy 190.776117 -275.25163) (xy 190.737996 -275.220505) (xy 190.705361 -275.183668)
			(xy 190.679058 -275.142072) (xy 190.659767 -275.096796) (xy 190.64799 -275.049012) (xy 190.64403 -274.999958)
			(xy 190.326772 -274.999958) (xy 190.326268 -275.025666) (xy 190.318225 -275.076448) (xy 190.302337 -275.125347)
			(xy 190.278994 -275.171159) (xy 190.248773 -275.212755) (xy 190.212417 -275.249111) (xy 190.170821 -275.279332)
			(xy 190.125009 -275.302675) (xy 190.07611 -275.318563) (xy 190.025328 -275.326606) (xy 189.973912 -275.326606)
			(xy 189.92313 -275.318563) (xy 189.874231 -275.302675) (xy 189.828419 -275.279332) (xy 189.786823 -275.249111)
			(xy 189.750467 -275.212755) (xy 189.720246 -275.171159) (xy 189.696903 -275.125347) (xy 189.681015 -275.076448)
			(xy 189.672972 -275.025666) (xy 189.354548 -275.025666) (xy 189.346832 -275.073142) (xy 189.331248 -275.119823)
			(xy 189.308377 -275.1634) (xy 189.278812 -275.202744) (xy 189.243319 -275.236836) (xy 189.202816 -275.264792)
			(xy 189.158354 -275.28589) (xy 189.111083 -275.299582) (xy 189.062228 -275.305514) (xy 189.013053 -275.303533)
			(xy 188.964834 -275.293689) (xy 188.918818 -275.276237) (xy 188.876197 -275.25163) (xy 188.838076 -275.220505)
			(xy 188.805441 -275.183668) (xy 188.779138 -275.142072) (xy 188.759847 -275.096796) (xy 188.74807 -275.049012)
			(xy 188.74411 -274.999958) (xy 188.426847 -274.999958) (xy 188.426348 -275.025412) (xy 188.418305 -275.076194)
			(xy 188.402417 -275.125093) (xy 188.379074 -275.170905) (xy 188.348853 -275.212501) (xy 188.312497 -275.248857)
			(xy 188.270901 -275.279078) (xy 188.225089 -275.302421) (xy 188.17619 -275.318309) (xy 188.125408 -275.326352)
			(xy 188.073992 -275.326352) (xy 188.02321 -275.318309) (xy 187.974311 -275.302421) (xy 187.928499 -275.279078)
			(xy 187.886903 -275.248857) (xy 187.850547 -275.212501) (xy 187.820326 -275.170905) (xy 187.796983 -275.125093)
			(xy 187.781095 -275.076194) (xy 187.773052 -275.025412) (xy 187.454669 -275.025412) (xy 187.446912 -275.073142)
			(xy 187.431328 -275.119823) (xy 187.408457 -275.1634) (xy 187.378892 -275.202744) (xy 187.343399 -275.236836)
			(xy 187.302896 -275.264792) (xy 187.258434 -275.28589) (xy 187.211163 -275.299582) (xy 187.162308 -275.305514)
			(xy 187.113133 -275.303533) (xy 187.064914 -275.293689) (xy 187.018898 -275.276237) (xy 186.976277 -275.25163)
			(xy 186.938156 -275.220505) (xy 186.905521 -275.183668) (xy 186.879218 -275.142072) (xy 186.859927 -275.096796)
			(xy 186.84815 -275.049012) (xy 186.84419 -274.999958) (xy 186.526678 -274.999958) (xy 186.526174 -275.025666)
			(xy 186.518131 -275.076448) (xy 186.502243 -275.125347) (xy 186.4789 -275.171159) (xy 186.448679 -275.212755)
			(xy 186.412323 -275.249111) (xy 186.370727 -275.279332) (xy 186.324915 -275.302675) (xy 186.276016 -275.318563)
			(xy 186.225234 -275.326606) (xy 186.173818 -275.326606) (xy 186.123036 -275.318563) (xy 186.074137 -275.302675)
			(xy 186.028325 -275.279332) (xy 185.986729 -275.249111) (xy 185.950373 -275.212755) (xy 185.920152 -275.171159)
			(xy 185.896809 -275.125347) (xy 185.880921 -275.076448) (xy 185.872878 -275.025666) (xy 185.554708 -275.025666)
			(xy 185.546992 -275.073142) (xy 185.531408 -275.119823) (xy 185.508537 -275.1634) (xy 185.478972 -275.202744)
			(xy 185.443479 -275.236836) (xy 185.402976 -275.264792) (xy 185.358514 -275.28589) (xy 185.311243 -275.299582)
			(xy 185.262388 -275.305514) (xy 185.213213 -275.303533) (xy 185.164994 -275.293689) (xy 185.118978 -275.276237)
			(xy 185.076357 -275.25163) (xy 185.038236 -275.220505) (xy 185.005601 -275.183668) (xy 184.979298 -275.142072)
			(xy 184.960007 -275.096796) (xy 184.94823 -275.049012) (xy 184.94427 -274.999958) (xy 184.626753 -274.999958)
			(xy 184.626254 -275.025412) (xy 184.618211 -275.076194) (xy 184.602323 -275.125093) (xy 184.57898 -275.170905)
			(xy 184.548759 -275.212501) (xy 184.512403 -275.248857) (xy 184.470807 -275.279078) (xy 184.424995 -275.302421)
			(xy 184.376096 -275.318309) (xy 184.325314 -275.326352) (xy 184.273898 -275.326352) (xy 184.223116 -275.318309)
			(xy 184.174217 -275.302421) (xy 184.128405 -275.279078) (xy 184.086809 -275.248857) (xy 184.050453 -275.212501)
			(xy 184.020232 -275.170905) (xy 183.996889 -275.125093) (xy 183.981001 -275.076194) (xy 183.972958 -275.025412)
			(xy 183.654575 -275.025412) (xy 183.646818 -275.073142) (xy 183.631234 -275.119823) (xy 183.608363 -275.1634)
			(xy 183.578798 -275.202744) (xy 183.543305 -275.236836) (xy 183.502802 -275.264792) (xy 183.45834 -275.28589)
			(xy 183.411069 -275.299582) (xy 183.362214 -275.305514) (xy 183.313039 -275.303533) (xy 183.26482 -275.293689)
			(xy 183.218804 -275.276237) (xy 183.176183 -275.25163) (xy 183.138062 -275.220505) (xy 183.105427 -275.183668)
			(xy 183.079124 -275.142072) (xy 183.059833 -275.096796) (xy 183.048056 -275.049012) (xy 183.044096 -274.999958)
			(xy 182.726838 -274.999958) (xy 182.726334 -275.025666) (xy 182.718291 -275.076448) (xy 182.702403 -275.125347)
			(xy 182.67906 -275.171159) (xy 182.648839 -275.212755) (xy 182.612483 -275.249111) (xy 182.570887 -275.279332)
			(xy 182.525075 -275.302675) (xy 182.476176 -275.318563) (xy 182.425394 -275.326606) (xy 182.373978 -275.326606)
			(xy 182.323196 -275.318563) (xy 182.274297 -275.302675) (xy 182.228485 -275.279332) (xy 182.186889 -275.249111)
			(xy 182.150533 -275.212755) (xy 182.120312 -275.171159) (xy 182.096969 -275.125347) (xy 182.081081 -275.076448)
			(xy 182.073038 -275.025666) (xy 181.754614 -275.025666) (xy 181.746898 -275.073142) (xy 181.731314 -275.119823)
			(xy 181.708443 -275.1634) (xy 181.678878 -275.202744) (xy 181.643385 -275.236836) (xy 181.602882 -275.264792)
			(xy 181.55842 -275.28589) (xy 181.511149 -275.299582) (xy 181.462294 -275.305514) (xy 181.413119 -275.303533)
			(xy 181.3649 -275.293689) (xy 181.318884 -275.276237) (xy 181.276263 -275.25163) (xy 181.238142 -275.220505)
			(xy 181.205507 -275.183668) (xy 181.179204 -275.142072) (xy 181.159913 -275.096796) (xy 181.148136 -275.049012)
			(xy 181.144176 -274.999958) (xy 180.826913 -274.999958) (xy 180.826414 -275.025412) (xy 180.818371 -275.076194)
			(xy 180.802483 -275.125093) (xy 180.77914 -275.170905) (xy 180.748919 -275.212501) (xy 180.712563 -275.248857)
			(xy 180.670967 -275.279078) (xy 180.625155 -275.302421) (xy 180.576256 -275.318309) (xy 180.525474 -275.326352)
			(xy 180.474058 -275.326352) (xy 180.423276 -275.318309) (xy 180.374377 -275.302421) (xy 180.328565 -275.279078)
			(xy 180.286969 -275.248857) (xy 180.250613 -275.212501) (xy 180.220392 -275.170905) (xy 180.197049 -275.125093)
			(xy 180.181161 -275.076194) (xy 180.173118 -275.025412) (xy 179.854735 -275.025412) (xy 179.846978 -275.073142)
			(xy 179.831394 -275.119823) (xy 179.808523 -275.1634) (xy 179.778958 -275.202744) (xy 179.743465 -275.236836)
			(xy 179.702962 -275.264792) (xy 179.6585 -275.28589) (xy 179.611229 -275.299582) (xy 179.562374 -275.305514)
			(xy 179.513199 -275.303533) (xy 179.46498 -275.293689) (xy 179.418964 -275.276237) (xy 179.376343 -275.25163)
			(xy 179.338222 -275.220505) (xy 179.305587 -275.183668) (xy 179.279284 -275.142072) (xy 179.259993 -275.096796)
			(xy 179.248216 -275.049012) (xy 179.244256 -274.999958) (xy 178.926744 -274.999958) (xy 178.92624 -275.025666)
			(xy 178.918197 -275.076448) (xy 178.902309 -275.125347) (xy 178.878966 -275.171159) (xy 178.848745 -275.212755)
			(xy 178.812389 -275.249111) (xy 178.770793 -275.279332) (xy 178.724981 -275.302675) (xy 178.676082 -275.318563)
			(xy 178.6253 -275.326606) (xy 178.573884 -275.326606) (xy 178.523102 -275.318563) (xy 178.474203 -275.302675)
			(xy 178.428391 -275.279332) (xy 178.386795 -275.249111) (xy 178.350439 -275.212755) (xy 178.320218 -275.171159)
			(xy 178.296875 -275.125347) (xy 178.280987 -275.076448) (xy 178.272944 -275.025666) (xy 177.95452 -275.025666)
			(xy 177.946804 -275.073142) (xy 177.93122 -275.119823) (xy 177.908349 -275.1634) (xy 177.878784 -275.202744)
			(xy 177.843291 -275.236836) (xy 177.802788 -275.264792) (xy 177.758326 -275.28589) (xy 177.711055 -275.299582)
			(xy 177.6622 -275.305514) (xy 177.613025 -275.303533) (xy 177.564806 -275.293689) (xy 177.51879 -275.276237)
			(xy 177.476169 -275.25163) (xy 177.438048 -275.220505) (xy 177.405413 -275.183668) (xy 177.37911 -275.142072)
			(xy 177.359819 -275.096796) (xy 177.348042 -275.049012) (xy 177.344082 -274.999958) (xy 177.026819 -274.999958)
			(xy 177.02632 -275.025412) (xy 177.018277 -275.076194) (xy 177.002389 -275.125093) (xy 176.979046 -275.170905)
			(xy 176.948825 -275.212501) (xy 176.912469 -275.248857) (xy 176.870873 -275.279078) (xy 176.825061 -275.302421)
			(xy 176.776162 -275.318309) (xy 176.72538 -275.326352) (xy 176.673964 -275.326352) (xy 176.623182 -275.318309)
			(xy 176.574283 -275.302421) (xy 176.528471 -275.279078) (xy 176.486875 -275.248857) (xy 176.450519 -275.212501)
			(xy 176.420298 -275.170905) (xy 176.396955 -275.125093) (xy 176.381067 -275.076194) (xy 176.373024 -275.025412)
			(xy 176.054641 -275.025412) (xy 176.046884 -275.073142) (xy 176.0313 -275.119823) (xy 176.008429 -275.1634)
			(xy 175.978864 -275.202744) (xy 175.943371 -275.236836) (xy 175.902868 -275.264792) (xy 175.858406 -275.28589)
			(xy 175.811135 -275.299582) (xy 175.76228 -275.305514) (xy 175.713105 -275.303533) (xy 175.664886 -275.293689)
			(xy 175.61887 -275.276237) (xy 175.576249 -275.25163) (xy 175.538128 -275.220505) (xy 175.505493 -275.183668)
			(xy 175.47919 -275.142072) (xy 175.459899 -275.096796) (xy 175.448122 -275.049012) (xy 175.444162 -274.999958)
			(xy 175.127158 -274.999958) (xy 175.126654 -275.025666) (xy 175.118611 -275.076448) (xy 175.102723 -275.125347)
			(xy 175.07938 -275.171159) (xy 175.049159 -275.212755) (xy 175.012803 -275.249111) (xy 174.971207 -275.279332)
			(xy 174.925395 -275.302675) (xy 174.876496 -275.318563) (xy 174.825714 -275.326606) (xy 174.774298 -275.326606)
			(xy 174.723516 -275.318563) (xy 174.674617 -275.302675) (xy 174.628805 -275.279332) (xy 174.587209 -275.249111)
			(xy 174.550853 -275.212755) (xy 174.520632 -275.171159) (xy 174.497289 -275.125347) (xy 174.481401 -275.076448)
			(xy 174.473358 -275.025666) (xy 174.15468 -275.025666) (xy 174.146964 -275.073142) (xy 174.13138 -275.119823)
			(xy 174.108509 -275.1634) (xy 174.078944 -275.202744) (xy 174.043451 -275.236836) (xy 174.002948 -275.264792)
			(xy 173.958486 -275.28589) (xy 173.911215 -275.299582) (xy 173.86236 -275.305514) (xy 173.813185 -275.303533)
			(xy 173.764966 -275.293689) (xy 173.71895 -275.276237) (xy 173.676329 -275.25163) (xy 173.638208 -275.220505)
			(xy 173.605573 -275.183668) (xy 173.57927 -275.142072) (xy 173.559979 -275.096796) (xy 173.548202 -275.049012)
			(xy 173.544242 -274.999958) (xy 173.227238 -274.999958) (xy 173.226734 -275.025666) (xy 173.218691 -275.076448)
			(xy 173.202803 -275.125347) (xy 173.17946 -275.171159) (xy 173.149239 -275.212755) (xy 173.112883 -275.249111)
			(xy 173.071287 -275.279332) (xy 173.025475 -275.302675) (xy 172.976576 -275.318563) (xy 172.925794 -275.326606)
			(xy 172.874378 -275.326606) (xy 172.823596 -275.318563) (xy 172.774697 -275.302675) (xy 172.728885 -275.279332)
			(xy 172.687289 -275.249111) (xy 172.650933 -275.212755) (xy 172.620712 -275.171159) (xy 172.597369 -275.125347)
			(xy 172.581481 -275.076448) (xy 172.573438 -275.025666) (xy 172.254506 -275.025666) (xy 172.24679 -275.073142)
			(xy 172.231206 -275.119823) (xy 172.208335 -275.1634) (xy 172.17877 -275.202744) (xy 172.143277 -275.236836)
			(xy 172.102774 -275.264792) (xy 172.058312 -275.28589) (xy 172.011041 -275.299582) (xy 171.962186 -275.305514)
			(xy 171.913011 -275.303533) (xy 171.864792 -275.293689) (xy 171.818776 -275.276237) (xy 171.776155 -275.25163)
			(xy 171.738034 -275.220505) (xy 171.705399 -275.183668) (xy 171.679096 -275.142072) (xy 171.659805 -275.096796)
			(xy 171.648028 -275.049012) (xy 171.644068 -274.999958) (xy 171.327064 -274.999958) (xy 171.32656 -275.025666)
			(xy 171.318517 -275.076448) (xy 171.302629 -275.125347) (xy 171.279286 -275.171159) (xy 171.249065 -275.212755)
			(xy 171.212709 -275.249111) (xy 171.171113 -275.279332) (xy 171.125301 -275.302675) (xy 171.076402 -275.318563)
			(xy 171.02562 -275.326606) (xy 170.974204 -275.326606) (xy 170.923422 -275.318563) (xy 170.874523 -275.302675)
			(xy 170.828711 -275.279332) (xy 170.787115 -275.249111) (xy 170.750759 -275.212755) (xy 170.720538 -275.171159)
			(xy 170.697195 -275.125347) (xy 170.681307 -275.076448) (xy 170.673264 -275.025666) (xy 170.354586 -275.025666)
			(xy 170.34687 -275.073142) (xy 170.331286 -275.119823) (xy 170.308415 -275.1634) (xy 170.27885 -275.202744)
			(xy 170.243357 -275.236836) (xy 170.202854 -275.264792) (xy 170.158392 -275.28589) (xy 170.111121 -275.299582)
			(xy 170.062266 -275.305514) (xy 170.013091 -275.303533) (xy 169.964872 -275.293689) (xy 169.918856 -275.276237)
			(xy 169.876235 -275.25163) (xy 169.838114 -275.220505) (xy 169.805479 -275.183668) (xy 169.779176 -275.142072)
			(xy 169.759885 -275.096796) (xy 169.748108 -275.049012) (xy 169.744148 -274.999958) (xy 169.427144 -274.999958)
			(xy 169.42664 -275.025666) (xy 169.418597 -275.076448) (xy 169.402709 -275.125347) (xy 169.379366 -275.171159)
			(xy 169.349145 -275.212755) (xy 169.312789 -275.249111) (xy 169.271193 -275.279332) (xy 169.225381 -275.302675)
			(xy 169.176482 -275.318563) (xy 169.1257 -275.326606) (xy 169.074284 -275.326606) (xy 169.023502 -275.318563)
			(xy 168.974603 -275.302675) (xy 168.928791 -275.279332) (xy 168.887195 -275.249111) (xy 168.850839 -275.212755)
			(xy 168.820618 -275.171159) (xy 168.797275 -275.125347) (xy 168.781387 -275.076448) (xy 168.773344 -275.025666)
			(xy 168.454666 -275.025666) (xy 168.44695 -275.073142) (xy 168.431366 -275.119823) (xy 168.408495 -275.1634)
			(xy 168.37893 -275.202744) (xy 168.343437 -275.236836) (xy 168.302934 -275.264792) (xy 168.258472 -275.28589)
			(xy 168.211201 -275.299582) (xy 168.162346 -275.305514) (xy 168.113171 -275.303533) (xy 168.064952 -275.293689)
			(xy 168.018936 -275.276237) (xy 167.976315 -275.25163) (xy 167.938194 -275.220505) (xy 167.905559 -275.183668)
			(xy 167.879256 -275.142072) (xy 167.859965 -275.096796) (xy 167.848188 -275.049012) (xy 167.844228 -274.999958)
			(xy 167.527224 -274.999958) (xy 167.52672 -275.025666) (xy 167.518677 -275.076448) (xy 167.502789 -275.125347)
			(xy 167.479446 -275.171159) (xy 167.449225 -275.212755) (xy 167.412869 -275.249111) (xy 167.371273 -275.279332)
			(xy 167.325461 -275.302675) (xy 167.276562 -275.318563) (xy 167.22578 -275.326606) (xy 167.174364 -275.326606)
			(xy 167.123582 -275.318563) (xy 167.074683 -275.302675) (xy 167.028871 -275.279332) (xy 166.987275 -275.249111)
			(xy 166.950919 -275.212755) (xy 166.920698 -275.171159) (xy 166.897355 -275.125347) (xy 166.881467 -275.076448)
			(xy 166.873424 -275.025666) (xy 166.554492 -275.025666) (xy 166.546776 -275.073142) (xy 166.531192 -275.119823)
			(xy 166.508321 -275.1634) (xy 166.478756 -275.202744) (xy 166.443263 -275.236836) (xy 166.40276 -275.264792)
			(xy 166.358298 -275.28589) (xy 166.311027 -275.299582) (xy 166.262172 -275.305514) (xy 166.212997 -275.303533)
			(xy 166.164778 -275.293689) (xy 166.118762 -275.276237) (xy 166.076141 -275.25163) (xy 166.03802 -275.220505)
			(xy 166.005385 -275.183668) (xy 165.979082 -275.142072) (xy 165.959791 -275.096796) (xy 165.948014 -275.049012)
			(xy 165.944054 -274.999958) (xy 165.62705 -274.999958) (xy 165.626546 -275.025666) (xy 165.618503 -275.076448)
			(xy 165.602615 -275.125347) (xy 165.579272 -275.171159) (xy 165.549051 -275.212755) (xy 165.512695 -275.249111)
			(xy 165.471099 -275.279332) (xy 165.425287 -275.302675) (xy 165.376388 -275.318563) (xy 165.325606 -275.326606)
			(xy 165.27419 -275.326606) (xy 165.223408 -275.318563) (xy 165.174509 -275.302675) (xy 165.128697 -275.279332)
			(xy 165.087101 -275.249111) (xy 165.050745 -275.212755) (xy 165.020524 -275.171159) (xy 164.997181 -275.125347)
			(xy 164.981293 -275.076448) (xy 164.97325 -275.025666) (xy 164.654572 -275.025666) (xy 164.646856 -275.073142)
			(xy 164.631272 -275.119823) (xy 164.608401 -275.1634) (xy 164.578836 -275.202744) (xy 164.543343 -275.236836)
			(xy 164.50284 -275.264792) (xy 164.458378 -275.28589) (xy 164.411107 -275.299582) (xy 164.362252 -275.305514)
			(xy 164.313077 -275.303533) (xy 164.264858 -275.293689) (xy 164.218842 -275.276237) (xy 164.176221 -275.25163)
			(xy 164.1381 -275.220505) (xy 164.105465 -275.183668) (xy 164.079162 -275.142072) (xy 164.059871 -275.096796)
			(xy 164.048094 -275.049012) (xy 164.044134 -274.999958) (xy 163.72713 -274.999958) (xy 163.726626 -275.025666)
			(xy 163.718583 -275.076448) (xy 163.702695 -275.125347) (xy 163.679352 -275.171159) (xy 163.649131 -275.212755)
			(xy 163.612775 -275.249111) (xy 163.571179 -275.279332) (xy 163.525367 -275.302675) (xy 163.476468 -275.318563)
			(xy 163.425686 -275.326606) (xy 163.37427 -275.326606) (xy 163.323488 -275.318563) (xy 163.274589 -275.302675)
			(xy 163.228777 -275.279332) (xy 163.187181 -275.249111) (xy 163.150825 -275.212755) (xy 163.120604 -275.171159)
			(xy 163.097261 -275.125347) (xy 163.081373 -275.076448) (xy 163.07333 -275.025666) (xy 162.754652 -275.025666)
			(xy 162.746936 -275.073142) (xy 162.731352 -275.119823) (xy 162.708481 -275.1634) (xy 162.678916 -275.202744)
			(xy 162.643423 -275.236836) (xy 162.60292 -275.264792) (xy 162.558458 -275.28589) (xy 162.511187 -275.299582)
			(xy 162.462332 -275.305514) (xy 162.413157 -275.303533) (xy 162.364938 -275.293689) (xy 162.318922 -275.276237)
			(xy 162.276301 -275.25163) (xy 162.23818 -275.220505) (xy 162.205545 -275.183668) (xy 162.179242 -275.142072)
			(xy 162.159951 -275.096796) (xy 162.148174 -275.049012) (xy 162.144214 -274.999958) (xy 161.82721 -274.999958)
			(xy 161.826706 -275.025666) (xy 161.818663 -275.076448) (xy 161.802775 -275.125347) (xy 161.779432 -275.171159)
			(xy 161.749211 -275.212755) (xy 161.712855 -275.249111) (xy 161.671259 -275.279332) (xy 161.625447 -275.302675)
			(xy 161.576548 -275.318563) (xy 161.525766 -275.326606) (xy 161.47435 -275.326606) (xy 161.423568 -275.318563)
			(xy 161.374669 -275.302675) (xy 161.328857 -275.279332) (xy 161.287261 -275.249111) (xy 161.250905 -275.212755)
			(xy 161.220684 -275.171159) (xy 161.197341 -275.125347) (xy 161.181453 -275.076448) (xy 161.17341 -275.025666)
			(xy 160.854478 -275.025666) (xy 160.846762 -275.073142) (xy 160.831178 -275.119823) (xy 160.808307 -275.1634)
			(xy 160.778742 -275.202744) (xy 160.743249 -275.236836) (xy 160.702746 -275.264792) (xy 160.658284 -275.28589)
			(xy 160.611013 -275.299582) (xy 160.562158 -275.305514) (xy 160.512983 -275.303533) (xy 160.464764 -275.293689)
			(xy 160.418748 -275.276237) (xy 160.376127 -275.25163) (xy 160.338006 -275.220505) (xy 160.305371 -275.183668)
			(xy 160.279068 -275.142072) (xy 160.259777 -275.096796) (xy 160.248 -275.049012) (xy 160.24404 -274.999958)
			(xy 148.149224 -274.999958) (xy 148.125304 -275.014431) (xy 147.954378 -275.10849) (xy 147.779735 -275.195452)
			(xy 147.601669 -275.27517) (xy 147.420481 -275.347511) (xy 147.236475 -275.412352) (xy 147.049962 -275.469584)
			(xy 147.029562 -275.474938) (xy 152.169126 -275.474938) (xy 152.173086 -275.425884) (xy 152.184863 -275.3781)
			(xy 152.204154 -275.332824) (xy 152.230457 -275.291228) (xy 152.263092 -275.254391) (xy 152.301213 -275.223266)
			(xy 152.343834 -275.198659) (xy 152.38985 -275.181207) (xy 152.438069 -275.171363) (xy 152.487244 -275.169382)
			(xy 152.536099 -275.175314) (xy 152.58337 -275.189006) (xy 152.627832 -275.210104) (xy 152.668335 -275.23806)
			(xy 152.703828 -275.272152) (xy 152.733393 -275.311496) (xy 152.756264 -275.355073) (xy 152.771848 -275.401754)
			(xy 152.779743 -275.450331) (xy 152.780238 -275.474938) (xy 153.119086 -275.474938) (xy 153.123046 -275.425884)
			(xy 153.134823 -275.3781) (xy 153.154114 -275.332824) (xy 153.180417 -275.291228) (xy 153.213052 -275.254391)
			(xy 153.251173 -275.223266) (xy 153.293794 -275.198659) (xy 153.33981 -275.181207) (xy 153.388029 -275.171363)
			(xy 153.437204 -275.169382) (xy 153.486059 -275.175314) (xy 153.53333 -275.189006) (xy 153.577792 -275.210104)
			(xy 153.618295 -275.23806) (xy 153.653788 -275.272152) (xy 153.683353 -275.311496) (xy 153.706224 -275.355073)
			(xy 153.721808 -275.401754) (xy 153.729703 -275.450331) (xy 153.730198 -275.474938) (xy 154.0693 -275.474938)
			(xy 154.07326 -275.425884) (xy 154.085037 -275.3781) (xy 154.104328 -275.332824) (xy 154.130631 -275.291228)
			(xy 154.163266 -275.254391) (xy 154.201387 -275.223266) (xy 154.244008 -275.198659) (xy 154.290024 -275.181207)
			(xy 154.338243 -275.171363) (xy 154.387418 -275.169382) (xy 154.436273 -275.175314) (xy 154.483544 -275.189006)
			(xy 154.528006 -275.210104) (xy 154.568509 -275.23806) (xy 154.604002 -275.272152) (xy 154.633567 -275.311496)
			(xy 154.656438 -275.355073) (xy 154.672022 -275.401754) (xy 154.679917 -275.450331) (xy 154.680412 -275.474938)
			(xy 155.01926 -275.474938) (xy 155.02322 -275.425884) (xy 155.034997 -275.3781) (xy 155.054288 -275.332824)
			(xy 155.080591 -275.291228) (xy 155.113226 -275.254391) (xy 155.151347 -275.223266) (xy 155.193968 -275.198659)
			(xy 155.239984 -275.181207) (xy 155.288203 -275.171363) (xy 155.337378 -275.169382) (xy 155.386233 -275.175314)
			(xy 155.433504 -275.189006) (xy 155.477966 -275.210104) (xy 155.518469 -275.23806) (xy 155.553962 -275.272152)
			(xy 155.583527 -275.311496) (xy 155.606398 -275.355073) (xy 155.621982 -275.401754) (xy 155.629877 -275.450331)
			(xy 155.630372 -275.474938) (xy 155.96922 -275.474938) (xy 155.97318 -275.425884) (xy 155.984957 -275.3781)
			(xy 156.004248 -275.332824) (xy 156.030551 -275.291228) (xy 156.063186 -275.254391) (xy 156.101307 -275.223266)
			(xy 156.143928 -275.198659) (xy 156.189944 -275.181207) (xy 156.238163 -275.171363) (xy 156.287338 -275.169382)
			(xy 156.336193 -275.175314) (xy 156.383464 -275.189006) (xy 156.427926 -275.210104) (xy 156.468429 -275.23806)
			(xy 156.503922 -275.272152) (xy 156.533487 -275.311496) (xy 156.556358 -275.355073) (xy 156.571942 -275.401754)
			(xy 156.579837 -275.450331) (xy 156.580332 -275.474938) (xy 156.91918 -275.474938) (xy 156.92314 -275.425884)
			(xy 156.934917 -275.3781) (xy 156.954208 -275.332824) (xy 156.980511 -275.291228) (xy 157.013146 -275.254391)
			(xy 157.051267 -275.223266) (xy 157.093888 -275.198659) (xy 157.139904 -275.181207) (xy 157.188123 -275.171363)
			(xy 157.237298 -275.169382) (xy 157.286153 -275.175314) (xy 157.333424 -275.189006) (xy 157.377886 -275.210104)
			(xy 157.418389 -275.23806) (xy 157.453882 -275.272152) (xy 157.483447 -275.311496) (xy 157.506318 -275.355073)
			(xy 157.521902 -275.401754) (xy 157.529797 -275.450331) (xy 157.530292 -275.474938) (xy 157.86914 -275.474938)
			(xy 157.8731 -275.425884) (xy 157.884877 -275.3781) (xy 157.904168 -275.332824) (xy 157.930471 -275.291228)
			(xy 157.963106 -275.254391) (xy 158.001227 -275.223266) (xy 158.043848 -275.198659) (xy 158.089864 -275.181207)
			(xy 158.138083 -275.171363) (xy 158.187258 -275.169382) (xy 158.236113 -275.175314) (xy 158.283384 -275.189006)
			(xy 158.327846 -275.210104) (xy 158.368349 -275.23806) (xy 158.403842 -275.272152) (xy 158.433407 -275.311496)
			(xy 158.456278 -275.355073) (xy 158.471862 -275.401754) (xy 158.479757 -275.450331) (xy 158.480252 -275.474938)
			(xy 158.8191 -275.474938) (xy 158.82306 -275.425884) (xy 158.834837 -275.3781) (xy 158.854128 -275.332824)
			(xy 158.880431 -275.291228) (xy 158.913066 -275.254391) (xy 158.951187 -275.223266) (xy 158.993808 -275.198659)
			(xy 159.039824 -275.181207) (xy 159.088043 -275.171363) (xy 159.137218 -275.169382) (xy 159.186073 -275.175314)
			(xy 159.233344 -275.189006) (xy 159.277806 -275.210104) (xy 159.318309 -275.23806) (xy 159.353802 -275.272152)
			(xy 159.383367 -275.311496) (xy 159.406238 -275.355073) (xy 159.421822 -275.401754) (xy 159.429717 -275.450331)
			(xy 159.430212 -275.474938) (xy 159.429717 -275.499545) (xy 159.421822 -275.548122) (xy 159.406238 -275.594803)
			(xy 159.383367 -275.63838) (xy 159.353802 -275.677724) (xy 159.318309 -275.711816) (xy 159.277806 -275.739772)
			(xy 159.233344 -275.76087) (xy 159.186073 -275.774562) (xy 159.137218 -275.780494) (xy 159.088043 -275.778513)
			(xy 159.039824 -275.768669) (xy 158.993808 -275.751217) (xy 158.951187 -275.72661) (xy 158.913066 -275.695485)
			(xy 158.880431 -275.658648) (xy 158.854128 -275.617052) (xy 158.834837 -275.571776) (xy 158.82306 -275.523992)
			(xy 158.8191 -275.474938) (xy 158.480252 -275.474938) (xy 158.479757 -275.499545) (xy 158.471862 -275.548122)
			(xy 158.456278 -275.594803) (xy 158.433407 -275.63838) (xy 158.403842 -275.677724) (xy 158.368349 -275.711816)
			(xy 158.327846 -275.739772) (xy 158.283384 -275.76087) (xy 158.236113 -275.774562) (xy 158.187258 -275.780494)
			(xy 158.138083 -275.778513) (xy 158.089864 -275.768669) (xy 158.043848 -275.751217) (xy 158.001227 -275.72661)
			(xy 157.963106 -275.695485) (xy 157.930471 -275.658648) (xy 157.904168 -275.617052) (xy 157.884877 -275.571776)
			(xy 157.8731 -275.523992) (xy 157.86914 -275.474938) (xy 157.530292 -275.474938) (xy 157.529797 -275.499545)
			(xy 157.521902 -275.548122) (xy 157.506318 -275.594803) (xy 157.483447 -275.63838) (xy 157.453882 -275.677724)
			(xy 157.418389 -275.711816) (xy 157.377886 -275.739772) (xy 157.333424 -275.76087) (xy 157.286153 -275.774562)
			(xy 157.237298 -275.780494) (xy 157.188123 -275.778513) (xy 157.139904 -275.768669) (xy 157.093888 -275.751217)
			(xy 157.051267 -275.72661) (xy 157.013146 -275.695485) (xy 156.980511 -275.658648) (xy 156.954208 -275.617052)
			(xy 156.934917 -275.571776) (xy 156.92314 -275.523992) (xy 156.91918 -275.474938) (xy 156.580332 -275.474938)
			(xy 156.579837 -275.499545) (xy 156.571942 -275.548122) (xy 156.556358 -275.594803) (xy 156.533487 -275.63838)
			(xy 156.503922 -275.677724) (xy 156.468429 -275.711816) (xy 156.427926 -275.739772) (xy 156.383464 -275.76087)
			(xy 156.336193 -275.774562) (xy 156.287338 -275.780494) (xy 156.238163 -275.778513) (xy 156.189944 -275.768669)
			(xy 156.143928 -275.751217) (xy 156.101307 -275.72661) (xy 156.063186 -275.695485) (xy 156.030551 -275.658648)
			(xy 156.004248 -275.617052) (xy 155.984957 -275.571776) (xy 155.97318 -275.523992) (xy 155.96922 -275.474938)
			(xy 155.630372 -275.474938) (xy 155.629877 -275.499545) (xy 155.621982 -275.548122) (xy 155.606398 -275.594803)
			(xy 155.583527 -275.63838) (xy 155.553962 -275.677724) (xy 155.518469 -275.711816) (xy 155.477966 -275.739772)
			(xy 155.433504 -275.76087) (xy 155.386233 -275.774562) (xy 155.337378 -275.780494) (xy 155.288203 -275.778513)
			(xy 155.239984 -275.768669) (xy 155.193968 -275.751217) (xy 155.151347 -275.72661) (xy 155.113226 -275.695485)
			(xy 155.080591 -275.658648) (xy 155.054288 -275.617052) (xy 155.034997 -275.571776) (xy 155.02322 -275.523992)
			(xy 155.01926 -275.474938) (xy 154.680412 -275.474938) (xy 154.679917 -275.499545) (xy 154.672022 -275.548122)
			(xy 154.656438 -275.594803) (xy 154.633567 -275.63838) (xy 154.604002 -275.677724) (xy 154.568509 -275.711816)
			(xy 154.528006 -275.739772) (xy 154.483544 -275.76087) (xy 154.436273 -275.774562) (xy 154.387418 -275.780494)
			(xy 154.338243 -275.778513) (xy 154.290024 -275.768669) (xy 154.244008 -275.751217) (xy 154.201387 -275.72661)
			(xy 154.163266 -275.695485) (xy 154.130631 -275.658648) (xy 154.104328 -275.617052) (xy 154.085037 -275.571776)
			(xy 154.07326 -275.523992) (xy 154.0693 -275.474938) (xy 153.730198 -275.474938) (xy 153.729703 -275.499545)
			(xy 153.721808 -275.548122) (xy 153.706224 -275.594803) (xy 153.683353 -275.63838) (xy 153.653788 -275.677724)
			(xy 153.618295 -275.711816) (xy 153.577792 -275.739772) (xy 153.53333 -275.76087) (xy 153.486059 -275.774562)
			(xy 153.437204 -275.780494) (xy 153.388029 -275.778513) (xy 153.33981 -275.768669) (xy 153.293794 -275.751217)
			(xy 153.251173 -275.72661) (xy 153.213052 -275.695485) (xy 153.180417 -275.658648) (xy 153.154114 -275.617052)
			(xy 153.134823 -275.571776) (xy 153.123046 -275.523992) (xy 153.119086 -275.474938) (xy 152.780238 -275.474938)
			(xy 152.779743 -275.499545) (xy 152.771848 -275.548122) (xy 152.756264 -275.594803) (xy 152.733393 -275.63838)
			(xy 152.703828 -275.677724) (xy 152.668335 -275.711816) (xy 152.627832 -275.739772) (xy 152.58337 -275.76087)
			(xy 152.536099 -275.774562) (xy 152.487244 -275.780494) (xy 152.438069 -275.778513) (xy 152.38985 -275.768669)
			(xy 152.343834 -275.751217) (xy 152.301213 -275.72661) (xy 152.263092 -275.695485) (xy 152.230457 -275.658648)
			(xy 152.204154 -275.617052) (xy 152.184863 -275.571776) (xy 152.173086 -275.523992) (xy 152.169126 -275.474938)
			(xy 147.029562 -275.474938) (xy 146.861257 -275.519111) (xy 146.670678 -275.560848) (xy 146.478545 -275.594726)
			(xy 146.285184 -275.620688) (xy 146.09092 -275.638689) (xy 145.896081 -275.6487) (xy 145.700995 -275.650703)
			(xy 145.505992 -275.644695) (xy 145.311399 -275.630686) (xy 145.117546 -275.6087) (xy 144.924759 -275.578774)
			(xy 144.733362 -275.540958) (xy 144.54368 -275.495316) (xy 144.356032 -275.441926) (xy 144.170733 -275.380876)
			(xy 143.988098 -275.312271) (xy 143.808433 -275.236225) (xy 143.632041 -275.152867) (xy 143.45922 -275.062338)
			(xy 143.290262 -274.96479) (xy 143.125451 -274.860387) (xy 142.965065 -274.749307) (xy 142.809375 -274.631735)
			(xy 142.658643 -274.507871) (xy 142.513124 -274.377922) (xy 142.373062 -274.242109) (xy 142.238694 -274.10066)
			(xy 142.110247 -273.953814) (xy 141.987936 -273.801819) (xy 141.871969 -273.64493) (xy 141.762541 -273.483412)
			(xy 141.659836 -273.317538) (xy 141.564028 -273.147587) (xy 141.475277 -272.973846) (xy 141.393735 -272.796608)
			(xy 141.319538 -272.616172) (xy 141.252811 -272.432841) (xy 141.193667 -272.246926) (xy 141.142206 -272.058739)
			(xy 141.098514 -271.868599) (xy 141.062665 -271.676824) (xy 141.03472 -271.48374) (xy 141.014725 -271.289671)
			(xy 141.002715 -271.094945) (xy 140.998709 -270.89989) (xy 136.94918 -270.89989) (xy 136.94918 -272.663666)
			(xy 136.949713 -272.675159) (xy 136.959703 -272.695861) (xy 136.977708 -272.71015) (xy 136.988804 -272.713196)
			(xy 137.068204 -272.731485) (xy 137.225315 -272.774733) (xy 137.380159 -272.825506) (xy 137.532374 -272.883684)
			(xy 137.681608 -272.949133) (xy 137.827514 -273.021701) (xy 137.969751 -273.101218) (xy 138.107989 -273.1875)
			(xy 138.241906 -273.280347) (xy 138.371192 -273.379541) (xy 138.495545 -273.484853) (xy 138.614677 -273.596038)
			(xy 138.72831 -273.712837) (xy 138.83618 -273.834978) (xy 138.938036 -273.962178) (xy 139.033641 -274.09414)
			(xy 139.122773 -274.230558) (xy 139.205225 -274.371114) (xy 139.280804 -274.515482) (xy 139.349336 -274.663325)
			(xy 139.410661 -274.814301) (xy 139.464635 -274.968058) (xy 139.511135 -275.124238) (xy 139.55005 -275.282478)
			(xy 139.581292 -275.44241) (xy 139.604787 -275.603663) (xy 139.620481 -275.76586) (xy 139.628337 -275.928626)
			(xy 139.628337 -275.949918) (xy 160.24404 -275.949918) (xy 160.248 -275.900864) (xy 160.259777 -275.85308)
			(xy 160.279068 -275.807804) (xy 160.305371 -275.766208) (xy 160.338006 -275.729371) (xy 160.376127 -275.698246)
			(xy 160.418748 -275.673639) (xy 160.464764 -275.656187) (xy 160.512983 -275.646343) (xy 160.562158 -275.644362)
			(xy 160.611013 -275.650294) (xy 160.658284 -275.663986) (xy 160.702746 -275.685084) (xy 160.743249 -275.71304)
			(xy 160.778742 -275.747132) (xy 160.808307 -275.786476) (xy 160.831178 -275.830053) (xy 160.846762 -275.876734)
			(xy 160.854657 -275.925311) (xy 160.855152 -275.949918) (xy 160.854657 -275.974525) (xy 160.854478 -275.975626)
			(xy 161.17341 -275.975626) (xy 161.17341 -275.92421) (xy 161.181453 -275.873428) (xy 161.197341 -275.824529)
			(xy 161.220684 -275.778717) (xy 161.250905 -275.737121) (xy 161.287261 -275.700765) (xy 161.328857 -275.670544)
			(xy 161.374669 -275.647201) (xy 161.423568 -275.631313) (xy 161.47435 -275.62327) (xy 161.525766 -275.62327)
			(xy 161.576548 -275.631313) (xy 161.625447 -275.647201) (xy 161.671259 -275.670544) (xy 161.712855 -275.700765)
			(xy 161.749211 -275.737121) (xy 161.779432 -275.778717) (xy 161.802775 -275.824529) (xy 161.818663 -275.873428)
			(xy 161.826706 -275.92421) (xy 161.82721 -275.949918) (xy 162.144214 -275.949918) (xy 162.148174 -275.900864)
			(xy 162.159951 -275.85308) (xy 162.179242 -275.807804) (xy 162.205545 -275.766208) (xy 162.23818 -275.729371)
			(xy 162.276301 -275.698246) (xy 162.318922 -275.673639) (xy 162.364938 -275.656187) (xy 162.413157 -275.646343)
			(xy 162.462332 -275.644362) (xy 162.511187 -275.650294) (xy 162.558458 -275.663986) (xy 162.60292 -275.685084)
			(xy 162.643423 -275.71304) (xy 162.678916 -275.747132) (xy 162.708481 -275.786476) (xy 162.731352 -275.830053)
			(xy 162.746936 -275.876734) (xy 162.754831 -275.925311) (xy 162.755326 -275.949918) (xy 162.754831 -275.974525)
			(xy 162.754652 -275.975626) (xy 163.07333 -275.975626) (xy 163.07333 -275.92421) (xy 163.081373 -275.873428)
			(xy 163.097261 -275.824529) (xy 163.120604 -275.778717) (xy 163.150825 -275.737121) (xy 163.187181 -275.700765)
			(xy 163.228777 -275.670544) (xy 163.274589 -275.647201) (xy 163.323488 -275.631313) (xy 163.37427 -275.62327)
			(xy 163.425686 -275.62327) (xy 163.476468 -275.631313) (xy 163.525367 -275.647201) (xy 163.571179 -275.670544)
			(xy 163.612775 -275.700765) (xy 163.649131 -275.737121) (xy 163.679352 -275.778717) (xy 163.702695 -275.824529)
			(xy 163.718583 -275.873428) (xy 163.726626 -275.92421) (xy 163.72713 -275.949918) (xy 164.044134 -275.949918)
			(xy 164.048094 -275.900864) (xy 164.059871 -275.85308) (xy 164.079162 -275.807804) (xy 164.105465 -275.766208)
			(xy 164.1381 -275.729371) (xy 164.176221 -275.698246) (xy 164.218842 -275.673639) (xy 164.264858 -275.656187)
			(xy 164.313077 -275.646343) (xy 164.362252 -275.644362) (xy 164.411107 -275.650294) (xy 164.458378 -275.663986)
			(xy 164.50284 -275.685084) (xy 164.543343 -275.71304) (xy 164.578836 -275.747132) (xy 164.608401 -275.786476)
			(xy 164.631272 -275.830053) (xy 164.646856 -275.876734) (xy 164.654751 -275.925311) (xy 164.655246 -275.949918)
			(xy 164.654751 -275.974525) (xy 164.654572 -275.975626) (xy 164.97325 -275.975626) (xy 164.97325 -275.92421)
			(xy 164.981293 -275.873428) (xy 164.997181 -275.824529) (xy 165.020524 -275.778717) (xy 165.050745 -275.737121)
			(xy 165.087101 -275.700765) (xy 165.128697 -275.670544) (xy 165.174509 -275.647201) (xy 165.223408 -275.631313)
			(xy 165.27419 -275.62327) (xy 165.325606 -275.62327) (xy 165.376388 -275.631313) (xy 165.425287 -275.647201)
			(xy 165.471099 -275.670544) (xy 165.512695 -275.700765) (xy 165.549051 -275.737121) (xy 165.579272 -275.778717)
			(xy 165.602615 -275.824529) (xy 165.618503 -275.873428) (xy 165.626546 -275.92421) (xy 165.62705 -275.949918)
			(xy 165.944054 -275.949918) (xy 165.948014 -275.900864) (xy 165.959791 -275.85308) (xy 165.979082 -275.807804)
			(xy 166.005385 -275.766208) (xy 166.03802 -275.729371) (xy 166.076141 -275.698246) (xy 166.118762 -275.673639)
			(xy 166.164778 -275.656187) (xy 166.212997 -275.646343) (xy 166.262172 -275.644362) (xy 166.311027 -275.650294)
			(xy 166.358298 -275.663986) (xy 166.40276 -275.685084) (xy 166.443263 -275.71304) (xy 166.478756 -275.747132)
			(xy 166.508321 -275.786476) (xy 166.531192 -275.830053) (xy 166.546776 -275.876734) (xy 166.554671 -275.925311)
			(xy 166.555166 -275.949918) (xy 166.554671 -275.974525) (xy 166.554492 -275.975626) (xy 166.873424 -275.975626)
			(xy 166.873424 -275.92421) (xy 166.881467 -275.873428) (xy 166.897355 -275.824529) (xy 166.920698 -275.778717)
			(xy 166.950919 -275.737121) (xy 166.987275 -275.700765) (xy 167.028871 -275.670544) (xy 167.074683 -275.647201)
			(xy 167.123582 -275.631313) (xy 167.174364 -275.62327) (xy 167.22578 -275.62327) (xy 167.276562 -275.631313)
			(xy 167.325461 -275.647201) (xy 167.371273 -275.670544) (xy 167.412869 -275.700765) (xy 167.449225 -275.737121)
			(xy 167.479446 -275.778717) (xy 167.502789 -275.824529) (xy 167.518677 -275.873428) (xy 167.52672 -275.92421)
			(xy 167.527224 -275.949918) (xy 167.844228 -275.949918) (xy 167.848188 -275.900864) (xy 167.859965 -275.85308)
			(xy 167.879256 -275.807804) (xy 167.905559 -275.766208) (xy 167.938194 -275.729371) (xy 167.976315 -275.698246)
			(xy 168.018936 -275.673639) (xy 168.064952 -275.656187) (xy 168.113171 -275.646343) (xy 168.162346 -275.644362)
			(xy 168.211201 -275.650294) (xy 168.258472 -275.663986) (xy 168.302934 -275.685084) (xy 168.343437 -275.71304)
			(xy 168.37893 -275.747132) (xy 168.408495 -275.786476) (xy 168.431366 -275.830053) (xy 168.44695 -275.876734)
			(xy 168.454845 -275.925311) (xy 168.45534 -275.949918) (xy 168.454845 -275.974525) (xy 168.454666 -275.975626)
			(xy 168.773344 -275.975626) (xy 168.773344 -275.92421) (xy 168.781387 -275.873428) (xy 168.797275 -275.824529)
			(xy 168.820618 -275.778717) (xy 168.850839 -275.737121) (xy 168.887195 -275.700765) (xy 168.928791 -275.670544)
			(xy 168.974603 -275.647201) (xy 169.023502 -275.631313) (xy 169.074284 -275.62327) (xy 169.1257 -275.62327)
			(xy 169.176482 -275.631313) (xy 169.225381 -275.647201) (xy 169.271193 -275.670544) (xy 169.312789 -275.700765)
			(xy 169.349145 -275.737121) (xy 169.379366 -275.778717) (xy 169.402709 -275.824529) (xy 169.418597 -275.873428)
			(xy 169.42664 -275.92421) (xy 169.427144 -275.949918) (xy 169.744148 -275.949918) (xy 169.748108 -275.900864)
			(xy 169.759885 -275.85308) (xy 169.779176 -275.807804) (xy 169.805479 -275.766208) (xy 169.838114 -275.729371)
			(xy 169.876235 -275.698246) (xy 169.918856 -275.673639) (xy 169.964872 -275.656187) (xy 170.013091 -275.646343)
			(xy 170.062266 -275.644362) (xy 170.111121 -275.650294) (xy 170.158392 -275.663986) (xy 170.202854 -275.685084)
			(xy 170.243357 -275.71304) (xy 170.27885 -275.747132) (xy 170.308415 -275.786476) (xy 170.331286 -275.830053)
			(xy 170.34687 -275.876734) (xy 170.354765 -275.925311) (xy 170.35526 -275.949918) (xy 170.354765 -275.974525)
			(xy 170.354586 -275.975626) (xy 170.673264 -275.975626) (xy 170.673264 -275.92421) (xy 170.681307 -275.873428)
			(xy 170.697195 -275.824529) (xy 170.720538 -275.778717) (xy 170.750759 -275.737121) (xy 170.787115 -275.700765)
			(xy 170.828711 -275.670544) (xy 170.874523 -275.647201) (xy 170.923422 -275.631313) (xy 170.974204 -275.62327)
			(xy 171.02562 -275.62327) (xy 171.076402 -275.631313) (xy 171.125301 -275.647201) (xy 171.171113 -275.670544)
			(xy 171.212709 -275.700765) (xy 171.249065 -275.737121) (xy 171.279286 -275.778717) (xy 171.302629 -275.824529)
			(xy 171.318517 -275.873428) (xy 171.32656 -275.92421) (xy 171.327064 -275.949918) (xy 171.644068 -275.949918)
			(xy 171.648028 -275.900864) (xy 171.659805 -275.85308) (xy 171.679096 -275.807804) (xy 171.705399 -275.766208)
			(xy 171.738034 -275.729371) (xy 171.776155 -275.698246) (xy 171.818776 -275.673639) (xy 171.864792 -275.656187)
			(xy 171.913011 -275.646343) (xy 171.962186 -275.644362) (xy 172.011041 -275.650294) (xy 172.058312 -275.663986)
			(xy 172.102774 -275.685084) (xy 172.143277 -275.71304) (xy 172.17877 -275.747132) (xy 172.208335 -275.786476)
			(xy 172.231206 -275.830053) (xy 172.24679 -275.876734) (xy 172.254685 -275.925311) (xy 172.25518 -275.949918)
			(xy 172.254685 -275.974525) (xy 172.254506 -275.975626) (xy 172.573438 -275.975626) (xy 172.573438 -275.92421)
			(xy 172.581481 -275.873428) (xy 172.597369 -275.824529) (xy 172.620712 -275.778717) (xy 172.650933 -275.737121)
			(xy 172.687289 -275.700765) (xy 172.728885 -275.670544) (xy 172.774697 -275.647201) (xy 172.823596 -275.631313)
			(xy 172.874378 -275.62327) (xy 172.925794 -275.62327) (xy 172.976576 -275.631313) (xy 173.025475 -275.647201)
			(xy 173.071287 -275.670544) (xy 173.112883 -275.700765) (xy 173.149239 -275.737121) (xy 173.17946 -275.778717)
			(xy 173.202803 -275.824529) (xy 173.218691 -275.873428) (xy 173.226734 -275.92421) (xy 173.227238 -275.949918)
			(xy 173.544242 -275.949918) (xy 173.548202 -275.900864) (xy 173.559979 -275.85308) (xy 173.57927 -275.807804)
			(xy 173.605573 -275.766208) (xy 173.638208 -275.729371) (xy 173.676329 -275.698246) (xy 173.71895 -275.673639)
			(xy 173.764966 -275.656187) (xy 173.813185 -275.646343) (xy 173.86236 -275.644362) (xy 173.911215 -275.650294)
			(xy 173.958486 -275.663986) (xy 174.002948 -275.685084) (xy 174.043451 -275.71304) (xy 174.078944 -275.747132)
			(xy 174.108509 -275.786476) (xy 174.13138 -275.830053) (xy 174.146964 -275.876734) (xy 174.154859 -275.925311)
			(xy 174.155354 -275.949918) (xy 174.154859 -275.974525) (xy 174.15468 -275.975626) (xy 174.473358 -275.975626)
			(xy 174.473358 -275.92421) (xy 174.481401 -275.873428) (xy 174.497289 -275.824529) (xy 174.520632 -275.778717)
			(xy 174.550853 -275.737121) (xy 174.587209 -275.700765) (xy 174.628805 -275.670544) (xy 174.674617 -275.647201)
			(xy 174.723516 -275.631313) (xy 174.774298 -275.62327) (xy 174.825714 -275.62327) (xy 174.876496 -275.631313)
			(xy 174.925395 -275.647201) (xy 174.971207 -275.670544) (xy 175.012803 -275.700765) (xy 175.049159 -275.737121)
			(xy 175.07938 -275.778717) (xy 175.102723 -275.824529) (xy 175.118611 -275.873428) (xy 175.126654 -275.92421)
			(xy 175.127158 -275.949918) (xy 175.444162 -275.949918) (xy 175.448122 -275.900864) (xy 175.459899 -275.85308)
			(xy 175.47919 -275.807804) (xy 175.505493 -275.766208) (xy 175.538128 -275.729371) (xy 175.576249 -275.698246)
			(xy 175.61887 -275.673639) (xy 175.664886 -275.656187) (xy 175.713105 -275.646343) (xy 175.76228 -275.644362)
			(xy 175.811135 -275.650294) (xy 175.858406 -275.663986) (xy 175.902868 -275.685084) (xy 175.943371 -275.71304)
			(xy 175.978864 -275.747132) (xy 176.008429 -275.786476) (xy 176.0313 -275.830053) (xy 176.046884 -275.876734)
			(xy 176.054779 -275.925311) (xy 176.055274 -275.949918) (xy 176.054779 -275.974525) (xy 176.054641 -275.975372)
			(xy 176.373024 -275.975372) (xy 176.373024 -275.923956) (xy 176.381067 -275.873174) (xy 176.396955 -275.824275)
			(xy 176.420298 -275.778463) (xy 176.450519 -275.736867) (xy 176.486875 -275.700511) (xy 176.528471 -275.67029)
			(xy 176.574283 -275.646947) (xy 176.623182 -275.631059) (xy 176.673964 -275.623016) (xy 176.72538 -275.623016)
			(xy 176.776162 -275.631059) (xy 176.825061 -275.646947) (xy 176.870873 -275.67029) (xy 176.912469 -275.700511)
			(xy 176.948825 -275.736867) (xy 176.979046 -275.778463) (xy 177.002389 -275.824275) (xy 177.018277 -275.873174)
			(xy 177.02632 -275.923956) (xy 177.026824 -275.949664) (xy 177.026819 -275.949918) (xy 177.344082 -275.949918)
			(xy 177.348042 -275.900864) (xy 177.359819 -275.85308) (xy 177.37911 -275.807804) (xy 177.405413 -275.766208)
			(xy 177.438048 -275.729371) (xy 177.476169 -275.698246) (xy 177.51879 -275.673639) (xy 177.564806 -275.656187)
			(xy 177.613025 -275.646343) (xy 177.6622 -275.644362) (xy 177.711055 -275.650294) (xy 177.758326 -275.663986)
			(xy 177.802788 -275.685084) (xy 177.843291 -275.71304) (xy 177.878784 -275.747132) (xy 177.908349 -275.786476)
			(xy 177.93122 -275.830053) (xy 177.946804 -275.876734) (xy 177.954699 -275.925311) (xy 177.955194 -275.949918)
			(xy 177.954699 -275.974525) (xy 177.95452 -275.975626) (xy 178.272944 -275.975626) (xy 178.272944 -275.92421)
			(xy 178.280987 -275.873428) (xy 178.296875 -275.824529) (xy 178.320218 -275.778717) (xy 178.350439 -275.737121)
			(xy 178.386795 -275.700765) (xy 178.428391 -275.670544) (xy 178.474203 -275.647201) (xy 178.523102 -275.631313)
			(xy 178.573884 -275.62327) (xy 178.6253 -275.62327) (xy 178.676082 -275.631313) (xy 178.724981 -275.647201)
			(xy 178.770793 -275.670544) (xy 178.812389 -275.700765) (xy 178.848745 -275.737121) (xy 178.878966 -275.778717)
			(xy 178.902309 -275.824529) (xy 178.918197 -275.873428) (xy 178.92624 -275.92421) (xy 178.926744 -275.949918)
			(xy 179.244256 -275.949918) (xy 179.248216 -275.900864) (xy 179.259993 -275.85308) (xy 179.279284 -275.807804)
			(xy 179.305587 -275.766208) (xy 179.338222 -275.729371) (xy 179.376343 -275.698246) (xy 179.418964 -275.673639)
			(xy 179.46498 -275.656187) (xy 179.513199 -275.646343) (xy 179.562374 -275.644362) (xy 179.611229 -275.650294)
			(xy 179.6585 -275.663986) (xy 179.702962 -275.685084) (xy 179.743465 -275.71304) (xy 179.778958 -275.747132)
			(xy 179.808523 -275.786476) (xy 179.831394 -275.830053) (xy 179.846978 -275.876734) (xy 179.854873 -275.925311)
			(xy 179.855368 -275.949918) (xy 179.854873 -275.974525) (xy 179.854735 -275.975372) (xy 180.173118 -275.975372)
			(xy 180.173118 -275.923956) (xy 180.181161 -275.873174) (xy 180.197049 -275.824275) (xy 180.220392 -275.778463)
			(xy 180.250613 -275.736867) (xy 180.286969 -275.700511) (xy 180.328565 -275.67029) (xy 180.374377 -275.646947)
			(xy 180.423276 -275.631059) (xy 180.474058 -275.623016) (xy 180.525474 -275.623016) (xy 180.576256 -275.631059)
			(xy 180.625155 -275.646947) (xy 180.670967 -275.67029) (xy 180.712563 -275.700511) (xy 180.748919 -275.736867)
			(xy 180.77914 -275.778463) (xy 180.802483 -275.824275) (xy 180.818371 -275.873174) (xy 180.826414 -275.923956)
			(xy 180.826918 -275.949664) (xy 180.826913 -275.949918) (xy 181.144176 -275.949918) (xy 181.148136 -275.900864)
			(xy 181.159913 -275.85308) (xy 181.179204 -275.807804) (xy 181.205507 -275.766208) (xy 181.238142 -275.729371)
			(xy 181.276263 -275.698246) (xy 181.318884 -275.673639) (xy 181.3649 -275.656187) (xy 181.413119 -275.646343)
			(xy 181.462294 -275.644362) (xy 181.511149 -275.650294) (xy 181.55842 -275.663986) (xy 181.602882 -275.685084)
			(xy 181.643385 -275.71304) (xy 181.678878 -275.747132) (xy 181.708443 -275.786476) (xy 181.731314 -275.830053)
			(xy 181.746898 -275.876734) (xy 181.754793 -275.925311) (xy 181.755288 -275.949918) (xy 181.754793 -275.974525)
			(xy 181.754614 -275.975626) (xy 182.073038 -275.975626) (xy 182.073038 -275.92421) (xy 182.081081 -275.873428)
			(xy 182.096969 -275.824529) (xy 182.120312 -275.778717) (xy 182.150533 -275.737121) (xy 182.186889 -275.700765)
			(xy 182.228485 -275.670544) (xy 182.274297 -275.647201) (xy 182.323196 -275.631313) (xy 182.373978 -275.62327)
			(xy 182.425394 -275.62327) (xy 182.476176 -275.631313) (xy 182.525075 -275.647201) (xy 182.570887 -275.670544)
			(xy 182.612483 -275.700765) (xy 182.648839 -275.737121) (xy 182.67906 -275.778717) (xy 182.702403 -275.824529)
			(xy 182.718291 -275.873428) (xy 182.726334 -275.92421) (xy 182.726838 -275.949918) (xy 183.044096 -275.949918)
			(xy 183.048056 -275.900864) (xy 183.059833 -275.85308) (xy 183.079124 -275.807804) (xy 183.105427 -275.766208)
			(xy 183.138062 -275.729371) (xy 183.176183 -275.698246) (xy 183.218804 -275.673639) (xy 183.26482 -275.656187)
			(xy 183.313039 -275.646343) (xy 183.362214 -275.644362) (xy 183.411069 -275.650294) (xy 183.45834 -275.663986)
			(xy 183.502802 -275.685084) (xy 183.543305 -275.71304) (xy 183.578798 -275.747132) (xy 183.608363 -275.786476)
			(xy 183.631234 -275.830053) (xy 183.646818 -275.876734) (xy 183.654713 -275.925311) (xy 183.655208 -275.949918)
			(xy 183.654713 -275.974525) (xy 183.654575 -275.975372) (xy 183.972958 -275.975372) (xy 183.972958 -275.923956)
			(xy 183.981001 -275.873174) (xy 183.996889 -275.824275) (xy 184.020232 -275.778463) (xy 184.050453 -275.736867)
			(xy 184.086809 -275.700511) (xy 184.128405 -275.67029) (xy 184.174217 -275.646947) (xy 184.223116 -275.631059)
			(xy 184.273898 -275.623016) (xy 184.325314 -275.623016) (xy 184.376096 -275.631059) (xy 184.424995 -275.646947)
			(xy 184.470807 -275.67029) (xy 184.512403 -275.700511) (xy 184.548759 -275.736867) (xy 184.57898 -275.778463)
			(xy 184.602323 -275.824275) (xy 184.618211 -275.873174) (xy 184.626254 -275.923956) (xy 184.626758 -275.949664)
			(xy 184.626753 -275.949918) (xy 184.94427 -275.949918) (xy 184.94823 -275.900864) (xy 184.960007 -275.85308)
			(xy 184.979298 -275.807804) (xy 185.005601 -275.766208) (xy 185.038236 -275.729371) (xy 185.076357 -275.698246)
			(xy 185.118978 -275.673639) (xy 185.164994 -275.656187) (xy 185.213213 -275.646343) (xy 185.262388 -275.644362)
			(xy 185.311243 -275.650294) (xy 185.358514 -275.663986) (xy 185.402976 -275.685084) (xy 185.443479 -275.71304)
			(xy 185.478972 -275.747132) (xy 185.508537 -275.786476) (xy 185.531408 -275.830053) (xy 185.546992 -275.876734)
			(xy 185.554887 -275.925311) (xy 185.555382 -275.949918) (xy 185.554887 -275.974525) (xy 185.554708 -275.975626)
			(xy 185.872878 -275.975626) (xy 185.872878 -275.92421) (xy 185.880921 -275.873428) (xy 185.896809 -275.824529)
			(xy 185.920152 -275.778717) (xy 185.950373 -275.737121) (xy 185.986729 -275.700765) (xy 186.028325 -275.670544)
			(xy 186.074137 -275.647201) (xy 186.123036 -275.631313) (xy 186.173818 -275.62327) (xy 186.225234 -275.62327)
			(xy 186.276016 -275.631313) (xy 186.324915 -275.647201) (xy 186.370727 -275.670544) (xy 186.412323 -275.700765)
			(xy 186.448679 -275.737121) (xy 186.4789 -275.778717) (xy 186.502243 -275.824529) (xy 186.518131 -275.873428)
			(xy 186.526174 -275.92421) (xy 186.526678 -275.949918) (xy 186.84419 -275.949918) (xy 186.84815 -275.900864)
			(xy 186.859927 -275.85308) (xy 186.879218 -275.807804) (xy 186.905521 -275.766208) (xy 186.938156 -275.729371)
			(xy 186.976277 -275.698246) (xy 187.018898 -275.673639) (xy 187.064914 -275.656187) (xy 187.113133 -275.646343)
			(xy 187.162308 -275.644362) (xy 187.211163 -275.650294) (xy 187.258434 -275.663986) (xy 187.302896 -275.685084)
			(xy 187.343399 -275.71304) (xy 187.378892 -275.747132) (xy 187.408457 -275.786476) (xy 187.431328 -275.830053)
			(xy 187.446912 -275.876734) (xy 187.454807 -275.925311) (xy 187.455302 -275.949918) (xy 187.454807 -275.974525)
			(xy 187.454669 -275.975372) (xy 187.773052 -275.975372) (xy 187.773052 -275.923956) (xy 187.781095 -275.873174)
			(xy 187.796983 -275.824275) (xy 187.820326 -275.778463) (xy 187.850547 -275.736867) (xy 187.886903 -275.700511)
			(xy 187.928499 -275.67029) (xy 187.974311 -275.646947) (xy 188.02321 -275.631059) (xy 188.073992 -275.623016)
			(xy 188.125408 -275.623016) (xy 188.17619 -275.631059) (xy 188.225089 -275.646947) (xy 188.270901 -275.67029)
			(xy 188.312497 -275.700511) (xy 188.348853 -275.736867) (xy 188.379074 -275.778463) (xy 188.402417 -275.824275)
			(xy 188.418305 -275.873174) (xy 188.426348 -275.923956) (xy 188.426852 -275.949664) (xy 188.426847 -275.949918)
			(xy 188.74411 -275.949918) (xy 188.74807 -275.900864) (xy 188.759847 -275.85308) (xy 188.779138 -275.807804)
			(xy 188.805441 -275.766208) (xy 188.838076 -275.729371) (xy 188.876197 -275.698246) (xy 188.918818 -275.673639)
			(xy 188.964834 -275.656187) (xy 189.013053 -275.646343) (xy 189.062228 -275.644362) (xy 189.111083 -275.650294)
			(xy 189.158354 -275.663986) (xy 189.202816 -275.685084) (xy 189.243319 -275.71304) (xy 189.278812 -275.747132)
			(xy 189.308377 -275.786476) (xy 189.331248 -275.830053) (xy 189.346832 -275.876734) (xy 189.354727 -275.925311)
			(xy 189.355222 -275.949918) (xy 189.354727 -275.974525) (xy 189.354548 -275.975626) (xy 189.672972 -275.975626)
			(xy 189.672972 -275.92421) (xy 189.681015 -275.873428) (xy 189.696903 -275.824529) (xy 189.720246 -275.778717)
			(xy 189.750467 -275.737121) (xy 189.786823 -275.700765) (xy 189.828419 -275.670544) (xy 189.874231 -275.647201)
			(xy 189.92313 -275.631313) (xy 189.973912 -275.62327) (xy 190.025328 -275.62327) (xy 190.07611 -275.631313)
			(xy 190.125009 -275.647201) (xy 190.170821 -275.670544) (xy 190.212417 -275.700765) (xy 190.248773 -275.737121)
			(xy 190.278994 -275.778717) (xy 190.302337 -275.824529) (xy 190.318225 -275.873428) (xy 190.326268 -275.92421)
			(xy 190.326772 -275.949918) (xy 190.644284 -275.949918) (xy 190.648244 -275.900864) (xy 190.660021 -275.85308)
			(xy 190.679312 -275.807804) (xy 190.705615 -275.766208) (xy 190.73825 -275.729371) (xy 190.776371 -275.698246)
			(xy 190.818992 -275.673639) (xy 190.865008 -275.656187) (xy 190.913227 -275.646343) (xy 190.962402 -275.644362)
			(xy 191.011257 -275.650294) (xy 191.058528 -275.663986) (xy 191.10299 -275.685084) (xy 191.143493 -275.71304)
			(xy 191.178986 -275.747132) (xy 191.208551 -275.786476) (xy 191.231422 -275.830053) (xy 191.247006 -275.876734)
			(xy 191.254901 -275.925311) (xy 191.255396 -275.949918) (xy 191.254901 -275.974525) (xy 191.254763 -275.975372)
			(xy 191.573146 -275.975372) (xy 191.573146 -275.923956) (xy 191.581189 -275.873174) (xy 191.597077 -275.824275)
			(xy 191.62042 -275.778463) (xy 191.650641 -275.736867) (xy 191.686997 -275.700511) (xy 191.728593 -275.67029)
			(xy 191.774405 -275.646947) (xy 191.823304 -275.631059) (xy 191.874086 -275.623016) (xy 191.925502 -275.623016)
			(xy 191.976284 -275.631059) (xy 192.025183 -275.646947) (xy 192.070995 -275.67029) (xy 192.112591 -275.700511)
			(xy 192.148947 -275.736867) (xy 192.179168 -275.778463) (xy 192.202511 -275.824275) (xy 192.218399 -275.873174)
			(xy 192.226442 -275.923956) (xy 192.226946 -275.949664) (xy 192.226941 -275.949918) (xy 192.544204 -275.949918)
			(xy 192.548164 -275.900864) (xy 192.559941 -275.85308) (xy 192.579232 -275.807804) (xy 192.605535 -275.766208)
			(xy 192.63817 -275.729371) (xy 192.676291 -275.698246) (xy 192.718912 -275.673639) (xy 192.764928 -275.656187)
			(xy 192.813147 -275.646343) (xy 192.862322 -275.644362) (xy 192.911177 -275.650294) (xy 192.958448 -275.663986)
			(xy 193.00291 -275.685084) (xy 193.043413 -275.71304) (xy 193.078906 -275.747132) (xy 193.108471 -275.786476)
			(xy 193.131342 -275.830053) (xy 193.146926 -275.876734) (xy 193.154821 -275.925311) (xy 193.155316 -275.949918)
			(xy 193.154821 -275.974525) (xy 193.154642 -275.975626) (xy 193.473066 -275.975626) (xy 193.473066 -275.92421)
			(xy 193.481109 -275.873428) (xy 193.496997 -275.824529) (xy 193.52034 -275.778717) (xy 193.550561 -275.737121)
			(xy 193.586917 -275.700765) (xy 193.628513 -275.670544) (xy 193.674325 -275.647201) (xy 193.723224 -275.631313)
			(xy 193.774006 -275.62327) (xy 193.825422 -275.62327) (xy 193.876204 -275.631313) (xy 193.925103 -275.647201)
			(xy 193.970915 -275.670544) (xy 194.012511 -275.700765) (xy 194.048867 -275.737121) (xy 194.079088 -275.778717)
			(xy 194.102431 -275.824529) (xy 194.118319 -275.873428) (xy 194.126362 -275.92421) (xy 194.126866 -275.949918)
			(xy 194.444124 -275.949918) (xy 194.448084 -275.900864) (xy 194.459861 -275.85308) (xy 194.479152 -275.807804)
			(xy 194.505455 -275.766208) (xy 194.53809 -275.729371) (xy 194.576211 -275.698246) (xy 194.618832 -275.673639)
			(xy 194.664848 -275.656187) (xy 194.713067 -275.646343) (xy 194.762242 -275.644362) (xy 194.811097 -275.650294)
			(xy 194.858368 -275.663986) (xy 194.90283 -275.685084) (xy 194.943333 -275.71304) (xy 194.978826 -275.747132)
			(xy 195.008391 -275.786476) (xy 195.031262 -275.830053) (xy 195.046846 -275.876734) (xy 195.054741 -275.925311)
			(xy 195.055236 -275.949918) (xy 195.054741 -275.974525) (xy 195.054562 -275.975626) (xy 195.372986 -275.975626)
			(xy 195.372986 -275.92421) (xy 195.381029 -275.873428) (xy 195.396917 -275.824529) (xy 195.42026 -275.778717)
			(xy 195.450481 -275.737121) (xy 195.486837 -275.700765) (xy 195.528433 -275.670544) (xy 195.574245 -275.647201)
			(xy 195.623144 -275.631313) (xy 195.673926 -275.62327) (xy 195.725342 -275.62327) (xy 195.776124 -275.631313)
			(xy 195.825023 -275.647201) (xy 195.870835 -275.670544) (xy 195.912431 -275.700765) (xy 195.948787 -275.737121)
			(xy 195.979008 -275.778717) (xy 196.002351 -275.824529) (xy 196.018239 -275.873428) (xy 196.026282 -275.92421)
			(xy 196.026786 -275.949918) (xy 196.344298 -275.949918) (xy 196.348258 -275.900864) (xy 196.360035 -275.85308)
			(xy 196.379326 -275.807804) (xy 196.405629 -275.766208) (xy 196.438264 -275.729371) (xy 196.476385 -275.698246)
			(xy 196.519006 -275.673639) (xy 196.565022 -275.656187) (xy 196.613241 -275.646343) (xy 196.662416 -275.644362)
			(xy 196.711271 -275.650294) (xy 196.758542 -275.663986) (xy 196.803004 -275.685084) (xy 196.843507 -275.71304)
			(xy 196.879 -275.747132) (xy 196.908565 -275.786476) (xy 196.931436 -275.830053) (xy 196.94702 -275.876734)
			(xy 196.954915 -275.925311) (xy 196.95541 -275.949918) (xy 197.294258 -275.949918) (xy 197.298218 -275.900864)
			(xy 197.309995 -275.85308) (xy 197.329286 -275.807804) (xy 197.355589 -275.766208) (xy 197.388224 -275.729371)
			(xy 197.426345 -275.698246) (xy 197.468966 -275.673639) (xy 197.514982 -275.656187) (xy 197.563201 -275.646343)
			(xy 197.612376 -275.644362) (xy 197.661231 -275.650294) (xy 197.708502 -275.663986) (xy 197.752964 -275.685084)
			(xy 197.793467 -275.71304) (xy 197.82896 -275.747132) (xy 197.858525 -275.786476) (xy 197.881396 -275.830053)
			(xy 197.89698 -275.876734) (xy 197.904875 -275.925311) (xy 197.90537 -275.949918) (xy 198.244218 -275.949918)
			(xy 198.248178 -275.900864) (xy 198.259955 -275.85308) (xy 198.279246 -275.807804) (xy 198.305549 -275.766208)
			(xy 198.338184 -275.729371) (xy 198.376305 -275.698246) (xy 198.418926 -275.673639) (xy 198.464942 -275.656187)
			(xy 198.513161 -275.646343) (xy 198.562336 -275.644362) (xy 198.611191 -275.650294) (xy 198.658462 -275.663986)
			(xy 198.702924 -275.685084) (xy 198.743427 -275.71304) (xy 198.77892 -275.747132) (xy 198.808485 -275.786476)
			(xy 198.831356 -275.830053) (xy 198.84694 -275.876734) (xy 198.854835 -275.925311) (xy 198.85533 -275.949918)
			(xy 276.343884 -275.949918) (xy 276.347844 -275.900864) (xy 276.359621 -275.85308) (xy 276.378912 -275.807804)
			(xy 276.405215 -275.766208) (xy 276.43785 -275.729371) (xy 276.475971 -275.698246) (xy 276.518592 -275.673639)
			(xy 276.564608 -275.656187) (xy 276.612827 -275.646343) (xy 276.662002 -275.644362) (xy 276.710857 -275.650294)
			(xy 276.758128 -275.663986) (xy 276.80259 -275.685084) (xy 276.843093 -275.71304) (xy 276.878586 -275.747132)
			(xy 276.908151 -275.786476) (xy 276.931022 -275.830053) (xy 276.946606 -275.876734) (xy 276.954501 -275.925311)
			(xy 276.954996 -275.949918) (xy 276.954501 -275.974525) (xy 276.954322 -275.975626) (xy 277.273254 -275.975626)
			(xy 277.273254 -275.92421) (xy 277.281297 -275.873428) (xy 277.297185 -275.824529) (xy 277.320528 -275.778717)
			(xy 277.350749 -275.737121) (xy 277.387105 -275.700765) (xy 277.428701 -275.670544) (xy 277.474513 -275.647201)
			(xy 277.523412 -275.631313) (xy 277.574194 -275.62327) (xy 277.62561 -275.62327) (xy 277.676392 -275.631313)
			(xy 277.725291 -275.647201) (xy 277.771103 -275.670544) (xy 277.812699 -275.700765) (xy 277.849055 -275.737121)
			(xy 277.879276 -275.778717) (xy 277.902619 -275.824529) (xy 277.918507 -275.873428) (xy 277.92655 -275.92421)
			(xy 277.927054 -275.949918) (xy 278.244058 -275.949918) (xy 278.248018 -275.900864) (xy 278.259795 -275.85308)
			(xy 278.279086 -275.807804) (xy 278.305389 -275.766208) (xy 278.338024 -275.729371) (xy 278.376145 -275.698246)
			(xy 278.418766 -275.673639) (xy 278.464782 -275.656187) (xy 278.513001 -275.646343) (xy 278.562176 -275.644362)
			(xy 278.611031 -275.650294) (xy 278.658302 -275.663986) (xy 278.702764 -275.685084) (xy 278.743267 -275.71304)
			(xy 278.77876 -275.747132) (xy 278.808325 -275.786476) (xy 278.831196 -275.830053) (xy 278.84678 -275.876734)
			(xy 278.854675 -275.925311) (xy 278.85517 -275.949918) (xy 278.854675 -275.974525) (xy 278.854496 -275.975626)
			(xy 279.173174 -275.975626) (xy 279.173174 -275.92421) (xy 279.181217 -275.873428) (xy 279.197105 -275.824529)
			(xy 279.220448 -275.778717) (xy 279.250669 -275.737121) (xy 279.287025 -275.700765) (xy 279.328621 -275.670544)
			(xy 279.374433 -275.647201) (xy 279.423332 -275.631313) (xy 279.474114 -275.62327) (xy 279.52553 -275.62327)
			(xy 279.576312 -275.631313) (xy 279.625211 -275.647201) (xy 279.671023 -275.670544) (xy 279.712619 -275.700765)
			(xy 279.748975 -275.737121) (xy 279.779196 -275.778717) (xy 279.802539 -275.824529) (xy 279.818427 -275.873428)
			(xy 279.82647 -275.92421) (xy 279.826974 -275.949918) (xy 280.143978 -275.949918) (xy 280.147938 -275.900864)
			(xy 280.159715 -275.85308) (xy 280.179006 -275.807804) (xy 280.205309 -275.766208) (xy 280.237944 -275.729371)
			(xy 280.276065 -275.698246) (xy 280.318686 -275.673639) (xy 280.364702 -275.656187) (xy 280.412921 -275.646343)
			(xy 280.462096 -275.644362) (xy 280.510951 -275.650294) (xy 280.558222 -275.663986) (xy 280.602684 -275.685084)
			(xy 280.643187 -275.71304) (xy 280.67868 -275.747132) (xy 280.708245 -275.786476) (xy 280.731116 -275.830053)
			(xy 280.7467 -275.876734) (xy 280.754595 -275.925311) (xy 280.75509 -275.949918) (xy 280.754595 -275.974525)
			(xy 280.754416 -275.975626) (xy 281.073094 -275.975626) (xy 281.073094 -275.92421) (xy 281.081137 -275.873428)
			(xy 281.097025 -275.824529) (xy 281.120368 -275.778717) (xy 281.150589 -275.737121) (xy 281.186945 -275.700765)
			(xy 281.228541 -275.670544) (xy 281.274353 -275.647201) (xy 281.323252 -275.631313) (xy 281.374034 -275.62327)
			(xy 281.42545 -275.62327) (xy 281.476232 -275.631313) (xy 281.525131 -275.647201) (xy 281.570943 -275.670544)
			(xy 281.612539 -275.700765) (xy 281.648895 -275.737121) (xy 281.679116 -275.778717) (xy 281.702459 -275.824529)
			(xy 281.718347 -275.873428) (xy 281.72639 -275.92421) (xy 281.726894 -275.949918) (xy 282.043898 -275.949918)
			(xy 282.047858 -275.900864) (xy 282.059635 -275.85308) (xy 282.078926 -275.807804) (xy 282.105229 -275.766208)
			(xy 282.137864 -275.729371) (xy 282.175985 -275.698246) (xy 282.218606 -275.673639) (xy 282.264622 -275.656187)
			(xy 282.312841 -275.646343) (xy 282.362016 -275.644362) (xy 282.410871 -275.650294) (xy 282.458142 -275.663986)
			(xy 282.502604 -275.685084) (xy 282.543107 -275.71304) (xy 282.5786 -275.747132) (xy 282.608165 -275.786476)
			(xy 282.631036 -275.830053) (xy 282.64662 -275.876734) (xy 282.654515 -275.925311) (xy 282.65501 -275.949918)
			(xy 282.654515 -275.974525) (xy 282.654336 -275.975626) (xy 282.973268 -275.975626) (xy 282.973268 -275.92421)
			(xy 282.981311 -275.873428) (xy 282.997199 -275.824529) (xy 283.020542 -275.778717) (xy 283.050763 -275.737121)
			(xy 283.087119 -275.700765) (xy 283.128715 -275.670544) (xy 283.174527 -275.647201) (xy 283.223426 -275.631313)
			(xy 283.274208 -275.62327) (xy 283.325624 -275.62327) (xy 283.376406 -275.631313) (xy 283.425305 -275.647201)
			(xy 283.471117 -275.670544) (xy 283.512713 -275.700765) (xy 283.549069 -275.737121) (xy 283.57929 -275.778717)
			(xy 283.602633 -275.824529) (xy 283.618521 -275.873428) (xy 283.626564 -275.92421) (xy 283.627068 -275.949918)
			(xy 283.944072 -275.949918) (xy 283.948032 -275.900864) (xy 283.959809 -275.85308) (xy 283.9791 -275.807804)
			(xy 284.005403 -275.766208) (xy 284.038038 -275.729371) (xy 284.076159 -275.698246) (xy 284.11878 -275.673639)
			(xy 284.164796 -275.656187) (xy 284.213015 -275.646343) (xy 284.26219 -275.644362) (xy 284.311045 -275.650294)
			(xy 284.358316 -275.663986) (xy 284.402778 -275.685084) (xy 284.443281 -275.71304) (xy 284.478774 -275.747132)
			(xy 284.508339 -275.786476) (xy 284.53121 -275.830053) (xy 284.546794 -275.876734) (xy 284.554689 -275.925311)
			(xy 284.555184 -275.949918) (xy 284.554689 -275.974525) (xy 284.55451 -275.975626) (xy 284.873188 -275.975626)
			(xy 284.873188 -275.92421) (xy 284.881231 -275.873428) (xy 284.897119 -275.824529) (xy 284.920462 -275.778717)
			(xy 284.950683 -275.737121) (xy 284.987039 -275.700765) (xy 285.028635 -275.670544) (xy 285.074447 -275.647201)
			(xy 285.123346 -275.631313) (xy 285.174128 -275.62327) (xy 285.225544 -275.62327) (xy 285.276326 -275.631313)
			(xy 285.325225 -275.647201) (xy 285.371037 -275.670544) (xy 285.412633 -275.700765) (xy 285.448989 -275.737121)
			(xy 285.47921 -275.778717) (xy 285.502553 -275.824529) (xy 285.518441 -275.873428) (xy 285.526484 -275.92421)
			(xy 285.526988 -275.949918) (xy 285.843992 -275.949918) (xy 285.847952 -275.900864) (xy 285.859729 -275.85308)
			(xy 285.87902 -275.807804) (xy 285.905323 -275.766208) (xy 285.937958 -275.729371) (xy 285.976079 -275.698246)
			(xy 286.0187 -275.673639) (xy 286.064716 -275.656187) (xy 286.112935 -275.646343) (xy 286.16211 -275.644362)
			(xy 286.210965 -275.650294) (xy 286.258236 -275.663986) (xy 286.302698 -275.685084) (xy 286.343201 -275.71304)
			(xy 286.378694 -275.747132) (xy 286.408259 -275.786476) (xy 286.43113 -275.830053) (xy 286.446714 -275.876734)
			(xy 286.454609 -275.925311) (xy 286.455104 -275.949918) (xy 286.454609 -275.974525) (xy 286.45443 -275.975626)
			(xy 286.773108 -275.975626) (xy 286.773108 -275.92421) (xy 286.781151 -275.873428) (xy 286.797039 -275.824529)
			(xy 286.820382 -275.778717) (xy 286.850603 -275.737121) (xy 286.886959 -275.700765) (xy 286.928555 -275.670544)
			(xy 286.974367 -275.647201) (xy 287.023266 -275.631313) (xy 287.074048 -275.62327) (xy 287.125464 -275.62327)
			(xy 287.176246 -275.631313) (xy 287.225145 -275.647201) (xy 287.270957 -275.670544) (xy 287.312553 -275.700765)
			(xy 287.348909 -275.737121) (xy 287.37913 -275.778717) (xy 287.402473 -275.824529) (xy 287.418361 -275.873428)
			(xy 287.426404 -275.92421) (xy 287.426908 -275.949918) (xy 287.743912 -275.949918) (xy 287.747872 -275.900864)
			(xy 287.759649 -275.85308) (xy 287.77894 -275.807804) (xy 287.805243 -275.766208) (xy 287.837878 -275.729371)
			(xy 287.875999 -275.698246) (xy 287.91862 -275.673639) (xy 287.964636 -275.656187) (xy 288.012855 -275.646343)
			(xy 288.06203 -275.644362) (xy 288.110885 -275.650294) (xy 288.158156 -275.663986) (xy 288.202618 -275.685084)
			(xy 288.243121 -275.71304) (xy 288.278614 -275.747132) (xy 288.308179 -275.786476) (xy 288.33105 -275.830053)
			(xy 288.346634 -275.876734) (xy 288.354529 -275.925311) (xy 288.355024 -275.949918) (xy 288.354529 -275.974525)
			(xy 288.35435 -275.975626) (xy 288.673282 -275.975626) (xy 288.673282 -275.92421) (xy 288.681325 -275.873428)
			(xy 288.697213 -275.824529) (xy 288.720556 -275.778717) (xy 288.750777 -275.737121) (xy 288.787133 -275.700765)
			(xy 288.828729 -275.670544) (xy 288.874541 -275.647201) (xy 288.92344 -275.631313) (xy 288.974222 -275.62327)
			(xy 289.025638 -275.62327) (xy 289.07642 -275.631313) (xy 289.125319 -275.647201) (xy 289.171131 -275.670544)
			(xy 289.212727 -275.700765) (xy 289.249083 -275.737121) (xy 289.279304 -275.778717) (xy 289.302647 -275.824529)
			(xy 289.318535 -275.873428) (xy 289.326578 -275.92421) (xy 289.327082 -275.949918) (xy 289.644086 -275.949918)
			(xy 289.648046 -275.900864) (xy 289.659823 -275.85308) (xy 289.679114 -275.807804) (xy 289.705417 -275.766208)
			(xy 289.738052 -275.729371) (xy 289.776173 -275.698246) (xy 289.818794 -275.673639) (xy 289.86481 -275.656187)
			(xy 289.913029 -275.646343) (xy 289.962204 -275.644362) (xy 290.011059 -275.650294) (xy 290.05833 -275.663986)
			(xy 290.102792 -275.685084) (xy 290.143295 -275.71304) (xy 290.178788 -275.747132) (xy 290.208353 -275.786476)
			(xy 290.231224 -275.830053) (xy 290.246808 -275.876734) (xy 290.254703 -275.925311) (xy 290.255198 -275.949918)
			(xy 290.254703 -275.974525) (xy 290.254524 -275.975626) (xy 290.573202 -275.975626) (xy 290.573202 -275.92421)
			(xy 290.581245 -275.873428) (xy 290.597133 -275.824529) (xy 290.620476 -275.778717) (xy 290.650697 -275.737121)
			(xy 290.687053 -275.700765) (xy 290.728649 -275.670544) (xy 290.774461 -275.647201) (xy 290.82336 -275.631313)
			(xy 290.874142 -275.62327) (xy 290.925558 -275.62327) (xy 290.97634 -275.631313) (xy 291.025239 -275.647201)
			(xy 291.071051 -275.670544) (xy 291.112647 -275.700765) (xy 291.149003 -275.737121) (xy 291.179224 -275.778717)
			(xy 291.202567 -275.824529) (xy 291.218455 -275.873428) (xy 291.226498 -275.92421) (xy 291.227002 -275.949918)
			(xy 291.544006 -275.949918) (xy 291.547966 -275.900864) (xy 291.559743 -275.85308) (xy 291.579034 -275.807804)
			(xy 291.605337 -275.766208) (xy 291.637972 -275.729371) (xy 291.676093 -275.698246) (xy 291.718714 -275.673639)
			(xy 291.76473 -275.656187) (xy 291.812949 -275.646343) (xy 291.862124 -275.644362) (xy 291.910979 -275.650294)
			(xy 291.95825 -275.663986) (xy 292.002712 -275.685084) (xy 292.043215 -275.71304) (xy 292.078708 -275.747132)
			(xy 292.108273 -275.786476) (xy 292.131144 -275.830053) (xy 292.146728 -275.876734) (xy 292.154623 -275.925311)
			(xy 292.155118 -275.949918) (xy 292.154623 -275.974525) (xy 292.154485 -275.975372) (xy 292.472868 -275.975372)
			(xy 292.472868 -275.923956) (xy 292.480911 -275.873174) (xy 292.496799 -275.824275) (xy 292.520142 -275.778463)
			(xy 292.550363 -275.736867) (xy 292.586719 -275.700511) (xy 292.628315 -275.67029) (xy 292.674127 -275.646947)
			(xy 292.723026 -275.631059) (xy 292.773808 -275.623016) (xy 292.825224 -275.623016) (xy 292.876006 -275.631059)
			(xy 292.924905 -275.646947) (xy 292.970717 -275.67029) (xy 293.012313 -275.700511) (xy 293.048669 -275.736867)
			(xy 293.07889 -275.778463) (xy 293.102233 -275.824275) (xy 293.118121 -275.873174) (xy 293.126164 -275.923956)
			(xy 293.126668 -275.949664) (xy 293.126663 -275.949918) (xy 293.443926 -275.949918) (xy 293.447886 -275.900864)
			(xy 293.459663 -275.85308) (xy 293.478954 -275.807804) (xy 293.505257 -275.766208) (xy 293.537892 -275.729371)
			(xy 293.576013 -275.698246) (xy 293.618634 -275.673639) (xy 293.66465 -275.656187) (xy 293.712869 -275.646343)
			(xy 293.762044 -275.644362) (xy 293.810899 -275.650294) (xy 293.85817 -275.663986) (xy 293.902632 -275.685084)
			(xy 293.943135 -275.71304) (xy 293.978628 -275.747132) (xy 294.008193 -275.786476) (xy 294.031064 -275.830053)
			(xy 294.046648 -275.876734) (xy 294.054543 -275.925311) (xy 294.055038 -275.949918) (xy 294.054543 -275.974525)
			(xy 294.054364 -275.975626) (xy 294.372788 -275.975626) (xy 294.372788 -275.92421) (xy 294.380831 -275.873428)
			(xy 294.396719 -275.824529) (xy 294.420062 -275.778717) (xy 294.450283 -275.737121) (xy 294.486639 -275.700765)
			(xy 294.528235 -275.670544) (xy 294.574047 -275.647201) (xy 294.622946 -275.631313) (xy 294.673728 -275.62327)
			(xy 294.725144 -275.62327) (xy 294.775926 -275.631313) (xy 294.824825 -275.647201) (xy 294.870637 -275.670544)
			(xy 294.912233 -275.700765) (xy 294.948589 -275.737121) (xy 294.97881 -275.778717) (xy 295.002153 -275.824529)
			(xy 295.018041 -275.873428) (xy 295.026084 -275.92421) (xy 295.026588 -275.949918) (xy 295.3441 -275.949918)
			(xy 295.34806 -275.900864) (xy 295.359837 -275.85308) (xy 295.379128 -275.807804) (xy 295.405431 -275.766208)
			(xy 295.438066 -275.729371) (xy 295.476187 -275.698246) (xy 295.518808 -275.673639) (xy 295.564824 -275.656187)
			(xy 295.613043 -275.646343) (xy 295.662218 -275.644362) (xy 295.711073 -275.650294) (xy 295.758344 -275.663986)
			(xy 295.802806 -275.685084) (xy 295.843309 -275.71304) (xy 295.878802 -275.747132) (xy 295.908367 -275.786476)
			(xy 295.931238 -275.830053) (xy 295.946822 -275.876734) (xy 295.954717 -275.925311) (xy 295.955212 -275.949918)
			(xy 295.954717 -275.974525) (xy 295.954579 -275.975372) (xy 296.272962 -275.975372) (xy 296.272962 -275.923956)
			(xy 296.281005 -275.873174) (xy 296.296893 -275.824275) (xy 296.320236 -275.778463) (xy 296.350457 -275.736867)
			(xy 296.386813 -275.700511) (xy 296.428409 -275.67029) (xy 296.474221 -275.646947) (xy 296.52312 -275.631059)
			(xy 296.573902 -275.623016) (xy 296.625318 -275.623016) (xy 296.6761 -275.631059) (xy 296.724999 -275.646947)
			(xy 296.770811 -275.67029) (xy 296.812407 -275.700511) (xy 296.848763 -275.736867) (xy 296.878984 -275.778463)
			(xy 296.902327 -275.824275) (xy 296.918215 -275.873174) (xy 296.926258 -275.923956) (xy 296.926762 -275.949664)
			(xy 296.926757 -275.949918) (xy 297.24402 -275.949918) (xy 297.24798 -275.900864) (xy 297.259757 -275.85308)
			(xy 297.279048 -275.807804) (xy 297.305351 -275.766208) (xy 297.337986 -275.729371) (xy 297.376107 -275.698246)
			(xy 297.418728 -275.673639) (xy 297.464744 -275.656187) (xy 297.512963 -275.646343) (xy 297.562138 -275.644362)
			(xy 297.610993 -275.650294) (xy 297.658264 -275.663986) (xy 297.702726 -275.685084) (xy 297.743229 -275.71304)
			(xy 297.778722 -275.747132) (xy 297.808287 -275.786476) (xy 297.831158 -275.830053) (xy 297.846742 -275.876734)
			(xy 297.854637 -275.925311) (xy 297.855132 -275.949918) (xy 297.854637 -275.974525) (xy 297.854458 -275.975626)
			(xy 298.172882 -275.975626) (xy 298.172882 -275.92421) (xy 298.180925 -275.873428) (xy 298.196813 -275.824529)
			(xy 298.220156 -275.778717) (xy 298.250377 -275.737121) (xy 298.286733 -275.700765) (xy 298.328329 -275.670544)
			(xy 298.374141 -275.647201) (xy 298.42304 -275.631313) (xy 298.473822 -275.62327) (xy 298.525238 -275.62327)
			(xy 298.57602 -275.631313) (xy 298.624919 -275.647201) (xy 298.670731 -275.670544) (xy 298.712327 -275.700765)
			(xy 298.748683 -275.737121) (xy 298.778904 -275.778717) (xy 298.802247 -275.824529) (xy 298.818135 -275.873428)
			(xy 298.826178 -275.92421) (xy 298.826682 -275.949918) (xy 299.14394 -275.949918) (xy 299.1479 -275.900864)
			(xy 299.159677 -275.85308) (xy 299.178968 -275.807804) (xy 299.205271 -275.766208) (xy 299.237906 -275.729371)
			(xy 299.276027 -275.698246) (xy 299.318648 -275.673639) (xy 299.364664 -275.656187) (xy 299.412883 -275.646343)
			(xy 299.462058 -275.644362) (xy 299.510913 -275.650294) (xy 299.558184 -275.663986) (xy 299.602646 -275.685084)
			(xy 299.643149 -275.71304) (xy 299.678642 -275.747132) (xy 299.708207 -275.786476) (xy 299.731078 -275.830053)
			(xy 299.746662 -275.876734) (xy 299.754557 -275.925311) (xy 299.755052 -275.949918) (xy 299.754557 -275.974525)
			(xy 299.754419 -275.975372) (xy 300.072802 -275.975372) (xy 300.072802 -275.923956) (xy 300.080845 -275.873174)
			(xy 300.096733 -275.824275) (xy 300.120076 -275.778463) (xy 300.150297 -275.736867) (xy 300.186653 -275.700511)
			(xy 300.228249 -275.67029) (xy 300.274061 -275.646947) (xy 300.32296 -275.631059) (xy 300.373742 -275.623016)
			(xy 300.425158 -275.623016) (xy 300.47594 -275.631059) (xy 300.524839 -275.646947) (xy 300.570651 -275.67029)
			(xy 300.612247 -275.700511) (xy 300.648603 -275.736867) (xy 300.678824 -275.778463) (xy 300.702167 -275.824275)
			(xy 300.718055 -275.873174) (xy 300.726098 -275.923956) (xy 300.726602 -275.949664) (xy 300.726597 -275.949918)
			(xy 301.044114 -275.949918) (xy 301.048074 -275.900864) (xy 301.059851 -275.85308) (xy 301.079142 -275.807804)
			(xy 301.105445 -275.766208) (xy 301.13808 -275.729371) (xy 301.176201 -275.698246) (xy 301.218822 -275.673639)
			(xy 301.264838 -275.656187) (xy 301.313057 -275.646343) (xy 301.362232 -275.644362) (xy 301.411087 -275.650294)
			(xy 301.458358 -275.663986) (xy 301.50282 -275.685084) (xy 301.543323 -275.71304) (xy 301.578816 -275.747132)
			(xy 301.608381 -275.786476) (xy 301.631252 -275.830053) (xy 301.646836 -275.876734) (xy 301.654731 -275.925311)
			(xy 301.655226 -275.949918) (xy 301.654731 -275.974525) (xy 301.654552 -275.975626) (xy 301.972722 -275.975626)
			(xy 301.972722 -275.92421) (xy 301.980765 -275.873428) (xy 301.996653 -275.824529) (xy 302.019996 -275.778717)
			(xy 302.050217 -275.737121) (xy 302.086573 -275.700765) (xy 302.128169 -275.670544) (xy 302.173981 -275.647201)
			(xy 302.22288 -275.631313) (xy 302.273662 -275.62327) (xy 302.325078 -275.62327) (xy 302.37586 -275.631313)
			(xy 302.424759 -275.647201) (xy 302.470571 -275.670544) (xy 302.512167 -275.700765) (xy 302.548523 -275.737121)
			(xy 302.578744 -275.778717) (xy 302.602087 -275.824529) (xy 302.617975 -275.873428) (xy 302.626018 -275.92421)
			(xy 302.626522 -275.949918) (xy 302.944034 -275.949918) (xy 302.947994 -275.900864) (xy 302.959771 -275.85308)
			(xy 302.979062 -275.807804) (xy 303.005365 -275.766208) (xy 303.038 -275.729371) (xy 303.076121 -275.698246)
			(xy 303.118742 -275.673639) (xy 303.164758 -275.656187) (xy 303.212977 -275.646343) (xy 303.262152 -275.644362)
			(xy 303.311007 -275.650294) (xy 303.358278 -275.663986) (xy 303.40274 -275.685084) (xy 303.443243 -275.71304)
			(xy 303.478736 -275.747132) (xy 303.508301 -275.786476) (xy 303.531172 -275.830053) (xy 303.546756 -275.876734)
			(xy 303.554651 -275.925311) (xy 303.555146 -275.949918) (xy 303.554651 -275.974525) (xy 303.554513 -275.975372)
			(xy 303.872896 -275.975372) (xy 303.872896 -275.923956) (xy 303.880939 -275.873174) (xy 303.896827 -275.824275)
			(xy 303.92017 -275.778463) (xy 303.950391 -275.736867) (xy 303.986747 -275.700511) (xy 304.028343 -275.67029)
			(xy 304.074155 -275.646947) (xy 304.123054 -275.631059) (xy 304.173836 -275.623016) (xy 304.225252 -275.623016)
			(xy 304.276034 -275.631059) (xy 304.324933 -275.646947) (xy 304.370745 -275.67029) (xy 304.412341 -275.700511)
			(xy 304.448697 -275.736867) (xy 304.478918 -275.778463) (xy 304.502261 -275.824275) (xy 304.518149 -275.873174)
			(xy 304.526192 -275.923956) (xy 304.526696 -275.949664) (xy 304.526691 -275.949918) (xy 304.843954 -275.949918)
			(xy 304.847914 -275.900864) (xy 304.859691 -275.85308) (xy 304.878982 -275.807804) (xy 304.905285 -275.766208)
			(xy 304.93792 -275.729371) (xy 304.976041 -275.698246) (xy 305.018662 -275.673639) (xy 305.064678 -275.656187)
			(xy 305.112897 -275.646343) (xy 305.162072 -275.644362) (xy 305.210927 -275.650294) (xy 305.258198 -275.663986)
			(xy 305.30266 -275.685084) (xy 305.343163 -275.71304) (xy 305.378656 -275.747132) (xy 305.408221 -275.786476)
			(xy 305.431092 -275.830053) (xy 305.446676 -275.876734) (xy 305.454571 -275.925311) (xy 305.455066 -275.949918)
			(xy 305.454571 -275.974525) (xy 305.454392 -275.975626) (xy 305.772816 -275.975626) (xy 305.772816 -275.92421)
			(xy 305.780859 -275.873428) (xy 305.796747 -275.824529) (xy 305.82009 -275.778717) (xy 305.850311 -275.737121)
			(xy 305.886667 -275.700765) (xy 305.928263 -275.670544) (xy 305.974075 -275.647201) (xy 306.022974 -275.631313)
			(xy 306.073756 -275.62327) (xy 306.125172 -275.62327) (xy 306.175954 -275.631313) (xy 306.224853 -275.647201)
			(xy 306.270665 -275.670544) (xy 306.312261 -275.700765) (xy 306.348617 -275.737121) (xy 306.378838 -275.778717)
			(xy 306.402181 -275.824529) (xy 306.418069 -275.873428) (xy 306.426112 -275.92421) (xy 306.426616 -275.949918)
			(xy 306.744128 -275.949918) (xy 306.748088 -275.900864) (xy 306.759865 -275.85308) (xy 306.779156 -275.807804)
			(xy 306.805459 -275.766208) (xy 306.838094 -275.729371) (xy 306.876215 -275.698246) (xy 306.918836 -275.673639)
			(xy 306.964852 -275.656187) (xy 307.013071 -275.646343) (xy 307.062246 -275.644362) (xy 307.111101 -275.650294)
			(xy 307.158372 -275.663986) (xy 307.202834 -275.685084) (xy 307.243337 -275.71304) (xy 307.27883 -275.747132)
			(xy 307.308395 -275.786476) (xy 307.331266 -275.830053) (xy 307.34685 -275.876734) (xy 307.354745 -275.925311)
			(xy 307.35524 -275.949918) (xy 307.354745 -275.974525) (xy 307.354607 -275.975372) (xy 307.67299 -275.975372)
			(xy 307.67299 -275.923956) (xy 307.681033 -275.873174) (xy 307.696921 -275.824275) (xy 307.720264 -275.778463)
			(xy 307.750485 -275.736867) (xy 307.786841 -275.700511) (xy 307.828437 -275.67029) (xy 307.874249 -275.646947)
			(xy 307.923148 -275.631059) (xy 307.97393 -275.623016) (xy 308.025346 -275.623016) (xy 308.076128 -275.631059)
			(xy 308.125027 -275.646947) (xy 308.170839 -275.67029) (xy 308.212435 -275.700511) (xy 308.248791 -275.736867)
			(xy 308.279012 -275.778463) (xy 308.302355 -275.824275) (xy 308.318243 -275.873174) (xy 308.326286 -275.923956)
			(xy 308.32679 -275.949664) (xy 308.326785 -275.949918) (xy 308.644048 -275.949918) (xy 308.648008 -275.900864)
			(xy 308.659785 -275.85308) (xy 308.679076 -275.807804) (xy 308.705379 -275.766208) (xy 308.738014 -275.729371)
			(xy 308.776135 -275.698246) (xy 308.818756 -275.673639) (xy 308.864772 -275.656187) (xy 308.912991 -275.646343)
			(xy 308.962166 -275.644362) (xy 309.011021 -275.650294) (xy 309.058292 -275.663986) (xy 309.102754 -275.685084)
			(xy 309.143257 -275.71304) (xy 309.17875 -275.747132) (xy 309.208315 -275.786476) (xy 309.231186 -275.830053)
			(xy 309.24677 -275.876734) (xy 309.254665 -275.925311) (xy 309.25516 -275.949918) (xy 309.254665 -275.974525)
			(xy 309.254486 -275.975626) (xy 309.57291 -275.975626) (xy 309.57291 -275.92421) (xy 309.580953 -275.873428)
			(xy 309.596841 -275.824529) (xy 309.620184 -275.778717) (xy 309.650405 -275.737121) (xy 309.686761 -275.700765)
			(xy 309.728357 -275.670544) (xy 309.774169 -275.647201) (xy 309.823068 -275.631313) (xy 309.87385 -275.62327)
			(xy 309.925266 -275.62327) (xy 309.976048 -275.631313) (xy 310.024947 -275.647201) (xy 310.070759 -275.670544)
			(xy 310.112355 -275.700765) (xy 310.148711 -275.737121) (xy 310.178932 -275.778717) (xy 310.202275 -275.824529)
			(xy 310.218163 -275.873428) (xy 310.226206 -275.92421) (xy 310.22671 -275.949918) (xy 310.543968 -275.949918)
			(xy 310.547928 -275.900864) (xy 310.559705 -275.85308) (xy 310.578996 -275.807804) (xy 310.605299 -275.766208)
			(xy 310.637934 -275.729371) (xy 310.676055 -275.698246) (xy 310.718676 -275.673639) (xy 310.764692 -275.656187)
			(xy 310.812911 -275.646343) (xy 310.862086 -275.644362) (xy 310.910941 -275.650294) (xy 310.958212 -275.663986)
			(xy 311.002674 -275.685084) (xy 311.043177 -275.71304) (xy 311.07867 -275.747132) (xy 311.108235 -275.786476)
			(xy 311.131106 -275.830053) (xy 311.14669 -275.876734) (xy 311.154585 -275.925311) (xy 311.15508 -275.949918)
			(xy 311.154585 -275.974525) (xy 311.154406 -275.975626) (xy 311.47283 -275.975626) (xy 311.47283 -275.92421)
			(xy 311.480873 -275.873428) (xy 311.496761 -275.824529) (xy 311.520104 -275.778717) (xy 311.550325 -275.737121)
			(xy 311.586681 -275.700765) (xy 311.628277 -275.670544) (xy 311.674089 -275.647201) (xy 311.722988 -275.631313)
			(xy 311.77377 -275.62327) (xy 311.825186 -275.62327) (xy 311.875968 -275.631313) (xy 311.924867 -275.647201)
			(xy 311.970679 -275.670544) (xy 312.012275 -275.700765) (xy 312.048631 -275.737121) (xy 312.078852 -275.778717)
			(xy 312.102195 -275.824529) (xy 312.118083 -275.873428) (xy 312.126126 -275.92421) (xy 312.12663 -275.949918)
			(xy 312.444142 -275.949918) (xy 312.448102 -275.900864) (xy 312.459879 -275.85308) (xy 312.47917 -275.807804)
			(xy 312.505473 -275.766208) (xy 312.538108 -275.729371) (xy 312.576229 -275.698246) (xy 312.61885 -275.673639)
			(xy 312.664866 -275.656187) (xy 312.713085 -275.646343) (xy 312.76226 -275.644362) (xy 312.811115 -275.650294)
			(xy 312.858386 -275.663986) (xy 312.902848 -275.685084) (xy 312.943351 -275.71304) (xy 312.978844 -275.747132)
			(xy 313.008409 -275.786476) (xy 313.03128 -275.830053) (xy 313.046864 -275.876734) (xy 313.054759 -275.925311)
			(xy 313.055254 -275.949918) (xy 313.394102 -275.949918) (xy 313.398062 -275.900864) (xy 313.409839 -275.85308)
			(xy 313.42913 -275.807804) (xy 313.455433 -275.766208) (xy 313.488068 -275.729371) (xy 313.526189 -275.698246)
			(xy 313.56881 -275.673639) (xy 313.614826 -275.656187) (xy 313.663045 -275.646343) (xy 313.71222 -275.644362)
			(xy 313.761075 -275.650294) (xy 313.808346 -275.663986) (xy 313.852808 -275.685084) (xy 313.893311 -275.71304)
			(xy 313.928804 -275.747132) (xy 313.958369 -275.786476) (xy 313.98124 -275.830053) (xy 313.996824 -275.876734)
			(xy 314.004719 -275.925311) (xy 314.005214 -275.949918) (xy 314.344062 -275.949918) (xy 314.348022 -275.900864)
			(xy 314.359799 -275.85308) (xy 314.37909 -275.807804) (xy 314.405393 -275.766208) (xy 314.438028 -275.729371)
			(xy 314.476149 -275.698246) (xy 314.51877 -275.673639) (xy 314.564786 -275.656187) (xy 314.613005 -275.646343)
			(xy 314.66218 -275.644362) (xy 314.711035 -275.650294) (xy 314.758306 -275.663986) (xy 314.802768 -275.685084)
			(xy 314.843271 -275.71304) (xy 314.878764 -275.747132) (xy 314.908329 -275.786476) (xy 314.9312 -275.830053)
			(xy 314.946784 -275.876734) (xy 314.954679 -275.925311) (xy 314.955174 -275.949918) (xy 314.954679 -275.974525)
			(xy 314.946784 -276.023102) (xy 314.9312 -276.069783) (xy 314.908329 -276.11336) (xy 314.878764 -276.152704)
			(xy 314.843271 -276.186796) (xy 314.802768 -276.214752) (xy 314.758306 -276.23585) (xy 314.711035 -276.249542)
			(xy 314.66218 -276.255474) (xy 314.613005 -276.253493) (xy 314.564786 -276.243649) (xy 314.51877 -276.226197)
			(xy 314.476149 -276.20159) (xy 314.438028 -276.170465) (xy 314.405393 -276.133628) (xy 314.37909 -276.092032)
			(xy 314.359799 -276.046756) (xy 314.348022 -275.998972) (xy 314.344062 -275.949918) (xy 314.005214 -275.949918)
			(xy 314.004719 -275.974525) (xy 313.996824 -276.023102) (xy 313.98124 -276.069783) (xy 313.958369 -276.11336)
			(xy 313.928804 -276.152704) (xy 313.893311 -276.186796) (xy 313.852808 -276.214752) (xy 313.808346 -276.23585)
			(xy 313.761075 -276.249542) (xy 313.71222 -276.255474) (xy 313.663045 -276.253493) (xy 313.614826 -276.243649)
			(xy 313.56881 -276.226197) (xy 313.526189 -276.20159) (xy 313.488068 -276.170465) (xy 313.455433 -276.133628)
			(xy 313.42913 -276.092032) (xy 313.409839 -276.046756) (xy 313.398062 -275.998972) (xy 313.394102 -275.949918)
			(xy 313.055254 -275.949918) (xy 313.054759 -275.974525) (xy 313.046864 -276.023102) (xy 313.03128 -276.069783)
			(xy 313.008409 -276.11336) (xy 312.978844 -276.152704) (xy 312.943351 -276.186796) (xy 312.902848 -276.214752)
			(xy 312.858386 -276.23585) (xy 312.811115 -276.249542) (xy 312.76226 -276.255474) (xy 312.713085 -276.253493)
			(xy 312.664866 -276.243649) (xy 312.61885 -276.226197) (xy 312.576229 -276.20159) (xy 312.538108 -276.170465)
			(xy 312.505473 -276.133628) (xy 312.47917 -276.092032) (xy 312.459879 -276.046756) (xy 312.448102 -275.998972)
			(xy 312.444142 -275.949918) (xy 312.12663 -275.949918) (xy 312.126126 -275.975626) (xy 312.118083 -276.026408)
			(xy 312.102195 -276.075307) (xy 312.078852 -276.121119) (xy 312.048631 -276.162715) (xy 312.012275 -276.199071)
			(xy 311.970679 -276.229292) (xy 311.924867 -276.252635) (xy 311.875968 -276.268523) (xy 311.825186 -276.276566)
			(xy 311.77377 -276.276566) (xy 311.722988 -276.268523) (xy 311.674089 -276.252635) (xy 311.628277 -276.229292)
			(xy 311.586681 -276.199071) (xy 311.550325 -276.162715) (xy 311.520104 -276.121119) (xy 311.496761 -276.075307)
			(xy 311.480873 -276.026408) (xy 311.47283 -275.975626) (xy 311.154406 -275.975626) (xy 311.14669 -276.023102)
			(xy 311.131106 -276.069783) (xy 311.108235 -276.11336) (xy 311.07867 -276.152704) (xy 311.043177 -276.186796)
			(xy 311.002674 -276.214752) (xy 310.958212 -276.23585) (xy 310.910941 -276.249542) (xy 310.862086 -276.255474)
			(xy 310.812911 -276.253493) (xy 310.764692 -276.243649) (xy 310.718676 -276.226197) (xy 310.676055 -276.20159)
			(xy 310.637934 -276.170465) (xy 310.605299 -276.133628) (xy 310.578996 -276.092032) (xy 310.559705 -276.046756)
			(xy 310.547928 -275.998972) (xy 310.543968 -275.949918) (xy 310.22671 -275.949918) (xy 310.226206 -275.975626)
			(xy 310.218163 -276.026408) (xy 310.202275 -276.075307) (xy 310.178932 -276.121119) (xy 310.148711 -276.162715)
			(xy 310.112355 -276.199071) (xy 310.070759 -276.229292) (xy 310.024947 -276.252635) (xy 309.976048 -276.268523)
			(xy 309.925266 -276.276566) (xy 309.87385 -276.276566) (xy 309.823068 -276.268523) (xy 309.774169 -276.252635)
			(xy 309.728357 -276.229292) (xy 309.686761 -276.199071) (xy 309.650405 -276.162715) (xy 309.620184 -276.121119)
			(xy 309.596841 -276.075307) (xy 309.580953 -276.026408) (xy 309.57291 -275.975626) (xy 309.254486 -275.975626)
			(xy 309.24677 -276.023102) (xy 309.231186 -276.069783) (xy 309.208315 -276.11336) (xy 309.17875 -276.152704)
			(xy 309.143257 -276.186796) (xy 309.102754 -276.214752) (xy 309.058292 -276.23585) (xy 309.011021 -276.249542)
			(xy 308.962166 -276.255474) (xy 308.912991 -276.253493) (xy 308.864772 -276.243649) (xy 308.818756 -276.226197)
			(xy 308.776135 -276.20159) (xy 308.738014 -276.170465) (xy 308.705379 -276.133628) (xy 308.679076 -276.092032)
			(xy 308.659785 -276.046756) (xy 308.648008 -275.998972) (xy 308.644048 -275.949918) (xy 308.326785 -275.949918)
			(xy 308.326286 -275.975372) (xy 308.318243 -276.026154) (xy 308.302355 -276.075053) (xy 308.279012 -276.120865)
			(xy 308.248791 -276.162461) (xy 308.212435 -276.198817) (xy 308.170839 -276.229038) (xy 308.125027 -276.252381)
			(xy 308.076128 -276.268269) (xy 308.025346 -276.276312) (xy 307.97393 -276.276312) (xy 307.923148 -276.268269)
			(xy 307.874249 -276.252381) (xy 307.828437 -276.229038) (xy 307.786841 -276.198817) (xy 307.750485 -276.162461)
			(xy 307.720264 -276.120865) (xy 307.696921 -276.075053) (xy 307.681033 -276.026154) (xy 307.67299 -275.975372)
			(xy 307.354607 -275.975372) (xy 307.34685 -276.023102) (xy 307.331266 -276.069783) (xy 307.308395 -276.11336)
			(xy 307.27883 -276.152704) (xy 307.243337 -276.186796) (xy 307.202834 -276.214752) (xy 307.158372 -276.23585)
			(xy 307.111101 -276.249542) (xy 307.062246 -276.255474) (xy 307.013071 -276.253493) (xy 306.964852 -276.243649)
			(xy 306.918836 -276.226197) (xy 306.876215 -276.20159) (xy 306.838094 -276.170465) (xy 306.805459 -276.133628)
			(xy 306.779156 -276.092032) (xy 306.759865 -276.046756) (xy 306.748088 -275.998972) (xy 306.744128 -275.949918)
			(xy 306.426616 -275.949918) (xy 306.426112 -275.975626) (xy 306.418069 -276.026408) (xy 306.402181 -276.075307)
			(xy 306.378838 -276.121119) (xy 306.348617 -276.162715) (xy 306.312261 -276.199071) (xy 306.270665 -276.229292)
			(xy 306.224853 -276.252635) (xy 306.175954 -276.268523) (xy 306.125172 -276.276566) (xy 306.073756 -276.276566)
			(xy 306.022974 -276.268523) (xy 305.974075 -276.252635) (xy 305.928263 -276.229292) (xy 305.886667 -276.199071)
			(xy 305.850311 -276.162715) (xy 305.82009 -276.121119) (xy 305.796747 -276.075307) (xy 305.780859 -276.026408)
			(xy 305.772816 -275.975626) (xy 305.454392 -275.975626) (xy 305.446676 -276.023102) (xy 305.431092 -276.069783)
			(xy 305.408221 -276.11336) (xy 305.378656 -276.152704) (xy 305.343163 -276.186796) (xy 305.30266 -276.214752)
			(xy 305.258198 -276.23585) (xy 305.210927 -276.249542) (xy 305.162072 -276.255474) (xy 305.112897 -276.253493)
			(xy 305.064678 -276.243649) (xy 305.018662 -276.226197) (xy 304.976041 -276.20159) (xy 304.93792 -276.170465)
			(xy 304.905285 -276.133628) (xy 304.878982 -276.092032) (xy 304.859691 -276.046756) (xy 304.847914 -275.998972)
			(xy 304.843954 -275.949918) (xy 304.526691 -275.949918) (xy 304.526192 -275.975372) (xy 304.518149 -276.026154)
			(xy 304.502261 -276.075053) (xy 304.478918 -276.120865) (xy 304.448697 -276.162461) (xy 304.412341 -276.198817)
			(xy 304.370745 -276.229038) (xy 304.324933 -276.252381) (xy 304.276034 -276.268269) (xy 304.225252 -276.276312)
			(xy 304.173836 -276.276312) (xy 304.123054 -276.268269) (xy 304.074155 -276.252381) (xy 304.028343 -276.229038)
			(xy 303.986747 -276.198817) (xy 303.950391 -276.162461) (xy 303.92017 -276.120865) (xy 303.896827 -276.075053)
			(xy 303.880939 -276.026154) (xy 303.872896 -275.975372) (xy 303.554513 -275.975372) (xy 303.546756 -276.023102)
			(xy 303.531172 -276.069783) (xy 303.508301 -276.11336) (xy 303.478736 -276.152704) (xy 303.443243 -276.186796)
			(xy 303.40274 -276.214752) (xy 303.358278 -276.23585) (xy 303.311007 -276.249542) (xy 303.262152 -276.255474)
			(xy 303.212977 -276.253493) (xy 303.164758 -276.243649) (xy 303.118742 -276.226197) (xy 303.076121 -276.20159)
			(xy 303.038 -276.170465) (xy 303.005365 -276.133628) (xy 302.979062 -276.092032) (xy 302.959771 -276.046756)
			(xy 302.947994 -275.998972) (xy 302.944034 -275.949918) (xy 302.626522 -275.949918) (xy 302.626018 -275.975626)
			(xy 302.617975 -276.026408) (xy 302.602087 -276.075307) (xy 302.578744 -276.121119) (xy 302.548523 -276.162715)
			(xy 302.512167 -276.199071) (xy 302.470571 -276.229292) (xy 302.424759 -276.252635) (xy 302.37586 -276.268523)
			(xy 302.325078 -276.276566) (xy 302.273662 -276.276566) (xy 302.22288 -276.268523) (xy 302.173981 -276.252635)
			(xy 302.128169 -276.229292) (xy 302.086573 -276.199071) (xy 302.050217 -276.162715) (xy 302.019996 -276.121119)
			(xy 301.996653 -276.075307) (xy 301.980765 -276.026408) (xy 301.972722 -275.975626) (xy 301.654552 -275.975626)
			(xy 301.646836 -276.023102) (xy 301.631252 -276.069783) (xy 301.608381 -276.11336) (xy 301.578816 -276.152704)
			(xy 301.543323 -276.186796) (xy 301.50282 -276.214752) (xy 301.458358 -276.23585) (xy 301.411087 -276.249542)
			(xy 301.362232 -276.255474) (xy 301.313057 -276.253493) (xy 301.264838 -276.243649) (xy 301.218822 -276.226197)
			(xy 301.176201 -276.20159) (xy 301.13808 -276.170465) (xy 301.105445 -276.133628) (xy 301.079142 -276.092032)
			(xy 301.059851 -276.046756) (xy 301.048074 -275.998972) (xy 301.044114 -275.949918) (xy 300.726597 -275.949918)
			(xy 300.726098 -275.975372) (xy 300.718055 -276.026154) (xy 300.702167 -276.075053) (xy 300.678824 -276.120865)
			(xy 300.648603 -276.162461) (xy 300.612247 -276.198817) (xy 300.570651 -276.229038) (xy 300.524839 -276.252381)
			(xy 300.47594 -276.268269) (xy 300.425158 -276.276312) (xy 300.373742 -276.276312) (xy 300.32296 -276.268269)
			(xy 300.274061 -276.252381) (xy 300.228249 -276.229038) (xy 300.186653 -276.198817) (xy 300.150297 -276.162461)
			(xy 300.120076 -276.120865) (xy 300.096733 -276.075053) (xy 300.080845 -276.026154) (xy 300.072802 -275.975372)
			(xy 299.754419 -275.975372) (xy 299.746662 -276.023102) (xy 299.731078 -276.069783) (xy 299.708207 -276.11336)
			(xy 299.678642 -276.152704) (xy 299.643149 -276.186796) (xy 299.602646 -276.214752) (xy 299.558184 -276.23585)
			(xy 299.510913 -276.249542) (xy 299.462058 -276.255474) (xy 299.412883 -276.253493) (xy 299.364664 -276.243649)
			(xy 299.318648 -276.226197) (xy 299.276027 -276.20159) (xy 299.237906 -276.170465) (xy 299.205271 -276.133628)
			(xy 299.178968 -276.092032) (xy 299.159677 -276.046756) (xy 299.1479 -275.998972) (xy 299.14394 -275.949918)
			(xy 298.826682 -275.949918) (xy 298.826178 -275.975626) (xy 298.818135 -276.026408) (xy 298.802247 -276.075307)
			(xy 298.778904 -276.121119) (xy 298.748683 -276.162715) (xy 298.712327 -276.199071) (xy 298.670731 -276.229292)
			(xy 298.624919 -276.252635) (xy 298.57602 -276.268523) (xy 298.525238 -276.276566) (xy 298.473822 -276.276566)
			(xy 298.42304 -276.268523) (xy 298.374141 -276.252635) (xy 298.328329 -276.229292) (xy 298.286733 -276.199071)
			(xy 298.250377 -276.162715) (xy 298.220156 -276.121119) (xy 298.196813 -276.075307) (xy 298.180925 -276.026408)
			(xy 298.172882 -275.975626) (xy 297.854458 -275.975626) (xy 297.846742 -276.023102) (xy 297.831158 -276.069783)
			(xy 297.808287 -276.11336) (xy 297.778722 -276.152704) (xy 297.743229 -276.186796) (xy 297.702726 -276.214752)
			(xy 297.658264 -276.23585) (xy 297.610993 -276.249542) (xy 297.562138 -276.255474) (xy 297.512963 -276.253493)
			(xy 297.464744 -276.243649) (xy 297.418728 -276.226197) (xy 297.376107 -276.20159) (xy 297.337986 -276.170465)
			(xy 297.305351 -276.133628) (xy 297.279048 -276.092032) (xy 297.259757 -276.046756) (xy 297.24798 -275.998972)
			(xy 297.24402 -275.949918) (xy 296.926757 -275.949918) (xy 296.926258 -275.975372) (xy 296.918215 -276.026154)
			(xy 296.902327 -276.075053) (xy 296.878984 -276.120865) (xy 296.848763 -276.162461) (xy 296.812407 -276.198817)
			(xy 296.770811 -276.229038) (xy 296.724999 -276.252381) (xy 296.6761 -276.268269) (xy 296.625318 -276.276312)
			(xy 296.573902 -276.276312) (xy 296.52312 -276.268269) (xy 296.474221 -276.252381) (xy 296.428409 -276.229038)
			(xy 296.386813 -276.198817) (xy 296.350457 -276.162461) (xy 296.320236 -276.120865) (xy 296.296893 -276.075053)
			(xy 296.281005 -276.026154) (xy 296.272962 -275.975372) (xy 295.954579 -275.975372) (xy 295.946822 -276.023102)
			(xy 295.931238 -276.069783) (xy 295.908367 -276.11336) (xy 295.878802 -276.152704) (xy 295.843309 -276.186796)
			(xy 295.802806 -276.214752) (xy 295.758344 -276.23585) (xy 295.711073 -276.249542) (xy 295.662218 -276.255474)
			(xy 295.613043 -276.253493) (xy 295.564824 -276.243649) (xy 295.518808 -276.226197) (xy 295.476187 -276.20159)
			(xy 295.438066 -276.170465) (xy 295.405431 -276.133628) (xy 295.379128 -276.092032) (xy 295.359837 -276.046756)
			(xy 295.34806 -275.998972) (xy 295.3441 -275.949918) (xy 295.026588 -275.949918) (xy 295.026084 -275.975626)
			(xy 295.018041 -276.026408) (xy 295.002153 -276.075307) (xy 294.97881 -276.121119) (xy 294.948589 -276.162715)
			(xy 294.912233 -276.199071) (xy 294.870637 -276.229292) (xy 294.824825 -276.252635) (xy 294.775926 -276.268523)
			(xy 294.725144 -276.276566) (xy 294.673728 -276.276566) (xy 294.622946 -276.268523) (xy 294.574047 -276.252635)
			(xy 294.528235 -276.229292) (xy 294.486639 -276.199071) (xy 294.450283 -276.162715) (xy 294.420062 -276.121119)
			(xy 294.396719 -276.075307) (xy 294.380831 -276.026408) (xy 294.372788 -275.975626) (xy 294.054364 -275.975626)
			(xy 294.046648 -276.023102) (xy 294.031064 -276.069783) (xy 294.008193 -276.11336) (xy 293.978628 -276.152704)
			(xy 293.943135 -276.186796) (xy 293.902632 -276.214752) (xy 293.85817 -276.23585) (xy 293.810899 -276.249542)
			(xy 293.762044 -276.255474) (xy 293.712869 -276.253493) (xy 293.66465 -276.243649) (xy 293.618634 -276.226197)
			(xy 293.576013 -276.20159) (xy 293.537892 -276.170465) (xy 293.505257 -276.133628) (xy 293.478954 -276.092032)
			(xy 293.459663 -276.046756) (xy 293.447886 -275.998972) (xy 293.443926 -275.949918) (xy 293.126663 -275.949918)
			(xy 293.126164 -275.975372) (xy 293.118121 -276.026154) (xy 293.102233 -276.075053) (xy 293.07889 -276.120865)
			(xy 293.048669 -276.162461) (xy 293.012313 -276.198817) (xy 292.970717 -276.229038) (xy 292.924905 -276.252381)
			(xy 292.876006 -276.268269) (xy 292.825224 -276.276312) (xy 292.773808 -276.276312) (xy 292.723026 -276.268269)
			(xy 292.674127 -276.252381) (xy 292.628315 -276.229038) (xy 292.586719 -276.198817) (xy 292.550363 -276.162461)
			(xy 292.520142 -276.120865) (xy 292.496799 -276.075053) (xy 292.480911 -276.026154) (xy 292.472868 -275.975372)
			(xy 292.154485 -275.975372) (xy 292.146728 -276.023102) (xy 292.131144 -276.069783) (xy 292.108273 -276.11336)
			(xy 292.078708 -276.152704) (xy 292.043215 -276.186796) (xy 292.002712 -276.214752) (xy 291.95825 -276.23585)
			(xy 291.910979 -276.249542) (xy 291.862124 -276.255474) (xy 291.812949 -276.253493) (xy 291.76473 -276.243649)
			(xy 291.718714 -276.226197) (xy 291.676093 -276.20159) (xy 291.637972 -276.170465) (xy 291.605337 -276.133628)
			(xy 291.579034 -276.092032) (xy 291.559743 -276.046756) (xy 291.547966 -275.998972) (xy 291.544006 -275.949918)
			(xy 291.227002 -275.949918) (xy 291.226498 -275.975626) (xy 291.218455 -276.026408) (xy 291.202567 -276.075307)
			(xy 291.179224 -276.121119) (xy 291.149003 -276.162715) (xy 291.112647 -276.199071) (xy 291.071051 -276.229292)
			(xy 291.025239 -276.252635) (xy 290.97634 -276.268523) (xy 290.925558 -276.276566) (xy 290.874142 -276.276566)
			(xy 290.82336 -276.268523) (xy 290.774461 -276.252635) (xy 290.728649 -276.229292) (xy 290.687053 -276.199071)
			(xy 290.650697 -276.162715) (xy 290.620476 -276.121119) (xy 290.597133 -276.075307) (xy 290.581245 -276.026408)
			(xy 290.573202 -275.975626) (xy 290.254524 -275.975626) (xy 290.246808 -276.023102) (xy 290.231224 -276.069783)
			(xy 290.208353 -276.11336) (xy 290.178788 -276.152704) (xy 290.143295 -276.186796) (xy 290.102792 -276.214752)
			(xy 290.05833 -276.23585) (xy 290.011059 -276.249542) (xy 289.962204 -276.255474) (xy 289.913029 -276.253493)
			(xy 289.86481 -276.243649) (xy 289.818794 -276.226197) (xy 289.776173 -276.20159) (xy 289.738052 -276.170465)
			(xy 289.705417 -276.133628) (xy 289.679114 -276.092032) (xy 289.659823 -276.046756) (xy 289.648046 -275.998972)
			(xy 289.644086 -275.949918) (xy 289.327082 -275.949918) (xy 289.326578 -275.975626) (xy 289.318535 -276.026408)
			(xy 289.302647 -276.075307) (xy 289.279304 -276.121119) (xy 289.249083 -276.162715) (xy 289.212727 -276.199071)
			(xy 289.171131 -276.229292) (xy 289.125319 -276.252635) (xy 289.07642 -276.268523) (xy 289.025638 -276.276566)
			(xy 288.974222 -276.276566) (xy 288.92344 -276.268523) (xy 288.874541 -276.252635) (xy 288.828729 -276.229292)
			(xy 288.787133 -276.199071) (xy 288.750777 -276.162715) (xy 288.720556 -276.121119) (xy 288.697213 -276.075307)
			(xy 288.681325 -276.026408) (xy 288.673282 -275.975626) (xy 288.35435 -275.975626) (xy 288.346634 -276.023102)
			(xy 288.33105 -276.069783) (xy 288.308179 -276.11336) (xy 288.278614 -276.152704) (xy 288.243121 -276.186796)
			(xy 288.202618 -276.214752) (xy 288.158156 -276.23585) (xy 288.110885 -276.249542) (xy 288.06203 -276.255474)
			(xy 288.012855 -276.253493) (xy 287.964636 -276.243649) (xy 287.91862 -276.226197) (xy 287.875999 -276.20159)
			(xy 287.837878 -276.170465) (xy 287.805243 -276.133628) (xy 287.77894 -276.092032) (xy 287.759649 -276.046756)
			(xy 287.747872 -275.998972) (xy 287.743912 -275.949918) (xy 287.426908 -275.949918) (xy 287.426404 -275.975626)
			(xy 287.418361 -276.026408) (xy 287.402473 -276.075307) (xy 287.37913 -276.121119) (xy 287.348909 -276.162715)
			(xy 287.312553 -276.199071) (xy 287.270957 -276.229292) (xy 287.225145 -276.252635) (xy 287.176246 -276.268523)
			(xy 287.125464 -276.276566) (xy 287.074048 -276.276566) (xy 287.023266 -276.268523) (xy 286.974367 -276.252635)
			(xy 286.928555 -276.229292) (xy 286.886959 -276.199071) (xy 286.850603 -276.162715) (xy 286.820382 -276.121119)
			(xy 286.797039 -276.075307) (xy 286.781151 -276.026408) (xy 286.773108 -275.975626) (xy 286.45443 -275.975626)
			(xy 286.446714 -276.023102) (xy 286.43113 -276.069783) (xy 286.408259 -276.11336) (xy 286.378694 -276.152704)
			(xy 286.343201 -276.186796) (xy 286.302698 -276.214752) (xy 286.258236 -276.23585) (xy 286.210965 -276.249542)
			(xy 286.16211 -276.255474) (xy 286.112935 -276.253493) (xy 286.064716 -276.243649) (xy 286.0187 -276.226197)
			(xy 285.976079 -276.20159) (xy 285.937958 -276.170465) (xy 285.905323 -276.133628) (xy 285.87902 -276.092032)
			(xy 285.859729 -276.046756) (xy 285.847952 -275.998972) (xy 285.843992 -275.949918) (xy 285.526988 -275.949918)
			(xy 285.526484 -275.975626) (xy 285.518441 -276.026408) (xy 285.502553 -276.075307) (xy 285.47921 -276.121119)
			(xy 285.448989 -276.162715) (xy 285.412633 -276.199071) (xy 285.371037 -276.229292) (xy 285.325225 -276.252635)
			(xy 285.276326 -276.268523) (xy 285.225544 -276.276566) (xy 285.174128 -276.276566) (xy 285.123346 -276.268523)
			(xy 285.074447 -276.252635) (xy 285.028635 -276.229292) (xy 284.987039 -276.199071) (xy 284.950683 -276.162715)
			(xy 284.920462 -276.121119) (xy 284.897119 -276.075307) (xy 284.881231 -276.026408) (xy 284.873188 -275.975626)
			(xy 284.55451 -275.975626) (xy 284.546794 -276.023102) (xy 284.53121 -276.069783) (xy 284.508339 -276.11336)
			(xy 284.478774 -276.152704) (xy 284.443281 -276.186796) (xy 284.402778 -276.214752) (xy 284.358316 -276.23585)
			(xy 284.311045 -276.249542) (xy 284.26219 -276.255474) (xy 284.213015 -276.253493) (xy 284.164796 -276.243649)
			(xy 284.11878 -276.226197) (xy 284.076159 -276.20159) (xy 284.038038 -276.170465) (xy 284.005403 -276.133628)
			(xy 283.9791 -276.092032) (xy 283.959809 -276.046756) (xy 283.948032 -275.998972) (xy 283.944072 -275.949918)
			(xy 283.627068 -275.949918) (xy 283.626564 -275.975626) (xy 283.618521 -276.026408) (xy 283.602633 -276.075307)
			(xy 283.57929 -276.121119) (xy 283.549069 -276.162715) (xy 283.512713 -276.199071) (xy 283.471117 -276.229292)
			(xy 283.425305 -276.252635) (xy 283.376406 -276.268523) (xy 283.325624 -276.276566) (xy 283.274208 -276.276566)
			(xy 283.223426 -276.268523) (xy 283.174527 -276.252635) (xy 283.128715 -276.229292) (xy 283.087119 -276.199071)
			(xy 283.050763 -276.162715) (xy 283.020542 -276.121119) (xy 282.997199 -276.075307) (xy 282.981311 -276.026408)
			(xy 282.973268 -275.975626) (xy 282.654336 -275.975626) (xy 282.64662 -276.023102) (xy 282.631036 -276.069783)
			(xy 282.608165 -276.11336) (xy 282.5786 -276.152704) (xy 282.543107 -276.186796) (xy 282.502604 -276.214752)
			(xy 282.458142 -276.23585) (xy 282.410871 -276.249542) (xy 282.362016 -276.255474) (xy 282.312841 -276.253493)
			(xy 282.264622 -276.243649) (xy 282.218606 -276.226197) (xy 282.175985 -276.20159) (xy 282.137864 -276.170465)
			(xy 282.105229 -276.133628) (xy 282.078926 -276.092032) (xy 282.059635 -276.046756) (xy 282.047858 -275.998972)
			(xy 282.043898 -275.949918) (xy 281.726894 -275.949918) (xy 281.72639 -275.975626) (xy 281.718347 -276.026408)
			(xy 281.702459 -276.075307) (xy 281.679116 -276.121119) (xy 281.648895 -276.162715) (xy 281.612539 -276.199071)
			(xy 281.570943 -276.229292) (xy 281.525131 -276.252635) (xy 281.476232 -276.268523) (xy 281.42545 -276.276566)
			(xy 281.374034 -276.276566) (xy 281.323252 -276.268523) (xy 281.274353 -276.252635) (xy 281.228541 -276.229292)
			(xy 281.186945 -276.199071) (xy 281.150589 -276.162715) (xy 281.120368 -276.121119) (xy 281.097025 -276.075307)
			(xy 281.081137 -276.026408) (xy 281.073094 -275.975626) (xy 280.754416 -275.975626) (xy 280.7467 -276.023102)
			(xy 280.731116 -276.069783) (xy 280.708245 -276.11336) (xy 280.67868 -276.152704) (xy 280.643187 -276.186796)
			(xy 280.602684 -276.214752) (xy 280.558222 -276.23585) (xy 280.510951 -276.249542) (xy 280.462096 -276.255474)
			(xy 280.412921 -276.253493) (xy 280.364702 -276.243649) (xy 280.318686 -276.226197) (xy 280.276065 -276.20159)
			(xy 280.237944 -276.170465) (xy 280.205309 -276.133628) (xy 280.179006 -276.092032) (xy 280.159715 -276.046756)
			(xy 280.147938 -275.998972) (xy 280.143978 -275.949918) (xy 279.826974 -275.949918) (xy 279.82647 -275.975626)
			(xy 279.818427 -276.026408) (xy 279.802539 -276.075307) (xy 279.779196 -276.121119) (xy 279.748975 -276.162715)
			(xy 279.712619 -276.199071) (xy 279.671023 -276.229292) (xy 279.625211 -276.252635) (xy 279.576312 -276.268523)
			(xy 279.52553 -276.276566) (xy 279.474114 -276.276566) (xy 279.423332 -276.268523) (xy 279.374433 -276.252635)
			(xy 279.328621 -276.229292) (xy 279.287025 -276.199071) (xy 279.250669 -276.162715) (xy 279.220448 -276.121119)
			(xy 279.197105 -276.075307) (xy 279.181217 -276.026408) (xy 279.173174 -275.975626) (xy 278.854496 -275.975626)
			(xy 278.84678 -276.023102) (xy 278.831196 -276.069783) (xy 278.808325 -276.11336) (xy 278.77876 -276.152704)
			(xy 278.743267 -276.186796) (xy 278.702764 -276.214752) (xy 278.658302 -276.23585) (xy 278.611031 -276.249542)
			(xy 278.562176 -276.255474) (xy 278.513001 -276.253493) (xy 278.464782 -276.243649) (xy 278.418766 -276.226197)
			(xy 278.376145 -276.20159) (xy 278.338024 -276.170465) (xy 278.305389 -276.133628) (xy 278.279086 -276.092032)
			(xy 278.259795 -276.046756) (xy 278.248018 -275.998972) (xy 278.244058 -275.949918) (xy 277.927054 -275.949918)
			(xy 277.92655 -275.975626) (xy 277.918507 -276.026408) (xy 277.902619 -276.075307) (xy 277.879276 -276.121119)
			(xy 277.849055 -276.162715) (xy 277.812699 -276.199071) (xy 277.771103 -276.229292) (xy 277.725291 -276.252635)
			(xy 277.676392 -276.268523) (xy 277.62561 -276.276566) (xy 277.574194 -276.276566) (xy 277.523412 -276.268523)
			(xy 277.474513 -276.252635) (xy 277.428701 -276.229292) (xy 277.387105 -276.199071) (xy 277.350749 -276.162715)
			(xy 277.320528 -276.121119) (xy 277.297185 -276.075307) (xy 277.281297 -276.026408) (xy 277.273254 -275.975626)
			(xy 276.954322 -275.975626) (xy 276.946606 -276.023102) (xy 276.931022 -276.069783) (xy 276.908151 -276.11336)
			(xy 276.878586 -276.152704) (xy 276.843093 -276.186796) (xy 276.80259 -276.214752) (xy 276.758128 -276.23585)
			(xy 276.710857 -276.249542) (xy 276.662002 -276.255474) (xy 276.612827 -276.253493) (xy 276.564608 -276.243649)
			(xy 276.518592 -276.226197) (xy 276.475971 -276.20159) (xy 276.43785 -276.170465) (xy 276.405215 -276.133628)
			(xy 276.378912 -276.092032) (xy 276.359621 -276.046756) (xy 276.347844 -275.998972) (xy 276.343884 -275.949918)
			(xy 198.85533 -275.949918) (xy 198.854835 -275.974525) (xy 198.84694 -276.023102) (xy 198.831356 -276.069783)
			(xy 198.808485 -276.11336) (xy 198.77892 -276.152704) (xy 198.743427 -276.186796) (xy 198.702924 -276.214752)
			(xy 198.658462 -276.23585) (xy 198.611191 -276.249542) (xy 198.562336 -276.255474) (xy 198.513161 -276.253493)
			(xy 198.464942 -276.243649) (xy 198.418926 -276.226197) (xy 198.376305 -276.20159) (xy 198.338184 -276.170465)
			(xy 198.305549 -276.133628) (xy 198.279246 -276.092032) (xy 198.259955 -276.046756) (xy 198.248178 -275.998972)
			(xy 198.244218 -275.949918) (xy 197.90537 -275.949918) (xy 197.904875 -275.974525) (xy 197.89698 -276.023102)
			(xy 197.881396 -276.069783) (xy 197.858525 -276.11336) (xy 197.82896 -276.152704) (xy 197.793467 -276.186796)
			(xy 197.752964 -276.214752) (xy 197.708502 -276.23585) (xy 197.661231 -276.249542) (xy 197.612376 -276.255474)
			(xy 197.563201 -276.253493) (xy 197.514982 -276.243649) (xy 197.468966 -276.226197) (xy 197.426345 -276.20159)
			(xy 197.388224 -276.170465) (xy 197.355589 -276.133628) (xy 197.329286 -276.092032) (xy 197.309995 -276.046756)
			(xy 197.298218 -275.998972) (xy 197.294258 -275.949918) (xy 196.95541 -275.949918) (xy 196.954915 -275.974525)
			(xy 196.94702 -276.023102) (xy 196.931436 -276.069783) (xy 196.908565 -276.11336) (xy 196.879 -276.152704)
			(xy 196.843507 -276.186796) (xy 196.803004 -276.214752) (xy 196.758542 -276.23585) (xy 196.711271 -276.249542)
			(xy 196.662416 -276.255474) (xy 196.613241 -276.253493) (xy 196.565022 -276.243649) (xy 196.519006 -276.226197)
			(xy 196.476385 -276.20159) (xy 196.438264 -276.170465) (xy 196.405629 -276.133628) (xy 196.379326 -276.092032)
			(xy 196.360035 -276.046756) (xy 196.348258 -275.998972) (xy 196.344298 -275.949918) (xy 196.026786 -275.949918)
			(xy 196.026282 -275.975626) (xy 196.018239 -276.026408) (xy 196.002351 -276.075307) (xy 195.979008 -276.121119)
			(xy 195.948787 -276.162715) (xy 195.912431 -276.199071) (xy 195.870835 -276.229292) (xy 195.825023 -276.252635)
			(xy 195.776124 -276.268523) (xy 195.725342 -276.276566) (xy 195.673926 -276.276566) (xy 195.623144 -276.268523)
			(xy 195.574245 -276.252635) (xy 195.528433 -276.229292) (xy 195.486837 -276.199071) (xy 195.450481 -276.162715)
			(xy 195.42026 -276.121119) (xy 195.396917 -276.075307) (xy 195.381029 -276.026408) (xy 195.372986 -275.975626)
			(xy 195.054562 -275.975626) (xy 195.046846 -276.023102) (xy 195.031262 -276.069783) (xy 195.008391 -276.11336)
			(xy 194.978826 -276.152704) (xy 194.943333 -276.186796) (xy 194.90283 -276.214752) (xy 194.858368 -276.23585)
			(xy 194.811097 -276.249542) (xy 194.762242 -276.255474) (xy 194.713067 -276.253493) (xy 194.664848 -276.243649)
			(xy 194.618832 -276.226197) (xy 194.576211 -276.20159) (xy 194.53809 -276.170465) (xy 194.505455 -276.133628)
			(xy 194.479152 -276.092032) (xy 194.459861 -276.046756) (xy 194.448084 -275.998972) (xy 194.444124 -275.949918)
			(xy 194.126866 -275.949918) (xy 194.126362 -275.975626) (xy 194.118319 -276.026408) (xy 194.102431 -276.075307)
			(xy 194.079088 -276.121119) (xy 194.048867 -276.162715) (xy 194.012511 -276.199071) (xy 193.970915 -276.229292)
			(xy 193.925103 -276.252635) (xy 193.876204 -276.268523) (xy 193.825422 -276.276566) (xy 193.774006 -276.276566)
			(xy 193.723224 -276.268523) (xy 193.674325 -276.252635) (xy 193.628513 -276.229292) (xy 193.586917 -276.199071)
			(xy 193.550561 -276.162715) (xy 193.52034 -276.121119) (xy 193.496997 -276.075307) (xy 193.481109 -276.026408)
			(xy 193.473066 -275.975626) (xy 193.154642 -275.975626) (xy 193.146926 -276.023102) (xy 193.131342 -276.069783)
			(xy 193.108471 -276.11336) (xy 193.078906 -276.152704) (xy 193.043413 -276.186796) (xy 193.00291 -276.214752)
			(xy 192.958448 -276.23585) (xy 192.911177 -276.249542) (xy 192.862322 -276.255474) (xy 192.813147 -276.253493)
			(xy 192.764928 -276.243649) (xy 192.718912 -276.226197) (xy 192.676291 -276.20159) (xy 192.63817 -276.170465)
			(xy 192.605535 -276.133628) (xy 192.579232 -276.092032) (xy 192.559941 -276.046756) (xy 192.548164 -275.998972)
			(xy 192.544204 -275.949918) (xy 192.226941 -275.949918) (xy 192.226442 -275.975372) (xy 192.218399 -276.026154)
			(xy 192.202511 -276.075053) (xy 192.179168 -276.120865) (xy 192.148947 -276.162461) (xy 192.112591 -276.198817)
			(xy 192.070995 -276.229038) (xy 192.025183 -276.252381) (xy 191.976284 -276.268269) (xy 191.925502 -276.276312)
			(xy 191.874086 -276.276312) (xy 191.823304 -276.268269) (xy 191.774405 -276.252381) (xy 191.728593 -276.229038)
			(xy 191.686997 -276.198817) (xy 191.650641 -276.162461) (xy 191.62042 -276.120865) (xy 191.597077 -276.075053)
			(xy 191.581189 -276.026154) (xy 191.573146 -275.975372) (xy 191.254763 -275.975372) (xy 191.247006 -276.023102)
			(xy 191.231422 -276.069783) (xy 191.208551 -276.11336) (xy 191.178986 -276.152704) (xy 191.143493 -276.186796)
			(xy 191.10299 -276.214752) (xy 191.058528 -276.23585) (xy 191.011257 -276.249542) (xy 190.962402 -276.255474)
			(xy 190.913227 -276.253493) (xy 190.865008 -276.243649) (xy 190.818992 -276.226197) (xy 190.776371 -276.20159)
			(xy 190.73825 -276.170465) (xy 190.705615 -276.133628) (xy 190.679312 -276.092032) (xy 190.660021 -276.046756)
			(xy 190.648244 -275.998972) (xy 190.644284 -275.949918) (xy 190.326772 -275.949918) (xy 190.326268 -275.975626)
			(xy 190.318225 -276.026408) (xy 190.302337 -276.075307) (xy 190.278994 -276.121119) (xy 190.248773 -276.162715)
			(xy 190.212417 -276.199071) (xy 190.170821 -276.229292) (xy 190.125009 -276.252635) (xy 190.07611 -276.268523)
			(xy 190.025328 -276.276566) (xy 189.973912 -276.276566) (xy 189.92313 -276.268523) (xy 189.874231 -276.252635)
			(xy 189.828419 -276.229292) (xy 189.786823 -276.199071) (xy 189.750467 -276.162715) (xy 189.720246 -276.121119)
			(xy 189.696903 -276.075307) (xy 189.681015 -276.026408) (xy 189.672972 -275.975626) (xy 189.354548 -275.975626)
			(xy 189.346832 -276.023102) (xy 189.331248 -276.069783) (xy 189.308377 -276.11336) (xy 189.278812 -276.152704)
			(xy 189.243319 -276.186796) (xy 189.202816 -276.214752) (xy 189.158354 -276.23585) (xy 189.111083 -276.249542)
			(xy 189.062228 -276.255474) (xy 189.013053 -276.253493) (xy 188.964834 -276.243649) (xy 188.918818 -276.226197)
			(xy 188.876197 -276.20159) (xy 188.838076 -276.170465) (xy 188.805441 -276.133628) (xy 188.779138 -276.092032)
			(xy 188.759847 -276.046756) (xy 188.74807 -275.998972) (xy 188.74411 -275.949918) (xy 188.426847 -275.949918)
			(xy 188.426348 -275.975372) (xy 188.418305 -276.026154) (xy 188.402417 -276.075053) (xy 188.379074 -276.120865)
			(xy 188.348853 -276.162461) (xy 188.312497 -276.198817) (xy 188.270901 -276.229038) (xy 188.225089 -276.252381)
			(xy 188.17619 -276.268269) (xy 188.125408 -276.276312) (xy 188.073992 -276.276312) (xy 188.02321 -276.268269)
			(xy 187.974311 -276.252381) (xy 187.928499 -276.229038) (xy 187.886903 -276.198817) (xy 187.850547 -276.162461)
			(xy 187.820326 -276.120865) (xy 187.796983 -276.075053) (xy 187.781095 -276.026154) (xy 187.773052 -275.975372)
			(xy 187.454669 -275.975372) (xy 187.446912 -276.023102) (xy 187.431328 -276.069783) (xy 187.408457 -276.11336)
			(xy 187.378892 -276.152704) (xy 187.343399 -276.186796) (xy 187.302896 -276.214752) (xy 187.258434 -276.23585)
			(xy 187.211163 -276.249542) (xy 187.162308 -276.255474) (xy 187.113133 -276.253493) (xy 187.064914 -276.243649)
			(xy 187.018898 -276.226197) (xy 186.976277 -276.20159) (xy 186.938156 -276.170465) (xy 186.905521 -276.133628)
			(xy 186.879218 -276.092032) (xy 186.859927 -276.046756) (xy 186.84815 -275.998972) (xy 186.84419 -275.949918)
			(xy 186.526678 -275.949918) (xy 186.526174 -275.975626) (xy 186.518131 -276.026408) (xy 186.502243 -276.075307)
			(xy 186.4789 -276.121119) (xy 186.448679 -276.162715) (xy 186.412323 -276.199071) (xy 186.370727 -276.229292)
			(xy 186.324915 -276.252635) (xy 186.276016 -276.268523) (xy 186.225234 -276.276566) (xy 186.173818 -276.276566)
			(xy 186.123036 -276.268523) (xy 186.074137 -276.252635) (xy 186.028325 -276.229292) (xy 185.986729 -276.199071)
			(xy 185.950373 -276.162715) (xy 185.920152 -276.121119) (xy 185.896809 -276.075307) (xy 185.880921 -276.026408)
			(xy 185.872878 -275.975626) (xy 185.554708 -275.975626) (xy 185.546992 -276.023102) (xy 185.531408 -276.069783)
			(xy 185.508537 -276.11336) (xy 185.478972 -276.152704) (xy 185.443479 -276.186796) (xy 185.402976 -276.214752)
			(xy 185.358514 -276.23585) (xy 185.311243 -276.249542) (xy 185.262388 -276.255474) (xy 185.213213 -276.253493)
			(xy 185.164994 -276.243649) (xy 185.118978 -276.226197) (xy 185.076357 -276.20159) (xy 185.038236 -276.170465)
			(xy 185.005601 -276.133628) (xy 184.979298 -276.092032) (xy 184.960007 -276.046756) (xy 184.94823 -275.998972)
			(xy 184.94427 -275.949918) (xy 184.626753 -275.949918) (xy 184.626254 -275.975372) (xy 184.618211 -276.026154)
			(xy 184.602323 -276.075053) (xy 184.57898 -276.120865) (xy 184.548759 -276.162461) (xy 184.512403 -276.198817)
			(xy 184.470807 -276.229038) (xy 184.424995 -276.252381) (xy 184.376096 -276.268269) (xy 184.325314 -276.276312)
			(xy 184.273898 -276.276312) (xy 184.223116 -276.268269) (xy 184.174217 -276.252381) (xy 184.128405 -276.229038)
			(xy 184.086809 -276.198817) (xy 184.050453 -276.162461) (xy 184.020232 -276.120865) (xy 183.996889 -276.075053)
			(xy 183.981001 -276.026154) (xy 183.972958 -275.975372) (xy 183.654575 -275.975372) (xy 183.646818 -276.023102)
			(xy 183.631234 -276.069783) (xy 183.608363 -276.11336) (xy 183.578798 -276.152704) (xy 183.543305 -276.186796)
			(xy 183.502802 -276.214752) (xy 183.45834 -276.23585) (xy 183.411069 -276.249542) (xy 183.362214 -276.255474)
			(xy 183.313039 -276.253493) (xy 183.26482 -276.243649) (xy 183.218804 -276.226197) (xy 183.176183 -276.20159)
			(xy 183.138062 -276.170465) (xy 183.105427 -276.133628) (xy 183.079124 -276.092032) (xy 183.059833 -276.046756)
			(xy 183.048056 -275.998972) (xy 183.044096 -275.949918) (xy 182.726838 -275.949918) (xy 182.726334 -275.975626)
			(xy 182.718291 -276.026408) (xy 182.702403 -276.075307) (xy 182.67906 -276.121119) (xy 182.648839 -276.162715)
			(xy 182.612483 -276.199071) (xy 182.570887 -276.229292) (xy 182.525075 -276.252635) (xy 182.476176 -276.268523)
			(xy 182.425394 -276.276566) (xy 182.373978 -276.276566) (xy 182.323196 -276.268523) (xy 182.274297 -276.252635)
			(xy 182.228485 -276.229292) (xy 182.186889 -276.199071) (xy 182.150533 -276.162715) (xy 182.120312 -276.121119)
			(xy 182.096969 -276.075307) (xy 182.081081 -276.026408) (xy 182.073038 -275.975626) (xy 181.754614 -275.975626)
			(xy 181.746898 -276.023102) (xy 181.731314 -276.069783) (xy 181.708443 -276.11336) (xy 181.678878 -276.152704)
			(xy 181.643385 -276.186796) (xy 181.602882 -276.214752) (xy 181.55842 -276.23585) (xy 181.511149 -276.249542)
			(xy 181.462294 -276.255474) (xy 181.413119 -276.253493) (xy 181.3649 -276.243649) (xy 181.318884 -276.226197)
			(xy 181.276263 -276.20159) (xy 181.238142 -276.170465) (xy 181.205507 -276.133628) (xy 181.179204 -276.092032)
			(xy 181.159913 -276.046756) (xy 181.148136 -275.998972) (xy 181.144176 -275.949918) (xy 180.826913 -275.949918)
			(xy 180.826414 -275.975372) (xy 180.818371 -276.026154) (xy 180.802483 -276.075053) (xy 180.77914 -276.120865)
			(xy 180.748919 -276.162461) (xy 180.712563 -276.198817) (xy 180.670967 -276.229038) (xy 180.625155 -276.252381)
			(xy 180.576256 -276.268269) (xy 180.525474 -276.276312) (xy 180.474058 -276.276312) (xy 180.423276 -276.268269)
			(xy 180.374377 -276.252381) (xy 180.328565 -276.229038) (xy 180.286969 -276.198817) (xy 180.250613 -276.162461)
			(xy 180.220392 -276.120865) (xy 180.197049 -276.075053) (xy 180.181161 -276.026154) (xy 180.173118 -275.975372)
			(xy 179.854735 -275.975372) (xy 179.846978 -276.023102) (xy 179.831394 -276.069783) (xy 179.808523 -276.11336)
			(xy 179.778958 -276.152704) (xy 179.743465 -276.186796) (xy 179.702962 -276.214752) (xy 179.6585 -276.23585)
			(xy 179.611229 -276.249542) (xy 179.562374 -276.255474) (xy 179.513199 -276.253493) (xy 179.46498 -276.243649)
			(xy 179.418964 -276.226197) (xy 179.376343 -276.20159) (xy 179.338222 -276.170465) (xy 179.305587 -276.133628)
			(xy 179.279284 -276.092032) (xy 179.259993 -276.046756) (xy 179.248216 -275.998972) (xy 179.244256 -275.949918)
			(xy 178.926744 -275.949918) (xy 178.92624 -275.975626) (xy 178.918197 -276.026408) (xy 178.902309 -276.075307)
			(xy 178.878966 -276.121119) (xy 178.848745 -276.162715) (xy 178.812389 -276.199071) (xy 178.770793 -276.229292)
			(xy 178.724981 -276.252635) (xy 178.676082 -276.268523) (xy 178.6253 -276.276566) (xy 178.573884 -276.276566)
			(xy 178.523102 -276.268523) (xy 178.474203 -276.252635) (xy 178.428391 -276.229292) (xy 178.386795 -276.199071)
			(xy 178.350439 -276.162715) (xy 178.320218 -276.121119) (xy 178.296875 -276.075307) (xy 178.280987 -276.026408)
			(xy 178.272944 -275.975626) (xy 177.95452 -275.975626) (xy 177.946804 -276.023102) (xy 177.93122 -276.069783)
			(xy 177.908349 -276.11336) (xy 177.878784 -276.152704) (xy 177.843291 -276.186796) (xy 177.802788 -276.214752)
			(xy 177.758326 -276.23585) (xy 177.711055 -276.249542) (xy 177.6622 -276.255474) (xy 177.613025 -276.253493)
			(xy 177.564806 -276.243649) (xy 177.51879 -276.226197) (xy 177.476169 -276.20159) (xy 177.438048 -276.170465)
			(xy 177.405413 -276.133628) (xy 177.37911 -276.092032) (xy 177.359819 -276.046756) (xy 177.348042 -275.998972)
			(xy 177.344082 -275.949918) (xy 177.026819 -275.949918) (xy 177.02632 -275.975372) (xy 177.018277 -276.026154)
			(xy 177.002389 -276.075053) (xy 176.979046 -276.120865) (xy 176.948825 -276.162461) (xy 176.912469 -276.198817)
			(xy 176.870873 -276.229038) (xy 176.825061 -276.252381) (xy 176.776162 -276.268269) (xy 176.72538 -276.276312)
			(xy 176.673964 -276.276312) (xy 176.623182 -276.268269) (xy 176.574283 -276.252381) (xy 176.528471 -276.229038)
			(xy 176.486875 -276.198817) (xy 176.450519 -276.162461) (xy 176.420298 -276.120865) (xy 176.396955 -276.075053)
			(xy 176.381067 -276.026154) (xy 176.373024 -275.975372) (xy 176.054641 -275.975372) (xy 176.046884 -276.023102)
			(xy 176.0313 -276.069783) (xy 176.008429 -276.11336) (xy 175.978864 -276.152704) (xy 175.943371 -276.186796)
			(xy 175.902868 -276.214752) (xy 175.858406 -276.23585) (xy 175.811135 -276.249542) (xy 175.76228 -276.255474)
			(xy 175.713105 -276.253493) (xy 175.664886 -276.243649) (xy 175.61887 -276.226197) (xy 175.576249 -276.20159)
			(xy 175.538128 -276.170465) (xy 175.505493 -276.133628) (xy 175.47919 -276.092032) (xy 175.459899 -276.046756)
			(xy 175.448122 -275.998972) (xy 175.444162 -275.949918) (xy 175.127158 -275.949918) (xy 175.126654 -275.975626)
			(xy 175.118611 -276.026408) (xy 175.102723 -276.075307) (xy 175.07938 -276.121119) (xy 175.049159 -276.162715)
			(xy 175.012803 -276.199071) (xy 174.971207 -276.229292) (xy 174.925395 -276.252635) (xy 174.876496 -276.268523)
			(xy 174.825714 -276.276566) (xy 174.774298 -276.276566) (xy 174.723516 -276.268523) (xy 174.674617 -276.252635)
			(xy 174.628805 -276.229292) (xy 174.587209 -276.199071) (xy 174.550853 -276.162715) (xy 174.520632 -276.121119)
			(xy 174.497289 -276.075307) (xy 174.481401 -276.026408) (xy 174.473358 -275.975626) (xy 174.15468 -275.975626)
			(xy 174.146964 -276.023102) (xy 174.13138 -276.069783) (xy 174.108509 -276.11336) (xy 174.078944 -276.152704)
			(xy 174.043451 -276.186796) (xy 174.002948 -276.214752) (xy 173.958486 -276.23585) (xy 173.911215 -276.249542)
			(xy 173.86236 -276.255474) (xy 173.813185 -276.253493) (xy 173.764966 -276.243649) (xy 173.71895 -276.226197)
			(xy 173.676329 -276.20159) (xy 173.638208 -276.170465) (xy 173.605573 -276.133628) (xy 173.57927 -276.092032)
			(xy 173.559979 -276.046756) (xy 173.548202 -275.998972) (xy 173.544242 -275.949918) (xy 173.227238 -275.949918)
			(xy 173.226734 -275.975626) (xy 173.218691 -276.026408) (xy 173.202803 -276.075307) (xy 173.17946 -276.121119)
			(xy 173.149239 -276.162715) (xy 173.112883 -276.199071) (xy 173.071287 -276.229292) (xy 173.025475 -276.252635)
			(xy 172.976576 -276.268523) (xy 172.925794 -276.276566) (xy 172.874378 -276.276566) (xy 172.823596 -276.268523)
			(xy 172.774697 -276.252635) (xy 172.728885 -276.229292) (xy 172.687289 -276.199071) (xy 172.650933 -276.162715)
			(xy 172.620712 -276.121119) (xy 172.597369 -276.075307) (xy 172.581481 -276.026408) (xy 172.573438 -275.975626)
			(xy 172.254506 -275.975626) (xy 172.24679 -276.023102) (xy 172.231206 -276.069783) (xy 172.208335 -276.11336)
			(xy 172.17877 -276.152704) (xy 172.143277 -276.186796) (xy 172.102774 -276.214752) (xy 172.058312 -276.23585)
			(xy 172.011041 -276.249542) (xy 171.962186 -276.255474) (xy 171.913011 -276.253493) (xy 171.864792 -276.243649)
			(xy 171.818776 -276.226197) (xy 171.776155 -276.20159) (xy 171.738034 -276.170465) (xy 171.705399 -276.133628)
			(xy 171.679096 -276.092032) (xy 171.659805 -276.046756) (xy 171.648028 -275.998972) (xy 171.644068 -275.949918)
			(xy 171.327064 -275.949918) (xy 171.32656 -275.975626) (xy 171.318517 -276.026408) (xy 171.302629 -276.075307)
			(xy 171.279286 -276.121119) (xy 171.249065 -276.162715) (xy 171.212709 -276.199071) (xy 171.171113 -276.229292)
			(xy 171.125301 -276.252635) (xy 171.076402 -276.268523) (xy 171.02562 -276.276566) (xy 170.974204 -276.276566)
			(xy 170.923422 -276.268523) (xy 170.874523 -276.252635) (xy 170.828711 -276.229292) (xy 170.787115 -276.199071)
			(xy 170.750759 -276.162715) (xy 170.720538 -276.121119) (xy 170.697195 -276.075307) (xy 170.681307 -276.026408)
			(xy 170.673264 -275.975626) (xy 170.354586 -275.975626) (xy 170.34687 -276.023102) (xy 170.331286 -276.069783)
			(xy 170.308415 -276.11336) (xy 170.27885 -276.152704) (xy 170.243357 -276.186796) (xy 170.202854 -276.214752)
			(xy 170.158392 -276.23585) (xy 170.111121 -276.249542) (xy 170.062266 -276.255474) (xy 170.013091 -276.253493)
			(xy 169.964872 -276.243649) (xy 169.918856 -276.226197) (xy 169.876235 -276.20159) (xy 169.838114 -276.170465)
			(xy 169.805479 -276.133628) (xy 169.779176 -276.092032) (xy 169.759885 -276.046756) (xy 169.748108 -275.998972)
			(xy 169.744148 -275.949918) (xy 169.427144 -275.949918) (xy 169.42664 -275.975626) (xy 169.418597 -276.026408)
			(xy 169.402709 -276.075307) (xy 169.379366 -276.121119) (xy 169.349145 -276.162715) (xy 169.312789 -276.199071)
			(xy 169.271193 -276.229292) (xy 169.225381 -276.252635) (xy 169.176482 -276.268523) (xy 169.1257 -276.276566)
			(xy 169.074284 -276.276566) (xy 169.023502 -276.268523) (xy 168.974603 -276.252635) (xy 168.928791 -276.229292)
			(xy 168.887195 -276.199071) (xy 168.850839 -276.162715) (xy 168.820618 -276.121119) (xy 168.797275 -276.075307)
			(xy 168.781387 -276.026408) (xy 168.773344 -275.975626) (xy 168.454666 -275.975626) (xy 168.44695 -276.023102)
			(xy 168.431366 -276.069783) (xy 168.408495 -276.11336) (xy 168.37893 -276.152704) (xy 168.343437 -276.186796)
			(xy 168.302934 -276.214752) (xy 168.258472 -276.23585) (xy 168.211201 -276.249542) (xy 168.162346 -276.255474)
			(xy 168.113171 -276.253493) (xy 168.064952 -276.243649) (xy 168.018936 -276.226197) (xy 167.976315 -276.20159)
			(xy 167.938194 -276.170465) (xy 167.905559 -276.133628) (xy 167.879256 -276.092032) (xy 167.859965 -276.046756)
			(xy 167.848188 -275.998972) (xy 167.844228 -275.949918) (xy 167.527224 -275.949918) (xy 167.52672 -275.975626)
			(xy 167.518677 -276.026408) (xy 167.502789 -276.075307) (xy 167.479446 -276.121119) (xy 167.449225 -276.162715)
			(xy 167.412869 -276.199071) (xy 167.371273 -276.229292) (xy 167.325461 -276.252635) (xy 167.276562 -276.268523)
			(xy 167.22578 -276.276566) (xy 167.174364 -276.276566) (xy 167.123582 -276.268523) (xy 167.074683 -276.252635)
			(xy 167.028871 -276.229292) (xy 166.987275 -276.199071) (xy 166.950919 -276.162715) (xy 166.920698 -276.121119)
			(xy 166.897355 -276.075307) (xy 166.881467 -276.026408) (xy 166.873424 -275.975626) (xy 166.554492 -275.975626)
			(xy 166.546776 -276.023102) (xy 166.531192 -276.069783) (xy 166.508321 -276.11336) (xy 166.478756 -276.152704)
			(xy 166.443263 -276.186796) (xy 166.40276 -276.214752) (xy 166.358298 -276.23585) (xy 166.311027 -276.249542)
			(xy 166.262172 -276.255474) (xy 166.212997 -276.253493) (xy 166.164778 -276.243649) (xy 166.118762 -276.226197)
			(xy 166.076141 -276.20159) (xy 166.03802 -276.170465) (xy 166.005385 -276.133628) (xy 165.979082 -276.092032)
			(xy 165.959791 -276.046756) (xy 165.948014 -275.998972) (xy 165.944054 -275.949918) (xy 165.62705 -275.949918)
			(xy 165.626546 -275.975626) (xy 165.618503 -276.026408) (xy 165.602615 -276.075307) (xy 165.579272 -276.121119)
			(xy 165.549051 -276.162715) (xy 165.512695 -276.199071) (xy 165.471099 -276.229292) (xy 165.425287 -276.252635)
			(xy 165.376388 -276.268523) (xy 165.325606 -276.276566) (xy 165.27419 -276.276566) (xy 165.223408 -276.268523)
			(xy 165.174509 -276.252635) (xy 165.128697 -276.229292) (xy 165.087101 -276.199071) (xy 165.050745 -276.162715)
			(xy 165.020524 -276.121119) (xy 164.997181 -276.075307) (xy 164.981293 -276.026408) (xy 164.97325 -275.975626)
			(xy 164.654572 -275.975626) (xy 164.646856 -276.023102) (xy 164.631272 -276.069783) (xy 164.608401 -276.11336)
			(xy 164.578836 -276.152704) (xy 164.543343 -276.186796) (xy 164.50284 -276.214752) (xy 164.458378 -276.23585)
			(xy 164.411107 -276.249542) (xy 164.362252 -276.255474) (xy 164.313077 -276.253493) (xy 164.264858 -276.243649)
			(xy 164.218842 -276.226197) (xy 164.176221 -276.20159) (xy 164.1381 -276.170465) (xy 164.105465 -276.133628)
			(xy 164.079162 -276.092032) (xy 164.059871 -276.046756) (xy 164.048094 -275.998972) (xy 164.044134 -275.949918)
			(xy 163.72713 -275.949918) (xy 163.726626 -275.975626) (xy 163.718583 -276.026408) (xy 163.702695 -276.075307)
			(xy 163.679352 -276.121119) (xy 163.649131 -276.162715) (xy 163.612775 -276.199071) (xy 163.571179 -276.229292)
			(xy 163.525367 -276.252635) (xy 163.476468 -276.268523) (xy 163.425686 -276.276566) (xy 163.37427 -276.276566)
			(xy 163.323488 -276.268523) (xy 163.274589 -276.252635) (xy 163.228777 -276.229292) (xy 163.187181 -276.199071)
			(xy 163.150825 -276.162715) (xy 163.120604 -276.121119) (xy 163.097261 -276.075307) (xy 163.081373 -276.026408)
			(xy 163.07333 -275.975626) (xy 162.754652 -275.975626) (xy 162.746936 -276.023102) (xy 162.731352 -276.069783)
			(xy 162.708481 -276.11336) (xy 162.678916 -276.152704) (xy 162.643423 -276.186796) (xy 162.60292 -276.214752)
			(xy 162.558458 -276.23585) (xy 162.511187 -276.249542) (xy 162.462332 -276.255474) (xy 162.413157 -276.253493)
			(xy 162.364938 -276.243649) (xy 162.318922 -276.226197) (xy 162.276301 -276.20159) (xy 162.23818 -276.170465)
			(xy 162.205545 -276.133628) (xy 162.179242 -276.092032) (xy 162.159951 -276.046756) (xy 162.148174 -275.998972)
			(xy 162.144214 -275.949918) (xy 161.82721 -275.949918) (xy 161.826706 -275.975626) (xy 161.818663 -276.026408)
			(xy 161.802775 -276.075307) (xy 161.779432 -276.121119) (xy 161.749211 -276.162715) (xy 161.712855 -276.199071)
			(xy 161.671259 -276.229292) (xy 161.625447 -276.252635) (xy 161.576548 -276.268523) (xy 161.525766 -276.276566)
			(xy 161.47435 -276.276566) (xy 161.423568 -276.268523) (xy 161.374669 -276.252635) (xy 161.328857 -276.229292)
			(xy 161.287261 -276.199071) (xy 161.250905 -276.162715) (xy 161.220684 -276.121119) (xy 161.197341 -276.075307)
			(xy 161.181453 -276.026408) (xy 161.17341 -275.975626) (xy 160.854478 -275.975626) (xy 160.846762 -276.023102)
			(xy 160.831178 -276.069783) (xy 160.808307 -276.11336) (xy 160.778742 -276.152704) (xy 160.743249 -276.186796)
			(xy 160.702746 -276.214752) (xy 160.658284 -276.23585) (xy 160.611013 -276.249542) (xy 160.562158 -276.255474)
			(xy 160.512983 -276.253493) (xy 160.464764 -276.243649) (xy 160.418748 -276.226197) (xy 160.376127 -276.20159)
			(xy 160.338006 -276.170465) (xy 160.305371 -276.133628) (xy 160.279068 -276.092032) (xy 160.259777 -276.046756)
			(xy 160.248 -275.998972) (xy 160.24404 -275.949918) (xy 139.628337 -275.949918) (xy 139.628337 -276.091581)
			(xy 139.62048 -276.254347) (xy 139.604786 -276.416544) (xy 139.603569 -276.424898) (xy 152.169126 -276.424898)
			(xy 152.173086 -276.375844) (xy 152.184863 -276.32806) (xy 152.204154 -276.282784) (xy 152.230457 -276.241188)
			(xy 152.263092 -276.204351) (xy 152.301213 -276.173226) (xy 152.343834 -276.148619) (xy 152.38985 -276.131167)
			(xy 152.438069 -276.121323) (xy 152.487244 -276.119342) (xy 152.536099 -276.125274) (xy 152.58337 -276.138966)
			(xy 152.627832 -276.160064) (xy 152.668335 -276.18802) (xy 152.703828 -276.222112) (xy 152.733393 -276.261456)
			(xy 152.756264 -276.305033) (xy 152.771848 -276.351714) (xy 152.779743 -276.400291) (xy 152.780238 -276.424898)
			(xy 153.119086 -276.424898) (xy 153.123046 -276.375844) (xy 153.134823 -276.32806) (xy 153.154114 -276.282784)
			(xy 153.180417 -276.241188) (xy 153.213052 -276.204351) (xy 153.251173 -276.173226) (xy 153.293794 -276.148619)
			(xy 153.33981 -276.131167) (xy 153.388029 -276.121323) (xy 153.437204 -276.119342) (xy 153.486059 -276.125274)
			(xy 153.53333 -276.138966) (xy 153.577792 -276.160064) (xy 153.618295 -276.18802) (xy 153.653788 -276.222112)
			(xy 153.683353 -276.261456) (xy 153.706224 -276.305033) (xy 153.721808 -276.351714) (xy 153.729703 -276.400291)
			(xy 153.730198 -276.424898) (xy 154.0693 -276.424898) (xy 154.07326 -276.375844) (xy 154.085037 -276.32806)
			(xy 154.104328 -276.282784) (xy 154.130631 -276.241188) (xy 154.163266 -276.204351) (xy 154.201387 -276.173226)
			(xy 154.244008 -276.148619) (xy 154.290024 -276.131167) (xy 154.338243 -276.121323) (xy 154.387418 -276.119342)
			(xy 154.436273 -276.125274) (xy 154.483544 -276.138966) (xy 154.528006 -276.160064) (xy 154.568509 -276.18802)
			(xy 154.604002 -276.222112) (xy 154.633567 -276.261456) (xy 154.656438 -276.305033) (xy 154.672022 -276.351714)
			(xy 154.679917 -276.400291) (xy 154.680412 -276.424898) (xy 155.01926 -276.424898) (xy 155.02322 -276.375844)
			(xy 155.034997 -276.32806) (xy 155.054288 -276.282784) (xy 155.080591 -276.241188) (xy 155.113226 -276.204351)
			(xy 155.151347 -276.173226) (xy 155.193968 -276.148619) (xy 155.239984 -276.131167) (xy 155.288203 -276.121323)
			(xy 155.337378 -276.119342) (xy 155.386233 -276.125274) (xy 155.433504 -276.138966) (xy 155.477966 -276.160064)
			(xy 155.518469 -276.18802) (xy 155.553962 -276.222112) (xy 155.583527 -276.261456) (xy 155.606398 -276.305033)
			(xy 155.621982 -276.351714) (xy 155.629877 -276.400291) (xy 155.630372 -276.424898) (xy 155.96922 -276.424898)
			(xy 155.97318 -276.375844) (xy 155.984957 -276.32806) (xy 156.004248 -276.282784) (xy 156.030551 -276.241188)
			(xy 156.063186 -276.204351) (xy 156.101307 -276.173226) (xy 156.143928 -276.148619) (xy 156.189944 -276.131167)
			(xy 156.238163 -276.121323) (xy 156.287338 -276.119342) (xy 156.336193 -276.125274) (xy 156.383464 -276.138966)
			(xy 156.427926 -276.160064) (xy 156.468429 -276.18802) (xy 156.503922 -276.222112) (xy 156.533487 -276.261456)
			(xy 156.556358 -276.305033) (xy 156.571942 -276.351714) (xy 156.579837 -276.400291) (xy 156.580332 -276.424898)
			(xy 156.91918 -276.424898) (xy 156.92314 -276.375844) (xy 156.934917 -276.32806) (xy 156.954208 -276.282784)
			(xy 156.980511 -276.241188) (xy 157.013146 -276.204351) (xy 157.051267 -276.173226) (xy 157.093888 -276.148619)
			(xy 157.139904 -276.131167) (xy 157.188123 -276.121323) (xy 157.237298 -276.119342) (xy 157.286153 -276.125274)
			(xy 157.333424 -276.138966) (xy 157.377886 -276.160064) (xy 157.418389 -276.18802) (xy 157.453882 -276.222112)
			(xy 157.483447 -276.261456) (xy 157.506318 -276.305033) (xy 157.521902 -276.351714) (xy 157.529797 -276.400291)
			(xy 157.530292 -276.424898) (xy 157.86914 -276.424898) (xy 157.8731 -276.375844) (xy 157.884877 -276.32806)
			(xy 157.904168 -276.282784) (xy 157.930471 -276.241188) (xy 157.963106 -276.204351) (xy 158.001227 -276.173226)
			(xy 158.043848 -276.148619) (xy 158.089864 -276.131167) (xy 158.138083 -276.121323) (xy 158.187258 -276.119342)
			(xy 158.236113 -276.125274) (xy 158.283384 -276.138966) (xy 158.327846 -276.160064) (xy 158.368349 -276.18802)
			(xy 158.403842 -276.222112) (xy 158.433407 -276.261456) (xy 158.456278 -276.305033) (xy 158.471862 -276.351714)
			(xy 158.479757 -276.400291) (xy 158.480252 -276.424898) (xy 158.479757 -276.449505) (xy 158.471862 -276.498082)
			(xy 158.456278 -276.544763) (xy 158.433407 -276.58834) (xy 158.403842 -276.627684) (xy 158.368349 -276.661776)
			(xy 158.327846 -276.689732) (xy 158.283384 -276.71083) (xy 158.236113 -276.724522) (xy 158.187258 -276.730454)
			(xy 158.138083 -276.728473) (xy 158.089864 -276.718629) (xy 158.043848 -276.701177) (xy 158.001227 -276.67657)
			(xy 157.963106 -276.645445) (xy 157.930471 -276.608608) (xy 157.904168 -276.567012) (xy 157.884877 -276.521736)
			(xy 157.8731 -276.473952) (xy 157.86914 -276.424898) (xy 157.530292 -276.424898) (xy 157.529797 -276.449505)
			(xy 157.521902 -276.498082) (xy 157.506318 -276.544763) (xy 157.483447 -276.58834) (xy 157.453882 -276.627684)
			(xy 157.418389 -276.661776) (xy 157.377886 -276.689732) (xy 157.333424 -276.71083) (xy 157.286153 -276.724522)
			(xy 157.237298 -276.730454) (xy 157.188123 -276.728473) (xy 157.139904 -276.718629) (xy 157.093888 -276.701177)
			(xy 157.051267 -276.67657) (xy 157.013146 -276.645445) (xy 156.980511 -276.608608) (xy 156.954208 -276.567012)
			(xy 156.934917 -276.521736) (xy 156.92314 -276.473952) (xy 156.91918 -276.424898) (xy 156.580332 -276.424898)
			(xy 156.579837 -276.449505) (xy 156.571942 -276.498082) (xy 156.556358 -276.544763) (xy 156.533487 -276.58834)
			(xy 156.503922 -276.627684) (xy 156.468429 -276.661776) (xy 156.427926 -276.689732) (xy 156.383464 -276.71083)
			(xy 156.336193 -276.724522) (xy 156.287338 -276.730454) (xy 156.238163 -276.728473) (xy 156.189944 -276.718629)
			(xy 156.143928 -276.701177) (xy 156.101307 -276.67657) (xy 156.063186 -276.645445) (xy 156.030551 -276.608608)
			(xy 156.004248 -276.567012) (xy 155.984957 -276.521736) (xy 155.97318 -276.473952) (xy 155.96922 -276.424898)
			(xy 155.630372 -276.424898) (xy 155.629877 -276.449505) (xy 155.621982 -276.498082) (xy 155.606398 -276.544763)
			(xy 155.583527 -276.58834) (xy 155.553962 -276.627684) (xy 155.518469 -276.661776) (xy 155.477966 -276.689732)
			(xy 155.433504 -276.71083) (xy 155.386233 -276.724522) (xy 155.337378 -276.730454) (xy 155.288203 -276.728473)
			(xy 155.239984 -276.718629) (xy 155.193968 -276.701177) (xy 155.151347 -276.67657) (xy 155.113226 -276.645445)
			(xy 155.080591 -276.608608) (xy 155.054288 -276.567012) (xy 155.034997 -276.521736) (xy 155.02322 -276.473952)
			(xy 155.01926 -276.424898) (xy 154.680412 -276.424898) (xy 154.679917 -276.449505) (xy 154.672022 -276.498082)
			(xy 154.656438 -276.544763) (xy 154.633567 -276.58834) (xy 154.604002 -276.627684) (xy 154.568509 -276.661776)
			(xy 154.528006 -276.689732) (xy 154.483544 -276.71083) (xy 154.436273 -276.724522) (xy 154.387418 -276.730454)
			(xy 154.338243 -276.728473) (xy 154.290024 -276.718629) (xy 154.244008 -276.701177) (xy 154.201387 -276.67657)
			(xy 154.163266 -276.645445) (xy 154.130631 -276.608608) (xy 154.104328 -276.567012) (xy 154.085037 -276.521736)
			(xy 154.07326 -276.473952) (xy 154.0693 -276.424898) (xy 153.730198 -276.424898) (xy 153.729703 -276.449505)
			(xy 153.721808 -276.498082) (xy 153.706224 -276.544763) (xy 153.683353 -276.58834) (xy 153.653788 -276.627684)
			(xy 153.618295 -276.661776) (xy 153.577792 -276.689732) (xy 153.53333 -276.71083) (xy 153.486059 -276.724522)
			(xy 153.437204 -276.730454) (xy 153.388029 -276.728473) (xy 153.33981 -276.718629) (xy 153.293794 -276.701177)
			(xy 153.251173 -276.67657) (xy 153.213052 -276.645445) (xy 153.180417 -276.608608) (xy 153.154114 -276.567012)
			(xy 153.134823 -276.521736) (xy 153.123046 -276.473952) (xy 153.119086 -276.424898) (xy 152.780238 -276.424898)
			(xy 152.779743 -276.449505) (xy 152.771848 -276.498082) (xy 152.756264 -276.544763) (xy 152.733393 -276.58834)
			(xy 152.703828 -276.627684) (xy 152.668335 -276.661776) (xy 152.627832 -276.689732) (xy 152.58337 -276.71083)
			(xy 152.536099 -276.724522) (xy 152.487244 -276.730454) (xy 152.438069 -276.728473) (xy 152.38985 -276.718629)
			(xy 152.343834 -276.701177) (xy 152.301213 -276.67657) (xy 152.263092 -276.645445) (xy 152.230457 -276.608608)
			(xy 152.204154 -276.567012) (xy 152.184863 -276.521736) (xy 152.173086 -276.473952) (xy 152.169126 -276.424898)
			(xy 139.603569 -276.424898) (xy 139.581291 -276.577797) (xy 139.550049 -276.737729) (xy 139.511133 -276.895969)
			(xy 139.464633 -277.052149) (xy 139.410658 -277.205905) (xy 139.349333 -277.356881) (xy 139.341 -277.374858)
			(xy 152.169126 -277.374858) (xy 152.173086 -277.325804) (xy 152.184863 -277.27802) (xy 152.204154 -277.232744)
			(xy 152.230457 -277.191148) (xy 152.263092 -277.154311) (xy 152.301213 -277.123186) (xy 152.343834 -277.098579)
			(xy 152.38985 -277.081127) (xy 152.438069 -277.071283) (xy 152.487244 -277.069302) (xy 152.536099 -277.075234)
			(xy 152.58337 -277.088926) (xy 152.627832 -277.110024) (xy 152.668335 -277.13798) (xy 152.703828 -277.172072)
			(xy 152.733393 -277.211416) (xy 152.756264 -277.254993) (xy 152.771848 -277.301674) (xy 152.779743 -277.350251)
			(xy 152.780238 -277.374858) (xy 153.119086 -277.374858) (xy 153.123046 -277.325804) (xy 153.134823 -277.27802)
			(xy 153.154114 -277.232744) (xy 153.180417 -277.191148) (xy 153.213052 -277.154311) (xy 153.251173 -277.123186)
			(xy 153.293794 -277.098579) (xy 153.33981 -277.081127) (xy 153.388029 -277.071283) (xy 153.437204 -277.069302)
			(xy 153.486059 -277.075234) (xy 153.53333 -277.088926) (xy 153.577792 -277.110024) (xy 153.618295 -277.13798)
			(xy 153.653788 -277.172072) (xy 153.683353 -277.211416) (xy 153.706224 -277.254993) (xy 153.721808 -277.301674)
			(xy 153.729703 -277.350251) (xy 153.730198 -277.374858) (xy 154.0693 -277.374858) (xy 154.07326 -277.325804)
			(xy 154.085037 -277.27802) (xy 154.104328 -277.232744) (xy 154.130631 -277.191148) (xy 154.163266 -277.154311)
			(xy 154.201387 -277.123186) (xy 154.244008 -277.098579) (xy 154.290024 -277.081127) (xy 154.338243 -277.071283)
			(xy 154.387418 -277.069302) (xy 154.436273 -277.075234) (xy 154.483544 -277.088926) (xy 154.528006 -277.110024)
			(xy 154.568509 -277.13798) (xy 154.604002 -277.172072) (xy 154.633567 -277.211416) (xy 154.656438 -277.254993)
			(xy 154.672022 -277.301674) (xy 154.679917 -277.350251) (xy 154.680412 -277.374858) (xy 155.01926 -277.374858)
			(xy 155.02322 -277.325804) (xy 155.034997 -277.27802) (xy 155.054288 -277.232744) (xy 155.080591 -277.191148)
			(xy 155.113226 -277.154311) (xy 155.151347 -277.123186) (xy 155.193968 -277.098579) (xy 155.239984 -277.081127)
			(xy 155.288203 -277.071283) (xy 155.337378 -277.069302) (xy 155.386233 -277.075234) (xy 155.433504 -277.088926)
			(xy 155.477966 -277.110024) (xy 155.518469 -277.13798) (xy 155.553962 -277.172072) (xy 155.583527 -277.211416)
			(xy 155.606398 -277.254993) (xy 155.621982 -277.301674) (xy 155.629877 -277.350251) (xy 155.630372 -277.374858)
			(xy 155.96922 -277.374858) (xy 155.97318 -277.325804) (xy 155.984957 -277.27802) (xy 156.004248 -277.232744)
			(xy 156.030551 -277.191148) (xy 156.063186 -277.154311) (xy 156.101307 -277.123186) (xy 156.143928 -277.098579)
			(xy 156.189944 -277.081127) (xy 156.238163 -277.071283) (xy 156.287338 -277.069302) (xy 156.336193 -277.075234)
			(xy 156.383464 -277.088926) (xy 156.427926 -277.110024) (xy 156.468429 -277.13798) (xy 156.503922 -277.172072)
			(xy 156.533487 -277.211416) (xy 156.556358 -277.254993) (xy 156.571942 -277.301674) (xy 156.579837 -277.350251)
			(xy 156.580332 -277.374858) (xy 156.91918 -277.374858) (xy 156.92314 -277.325804) (xy 156.934917 -277.27802)
			(xy 156.954208 -277.232744) (xy 156.980511 -277.191148) (xy 157.013146 -277.154311) (xy 157.051267 -277.123186)
			(xy 157.093888 -277.098579) (xy 157.139904 -277.081127) (xy 157.188123 -277.071283) (xy 157.237298 -277.069302)
			(xy 157.286153 -277.075234) (xy 157.333424 -277.088926) (xy 157.377886 -277.110024) (xy 157.418389 -277.13798)
			(xy 157.453882 -277.172072) (xy 157.483447 -277.211416) (xy 157.506318 -277.254993) (xy 157.521902 -277.301674)
			(xy 157.529797 -277.350251) (xy 157.530292 -277.374858) (xy 157.86914 -277.374858) (xy 157.8731 -277.325804)
			(xy 157.884877 -277.27802) (xy 157.904168 -277.232744) (xy 157.930471 -277.191148) (xy 157.963106 -277.154311)
			(xy 158.001227 -277.123186) (xy 158.043848 -277.098579) (xy 158.089864 -277.081127) (xy 158.138083 -277.071283)
			(xy 158.187258 -277.069302) (xy 158.236113 -277.075234) (xy 158.283384 -277.088926) (xy 158.327846 -277.110024)
			(xy 158.368349 -277.13798) (xy 158.403842 -277.172072) (xy 158.433407 -277.211416) (xy 158.456278 -277.254993)
			(xy 158.471862 -277.301674) (xy 158.479757 -277.350251) (xy 158.480252 -277.374858) (xy 158.480251 -277.3749)
			(xy 158.818998 -277.3749) (xy 158.82317 -277.32455) (xy 158.835573 -277.275573) (xy 158.855868 -277.229306)
			(xy 158.883501 -277.18701) (xy 158.91772 -277.149839) (xy 158.95759 -277.118808) (xy 159.002023 -277.094762)
			(xy 159.049809 -277.078358) (xy 159.099643 -277.070042) (xy 159.124904 -277.06955) (xy 159.139087 -277.069727)
			(xy 159.167327 -277.072399) (xy 159.181292 -277.074884) (xy 159.193738 -277.07717) (xy 159.21736 -277.069804)
			(xy 159.29483 -276.992334) (xy 159.302196 -276.968712) (xy 159.29991 -276.956266) (xy 159.297433 -276.9423)
			(xy 159.294762 -276.914061) (xy 159.294576 -276.899878) (xy 159.29475 -276.885695) (xy 159.297424 -276.857455)
			(xy 159.29991 -276.84349) (xy 159.302196 -276.831044) (xy 159.29483 -276.807422) (xy 159.21736 -276.729952)
			(xy 159.193738 -276.722586) (xy 159.181292 -276.724872) (xy 159.167326 -276.727345) (xy 159.139086 -276.730019)
			(xy 159.124904 -276.730206) (xy 159.100083 -276.729726) (xy 159.051094 -276.721696) (xy 159.00405 -276.705846)
			(xy 158.96019 -276.682593) (xy 158.92067 -276.652551) (xy 158.88653 -276.616512) (xy 158.858671 -276.575423)
			(xy 158.837826 -276.530369) (xy 158.824545 -276.482537) (xy 158.819177 -276.433185) (xy 158.821864 -276.383616)
			(xy 158.832535 -276.335134) (xy 158.85091 -276.289017) (xy 158.876502 -276.24648) (xy 158.90864 -276.208644)
			(xy 158.946475 -276.176506) (xy 158.989011 -276.150912) (xy 159.035128 -276.132537) (xy 159.08361 -276.121865)
			(xy 159.133179 -276.119177) (xy 159.182531 -276.124544) (xy 159.230364 -276.137824) (xy 159.275418 -276.158668)
			(xy 159.316507 -276.186527) (xy 159.352547 -276.220665) (xy 159.38259 -276.260185) (xy 159.405843 -276.304045)
			(xy 159.421694 -276.351088) (xy 159.429726 -276.400077) (xy 159.430212 -276.424898) (xy 159.430035 -276.439081)
			(xy 159.427363 -276.467321) (xy 159.424878 -276.481286) (xy 159.422592 -276.493732) (xy 159.429958 -276.517354)
			(xy 159.507428 -276.594824) (xy 159.53105 -276.60219) (xy 159.543496 -276.599904) (xy 159.557463 -276.597432)
			(xy 159.585702 -276.594757) (xy 159.599884 -276.59457) (xy 159.625141 -276.595105) (xy 159.674966 -276.603417)
			(xy 159.722743 -276.619817) (xy 159.767169 -276.643857) (xy 159.807032 -276.674882) (xy 159.841245 -276.712045)
			(xy 159.868874 -276.754333) (xy 159.889166 -276.800591) (xy 159.901566 -276.849559) (xy 159.905736 -276.899878)
			(xy 160.24404 -276.899878) (xy 160.248 -276.850824) (xy 160.259777 -276.80304) (xy 160.279068 -276.757764)
			(xy 160.305371 -276.716168) (xy 160.338006 -276.679331) (xy 160.376127 -276.648206) (xy 160.418748 -276.623599)
			(xy 160.464764 -276.606147) (xy 160.512983 -276.596303) (xy 160.562158 -276.594322) (xy 160.611013 -276.600254)
			(xy 160.658284 -276.613946) (xy 160.702746 -276.635044) (xy 160.743249 -276.663) (xy 160.778742 -276.697092)
			(xy 160.808307 -276.736436) (xy 160.831178 -276.780013) (xy 160.846762 -276.826694) (xy 160.854657 -276.875271)
			(xy 160.855152 -276.899878) (xy 161.194254 -276.899878) (xy 161.198214 -276.850824) (xy 161.209991 -276.80304)
			(xy 161.229282 -276.757764) (xy 161.255585 -276.716168) (xy 161.28822 -276.679331) (xy 161.326341 -276.648206)
			(xy 161.368962 -276.623599) (xy 161.414978 -276.606147) (xy 161.463197 -276.596303) (xy 161.512372 -276.594322)
			(xy 161.561227 -276.600254) (xy 161.608498 -276.613946) (xy 161.65296 -276.635044) (xy 161.693463 -276.663)
			(xy 161.728956 -276.697092) (xy 161.758521 -276.736436) (xy 161.781392 -276.780013) (xy 161.796976 -276.826694)
			(xy 161.804871 -276.875271) (xy 161.805366 -276.899878) (xy 162.144214 -276.899878) (xy 162.148174 -276.850824)
			(xy 162.159951 -276.80304) (xy 162.179242 -276.757764) (xy 162.205545 -276.716168) (xy 162.23818 -276.679331)
			(xy 162.276301 -276.648206) (xy 162.318922 -276.623599) (xy 162.364938 -276.606147) (xy 162.413157 -276.596303)
			(xy 162.462332 -276.594322) (xy 162.511187 -276.600254) (xy 162.558458 -276.613946) (xy 162.60292 -276.635044)
			(xy 162.643423 -276.663) (xy 162.678916 -276.697092) (xy 162.708481 -276.736436) (xy 162.731352 -276.780013)
			(xy 162.746936 -276.826694) (xy 162.754831 -276.875271) (xy 162.755326 -276.899878) (xy 163.094174 -276.899878)
			(xy 163.098134 -276.850824) (xy 163.109911 -276.80304) (xy 163.129202 -276.757764) (xy 163.155505 -276.716168)
			(xy 163.18814 -276.679331) (xy 163.226261 -276.648206) (xy 163.268882 -276.623599) (xy 163.314898 -276.606147)
			(xy 163.363117 -276.596303) (xy 163.412292 -276.594322) (xy 163.461147 -276.600254) (xy 163.508418 -276.613946)
			(xy 163.55288 -276.635044) (xy 163.593383 -276.663) (xy 163.628876 -276.697092) (xy 163.658441 -276.736436)
			(xy 163.681312 -276.780013) (xy 163.696896 -276.826694) (xy 163.704791 -276.875271) (xy 163.705286 -276.899878)
			(xy 164.044134 -276.899878) (xy 164.048094 -276.850824) (xy 164.059871 -276.80304) (xy 164.079162 -276.757764)
			(xy 164.105465 -276.716168) (xy 164.1381 -276.679331) (xy 164.176221 -276.648206) (xy 164.218842 -276.623599)
			(xy 164.264858 -276.606147) (xy 164.313077 -276.596303) (xy 164.362252 -276.594322) (xy 164.411107 -276.600254)
			(xy 164.458378 -276.613946) (xy 164.50284 -276.635044) (xy 164.543343 -276.663) (xy 164.578836 -276.697092)
			(xy 164.608401 -276.736436) (xy 164.631272 -276.780013) (xy 164.646856 -276.826694) (xy 164.654751 -276.875271)
			(xy 164.655246 -276.899878) (xy 164.994094 -276.899878) (xy 164.998054 -276.850824) (xy 165.009831 -276.80304)
			(xy 165.029122 -276.757764) (xy 165.055425 -276.716168) (xy 165.08806 -276.679331) (xy 165.126181 -276.648206)
			(xy 165.168802 -276.623599) (xy 165.214818 -276.606147) (xy 165.263037 -276.596303) (xy 165.312212 -276.594322)
			(xy 165.361067 -276.600254) (xy 165.408338 -276.613946) (xy 165.4528 -276.635044) (xy 165.493303 -276.663)
			(xy 165.528796 -276.697092) (xy 165.558361 -276.736436) (xy 165.581232 -276.780013) (xy 165.596816 -276.826694)
			(xy 165.604711 -276.875271) (xy 165.605206 -276.899878) (xy 165.944054 -276.899878) (xy 165.948014 -276.850824)
			(xy 165.959791 -276.80304) (xy 165.979082 -276.757764) (xy 166.005385 -276.716168) (xy 166.03802 -276.679331)
			(xy 166.076141 -276.648206) (xy 166.118762 -276.623599) (xy 166.164778 -276.606147) (xy 166.212997 -276.596303)
			(xy 166.262172 -276.594322) (xy 166.311027 -276.600254) (xy 166.358298 -276.613946) (xy 166.40276 -276.635044)
			(xy 166.443263 -276.663) (xy 166.478756 -276.697092) (xy 166.508321 -276.736436) (xy 166.531192 -276.780013)
			(xy 166.546776 -276.826694) (xy 166.554671 -276.875271) (xy 166.555166 -276.899878) (xy 166.894268 -276.899878)
			(xy 166.898228 -276.850824) (xy 166.910005 -276.80304) (xy 166.929296 -276.757764) (xy 166.955599 -276.716168)
			(xy 166.988234 -276.679331) (xy 167.026355 -276.648206) (xy 167.068976 -276.623599) (xy 167.114992 -276.606147)
			(xy 167.163211 -276.596303) (xy 167.212386 -276.594322) (xy 167.261241 -276.600254) (xy 167.308512 -276.613946)
			(xy 167.352974 -276.635044) (xy 167.393477 -276.663) (xy 167.42897 -276.697092) (xy 167.458535 -276.736436)
			(xy 167.481406 -276.780013) (xy 167.49699 -276.826694) (xy 167.504885 -276.875271) (xy 167.50538 -276.899878)
			(xy 167.844228 -276.899878) (xy 167.848188 -276.850824) (xy 167.859965 -276.80304) (xy 167.879256 -276.757764)
			(xy 167.905559 -276.716168) (xy 167.938194 -276.679331) (xy 167.976315 -276.648206) (xy 168.018936 -276.623599)
			(xy 168.064952 -276.606147) (xy 168.113171 -276.596303) (xy 168.162346 -276.594322) (xy 168.211201 -276.600254)
			(xy 168.258472 -276.613946) (xy 168.302934 -276.635044) (xy 168.343437 -276.663) (xy 168.37893 -276.697092)
			(xy 168.408495 -276.736436) (xy 168.431366 -276.780013) (xy 168.44695 -276.826694) (xy 168.454845 -276.875271)
			(xy 168.45534 -276.899878) (xy 168.794188 -276.899878) (xy 168.798148 -276.850824) (xy 168.809925 -276.80304)
			(xy 168.829216 -276.757764) (xy 168.855519 -276.716168) (xy 168.888154 -276.679331) (xy 168.926275 -276.648206)
			(xy 168.968896 -276.623599) (xy 169.014912 -276.606147) (xy 169.063131 -276.596303) (xy 169.112306 -276.594322)
			(xy 169.161161 -276.600254) (xy 169.208432 -276.613946) (xy 169.252894 -276.635044) (xy 169.293397 -276.663)
			(xy 169.32889 -276.697092) (xy 169.358455 -276.736436) (xy 169.381326 -276.780013) (xy 169.39691 -276.826694)
			(xy 169.404805 -276.875271) (xy 169.4053 -276.899878) (xy 169.744148 -276.899878) (xy 169.748108 -276.850824)
			(xy 169.759885 -276.80304) (xy 169.779176 -276.757764) (xy 169.805479 -276.716168) (xy 169.838114 -276.679331)
			(xy 169.876235 -276.648206) (xy 169.918856 -276.623599) (xy 169.964872 -276.606147) (xy 170.013091 -276.596303)
			(xy 170.062266 -276.594322) (xy 170.111121 -276.600254) (xy 170.158392 -276.613946) (xy 170.202854 -276.635044)
			(xy 170.243357 -276.663) (xy 170.27885 -276.697092) (xy 170.308415 -276.736436) (xy 170.331286 -276.780013)
			(xy 170.34687 -276.826694) (xy 170.354765 -276.875271) (xy 170.35526 -276.899878) (xy 170.694108 -276.899878)
			(xy 170.698068 -276.850824) (xy 170.709845 -276.80304) (xy 170.729136 -276.757764) (xy 170.755439 -276.716168)
			(xy 170.788074 -276.679331) (xy 170.826195 -276.648206) (xy 170.868816 -276.623599) (xy 170.914832 -276.606147)
			(xy 170.963051 -276.596303) (xy 171.012226 -276.594322) (xy 171.061081 -276.600254) (xy 171.108352 -276.613946)
			(xy 171.152814 -276.635044) (xy 171.193317 -276.663) (xy 171.22881 -276.697092) (xy 171.258375 -276.736436)
			(xy 171.281246 -276.780013) (xy 171.29683 -276.826694) (xy 171.304725 -276.875271) (xy 171.30522 -276.899878)
			(xy 171.644068 -276.899878) (xy 171.648028 -276.850824) (xy 171.659805 -276.80304) (xy 171.679096 -276.757764)
			(xy 171.705399 -276.716168) (xy 171.738034 -276.679331) (xy 171.776155 -276.648206) (xy 171.818776 -276.623599)
			(xy 171.864792 -276.606147) (xy 171.913011 -276.596303) (xy 171.962186 -276.594322) (xy 172.011041 -276.600254)
			(xy 172.058312 -276.613946) (xy 172.102774 -276.635044) (xy 172.143277 -276.663) (xy 172.17877 -276.697092)
			(xy 172.208335 -276.736436) (xy 172.231206 -276.780013) (xy 172.24679 -276.826694) (xy 172.254685 -276.875271)
			(xy 172.25518 -276.899878) (xy 172.594282 -276.899878) (xy 172.598242 -276.850824) (xy 172.610019 -276.80304)
			(xy 172.62931 -276.757764) (xy 172.655613 -276.716168) (xy 172.688248 -276.679331) (xy 172.726369 -276.648206)
			(xy 172.76899 -276.623599) (xy 172.815006 -276.606147) (xy 172.863225 -276.596303) (xy 172.9124 -276.594322)
			(xy 172.961255 -276.600254) (xy 173.008526 -276.613946) (xy 173.052988 -276.635044) (xy 173.093491 -276.663)
			(xy 173.128984 -276.697092) (xy 173.158549 -276.736436) (xy 173.18142 -276.780013) (xy 173.197004 -276.826694)
			(xy 173.204899 -276.875271) (xy 173.205394 -276.899878) (xy 173.544242 -276.899878) (xy 173.548202 -276.850824)
			(xy 173.559979 -276.80304) (xy 173.57927 -276.757764) (xy 173.605573 -276.716168) (xy 173.638208 -276.679331)
			(xy 173.676329 -276.648206) (xy 173.71895 -276.623599) (xy 173.764966 -276.606147) (xy 173.813185 -276.596303)
			(xy 173.86236 -276.594322) (xy 173.911215 -276.600254) (xy 173.958486 -276.613946) (xy 174.002948 -276.635044)
			(xy 174.043451 -276.663) (xy 174.078944 -276.697092) (xy 174.108509 -276.736436) (xy 174.13138 -276.780013)
			(xy 174.146964 -276.826694) (xy 174.154859 -276.875271) (xy 174.155354 -276.899878) (xy 174.494202 -276.899878)
			(xy 174.498162 -276.850824) (xy 174.509939 -276.80304) (xy 174.52923 -276.757764) (xy 174.555533 -276.716168)
			(xy 174.588168 -276.679331) (xy 174.626289 -276.648206) (xy 174.66891 -276.623599) (xy 174.714926 -276.606147)
			(xy 174.763145 -276.596303) (xy 174.81232 -276.594322) (xy 174.861175 -276.600254) (xy 174.908446 -276.613946)
			(xy 174.952908 -276.635044) (xy 174.993411 -276.663) (xy 175.028904 -276.697092) (xy 175.058469 -276.736436)
			(xy 175.08134 -276.780013) (xy 175.096924 -276.826694) (xy 175.104819 -276.875271) (xy 175.105314 -276.899878)
			(xy 175.444162 -276.899878) (xy 175.448122 -276.850824) (xy 175.459899 -276.80304) (xy 175.47919 -276.757764)
			(xy 175.505493 -276.716168) (xy 175.538128 -276.679331) (xy 175.576249 -276.648206) (xy 175.61887 -276.623599)
			(xy 175.664886 -276.606147) (xy 175.713105 -276.596303) (xy 175.76228 -276.594322) (xy 175.811135 -276.600254)
			(xy 175.858406 -276.613946) (xy 175.902868 -276.635044) (xy 175.943371 -276.663) (xy 175.978864 -276.697092)
			(xy 176.008429 -276.736436) (xy 176.0313 -276.780013) (xy 176.046884 -276.826694) (xy 176.054779 -276.875271)
			(xy 176.055274 -276.899878) (xy 176.394122 -276.899878) (xy 176.398082 -276.850824) (xy 176.409859 -276.80304)
			(xy 176.42915 -276.757764) (xy 176.455453 -276.716168) (xy 176.488088 -276.679331) (xy 176.526209 -276.648206)
			(xy 176.56883 -276.623599) (xy 176.614846 -276.606147) (xy 176.663065 -276.596303) (xy 176.71224 -276.594322)
			(xy 176.761095 -276.600254) (xy 176.808366 -276.613946) (xy 176.852828 -276.635044) (xy 176.893331 -276.663)
			(xy 176.928824 -276.697092) (xy 176.958389 -276.736436) (xy 176.98126 -276.780013) (xy 176.996844 -276.826694)
			(xy 177.004739 -276.875271) (xy 177.005234 -276.899878) (xy 177.344082 -276.899878) (xy 177.348042 -276.850824)
			(xy 177.359819 -276.80304) (xy 177.37911 -276.757764) (xy 177.405413 -276.716168) (xy 177.438048 -276.679331)
			(xy 177.476169 -276.648206) (xy 177.51879 -276.623599) (xy 177.564806 -276.606147) (xy 177.613025 -276.596303)
			(xy 177.6622 -276.594322) (xy 177.711055 -276.600254) (xy 177.758326 -276.613946) (xy 177.802788 -276.635044)
			(xy 177.843291 -276.663) (xy 177.878784 -276.697092) (xy 177.908349 -276.736436) (xy 177.93122 -276.780013)
			(xy 177.946804 -276.826694) (xy 177.954699 -276.875271) (xy 177.955194 -276.899878) (xy 178.294042 -276.899878)
			(xy 178.298002 -276.850824) (xy 178.309779 -276.80304) (xy 178.32907 -276.757764) (xy 178.355373 -276.716168)
			(xy 178.388008 -276.679331) (xy 178.426129 -276.648206) (xy 178.46875 -276.623599) (xy 178.514766 -276.606147)
			(xy 178.562985 -276.596303) (xy 178.61216 -276.594322) (xy 178.661015 -276.600254) (xy 178.708286 -276.613946)
			(xy 178.752748 -276.635044) (xy 178.793251 -276.663) (xy 178.828744 -276.697092) (xy 178.858309 -276.736436)
			(xy 178.88118 -276.780013) (xy 178.896764 -276.826694) (xy 178.904659 -276.875271) (xy 178.905154 -276.899878)
			(xy 179.244256 -276.899878) (xy 179.248216 -276.850824) (xy 179.259993 -276.80304) (xy 179.279284 -276.757764)
			(xy 179.305587 -276.716168) (xy 179.338222 -276.679331) (xy 179.376343 -276.648206) (xy 179.418964 -276.623599)
			(xy 179.46498 -276.606147) (xy 179.513199 -276.596303) (xy 179.562374 -276.594322) (xy 179.611229 -276.600254)
			(xy 179.6585 -276.613946) (xy 179.702962 -276.635044) (xy 179.743465 -276.663) (xy 179.778958 -276.697092)
			(xy 179.808523 -276.736436) (xy 179.831394 -276.780013) (xy 179.846978 -276.826694) (xy 179.854873 -276.875271)
			(xy 179.855368 -276.899878) (xy 180.194216 -276.899878) (xy 180.198176 -276.850824) (xy 180.209953 -276.80304)
			(xy 180.229244 -276.757764) (xy 180.255547 -276.716168) (xy 180.288182 -276.679331) (xy 180.326303 -276.648206)
			(xy 180.368924 -276.623599) (xy 180.41494 -276.606147) (xy 180.463159 -276.596303) (xy 180.512334 -276.594322)
			(xy 180.561189 -276.600254) (xy 180.60846 -276.613946) (xy 180.652922 -276.635044) (xy 180.693425 -276.663)
			(xy 180.728918 -276.697092) (xy 180.758483 -276.736436) (xy 180.781354 -276.780013) (xy 180.796938 -276.826694)
			(xy 180.804833 -276.875271) (xy 180.805328 -276.899878) (xy 181.144176 -276.899878) (xy 181.148136 -276.850824)
			(xy 181.159913 -276.80304) (xy 181.179204 -276.757764) (xy 181.205507 -276.716168) (xy 181.238142 -276.679331)
			(xy 181.276263 -276.648206) (xy 181.318884 -276.623599) (xy 181.3649 -276.606147) (xy 181.413119 -276.596303)
			(xy 181.462294 -276.594322) (xy 181.511149 -276.600254) (xy 181.55842 -276.613946) (xy 181.602882 -276.635044)
			(xy 181.643385 -276.663) (xy 181.678878 -276.697092) (xy 181.708443 -276.736436) (xy 181.731314 -276.780013)
			(xy 181.746898 -276.826694) (xy 181.754793 -276.875271) (xy 181.755288 -276.899878) (xy 182.094136 -276.899878)
			(xy 182.098096 -276.850824) (xy 182.109873 -276.80304) (xy 182.129164 -276.757764) (xy 182.155467 -276.716168)
			(xy 182.188102 -276.679331) (xy 182.226223 -276.648206) (xy 182.268844 -276.623599) (xy 182.31486 -276.606147)
			(xy 182.363079 -276.596303) (xy 182.412254 -276.594322) (xy 182.461109 -276.600254) (xy 182.50838 -276.613946)
			(xy 182.552842 -276.635044) (xy 182.593345 -276.663) (xy 182.628838 -276.697092) (xy 182.658403 -276.736436)
			(xy 182.681274 -276.780013) (xy 182.696858 -276.826694) (xy 182.704753 -276.875271) (xy 182.705248 -276.899878)
			(xy 183.044096 -276.899878) (xy 183.048056 -276.850824) (xy 183.059833 -276.80304) (xy 183.079124 -276.757764)
			(xy 183.105427 -276.716168) (xy 183.138062 -276.679331) (xy 183.176183 -276.648206) (xy 183.218804 -276.623599)
			(xy 183.26482 -276.606147) (xy 183.313039 -276.596303) (xy 183.362214 -276.594322) (xy 183.411069 -276.600254)
			(xy 183.45834 -276.613946) (xy 183.502802 -276.635044) (xy 183.543305 -276.663) (xy 183.578798 -276.697092)
			(xy 183.608363 -276.736436) (xy 183.631234 -276.780013) (xy 183.646818 -276.826694) (xy 183.654713 -276.875271)
			(xy 183.655208 -276.899878) (xy 183.994056 -276.899878) (xy 183.998016 -276.850824) (xy 184.009793 -276.80304)
			(xy 184.029084 -276.757764) (xy 184.055387 -276.716168) (xy 184.088022 -276.679331) (xy 184.126143 -276.648206)
			(xy 184.168764 -276.623599) (xy 184.21478 -276.606147) (xy 184.262999 -276.596303) (xy 184.312174 -276.594322)
			(xy 184.361029 -276.600254) (xy 184.4083 -276.613946) (xy 184.452762 -276.635044) (xy 184.493265 -276.663)
			(xy 184.528758 -276.697092) (xy 184.558323 -276.736436) (xy 184.581194 -276.780013) (xy 184.596778 -276.826694)
			(xy 184.604673 -276.875271) (xy 184.605168 -276.899878) (xy 184.94427 -276.899878) (xy 184.94823 -276.850824)
			(xy 184.960007 -276.80304) (xy 184.979298 -276.757764) (xy 185.005601 -276.716168) (xy 185.038236 -276.679331)
			(xy 185.076357 -276.648206) (xy 185.118978 -276.623599) (xy 185.164994 -276.606147) (xy 185.213213 -276.596303)
			(xy 185.262388 -276.594322) (xy 185.311243 -276.600254) (xy 185.358514 -276.613946) (xy 185.402976 -276.635044)
			(xy 185.443479 -276.663) (xy 185.478972 -276.697092) (xy 185.508537 -276.736436) (xy 185.531408 -276.780013)
			(xy 185.546992 -276.826694) (xy 185.554887 -276.875271) (xy 185.555382 -276.899878) (xy 185.89423 -276.899878)
			(xy 185.89819 -276.850824) (xy 185.909967 -276.80304) (xy 185.929258 -276.757764) (xy 185.955561 -276.716168)
			(xy 185.988196 -276.679331) (xy 186.026317 -276.648206) (xy 186.068938 -276.623599) (xy 186.114954 -276.606147)
			(xy 186.163173 -276.596303) (xy 186.212348 -276.594322) (xy 186.261203 -276.600254) (xy 186.308474 -276.613946)
			(xy 186.352936 -276.635044) (xy 186.393439 -276.663) (xy 186.428932 -276.697092) (xy 186.458497 -276.736436)
			(xy 186.481368 -276.780013) (xy 186.496952 -276.826694) (xy 186.504847 -276.875271) (xy 186.505342 -276.899878)
			(xy 186.84419 -276.899878) (xy 186.84815 -276.850824) (xy 186.859927 -276.80304) (xy 186.879218 -276.757764)
			(xy 186.905521 -276.716168) (xy 186.938156 -276.679331) (xy 186.976277 -276.648206) (xy 187.018898 -276.623599)
			(xy 187.064914 -276.606147) (xy 187.113133 -276.596303) (xy 187.162308 -276.594322) (xy 187.211163 -276.600254)
			(xy 187.258434 -276.613946) (xy 187.302896 -276.635044) (xy 187.343399 -276.663) (xy 187.378892 -276.697092)
			(xy 187.408457 -276.736436) (xy 187.431328 -276.780013) (xy 187.446912 -276.826694) (xy 187.454807 -276.875271)
			(xy 187.455302 -276.899878) (xy 187.79415 -276.899878) (xy 187.79811 -276.850824) (xy 187.809887 -276.80304)
			(xy 187.829178 -276.757764) (xy 187.855481 -276.716168) (xy 187.888116 -276.679331) (xy 187.926237 -276.648206)
			(xy 187.968858 -276.623599) (xy 188.014874 -276.606147) (xy 188.063093 -276.596303) (xy 188.112268 -276.594322)
			(xy 188.161123 -276.600254) (xy 188.208394 -276.613946) (xy 188.252856 -276.635044) (xy 188.293359 -276.663)
			(xy 188.328852 -276.697092) (xy 188.358417 -276.736436) (xy 188.381288 -276.780013) (xy 188.396872 -276.826694)
			(xy 188.404767 -276.875271) (xy 188.405262 -276.899878) (xy 188.74411 -276.899878) (xy 188.74807 -276.850824)
			(xy 188.759847 -276.80304) (xy 188.779138 -276.757764) (xy 188.805441 -276.716168) (xy 188.838076 -276.679331)
			(xy 188.876197 -276.648206) (xy 188.918818 -276.623599) (xy 188.964834 -276.606147) (xy 189.013053 -276.596303)
			(xy 189.062228 -276.594322) (xy 189.111083 -276.600254) (xy 189.158354 -276.613946) (xy 189.202816 -276.635044)
			(xy 189.243319 -276.663) (xy 189.278812 -276.697092) (xy 189.308377 -276.736436) (xy 189.331248 -276.780013)
			(xy 189.346832 -276.826694) (xy 189.354727 -276.875271) (xy 189.355222 -276.899878) (xy 189.693816 -276.899878)
			(xy 189.697776 -276.850824) (xy 189.709553 -276.80304) (xy 189.728844 -276.757764) (xy 189.755147 -276.716168)
			(xy 189.787782 -276.679331) (xy 189.825903 -276.648206) (xy 189.868524 -276.623599) (xy 189.91454 -276.606147)
			(xy 189.962759 -276.596303) (xy 190.011934 -276.594322) (xy 190.060789 -276.600254) (xy 190.10806 -276.613946)
			(xy 190.152522 -276.635044) (xy 190.193025 -276.663) (xy 190.228518 -276.697092) (xy 190.258083 -276.736436)
			(xy 190.280954 -276.780013) (xy 190.296538 -276.826694) (xy 190.304433 -276.875271) (xy 190.304928 -276.899878)
			(xy 190.64403 -276.899878) (xy 190.64799 -276.850824) (xy 190.659767 -276.80304) (xy 190.679058 -276.757764)
			(xy 190.705361 -276.716168) (xy 190.737996 -276.679331) (xy 190.776117 -276.648206) (xy 190.818738 -276.623599)
			(xy 190.864754 -276.606147) (xy 190.912973 -276.596303) (xy 190.962148 -276.594322) (xy 191.011003 -276.600254)
			(xy 191.058274 -276.613946) (xy 191.102736 -276.635044) (xy 191.143239 -276.663) (xy 191.178732 -276.697092)
			(xy 191.208297 -276.736436) (xy 191.231168 -276.780013) (xy 191.246752 -276.826694) (xy 191.254647 -276.875271)
			(xy 191.255142 -276.899878) (xy 191.59399 -276.899878) (xy 191.59795 -276.850824) (xy 191.609727 -276.80304)
			(xy 191.629018 -276.757764) (xy 191.655321 -276.716168) (xy 191.687956 -276.679331) (xy 191.726077 -276.648206)
			(xy 191.768698 -276.623599) (xy 191.814714 -276.606147) (xy 191.862933 -276.596303) (xy 191.912108 -276.594322)
			(xy 191.960963 -276.600254) (xy 192.008234 -276.613946) (xy 192.052696 -276.635044) (xy 192.093199 -276.663)
			(xy 192.128692 -276.697092) (xy 192.158257 -276.736436) (xy 192.181128 -276.780013) (xy 192.196712 -276.826694)
			(xy 192.204607 -276.875271) (xy 192.205102 -276.899878) (xy 192.54395 -276.899878) (xy 192.54791 -276.850824)
			(xy 192.559687 -276.80304) (xy 192.578978 -276.757764) (xy 192.605281 -276.716168) (xy 192.637916 -276.679331)
			(xy 192.676037 -276.648206) (xy 192.718658 -276.623599) (xy 192.764674 -276.606147) (xy 192.812893 -276.596303)
			(xy 192.862068 -276.594322) (xy 192.910923 -276.600254) (xy 192.958194 -276.613946) (xy 193.002656 -276.635044)
			(xy 193.043159 -276.663) (xy 193.078652 -276.697092) (xy 193.108217 -276.736436) (xy 193.131088 -276.780013)
			(xy 193.146672 -276.826694) (xy 193.154567 -276.875271) (xy 193.155062 -276.899878) (xy 193.49391 -276.899878)
			(xy 193.49787 -276.850824) (xy 193.509647 -276.80304) (xy 193.528938 -276.757764) (xy 193.555241 -276.716168)
			(xy 193.587876 -276.679331) (xy 193.625997 -276.648206) (xy 193.668618 -276.623599) (xy 193.714634 -276.606147)
			(xy 193.762853 -276.596303) (xy 193.812028 -276.594322) (xy 193.860883 -276.600254) (xy 193.908154 -276.613946)
			(xy 193.952616 -276.635044) (xy 193.993119 -276.663) (xy 194.028612 -276.697092) (xy 194.058177 -276.736436)
			(xy 194.081048 -276.780013) (xy 194.096632 -276.826694) (xy 194.104527 -276.875271) (xy 194.105022 -276.899878)
			(xy 194.44387 -276.899878) (xy 194.44783 -276.850824) (xy 194.459607 -276.80304) (xy 194.478898 -276.757764)
			(xy 194.505201 -276.716168) (xy 194.537836 -276.679331) (xy 194.575957 -276.648206) (xy 194.618578 -276.623599)
			(xy 194.664594 -276.606147) (xy 194.712813 -276.596303) (xy 194.761988 -276.594322) (xy 194.810843 -276.600254)
			(xy 194.858114 -276.613946) (xy 194.902576 -276.635044) (xy 194.943079 -276.663) (xy 194.978572 -276.697092)
			(xy 195.008137 -276.736436) (xy 195.031008 -276.780013) (xy 195.046592 -276.826694) (xy 195.054487 -276.875271)
			(xy 195.054982 -276.899878) (xy 195.39383 -276.899878) (xy 195.39779 -276.850824) (xy 195.409567 -276.80304)
			(xy 195.428858 -276.757764) (xy 195.455161 -276.716168) (xy 195.487796 -276.679331) (xy 195.525917 -276.648206)
			(xy 195.568538 -276.623599) (xy 195.614554 -276.606147) (xy 195.662773 -276.596303) (xy 195.711948 -276.594322)
			(xy 195.760803 -276.600254) (xy 195.808074 -276.613946) (xy 195.852536 -276.635044) (xy 195.893039 -276.663)
			(xy 195.928532 -276.697092) (xy 195.958097 -276.736436) (xy 195.980968 -276.780013) (xy 195.996552 -276.826694)
			(xy 196.004447 -276.875271) (xy 196.004942 -276.899878) (xy 196.344044 -276.899878) (xy 196.348004 -276.850824)
			(xy 196.359781 -276.80304) (xy 196.379072 -276.757764) (xy 196.405375 -276.716168) (xy 196.43801 -276.679331)
			(xy 196.476131 -276.648206) (xy 196.518752 -276.623599) (xy 196.564768 -276.606147) (xy 196.612987 -276.596303)
			(xy 196.662162 -276.594322) (xy 196.711017 -276.600254) (xy 196.758288 -276.613946) (xy 196.80275 -276.635044)
			(xy 196.843253 -276.663) (xy 196.878746 -276.697092) (xy 196.908311 -276.736436) (xy 196.931182 -276.780013)
			(xy 196.946766 -276.826694) (xy 196.954661 -276.875271) (xy 196.955156 -276.899878) (xy 196.954661 -276.924485)
			(xy 196.954482 -276.925586) (xy 197.273414 -276.925586) (xy 197.273414 -276.87417) (xy 197.281457 -276.823388)
			(xy 197.297345 -276.774489) (xy 197.320688 -276.728677) (xy 197.350909 -276.687081) (xy 197.387265 -276.650725)
			(xy 197.428861 -276.620504) (xy 197.474673 -276.597161) (xy 197.523572 -276.581273) (xy 197.574354 -276.57323)
			(xy 197.62577 -276.57323) (xy 197.676552 -276.581273) (xy 197.725451 -276.597161) (xy 197.771263 -276.620504)
			(xy 197.812859 -276.650725) (xy 197.849215 -276.687081) (xy 197.879436 -276.728677) (xy 197.902779 -276.774489)
			(xy 197.918667 -276.823388) (xy 197.92671 -276.87417) (xy 197.927214 -276.899878) (xy 197.92671 -276.925586)
			(xy 198.223374 -276.925586) (xy 198.223374 -276.87417) (xy 198.231417 -276.823388) (xy 198.247305 -276.774489)
			(xy 198.270648 -276.728677) (xy 198.300869 -276.687081) (xy 198.337225 -276.650725) (xy 198.378821 -276.620504)
			(xy 198.424633 -276.597161) (xy 198.473532 -276.581273) (xy 198.524314 -276.57323) (xy 198.57573 -276.57323)
			(xy 198.626512 -276.581273) (xy 198.675411 -276.597161) (xy 198.721223 -276.620504) (xy 198.762819 -276.650725)
			(xy 198.799175 -276.687081) (xy 198.829396 -276.728677) (xy 198.852739 -276.774489) (xy 198.868627 -276.823388)
			(xy 198.87667 -276.87417) (xy 198.877174 -276.899878) (xy 198.877169 -276.900132) (xy 199.194432 -276.900132)
			(xy 199.198392 -276.851078) (xy 199.210169 -276.803294) (xy 199.22946 -276.758018) (xy 199.255763 -276.716422)
			(xy 199.288398 -276.679585) (xy 199.326519 -276.64846) (xy 199.36914 -276.623853) (xy 199.415156 -276.606401)
			(xy 199.463375 -276.596557) (xy 199.51255 -276.594576) (xy 199.561405 -276.600508) (xy 199.608676 -276.6142)
			(xy 199.653138 -276.635298) (xy 199.693641 -276.663254) (xy 199.729134 -276.697346) (xy 199.758699 -276.73669)
			(xy 199.78157 -276.780267) (xy 199.797154 -276.826948) (xy 199.805049 -276.875525) (xy 199.805544 -276.900132)
			(xy 199.805049 -276.924739) (xy 199.797154 -276.973316) (xy 199.78157 -277.019997) (xy 199.758699 -277.063574)
			(xy 199.729134 -277.102918) (xy 199.698293 -277.132542) (xy 215.516966 -277.132542) (xy 215.521037 -277.07692)
			(xy 215.533163 -277.022483) (xy 215.553086 -276.970392) (xy 215.580382 -276.921757) (xy 215.614468 -276.877614)
			(xy 215.654617 -276.838905) (xy 215.699975 -276.806454) (xy 215.749575 -276.780953) (xy 215.802359 -276.762946)
			(xy 215.857202 -276.752816) (xy 215.912936 -276.750779) (xy 215.968373 -276.756879) (xy 216.02233 -276.770985)
			(xy 216.073659 -276.792797) (xy 216.121265 -276.821851) (xy 216.164133 -276.857526) (xy 216.20135 -276.899063)
			(xy 216.232123 -276.945576) (xy 216.255795 -276.996073) (xy 216.271863 -277.04948) (xy 216.279983 -277.104656)
			(xy 216.280492 -277.132542) (xy 216.279983 -277.160428) (xy 216.271863 -277.215604) (xy 216.256275 -277.267416)
			(xy 219.95257 -277.267416) (xy 219.953028 -277.240045) (xy 219.960845 -277.185865) (xy 219.976335 -277.133361)
			(xy 219.999179 -277.083615) (xy 220.028907 -277.037649) (xy 220.04655 -277.016718) (xy 220.052646 -277.009606)
			(xy 220.058996 -276.992588) (xy 220.058996 -276.907244) (xy 220.052646 -276.890226) (xy 220.04655 -276.883114)
			(xy 220.028912 -276.862181) (xy 219.999198 -276.816209) (xy 219.976361 -276.766462) (xy 219.96087 -276.713961)
			(xy 219.953043 -276.659785) (xy 219.95257 -276.632416) (xy 219.953093 -276.605166) (xy 219.960847 -276.551221)
			(xy 219.976199 -276.498928) (xy 219.998836 -276.449353) (xy 220.028299 -276.403503) (xy 220.063987 -276.362314)
			(xy 220.105173 -276.326622) (xy 220.151019 -276.297155) (xy 220.200593 -276.274512) (xy 220.252884 -276.259155)
			(xy 220.306828 -276.251396) (xy 220.334078 -276.250908) (xy 220.362816 -276.251443) (xy 220.419643 -276.260063)
			(xy 220.474534 -276.27711) (xy 220.526246 -276.302199) (xy 220.573609 -276.334762) (xy 220.594936 -276.354032)
			(xy 220.602048 -276.360636) (xy 220.619574 -276.367748) (xy 220.708982 -276.367748) (xy 220.726508 -276.360636)
			(xy 220.73362 -276.354032) (xy 220.754947 -276.334762) (xy 220.80231 -276.302197) (xy 220.854021 -276.277106)
			(xy 220.908912 -276.260056) (xy 220.965739 -276.251434) (xy 221.023217 -276.251434) (xy 221.080044 -276.260056)
			(xy 221.134935 -276.277106) (xy 221.186646 -276.302197) (xy 221.234009 -276.334762) (xy 221.255336 -276.354032)
			(xy 221.262448 -276.360636) (xy 221.279974 -276.367748) (xy 221.369382 -276.367748) (xy 221.386908 -276.360636)
			(xy 221.39402 -276.354032) (xy 221.415347 -276.334762) (xy 221.46271 -276.302197) (xy 221.514421 -276.277106)
			(xy 221.569312 -276.260056) (xy 221.626139 -276.251434) (xy 221.683617 -276.251434) (xy 221.740444 -276.260056)
			(xy 221.795335 -276.277106) (xy 221.847046 -276.302197) (xy 221.894409 -276.334762) (xy 221.915736 -276.354032)
			(xy 221.922848 -276.360636) (xy 221.940374 -276.367748) (xy 222.029782 -276.367748) (xy 222.047308 -276.360636)
			(xy 222.05442 -276.354032) (xy 222.075755 -276.334771) (xy 222.123115 -276.302203) (xy 222.174825 -276.277109)
			(xy 222.229714 -276.260056) (xy 222.28654 -276.251431) (xy 222.315278 -276.250908) (xy 222.342531 -276.251376)
			(xy 222.396483 -276.25913) (xy 222.448781 -276.274484) (xy 222.498362 -276.297125) (xy 222.544216 -276.326593)
			(xy 222.58541 -276.362286) (xy 222.591243 -276.369018) (xy 225.13493 -276.369018) (xy 225.139001 -276.313396)
			(xy 225.151127 -276.258959) (xy 225.17105 -276.206868) (xy 225.198346 -276.158233) (xy 225.232432 -276.11409)
			(xy 225.272581 -276.075381) (xy 225.317939 -276.04293) (xy 225.367539 -276.017429) (xy 225.420323 -275.999422)
			(xy 225.475166 -275.989292) (xy 225.5309 -275.987255) (xy 225.586337 -275.993355) (xy 225.640294 -276.007461)
			(xy 225.691623 -276.029273) (xy 225.739229 -276.058327) (xy 225.782097 -276.094002) (xy 225.819314 -276.135539)
			(xy 225.850087 -276.182052) (xy 225.873759 -276.232549) (xy 225.889827 -276.285956) (xy 225.897947 -276.341132)
			(xy 225.898456 -276.369018) (xy 225.897947 -276.396904) (xy 225.889827 -276.45208) (xy 225.873759 -276.505487)
			(xy 225.867243 -276.519386) (xy 230.452928 -276.519386) (xy 230.456999 -276.463764) (xy 230.469125 -276.409327)
			(xy 230.489048 -276.357236) (xy 230.516344 -276.308601) (xy 230.55043 -276.264458) (xy 230.590579 -276.225749)
			(xy 230.635937 -276.193298) (xy 230.685537 -276.167797) (xy 230.738321 -276.14979) (xy 230.793164 -276.13966)
			(xy 230.848898 -276.137623) (xy 230.904335 -276.143723) (xy 230.958292 -276.157829) (xy 231.009621 -276.179641)
			(xy 231.057227 -276.208695) (xy 231.100095 -276.24437) (xy 231.137312 -276.285907) (xy 231.168085 -276.33242)
			(xy 231.191757 -276.382917) (xy 231.207825 -276.436324) (xy 231.215945 -276.4915) (xy 231.216454 -276.519386)
			(xy 232.472228 -276.519386) (xy 232.476299 -276.463764) (xy 232.488425 -276.409327) (xy 232.508348 -276.357236)
			(xy 232.535644 -276.308601) (xy 232.56973 -276.264458) (xy 232.609879 -276.225749) (xy 232.655237 -276.193298)
			(xy 232.704837 -276.167797) (xy 232.757621 -276.14979) (xy 232.812464 -276.13966) (xy 232.868198 -276.137623)
			(xy 232.923635 -276.143723) (xy 232.977592 -276.157829) (xy 233.028921 -276.179641) (xy 233.076527 -276.208695)
			(xy 233.119395 -276.24437) (xy 233.156612 -276.285907) (xy 233.187385 -276.33242) (xy 233.211057 -276.382917)
			(xy 233.227125 -276.436324) (xy 233.235245 -276.4915) (xy 233.235754 -276.519386) (xy 233.235245 -276.547272)
			(xy 233.227125 -276.602448) (xy 233.211057 -276.655855) (xy 233.187385 -276.706352) (xy 233.156612 -276.752865)
			(xy 233.119395 -276.794402) (xy 233.076527 -276.830077) (xy 233.028921 -276.859131) (xy 232.977592 -276.880943)
			(xy 232.923635 -276.895049) (xy 232.868198 -276.901149) (xy 232.812464 -276.899112) (xy 232.757621 -276.888982)
			(xy 232.704837 -276.870975) (xy 232.655237 -276.845474) (xy 232.609879 -276.813023) (xy 232.56973 -276.774314)
			(xy 232.535644 -276.730171) (xy 232.508348 -276.681536) (xy 232.488425 -276.629445) (xy 232.476299 -276.575008)
			(xy 232.472228 -276.519386) (xy 231.216454 -276.519386) (xy 231.215945 -276.547272) (xy 231.207825 -276.602448)
			(xy 231.191757 -276.655855) (xy 231.168085 -276.706352) (xy 231.137312 -276.752865) (xy 231.100095 -276.794402)
			(xy 231.057227 -276.830077) (xy 231.009621 -276.859131) (xy 230.958292 -276.880943) (xy 230.904335 -276.895049)
			(xy 230.848898 -276.901149) (xy 230.793164 -276.899112) (xy 230.738321 -276.888982) (xy 230.685537 -276.870975)
			(xy 230.635937 -276.845474) (xy 230.590579 -276.813023) (xy 230.55043 -276.774314) (xy 230.516344 -276.730171)
			(xy 230.489048 -276.681536) (xy 230.469125 -276.629445) (xy 230.456999 -276.575008) (xy 230.452928 -276.519386)
			(xy 225.867243 -276.519386) (xy 225.850087 -276.555984) (xy 225.819314 -276.602497) (xy 225.782097 -276.644034)
			(xy 225.739229 -276.679709) (xy 225.691623 -276.708763) (xy 225.640294 -276.730575) (xy 225.586337 -276.744681)
			(xy 225.5309 -276.750781) (xy 225.475166 -276.748744) (xy 225.420323 -276.738614) (xy 225.367539 -276.720607)
			(xy 225.317939 -276.695106) (xy 225.272581 -276.662655) (xy 225.232432 -276.623946) (xy 225.198346 -276.579803)
			(xy 225.17105 -276.531168) (xy 225.151127 -276.479077) (xy 225.139001 -276.42464) (xy 225.13493 -276.369018)
			(xy 222.591243 -276.369018) (xy 222.621104 -276.403479) (xy 222.650572 -276.449332) (xy 222.673214 -276.498913)
			(xy 222.688568 -276.551211) (xy 222.696324 -276.605163) (xy 222.696786 -276.632416) (xy 222.696333 -276.659787)
			(xy 222.688512 -276.713966) (xy 222.67302 -276.76647) (xy 222.650176 -276.816217) (xy 222.620449 -276.862183)
			(xy 222.602806 -276.883114) (xy 222.59671 -276.890226) (xy 222.59036 -276.907244) (xy 222.59036 -276.992588)
			(xy 222.59671 -277.009606) (xy 222.602806 -277.016718) (xy 222.620421 -277.037669) (xy 222.650136 -277.083637)
			(xy 222.672977 -277.13338) (xy 222.688474 -277.185876) (xy 222.692442 -277.213314) (xy 227.470206 -277.213314)
			(xy 227.474277 -277.157692) (xy 227.486403 -277.103255) (xy 227.506326 -277.051164) (xy 227.533622 -277.002529)
			(xy 227.567708 -276.958386) (xy 227.607857 -276.919677) (xy 227.653215 -276.887226) (xy 227.702815 -276.861725)
			(xy 227.755599 -276.843718) (xy 227.810442 -276.833588) (xy 227.866176 -276.831551) (xy 227.921613 -276.837651)
			(xy 227.97557 -276.851757) (xy 228.026899 -276.873569) (xy 228.074505 -276.902623) (xy 228.117373 -276.938298)
			(xy 228.15459 -276.979835) (xy 228.185363 -277.026348) (xy 228.209035 -277.076845) (xy 228.225103 -277.130252)
			(xy 228.233223 -277.185428) (xy 228.233523 -277.201884) (xy 228.659688 -277.201884) (xy 228.663759 -277.146262)
			(xy 228.675885 -277.091825) (xy 228.695808 -277.039734) (xy 228.723104 -276.991099) (xy 228.75719 -276.946956)
			(xy 228.797339 -276.908247) (xy 228.842697 -276.875796) (xy 228.892297 -276.850295) (xy 228.945081 -276.832288)
			(xy 228.999924 -276.822158) (xy 229.055658 -276.820121) (xy 229.111095 -276.826221) (xy 229.165052 -276.840327)
			(xy 229.216381 -276.862139) (xy 229.263987 -276.891193) (xy 229.306855 -276.926868) (xy 229.344072 -276.968405)
			(xy 229.374845 -277.014918) (xy 229.398517 -277.065415) (xy 229.414585 -277.118822) (xy 229.422705 -277.173998)
			(xy 229.423214 -277.201884) (xy 229.422705 -277.22977) (xy 229.414585 -277.284946) (xy 229.398517 -277.338353)
			(xy 229.374845 -277.38885) (xy 229.344072 -277.435363) (xy 229.306855 -277.4769) (xy 229.263987 -277.512575)
			(xy 229.216381 -277.541629) (xy 229.165052 -277.563441) (xy 229.111095 -277.577547) (xy 229.055658 -277.583647)
			(xy 228.999924 -277.58161) (xy 228.945081 -277.57148) (xy 228.892297 -277.553473) (xy 228.842697 -277.527972)
			(xy 228.797339 -277.495521) (xy 228.75719 -277.456812) (xy 228.723104 -277.412669) (xy 228.695808 -277.364034)
			(xy 228.675885 -277.311943) (xy 228.663759 -277.257506) (xy 228.659688 -277.201884) (xy 228.233523 -277.201884)
			(xy 228.233732 -277.213314) (xy 228.233223 -277.2412) (xy 228.225103 -277.296376) (xy 228.209035 -277.349783)
			(xy 228.185363 -277.40028) (xy 228.15459 -277.446793) (xy 228.117373 -277.48833) (xy 228.074505 -277.524005)
			(xy 228.026899 -277.553059) (xy 227.97557 -277.574871) (xy 227.921613 -277.588977) (xy 227.866176 -277.595077)
			(xy 227.810442 -277.59304) (xy 227.755599 -277.58291) (xy 227.702815 -277.564903) (xy 227.653215 -277.539402)
			(xy 227.607857 -277.506951) (xy 227.567708 -277.468242) (xy 227.533622 -277.424099) (xy 227.506326 -277.375464)
			(xy 227.486403 -277.323373) (xy 227.474277 -277.268936) (xy 227.470206 -277.213314) (xy 222.692442 -277.213314)
			(xy 222.696308 -277.240048) (xy 222.696786 -277.267416) (xy 222.69636 -277.29467) (xy 222.6886 -277.348624)
			(xy 222.673241 -277.400924) (xy 222.650595 -277.450505) (xy 222.621123 -277.49636) (xy 222.585426 -277.537553)
			(xy 222.544229 -277.573246) (xy 222.498372 -277.602713) (xy 222.448788 -277.625354) (xy 222.396487 -277.640708)
			(xy 222.342532 -277.648463) (xy 222.315278 -277.648924) (xy 222.286539 -277.648407) (xy 222.229712 -277.639782)
			(xy 222.174821 -277.62273) (xy 222.123109 -277.597637) (xy 222.075747 -277.565071) (xy 222.05442 -277.5458)
			(xy 222.047308 -277.539196) (xy 222.029782 -277.532084) (xy 221.940374 -277.532084) (xy 221.922848 -277.539196)
			(xy 221.915736 -277.5458) (xy 221.894409 -277.56507) (xy 221.847046 -277.597635) (xy 221.795335 -277.622726)
			(xy 221.740444 -277.639776) (xy 221.683617 -277.648398) (xy 221.626139 -277.648398) (xy 221.569312 -277.639776)
			(xy 221.514421 -277.622726) (xy 221.46271 -277.597635) (xy 221.415347 -277.56507) (xy 221.39402 -277.5458)
			(xy 221.386908 -277.539196) (xy 221.369382 -277.532084) (xy 221.279974 -277.532084) (xy 221.262448 -277.539196)
			(xy 221.255336 -277.5458) (xy 221.234009 -277.56507) (xy 221.186646 -277.597635) (xy 221.134935 -277.622726)
			(xy 221.080044 -277.639776) (xy 221.023217 -277.648398) (xy 220.965739 -277.648398) (xy 220.908912 -277.639776)
			(xy 220.854021 -277.622726) (xy 220.80231 -277.597635) (xy 220.754947 -277.56507) (xy 220.73362 -277.5458)
			(xy 220.726508 -277.539196) (xy 220.708982 -277.532084) (xy 220.619574 -277.532084) (xy 220.602048 -277.539196)
			(xy 220.594936 -277.5458) (xy 220.573609 -277.565071) (xy 220.526248 -277.597639) (xy 220.474536 -277.622733)
			(xy 220.419645 -277.639783) (xy 220.362817 -277.648404) (xy 220.334078 -277.648924) (xy 220.306827 -277.648443)
			(xy 220.25288 -277.640684) (xy 220.200586 -277.625327) (xy 220.15101 -277.602684) (xy 220.10516 -277.573217)
			(xy 220.063971 -277.537525) (xy 220.02828 -277.496335) (xy 219.998813 -277.450485) (xy 219.976171 -277.400908)
			(xy 219.960815 -277.348614) (xy 219.953057 -277.294667) (xy 219.95257 -277.267416) (xy 216.256275 -277.267416)
			(xy 216.255795 -277.269011) (xy 216.232123 -277.319508) (xy 216.20135 -277.366021) (xy 216.164133 -277.407558)
			(xy 216.121265 -277.443233) (xy 216.073659 -277.472287) (xy 216.02233 -277.494099) (xy 215.968373 -277.508205)
			(xy 215.912936 -277.514305) (xy 215.857202 -277.512268) (xy 215.802359 -277.502138) (xy 215.749575 -277.484131)
			(xy 215.699975 -277.45863) (xy 215.654617 -277.426179) (xy 215.614468 -277.38747) (xy 215.580382 -277.343327)
			(xy 215.553086 -277.294692) (xy 215.533163 -277.242601) (xy 215.521037 -277.188164) (xy 215.516966 -277.132542)
			(xy 199.698293 -277.132542) (xy 199.693641 -277.13701) (xy 199.653138 -277.164966) (xy 199.608676 -277.186064)
			(xy 199.561405 -277.199756) (xy 199.51255 -277.205688) (xy 199.463375 -277.203707) (xy 199.415156 -277.193863)
			(xy 199.36914 -277.176411) (xy 199.326519 -277.151804) (xy 199.288398 -277.120679) (xy 199.255763 -277.083842)
			(xy 199.22946 -277.042246) (xy 199.210169 -276.99697) (xy 199.198392 -276.949186) (xy 199.194432 -276.900132)
			(xy 198.877169 -276.900132) (xy 198.87667 -276.925586) (xy 198.868627 -276.976368) (xy 198.852739 -277.025267)
			(xy 198.829396 -277.071079) (xy 198.799175 -277.112675) (xy 198.762819 -277.149031) (xy 198.721223 -277.179252)
			(xy 198.675411 -277.202595) (xy 198.626512 -277.218483) (xy 198.57573 -277.226526) (xy 198.524314 -277.226526)
			(xy 198.473532 -277.218483) (xy 198.424633 -277.202595) (xy 198.378821 -277.179252) (xy 198.337225 -277.149031)
			(xy 198.300869 -277.112675) (xy 198.270648 -277.071079) (xy 198.247305 -277.025267) (xy 198.231417 -276.976368)
			(xy 198.223374 -276.925586) (xy 197.92671 -276.925586) (xy 197.918667 -276.976368) (xy 197.902779 -277.025267)
			(xy 197.879436 -277.071079) (xy 197.849215 -277.112675) (xy 197.812859 -277.149031) (xy 197.771263 -277.179252)
			(xy 197.725451 -277.202595) (xy 197.676552 -277.218483) (xy 197.62577 -277.226526) (xy 197.574354 -277.226526)
			(xy 197.523572 -277.218483) (xy 197.474673 -277.202595) (xy 197.428861 -277.179252) (xy 197.387265 -277.149031)
			(xy 197.350909 -277.112675) (xy 197.320688 -277.071079) (xy 197.297345 -277.025267) (xy 197.281457 -276.976368)
			(xy 197.273414 -276.925586) (xy 196.954482 -276.925586) (xy 196.946766 -276.973062) (xy 196.931182 -277.019743)
			(xy 196.908311 -277.06332) (xy 196.878746 -277.102664) (xy 196.843253 -277.136756) (xy 196.80275 -277.164712)
			(xy 196.758288 -277.18581) (xy 196.711017 -277.199502) (xy 196.662162 -277.205434) (xy 196.612987 -277.203453)
			(xy 196.564768 -277.193609) (xy 196.518752 -277.176157) (xy 196.476131 -277.15155) (xy 196.43801 -277.120425)
			(xy 196.405375 -277.083588) (xy 196.379072 -277.041992) (xy 196.359781 -276.996716) (xy 196.348004 -276.948932)
			(xy 196.344044 -276.899878) (xy 196.004942 -276.899878) (xy 196.004447 -276.924485) (xy 195.996552 -276.973062)
			(xy 195.980968 -277.019743) (xy 195.958097 -277.06332) (xy 195.928532 -277.102664) (xy 195.893039 -277.136756)
			(xy 195.852536 -277.164712) (xy 195.808074 -277.18581) (xy 195.760803 -277.199502) (xy 195.711948 -277.205434)
			(xy 195.662773 -277.203453) (xy 195.614554 -277.193609) (xy 195.568538 -277.176157) (xy 195.525917 -277.15155)
			(xy 195.487796 -277.120425) (xy 195.455161 -277.083588) (xy 195.428858 -277.041992) (xy 195.409567 -276.996716)
			(xy 195.39779 -276.948932) (xy 195.39383 -276.899878) (xy 195.054982 -276.899878) (xy 195.054487 -276.924485)
			(xy 195.046592 -276.973062) (xy 195.031008 -277.019743) (xy 195.008137 -277.06332) (xy 194.978572 -277.102664)
			(xy 194.943079 -277.136756) (xy 194.902576 -277.164712) (xy 194.858114 -277.18581) (xy 194.810843 -277.199502)
			(xy 194.761988 -277.205434) (xy 194.712813 -277.203453) (xy 194.664594 -277.193609) (xy 194.618578 -277.176157)
			(xy 194.575957 -277.15155) (xy 194.537836 -277.120425) (xy 194.505201 -277.083588) (xy 194.478898 -277.041992)
			(xy 194.459607 -276.996716) (xy 194.44783 -276.948932) (xy 194.44387 -276.899878) (xy 194.105022 -276.899878)
			(xy 194.104527 -276.924485) (xy 194.096632 -276.973062) (xy 194.081048 -277.019743) (xy 194.058177 -277.06332)
			(xy 194.028612 -277.102664) (xy 193.993119 -277.136756) (xy 193.952616 -277.164712) (xy 193.908154 -277.18581)
			(xy 193.860883 -277.199502) (xy 193.812028 -277.205434) (xy 193.762853 -277.203453) (xy 193.714634 -277.193609)
			(xy 193.668618 -277.176157) (xy 193.625997 -277.15155) (xy 193.587876 -277.120425) (xy 193.555241 -277.083588)
			(xy 193.528938 -277.041992) (xy 193.509647 -276.996716) (xy 193.49787 -276.948932) (xy 193.49391 -276.899878)
			(xy 193.155062 -276.899878) (xy 193.154567 -276.924485) (xy 193.146672 -276.973062) (xy 193.131088 -277.019743)
			(xy 193.108217 -277.06332) (xy 193.078652 -277.102664) (xy 193.043159 -277.136756) (xy 193.002656 -277.164712)
			(xy 192.958194 -277.18581) (xy 192.910923 -277.199502) (xy 192.862068 -277.205434) (xy 192.812893 -277.203453)
			(xy 192.764674 -277.193609) (xy 192.718658 -277.176157) (xy 192.676037 -277.15155) (xy 192.637916 -277.120425)
			(xy 192.605281 -277.083588) (xy 192.578978 -277.041992) (xy 192.559687 -276.996716) (xy 192.54791 -276.948932)
			(xy 192.54395 -276.899878) (xy 192.205102 -276.899878) (xy 192.204607 -276.924485) (xy 192.196712 -276.973062)
			(xy 192.181128 -277.019743) (xy 192.158257 -277.06332) (xy 192.128692 -277.102664) (xy 192.093199 -277.136756)
			(xy 192.052696 -277.164712) (xy 192.008234 -277.18581) (xy 191.960963 -277.199502) (xy 191.912108 -277.205434)
			(xy 191.862933 -277.203453) (xy 191.814714 -277.193609) (xy 191.768698 -277.176157) (xy 191.726077 -277.15155)
			(xy 191.687956 -277.120425) (xy 191.655321 -277.083588) (xy 191.629018 -277.041992) (xy 191.609727 -276.996716)
			(xy 191.59795 -276.948932) (xy 191.59399 -276.899878) (xy 191.255142 -276.899878) (xy 191.254647 -276.924485)
			(xy 191.246752 -276.973062) (xy 191.231168 -277.019743) (xy 191.208297 -277.06332) (xy 191.178732 -277.102664)
			(xy 191.143239 -277.136756) (xy 191.102736 -277.164712) (xy 191.058274 -277.18581) (xy 191.011003 -277.199502)
			(xy 190.962148 -277.205434) (xy 190.912973 -277.203453) (xy 190.864754 -277.193609) (xy 190.818738 -277.176157)
			(xy 190.776117 -277.15155) (xy 190.737996 -277.120425) (xy 190.705361 -277.083588) (xy 190.679058 -277.041992)
			(xy 190.659767 -276.996716) (xy 190.64799 -276.948932) (xy 190.64403 -276.899878) (xy 190.304928 -276.899878)
			(xy 190.304433 -276.924485) (xy 190.296538 -276.973062) (xy 190.280954 -277.019743) (xy 190.258083 -277.06332)
			(xy 190.228518 -277.102664) (xy 190.193025 -277.136756) (xy 190.152522 -277.164712) (xy 190.10806 -277.18581)
			(xy 190.060789 -277.199502) (xy 190.011934 -277.205434) (xy 189.962759 -277.203453) (xy 189.91454 -277.193609)
			(xy 189.868524 -277.176157) (xy 189.825903 -277.15155) (xy 189.787782 -277.120425) (xy 189.755147 -277.083588)
			(xy 189.728844 -277.041992) (xy 189.709553 -276.996716) (xy 189.697776 -276.948932) (xy 189.693816 -276.899878)
			(xy 189.355222 -276.899878) (xy 189.354727 -276.924485) (xy 189.346832 -276.973062) (xy 189.331248 -277.019743)
			(xy 189.308377 -277.06332) (xy 189.278812 -277.102664) (xy 189.243319 -277.136756) (xy 189.202816 -277.164712)
			(xy 189.158354 -277.18581) (xy 189.111083 -277.199502) (xy 189.062228 -277.205434) (xy 189.013053 -277.203453)
			(xy 188.964834 -277.193609) (xy 188.918818 -277.176157) (xy 188.876197 -277.15155) (xy 188.838076 -277.120425)
			(xy 188.805441 -277.083588) (xy 188.779138 -277.041992) (xy 188.759847 -276.996716) (xy 188.74807 -276.948932)
			(xy 188.74411 -276.899878) (xy 188.405262 -276.899878) (xy 188.404767 -276.924485) (xy 188.396872 -276.973062)
			(xy 188.381288 -277.019743) (xy 188.358417 -277.06332) (xy 188.328852 -277.102664) (xy 188.293359 -277.136756)
			(xy 188.252856 -277.164712) (xy 188.208394 -277.18581) (xy 188.161123 -277.199502) (xy 188.112268 -277.205434)
			(xy 188.063093 -277.203453) (xy 188.014874 -277.193609) (xy 187.968858 -277.176157) (xy 187.926237 -277.15155)
			(xy 187.888116 -277.120425) (xy 187.855481 -277.083588) (xy 187.829178 -277.041992) (xy 187.809887 -276.996716)
			(xy 187.79811 -276.948932) (xy 187.79415 -276.899878) (xy 187.455302 -276.899878) (xy 187.454807 -276.924485)
			(xy 187.446912 -276.973062) (xy 187.431328 -277.019743) (xy 187.408457 -277.06332) (xy 187.378892 -277.102664)
			(xy 187.343399 -277.136756) (xy 187.302896 -277.164712) (xy 187.258434 -277.18581) (xy 187.211163 -277.199502)
			(xy 187.162308 -277.205434) (xy 187.113133 -277.203453) (xy 187.064914 -277.193609) (xy 187.018898 -277.176157)
			(xy 186.976277 -277.15155) (xy 186.938156 -277.120425) (xy 186.905521 -277.083588) (xy 186.879218 -277.041992)
			(xy 186.859927 -276.996716) (xy 186.84815 -276.948932) (xy 186.84419 -276.899878) (xy 186.505342 -276.899878)
			(xy 186.504847 -276.924485) (xy 186.496952 -276.973062) (xy 186.481368 -277.019743) (xy 186.458497 -277.06332)
			(xy 186.428932 -277.102664) (xy 186.393439 -277.136756) (xy 186.352936 -277.164712) (xy 186.308474 -277.18581)
			(xy 186.261203 -277.199502) (xy 186.212348 -277.205434) (xy 186.163173 -277.203453) (xy 186.114954 -277.193609)
			(xy 186.068938 -277.176157) (xy 186.026317 -277.15155) (xy 185.988196 -277.120425) (xy 185.955561 -277.083588)
			(xy 185.929258 -277.041992) (xy 185.909967 -276.996716) (xy 185.89819 -276.948932) (xy 185.89423 -276.899878)
			(xy 185.555382 -276.899878) (xy 185.554887 -276.924485) (xy 185.546992 -276.973062) (xy 185.531408 -277.019743)
			(xy 185.508537 -277.06332) (xy 185.478972 -277.102664) (xy 185.443479 -277.136756) (xy 185.402976 -277.164712)
			(xy 185.358514 -277.18581) (xy 185.311243 -277.199502) (xy 185.262388 -277.205434) (xy 185.213213 -277.203453)
			(xy 185.164994 -277.193609) (xy 185.118978 -277.176157) (xy 185.076357 -277.15155) (xy 185.038236 -277.120425)
			(xy 185.005601 -277.083588) (xy 184.979298 -277.041992) (xy 184.960007 -276.996716) (xy 184.94823 -276.948932)
			(xy 184.94427 -276.899878) (xy 184.605168 -276.899878) (xy 184.604673 -276.924485) (xy 184.596778 -276.973062)
			(xy 184.581194 -277.019743) (xy 184.558323 -277.06332) (xy 184.528758 -277.102664) (xy 184.493265 -277.136756)
			(xy 184.452762 -277.164712) (xy 184.4083 -277.18581) (xy 184.361029 -277.199502) (xy 184.312174 -277.205434)
			(xy 184.262999 -277.203453) (xy 184.21478 -277.193609) (xy 184.168764 -277.176157) (xy 184.126143 -277.15155)
			(xy 184.088022 -277.120425) (xy 184.055387 -277.083588) (xy 184.029084 -277.041992) (xy 184.009793 -276.996716)
			(xy 183.998016 -276.948932) (xy 183.994056 -276.899878) (xy 183.655208 -276.899878) (xy 183.654713 -276.924485)
			(xy 183.646818 -276.973062) (xy 183.631234 -277.019743) (xy 183.608363 -277.06332) (xy 183.578798 -277.102664)
			(xy 183.543305 -277.136756) (xy 183.502802 -277.164712) (xy 183.45834 -277.18581) (xy 183.411069 -277.199502)
			(xy 183.362214 -277.205434) (xy 183.313039 -277.203453) (xy 183.26482 -277.193609) (xy 183.218804 -277.176157)
			(xy 183.176183 -277.15155) (xy 183.138062 -277.120425) (xy 183.105427 -277.083588) (xy 183.079124 -277.041992)
			(xy 183.059833 -276.996716) (xy 183.048056 -276.948932) (xy 183.044096 -276.899878) (xy 182.705248 -276.899878)
			(xy 182.704753 -276.924485) (xy 182.696858 -276.973062) (xy 182.681274 -277.019743) (xy 182.658403 -277.06332)
			(xy 182.628838 -277.102664) (xy 182.593345 -277.136756) (xy 182.552842 -277.164712) (xy 182.50838 -277.18581)
			(xy 182.461109 -277.199502) (xy 182.412254 -277.205434) (xy 182.363079 -277.203453) (xy 182.31486 -277.193609)
			(xy 182.268844 -277.176157) (xy 182.226223 -277.15155) (xy 182.188102 -277.120425) (xy 182.155467 -277.083588)
			(xy 182.129164 -277.041992) (xy 182.109873 -276.996716) (xy 182.098096 -276.948932) (xy 182.094136 -276.899878)
			(xy 181.755288 -276.899878) (xy 181.754793 -276.924485) (xy 181.746898 -276.973062) (xy 181.731314 -277.019743)
			(xy 181.708443 -277.06332) (xy 181.678878 -277.102664) (xy 181.643385 -277.136756) (xy 181.602882 -277.164712)
			(xy 181.55842 -277.18581) (xy 181.511149 -277.199502) (xy 181.462294 -277.205434) (xy 181.413119 -277.203453)
			(xy 181.3649 -277.193609) (xy 181.318884 -277.176157) (xy 181.276263 -277.15155) (xy 181.238142 -277.120425)
			(xy 181.205507 -277.083588) (xy 181.179204 -277.041992) (xy 181.159913 -276.996716) (xy 181.148136 -276.948932)
			(xy 181.144176 -276.899878) (xy 180.805328 -276.899878) (xy 180.804833 -276.924485) (xy 180.796938 -276.973062)
			(xy 180.781354 -277.019743) (xy 180.758483 -277.06332) (xy 180.728918 -277.102664) (xy 180.693425 -277.136756)
			(xy 180.652922 -277.164712) (xy 180.60846 -277.18581) (xy 180.561189 -277.199502) (xy 180.512334 -277.205434)
			(xy 180.463159 -277.203453) (xy 180.41494 -277.193609) (xy 180.368924 -277.176157) (xy 180.326303 -277.15155)
			(xy 180.288182 -277.120425) (xy 180.255547 -277.083588) (xy 180.229244 -277.041992) (xy 180.209953 -276.996716)
			(xy 180.198176 -276.948932) (xy 180.194216 -276.899878) (xy 179.855368 -276.899878) (xy 179.854873 -276.924485)
			(xy 179.846978 -276.973062) (xy 179.831394 -277.019743) (xy 179.808523 -277.06332) (xy 179.778958 -277.102664)
			(xy 179.743465 -277.136756) (xy 179.702962 -277.164712) (xy 179.6585 -277.18581) (xy 179.611229 -277.199502)
			(xy 179.562374 -277.205434) (xy 179.513199 -277.203453) (xy 179.46498 -277.193609) (xy 179.418964 -277.176157)
			(xy 179.376343 -277.15155) (xy 179.338222 -277.120425) (xy 179.305587 -277.083588) (xy 179.279284 -277.041992)
			(xy 179.259993 -276.996716) (xy 179.248216 -276.948932) (xy 179.244256 -276.899878) (xy 178.905154 -276.899878)
			(xy 178.904659 -276.924485) (xy 178.896764 -276.973062) (xy 178.88118 -277.019743) (xy 178.858309 -277.06332)
			(xy 178.828744 -277.102664) (xy 178.793251 -277.136756) (xy 178.752748 -277.164712) (xy 178.708286 -277.18581)
			(xy 178.661015 -277.199502) (xy 178.61216 -277.205434) (xy 178.562985 -277.203453) (xy 178.514766 -277.193609)
			(xy 178.46875 -277.176157) (xy 178.426129 -277.15155) (xy 178.388008 -277.120425) (xy 178.355373 -277.083588)
			(xy 178.32907 -277.041992) (xy 178.309779 -276.996716) (xy 178.298002 -276.948932) (xy 178.294042 -276.899878)
			(xy 177.955194 -276.899878) (xy 177.954699 -276.924485) (xy 177.946804 -276.973062) (xy 177.93122 -277.019743)
			(xy 177.908349 -277.06332) (xy 177.878784 -277.102664) (xy 177.843291 -277.136756) (xy 177.802788 -277.164712)
			(xy 177.758326 -277.18581) (xy 177.711055 -277.199502) (xy 177.6622 -277.205434) (xy 177.613025 -277.203453)
			(xy 177.564806 -277.193609) (xy 177.51879 -277.176157) (xy 177.476169 -277.15155) (xy 177.438048 -277.120425)
			(xy 177.405413 -277.083588) (xy 177.37911 -277.041992) (xy 177.359819 -276.996716) (xy 177.348042 -276.948932)
			(xy 177.344082 -276.899878) (xy 177.005234 -276.899878) (xy 177.004739 -276.924485) (xy 176.996844 -276.973062)
			(xy 176.98126 -277.019743) (xy 176.958389 -277.06332) (xy 176.928824 -277.102664) (xy 176.893331 -277.136756)
			(xy 176.852828 -277.164712) (xy 176.808366 -277.18581) (xy 176.761095 -277.199502) (xy 176.71224 -277.205434)
			(xy 176.663065 -277.203453) (xy 176.614846 -277.193609) (xy 176.56883 -277.176157) (xy 176.526209 -277.15155)
			(xy 176.488088 -277.120425) (xy 176.455453 -277.083588) (xy 176.42915 -277.041992) (xy 176.409859 -276.996716)
			(xy 176.398082 -276.948932) (xy 176.394122 -276.899878) (xy 176.055274 -276.899878) (xy 176.054779 -276.924485)
			(xy 176.046884 -276.973062) (xy 176.0313 -277.019743) (xy 176.008429 -277.06332) (xy 175.978864 -277.102664)
			(xy 175.943371 -277.136756) (xy 175.902868 -277.164712) (xy 175.858406 -277.18581) (xy 175.811135 -277.199502)
			(xy 175.76228 -277.205434) (xy 175.713105 -277.203453) (xy 175.664886 -277.193609) (xy 175.61887 -277.176157)
			(xy 175.576249 -277.15155) (xy 175.538128 -277.120425) (xy 175.505493 -277.083588) (xy 175.47919 -277.041992)
			(xy 175.459899 -276.996716) (xy 175.448122 -276.948932) (xy 175.444162 -276.899878) (xy 175.105314 -276.899878)
			(xy 175.104819 -276.924485) (xy 175.096924 -276.973062) (xy 175.08134 -277.019743) (xy 175.058469 -277.06332)
			(xy 175.028904 -277.102664) (xy 174.993411 -277.136756) (xy 174.952908 -277.164712) (xy 174.908446 -277.18581)
			(xy 174.861175 -277.199502) (xy 174.81232 -277.205434) (xy 174.763145 -277.203453) (xy 174.714926 -277.193609)
			(xy 174.66891 -277.176157) (xy 174.626289 -277.15155) (xy 174.588168 -277.120425) (xy 174.555533 -277.083588)
			(xy 174.52923 -277.041992) (xy 174.509939 -276.996716) (xy 174.498162 -276.948932) (xy 174.494202 -276.899878)
			(xy 174.155354 -276.899878) (xy 174.154859 -276.924485) (xy 174.146964 -276.973062) (xy 174.13138 -277.019743)
			(xy 174.108509 -277.06332) (xy 174.078944 -277.102664) (xy 174.043451 -277.136756) (xy 174.002948 -277.164712)
			(xy 173.958486 -277.18581) (xy 173.911215 -277.199502) (xy 173.86236 -277.205434) (xy 173.813185 -277.203453)
			(xy 173.764966 -277.193609) (xy 173.71895 -277.176157) (xy 173.676329 -277.15155) (xy 173.638208 -277.120425)
			(xy 173.605573 -277.083588) (xy 173.57927 -277.041992) (xy 173.559979 -276.996716) (xy 173.548202 -276.948932)
			(xy 173.544242 -276.899878) (xy 173.205394 -276.899878) (xy 173.204899 -276.924485) (xy 173.197004 -276.973062)
			(xy 173.18142 -277.019743) (xy 173.158549 -277.06332) (xy 173.128984 -277.102664) (xy 173.093491 -277.136756)
			(xy 173.052988 -277.164712) (xy 173.008526 -277.18581) (xy 172.961255 -277.199502) (xy 172.9124 -277.205434)
			(xy 172.863225 -277.203453) (xy 172.815006 -277.193609) (xy 172.76899 -277.176157) (xy 172.726369 -277.15155)
			(xy 172.688248 -277.120425) (xy 172.655613 -277.083588) (xy 172.62931 -277.041992) (xy 172.610019 -276.996716)
			(xy 172.598242 -276.948932) (xy 172.594282 -276.899878) (xy 172.25518 -276.899878) (xy 172.254685 -276.924485)
			(xy 172.24679 -276.973062) (xy 172.231206 -277.019743) (xy 172.208335 -277.06332) (xy 172.17877 -277.102664)
			(xy 172.143277 -277.136756) (xy 172.102774 -277.164712) (xy 172.058312 -277.18581) (xy 172.011041 -277.199502)
			(xy 171.962186 -277.205434) (xy 171.913011 -277.203453) (xy 171.864792 -277.193609) (xy 171.818776 -277.176157)
			(xy 171.776155 -277.15155) (xy 171.738034 -277.120425) (xy 171.705399 -277.083588) (xy 171.679096 -277.041992)
			(xy 171.659805 -276.996716) (xy 171.648028 -276.948932) (xy 171.644068 -276.899878) (xy 171.30522 -276.899878)
			(xy 171.304725 -276.924485) (xy 171.29683 -276.973062) (xy 171.281246 -277.019743) (xy 171.258375 -277.06332)
			(xy 171.22881 -277.102664) (xy 171.193317 -277.136756) (xy 171.152814 -277.164712) (xy 171.108352 -277.18581)
			(xy 171.061081 -277.199502) (xy 171.012226 -277.205434) (xy 170.963051 -277.203453) (xy 170.914832 -277.193609)
			(xy 170.868816 -277.176157) (xy 170.826195 -277.15155) (xy 170.788074 -277.120425) (xy 170.755439 -277.083588)
			(xy 170.729136 -277.041992) (xy 170.709845 -276.996716) (xy 170.698068 -276.948932) (xy 170.694108 -276.899878)
			(xy 170.35526 -276.899878) (xy 170.354765 -276.924485) (xy 170.34687 -276.973062) (xy 170.331286 -277.019743)
			(xy 170.308415 -277.06332) (xy 170.27885 -277.102664) (xy 170.243357 -277.136756) (xy 170.202854 -277.164712)
			(xy 170.158392 -277.18581) (xy 170.111121 -277.199502) (xy 170.062266 -277.205434) (xy 170.013091 -277.203453)
			(xy 169.964872 -277.193609) (xy 169.918856 -277.176157) (xy 169.876235 -277.15155) (xy 169.838114 -277.120425)
			(xy 169.805479 -277.083588) (xy 169.779176 -277.041992) (xy 169.759885 -276.996716) (xy 169.748108 -276.948932)
			(xy 169.744148 -276.899878) (xy 169.4053 -276.899878) (xy 169.404805 -276.924485) (xy 169.39691 -276.973062)
			(xy 169.381326 -277.019743) (xy 169.358455 -277.06332) (xy 169.32889 -277.102664) (xy 169.293397 -277.136756)
			(xy 169.252894 -277.164712) (xy 169.208432 -277.18581) (xy 169.161161 -277.199502) (xy 169.112306 -277.205434)
			(xy 169.063131 -277.203453) (xy 169.014912 -277.193609) (xy 168.968896 -277.176157) (xy 168.926275 -277.15155)
			(xy 168.888154 -277.120425) (xy 168.855519 -277.083588) (xy 168.829216 -277.041992) (xy 168.809925 -276.996716)
			(xy 168.798148 -276.948932) (xy 168.794188 -276.899878) (xy 168.45534 -276.899878) (xy 168.454845 -276.924485)
			(xy 168.44695 -276.973062) (xy 168.431366 -277.019743) (xy 168.408495 -277.06332) (xy 168.37893 -277.102664)
			(xy 168.343437 -277.136756) (xy 168.302934 -277.164712) (xy 168.258472 -277.18581) (xy 168.211201 -277.199502)
			(xy 168.162346 -277.205434) (xy 168.113171 -277.203453) (xy 168.064952 -277.193609) (xy 168.018936 -277.176157)
			(xy 167.976315 -277.15155) (xy 167.938194 -277.120425) (xy 167.905559 -277.083588) (xy 167.879256 -277.041992)
			(xy 167.859965 -276.996716) (xy 167.848188 -276.948932) (xy 167.844228 -276.899878) (xy 167.50538 -276.899878)
			(xy 167.504885 -276.924485) (xy 167.49699 -276.973062) (xy 167.481406 -277.019743) (xy 167.458535 -277.06332)
			(xy 167.42897 -277.102664) (xy 167.393477 -277.136756) (xy 167.352974 -277.164712) (xy 167.308512 -277.18581)
			(xy 167.261241 -277.199502) (xy 167.212386 -277.205434) (xy 167.163211 -277.203453) (xy 167.114992 -277.193609)
			(xy 167.068976 -277.176157) (xy 167.026355 -277.15155) (xy 166.988234 -277.120425) (xy 166.955599 -277.083588)
			(xy 166.929296 -277.041992) (xy 166.910005 -276.996716) (xy 166.898228 -276.948932) (xy 166.894268 -276.899878)
			(xy 166.555166 -276.899878) (xy 166.554671 -276.924485) (xy 166.546776 -276.973062) (xy 166.531192 -277.019743)
			(xy 166.508321 -277.06332) (xy 166.478756 -277.102664) (xy 166.443263 -277.136756) (xy 166.40276 -277.164712)
			(xy 166.358298 -277.18581) (xy 166.311027 -277.199502) (xy 166.262172 -277.205434) (xy 166.212997 -277.203453)
			(xy 166.164778 -277.193609) (xy 166.118762 -277.176157) (xy 166.076141 -277.15155) (xy 166.03802 -277.120425)
			(xy 166.005385 -277.083588) (xy 165.979082 -277.041992) (xy 165.959791 -276.996716) (xy 165.948014 -276.948932)
			(xy 165.944054 -276.899878) (xy 165.605206 -276.899878) (xy 165.604711 -276.924485) (xy 165.596816 -276.973062)
			(xy 165.581232 -277.019743) (xy 165.558361 -277.06332) (xy 165.528796 -277.102664) (xy 165.493303 -277.136756)
			(xy 165.4528 -277.164712) (xy 165.408338 -277.18581) (xy 165.361067 -277.199502) (xy 165.312212 -277.205434)
			(xy 165.263037 -277.203453) (xy 165.214818 -277.193609) (xy 165.168802 -277.176157) (xy 165.126181 -277.15155)
			(xy 165.08806 -277.120425) (xy 165.055425 -277.083588) (xy 165.029122 -277.041992) (xy 165.009831 -276.996716)
			(xy 164.998054 -276.948932) (xy 164.994094 -276.899878) (xy 164.655246 -276.899878) (xy 164.654751 -276.924485)
			(xy 164.646856 -276.973062) (xy 164.631272 -277.019743) (xy 164.608401 -277.06332) (xy 164.578836 -277.102664)
			(xy 164.543343 -277.136756) (xy 164.50284 -277.164712) (xy 164.458378 -277.18581) (xy 164.411107 -277.199502)
			(xy 164.362252 -277.205434) (xy 164.313077 -277.203453) (xy 164.264858 -277.193609) (xy 164.218842 -277.176157)
			(xy 164.176221 -277.15155) (xy 164.1381 -277.120425) (xy 164.105465 -277.083588) (xy 164.079162 -277.041992)
			(xy 164.059871 -276.996716) (xy 164.048094 -276.948932) (xy 164.044134 -276.899878) (xy 163.705286 -276.899878)
			(xy 163.704791 -276.924485) (xy 163.696896 -276.973062) (xy 163.681312 -277.019743) (xy 163.658441 -277.06332)
			(xy 163.628876 -277.102664) (xy 163.593383 -277.136756) (xy 163.55288 -277.164712) (xy 163.508418 -277.18581)
			(xy 163.461147 -277.199502) (xy 163.412292 -277.205434) (xy 163.363117 -277.203453) (xy 163.314898 -277.193609)
			(xy 163.268882 -277.176157) (xy 163.226261 -277.15155) (xy 163.18814 -277.120425) (xy 163.155505 -277.083588)
			(xy 163.129202 -277.041992) (xy 163.109911 -276.996716) (xy 163.098134 -276.948932) (xy 163.094174 -276.899878)
			(xy 162.755326 -276.899878) (xy 162.754831 -276.924485) (xy 162.746936 -276.973062) (xy 162.731352 -277.019743)
			(xy 162.708481 -277.06332) (xy 162.678916 -277.102664) (xy 162.643423 -277.136756) (xy 162.60292 -277.164712)
			(xy 162.558458 -277.18581) (xy 162.511187 -277.199502) (xy 162.462332 -277.205434) (xy 162.413157 -277.203453)
			(xy 162.364938 -277.193609) (xy 162.318922 -277.176157) (xy 162.276301 -277.15155) (xy 162.23818 -277.120425)
			(xy 162.205545 -277.083588) (xy 162.179242 -277.041992) (xy 162.159951 -276.996716) (xy 162.148174 -276.948932)
			(xy 162.144214 -276.899878) (xy 161.805366 -276.899878) (xy 161.804871 -276.924485) (xy 161.796976 -276.973062)
			(xy 161.781392 -277.019743) (xy 161.758521 -277.06332) (xy 161.728956 -277.102664) (xy 161.693463 -277.136756)
			(xy 161.65296 -277.164712) (xy 161.608498 -277.18581) (xy 161.561227 -277.199502) (xy 161.512372 -277.205434)
			(xy 161.463197 -277.203453) (xy 161.414978 -277.193609) (xy 161.368962 -277.176157) (xy 161.326341 -277.15155)
			(xy 161.28822 -277.120425) (xy 161.255585 -277.083588) (xy 161.229282 -277.041992) (xy 161.209991 -276.996716)
			(xy 161.198214 -276.948932) (xy 161.194254 -276.899878) (xy 160.855152 -276.899878) (xy 160.854657 -276.924485)
			(xy 160.846762 -276.973062) (xy 160.831178 -277.019743) (xy 160.808307 -277.06332) (xy 160.778742 -277.102664)
			(xy 160.743249 -277.136756) (xy 160.702746 -277.164712) (xy 160.658284 -277.18581) (xy 160.611013 -277.199502)
			(xy 160.562158 -277.205434) (xy 160.512983 -277.203453) (xy 160.464764 -277.193609) (xy 160.418748 -277.176157)
			(xy 160.376127 -277.15155) (xy 160.338006 -277.120425) (xy 160.305371 -277.083588) (xy 160.279068 -277.041992)
			(xy 160.259777 -276.996716) (xy 160.248 -276.948932) (xy 160.24404 -276.899878) (xy 159.905736 -276.899878)
			(xy 159.905738 -276.8999) (xy 159.901566 -276.950241) (xy 159.889166 -276.999209) (xy 159.868874 -277.045467)
			(xy 159.841245 -277.087755) (xy 159.807032 -277.124918) (xy 159.767169 -277.155943) (xy 159.722743 -277.179983)
			(xy 159.674966 -277.196383) (xy 159.625141 -277.204695) (xy 159.599884 -277.205186) (xy 159.585701 -277.205012)
			(xy 159.557461 -277.202338) (xy 159.543496 -277.199852) (xy 159.53105 -277.197566) (xy 159.507428 -277.204932)
			(xy 159.429958 -277.282402) (xy 159.422592 -277.306024) (xy 159.424878 -277.31847) (xy 159.42736 -277.332435)
			(xy 159.430028 -277.360675) (xy 159.430212 -277.374858) (xy 159.430029 -277.389041) (xy 159.427361 -277.417281)
			(xy 159.424878 -277.431246) (xy 159.422592 -277.443692) (xy 159.429958 -277.467314) (xy 159.507428 -277.544784)
			(xy 159.53105 -277.55215) (xy 159.543496 -277.549864) (xy 159.557463 -277.547393) (xy 159.585702 -277.544717)
			(xy 159.599884 -277.54453) (xy 159.625146 -277.544946) (xy 159.67498 -277.553259) (xy 159.722767 -277.569662)
			(xy 159.767202 -277.593707) (xy 159.807073 -277.624738) (xy 159.841292 -277.661908) (xy 159.868927 -277.704204)
			(xy 159.889223 -277.750472) (xy 159.901626 -277.799449) (xy 159.905798 -277.8498) (xy 159.903665 -277.875546)
			(xy 160.223196 -277.875546) (xy 160.223196 -277.82413) (xy 160.231239 -277.773348) (xy 160.247127 -277.724449)
			(xy 160.27047 -277.678637) (xy 160.300691 -277.637041) (xy 160.337047 -277.600685) (xy 160.378643 -277.570464)
			(xy 160.424455 -277.547121) (xy 160.473354 -277.531233) (xy 160.524136 -277.52319) (xy 160.575552 -277.52319)
			(xy 160.626334 -277.531233) (xy 160.675233 -277.547121) (xy 160.721045 -277.570464) (xy 160.762641 -277.600685)
			(xy 160.798997 -277.637041) (xy 160.829218 -277.678637) (xy 160.852561 -277.724449) (xy 160.868449 -277.773348)
			(xy 160.876492 -277.82413) (xy 160.876996 -277.849838) (xy 161.194254 -277.849838) (xy 161.198214 -277.800784)
			(xy 161.209991 -277.753) (xy 161.229282 -277.707724) (xy 161.255585 -277.666128) (xy 161.28822 -277.629291)
			(xy 161.326341 -277.598166) (xy 161.368962 -277.573559) (xy 161.414978 -277.556107) (xy 161.463197 -277.546263)
			(xy 161.512372 -277.544282) (xy 161.561227 -277.550214) (xy 161.608498 -277.563906) (xy 161.65296 -277.585004)
			(xy 161.693463 -277.61296) (xy 161.728956 -277.647052) (xy 161.758521 -277.686396) (xy 161.781392 -277.729973)
			(xy 161.796976 -277.776654) (xy 161.804871 -277.825231) (xy 161.805366 -277.849838) (xy 161.804871 -277.874445)
			(xy 161.804692 -277.875546) (xy 162.12337 -277.875546) (xy 162.12337 -277.82413) (xy 162.131413 -277.773348)
			(xy 162.147301 -277.724449) (xy 162.170644 -277.678637) (xy 162.200865 -277.637041) (xy 162.237221 -277.600685)
			(xy 162.278817 -277.570464) (xy 162.324629 -277.547121) (xy 162.373528 -277.531233) (xy 162.42431 -277.52319)
			(xy 162.475726 -277.52319) (xy 162.526508 -277.531233) (xy 162.575407 -277.547121) (xy 162.621219 -277.570464)
			(xy 162.662815 -277.600685) (xy 162.699171 -277.637041) (xy 162.729392 -277.678637) (xy 162.752735 -277.724449)
			(xy 162.768623 -277.773348) (xy 162.776666 -277.82413) (xy 162.77717 -277.849838) (xy 163.094174 -277.849838)
			(xy 163.098134 -277.800784) (xy 163.109911 -277.753) (xy 163.129202 -277.707724) (xy 163.155505 -277.666128)
			(xy 163.18814 -277.629291) (xy 163.226261 -277.598166) (xy 163.268882 -277.573559) (xy 163.314898 -277.556107)
			(xy 163.363117 -277.546263) (xy 163.412292 -277.544282) (xy 163.461147 -277.550214) (xy 163.508418 -277.563906)
			(xy 163.55288 -277.585004) (xy 163.593383 -277.61296) (xy 163.628876 -277.647052) (xy 163.658441 -277.686396)
			(xy 163.681312 -277.729973) (xy 163.696896 -277.776654) (xy 163.704791 -277.825231) (xy 163.705286 -277.849838)
			(xy 163.704791 -277.874445) (xy 163.704612 -277.875546) (xy 164.02329 -277.875546) (xy 164.02329 -277.82413)
			(xy 164.031333 -277.773348) (xy 164.047221 -277.724449) (xy 164.070564 -277.678637) (xy 164.100785 -277.637041)
			(xy 164.137141 -277.600685) (xy 164.178737 -277.570464) (xy 164.224549 -277.547121) (xy 164.273448 -277.531233)
			(xy 164.32423 -277.52319) (xy 164.375646 -277.52319) (xy 164.426428 -277.531233) (xy 164.475327 -277.547121)
			(xy 164.521139 -277.570464) (xy 164.562735 -277.600685) (xy 164.599091 -277.637041) (xy 164.629312 -277.678637)
			(xy 164.652655 -277.724449) (xy 164.668543 -277.773348) (xy 164.676586 -277.82413) (xy 164.67709 -277.849838)
			(xy 164.994094 -277.849838) (xy 164.998054 -277.800784) (xy 165.009831 -277.753) (xy 165.029122 -277.707724)
			(xy 165.055425 -277.666128) (xy 165.08806 -277.629291) (xy 165.126181 -277.598166) (xy 165.168802 -277.573559)
			(xy 165.214818 -277.556107) (xy 165.263037 -277.546263) (xy 165.312212 -277.544282) (xy 165.361067 -277.550214)
			(xy 165.408338 -277.563906) (xy 165.4528 -277.585004) (xy 165.493303 -277.61296) (xy 165.528796 -277.647052)
			(xy 165.558361 -277.686396) (xy 165.581232 -277.729973) (xy 165.596816 -277.776654) (xy 165.604711 -277.825231)
			(xy 165.605206 -277.849838) (xy 165.604711 -277.874445) (xy 165.604532 -277.875546) (xy 165.92321 -277.875546)
			(xy 165.92321 -277.82413) (xy 165.931253 -277.773348) (xy 165.947141 -277.724449) (xy 165.970484 -277.678637)
			(xy 166.000705 -277.637041) (xy 166.037061 -277.600685) (xy 166.078657 -277.570464) (xy 166.124469 -277.547121)
			(xy 166.173368 -277.531233) (xy 166.22415 -277.52319) (xy 166.275566 -277.52319) (xy 166.326348 -277.531233)
			(xy 166.375247 -277.547121) (xy 166.421059 -277.570464) (xy 166.462655 -277.600685) (xy 166.499011 -277.637041)
			(xy 166.529232 -277.678637) (xy 166.552575 -277.724449) (xy 166.568463 -277.773348) (xy 166.576506 -277.82413)
			(xy 166.57701 -277.849838) (xy 166.894268 -277.849838) (xy 166.898228 -277.800784) (xy 166.910005 -277.753)
			(xy 166.929296 -277.707724) (xy 166.955599 -277.666128) (xy 166.988234 -277.629291) (xy 167.026355 -277.598166)
			(xy 167.068976 -277.573559) (xy 167.114992 -277.556107) (xy 167.163211 -277.546263) (xy 167.212386 -277.544282)
			(xy 167.261241 -277.550214) (xy 167.308512 -277.563906) (xy 167.352974 -277.585004) (xy 167.393477 -277.61296)
			(xy 167.42897 -277.647052) (xy 167.458535 -277.686396) (xy 167.481406 -277.729973) (xy 167.49699 -277.776654)
			(xy 167.504885 -277.825231) (xy 167.50538 -277.849838) (xy 167.504885 -277.874445) (xy 167.504706 -277.875546)
			(xy 167.823384 -277.875546) (xy 167.823384 -277.82413) (xy 167.831427 -277.773348) (xy 167.847315 -277.724449)
			(xy 167.870658 -277.678637) (xy 167.900879 -277.637041) (xy 167.937235 -277.600685) (xy 167.978831 -277.570464)
			(xy 168.024643 -277.547121) (xy 168.073542 -277.531233) (xy 168.124324 -277.52319) (xy 168.17574 -277.52319)
			(xy 168.226522 -277.531233) (xy 168.275421 -277.547121) (xy 168.321233 -277.570464) (xy 168.362829 -277.600685)
			(xy 168.399185 -277.637041) (xy 168.429406 -277.678637) (xy 168.452749 -277.724449) (xy 168.468637 -277.773348)
			(xy 168.47668 -277.82413) (xy 168.477184 -277.849838) (xy 168.794188 -277.849838) (xy 168.798148 -277.800784)
			(xy 168.809925 -277.753) (xy 168.829216 -277.707724) (xy 168.855519 -277.666128) (xy 168.888154 -277.629291)
			(xy 168.926275 -277.598166) (xy 168.968896 -277.573559) (xy 169.014912 -277.556107) (xy 169.063131 -277.546263)
			(xy 169.112306 -277.544282) (xy 169.161161 -277.550214) (xy 169.208432 -277.563906) (xy 169.252894 -277.585004)
			(xy 169.293397 -277.61296) (xy 169.32889 -277.647052) (xy 169.358455 -277.686396) (xy 169.381326 -277.729973)
			(xy 169.39691 -277.776654) (xy 169.404805 -277.825231) (xy 169.4053 -277.849838) (xy 169.404805 -277.874445)
			(xy 169.404626 -277.875546) (xy 169.723304 -277.875546) (xy 169.723304 -277.82413) (xy 169.731347 -277.773348)
			(xy 169.747235 -277.724449) (xy 169.770578 -277.678637) (xy 169.800799 -277.637041) (xy 169.837155 -277.600685)
			(xy 169.878751 -277.570464) (xy 169.924563 -277.547121) (xy 169.973462 -277.531233) (xy 170.024244 -277.52319)
			(xy 170.07566 -277.52319) (xy 170.126442 -277.531233) (xy 170.175341 -277.547121) (xy 170.221153 -277.570464)
			(xy 170.262749 -277.600685) (xy 170.299105 -277.637041) (xy 170.329326 -277.678637) (xy 170.352669 -277.724449)
			(xy 170.368557 -277.773348) (xy 170.3766 -277.82413) (xy 170.377104 -277.849838) (xy 170.694108 -277.849838)
			(xy 170.698068 -277.800784) (xy 170.709845 -277.753) (xy 170.729136 -277.707724) (xy 170.755439 -277.666128)
			(xy 170.788074 -277.629291) (xy 170.826195 -277.598166) (xy 170.868816 -277.573559) (xy 170.914832 -277.556107)
			(xy 170.963051 -277.546263) (xy 171.012226 -277.544282) (xy 171.061081 -277.550214) (xy 171.108352 -277.563906)
			(xy 171.152814 -277.585004) (xy 171.193317 -277.61296) (xy 171.22881 -277.647052) (xy 171.258375 -277.686396)
			(xy 171.281246 -277.729973) (xy 171.29683 -277.776654) (xy 171.304725 -277.825231) (xy 171.30522 -277.849838)
			(xy 171.304725 -277.874445) (xy 171.304546 -277.875546) (xy 171.623224 -277.875546) (xy 171.623224 -277.82413)
			(xy 171.631267 -277.773348) (xy 171.647155 -277.724449) (xy 171.670498 -277.678637) (xy 171.700719 -277.637041)
			(xy 171.737075 -277.600685) (xy 171.778671 -277.570464) (xy 171.824483 -277.547121) (xy 171.873382 -277.531233)
			(xy 171.924164 -277.52319) (xy 171.97558 -277.52319) (xy 172.026362 -277.531233) (xy 172.075261 -277.547121)
			(xy 172.121073 -277.570464) (xy 172.162669 -277.600685) (xy 172.199025 -277.637041) (xy 172.229246 -277.678637)
			(xy 172.252589 -277.724449) (xy 172.268477 -277.773348) (xy 172.27652 -277.82413) (xy 172.277024 -277.849838)
			(xy 172.594282 -277.849838) (xy 172.598242 -277.800784) (xy 172.610019 -277.753) (xy 172.62931 -277.707724)
			(xy 172.655613 -277.666128) (xy 172.688248 -277.629291) (xy 172.726369 -277.598166) (xy 172.76899 -277.573559)
			(xy 172.815006 -277.556107) (xy 172.863225 -277.546263) (xy 172.9124 -277.544282) (xy 172.961255 -277.550214)
			(xy 173.008526 -277.563906) (xy 173.052988 -277.585004) (xy 173.093491 -277.61296) (xy 173.128984 -277.647052)
			(xy 173.158549 -277.686396) (xy 173.18142 -277.729973) (xy 173.197004 -277.776654) (xy 173.204899 -277.825231)
			(xy 173.205394 -277.849838) (xy 173.204899 -277.874445) (xy 173.20472 -277.875546) (xy 173.523398 -277.875546)
			(xy 173.523398 -277.82413) (xy 173.531441 -277.773348) (xy 173.547329 -277.724449) (xy 173.570672 -277.678637)
			(xy 173.600893 -277.637041) (xy 173.637249 -277.600685) (xy 173.678845 -277.570464) (xy 173.724657 -277.547121)
			(xy 173.773556 -277.531233) (xy 173.824338 -277.52319) (xy 173.875754 -277.52319) (xy 173.926536 -277.531233)
			(xy 173.975435 -277.547121) (xy 174.021247 -277.570464) (xy 174.062843 -277.600685) (xy 174.099199 -277.637041)
			(xy 174.12942 -277.678637) (xy 174.152763 -277.724449) (xy 174.168651 -277.773348) (xy 174.176694 -277.82413)
			(xy 174.177198 -277.849838) (xy 174.494202 -277.849838) (xy 174.498162 -277.800784) (xy 174.509939 -277.753)
			(xy 174.52923 -277.707724) (xy 174.555533 -277.666128) (xy 174.588168 -277.629291) (xy 174.626289 -277.598166)
			(xy 174.66891 -277.573559) (xy 174.714926 -277.556107) (xy 174.763145 -277.546263) (xy 174.81232 -277.544282)
			(xy 174.861175 -277.550214) (xy 174.908446 -277.563906) (xy 174.952908 -277.585004) (xy 174.993411 -277.61296)
			(xy 175.028904 -277.647052) (xy 175.058469 -277.686396) (xy 175.08134 -277.729973) (xy 175.096924 -277.776654)
			(xy 175.104819 -277.825231) (xy 175.105314 -277.849838) (xy 175.104819 -277.874445) (xy 175.10464 -277.875546)
			(xy 175.423064 -277.875546) (xy 175.423064 -277.82413) (xy 175.431107 -277.773348) (xy 175.446995 -277.724449)
			(xy 175.470338 -277.678637) (xy 175.500559 -277.637041) (xy 175.536915 -277.600685) (xy 175.578511 -277.570464)
			(xy 175.624323 -277.547121) (xy 175.673222 -277.531233) (xy 175.724004 -277.52319) (xy 175.77542 -277.52319)
			(xy 175.826202 -277.531233) (xy 175.875101 -277.547121) (xy 175.920913 -277.570464) (xy 175.962509 -277.600685)
			(xy 175.998865 -277.637041) (xy 176.029086 -277.678637) (xy 176.052429 -277.724449) (xy 176.068317 -277.773348)
			(xy 176.07636 -277.82413) (xy 176.076864 -277.849838) (xy 176.394122 -277.849838) (xy 176.398082 -277.800784)
			(xy 176.409859 -277.753) (xy 176.42915 -277.707724) (xy 176.455453 -277.666128) (xy 176.488088 -277.629291)
			(xy 176.526209 -277.598166) (xy 176.56883 -277.573559) (xy 176.614846 -277.556107) (xy 176.663065 -277.546263)
			(xy 176.71224 -277.544282) (xy 176.761095 -277.550214) (xy 176.808366 -277.563906) (xy 176.852828 -277.585004)
			(xy 176.893331 -277.61296) (xy 176.928824 -277.647052) (xy 176.958389 -277.686396) (xy 176.98126 -277.729973)
			(xy 176.996844 -277.776654) (xy 177.004739 -277.825231) (xy 177.005234 -277.849838) (xy 177.004739 -277.874445)
			(xy 177.00456 -277.875546) (xy 177.322984 -277.875546) (xy 177.322984 -277.82413) (xy 177.331027 -277.773348)
			(xy 177.346915 -277.724449) (xy 177.370258 -277.678637) (xy 177.400479 -277.637041) (xy 177.436835 -277.600685)
			(xy 177.478431 -277.570464) (xy 177.524243 -277.547121) (xy 177.573142 -277.531233) (xy 177.623924 -277.52319)
			(xy 177.67534 -277.52319) (xy 177.726122 -277.531233) (xy 177.775021 -277.547121) (xy 177.820833 -277.570464)
			(xy 177.862429 -277.600685) (xy 177.898785 -277.637041) (xy 177.929006 -277.678637) (xy 177.952349 -277.724449)
			(xy 177.968237 -277.773348) (xy 177.97628 -277.82413) (xy 177.976784 -277.849838) (xy 178.294042 -277.849838)
			(xy 178.298002 -277.800784) (xy 178.309779 -277.753) (xy 178.32907 -277.707724) (xy 178.355373 -277.666128)
			(xy 178.388008 -277.629291) (xy 178.426129 -277.598166) (xy 178.46875 -277.573559) (xy 178.514766 -277.556107)
			(xy 178.562985 -277.546263) (xy 178.61216 -277.544282) (xy 178.661015 -277.550214) (xy 178.708286 -277.563906)
			(xy 178.752748 -277.585004) (xy 178.793251 -277.61296) (xy 178.828744 -277.647052) (xy 178.858309 -277.686396)
			(xy 178.88118 -277.729973) (xy 178.896764 -277.776654) (xy 178.904659 -277.825231) (xy 178.905154 -277.849838)
			(xy 178.904659 -277.874445) (xy 178.90448 -277.875546) (xy 179.223158 -277.875546) (xy 179.223158 -277.82413)
			(xy 179.231201 -277.773348) (xy 179.247089 -277.724449) (xy 179.270432 -277.678637) (xy 179.300653 -277.637041)
			(xy 179.337009 -277.600685) (xy 179.378605 -277.570464) (xy 179.424417 -277.547121) (xy 179.473316 -277.531233)
			(xy 179.524098 -277.52319) (xy 179.575514 -277.52319) (xy 179.626296 -277.531233) (xy 179.675195 -277.547121)
			(xy 179.721007 -277.570464) (xy 179.762603 -277.600685) (xy 179.798959 -277.637041) (xy 179.82918 -277.678637)
			(xy 179.852523 -277.724449) (xy 179.868411 -277.773348) (xy 179.876454 -277.82413) (xy 179.876958 -277.849838)
			(xy 180.194216 -277.849838) (xy 180.198176 -277.800784) (xy 180.209953 -277.753) (xy 180.229244 -277.707724)
			(xy 180.255547 -277.666128) (xy 180.288182 -277.629291) (xy 180.326303 -277.598166) (xy 180.368924 -277.573559)
			(xy 180.41494 -277.556107) (xy 180.463159 -277.546263) (xy 180.512334 -277.544282) (xy 180.561189 -277.550214)
			(xy 180.60846 -277.563906) (xy 180.652922 -277.585004) (xy 180.693425 -277.61296) (xy 180.728918 -277.647052)
			(xy 180.758483 -277.686396) (xy 180.781354 -277.729973) (xy 180.796938 -277.776654) (xy 180.804833 -277.825231)
			(xy 180.805328 -277.849838) (xy 180.804833 -277.874445) (xy 180.804654 -277.875546) (xy 181.123078 -277.875546)
			(xy 181.123078 -277.82413) (xy 181.131121 -277.773348) (xy 181.147009 -277.724449) (xy 181.170352 -277.678637)
			(xy 181.200573 -277.637041) (xy 181.236929 -277.600685) (xy 181.278525 -277.570464) (xy 181.324337 -277.547121)
			(xy 181.373236 -277.531233) (xy 181.424018 -277.52319) (xy 181.475434 -277.52319) (xy 181.526216 -277.531233)
			(xy 181.575115 -277.547121) (xy 181.620927 -277.570464) (xy 181.662523 -277.600685) (xy 181.698879 -277.637041)
			(xy 181.7291 -277.678637) (xy 181.752443 -277.724449) (xy 181.768331 -277.773348) (xy 181.776374 -277.82413)
			(xy 181.776878 -277.849838) (xy 182.094136 -277.849838) (xy 182.098096 -277.800784) (xy 182.109873 -277.753)
			(xy 182.129164 -277.707724) (xy 182.155467 -277.666128) (xy 182.188102 -277.629291) (xy 182.226223 -277.598166)
			(xy 182.268844 -277.573559) (xy 182.31486 -277.556107) (xy 182.363079 -277.546263) (xy 182.412254 -277.544282)
			(xy 182.461109 -277.550214) (xy 182.50838 -277.563906) (xy 182.552842 -277.585004) (xy 182.593345 -277.61296)
			(xy 182.628838 -277.647052) (xy 182.658403 -277.686396) (xy 182.681274 -277.729973) (xy 182.696858 -277.776654)
			(xy 182.704753 -277.825231) (xy 182.705248 -277.849838) (xy 182.704753 -277.874445) (xy 182.704574 -277.875546)
			(xy 183.022998 -277.875546) (xy 183.022998 -277.82413) (xy 183.031041 -277.773348) (xy 183.046929 -277.724449)
			(xy 183.070272 -277.678637) (xy 183.100493 -277.637041) (xy 183.136849 -277.600685) (xy 183.178445 -277.570464)
			(xy 183.224257 -277.547121) (xy 183.273156 -277.531233) (xy 183.323938 -277.52319) (xy 183.375354 -277.52319)
			(xy 183.426136 -277.531233) (xy 183.475035 -277.547121) (xy 183.520847 -277.570464) (xy 183.562443 -277.600685)
			(xy 183.598799 -277.637041) (xy 183.62902 -277.678637) (xy 183.652363 -277.724449) (xy 183.668251 -277.773348)
			(xy 183.676294 -277.82413) (xy 183.676798 -277.849838) (xy 183.994056 -277.849838) (xy 183.998016 -277.800784)
			(xy 184.009793 -277.753) (xy 184.029084 -277.707724) (xy 184.055387 -277.666128) (xy 184.088022 -277.629291)
			(xy 184.126143 -277.598166) (xy 184.168764 -277.573559) (xy 184.21478 -277.556107) (xy 184.262999 -277.546263)
			(xy 184.312174 -277.544282) (xy 184.361029 -277.550214) (xy 184.4083 -277.563906) (xy 184.452762 -277.585004)
			(xy 184.493265 -277.61296) (xy 184.528758 -277.647052) (xy 184.558323 -277.686396) (xy 184.581194 -277.729973)
			(xy 184.596778 -277.776654) (xy 184.604673 -277.825231) (xy 184.605168 -277.849838) (xy 184.604673 -277.874445)
			(xy 184.604494 -277.875546) (xy 184.923172 -277.875546) (xy 184.923172 -277.82413) (xy 184.931215 -277.773348)
			(xy 184.947103 -277.724449) (xy 184.970446 -277.678637) (xy 185.000667 -277.637041) (xy 185.037023 -277.600685)
			(xy 185.078619 -277.570464) (xy 185.124431 -277.547121) (xy 185.17333 -277.531233) (xy 185.224112 -277.52319)
			(xy 185.275528 -277.52319) (xy 185.32631 -277.531233) (xy 185.375209 -277.547121) (xy 185.421021 -277.570464)
			(xy 185.462617 -277.600685) (xy 185.498973 -277.637041) (xy 185.529194 -277.678637) (xy 185.552537 -277.724449)
			(xy 185.568425 -277.773348) (xy 185.576468 -277.82413) (xy 185.576972 -277.849838) (xy 185.89423 -277.849838)
			(xy 185.89819 -277.800784) (xy 185.909967 -277.753) (xy 185.929258 -277.707724) (xy 185.955561 -277.666128)
			(xy 185.988196 -277.629291) (xy 186.026317 -277.598166) (xy 186.068938 -277.573559) (xy 186.114954 -277.556107)
			(xy 186.163173 -277.546263) (xy 186.212348 -277.544282) (xy 186.261203 -277.550214) (xy 186.308474 -277.563906)
			(xy 186.352936 -277.585004) (xy 186.393439 -277.61296) (xy 186.428932 -277.647052) (xy 186.458497 -277.686396)
			(xy 186.481368 -277.729973) (xy 186.496952 -277.776654) (xy 186.504847 -277.825231) (xy 186.505342 -277.849838)
			(xy 186.504847 -277.874445) (xy 186.504668 -277.875546) (xy 186.823092 -277.875546) (xy 186.823092 -277.82413)
			(xy 186.831135 -277.773348) (xy 186.847023 -277.724449) (xy 186.870366 -277.678637) (xy 186.900587 -277.637041)
			(xy 186.936943 -277.600685) (xy 186.978539 -277.570464) (xy 187.024351 -277.547121) (xy 187.07325 -277.531233)
			(xy 187.124032 -277.52319) (xy 187.175448 -277.52319) (xy 187.22623 -277.531233) (xy 187.275129 -277.547121)
			(xy 187.320941 -277.570464) (xy 187.362537 -277.600685) (xy 187.398893 -277.637041) (xy 187.429114 -277.678637)
			(xy 187.452457 -277.724449) (xy 187.468345 -277.773348) (xy 187.476388 -277.82413) (xy 187.476892 -277.849838)
			(xy 187.79415 -277.849838) (xy 187.79811 -277.800784) (xy 187.809887 -277.753) (xy 187.829178 -277.707724)
			(xy 187.855481 -277.666128) (xy 187.888116 -277.629291) (xy 187.926237 -277.598166) (xy 187.968858 -277.573559)
			(xy 188.014874 -277.556107) (xy 188.063093 -277.546263) (xy 188.112268 -277.544282) (xy 188.161123 -277.550214)
			(xy 188.208394 -277.563906) (xy 188.252856 -277.585004) (xy 188.293359 -277.61296) (xy 188.328852 -277.647052)
			(xy 188.358417 -277.686396) (xy 188.381288 -277.729973) (xy 188.396872 -277.776654) (xy 188.404767 -277.825231)
			(xy 188.405262 -277.849838) (xy 188.404767 -277.874445) (xy 188.404588 -277.875546) (xy 188.723012 -277.875546)
			(xy 188.723012 -277.82413) (xy 188.731055 -277.773348) (xy 188.746943 -277.724449) (xy 188.770286 -277.678637)
			(xy 188.800507 -277.637041) (xy 188.836863 -277.600685) (xy 188.878459 -277.570464) (xy 188.924271 -277.547121)
			(xy 188.97317 -277.531233) (xy 189.023952 -277.52319) (xy 189.075368 -277.52319) (xy 189.12615 -277.531233)
			(xy 189.175049 -277.547121) (xy 189.220861 -277.570464) (xy 189.262457 -277.600685) (xy 189.298813 -277.637041)
			(xy 189.329034 -277.678637) (xy 189.352377 -277.724449) (xy 189.368265 -277.773348) (xy 189.376308 -277.82413)
			(xy 189.376812 -277.849838) (xy 189.69407 -277.849838) (xy 189.69803 -277.800784) (xy 189.709807 -277.753)
			(xy 189.729098 -277.707724) (xy 189.755401 -277.666128) (xy 189.788036 -277.629291) (xy 189.826157 -277.598166)
			(xy 189.868778 -277.573559) (xy 189.914794 -277.556107) (xy 189.963013 -277.546263) (xy 190.012188 -277.544282)
			(xy 190.061043 -277.550214) (xy 190.108314 -277.563906) (xy 190.152776 -277.585004) (xy 190.193279 -277.61296)
			(xy 190.228772 -277.647052) (xy 190.258337 -277.686396) (xy 190.281208 -277.729973) (xy 190.296792 -277.776654)
			(xy 190.304687 -277.825231) (xy 190.305182 -277.849838) (xy 190.304687 -277.874445) (xy 190.304508 -277.875546)
			(xy 190.623186 -277.875546) (xy 190.623186 -277.82413) (xy 190.631229 -277.773348) (xy 190.647117 -277.724449)
			(xy 190.67046 -277.678637) (xy 190.700681 -277.637041) (xy 190.737037 -277.600685) (xy 190.778633 -277.570464)
			(xy 190.824445 -277.547121) (xy 190.873344 -277.531233) (xy 190.924126 -277.52319) (xy 190.975542 -277.52319)
			(xy 191.026324 -277.531233) (xy 191.075223 -277.547121) (xy 191.121035 -277.570464) (xy 191.162631 -277.600685)
			(xy 191.198987 -277.637041) (xy 191.229208 -277.678637) (xy 191.252551 -277.724449) (xy 191.268439 -277.773348)
			(xy 191.276482 -277.82413) (xy 191.276986 -277.849838) (xy 191.594244 -277.849838) (xy 191.598204 -277.800784)
			(xy 191.609981 -277.753) (xy 191.629272 -277.707724) (xy 191.655575 -277.666128) (xy 191.68821 -277.629291)
			(xy 191.726331 -277.598166) (xy 191.768952 -277.573559) (xy 191.814968 -277.556107) (xy 191.863187 -277.546263)
			(xy 191.912362 -277.544282) (xy 191.961217 -277.550214) (xy 192.008488 -277.563906) (xy 192.05295 -277.585004)
			(xy 192.093453 -277.61296) (xy 192.128946 -277.647052) (xy 192.158511 -277.686396) (xy 192.181382 -277.729973)
			(xy 192.196966 -277.776654) (xy 192.204861 -277.825231) (xy 192.205356 -277.849838) (xy 192.204861 -277.874445)
			(xy 192.204682 -277.875546) (xy 192.523106 -277.875546) (xy 192.523106 -277.82413) (xy 192.531149 -277.773348)
			(xy 192.547037 -277.724449) (xy 192.57038 -277.678637) (xy 192.600601 -277.637041) (xy 192.636957 -277.600685)
			(xy 192.678553 -277.570464) (xy 192.724365 -277.547121) (xy 192.773264 -277.531233) (xy 192.824046 -277.52319)
			(xy 192.875462 -277.52319) (xy 192.926244 -277.531233) (xy 192.975143 -277.547121) (xy 193.020955 -277.570464)
			(xy 193.062551 -277.600685) (xy 193.098907 -277.637041) (xy 193.129128 -277.678637) (xy 193.152471 -277.724449)
			(xy 193.168359 -277.773348) (xy 193.176402 -277.82413) (xy 193.176906 -277.849838) (xy 193.494164 -277.849838)
			(xy 193.498124 -277.800784) (xy 193.509901 -277.753) (xy 193.529192 -277.707724) (xy 193.555495 -277.666128)
			(xy 193.58813 -277.629291) (xy 193.626251 -277.598166) (xy 193.668872 -277.573559) (xy 193.714888 -277.556107)
			(xy 193.763107 -277.546263) (xy 193.812282 -277.544282) (xy 193.861137 -277.550214) (xy 193.908408 -277.563906)
			(xy 193.95287 -277.585004) (xy 193.993373 -277.61296) (xy 194.028866 -277.647052) (xy 194.058431 -277.686396)
			(xy 194.081302 -277.729973) (xy 194.096886 -277.776654) (xy 194.104781 -277.825231) (xy 194.105276 -277.849838)
			(xy 194.104781 -277.874445) (xy 194.104602 -277.875546) (xy 194.423026 -277.875546) (xy 194.423026 -277.82413)
			(xy 194.431069 -277.773348) (xy 194.446957 -277.724449) (xy 194.4703 -277.678637) (xy 194.500521 -277.637041)
			(xy 194.536877 -277.600685) (xy 194.578473 -277.570464) (xy 194.624285 -277.547121) (xy 194.673184 -277.531233)
			(xy 194.723966 -277.52319) (xy 194.775382 -277.52319) (xy 194.826164 -277.531233) (xy 194.875063 -277.547121)
			(xy 194.920875 -277.570464) (xy 194.962471 -277.600685) (xy 194.998827 -277.637041) (xy 195.029048 -277.678637)
			(xy 195.052391 -277.724449) (xy 195.068279 -277.773348) (xy 195.076322 -277.82413) (xy 195.076826 -277.849838)
			(xy 195.394084 -277.849838) (xy 195.398044 -277.800784) (xy 195.409821 -277.753) (xy 195.429112 -277.707724)
			(xy 195.455415 -277.666128) (xy 195.48805 -277.629291) (xy 195.526171 -277.598166) (xy 195.568792 -277.573559)
			(xy 195.614808 -277.556107) (xy 195.663027 -277.546263) (xy 195.712202 -277.544282) (xy 195.761057 -277.550214)
			(xy 195.808328 -277.563906) (xy 195.85279 -277.585004) (xy 195.893293 -277.61296) (xy 195.928786 -277.647052)
			(xy 195.958351 -277.686396) (xy 195.981222 -277.729973) (xy 195.996806 -277.776654) (xy 196.004701 -277.825231)
			(xy 196.005196 -277.849838) (xy 196.004701 -277.874445) (xy 196.004522 -277.875546) (xy 196.3232 -277.875546)
			(xy 196.3232 -277.82413) (xy 196.331243 -277.773348) (xy 196.347131 -277.724449) (xy 196.370474 -277.678637)
			(xy 196.400695 -277.637041) (xy 196.437051 -277.600685) (xy 196.478647 -277.570464) (xy 196.524459 -277.547121)
			(xy 196.573358 -277.531233) (xy 196.62414 -277.52319) (xy 196.675556 -277.52319) (xy 196.726338 -277.531233)
			(xy 196.775237 -277.547121) (xy 196.821049 -277.570464) (xy 196.862645 -277.600685) (xy 196.899001 -277.637041)
			(xy 196.929222 -277.678637) (xy 196.952565 -277.724449) (xy 196.968453 -277.773348) (xy 196.976496 -277.82413)
			(xy 196.977 -277.849838) (xy 197.294258 -277.849838) (xy 197.298218 -277.800784) (xy 197.309995 -277.753)
			(xy 197.329286 -277.707724) (xy 197.355589 -277.666128) (xy 197.388224 -277.629291) (xy 197.426345 -277.598166)
			(xy 197.468966 -277.573559) (xy 197.514982 -277.556107) (xy 197.563201 -277.546263) (xy 197.612376 -277.544282)
			(xy 197.661231 -277.550214) (xy 197.708502 -277.563906) (xy 197.752964 -277.585004) (xy 197.793467 -277.61296)
			(xy 197.82896 -277.647052) (xy 197.858525 -277.686396) (xy 197.881396 -277.729973) (xy 197.89698 -277.776654)
			(xy 197.904875 -277.825231) (xy 197.90537 -277.849838) (xy 198.244218 -277.849838) (xy 198.248178 -277.800784)
			(xy 198.259955 -277.753) (xy 198.279246 -277.707724) (xy 198.305549 -277.666128) (xy 198.338184 -277.629291)
			(xy 198.376305 -277.598166) (xy 198.418926 -277.573559) (xy 198.464942 -277.556107) (xy 198.513161 -277.546263)
			(xy 198.562336 -277.544282) (xy 198.611191 -277.550214) (xy 198.658462 -277.563906) (xy 198.702924 -277.585004)
			(xy 198.743427 -277.61296) (xy 198.77892 -277.647052) (xy 198.808485 -277.686396) (xy 198.831356 -277.729973)
			(xy 198.84694 -277.776654) (xy 198.854835 -277.825231) (xy 198.85533 -277.849838) (xy 198.854835 -277.874445)
			(xy 198.84694 -277.923022) (xy 198.831356 -277.969703) (xy 198.808485 -278.01328) (xy 198.77892 -278.052624)
			(xy 198.743427 -278.086716) (xy 198.702924 -278.114672) (xy 198.658462 -278.13577) (xy 198.611191 -278.149462)
			(xy 198.562336 -278.155394) (xy 198.513161 -278.153413) (xy 198.464942 -278.143569) (xy 198.418926 -278.126117)
			(xy 198.376305 -278.10151) (xy 198.338184 -278.070385) (xy 198.305549 -278.033548) (xy 198.279246 -277.991952)
			(xy 198.259955 -277.946676) (xy 198.248178 -277.898892) (xy 198.244218 -277.849838) (xy 197.90537 -277.849838)
			(xy 197.904875 -277.874445) (xy 197.89698 -277.923022) (xy 197.881396 -277.969703) (xy 197.858525 -278.01328)
			(xy 197.82896 -278.052624) (xy 197.793467 -278.086716) (xy 197.752964 -278.114672) (xy 197.708502 -278.13577)
			(xy 197.661231 -278.149462) (xy 197.612376 -278.155394) (xy 197.563201 -278.153413) (xy 197.514982 -278.143569)
			(xy 197.468966 -278.126117) (xy 197.426345 -278.10151) (xy 197.388224 -278.070385) (xy 197.355589 -278.033548)
			(xy 197.329286 -277.991952) (xy 197.309995 -277.946676) (xy 197.298218 -277.898892) (xy 197.294258 -277.849838)
			(xy 196.977 -277.849838) (xy 196.976496 -277.875546) (xy 196.968453 -277.926328) (xy 196.952565 -277.975227)
			(xy 196.929222 -278.021039) (xy 196.899001 -278.062635) (xy 196.862645 -278.098991) (xy 196.821049 -278.129212)
			(xy 196.775237 -278.152555) (xy 196.726338 -278.168443) (xy 196.681996 -278.175466) (xy 215.523824 -278.175466)
			(xy 215.527895 -278.119844) (xy 215.540021 -278.065407) (xy 215.559944 -278.013316) (xy 215.58724 -277.964681)
			(xy 215.621326 -277.920538) (xy 215.661475 -277.881829) (xy 215.706833 -277.849378) (xy 215.756433 -277.823877)
			(xy 215.809217 -277.80587) (xy 215.86406 -277.79574) (xy 215.919794 -277.793703) (xy 215.975231 -277.799803)
			(xy 216.029188 -277.813909) (xy 216.080517 -277.835721) (xy 216.128123 -277.864775) (xy 216.170991 -277.90045)
			(xy 216.208208 -277.941987) (xy 216.238981 -277.9885) (xy 216.262653 -278.038997) (xy 216.278721 -278.092404)
			(xy 216.286841 -278.14758) (xy 216.28735 -278.175466) (xy 216.286841 -278.203352) (xy 216.282422 -278.233378)
			(xy 225.945952 -278.233378) (xy 225.950023 -278.177756) (xy 225.962149 -278.123319) (xy 225.982072 -278.071228)
			(xy 226.009368 -278.022593) (xy 226.043454 -277.97845) (xy 226.083603 -277.939741) (xy 226.128961 -277.90729)
			(xy 226.178561 -277.881789) (xy 226.231345 -277.863782) (xy 226.286188 -277.853652) (xy 226.341922 -277.851615)
			(xy 226.397359 -277.857715) (xy 226.451316 -277.871821) (xy 226.502645 -277.893633) (xy 226.550251 -277.922687)
			(xy 226.593119 -277.958362) (xy 226.630336 -277.999899) (xy 226.661109 -278.046412) (xy 226.684781 -278.096909)
			(xy 226.700849 -278.150316) (xy 226.708969 -278.205492) (xy 226.709478 -278.233378) (xy 226.708969 -278.261264)
			(xy 226.700849 -278.31644) (xy 226.684781 -278.369847) (xy 226.661109 -278.420344) (xy 226.630336 -278.466857)
			(xy 226.593119 -278.508394) (xy 226.550251 -278.544069) (xy 226.502645 -278.573123) (xy 226.451316 -278.594935)
			(xy 226.397359 -278.609041) (xy 226.341922 -278.615141) (xy 226.286188 -278.613104) (xy 226.231345 -278.602974)
			(xy 226.178561 -278.584967) (xy 226.128961 -278.559466) (xy 226.083603 -278.527015) (xy 226.043454 -278.488306)
			(xy 226.009368 -278.444163) (xy 225.982072 -278.395528) (xy 225.962149 -278.343437) (xy 225.950023 -278.289)
			(xy 225.945952 -278.233378) (xy 216.282422 -278.233378) (xy 216.278721 -278.258528) (xy 216.262653 -278.311935)
			(xy 216.238981 -278.362432) (xy 216.208208 -278.408945) (xy 216.170991 -278.450482) (xy 216.128123 -278.486157)
			(xy 216.080517 -278.515211) (xy 216.029188 -278.537023) (xy 215.975231 -278.551129) (xy 215.919794 -278.557229)
			(xy 215.86406 -278.555192) (xy 215.809217 -278.545062) (xy 215.756433 -278.527055) (xy 215.706833 -278.501554)
			(xy 215.661475 -278.469103) (xy 215.621326 -278.430394) (xy 215.58724 -278.386251) (xy 215.559944 -278.337616)
			(xy 215.540021 -278.285525) (xy 215.527895 -278.231088) (xy 215.523824 -278.175466) (xy 196.681996 -278.175466)
			(xy 196.675556 -278.176486) (xy 196.62414 -278.176486) (xy 196.573358 -278.168443) (xy 196.524459 -278.152555)
			(xy 196.478647 -278.129212) (xy 196.437051 -278.098991) (xy 196.400695 -278.062635) (xy 196.370474 -278.021039)
			(xy 196.347131 -277.975227) (xy 196.331243 -277.926328) (xy 196.3232 -277.875546) (xy 196.004522 -277.875546)
			(xy 195.996806 -277.923022) (xy 195.981222 -277.969703) (xy 195.958351 -278.01328) (xy 195.928786 -278.052624)
			(xy 195.893293 -278.086716) (xy 195.85279 -278.114672) (xy 195.808328 -278.13577) (xy 195.761057 -278.149462)
			(xy 195.712202 -278.155394) (xy 195.663027 -278.153413) (xy 195.614808 -278.143569) (xy 195.568792 -278.126117)
			(xy 195.526171 -278.10151) (xy 195.48805 -278.070385) (xy 195.455415 -278.033548) (xy 195.429112 -277.991952)
			(xy 195.409821 -277.946676) (xy 195.398044 -277.898892) (xy 195.394084 -277.849838) (xy 195.076826 -277.849838)
			(xy 195.076322 -277.875546) (xy 195.068279 -277.926328) (xy 195.052391 -277.975227) (xy 195.029048 -278.021039)
			(xy 194.998827 -278.062635) (xy 194.962471 -278.098991) (xy 194.920875 -278.129212) (xy 194.875063 -278.152555)
			(xy 194.826164 -278.168443) (xy 194.775382 -278.176486) (xy 194.723966 -278.176486) (xy 194.673184 -278.168443)
			(xy 194.624285 -278.152555) (xy 194.578473 -278.129212) (xy 194.536877 -278.098991) (xy 194.500521 -278.062635)
			(xy 194.4703 -278.021039) (xy 194.446957 -277.975227) (xy 194.431069 -277.926328) (xy 194.423026 -277.875546)
			(xy 194.104602 -277.875546) (xy 194.096886 -277.923022) (xy 194.081302 -277.969703) (xy 194.058431 -278.01328)
			(xy 194.028866 -278.052624) (xy 193.993373 -278.086716) (xy 193.95287 -278.114672) (xy 193.908408 -278.13577)
			(xy 193.861137 -278.149462) (xy 193.812282 -278.155394) (xy 193.763107 -278.153413) (xy 193.714888 -278.143569)
			(xy 193.668872 -278.126117) (xy 193.626251 -278.10151) (xy 193.58813 -278.070385) (xy 193.555495 -278.033548)
			(xy 193.529192 -277.991952) (xy 193.509901 -277.946676) (xy 193.498124 -277.898892) (xy 193.494164 -277.849838)
			(xy 193.176906 -277.849838) (xy 193.176402 -277.875546) (xy 193.168359 -277.926328) (xy 193.152471 -277.975227)
			(xy 193.129128 -278.021039) (xy 193.098907 -278.062635) (xy 193.062551 -278.098991) (xy 193.020955 -278.129212)
			(xy 192.975143 -278.152555) (xy 192.926244 -278.168443) (xy 192.875462 -278.176486) (xy 192.824046 -278.176486)
			(xy 192.773264 -278.168443) (xy 192.724365 -278.152555) (xy 192.678553 -278.129212) (xy 192.636957 -278.098991)
			(xy 192.600601 -278.062635) (xy 192.57038 -278.021039) (xy 192.547037 -277.975227) (xy 192.531149 -277.926328)
			(xy 192.523106 -277.875546) (xy 192.204682 -277.875546) (xy 192.196966 -277.923022) (xy 192.181382 -277.969703)
			(xy 192.158511 -278.01328) (xy 192.128946 -278.052624) (xy 192.093453 -278.086716) (xy 192.05295 -278.114672)
			(xy 192.008488 -278.13577) (xy 191.961217 -278.149462) (xy 191.912362 -278.155394) (xy 191.863187 -278.153413)
			(xy 191.814968 -278.143569) (xy 191.768952 -278.126117) (xy 191.726331 -278.10151) (xy 191.68821 -278.070385)
			(xy 191.655575 -278.033548) (xy 191.629272 -277.991952) (xy 191.609981 -277.946676) (xy 191.598204 -277.898892)
			(xy 191.594244 -277.849838) (xy 191.276986 -277.849838) (xy 191.276482 -277.875546) (xy 191.268439 -277.926328)
			(xy 191.252551 -277.975227) (xy 191.229208 -278.021039) (xy 191.198987 -278.062635) (xy 191.162631 -278.098991)
			(xy 191.121035 -278.129212) (xy 191.075223 -278.152555) (xy 191.026324 -278.168443) (xy 190.975542 -278.176486)
			(xy 190.924126 -278.176486) (xy 190.873344 -278.168443) (xy 190.824445 -278.152555) (xy 190.778633 -278.129212)
			(xy 190.737037 -278.098991) (xy 190.700681 -278.062635) (xy 190.67046 -278.021039) (xy 190.647117 -277.975227)
			(xy 190.631229 -277.926328) (xy 190.623186 -277.875546) (xy 190.304508 -277.875546) (xy 190.296792 -277.923022)
			(xy 190.281208 -277.969703) (xy 190.258337 -278.01328) (xy 190.228772 -278.052624) (xy 190.193279 -278.086716)
			(xy 190.152776 -278.114672) (xy 190.108314 -278.13577) (xy 190.061043 -278.149462) (xy 190.012188 -278.155394)
			(xy 189.963013 -278.153413) (xy 189.914794 -278.143569) (xy 189.868778 -278.126117) (xy 189.826157 -278.10151)
			(xy 189.788036 -278.070385) (xy 189.755401 -278.033548) (xy 189.729098 -277.991952) (xy 189.709807 -277.946676)
			(xy 189.69803 -277.898892) (xy 189.69407 -277.849838) (xy 189.376812 -277.849838) (xy 189.376308 -277.875546)
			(xy 189.368265 -277.926328) (xy 189.352377 -277.975227) (xy 189.329034 -278.021039) (xy 189.298813 -278.062635)
			(xy 189.262457 -278.098991) (xy 189.220861 -278.129212) (xy 189.175049 -278.152555) (xy 189.12615 -278.168443)
			(xy 189.075368 -278.176486) (xy 189.023952 -278.176486) (xy 188.97317 -278.168443) (xy 188.924271 -278.152555)
			(xy 188.878459 -278.129212) (xy 188.836863 -278.098991) (xy 188.800507 -278.062635) (xy 188.770286 -278.021039)
			(xy 188.746943 -277.975227) (xy 188.731055 -277.926328) (xy 188.723012 -277.875546) (xy 188.404588 -277.875546)
			(xy 188.396872 -277.923022) (xy 188.381288 -277.969703) (xy 188.358417 -278.01328) (xy 188.328852 -278.052624)
			(xy 188.293359 -278.086716) (xy 188.252856 -278.114672) (xy 188.208394 -278.13577) (xy 188.161123 -278.149462)
			(xy 188.112268 -278.155394) (xy 188.063093 -278.153413) (xy 188.014874 -278.143569) (xy 187.968858 -278.126117)
			(xy 187.926237 -278.10151) (xy 187.888116 -278.070385) (xy 187.855481 -278.033548) (xy 187.829178 -277.991952)
			(xy 187.809887 -277.946676) (xy 187.79811 -277.898892) (xy 187.79415 -277.849838) (xy 187.476892 -277.849838)
			(xy 187.476388 -277.875546) (xy 187.468345 -277.926328) (xy 187.452457 -277.975227) (xy 187.429114 -278.021039)
			(xy 187.398893 -278.062635) (xy 187.362537 -278.098991) (xy 187.320941 -278.129212) (xy 187.275129 -278.152555)
			(xy 187.22623 -278.168443) (xy 187.175448 -278.176486) (xy 187.124032 -278.176486) (xy 187.07325 -278.168443)
			(xy 187.024351 -278.152555) (xy 186.978539 -278.129212) (xy 186.936943 -278.098991) (xy 186.900587 -278.062635)
			(xy 186.870366 -278.021039) (xy 186.847023 -277.975227) (xy 186.831135 -277.926328) (xy 186.823092 -277.875546)
			(xy 186.504668 -277.875546) (xy 186.496952 -277.923022) (xy 186.481368 -277.969703) (xy 186.458497 -278.01328)
			(xy 186.428932 -278.052624) (xy 186.393439 -278.086716) (xy 186.352936 -278.114672) (xy 186.308474 -278.13577)
			(xy 186.261203 -278.149462) (xy 186.212348 -278.155394) (xy 186.163173 -278.153413) (xy 186.114954 -278.143569)
			(xy 186.068938 -278.126117) (xy 186.026317 -278.10151) (xy 185.988196 -278.070385) (xy 185.955561 -278.033548)
			(xy 185.929258 -277.991952) (xy 185.909967 -277.946676) (xy 185.89819 -277.898892) (xy 185.89423 -277.849838)
			(xy 185.576972 -277.849838) (xy 185.576468 -277.875546) (xy 185.568425 -277.926328) (xy 185.552537 -277.975227)
			(xy 185.529194 -278.021039) (xy 185.498973 -278.062635) (xy 185.462617 -278.098991) (xy 185.421021 -278.129212)
			(xy 185.375209 -278.152555) (xy 185.32631 -278.168443) (xy 185.275528 -278.176486) (xy 185.224112 -278.176486)
			(xy 185.17333 -278.168443) (xy 185.124431 -278.152555) (xy 185.078619 -278.129212) (xy 185.037023 -278.098991)
			(xy 185.000667 -278.062635) (xy 184.970446 -278.021039) (xy 184.947103 -277.975227) (xy 184.931215 -277.926328)
			(xy 184.923172 -277.875546) (xy 184.604494 -277.875546) (xy 184.596778 -277.923022) (xy 184.581194 -277.969703)
			(xy 184.558323 -278.01328) (xy 184.528758 -278.052624) (xy 184.493265 -278.086716) (xy 184.452762 -278.114672)
			(xy 184.4083 -278.13577) (xy 184.361029 -278.149462) (xy 184.312174 -278.155394) (xy 184.262999 -278.153413)
			(xy 184.21478 -278.143569) (xy 184.168764 -278.126117) (xy 184.126143 -278.10151) (xy 184.088022 -278.070385)
			(xy 184.055387 -278.033548) (xy 184.029084 -277.991952) (xy 184.009793 -277.946676) (xy 183.998016 -277.898892)
			(xy 183.994056 -277.849838) (xy 183.676798 -277.849838) (xy 183.676294 -277.875546) (xy 183.668251 -277.926328)
			(xy 183.652363 -277.975227) (xy 183.62902 -278.021039) (xy 183.598799 -278.062635) (xy 183.562443 -278.098991)
			(xy 183.520847 -278.129212) (xy 183.475035 -278.152555) (xy 183.426136 -278.168443) (xy 183.375354 -278.176486)
			(xy 183.323938 -278.176486) (xy 183.273156 -278.168443) (xy 183.224257 -278.152555) (xy 183.178445 -278.129212)
			(xy 183.136849 -278.098991) (xy 183.100493 -278.062635) (xy 183.070272 -278.021039) (xy 183.046929 -277.975227)
			(xy 183.031041 -277.926328) (xy 183.022998 -277.875546) (xy 182.704574 -277.875546) (xy 182.696858 -277.923022)
			(xy 182.681274 -277.969703) (xy 182.658403 -278.01328) (xy 182.628838 -278.052624) (xy 182.593345 -278.086716)
			(xy 182.552842 -278.114672) (xy 182.50838 -278.13577) (xy 182.461109 -278.149462) (xy 182.412254 -278.155394)
			(xy 182.363079 -278.153413) (xy 182.31486 -278.143569) (xy 182.268844 -278.126117) (xy 182.226223 -278.10151)
			(xy 182.188102 -278.070385) (xy 182.155467 -278.033548) (xy 182.129164 -277.991952) (xy 182.109873 -277.946676)
			(xy 182.098096 -277.898892) (xy 182.094136 -277.849838) (xy 181.776878 -277.849838) (xy 181.776374 -277.875546)
			(xy 181.768331 -277.926328) (xy 181.752443 -277.975227) (xy 181.7291 -278.021039) (xy 181.698879 -278.062635)
			(xy 181.662523 -278.098991) (xy 181.620927 -278.129212) (xy 181.575115 -278.152555) (xy 181.526216 -278.168443)
			(xy 181.475434 -278.176486) (xy 181.424018 -278.176486) (xy 181.373236 -278.168443) (xy 181.324337 -278.152555)
			(xy 181.278525 -278.129212) (xy 181.236929 -278.098991) (xy 181.200573 -278.062635) (xy 181.170352 -278.021039)
			(xy 181.147009 -277.975227) (xy 181.131121 -277.926328) (xy 181.123078 -277.875546) (xy 180.804654 -277.875546)
			(xy 180.796938 -277.923022) (xy 180.781354 -277.969703) (xy 180.758483 -278.01328) (xy 180.728918 -278.052624)
			(xy 180.693425 -278.086716) (xy 180.652922 -278.114672) (xy 180.60846 -278.13577) (xy 180.561189 -278.149462)
			(xy 180.512334 -278.155394) (xy 180.463159 -278.153413) (xy 180.41494 -278.143569) (xy 180.368924 -278.126117)
			(xy 180.326303 -278.10151) (xy 180.288182 -278.070385) (xy 180.255547 -278.033548) (xy 180.229244 -277.991952)
			(xy 180.209953 -277.946676) (xy 180.198176 -277.898892) (xy 180.194216 -277.849838) (xy 179.876958 -277.849838)
			(xy 179.876454 -277.875546) (xy 179.868411 -277.926328) (xy 179.852523 -277.975227) (xy 179.82918 -278.021039)
			(xy 179.798959 -278.062635) (xy 179.762603 -278.098991) (xy 179.721007 -278.129212) (xy 179.675195 -278.152555)
			(xy 179.626296 -278.168443) (xy 179.575514 -278.176486) (xy 179.524098 -278.176486) (xy 179.473316 -278.168443)
			(xy 179.424417 -278.152555) (xy 179.378605 -278.129212) (xy 179.337009 -278.098991) (xy 179.300653 -278.062635)
			(xy 179.270432 -278.021039) (xy 179.247089 -277.975227) (xy 179.231201 -277.926328) (xy 179.223158 -277.875546)
			(xy 178.90448 -277.875546) (xy 178.896764 -277.923022) (xy 178.88118 -277.969703) (xy 178.858309 -278.01328)
			(xy 178.828744 -278.052624) (xy 178.793251 -278.086716) (xy 178.752748 -278.114672) (xy 178.708286 -278.13577)
			(xy 178.661015 -278.149462) (xy 178.61216 -278.155394) (xy 178.562985 -278.153413) (xy 178.514766 -278.143569)
			(xy 178.46875 -278.126117) (xy 178.426129 -278.10151) (xy 178.388008 -278.070385) (xy 178.355373 -278.033548)
			(xy 178.32907 -277.991952) (xy 178.309779 -277.946676) (xy 178.298002 -277.898892) (xy 178.294042 -277.849838)
			(xy 177.976784 -277.849838) (xy 177.97628 -277.875546) (xy 177.968237 -277.926328) (xy 177.952349 -277.975227)
			(xy 177.929006 -278.021039) (xy 177.898785 -278.062635) (xy 177.862429 -278.098991) (xy 177.820833 -278.129212)
			(xy 177.775021 -278.152555) (xy 177.726122 -278.168443) (xy 177.67534 -278.176486) (xy 177.623924 -278.176486)
			(xy 177.573142 -278.168443) (xy 177.524243 -278.152555) (xy 177.478431 -278.129212) (xy 177.436835 -278.098991)
			(xy 177.400479 -278.062635) (xy 177.370258 -278.021039) (xy 177.346915 -277.975227) (xy 177.331027 -277.926328)
			(xy 177.322984 -277.875546) (xy 177.00456 -277.875546) (xy 176.996844 -277.923022) (xy 176.98126 -277.969703)
			(xy 176.958389 -278.01328) (xy 176.928824 -278.052624) (xy 176.893331 -278.086716) (xy 176.852828 -278.114672)
			(xy 176.808366 -278.13577) (xy 176.761095 -278.149462) (xy 176.71224 -278.155394) (xy 176.663065 -278.153413)
			(xy 176.614846 -278.143569) (xy 176.56883 -278.126117) (xy 176.526209 -278.10151) (xy 176.488088 -278.070385)
			(xy 176.455453 -278.033548) (xy 176.42915 -277.991952) (xy 176.409859 -277.946676) (xy 176.398082 -277.898892)
			(xy 176.394122 -277.849838) (xy 176.076864 -277.849838) (xy 176.07636 -277.875546) (xy 176.068317 -277.926328)
			(xy 176.052429 -277.975227) (xy 176.029086 -278.021039) (xy 175.998865 -278.062635) (xy 175.962509 -278.098991)
			(xy 175.920913 -278.129212) (xy 175.875101 -278.152555) (xy 175.826202 -278.168443) (xy 175.77542 -278.176486)
			(xy 175.724004 -278.176486) (xy 175.673222 -278.168443) (xy 175.624323 -278.152555) (xy 175.578511 -278.129212)
			(xy 175.536915 -278.098991) (xy 175.500559 -278.062635) (xy 175.470338 -278.021039) (xy 175.446995 -277.975227)
			(xy 175.431107 -277.926328) (xy 175.423064 -277.875546) (xy 175.10464 -277.875546) (xy 175.096924 -277.923022)
			(xy 175.08134 -277.969703) (xy 175.058469 -278.01328) (xy 175.028904 -278.052624) (xy 174.993411 -278.086716)
			(xy 174.952908 -278.114672) (xy 174.908446 -278.13577) (xy 174.861175 -278.149462) (xy 174.81232 -278.155394)
			(xy 174.763145 -278.153413) (xy 174.714926 -278.143569) (xy 174.66891 -278.126117) (xy 174.626289 -278.10151)
			(xy 174.588168 -278.070385) (xy 174.555533 -278.033548) (xy 174.52923 -277.991952) (xy 174.509939 -277.946676)
			(xy 174.498162 -277.898892) (xy 174.494202 -277.849838) (xy 174.177198 -277.849838) (xy 174.176694 -277.875546)
			(xy 174.168651 -277.926328) (xy 174.152763 -277.975227) (xy 174.12942 -278.021039) (xy 174.099199 -278.062635)
			(xy 174.062843 -278.098991) (xy 174.021247 -278.129212) (xy 173.975435 -278.152555) (xy 173.926536 -278.168443)
			(xy 173.875754 -278.176486) (xy 173.824338 -278.176486) (xy 173.773556 -278.168443) (xy 173.724657 -278.152555)
			(xy 173.678845 -278.129212) (xy 173.637249 -278.098991) (xy 173.600893 -278.062635) (xy 173.570672 -278.021039)
			(xy 173.547329 -277.975227) (xy 173.531441 -277.926328) (xy 173.523398 -277.875546) (xy 173.20472 -277.875546)
			(xy 173.197004 -277.923022) (xy 173.18142 -277.969703) (xy 173.158549 -278.01328) (xy 173.128984 -278.052624)
			(xy 173.093491 -278.086716) (xy 173.052988 -278.114672) (xy 173.008526 -278.13577) (xy 172.961255 -278.149462)
			(xy 172.9124 -278.155394) (xy 172.863225 -278.153413) (xy 172.815006 -278.143569) (xy 172.76899 -278.126117)
			(xy 172.726369 -278.10151) (xy 172.688248 -278.070385) (xy 172.655613 -278.033548) (xy 172.62931 -277.991952)
			(xy 172.610019 -277.946676) (xy 172.598242 -277.898892) (xy 172.594282 -277.849838) (xy 172.277024 -277.849838)
			(xy 172.27652 -277.875546) (xy 172.268477 -277.926328) (xy 172.252589 -277.975227) (xy 172.229246 -278.021039)
			(xy 172.199025 -278.062635) (xy 172.162669 -278.098991) (xy 172.121073 -278.129212) (xy 172.075261 -278.152555)
			(xy 172.026362 -278.168443) (xy 171.97558 -278.176486) (xy 171.924164 -278.176486) (xy 171.873382 -278.168443)
			(xy 171.824483 -278.152555) (xy 171.778671 -278.129212) (xy 171.737075 -278.098991) (xy 171.700719 -278.062635)
			(xy 171.670498 -278.021039) (xy 171.647155 -277.975227) (xy 171.631267 -277.926328) (xy 171.623224 -277.875546)
			(xy 171.304546 -277.875546) (xy 171.29683 -277.923022) (xy 171.281246 -277.969703) (xy 171.258375 -278.01328)
			(xy 171.22881 -278.052624) (xy 171.193317 -278.086716) (xy 171.152814 -278.114672) (xy 171.108352 -278.13577)
			(xy 171.061081 -278.149462) (xy 171.012226 -278.155394) (xy 170.963051 -278.153413) (xy 170.914832 -278.143569)
			(xy 170.868816 -278.126117) (xy 170.826195 -278.10151) (xy 170.788074 -278.070385) (xy 170.755439 -278.033548)
			(xy 170.729136 -277.991952) (xy 170.709845 -277.946676) (xy 170.698068 -277.898892) (xy 170.694108 -277.849838)
			(xy 170.377104 -277.849838) (xy 170.3766 -277.875546) (xy 170.368557 -277.926328) (xy 170.352669 -277.975227)
			(xy 170.329326 -278.021039) (xy 170.299105 -278.062635) (xy 170.262749 -278.098991) (xy 170.221153 -278.129212)
			(xy 170.175341 -278.152555) (xy 170.126442 -278.168443) (xy 170.07566 -278.176486) (xy 170.024244 -278.176486)
			(xy 169.973462 -278.168443) (xy 169.924563 -278.152555) (xy 169.878751 -278.129212) (xy 169.837155 -278.098991)
			(xy 169.800799 -278.062635) (xy 169.770578 -278.021039) (xy 169.747235 -277.975227) (xy 169.731347 -277.926328)
			(xy 169.723304 -277.875546) (xy 169.404626 -277.875546) (xy 169.39691 -277.923022) (xy 169.381326 -277.969703)
			(xy 169.358455 -278.01328) (xy 169.32889 -278.052624) (xy 169.293397 -278.086716) (xy 169.252894 -278.114672)
			(xy 169.208432 -278.13577) (xy 169.161161 -278.149462) (xy 169.112306 -278.155394) (xy 169.063131 -278.153413)
			(xy 169.014912 -278.143569) (xy 168.968896 -278.126117) (xy 168.926275 -278.10151) (xy 168.888154 -278.070385)
			(xy 168.855519 -278.033548) (xy 168.829216 -277.991952) (xy 168.809925 -277.946676) (xy 168.798148 -277.898892)
			(xy 168.794188 -277.849838) (xy 168.477184 -277.849838) (xy 168.47668 -277.875546) (xy 168.468637 -277.926328)
			(xy 168.452749 -277.975227) (xy 168.429406 -278.021039) (xy 168.399185 -278.062635) (xy 168.362829 -278.098991)
			(xy 168.321233 -278.129212) (xy 168.275421 -278.152555) (xy 168.226522 -278.168443) (xy 168.17574 -278.176486)
			(xy 168.124324 -278.176486) (xy 168.073542 -278.168443) (xy 168.024643 -278.152555) (xy 167.978831 -278.129212)
			(xy 167.937235 -278.098991) (xy 167.900879 -278.062635) (xy 167.870658 -278.021039) (xy 167.847315 -277.975227)
			(xy 167.831427 -277.926328) (xy 167.823384 -277.875546) (xy 167.504706 -277.875546) (xy 167.49699 -277.923022)
			(xy 167.481406 -277.969703) (xy 167.458535 -278.01328) (xy 167.42897 -278.052624) (xy 167.393477 -278.086716)
			(xy 167.352974 -278.114672) (xy 167.308512 -278.13577) (xy 167.261241 -278.149462) (xy 167.212386 -278.155394)
			(xy 167.163211 -278.153413) (xy 167.114992 -278.143569) (xy 167.068976 -278.126117) (xy 167.026355 -278.10151)
			(xy 166.988234 -278.070385) (xy 166.955599 -278.033548) (xy 166.929296 -277.991952) (xy 166.910005 -277.946676)
			(xy 166.898228 -277.898892) (xy 166.894268 -277.849838) (xy 166.57701 -277.849838) (xy 166.576506 -277.875546)
			(xy 166.568463 -277.926328) (xy 166.552575 -277.975227) (xy 166.529232 -278.021039) (xy 166.499011 -278.062635)
			(xy 166.462655 -278.098991) (xy 166.421059 -278.129212) (xy 166.375247 -278.152555) (xy 166.326348 -278.168443)
			(xy 166.275566 -278.176486) (xy 166.22415 -278.176486) (xy 166.173368 -278.168443) (xy 166.124469 -278.152555)
			(xy 166.078657 -278.129212) (xy 166.037061 -278.098991) (xy 166.000705 -278.062635) (xy 165.970484 -278.021039)
			(xy 165.947141 -277.975227) (xy 165.931253 -277.926328) (xy 165.92321 -277.875546) (xy 165.604532 -277.875546)
			(xy 165.596816 -277.923022) (xy 165.581232 -277.969703) (xy 165.558361 -278.01328) (xy 165.528796 -278.052624)
			(xy 165.493303 -278.086716) (xy 165.4528 -278.114672) (xy 165.408338 -278.13577) (xy 165.361067 -278.149462)
			(xy 165.312212 -278.155394) (xy 165.263037 -278.153413) (xy 165.214818 -278.143569) (xy 165.168802 -278.126117)
			(xy 165.126181 -278.10151) (xy 165.08806 -278.070385) (xy 165.055425 -278.033548) (xy 165.029122 -277.991952)
			(xy 165.009831 -277.946676) (xy 164.998054 -277.898892) (xy 164.994094 -277.849838) (xy 164.67709 -277.849838)
			(xy 164.676586 -277.875546) (xy 164.668543 -277.926328) (xy 164.652655 -277.975227) (xy 164.629312 -278.021039)
			(xy 164.599091 -278.062635) (xy 164.562735 -278.098991) (xy 164.521139 -278.129212) (xy 164.475327 -278.152555)
			(xy 164.426428 -278.168443) (xy 164.375646 -278.176486) (xy 164.32423 -278.176486) (xy 164.273448 -278.168443)
			(xy 164.224549 -278.152555) (xy 164.178737 -278.129212) (xy 164.137141 -278.098991) (xy 164.100785 -278.062635)
			(xy 164.070564 -278.021039) (xy 164.047221 -277.975227) (xy 164.031333 -277.926328) (xy 164.02329 -277.875546)
			(xy 163.704612 -277.875546) (xy 163.696896 -277.923022) (xy 163.681312 -277.969703) (xy 163.658441 -278.01328)
			(xy 163.628876 -278.052624) (xy 163.593383 -278.086716) (xy 163.55288 -278.114672) (xy 163.508418 -278.13577)
			(xy 163.461147 -278.149462) (xy 163.412292 -278.155394) (xy 163.363117 -278.153413) (xy 163.314898 -278.143569)
			(xy 163.268882 -278.126117) (xy 163.226261 -278.10151) (xy 163.18814 -278.070385) (xy 163.155505 -278.033548)
			(xy 163.129202 -277.991952) (xy 163.109911 -277.946676) (xy 163.098134 -277.898892) (xy 163.094174 -277.849838)
			(xy 162.77717 -277.849838) (xy 162.776666 -277.875546) (xy 162.768623 -277.926328) (xy 162.752735 -277.975227)
			(xy 162.729392 -278.021039) (xy 162.699171 -278.062635) (xy 162.662815 -278.098991) (xy 162.621219 -278.129212)
			(xy 162.575407 -278.152555) (xy 162.526508 -278.168443) (xy 162.475726 -278.176486) (xy 162.42431 -278.176486)
			(xy 162.373528 -278.168443) (xy 162.324629 -278.152555) (xy 162.278817 -278.129212) (xy 162.237221 -278.098991)
			(xy 162.200865 -278.062635) (xy 162.170644 -278.021039) (xy 162.147301 -277.975227) (xy 162.131413 -277.926328)
			(xy 162.12337 -277.875546) (xy 161.804692 -277.875546) (xy 161.796976 -277.923022) (xy 161.781392 -277.969703)
			(xy 161.758521 -278.01328) (xy 161.728956 -278.052624) (xy 161.693463 -278.086716) (xy 161.65296 -278.114672)
			(xy 161.608498 -278.13577) (xy 161.561227 -278.149462) (xy 161.512372 -278.155394) (xy 161.463197 -278.153413)
			(xy 161.414978 -278.143569) (xy 161.368962 -278.126117) (xy 161.326341 -278.10151) (xy 161.28822 -278.070385)
			(xy 161.255585 -278.033548) (xy 161.229282 -277.991952) (xy 161.209991 -277.946676) (xy 161.198214 -277.898892)
			(xy 161.194254 -277.849838) (xy 160.876996 -277.849838) (xy 160.876492 -277.875546) (xy 160.868449 -277.926328)
			(xy 160.852561 -277.975227) (xy 160.829218 -278.021039) (xy 160.798997 -278.062635) (xy 160.762641 -278.098991)
			(xy 160.721045 -278.129212) (xy 160.675233 -278.152555) (xy 160.626334 -278.168443) (xy 160.575552 -278.176486)
			(xy 160.524136 -278.176486) (xy 160.473354 -278.168443) (xy 160.424455 -278.152555) (xy 160.378643 -278.129212)
			(xy 160.337047 -278.098991) (xy 160.300691 -278.062635) (xy 160.27047 -278.021039) (xy 160.247127 -277.975227)
			(xy 160.231239 -277.926328) (xy 160.223196 -277.875546) (xy 159.903665 -277.875546) (xy 159.901626 -277.900151)
			(xy 159.889223 -277.949128) (xy 159.868927 -277.995396) (xy 159.841292 -278.037692) (xy 159.807073 -278.074862)
			(xy 159.767202 -278.105893) (xy 159.722767 -278.129938) (xy 159.67498 -278.146341) (xy 159.625146 -278.154654)
			(xy 159.599884 -278.155146) (xy 159.585701 -278.154971) (xy 159.557461 -278.152298) (xy 159.543496 -278.149812)
			(xy 159.53105 -278.147526) (xy 159.507428 -278.154892) (xy 159.429958 -278.232362) (xy 159.422592 -278.255984)
			(xy 159.424878 -278.26843) (xy 159.427354 -278.282396) (xy 159.430026 -278.310635) (xy 159.430212 -278.324818)
			(xy 159.430038 -278.339001) (xy 159.427364 -278.367241) (xy 159.424878 -278.381206) (xy 159.422592 -278.393652)
			(xy 159.429958 -278.417274) (xy 159.507428 -278.494744) (xy 159.53105 -278.50211) (xy 159.543496 -278.499824)
			(xy 159.557463 -278.497352) (xy 159.585702 -278.494677) (xy 159.599884 -278.49449) (xy 159.623877 -278.494953)
			(xy 159.671271 -278.502457) (xy 159.716909 -278.517283) (xy 159.759665 -278.539067) (xy 159.798486 -278.56727)
			(xy 159.832418 -278.6012) (xy 159.860624 -278.64002) (xy 159.88241 -278.682775) (xy 159.897239 -278.728411)
			(xy 159.904746 -278.775805) (xy 159.905192 -278.799798) (xy 159.905015 -278.813981) (xy 159.902343 -278.842221)
			(xy 159.899858 -278.856186) (xy 159.897572 -278.868632) (xy 159.904938 -278.892254) (xy 159.982408 -278.969724)
			(xy 160.00603 -278.97709) (xy 160.018476 -278.974804) (xy 160.032441 -278.972321) (xy 160.060681 -278.969654)
			(xy 160.074864 -278.96947) (xy 160.084735 -278.969546) (xy 160.104436 -278.970815) (xy 160.114234 -278.97201)
			(xy 160.126172 -278.973534) (xy 160.148778 -278.96566) (xy 160.222438 -278.889206) (xy 160.229296 -278.866346)
			(xy 160.227518 -278.854408) (xy 160.225295 -278.840864) (xy 160.222883 -278.813522) (xy 160.222692 -278.799798)
			(xy 160.223208 -278.774114) (xy 160.231242 -278.72338) (xy 160.247113 -278.674526) (xy 160.27043 -278.628756)
			(xy 160.300619 -278.587196) (xy 160.336937 -278.55087) (xy 160.378489 -278.520671) (xy 160.424254 -278.497343)
			(xy 160.473104 -278.48146) (xy 160.523837 -278.473414) (xy 160.575204 -278.473401) (xy 160.62594 -278.481423)
			(xy 160.674798 -278.497282) (xy 160.720574 -278.520587) (xy 160.762141 -278.550766) (xy 160.798477 -278.587074)
			(xy 160.828686 -278.628619) (xy 160.852025 -278.674378) (xy 160.86792 -278.723224) (xy 160.87598 -278.773955)
			(xy 160.875993 -278.799798) (xy 161.194254 -278.799798) (xy 161.198214 -278.750744) (xy 161.209991 -278.70296)
			(xy 161.229282 -278.657684) (xy 161.255585 -278.616088) (xy 161.28822 -278.579251) (xy 161.326341 -278.548126)
			(xy 161.368962 -278.523519) (xy 161.414978 -278.506067) (xy 161.463197 -278.496223) (xy 161.512372 -278.494242)
			(xy 161.561227 -278.500174) (xy 161.608498 -278.513866) (xy 161.65296 -278.534964) (xy 161.693463 -278.56292)
			(xy 161.728956 -278.597012) (xy 161.758521 -278.636356) (xy 161.781392 -278.679933) (xy 161.796976 -278.726614)
			(xy 161.804871 -278.775191) (xy 161.805366 -278.799798) (xy 161.804871 -278.824405) (xy 161.804692 -278.825506)
			(xy 162.12337 -278.825506) (xy 162.12337 -278.77409) (xy 162.131413 -278.723308) (xy 162.147301 -278.674409)
			(xy 162.170644 -278.628597) (xy 162.200865 -278.587001) (xy 162.237221 -278.550645) (xy 162.278817 -278.520424)
			(xy 162.324629 -278.497081) (xy 162.373528 -278.481193) (xy 162.42431 -278.47315) (xy 162.475726 -278.47315)
			(xy 162.526508 -278.481193) (xy 162.575407 -278.497081) (xy 162.621219 -278.520424) (xy 162.662815 -278.550645)
			(xy 162.699171 -278.587001) (xy 162.729392 -278.628597) (xy 162.752735 -278.674409) (xy 162.768623 -278.723308)
			(xy 162.776666 -278.77409) (xy 162.77717 -278.799798) (xy 163.094174 -278.799798) (xy 163.098134 -278.750744)
			(xy 163.109911 -278.70296) (xy 163.129202 -278.657684) (xy 163.155505 -278.616088) (xy 163.18814 -278.579251)
			(xy 163.226261 -278.548126) (xy 163.268882 -278.523519) (xy 163.314898 -278.506067) (xy 163.363117 -278.496223)
			(xy 163.412292 -278.494242) (xy 163.461147 -278.500174) (xy 163.508418 -278.513866) (xy 163.55288 -278.534964)
			(xy 163.593383 -278.56292) (xy 163.628876 -278.597012) (xy 163.658441 -278.636356) (xy 163.681312 -278.679933)
			(xy 163.696896 -278.726614) (xy 163.704791 -278.775191) (xy 163.705286 -278.799798) (xy 163.704791 -278.824405)
			(xy 163.704612 -278.825506) (xy 164.02329 -278.825506) (xy 164.02329 -278.77409) (xy 164.031333 -278.723308)
			(xy 164.047221 -278.674409) (xy 164.070564 -278.628597) (xy 164.100785 -278.587001) (xy 164.137141 -278.550645)
			(xy 164.178737 -278.520424) (xy 164.224549 -278.497081) (xy 164.273448 -278.481193) (xy 164.32423 -278.47315)
			(xy 164.375646 -278.47315) (xy 164.426428 -278.481193) (xy 164.475327 -278.497081) (xy 164.521139 -278.520424)
			(xy 164.562735 -278.550645) (xy 164.599091 -278.587001) (xy 164.629312 -278.628597) (xy 164.652655 -278.674409)
			(xy 164.668543 -278.723308) (xy 164.676586 -278.77409) (xy 164.67709 -278.799798) (xy 164.994094 -278.799798)
			(xy 164.998054 -278.750744) (xy 165.009831 -278.70296) (xy 165.029122 -278.657684) (xy 165.055425 -278.616088)
			(xy 165.08806 -278.579251) (xy 165.126181 -278.548126) (xy 165.168802 -278.523519) (xy 165.214818 -278.506067)
			(xy 165.263037 -278.496223) (xy 165.312212 -278.494242) (xy 165.361067 -278.500174) (xy 165.408338 -278.513866)
			(xy 165.4528 -278.534964) (xy 165.493303 -278.56292) (xy 165.528796 -278.597012) (xy 165.558361 -278.636356)
			(xy 165.581232 -278.679933) (xy 165.596816 -278.726614) (xy 165.604711 -278.775191) (xy 165.605206 -278.799798)
			(xy 165.604711 -278.824405) (xy 165.604532 -278.825506) (xy 165.92321 -278.825506) (xy 165.92321 -278.77409)
			(xy 165.931253 -278.723308) (xy 165.947141 -278.674409) (xy 165.970484 -278.628597) (xy 166.000705 -278.587001)
			(xy 166.037061 -278.550645) (xy 166.078657 -278.520424) (xy 166.124469 -278.497081) (xy 166.173368 -278.481193)
			(xy 166.22415 -278.47315) (xy 166.275566 -278.47315) (xy 166.326348 -278.481193) (xy 166.375247 -278.497081)
			(xy 166.421059 -278.520424) (xy 166.462655 -278.550645) (xy 166.499011 -278.587001) (xy 166.529232 -278.628597)
			(xy 166.552575 -278.674409) (xy 166.568463 -278.723308) (xy 166.576506 -278.77409) (xy 166.57701 -278.799798)
			(xy 166.894268 -278.799798) (xy 166.898228 -278.750744) (xy 166.910005 -278.70296) (xy 166.929296 -278.657684)
			(xy 166.955599 -278.616088) (xy 166.988234 -278.579251) (xy 167.026355 -278.548126) (xy 167.068976 -278.523519)
			(xy 167.114992 -278.506067) (xy 167.163211 -278.496223) (xy 167.212386 -278.494242) (xy 167.261241 -278.500174)
			(xy 167.308512 -278.513866) (xy 167.352974 -278.534964) (xy 167.393477 -278.56292) (xy 167.42897 -278.597012)
			(xy 167.458535 -278.636356) (xy 167.481406 -278.679933) (xy 167.49699 -278.726614) (xy 167.504885 -278.775191)
			(xy 167.50538 -278.799798) (xy 167.504885 -278.824405) (xy 167.504706 -278.825506) (xy 167.823384 -278.825506)
			(xy 167.823384 -278.77409) (xy 167.831427 -278.723308) (xy 167.847315 -278.674409) (xy 167.870658 -278.628597)
			(xy 167.900879 -278.587001) (xy 167.937235 -278.550645) (xy 167.978831 -278.520424) (xy 168.024643 -278.497081)
			(xy 168.073542 -278.481193) (xy 168.124324 -278.47315) (xy 168.17574 -278.47315) (xy 168.226522 -278.481193)
			(xy 168.275421 -278.497081) (xy 168.321233 -278.520424) (xy 168.362829 -278.550645) (xy 168.399185 -278.587001)
			(xy 168.429406 -278.628597) (xy 168.452749 -278.674409) (xy 168.468637 -278.723308) (xy 168.47668 -278.77409)
			(xy 168.477184 -278.799798) (xy 168.794188 -278.799798) (xy 168.798148 -278.750744) (xy 168.809925 -278.70296)
			(xy 168.829216 -278.657684) (xy 168.855519 -278.616088) (xy 168.888154 -278.579251) (xy 168.926275 -278.548126)
			(xy 168.968896 -278.523519) (xy 169.014912 -278.506067) (xy 169.063131 -278.496223) (xy 169.112306 -278.494242)
			(xy 169.161161 -278.500174) (xy 169.208432 -278.513866) (xy 169.252894 -278.534964) (xy 169.293397 -278.56292)
			(xy 169.32889 -278.597012) (xy 169.358455 -278.636356) (xy 169.381326 -278.679933) (xy 169.39691 -278.726614)
			(xy 169.404805 -278.775191) (xy 169.4053 -278.799798) (xy 169.404805 -278.824405) (xy 169.404626 -278.825506)
			(xy 169.723304 -278.825506) (xy 169.723304 -278.77409) (xy 169.731347 -278.723308) (xy 169.747235 -278.674409)
			(xy 169.770578 -278.628597) (xy 169.800799 -278.587001) (xy 169.837155 -278.550645) (xy 169.878751 -278.520424)
			(xy 169.924563 -278.497081) (xy 169.973462 -278.481193) (xy 170.024244 -278.47315) (xy 170.07566 -278.47315)
			(xy 170.126442 -278.481193) (xy 170.175341 -278.497081) (xy 170.221153 -278.520424) (xy 170.262749 -278.550645)
			(xy 170.299105 -278.587001) (xy 170.329326 -278.628597) (xy 170.352669 -278.674409) (xy 170.368557 -278.723308)
			(xy 170.3766 -278.77409) (xy 170.377104 -278.799798) (xy 170.694108 -278.799798) (xy 170.698068 -278.750744)
			(xy 170.709845 -278.70296) (xy 170.729136 -278.657684) (xy 170.755439 -278.616088) (xy 170.788074 -278.579251)
			(xy 170.826195 -278.548126) (xy 170.868816 -278.523519) (xy 170.914832 -278.506067) (xy 170.963051 -278.496223)
			(xy 171.012226 -278.494242) (xy 171.061081 -278.500174) (xy 171.108352 -278.513866) (xy 171.152814 -278.534964)
			(xy 171.193317 -278.56292) (xy 171.22881 -278.597012) (xy 171.258375 -278.636356) (xy 171.281246 -278.679933)
			(xy 171.29683 -278.726614) (xy 171.304725 -278.775191) (xy 171.30522 -278.799798) (xy 171.304725 -278.824405)
			(xy 171.304546 -278.825506) (xy 171.623224 -278.825506) (xy 171.623224 -278.77409) (xy 171.631267 -278.723308)
			(xy 171.647155 -278.674409) (xy 171.670498 -278.628597) (xy 171.700719 -278.587001) (xy 171.737075 -278.550645)
			(xy 171.778671 -278.520424) (xy 171.824483 -278.497081) (xy 171.873382 -278.481193) (xy 171.924164 -278.47315)
			(xy 171.97558 -278.47315) (xy 172.026362 -278.481193) (xy 172.075261 -278.497081) (xy 172.121073 -278.520424)
			(xy 172.162669 -278.550645) (xy 172.199025 -278.587001) (xy 172.229246 -278.628597) (xy 172.252589 -278.674409)
			(xy 172.268477 -278.723308) (xy 172.27652 -278.77409) (xy 172.277024 -278.799798) (xy 172.594282 -278.799798)
			(xy 172.598242 -278.750744) (xy 172.610019 -278.70296) (xy 172.62931 -278.657684) (xy 172.655613 -278.616088)
			(xy 172.688248 -278.579251) (xy 172.726369 -278.548126) (xy 172.76899 -278.523519) (xy 172.815006 -278.506067)
			(xy 172.863225 -278.496223) (xy 172.9124 -278.494242) (xy 172.961255 -278.500174) (xy 173.008526 -278.513866)
			(xy 173.052988 -278.534964) (xy 173.093491 -278.56292) (xy 173.128984 -278.597012) (xy 173.158549 -278.636356)
			(xy 173.18142 -278.679933) (xy 173.197004 -278.726614) (xy 173.204899 -278.775191) (xy 173.205394 -278.799798)
			(xy 173.204899 -278.824405) (xy 173.20472 -278.825506) (xy 173.523398 -278.825506) (xy 173.523398 -278.77409)
			(xy 173.531441 -278.723308) (xy 173.547329 -278.674409) (xy 173.570672 -278.628597) (xy 173.600893 -278.587001)
			(xy 173.637249 -278.550645) (xy 173.678845 -278.520424) (xy 173.724657 -278.497081) (xy 173.773556 -278.481193)
			(xy 173.824338 -278.47315) (xy 173.875754 -278.47315) (xy 173.926536 -278.481193) (xy 173.975435 -278.497081)
			(xy 174.021247 -278.520424) (xy 174.062843 -278.550645) (xy 174.099199 -278.587001) (xy 174.12942 -278.628597)
			(xy 174.152763 -278.674409) (xy 174.168651 -278.723308) (xy 174.176694 -278.77409) (xy 174.177198 -278.799798)
			(xy 174.494202 -278.799798) (xy 174.498162 -278.750744) (xy 174.509939 -278.70296) (xy 174.52923 -278.657684)
			(xy 174.555533 -278.616088) (xy 174.588168 -278.579251) (xy 174.626289 -278.548126) (xy 174.66891 -278.523519)
			(xy 174.714926 -278.506067) (xy 174.763145 -278.496223) (xy 174.81232 -278.494242) (xy 174.861175 -278.500174)
			(xy 174.908446 -278.513866) (xy 174.952908 -278.534964) (xy 174.993411 -278.56292) (xy 175.028904 -278.597012)
			(xy 175.058469 -278.636356) (xy 175.08134 -278.679933) (xy 175.096924 -278.726614) (xy 175.104819 -278.775191)
			(xy 175.105314 -278.799798) (xy 175.104819 -278.824405) (xy 175.10464 -278.825506) (xy 175.423064 -278.825506)
			(xy 175.423064 -278.77409) (xy 175.431107 -278.723308) (xy 175.446995 -278.674409) (xy 175.470338 -278.628597)
			(xy 175.500559 -278.587001) (xy 175.536915 -278.550645) (xy 175.578511 -278.520424) (xy 175.624323 -278.497081)
			(xy 175.673222 -278.481193) (xy 175.724004 -278.47315) (xy 175.77542 -278.47315) (xy 175.826202 -278.481193)
			(xy 175.875101 -278.497081) (xy 175.920913 -278.520424) (xy 175.962509 -278.550645) (xy 175.998865 -278.587001)
			(xy 176.029086 -278.628597) (xy 176.052429 -278.674409) (xy 176.068317 -278.723308) (xy 176.07636 -278.77409)
			(xy 176.076864 -278.799798) (xy 176.394122 -278.799798) (xy 176.398082 -278.750744) (xy 176.409859 -278.70296)
			(xy 176.42915 -278.657684) (xy 176.455453 -278.616088) (xy 176.488088 -278.579251) (xy 176.526209 -278.548126)
			(xy 176.56883 -278.523519) (xy 176.614846 -278.506067) (xy 176.663065 -278.496223) (xy 176.71224 -278.494242)
			(xy 176.761095 -278.500174) (xy 176.808366 -278.513866) (xy 176.852828 -278.534964) (xy 176.893331 -278.56292)
			(xy 176.928824 -278.597012) (xy 176.958389 -278.636356) (xy 176.98126 -278.679933) (xy 176.996844 -278.726614)
			(xy 177.004739 -278.775191) (xy 177.005234 -278.799798) (xy 177.004739 -278.824405) (xy 177.00456 -278.825506)
			(xy 177.322984 -278.825506) (xy 177.322984 -278.77409) (xy 177.331027 -278.723308) (xy 177.346915 -278.674409)
			(xy 177.370258 -278.628597) (xy 177.400479 -278.587001) (xy 177.436835 -278.550645) (xy 177.478431 -278.520424)
			(xy 177.524243 -278.497081) (xy 177.573142 -278.481193) (xy 177.623924 -278.47315) (xy 177.67534 -278.47315)
			(xy 177.726122 -278.481193) (xy 177.775021 -278.497081) (xy 177.820833 -278.520424) (xy 177.862429 -278.550645)
			(xy 177.898785 -278.587001) (xy 177.929006 -278.628597) (xy 177.952349 -278.674409) (xy 177.968237 -278.723308)
			(xy 177.97628 -278.77409) (xy 177.976784 -278.799798) (xy 178.294042 -278.799798) (xy 178.298002 -278.750744)
			(xy 178.309779 -278.70296) (xy 178.32907 -278.657684) (xy 178.355373 -278.616088) (xy 178.388008 -278.579251)
			(xy 178.426129 -278.548126) (xy 178.46875 -278.523519) (xy 178.514766 -278.506067) (xy 178.562985 -278.496223)
			(xy 178.61216 -278.494242) (xy 178.661015 -278.500174) (xy 178.708286 -278.513866) (xy 178.752748 -278.534964)
			(xy 178.793251 -278.56292) (xy 178.828744 -278.597012) (xy 178.858309 -278.636356) (xy 178.88118 -278.679933)
			(xy 178.896764 -278.726614) (xy 178.904659 -278.775191) (xy 178.905154 -278.799798) (xy 178.904659 -278.824405)
			(xy 178.90448 -278.825506) (xy 179.223158 -278.825506) (xy 179.223158 -278.77409) (xy 179.231201 -278.723308)
			(xy 179.247089 -278.674409) (xy 179.270432 -278.628597) (xy 179.300653 -278.587001) (xy 179.337009 -278.550645)
			(xy 179.378605 -278.520424) (xy 179.424417 -278.497081) (xy 179.473316 -278.481193) (xy 179.524098 -278.47315)
			(xy 179.575514 -278.47315) (xy 179.626296 -278.481193) (xy 179.675195 -278.497081) (xy 179.721007 -278.520424)
			(xy 179.762603 -278.550645) (xy 179.798959 -278.587001) (xy 179.82918 -278.628597) (xy 179.852523 -278.674409)
			(xy 179.868411 -278.723308) (xy 179.876454 -278.77409) (xy 179.876958 -278.799798) (xy 180.194216 -278.799798)
			(xy 180.198176 -278.750744) (xy 180.209953 -278.70296) (xy 180.229244 -278.657684) (xy 180.255547 -278.616088)
			(xy 180.288182 -278.579251) (xy 180.326303 -278.548126) (xy 180.368924 -278.523519) (xy 180.41494 -278.506067)
			(xy 180.463159 -278.496223) (xy 180.512334 -278.494242) (xy 180.561189 -278.500174) (xy 180.60846 -278.513866)
			(xy 180.652922 -278.534964) (xy 180.693425 -278.56292) (xy 180.728918 -278.597012) (xy 180.758483 -278.636356)
			(xy 180.781354 -278.679933) (xy 180.796938 -278.726614) (xy 180.804833 -278.775191) (xy 180.805328 -278.799798)
			(xy 180.804833 -278.824405) (xy 180.804654 -278.825506) (xy 181.123078 -278.825506) (xy 181.123078 -278.77409)
			(xy 181.131121 -278.723308) (xy 181.147009 -278.674409) (xy 181.170352 -278.628597) (xy 181.200573 -278.587001)
			(xy 181.236929 -278.550645) (xy 181.278525 -278.520424) (xy 181.324337 -278.497081) (xy 181.373236 -278.481193)
			(xy 181.424018 -278.47315) (xy 181.475434 -278.47315) (xy 181.526216 -278.481193) (xy 181.575115 -278.497081)
			(xy 181.620927 -278.520424) (xy 181.662523 -278.550645) (xy 181.698879 -278.587001) (xy 181.7291 -278.628597)
			(xy 181.752443 -278.674409) (xy 181.768331 -278.723308) (xy 181.776374 -278.77409) (xy 181.776878 -278.799798)
			(xy 182.094136 -278.799798) (xy 182.098096 -278.750744) (xy 182.109873 -278.70296) (xy 182.129164 -278.657684)
			(xy 182.155467 -278.616088) (xy 182.188102 -278.579251) (xy 182.226223 -278.548126) (xy 182.268844 -278.523519)
			(xy 182.31486 -278.506067) (xy 182.363079 -278.496223) (xy 182.412254 -278.494242) (xy 182.461109 -278.500174)
			(xy 182.50838 -278.513866) (xy 182.552842 -278.534964) (xy 182.593345 -278.56292) (xy 182.628838 -278.597012)
			(xy 182.658403 -278.636356) (xy 182.681274 -278.679933) (xy 182.696858 -278.726614) (xy 182.704753 -278.775191)
			(xy 182.705248 -278.799798) (xy 182.704753 -278.824405) (xy 182.704574 -278.825506) (xy 183.022998 -278.825506)
			(xy 183.022998 -278.77409) (xy 183.031041 -278.723308) (xy 183.046929 -278.674409) (xy 183.070272 -278.628597)
			(xy 183.100493 -278.587001) (xy 183.136849 -278.550645) (xy 183.178445 -278.520424) (xy 183.224257 -278.497081)
			(xy 183.273156 -278.481193) (xy 183.323938 -278.47315) (xy 183.375354 -278.47315) (xy 183.426136 -278.481193)
			(xy 183.475035 -278.497081) (xy 183.520847 -278.520424) (xy 183.562443 -278.550645) (xy 183.598799 -278.587001)
			(xy 183.62902 -278.628597) (xy 183.652363 -278.674409) (xy 183.668251 -278.723308) (xy 183.676294 -278.77409)
			(xy 183.676798 -278.799798) (xy 183.994056 -278.799798) (xy 183.998016 -278.750744) (xy 184.009793 -278.70296)
			(xy 184.029084 -278.657684) (xy 184.055387 -278.616088) (xy 184.088022 -278.579251) (xy 184.126143 -278.548126)
			(xy 184.168764 -278.523519) (xy 184.21478 -278.506067) (xy 184.262999 -278.496223) (xy 184.312174 -278.494242)
			(xy 184.361029 -278.500174) (xy 184.4083 -278.513866) (xy 184.452762 -278.534964) (xy 184.493265 -278.56292)
			(xy 184.528758 -278.597012) (xy 184.558323 -278.636356) (xy 184.581194 -278.679933) (xy 184.596778 -278.726614)
			(xy 184.604673 -278.775191) (xy 184.605168 -278.799798) (xy 184.604673 -278.824405) (xy 184.604494 -278.825506)
			(xy 184.923172 -278.825506) (xy 184.923172 -278.77409) (xy 184.931215 -278.723308) (xy 184.947103 -278.674409)
			(xy 184.970446 -278.628597) (xy 185.000667 -278.587001) (xy 185.037023 -278.550645) (xy 185.078619 -278.520424)
			(xy 185.124431 -278.497081) (xy 185.17333 -278.481193) (xy 185.224112 -278.47315) (xy 185.275528 -278.47315)
			(xy 185.32631 -278.481193) (xy 185.375209 -278.497081) (xy 185.421021 -278.520424) (xy 185.462617 -278.550645)
			(xy 185.498973 -278.587001) (xy 185.529194 -278.628597) (xy 185.552537 -278.674409) (xy 185.568425 -278.723308)
			(xy 185.576468 -278.77409) (xy 185.576972 -278.799798) (xy 185.89423 -278.799798) (xy 185.89819 -278.750744)
			(xy 185.909967 -278.70296) (xy 185.929258 -278.657684) (xy 185.955561 -278.616088) (xy 185.988196 -278.579251)
			(xy 186.026317 -278.548126) (xy 186.068938 -278.523519) (xy 186.114954 -278.506067) (xy 186.163173 -278.496223)
			(xy 186.212348 -278.494242) (xy 186.261203 -278.500174) (xy 186.308474 -278.513866) (xy 186.352936 -278.534964)
			(xy 186.393439 -278.56292) (xy 186.428932 -278.597012) (xy 186.458497 -278.636356) (xy 186.481368 -278.679933)
			(xy 186.496952 -278.726614) (xy 186.504847 -278.775191) (xy 186.505342 -278.799798) (xy 186.504847 -278.824405)
			(xy 186.504668 -278.825506) (xy 186.823092 -278.825506) (xy 186.823092 -278.77409) (xy 186.831135 -278.723308)
			(xy 186.847023 -278.674409) (xy 186.870366 -278.628597) (xy 186.900587 -278.587001) (xy 186.936943 -278.550645)
			(xy 186.978539 -278.520424) (xy 187.024351 -278.497081) (xy 187.07325 -278.481193) (xy 187.124032 -278.47315)
			(xy 187.175448 -278.47315) (xy 187.22623 -278.481193) (xy 187.275129 -278.497081) (xy 187.320941 -278.520424)
			(xy 187.362537 -278.550645) (xy 187.398893 -278.587001) (xy 187.429114 -278.628597) (xy 187.452457 -278.674409)
			(xy 187.468345 -278.723308) (xy 187.476388 -278.77409) (xy 187.476892 -278.799798) (xy 187.79415 -278.799798)
			(xy 187.79811 -278.750744) (xy 187.809887 -278.70296) (xy 187.829178 -278.657684) (xy 187.855481 -278.616088)
			(xy 187.888116 -278.579251) (xy 187.926237 -278.548126) (xy 187.968858 -278.523519) (xy 188.014874 -278.506067)
			(xy 188.063093 -278.496223) (xy 188.112268 -278.494242) (xy 188.161123 -278.500174) (xy 188.208394 -278.513866)
			(xy 188.252856 -278.534964) (xy 188.293359 -278.56292) (xy 188.328852 -278.597012) (xy 188.358417 -278.636356)
			(xy 188.381288 -278.679933) (xy 188.396872 -278.726614) (xy 188.404767 -278.775191) (xy 188.405262 -278.799798)
			(xy 188.404767 -278.824405) (xy 188.404588 -278.825506) (xy 188.723012 -278.825506) (xy 188.723012 -278.77409)
			(xy 188.731055 -278.723308) (xy 188.746943 -278.674409) (xy 188.770286 -278.628597) (xy 188.800507 -278.587001)
			(xy 188.836863 -278.550645) (xy 188.878459 -278.520424) (xy 188.924271 -278.497081) (xy 188.97317 -278.481193)
			(xy 189.023952 -278.47315) (xy 189.075368 -278.47315) (xy 189.12615 -278.481193) (xy 189.175049 -278.497081)
			(xy 189.220861 -278.520424) (xy 189.262457 -278.550645) (xy 189.298813 -278.587001) (xy 189.329034 -278.628597)
			(xy 189.352377 -278.674409) (xy 189.368265 -278.723308) (xy 189.376308 -278.77409) (xy 189.376812 -278.799798)
			(xy 189.69407 -278.799798) (xy 189.69803 -278.750744) (xy 189.709807 -278.70296) (xy 189.729098 -278.657684)
			(xy 189.755401 -278.616088) (xy 189.788036 -278.579251) (xy 189.826157 -278.548126) (xy 189.868778 -278.523519)
			(xy 189.914794 -278.506067) (xy 189.963013 -278.496223) (xy 190.012188 -278.494242) (xy 190.061043 -278.500174)
			(xy 190.108314 -278.513866) (xy 190.152776 -278.534964) (xy 190.193279 -278.56292) (xy 190.228772 -278.597012)
			(xy 190.258337 -278.636356) (xy 190.281208 -278.679933) (xy 190.296792 -278.726614) (xy 190.304687 -278.775191)
			(xy 190.305182 -278.799798) (xy 190.304687 -278.824405) (xy 190.304508 -278.825506) (xy 190.623186 -278.825506)
			(xy 190.623186 -278.77409) (xy 190.631229 -278.723308) (xy 190.647117 -278.674409) (xy 190.67046 -278.628597)
			(xy 190.700681 -278.587001) (xy 190.737037 -278.550645) (xy 190.778633 -278.520424) (xy 190.824445 -278.497081)
			(xy 190.873344 -278.481193) (xy 190.924126 -278.47315) (xy 190.975542 -278.47315) (xy 191.026324 -278.481193)
			(xy 191.075223 -278.497081) (xy 191.121035 -278.520424) (xy 191.162631 -278.550645) (xy 191.198987 -278.587001)
			(xy 191.229208 -278.628597) (xy 191.252551 -278.674409) (xy 191.268439 -278.723308) (xy 191.276482 -278.77409)
			(xy 191.276986 -278.799798) (xy 191.594244 -278.799798) (xy 191.598204 -278.750744) (xy 191.609981 -278.70296)
			(xy 191.629272 -278.657684) (xy 191.655575 -278.616088) (xy 191.68821 -278.579251) (xy 191.726331 -278.548126)
			(xy 191.768952 -278.523519) (xy 191.814968 -278.506067) (xy 191.863187 -278.496223) (xy 191.912362 -278.494242)
			(xy 191.961217 -278.500174) (xy 192.008488 -278.513866) (xy 192.05295 -278.534964) (xy 192.093453 -278.56292)
			(xy 192.128946 -278.597012) (xy 192.158511 -278.636356) (xy 192.181382 -278.679933) (xy 192.196966 -278.726614)
			(xy 192.204861 -278.775191) (xy 192.205356 -278.799798) (xy 192.204861 -278.824405) (xy 192.204682 -278.825506)
			(xy 192.523106 -278.825506) (xy 192.523106 -278.77409) (xy 192.531149 -278.723308) (xy 192.547037 -278.674409)
			(xy 192.57038 -278.628597) (xy 192.600601 -278.587001) (xy 192.636957 -278.550645) (xy 192.678553 -278.520424)
			(xy 192.724365 -278.497081) (xy 192.773264 -278.481193) (xy 192.824046 -278.47315) (xy 192.875462 -278.47315)
			(xy 192.926244 -278.481193) (xy 192.975143 -278.497081) (xy 193.020955 -278.520424) (xy 193.062551 -278.550645)
			(xy 193.098907 -278.587001) (xy 193.129128 -278.628597) (xy 193.152471 -278.674409) (xy 193.168359 -278.723308)
			(xy 193.176402 -278.77409) (xy 193.176906 -278.799798) (xy 193.494164 -278.799798) (xy 193.498124 -278.750744)
			(xy 193.509901 -278.70296) (xy 193.529192 -278.657684) (xy 193.555495 -278.616088) (xy 193.58813 -278.579251)
			(xy 193.626251 -278.548126) (xy 193.668872 -278.523519) (xy 193.714888 -278.506067) (xy 193.763107 -278.496223)
			(xy 193.812282 -278.494242) (xy 193.861137 -278.500174) (xy 193.908408 -278.513866) (xy 193.95287 -278.534964)
			(xy 193.993373 -278.56292) (xy 194.028866 -278.597012) (xy 194.058431 -278.636356) (xy 194.081302 -278.679933)
			(xy 194.096886 -278.726614) (xy 194.104781 -278.775191) (xy 194.105276 -278.799798) (xy 194.104781 -278.824405)
			(xy 194.104602 -278.825506) (xy 194.423026 -278.825506) (xy 194.423026 -278.77409) (xy 194.431069 -278.723308)
			(xy 194.446957 -278.674409) (xy 194.4703 -278.628597) (xy 194.500521 -278.587001) (xy 194.536877 -278.550645)
			(xy 194.578473 -278.520424) (xy 194.624285 -278.497081) (xy 194.673184 -278.481193) (xy 194.723966 -278.47315)
			(xy 194.775382 -278.47315) (xy 194.826164 -278.481193) (xy 194.875063 -278.497081) (xy 194.920875 -278.520424)
			(xy 194.962471 -278.550645) (xy 194.998827 -278.587001) (xy 195.029048 -278.628597) (xy 195.052391 -278.674409)
			(xy 195.068279 -278.723308) (xy 195.076322 -278.77409) (xy 195.076826 -278.799798) (xy 195.394084 -278.799798)
			(xy 195.398044 -278.750744) (xy 195.409821 -278.70296) (xy 195.429112 -278.657684) (xy 195.455415 -278.616088)
			(xy 195.48805 -278.579251) (xy 195.526171 -278.548126) (xy 195.568792 -278.523519) (xy 195.614808 -278.506067)
			(xy 195.663027 -278.496223) (xy 195.712202 -278.494242) (xy 195.761057 -278.500174) (xy 195.808328 -278.513866)
			(xy 195.85279 -278.534964) (xy 195.893293 -278.56292) (xy 195.928786 -278.597012) (xy 195.958351 -278.636356)
			(xy 195.981222 -278.679933) (xy 195.996806 -278.726614) (xy 196.004701 -278.775191) (xy 196.005196 -278.799798)
			(xy 196.004701 -278.824405) (xy 196.004522 -278.825506) (xy 196.3232 -278.825506) (xy 196.3232 -278.77409)
			(xy 196.331243 -278.723308) (xy 196.347131 -278.674409) (xy 196.370474 -278.628597) (xy 196.400695 -278.587001)
			(xy 196.437051 -278.550645) (xy 196.478647 -278.520424) (xy 196.524459 -278.497081) (xy 196.573358 -278.481193)
			(xy 196.62414 -278.47315) (xy 196.675556 -278.47315) (xy 196.726338 -278.481193) (xy 196.775237 -278.497081)
			(xy 196.821049 -278.520424) (xy 196.862645 -278.550645) (xy 196.899001 -278.587001) (xy 196.929222 -278.628597)
			(xy 196.952565 -278.674409) (xy 196.968453 -278.723308) (xy 196.976496 -278.77409) (xy 196.977 -278.799798)
			(xy 197.294258 -278.799798) (xy 197.298218 -278.750744) (xy 197.309995 -278.70296) (xy 197.329286 -278.657684)
			(xy 197.355589 -278.616088) (xy 197.388224 -278.579251) (xy 197.426345 -278.548126) (xy 197.468966 -278.523519)
			(xy 197.514982 -278.506067) (xy 197.563201 -278.496223) (xy 197.612376 -278.494242) (xy 197.661231 -278.500174)
			(xy 197.708502 -278.513866) (xy 197.752964 -278.534964) (xy 197.793467 -278.56292) (xy 197.82896 -278.597012)
			(xy 197.858525 -278.636356) (xy 197.881396 -278.679933) (xy 197.89698 -278.726614) (xy 197.904875 -278.775191)
			(xy 197.90537 -278.799798) (xy 198.244218 -278.799798) (xy 198.248178 -278.750744) (xy 198.259955 -278.70296)
			(xy 198.279246 -278.657684) (xy 198.305549 -278.616088) (xy 198.338184 -278.579251) (xy 198.376305 -278.548126)
			(xy 198.418926 -278.523519) (xy 198.464942 -278.506067) (xy 198.513161 -278.496223) (xy 198.562336 -278.494242)
			(xy 198.611191 -278.500174) (xy 198.658462 -278.513866) (xy 198.702924 -278.534964) (xy 198.743427 -278.56292)
			(xy 198.77892 -278.597012) (xy 198.808485 -278.636356) (xy 198.831356 -278.679933) (xy 198.84694 -278.726614)
			(xy 198.854835 -278.775191) (xy 198.85533 -278.799798) (xy 198.854835 -278.824405) (xy 198.84694 -278.872982)
			(xy 198.831356 -278.919663) (xy 198.808485 -278.96324) (xy 198.77892 -279.002584) (xy 198.743427 -279.036676)
			(xy 198.702924 -279.064632) (xy 198.679186 -279.075896) (xy 224.380042 -279.075896) (xy 224.384113 -279.020274)
			(xy 224.396239 -278.965837) (xy 224.416162 -278.913746) (xy 224.443458 -278.865111) (xy 224.477544 -278.820968)
			(xy 224.517693 -278.782259) (xy 224.563051 -278.749808) (xy 224.612651 -278.724307) (xy 224.665435 -278.7063)
			(xy 224.720278 -278.69617) (xy 224.776012 -278.694133) (xy 224.831449 -278.700233) (xy 224.885406 -278.714339)
			(xy 224.936735 -278.736151) (xy 224.984341 -278.765205) (xy 225.027209 -278.80088) (xy 225.064426 -278.842417)
			(xy 225.095199 -278.88893) (xy 225.118871 -278.939427) (xy 225.134939 -278.992834) (xy 225.143059 -279.04801)
			(xy 225.143568 -279.075896) (xy 225.143059 -279.103782) (xy 225.134939 -279.158958) (xy 225.118871 -279.212365)
			(xy 225.095199 -279.262862) (xy 225.064426 -279.309375) (xy 225.027209 -279.350912) (xy 224.984341 -279.386587)
			(xy 224.936735 -279.415641) (xy 224.885406 -279.437453) (xy 224.831449 -279.451559) (xy 224.776012 -279.457659)
			(xy 224.720278 -279.455622) (xy 224.665435 -279.445492) (xy 224.612651 -279.427485) (xy 224.563051 -279.401984)
			(xy 224.517693 -279.369533) (xy 224.477544 -279.330824) (xy 224.443458 -279.286681) (xy 224.416162 -279.238046)
			(xy 224.396239 -279.185955) (xy 224.384113 -279.131518) (xy 224.380042 -279.075896) (xy 198.679186 -279.075896)
			(xy 198.658462 -279.08573) (xy 198.611191 -279.099422) (xy 198.562336 -279.105354) (xy 198.513161 -279.103373)
			(xy 198.464942 -279.093529) (xy 198.418926 -279.076077) (xy 198.376305 -279.05147) (xy 198.338184 -279.020345)
			(xy 198.305549 -278.983508) (xy 198.279246 -278.941912) (xy 198.259955 -278.896636) (xy 198.248178 -278.848852)
			(xy 198.244218 -278.799798) (xy 197.90537 -278.799798) (xy 197.904875 -278.824405) (xy 197.89698 -278.872982)
			(xy 197.881396 -278.919663) (xy 197.858525 -278.96324) (xy 197.82896 -279.002584) (xy 197.793467 -279.036676)
			(xy 197.752964 -279.064632) (xy 197.708502 -279.08573) (xy 197.661231 -279.099422) (xy 197.612376 -279.105354)
			(xy 197.563201 -279.103373) (xy 197.514982 -279.093529) (xy 197.468966 -279.076077) (xy 197.426345 -279.05147)
			(xy 197.388224 -279.020345) (xy 197.355589 -278.983508) (xy 197.329286 -278.941912) (xy 197.309995 -278.896636)
			(xy 197.298218 -278.848852) (xy 197.294258 -278.799798) (xy 196.977 -278.799798) (xy 196.976496 -278.825506)
			(xy 196.968453 -278.876288) (xy 196.952565 -278.925187) (xy 196.929222 -278.970999) (xy 196.899001 -279.012595)
			(xy 196.862645 -279.048951) (xy 196.821049 -279.079172) (xy 196.775237 -279.102515) (xy 196.726338 -279.118403)
			(xy 196.675556 -279.126446) (xy 196.62414 -279.126446) (xy 196.573358 -279.118403) (xy 196.524459 -279.102515)
			(xy 196.478647 -279.079172) (xy 196.437051 -279.048951) (xy 196.400695 -279.012595) (xy 196.370474 -278.970999)
			(xy 196.347131 -278.925187) (xy 196.331243 -278.876288) (xy 196.3232 -278.825506) (xy 196.004522 -278.825506)
			(xy 195.996806 -278.872982) (xy 195.981222 -278.919663) (xy 195.958351 -278.96324) (xy 195.928786 -279.002584)
			(xy 195.893293 -279.036676) (xy 195.85279 -279.064632) (xy 195.808328 -279.08573) (xy 195.761057 -279.099422)
			(xy 195.712202 -279.105354) (xy 195.663027 -279.103373) (xy 195.614808 -279.093529) (xy 195.568792 -279.076077)
			(xy 195.526171 -279.05147) (xy 195.48805 -279.020345) (xy 195.455415 -278.983508) (xy 195.429112 -278.941912)
			(xy 195.409821 -278.896636) (xy 195.398044 -278.848852) (xy 195.394084 -278.799798) (xy 195.076826 -278.799798)
			(xy 195.076322 -278.825506) (xy 195.068279 -278.876288) (xy 195.052391 -278.925187) (xy 195.029048 -278.970999)
			(xy 194.998827 -279.012595) (xy 194.962471 -279.048951) (xy 194.920875 -279.079172) (xy 194.875063 -279.102515)
			(xy 194.826164 -279.118403) (xy 194.775382 -279.126446) (xy 194.723966 -279.126446) (xy 194.673184 -279.118403)
			(xy 194.624285 -279.102515) (xy 194.578473 -279.079172) (xy 194.536877 -279.048951) (xy 194.500521 -279.012595)
			(xy 194.4703 -278.970999) (xy 194.446957 -278.925187) (xy 194.431069 -278.876288) (xy 194.423026 -278.825506)
			(xy 194.104602 -278.825506) (xy 194.096886 -278.872982) (xy 194.081302 -278.919663) (xy 194.058431 -278.96324)
			(xy 194.028866 -279.002584) (xy 193.993373 -279.036676) (xy 193.95287 -279.064632) (xy 193.908408 -279.08573)
			(xy 193.861137 -279.099422) (xy 193.812282 -279.105354) (xy 193.763107 -279.103373) (xy 193.714888 -279.093529)
			(xy 193.668872 -279.076077) (xy 193.626251 -279.05147) (xy 193.58813 -279.020345) (xy 193.555495 -278.983508)
			(xy 193.529192 -278.941912) (xy 193.509901 -278.896636) (xy 193.498124 -278.848852) (xy 193.494164 -278.799798)
			(xy 193.176906 -278.799798) (xy 193.176402 -278.825506) (xy 193.168359 -278.876288) (xy 193.152471 -278.925187)
			(xy 193.129128 -278.970999) (xy 193.098907 -279.012595) (xy 193.062551 -279.048951) (xy 193.020955 -279.079172)
			(xy 192.975143 -279.102515) (xy 192.926244 -279.118403) (xy 192.875462 -279.126446) (xy 192.824046 -279.126446)
			(xy 192.773264 -279.118403) (xy 192.724365 -279.102515) (xy 192.678553 -279.079172) (xy 192.636957 -279.048951)
			(xy 192.600601 -279.012595) (xy 192.57038 -278.970999) (xy 192.547037 -278.925187) (xy 192.531149 -278.876288)
			(xy 192.523106 -278.825506) (xy 192.204682 -278.825506) (xy 192.196966 -278.872982) (xy 192.181382 -278.919663)
			(xy 192.158511 -278.96324) (xy 192.128946 -279.002584) (xy 192.093453 -279.036676) (xy 192.05295 -279.064632)
			(xy 192.008488 -279.08573) (xy 191.961217 -279.099422) (xy 191.912362 -279.105354) (xy 191.863187 -279.103373)
			(xy 191.814968 -279.093529) (xy 191.768952 -279.076077) (xy 191.726331 -279.05147) (xy 191.68821 -279.020345)
			(xy 191.655575 -278.983508) (xy 191.629272 -278.941912) (xy 191.609981 -278.896636) (xy 191.598204 -278.848852)
			(xy 191.594244 -278.799798) (xy 191.276986 -278.799798) (xy 191.276482 -278.825506) (xy 191.268439 -278.876288)
			(xy 191.252551 -278.925187) (xy 191.229208 -278.970999) (xy 191.198987 -279.012595) (xy 191.162631 -279.048951)
			(xy 191.121035 -279.079172) (xy 191.075223 -279.102515) (xy 191.026324 -279.118403) (xy 190.975542 -279.126446)
			(xy 190.924126 -279.126446) (xy 190.873344 -279.118403) (xy 190.824445 -279.102515) (xy 190.778633 -279.079172)
			(xy 190.737037 -279.048951) (xy 190.700681 -279.012595) (xy 190.67046 -278.970999) (xy 190.647117 -278.925187)
			(xy 190.631229 -278.876288) (xy 190.623186 -278.825506) (xy 190.304508 -278.825506) (xy 190.296792 -278.872982)
			(xy 190.281208 -278.919663) (xy 190.258337 -278.96324) (xy 190.228772 -279.002584) (xy 190.193279 -279.036676)
			(xy 190.152776 -279.064632) (xy 190.108314 -279.08573) (xy 190.061043 -279.099422) (xy 190.012188 -279.105354)
			(xy 189.963013 -279.103373) (xy 189.914794 -279.093529) (xy 189.868778 -279.076077) (xy 189.826157 -279.05147)
			(xy 189.788036 -279.020345) (xy 189.755401 -278.983508) (xy 189.729098 -278.941912) (xy 189.709807 -278.896636)
			(xy 189.69803 -278.848852) (xy 189.69407 -278.799798) (xy 189.376812 -278.799798) (xy 189.376308 -278.825506)
			(xy 189.368265 -278.876288) (xy 189.352377 -278.925187) (xy 189.329034 -278.970999) (xy 189.298813 -279.012595)
			(xy 189.262457 -279.048951) (xy 189.220861 -279.079172) (xy 189.175049 -279.102515) (xy 189.12615 -279.118403)
			(xy 189.075368 -279.126446) (xy 189.023952 -279.126446) (xy 188.97317 -279.118403) (xy 188.924271 -279.102515)
			(xy 188.878459 -279.079172) (xy 188.836863 -279.048951) (xy 188.800507 -279.012595) (xy 188.770286 -278.970999)
			(xy 188.746943 -278.925187) (xy 188.731055 -278.876288) (xy 188.723012 -278.825506) (xy 188.404588 -278.825506)
			(xy 188.396872 -278.872982) (xy 188.381288 -278.919663) (xy 188.358417 -278.96324) (xy 188.328852 -279.002584)
			(xy 188.293359 -279.036676) (xy 188.252856 -279.064632) (xy 188.208394 -279.08573) (xy 188.161123 -279.099422)
			(xy 188.112268 -279.105354) (xy 188.063093 -279.103373) (xy 188.014874 -279.093529) (xy 187.968858 -279.076077)
			(xy 187.926237 -279.05147) (xy 187.888116 -279.020345) (xy 187.855481 -278.983508) (xy 187.829178 -278.941912)
			(xy 187.809887 -278.896636) (xy 187.79811 -278.848852) (xy 187.79415 -278.799798) (xy 187.476892 -278.799798)
			(xy 187.476388 -278.825506) (xy 187.468345 -278.876288) (xy 187.452457 -278.925187) (xy 187.429114 -278.970999)
			(xy 187.398893 -279.012595) (xy 187.362537 -279.048951) (xy 187.320941 -279.079172) (xy 187.275129 -279.102515)
			(xy 187.22623 -279.118403) (xy 187.175448 -279.126446) (xy 187.124032 -279.126446) (xy 187.07325 -279.118403)
			(xy 187.024351 -279.102515) (xy 186.978539 -279.079172) (xy 186.936943 -279.048951) (xy 186.900587 -279.012595)
			(xy 186.870366 -278.970999) (xy 186.847023 -278.925187) (xy 186.831135 -278.876288) (xy 186.823092 -278.825506)
			(xy 186.504668 -278.825506) (xy 186.496952 -278.872982) (xy 186.481368 -278.919663) (xy 186.458497 -278.96324)
			(xy 186.428932 -279.002584) (xy 186.393439 -279.036676) (xy 186.352936 -279.064632) (xy 186.308474 -279.08573)
			(xy 186.261203 -279.099422) (xy 186.212348 -279.105354) (xy 186.163173 -279.103373) (xy 186.114954 -279.093529)
			(xy 186.068938 -279.076077) (xy 186.026317 -279.05147) (xy 185.988196 -279.020345) (xy 185.955561 -278.983508)
			(xy 185.929258 -278.941912) (xy 185.909967 -278.896636) (xy 185.89819 -278.848852) (xy 185.89423 -278.799798)
			(xy 185.576972 -278.799798) (xy 185.576468 -278.825506) (xy 185.568425 -278.876288) (xy 185.552537 -278.925187)
			(xy 185.529194 -278.970999) (xy 185.498973 -279.012595) (xy 185.462617 -279.048951) (xy 185.421021 -279.079172)
			(xy 185.375209 -279.102515) (xy 185.32631 -279.118403) (xy 185.275528 -279.126446) (xy 185.224112 -279.126446)
			(xy 185.17333 -279.118403) (xy 185.124431 -279.102515) (xy 185.078619 -279.079172) (xy 185.037023 -279.048951)
			(xy 185.000667 -279.012595) (xy 184.970446 -278.970999) (xy 184.947103 -278.925187) (xy 184.931215 -278.876288)
			(xy 184.923172 -278.825506) (xy 184.604494 -278.825506) (xy 184.596778 -278.872982) (xy 184.581194 -278.919663)
			(xy 184.558323 -278.96324) (xy 184.528758 -279.002584) (xy 184.493265 -279.036676) (xy 184.452762 -279.064632)
			(xy 184.4083 -279.08573) (xy 184.361029 -279.099422) (xy 184.312174 -279.105354) (xy 184.262999 -279.103373)
			(xy 184.21478 -279.093529) (xy 184.168764 -279.076077) (xy 184.126143 -279.05147) (xy 184.088022 -279.020345)
			(xy 184.055387 -278.983508) (xy 184.029084 -278.941912) (xy 184.009793 -278.896636) (xy 183.998016 -278.848852)
			(xy 183.994056 -278.799798) (xy 183.676798 -278.799798) (xy 183.676294 -278.825506) (xy 183.668251 -278.876288)
			(xy 183.652363 -278.925187) (xy 183.62902 -278.970999) (xy 183.598799 -279.012595) (xy 183.562443 -279.048951)
			(xy 183.520847 -279.079172) (xy 183.475035 -279.102515) (xy 183.426136 -279.118403) (xy 183.375354 -279.126446)
			(xy 183.323938 -279.126446) (xy 183.273156 -279.118403) (xy 183.224257 -279.102515) (xy 183.178445 -279.079172)
			(xy 183.136849 -279.048951) (xy 183.100493 -279.012595) (xy 183.070272 -278.970999) (xy 183.046929 -278.925187)
			(xy 183.031041 -278.876288) (xy 183.022998 -278.825506) (xy 182.704574 -278.825506) (xy 182.696858 -278.872982)
			(xy 182.681274 -278.919663) (xy 182.658403 -278.96324) (xy 182.628838 -279.002584) (xy 182.593345 -279.036676)
			(xy 182.552842 -279.064632) (xy 182.50838 -279.08573) (xy 182.461109 -279.099422) (xy 182.412254 -279.105354)
			(xy 182.363079 -279.103373) (xy 182.31486 -279.093529) (xy 182.268844 -279.076077) (xy 182.226223 -279.05147)
			(xy 182.188102 -279.020345) (xy 182.155467 -278.983508) (xy 182.129164 -278.941912) (xy 182.109873 -278.896636)
			(xy 182.098096 -278.848852) (xy 182.094136 -278.799798) (xy 181.776878 -278.799798) (xy 181.776374 -278.825506)
			(xy 181.768331 -278.876288) (xy 181.752443 -278.925187) (xy 181.7291 -278.970999) (xy 181.698879 -279.012595)
			(xy 181.662523 -279.048951) (xy 181.620927 -279.079172) (xy 181.575115 -279.102515) (xy 181.526216 -279.118403)
			(xy 181.475434 -279.126446) (xy 181.424018 -279.126446) (xy 181.373236 -279.118403) (xy 181.324337 -279.102515)
			(xy 181.278525 -279.079172) (xy 181.236929 -279.048951) (xy 181.200573 -279.012595) (xy 181.170352 -278.970999)
			(xy 181.147009 -278.925187) (xy 181.131121 -278.876288) (xy 181.123078 -278.825506) (xy 180.804654 -278.825506)
			(xy 180.796938 -278.872982) (xy 180.781354 -278.919663) (xy 180.758483 -278.96324) (xy 180.728918 -279.002584)
			(xy 180.693425 -279.036676) (xy 180.652922 -279.064632) (xy 180.60846 -279.08573) (xy 180.561189 -279.099422)
			(xy 180.512334 -279.105354) (xy 180.463159 -279.103373) (xy 180.41494 -279.093529) (xy 180.368924 -279.076077)
			(xy 180.326303 -279.05147) (xy 180.288182 -279.020345) (xy 180.255547 -278.983508) (xy 180.229244 -278.941912)
			(xy 180.209953 -278.896636) (xy 180.198176 -278.848852) (xy 180.194216 -278.799798) (xy 179.876958 -278.799798)
			(xy 179.876454 -278.825506) (xy 179.868411 -278.876288) (xy 179.852523 -278.925187) (xy 179.82918 -278.970999)
			(xy 179.798959 -279.012595) (xy 179.762603 -279.048951) (xy 179.721007 -279.079172) (xy 179.675195 -279.102515)
			(xy 179.626296 -279.118403) (xy 179.575514 -279.126446) (xy 179.524098 -279.126446) (xy 179.473316 -279.118403)
			(xy 179.424417 -279.102515) (xy 179.378605 -279.079172) (xy 179.337009 -279.048951) (xy 179.300653 -279.012595)
			(xy 179.270432 -278.970999) (xy 179.247089 -278.925187) (xy 179.231201 -278.876288) (xy 179.223158 -278.825506)
			(xy 178.90448 -278.825506) (xy 178.896764 -278.872982) (xy 178.88118 -278.919663) (xy 178.858309 -278.96324)
			(xy 178.828744 -279.002584) (xy 178.793251 -279.036676) (xy 178.752748 -279.064632) (xy 178.708286 -279.08573)
			(xy 178.661015 -279.099422) (xy 178.61216 -279.105354) (xy 178.562985 -279.103373) (xy 178.514766 -279.093529)
			(xy 178.46875 -279.076077) (xy 178.426129 -279.05147) (xy 178.388008 -279.020345) (xy 178.355373 -278.983508)
			(xy 178.32907 -278.941912) (xy 178.309779 -278.896636) (xy 178.298002 -278.848852) (xy 178.294042 -278.799798)
			(xy 177.976784 -278.799798) (xy 177.97628 -278.825506) (xy 177.968237 -278.876288) (xy 177.952349 -278.925187)
			(xy 177.929006 -278.970999) (xy 177.898785 -279.012595) (xy 177.862429 -279.048951) (xy 177.820833 -279.079172)
			(xy 177.775021 -279.102515) (xy 177.726122 -279.118403) (xy 177.67534 -279.126446) (xy 177.623924 -279.126446)
			(xy 177.573142 -279.118403) (xy 177.524243 -279.102515) (xy 177.478431 -279.079172) (xy 177.436835 -279.048951)
			(xy 177.400479 -279.012595) (xy 177.370258 -278.970999) (xy 177.346915 -278.925187) (xy 177.331027 -278.876288)
			(xy 177.322984 -278.825506) (xy 177.00456 -278.825506) (xy 176.996844 -278.872982) (xy 176.98126 -278.919663)
			(xy 176.958389 -278.96324) (xy 176.928824 -279.002584) (xy 176.893331 -279.036676) (xy 176.852828 -279.064632)
			(xy 176.808366 -279.08573) (xy 176.761095 -279.099422) (xy 176.71224 -279.105354) (xy 176.663065 -279.103373)
			(xy 176.614846 -279.093529) (xy 176.56883 -279.076077) (xy 176.526209 -279.05147) (xy 176.488088 -279.020345)
			(xy 176.455453 -278.983508) (xy 176.42915 -278.941912) (xy 176.409859 -278.896636) (xy 176.398082 -278.848852)
			(xy 176.394122 -278.799798) (xy 176.076864 -278.799798) (xy 176.07636 -278.825506) (xy 176.068317 -278.876288)
			(xy 176.052429 -278.925187) (xy 176.029086 -278.970999) (xy 175.998865 -279.012595) (xy 175.962509 -279.048951)
			(xy 175.920913 -279.079172) (xy 175.875101 -279.102515) (xy 175.826202 -279.118403) (xy 175.77542 -279.126446)
			(xy 175.724004 -279.126446) (xy 175.673222 -279.118403) (xy 175.624323 -279.102515) (xy 175.578511 -279.079172)
			(xy 175.536915 -279.048951) (xy 175.500559 -279.012595) (xy 175.470338 -278.970999) (xy 175.446995 -278.925187)
			(xy 175.431107 -278.876288) (xy 175.423064 -278.825506) (xy 175.10464 -278.825506) (xy 175.096924 -278.872982)
			(xy 175.08134 -278.919663) (xy 175.058469 -278.96324) (xy 175.028904 -279.002584) (xy 174.993411 -279.036676)
			(xy 174.952908 -279.064632) (xy 174.908446 -279.08573) (xy 174.861175 -279.099422) (xy 174.81232 -279.105354)
			(xy 174.763145 -279.103373) (xy 174.714926 -279.093529) (xy 174.66891 -279.076077) (xy 174.626289 -279.05147)
			(xy 174.588168 -279.020345) (xy 174.555533 -278.983508) (xy 174.52923 -278.941912) (xy 174.509939 -278.896636)
			(xy 174.498162 -278.848852) (xy 174.494202 -278.799798) (xy 174.177198 -278.799798) (xy 174.176694 -278.825506)
			(xy 174.168651 -278.876288) (xy 174.152763 -278.925187) (xy 174.12942 -278.970999) (xy 174.099199 -279.012595)
			(xy 174.062843 -279.048951) (xy 174.021247 -279.079172) (xy 173.975435 -279.102515) (xy 173.926536 -279.118403)
			(xy 173.875754 -279.126446) (xy 173.824338 -279.126446) (xy 173.773556 -279.118403) (xy 173.724657 -279.102515)
			(xy 173.678845 -279.079172) (xy 173.637249 -279.048951) (xy 173.600893 -279.012595) (xy 173.570672 -278.970999)
			(xy 173.547329 -278.925187) (xy 173.531441 -278.876288) (xy 173.523398 -278.825506) (xy 173.20472 -278.825506)
			(xy 173.197004 -278.872982) (xy 173.18142 -278.919663) (xy 173.158549 -278.96324) (xy 173.128984 -279.002584)
			(xy 173.093491 -279.036676) (xy 173.052988 -279.064632) (xy 173.008526 -279.08573) (xy 172.961255 -279.099422)
			(xy 172.9124 -279.105354) (xy 172.863225 -279.103373) (xy 172.815006 -279.093529) (xy 172.76899 -279.076077)
			(xy 172.726369 -279.05147) (xy 172.688248 -279.020345) (xy 172.655613 -278.983508) (xy 172.62931 -278.941912)
			(xy 172.610019 -278.896636) (xy 172.598242 -278.848852) (xy 172.594282 -278.799798) (xy 172.277024 -278.799798)
			(xy 172.27652 -278.825506) (xy 172.268477 -278.876288) (xy 172.252589 -278.925187) (xy 172.229246 -278.970999)
			(xy 172.199025 -279.012595) (xy 172.162669 -279.048951) (xy 172.121073 -279.079172) (xy 172.075261 -279.102515)
			(xy 172.026362 -279.118403) (xy 171.97558 -279.126446) (xy 171.924164 -279.126446) (xy 171.873382 -279.118403)
			(xy 171.824483 -279.102515) (xy 171.778671 -279.079172) (xy 171.737075 -279.048951) (xy 171.700719 -279.012595)
			(xy 171.670498 -278.970999) (xy 171.647155 -278.925187) (xy 171.631267 -278.876288) (xy 171.623224 -278.825506)
			(xy 171.304546 -278.825506) (xy 171.29683 -278.872982) (xy 171.281246 -278.919663) (xy 171.258375 -278.96324)
			(xy 171.22881 -279.002584) (xy 171.193317 -279.036676) (xy 171.152814 -279.064632) (xy 171.108352 -279.08573)
			(xy 171.061081 -279.099422) (xy 171.012226 -279.105354) (xy 170.963051 -279.103373) (xy 170.914832 -279.093529)
			(xy 170.868816 -279.076077) (xy 170.826195 -279.05147) (xy 170.788074 -279.020345) (xy 170.755439 -278.983508)
			(xy 170.729136 -278.941912) (xy 170.709845 -278.896636) (xy 170.698068 -278.848852) (xy 170.694108 -278.799798)
			(xy 170.377104 -278.799798) (xy 170.3766 -278.825506) (xy 170.368557 -278.876288) (xy 170.352669 -278.925187)
			(xy 170.329326 -278.970999) (xy 170.299105 -279.012595) (xy 170.262749 -279.048951) (xy 170.221153 -279.079172)
			(xy 170.175341 -279.102515) (xy 170.126442 -279.118403) (xy 170.07566 -279.126446) (xy 170.024244 -279.126446)
			(xy 169.973462 -279.118403) (xy 169.924563 -279.102515) (xy 169.878751 -279.079172) (xy 169.837155 -279.048951)
			(xy 169.800799 -279.012595) (xy 169.770578 -278.970999) (xy 169.747235 -278.925187) (xy 169.731347 -278.876288)
			(xy 169.723304 -278.825506) (xy 169.404626 -278.825506) (xy 169.39691 -278.872982) (xy 169.381326 -278.919663)
			(xy 169.358455 -278.96324) (xy 169.32889 -279.002584) (xy 169.293397 -279.036676) (xy 169.252894 -279.064632)
			(xy 169.208432 -279.08573) (xy 169.161161 -279.099422) (xy 169.112306 -279.105354) (xy 169.063131 -279.103373)
			(xy 169.014912 -279.093529) (xy 168.968896 -279.076077) (xy 168.926275 -279.05147) (xy 168.888154 -279.020345)
			(xy 168.855519 -278.983508) (xy 168.829216 -278.941912) (xy 168.809925 -278.896636) (xy 168.798148 -278.848852)
			(xy 168.794188 -278.799798) (xy 168.477184 -278.799798) (xy 168.47668 -278.825506) (xy 168.468637 -278.876288)
			(xy 168.452749 -278.925187) (xy 168.429406 -278.970999) (xy 168.399185 -279.012595) (xy 168.362829 -279.048951)
			(xy 168.321233 -279.079172) (xy 168.275421 -279.102515) (xy 168.226522 -279.118403) (xy 168.17574 -279.126446)
			(xy 168.124324 -279.126446) (xy 168.073542 -279.118403) (xy 168.024643 -279.102515) (xy 167.978831 -279.079172)
			(xy 167.937235 -279.048951) (xy 167.900879 -279.012595) (xy 167.870658 -278.970999) (xy 167.847315 -278.925187)
			(xy 167.831427 -278.876288) (xy 167.823384 -278.825506) (xy 167.504706 -278.825506) (xy 167.49699 -278.872982)
			(xy 167.481406 -278.919663) (xy 167.458535 -278.96324) (xy 167.42897 -279.002584) (xy 167.393477 -279.036676)
			(xy 167.352974 -279.064632) (xy 167.308512 -279.08573) (xy 167.261241 -279.099422) (xy 167.212386 -279.105354)
			(xy 167.163211 -279.103373) (xy 167.114992 -279.093529) (xy 167.068976 -279.076077) (xy 167.026355 -279.05147)
			(xy 166.988234 -279.020345) (xy 166.955599 -278.983508) (xy 166.929296 -278.941912) (xy 166.910005 -278.896636)
			(xy 166.898228 -278.848852) (xy 166.894268 -278.799798) (xy 166.57701 -278.799798) (xy 166.576506 -278.825506)
			(xy 166.568463 -278.876288) (xy 166.552575 -278.925187) (xy 166.529232 -278.970999) (xy 166.499011 -279.012595)
			(xy 166.462655 -279.048951) (xy 166.421059 -279.079172) (xy 166.375247 -279.102515) (xy 166.326348 -279.118403)
			(xy 166.275566 -279.126446) (xy 166.22415 -279.126446) (xy 166.173368 -279.118403) (xy 166.124469 -279.102515)
			(xy 166.078657 -279.079172) (xy 166.037061 -279.048951) (xy 166.000705 -279.012595) (xy 165.970484 -278.970999)
			(xy 165.947141 -278.925187) (xy 165.931253 -278.876288) (xy 165.92321 -278.825506) (xy 165.604532 -278.825506)
			(xy 165.596816 -278.872982) (xy 165.581232 -278.919663) (xy 165.558361 -278.96324) (xy 165.528796 -279.002584)
			(xy 165.493303 -279.036676) (xy 165.4528 -279.064632) (xy 165.408338 -279.08573) (xy 165.361067 -279.099422)
			(xy 165.312212 -279.105354) (xy 165.263037 -279.103373) (xy 165.214818 -279.093529) (xy 165.168802 -279.076077)
			(xy 165.126181 -279.05147) (xy 165.08806 -279.020345) (xy 165.055425 -278.983508) (xy 165.029122 -278.941912)
			(xy 165.009831 -278.896636) (xy 164.998054 -278.848852) (xy 164.994094 -278.799798) (xy 164.67709 -278.799798)
			(xy 164.676586 -278.825506) (xy 164.668543 -278.876288) (xy 164.652655 -278.925187) (xy 164.629312 -278.970999)
			(xy 164.599091 -279.012595) (xy 164.562735 -279.048951) (xy 164.521139 -279.079172) (xy 164.475327 -279.102515)
			(xy 164.426428 -279.118403) (xy 164.375646 -279.126446) (xy 164.32423 -279.126446) (xy 164.273448 -279.118403)
			(xy 164.224549 -279.102515) (xy 164.178737 -279.079172) (xy 164.137141 -279.048951) (xy 164.100785 -279.012595)
			(xy 164.070564 -278.970999) (xy 164.047221 -278.925187) (xy 164.031333 -278.876288) (xy 164.02329 -278.825506)
			(xy 163.704612 -278.825506) (xy 163.696896 -278.872982) (xy 163.681312 -278.919663) (xy 163.658441 -278.96324)
			(xy 163.628876 -279.002584) (xy 163.593383 -279.036676) (xy 163.55288 -279.064632) (xy 163.508418 -279.08573)
			(xy 163.461147 -279.099422) (xy 163.412292 -279.105354) (xy 163.363117 -279.103373) (xy 163.314898 -279.093529)
			(xy 163.268882 -279.076077) (xy 163.226261 -279.05147) (xy 163.18814 -279.020345) (xy 163.155505 -278.983508)
			(xy 163.129202 -278.941912) (xy 163.109911 -278.896636) (xy 163.098134 -278.848852) (xy 163.094174 -278.799798)
			(xy 162.77717 -278.799798) (xy 162.776666 -278.825506) (xy 162.768623 -278.876288) (xy 162.752735 -278.925187)
			(xy 162.729392 -278.970999) (xy 162.699171 -279.012595) (xy 162.662815 -279.048951) (xy 162.621219 -279.079172)
			(xy 162.575407 -279.102515) (xy 162.526508 -279.118403) (xy 162.475726 -279.126446) (xy 162.42431 -279.126446)
			(xy 162.373528 -279.118403) (xy 162.324629 -279.102515) (xy 162.278817 -279.079172) (xy 162.237221 -279.048951)
			(xy 162.200865 -279.012595) (xy 162.170644 -278.970999) (xy 162.147301 -278.925187) (xy 162.131413 -278.876288)
			(xy 162.12337 -278.825506) (xy 161.804692 -278.825506) (xy 161.796976 -278.872982) (xy 161.781392 -278.919663)
			(xy 161.758521 -278.96324) (xy 161.728956 -279.002584) (xy 161.693463 -279.036676) (xy 161.65296 -279.064632)
			(xy 161.608498 -279.08573) (xy 161.561227 -279.099422) (xy 161.512372 -279.105354) (xy 161.463197 -279.103373)
			(xy 161.414978 -279.093529) (xy 161.368962 -279.076077) (xy 161.326341 -279.05147) (xy 161.28822 -279.020345)
			(xy 161.255585 -278.983508) (xy 161.229282 -278.941912) (xy 161.209991 -278.896636) (xy 161.198214 -278.848852)
			(xy 161.194254 -278.799798) (xy 160.875993 -278.799798) (xy 160.876005 -278.825322) (xy 160.867996 -278.876061)
			(xy 160.85215 -278.924922) (xy 160.828855 -278.970704) (xy 160.798687 -279.012279) (xy 160.762388 -279.048623)
			(xy 160.720851 -279.078843) (xy 160.675098 -279.102194) (xy 160.626256 -279.118101) (xy 160.575527 -279.126173)
			(xy 160.549844 -279.126696) (xy 160.536126 -279.126555) (xy 160.508785 -279.124263) (xy 160.495234 -279.122124)
			(xy 160.483296 -279.120346) (xy 160.460436 -279.127204) (xy 160.383982 -279.200864) (xy 160.376108 -279.22347)
			(xy 160.377632 -279.235408) (xy 160.378816 -279.245208) (xy 160.38009 -279.264908) (xy 160.380172 -279.274778)
			(xy 160.379993 -279.288961) (xy 160.377323 -279.317201) (xy 160.374838 -279.331166) (xy 160.372552 -279.343612)
			(xy 160.379918 -279.367234) (xy 160.457388 -279.444704) (xy 160.48101 -279.45207) (xy 160.493456 -279.449784)
			(xy 160.507421 -279.447304) (xy 160.535661 -279.444634) (xy 160.549844 -279.44445) (xy 160.575093 -279.445059)
			(xy 160.624903 -279.453377) (xy 160.672664 -279.46978) (xy 160.717074 -279.493819) (xy 160.756922 -279.524839)
			(xy 160.791122 -279.561995) (xy 160.81874 -279.604273) (xy 160.839024 -279.650519) (xy 160.851419 -279.699473)
			(xy 160.855589 -279.7498) (xy 160.853483 -279.775212) (xy 161.17341 -279.775212) (xy 161.17341 -279.723796)
			(xy 161.181453 -279.673014) (xy 161.197341 -279.624115) (xy 161.220684 -279.578303) (xy 161.250905 -279.536707)
			(xy 161.287261 -279.500351) (xy 161.328857 -279.47013) (xy 161.374669 -279.446787) (xy 161.423568 -279.430899)
			(xy 161.47435 -279.422856) (xy 161.525766 -279.422856) (xy 161.576548 -279.430899) (xy 161.625447 -279.446787)
			(xy 161.671259 -279.47013) (xy 161.712855 -279.500351) (xy 161.749211 -279.536707) (xy 161.779432 -279.578303)
			(xy 161.802775 -279.624115) (xy 161.818663 -279.673014) (xy 161.826706 -279.723796) (xy 161.82721 -279.749504)
			(xy 161.827205 -279.749758) (xy 162.144214 -279.749758) (xy 162.148174 -279.700704) (xy 162.159951 -279.65292)
			(xy 162.179242 -279.607644) (xy 162.205545 -279.566048) (xy 162.23818 -279.529211) (xy 162.276301 -279.498086)
			(xy 162.318922 -279.473479) (xy 162.364938 -279.456027) (xy 162.413157 -279.446183) (xy 162.462332 -279.444202)
			(xy 162.511187 -279.450134) (xy 162.558458 -279.463826) (xy 162.60292 -279.484924) (xy 162.643423 -279.51288)
			(xy 162.678916 -279.546972) (xy 162.708481 -279.586316) (xy 162.731352 -279.629893) (xy 162.746936 -279.676574)
			(xy 162.754831 -279.725151) (xy 162.755326 -279.749758) (xy 162.754831 -279.774365) (xy 162.754693 -279.775212)
			(xy 163.07333 -279.775212) (xy 163.07333 -279.723796) (xy 163.081373 -279.673014) (xy 163.097261 -279.624115)
			(xy 163.120604 -279.578303) (xy 163.150825 -279.536707) (xy 163.187181 -279.500351) (xy 163.228777 -279.47013)
			(xy 163.274589 -279.446787) (xy 163.323488 -279.430899) (xy 163.37427 -279.422856) (xy 163.425686 -279.422856)
			(xy 163.476468 -279.430899) (xy 163.525367 -279.446787) (xy 163.571179 -279.47013) (xy 163.612775 -279.500351)
			(xy 163.649131 -279.536707) (xy 163.679352 -279.578303) (xy 163.702695 -279.624115) (xy 163.718583 -279.673014)
			(xy 163.726626 -279.723796) (xy 163.72713 -279.749504) (xy 163.727125 -279.749758) (xy 164.044134 -279.749758)
			(xy 164.048094 -279.700704) (xy 164.059871 -279.65292) (xy 164.079162 -279.607644) (xy 164.105465 -279.566048)
			(xy 164.1381 -279.529211) (xy 164.176221 -279.498086) (xy 164.218842 -279.473479) (xy 164.264858 -279.456027)
			(xy 164.313077 -279.446183) (xy 164.362252 -279.444202) (xy 164.411107 -279.450134) (xy 164.458378 -279.463826)
			(xy 164.50284 -279.484924) (xy 164.543343 -279.51288) (xy 164.578836 -279.546972) (xy 164.608401 -279.586316)
			(xy 164.631272 -279.629893) (xy 164.646856 -279.676574) (xy 164.654751 -279.725151) (xy 164.655246 -279.749758)
			(xy 164.654751 -279.774365) (xy 164.654613 -279.775212) (xy 164.97325 -279.775212) (xy 164.97325 -279.723796)
			(xy 164.981293 -279.673014) (xy 164.997181 -279.624115) (xy 165.020524 -279.578303) (xy 165.050745 -279.536707)
			(xy 165.087101 -279.500351) (xy 165.128697 -279.47013) (xy 165.174509 -279.446787) (xy 165.223408 -279.430899)
			(xy 165.27419 -279.422856) (xy 165.325606 -279.422856) (xy 165.376388 -279.430899) (xy 165.425287 -279.446787)
			(xy 165.471099 -279.47013) (xy 165.512695 -279.500351) (xy 165.549051 -279.536707) (xy 165.579272 -279.578303)
			(xy 165.602615 -279.624115) (xy 165.618503 -279.673014) (xy 165.626546 -279.723796) (xy 165.62705 -279.749504)
			(xy 165.627045 -279.749758) (xy 165.944054 -279.749758) (xy 165.948014 -279.700704) (xy 165.959791 -279.65292)
			(xy 165.979082 -279.607644) (xy 166.005385 -279.566048) (xy 166.03802 -279.529211) (xy 166.076141 -279.498086)
			(xy 166.118762 -279.473479) (xy 166.164778 -279.456027) (xy 166.212997 -279.446183) (xy 166.262172 -279.444202)
			(xy 166.311027 -279.450134) (xy 166.358298 -279.463826) (xy 166.40276 -279.484924) (xy 166.443263 -279.51288)
			(xy 166.478756 -279.546972) (xy 166.508321 -279.586316) (xy 166.531192 -279.629893) (xy 166.546776 -279.676574)
			(xy 166.554671 -279.725151) (xy 166.555166 -279.749758) (xy 166.554671 -279.774365) (xy 166.554533 -279.775212)
			(xy 166.873424 -279.775212) (xy 166.873424 -279.723796) (xy 166.881467 -279.673014) (xy 166.897355 -279.624115)
			(xy 166.920698 -279.578303) (xy 166.950919 -279.536707) (xy 166.987275 -279.500351) (xy 167.028871 -279.47013)
			(xy 167.074683 -279.446787) (xy 167.123582 -279.430899) (xy 167.174364 -279.422856) (xy 167.22578 -279.422856)
			(xy 167.276562 -279.430899) (xy 167.325461 -279.446787) (xy 167.371273 -279.47013) (xy 167.412869 -279.500351)
			(xy 167.449225 -279.536707) (xy 167.479446 -279.578303) (xy 167.502789 -279.624115) (xy 167.518677 -279.673014)
			(xy 167.52672 -279.723796) (xy 167.527224 -279.749504) (xy 167.527219 -279.749758) (xy 167.844228 -279.749758)
			(xy 167.848188 -279.700704) (xy 167.859965 -279.65292) (xy 167.879256 -279.607644) (xy 167.905559 -279.566048)
			(xy 167.938194 -279.529211) (xy 167.976315 -279.498086) (xy 168.018936 -279.473479) (xy 168.064952 -279.456027)
			(xy 168.113171 -279.446183) (xy 168.162346 -279.444202) (xy 168.211201 -279.450134) (xy 168.258472 -279.463826)
			(xy 168.302934 -279.484924) (xy 168.343437 -279.51288) (xy 168.37893 -279.546972) (xy 168.408495 -279.586316)
			(xy 168.431366 -279.629893) (xy 168.44695 -279.676574) (xy 168.454845 -279.725151) (xy 168.45534 -279.749758)
			(xy 168.454845 -279.774365) (xy 168.454707 -279.775212) (xy 168.773344 -279.775212) (xy 168.773344 -279.723796)
			(xy 168.781387 -279.673014) (xy 168.797275 -279.624115) (xy 168.820618 -279.578303) (xy 168.850839 -279.536707)
			(xy 168.887195 -279.500351) (xy 168.928791 -279.47013) (xy 168.974603 -279.446787) (xy 169.023502 -279.430899)
			(xy 169.074284 -279.422856) (xy 169.1257 -279.422856) (xy 169.176482 -279.430899) (xy 169.225381 -279.446787)
			(xy 169.271193 -279.47013) (xy 169.312789 -279.500351) (xy 169.349145 -279.536707) (xy 169.379366 -279.578303)
			(xy 169.402709 -279.624115) (xy 169.418597 -279.673014) (xy 169.42664 -279.723796) (xy 169.427144 -279.749504)
			(xy 169.427139 -279.749758) (xy 169.744148 -279.749758) (xy 169.748108 -279.700704) (xy 169.759885 -279.65292)
			(xy 169.779176 -279.607644) (xy 169.805479 -279.566048) (xy 169.838114 -279.529211) (xy 169.876235 -279.498086)
			(xy 169.918856 -279.473479) (xy 169.964872 -279.456027) (xy 170.013091 -279.446183) (xy 170.062266 -279.444202)
			(xy 170.111121 -279.450134) (xy 170.158392 -279.463826) (xy 170.202854 -279.484924) (xy 170.243357 -279.51288)
			(xy 170.27885 -279.546972) (xy 170.308415 -279.586316) (xy 170.331286 -279.629893) (xy 170.34687 -279.676574)
			(xy 170.354765 -279.725151) (xy 170.35526 -279.749758) (xy 170.354765 -279.774365) (xy 170.354627 -279.775212)
			(xy 170.673264 -279.775212) (xy 170.673264 -279.723796) (xy 170.681307 -279.673014) (xy 170.697195 -279.624115)
			(xy 170.720538 -279.578303) (xy 170.750759 -279.536707) (xy 170.787115 -279.500351) (xy 170.828711 -279.47013)
			(xy 170.874523 -279.446787) (xy 170.923422 -279.430899) (xy 170.974204 -279.422856) (xy 171.02562 -279.422856)
			(xy 171.076402 -279.430899) (xy 171.125301 -279.446787) (xy 171.171113 -279.47013) (xy 171.212709 -279.500351)
			(xy 171.249065 -279.536707) (xy 171.279286 -279.578303) (xy 171.302629 -279.624115) (xy 171.318517 -279.673014)
			(xy 171.32656 -279.723796) (xy 171.327064 -279.749504) (xy 171.327059 -279.749758) (xy 171.644068 -279.749758)
			(xy 171.648028 -279.700704) (xy 171.659805 -279.65292) (xy 171.679096 -279.607644) (xy 171.705399 -279.566048)
			(xy 171.738034 -279.529211) (xy 171.776155 -279.498086) (xy 171.818776 -279.473479) (xy 171.864792 -279.456027)
			(xy 171.913011 -279.446183) (xy 171.962186 -279.444202) (xy 172.011041 -279.450134) (xy 172.058312 -279.463826)
			(xy 172.102774 -279.484924) (xy 172.143277 -279.51288) (xy 172.17877 -279.546972) (xy 172.208335 -279.586316)
			(xy 172.231206 -279.629893) (xy 172.24679 -279.676574) (xy 172.254685 -279.725151) (xy 172.25518 -279.749758)
			(xy 172.254685 -279.774365) (xy 172.254547 -279.775212) (xy 172.573184 -279.775212) (xy 172.573184 -279.723796)
			(xy 172.581227 -279.673014) (xy 172.597115 -279.624115) (xy 172.620458 -279.578303) (xy 172.650679 -279.536707)
			(xy 172.687035 -279.500351) (xy 172.728631 -279.47013) (xy 172.774443 -279.446787) (xy 172.823342 -279.430899)
			(xy 172.874124 -279.422856) (xy 172.92554 -279.422856) (xy 172.976322 -279.430899) (xy 173.025221 -279.446787)
			(xy 173.071033 -279.47013) (xy 173.112629 -279.500351) (xy 173.148985 -279.536707) (xy 173.179206 -279.578303)
			(xy 173.202549 -279.624115) (xy 173.218437 -279.673014) (xy 173.22648 -279.723796) (xy 173.226984 -279.749504)
			(xy 173.226979 -279.749758) (xy 173.544242 -279.749758) (xy 173.548202 -279.700704) (xy 173.559979 -279.65292)
			(xy 173.57927 -279.607644) (xy 173.605573 -279.566048) (xy 173.638208 -279.529211) (xy 173.676329 -279.498086)
			(xy 173.71895 -279.473479) (xy 173.764966 -279.456027) (xy 173.813185 -279.446183) (xy 173.86236 -279.444202)
			(xy 173.911215 -279.450134) (xy 173.958486 -279.463826) (xy 174.002948 -279.484924) (xy 174.043451 -279.51288)
			(xy 174.078944 -279.546972) (xy 174.108509 -279.586316) (xy 174.13138 -279.629893) (xy 174.146964 -279.676574)
			(xy 174.154859 -279.725151) (xy 174.155354 -279.749758) (xy 174.154859 -279.774365) (xy 174.154721 -279.775212)
			(xy 174.473358 -279.775212) (xy 174.473358 -279.723796) (xy 174.481401 -279.673014) (xy 174.497289 -279.624115)
			(xy 174.520632 -279.578303) (xy 174.550853 -279.536707) (xy 174.587209 -279.500351) (xy 174.628805 -279.47013)
			(xy 174.674617 -279.446787) (xy 174.723516 -279.430899) (xy 174.774298 -279.422856) (xy 174.825714 -279.422856)
			(xy 174.876496 -279.430899) (xy 174.925395 -279.446787) (xy 174.971207 -279.47013) (xy 175.012803 -279.500351)
			(xy 175.049159 -279.536707) (xy 175.07938 -279.578303) (xy 175.102723 -279.624115) (xy 175.118611 -279.673014)
			(xy 175.126654 -279.723796) (xy 175.127158 -279.749504) (xy 175.127153 -279.749758) (xy 175.444162 -279.749758)
			(xy 175.448122 -279.700704) (xy 175.459899 -279.65292) (xy 175.47919 -279.607644) (xy 175.505493 -279.566048)
			(xy 175.538128 -279.529211) (xy 175.576249 -279.498086) (xy 175.61887 -279.473479) (xy 175.664886 -279.456027)
			(xy 175.713105 -279.446183) (xy 175.76228 -279.444202) (xy 175.811135 -279.450134) (xy 175.858406 -279.463826)
			(xy 175.902868 -279.484924) (xy 175.943371 -279.51288) (xy 175.978864 -279.546972) (xy 176.008429 -279.586316)
			(xy 176.0313 -279.629893) (xy 176.046884 -279.676574) (xy 176.054779 -279.725151) (xy 176.055274 -279.749758)
			(xy 176.054779 -279.774365) (xy 176.054641 -279.775212) (xy 176.373278 -279.775212) (xy 176.373278 -279.723796)
			(xy 176.381321 -279.673014) (xy 176.397209 -279.624115) (xy 176.420552 -279.578303) (xy 176.450773 -279.536707)
			(xy 176.487129 -279.500351) (xy 176.528725 -279.47013) (xy 176.574537 -279.446787) (xy 176.623436 -279.430899)
			(xy 176.674218 -279.422856) (xy 176.725634 -279.422856) (xy 176.776416 -279.430899) (xy 176.825315 -279.446787)
			(xy 176.871127 -279.47013) (xy 176.912723 -279.500351) (xy 176.949079 -279.536707) (xy 176.9793 -279.578303)
			(xy 177.002643 -279.624115) (xy 177.018531 -279.673014) (xy 177.026574 -279.723796) (xy 177.027078 -279.749504)
			(xy 177.027073 -279.749758) (xy 177.344082 -279.749758) (xy 177.348042 -279.700704) (xy 177.359819 -279.65292)
			(xy 177.37911 -279.607644) (xy 177.405413 -279.566048) (xy 177.438048 -279.529211) (xy 177.476169 -279.498086)
			(xy 177.51879 -279.473479) (xy 177.564806 -279.456027) (xy 177.613025 -279.446183) (xy 177.6622 -279.444202)
			(xy 177.711055 -279.450134) (xy 177.758326 -279.463826) (xy 177.802788 -279.484924) (xy 177.843291 -279.51288)
			(xy 177.878784 -279.546972) (xy 177.908349 -279.586316) (xy 177.93122 -279.629893) (xy 177.946804 -279.676574)
			(xy 177.954699 -279.725151) (xy 177.955194 -279.749758) (xy 177.954699 -279.774365) (xy 177.954561 -279.775212)
			(xy 178.273198 -279.775212) (xy 178.273198 -279.723796) (xy 178.281241 -279.673014) (xy 178.297129 -279.624115)
			(xy 178.320472 -279.578303) (xy 178.350693 -279.536707) (xy 178.387049 -279.500351) (xy 178.428645 -279.47013)
			(xy 178.474457 -279.446787) (xy 178.523356 -279.430899) (xy 178.574138 -279.422856) (xy 178.625554 -279.422856)
			(xy 178.676336 -279.430899) (xy 178.725235 -279.446787) (xy 178.771047 -279.47013) (xy 178.812643 -279.500351)
			(xy 178.848999 -279.536707) (xy 178.87922 -279.578303) (xy 178.902563 -279.624115) (xy 178.918451 -279.673014)
			(xy 178.926494 -279.723796) (xy 178.926998 -279.749504) (xy 178.926993 -279.749758) (xy 179.244256 -279.749758)
			(xy 179.248216 -279.700704) (xy 179.259993 -279.65292) (xy 179.279284 -279.607644) (xy 179.305587 -279.566048)
			(xy 179.338222 -279.529211) (xy 179.376343 -279.498086) (xy 179.418964 -279.473479) (xy 179.46498 -279.456027)
			(xy 179.513199 -279.446183) (xy 179.562374 -279.444202) (xy 179.611229 -279.450134) (xy 179.6585 -279.463826)
			(xy 179.702962 -279.484924) (xy 179.743465 -279.51288) (xy 179.778958 -279.546972) (xy 179.808523 -279.586316)
			(xy 179.831394 -279.629893) (xy 179.846978 -279.676574) (xy 179.854873 -279.725151) (xy 179.855368 -279.749758)
			(xy 179.854873 -279.774365) (xy 179.854735 -279.775212) (xy 180.173372 -279.775212) (xy 180.173372 -279.723796)
			(xy 180.181415 -279.673014) (xy 180.197303 -279.624115) (xy 180.220646 -279.578303) (xy 180.250867 -279.536707)
			(xy 180.287223 -279.500351) (xy 180.328819 -279.47013) (xy 180.374631 -279.446787) (xy 180.42353 -279.430899)
			(xy 180.474312 -279.422856) (xy 180.525728 -279.422856) (xy 180.57651 -279.430899) (xy 180.625409 -279.446787)
			(xy 180.671221 -279.47013) (xy 180.712817 -279.500351) (xy 180.749173 -279.536707) (xy 180.779394 -279.578303)
			(xy 180.802737 -279.624115) (xy 180.818625 -279.673014) (xy 180.826668 -279.723796) (xy 180.827172 -279.749504)
			(xy 180.827167 -279.749758) (xy 181.144176 -279.749758) (xy 181.148136 -279.700704) (xy 181.159913 -279.65292)
			(xy 181.179204 -279.607644) (xy 181.205507 -279.566048) (xy 181.238142 -279.529211) (xy 181.276263 -279.498086)
			(xy 181.318884 -279.473479) (xy 181.3649 -279.456027) (xy 181.413119 -279.446183) (xy 181.462294 -279.444202)
			(xy 181.511149 -279.450134) (xy 181.55842 -279.463826) (xy 181.602882 -279.484924) (xy 181.643385 -279.51288)
			(xy 181.678878 -279.546972) (xy 181.708443 -279.586316) (xy 181.731314 -279.629893) (xy 181.746898 -279.676574)
			(xy 181.754793 -279.725151) (xy 181.755288 -279.749758) (xy 181.754793 -279.774365) (xy 181.754655 -279.775212)
			(xy 182.073292 -279.775212) (xy 182.073292 -279.723796) (xy 182.081335 -279.673014) (xy 182.097223 -279.624115)
			(xy 182.120566 -279.578303) (xy 182.150787 -279.536707) (xy 182.187143 -279.500351) (xy 182.228739 -279.47013)
			(xy 182.274551 -279.446787) (xy 182.32345 -279.430899) (xy 182.374232 -279.422856) (xy 182.425648 -279.422856)
			(xy 182.47643 -279.430899) (xy 182.525329 -279.446787) (xy 182.571141 -279.47013) (xy 182.612737 -279.500351)
			(xy 182.649093 -279.536707) (xy 182.679314 -279.578303) (xy 182.702657 -279.624115) (xy 182.718545 -279.673014)
			(xy 182.726588 -279.723796) (xy 182.727092 -279.749504) (xy 182.727087 -279.749758) (xy 183.044096 -279.749758)
			(xy 183.048056 -279.700704) (xy 183.059833 -279.65292) (xy 183.079124 -279.607644) (xy 183.105427 -279.566048)
			(xy 183.138062 -279.529211) (xy 183.176183 -279.498086) (xy 183.218804 -279.473479) (xy 183.26482 -279.456027)
			(xy 183.313039 -279.446183) (xy 183.362214 -279.444202) (xy 183.411069 -279.450134) (xy 183.45834 -279.463826)
			(xy 183.502802 -279.484924) (xy 183.543305 -279.51288) (xy 183.578798 -279.546972) (xy 183.608363 -279.586316)
			(xy 183.631234 -279.629893) (xy 183.646818 -279.676574) (xy 183.654713 -279.725151) (xy 183.655208 -279.749758)
			(xy 183.654713 -279.774365) (xy 183.654575 -279.775212) (xy 183.973212 -279.775212) (xy 183.973212 -279.723796)
			(xy 183.981255 -279.673014) (xy 183.997143 -279.624115) (xy 184.020486 -279.578303) (xy 184.050707 -279.536707)
			(xy 184.087063 -279.500351) (xy 184.128659 -279.47013) (xy 184.174471 -279.446787) (xy 184.22337 -279.430899)
			(xy 184.274152 -279.422856) (xy 184.325568 -279.422856) (xy 184.37635 -279.430899) (xy 184.425249 -279.446787)
			(xy 184.471061 -279.47013) (xy 184.512657 -279.500351) (xy 184.549013 -279.536707) (xy 184.579234 -279.578303)
			(xy 184.602577 -279.624115) (xy 184.618465 -279.673014) (xy 184.626508 -279.723796) (xy 184.627012 -279.749504)
			(xy 184.627007 -279.749758) (xy 184.94427 -279.749758) (xy 184.94823 -279.700704) (xy 184.960007 -279.65292)
			(xy 184.979298 -279.607644) (xy 185.005601 -279.566048) (xy 185.038236 -279.529211) (xy 185.076357 -279.498086)
			(xy 185.118978 -279.473479) (xy 185.164994 -279.456027) (xy 185.213213 -279.446183) (xy 185.262388 -279.444202)
			(xy 185.311243 -279.450134) (xy 185.358514 -279.463826) (xy 185.402976 -279.484924) (xy 185.443479 -279.51288)
			(xy 185.478972 -279.546972) (xy 185.508537 -279.586316) (xy 185.531408 -279.629893) (xy 185.546992 -279.676574)
			(xy 185.554887 -279.725151) (xy 185.555382 -279.749758) (xy 185.554887 -279.774365) (xy 185.554749 -279.775212)
			(xy 185.873386 -279.775212) (xy 185.873386 -279.723796) (xy 185.881429 -279.673014) (xy 185.897317 -279.624115)
			(xy 185.92066 -279.578303) (xy 185.950881 -279.536707) (xy 185.987237 -279.500351) (xy 186.028833 -279.47013)
			(xy 186.074645 -279.446787) (xy 186.123544 -279.430899) (xy 186.174326 -279.422856) (xy 186.225742 -279.422856)
			(xy 186.276524 -279.430899) (xy 186.325423 -279.446787) (xy 186.371235 -279.47013) (xy 186.412831 -279.500351)
			(xy 186.449187 -279.536707) (xy 186.479408 -279.578303) (xy 186.502751 -279.624115) (xy 186.518639 -279.673014)
			(xy 186.526682 -279.723796) (xy 186.527186 -279.749504) (xy 186.527181 -279.749758) (xy 186.84419 -279.749758)
			(xy 186.84815 -279.700704) (xy 186.859927 -279.65292) (xy 186.879218 -279.607644) (xy 186.905521 -279.566048)
			(xy 186.938156 -279.529211) (xy 186.976277 -279.498086) (xy 187.018898 -279.473479) (xy 187.064914 -279.456027)
			(xy 187.113133 -279.446183) (xy 187.162308 -279.444202) (xy 187.211163 -279.450134) (xy 187.258434 -279.463826)
			(xy 187.302896 -279.484924) (xy 187.343399 -279.51288) (xy 187.378892 -279.546972) (xy 187.408457 -279.586316)
			(xy 187.431328 -279.629893) (xy 187.446912 -279.676574) (xy 187.454807 -279.725151) (xy 187.455302 -279.749758)
			(xy 187.454807 -279.774365) (xy 187.454669 -279.775212) (xy 187.773306 -279.775212) (xy 187.773306 -279.723796)
			(xy 187.781349 -279.673014) (xy 187.797237 -279.624115) (xy 187.82058 -279.578303) (xy 187.850801 -279.536707)
			(xy 187.887157 -279.500351) (xy 187.928753 -279.47013) (xy 187.974565 -279.446787) (xy 188.023464 -279.430899)
			(xy 188.074246 -279.422856) (xy 188.125662 -279.422856) (xy 188.176444 -279.430899) (xy 188.225343 -279.446787)
			(xy 188.271155 -279.47013) (xy 188.312751 -279.500351) (xy 188.349107 -279.536707) (xy 188.379328 -279.578303)
			(xy 188.402671 -279.624115) (xy 188.418559 -279.673014) (xy 188.426602 -279.723796) (xy 188.427106 -279.749504)
			(xy 188.427101 -279.749758) (xy 188.74411 -279.749758) (xy 188.74807 -279.700704) (xy 188.759847 -279.65292)
			(xy 188.779138 -279.607644) (xy 188.805441 -279.566048) (xy 188.838076 -279.529211) (xy 188.876197 -279.498086)
			(xy 188.918818 -279.473479) (xy 188.964834 -279.456027) (xy 189.013053 -279.446183) (xy 189.062228 -279.444202)
			(xy 189.111083 -279.450134) (xy 189.158354 -279.463826) (xy 189.202816 -279.484924) (xy 189.243319 -279.51288)
			(xy 189.278812 -279.546972) (xy 189.308377 -279.586316) (xy 189.331248 -279.629893) (xy 189.346832 -279.676574)
			(xy 189.354727 -279.725151) (xy 189.355222 -279.749758) (xy 189.354727 -279.774365) (xy 189.354589 -279.775212)
			(xy 189.673226 -279.775212) (xy 189.673226 -279.723796) (xy 189.681269 -279.673014) (xy 189.697157 -279.624115)
			(xy 189.7205 -279.578303) (xy 189.750721 -279.536707) (xy 189.787077 -279.500351) (xy 189.828673 -279.47013)
			(xy 189.874485 -279.446787) (xy 189.923384 -279.430899) (xy 189.974166 -279.422856) (xy 190.025582 -279.422856)
			(xy 190.076364 -279.430899) (xy 190.125263 -279.446787) (xy 190.171075 -279.47013) (xy 190.212671 -279.500351)
			(xy 190.249027 -279.536707) (xy 190.279248 -279.578303) (xy 190.302591 -279.624115) (xy 190.318479 -279.673014)
			(xy 190.326522 -279.723796) (xy 190.327026 -279.749504) (xy 190.327021 -279.749758) (xy 190.64403 -279.749758)
			(xy 190.64799 -279.700704) (xy 190.659767 -279.65292) (xy 190.679058 -279.607644) (xy 190.705361 -279.566048)
			(xy 190.737996 -279.529211) (xy 190.776117 -279.498086) (xy 190.818738 -279.473479) (xy 190.864754 -279.456027)
			(xy 190.912973 -279.446183) (xy 190.962148 -279.444202) (xy 191.011003 -279.450134) (xy 191.058274 -279.463826)
			(xy 191.102736 -279.484924) (xy 191.143239 -279.51288) (xy 191.178732 -279.546972) (xy 191.208297 -279.586316)
			(xy 191.231168 -279.629893) (xy 191.246752 -279.676574) (xy 191.254647 -279.725151) (xy 191.255142 -279.749758)
			(xy 191.254647 -279.774365) (xy 191.254509 -279.775212) (xy 191.5734 -279.775212) (xy 191.5734 -279.723796)
			(xy 191.581443 -279.673014) (xy 191.597331 -279.624115) (xy 191.620674 -279.578303) (xy 191.650895 -279.536707)
			(xy 191.687251 -279.500351) (xy 191.728847 -279.47013) (xy 191.774659 -279.446787) (xy 191.823558 -279.430899)
			(xy 191.87434 -279.422856) (xy 191.925756 -279.422856) (xy 191.976538 -279.430899) (xy 192.025437 -279.446787)
			(xy 192.071249 -279.47013) (xy 192.112845 -279.500351) (xy 192.149201 -279.536707) (xy 192.179422 -279.578303)
			(xy 192.202765 -279.624115) (xy 192.218653 -279.673014) (xy 192.226696 -279.723796) (xy 192.2272 -279.749504)
			(xy 192.227195 -279.749758) (xy 192.544204 -279.749758) (xy 192.548164 -279.700704) (xy 192.559941 -279.65292)
			(xy 192.579232 -279.607644) (xy 192.605535 -279.566048) (xy 192.63817 -279.529211) (xy 192.676291 -279.498086)
			(xy 192.718912 -279.473479) (xy 192.764928 -279.456027) (xy 192.813147 -279.446183) (xy 192.862322 -279.444202)
			(xy 192.911177 -279.450134) (xy 192.958448 -279.463826) (xy 193.00291 -279.484924) (xy 193.043413 -279.51288)
			(xy 193.078906 -279.546972) (xy 193.108471 -279.586316) (xy 193.131342 -279.629893) (xy 193.146926 -279.676574)
			(xy 193.154821 -279.725151) (xy 193.155316 -279.749758) (xy 193.154821 -279.774365) (xy 193.154683 -279.775212)
			(xy 193.47332 -279.775212) (xy 193.47332 -279.723796) (xy 193.481363 -279.673014) (xy 193.497251 -279.624115)
			(xy 193.520594 -279.578303) (xy 193.550815 -279.536707) (xy 193.587171 -279.500351) (xy 193.628767 -279.47013)
			(xy 193.674579 -279.446787) (xy 193.723478 -279.430899) (xy 193.77426 -279.422856) (xy 193.825676 -279.422856)
			(xy 193.876458 -279.430899) (xy 193.925357 -279.446787) (xy 193.971169 -279.47013) (xy 194.012765 -279.500351)
			(xy 194.049121 -279.536707) (xy 194.079342 -279.578303) (xy 194.102685 -279.624115) (xy 194.118573 -279.673014)
			(xy 194.126616 -279.723796) (xy 194.12712 -279.749504) (xy 194.127115 -279.749758) (xy 194.444124 -279.749758)
			(xy 194.448084 -279.700704) (xy 194.459861 -279.65292) (xy 194.479152 -279.607644) (xy 194.505455 -279.566048)
			(xy 194.53809 -279.529211) (xy 194.576211 -279.498086) (xy 194.618832 -279.473479) (xy 194.664848 -279.456027)
			(xy 194.713067 -279.446183) (xy 194.762242 -279.444202) (xy 194.811097 -279.450134) (xy 194.858368 -279.463826)
			(xy 194.90283 -279.484924) (xy 194.943333 -279.51288) (xy 194.978826 -279.546972) (xy 195.008391 -279.586316)
			(xy 195.031262 -279.629893) (xy 195.046846 -279.676574) (xy 195.054741 -279.725151) (xy 195.055236 -279.749758)
			(xy 195.054741 -279.774365) (xy 195.054562 -279.775466) (xy 195.37324 -279.775466) (xy 195.37324 -279.72405)
			(xy 195.381283 -279.673268) (xy 195.397171 -279.624369) (xy 195.420514 -279.578557) (xy 195.450735 -279.536961)
			(xy 195.487091 -279.500605) (xy 195.528687 -279.470384) (xy 195.574499 -279.447041) (xy 195.623398 -279.431153)
			(xy 195.67418 -279.42311) (xy 195.725596 -279.42311) (xy 195.776378 -279.431153) (xy 195.825277 -279.447041)
			(xy 195.871089 -279.470384) (xy 195.912685 -279.500605) (xy 195.949041 -279.536961) (xy 195.979262 -279.578557)
			(xy 196.002605 -279.624369) (xy 196.018493 -279.673268) (xy 196.026536 -279.72405) (xy 196.02704 -279.749758)
			(xy 196.344044 -279.749758) (xy 196.348004 -279.700704) (xy 196.359781 -279.65292) (xy 196.379072 -279.607644)
			(xy 196.405375 -279.566048) (xy 196.43801 -279.529211) (xy 196.476131 -279.498086) (xy 196.518752 -279.473479)
			(xy 196.564768 -279.456027) (xy 196.612987 -279.446183) (xy 196.662162 -279.444202) (xy 196.711017 -279.450134)
			(xy 196.758288 -279.463826) (xy 196.80275 -279.484924) (xy 196.843253 -279.51288) (xy 196.878746 -279.546972)
			(xy 196.908311 -279.586316) (xy 196.931182 -279.629893) (xy 196.946766 -279.676574) (xy 196.954661 -279.725151)
			(xy 196.955156 -279.749758) (xy 196.954661 -279.774365) (xy 196.954482 -279.775466) (xy 197.273414 -279.775466)
			(xy 197.273414 -279.72405) (xy 197.281457 -279.673268) (xy 197.297345 -279.624369) (xy 197.320688 -279.578557)
			(xy 197.350909 -279.536961) (xy 197.387265 -279.500605) (xy 197.428861 -279.470384) (xy 197.474673 -279.447041)
			(xy 197.523572 -279.431153) (xy 197.574354 -279.42311) (xy 197.62577 -279.42311) (xy 197.676552 -279.431153)
			(xy 197.725451 -279.447041) (xy 197.771263 -279.470384) (xy 197.812859 -279.500605) (xy 197.849215 -279.536961)
			(xy 197.879436 -279.578557) (xy 197.902779 -279.624369) (xy 197.918667 -279.673268) (xy 197.92671 -279.72405)
			(xy 197.927214 -279.749758) (xy 197.92671 -279.775466) (xy 198.223374 -279.775466) (xy 198.223374 -279.72405)
			(xy 198.231417 -279.673268) (xy 198.247305 -279.624369) (xy 198.270648 -279.578557) (xy 198.300869 -279.536961)
			(xy 198.337225 -279.500605) (xy 198.378821 -279.470384) (xy 198.424633 -279.447041) (xy 198.473532 -279.431153)
			(xy 198.524314 -279.42311) (xy 198.57573 -279.42311) (xy 198.626512 -279.431153) (xy 198.675411 -279.447041)
			(xy 198.721223 -279.470384) (xy 198.762819 -279.500605) (xy 198.799175 -279.536961) (xy 198.829396 -279.578557)
			(xy 198.852739 -279.624369) (xy 198.868627 -279.673268) (xy 198.87667 -279.72405) (xy 198.877174 -279.749758)
			(xy 198.877169 -279.750012) (xy 199.194432 -279.750012) (xy 199.198392 -279.700958) (xy 199.210169 -279.653174)
			(xy 199.22946 -279.607898) (xy 199.255763 -279.566302) (xy 199.288398 -279.529465) (xy 199.326519 -279.49834)
			(xy 199.36914 -279.473733) (xy 199.415156 -279.456281) (xy 199.463375 -279.446437) (xy 199.51255 -279.444456)
			(xy 199.561405 -279.450388) (xy 199.608676 -279.46408) (xy 199.653138 -279.485178) (xy 199.693641 -279.513134)
			(xy 199.729134 -279.547226) (xy 199.758699 -279.58657) (xy 199.78157 -279.630147) (xy 199.797154 -279.676828)
			(xy 199.805049 -279.725405) (xy 199.805544 -279.750012) (xy 199.805049 -279.774619) (xy 199.797154 -279.823196)
			(xy 199.78157 -279.869877) (xy 199.758699 -279.913454) (xy 199.729134 -279.952798) (xy 199.693641 -279.98689)
			(xy 199.653138 -280.014846) (xy 199.608676 -280.035944) (xy 199.561405 -280.049636) (xy 199.51255 -280.055568)
			(xy 199.463375 -280.053587) (xy 199.415156 -280.043743) (xy 199.36914 -280.026291) (xy 199.326519 -280.001684)
			(xy 199.288398 -279.970559) (xy 199.255763 -279.933722) (xy 199.22946 -279.892126) (xy 199.210169 -279.84685)
			(xy 199.198392 -279.799066) (xy 199.194432 -279.750012) (xy 198.877169 -279.750012) (xy 198.87667 -279.775466)
			(xy 198.868627 -279.826248) (xy 198.852739 -279.875147) (xy 198.829396 -279.920959) (xy 198.799175 -279.962555)
			(xy 198.762819 -279.998911) (xy 198.721223 -280.029132) (xy 198.675411 -280.052475) (xy 198.626512 -280.068363)
			(xy 198.57573 -280.076406) (xy 198.524314 -280.076406) (xy 198.473532 -280.068363) (xy 198.424633 -280.052475)
			(xy 198.378821 -280.029132) (xy 198.337225 -279.998911) (xy 198.300869 -279.962555) (xy 198.270648 -279.920959)
			(xy 198.247305 -279.875147) (xy 198.231417 -279.826248) (xy 198.223374 -279.775466) (xy 197.92671 -279.775466)
			(xy 197.918667 -279.826248) (xy 197.902779 -279.875147) (xy 197.879436 -279.920959) (xy 197.849215 -279.962555)
			(xy 197.812859 -279.998911) (xy 197.771263 -280.029132) (xy 197.725451 -280.052475) (xy 197.676552 -280.068363)
			(xy 197.62577 -280.076406) (xy 197.574354 -280.076406) (xy 197.523572 -280.068363) (xy 197.474673 -280.052475)
			(xy 197.428861 -280.029132) (xy 197.387265 -279.998911) (xy 197.350909 -279.962555) (xy 197.320688 -279.920959)
			(xy 197.297345 -279.875147) (xy 197.281457 -279.826248) (xy 197.273414 -279.775466) (xy 196.954482 -279.775466)
			(xy 196.946766 -279.822942) (xy 196.931182 -279.869623) (xy 196.908311 -279.9132) (xy 196.878746 -279.952544)
			(xy 196.843253 -279.986636) (xy 196.80275 -280.014592) (xy 196.758288 -280.03569) (xy 196.711017 -280.049382)
			(xy 196.662162 -280.055314) (xy 196.612987 -280.053333) (xy 196.564768 -280.043489) (xy 196.518752 -280.026037)
			(xy 196.476131 -280.00143) (xy 196.43801 -279.970305) (xy 196.405375 -279.933468) (xy 196.379072 -279.891872)
			(xy 196.359781 -279.846596) (xy 196.348004 -279.798812) (xy 196.344044 -279.749758) (xy 196.02704 -279.749758)
			(xy 196.026536 -279.775466) (xy 196.018493 -279.826248) (xy 196.002605 -279.875147) (xy 195.979262 -279.920959)
			(xy 195.949041 -279.962555) (xy 195.912685 -279.998911) (xy 195.871089 -280.029132) (xy 195.825277 -280.052475)
			(xy 195.776378 -280.068363) (xy 195.725596 -280.076406) (xy 195.67418 -280.076406) (xy 195.623398 -280.068363)
			(xy 195.574499 -280.052475) (xy 195.528687 -280.029132) (xy 195.487091 -279.998911) (xy 195.450735 -279.962555)
			(xy 195.420514 -279.920959) (xy 195.397171 -279.875147) (xy 195.381283 -279.826248) (xy 195.37324 -279.775466)
			(xy 195.054562 -279.775466) (xy 195.046846 -279.822942) (xy 195.031262 -279.869623) (xy 195.008391 -279.9132)
			(xy 194.978826 -279.952544) (xy 194.943333 -279.986636) (xy 194.90283 -280.014592) (xy 194.858368 -280.03569)
			(xy 194.811097 -280.049382) (xy 194.762242 -280.055314) (xy 194.713067 -280.053333) (xy 194.664848 -280.043489)
			(xy 194.618832 -280.026037) (xy 194.576211 -280.00143) (xy 194.53809 -279.970305) (xy 194.505455 -279.933468)
			(xy 194.479152 -279.891872) (xy 194.459861 -279.846596) (xy 194.448084 -279.798812) (xy 194.444124 -279.749758)
			(xy 194.127115 -279.749758) (xy 194.126616 -279.775212) (xy 194.118573 -279.825994) (xy 194.102685 -279.874893)
			(xy 194.079342 -279.920705) (xy 194.049121 -279.962301) (xy 194.012765 -279.998657) (xy 193.971169 -280.028878)
			(xy 193.925357 -280.052221) (xy 193.876458 -280.068109) (xy 193.825676 -280.076152) (xy 193.77426 -280.076152)
			(xy 193.723478 -280.068109) (xy 193.674579 -280.052221) (xy 193.628767 -280.028878) (xy 193.587171 -279.998657)
			(xy 193.550815 -279.962301) (xy 193.520594 -279.920705) (xy 193.497251 -279.874893) (xy 193.481363 -279.825994)
			(xy 193.47332 -279.775212) (xy 193.154683 -279.775212) (xy 193.146926 -279.822942) (xy 193.131342 -279.869623)
			(xy 193.108471 -279.9132) (xy 193.078906 -279.952544) (xy 193.043413 -279.986636) (xy 193.00291 -280.014592)
			(xy 192.958448 -280.03569) (xy 192.911177 -280.049382) (xy 192.862322 -280.055314) (xy 192.813147 -280.053333)
			(xy 192.764928 -280.043489) (xy 192.718912 -280.026037) (xy 192.676291 -280.00143) (xy 192.63817 -279.970305)
			(xy 192.605535 -279.933468) (xy 192.579232 -279.891872) (xy 192.559941 -279.846596) (xy 192.548164 -279.798812)
			(xy 192.544204 -279.749758) (xy 192.227195 -279.749758) (xy 192.226696 -279.775212) (xy 192.218653 -279.825994)
			(xy 192.202765 -279.874893) (xy 192.179422 -279.920705) (xy 192.149201 -279.962301) (xy 192.112845 -279.998657)
			(xy 192.071249 -280.028878) (xy 192.025437 -280.052221) (xy 191.976538 -280.068109) (xy 191.925756 -280.076152)
			(xy 191.87434 -280.076152) (xy 191.823558 -280.068109) (xy 191.774659 -280.052221) (xy 191.728847 -280.028878)
			(xy 191.687251 -279.998657) (xy 191.650895 -279.962301) (xy 191.620674 -279.920705) (xy 191.597331 -279.874893)
			(xy 191.581443 -279.825994) (xy 191.5734 -279.775212) (xy 191.254509 -279.775212) (xy 191.246752 -279.822942)
			(xy 191.231168 -279.869623) (xy 191.208297 -279.9132) (xy 191.178732 -279.952544) (xy 191.143239 -279.986636)
			(xy 191.102736 -280.014592) (xy 191.058274 -280.03569) (xy 191.011003 -280.049382) (xy 190.962148 -280.055314)
			(xy 190.912973 -280.053333) (xy 190.864754 -280.043489) (xy 190.818738 -280.026037) (xy 190.776117 -280.00143)
			(xy 190.737996 -279.970305) (xy 190.705361 -279.933468) (xy 190.679058 -279.891872) (xy 190.659767 -279.846596)
			(xy 190.64799 -279.798812) (xy 190.64403 -279.749758) (xy 190.327021 -279.749758) (xy 190.326522 -279.775212)
			(xy 190.318479 -279.825994) (xy 190.302591 -279.874893) (xy 190.279248 -279.920705) (xy 190.249027 -279.962301)
			(xy 190.212671 -279.998657) (xy 190.171075 -280.028878) (xy 190.125263 -280.052221) (xy 190.076364 -280.068109)
			(xy 190.025582 -280.076152) (xy 189.974166 -280.076152) (xy 189.923384 -280.068109) (xy 189.874485 -280.052221)
			(xy 189.828673 -280.028878) (xy 189.787077 -279.998657) (xy 189.750721 -279.962301) (xy 189.7205 -279.920705)
			(xy 189.697157 -279.874893) (xy 189.681269 -279.825994) (xy 189.673226 -279.775212) (xy 189.354589 -279.775212)
			(xy 189.346832 -279.822942) (xy 189.331248 -279.869623) (xy 189.308377 -279.9132) (xy 189.278812 -279.952544)
			(xy 189.243319 -279.986636) (xy 189.202816 -280.014592) (xy 189.158354 -280.03569) (xy 189.111083 -280.049382)
			(xy 189.062228 -280.055314) (xy 189.013053 -280.053333) (xy 188.964834 -280.043489) (xy 188.918818 -280.026037)
			(xy 188.876197 -280.00143) (xy 188.838076 -279.970305) (xy 188.805441 -279.933468) (xy 188.779138 -279.891872)
			(xy 188.759847 -279.846596) (xy 188.74807 -279.798812) (xy 188.74411 -279.749758) (xy 188.427101 -279.749758)
			(xy 188.426602 -279.775212) (xy 188.418559 -279.825994) (xy 188.402671 -279.874893) (xy 188.379328 -279.920705)
			(xy 188.349107 -279.962301) (xy 188.312751 -279.998657) (xy 188.271155 -280.028878) (xy 188.225343 -280.052221)
			(xy 188.176444 -280.068109) (xy 188.125662 -280.076152) (xy 188.074246 -280.076152) (xy 188.023464 -280.068109)
			(xy 187.974565 -280.052221) (xy 187.928753 -280.028878) (xy 187.887157 -279.998657) (xy 187.850801 -279.962301)
			(xy 187.82058 -279.920705) (xy 187.797237 -279.874893) (xy 187.781349 -279.825994) (xy 187.773306 -279.775212)
			(xy 187.454669 -279.775212) (xy 187.446912 -279.822942) (xy 187.431328 -279.869623) (xy 187.408457 -279.9132)
			(xy 187.378892 -279.952544) (xy 187.343399 -279.986636) (xy 187.302896 -280.014592) (xy 187.258434 -280.03569)
			(xy 187.211163 -280.049382) (xy 187.162308 -280.055314) (xy 187.113133 -280.053333) (xy 187.064914 -280.043489)
			(xy 187.018898 -280.026037) (xy 186.976277 -280.00143) (xy 186.938156 -279.970305) (xy 186.905521 -279.933468)
			(xy 186.879218 -279.891872) (xy 186.859927 -279.846596) (xy 186.84815 -279.798812) (xy 186.84419 -279.749758)
			(xy 186.527181 -279.749758) (xy 186.526682 -279.775212) (xy 186.518639 -279.825994) (xy 186.502751 -279.874893)
			(xy 186.479408 -279.920705) (xy 186.449187 -279.962301) (xy 186.412831 -279.998657) (xy 186.371235 -280.028878)
			(xy 186.325423 -280.052221) (xy 186.276524 -280.068109) (xy 186.225742 -280.076152) (xy 186.174326 -280.076152)
			(xy 186.123544 -280.068109) (xy 186.074645 -280.052221) (xy 186.028833 -280.028878) (xy 185.987237 -279.998657)
			(xy 185.950881 -279.962301) (xy 185.92066 -279.920705) (xy 185.897317 -279.874893) (xy 185.881429 -279.825994)
			(xy 185.873386 -279.775212) (xy 185.554749 -279.775212) (xy 185.546992 -279.822942) (xy 185.531408 -279.869623)
			(xy 185.508537 -279.9132) (xy 185.478972 -279.952544) (xy 185.443479 -279.986636) (xy 185.402976 -280.014592)
			(xy 185.358514 -280.03569) (xy 185.311243 -280.049382) (xy 185.262388 -280.055314) (xy 185.213213 -280.053333)
			(xy 185.164994 -280.043489) (xy 185.118978 -280.026037) (xy 185.076357 -280.00143) (xy 185.038236 -279.970305)
			(xy 185.005601 -279.933468) (xy 184.979298 -279.891872) (xy 184.960007 -279.846596) (xy 184.94823 -279.798812)
			(xy 184.94427 -279.749758) (xy 184.627007 -279.749758) (xy 184.626508 -279.775212) (xy 184.618465 -279.825994)
			(xy 184.602577 -279.874893) (xy 184.579234 -279.920705) (xy 184.549013 -279.962301) (xy 184.512657 -279.998657)
			(xy 184.471061 -280.028878) (xy 184.425249 -280.052221) (xy 184.37635 -280.068109) (xy 184.325568 -280.076152)
			(xy 184.274152 -280.076152) (xy 184.22337 -280.068109) (xy 184.174471 -280.052221) (xy 184.128659 -280.028878)
			(xy 184.087063 -279.998657) (xy 184.050707 -279.962301) (xy 184.020486 -279.920705) (xy 183.997143 -279.874893)
			(xy 183.981255 -279.825994) (xy 183.973212 -279.775212) (xy 183.654575 -279.775212) (xy 183.646818 -279.822942)
			(xy 183.631234 -279.869623) (xy 183.608363 -279.9132) (xy 183.578798 -279.952544) (xy 183.543305 -279.986636)
			(xy 183.502802 -280.014592) (xy 183.45834 -280.03569) (xy 183.411069 -280.049382) (xy 183.362214 -280.055314)
			(xy 183.313039 -280.053333) (xy 183.26482 -280.043489) (xy 183.218804 -280.026037) (xy 183.176183 -280.00143)
			(xy 183.138062 -279.970305) (xy 183.105427 -279.933468) (xy 183.079124 -279.891872) (xy 183.059833 -279.846596)
			(xy 183.048056 -279.798812) (xy 183.044096 -279.749758) (xy 182.727087 -279.749758) (xy 182.726588 -279.775212)
			(xy 182.718545 -279.825994) (xy 182.702657 -279.874893) (xy 182.679314 -279.920705) (xy 182.649093 -279.962301)
			(xy 182.612737 -279.998657) (xy 182.571141 -280.028878) (xy 182.525329 -280.052221) (xy 182.47643 -280.068109)
			(xy 182.425648 -280.076152) (xy 182.374232 -280.076152) (xy 182.32345 -280.068109) (xy 182.274551 -280.052221)
			(xy 182.228739 -280.028878) (xy 182.187143 -279.998657) (xy 182.150787 -279.962301) (xy 182.120566 -279.920705)
			(xy 182.097223 -279.874893) (xy 182.081335 -279.825994) (xy 182.073292 -279.775212) (xy 181.754655 -279.775212)
			(xy 181.746898 -279.822942) (xy 181.731314 -279.869623) (xy 181.708443 -279.9132) (xy 181.678878 -279.952544)
			(xy 181.643385 -279.986636) (xy 181.602882 -280.014592) (xy 181.55842 -280.03569) (xy 181.511149 -280.049382)
			(xy 181.462294 -280.055314) (xy 181.413119 -280.053333) (xy 181.3649 -280.043489) (xy 181.318884 -280.026037)
			(xy 181.276263 -280.00143) (xy 181.238142 -279.970305) (xy 181.205507 -279.933468) (xy 181.179204 -279.891872)
			(xy 181.159913 -279.846596) (xy 181.148136 -279.798812) (xy 181.144176 -279.749758) (xy 180.827167 -279.749758)
			(xy 180.826668 -279.775212) (xy 180.818625 -279.825994) (xy 180.802737 -279.874893) (xy 180.779394 -279.920705)
			(xy 180.749173 -279.962301) (xy 180.712817 -279.998657) (xy 180.671221 -280.028878) (xy 180.625409 -280.052221)
			(xy 180.57651 -280.068109) (xy 180.525728 -280.076152) (xy 180.474312 -280.076152) (xy 180.42353 -280.068109)
			(xy 180.374631 -280.052221) (xy 180.328819 -280.028878) (xy 180.287223 -279.998657) (xy 180.250867 -279.962301)
			(xy 180.220646 -279.920705) (xy 180.197303 -279.874893) (xy 180.181415 -279.825994) (xy 180.173372 -279.775212)
			(xy 179.854735 -279.775212) (xy 179.846978 -279.822942) (xy 179.831394 -279.869623) (xy 179.808523 -279.9132)
			(xy 179.778958 -279.952544) (xy 179.743465 -279.986636) (xy 179.702962 -280.014592) (xy 179.6585 -280.03569)
			(xy 179.611229 -280.049382) (xy 179.562374 -280.055314) (xy 179.513199 -280.053333) (xy 179.46498 -280.043489)
			(xy 179.418964 -280.026037) (xy 179.376343 -280.00143) (xy 179.338222 -279.970305) (xy 179.305587 -279.933468)
			(xy 179.279284 -279.891872) (xy 179.259993 -279.846596) (xy 179.248216 -279.798812) (xy 179.244256 -279.749758)
			(xy 178.926993 -279.749758) (xy 178.926494 -279.775212) (xy 178.918451 -279.825994) (xy 178.902563 -279.874893)
			(xy 178.87922 -279.920705) (xy 178.848999 -279.962301) (xy 178.812643 -279.998657) (xy 178.771047 -280.028878)
			(xy 178.725235 -280.052221) (xy 178.676336 -280.068109) (xy 178.625554 -280.076152) (xy 178.574138 -280.076152)
			(xy 178.523356 -280.068109) (xy 178.474457 -280.052221) (xy 178.428645 -280.028878) (xy 178.387049 -279.998657)
			(xy 178.350693 -279.962301) (xy 178.320472 -279.920705) (xy 178.297129 -279.874893) (xy 178.281241 -279.825994)
			(xy 178.273198 -279.775212) (xy 177.954561 -279.775212) (xy 177.946804 -279.822942) (xy 177.93122 -279.869623)
			(xy 177.908349 -279.9132) (xy 177.878784 -279.952544) (xy 177.843291 -279.986636) (xy 177.802788 -280.014592)
			(xy 177.758326 -280.03569) (xy 177.711055 -280.049382) (xy 177.6622 -280.055314) (xy 177.613025 -280.053333)
			(xy 177.564806 -280.043489) (xy 177.51879 -280.026037) (xy 177.476169 -280.00143) (xy 177.438048 -279.970305)
			(xy 177.405413 -279.933468) (xy 177.37911 -279.891872) (xy 177.359819 -279.846596) (xy 177.348042 -279.798812)
			(xy 177.344082 -279.749758) (xy 177.027073 -279.749758) (xy 177.026574 -279.775212) (xy 177.018531 -279.825994)
			(xy 177.002643 -279.874893) (xy 176.9793 -279.920705) (xy 176.949079 -279.962301) (xy 176.912723 -279.998657)
			(xy 176.871127 -280.028878) (xy 176.825315 -280.052221) (xy 176.776416 -280.068109) (xy 176.725634 -280.076152)
			(xy 176.674218 -280.076152) (xy 176.623436 -280.068109) (xy 176.574537 -280.052221) (xy 176.528725 -280.028878)
			(xy 176.487129 -279.998657) (xy 176.450773 -279.962301) (xy 176.420552 -279.920705) (xy 176.397209 -279.874893)
			(xy 176.381321 -279.825994) (xy 176.373278 -279.775212) (xy 176.054641 -279.775212) (xy 176.046884 -279.822942)
			(xy 176.0313 -279.869623) (xy 176.008429 -279.9132) (xy 175.978864 -279.952544) (xy 175.943371 -279.986636)
			(xy 175.902868 -280.014592) (xy 175.858406 -280.03569) (xy 175.811135 -280.049382) (xy 175.76228 -280.055314)
			(xy 175.713105 -280.053333) (xy 175.664886 -280.043489) (xy 175.61887 -280.026037) (xy 175.576249 -280.00143)
			(xy 175.538128 -279.970305) (xy 175.505493 -279.933468) (xy 175.47919 -279.891872) (xy 175.459899 -279.846596)
			(xy 175.448122 -279.798812) (xy 175.444162 -279.749758) (xy 175.127153 -279.749758) (xy 175.126654 -279.775212)
			(xy 175.118611 -279.825994) (xy 175.102723 -279.874893) (xy 175.07938 -279.920705) (xy 175.049159 -279.962301)
			(xy 175.012803 -279.998657) (xy 174.971207 -280.028878) (xy 174.925395 -280.052221) (xy 174.876496 -280.068109)
			(xy 174.825714 -280.076152) (xy 174.774298 -280.076152) (xy 174.723516 -280.068109) (xy 174.674617 -280.052221)
			(xy 174.628805 -280.028878) (xy 174.587209 -279.998657) (xy 174.550853 -279.962301) (xy 174.520632 -279.920705)
			(xy 174.497289 -279.874893) (xy 174.481401 -279.825994) (xy 174.473358 -279.775212) (xy 174.154721 -279.775212)
			(xy 174.146964 -279.822942) (xy 174.13138 -279.869623) (xy 174.108509 -279.9132) (xy 174.078944 -279.952544)
			(xy 174.043451 -279.986636) (xy 174.002948 -280.014592) (xy 173.958486 -280.03569) (xy 173.911215 -280.049382)
			(xy 173.86236 -280.055314) (xy 173.813185 -280.053333) (xy 173.764966 -280.043489) (xy 173.71895 -280.026037)
			(xy 173.676329 -280.00143) (xy 173.638208 -279.970305) (xy 173.605573 -279.933468) (xy 173.57927 -279.891872)
			(xy 173.559979 -279.846596) (xy 173.548202 -279.798812) (xy 173.544242 -279.749758) (xy 173.226979 -279.749758)
			(xy 173.22648 -279.775212) (xy 173.218437 -279.825994) (xy 173.202549 -279.874893) (xy 173.179206 -279.920705)
			(xy 173.148985 -279.962301) (xy 173.112629 -279.998657) (xy 173.071033 -280.028878) (xy 173.025221 -280.052221)
			(xy 172.976322 -280.068109) (xy 172.92554 -280.076152) (xy 172.874124 -280.076152) (xy 172.823342 -280.068109)
			(xy 172.774443 -280.052221) (xy 172.728631 -280.028878) (xy 172.687035 -279.998657) (xy 172.650679 -279.962301)
			(xy 172.620458 -279.920705) (xy 172.597115 -279.874893) (xy 172.581227 -279.825994) (xy 172.573184 -279.775212)
			(xy 172.254547 -279.775212) (xy 172.24679 -279.822942) (xy 172.231206 -279.869623) (xy 172.208335 -279.9132)
			(xy 172.17877 -279.952544) (xy 172.143277 -279.986636) (xy 172.102774 -280.014592) (xy 172.058312 -280.03569)
			(xy 172.011041 -280.049382) (xy 171.962186 -280.055314) (xy 171.913011 -280.053333) (xy 171.864792 -280.043489)
			(xy 171.818776 -280.026037) (xy 171.776155 -280.00143) (xy 171.738034 -279.970305) (xy 171.705399 -279.933468)
			(xy 171.679096 -279.891872) (xy 171.659805 -279.846596) (xy 171.648028 -279.798812) (xy 171.644068 -279.749758)
			(xy 171.327059 -279.749758) (xy 171.32656 -279.775212) (xy 171.318517 -279.825994) (xy 171.302629 -279.874893)
			(xy 171.279286 -279.920705) (xy 171.249065 -279.962301) (xy 171.212709 -279.998657) (xy 171.171113 -280.028878)
			(xy 171.125301 -280.052221) (xy 171.076402 -280.068109) (xy 171.02562 -280.076152) (xy 170.974204 -280.076152)
			(xy 170.923422 -280.068109) (xy 170.874523 -280.052221) (xy 170.828711 -280.028878) (xy 170.787115 -279.998657)
			(xy 170.750759 -279.962301) (xy 170.720538 -279.920705) (xy 170.697195 -279.874893) (xy 170.681307 -279.825994)
			(xy 170.673264 -279.775212) (xy 170.354627 -279.775212) (xy 170.34687 -279.822942) (xy 170.331286 -279.869623)
			(xy 170.308415 -279.9132) (xy 170.27885 -279.952544) (xy 170.243357 -279.986636) (xy 170.202854 -280.014592)
			(xy 170.158392 -280.03569) (xy 170.111121 -280.049382) (xy 170.062266 -280.055314) (xy 170.013091 -280.053333)
			(xy 169.964872 -280.043489) (xy 169.918856 -280.026037) (xy 169.876235 -280.00143) (xy 169.838114 -279.970305)
			(xy 169.805479 -279.933468) (xy 169.779176 -279.891872) (xy 169.759885 -279.846596) (xy 169.748108 -279.798812)
			(xy 169.744148 -279.749758) (xy 169.427139 -279.749758) (xy 169.42664 -279.775212) (xy 169.418597 -279.825994)
			(xy 169.402709 -279.874893) (xy 169.379366 -279.920705) (xy 169.349145 -279.962301) (xy 169.312789 -279.998657)
			(xy 169.271193 -280.028878) (xy 169.225381 -280.052221) (xy 169.176482 -280.068109) (xy 169.1257 -280.076152)
			(xy 169.074284 -280.076152) (xy 169.023502 -280.068109) (xy 168.974603 -280.052221) (xy 168.928791 -280.028878)
			(xy 168.887195 -279.998657) (xy 168.850839 -279.962301) (xy 168.820618 -279.920705) (xy 168.797275 -279.874893)
			(xy 168.781387 -279.825994) (xy 168.773344 -279.775212) (xy 168.454707 -279.775212) (xy 168.44695 -279.822942)
			(xy 168.431366 -279.869623) (xy 168.408495 -279.9132) (xy 168.37893 -279.952544) (xy 168.343437 -279.986636)
			(xy 168.302934 -280.014592) (xy 168.258472 -280.03569) (xy 168.211201 -280.049382) (xy 168.162346 -280.055314)
			(xy 168.113171 -280.053333) (xy 168.064952 -280.043489) (xy 168.018936 -280.026037) (xy 167.976315 -280.00143)
			(xy 167.938194 -279.970305) (xy 167.905559 -279.933468) (xy 167.879256 -279.891872) (xy 167.859965 -279.846596)
			(xy 167.848188 -279.798812) (xy 167.844228 -279.749758) (xy 167.527219 -279.749758) (xy 167.52672 -279.775212)
			(xy 167.518677 -279.825994) (xy 167.502789 -279.874893) (xy 167.479446 -279.920705) (xy 167.449225 -279.962301)
			(xy 167.412869 -279.998657) (xy 167.371273 -280.028878) (xy 167.325461 -280.052221) (xy 167.276562 -280.068109)
			(xy 167.22578 -280.076152) (xy 167.174364 -280.076152) (xy 167.123582 -280.068109) (xy 167.074683 -280.052221)
			(xy 167.028871 -280.028878) (xy 166.987275 -279.998657) (xy 166.950919 -279.962301) (xy 166.920698 -279.920705)
			(xy 166.897355 -279.874893) (xy 166.881467 -279.825994) (xy 166.873424 -279.775212) (xy 166.554533 -279.775212)
			(xy 166.546776 -279.822942) (xy 166.531192 -279.869623) (xy 166.508321 -279.9132) (xy 166.478756 -279.952544)
			(xy 166.443263 -279.986636) (xy 166.40276 -280.014592) (xy 166.358298 -280.03569) (xy 166.311027 -280.049382)
			(xy 166.262172 -280.055314) (xy 166.212997 -280.053333) (xy 166.164778 -280.043489) (xy 166.118762 -280.026037)
			(xy 166.076141 -280.00143) (xy 166.03802 -279.970305) (xy 166.005385 -279.933468) (xy 165.979082 -279.891872)
			(xy 165.959791 -279.846596) (xy 165.948014 -279.798812) (xy 165.944054 -279.749758) (xy 165.627045 -279.749758)
			(xy 165.626546 -279.775212) (xy 165.618503 -279.825994) (xy 165.602615 -279.874893) (xy 165.579272 -279.920705)
			(xy 165.549051 -279.962301) (xy 165.512695 -279.998657) (xy 165.471099 -280.028878) (xy 165.425287 -280.052221)
			(xy 165.376388 -280.068109) (xy 165.325606 -280.076152) (xy 165.27419 -280.076152) (xy 165.223408 -280.068109)
			(xy 165.174509 -280.052221) (xy 165.128697 -280.028878) (xy 165.087101 -279.998657) (xy 165.050745 -279.962301)
			(xy 165.020524 -279.920705) (xy 164.997181 -279.874893) (xy 164.981293 -279.825994) (xy 164.97325 -279.775212)
			(xy 164.654613 -279.775212) (xy 164.646856 -279.822942) (xy 164.631272 -279.869623) (xy 164.608401 -279.9132)
			(xy 164.578836 -279.952544) (xy 164.543343 -279.986636) (xy 164.50284 -280.014592) (xy 164.458378 -280.03569)
			(xy 164.411107 -280.049382) (xy 164.362252 -280.055314) (xy 164.313077 -280.053333) (xy 164.264858 -280.043489)
			(xy 164.218842 -280.026037) (xy 164.176221 -280.00143) (xy 164.1381 -279.970305) (xy 164.105465 -279.933468)
			(xy 164.079162 -279.891872) (xy 164.059871 -279.846596) (xy 164.048094 -279.798812) (xy 164.044134 -279.749758)
			(xy 163.727125 -279.749758) (xy 163.726626 -279.775212) (xy 163.718583 -279.825994) (xy 163.702695 -279.874893)
			(xy 163.679352 -279.920705) (xy 163.649131 -279.962301) (xy 163.612775 -279.998657) (xy 163.571179 -280.028878)
			(xy 163.525367 -280.052221) (xy 163.476468 -280.068109) (xy 163.425686 -280.076152) (xy 163.37427 -280.076152)
			(xy 163.323488 -280.068109) (xy 163.274589 -280.052221) (xy 163.228777 -280.028878) (xy 163.187181 -279.998657)
			(xy 163.150825 -279.962301) (xy 163.120604 -279.920705) (xy 163.097261 -279.874893) (xy 163.081373 -279.825994)
			(xy 163.07333 -279.775212) (xy 162.754693 -279.775212) (xy 162.746936 -279.822942) (xy 162.731352 -279.869623)
			(xy 162.708481 -279.9132) (xy 162.678916 -279.952544) (xy 162.643423 -279.986636) (xy 162.60292 -280.014592)
			(xy 162.558458 -280.03569) (xy 162.511187 -280.049382) (xy 162.462332 -280.055314) (xy 162.413157 -280.053333)
			(xy 162.364938 -280.043489) (xy 162.318922 -280.026037) (xy 162.276301 -280.00143) (xy 162.23818 -279.970305)
			(xy 162.205545 -279.933468) (xy 162.179242 -279.891872) (xy 162.159951 -279.846596) (xy 162.148174 -279.798812)
			(xy 162.144214 -279.749758) (xy 161.827205 -279.749758) (xy 161.826706 -279.775212) (xy 161.818663 -279.825994)
			(xy 161.802775 -279.874893) (xy 161.779432 -279.920705) (xy 161.749211 -279.962301) (xy 161.712855 -279.998657)
			(xy 161.671259 -280.028878) (xy 161.625447 -280.052221) (xy 161.576548 -280.068109) (xy 161.525766 -280.076152)
			(xy 161.47435 -280.076152) (xy 161.423568 -280.068109) (xy 161.374669 -280.052221) (xy 161.328857 -280.028878)
			(xy 161.287261 -279.998657) (xy 161.250905 -279.962301) (xy 161.220684 -279.920705) (xy 161.197341 -279.874893)
			(xy 161.181453 -279.825994) (xy 161.17341 -279.775212) (xy 160.853483 -279.775212) (xy 160.851419 -279.800127)
			(xy 160.839024 -279.849081) (xy 160.81874 -279.895327) (xy 160.791122 -279.937605) (xy 160.756922 -279.974761)
			(xy 160.717074 -280.005781) (xy 160.672664 -280.02982) (xy 160.624903 -280.046223) (xy 160.575093 -280.054541)
			(xy 160.549844 -280.055066) (xy 160.535661 -280.054884) (xy 160.507421 -280.052216) (xy 160.493456 -280.049732)
			(xy 160.48101 -280.047446) (xy 160.457388 -280.054812) (xy 160.41116 -280.10104) (xy 224.384106 -280.10104)
			(xy 224.388177 -280.045418) (xy 224.400303 -279.990981) (xy 224.420226 -279.93889) (xy 224.447522 -279.890255)
			(xy 224.481608 -279.846112) (xy 224.521757 -279.807403) (xy 224.567115 -279.774952) (xy 224.616715 -279.749451)
			(xy 224.669499 -279.731444) (xy 224.724342 -279.721314) (xy 224.780076 -279.719277) (xy 224.835513 -279.725377)
			(xy 224.88947 -279.739483) (xy 224.940799 -279.761295) (xy 224.988405 -279.790349) (xy 225.031273 -279.826024)
			(xy 225.06849 -279.867561) (xy 225.099263 -279.914074) (xy 225.122935 -279.964571) (xy 225.139003 -280.017978)
			(xy 225.147123 -280.073154) (xy 225.147632 -280.10104) (xy 225.147123 -280.128926) (xy 225.139003 -280.184102)
			(xy 225.122935 -280.237509) (xy 225.099263 -280.288006) (xy 225.06849 -280.334519) (xy 225.031273 -280.376056)
			(xy 224.988405 -280.411731) (xy 224.940799 -280.440785) (xy 224.88947 -280.462597) (xy 224.835513 -280.476703)
			(xy 224.780076 -280.482803) (xy 224.724342 -280.480766) (xy 224.669499 -280.470636) (xy 224.616715 -280.452629)
			(xy 224.567115 -280.427128) (xy 224.521757 -280.394677) (xy 224.481608 -280.355968) (xy 224.447522 -280.311825)
			(xy 224.420226 -280.26319) (xy 224.400303 -280.211099) (xy 224.388177 -280.156662) (xy 224.384106 -280.10104)
			(xy 160.41116 -280.10104) (xy 160.379918 -280.132282) (xy 160.372552 -280.155904) (xy 160.374838 -280.16835)
			(xy 160.377317 -280.182316) (xy 160.379987 -280.210555) (xy 160.380172 -280.224738) (xy 160.380001 -280.238921)
			(xy 160.377325 -280.267161) (xy 160.374838 -280.281126) (xy 160.372552 -280.293572) (xy 160.379918 -280.317194)
			(xy 160.457388 -280.394664) (xy 160.48101 -280.40203) (xy 160.493456 -280.399744) (xy 160.507421 -280.397264)
			(xy 160.535661 -280.394595) (xy 160.549844 -280.39441) (xy 160.57466 -280.394925) (xy 160.623638 -280.402962)
			(xy 160.67067 -280.418815) (xy 160.714518 -280.442069) (xy 160.754026 -280.47211) (xy 160.788155 -280.508147)
			(xy 160.816004 -280.54923) (xy 160.836839 -280.594277) (xy 160.850113 -280.642101) (xy 160.855476 -280.691443)
			(xy 160.853631 -280.725426) (xy 161.17341 -280.725426) (xy 161.17341 -280.67401) (xy 161.181453 -280.623228)
			(xy 161.197341 -280.574329) (xy 161.220684 -280.528517) (xy 161.250905 -280.486921) (xy 161.287261 -280.450565)
			(xy 161.328857 -280.420344) (xy 161.374669 -280.397001) (xy 161.423568 -280.381113) (xy 161.47435 -280.37307)
			(xy 161.525766 -280.37307) (xy 161.576548 -280.381113) (xy 161.625447 -280.397001) (xy 161.671259 -280.420344)
			(xy 161.712855 -280.450565) (xy 161.749211 -280.486921) (xy 161.779432 -280.528517) (xy 161.802775 -280.574329)
			(xy 161.818663 -280.623228) (xy 161.826706 -280.67401) (xy 161.82721 -280.699718) (xy 162.144214 -280.699718)
			(xy 162.148174 -280.650664) (xy 162.159951 -280.60288) (xy 162.179242 -280.557604) (xy 162.205545 -280.516008)
			(xy 162.23818 -280.479171) (xy 162.276301 -280.448046) (xy 162.318922 -280.423439) (xy 162.364938 -280.405987)
			(xy 162.413157 -280.396143) (xy 162.462332 -280.394162) (xy 162.511187 -280.400094) (xy 162.558458 -280.413786)
			(xy 162.60292 -280.434884) (xy 162.643423 -280.46284) (xy 162.678916 -280.496932) (xy 162.708481 -280.536276)
			(xy 162.731352 -280.579853) (xy 162.746936 -280.626534) (xy 162.754831 -280.675111) (xy 162.755326 -280.699718)
			(xy 162.754831 -280.724325) (xy 162.754652 -280.725426) (xy 163.07333 -280.725426) (xy 163.07333 -280.67401)
			(xy 163.081373 -280.623228) (xy 163.097261 -280.574329) (xy 163.120604 -280.528517) (xy 163.150825 -280.486921)
			(xy 163.187181 -280.450565) (xy 163.228777 -280.420344) (xy 163.274589 -280.397001) (xy 163.323488 -280.381113)
			(xy 163.37427 -280.37307) (xy 163.425686 -280.37307) (xy 163.476468 -280.381113) (xy 163.525367 -280.397001)
			(xy 163.571179 -280.420344) (xy 163.612775 -280.450565) (xy 163.649131 -280.486921) (xy 163.679352 -280.528517)
			(xy 163.702695 -280.574329) (xy 163.718583 -280.623228) (xy 163.726626 -280.67401) (xy 163.72713 -280.699718)
			(xy 164.044134 -280.699718) (xy 164.048094 -280.650664) (xy 164.059871 -280.60288) (xy 164.079162 -280.557604)
			(xy 164.105465 -280.516008) (xy 164.1381 -280.479171) (xy 164.176221 -280.448046) (xy 164.218842 -280.423439)
			(xy 164.264858 -280.405987) (xy 164.313077 -280.396143) (xy 164.362252 -280.394162) (xy 164.411107 -280.400094)
			(xy 164.458378 -280.413786) (xy 164.50284 -280.434884) (xy 164.543343 -280.46284) (xy 164.578836 -280.496932)
			(xy 164.608401 -280.536276) (xy 164.631272 -280.579853) (xy 164.646856 -280.626534) (xy 164.654751 -280.675111)
			(xy 164.655246 -280.699718) (xy 164.654751 -280.724325) (xy 164.654572 -280.725426) (xy 164.97325 -280.725426)
			(xy 164.97325 -280.67401) (xy 164.981293 -280.623228) (xy 164.997181 -280.574329) (xy 165.020524 -280.528517)
			(xy 165.050745 -280.486921) (xy 165.087101 -280.450565) (xy 165.128697 -280.420344) (xy 165.174509 -280.397001)
			(xy 165.223408 -280.381113) (xy 165.27419 -280.37307) (xy 165.325606 -280.37307) (xy 165.376388 -280.381113)
			(xy 165.425287 -280.397001) (xy 165.471099 -280.420344) (xy 165.512695 -280.450565) (xy 165.549051 -280.486921)
			(xy 165.579272 -280.528517) (xy 165.602615 -280.574329) (xy 165.618503 -280.623228) (xy 165.626546 -280.67401)
			(xy 165.62705 -280.699718) (xy 165.944054 -280.699718) (xy 165.948014 -280.650664) (xy 165.959791 -280.60288)
			(xy 165.979082 -280.557604) (xy 166.005385 -280.516008) (xy 166.03802 -280.479171) (xy 166.076141 -280.448046)
			(xy 166.118762 -280.423439) (xy 166.164778 -280.405987) (xy 166.212997 -280.396143) (xy 166.262172 -280.394162)
			(xy 166.311027 -280.400094) (xy 166.358298 -280.413786) (xy 166.40276 -280.434884) (xy 166.443263 -280.46284)
			(xy 166.478756 -280.496932) (xy 166.508321 -280.536276) (xy 166.531192 -280.579853) (xy 166.546776 -280.626534)
			(xy 166.554671 -280.675111) (xy 166.555166 -280.699718) (xy 166.554671 -280.724325) (xy 166.554492 -280.725426)
			(xy 166.873424 -280.725426) (xy 166.873424 -280.67401) (xy 166.881467 -280.623228) (xy 166.897355 -280.574329)
			(xy 166.920698 -280.528517) (xy 166.950919 -280.486921) (xy 166.987275 -280.450565) (xy 167.028871 -280.420344)
			(xy 167.074683 -280.397001) (xy 167.123582 -280.381113) (xy 167.174364 -280.37307) (xy 167.22578 -280.37307)
			(xy 167.276562 -280.381113) (xy 167.325461 -280.397001) (xy 167.371273 -280.420344) (xy 167.412869 -280.450565)
			(xy 167.449225 -280.486921) (xy 167.479446 -280.528517) (xy 167.502789 -280.574329) (xy 167.518677 -280.623228)
			(xy 167.52672 -280.67401) (xy 167.527224 -280.699718) (xy 167.844228 -280.699718) (xy 167.848188 -280.650664)
			(xy 167.859965 -280.60288) (xy 167.879256 -280.557604) (xy 167.905559 -280.516008) (xy 167.938194 -280.479171)
			(xy 167.976315 -280.448046) (xy 168.018936 -280.423439) (xy 168.064952 -280.405987) (xy 168.113171 -280.396143)
			(xy 168.162346 -280.394162) (xy 168.211201 -280.400094) (xy 168.258472 -280.413786) (xy 168.302934 -280.434884)
			(xy 168.343437 -280.46284) (xy 168.37893 -280.496932) (xy 168.408495 -280.536276) (xy 168.431366 -280.579853)
			(xy 168.44695 -280.626534) (xy 168.454845 -280.675111) (xy 168.45534 -280.699718) (xy 168.454845 -280.724325)
			(xy 168.454666 -280.725426) (xy 168.773344 -280.725426) (xy 168.773344 -280.67401) (xy 168.781387 -280.623228)
			(xy 168.797275 -280.574329) (xy 168.820618 -280.528517) (xy 168.850839 -280.486921) (xy 168.887195 -280.450565)
			(xy 168.928791 -280.420344) (xy 168.974603 -280.397001) (xy 169.023502 -280.381113) (xy 169.074284 -280.37307)
			(xy 169.1257 -280.37307) (xy 169.176482 -280.381113) (xy 169.225381 -280.397001) (xy 169.271193 -280.420344)
			(xy 169.312789 -280.450565) (xy 169.349145 -280.486921) (xy 169.379366 -280.528517) (xy 169.402709 -280.574329)
			(xy 169.418597 -280.623228) (xy 169.42664 -280.67401) (xy 169.427144 -280.699718) (xy 169.744148 -280.699718)
			(xy 169.748108 -280.650664) (xy 169.759885 -280.60288) (xy 169.779176 -280.557604) (xy 169.805479 -280.516008)
			(xy 169.838114 -280.479171) (xy 169.876235 -280.448046) (xy 169.918856 -280.423439) (xy 169.964872 -280.405987)
			(xy 170.013091 -280.396143) (xy 170.062266 -280.394162) (xy 170.111121 -280.400094) (xy 170.158392 -280.413786)
			(xy 170.202854 -280.434884) (xy 170.243357 -280.46284) (xy 170.27885 -280.496932) (xy 170.308415 -280.536276)
			(xy 170.331286 -280.579853) (xy 170.34687 -280.626534) (xy 170.354765 -280.675111) (xy 170.35526 -280.699718)
			(xy 170.354765 -280.724325) (xy 170.354586 -280.725426) (xy 170.673264 -280.725426) (xy 170.673264 -280.67401)
			(xy 170.681307 -280.623228) (xy 170.697195 -280.574329) (xy 170.720538 -280.528517) (xy 170.750759 -280.486921)
			(xy 170.787115 -280.450565) (xy 170.828711 -280.420344) (xy 170.874523 -280.397001) (xy 170.923422 -280.381113)
			(xy 170.974204 -280.37307) (xy 171.02562 -280.37307) (xy 171.076402 -280.381113) (xy 171.125301 -280.397001)
			(xy 171.171113 -280.420344) (xy 171.212709 -280.450565) (xy 171.249065 -280.486921) (xy 171.279286 -280.528517)
			(xy 171.302629 -280.574329) (xy 171.318517 -280.623228) (xy 171.32656 -280.67401) (xy 171.327064 -280.699718)
			(xy 171.644068 -280.699718) (xy 171.648028 -280.650664) (xy 171.659805 -280.60288) (xy 171.679096 -280.557604)
			(xy 171.705399 -280.516008) (xy 171.738034 -280.479171) (xy 171.776155 -280.448046) (xy 171.818776 -280.423439)
			(xy 171.864792 -280.405987) (xy 171.913011 -280.396143) (xy 171.962186 -280.394162) (xy 172.011041 -280.400094)
			(xy 172.058312 -280.413786) (xy 172.102774 -280.434884) (xy 172.143277 -280.46284) (xy 172.17877 -280.496932)
			(xy 172.208335 -280.536276) (xy 172.231206 -280.579853) (xy 172.24679 -280.626534) (xy 172.254685 -280.675111)
			(xy 172.25518 -280.699718) (xy 172.254685 -280.724325) (xy 172.254506 -280.725426) (xy 172.573184 -280.725426)
			(xy 172.573184 -280.67401) (xy 172.581227 -280.623228) (xy 172.597115 -280.574329) (xy 172.620458 -280.528517)
			(xy 172.650679 -280.486921) (xy 172.687035 -280.450565) (xy 172.728631 -280.420344) (xy 172.774443 -280.397001)
			(xy 172.823342 -280.381113) (xy 172.874124 -280.37307) (xy 172.92554 -280.37307) (xy 172.976322 -280.381113)
			(xy 173.025221 -280.397001) (xy 173.071033 -280.420344) (xy 173.112629 -280.450565) (xy 173.148985 -280.486921)
			(xy 173.179206 -280.528517) (xy 173.202549 -280.574329) (xy 173.218437 -280.623228) (xy 173.22648 -280.67401)
			(xy 173.226984 -280.699718) (xy 173.544242 -280.699718) (xy 173.548202 -280.650664) (xy 173.559979 -280.60288)
			(xy 173.57927 -280.557604) (xy 173.605573 -280.516008) (xy 173.638208 -280.479171) (xy 173.676329 -280.448046)
			(xy 173.71895 -280.423439) (xy 173.764966 -280.405987) (xy 173.813185 -280.396143) (xy 173.86236 -280.394162)
			(xy 173.911215 -280.400094) (xy 173.958486 -280.413786) (xy 174.002948 -280.434884) (xy 174.043451 -280.46284)
			(xy 174.078944 -280.496932) (xy 174.108509 -280.536276) (xy 174.13138 -280.579853) (xy 174.146964 -280.626534)
			(xy 174.154859 -280.675111) (xy 174.155354 -280.699718) (xy 174.154859 -280.724325) (xy 174.15468 -280.725426)
			(xy 174.473358 -280.725426) (xy 174.473358 -280.67401) (xy 174.481401 -280.623228) (xy 174.497289 -280.574329)
			(xy 174.520632 -280.528517) (xy 174.550853 -280.486921) (xy 174.587209 -280.450565) (xy 174.628805 -280.420344)
			(xy 174.674617 -280.397001) (xy 174.723516 -280.381113) (xy 174.774298 -280.37307) (xy 174.825714 -280.37307)
			(xy 174.876496 -280.381113) (xy 174.925395 -280.397001) (xy 174.971207 -280.420344) (xy 175.012803 -280.450565)
			(xy 175.049159 -280.486921) (xy 175.07938 -280.528517) (xy 175.102723 -280.574329) (xy 175.118611 -280.623228)
			(xy 175.126654 -280.67401) (xy 175.127158 -280.699718) (xy 175.444162 -280.699718) (xy 175.448122 -280.650664)
			(xy 175.459899 -280.60288) (xy 175.47919 -280.557604) (xy 175.505493 -280.516008) (xy 175.538128 -280.479171)
			(xy 175.576249 -280.448046) (xy 175.61887 -280.423439) (xy 175.664886 -280.405987) (xy 175.713105 -280.396143)
			(xy 175.76228 -280.394162) (xy 175.811135 -280.400094) (xy 175.858406 -280.413786) (xy 175.902868 -280.434884)
			(xy 175.943371 -280.46284) (xy 175.978864 -280.496932) (xy 176.008429 -280.536276) (xy 176.0313 -280.579853)
			(xy 176.046884 -280.626534) (xy 176.054779 -280.675111) (xy 176.055274 -280.699718) (xy 176.054779 -280.724325)
			(xy 176.0546 -280.725426) (xy 176.373278 -280.725426) (xy 176.373278 -280.67401) (xy 176.381321 -280.623228)
			(xy 176.397209 -280.574329) (xy 176.420552 -280.528517) (xy 176.450773 -280.486921) (xy 176.487129 -280.450565)
			(xy 176.528725 -280.420344) (xy 176.574537 -280.397001) (xy 176.623436 -280.381113) (xy 176.674218 -280.37307)
			(xy 176.725634 -280.37307) (xy 176.776416 -280.381113) (xy 176.825315 -280.397001) (xy 176.871127 -280.420344)
			(xy 176.912723 -280.450565) (xy 176.949079 -280.486921) (xy 176.9793 -280.528517) (xy 177.002643 -280.574329)
			(xy 177.018531 -280.623228) (xy 177.026574 -280.67401) (xy 177.027078 -280.699718) (xy 177.344082 -280.699718)
			(xy 177.348042 -280.650664) (xy 177.359819 -280.60288) (xy 177.37911 -280.557604) (xy 177.405413 -280.516008)
			(xy 177.438048 -280.479171) (xy 177.476169 -280.448046) (xy 177.51879 -280.423439) (xy 177.564806 -280.405987)
			(xy 177.613025 -280.396143) (xy 177.6622 -280.394162) (xy 177.711055 -280.400094) (xy 177.758326 -280.413786)
			(xy 177.802788 -280.434884) (xy 177.843291 -280.46284) (xy 177.878784 -280.496932) (xy 177.908349 -280.536276)
			(xy 177.93122 -280.579853) (xy 177.946804 -280.626534) (xy 177.954699 -280.675111) (xy 177.955194 -280.699718)
			(xy 177.954699 -280.724325) (xy 177.95452 -280.725426) (xy 178.273198 -280.725426) (xy 178.273198 -280.67401)
			(xy 178.281241 -280.623228) (xy 178.297129 -280.574329) (xy 178.320472 -280.528517) (xy 178.350693 -280.486921)
			(xy 178.387049 -280.450565) (xy 178.428645 -280.420344) (xy 178.474457 -280.397001) (xy 178.523356 -280.381113)
			(xy 178.574138 -280.37307) (xy 178.625554 -280.37307) (xy 178.676336 -280.381113) (xy 178.725235 -280.397001)
			(xy 178.771047 -280.420344) (xy 178.812643 -280.450565) (xy 178.848999 -280.486921) (xy 178.87922 -280.528517)
			(xy 178.902563 -280.574329) (xy 178.918451 -280.623228) (xy 178.926494 -280.67401) (xy 178.926998 -280.699718)
			(xy 179.244256 -280.699718) (xy 179.248216 -280.650664) (xy 179.259993 -280.60288) (xy 179.279284 -280.557604)
			(xy 179.305587 -280.516008) (xy 179.338222 -280.479171) (xy 179.376343 -280.448046) (xy 179.418964 -280.423439)
			(xy 179.46498 -280.405987) (xy 179.513199 -280.396143) (xy 179.562374 -280.394162) (xy 179.611229 -280.400094)
			(xy 179.6585 -280.413786) (xy 179.702962 -280.434884) (xy 179.743465 -280.46284) (xy 179.778958 -280.496932)
			(xy 179.808523 -280.536276) (xy 179.831394 -280.579853) (xy 179.846978 -280.626534) (xy 179.854873 -280.675111)
			(xy 179.855368 -280.699718) (xy 179.854873 -280.724325) (xy 179.854694 -280.725426) (xy 180.173372 -280.725426)
			(xy 180.173372 -280.67401) (xy 180.181415 -280.623228) (xy 180.197303 -280.574329) (xy 180.220646 -280.528517)
			(xy 180.250867 -280.486921) (xy 180.287223 -280.450565) (xy 180.328819 -280.420344) (xy 180.374631 -280.397001)
			(xy 180.42353 -280.381113) (xy 180.474312 -280.37307) (xy 180.525728 -280.37307) (xy 180.57651 -280.381113)
			(xy 180.625409 -280.397001) (xy 180.671221 -280.420344) (xy 180.712817 -280.450565) (xy 180.749173 -280.486921)
			(xy 180.779394 -280.528517) (xy 180.802737 -280.574329) (xy 180.818625 -280.623228) (xy 180.826668 -280.67401)
			(xy 180.827172 -280.699718) (xy 181.144176 -280.699718) (xy 181.148136 -280.650664) (xy 181.159913 -280.60288)
			(xy 181.179204 -280.557604) (xy 181.205507 -280.516008) (xy 181.238142 -280.479171) (xy 181.276263 -280.448046)
			(xy 181.318884 -280.423439) (xy 181.3649 -280.405987) (xy 181.413119 -280.396143) (xy 181.462294 -280.394162)
			(xy 181.511149 -280.400094) (xy 181.55842 -280.413786) (xy 181.602882 -280.434884) (xy 181.643385 -280.46284)
			(xy 181.678878 -280.496932) (xy 181.708443 -280.536276) (xy 181.731314 -280.579853) (xy 181.746898 -280.626534)
			(xy 181.754793 -280.675111) (xy 181.755288 -280.699718) (xy 181.754793 -280.724325) (xy 181.754614 -280.725426)
			(xy 182.073292 -280.725426) (xy 182.073292 -280.67401) (xy 182.081335 -280.623228) (xy 182.097223 -280.574329)
			(xy 182.120566 -280.528517) (xy 182.150787 -280.486921) (xy 182.187143 -280.450565) (xy 182.228739 -280.420344)
			(xy 182.274551 -280.397001) (xy 182.32345 -280.381113) (xy 182.374232 -280.37307) (xy 182.425648 -280.37307)
			(xy 182.47643 -280.381113) (xy 182.525329 -280.397001) (xy 182.571141 -280.420344) (xy 182.612737 -280.450565)
			(xy 182.649093 -280.486921) (xy 182.679314 -280.528517) (xy 182.702657 -280.574329) (xy 182.718545 -280.623228)
			(xy 182.726588 -280.67401) (xy 182.727092 -280.699718) (xy 183.044096 -280.699718) (xy 183.048056 -280.650664)
			(xy 183.059833 -280.60288) (xy 183.079124 -280.557604) (xy 183.105427 -280.516008) (xy 183.138062 -280.479171)
			(xy 183.176183 -280.448046) (xy 183.218804 -280.423439) (xy 183.26482 -280.405987) (xy 183.313039 -280.396143)
			(xy 183.362214 -280.394162) (xy 183.411069 -280.400094) (xy 183.45834 -280.413786) (xy 183.502802 -280.434884)
			(xy 183.543305 -280.46284) (xy 183.578798 -280.496932) (xy 183.608363 -280.536276) (xy 183.631234 -280.579853)
			(xy 183.646818 -280.626534) (xy 183.654713 -280.675111) (xy 183.655208 -280.699718) (xy 183.654713 -280.724325)
			(xy 183.654534 -280.725426) (xy 183.973212 -280.725426) (xy 183.973212 -280.67401) (xy 183.981255 -280.623228)
			(xy 183.997143 -280.574329) (xy 184.020486 -280.528517) (xy 184.050707 -280.486921) (xy 184.087063 -280.450565)
			(xy 184.128659 -280.420344) (xy 184.174471 -280.397001) (xy 184.22337 -280.381113) (xy 184.274152 -280.37307)
			(xy 184.325568 -280.37307) (xy 184.37635 -280.381113) (xy 184.425249 -280.397001) (xy 184.471061 -280.420344)
			(xy 184.512657 -280.450565) (xy 184.549013 -280.486921) (xy 184.579234 -280.528517) (xy 184.602577 -280.574329)
			(xy 184.618465 -280.623228) (xy 184.626508 -280.67401) (xy 184.627012 -280.699718) (xy 184.94427 -280.699718)
			(xy 184.94823 -280.650664) (xy 184.960007 -280.60288) (xy 184.979298 -280.557604) (xy 185.005601 -280.516008)
			(xy 185.038236 -280.479171) (xy 185.076357 -280.448046) (xy 185.118978 -280.423439) (xy 185.164994 -280.405987)
			(xy 185.213213 -280.396143) (xy 185.262388 -280.394162) (xy 185.311243 -280.400094) (xy 185.358514 -280.413786)
			(xy 185.402976 -280.434884) (xy 185.443479 -280.46284) (xy 185.478972 -280.496932) (xy 185.508537 -280.536276)
			(xy 185.531408 -280.579853) (xy 185.546992 -280.626534) (xy 185.554887 -280.675111) (xy 185.555382 -280.699718)
			(xy 185.554887 -280.724325) (xy 185.554708 -280.725426) (xy 185.873386 -280.725426) (xy 185.873386 -280.67401)
			(xy 185.881429 -280.623228) (xy 185.897317 -280.574329) (xy 185.92066 -280.528517) (xy 185.950881 -280.486921)
			(xy 185.987237 -280.450565) (xy 186.028833 -280.420344) (xy 186.074645 -280.397001) (xy 186.123544 -280.381113)
			(xy 186.174326 -280.37307) (xy 186.225742 -280.37307) (xy 186.276524 -280.381113) (xy 186.325423 -280.397001)
			(xy 186.371235 -280.420344) (xy 186.412831 -280.450565) (xy 186.449187 -280.486921) (xy 186.479408 -280.528517)
			(xy 186.502751 -280.574329) (xy 186.518639 -280.623228) (xy 186.526682 -280.67401) (xy 186.527186 -280.699718)
			(xy 186.84419 -280.699718) (xy 186.84815 -280.650664) (xy 186.859927 -280.60288) (xy 186.879218 -280.557604)
			(xy 186.905521 -280.516008) (xy 186.938156 -280.479171) (xy 186.976277 -280.448046) (xy 187.018898 -280.423439)
			(xy 187.064914 -280.405987) (xy 187.113133 -280.396143) (xy 187.162308 -280.394162) (xy 187.211163 -280.400094)
			(xy 187.258434 -280.413786) (xy 187.302896 -280.434884) (xy 187.343399 -280.46284) (xy 187.378892 -280.496932)
			(xy 187.408457 -280.536276) (xy 187.431328 -280.579853) (xy 187.446912 -280.626534) (xy 187.454807 -280.675111)
			(xy 187.455302 -280.699718) (xy 187.454807 -280.724325) (xy 187.454628 -280.725426) (xy 187.773306 -280.725426)
			(xy 187.773306 -280.67401) (xy 187.781349 -280.623228) (xy 187.797237 -280.574329) (xy 187.82058 -280.528517)
			(xy 187.850801 -280.486921) (xy 187.887157 -280.450565) (xy 187.928753 -280.420344) (xy 187.974565 -280.397001)
			(xy 188.023464 -280.381113) (xy 188.074246 -280.37307) (xy 188.125662 -280.37307) (xy 188.176444 -280.381113)
			(xy 188.225343 -280.397001) (xy 188.271155 -280.420344) (xy 188.312751 -280.450565) (xy 188.349107 -280.486921)
			(xy 188.379328 -280.528517) (xy 188.402671 -280.574329) (xy 188.418559 -280.623228) (xy 188.426602 -280.67401)
			(xy 188.427106 -280.699718) (xy 188.74411 -280.699718) (xy 188.74807 -280.650664) (xy 188.759847 -280.60288)
			(xy 188.779138 -280.557604) (xy 188.805441 -280.516008) (xy 188.838076 -280.479171) (xy 188.876197 -280.448046)
			(xy 188.918818 -280.423439) (xy 188.964834 -280.405987) (xy 189.013053 -280.396143) (xy 189.062228 -280.394162)
			(xy 189.111083 -280.400094) (xy 189.158354 -280.413786) (xy 189.202816 -280.434884) (xy 189.243319 -280.46284)
			(xy 189.278812 -280.496932) (xy 189.308377 -280.536276) (xy 189.331248 -280.579853) (xy 189.346832 -280.626534)
			(xy 189.354727 -280.675111) (xy 189.355222 -280.699718) (xy 189.354727 -280.724325) (xy 189.354548 -280.725426)
			(xy 189.673226 -280.725426) (xy 189.673226 -280.67401) (xy 189.681269 -280.623228) (xy 189.697157 -280.574329)
			(xy 189.7205 -280.528517) (xy 189.750721 -280.486921) (xy 189.787077 -280.450565) (xy 189.828673 -280.420344)
			(xy 189.874485 -280.397001) (xy 189.923384 -280.381113) (xy 189.974166 -280.37307) (xy 190.025582 -280.37307)
			(xy 190.076364 -280.381113) (xy 190.125263 -280.397001) (xy 190.171075 -280.420344) (xy 190.212671 -280.450565)
			(xy 190.249027 -280.486921) (xy 190.279248 -280.528517) (xy 190.302591 -280.574329) (xy 190.318479 -280.623228)
			(xy 190.326522 -280.67401) (xy 190.327026 -280.699718) (xy 190.644284 -280.699718) (xy 190.648244 -280.650664)
			(xy 190.660021 -280.60288) (xy 190.679312 -280.557604) (xy 190.705615 -280.516008) (xy 190.73825 -280.479171)
			(xy 190.776371 -280.448046) (xy 190.818992 -280.423439) (xy 190.865008 -280.405987) (xy 190.913227 -280.396143)
			(xy 190.962402 -280.394162) (xy 191.011257 -280.400094) (xy 191.058528 -280.413786) (xy 191.10299 -280.434884)
			(xy 191.143493 -280.46284) (xy 191.178986 -280.496932) (xy 191.208551 -280.536276) (xy 191.231422 -280.579853)
			(xy 191.247006 -280.626534) (xy 191.254901 -280.675111) (xy 191.255396 -280.699718) (xy 191.254901 -280.724325)
			(xy 191.254722 -280.725426) (xy 191.5734 -280.725426) (xy 191.5734 -280.67401) (xy 191.581443 -280.623228)
			(xy 191.597331 -280.574329) (xy 191.620674 -280.528517) (xy 191.650895 -280.486921) (xy 191.687251 -280.450565)
			(xy 191.728847 -280.420344) (xy 191.774659 -280.397001) (xy 191.823558 -280.381113) (xy 191.87434 -280.37307)
			(xy 191.925756 -280.37307) (xy 191.976538 -280.381113) (xy 192.025437 -280.397001) (xy 192.071249 -280.420344)
			(xy 192.112845 -280.450565) (xy 192.149201 -280.486921) (xy 192.179422 -280.528517) (xy 192.202765 -280.574329)
			(xy 192.218653 -280.623228) (xy 192.226696 -280.67401) (xy 192.2272 -280.699718) (xy 192.544204 -280.699718)
			(xy 192.548164 -280.650664) (xy 192.559941 -280.60288) (xy 192.579232 -280.557604) (xy 192.605535 -280.516008)
			(xy 192.63817 -280.479171) (xy 192.676291 -280.448046) (xy 192.718912 -280.423439) (xy 192.764928 -280.405987)
			(xy 192.813147 -280.396143) (xy 192.862322 -280.394162) (xy 192.911177 -280.400094) (xy 192.958448 -280.413786)
			(xy 193.00291 -280.434884) (xy 193.043413 -280.46284) (xy 193.078906 -280.496932) (xy 193.108471 -280.536276)
			(xy 193.131342 -280.579853) (xy 193.146926 -280.626534) (xy 193.154821 -280.675111) (xy 193.155316 -280.699718)
			(xy 193.154821 -280.724325) (xy 193.154642 -280.725426) (xy 193.47332 -280.725426) (xy 193.47332 -280.67401)
			(xy 193.481363 -280.623228) (xy 193.497251 -280.574329) (xy 193.520594 -280.528517) (xy 193.550815 -280.486921)
			(xy 193.587171 -280.450565) (xy 193.628767 -280.420344) (xy 193.674579 -280.397001) (xy 193.723478 -280.381113)
			(xy 193.77426 -280.37307) (xy 193.825676 -280.37307) (xy 193.876458 -280.381113) (xy 193.925357 -280.397001)
			(xy 193.971169 -280.420344) (xy 194.012765 -280.450565) (xy 194.049121 -280.486921) (xy 194.079342 -280.528517)
			(xy 194.102685 -280.574329) (xy 194.118573 -280.623228) (xy 194.126616 -280.67401) (xy 194.12712 -280.699718)
			(xy 194.444124 -280.699718) (xy 194.448084 -280.650664) (xy 194.459861 -280.60288) (xy 194.479152 -280.557604)
			(xy 194.505455 -280.516008) (xy 194.53809 -280.479171) (xy 194.576211 -280.448046) (xy 194.618832 -280.423439)
			(xy 194.664848 -280.405987) (xy 194.713067 -280.396143) (xy 194.762242 -280.394162) (xy 194.811097 -280.400094)
			(xy 194.858368 -280.413786) (xy 194.90283 -280.434884) (xy 194.943333 -280.46284) (xy 194.978826 -280.496932)
			(xy 195.008391 -280.536276) (xy 195.031262 -280.579853) (xy 195.046846 -280.626534) (xy 195.054741 -280.675111)
			(xy 195.055236 -280.699718) (xy 195.054741 -280.724325) (xy 195.054562 -280.725426) (xy 195.37324 -280.725426)
			(xy 195.37324 -280.67401) (xy 195.381283 -280.623228) (xy 195.397171 -280.574329) (xy 195.420514 -280.528517)
			(xy 195.450735 -280.486921) (xy 195.487091 -280.450565) (xy 195.528687 -280.420344) (xy 195.574499 -280.397001)
			(xy 195.623398 -280.381113) (xy 195.67418 -280.37307) (xy 195.725596 -280.37307) (xy 195.776378 -280.381113)
			(xy 195.825277 -280.397001) (xy 195.871089 -280.420344) (xy 195.912685 -280.450565) (xy 195.949041 -280.486921)
			(xy 195.979262 -280.528517) (xy 196.002605 -280.574329) (xy 196.018493 -280.623228) (xy 196.026536 -280.67401)
			(xy 196.02704 -280.699718) (xy 196.344298 -280.699718) (xy 196.348258 -280.650664) (xy 196.360035 -280.60288)
			(xy 196.379326 -280.557604) (xy 196.405629 -280.516008) (xy 196.438264 -280.479171) (xy 196.476385 -280.448046)
			(xy 196.519006 -280.423439) (xy 196.565022 -280.405987) (xy 196.613241 -280.396143) (xy 196.662416 -280.394162)
			(xy 196.711271 -280.400094) (xy 196.758542 -280.413786) (xy 196.803004 -280.434884) (xy 196.843507 -280.46284)
			(xy 196.879 -280.496932) (xy 196.908565 -280.536276) (xy 196.931436 -280.579853) (xy 196.94702 -280.626534)
			(xy 196.954915 -280.675111) (xy 196.95541 -280.699718) (xy 197.294258 -280.699718) (xy 197.298218 -280.650664)
			(xy 197.309995 -280.60288) (xy 197.329286 -280.557604) (xy 197.355589 -280.516008) (xy 197.388224 -280.479171)
			(xy 197.426345 -280.448046) (xy 197.468966 -280.423439) (xy 197.514982 -280.405987) (xy 197.563201 -280.396143)
			(xy 197.612376 -280.394162) (xy 197.661231 -280.400094) (xy 197.708502 -280.413786) (xy 197.752964 -280.434884)
			(xy 197.793467 -280.46284) (xy 197.82896 -280.496932) (xy 197.858525 -280.536276) (xy 197.881396 -280.579853)
			(xy 197.89698 -280.626534) (xy 197.904875 -280.675111) (xy 197.90537 -280.699718) (xy 198.244218 -280.699718)
			(xy 198.248178 -280.650664) (xy 198.259955 -280.60288) (xy 198.279246 -280.557604) (xy 198.305549 -280.516008)
			(xy 198.338184 -280.479171) (xy 198.376305 -280.448046) (xy 198.418926 -280.423439) (xy 198.464942 -280.405987)
			(xy 198.513161 -280.396143) (xy 198.562336 -280.394162) (xy 198.611191 -280.400094) (xy 198.658462 -280.413786)
			(xy 198.702924 -280.434884) (xy 198.743427 -280.46284) (xy 198.77892 -280.496932) (xy 198.808485 -280.536276)
			(xy 198.831356 -280.579853) (xy 198.84694 -280.626534) (xy 198.854835 -280.675111) (xy 198.85533 -280.699718)
			(xy 198.854835 -280.724325) (xy 198.84694 -280.772902) (xy 198.831356 -280.819583) (xy 198.808485 -280.86316)
			(xy 198.77892 -280.902504) (xy 198.743427 -280.936596) (xy 198.702924 -280.964552) (xy 198.658462 -280.98565)
			(xy 198.611191 -280.999342) (xy 198.562336 -281.005274) (xy 198.513161 -281.003293) (xy 198.464942 -280.993449)
			(xy 198.418926 -280.975997) (xy 198.376305 -280.95139) (xy 198.338184 -280.920265) (xy 198.305549 -280.883428)
			(xy 198.279246 -280.841832) (xy 198.259955 -280.796556) (xy 198.248178 -280.748772) (xy 198.244218 -280.699718)
			(xy 197.90537 -280.699718) (xy 197.904875 -280.724325) (xy 197.89698 -280.772902) (xy 197.881396 -280.819583)
			(xy 197.858525 -280.86316) (xy 197.82896 -280.902504) (xy 197.793467 -280.936596) (xy 197.752964 -280.964552)
			(xy 197.708502 -280.98565) (xy 197.661231 -280.999342) (xy 197.612376 -281.005274) (xy 197.563201 -281.003293)
			(xy 197.514982 -280.993449) (xy 197.468966 -280.975997) (xy 197.426345 -280.95139) (xy 197.388224 -280.920265)
			(xy 197.355589 -280.883428) (xy 197.329286 -280.841832) (xy 197.309995 -280.796556) (xy 197.298218 -280.748772)
			(xy 197.294258 -280.699718) (xy 196.95541 -280.699718) (xy 196.954915 -280.724325) (xy 196.94702 -280.772902)
			(xy 196.931436 -280.819583) (xy 196.908565 -280.86316) (xy 196.879 -280.902504) (xy 196.843507 -280.936596)
			(xy 196.803004 -280.964552) (xy 196.758542 -280.98565) (xy 196.711271 -280.999342) (xy 196.662416 -281.005274)
			(xy 196.613241 -281.003293) (xy 196.565022 -280.993449) (xy 196.519006 -280.975997) (xy 196.476385 -280.95139)
			(xy 196.438264 -280.920265) (xy 196.405629 -280.883428) (xy 196.379326 -280.841832) (xy 196.360035 -280.796556)
			(xy 196.348258 -280.748772) (xy 196.344298 -280.699718) (xy 196.02704 -280.699718) (xy 196.026536 -280.725426)
			(xy 196.018493 -280.776208) (xy 196.002605 -280.825107) (xy 195.979262 -280.870919) (xy 195.949041 -280.912515)
			(xy 195.912685 -280.948871) (xy 195.871089 -280.979092) (xy 195.825277 -281.002435) (xy 195.776378 -281.018323)
			(xy 195.725596 -281.026366) (xy 195.67418 -281.026366) (xy 195.623398 -281.018323) (xy 195.574499 -281.002435)
			(xy 195.528687 -280.979092) (xy 195.487091 -280.948871) (xy 195.450735 -280.912515) (xy 195.420514 -280.870919)
			(xy 195.397171 -280.825107) (xy 195.381283 -280.776208) (xy 195.37324 -280.725426) (xy 195.054562 -280.725426)
			(xy 195.046846 -280.772902) (xy 195.031262 -280.819583) (xy 195.008391 -280.86316) (xy 194.978826 -280.902504)
			(xy 194.943333 -280.936596) (xy 194.90283 -280.964552) (xy 194.858368 -280.98565) (xy 194.811097 -280.999342)
			(xy 194.762242 -281.005274) (xy 194.713067 -281.003293) (xy 194.664848 -280.993449) (xy 194.618832 -280.975997)
			(xy 194.576211 -280.95139) (xy 194.53809 -280.920265) (xy 194.505455 -280.883428) (xy 194.479152 -280.841832)
			(xy 194.459861 -280.796556) (xy 194.448084 -280.748772) (xy 194.444124 -280.699718) (xy 194.12712 -280.699718)
			(xy 194.126616 -280.725426) (xy 194.118573 -280.776208) (xy 194.102685 -280.825107) (xy 194.079342 -280.870919)
			(xy 194.049121 -280.912515) (xy 194.012765 -280.948871) (xy 193.971169 -280.979092) (xy 193.925357 -281.002435)
			(xy 193.876458 -281.018323) (xy 193.825676 -281.026366) (xy 193.77426 -281.026366) (xy 193.723478 -281.018323)
			(xy 193.674579 -281.002435) (xy 193.628767 -280.979092) (xy 193.587171 -280.948871) (xy 193.550815 -280.912515)
			(xy 193.520594 -280.870919) (xy 193.497251 -280.825107) (xy 193.481363 -280.776208) (xy 193.47332 -280.725426)
			(xy 193.154642 -280.725426) (xy 193.146926 -280.772902) (xy 193.131342 -280.819583) (xy 193.108471 -280.86316)
			(xy 193.078906 -280.902504) (xy 193.043413 -280.936596) (xy 193.00291 -280.964552) (xy 192.958448 -280.98565)
			(xy 192.911177 -280.999342) (xy 192.862322 -281.005274) (xy 192.813147 -281.003293) (xy 192.764928 -280.993449)
			(xy 192.718912 -280.975997) (xy 192.676291 -280.95139) (xy 192.63817 -280.920265) (xy 192.605535 -280.883428)
			(xy 192.579232 -280.841832) (xy 192.559941 -280.796556) (xy 192.548164 -280.748772) (xy 192.544204 -280.699718)
			(xy 192.2272 -280.699718) (xy 192.226696 -280.725426) (xy 192.218653 -280.776208) (xy 192.202765 -280.825107)
			(xy 192.179422 -280.870919) (xy 192.149201 -280.912515) (xy 192.112845 -280.948871) (xy 192.071249 -280.979092)
			(xy 192.025437 -281.002435) (xy 191.976538 -281.018323) (xy 191.925756 -281.026366) (xy 191.87434 -281.026366)
			(xy 191.823558 -281.018323) (xy 191.774659 -281.002435) (xy 191.728847 -280.979092) (xy 191.687251 -280.948871)
			(xy 191.650895 -280.912515) (xy 191.620674 -280.870919) (xy 191.597331 -280.825107) (xy 191.581443 -280.776208)
			(xy 191.5734 -280.725426) (xy 191.254722 -280.725426) (xy 191.247006 -280.772902) (xy 191.231422 -280.819583)
			(xy 191.208551 -280.86316) (xy 191.178986 -280.902504) (xy 191.143493 -280.936596) (xy 191.10299 -280.964552)
			(xy 191.058528 -280.98565) (xy 191.011257 -280.999342) (xy 190.962402 -281.005274) (xy 190.913227 -281.003293)
			(xy 190.865008 -280.993449) (xy 190.818992 -280.975997) (xy 190.776371 -280.95139) (xy 190.73825 -280.920265)
			(xy 190.705615 -280.883428) (xy 190.679312 -280.841832) (xy 190.660021 -280.796556) (xy 190.648244 -280.748772)
			(xy 190.644284 -280.699718) (xy 190.327026 -280.699718) (xy 190.326522 -280.725426) (xy 190.318479 -280.776208)
			(xy 190.302591 -280.825107) (xy 190.279248 -280.870919) (xy 190.249027 -280.912515) (xy 190.212671 -280.948871)
			(xy 190.171075 -280.979092) (xy 190.125263 -281.002435) (xy 190.076364 -281.018323) (xy 190.025582 -281.026366)
			(xy 189.974166 -281.026366) (xy 189.923384 -281.018323) (xy 189.874485 -281.002435) (xy 189.828673 -280.979092)
			(xy 189.787077 -280.948871) (xy 189.750721 -280.912515) (xy 189.7205 -280.870919) (xy 189.697157 -280.825107)
			(xy 189.681269 -280.776208) (xy 189.673226 -280.725426) (xy 189.354548 -280.725426) (xy 189.346832 -280.772902)
			(xy 189.331248 -280.819583) (xy 189.308377 -280.86316) (xy 189.278812 -280.902504) (xy 189.243319 -280.936596)
			(xy 189.202816 -280.964552) (xy 189.158354 -280.98565) (xy 189.111083 -280.999342) (xy 189.062228 -281.005274)
			(xy 189.013053 -281.003293) (xy 188.964834 -280.993449) (xy 188.918818 -280.975997) (xy 188.876197 -280.95139)
			(xy 188.838076 -280.920265) (xy 188.805441 -280.883428) (xy 188.779138 -280.841832) (xy 188.759847 -280.796556)
			(xy 188.74807 -280.748772) (xy 188.74411 -280.699718) (xy 188.427106 -280.699718) (xy 188.426602 -280.725426)
			(xy 188.418559 -280.776208) (xy 188.402671 -280.825107) (xy 188.379328 -280.870919) (xy 188.349107 -280.912515)
			(xy 188.312751 -280.948871) (xy 188.271155 -280.979092) (xy 188.225343 -281.002435) (xy 188.176444 -281.018323)
			(xy 188.125662 -281.026366) (xy 188.074246 -281.026366) (xy 188.023464 -281.018323) (xy 187.974565 -281.002435)
			(xy 187.928753 -280.979092) (xy 187.887157 -280.948871) (xy 187.850801 -280.912515) (xy 187.82058 -280.870919)
			(xy 187.797237 -280.825107) (xy 187.781349 -280.776208) (xy 187.773306 -280.725426) (xy 187.454628 -280.725426)
			(xy 187.446912 -280.772902) (xy 187.431328 -280.819583) (xy 187.408457 -280.86316) (xy 187.378892 -280.902504)
			(xy 187.343399 -280.936596) (xy 187.302896 -280.964552) (xy 187.258434 -280.98565) (xy 187.211163 -280.999342)
			(xy 187.162308 -281.005274) (xy 187.113133 -281.003293) (xy 187.064914 -280.993449) (xy 187.018898 -280.975997)
			(xy 186.976277 -280.95139) (xy 186.938156 -280.920265) (xy 186.905521 -280.883428) (xy 186.879218 -280.841832)
			(xy 186.859927 -280.796556) (xy 186.84815 -280.748772) (xy 186.84419 -280.699718) (xy 186.527186 -280.699718)
			(xy 186.526682 -280.725426) (xy 186.518639 -280.776208) (xy 186.502751 -280.825107) (xy 186.479408 -280.870919)
			(xy 186.449187 -280.912515) (xy 186.412831 -280.948871) (xy 186.371235 -280.979092) (xy 186.325423 -281.002435)
			(xy 186.276524 -281.018323) (xy 186.225742 -281.026366) (xy 186.174326 -281.026366) (xy 186.123544 -281.018323)
			(xy 186.074645 -281.002435) (xy 186.028833 -280.979092) (xy 185.987237 -280.948871) (xy 185.950881 -280.912515)
			(xy 185.92066 -280.870919) (xy 185.897317 -280.825107) (xy 185.881429 -280.776208) (xy 185.873386 -280.725426)
			(xy 185.554708 -280.725426) (xy 185.546992 -280.772902) (xy 185.531408 -280.819583) (xy 185.508537 -280.86316)
			(xy 185.478972 -280.902504) (xy 185.443479 -280.936596) (xy 185.402976 -280.964552) (xy 185.358514 -280.98565)
			(xy 185.311243 -280.999342) (xy 185.262388 -281.005274) (xy 185.213213 -281.003293) (xy 185.164994 -280.993449)
			(xy 185.118978 -280.975997) (xy 185.076357 -280.95139) (xy 185.038236 -280.920265) (xy 185.005601 -280.883428)
			(xy 184.979298 -280.841832) (xy 184.960007 -280.796556) (xy 184.94823 -280.748772) (xy 184.94427 -280.699718)
			(xy 184.627012 -280.699718) (xy 184.626508 -280.725426) (xy 184.618465 -280.776208) (xy 184.602577 -280.825107)
			(xy 184.579234 -280.870919) (xy 184.549013 -280.912515) (xy 184.512657 -280.948871) (xy 184.471061 -280.979092)
			(xy 184.425249 -281.002435) (xy 184.37635 -281.018323) (xy 184.325568 -281.026366) (xy 184.274152 -281.026366)
			(xy 184.22337 -281.018323) (xy 184.174471 -281.002435) (xy 184.128659 -280.979092) (xy 184.087063 -280.948871)
			(xy 184.050707 -280.912515) (xy 184.020486 -280.870919) (xy 183.997143 -280.825107) (xy 183.981255 -280.776208)
			(xy 183.973212 -280.725426) (xy 183.654534 -280.725426) (xy 183.646818 -280.772902) (xy 183.631234 -280.819583)
			(xy 183.608363 -280.86316) (xy 183.578798 -280.902504) (xy 183.543305 -280.936596) (xy 183.502802 -280.964552)
			(xy 183.45834 -280.98565) (xy 183.411069 -280.999342) (xy 183.362214 -281.005274) (xy 183.313039 -281.003293)
			(xy 183.26482 -280.993449) (xy 183.218804 -280.975997) (xy 183.176183 -280.95139) (xy 183.138062 -280.920265)
			(xy 183.105427 -280.883428) (xy 183.079124 -280.841832) (xy 183.059833 -280.796556) (xy 183.048056 -280.748772)
			(xy 183.044096 -280.699718) (xy 182.727092 -280.699718) (xy 182.726588 -280.725426) (xy 182.718545 -280.776208)
			(xy 182.702657 -280.825107) (xy 182.679314 -280.870919) (xy 182.649093 -280.912515) (xy 182.612737 -280.948871)
			(xy 182.571141 -280.979092) (xy 182.525329 -281.002435) (xy 182.47643 -281.018323) (xy 182.425648 -281.026366)
			(xy 182.374232 -281.026366) (xy 182.32345 -281.018323) (xy 182.274551 -281.002435) (xy 182.228739 -280.979092)
			(xy 182.187143 -280.948871) (xy 182.150787 -280.912515) (xy 182.120566 -280.870919) (xy 182.097223 -280.825107)
			(xy 182.081335 -280.776208) (xy 182.073292 -280.725426) (xy 181.754614 -280.725426) (xy 181.746898 -280.772902)
			(xy 181.731314 -280.819583) (xy 181.708443 -280.86316) (xy 181.678878 -280.902504) (xy 181.643385 -280.936596)
			(xy 181.602882 -280.964552) (xy 181.55842 -280.98565) (xy 181.511149 -280.999342) (xy 181.462294 -281.005274)
			(xy 181.413119 -281.003293) (xy 181.3649 -280.993449) (xy 181.318884 -280.975997) (xy 181.276263 -280.95139)
			(xy 181.238142 -280.920265) (xy 181.205507 -280.883428) (xy 181.179204 -280.841832) (xy 181.159913 -280.796556)
			(xy 181.148136 -280.748772) (xy 181.144176 -280.699718) (xy 180.827172 -280.699718) (xy 180.826668 -280.725426)
			(xy 180.818625 -280.776208) (xy 180.802737 -280.825107) (xy 180.779394 -280.870919) (xy 180.749173 -280.912515)
			(xy 180.712817 -280.948871) (xy 180.671221 -280.979092) (xy 180.625409 -281.002435) (xy 180.57651 -281.018323)
			(xy 180.525728 -281.026366) (xy 180.474312 -281.026366) (xy 180.42353 -281.018323) (xy 180.374631 -281.002435)
			(xy 180.328819 -280.979092) (xy 180.287223 -280.948871) (xy 180.250867 -280.912515) (xy 180.220646 -280.870919)
			(xy 180.197303 -280.825107) (xy 180.181415 -280.776208) (xy 180.173372 -280.725426) (xy 179.854694 -280.725426)
			(xy 179.846978 -280.772902) (xy 179.831394 -280.819583) (xy 179.808523 -280.86316) (xy 179.778958 -280.902504)
			(xy 179.743465 -280.936596) (xy 179.702962 -280.964552) (xy 179.6585 -280.98565) (xy 179.611229 -280.999342)
			(xy 179.562374 -281.005274) (xy 179.513199 -281.003293) (xy 179.46498 -280.993449) (xy 179.418964 -280.975997)
			(xy 179.376343 -280.95139) (xy 179.338222 -280.920265) (xy 179.305587 -280.883428) (xy 179.279284 -280.841832)
			(xy 179.259993 -280.796556) (xy 179.248216 -280.748772) (xy 179.244256 -280.699718) (xy 178.926998 -280.699718)
			(xy 178.926494 -280.725426) (xy 178.918451 -280.776208) (xy 178.902563 -280.825107) (xy 178.87922 -280.870919)
			(xy 178.848999 -280.912515) (xy 178.812643 -280.948871) (xy 178.771047 -280.979092) (xy 178.725235 -281.002435)
			(xy 178.676336 -281.018323) (xy 178.625554 -281.026366) (xy 178.574138 -281.026366) (xy 178.523356 -281.018323)
			(xy 178.474457 -281.002435) (xy 178.428645 -280.979092) (xy 178.387049 -280.948871) (xy 178.350693 -280.912515)
			(xy 178.320472 -280.870919) (xy 178.297129 -280.825107) (xy 178.281241 -280.776208) (xy 178.273198 -280.725426)
			(xy 177.95452 -280.725426) (xy 177.946804 -280.772902) (xy 177.93122 -280.819583) (xy 177.908349 -280.86316)
			(xy 177.878784 -280.902504) (xy 177.843291 -280.936596) (xy 177.802788 -280.964552) (xy 177.758326 -280.98565)
			(xy 177.711055 -280.999342) (xy 177.6622 -281.005274) (xy 177.613025 -281.003293) (xy 177.564806 -280.993449)
			(xy 177.51879 -280.975997) (xy 177.476169 -280.95139) (xy 177.438048 -280.920265) (xy 177.405413 -280.883428)
			(xy 177.37911 -280.841832) (xy 177.359819 -280.796556) (xy 177.348042 -280.748772) (xy 177.344082 -280.699718)
			(xy 177.027078 -280.699718) (xy 177.026574 -280.725426) (xy 177.018531 -280.776208) (xy 177.002643 -280.825107)
			(xy 176.9793 -280.870919) (xy 176.949079 -280.912515) (xy 176.912723 -280.948871) (xy 176.871127 -280.979092)
			(xy 176.825315 -281.002435) (xy 176.776416 -281.018323) (xy 176.725634 -281.026366) (xy 176.674218 -281.026366)
			(xy 176.623436 -281.018323) (xy 176.574537 -281.002435) (xy 176.528725 -280.979092) (xy 176.487129 -280.948871)
			(xy 176.450773 -280.912515) (xy 176.420552 -280.870919) (xy 176.397209 -280.825107) (xy 176.381321 -280.776208)
			(xy 176.373278 -280.725426) (xy 176.0546 -280.725426) (xy 176.046884 -280.772902) (xy 176.0313 -280.819583)
			(xy 176.008429 -280.86316) (xy 175.978864 -280.902504) (xy 175.943371 -280.936596) (xy 175.902868 -280.964552)
			(xy 175.858406 -280.98565) (xy 175.811135 -280.999342) (xy 175.76228 -281.005274) (xy 175.713105 -281.003293)
			(xy 175.664886 -280.993449) (xy 175.61887 -280.975997) (xy 175.576249 -280.95139) (xy 175.538128 -280.920265)
			(xy 175.505493 -280.883428) (xy 175.47919 -280.841832) (xy 175.459899 -280.796556) (xy 175.448122 -280.748772)
			(xy 175.444162 -280.699718) (xy 175.127158 -280.699718) (xy 175.126654 -280.725426) (xy 175.118611 -280.776208)
			(xy 175.102723 -280.825107) (xy 175.07938 -280.870919) (xy 175.049159 -280.912515) (xy 175.012803 -280.948871)
			(xy 174.971207 -280.979092) (xy 174.925395 -281.002435) (xy 174.876496 -281.018323) (xy 174.825714 -281.026366)
			(xy 174.774298 -281.026366) (xy 174.723516 -281.018323) (xy 174.674617 -281.002435) (xy 174.628805 -280.979092)
			(xy 174.587209 -280.948871) (xy 174.550853 -280.912515) (xy 174.520632 -280.870919) (xy 174.497289 -280.825107)
			(xy 174.481401 -280.776208) (xy 174.473358 -280.725426) (xy 174.15468 -280.725426) (xy 174.146964 -280.772902)
			(xy 174.13138 -280.819583) (xy 174.108509 -280.86316) (xy 174.078944 -280.902504) (xy 174.043451 -280.936596)
			(xy 174.002948 -280.964552) (xy 173.958486 -280.98565) (xy 173.911215 -280.999342) (xy 173.86236 -281.005274)
			(xy 173.813185 -281.003293) (xy 173.764966 -280.993449) (xy 173.71895 -280.975997) (xy 173.676329 -280.95139)
			(xy 173.638208 -280.920265) (xy 173.605573 -280.883428) (xy 173.57927 -280.841832) (xy 173.559979 -280.796556)
			(xy 173.548202 -280.748772) (xy 173.544242 -280.699718) (xy 173.226984 -280.699718) (xy 173.22648 -280.725426)
			(xy 173.218437 -280.776208) (xy 173.202549 -280.825107) (xy 173.179206 -280.870919) (xy 173.148985 -280.912515)
			(xy 173.112629 -280.948871) (xy 173.071033 -280.979092) (xy 173.025221 -281.002435) (xy 172.976322 -281.018323)
			(xy 172.92554 -281.026366) (xy 172.874124 -281.026366) (xy 172.823342 -281.018323) (xy 172.774443 -281.002435)
			(xy 172.728631 -280.979092) (xy 172.687035 -280.948871) (xy 172.650679 -280.912515) (xy 172.620458 -280.870919)
			(xy 172.597115 -280.825107) (xy 172.581227 -280.776208) (xy 172.573184 -280.725426) (xy 172.254506 -280.725426)
			(xy 172.24679 -280.772902) (xy 172.231206 -280.819583) (xy 172.208335 -280.86316) (xy 172.17877 -280.902504)
			(xy 172.143277 -280.936596) (xy 172.102774 -280.964552) (xy 172.058312 -280.98565) (xy 172.011041 -280.999342)
			(xy 171.962186 -281.005274) (xy 171.913011 -281.003293) (xy 171.864792 -280.993449) (xy 171.818776 -280.975997)
			(xy 171.776155 -280.95139) (xy 171.738034 -280.920265) (xy 171.705399 -280.883428) (xy 171.679096 -280.841832)
			(xy 171.659805 -280.796556) (xy 171.648028 -280.748772) (xy 171.644068 -280.699718) (xy 171.327064 -280.699718)
			(xy 171.32656 -280.725426) (xy 171.318517 -280.776208) (xy 171.302629 -280.825107) (xy 171.279286 -280.870919)
			(xy 171.249065 -280.912515) (xy 171.212709 -280.948871) (xy 171.171113 -280.979092) (xy 171.125301 -281.002435)
			(xy 171.076402 -281.018323) (xy 171.02562 -281.026366) (xy 170.974204 -281.026366) (xy 170.923422 -281.018323)
			(xy 170.874523 -281.002435) (xy 170.828711 -280.979092) (xy 170.787115 -280.948871) (xy 170.750759 -280.912515)
			(xy 170.720538 -280.870919) (xy 170.697195 -280.825107) (xy 170.681307 -280.776208) (xy 170.673264 -280.725426)
			(xy 170.354586 -280.725426) (xy 170.34687 -280.772902) (xy 170.331286 -280.819583) (xy 170.308415 -280.86316)
			(xy 170.27885 -280.902504) (xy 170.243357 -280.936596) (xy 170.202854 -280.964552) (xy 170.158392 -280.98565)
			(xy 170.111121 -280.999342) (xy 170.062266 -281.005274) (xy 170.013091 -281.003293) (xy 169.964872 -280.993449)
			(xy 169.918856 -280.975997) (xy 169.876235 -280.95139) (xy 169.838114 -280.920265) (xy 169.805479 -280.883428)
			(xy 169.779176 -280.841832) (xy 169.759885 -280.796556) (xy 169.748108 -280.748772) (xy 169.744148 -280.699718)
			(xy 169.427144 -280.699718) (xy 169.42664 -280.725426) (xy 169.418597 -280.776208) (xy 169.402709 -280.825107)
			(xy 169.379366 -280.870919) (xy 169.349145 -280.912515) (xy 169.312789 -280.948871) (xy 169.271193 -280.979092)
			(xy 169.225381 -281.002435) (xy 169.176482 -281.018323) (xy 169.1257 -281.026366) (xy 169.074284 -281.026366)
			(xy 169.023502 -281.018323) (xy 168.974603 -281.002435) (xy 168.928791 -280.979092) (xy 168.887195 -280.948871)
			(xy 168.850839 -280.912515) (xy 168.820618 -280.870919) (xy 168.797275 -280.825107) (xy 168.781387 -280.776208)
			(xy 168.773344 -280.725426) (xy 168.454666 -280.725426) (xy 168.44695 -280.772902) (xy 168.431366 -280.819583)
			(xy 168.408495 -280.86316) (xy 168.37893 -280.902504) (xy 168.343437 -280.936596) (xy 168.302934 -280.964552)
			(xy 168.258472 -280.98565) (xy 168.211201 -280.999342) (xy 168.162346 -281.005274) (xy 168.113171 -281.003293)
			(xy 168.064952 -280.993449) (xy 168.018936 -280.975997) (xy 167.976315 -280.95139) (xy 167.938194 -280.920265)
			(xy 167.905559 -280.883428) (xy 167.879256 -280.841832) (xy 167.859965 -280.796556) (xy 167.848188 -280.748772)
			(xy 167.844228 -280.699718) (xy 167.527224 -280.699718) (xy 167.52672 -280.725426) (xy 167.518677 -280.776208)
			(xy 167.502789 -280.825107) (xy 167.479446 -280.870919) (xy 167.449225 -280.912515) (xy 167.412869 -280.948871)
			(xy 167.371273 -280.979092) (xy 167.325461 -281.002435) (xy 167.276562 -281.018323) (xy 167.22578 -281.026366)
			(xy 167.174364 -281.026366) (xy 167.123582 -281.018323) (xy 167.074683 -281.002435) (xy 167.028871 -280.979092)
			(xy 166.987275 -280.948871) (xy 166.950919 -280.912515) (xy 166.920698 -280.870919) (xy 166.897355 -280.825107)
			(xy 166.881467 -280.776208) (xy 166.873424 -280.725426) (xy 166.554492 -280.725426) (xy 166.546776 -280.772902)
			(xy 166.531192 -280.819583) (xy 166.508321 -280.86316) (xy 166.478756 -280.902504) (xy 166.443263 -280.936596)
			(xy 166.40276 -280.964552) (xy 166.358298 -280.98565) (xy 166.311027 -280.999342) (xy 166.262172 -281.005274)
			(xy 166.212997 -281.003293) (xy 166.164778 -280.993449) (xy 166.118762 -280.975997) (xy 166.076141 -280.95139)
			(xy 166.03802 -280.920265) (xy 166.005385 -280.883428) (xy 165.979082 -280.841832) (xy 165.959791 -280.796556)
			(xy 165.948014 -280.748772) (xy 165.944054 -280.699718) (xy 165.62705 -280.699718) (xy 165.626546 -280.725426)
			(xy 165.618503 -280.776208) (xy 165.602615 -280.825107) (xy 165.579272 -280.870919) (xy 165.549051 -280.912515)
			(xy 165.512695 -280.948871) (xy 165.471099 -280.979092) (xy 165.425287 -281.002435) (xy 165.376388 -281.018323)
			(xy 165.325606 -281.026366) (xy 165.27419 -281.026366) (xy 165.223408 -281.018323) (xy 165.174509 -281.002435)
			(xy 165.128697 -280.979092) (xy 165.087101 -280.948871) (xy 165.050745 -280.912515) (xy 165.020524 -280.870919)
			(xy 164.997181 -280.825107) (xy 164.981293 -280.776208) (xy 164.97325 -280.725426) (xy 164.654572 -280.725426)
			(xy 164.646856 -280.772902) (xy 164.631272 -280.819583) (xy 164.608401 -280.86316) (xy 164.578836 -280.902504)
			(xy 164.543343 -280.936596) (xy 164.50284 -280.964552) (xy 164.458378 -280.98565) (xy 164.411107 -280.999342)
			(xy 164.362252 -281.005274) (xy 164.313077 -281.003293) (xy 164.264858 -280.993449) (xy 164.218842 -280.975997)
			(xy 164.176221 -280.95139) (xy 164.1381 -280.920265) (xy 164.105465 -280.883428) (xy 164.079162 -280.841832)
			(xy 164.059871 -280.796556) (xy 164.048094 -280.748772) (xy 164.044134 -280.699718) (xy 163.72713 -280.699718)
			(xy 163.726626 -280.725426) (xy 163.718583 -280.776208) (xy 163.702695 -280.825107) (xy 163.679352 -280.870919)
			(xy 163.649131 -280.912515) (xy 163.612775 -280.948871) (xy 163.571179 -280.979092) (xy 163.525367 -281.002435)
			(xy 163.476468 -281.018323) (xy 163.425686 -281.026366) (xy 163.37427 -281.026366) (xy 163.323488 -281.018323)
			(xy 163.274589 -281.002435) (xy 163.228777 -280.979092) (xy 163.187181 -280.948871) (xy 163.150825 -280.912515)
			(xy 163.120604 -280.870919) (xy 163.097261 -280.825107) (xy 163.081373 -280.776208) (xy 163.07333 -280.725426)
			(xy 162.754652 -280.725426) (xy 162.746936 -280.772902) (xy 162.731352 -280.819583) (xy 162.708481 -280.86316)
			(xy 162.678916 -280.902504) (xy 162.643423 -280.936596) (xy 162.60292 -280.964552) (xy 162.558458 -280.98565)
			(xy 162.511187 -280.999342) (xy 162.462332 -281.005274) (xy 162.413157 -281.003293) (xy 162.364938 -280.993449)
			(xy 162.318922 -280.975997) (xy 162.276301 -280.95139) (xy 162.23818 -280.920265) (xy 162.205545 -280.883428)
			(xy 162.179242 -280.841832) (xy 162.159951 -280.796556) (xy 162.148174 -280.748772) (xy 162.144214 -280.699718)
			(xy 161.82721 -280.699718) (xy 161.826706 -280.725426) (xy 161.818663 -280.776208) (xy 161.802775 -280.825107)
			(xy 161.779432 -280.870919) (xy 161.749211 -280.912515) (xy 161.712855 -280.948871) (xy 161.671259 -280.979092)
			(xy 161.625447 -281.002435) (xy 161.576548 -281.018323) (xy 161.525766 -281.026366) (xy 161.47435 -281.026366)
			(xy 161.423568 -281.018323) (xy 161.374669 -281.002435) (xy 161.328857 -280.979092) (xy 161.287261 -280.948871)
			(xy 161.250905 -280.912515) (xy 161.220684 -280.870919) (xy 161.197341 -280.825107) (xy 161.181453 -280.776208)
			(xy 161.17341 -280.725426) (xy 160.853631 -280.725426) (xy 160.852785 -280.741003) (xy 160.842112 -280.789474)
			(xy 160.823738 -280.83558) (xy 160.798148 -280.878107) (xy 160.766015 -280.915933) (xy 160.728186 -280.948063)
			(xy 160.685657 -280.97365) (xy 160.639549 -280.99202) (xy 160.591077 -281.002688) (xy 160.541517 -281.005375)
			(xy 160.492176 -281.000008) (xy 160.444352 -280.98673) (xy 160.399307 -280.965891) (xy 160.358226 -280.938038)
			(xy 160.322193 -280.903907) (xy 160.292155 -280.864396) (xy 160.268905 -280.820546) (xy 160.253055 -280.773512)
			(xy 160.245023 -280.724534) (xy 160.244536 -280.699718) (xy 160.244714 -280.685535) (xy 160.247385 -280.657295)
			(xy 160.24987 -280.64333) (xy 160.252156 -280.630884) (xy 160.24479 -280.607262) (xy 160.16732 -280.529792)
			(xy 160.143698 -280.522426) (xy 160.131252 -280.524712) (xy 160.117287 -280.527191) (xy 160.089047 -280.529861)
			(xy 160.074864 -280.530046) (xy 160.049614 -280.529446) (xy 159.999803 -280.521128) (xy 159.95204 -280.504726)
			(xy 159.907628 -280.480687) (xy 159.867778 -280.449666) (xy 159.833577 -280.41251) (xy 159.805958 -280.370231)
			(xy 159.785673 -280.323984) (xy 159.773277 -280.275028) (xy 159.769107 -280.2247) (xy 159.773277 -280.174372)
			(xy 159.785673 -280.125416) (xy 159.805958 -280.079169) (xy 159.833577 -280.03689) (xy 159.867778 -279.999734)
			(xy 159.907628 -279.968713) (xy 159.95204 -279.944674) (xy 159.999803 -279.928272) (xy 160.049614 -279.919954)
			(xy 160.074864 -279.91943) (xy 160.089047 -279.919611) (xy 160.117287 -279.92228) (xy 160.131252 -279.924764)
			(xy 160.143698 -279.92705) (xy 160.16732 -279.919684) (xy 160.24479 -279.842214) (xy 160.252156 -279.818592)
			(xy 160.24987 -279.806146) (xy 160.24739 -279.792181) (xy 160.244721 -279.763941) (xy 160.244536 -279.749758)
			(xy 160.244706 -279.735575) (xy 160.247382 -279.707335) (xy 160.24987 -279.69337) (xy 160.252156 -279.680924)
			(xy 160.24479 -279.657302) (xy 160.16732 -279.579832) (xy 160.143698 -279.572466) (xy 160.131252 -279.574752)
			(xy 160.117286 -279.577231) (xy 160.089047 -279.579901) (xy 160.074864 -279.580086) (xy 160.050871 -279.57967)
			(xy 160.003476 -279.572158) (xy 159.957839 -279.557325) (xy 159.915085 -279.535535) (xy 159.876266 -279.507325)
			(xy 159.842337 -279.47339) (xy 159.814135 -279.434565) (xy 159.792353 -279.391807) (xy 159.777528 -279.346168)
			(xy 159.770025 -279.298771) (xy 159.769556 -279.274778) (xy 159.76973 -279.260595) (xy 159.772404 -279.232355)
			(xy 159.77489 -279.21839) (xy 159.777176 -279.205944) (xy 159.76981 -279.182322) (xy 159.69234 -279.104852)
			(xy 159.668718 -279.097486) (xy 159.656272 -279.099772) (xy 159.642306 -279.102248) (xy 159.614067 -279.10492)
			(xy 159.599884 -279.105106) (xy 159.585701 -279.104932) (xy 159.557461 -279.102258) (xy 159.543496 -279.099772)
			(xy 159.53105 -279.097486) (xy 159.507428 -279.104852) (xy 159.429958 -279.182322) (xy 159.422592 -279.205944)
			(xy 159.424878 -279.21839) (xy 159.427349 -279.232357) (xy 159.430024 -279.260596) (xy 159.430212 -279.274778)
			(xy 159.429746 -279.299601) (xy 159.421717 -279.348594) (xy 159.405868 -279.395642) (xy 159.382616 -279.439507)
			(xy 159.352574 -279.479031) (xy 159.316533 -279.513175) (xy 159.275443 -279.541038) (xy 159.230387 -279.561886)
			(xy 159.182551 -279.575171) (xy 159.133196 -279.58054) (xy 159.083622 -279.577855) (xy 159.035136 -279.567184)
			(xy 158.989016 -279.54881) (xy 158.946475 -279.523216) (xy 158.908636 -279.491077) (xy 158.876494 -279.45324)
			(xy 158.850898 -279.410701) (xy 158.832521 -279.364581) (xy 158.821848 -279.316096) (xy 158.819159 -279.266522)
			(xy 158.824526 -279.217167) (xy 158.837807 -279.16933) (xy 158.858653 -279.124272) (xy 158.886513 -279.083181)
			(xy 158.920655 -279.047138) (xy 158.960178 -279.017093) (xy 159.004041 -278.993839) (xy 159.051089 -278.977987)
			(xy 159.100081 -278.969956) (xy 159.124904 -278.96947) (xy 159.139087 -278.969646) (xy 159.167327 -278.972319)
			(xy 159.181292 -278.974804) (xy 159.193738 -278.97709) (xy 159.21736 -278.969724) (xy 159.29483 -278.892254)
			(xy 159.302196 -278.868632) (xy 159.29991 -278.856186) (xy 159.297436 -278.84222) (xy 159.294762 -278.81398)
			(xy 159.294576 -278.799798) (xy 159.294753 -278.785615) (xy 159.297425 -278.757375) (xy 159.29991 -278.74341)
			(xy 159.302196 -278.730964) (xy 159.29483 -278.707342) (xy 159.21736 -278.629872) (xy 159.193738 -278.622506)
			(xy 159.181292 -278.624792) (xy 159.167326 -278.627266) (xy 159.139086 -278.629939) (xy 159.124904 -278.630126)
			(xy 159.099648 -278.629598) (xy 159.049823 -278.621284) (xy 159.002047 -278.604883) (xy 158.957622 -278.580842)
			(xy 158.91776 -278.549817) (xy 158.883549 -278.512653) (xy 158.855921 -278.470366) (xy 158.83563 -278.424108)
			(xy 158.823229 -278.37514) (xy 158.819058 -278.3248) (xy 158.823229 -278.27446) (xy 158.83563 -278.225492)
			(xy 158.855921 -278.179234) (xy 158.883549 -278.136947) (xy 158.91776 -278.099783) (xy 158.957622 -278.068758)
			(xy 159.002047 -278.044717) (xy 159.049823 -278.028316) (xy 159.099648 -278.020002) (xy 159.124904 -278.01951)
			(xy 159.139087 -278.019686) (xy 159.167327 -278.022358) (xy 159.181292 -278.024844) (xy 159.193738 -278.02713)
			(xy 159.21736 -278.019764) (xy 159.29483 -277.942294) (xy 159.302196 -277.918672) (xy 159.29991 -277.906226)
			(xy 159.297427 -277.892261) (xy 159.29476 -277.864021) (xy 159.294576 -277.849838) (xy 159.294758 -277.835655)
			(xy 159.297427 -277.807415) (xy 159.29991 -277.79345) (xy 159.302196 -277.781004) (xy 159.29483 -277.757382)
			(xy 159.21736 -277.679912) (xy 159.193738 -277.672546) (xy 159.181292 -277.674832) (xy 159.167326 -277.677306)
			(xy 159.139086 -277.679979) (xy 159.124904 -277.680166) (xy 159.099643 -277.679758) (xy 159.049809 -277.671442)
			(xy 159.002023 -277.655038) (xy 158.95759 -277.630992) (xy 158.91772 -277.599961) (xy 158.883501 -277.56279)
			(xy 158.855868 -277.520494) (xy 158.835573 -277.474227) (xy 158.82317 -277.42525) (xy 158.818998 -277.3749)
			(xy 158.480251 -277.3749) (xy 158.479757 -277.399465) (xy 158.471862 -277.448042) (xy 158.456278 -277.494723)
			(xy 158.433407 -277.5383) (xy 158.403842 -277.577644) (xy 158.368349 -277.611736) (xy 158.327846 -277.639692)
			(xy 158.283384 -277.66079) (xy 158.236113 -277.674482) (xy 158.187258 -277.680414) (xy 158.138083 -277.678433)
			(xy 158.089864 -277.668589) (xy 158.043848 -277.651137) (xy 158.001227 -277.62653) (xy 157.963106 -277.595405)
			(xy 157.930471 -277.558568) (xy 157.904168 -277.516972) (xy 157.884877 -277.471696) (xy 157.8731 -277.423912)
			(xy 157.86914 -277.374858) (xy 157.530292 -277.374858) (xy 157.529797 -277.399465) (xy 157.521902 -277.448042)
			(xy 157.506318 -277.494723) (xy 157.483447 -277.5383) (xy 157.453882 -277.577644) (xy 157.418389 -277.611736)
			(xy 157.377886 -277.639692) (xy 157.333424 -277.66079) (xy 157.286153 -277.674482) (xy 157.237298 -277.680414)
			(xy 157.188123 -277.678433) (xy 157.139904 -277.668589) (xy 157.093888 -277.651137) (xy 157.051267 -277.62653)
			(xy 157.013146 -277.595405) (xy 156.980511 -277.558568) (xy 156.954208 -277.516972) (xy 156.934917 -277.471696)
			(xy 156.92314 -277.423912) (xy 156.91918 -277.374858) (xy 156.580332 -277.374858) (xy 156.579837 -277.399465)
			(xy 156.571942 -277.448042) (xy 156.556358 -277.494723) (xy 156.533487 -277.5383) (xy 156.503922 -277.577644)
			(xy 156.468429 -277.611736) (xy 156.427926 -277.639692) (xy 156.383464 -277.66079) (xy 156.336193 -277.674482)
			(xy 156.287338 -277.680414) (xy 156.238163 -277.678433) (xy 156.189944 -277.668589) (xy 156.143928 -277.651137)
			(xy 156.101307 -277.62653) (xy 156.063186 -277.595405) (xy 156.030551 -277.558568) (xy 156.004248 -277.516972)
			(xy 155.984957 -277.471696) (xy 155.97318 -277.423912) (xy 155.96922 -277.374858) (xy 155.630372 -277.374858)
			(xy 155.629877 -277.399465) (xy 155.621982 -277.448042) (xy 155.606398 -277.494723) (xy 155.583527 -277.5383)
			(xy 155.553962 -277.577644) (xy 155.518469 -277.611736) (xy 155.477966 -277.639692) (xy 155.433504 -277.66079)
			(xy 155.386233 -277.674482) (xy 155.337378 -277.680414) (xy 155.288203 -277.678433) (xy 155.239984 -277.668589)
			(xy 155.193968 -277.651137) (xy 155.151347 -277.62653) (xy 155.113226 -277.595405) (xy 155.080591 -277.558568)
			(xy 155.054288 -277.516972) (xy 155.034997 -277.471696) (xy 155.02322 -277.423912) (xy 155.01926 -277.374858)
			(xy 154.680412 -277.374858) (xy 154.679917 -277.399465) (xy 154.672022 -277.448042) (xy 154.656438 -277.494723)
			(xy 154.633567 -277.5383) (xy 154.604002 -277.577644) (xy 154.568509 -277.611736) (xy 154.528006 -277.639692)
			(xy 154.483544 -277.66079) (xy 154.436273 -277.674482) (xy 154.387418 -277.680414) (xy 154.338243 -277.678433)
			(xy 154.290024 -277.668589) (xy 154.244008 -277.651137) (xy 154.201387 -277.62653) (xy 154.163266 -277.595405)
			(xy 154.130631 -277.558568) (xy 154.104328 -277.516972) (xy 154.085037 -277.471696) (xy 154.07326 -277.423912)
			(xy 154.0693 -277.374858) (xy 153.730198 -277.374858) (xy 153.729703 -277.399465) (xy 153.721808 -277.448042)
			(xy 153.706224 -277.494723) (xy 153.683353 -277.5383) (xy 153.653788 -277.577644) (xy 153.618295 -277.611736)
			(xy 153.577792 -277.639692) (xy 153.53333 -277.66079) (xy 153.486059 -277.674482) (xy 153.437204 -277.680414)
			(xy 153.388029 -277.678433) (xy 153.33981 -277.668589) (xy 153.293794 -277.651137) (xy 153.251173 -277.62653)
			(xy 153.213052 -277.595405) (xy 153.180417 -277.558568) (xy 153.154114 -277.516972) (xy 153.134823 -277.471696)
			(xy 153.123046 -277.423912) (xy 153.119086 -277.374858) (xy 152.780238 -277.374858) (xy 152.779743 -277.399465)
			(xy 152.771848 -277.448042) (xy 152.756264 -277.494723) (xy 152.733393 -277.5383) (xy 152.703828 -277.577644)
			(xy 152.668335 -277.611736) (xy 152.627832 -277.639692) (xy 152.58337 -277.66079) (xy 152.536099 -277.674482)
			(xy 152.487244 -277.680414) (xy 152.438069 -277.678433) (xy 152.38985 -277.668589) (xy 152.343834 -277.651137)
			(xy 152.301213 -277.62653) (xy 152.263092 -277.595405) (xy 152.230457 -277.558568) (xy 152.204154 -277.516972)
			(xy 152.184863 -277.471696) (xy 152.173086 -277.423912) (xy 152.169126 -277.374858) (xy 139.341 -277.374858)
			(xy 139.280801 -277.504725) (xy 139.205221 -277.649092) (xy 139.122769 -277.789648) (xy 139.033637 -277.926066)
			(xy 138.938031 -278.058028) (xy 138.836175 -278.185227) (xy 138.728305 -278.307368) (xy 138.711328 -278.324818)
			(xy 152.169126 -278.324818) (xy 152.173086 -278.275764) (xy 152.184863 -278.22798) (xy 152.204154 -278.182704)
			(xy 152.230457 -278.141108) (xy 152.263092 -278.104271) (xy 152.301213 -278.073146) (xy 152.343834 -278.048539)
			(xy 152.38985 -278.031087) (xy 152.438069 -278.021243) (xy 152.487244 -278.019262) (xy 152.536099 -278.025194)
			(xy 152.58337 -278.038886) (xy 152.627832 -278.059984) (xy 152.668335 -278.08794) (xy 152.703828 -278.122032)
			(xy 152.733393 -278.161376) (xy 152.756264 -278.204953) (xy 152.771848 -278.251634) (xy 152.779743 -278.300211)
			(xy 152.780238 -278.324818) (xy 153.119086 -278.324818) (xy 153.123046 -278.275764) (xy 153.134823 -278.22798)
			(xy 153.154114 -278.182704) (xy 153.180417 -278.141108) (xy 153.213052 -278.104271) (xy 153.251173 -278.073146)
			(xy 153.293794 -278.048539) (xy 153.33981 -278.031087) (xy 153.388029 -278.021243) (xy 153.437204 -278.019262)
			(xy 153.486059 -278.025194) (xy 153.53333 -278.038886) (xy 153.577792 -278.059984) (xy 153.618295 -278.08794)
			(xy 153.653788 -278.122032) (xy 153.683353 -278.161376) (xy 153.706224 -278.204953) (xy 153.721808 -278.251634)
			(xy 153.729703 -278.300211) (xy 153.730198 -278.324818) (xy 154.0693 -278.324818) (xy 154.07326 -278.275764)
			(xy 154.085037 -278.22798) (xy 154.104328 -278.182704) (xy 154.130631 -278.141108) (xy 154.163266 -278.104271)
			(xy 154.201387 -278.073146) (xy 154.244008 -278.048539) (xy 154.290024 -278.031087) (xy 154.338243 -278.021243)
			(xy 154.387418 -278.019262) (xy 154.436273 -278.025194) (xy 154.483544 -278.038886) (xy 154.528006 -278.059984)
			(xy 154.568509 -278.08794) (xy 154.604002 -278.122032) (xy 154.633567 -278.161376) (xy 154.656438 -278.204953)
			(xy 154.672022 -278.251634) (xy 154.679917 -278.300211) (xy 154.680412 -278.324818) (xy 155.01926 -278.324818)
			(xy 155.02322 -278.275764) (xy 155.034997 -278.22798) (xy 155.054288 -278.182704) (xy 155.080591 -278.141108)
			(xy 155.113226 -278.104271) (xy 155.151347 -278.073146) (xy 155.193968 -278.048539) (xy 155.239984 -278.031087)
			(xy 155.288203 -278.021243) (xy 155.337378 -278.019262) (xy 155.386233 -278.025194) (xy 155.433504 -278.038886)
			(xy 155.477966 -278.059984) (xy 155.518469 -278.08794) (xy 155.553962 -278.122032) (xy 155.583527 -278.161376)
			(xy 155.606398 -278.204953) (xy 155.621982 -278.251634) (xy 155.629877 -278.300211) (xy 155.630372 -278.324818)
			(xy 155.96922 -278.324818) (xy 155.97318 -278.275764) (xy 155.984957 -278.22798) (xy 156.004248 -278.182704)
			(xy 156.030551 -278.141108) (xy 156.063186 -278.104271) (xy 156.101307 -278.073146) (xy 156.143928 -278.048539)
			(xy 156.189944 -278.031087) (xy 156.238163 -278.021243) (xy 156.287338 -278.019262) (xy 156.336193 -278.025194)
			(xy 156.383464 -278.038886) (xy 156.427926 -278.059984) (xy 156.468429 -278.08794) (xy 156.503922 -278.122032)
			(xy 156.533487 -278.161376) (xy 156.556358 -278.204953) (xy 156.571942 -278.251634) (xy 156.579837 -278.300211)
			(xy 156.580332 -278.324818) (xy 156.91918 -278.324818) (xy 156.92314 -278.275764) (xy 156.934917 -278.22798)
			(xy 156.954208 -278.182704) (xy 156.980511 -278.141108) (xy 157.013146 -278.104271) (xy 157.051267 -278.073146)
			(xy 157.093888 -278.048539) (xy 157.139904 -278.031087) (xy 157.188123 -278.021243) (xy 157.237298 -278.019262)
			(xy 157.286153 -278.025194) (xy 157.333424 -278.038886) (xy 157.377886 -278.059984) (xy 157.418389 -278.08794)
			(xy 157.453882 -278.122032) (xy 157.483447 -278.161376) (xy 157.506318 -278.204953) (xy 157.521902 -278.251634)
			(xy 157.529797 -278.300211) (xy 157.530292 -278.324818) (xy 157.86914 -278.324818) (xy 157.8731 -278.275764)
			(xy 157.884877 -278.22798) (xy 157.904168 -278.182704) (xy 157.930471 -278.141108) (xy 157.963106 -278.104271)
			(xy 158.001227 -278.073146) (xy 158.043848 -278.048539) (xy 158.089864 -278.031087) (xy 158.138083 -278.021243)
			(xy 158.187258 -278.019262) (xy 158.236113 -278.025194) (xy 158.283384 -278.038886) (xy 158.327846 -278.059984)
			(xy 158.368349 -278.08794) (xy 158.403842 -278.122032) (xy 158.433407 -278.161376) (xy 158.456278 -278.204953)
			(xy 158.471862 -278.251634) (xy 158.479757 -278.300211) (xy 158.480252 -278.324818) (xy 158.479757 -278.349425)
			(xy 158.471862 -278.398002) (xy 158.456278 -278.444683) (xy 158.433407 -278.48826) (xy 158.403842 -278.527604)
			(xy 158.368349 -278.561696) (xy 158.327846 -278.589652) (xy 158.283384 -278.61075) (xy 158.236113 -278.624442)
			(xy 158.187258 -278.630374) (xy 158.138083 -278.628393) (xy 158.089864 -278.618549) (xy 158.043848 -278.601097)
			(xy 158.001227 -278.57649) (xy 157.963106 -278.545365) (xy 157.930471 -278.508528) (xy 157.904168 -278.466932)
			(xy 157.884877 -278.421656) (xy 157.8731 -278.373872) (xy 157.86914 -278.324818) (xy 157.530292 -278.324818)
			(xy 157.529797 -278.349425) (xy 157.521902 -278.398002) (xy 157.506318 -278.444683) (xy 157.483447 -278.48826)
			(xy 157.453882 -278.527604) (xy 157.418389 -278.561696) (xy 157.377886 -278.589652) (xy 157.333424 -278.61075)
			(xy 157.286153 -278.624442) (xy 157.237298 -278.630374) (xy 157.188123 -278.628393) (xy 157.139904 -278.618549)
			(xy 157.093888 -278.601097) (xy 157.051267 -278.57649) (xy 157.013146 -278.545365) (xy 156.980511 -278.508528)
			(xy 156.954208 -278.466932) (xy 156.934917 -278.421656) (xy 156.92314 -278.373872) (xy 156.91918 -278.324818)
			(xy 156.580332 -278.324818) (xy 156.579837 -278.349425) (xy 156.571942 -278.398002) (xy 156.556358 -278.444683)
			(xy 156.533487 -278.48826) (xy 156.503922 -278.527604) (xy 156.468429 -278.561696) (xy 156.427926 -278.589652)
			(xy 156.383464 -278.61075) (xy 156.336193 -278.624442) (xy 156.287338 -278.630374) (xy 156.238163 -278.628393)
			(xy 156.189944 -278.618549) (xy 156.143928 -278.601097) (xy 156.101307 -278.57649) (xy 156.063186 -278.545365)
			(xy 156.030551 -278.508528) (xy 156.004248 -278.466932) (xy 155.984957 -278.421656) (xy 155.97318 -278.373872)
			(xy 155.96922 -278.324818) (xy 155.630372 -278.324818) (xy 155.629877 -278.349425) (xy 155.621982 -278.398002)
			(xy 155.606398 -278.444683) (xy 155.583527 -278.48826) (xy 155.553962 -278.527604) (xy 155.518469 -278.561696)
			(xy 155.477966 -278.589652) (xy 155.433504 -278.61075) (xy 155.386233 -278.624442) (xy 155.337378 -278.630374)
			(xy 155.288203 -278.628393) (xy 155.239984 -278.618549) (xy 155.193968 -278.601097) (xy 155.151347 -278.57649)
			(xy 155.113226 -278.545365) (xy 155.080591 -278.508528) (xy 155.054288 -278.466932) (xy 155.034997 -278.421656)
			(xy 155.02322 -278.373872) (xy 155.01926 -278.324818) (xy 154.680412 -278.324818) (xy 154.679917 -278.349425)
			(xy 154.672022 -278.398002) (xy 154.656438 -278.444683) (xy 154.633567 -278.48826) (xy 154.604002 -278.527604)
			(xy 154.568509 -278.561696) (xy 154.528006 -278.589652) (xy 154.483544 -278.61075) (xy 154.436273 -278.624442)
			(xy 154.387418 -278.630374) (xy 154.338243 -278.628393) (xy 154.290024 -278.618549) (xy 154.244008 -278.601097)
			(xy 154.201387 -278.57649) (xy 154.163266 -278.545365) (xy 154.130631 -278.508528) (xy 154.104328 -278.466932)
			(xy 154.085037 -278.421656) (xy 154.07326 -278.373872) (xy 154.0693 -278.324818) (xy 153.730198 -278.324818)
			(xy 153.729703 -278.349425) (xy 153.721808 -278.398002) (xy 153.706224 -278.444683) (xy 153.683353 -278.48826)
			(xy 153.653788 -278.527604) (xy 153.618295 -278.561696) (xy 153.577792 -278.589652) (xy 153.53333 -278.61075)
			(xy 153.486059 -278.624442) (xy 153.437204 -278.630374) (xy 153.388029 -278.628393) (xy 153.33981 -278.618549)
			(xy 153.293794 -278.601097) (xy 153.251173 -278.57649) (xy 153.213052 -278.545365) (xy 153.180417 -278.508528)
			(xy 153.154114 -278.466932) (xy 153.134823 -278.421656) (xy 153.123046 -278.373872) (xy 153.119086 -278.324818)
			(xy 152.780238 -278.324818) (xy 152.779743 -278.349425) (xy 152.771848 -278.398002) (xy 152.756264 -278.444683)
			(xy 152.733393 -278.48826) (xy 152.703828 -278.527604) (xy 152.668335 -278.561696) (xy 152.627832 -278.589652)
			(xy 152.58337 -278.61075) (xy 152.536099 -278.624442) (xy 152.487244 -278.630374) (xy 152.438069 -278.628393)
			(xy 152.38985 -278.618549) (xy 152.343834 -278.601097) (xy 152.301213 -278.57649) (xy 152.263092 -278.545365)
			(xy 152.230457 -278.508528) (xy 152.204154 -278.466932) (xy 152.184863 -278.421656) (xy 152.173086 -278.373872)
			(xy 152.169126 -278.324818) (xy 138.711328 -278.324818) (xy 138.614672 -278.424167) (xy 138.49554 -278.535351)
			(xy 138.371187 -278.640663) (xy 138.241901 -278.739857) (xy 138.107983 -278.832703) (xy 137.969745 -278.918985)
			(xy 137.827507 -278.998502) (xy 137.681602 -279.07107) (xy 137.532368 -279.136518) (xy 137.380152 -279.194697)
			(xy 137.225308 -279.245469) (xy 137.118834 -279.274778) (xy 152.169126 -279.274778) (xy 152.173086 -279.225724)
			(xy 152.184863 -279.17794) (xy 152.204154 -279.132664) (xy 152.230457 -279.091068) (xy 152.263092 -279.054231)
			(xy 152.301213 -279.023106) (xy 152.343834 -278.998499) (xy 152.38985 -278.981047) (xy 152.438069 -278.971203)
			(xy 152.487244 -278.969222) (xy 152.536099 -278.975154) (xy 152.58337 -278.988846) (xy 152.627832 -279.009944)
			(xy 152.668335 -279.0379) (xy 152.703828 -279.071992) (xy 152.733393 -279.111336) (xy 152.756264 -279.154913)
			(xy 152.771848 -279.201594) (xy 152.779743 -279.250171) (xy 152.780238 -279.274778) (xy 153.119086 -279.274778)
			(xy 153.123046 -279.225724) (xy 153.134823 -279.17794) (xy 153.154114 -279.132664) (xy 153.180417 -279.091068)
			(xy 153.213052 -279.054231) (xy 153.251173 -279.023106) (xy 153.293794 -278.998499) (xy 153.33981 -278.981047)
			(xy 153.388029 -278.971203) (xy 153.437204 -278.969222) (xy 153.486059 -278.975154) (xy 153.53333 -278.988846)
			(xy 153.577792 -279.009944) (xy 153.618295 -279.0379) (xy 153.653788 -279.071992) (xy 153.683353 -279.111336)
			(xy 153.706224 -279.154913) (xy 153.721808 -279.201594) (xy 153.729703 -279.250171) (xy 153.730198 -279.274778)
			(xy 154.0693 -279.274778) (xy 154.07326 -279.225724) (xy 154.085037 -279.17794) (xy 154.104328 -279.132664)
			(xy 154.130631 -279.091068) (xy 154.163266 -279.054231) (xy 154.201387 -279.023106) (xy 154.244008 -278.998499)
			(xy 154.290024 -278.981047) (xy 154.338243 -278.971203) (xy 154.387418 -278.969222) (xy 154.436273 -278.975154)
			(xy 154.483544 -278.988846) (xy 154.528006 -279.009944) (xy 154.568509 -279.0379) (xy 154.604002 -279.071992)
			(xy 154.633567 -279.111336) (xy 154.656438 -279.154913) (xy 154.672022 -279.201594) (xy 154.679917 -279.250171)
			(xy 154.680412 -279.274778) (xy 155.01926 -279.274778) (xy 155.02322 -279.225724) (xy 155.034997 -279.17794)
			(xy 155.054288 -279.132664) (xy 155.080591 -279.091068) (xy 155.113226 -279.054231) (xy 155.151347 -279.023106)
			(xy 155.193968 -278.998499) (xy 155.239984 -278.981047) (xy 155.288203 -278.971203) (xy 155.337378 -278.969222)
			(xy 155.386233 -278.975154) (xy 155.433504 -278.988846) (xy 155.477966 -279.009944) (xy 155.518469 -279.0379)
			(xy 155.553962 -279.071992) (xy 155.583527 -279.111336) (xy 155.606398 -279.154913) (xy 155.621982 -279.201594)
			(xy 155.629877 -279.250171) (xy 155.630372 -279.274778) (xy 155.96922 -279.274778) (xy 155.97318 -279.225724)
			(xy 155.984957 -279.17794) (xy 156.004248 -279.132664) (xy 156.030551 -279.091068) (xy 156.063186 -279.054231)
			(xy 156.101307 -279.023106) (xy 156.143928 -278.998499) (xy 156.189944 -278.981047) (xy 156.238163 -278.971203)
			(xy 156.287338 -278.969222) (xy 156.336193 -278.975154) (xy 156.383464 -278.988846) (xy 156.427926 -279.009944)
			(xy 156.468429 -279.0379) (xy 156.503922 -279.071992) (xy 156.533487 -279.111336) (xy 156.556358 -279.154913)
			(xy 156.571942 -279.201594) (xy 156.579837 -279.250171) (xy 156.580332 -279.274778) (xy 156.91918 -279.274778)
			(xy 156.92314 -279.225724) (xy 156.934917 -279.17794) (xy 156.954208 -279.132664) (xy 156.980511 -279.091068)
			(xy 157.013146 -279.054231) (xy 157.051267 -279.023106) (xy 157.093888 -278.998499) (xy 157.139904 -278.981047)
			(xy 157.188123 -278.971203) (xy 157.237298 -278.969222) (xy 157.286153 -278.975154) (xy 157.333424 -278.988846)
			(xy 157.377886 -279.009944) (xy 157.418389 -279.0379) (xy 157.453882 -279.071992) (xy 157.483447 -279.111336)
			(xy 157.506318 -279.154913) (xy 157.521902 -279.201594) (xy 157.529797 -279.250171) (xy 157.530292 -279.274778)
			(xy 157.86914 -279.274778) (xy 157.8731 -279.225724) (xy 157.884877 -279.17794) (xy 157.904168 -279.132664)
			(xy 157.930471 -279.091068) (xy 157.963106 -279.054231) (xy 158.001227 -279.023106) (xy 158.043848 -278.998499)
			(xy 158.089864 -278.981047) (xy 158.138083 -278.971203) (xy 158.187258 -278.969222) (xy 158.236113 -278.975154)
			(xy 158.283384 -278.988846) (xy 158.327846 -279.009944) (xy 158.368349 -279.0379) (xy 158.403842 -279.071992)
			(xy 158.433407 -279.111336) (xy 158.456278 -279.154913) (xy 158.471862 -279.201594) (xy 158.479757 -279.250171)
			(xy 158.480252 -279.274778) (xy 158.479757 -279.299385) (xy 158.471862 -279.347962) (xy 158.456278 -279.394643)
			(xy 158.433407 -279.43822) (xy 158.403842 -279.477564) (xy 158.368349 -279.511656) (xy 158.327846 -279.539612)
			(xy 158.283384 -279.56071) (xy 158.236113 -279.574402) (xy 158.187258 -279.580334) (xy 158.138083 -279.578353)
			(xy 158.089864 -279.568509) (xy 158.043848 -279.551057) (xy 158.001227 -279.52645) (xy 157.963106 -279.495325)
			(xy 157.930471 -279.458488) (xy 157.904168 -279.416892) (xy 157.884877 -279.371616) (xy 157.8731 -279.323832)
			(xy 157.86914 -279.274778) (xy 157.530292 -279.274778) (xy 157.529797 -279.299385) (xy 157.521902 -279.347962)
			(xy 157.506318 -279.394643) (xy 157.483447 -279.43822) (xy 157.453882 -279.477564) (xy 157.418389 -279.511656)
			(xy 157.377886 -279.539612) (xy 157.333424 -279.56071) (xy 157.286153 -279.574402) (xy 157.237298 -279.580334)
			(xy 157.188123 -279.578353) (xy 157.139904 -279.568509) (xy 157.093888 -279.551057) (xy 157.051267 -279.52645)
			(xy 157.013146 -279.495325) (xy 156.980511 -279.458488) (xy 156.954208 -279.416892) (xy 156.934917 -279.371616)
			(xy 156.92314 -279.323832) (xy 156.91918 -279.274778) (xy 156.580332 -279.274778) (xy 156.579837 -279.299385)
			(xy 156.571942 -279.347962) (xy 156.556358 -279.394643) (xy 156.533487 -279.43822) (xy 156.503922 -279.477564)
			(xy 156.468429 -279.511656) (xy 156.427926 -279.539612) (xy 156.383464 -279.56071) (xy 156.336193 -279.574402)
			(xy 156.287338 -279.580334) (xy 156.238163 -279.578353) (xy 156.189944 -279.568509) (xy 156.143928 -279.551057)
			(xy 156.101307 -279.52645) (xy 156.063186 -279.495325) (xy 156.030551 -279.458488) (xy 156.004248 -279.416892)
			(xy 155.984957 -279.371616) (xy 155.97318 -279.323832) (xy 155.96922 -279.274778) (xy 155.630372 -279.274778)
			(xy 155.629877 -279.299385) (xy 155.621982 -279.347962) (xy 155.606398 -279.394643) (xy 155.583527 -279.43822)
			(xy 155.553962 -279.477564) (xy 155.518469 -279.511656) (xy 155.477966 -279.539612) (xy 155.433504 -279.56071)
			(xy 155.386233 -279.574402) (xy 155.337378 -279.580334) (xy 155.288203 -279.578353) (xy 155.239984 -279.568509)
			(xy 155.193968 -279.551057) (xy 155.151347 -279.52645) (xy 155.113226 -279.495325) (xy 155.080591 -279.458488)
			(xy 155.054288 -279.416892) (xy 155.034997 -279.371616) (xy 155.02322 -279.323832) (xy 155.01926 -279.274778)
			(xy 154.680412 -279.274778) (xy 154.679917 -279.299385) (xy 154.672022 -279.347962) (xy 154.656438 -279.394643)
			(xy 154.633567 -279.43822) (xy 154.604002 -279.477564) (xy 154.568509 -279.511656) (xy 154.528006 -279.539612)
			(xy 154.483544 -279.56071) (xy 154.436273 -279.574402) (xy 154.387418 -279.580334) (xy 154.338243 -279.578353)
			(xy 154.290024 -279.568509) (xy 154.244008 -279.551057) (xy 154.201387 -279.52645) (xy 154.163266 -279.495325)
			(xy 154.130631 -279.458488) (xy 154.104328 -279.416892) (xy 154.085037 -279.371616) (xy 154.07326 -279.323832)
			(xy 154.0693 -279.274778) (xy 153.730198 -279.274778) (xy 153.729703 -279.299385) (xy 153.721808 -279.347962)
			(xy 153.706224 -279.394643) (xy 153.683353 -279.43822) (xy 153.653788 -279.477564) (xy 153.618295 -279.511656)
			(xy 153.577792 -279.539612) (xy 153.53333 -279.56071) (xy 153.486059 -279.574402) (xy 153.437204 -279.580334)
			(xy 153.388029 -279.578353) (xy 153.33981 -279.568509) (xy 153.293794 -279.551057) (xy 153.251173 -279.52645)
			(xy 153.213052 -279.495325) (xy 153.180417 -279.458488) (xy 153.154114 -279.416892) (xy 153.134823 -279.371616)
			(xy 153.123046 -279.323832) (xy 153.119086 -279.274778) (xy 152.780238 -279.274778) (xy 152.779743 -279.299385)
			(xy 152.771848 -279.347962) (xy 152.756264 -279.394643) (xy 152.733393 -279.43822) (xy 152.703828 -279.477564)
			(xy 152.668335 -279.511656) (xy 152.627832 -279.539612) (xy 152.58337 -279.56071) (xy 152.536099 -279.574402)
			(xy 152.487244 -279.580334) (xy 152.438069 -279.578353) (xy 152.38985 -279.568509) (xy 152.343834 -279.551057)
			(xy 152.301213 -279.52645) (xy 152.263092 -279.495325) (xy 152.230457 -279.458488) (xy 152.204154 -279.416892)
			(xy 152.184863 -279.371616) (xy 152.173086 -279.323832) (xy 152.169126 -279.274778) (xy 137.118834 -279.274778)
			(xy 137.068197 -279.288717) (xy 136.988804 -279.307036) (xy 136.977715 -279.31009) (xy 136.959725 -279.324386)
			(xy 136.94973 -279.345077) (xy 136.94918 -279.356566) (xy 136.94918 -279.931114) (xy 141.911576 -279.931114)
			(xy 141.915647 -279.875492) (xy 141.927773 -279.821055) (xy 141.947696 -279.768964) (xy 141.974992 -279.720329)
			(xy 142.009078 -279.676186) (xy 142.049227 -279.637477) (xy 142.094585 -279.605026) (xy 142.144185 -279.579525)
			(xy 142.196969 -279.561518) (xy 142.251812 -279.551388) (xy 142.307546 -279.549351) (xy 142.362983 -279.555451)
			(xy 142.41694 -279.569557) (xy 142.468269 -279.591369) (xy 142.515875 -279.620423) (xy 142.558743 -279.656098)
			(xy 142.59596 -279.697635) (xy 142.626733 -279.744148) (xy 142.650405 -279.794645) (xy 142.666473 -279.848052)
			(xy 142.674593 -279.903228) (xy 142.675102 -279.931114) (xy 143.387062 -279.931114) (xy 143.391133 -279.875492)
			(xy 143.403259 -279.821055) (xy 143.423182 -279.768964) (xy 143.450478 -279.720329) (xy 143.484564 -279.676186)
			(xy 143.524713 -279.637477) (xy 143.570071 -279.605026) (xy 143.619671 -279.579525) (xy 143.672455 -279.561518)
			(xy 143.727298 -279.551388) (xy 143.783032 -279.549351) (xy 143.838469 -279.555451) (xy 143.892426 -279.569557)
			(xy 143.943755 -279.591369) (xy 143.991361 -279.620423) (xy 144.034229 -279.656098) (xy 144.071446 -279.697635)
			(xy 144.102219 -279.744148) (xy 144.125891 -279.794645) (xy 144.141959 -279.848052) (xy 144.150079 -279.903228)
			(xy 144.150588 -279.931114) (xy 144.276062 -279.931114) (xy 144.280133 -279.875492) (xy 144.292259 -279.821055)
			(xy 144.312182 -279.768964) (xy 144.339478 -279.720329) (xy 144.373564 -279.676186) (xy 144.413713 -279.637477)
			(xy 144.459071 -279.605026) (xy 144.508671 -279.579525) (xy 144.561455 -279.561518) (xy 144.616298 -279.551388)
			(xy 144.672032 -279.549351) (xy 144.727469 -279.555451) (xy 144.781426 -279.569557) (xy 144.832755 -279.591369)
			(xy 144.880361 -279.620423) (xy 144.923229 -279.656098) (xy 144.960446 -279.697635) (xy 144.991219 -279.744148)
			(xy 145.014891 -279.794645) (xy 145.030959 -279.848052) (xy 145.039079 -279.903228) (xy 145.039588 -279.931114)
			(xy 145.039079 -279.959) (xy 145.030959 -280.014176) (xy 145.014891 -280.067583) (xy 144.991219 -280.11808)
			(xy 144.960446 -280.164593) (xy 144.923229 -280.20613) (xy 144.880361 -280.241805) (xy 144.832755 -280.270859)
			(xy 144.781426 -280.292671) (xy 144.727469 -280.306777) (xy 144.672032 -280.312877) (xy 144.616298 -280.31084)
			(xy 144.561455 -280.30071) (xy 144.508671 -280.282703) (xy 144.459071 -280.257202) (xy 144.413713 -280.224751)
			(xy 144.373564 -280.186042) (xy 144.339478 -280.141899) (xy 144.312182 -280.093264) (xy 144.292259 -280.041173)
			(xy 144.280133 -279.986736) (xy 144.276062 -279.931114) (xy 144.150588 -279.931114) (xy 144.150079 -279.959)
			(xy 144.141959 -280.014176) (xy 144.125891 -280.067583) (xy 144.102219 -280.11808) (xy 144.071446 -280.164593)
			(xy 144.034229 -280.20613) (xy 143.991361 -280.241805) (xy 143.943755 -280.270859) (xy 143.892426 -280.292671)
			(xy 143.838469 -280.306777) (xy 143.783032 -280.312877) (xy 143.727298 -280.31084) (xy 143.672455 -280.30071)
			(xy 143.619671 -280.282703) (xy 143.570071 -280.257202) (xy 143.524713 -280.224751) (xy 143.484564 -280.186042)
			(xy 143.450478 -280.141899) (xy 143.423182 -280.093264) (xy 143.403259 -280.041173) (xy 143.391133 -279.986736)
			(xy 143.387062 -279.931114) (xy 142.675102 -279.931114) (xy 142.674593 -279.959) (xy 142.666473 -280.014176)
			(xy 142.650405 -280.067583) (xy 142.626733 -280.11808) (xy 142.59596 -280.164593) (xy 142.558743 -280.20613)
			(xy 142.515875 -280.241805) (xy 142.468269 -280.270859) (xy 142.41694 -280.292671) (xy 142.362983 -280.306777)
			(xy 142.307546 -280.312877) (xy 142.251812 -280.31084) (xy 142.196969 -280.30071) (xy 142.144185 -280.282703)
			(xy 142.094585 -280.257202) (xy 142.049227 -280.224751) (xy 142.009078 -280.186042) (xy 141.974992 -280.141899)
			(xy 141.947696 -280.093264) (xy 141.927773 -280.041173) (xy 141.915647 -279.986736) (xy 141.911576 -279.931114)
			(xy 136.94918 -279.931114) (xy 136.94918 -280.693114) (xy 147.43811 -280.693114) (xy 147.438654 -280.663732)
			(xy 147.447683 -280.605665) (xy 147.465514 -280.549671) (xy 147.491725 -280.497075) (xy 147.525695 -280.449124)
			(xy 147.56662 -280.406952) (xy 147.589748 -280.388822) (xy 147.599146 -280.381456) (xy 147.60956 -280.360882)
			(xy 147.611084 -280.256996) (xy 147.601178 -280.235914) (xy 147.592034 -280.228548) (xy 147.570186 -280.210342)
			(xy 147.531644 -280.168524) (xy 147.499736 -280.121449) (xy 147.475169 -280.070159) (xy 147.458486 -280.015791)
			(xy 147.450058 -279.959549) (xy 147.44954 -279.931114) (xy 147.450026 -279.903863) (xy 147.457782 -279.849915)
			(xy 147.473137 -279.79762) (xy 147.495779 -279.748043) (xy 147.525245 -279.702193) (xy 147.560936 -279.661002)
			(xy 147.602127 -279.625311) (xy 147.647977 -279.595845) (xy 147.697554 -279.573203) (xy 147.749849 -279.557848)
			(xy 147.803797 -279.550092) (xy 147.858299 -279.550092) (xy 147.912247 -279.557848) (xy 147.964542 -279.573203)
			(xy 148.014119 -279.595845) (xy 148.059969 -279.625311) (xy 148.10116 -279.661002) (xy 148.136851 -279.702193)
			(xy 148.166317 -279.748043) (xy 148.188959 -279.79762) (xy 148.204314 -279.849915) (xy 148.21207 -279.903863)
			(xy 148.212556 -279.931114) (xy 148.212006 -279.960496) (xy 148.202975 -280.018561) (xy 148.185143 -280.074554)
			(xy 148.158933 -280.127149) (xy 148.124966 -280.175101) (xy 148.084044 -280.217274) (xy 148.074524 -280.224738)
			(xy 152.169126 -280.224738) (xy 152.173086 -280.175684) (xy 152.184863 -280.1279) (xy 152.204154 -280.082624)
			(xy 152.230457 -280.041028) (xy 152.263092 -280.004191) (xy 152.301213 -279.973066) (xy 152.343834 -279.948459)
			(xy 152.38985 -279.931007) (xy 152.438069 -279.921163) (xy 152.487244 -279.919182) (xy 152.536099 -279.925114)
			(xy 152.58337 -279.938806) (xy 152.627832 -279.959904) (xy 152.668335 -279.98786) (xy 152.703828 -280.021952)
			(xy 152.733393 -280.061296) (xy 152.756264 -280.104873) (xy 152.771848 -280.151554) (xy 152.779743 -280.200131)
			(xy 152.780238 -280.224738) (xy 153.119086 -280.224738) (xy 153.123046 -280.175684) (xy 153.134823 -280.1279)
			(xy 153.154114 -280.082624) (xy 153.180417 -280.041028) (xy 153.213052 -280.004191) (xy 153.251173 -279.973066)
			(xy 153.293794 -279.948459) (xy 153.33981 -279.931007) (xy 153.388029 -279.921163) (xy 153.437204 -279.919182)
			(xy 153.486059 -279.925114) (xy 153.53333 -279.938806) (xy 153.577792 -279.959904) (xy 153.618295 -279.98786)
			(xy 153.653788 -280.021952) (xy 153.683353 -280.061296) (xy 153.706224 -280.104873) (xy 153.721808 -280.151554)
			(xy 153.729703 -280.200131) (xy 153.730198 -280.224738) (xy 154.0693 -280.224738) (xy 154.07326 -280.175684)
			(xy 154.085037 -280.1279) (xy 154.104328 -280.082624) (xy 154.130631 -280.041028) (xy 154.163266 -280.004191)
			(xy 154.201387 -279.973066) (xy 154.244008 -279.948459) (xy 154.290024 -279.931007) (xy 154.338243 -279.921163)
			(xy 154.387418 -279.919182) (xy 154.436273 -279.925114) (xy 154.483544 -279.938806) (xy 154.528006 -279.959904)
			(xy 154.568509 -279.98786) (xy 154.604002 -280.021952) (xy 154.633567 -280.061296) (xy 154.656438 -280.104873)
			(xy 154.672022 -280.151554) (xy 154.679917 -280.200131) (xy 154.680412 -280.224738) (xy 155.01926 -280.224738)
			(xy 155.02322 -280.175684) (xy 155.034997 -280.1279) (xy 155.054288 -280.082624) (xy 155.080591 -280.041028)
			(xy 155.113226 -280.004191) (xy 155.151347 -279.973066) (xy 155.193968 -279.948459) (xy 155.239984 -279.931007)
			(xy 155.288203 -279.921163) (xy 155.337378 -279.919182) (xy 155.386233 -279.925114) (xy 155.433504 -279.938806)
			(xy 155.477966 -279.959904) (xy 155.518469 -279.98786) (xy 155.553962 -280.021952) (xy 155.583527 -280.061296)
			(xy 155.606398 -280.104873) (xy 155.621982 -280.151554) (xy 155.629877 -280.200131) (xy 155.630372 -280.224738)
			(xy 155.96922 -280.224738) (xy 155.97318 -280.175684) (xy 155.984957 -280.1279) (xy 156.004248 -280.082624)
			(xy 156.030551 -280.041028) (xy 156.063186 -280.004191) (xy 156.101307 -279.973066) (xy 156.143928 -279.948459)
			(xy 156.189944 -279.931007) (xy 156.238163 -279.921163) (xy 156.287338 -279.919182) (xy 156.336193 -279.925114)
			(xy 156.383464 -279.938806) (xy 156.427926 -279.959904) (xy 156.468429 -279.98786) (xy 156.503922 -280.021952)
			(xy 156.533487 -280.061296) (xy 156.556358 -280.104873) (xy 156.571942 -280.151554) (xy 156.579837 -280.200131)
			(xy 156.580332 -280.224738) (xy 156.91918 -280.224738) (xy 156.92314 -280.175684) (xy 156.934917 -280.1279)
			(xy 156.954208 -280.082624) (xy 156.980511 -280.041028) (xy 157.013146 -280.004191) (xy 157.051267 -279.973066)
			(xy 157.093888 -279.948459) (xy 157.139904 -279.931007) (xy 157.188123 -279.921163) (xy 157.237298 -279.919182)
			(xy 157.286153 -279.925114) (xy 157.333424 -279.938806) (xy 157.377886 -279.959904) (xy 157.418389 -279.98786)
			(xy 157.453882 -280.021952) (xy 157.483447 -280.061296) (xy 157.506318 -280.104873) (xy 157.521902 -280.151554)
			(xy 157.529797 -280.200131) (xy 157.530292 -280.224738) (xy 157.86914 -280.224738) (xy 157.8731 -280.175684)
			(xy 157.884877 -280.1279) (xy 157.904168 -280.082624) (xy 157.930471 -280.041028) (xy 157.963106 -280.004191)
			(xy 158.001227 -279.973066) (xy 158.043848 -279.948459) (xy 158.089864 -279.931007) (xy 158.138083 -279.921163)
			(xy 158.187258 -279.919182) (xy 158.236113 -279.925114) (xy 158.283384 -279.938806) (xy 158.327846 -279.959904)
			(xy 158.368349 -279.98786) (xy 158.403842 -280.021952) (xy 158.433407 -280.061296) (xy 158.456278 -280.104873)
			(xy 158.471862 -280.151554) (xy 158.479757 -280.200131) (xy 158.480252 -280.224738) (xy 158.8191 -280.224738)
			(xy 158.82306 -280.175684) (xy 158.834837 -280.1279) (xy 158.854128 -280.082624) (xy 158.880431 -280.041028)
			(xy 158.913066 -280.004191) (xy 158.951187 -279.973066) (xy 158.993808 -279.948459) (xy 159.039824 -279.931007)
			(xy 159.088043 -279.921163) (xy 159.137218 -279.919182) (xy 159.186073 -279.925114) (xy 159.233344 -279.938806)
			(xy 159.277806 -279.959904) (xy 159.318309 -279.98786) (xy 159.353802 -280.021952) (xy 159.383367 -280.061296)
			(xy 159.406238 -280.104873) (xy 159.421822 -280.151554) (xy 159.429717 -280.200131) (xy 159.430212 -280.224738)
			(xy 159.429717 -280.249345) (xy 159.421822 -280.297922) (xy 159.406238 -280.344603) (xy 159.383367 -280.38818)
			(xy 159.353802 -280.427524) (xy 159.318309 -280.461616) (xy 159.277806 -280.489572) (xy 159.233344 -280.51067)
			(xy 159.186073 -280.524362) (xy 159.137218 -280.530294) (xy 159.088043 -280.528313) (xy 159.039824 -280.518469)
			(xy 158.993808 -280.501017) (xy 158.951187 -280.47641) (xy 158.913066 -280.445285) (xy 158.880431 -280.408448)
			(xy 158.854128 -280.366852) (xy 158.834837 -280.321576) (xy 158.82306 -280.273792) (xy 158.8191 -280.224738)
			(xy 158.480252 -280.224738) (xy 158.479757 -280.249345) (xy 158.471862 -280.297922) (xy 158.456278 -280.344603)
			(xy 158.433407 -280.38818) (xy 158.403842 -280.427524) (xy 158.368349 -280.461616) (xy 158.327846 -280.489572)
			(xy 158.283384 -280.51067) (xy 158.236113 -280.524362) (xy 158.187258 -280.530294) (xy 158.138083 -280.528313)
			(xy 158.089864 -280.518469) (xy 158.043848 -280.501017) (xy 158.001227 -280.47641) (xy 157.963106 -280.445285)
			(xy 157.930471 -280.408448) (xy 157.904168 -280.366852) (xy 157.884877 -280.321576) (xy 157.8731 -280.273792)
			(xy 157.86914 -280.224738) (xy 157.530292 -280.224738) (xy 157.529797 -280.249345) (xy 157.521902 -280.297922)
			(xy 157.506318 -280.344603) (xy 157.483447 -280.38818) (xy 157.453882 -280.427524) (xy 157.418389 -280.461616)
			(xy 157.377886 -280.489572) (xy 157.333424 -280.51067) (xy 157.286153 -280.524362) (xy 157.237298 -280.530294)
			(xy 157.188123 -280.528313) (xy 157.139904 -280.518469) (xy 157.093888 -280.501017) (xy 157.051267 -280.47641)
			(xy 157.013146 -280.445285) (xy 156.980511 -280.408448) (xy 156.954208 -280.366852) (xy 156.934917 -280.321576)
			(xy 156.92314 -280.273792) (xy 156.91918 -280.224738) (xy 156.580332 -280.224738) (xy 156.579837 -280.249345)
			(xy 156.571942 -280.297922) (xy 156.556358 -280.344603) (xy 156.533487 -280.38818) (xy 156.503922 -280.427524)
			(xy 156.468429 -280.461616) (xy 156.427926 -280.489572) (xy 156.383464 -280.51067) (xy 156.336193 -280.524362)
			(xy 156.287338 -280.530294) (xy 156.238163 -280.528313) (xy 156.189944 -280.518469) (xy 156.143928 -280.501017)
			(xy 156.101307 -280.47641) (xy 156.063186 -280.445285) (xy 156.030551 -280.408448) (xy 156.004248 -280.366852)
			(xy 155.984957 -280.321576) (xy 155.97318 -280.273792) (xy 155.96922 -280.224738) (xy 155.630372 -280.224738)
			(xy 155.629877 -280.249345) (xy 155.621982 -280.297922) (xy 155.606398 -280.344603) (xy 155.583527 -280.38818)
			(xy 155.553962 -280.427524) (xy 155.518469 -280.461616) (xy 155.477966 -280.489572) (xy 155.433504 -280.51067)
			(xy 155.386233 -280.524362) (xy 155.337378 -280.530294) (xy 155.288203 -280.528313) (xy 155.239984 -280.518469)
			(xy 155.193968 -280.501017) (xy 155.151347 -280.47641) (xy 155.113226 -280.445285) (xy 155.080591 -280.408448)
			(xy 155.054288 -280.366852) (xy 155.034997 -280.321576) (xy 155.02322 -280.273792) (xy 155.01926 -280.224738)
			(xy 154.680412 -280.224738) (xy 154.679917 -280.249345) (xy 154.672022 -280.297922) (xy 154.656438 -280.344603)
			(xy 154.633567 -280.38818) (xy 154.604002 -280.427524) (xy 154.568509 -280.461616) (xy 154.528006 -280.489572)
			(xy 154.483544 -280.51067) (xy 154.436273 -280.524362) (xy 154.387418 -280.530294) (xy 154.338243 -280.528313)
			(xy 154.290024 -280.518469) (xy 154.244008 -280.501017) (xy 154.201387 -280.47641) (xy 154.163266 -280.445285)
			(xy 154.130631 -280.408448) (xy 154.104328 -280.366852) (xy 154.085037 -280.321576) (xy 154.07326 -280.273792)
			(xy 154.0693 -280.224738) (xy 153.730198 -280.224738) (xy 153.729703 -280.249345) (xy 153.721808 -280.297922)
			(xy 153.706224 -280.344603) (xy 153.683353 -280.38818) (xy 153.653788 -280.427524) (xy 153.618295 -280.461616)
			(xy 153.577792 -280.489572) (xy 153.53333 -280.51067) (xy 153.486059 -280.524362) (xy 153.437204 -280.530294)
			(xy 153.388029 -280.528313) (xy 153.33981 -280.518469) (xy 153.293794 -280.501017) (xy 153.251173 -280.47641)
			(xy 153.213052 -280.445285) (xy 153.180417 -280.408448) (xy 153.154114 -280.366852) (xy 153.134823 -280.321576)
			(xy 153.123046 -280.273792) (xy 153.119086 -280.224738) (xy 152.780238 -280.224738) (xy 152.779743 -280.249345)
			(xy 152.771848 -280.297922) (xy 152.756264 -280.344603) (xy 152.733393 -280.38818) (xy 152.703828 -280.427524)
			(xy 152.668335 -280.461616) (xy 152.627832 -280.489572) (xy 152.58337 -280.51067) (xy 152.536099 -280.524362)
			(xy 152.487244 -280.530294) (xy 152.438069 -280.528313) (xy 152.38985 -280.518469) (xy 152.343834 -280.501017)
			(xy 152.301213 -280.47641) (xy 152.263092 -280.445285) (xy 152.230457 -280.408448) (xy 152.204154 -280.366852)
			(xy 152.184863 -280.321576) (xy 152.173086 -280.273792) (xy 152.169126 -280.224738) (xy 148.074524 -280.224738)
			(xy 148.060918 -280.235406) (xy 148.05152 -280.242772) (xy 148.041106 -280.263346) (xy 148.039582 -280.367232)
			(xy 148.049488 -280.388314) (xy 148.058632 -280.39568) (xy 148.080459 -280.413909) (xy 148.118999 -280.455724)
			(xy 148.150908 -280.502795) (xy 148.175478 -280.55408) (xy 148.192166 -280.608443) (xy 148.200603 -280.664681)
			(xy 148.201126 -280.693114) (xy 148.8346 -280.693114) (xy 148.838671 -280.637492) (xy 148.850797 -280.583055)
			(xy 148.87072 -280.530964) (xy 148.898016 -280.482329) (xy 148.932102 -280.438186) (xy 148.972251 -280.399477)
			(xy 149.017609 -280.367026) (xy 149.067209 -280.341525) (xy 149.119993 -280.323518) (xy 149.174836 -280.313388)
			(xy 149.23057 -280.311351) (xy 149.286007 -280.317451) (xy 149.339964 -280.331557) (xy 149.391293 -280.353369)
			(xy 149.438899 -280.382423) (xy 149.481767 -280.418098) (xy 149.518984 -280.459635) (xy 149.549757 -280.506148)
			(xy 149.573429 -280.556645) (xy 149.589497 -280.610052) (xy 149.597617 -280.665228) (xy 149.598126 -280.693114)
			(xy 149.72106 -280.693114) (xy 149.725131 -280.637492) (xy 149.737257 -280.583055) (xy 149.75718 -280.530964)
			(xy 149.784476 -280.482329) (xy 149.818562 -280.438186) (xy 149.858711 -280.399477) (xy 149.904069 -280.367026)
			(xy 149.953669 -280.341525) (xy 150.006453 -280.323518) (xy 150.061296 -280.313388) (xy 150.11703 -280.311351)
			(xy 150.172467 -280.317451) (xy 150.226424 -280.331557) (xy 150.277753 -280.353369) (xy 150.325359 -280.382423)
			(xy 150.368227 -280.418098) (xy 150.405444 -280.459635) (xy 150.436217 -280.506148) (xy 150.459889 -280.556645)
			(xy 150.475957 -280.610052) (xy 150.484077 -280.665228) (xy 150.484586 -280.693114) (xy 150.484077 -280.721)
			(xy 150.475957 -280.776176) (xy 150.459889 -280.829583) (xy 150.436217 -280.88008) (xy 150.405444 -280.926593)
			(xy 150.368227 -280.96813) (xy 150.325359 -281.003805) (xy 150.277753 -281.032859) (xy 150.226424 -281.054671)
			(xy 150.172467 -281.068777) (xy 150.11703 -281.074877) (xy 150.061296 -281.07284) (xy 150.006453 -281.06271)
			(xy 149.953669 -281.044703) (xy 149.904069 -281.019202) (xy 149.858711 -280.986751) (xy 149.818562 -280.948042)
			(xy 149.784476 -280.903899) (xy 149.75718 -280.855264) (xy 149.737257 -280.803173) (xy 149.725131 -280.748736)
			(xy 149.72106 -280.693114) (xy 149.598126 -280.693114) (xy 149.597617 -280.721) (xy 149.589497 -280.776176)
			(xy 149.573429 -280.829583) (xy 149.549757 -280.88008) (xy 149.518984 -280.926593) (xy 149.481767 -280.96813)
			(xy 149.438899 -281.003805) (xy 149.391293 -281.032859) (xy 149.339964 -281.054671) (xy 149.286007 -281.068777)
			(xy 149.23057 -281.074877) (xy 149.174836 -281.07284) (xy 149.119993 -281.06271) (xy 149.067209 -281.044703)
			(xy 149.017609 -281.019202) (xy 148.972251 -280.986751) (xy 148.932102 -280.948042) (xy 148.898016 -280.903899)
			(xy 148.87072 -280.855264) (xy 148.850797 -280.803173) (xy 148.838671 -280.748736) (xy 148.8346 -280.693114)
			(xy 148.201126 -280.693114) (xy 148.20064 -280.720365) (xy 148.192884 -280.774313) (xy 148.177529 -280.826608)
			(xy 148.154887 -280.876185) (xy 148.125421 -280.922035) (xy 148.08973 -280.963226) (xy 148.048539 -280.998917)
			(xy 148.002689 -281.028383) (xy 147.953112 -281.051025) (xy 147.900817 -281.06638) (xy 147.846869 -281.074136)
			(xy 147.792367 -281.074136) (xy 147.738419 -281.06638) (xy 147.686124 -281.051025) (xy 147.636547 -281.028383)
			(xy 147.590697 -280.998917) (xy 147.549506 -280.963226) (xy 147.513815 -280.922035) (xy 147.484349 -280.876185)
			(xy 147.461707 -280.826608) (xy 147.446352 -280.774313) (xy 147.438596 -280.720365) (xy 147.43811 -280.693114)
			(xy 136.94918 -280.693114) (xy 136.94918 -281.174952) (xy 152.169126 -281.174952) (xy 152.173086 -281.125898)
			(xy 152.184863 -281.078114) (xy 152.204154 -281.032838) (xy 152.230457 -280.991242) (xy 152.263092 -280.954405)
			(xy 152.301213 -280.92328) (xy 152.343834 -280.898673) (xy 152.38985 -280.881221) (xy 152.438069 -280.871377)
			(xy 152.487244 -280.869396) (xy 152.536099 -280.875328) (xy 152.58337 -280.88902) (xy 152.627832 -280.910118)
			(xy 152.668335 -280.938074) (xy 152.703828 -280.972166) (xy 152.733393 -281.01151) (xy 152.756264 -281.055087)
			(xy 152.771848 -281.101768) (xy 152.779743 -281.150345) (xy 152.780238 -281.174952) (xy 153.119086 -281.174952)
			(xy 153.123046 -281.125898) (xy 153.134823 -281.078114) (xy 153.154114 -281.032838) (xy 153.180417 -280.991242)
			(xy 153.213052 -280.954405) (xy 153.251173 -280.92328) (xy 153.293794 -280.898673) (xy 153.33981 -280.881221)
			(xy 153.388029 -280.871377) (xy 153.437204 -280.869396) (xy 153.486059 -280.875328) (xy 153.53333 -280.88902)
			(xy 153.577792 -280.910118) (xy 153.618295 -280.938074) (xy 153.653788 -280.972166) (xy 153.683353 -281.01151)
			(xy 153.706224 -281.055087) (xy 153.721808 -281.101768) (xy 153.729703 -281.150345) (xy 153.730198 -281.174952)
			(xy 154.0693 -281.174952) (xy 154.07326 -281.125898) (xy 154.085037 -281.078114) (xy 154.104328 -281.032838)
			(xy 154.130631 -280.991242) (xy 154.163266 -280.954405) (xy 154.201387 -280.92328) (xy 154.244008 -280.898673)
			(xy 154.290024 -280.881221) (xy 154.338243 -280.871377) (xy 154.387418 -280.869396) (xy 154.436273 -280.875328)
			(xy 154.483544 -280.88902) (xy 154.528006 -280.910118) (xy 154.568509 -280.938074) (xy 154.604002 -280.972166)
			(xy 154.633567 -281.01151) (xy 154.656438 -281.055087) (xy 154.672022 -281.101768) (xy 154.679917 -281.150345)
			(xy 154.680412 -281.174952) (xy 155.01926 -281.174952) (xy 155.02322 -281.125898) (xy 155.034997 -281.078114)
			(xy 155.054288 -281.032838) (xy 155.080591 -280.991242) (xy 155.113226 -280.954405) (xy 155.151347 -280.92328)
			(xy 155.193968 -280.898673) (xy 155.239984 -280.881221) (xy 155.288203 -280.871377) (xy 155.337378 -280.869396)
			(xy 155.386233 -280.875328) (xy 155.433504 -280.88902) (xy 155.477966 -280.910118) (xy 155.518469 -280.938074)
			(xy 155.553962 -280.972166) (xy 155.583527 -281.01151) (xy 155.606398 -281.055087) (xy 155.621982 -281.101768)
			(xy 155.629877 -281.150345) (xy 155.630372 -281.174952) (xy 155.96922 -281.174952) (xy 155.97318 -281.125898)
			(xy 155.984957 -281.078114) (xy 156.004248 -281.032838) (xy 156.030551 -280.991242) (xy 156.063186 -280.954405)
			(xy 156.101307 -280.92328) (xy 156.143928 -280.898673) (xy 156.189944 -280.881221) (xy 156.238163 -280.871377)
			(xy 156.287338 -280.869396) (xy 156.336193 -280.875328) (xy 156.383464 -280.88902) (xy 156.427926 -280.910118)
			(xy 156.468429 -280.938074) (xy 156.503922 -280.972166) (xy 156.533487 -281.01151) (xy 156.556358 -281.055087)
			(xy 156.571942 -281.101768) (xy 156.579837 -281.150345) (xy 156.580332 -281.174952) (xy 156.91918 -281.174952)
			(xy 156.92314 -281.125898) (xy 156.934917 -281.078114) (xy 156.954208 -281.032838) (xy 156.980511 -280.991242)
			(xy 157.013146 -280.954405) (xy 157.051267 -280.92328) (xy 157.093888 -280.898673) (xy 157.139904 -280.881221)
			(xy 157.188123 -280.871377) (xy 157.237298 -280.869396) (xy 157.286153 -280.875328) (xy 157.333424 -280.88902)
			(xy 157.377886 -280.910118) (xy 157.418389 -280.938074) (xy 157.453882 -280.972166) (xy 157.483447 -281.01151)
			(xy 157.506318 -281.055087) (xy 157.521902 -281.101768) (xy 157.529797 -281.150345) (xy 157.530292 -281.174952)
			(xy 157.86914 -281.174952) (xy 157.8731 -281.125898) (xy 157.884877 -281.078114) (xy 157.904168 -281.032838)
			(xy 157.930471 -280.991242) (xy 157.963106 -280.954405) (xy 158.001227 -280.92328) (xy 158.043848 -280.898673)
			(xy 158.089864 -280.881221) (xy 158.138083 -280.871377) (xy 158.187258 -280.869396) (xy 158.236113 -280.875328)
			(xy 158.283384 -280.88902) (xy 158.327846 -280.910118) (xy 158.368349 -280.938074) (xy 158.403842 -280.972166)
			(xy 158.433407 -281.01151) (xy 158.456278 -281.055087) (xy 158.471862 -281.101768) (xy 158.479757 -281.150345)
			(xy 158.480252 -281.174952) (xy 158.8191 -281.174952) (xy 158.82306 -281.125898) (xy 158.834837 -281.078114)
			(xy 158.854128 -281.032838) (xy 158.880431 -280.991242) (xy 158.913066 -280.954405) (xy 158.951187 -280.92328)
			(xy 158.993808 -280.898673) (xy 159.039824 -280.881221) (xy 159.088043 -280.871377) (xy 159.137218 -280.869396)
			(xy 159.186073 -280.875328) (xy 159.233344 -280.88902) (xy 159.277806 -280.910118) (xy 159.318309 -280.938074)
			(xy 159.353802 -280.972166) (xy 159.383367 -281.01151) (xy 159.406238 -281.055087) (xy 159.421822 -281.101768)
			(xy 159.429717 -281.150345) (xy 159.430212 -281.174952) (xy 159.429717 -281.199559) (xy 159.421822 -281.248136)
			(xy 159.406238 -281.294817) (xy 159.383367 -281.338394) (xy 159.353802 -281.377738) (xy 159.318309 -281.41183)
			(xy 159.277806 -281.439786) (xy 159.233344 -281.460884) (xy 159.186073 -281.474576) (xy 159.137218 -281.480508)
			(xy 159.088043 -281.478527) (xy 159.039824 -281.468683) (xy 158.993808 -281.451231) (xy 158.951187 -281.426624)
			(xy 158.913066 -281.395499) (xy 158.880431 -281.358662) (xy 158.854128 -281.317066) (xy 158.834837 -281.27179)
			(xy 158.82306 -281.224006) (xy 158.8191 -281.174952) (xy 158.480252 -281.174952) (xy 158.479757 -281.199559)
			(xy 158.471862 -281.248136) (xy 158.456278 -281.294817) (xy 158.433407 -281.338394) (xy 158.403842 -281.377738)
			(xy 158.368349 -281.41183) (xy 158.327846 -281.439786) (xy 158.283384 -281.460884) (xy 158.236113 -281.474576)
			(xy 158.187258 -281.480508) (xy 158.138083 -281.478527) (xy 158.089864 -281.468683) (xy 158.043848 -281.451231)
			(xy 158.001227 -281.426624) (xy 157.963106 -281.395499) (xy 157.930471 -281.358662) (xy 157.904168 -281.317066)
			(xy 157.884877 -281.27179) (xy 157.8731 -281.224006) (xy 157.86914 -281.174952) (xy 157.530292 -281.174952)
			(xy 157.529797 -281.199559) (xy 157.521902 -281.248136) (xy 157.506318 -281.294817) (xy 157.483447 -281.338394)
			(xy 157.453882 -281.377738) (xy 157.418389 -281.41183) (xy 157.377886 -281.439786) (xy 157.333424 -281.460884)
			(xy 157.286153 -281.474576) (xy 157.237298 -281.480508) (xy 157.188123 -281.478527) (xy 157.139904 -281.468683)
			(xy 157.093888 -281.451231) (xy 157.051267 -281.426624) (xy 157.013146 -281.395499) (xy 156.980511 -281.358662)
			(xy 156.954208 -281.317066) (xy 156.934917 -281.27179) (xy 156.92314 -281.224006) (xy 156.91918 -281.174952)
			(xy 156.580332 -281.174952) (xy 156.579837 -281.199559) (xy 156.571942 -281.248136) (xy 156.556358 -281.294817)
			(xy 156.533487 -281.338394) (xy 156.503922 -281.377738) (xy 156.468429 -281.41183) (xy 156.427926 -281.439786)
			(xy 156.383464 -281.460884) (xy 156.336193 -281.474576) (xy 156.287338 -281.480508) (xy 156.238163 -281.478527)
			(xy 156.189944 -281.468683) (xy 156.143928 -281.451231) (xy 156.101307 -281.426624) (xy 156.063186 -281.395499)
			(xy 156.030551 -281.358662) (xy 156.004248 -281.317066) (xy 155.984957 -281.27179) (xy 155.97318 -281.224006)
			(xy 155.96922 -281.174952) (xy 155.630372 -281.174952) (xy 155.629877 -281.199559) (xy 155.621982 -281.248136)
			(xy 155.606398 -281.294817) (xy 155.583527 -281.338394) (xy 155.553962 -281.377738) (xy 155.518469 -281.41183)
			(xy 155.477966 -281.439786) (xy 155.433504 -281.460884) (xy 155.386233 -281.474576) (xy 155.337378 -281.480508)
			(xy 155.288203 -281.478527) (xy 155.239984 -281.468683) (xy 155.193968 -281.451231) (xy 155.151347 -281.426624)
			(xy 155.113226 -281.395499) (xy 155.080591 -281.358662) (xy 155.054288 -281.317066) (xy 155.034997 -281.27179)
			(xy 155.02322 -281.224006) (xy 155.01926 -281.174952) (xy 154.680412 -281.174952) (xy 154.679917 -281.199559)
			(xy 154.672022 -281.248136) (xy 154.656438 -281.294817) (xy 154.633567 -281.338394) (xy 154.604002 -281.377738)
			(xy 154.568509 -281.41183) (xy 154.528006 -281.439786) (xy 154.483544 -281.460884) (xy 154.436273 -281.474576)
			(xy 154.387418 -281.480508) (xy 154.338243 -281.478527) (xy 154.290024 -281.468683) (xy 154.244008 -281.451231)
			(xy 154.201387 -281.426624) (xy 154.163266 -281.395499) (xy 154.130631 -281.358662) (xy 154.104328 -281.317066)
			(xy 154.085037 -281.27179) (xy 154.07326 -281.224006) (xy 154.0693 -281.174952) (xy 153.730198 -281.174952)
			(xy 153.729703 -281.199559) (xy 153.721808 -281.248136) (xy 153.706224 -281.294817) (xy 153.683353 -281.338394)
			(xy 153.653788 -281.377738) (xy 153.618295 -281.41183) (xy 153.577792 -281.439786) (xy 153.53333 -281.460884)
			(xy 153.486059 -281.474576) (xy 153.437204 -281.480508) (xy 153.388029 -281.478527) (xy 153.33981 -281.468683)
			(xy 153.293794 -281.451231) (xy 153.251173 -281.426624) (xy 153.213052 -281.395499) (xy 153.180417 -281.358662)
			(xy 153.154114 -281.317066) (xy 153.134823 -281.27179) (xy 153.123046 -281.224006) (xy 153.119086 -281.174952)
			(xy 152.780238 -281.174952) (xy 152.779743 -281.199559) (xy 152.771848 -281.248136) (xy 152.756264 -281.294817)
			(xy 152.733393 -281.338394) (xy 152.703828 -281.377738) (xy 152.668335 -281.41183) (xy 152.627832 -281.439786)
			(xy 152.58337 -281.460884) (xy 152.536099 -281.474576) (xy 152.487244 -281.480508) (xy 152.438069 -281.478527)
			(xy 152.38985 -281.468683) (xy 152.343834 -281.451231) (xy 152.301213 -281.426624) (xy 152.263092 -281.395499)
			(xy 152.230457 -281.358662) (xy 152.204154 -281.317066) (xy 152.184863 -281.27179) (xy 152.173086 -281.224006)
			(xy 152.169126 -281.174952) (xy 136.94918 -281.174952) (xy 136.94918 -281.829256) (xy 141.911576 -281.829256)
			(xy 141.915647 -281.773634) (xy 141.927773 -281.719197) (xy 141.947696 -281.667106) (xy 141.974992 -281.618471)
			(xy 142.009078 -281.574328) (xy 142.049227 -281.535619) (xy 142.094585 -281.503168) (xy 142.144185 -281.477667)
			(xy 142.196969 -281.45966) (xy 142.251812 -281.44953) (xy 142.307546 -281.447493) (xy 142.362983 -281.453593)
			(xy 142.41694 -281.467699) (xy 142.468269 -281.489511) (xy 142.515875 -281.518565) (xy 142.558743 -281.55424)
			(xy 142.59596 -281.595777) (xy 142.626733 -281.64229) (xy 142.650405 -281.692787) (xy 142.666473 -281.746194)
			(xy 142.674593 -281.80137) (xy 142.675102 -281.829256) (xy 143.396714 -281.829256) (xy 143.400785 -281.773634)
			(xy 143.412911 -281.719197) (xy 143.432834 -281.667106) (xy 143.46013 -281.618471) (xy 143.494216 -281.574328)
			(xy 143.534365 -281.535619) (xy 143.579723 -281.503168) (xy 143.629323 -281.477667) (xy 143.682107 -281.45966)
			(xy 143.73695 -281.44953) (xy 143.792684 -281.447493) (xy 143.848121 -281.453593) (xy 143.902078 -281.467699)
			(xy 143.953407 -281.489511) (xy 144.001013 -281.518565) (xy 144.043881 -281.55424) (xy 144.081098 -281.595777)
			(xy 144.111871 -281.64229) (xy 144.135543 -281.692787) (xy 144.151611 -281.746194) (xy 144.159731 -281.80137)
			(xy 144.16024 -281.829256) (xy 144.159731 -281.857142) (xy 144.151611 -281.912318) (xy 144.135543 -281.965725)
			(xy 144.111871 -282.016222) (xy 144.081098 -282.062735) (xy 144.043881 -282.104272) (xy 144.019079 -282.124912)
			(xy 152.169126 -282.124912) (xy 152.173086 -282.075858) (xy 152.184863 -282.028074) (xy 152.204154 -281.982798)
			(xy 152.230457 -281.941202) (xy 152.263092 -281.904365) (xy 152.301213 -281.87324) (xy 152.343834 -281.848633)
			(xy 152.38985 -281.831181) (xy 152.438069 -281.821337) (xy 152.487244 -281.819356) (xy 152.536099 -281.825288)
			(xy 152.58337 -281.83898) (xy 152.627832 -281.860078) (xy 152.668335 -281.888034) (xy 152.703828 -281.922126)
			(xy 152.733393 -281.96147) (xy 152.756264 -282.005047) (xy 152.771848 -282.051728) (xy 152.779743 -282.100305)
			(xy 152.780238 -282.124912) (xy 153.119086 -282.124912) (xy 153.123046 -282.075858) (xy 153.134823 -282.028074)
			(xy 153.154114 -281.982798) (xy 153.180417 -281.941202) (xy 153.213052 -281.904365) (xy 153.251173 -281.87324)
			(xy 153.293794 -281.848633) (xy 153.33981 -281.831181) (xy 153.388029 -281.821337) (xy 153.437204 -281.819356)
			(xy 153.486059 -281.825288) (xy 153.53333 -281.83898) (xy 153.577792 -281.860078) (xy 153.618295 -281.888034)
			(xy 153.653788 -281.922126) (xy 153.683353 -281.96147) (xy 153.706224 -282.005047) (xy 153.721808 -282.051728)
			(xy 153.729703 -282.100305) (xy 153.730198 -282.124912) (xy 154.0693 -282.124912) (xy 154.07326 -282.075858)
			(xy 154.085037 -282.028074) (xy 154.104328 -281.982798) (xy 154.130631 -281.941202) (xy 154.163266 -281.904365)
			(xy 154.201387 -281.87324) (xy 154.244008 -281.848633) (xy 154.290024 -281.831181) (xy 154.338243 -281.821337)
			(xy 154.387418 -281.819356) (xy 154.436273 -281.825288) (xy 154.483544 -281.83898) (xy 154.528006 -281.860078)
			(xy 154.568509 -281.888034) (xy 154.604002 -281.922126) (xy 154.633567 -281.96147) (xy 154.656438 -282.005047)
			(xy 154.672022 -282.051728) (xy 154.679917 -282.100305) (xy 154.680412 -282.124912) (xy 155.01926 -282.124912)
			(xy 155.02322 -282.075858) (xy 155.034997 -282.028074) (xy 155.054288 -281.982798) (xy 155.080591 -281.941202)
			(xy 155.113226 -281.904365) (xy 155.151347 -281.87324) (xy 155.193968 -281.848633) (xy 155.239984 -281.831181)
			(xy 155.288203 -281.821337) (xy 155.337378 -281.819356) (xy 155.386233 -281.825288) (xy 155.433504 -281.83898)
			(xy 155.477966 -281.860078) (xy 155.518469 -281.888034) (xy 155.553962 -281.922126) (xy 155.583527 -281.96147)
			(xy 155.606398 -282.005047) (xy 155.621982 -282.051728) (xy 155.629877 -282.100305) (xy 155.630372 -282.124912)
			(xy 155.96922 -282.124912) (xy 155.97318 -282.075858) (xy 155.984957 -282.028074) (xy 156.004248 -281.982798)
			(xy 156.030551 -281.941202) (xy 156.063186 -281.904365) (xy 156.101307 -281.87324) (xy 156.143928 -281.848633)
			(xy 156.189944 -281.831181) (xy 156.238163 -281.821337) (xy 156.287338 -281.819356) (xy 156.336193 -281.825288)
			(xy 156.383464 -281.83898) (xy 156.427926 -281.860078) (xy 156.468429 -281.888034) (xy 156.503922 -281.922126)
			(xy 156.533487 -281.96147) (xy 156.556358 -282.005047) (xy 156.571942 -282.051728) (xy 156.579837 -282.100305)
			(xy 156.580332 -282.124912) (xy 156.91918 -282.124912) (xy 156.92314 -282.075858) (xy 156.934917 -282.028074)
			(xy 156.954208 -281.982798) (xy 156.980511 -281.941202) (xy 157.013146 -281.904365) (xy 157.051267 -281.87324)
			(xy 157.093888 -281.848633) (xy 157.139904 -281.831181) (xy 157.188123 -281.821337) (xy 157.237298 -281.819356)
			(xy 157.286153 -281.825288) (xy 157.333424 -281.83898) (xy 157.377886 -281.860078) (xy 157.418389 -281.888034)
			(xy 157.453882 -281.922126) (xy 157.483447 -281.96147) (xy 157.506318 -282.005047) (xy 157.521902 -282.051728)
			(xy 157.529797 -282.100305) (xy 157.530292 -282.124912) (xy 157.86914 -282.124912) (xy 157.8731 -282.075858)
			(xy 157.884877 -282.028074) (xy 157.904168 -281.982798) (xy 157.930471 -281.941202) (xy 157.963106 -281.904365)
			(xy 158.001227 -281.87324) (xy 158.043848 -281.848633) (xy 158.089864 -281.831181) (xy 158.138083 -281.821337)
			(xy 158.187258 -281.819356) (xy 158.236113 -281.825288) (xy 158.283384 -281.83898) (xy 158.327846 -281.860078)
			(xy 158.368349 -281.888034) (xy 158.403842 -281.922126) (xy 158.433407 -281.96147) (xy 158.456278 -282.005047)
			(xy 158.471862 -282.051728) (xy 158.479757 -282.100305) (xy 158.480252 -282.124912) (xy 158.8191 -282.124912)
			(xy 158.82306 -282.075858) (xy 158.834837 -282.028074) (xy 158.854128 -281.982798) (xy 158.880431 -281.941202)
			(xy 158.913066 -281.904365) (xy 158.951187 -281.87324) (xy 158.993808 -281.848633) (xy 159.039824 -281.831181)
			(xy 159.088043 -281.821337) (xy 159.137218 -281.819356) (xy 159.186073 -281.825288) (xy 159.233344 -281.83898)
			(xy 159.277806 -281.860078) (xy 159.318309 -281.888034) (xy 159.353802 -281.922126) (xy 159.383367 -281.96147)
			(xy 159.406238 -282.005047) (xy 159.421822 -282.051728) (xy 159.429717 -282.100305) (xy 159.430046 -282.116639)
			(xy 159.769193 -282.116639) (xy 159.774556 -282.067291) (xy 159.787832 -282.019462) (xy 159.808671 -281.97441)
			(xy 159.836524 -281.933322) (xy 159.870657 -281.897282) (xy 159.91017 -281.867239) (xy 159.954024 -281.843983)
			(xy 160.001062 -281.828129) (xy 160.050045 -281.820093) (xy 160.074864 -281.819604) (xy 160.089047 -281.819785)
			(xy 160.117287 -281.822454) (xy 160.131252 -281.824938) (xy 160.143698 -281.827224) (xy 160.16732 -281.819858)
			(xy 160.24479 -281.742388) (xy 160.252156 -281.718766) (xy 160.24987 -281.70632) (xy 160.247386 -281.692355)
			(xy 160.244719 -281.664115) (xy 160.244536 -281.649932) (xy 160.245058 -281.624677) (xy 160.253371 -281.574855)
			(xy 160.269772 -281.527081) (xy 160.293813 -281.482658) (xy 160.324837 -281.442798) (xy 160.361999 -281.408588)
			(xy 160.404285 -281.380962) (xy 160.450541 -281.360672) (xy 160.499506 -281.348272) (xy 160.549844 -281.344101)
			(xy 160.600182 -281.348272) (xy 160.649147 -281.360672) (xy 160.695403 -281.380962) (xy 160.737689 -281.408588)
			(xy 160.774851 -281.442798) (xy 160.805875 -281.482658) (xy 160.829916 -281.527081) (xy 160.846317 -281.574855)
			(xy 160.85463 -281.624677) (xy 160.855152 -281.649932) (xy 160.854979 -281.664115) (xy 160.852304 -281.692355)
			(xy 160.849818 -281.70632) (xy 160.847532 -281.718766) (xy 160.854898 -281.742642) (xy 160.932114 -281.819858)
			(xy 160.956244 -281.827224) (xy 160.968436 -281.824938) (xy 160.982464 -281.82245) (xy 161.010832 -281.81978)
			(xy 161.025078 -281.819604) (xy 161.039261 -281.819784) (xy 161.067501 -281.822454) (xy 161.081466 -281.824938)
			(xy 161.093912 -281.827224) (xy 161.117534 -281.819858) (xy 161.195004 -281.742388) (xy 161.20237 -281.718766)
			(xy 161.200084 -281.70632) (xy 161.1976 -281.692355) (xy 161.194933 -281.664115) (xy 161.19475 -281.649932)
			(xy 161.195272 -281.624677) (xy 161.203585 -281.574855) (xy 161.219986 -281.527081) (xy 161.244027 -281.482658)
			(xy 161.275051 -281.442798) (xy 161.312213 -281.408588) (xy 161.354499 -281.380962) (xy 161.400755 -281.360672)
			(xy 161.44972 -281.348272) (xy 161.500058 -281.344101) (xy 161.550396 -281.348272) (xy 161.599361 -281.360672)
			(xy 161.645617 -281.380962) (xy 161.687903 -281.408588) (xy 161.725065 -281.442798) (xy 161.756089 -281.482658)
			(xy 161.78013 -281.527081) (xy 161.796531 -281.574855) (xy 161.804844 -281.624677) (xy 161.805366 -281.649932)
			(xy 161.805194 -281.664115) (xy 161.802519 -281.692355) (xy 161.800032 -281.70632) (xy 161.797746 -281.718766)
			(xy 161.805112 -281.742388) (xy 161.882582 -281.819858) (xy 161.906204 -281.827224) (xy 161.91865 -281.824938)
			(xy 161.932615 -281.822459) (xy 161.960855 -281.819789) (xy 161.975038 -281.819604) (xy 161.989221 -281.819775)
			(xy 162.017461 -281.822451) (xy 162.031426 -281.824938) (xy 162.043872 -281.827224) (xy 162.067494 -281.819858)
			(xy 162.144964 -281.742388) (xy 162.15233 -281.718766) (xy 162.150044 -281.70632) (xy 162.147561 -281.692355)
			(xy 162.144893 -281.664115) (xy 162.14471 -281.649932) (xy 162.145143 -281.625108) (xy 162.15317 -281.576114)
			(xy 162.169018 -281.529064) (xy 162.192269 -281.485198) (xy 162.22231 -281.445671) (xy 162.258351 -281.411525)
			(xy 162.299441 -281.383659) (xy 162.344498 -281.362809) (xy 162.392334 -281.349522) (xy 162.44169 -281.34415)
			(xy 162.491265 -281.346833) (xy 162.539752 -281.357502) (xy 162.585875 -281.375874) (xy 162.628418 -281.401467)
			(xy 162.66626 -281.433604) (xy 162.698404 -281.471441) (xy 162.724003 -281.51398) (xy 162.742383 -281.5601)
			(xy 162.75306 -281.608586) (xy 162.755304 -281.649932) (xy 163.094174 -281.649932) (xy 163.098134 -281.600878)
			(xy 163.109911 -281.553094) (xy 163.129202 -281.507818) (xy 163.155505 -281.466222) (xy 163.18814 -281.429385)
			(xy 163.226261 -281.39826) (xy 163.268882 -281.373653) (xy 163.314898 -281.356201) (xy 163.363117 -281.346357)
			(xy 163.412292 -281.344376) (xy 163.461147 -281.350308) (xy 163.508418 -281.364) (xy 163.55288 -281.385098)
			(xy 163.593383 -281.413054) (xy 163.628876 -281.447146) (xy 163.658441 -281.48649) (xy 163.681312 -281.530067)
			(xy 163.696896 -281.576748) (xy 163.704791 -281.625325) (xy 163.705286 -281.649932) (xy 164.044134 -281.649932)
			(xy 164.048094 -281.600878) (xy 164.059871 -281.553094) (xy 164.079162 -281.507818) (xy 164.105465 -281.466222)
			(xy 164.1381 -281.429385) (xy 164.176221 -281.39826) (xy 164.218842 -281.373653) (xy 164.264858 -281.356201)
			(xy 164.313077 -281.346357) (xy 164.362252 -281.344376) (xy 164.411107 -281.350308) (xy 164.458378 -281.364)
			(xy 164.50284 -281.385098) (xy 164.543343 -281.413054) (xy 164.578836 -281.447146) (xy 164.608401 -281.48649)
			(xy 164.631272 -281.530067) (xy 164.646856 -281.576748) (xy 164.654751 -281.625325) (xy 164.655246 -281.649932)
			(xy 164.994094 -281.649932) (xy 164.998054 -281.600878) (xy 165.009831 -281.553094) (xy 165.029122 -281.507818)
			(xy 165.055425 -281.466222) (xy 165.08806 -281.429385) (xy 165.126181 -281.39826) (xy 165.168802 -281.373653)
			(xy 165.214818 -281.356201) (xy 165.263037 -281.346357) (xy 165.312212 -281.344376) (xy 165.361067 -281.350308)
			(xy 165.408338 -281.364) (xy 165.4528 -281.385098) (xy 165.493303 -281.413054) (xy 165.528796 -281.447146)
			(xy 165.558361 -281.48649) (xy 165.581232 -281.530067) (xy 165.596816 -281.576748) (xy 165.604711 -281.625325)
			(xy 165.605206 -281.649932) (xy 165.944054 -281.649932) (xy 165.948014 -281.600878) (xy 165.959791 -281.553094)
			(xy 165.979082 -281.507818) (xy 166.005385 -281.466222) (xy 166.03802 -281.429385) (xy 166.076141 -281.39826)
			(xy 166.118762 -281.373653) (xy 166.164778 -281.356201) (xy 166.212997 -281.346357) (xy 166.262172 -281.344376)
			(xy 166.311027 -281.350308) (xy 166.358298 -281.364) (xy 166.40276 -281.385098) (xy 166.443263 -281.413054)
			(xy 166.478756 -281.447146) (xy 166.508321 -281.48649) (xy 166.531192 -281.530067) (xy 166.546776 -281.576748)
			(xy 166.554671 -281.625325) (xy 166.555166 -281.649932) (xy 166.894268 -281.649932) (xy 166.898228 -281.600878)
			(xy 166.910005 -281.553094) (xy 166.929296 -281.507818) (xy 166.955599 -281.466222) (xy 166.988234 -281.429385)
			(xy 167.026355 -281.39826) (xy 167.068976 -281.373653) (xy 167.114992 -281.356201) (xy 167.163211 -281.346357)
			(xy 167.212386 -281.344376) (xy 167.261241 -281.350308) (xy 167.308512 -281.364) (xy 167.352974 -281.385098)
			(xy 167.393477 -281.413054) (xy 167.42897 -281.447146) (xy 167.458535 -281.48649) (xy 167.481406 -281.530067)
			(xy 167.49699 -281.576748) (xy 167.504885 -281.625325) (xy 167.50538 -281.649932) (xy 167.844228 -281.649932)
			(xy 167.848188 -281.600878) (xy 167.859965 -281.553094) (xy 167.879256 -281.507818) (xy 167.905559 -281.466222)
			(xy 167.938194 -281.429385) (xy 167.976315 -281.39826) (xy 168.018936 -281.373653) (xy 168.064952 -281.356201)
			(xy 168.113171 -281.346357) (xy 168.162346 -281.344376) (xy 168.211201 -281.350308) (xy 168.258472 -281.364)
			(xy 168.302934 -281.385098) (xy 168.343437 -281.413054) (xy 168.37893 -281.447146) (xy 168.408495 -281.48649)
			(xy 168.431366 -281.530067) (xy 168.44695 -281.576748) (xy 168.454845 -281.625325) (xy 168.45534 -281.649932)
			(xy 168.794188 -281.649932) (xy 168.798148 -281.600878) (xy 168.809925 -281.553094) (xy 168.829216 -281.507818)
			(xy 168.855519 -281.466222) (xy 168.888154 -281.429385) (xy 168.926275 -281.39826) (xy 168.968896 -281.373653)
			(xy 169.014912 -281.356201) (xy 169.063131 -281.346357) (xy 169.112306 -281.344376) (xy 169.161161 -281.350308)
			(xy 169.208432 -281.364) (xy 169.252894 -281.385098) (xy 169.293397 -281.413054) (xy 169.32889 -281.447146)
			(xy 169.358455 -281.48649) (xy 169.381326 -281.530067) (xy 169.39691 -281.576748) (xy 169.404805 -281.625325)
			(xy 169.4053 -281.649932) (xy 169.744148 -281.649932) (xy 169.748108 -281.600878) (xy 169.759885 -281.553094)
			(xy 169.779176 -281.507818) (xy 169.805479 -281.466222) (xy 169.838114 -281.429385) (xy 169.876235 -281.39826)
			(xy 169.918856 -281.373653) (xy 169.964872 -281.356201) (xy 170.013091 -281.346357) (xy 170.062266 -281.344376)
			(xy 170.111121 -281.350308) (xy 170.158392 -281.364) (xy 170.202854 -281.385098) (xy 170.243357 -281.413054)
			(xy 170.27885 -281.447146) (xy 170.308415 -281.48649) (xy 170.331286 -281.530067) (xy 170.34687 -281.576748)
			(xy 170.354765 -281.625325) (xy 170.35526 -281.649932) (xy 170.694108 -281.649932) (xy 170.698068 -281.600878)
			(xy 170.709845 -281.553094) (xy 170.729136 -281.507818) (xy 170.755439 -281.466222) (xy 170.788074 -281.429385)
			(xy 170.826195 -281.39826) (xy 170.868816 -281.373653) (xy 170.914832 -281.356201) (xy 170.963051 -281.346357)
			(xy 171.012226 -281.344376) (xy 171.061081 -281.350308) (xy 171.108352 -281.364) (xy 171.152814 -281.385098)
			(xy 171.193317 -281.413054) (xy 171.22881 -281.447146) (xy 171.258375 -281.48649) (xy 171.281246 -281.530067)
			(xy 171.29683 -281.576748) (xy 171.304725 -281.625325) (xy 171.30522 -281.649932) (xy 171.644068 -281.649932)
			(xy 171.648028 -281.600878) (xy 171.659805 -281.553094) (xy 171.679096 -281.507818) (xy 171.705399 -281.466222)
			(xy 171.738034 -281.429385) (xy 171.776155 -281.39826) (xy 171.818776 -281.373653) (xy 171.864792 -281.356201)
			(xy 171.913011 -281.346357) (xy 171.962186 -281.344376) (xy 172.011041 -281.350308) (xy 172.058312 -281.364)
			(xy 172.102774 -281.385098) (xy 172.143277 -281.413054) (xy 172.17877 -281.447146) (xy 172.208335 -281.48649)
			(xy 172.231206 -281.530067) (xy 172.24679 -281.576748) (xy 172.254685 -281.625325) (xy 172.25518 -281.649932)
			(xy 172.594282 -281.649932) (xy 172.598242 -281.600878) (xy 172.610019 -281.553094) (xy 172.62931 -281.507818)
			(xy 172.655613 -281.466222) (xy 172.688248 -281.429385) (xy 172.726369 -281.39826) (xy 172.76899 -281.373653)
			(xy 172.815006 -281.356201) (xy 172.863225 -281.346357) (xy 172.9124 -281.344376) (xy 172.961255 -281.350308)
			(xy 173.008526 -281.364) (xy 173.052988 -281.385098) (xy 173.093491 -281.413054) (xy 173.128984 -281.447146)
			(xy 173.158549 -281.48649) (xy 173.18142 -281.530067) (xy 173.197004 -281.576748) (xy 173.204899 -281.625325)
			(xy 173.205394 -281.649932) (xy 173.544242 -281.649932) (xy 173.548202 -281.600878) (xy 173.559979 -281.553094)
			(xy 173.57927 -281.507818) (xy 173.605573 -281.466222) (xy 173.638208 -281.429385) (xy 173.676329 -281.39826)
			(xy 173.71895 -281.373653) (xy 173.764966 -281.356201) (xy 173.813185 -281.346357) (xy 173.86236 -281.344376)
			(xy 173.911215 -281.350308) (xy 173.958486 -281.364) (xy 174.002948 -281.385098) (xy 174.043451 -281.413054)
			(xy 174.078944 -281.447146) (xy 174.108509 -281.48649) (xy 174.13138 -281.530067) (xy 174.146964 -281.576748)
			(xy 174.154859 -281.625325) (xy 174.155354 -281.649932) (xy 174.494202 -281.649932) (xy 174.498162 -281.600878)
			(xy 174.509939 -281.553094) (xy 174.52923 -281.507818) (xy 174.555533 -281.466222) (xy 174.588168 -281.429385)
			(xy 174.626289 -281.39826) (xy 174.66891 -281.373653) (xy 174.714926 -281.356201) (xy 174.763145 -281.346357)
			(xy 174.81232 -281.344376) (xy 174.861175 -281.350308) (xy 174.908446 -281.364) (xy 174.952908 -281.385098)
			(xy 174.993411 -281.413054) (xy 175.028904 -281.447146) (xy 175.058469 -281.48649) (xy 175.08134 -281.530067)
			(xy 175.096924 -281.576748) (xy 175.104819 -281.625325) (xy 175.105314 -281.649932) (xy 175.444162 -281.649932)
			(xy 175.448122 -281.600878) (xy 175.459899 -281.553094) (xy 175.47919 -281.507818) (xy 175.505493 -281.466222)
			(xy 175.538128 -281.429385) (xy 175.576249 -281.39826) (xy 175.61887 -281.373653) (xy 175.664886 -281.356201)
			(xy 175.713105 -281.346357) (xy 175.76228 -281.344376) (xy 175.811135 -281.350308) (xy 175.858406 -281.364)
			(xy 175.902868 -281.385098) (xy 175.943371 -281.413054) (xy 175.978864 -281.447146) (xy 176.008429 -281.48649)
			(xy 176.0313 -281.530067) (xy 176.046884 -281.576748) (xy 176.054779 -281.625325) (xy 176.055274 -281.649932)
			(xy 176.394122 -281.649932) (xy 176.398082 -281.600878) (xy 176.409859 -281.553094) (xy 176.42915 -281.507818)
			(xy 176.455453 -281.466222) (xy 176.488088 -281.429385) (xy 176.526209 -281.39826) (xy 176.56883 -281.373653)
			(xy 176.614846 -281.356201) (xy 176.663065 -281.346357) (xy 176.71224 -281.344376) (xy 176.761095 -281.350308)
			(xy 176.808366 -281.364) (xy 176.852828 -281.385098) (xy 176.893331 -281.413054) (xy 176.928824 -281.447146)
			(xy 176.958389 -281.48649) (xy 176.98126 -281.530067) (xy 176.996844 -281.576748) (xy 177.004739 -281.625325)
			(xy 177.005234 -281.649932) (xy 177.344082 -281.649932) (xy 177.348042 -281.600878) (xy 177.359819 -281.553094)
			(xy 177.37911 -281.507818) (xy 177.405413 -281.466222) (xy 177.438048 -281.429385) (xy 177.476169 -281.39826)
			(xy 177.51879 -281.373653) (xy 177.564806 -281.356201) (xy 177.613025 -281.346357) (xy 177.6622 -281.344376)
			(xy 177.711055 -281.350308) (xy 177.758326 -281.364) (xy 177.802788 -281.385098) (xy 177.843291 -281.413054)
			(xy 177.878784 -281.447146) (xy 177.908349 -281.48649) (xy 177.93122 -281.530067) (xy 177.946804 -281.576748)
			(xy 177.954699 -281.625325) (xy 177.955194 -281.649932) (xy 178.294042 -281.649932) (xy 178.298002 -281.600878)
			(xy 178.309779 -281.553094) (xy 178.32907 -281.507818) (xy 178.355373 -281.466222) (xy 178.388008 -281.429385)
			(xy 178.426129 -281.39826) (xy 178.46875 -281.373653) (xy 178.514766 -281.356201) (xy 178.562985 -281.346357)
			(xy 178.61216 -281.344376) (xy 178.661015 -281.350308) (xy 178.708286 -281.364) (xy 178.752748 -281.385098)
			(xy 178.793251 -281.413054) (xy 178.828744 -281.447146) (xy 178.858309 -281.48649) (xy 178.88118 -281.530067)
			(xy 178.896764 -281.576748) (xy 178.904659 -281.625325) (xy 178.905154 -281.649932) (xy 179.244256 -281.649932)
			(xy 179.248216 -281.600878) (xy 179.259993 -281.553094) (xy 179.279284 -281.507818) (xy 179.305587 -281.466222)
			(xy 179.338222 -281.429385) (xy 179.376343 -281.39826) (xy 179.418964 -281.373653) (xy 179.46498 -281.356201)
			(xy 179.513199 -281.346357) (xy 179.562374 -281.344376) (xy 179.611229 -281.350308) (xy 179.6585 -281.364)
			(xy 179.702962 -281.385098) (xy 179.743465 -281.413054) (xy 179.778958 -281.447146) (xy 179.808523 -281.48649)
			(xy 179.831394 -281.530067) (xy 179.846978 -281.576748) (xy 179.854873 -281.625325) (xy 179.855368 -281.649932)
			(xy 180.194216 -281.649932) (xy 180.198176 -281.600878) (xy 180.209953 -281.553094) (xy 180.229244 -281.507818)
			(xy 180.255547 -281.466222) (xy 180.288182 -281.429385) (xy 180.326303 -281.39826) (xy 180.368924 -281.373653)
			(xy 180.41494 -281.356201) (xy 180.463159 -281.346357) (xy 180.512334 -281.344376) (xy 180.561189 -281.350308)
			(xy 180.60846 -281.364) (xy 180.652922 -281.385098) (xy 180.693425 -281.413054) (xy 180.728918 -281.447146)
			(xy 180.758483 -281.48649) (xy 180.781354 -281.530067) (xy 180.796938 -281.576748) (xy 180.804833 -281.625325)
			(xy 180.805328 -281.649932) (xy 181.144176 -281.649932) (xy 181.148136 -281.600878) (xy 181.159913 -281.553094)
			(xy 181.179204 -281.507818) (xy 181.205507 -281.466222) (xy 181.238142 -281.429385) (xy 181.276263 -281.39826)
			(xy 181.318884 -281.373653) (xy 181.3649 -281.356201) (xy 181.413119 -281.346357) (xy 181.462294 -281.344376)
			(xy 181.511149 -281.350308) (xy 181.55842 -281.364) (xy 181.602882 -281.385098) (xy 181.643385 -281.413054)
			(xy 181.678878 -281.447146) (xy 181.708443 -281.48649) (xy 181.731314 -281.530067) (xy 181.746898 -281.576748)
			(xy 181.754793 -281.625325) (xy 181.755288 -281.649932) (xy 182.094136 -281.649932) (xy 182.098096 -281.600878)
			(xy 182.109873 -281.553094) (xy 182.129164 -281.507818) (xy 182.155467 -281.466222) (xy 182.188102 -281.429385)
			(xy 182.226223 -281.39826) (xy 182.268844 -281.373653) (xy 182.31486 -281.356201) (xy 182.363079 -281.346357)
			(xy 182.412254 -281.344376) (xy 182.461109 -281.350308) (xy 182.50838 -281.364) (xy 182.552842 -281.385098)
			(xy 182.593345 -281.413054) (xy 182.628838 -281.447146) (xy 182.658403 -281.48649) (xy 182.681274 -281.530067)
			(xy 182.696858 -281.576748) (xy 182.704753 -281.625325) (xy 182.705248 -281.649932) (xy 183.044096 -281.649932)
			(xy 183.048056 -281.600878) (xy 183.059833 -281.553094) (xy 183.079124 -281.507818) (xy 183.105427 -281.466222)
			(xy 183.138062 -281.429385) (xy 183.176183 -281.39826) (xy 183.218804 -281.373653) (xy 183.26482 -281.356201)
			(xy 183.313039 -281.346357) (xy 183.362214 -281.344376) (xy 183.411069 -281.350308) (xy 183.45834 -281.364)
			(xy 183.502802 -281.385098) (xy 183.543305 -281.413054) (xy 183.578798 -281.447146) (xy 183.608363 -281.48649)
			(xy 183.631234 -281.530067) (xy 183.646818 -281.576748) (xy 183.654713 -281.625325) (xy 183.655208 -281.649932)
			(xy 183.994056 -281.649932) (xy 183.998016 -281.600878) (xy 184.009793 -281.553094) (xy 184.029084 -281.507818)
			(xy 184.055387 -281.466222) (xy 184.088022 -281.429385) (xy 184.126143 -281.39826) (xy 184.168764 -281.373653)
			(xy 184.21478 -281.356201) (xy 184.262999 -281.346357) (xy 184.312174 -281.344376) (xy 184.361029 -281.350308)
			(xy 184.4083 -281.364) (xy 184.452762 -281.385098) (xy 184.493265 -281.413054) (xy 184.528758 -281.447146)
			(xy 184.558323 -281.48649) (xy 184.581194 -281.530067) (xy 184.596778 -281.576748) (xy 184.604673 -281.625325)
			(xy 184.605168 -281.649932) (xy 184.94427 -281.649932) (xy 184.94823 -281.600878) (xy 184.960007 -281.553094)
			(xy 184.979298 -281.507818) (xy 185.005601 -281.466222) (xy 185.038236 -281.429385) (xy 185.076357 -281.39826)
			(xy 185.118978 -281.373653) (xy 185.164994 -281.356201) (xy 185.213213 -281.346357) (xy 185.262388 -281.344376)
			(xy 185.311243 -281.350308) (xy 185.358514 -281.364) (xy 185.402976 -281.385098) (xy 185.443479 -281.413054)
			(xy 185.478972 -281.447146) (xy 185.508537 -281.48649) (xy 185.531408 -281.530067) (xy 185.546992 -281.576748)
			(xy 185.554887 -281.625325) (xy 185.555382 -281.649932) (xy 185.89423 -281.649932) (xy 185.89819 -281.600878)
			(xy 185.909967 -281.553094) (xy 185.929258 -281.507818) (xy 185.955561 -281.466222) (xy 185.988196 -281.429385)
			(xy 186.026317 -281.39826) (xy 186.068938 -281.373653) (xy 186.114954 -281.356201) (xy 186.163173 -281.346357)
			(xy 186.212348 -281.344376) (xy 186.261203 -281.350308) (xy 186.308474 -281.364) (xy 186.352936 -281.385098)
			(xy 186.393439 -281.413054) (xy 186.428932 -281.447146) (xy 186.458497 -281.48649) (xy 186.481368 -281.530067)
			(xy 186.496952 -281.576748) (xy 186.504847 -281.625325) (xy 186.505342 -281.649932) (xy 186.84419 -281.649932)
			(xy 186.84815 -281.600878) (xy 186.859927 -281.553094) (xy 186.879218 -281.507818) (xy 186.905521 -281.466222)
			(xy 186.938156 -281.429385) (xy 186.976277 -281.39826) (xy 187.018898 -281.373653) (xy 187.064914 -281.356201)
			(xy 187.113133 -281.346357) (xy 187.162308 -281.344376) (xy 187.211163 -281.350308) (xy 187.258434 -281.364)
			(xy 187.302896 -281.385098) (xy 187.343399 -281.413054) (xy 187.378892 -281.447146) (xy 187.408457 -281.48649)
			(xy 187.431328 -281.530067) (xy 187.446912 -281.576748) (xy 187.454807 -281.625325) (xy 187.455302 -281.649932)
			(xy 187.79415 -281.649932) (xy 187.79811 -281.600878) (xy 187.809887 -281.553094) (xy 187.829178 -281.507818)
			(xy 187.855481 -281.466222) (xy 187.888116 -281.429385) (xy 187.926237 -281.39826) (xy 187.968858 -281.373653)
			(xy 188.014874 -281.356201) (xy 188.063093 -281.346357) (xy 188.112268 -281.344376) (xy 188.161123 -281.350308)
			(xy 188.208394 -281.364) (xy 188.252856 -281.385098) (xy 188.293359 -281.413054) (xy 188.328852 -281.447146)
			(xy 188.358417 -281.48649) (xy 188.381288 -281.530067) (xy 188.396872 -281.576748) (xy 188.404767 -281.625325)
			(xy 188.405262 -281.649932) (xy 188.74411 -281.649932) (xy 188.74807 -281.600878) (xy 188.759847 -281.553094)
			(xy 188.779138 -281.507818) (xy 188.805441 -281.466222) (xy 188.838076 -281.429385) (xy 188.876197 -281.39826)
			(xy 188.918818 -281.373653) (xy 188.964834 -281.356201) (xy 189.013053 -281.346357) (xy 189.062228 -281.344376)
			(xy 189.111083 -281.350308) (xy 189.158354 -281.364) (xy 189.202816 -281.385098) (xy 189.243319 -281.413054)
			(xy 189.278812 -281.447146) (xy 189.308377 -281.48649) (xy 189.331248 -281.530067) (xy 189.346832 -281.576748)
			(xy 189.354727 -281.625325) (xy 189.355222 -281.649932) (xy 189.69407 -281.649932) (xy 189.69803 -281.600878)
			(xy 189.709807 -281.553094) (xy 189.729098 -281.507818) (xy 189.755401 -281.466222) (xy 189.788036 -281.429385)
			(xy 189.826157 -281.39826) (xy 189.868778 -281.373653) (xy 189.914794 -281.356201) (xy 189.963013 -281.346357)
			(xy 190.012188 -281.344376) (xy 190.061043 -281.350308) (xy 190.108314 -281.364) (xy 190.152776 -281.385098)
			(xy 190.193279 -281.413054) (xy 190.228772 -281.447146) (xy 190.258337 -281.48649) (xy 190.281208 -281.530067)
			(xy 190.296792 -281.576748) (xy 190.304687 -281.625325) (xy 190.305182 -281.649932) (xy 190.644284 -281.649932)
			(xy 190.648244 -281.600878) (xy 190.660021 -281.553094) (xy 190.679312 -281.507818) (xy 190.705615 -281.466222)
			(xy 190.73825 -281.429385) (xy 190.776371 -281.39826) (xy 190.818992 -281.373653) (xy 190.865008 -281.356201)
			(xy 190.913227 -281.346357) (xy 190.962402 -281.344376) (xy 191.011257 -281.350308) (xy 191.058528 -281.364)
			(xy 191.10299 -281.385098) (xy 191.143493 -281.413054) (xy 191.178986 -281.447146) (xy 191.208551 -281.48649)
			(xy 191.231422 -281.530067) (xy 191.247006 -281.576748) (xy 191.254901 -281.625325) (xy 191.255396 -281.649932)
			(xy 191.594244 -281.649932) (xy 191.598204 -281.600878) (xy 191.609981 -281.553094) (xy 191.629272 -281.507818)
			(xy 191.655575 -281.466222) (xy 191.68821 -281.429385) (xy 191.726331 -281.39826) (xy 191.768952 -281.373653)
			(xy 191.814968 -281.356201) (xy 191.863187 -281.346357) (xy 191.912362 -281.344376) (xy 191.961217 -281.350308)
			(xy 192.008488 -281.364) (xy 192.05295 -281.385098) (xy 192.093453 -281.413054) (xy 192.128946 -281.447146)
			(xy 192.158511 -281.48649) (xy 192.181382 -281.530067) (xy 192.196966 -281.576748) (xy 192.204861 -281.625325)
			(xy 192.205356 -281.649932) (xy 192.544204 -281.649932) (xy 192.548164 -281.600878) (xy 192.559941 -281.553094)
			(xy 192.579232 -281.507818) (xy 192.605535 -281.466222) (xy 192.63817 -281.429385) (xy 192.676291 -281.39826)
			(xy 192.718912 -281.373653) (xy 192.764928 -281.356201) (xy 192.813147 -281.346357) (xy 192.862322 -281.344376)
			(xy 192.911177 -281.350308) (xy 192.958448 -281.364) (xy 193.00291 -281.385098) (xy 193.043413 -281.413054)
			(xy 193.078906 -281.447146) (xy 193.108471 -281.48649) (xy 193.131342 -281.530067) (xy 193.146926 -281.576748)
			(xy 193.154821 -281.625325) (xy 193.155311 -281.649678) (xy 193.49391 -281.649678) (xy 193.49787 -281.600624)
			(xy 193.509647 -281.55284) (xy 193.528938 -281.507564) (xy 193.555241 -281.465968) (xy 193.587876 -281.429131)
			(xy 193.625997 -281.398006) (xy 193.668618 -281.373399) (xy 193.714634 -281.355947) (xy 193.762853 -281.346103)
			(xy 193.812028 -281.344122) (xy 193.860883 -281.350054) (xy 193.908154 -281.363746) (xy 193.952616 -281.384844)
			(xy 193.993119 -281.4128) (xy 194.028612 -281.446892) (xy 194.058177 -281.486236) (xy 194.081048 -281.529813)
			(xy 194.096632 -281.576494) (xy 194.104527 -281.625071) (xy 194.105022 -281.649678) (xy 194.105017 -281.649932)
			(xy 194.44387 -281.649932) (xy 194.44783 -281.600878) (xy 194.459607 -281.553094) (xy 194.478898 -281.507818)
			(xy 194.505201 -281.466222) (xy 194.537836 -281.429385) (xy 194.575957 -281.39826) (xy 194.618578 -281.373653)
			(xy 194.664594 -281.356201) (xy 194.712813 -281.346357) (xy 194.761988 -281.344376) (xy 194.810843 -281.350308)
			(xy 194.858114 -281.364) (xy 194.902576 -281.385098) (xy 194.943079 -281.413054) (xy 194.978572 -281.447146)
			(xy 195.008137 -281.48649) (xy 195.031008 -281.530067) (xy 195.046592 -281.576748) (xy 195.054487 -281.625325)
			(xy 195.054982 -281.649932) (xy 195.394084 -281.649932) (xy 195.398044 -281.600878) (xy 195.409821 -281.553094)
			(xy 195.429112 -281.507818) (xy 195.455415 -281.466222) (xy 195.48805 -281.429385) (xy 195.526171 -281.39826)
			(xy 195.568792 -281.373653) (xy 195.614808 -281.356201) (xy 195.663027 -281.346357) (xy 195.712202 -281.344376)
			(xy 195.761057 -281.350308) (xy 195.808328 -281.364) (xy 195.85279 -281.385098) (xy 195.893293 -281.413054)
			(xy 195.928786 -281.447146) (xy 195.958351 -281.48649) (xy 195.981222 -281.530067) (xy 195.996806 -281.576748)
			(xy 196.004701 -281.625325) (xy 196.005196 -281.649932) (xy 196.344044 -281.649932) (xy 196.348004 -281.600878)
			(xy 196.359781 -281.553094) (xy 196.379072 -281.507818) (xy 196.405375 -281.466222) (xy 196.43801 -281.429385)
			(xy 196.476131 -281.39826) (xy 196.518752 -281.373653) (xy 196.564768 -281.356201) (xy 196.612987 -281.346357)
			(xy 196.662162 -281.344376) (xy 196.711017 -281.350308) (xy 196.758288 -281.364) (xy 196.80275 -281.385098)
			(xy 196.843253 -281.413054) (xy 196.878746 -281.447146) (xy 196.908311 -281.48649) (xy 196.931182 -281.530067)
			(xy 196.946766 -281.576748) (xy 196.954661 -281.625325) (xy 196.955156 -281.649932) (xy 196.954661 -281.674539)
			(xy 196.954482 -281.67564) (xy 197.273414 -281.67564) (xy 197.273414 -281.624224) (xy 197.281457 -281.573442)
			(xy 197.297345 -281.524543) (xy 197.320688 -281.478731) (xy 197.350909 -281.437135) (xy 197.387265 -281.400779)
			(xy 197.428861 -281.370558) (xy 197.474673 -281.347215) (xy 197.523572 -281.331327) (xy 197.574354 -281.323284)
			(xy 197.62577 -281.323284) (xy 197.676552 -281.331327) (xy 197.725451 -281.347215) (xy 197.771263 -281.370558)
			(xy 197.812859 -281.400779) (xy 197.849215 -281.437135) (xy 197.879436 -281.478731) (xy 197.902779 -281.524543)
			(xy 197.918667 -281.573442) (xy 197.92671 -281.624224) (xy 197.927214 -281.649932) (xy 197.92671 -281.67564)
			(xy 198.223374 -281.67564) (xy 198.223374 -281.624224) (xy 198.231417 -281.573442) (xy 198.247305 -281.524543)
			(xy 198.270648 -281.478731) (xy 198.300869 -281.437135) (xy 198.337225 -281.400779) (xy 198.378821 -281.370558)
			(xy 198.424633 -281.347215) (xy 198.473532 -281.331327) (xy 198.524314 -281.323284) (xy 198.57573 -281.323284)
			(xy 198.626512 -281.331327) (xy 198.660401 -281.342338) (xy 219.957142 -281.342338) (xy 219.957591 -281.315084)
			(xy 219.965344 -281.26113) (xy 219.980698 -281.208829) (xy 220.003339 -281.159245) (xy 220.032808 -281.11339)
			(xy 220.068504 -281.072195) (xy 220.109699 -281.036501) (xy 220.155556 -281.007034) (xy 220.20514 -280.984393)
			(xy 220.257441 -280.969041) (xy 220.311396 -280.96129) (xy 220.33865 -280.96083) (xy 220.367389 -280.961342)
			(xy 220.424216 -280.96997) (xy 220.479106 -280.987024) (xy 220.530818 -281.012118) (xy 220.578181 -281.044683)
			(xy 220.599508 -281.063954) (xy 220.60662 -281.070558) (xy 220.624146 -281.07767) (xy 220.713554 -281.07767)
			(xy 220.73108 -281.070558) (xy 220.738192 -281.063954) (xy 220.759519 -281.044684) (xy 220.806882 -281.012119)
			(xy 220.858593 -280.987028) (xy 220.913484 -280.969978) (xy 220.970311 -280.961356) (xy 221.027789 -280.961356)
			(xy 221.084616 -280.969978) (xy 221.139507 -280.987028) (xy 221.191218 -281.012119) (xy 221.238581 -281.044684)
			(xy 221.259908 -281.063954) (xy 221.26702 -281.070558) (xy 221.284546 -281.07767) (xy 221.373954 -281.07767)
			(xy 221.39148 -281.070558) (xy 221.398592 -281.063954) (xy 221.419901 -281.044662) (xy 221.467268 -281.012098)
			(xy 221.518984 -280.987009) (xy 221.573879 -280.969964) (xy 221.63071 -280.961347) (xy 221.65945 -280.96083)
			(xy 221.689572 -280.961438) (xy 221.749066 -280.970911) (xy 221.806334 -280.989613) (xy 221.859951 -281.017081)
			(xy 221.908588 -281.052631) (xy 221.930214 -281.073606) (xy 221.937326 -281.080972) (xy 221.956122 -281.088592)
			(xy 222.048578 -281.088592) (xy 222.067374 -281.080972) (xy 222.074486 -281.073606) (xy 222.096095 -281.052608)
			(xy 222.144728 -281.017042) (xy 222.198348 -280.989565) (xy 222.255622 -280.970861) (xy 222.315125 -280.961395)
			(xy 222.34525 -280.96083) (xy 222.372503 -280.961302) (xy 222.426456 -280.969053) (xy 222.478756 -280.984405)
			(xy 222.528338 -281.007044) (xy 222.574194 -281.03651) (xy 222.615388 -281.072204) (xy 222.651082 -281.113397)
			(xy 222.68055 -281.159251) (xy 222.703191 -281.208833) (xy 222.718544 -281.261132) (xy 222.726297 -281.315085)
			(xy 222.726758 -281.342338) (xy 222.726303 -281.370075) (xy 222.718308 -281.42497) (xy 222.702434 -281.478124)
			(xy 222.679017 -281.528413) (xy 222.648552 -281.574772) (xy 222.630492 -281.59583) (xy 222.624142 -281.602688)
			(xy 222.617538 -281.620214) (xy 222.617538 -281.706574) (xy 222.624142 -281.723846) (xy 222.630492 -281.730704)
			(xy 222.648552 -281.751802) (xy 222.679062 -281.798204) (xy 222.702529 -281.848536) (xy 222.718457 -281.901736)
			(xy 222.726509 -281.956683) (xy 222.727012 -281.98445) (xy 222.726498 -282.011701) (xy 222.718748 -282.06565)
			(xy 222.703399 -282.117947) (xy 222.680762 -282.167527) (xy 222.6513 -282.21338) (xy 222.615611 -282.254573)
			(xy 222.574423 -282.290267) (xy 222.528574 -282.319736) (xy 222.478998 -282.34238) (xy 222.426703 -282.357737)
			(xy 222.372755 -282.365494) (xy 222.345504 -282.365958) (xy 222.315381 -282.365383) (xy 222.255885 -282.355902)
			(xy 222.198617 -282.337192) (xy 222.145 -282.309718) (xy 222.096365 -282.27416) (xy 222.07474 -282.253182)
			(xy 222.067628 -282.245816) (xy 222.048832 -282.238196) (xy 221.956376 -282.238196) (xy 221.93758 -282.245816)
			(xy 221.930468 -282.253182) (xy 221.908833 -282.274152) (xy 221.860207 -282.309722) (xy 221.806594 -282.337204)
			(xy 221.749325 -282.355915) (xy 221.689828 -282.365389) (xy 221.659704 -282.365958) (xy 221.630966 -282.365416)
			(xy 221.57414 -282.356796) (xy 221.51925 -282.339749) (xy 221.467538 -282.314662) (xy 221.420174 -282.282102)
			(xy 221.398846 -282.262834) (xy 221.391734 -282.25623) (xy 221.374208 -282.249118) (xy 221.2848 -282.249118)
			(xy 221.267274 -282.25623) (xy 221.260162 -282.262834) (xy 221.238835 -282.282104) (xy 221.191472 -282.314669)
			(xy 221.139761 -282.33976) (xy 221.08487 -282.35681) (xy 221.028043 -282.365432) (xy 220.970565 -282.365432)
			(xy 220.913738 -282.35681) (xy 220.858847 -282.33976) (xy 220.807136 -282.314669) (xy 220.759773 -282.282104)
			(xy 220.738446 -282.262834) (xy 220.731334 -282.25623) (xy 220.713808 -282.249118) (xy 220.6244 -282.249118)
			(xy 220.606874 -282.25623) (xy 220.599762 -282.262834) (xy 220.578429 -282.282098) (xy 220.531069 -282.314666)
			(xy 220.479359 -282.339761) (xy 220.424469 -282.356813) (xy 220.367643 -282.365437) (xy 220.338904 -282.365958)
			(xy 220.311649 -282.365541) (xy 220.257694 -282.357783) (xy 220.205392 -282.342425) (xy 220.155809 -282.319779)
			(xy 220.109953 -282.290307) (xy 220.068759 -282.254608) (xy 220.033065 -282.21341) (xy 220.003599 -282.167551)
			(xy 219.980959 -282.117965) (xy 219.965607 -282.065661) (xy 219.957856 -282.011705) (xy 219.957396 -281.98445)
			(xy 219.957855 -281.956713) (xy 219.965851 -281.901819) (xy 219.981725 -281.848666) (xy 220.005141 -281.798377)
			(xy 220.035603 -281.752016) (xy 220.053662 -281.730958) (xy 220.060012 -281.7241) (xy 220.066616 -281.706574)
			(xy 220.066616 -281.620214) (xy 220.060012 -281.602942) (xy 220.053662 -281.596084) (xy 220.035589 -281.574997)
			(xy 220.005082 -281.528592) (xy 219.981619 -281.478257) (xy 219.965694 -281.425054) (xy 219.957644 -281.370105)
			(xy 219.957142 -281.342338) (xy 198.660401 -281.342338) (xy 198.675411 -281.347215) (xy 198.721223 -281.370558)
			(xy 198.762819 -281.400779) (xy 198.799175 -281.437135) (xy 198.829396 -281.478731) (xy 198.852739 -281.524543)
			(xy 198.868627 -281.573442) (xy 198.87667 -281.624224) (xy 198.877174 -281.649932) (xy 198.877169 -281.650186)
			(xy 199.194432 -281.650186) (xy 199.198392 -281.601132) (xy 199.210169 -281.553348) (xy 199.22946 -281.508072)
			(xy 199.255763 -281.466476) (xy 199.288398 -281.429639) (xy 199.326519 -281.398514) (xy 199.36914 -281.373907)
			(xy 199.415156 -281.356455) (xy 199.463375 -281.346611) (xy 199.51255 -281.34463) (xy 199.561405 -281.350562)
			(xy 199.608676 -281.364254) (xy 199.653138 -281.385352) (xy 199.693641 -281.413308) (xy 199.729134 -281.4474)
			(xy 199.758699 -281.486744) (xy 199.78157 -281.530321) (xy 199.797154 -281.577002) (xy 199.805049 -281.625579)
			(xy 199.805544 -281.650186) (xy 199.805049 -281.674793) (xy 199.797154 -281.72337) (xy 199.78157 -281.770051)
			(xy 199.758699 -281.813628) (xy 199.729134 -281.852972) (xy 199.693641 -281.887064) (xy 199.653138 -281.91502)
			(xy 199.608676 -281.936118) (xy 199.561405 -281.94981) (xy 199.51255 -281.955742) (xy 199.463375 -281.953761)
			(xy 199.415156 -281.943917) (xy 199.36914 -281.926465) (xy 199.326519 -281.901858) (xy 199.288398 -281.870733)
			(xy 199.255763 -281.833896) (xy 199.22946 -281.7923) (xy 199.210169 -281.747024) (xy 199.198392 -281.69924)
			(xy 199.194432 -281.650186) (xy 198.877169 -281.650186) (xy 198.87667 -281.67564) (xy 198.868627 -281.726422)
			(xy 198.852739 -281.775321) (xy 198.829396 -281.821133) (xy 198.799175 -281.862729) (xy 198.762819 -281.899085)
			(xy 198.721223 -281.929306) (xy 198.675411 -281.952649) (xy 198.626512 -281.968537) (xy 198.57573 -281.97658)
			(xy 198.524314 -281.97658) (xy 198.473532 -281.968537) (xy 198.424633 -281.952649) (xy 198.378821 -281.929306)
			(xy 198.337225 -281.899085) (xy 198.300869 -281.862729) (xy 198.270648 -281.821133) (xy 198.247305 -281.775321)
			(xy 198.231417 -281.726422) (xy 198.223374 -281.67564) (xy 197.92671 -281.67564) (xy 197.918667 -281.726422)
			(xy 197.902779 -281.775321) (xy 197.879436 -281.821133) (xy 197.849215 -281.862729) (xy 197.812859 -281.899085)
			(xy 197.771263 -281.929306) (xy 197.725451 -281.952649) (xy 197.676552 -281.968537) (xy 197.62577 -281.97658)
			(xy 197.574354 -281.97658) (xy 197.523572 -281.968537) (xy 197.474673 -281.952649) (xy 197.428861 -281.929306)
			(xy 197.387265 -281.899085) (xy 197.350909 -281.862729) (xy 197.320688 -281.821133) (xy 197.297345 -281.775321)
			(xy 197.281457 -281.726422) (xy 197.273414 -281.67564) (xy 196.954482 -281.67564) (xy 196.946766 -281.723116)
			(xy 196.931182 -281.769797) (xy 196.908311 -281.813374) (xy 196.878746 -281.852718) (xy 196.843253 -281.88681)
			(xy 196.80275 -281.914766) (xy 196.758288 -281.935864) (xy 196.711017 -281.949556) (xy 196.662162 -281.955488)
			(xy 196.612987 -281.953507) (xy 196.564768 -281.943663) (xy 196.518752 -281.926211) (xy 196.476131 -281.901604)
			(xy 196.43801 -281.870479) (xy 196.405375 -281.833642) (xy 196.379072 -281.792046) (xy 196.359781 -281.74677)
			(xy 196.348004 -281.698986) (xy 196.344044 -281.649932) (xy 196.005196 -281.649932) (xy 196.004701 -281.674539)
			(xy 195.996806 -281.723116) (xy 195.981222 -281.769797) (xy 195.958351 -281.813374) (xy 195.928786 -281.852718)
			(xy 195.893293 -281.88681) (xy 195.85279 -281.914766) (xy 195.808328 -281.935864) (xy 195.761057 -281.949556)
			(xy 195.712202 -281.955488) (xy 195.663027 -281.953507) (xy 195.614808 -281.943663) (xy 195.568792 -281.926211)
			(xy 195.526171 -281.901604) (xy 195.48805 -281.870479) (xy 195.455415 -281.833642) (xy 195.429112 -281.792046)
			(xy 195.409821 -281.74677) (xy 195.398044 -281.698986) (xy 195.394084 -281.649932) (xy 195.054982 -281.649932)
			(xy 195.054487 -281.674539) (xy 195.046592 -281.723116) (xy 195.031008 -281.769797) (xy 195.008137 -281.813374)
			(xy 194.978572 -281.852718) (xy 194.943079 -281.88681) (xy 194.902576 -281.914766) (xy 194.858114 -281.935864)
			(xy 194.810843 -281.949556) (xy 194.761988 -281.955488) (xy 194.712813 -281.953507) (xy 194.664594 -281.943663)
			(xy 194.618578 -281.926211) (xy 194.575957 -281.901604) (xy 194.537836 -281.870479) (xy 194.505201 -281.833642)
			(xy 194.478898 -281.792046) (xy 194.459607 -281.74677) (xy 194.44783 -281.698986) (xy 194.44387 -281.649932)
			(xy 194.105017 -281.649932) (xy 194.104527 -281.674285) (xy 194.096632 -281.722862) (xy 194.081048 -281.769543)
			(xy 194.058177 -281.81312) (xy 194.028612 -281.852464) (xy 193.993119 -281.886556) (xy 193.952616 -281.914512)
			(xy 193.908154 -281.93561) (xy 193.860883 -281.949302) (xy 193.812028 -281.955234) (xy 193.762853 -281.953253)
			(xy 193.714634 -281.943409) (xy 193.668618 -281.925957) (xy 193.625997 -281.90135) (xy 193.587876 -281.870225)
			(xy 193.555241 -281.833388) (xy 193.528938 -281.791792) (xy 193.509647 -281.746516) (xy 193.49787 -281.698732)
			(xy 193.49391 -281.649678) (xy 193.155311 -281.649678) (xy 193.155316 -281.649932) (xy 193.154821 -281.674539)
			(xy 193.146926 -281.723116) (xy 193.131342 -281.769797) (xy 193.108471 -281.813374) (xy 193.078906 -281.852718)
			(xy 193.043413 -281.88681) (xy 193.00291 -281.914766) (xy 192.958448 -281.935864) (xy 192.911177 -281.949556)
			(xy 192.862322 -281.955488) (xy 192.813147 -281.953507) (xy 192.764928 -281.943663) (xy 192.718912 -281.926211)
			(xy 192.676291 -281.901604) (xy 192.63817 -281.870479) (xy 192.605535 -281.833642) (xy 192.579232 -281.792046)
			(xy 192.559941 -281.74677) (xy 192.548164 -281.698986) (xy 192.544204 -281.649932) (xy 192.205356 -281.649932)
			(xy 192.204861 -281.674539) (xy 192.196966 -281.723116) (xy 192.181382 -281.769797) (xy 192.158511 -281.813374)
			(xy 192.128946 -281.852718) (xy 192.093453 -281.88681) (xy 192.05295 -281.914766) (xy 192.008488 -281.935864)
			(xy 191.961217 -281.949556) (xy 191.912362 -281.955488) (xy 191.863187 -281.953507) (xy 191.814968 -281.943663)
			(xy 191.768952 -281.926211) (xy 191.726331 -281.901604) (xy 191.68821 -281.870479) (xy 191.655575 -281.833642)
			(xy 191.629272 -281.792046) (xy 191.609981 -281.74677) (xy 191.598204 -281.698986) (xy 191.594244 -281.649932)
			(xy 191.255396 -281.649932) (xy 191.254901 -281.674539) (xy 191.247006 -281.723116) (xy 191.231422 -281.769797)
			(xy 191.208551 -281.813374) (xy 191.178986 -281.852718) (xy 191.143493 -281.88681) (xy 191.10299 -281.914766)
			(xy 191.058528 -281.935864) (xy 191.011257 -281.949556) (xy 190.962402 -281.955488) (xy 190.913227 -281.953507)
			(xy 190.865008 -281.943663) (xy 190.818992 -281.926211) (xy 190.776371 -281.901604) (xy 190.73825 -281.870479)
			(xy 190.705615 -281.833642) (xy 190.679312 -281.792046) (xy 190.660021 -281.74677) (xy 190.648244 -281.698986)
			(xy 190.644284 -281.649932) (xy 190.305182 -281.649932) (xy 190.304687 -281.674539) (xy 190.296792 -281.723116)
			(xy 190.281208 -281.769797) (xy 190.258337 -281.813374) (xy 190.228772 -281.852718) (xy 190.193279 -281.88681)
			(xy 190.152776 -281.914766) (xy 190.108314 -281.935864) (xy 190.061043 -281.949556) (xy 190.012188 -281.955488)
			(xy 189.963013 -281.953507) (xy 189.914794 -281.943663) (xy 189.868778 -281.926211) (xy 189.826157 -281.901604)
			(xy 189.788036 -281.870479) (xy 189.755401 -281.833642) (xy 189.729098 -281.792046) (xy 189.709807 -281.74677)
			(xy 189.69803 -281.698986) (xy 189.69407 -281.649932) (xy 189.355222 -281.649932) (xy 189.354727 -281.674539)
			(xy 189.346832 -281.723116) (xy 189.331248 -281.769797) (xy 189.308377 -281.813374) (xy 189.278812 -281.852718)
			(xy 189.243319 -281.88681) (xy 189.202816 -281.914766) (xy 189.158354 -281.935864) (xy 189.111083 -281.949556)
			(xy 189.062228 -281.955488) (xy 189.013053 -281.953507) (xy 188.964834 -281.943663) (xy 188.918818 -281.926211)
			(xy 188.876197 -281.901604) (xy 188.838076 -281.870479) (xy 188.805441 -281.833642) (xy 188.779138 -281.792046)
			(xy 188.759847 -281.74677) (xy 188.74807 -281.698986) (xy 188.74411 -281.649932) (xy 188.405262 -281.649932)
			(xy 188.404767 -281.674539) (xy 188.396872 -281.723116) (xy 188.381288 -281.769797) (xy 188.358417 -281.813374)
			(xy 188.328852 -281.852718) (xy 188.293359 -281.88681) (xy 188.252856 -281.914766) (xy 188.208394 -281.935864)
			(xy 188.161123 -281.949556) (xy 188.112268 -281.955488) (xy 188.063093 -281.953507) (xy 188.014874 -281.943663)
			(xy 187.968858 -281.926211) (xy 187.926237 -281.901604) (xy 187.888116 -281.870479) (xy 187.855481 -281.833642)
			(xy 187.829178 -281.792046) (xy 187.809887 -281.74677) (xy 187.79811 -281.698986) (xy 187.79415 -281.649932)
			(xy 187.455302 -281.649932) (xy 187.454807 -281.674539) (xy 187.446912 -281.723116) (xy 187.431328 -281.769797)
			(xy 187.408457 -281.813374) (xy 187.378892 -281.852718) (xy 187.343399 -281.88681) (xy 187.302896 -281.914766)
			(xy 187.258434 -281.935864) (xy 187.211163 -281.949556) (xy 187.162308 -281.955488) (xy 187.113133 -281.953507)
			(xy 187.064914 -281.943663) (xy 187.018898 -281.926211) (xy 186.976277 -281.901604) (xy 186.938156 -281.870479)
			(xy 186.905521 -281.833642) (xy 186.879218 -281.792046) (xy 186.859927 -281.74677) (xy 186.84815 -281.698986)
			(xy 186.84419 -281.649932) (xy 186.505342 -281.649932) (xy 186.504847 -281.674539) (xy 186.496952 -281.723116)
			(xy 186.481368 -281.769797) (xy 186.458497 -281.813374) (xy 186.428932 -281.852718) (xy 186.393439 -281.88681)
			(xy 186.352936 -281.914766) (xy 186.308474 -281.935864) (xy 186.261203 -281.949556) (xy 186.212348 -281.955488)
			(xy 186.163173 -281.953507) (xy 186.114954 -281.943663) (xy 186.068938 -281.926211) (xy 186.026317 -281.901604)
			(xy 185.988196 -281.870479) (xy 185.955561 -281.833642) (xy 185.929258 -281.792046) (xy 185.909967 -281.74677)
			(xy 185.89819 -281.698986) (xy 185.89423 -281.649932) (xy 185.555382 -281.649932) (xy 185.554887 -281.674539)
			(xy 185.546992 -281.723116) (xy 185.531408 -281.769797) (xy 185.508537 -281.813374) (xy 185.478972 -281.852718)
			(xy 185.443479 -281.88681) (xy 185.402976 -281.914766) (xy 185.358514 -281.935864) (xy 185.311243 -281.949556)
			(xy 185.262388 -281.955488) (xy 185.213213 -281.953507) (xy 185.164994 -281.943663) (xy 185.118978 -281.926211)
			(xy 185.076357 -281.901604) (xy 185.038236 -281.870479) (xy 185.005601 -281.833642) (xy 184.979298 -281.792046)
			(xy 184.960007 -281.74677) (xy 184.94823 -281.698986) (xy 184.94427 -281.649932) (xy 184.605168 -281.649932)
			(xy 184.604673 -281.674539) (xy 184.596778 -281.723116) (xy 184.581194 -281.769797) (xy 184.558323 -281.813374)
			(xy 184.528758 -281.852718) (xy 184.493265 -281.88681) (xy 184.452762 -281.914766) (xy 184.4083 -281.935864)
			(xy 184.361029 -281.949556) (xy 184.312174 -281.955488) (xy 184.262999 -281.953507) (xy 184.21478 -281.943663)
			(xy 184.168764 -281.926211) (xy 184.126143 -281.901604) (xy 184.088022 -281.870479) (xy 184.055387 -281.833642)
			(xy 184.029084 -281.792046) (xy 184.009793 -281.74677) (xy 183.998016 -281.698986) (xy 183.994056 -281.649932)
			(xy 183.655208 -281.649932) (xy 183.654713 -281.674539) (xy 183.646818 -281.723116) (xy 183.631234 -281.769797)
			(xy 183.608363 -281.813374) (xy 183.578798 -281.852718) (xy 183.543305 -281.88681) (xy 183.502802 -281.914766)
			(xy 183.45834 -281.935864) (xy 183.411069 -281.949556) (xy 183.362214 -281.955488) (xy 183.313039 -281.953507)
			(xy 183.26482 -281.943663) (xy 183.218804 -281.926211) (xy 183.176183 -281.901604) (xy 183.138062 -281.870479)
			(xy 183.105427 -281.833642) (xy 183.079124 -281.792046) (xy 183.059833 -281.74677) (xy 183.048056 -281.698986)
			(xy 183.044096 -281.649932) (xy 182.705248 -281.649932) (xy 182.704753 -281.674539) (xy 182.696858 -281.723116)
			(xy 182.681274 -281.769797) (xy 182.658403 -281.813374) (xy 182.628838 -281.852718) (xy 182.593345 -281.88681)
			(xy 182.552842 -281.914766) (xy 182.50838 -281.935864) (xy 182.461109 -281.949556) (xy 182.412254 -281.955488)
			(xy 182.363079 -281.953507) (xy 182.31486 -281.943663) (xy 182.268844 -281.926211) (xy 182.226223 -281.901604)
			(xy 182.188102 -281.870479) (xy 182.155467 -281.833642) (xy 182.129164 -281.792046) (xy 182.109873 -281.74677)
			(xy 182.098096 -281.698986) (xy 182.094136 -281.649932) (xy 181.755288 -281.649932) (xy 181.754793 -281.674539)
			(xy 181.746898 -281.723116) (xy 181.731314 -281.769797) (xy 181.708443 -281.813374) (xy 181.678878 -281.852718)
			(xy 181.643385 -281.88681) (xy 181.602882 -281.914766) (xy 181.55842 -281.935864) (xy 181.511149 -281.949556)
			(xy 181.462294 -281.955488) (xy 181.413119 -281.953507) (xy 181.3649 -281.943663) (xy 181.318884 -281.926211)
			(xy 181.276263 -281.901604) (xy 181.238142 -281.870479) (xy 181.205507 -281.833642) (xy 181.179204 -281.792046)
			(xy 181.159913 -281.74677) (xy 181.148136 -281.698986) (xy 181.144176 -281.649932) (xy 180.805328 -281.649932)
			(xy 180.804833 -281.674539) (xy 180.796938 -281.723116) (xy 180.781354 -281.769797) (xy 180.758483 -281.813374)
			(xy 180.728918 -281.852718) (xy 180.693425 -281.88681) (xy 180.652922 -281.914766) (xy 180.60846 -281.935864)
			(xy 180.561189 -281.949556) (xy 180.512334 -281.955488) (xy 180.463159 -281.953507) (xy 180.41494 -281.943663)
			(xy 180.368924 -281.926211) (xy 180.326303 -281.901604) (xy 180.288182 -281.870479) (xy 180.255547 -281.833642)
			(xy 180.229244 -281.792046) (xy 180.209953 -281.74677) (xy 180.198176 -281.698986) (xy 180.194216 -281.649932)
			(xy 179.855368 -281.649932) (xy 179.854873 -281.674539) (xy 179.846978 -281.723116) (xy 179.831394 -281.769797)
			(xy 179.808523 -281.813374) (xy 179.778958 -281.852718) (xy 179.743465 -281.88681) (xy 179.702962 -281.914766)
			(xy 179.6585 -281.935864) (xy 179.611229 -281.949556) (xy 179.562374 -281.955488) (xy 179.513199 -281.953507)
			(xy 179.46498 -281.943663) (xy 179.418964 -281.926211) (xy 179.376343 -281.901604) (xy 179.338222 -281.870479)
			(xy 179.305587 -281.833642) (xy 179.279284 -281.792046) (xy 179.259993 -281.74677) (xy 179.248216 -281.698986)
			(xy 179.244256 -281.649932) (xy 178.905154 -281.649932) (xy 178.904659 -281.674539) (xy 178.896764 -281.723116)
			(xy 178.88118 -281.769797) (xy 178.858309 -281.813374) (xy 178.828744 -281.852718) (xy 178.793251 -281.88681)
			(xy 178.752748 -281.914766) (xy 178.708286 -281.935864) (xy 178.661015 -281.949556) (xy 178.61216 -281.955488)
			(xy 178.562985 -281.953507) (xy 178.514766 -281.943663) (xy 178.46875 -281.926211) (xy 178.426129 -281.901604)
			(xy 178.388008 -281.870479) (xy 178.355373 -281.833642) (xy 178.32907 -281.792046) (xy 178.309779 -281.74677)
			(xy 178.298002 -281.698986) (xy 178.294042 -281.649932) (xy 177.955194 -281.649932) (xy 177.954699 -281.674539)
			(xy 177.946804 -281.723116) (xy 177.93122 -281.769797) (xy 177.908349 -281.813374) (xy 177.878784 -281.852718)
			(xy 177.843291 -281.88681) (xy 177.802788 -281.914766) (xy 177.758326 -281.935864) (xy 177.711055 -281.949556)
			(xy 177.6622 -281.955488) (xy 177.613025 -281.953507) (xy 177.564806 -281.943663) (xy 177.51879 -281.926211)
			(xy 177.476169 -281.901604) (xy 177.438048 -281.870479) (xy 177.405413 -281.833642) (xy 177.37911 -281.792046)
			(xy 177.359819 -281.74677) (xy 177.348042 -281.698986) (xy 177.344082 -281.649932) (xy 177.005234 -281.649932)
			(xy 177.004739 -281.674539) (xy 176.996844 -281.723116) (xy 176.98126 -281.769797) (xy 176.958389 -281.813374)
			(xy 176.928824 -281.852718) (xy 176.893331 -281.88681) (xy 176.852828 -281.914766) (xy 176.808366 -281.935864)
			(xy 176.761095 -281.949556) (xy 176.71224 -281.955488) (xy 176.663065 -281.953507) (xy 176.614846 -281.943663)
			(xy 176.56883 -281.926211) (xy 176.526209 -281.901604) (xy 176.488088 -281.870479) (xy 176.455453 -281.833642)
			(xy 176.42915 -281.792046) (xy 176.409859 -281.74677) (xy 176.398082 -281.698986) (xy 176.394122 -281.649932)
			(xy 176.055274 -281.649932) (xy 176.054779 -281.674539) (xy 176.046884 -281.723116) (xy 176.0313 -281.769797)
			(xy 176.008429 -281.813374) (xy 175.978864 -281.852718) (xy 175.943371 -281.88681) (xy 175.902868 -281.914766)
			(xy 175.858406 -281.935864) (xy 175.811135 -281.949556) (xy 175.76228 -281.955488) (xy 175.713105 -281.953507)
			(xy 175.664886 -281.943663) (xy 175.61887 -281.926211) (xy 175.576249 -281.901604) (xy 175.538128 -281.870479)
			(xy 175.505493 -281.833642) (xy 175.47919 -281.792046) (xy 175.459899 -281.74677) (xy 175.448122 -281.698986)
			(xy 175.444162 -281.649932) (xy 175.105314 -281.649932) (xy 175.104819 -281.674539) (xy 175.096924 -281.723116)
			(xy 175.08134 -281.769797) (xy 175.058469 -281.813374) (xy 175.028904 -281.852718) (xy 174.993411 -281.88681)
			(xy 174.952908 -281.914766) (xy 174.908446 -281.935864) (xy 174.861175 -281.949556) (xy 174.81232 -281.955488)
			(xy 174.763145 -281.953507) (xy 174.714926 -281.943663) (xy 174.66891 -281.926211) (xy 174.626289 -281.901604)
			(xy 174.588168 -281.870479) (xy 174.555533 -281.833642) (xy 174.52923 -281.792046) (xy 174.509939 -281.74677)
			(xy 174.498162 -281.698986) (xy 174.494202 -281.649932) (xy 174.155354 -281.649932) (xy 174.154859 -281.674539)
			(xy 174.146964 -281.723116) (xy 174.13138 -281.769797) (xy 174.108509 -281.813374) (xy 174.078944 -281.852718)
			(xy 174.043451 -281.88681) (xy 174.002948 -281.914766) (xy 173.958486 -281.935864) (xy 173.911215 -281.949556)
			(xy 173.86236 -281.955488) (xy 173.813185 -281.953507) (xy 173.764966 -281.943663) (xy 173.71895 -281.926211)
			(xy 173.676329 -281.901604) (xy 173.638208 -281.870479) (xy 173.605573 -281.833642) (xy 173.57927 -281.792046)
			(xy 173.559979 -281.74677) (xy 173.548202 -281.698986) (xy 173.544242 -281.649932) (xy 173.205394 -281.649932)
			(xy 173.204899 -281.674539) (xy 173.197004 -281.723116) (xy 173.18142 -281.769797) (xy 173.158549 -281.813374)
			(xy 173.128984 -281.852718) (xy 173.093491 -281.88681) (xy 173.052988 -281.914766) (xy 173.008526 -281.935864)
			(xy 172.961255 -281.949556) (xy 172.9124 -281.955488) (xy 172.863225 -281.953507) (xy 172.815006 -281.943663)
			(xy 172.76899 -281.926211) (xy 172.726369 -281.901604) (xy 172.688248 -281.870479) (xy 172.655613 -281.833642)
			(xy 172.62931 -281.792046) (xy 172.610019 -281.74677) (xy 172.598242 -281.698986) (xy 172.594282 -281.649932)
			(xy 172.25518 -281.649932) (xy 172.254685 -281.674539) (xy 172.24679 -281.723116) (xy 172.231206 -281.769797)
			(xy 172.208335 -281.813374) (xy 172.17877 -281.852718) (xy 172.143277 -281.88681) (xy 172.102774 -281.914766)
			(xy 172.058312 -281.935864) (xy 172.011041 -281.949556) (xy 171.962186 -281.955488) (xy 171.913011 -281.953507)
			(xy 171.864792 -281.943663) (xy 171.818776 -281.926211) (xy 171.776155 -281.901604) (xy 171.738034 -281.870479)
			(xy 171.705399 -281.833642) (xy 171.679096 -281.792046) (xy 171.659805 -281.74677) (xy 171.648028 -281.698986)
			(xy 171.644068 -281.649932) (xy 171.30522 -281.649932) (xy 171.304725 -281.674539) (xy 171.29683 -281.723116)
			(xy 171.281246 -281.769797) (xy 171.258375 -281.813374) (xy 171.22881 -281.852718) (xy 171.193317 -281.88681)
			(xy 171.152814 -281.914766) (xy 171.108352 -281.935864) (xy 171.061081 -281.949556) (xy 171.012226 -281.955488)
			(xy 170.963051 -281.953507) (xy 170.914832 -281.943663) (xy 170.868816 -281.926211) (xy 170.826195 -281.901604)
			(xy 170.788074 -281.870479) (xy 170.755439 -281.833642) (xy 170.729136 -281.792046) (xy 170.709845 -281.74677)
			(xy 170.698068 -281.698986) (xy 170.694108 -281.649932) (xy 170.35526 -281.649932) (xy 170.354765 -281.674539)
			(xy 170.34687 -281.723116) (xy 170.331286 -281.769797) (xy 170.308415 -281.813374) (xy 170.27885 -281.852718)
			(xy 170.243357 -281.88681) (xy 170.202854 -281.914766) (xy 170.158392 -281.935864) (xy 170.111121 -281.949556)
			(xy 170.062266 -281.955488) (xy 170.013091 -281.953507) (xy 169.964872 -281.943663) (xy 169.918856 -281.926211)
			(xy 169.876235 -281.901604) (xy 169.838114 -281.870479) (xy 169.805479 -281.833642) (xy 169.779176 -281.792046)
			(xy 169.759885 -281.74677) (xy 169.748108 -281.698986) (xy 169.744148 -281.649932) (xy 169.4053 -281.649932)
			(xy 169.404805 -281.674539) (xy 169.39691 -281.723116) (xy 169.381326 -281.769797) (xy 169.358455 -281.813374)
			(xy 169.32889 -281.852718) (xy 169.293397 -281.88681) (xy 169.252894 -281.914766) (xy 169.208432 -281.935864)
			(xy 169.161161 -281.949556) (xy 169.112306 -281.955488) (xy 169.063131 -281.953507) (xy 169.014912 -281.943663)
			(xy 168.968896 -281.926211) (xy 168.926275 -281.901604) (xy 168.888154 -281.870479) (xy 168.855519 -281.833642)
			(xy 168.829216 -281.792046) (xy 168.809925 -281.74677) (xy 168.798148 -281.698986) (xy 168.794188 -281.649932)
			(xy 168.45534 -281.649932) (xy 168.454845 -281.674539) (xy 168.44695 -281.723116) (xy 168.431366 -281.769797)
			(xy 168.408495 -281.813374) (xy 168.37893 -281.852718) (xy 168.343437 -281.88681) (xy 168.302934 -281.914766)
			(xy 168.258472 -281.935864) (xy 168.211201 -281.949556) (xy 168.162346 -281.955488) (xy 168.113171 -281.953507)
			(xy 168.064952 -281.943663) (xy 168.018936 -281.926211) (xy 167.976315 -281.901604) (xy 167.938194 -281.870479)
			(xy 167.905559 -281.833642) (xy 167.879256 -281.792046) (xy 167.859965 -281.74677) (xy 167.848188 -281.698986)
			(xy 167.844228 -281.649932) (xy 167.50538 -281.649932) (xy 167.504885 -281.674539) (xy 167.49699 -281.723116)
			(xy 167.481406 -281.769797) (xy 167.458535 -281.813374) (xy 167.42897 -281.852718) (xy 167.393477 -281.88681)
			(xy 167.352974 -281.914766) (xy 167.308512 -281.935864) (xy 167.261241 -281.949556) (xy 167.212386 -281.955488)
			(xy 167.163211 -281.953507) (xy 167.114992 -281.943663) (xy 167.068976 -281.926211) (xy 167.026355 -281.901604)
			(xy 166.988234 -281.870479) (xy 166.955599 -281.833642) (xy 166.929296 -281.792046) (xy 166.910005 -281.74677)
			(xy 166.898228 -281.698986) (xy 166.894268 -281.649932) (xy 166.555166 -281.649932) (xy 166.554671 -281.674539)
			(xy 166.546776 -281.723116) (xy 166.531192 -281.769797) (xy 166.508321 -281.813374) (xy 166.478756 -281.852718)
			(xy 166.443263 -281.88681) (xy 166.40276 -281.914766) (xy 166.358298 -281.935864) (xy 166.311027 -281.949556)
			(xy 166.262172 -281.955488) (xy 166.212997 -281.953507) (xy 166.164778 -281.943663) (xy 166.118762 -281.926211)
			(xy 166.076141 -281.901604) (xy 166.03802 -281.870479) (xy 166.005385 -281.833642) (xy 165.979082 -281.792046)
			(xy 165.959791 -281.74677) (xy 165.948014 -281.698986) (xy 165.944054 -281.649932) (xy 165.605206 -281.649932)
			(xy 165.604711 -281.674539) (xy 165.596816 -281.723116) (xy 165.581232 -281.769797) (xy 165.558361 -281.813374)
			(xy 165.528796 -281.852718) (xy 165.493303 -281.88681) (xy 165.4528 -281.914766) (xy 165.408338 -281.935864)
			(xy 165.361067 -281.949556) (xy 165.312212 -281.955488) (xy 165.263037 -281.953507) (xy 165.214818 -281.943663)
			(xy 165.168802 -281.926211) (xy 165.126181 -281.901604) (xy 165.08806 -281.870479) (xy 165.055425 -281.833642)
			(xy 165.029122 -281.792046) (xy 165.009831 -281.74677) (xy 164.998054 -281.698986) (xy 164.994094 -281.649932)
			(xy 164.655246 -281.649932) (xy 164.654751 -281.674539) (xy 164.646856 -281.723116) (xy 164.631272 -281.769797)
			(xy 164.608401 -281.813374) (xy 164.578836 -281.852718) (xy 164.543343 -281.88681) (xy 164.50284 -281.914766)
			(xy 164.458378 -281.935864) (xy 164.411107 -281.949556) (xy 164.362252 -281.955488) (xy 164.313077 -281.953507)
			(xy 164.264858 -281.943663) (xy 164.218842 -281.926211) (xy 164.176221 -281.901604) (xy 164.1381 -281.870479)
			(xy 164.105465 -281.833642) (xy 164.079162 -281.792046) (xy 164.059871 -281.74677) (xy 164.048094 -281.698986)
			(xy 164.044134 -281.649932) (xy 163.705286 -281.649932) (xy 163.704791 -281.674539) (xy 163.696896 -281.723116)
			(xy 163.681312 -281.769797) (xy 163.658441 -281.813374) (xy 163.628876 -281.852718) (xy 163.593383 -281.88681)
			(xy 163.55288 -281.914766) (xy 163.508418 -281.935864) (xy 163.461147 -281.949556) (xy 163.412292 -281.955488)
			(xy 163.363117 -281.953507) (xy 163.314898 -281.943663) (xy 163.268882 -281.926211) (xy 163.226261 -281.901604)
			(xy 163.18814 -281.870479) (xy 163.155505 -281.833642) (xy 163.129202 -281.792046) (xy 163.109911 -281.74677)
			(xy 163.098134 -281.698986) (xy 163.094174 -281.649932) (xy 162.755304 -281.649932) (xy 162.755751 -281.65816)
			(xy 162.750387 -281.707517) (xy 162.737109 -281.755355) (xy 162.716265 -281.800416) (xy 162.688407 -281.84151)
			(xy 162.654267 -281.877556) (xy 162.614745 -281.907604) (xy 162.570882 -281.930862) (xy 162.523835 -281.946718)
			(xy 162.474842 -281.954753) (xy 162.450018 -281.95524) (xy 162.435835 -281.95506) (xy 162.407595 -281.95239)
			(xy 162.39363 -281.949906) (xy 162.381184 -281.94762) (xy 162.357562 -281.954986) (xy 162.280092 -282.032456)
			(xy 162.272726 -282.056078) (xy 162.275012 -282.068524) (xy 162.277488 -282.08249) (xy 162.28016 -282.110729)
			(xy 162.280346 -282.124912) (xy 162.279824 -282.150167) (xy 162.271511 -282.199989) (xy 162.25511 -282.247763)
			(xy 162.231069 -282.292186) (xy 162.200045 -282.332046) (xy 162.162883 -282.366256) (xy 162.120597 -282.393882)
			(xy 162.074341 -282.414172) (xy 162.025376 -282.426572) (xy 161.975038 -282.430743) (xy 161.9247 -282.426572)
			(xy 161.875735 -282.414172) (xy 161.829479 -282.393882) (xy 161.787193 -282.366256) (xy 161.750031 -282.332046)
			(xy 161.719007 -282.292186) (xy 161.694966 -282.247763) (xy 161.678565 -282.199989) (xy 161.670252 -282.150167)
			(xy 161.66973 -282.124912) (xy 161.669908 -282.110729) (xy 161.672579 -282.082489) (xy 161.675064 -282.068524)
			(xy 161.67735 -282.056078) (xy 161.669984 -282.032456) (xy 161.592514 -281.954986) (xy 161.568892 -281.94762)
			(xy 161.556446 -281.949906) (xy 161.542481 -281.952386) (xy 161.514241 -281.955055) (xy 161.500058 -281.95524)
			(xy 161.485875 -281.955069) (xy 161.457635 -281.952393) (xy 161.44367 -281.949906) (xy 161.431224 -281.94762)
			(xy 161.407602 -281.954986) (xy 161.330132 -282.032456) (xy 161.322766 -282.056078) (xy 161.325052 -282.068524)
			(xy 161.327527 -282.08249) (xy 161.3302 -282.11073) (xy 161.330386 -282.124912) (xy 161.329864 -282.150167)
			(xy 161.321551 -282.199989) (xy 161.30515 -282.247763) (xy 161.281109 -282.292186) (xy 161.250085 -282.332046)
			(xy 161.212923 -282.366256) (xy 161.170637 -282.393882) (xy 161.124381 -282.414172) (xy 161.075416 -282.426572)
			(xy 161.025078 -282.430743) (xy 160.97474 -282.426572) (xy 160.925775 -282.414172) (xy 160.879519 -282.393882)
			(xy 160.837233 -282.366256) (xy 160.800071 -282.332046) (xy 160.769047 -282.292186) (xy 160.745006 -282.247763)
			(xy 160.728605 -282.199989) (xy 160.720292 -282.150167) (xy 160.71977 -282.124912) (xy 160.719949 -282.110729)
			(xy 160.722619 -282.082489) (xy 160.725104 -282.068524) (xy 160.72739 -282.056078) (xy 160.720024 -282.032202)
			(xy 160.642808 -281.954986) (xy 160.618678 -281.94762) (xy 160.606486 -281.949906) (xy 160.592457 -281.95239)
			(xy 160.56409 -281.955062) (xy 160.549844 -281.95524) (xy 160.535661 -281.955057) (xy 160.507421 -281.952389)
			(xy 160.493456 -281.949906) (xy 160.48101 -281.94762) (xy 160.457388 -281.954986) (xy 160.379918 -282.032456)
			(xy 160.372552 -282.056078) (xy 160.374838 -282.068524) (xy 160.377313 -282.08249) (xy 160.379986 -282.11073)
			(xy 160.380172 -282.124912) (xy 160.379709 -282.149731) (xy 160.371677 -282.198715) (xy 160.355826 -282.245754)
			(xy 160.332574 -282.28961) (xy 160.302534 -282.329126) (xy 160.266496 -282.363261) (xy 160.225411 -282.391117)
			(xy 160.180361 -282.41196) (xy 160.132532 -282.425239) (xy 160.083185 -282.430607) (xy 160.03362 -282.42792)
			(xy 159.985142 -282.41725) (xy 159.939029 -282.398879) (xy 159.896495 -282.373289) (xy 159.858662 -282.341155)
			(xy 159.826525 -282.303324) (xy 159.800932 -282.260793) (xy 159.782557 -282.214681) (xy 159.771883 -282.166204)
			(xy 159.769193 -282.116639) (xy 159.430046 -282.116639) (xy 159.430212 -282.124912) (xy 159.429717 -282.149519)
			(xy 159.421822 -282.198096) (xy 159.406238 -282.244777) (xy 159.383367 -282.288354) (xy 159.353802 -282.327698)
			(xy 159.318309 -282.36179) (xy 159.277806 -282.389746) (xy 159.233344 -282.410844) (xy 159.186073 -282.424536)
			(xy 159.137218 -282.430468) (xy 159.088043 -282.428487) (xy 159.039824 -282.418643) (xy 158.993808 -282.401191)
			(xy 158.951187 -282.376584) (xy 158.913066 -282.345459) (xy 158.880431 -282.308622) (xy 158.854128 -282.267026)
			(xy 158.834837 -282.22175) (xy 158.82306 -282.173966) (xy 158.8191 -282.124912) (xy 158.480252 -282.124912)
			(xy 158.479757 -282.149519) (xy 158.471862 -282.198096) (xy 158.456278 -282.244777) (xy 158.433407 -282.288354)
			(xy 158.403842 -282.327698) (xy 158.368349 -282.36179) (xy 158.327846 -282.389746) (xy 158.283384 -282.410844)
			(xy 158.236113 -282.424536) (xy 158.187258 -282.430468) (xy 158.138083 -282.428487) (xy 158.089864 -282.418643)
			(xy 158.043848 -282.401191) (xy 158.001227 -282.376584) (xy 157.963106 -282.345459) (xy 157.930471 -282.308622)
			(xy 157.904168 -282.267026) (xy 157.884877 -282.22175) (xy 157.8731 -282.173966) (xy 157.86914 -282.124912)
			(xy 157.530292 -282.124912) (xy 157.529797 -282.149519) (xy 157.521902 -282.198096) (xy 157.506318 -282.244777)
			(xy 157.483447 -282.288354) (xy 157.453882 -282.327698) (xy 157.418389 -282.36179) (xy 157.377886 -282.389746)
			(xy 157.333424 -282.410844) (xy 157.286153 -282.424536) (xy 157.237298 -282.430468) (xy 157.188123 -282.428487)
			(xy 157.139904 -282.418643) (xy 157.093888 -282.401191) (xy 157.051267 -282.376584) (xy 157.013146 -282.345459)
			(xy 156.980511 -282.308622) (xy 156.954208 -282.267026) (xy 156.934917 -282.22175) (xy 156.92314 -282.173966)
			(xy 156.91918 -282.124912) (xy 156.580332 -282.124912) (xy 156.579837 -282.149519) (xy 156.571942 -282.198096)
			(xy 156.556358 -282.244777) (xy 156.533487 -282.288354) (xy 156.503922 -282.327698) (xy 156.468429 -282.36179)
			(xy 156.427926 -282.389746) (xy 156.383464 -282.410844) (xy 156.336193 -282.424536) (xy 156.287338 -282.430468)
			(xy 156.238163 -282.428487) (xy 156.189944 -282.418643) (xy 156.143928 -282.401191) (xy 156.101307 -282.376584)
			(xy 156.063186 -282.345459) (xy 156.030551 -282.308622) (xy 156.004248 -282.267026) (xy 155.984957 -282.22175)
			(xy 155.97318 -282.173966) (xy 155.96922 -282.124912) (xy 155.630372 -282.124912) (xy 155.629877 -282.149519)
			(xy 155.621982 -282.198096) (xy 155.606398 -282.244777) (xy 155.583527 -282.288354) (xy 155.553962 -282.327698)
			(xy 155.518469 -282.36179) (xy 155.477966 -282.389746) (xy 155.433504 -282.410844) (xy 155.386233 -282.424536)
			(xy 155.337378 -282.430468) (xy 155.288203 -282.428487) (xy 155.239984 -282.418643) (xy 155.193968 -282.401191)
			(xy 155.151347 -282.376584) (xy 155.113226 -282.345459) (xy 155.080591 -282.308622) (xy 155.054288 -282.267026)
			(xy 155.034997 -282.22175) (xy 155.02322 -282.173966) (xy 155.01926 -282.124912) (xy 154.680412 -282.124912)
			(xy 154.679917 -282.149519) (xy 154.672022 -282.198096) (xy 154.656438 -282.244777) (xy 154.633567 -282.288354)
			(xy 154.604002 -282.327698) (xy 154.568509 -282.36179) (xy 154.528006 -282.389746) (xy 154.483544 -282.410844)
			(xy 154.436273 -282.424536) (xy 154.387418 -282.430468) (xy 154.338243 -282.428487) (xy 154.290024 -282.418643)
			(xy 154.244008 -282.401191) (xy 154.201387 -282.376584) (xy 154.163266 -282.345459) (xy 154.130631 -282.308622)
			(xy 154.104328 -282.267026) (xy 154.085037 -282.22175) (xy 154.07326 -282.173966) (xy 154.0693 -282.124912)
			(xy 153.730198 -282.124912) (xy 153.729703 -282.149519) (xy 153.721808 -282.198096) (xy 153.706224 -282.244777)
			(xy 153.683353 -282.288354) (xy 153.653788 -282.327698) (xy 153.618295 -282.36179) (xy 153.577792 -282.389746)
			(xy 153.53333 -282.410844) (xy 153.486059 -282.424536) (xy 153.437204 -282.430468) (xy 153.388029 -282.428487)
			(xy 153.33981 -282.418643) (xy 153.293794 -282.401191) (xy 153.251173 -282.376584) (xy 153.213052 -282.345459)
			(xy 153.180417 -282.308622) (xy 153.154114 -282.267026) (xy 153.134823 -282.22175) (xy 153.123046 -282.173966)
			(xy 153.119086 -282.124912) (xy 152.780238 -282.124912) (xy 152.779743 -282.149519) (xy 152.771848 -282.198096)
			(xy 152.756264 -282.244777) (xy 152.733393 -282.288354) (xy 152.703828 -282.327698) (xy 152.668335 -282.36179)
			(xy 152.627832 -282.389746) (xy 152.58337 -282.410844) (xy 152.536099 -282.424536) (xy 152.487244 -282.430468)
			(xy 152.438069 -282.428487) (xy 152.38985 -282.418643) (xy 152.343834 -282.401191) (xy 152.301213 -282.376584)
			(xy 152.263092 -282.345459) (xy 152.230457 -282.308622) (xy 152.204154 -282.267026) (xy 152.184863 -282.22175)
			(xy 152.173086 -282.173966) (xy 152.169126 -282.124912) (xy 144.019079 -282.124912) (xy 144.001013 -282.139947)
			(xy 143.953407 -282.169001) (xy 143.902078 -282.190813) (xy 143.848121 -282.204919) (xy 143.792684 -282.211019)
			(xy 143.73695 -282.208982) (xy 143.682107 -282.198852) (xy 143.629323 -282.180845) (xy 143.579723 -282.155344)
			(xy 143.534365 -282.122893) (xy 143.494216 -282.084184) (xy 143.46013 -282.040041) (xy 143.432834 -281.991406)
			(xy 143.412911 -281.939315) (xy 143.400785 -281.884878) (xy 143.396714 -281.829256) (xy 142.675102 -281.829256)
			(xy 142.674593 -281.857142) (xy 142.666473 -281.912318) (xy 142.650405 -281.965725) (xy 142.626733 -282.016222)
			(xy 142.59596 -282.062735) (xy 142.558743 -282.104272) (xy 142.515875 -282.139947) (xy 142.468269 -282.169001)
			(xy 142.41694 -282.190813) (xy 142.362983 -282.204919) (xy 142.307546 -282.211019) (xy 142.251812 -282.208982)
			(xy 142.196969 -282.198852) (xy 142.144185 -282.180845) (xy 142.094585 -282.155344) (xy 142.049227 -282.122893)
			(xy 142.009078 -282.084184) (xy 141.974992 -282.040041) (xy 141.947696 -281.991406) (xy 141.927773 -281.939315)
			(xy 141.915647 -281.884878) (xy 141.911576 -281.829256) (xy 136.94918 -281.829256) (xy 136.94918 -282.599892)
			(xy 189.69407 -282.599892) (xy 189.69803 -282.550838) (xy 189.709807 -282.503054) (xy 189.729098 -282.457778)
			(xy 189.755401 -282.416182) (xy 189.788036 -282.379345) (xy 189.826157 -282.34822) (xy 189.868778 -282.323613)
			(xy 189.914794 -282.306161) (xy 189.963013 -282.296317) (xy 190.012188 -282.294336) (xy 190.061043 -282.300268)
			(xy 190.108314 -282.31396) (xy 190.152776 -282.335058) (xy 190.193279 -282.363014) (xy 190.228772 -282.397106)
			(xy 190.258337 -282.43645) (xy 190.281208 -282.480027) (xy 190.296792 -282.526708) (xy 190.304687 -282.575285)
			(xy 190.305182 -282.599892) (xy 190.64403 -282.599892) (xy 190.64799 -282.550838) (xy 190.659767 -282.503054)
			(xy 190.679058 -282.457778) (xy 190.705361 -282.416182) (xy 190.737996 -282.379345) (xy 190.776117 -282.34822)
			(xy 190.818738 -282.323613) (xy 190.864754 -282.306161) (xy 190.912973 -282.296317) (xy 190.962148 -282.294336)
			(xy 191.011003 -282.300268) (xy 191.058274 -282.31396) (xy 191.102736 -282.335058) (xy 191.143239 -282.363014)
			(xy 191.178732 -282.397106) (xy 191.208297 -282.43645) (xy 191.231168 -282.480027) (xy 191.246752 -282.526708)
			(xy 191.254647 -282.575285) (xy 191.255142 -282.599892) (xy 191.254647 -282.624499) (xy 191.254468 -282.6256)
			(xy 192.52336 -282.6256) (xy 192.52336 -282.574184) (xy 192.531403 -282.523402) (xy 192.547291 -282.474503)
			(xy 192.570634 -282.428691) (xy 192.600855 -282.387095) (xy 192.637211 -282.350739) (xy 192.678807 -282.320518)
			(xy 192.724619 -282.297175) (xy 192.773518 -282.281287) (xy 192.8243 -282.273244) (xy 192.875716 -282.273244)
			(xy 192.926498 -282.281287) (xy 192.975397 -282.297175) (xy 193.021209 -282.320518) (xy 193.062805 -282.350739)
			(xy 193.099161 -282.387095) (xy 193.129382 -282.428691) (xy 193.152725 -282.474503) (xy 193.168613 -282.523402)
			(xy 193.176656 -282.574184) (xy 193.17716 -282.599892) (xy 193.176656 -282.6256) (xy 193.47332 -282.6256)
			(xy 193.47332 -282.574184) (xy 193.481363 -282.523402) (xy 193.497251 -282.474503) (xy 193.520594 -282.428691)
			(xy 193.550815 -282.387095) (xy 193.587171 -282.350739) (xy 193.628767 -282.320518) (xy 193.674579 -282.297175)
			(xy 193.723478 -282.281287) (xy 193.77426 -282.273244) (xy 193.825676 -282.273244) (xy 193.876458 -282.281287)
			(xy 193.925357 -282.297175) (xy 193.971169 -282.320518) (xy 194.012765 -282.350739) (xy 194.049121 -282.387095)
			(xy 194.079342 -282.428691) (xy 194.102685 -282.474503) (xy 194.118573 -282.523402) (xy 194.126616 -282.574184)
			(xy 194.12712 -282.599892) (xy 194.444124 -282.599892) (xy 194.448084 -282.550838) (xy 194.459861 -282.503054)
			(xy 194.479152 -282.457778) (xy 194.505455 -282.416182) (xy 194.53809 -282.379345) (xy 194.576211 -282.34822)
			(xy 194.618832 -282.323613) (xy 194.664848 -282.306161) (xy 194.713067 -282.296317) (xy 194.762242 -282.294336)
			(xy 194.811097 -282.300268) (xy 194.858368 -282.31396) (xy 194.90283 -282.335058) (xy 194.943333 -282.363014)
			(xy 194.978826 -282.397106) (xy 195.008391 -282.43645) (xy 195.031262 -282.480027) (xy 195.046846 -282.526708)
			(xy 195.054741 -282.575285) (xy 195.055236 -282.599892) (xy 195.054741 -282.624499) (xy 195.054562 -282.6256)
			(xy 195.37324 -282.6256) (xy 195.37324 -282.574184) (xy 195.381283 -282.523402) (xy 195.397171 -282.474503)
			(xy 195.420514 -282.428691) (xy 195.450735 -282.387095) (xy 195.487091 -282.350739) (xy 195.528687 -282.320518)
			(xy 195.574499 -282.297175) (xy 195.623398 -282.281287) (xy 195.67418 -282.273244) (xy 195.725596 -282.273244)
			(xy 195.776378 -282.281287) (xy 195.825277 -282.297175) (xy 195.871089 -282.320518) (xy 195.912685 -282.350739)
			(xy 195.949041 -282.387095) (xy 195.979262 -282.428691) (xy 196.002605 -282.474503) (xy 196.018493 -282.523402)
			(xy 196.026536 -282.574184) (xy 196.02704 -282.599892) (xy 196.026536 -282.6256) (xy 196.3232 -282.6256)
			(xy 196.3232 -282.574184) (xy 196.331243 -282.523402) (xy 196.347131 -282.474503) (xy 196.370474 -282.428691)
			(xy 196.400695 -282.387095) (xy 196.437051 -282.350739) (xy 196.478647 -282.320518) (xy 196.524459 -282.297175)
			(xy 196.573358 -282.281287) (xy 196.62414 -282.273244) (xy 196.675556 -282.273244) (xy 196.726338 -282.281287)
			(xy 196.775237 -282.297175) (xy 196.821049 -282.320518) (xy 196.862645 -282.350739) (xy 196.899001 -282.387095)
			(xy 196.929222 -282.428691) (xy 196.952565 -282.474503) (xy 196.968453 -282.523402) (xy 196.976496 -282.574184)
			(xy 196.977 -282.599892) (xy 197.294258 -282.599892) (xy 197.298218 -282.550838) (xy 197.309995 -282.503054)
			(xy 197.329286 -282.457778) (xy 197.355589 -282.416182) (xy 197.388224 -282.379345) (xy 197.426345 -282.34822)
			(xy 197.468966 -282.323613) (xy 197.514982 -282.306161) (xy 197.563201 -282.296317) (xy 197.612376 -282.294336)
			(xy 197.661231 -282.300268) (xy 197.708502 -282.31396) (xy 197.752964 -282.335058) (xy 197.793467 -282.363014)
			(xy 197.82896 -282.397106) (xy 197.858525 -282.43645) (xy 197.881396 -282.480027) (xy 197.89698 -282.526708)
			(xy 197.904875 -282.575285) (xy 197.90537 -282.599892) (xy 198.244218 -282.599892) (xy 198.248178 -282.550838)
			(xy 198.259955 -282.503054) (xy 198.279246 -282.457778) (xy 198.305549 -282.416182) (xy 198.338184 -282.379345)
			(xy 198.376305 -282.34822) (xy 198.418926 -282.323613) (xy 198.464942 -282.306161) (xy 198.513161 -282.296317)
			(xy 198.562336 -282.294336) (xy 198.611191 -282.300268) (xy 198.658462 -282.31396) (xy 198.702924 -282.335058)
			(xy 198.743427 -282.363014) (xy 198.77892 -282.397106) (xy 198.808485 -282.43645) (xy 198.831356 -282.480027)
			(xy 198.84694 -282.526708) (xy 198.854835 -282.575285) (xy 198.85533 -282.599892) (xy 198.854835 -282.624499)
			(xy 198.84694 -282.673076) (xy 198.831356 -282.719757) (xy 198.808485 -282.763334) (xy 198.77892 -282.802678)
			(xy 198.743427 -282.83677) (xy 198.702924 -282.864726) (xy 198.658462 -282.885824) (xy 198.611191 -282.899516)
			(xy 198.562336 -282.905448) (xy 198.513161 -282.903467) (xy 198.464942 -282.893623) (xy 198.418926 -282.876171)
			(xy 198.376305 -282.851564) (xy 198.338184 -282.820439) (xy 198.305549 -282.783602) (xy 198.279246 -282.742006)
			(xy 198.259955 -282.69673) (xy 198.248178 -282.648946) (xy 198.244218 -282.599892) (xy 197.90537 -282.599892)
			(xy 197.904875 -282.624499) (xy 197.89698 -282.673076) (xy 197.881396 -282.719757) (xy 197.858525 -282.763334)
			(xy 197.82896 -282.802678) (xy 197.793467 -282.83677) (xy 197.752964 -282.864726) (xy 197.708502 -282.885824)
			(xy 197.661231 -282.899516) (xy 197.612376 -282.905448) (xy 197.563201 -282.903467) (xy 197.514982 -282.893623)
			(xy 197.468966 -282.876171) (xy 197.426345 -282.851564) (xy 197.388224 -282.820439) (xy 197.355589 -282.783602)
			(xy 197.329286 -282.742006) (xy 197.309995 -282.69673) (xy 197.298218 -282.648946) (xy 197.294258 -282.599892)
			(xy 196.977 -282.599892) (xy 196.976496 -282.6256) (xy 196.968453 -282.676382) (xy 196.952565 -282.725281)
			(xy 196.929222 -282.771093) (xy 196.899001 -282.812689) (xy 196.862645 -282.849045) (xy 196.821049 -282.879266)
			(xy 196.775237 -282.902609) (xy 196.726338 -282.918497) (xy 196.675556 -282.92654) (xy 196.62414 -282.92654)
			(xy 196.573358 -282.918497) (xy 196.524459 -282.902609) (xy 196.478647 -282.879266) (xy 196.437051 -282.849045)
			(xy 196.400695 -282.812689) (xy 196.370474 -282.771093) (xy 196.347131 -282.725281) (xy 196.331243 -282.676382)
			(xy 196.3232 -282.6256) (xy 196.026536 -282.6256) (xy 196.018493 -282.676382) (xy 196.002605 -282.725281)
			(xy 195.979262 -282.771093) (xy 195.949041 -282.812689) (xy 195.912685 -282.849045) (xy 195.871089 -282.879266)
			(xy 195.825277 -282.902609) (xy 195.776378 -282.918497) (xy 195.725596 -282.92654) (xy 195.67418 -282.92654)
			(xy 195.623398 -282.918497) (xy 195.574499 -282.902609) (xy 195.528687 -282.879266) (xy 195.487091 -282.849045)
			(xy 195.450735 -282.812689) (xy 195.420514 -282.771093) (xy 195.397171 -282.725281) (xy 195.381283 -282.676382)
			(xy 195.37324 -282.6256) (xy 195.054562 -282.6256) (xy 195.046846 -282.673076) (xy 195.031262 -282.719757)
			(xy 195.008391 -282.763334) (xy 194.978826 -282.802678) (xy 194.943333 -282.83677) (xy 194.90283 -282.864726)
			(xy 194.858368 -282.885824) (xy 194.811097 -282.899516) (xy 194.762242 -282.905448) (xy 194.713067 -282.903467)
			(xy 194.664848 -282.893623) (xy 194.618832 -282.876171) (xy 194.576211 -282.851564) (xy 194.53809 -282.820439)
			(xy 194.505455 -282.783602) (xy 194.479152 -282.742006) (xy 194.459861 -282.69673) (xy 194.448084 -282.648946)
			(xy 194.444124 -282.599892) (xy 194.12712 -282.599892) (xy 194.126616 -282.6256) (xy 194.118573 -282.676382)
			(xy 194.102685 -282.725281) (xy 194.079342 -282.771093) (xy 194.049121 -282.812689) (xy 194.012765 -282.849045)
			(xy 193.971169 -282.879266) (xy 193.925357 -282.902609) (xy 193.876458 -282.918497) (xy 193.825676 -282.92654)
			(xy 193.77426 -282.92654) (xy 193.723478 -282.918497) (xy 193.674579 -282.902609) (xy 193.628767 -282.879266)
			(xy 193.587171 -282.849045) (xy 193.550815 -282.812689) (xy 193.520594 -282.771093) (xy 193.497251 -282.725281)
			(xy 193.481363 -282.676382) (xy 193.47332 -282.6256) (xy 193.176656 -282.6256) (xy 193.168613 -282.676382)
			(xy 193.152725 -282.725281) (xy 193.129382 -282.771093) (xy 193.099161 -282.812689) (xy 193.062805 -282.849045)
			(xy 193.021209 -282.879266) (xy 192.975397 -282.902609) (xy 192.926498 -282.918497) (xy 192.875716 -282.92654)
			(xy 192.8243 -282.92654) (xy 192.773518 -282.918497) (xy 192.724619 -282.902609) (xy 192.678807 -282.879266)
			(xy 192.637211 -282.849045) (xy 192.600855 -282.812689) (xy 192.570634 -282.771093) (xy 192.547291 -282.725281)
			(xy 192.531403 -282.676382) (xy 192.52336 -282.6256) (xy 191.254468 -282.6256) (xy 191.246752 -282.673076)
			(xy 191.231168 -282.719757) (xy 191.208297 -282.763334) (xy 191.178732 -282.802678) (xy 191.143239 -282.83677)
			(xy 191.102736 -282.864726) (xy 191.058274 -282.885824) (xy 191.011003 -282.899516) (xy 190.962148 -282.905448)
			(xy 190.912973 -282.903467) (xy 190.864754 -282.893623) (xy 190.818738 -282.876171) (xy 190.776117 -282.851564)
			(xy 190.737996 -282.820439) (xy 190.705361 -282.783602) (xy 190.679058 -282.742006) (xy 190.659767 -282.69673)
			(xy 190.64799 -282.648946) (xy 190.64403 -282.599892) (xy 190.305182 -282.599892) (xy 190.304687 -282.624499)
			(xy 190.296792 -282.673076) (xy 190.281208 -282.719757) (xy 190.258337 -282.763334) (xy 190.228772 -282.802678)
			(xy 190.193279 -282.83677) (xy 190.152776 -282.864726) (xy 190.108314 -282.885824) (xy 190.061043 -282.899516)
			(xy 190.012188 -282.905448) (xy 189.963013 -282.903467) (xy 189.914794 -282.893623) (xy 189.868778 -282.876171)
			(xy 189.826157 -282.851564) (xy 189.788036 -282.820439) (xy 189.755401 -282.783602) (xy 189.729098 -282.742006)
			(xy 189.709807 -282.69673) (xy 189.69803 -282.648946) (xy 189.69407 -282.599892) (xy 136.94918 -282.599892)
			(xy 136.94918 -283.131514) (xy 141.911576 -283.131514) (xy 141.915647 -283.075892) (xy 141.927773 -283.021455)
			(xy 141.947696 -282.969364) (xy 141.974992 -282.920729) (xy 142.009078 -282.876586) (xy 142.049227 -282.837877)
			(xy 142.094585 -282.805426) (xy 142.144185 -282.779925) (xy 142.196969 -282.761918) (xy 142.251812 -282.751788)
			(xy 142.307546 -282.749751) (xy 142.362983 -282.755851) (xy 142.41694 -282.769957) (xy 142.468269 -282.791769)
			(xy 142.515875 -282.820823) (xy 142.558743 -282.856498) (xy 142.59596 -282.898035) (xy 142.626733 -282.944548)
			(xy 142.650405 -282.995045) (xy 142.666473 -283.048452) (xy 142.674593 -283.103628) (xy 142.675102 -283.131514)
			(xy 143.387062 -283.131514) (xy 143.391133 -283.075892) (xy 143.403259 -283.021455) (xy 143.423182 -282.969364)
			(xy 143.450478 -282.920729) (xy 143.484564 -282.876586) (xy 143.524713 -282.837877) (xy 143.570071 -282.805426)
			(xy 143.619671 -282.779925) (xy 143.672455 -282.761918) (xy 143.727298 -282.751788) (xy 143.783032 -282.749751)
			(xy 143.838469 -282.755851) (xy 143.892426 -282.769957) (xy 143.943755 -282.791769) (xy 143.991361 -282.820823)
			(xy 144.034229 -282.856498) (xy 144.071446 -282.898035) (xy 144.102219 -282.944548) (xy 144.125891 -282.995045)
			(xy 144.141959 -283.048452) (xy 144.150079 -283.103628) (xy 144.150588 -283.131514) (xy 144.276062 -283.131514)
			(xy 144.280133 -283.075892) (xy 144.292259 -283.021455) (xy 144.312182 -282.969364) (xy 144.339478 -282.920729)
			(xy 144.373564 -282.876586) (xy 144.413713 -282.837877) (xy 144.459071 -282.805426) (xy 144.508671 -282.779925)
			(xy 144.561455 -282.761918) (xy 144.616298 -282.751788) (xy 144.672032 -282.749751) (xy 144.727469 -282.755851)
			(xy 144.781426 -282.769957) (xy 144.832755 -282.791769) (xy 144.880361 -282.820823) (xy 144.923229 -282.856498)
			(xy 144.960446 -282.898035) (xy 144.991219 -282.944548) (xy 145.014891 -282.995045) (xy 145.030959 -283.048452)
			(xy 145.039079 -283.103628) (xy 145.039588 -283.131514) (xy 145.039079 -283.1594) (xy 145.030959 -283.214576)
			(xy 145.014891 -283.267983) (xy 144.991219 -283.31848) (xy 144.960446 -283.364993) (xy 144.923229 -283.40653)
			(xy 144.880361 -283.442205) (xy 144.832755 -283.471259) (xy 144.781426 -283.493071) (xy 144.727469 -283.507177)
			(xy 144.672032 -283.513277) (xy 144.616298 -283.51124) (xy 144.561455 -283.50111) (xy 144.508671 -283.483103)
			(xy 144.459071 -283.457602) (xy 144.413713 -283.425151) (xy 144.373564 -283.386442) (xy 144.339478 -283.342299)
			(xy 144.312182 -283.293664) (xy 144.292259 -283.241573) (xy 144.280133 -283.187136) (xy 144.276062 -283.131514)
			(xy 144.150588 -283.131514) (xy 144.150079 -283.1594) (xy 144.141959 -283.214576) (xy 144.125891 -283.267983)
			(xy 144.102219 -283.31848) (xy 144.071446 -283.364993) (xy 144.034229 -283.40653) (xy 143.991361 -283.442205)
			(xy 143.943755 -283.471259) (xy 143.892426 -283.493071) (xy 143.838469 -283.507177) (xy 143.783032 -283.513277)
			(xy 143.727298 -283.51124) (xy 143.672455 -283.50111) (xy 143.619671 -283.483103) (xy 143.570071 -283.457602)
			(xy 143.524713 -283.425151) (xy 143.484564 -283.386442) (xy 143.450478 -283.342299) (xy 143.423182 -283.293664)
			(xy 143.403259 -283.241573) (xy 143.391133 -283.187136) (xy 143.387062 -283.131514) (xy 142.675102 -283.131514)
			(xy 142.674593 -283.1594) (xy 142.666473 -283.214576) (xy 142.650405 -283.267983) (xy 142.626733 -283.31848)
			(xy 142.59596 -283.364993) (xy 142.558743 -283.40653) (xy 142.515875 -283.442205) (xy 142.468269 -283.471259)
			(xy 142.41694 -283.493071) (xy 142.362983 -283.507177) (xy 142.307546 -283.513277) (xy 142.251812 -283.51124)
			(xy 142.196969 -283.50111) (xy 142.144185 -283.483103) (xy 142.094585 -283.457602) (xy 142.049227 -283.425151)
			(xy 142.009078 -283.386442) (xy 141.974992 -283.342299) (xy 141.947696 -283.293664) (xy 141.927773 -283.241573)
			(xy 141.915647 -283.187136) (xy 141.911576 -283.131514) (xy 136.94918 -283.131514) (xy 136.94918 -283.893514)
			(xy 147.43811 -283.893514) (xy 147.438654 -283.864132) (xy 147.447683 -283.806065) (xy 147.465514 -283.750071)
			(xy 147.491725 -283.697475) (xy 147.525695 -283.649524) (xy 147.56662 -283.607352) (xy 147.589748 -283.589222)
			(xy 147.599146 -283.581856) (xy 147.60956 -283.561282) (xy 147.611084 -283.457396) (xy 147.601178 -283.436314)
			(xy 147.592034 -283.428948) (xy 147.570186 -283.410742) (xy 147.531644 -283.368924) (xy 147.499736 -283.321849)
			(xy 147.475169 -283.270559) (xy 147.458486 -283.216191) (xy 147.450058 -283.159949) (xy 147.44954 -283.131514)
			(xy 147.450026 -283.104263) (xy 147.457782 -283.050315) (xy 147.473137 -282.99802) (xy 147.495779 -282.948443)
			(xy 147.525245 -282.902593) (xy 147.560936 -282.861402) (xy 147.602127 -282.825711) (xy 147.647977 -282.796245)
			(xy 147.697554 -282.773603) (xy 147.749849 -282.758248) (xy 147.803797 -282.750492) (xy 147.858299 -282.750492)
			(xy 147.912247 -282.758248) (xy 147.964542 -282.773603) (xy 148.014119 -282.796245) (xy 148.059969 -282.825711)
			(xy 148.10116 -282.861402) (xy 148.136851 -282.902593) (xy 148.166317 -282.948443) (xy 148.188959 -282.99802)
			(xy 148.204314 -283.050315) (xy 148.207845 -283.074872) (xy 152.169126 -283.074872) (xy 152.173086 -283.025818)
			(xy 152.184863 -282.978034) (xy 152.204154 -282.932758) (xy 152.230457 -282.891162) (xy 152.263092 -282.854325)
			(xy 152.301213 -282.8232) (xy 152.343834 -282.798593) (xy 152.38985 -282.781141) (xy 152.438069 -282.771297)
			(xy 152.487244 -282.769316) (xy 152.536099 -282.775248) (xy 152.58337 -282.78894) (xy 152.627832 -282.810038)
			(xy 152.668335 -282.837994) (xy 152.703828 -282.872086) (xy 152.733393 -282.91143) (xy 152.756264 -282.955007)
			(xy 152.771848 -283.001688) (xy 152.779743 -283.050265) (xy 152.780238 -283.074872) (xy 153.119086 -283.074872)
			(xy 153.123046 -283.025818) (xy 153.134823 -282.978034) (xy 153.154114 -282.932758) (xy 153.180417 -282.891162)
			(xy 153.213052 -282.854325) (xy 153.251173 -282.8232) (xy 153.293794 -282.798593) (xy 153.33981 -282.781141)
			(xy 153.388029 -282.771297) (xy 153.437204 -282.769316) (xy 153.486059 -282.775248) (xy 153.53333 -282.78894)
			(xy 153.577792 -282.810038) (xy 153.618295 -282.837994) (xy 153.653788 -282.872086) (xy 153.683353 -282.91143)
			(xy 153.706224 -282.955007) (xy 153.721808 -283.001688) (xy 153.729703 -283.050265) (xy 153.730198 -283.074872)
			(xy 154.0693 -283.074872) (xy 154.07326 -283.025818) (xy 154.085037 -282.978034) (xy 154.104328 -282.932758)
			(xy 154.130631 -282.891162) (xy 154.163266 -282.854325) (xy 154.201387 -282.8232) (xy 154.244008 -282.798593)
			(xy 154.290024 -282.781141) (xy 154.338243 -282.771297) (xy 154.387418 -282.769316) (xy 154.436273 -282.775248)
			(xy 154.483544 -282.78894) (xy 154.528006 -282.810038) (xy 154.568509 -282.837994) (xy 154.604002 -282.872086)
			(xy 154.633567 -282.91143) (xy 154.656438 -282.955007) (xy 154.672022 -283.001688) (xy 154.679917 -283.050265)
			(xy 154.680412 -283.074872) (xy 155.01926 -283.074872) (xy 155.02322 -283.025818) (xy 155.034997 -282.978034)
			(xy 155.054288 -282.932758) (xy 155.080591 -282.891162) (xy 155.113226 -282.854325) (xy 155.151347 -282.8232)
			(xy 155.193968 -282.798593) (xy 155.239984 -282.781141) (xy 155.288203 -282.771297) (xy 155.337378 -282.769316)
			(xy 155.386233 -282.775248) (xy 155.433504 -282.78894) (xy 155.477966 -282.810038) (xy 155.518469 -282.837994)
			(xy 155.553962 -282.872086) (xy 155.583527 -282.91143) (xy 155.606398 -282.955007) (xy 155.621982 -283.001688)
			(xy 155.629877 -283.050265) (xy 155.630372 -283.074872) (xy 155.96922 -283.074872) (xy 155.97318 -283.025818)
			(xy 155.984957 -282.978034) (xy 156.004248 -282.932758) (xy 156.030551 -282.891162) (xy 156.063186 -282.854325)
			(xy 156.101307 -282.8232) (xy 156.143928 -282.798593) (xy 156.189944 -282.781141) (xy 156.238163 -282.771297)
			(xy 156.287338 -282.769316) (xy 156.336193 -282.775248) (xy 156.383464 -282.78894) (xy 156.427926 -282.810038)
			(xy 156.468429 -282.837994) (xy 156.503922 -282.872086) (xy 156.533487 -282.91143) (xy 156.556358 -282.955007)
			(xy 156.571942 -283.001688) (xy 156.579837 -283.050265) (xy 156.580332 -283.074872) (xy 156.91918 -283.074872)
			(xy 156.92314 -283.025818) (xy 156.934917 -282.978034) (xy 156.954208 -282.932758) (xy 156.980511 -282.891162)
			(xy 157.013146 -282.854325) (xy 157.051267 -282.8232) (xy 157.093888 -282.798593) (xy 157.139904 -282.781141)
			(xy 157.188123 -282.771297) (xy 157.237298 -282.769316) (xy 157.286153 -282.775248) (xy 157.333424 -282.78894)
			(xy 157.377886 -282.810038) (xy 157.418389 -282.837994) (xy 157.453882 -282.872086) (xy 157.483447 -282.91143)
			(xy 157.506318 -282.955007) (xy 157.521902 -283.001688) (xy 157.529797 -283.050265) (xy 157.530292 -283.074872)
			(xy 157.86914 -283.074872) (xy 157.8731 -283.025818) (xy 157.884877 -282.978034) (xy 157.904168 -282.932758)
			(xy 157.930471 -282.891162) (xy 157.963106 -282.854325) (xy 158.001227 -282.8232) (xy 158.043848 -282.798593)
			(xy 158.089864 -282.781141) (xy 158.138083 -282.771297) (xy 158.187258 -282.769316) (xy 158.236113 -282.775248)
			(xy 158.283384 -282.78894) (xy 158.327846 -282.810038) (xy 158.368349 -282.837994) (xy 158.403842 -282.872086)
			(xy 158.433407 -282.91143) (xy 158.456278 -282.955007) (xy 158.471862 -283.001688) (xy 158.479757 -283.050265)
			(xy 158.480252 -283.074872) (xy 158.8191 -283.074872) (xy 158.82306 -283.025818) (xy 158.834837 -282.978034)
			(xy 158.854128 -282.932758) (xy 158.880431 -282.891162) (xy 158.913066 -282.854325) (xy 158.951187 -282.8232)
			(xy 158.993808 -282.798593) (xy 159.039824 -282.781141) (xy 159.088043 -282.771297) (xy 159.137218 -282.769316)
			(xy 159.186073 -282.775248) (xy 159.233344 -282.78894) (xy 159.277806 -282.810038) (xy 159.318309 -282.837994)
			(xy 159.353802 -282.872086) (xy 159.383367 -282.91143) (xy 159.406238 -282.955007) (xy 159.421822 -283.001688)
			(xy 159.429717 -283.050265) (xy 159.430212 -283.074872) (xy 159.76906 -283.074872) (xy 159.77302 -283.025818)
			(xy 159.784797 -282.978034) (xy 159.804088 -282.932758) (xy 159.830391 -282.891162) (xy 159.863026 -282.854325)
			(xy 159.901147 -282.8232) (xy 159.943768 -282.798593) (xy 159.989784 -282.781141) (xy 160.038003 -282.771297)
			(xy 160.087178 -282.769316) (xy 160.136033 -282.775248) (xy 160.183304 -282.78894) (xy 160.227766 -282.810038)
			(xy 160.268269 -282.837994) (xy 160.303762 -282.872086) (xy 160.333327 -282.91143) (xy 160.356198 -282.955007)
			(xy 160.371782 -283.001688) (xy 160.379677 -283.050265) (xy 160.380172 -283.074872) (xy 160.719274 -283.074872)
			(xy 160.723234 -283.025818) (xy 160.735011 -282.978034) (xy 160.754302 -282.932758) (xy 160.780605 -282.891162)
			(xy 160.81324 -282.854325) (xy 160.851361 -282.8232) (xy 160.893982 -282.798593) (xy 160.939998 -282.781141)
			(xy 160.988217 -282.771297) (xy 161.037392 -282.769316) (xy 161.086247 -282.775248) (xy 161.133518 -282.78894)
			(xy 161.17798 -282.810038) (xy 161.218483 -282.837994) (xy 161.253976 -282.872086) (xy 161.283541 -282.91143)
			(xy 161.306412 -282.955007) (xy 161.321996 -283.001688) (xy 161.329891 -283.050265) (xy 161.330386 -283.074872)
			(xy 161.669234 -283.074872) (xy 161.673194 -283.025818) (xy 161.684971 -282.978034) (xy 161.704262 -282.932758)
			(xy 161.730565 -282.891162) (xy 161.7632 -282.854325) (xy 161.801321 -282.8232) (xy 161.843942 -282.798593)
			(xy 161.889958 -282.781141) (xy 161.938177 -282.771297) (xy 161.987352 -282.769316) (xy 162.036207 -282.775248)
			(xy 162.083478 -282.78894) (xy 162.12794 -282.810038) (xy 162.168443 -282.837994) (xy 162.203936 -282.872086)
			(xy 162.233501 -282.91143) (xy 162.256372 -282.955007) (xy 162.271956 -283.001688) (xy 162.279851 -283.050265)
			(xy 162.280346 -283.074872) (xy 162.619194 -283.074872) (xy 162.623154 -283.025818) (xy 162.634931 -282.978034)
			(xy 162.654222 -282.932758) (xy 162.680525 -282.891162) (xy 162.71316 -282.854325) (xy 162.751281 -282.8232)
			(xy 162.793902 -282.798593) (xy 162.839918 -282.781141) (xy 162.888137 -282.771297) (xy 162.937312 -282.769316)
			(xy 162.986167 -282.775248) (xy 163.033438 -282.78894) (xy 163.0779 -282.810038) (xy 163.118403 -282.837994)
			(xy 163.153896 -282.872086) (xy 163.183461 -282.91143) (xy 163.206332 -282.955007) (xy 163.221916 -283.001688)
			(xy 163.229811 -283.050265) (xy 163.230306 -283.074872) (xy 163.569154 -283.074872) (xy 163.573114 -283.025818)
			(xy 163.584891 -282.978034) (xy 163.604182 -282.932758) (xy 163.630485 -282.891162) (xy 163.66312 -282.854325)
			(xy 163.701241 -282.8232) (xy 163.743862 -282.798593) (xy 163.789878 -282.781141) (xy 163.838097 -282.771297)
			(xy 163.887272 -282.769316) (xy 163.936127 -282.775248) (xy 163.983398 -282.78894) (xy 164.02786 -282.810038)
			(xy 164.068363 -282.837994) (xy 164.103856 -282.872086) (xy 164.133421 -282.91143) (xy 164.156292 -282.955007)
			(xy 164.171876 -283.001688) (xy 164.179771 -283.050265) (xy 164.180266 -283.074872) (xy 164.519114 -283.074872)
			(xy 164.523074 -283.025818) (xy 164.534851 -282.978034) (xy 164.554142 -282.932758) (xy 164.580445 -282.891162)
			(xy 164.61308 -282.854325) (xy 164.651201 -282.8232) (xy 164.693822 -282.798593) (xy 164.739838 -282.781141)
			(xy 164.788057 -282.771297) (xy 164.837232 -282.769316) (xy 164.886087 -282.775248) (xy 164.933358 -282.78894)
			(xy 164.97782 -282.810038) (xy 165.018323 -282.837994) (xy 165.053816 -282.872086) (xy 165.083381 -282.91143)
			(xy 165.106252 -282.955007) (xy 165.121836 -283.001688) (xy 165.129731 -283.050265) (xy 165.130226 -283.074872)
			(xy 165.469074 -283.074872) (xy 165.473034 -283.025818) (xy 165.484811 -282.978034) (xy 165.504102 -282.932758)
			(xy 165.530405 -282.891162) (xy 165.56304 -282.854325) (xy 165.601161 -282.8232) (xy 165.643782 -282.798593)
			(xy 165.689798 -282.781141) (xy 165.738017 -282.771297) (xy 165.787192 -282.769316) (xy 165.836047 -282.775248)
			(xy 165.883318 -282.78894) (xy 165.92778 -282.810038) (xy 165.968283 -282.837994) (xy 166.003776 -282.872086)
			(xy 166.033341 -282.91143) (xy 166.056212 -282.955007) (xy 166.071796 -283.001688) (xy 166.079691 -283.050265)
			(xy 166.080186 -283.074872) (xy 166.419288 -283.074872) (xy 166.423248 -283.025818) (xy 166.435025 -282.978034)
			(xy 166.454316 -282.932758) (xy 166.480619 -282.891162) (xy 166.513254 -282.854325) (xy 166.551375 -282.8232)
			(xy 166.593996 -282.798593) (xy 166.640012 -282.781141) (xy 166.688231 -282.771297) (xy 166.737406 -282.769316)
			(xy 166.786261 -282.775248) (xy 166.833532 -282.78894) (xy 166.877994 -282.810038) (xy 166.918497 -282.837994)
			(xy 166.95399 -282.872086) (xy 166.983555 -282.91143) (xy 167.006426 -282.955007) (xy 167.02201 -283.001688)
			(xy 167.029905 -283.050265) (xy 167.0304 -283.074872) (xy 167.369248 -283.074872) (xy 167.373208 -283.025818)
			(xy 167.384985 -282.978034) (xy 167.404276 -282.932758) (xy 167.430579 -282.891162) (xy 167.463214 -282.854325)
			(xy 167.501335 -282.8232) (xy 167.543956 -282.798593) (xy 167.589972 -282.781141) (xy 167.638191 -282.771297)
			(xy 167.687366 -282.769316) (xy 167.736221 -282.775248) (xy 167.783492 -282.78894) (xy 167.827954 -282.810038)
			(xy 167.868457 -282.837994) (xy 167.90395 -282.872086) (xy 167.933515 -282.91143) (xy 167.956386 -282.955007)
			(xy 167.97197 -283.001688) (xy 167.979865 -283.050265) (xy 167.98036 -283.074872) (xy 168.319208 -283.074872)
			(xy 168.323168 -283.025818) (xy 168.334945 -282.978034) (xy 168.354236 -282.932758) (xy 168.380539 -282.891162)
			(xy 168.413174 -282.854325) (xy 168.451295 -282.8232) (xy 168.493916 -282.798593) (xy 168.539932 -282.781141)
			(xy 168.588151 -282.771297) (xy 168.637326 -282.769316) (xy 168.686181 -282.775248) (xy 168.733452 -282.78894)
			(xy 168.777914 -282.810038) (xy 168.818417 -282.837994) (xy 168.85391 -282.872086) (xy 168.883475 -282.91143)
			(xy 168.906346 -282.955007) (xy 168.92193 -283.001688) (xy 168.929825 -283.050265) (xy 168.93032 -283.074872)
			(xy 169.269168 -283.074872) (xy 169.273128 -283.025818) (xy 169.284905 -282.978034) (xy 169.304196 -282.932758)
			(xy 169.330499 -282.891162) (xy 169.363134 -282.854325) (xy 169.401255 -282.8232) (xy 169.443876 -282.798593)
			(xy 169.489892 -282.781141) (xy 169.538111 -282.771297) (xy 169.587286 -282.769316) (xy 169.636141 -282.775248)
			(xy 169.683412 -282.78894) (xy 169.727874 -282.810038) (xy 169.768377 -282.837994) (xy 169.80387 -282.872086)
			(xy 169.833435 -282.91143) (xy 169.856306 -282.955007) (xy 169.87189 -283.001688) (xy 169.879785 -283.050265)
			(xy 169.88028 -283.074872) (xy 170.219128 -283.074872) (xy 170.223088 -283.025818) (xy 170.234865 -282.978034)
			(xy 170.254156 -282.932758) (xy 170.280459 -282.891162) (xy 170.313094 -282.854325) (xy 170.351215 -282.8232)
			(xy 170.393836 -282.798593) (xy 170.439852 -282.781141) (xy 170.488071 -282.771297) (xy 170.537246 -282.769316)
			(xy 170.586101 -282.775248) (xy 170.633372 -282.78894) (xy 170.677834 -282.810038) (xy 170.718337 -282.837994)
			(xy 170.75383 -282.872086) (xy 170.783395 -282.91143) (xy 170.806266 -282.955007) (xy 170.82185 -283.001688)
			(xy 170.829745 -283.050265) (xy 170.83024 -283.074872) (xy 171.169088 -283.074872) (xy 171.173048 -283.025818)
			(xy 171.184825 -282.978034) (xy 171.204116 -282.932758) (xy 171.230419 -282.891162) (xy 171.263054 -282.854325)
			(xy 171.301175 -282.8232) (xy 171.343796 -282.798593) (xy 171.389812 -282.781141) (xy 171.438031 -282.771297)
			(xy 171.487206 -282.769316) (xy 171.536061 -282.775248) (xy 171.583332 -282.78894) (xy 171.627794 -282.810038)
			(xy 171.668297 -282.837994) (xy 171.70379 -282.872086) (xy 171.733355 -282.91143) (xy 171.756226 -282.955007)
			(xy 171.77181 -283.001688) (xy 171.779705 -283.050265) (xy 171.7802 -283.074872) (xy 172.119302 -283.074872)
			(xy 172.123262 -283.025818) (xy 172.135039 -282.978034) (xy 172.15433 -282.932758) (xy 172.180633 -282.891162)
			(xy 172.213268 -282.854325) (xy 172.251389 -282.8232) (xy 172.29401 -282.798593) (xy 172.340026 -282.781141)
			(xy 172.388245 -282.771297) (xy 172.43742 -282.769316) (xy 172.486275 -282.775248) (xy 172.533546 -282.78894)
			(xy 172.578008 -282.810038) (xy 172.618511 -282.837994) (xy 172.654004 -282.872086) (xy 172.683569 -282.91143)
			(xy 172.70644 -282.955007) (xy 172.722024 -283.001688) (xy 172.729919 -283.050265) (xy 172.730414 -283.074872)
			(xy 173.069262 -283.074872) (xy 173.073222 -283.025818) (xy 173.084999 -282.978034) (xy 173.10429 -282.932758)
			(xy 173.130593 -282.891162) (xy 173.163228 -282.854325) (xy 173.201349 -282.8232) (xy 173.24397 -282.798593)
			(xy 173.289986 -282.781141) (xy 173.338205 -282.771297) (xy 173.38738 -282.769316) (xy 173.436235 -282.775248)
			(xy 173.483506 -282.78894) (xy 173.527968 -282.810038) (xy 173.568471 -282.837994) (xy 173.603964 -282.872086)
			(xy 173.633529 -282.91143) (xy 173.6564 -282.955007) (xy 173.671984 -283.001688) (xy 173.679879 -283.050265)
			(xy 173.680374 -283.074872) (xy 174.019222 -283.074872) (xy 174.023182 -283.025818) (xy 174.034959 -282.978034)
			(xy 174.05425 -282.932758) (xy 174.080553 -282.891162) (xy 174.113188 -282.854325) (xy 174.151309 -282.8232)
			(xy 174.19393 -282.798593) (xy 174.239946 -282.781141) (xy 174.288165 -282.771297) (xy 174.33734 -282.769316)
			(xy 174.386195 -282.775248) (xy 174.433466 -282.78894) (xy 174.477928 -282.810038) (xy 174.518431 -282.837994)
			(xy 174.553924 -282.872086) (xy 174.583489 -282.91143) (xy 174.60636 -282.955007) (xy 174.621944 -283.001688)
			(xy 174.629839 -283.050265) (xy 174.630334 -283.074872) (xy 175.919142 -283.074872) (xy 175.923102 -283.025818)
			(xy 175.934879 -282.978034) (xy 175.95417 -282.932758) (xy 175.980473 -282.891162) (xy 176.013108 -282.854325)
			(xy 176.051229 -282.8232) (xy 176.09385 -282.798593) (xy 176.139866 -282.781141) (xy 176.188085 -282.771297)
			(xy 176.23726 -282.769316) (xy 176.286115 -282.775248) (xy 176.333386 -282.78894) (xy 176.377848 -282.810038)
			(xy 176.418351 -282.837994) (xy 176.453844 -282.872086) (xy 176.483409 -282.91143) (xy 176.50628 -282.955007)
			(xy 176.521864 -283.001688) (xy 176.529759 -283.050265) (xy 176.530254 -283.074872) (xy 176.869102 -283.074872)
			(xy 176.873062 -283.025818) (xy 176.884839 -282.978034) (xy 176.90413 -282.932758) (xy 176.930433 -282.891162)
			(xy 176.963068 -282.854325) (xy 177.001189 -282.8232) (xy 177.04381 -282.798593) (xy 177.089826 -282.781141)
			(xy 177.138045 -282.771297) (xy 177.18722 -282.769316) (xy 177.236075 -282.775248) (xy 177.283346 -282.78894)
			(xy 177.327808 -282.810038) (xy 177.368311 -282.837994) (xy 177.403804 -282.872086) (xy 177.433369 -282.91143)
			(xy 177.45624 -282.955007) (xy 177.471824 -283.001688) (xy 177.479719 -283.050265) (xy 177.480214 -283.074872)
			(xy 177.819062 -283.074872) (xy 177.823022 -283.025818) (xy 177.834799 -282.978034) (xy 177.85409 -282.932758)
			(xy 177.880393 -282.891162) (xy 177.913028 -282.854325) (xy 177.951149 -282.8232) (xy 177.99377 -282.798593)
			(xy 178.039786 -282.781141) (xy 178.088005 -282.771297) (xy 178.13718 -282.769316) (xy 178.186035 -282.775248)
			(xy 178.233306 -282.78894) (xy 178.277768 -282.810038) (xy 178.318271 -282.837994) (xy 178.353764 -282.872086)
			(xy 178.383329 -282.91143) (xy 178.4062 -282.955007) (xy 178.421784 -283.001688) (xy 178.429679 -283.050265)
			(xy 178.430174 -283.074872) (xy 178.769276 -283.074872) (xy 178.773236 -283.025818) (xy 178.785013 -282.978034)
			(xy 178.804304 -282.932758) (xy 178.830607 -282.891162) (xy 178.863242 -282.854325) (xy 178.901363 -282.8232)
			(xy 178.943984 -282.798593) (xy 178.99 -282.781141) (xy 179.038219 -282.771297) (xy 179.087394 -282.769316)
			(xy 179.136249 -282.775248) (xy 179.18352 -282.78894) (xy 179.227982 -282.810038) (xy 179.268485 -282.837994)
			(xy 179.303978 -282.872086) (xy 179.333543 -282.91143) (xy 179.356414 -282.955007) (xy 179.371998 -283.001688)
			(xy 179.379893 -283.050265) (xy 179.380388 -283.074872) (xy 179.719236 -283.074872) (xy 179.723196 -283.025818)
			(xy 179.734973 -282.978034) (xy 179.754264 -282.932758) (xy 179.780567 -282.891162) (xy 179.813202 -282.854325)
			(xy 179.851323 -282.8232) (xy 179.893944 -282.798593) (xy 179.93996 -282.781141) (xy 179.988179 -282.771297)
			(xy 180.037354 -282.769316) (xy 180.086209 -282.775248) (xy 180.13348 -282.78894) (xy 180.177942 -282.810038)
			(xy 180.218445 -282.837994) (xy 180.253938 -282.872086) (xy 180.283503 -282.91143) (xy 180.306374 -282.955007)
			(xy 180.321958 -283.001688) (xy 180.329853 -283.050265) (xy 180.330348 -283.074872) (xy 180.669196 -283.074872)
			(xy 180.673156 -283.025818) (xy 180.684933 -282.978034) (xy 180.704224 -282.932758) (xy 180.730527 -282.891162)
			(xy 180.763162 -282.854325) (xy 180.801283 -282.8232) (xy 180.843904 -282.798593) (xy 180.88992 -282.781141)
			(xy 180.938139 -282.771297) (xy 180.987314 -282.769316) (xy 181.036169 -282.775248) (xy 181.08344 -282.78894)
			(xy 181.127902 -282.810038) (xy 181.168405 -282.837994) (xy 181.203898 -282.872086) (xy 181.233463 -282.91143)
			(xy 181.256334 -282.955007) (xy 181.271918 -283.001688) (xy 181.279813 -283.050265) (xy 181.280308 -283.074872)
			(xy 181.619156 -283.074872) (xy 181.623116 -283.025818) (xy 181.634893 -282.978034) (xy 181.654184 -282.932758)
			(xy 181.680487 -282.891162) (xy 181.713122 -282.854325) (xy 181.751243 -282.8232) (xy 181.793864 -282.798593)
			(xy 181.83988 -282.781141) (xy 181.888099 -282.771297) (xy 181.937274 -282.769316) (xy 181.986129 -282.775248)
			(xy 182.0334 -282.78894) (xy 182.077862 -282.810038) (xy 182.118365 -282.837994) (xy 182.153858 -282.872086)
			(xy 182.183423 -282.91143) (xy 182.206294 -282.955007) (xy 182.221878 -283.001688) (xy 182.229773 -283.050265)
			(xy 182.230268 -283.074872) (xy 182.569116 -283.074872) (xy 182.573076 -283.025818) (xy 182.584853 -282.978034)
			(xy 182.604144 -282.932758) (xy 182.630447 -282.891162) (xy 182.663082 -282.854325) (xy 182.701203 -282.8232)
			(xy 182.743824 -282.798593) (xy 182.78984 -282.781141) (xy 182.838059 -282.771297) (xy 182.887234 -282.769316)
			(xy 182.936089 -282.775248) (xy 182.98336 -282.78894) (xy 183.027822 -282.810038) (xy 183.068325 -282.837994)
			(xy 183.103818 -282.872086) (xy 183.133383 -282.91143) (xy 183.156254 -282.955007) (xy 183.171838 -283.001688)
			(xy 183.179733 -283.050265) (xy 183.180228 -283.074872) (xy 184.469036 -283.074872) (xy 184.472996 -283.025818)
			(xy 184.484773 -282.978034) (xy 184.504064 -282.932758) (xy 184.530367 -282.891162) (xy 184.563002 -282.854325)
			(xy 184.601123 -282.8232) (xy 184.643744 -282.798593) (xy 184.68976 -282.781141) (xy 184.737979 -282.771297)
			(xy 184.787154 -282.769316) (xy 184.836009 -282.775248) (xy 184.88328 -282.78894) (xy 184.927742 -282.810038)
			(xy 184.968245 -282.837994) (xy 185.003738 -282.872086) (xy 185.033303 -282.91143) (xy 185.056174 -282.955007)
			(xy 185.071758 -283.001688) (xy 185.079653 -283.050265) (xy 185.080148 -283.074872) (xy 185.41925 -283.074872)
			(xy 185.42321 -283.025818) (xy 185.434987 -282.978034) (xy 185.454278 -282.932758) (xy 185.480581 -282.891162)
			(xy 185.513216 -282.854325) (xy 185.551337 -282.8232) (xy 185.593958 -282.798593) (xy 185.639974 -282.781141)
			(xy 185.688193 -282.771297) (xy 185.737368 -282.769316) (xy 185.786223 -282.775248) (xy 185.833494 -282.78894)
			(xy 185.877956 -282.810038) (xy 185.918459 -282.837994) (xy 185.953952 -282.872086) (xy 185.983517 -282.91143)
			(xy 186.006388 -282.955007) (xy 186.021972 -283.001688) (xy 186.029867 -283.050265) (xy 186.030362 -283.074872)
			(xy 186.36921 -283.074872) (xy 186.37317 -283.025818) (xy 186.384947 -282.978034) (xy 186.404238 -282.932758)
			(xy 186.430541 -282.891162) (xy 186.463176 -282.854325) (xy 186.501297 -282.8232) (xy 186.543918 -282.798593)
			(xy 186.589934 -282.781141) (xy 186.638153 -282.771297) (xy 186.687328 -282.769316) (xy 186.736183 -282.775248)
			(xy 186.783454 -282.78894) (xy 186.827916 -282.810038) (xy 186.868419 -282.837994) (xy 186.903912 -282.872086)
			(xy 186.933477 -282.91143) (xy 186.956348 -282.955007) (xy 186.971932 -283.001688) (xy 186.979827 -283.050265)
			(xy 186.980322 -283.074872) (xy 187.31917 -283.074872) (xy 187.32313 -283.025818) (xy 187.334907 -282.978034)
			(xy 187.354198 -282.932758) (xy 187.380501 -282.891162) (xy 187.413136 -282.854325) (xy 187.451257 -282.8232)
			(xy 187.493878 -282.798593) (xy 187.539894 -282.781141) (xy 187.588113 -282.771297) (xy 187.637288 -282.769316)
			(xy 187.686143 -282.775248) (xy 187.733414 -282.78894) (xy 187.777876 -282.810038) (xy 187.818379 -282.837994)
			(xy 187.853872 -282.872086) (xy 187.883437 -282.91143) (xy 187.906308 -282.955007) (xy 187.921892 -283.001688)
			(xy 187.929787 -283.050265) (xy 187.930282 -283.074872) (xy 188.26913 -283.074872) (xy 188.27309 -283.025818)
			(xy 188.284867 -282.978034) (xy 188.304158 -282.932758) (xy 188.330461 -282.891162) (xy 188.363096 -282.854325)
			(xy 188.401217 -282.8232) (xy 188.443838 -282.798593) (xy 188.489854 -282.781141) (xy 188.538073 -282.771297)
			(xy 188.587248 -282.769316) (xy 188.636103 -282.775248) (xy 188.683374 -282.78894) (xy 188.727836 -282.810038)
			(xy 188.768339 -282.837994) (xy 188.803832 -282.872086) (xy 188.833397 -282.91143) (xy 188.856268 -282.955007)
			(xy 188.871852 -283.001688) (xy 188.879747 -283.050265) (xy 188.880242 -283.074872) (xy 188.879747 -283.099479)
			(xy 188.871852 -283.148056) (xy 188.856268 -283.194737) (xy 188.833397 -283.238314) (xy 188.803832 -283.277658)
			(xy 188.768339 -283.31175) (xy 188.727836 -283.339706) (xy 188.683374 -283.360804) (xy 188.636103 -283.374496)
			(xy 188.587248 -283.380428) (xy 188.538073 -283.378447) (xy 188.489854 -283.368603) (xy 188.443838 -283.351151)
			(xy 188.401217 -283.326544) (xy 188.363096 -283.295419) (xy 188.330461 -283.258582) (xy 188.304158 -283.216986)
			(xy 188.284867 -283.17171) (xy 188.27309 -283.123926) (xy 188.26913 -283.074872) (xy 187.930282 -283.074872)
			(xy 187.929787 -283.099479) (xy 187.921892 -283.148056) (xy 187.906308 -283.194737) (xy 187.883437 -283.238314)
			(xy 187.853872 -283.277658) (xy 187.818379 -283.31175) (xy 187.777876 -283.339706) (xy 187.733414 -283.360804)
			(xy 187.686143 -283.374496) (xy 187.637288 -283.380428) (xy 187.588113 -283.378447) (xy 187.539894 -283.368603)
			(xy 187.493878 -283.351151) (xy 187.451257 -283.326544) (xy 187.413136 -283.295419) (xy 187.380501 -283.258582)
			(xy 187.354198 -283.216986) (xy 187.334907 -283.17171) (xy 187.32313 -283.123926) (xy 187.31917 -283.074872)
			(xy 186.980322 -283.074872) (xy 186.979827 -283.099479) (xy 186.971932 -283.148056) (xy 186.956348 -283.194737)
			(xy 186.933477 -283.238314) (xy 186.903912 -283.277658) (xy 186.868419 -283.31175) (xy 186.827916 -283.339706)
			(xy 186.783454 -283.360804) (xy 186.736183 -283.374496) (xy 186.687328 -283.380428) (xy 186.638153 -283.378447)
			(xy 186.589934 -283.368603) (xy 186.543918 -283.351151) (xy 186.501297 -283.326544) (xy 186.463176 -283.295419)
			(xy 186.430541 -283.258582) (xy 186.404238 -283.216986) (xy 186.384947 -283.17171) (xy 186.37317 -283.123926)
			(xy 186.36921 -283.074872) (xy 186.030362 -283.074872) (xy 186.029867 -283.099479) (xy 186.021972 -283.148056)
			(xy 186.006388 -283.194737) (xy 185.983517 -283.238314) (xy 185.953952 -283.277658) (xy 185.918459 -283.31175)
			(xy 185.877956 -283.339706) (xy 185.833494 -283.360804) (xy 185.786223 -283.374496) (xy 185.737368 -283.380428)
			(xy 185.688193 -283.378447) (xy 185.639974 -283.368603) (xy 185.593958 -283.351151) (xy 185.551337 -283.326544)
			(xy 185.513216 -283.295419) (xy 185.480581 -283.258582) (xy 185.454278 -283.216986) (xy 185.434987 -283.17171)
			(xy 185.42321 -283.123926) (xy 185.41925 -283.074872) (xy 185.080148 -283.074872) (xy 185.079653 -283.099479)
			(xy 185.071758 -283.148056) (xy 185.056174 -283.194737) (xy 185.033303 -283.238314) (xy 185.003738 -283.277658)
			(xy 184.968245 -283.31175) (xy 184.927742 -283.339706) (xy 184.88328 -283.360804) (xy 184.836009 -283.374496)
			(xy 184.787154 -283.380428) (xy 184.737979 -283.378447) (xy 184.68976 -283.368603) (xy 184.643744 -283.351151)
			(xy 184.601123 -283.326544) (xy 184.563002 -283.295419) (xy 184.530367 -283.258582) (xy 184.504064 -283.216986)
			(xy 184.484773 -283.17171) (xy 184.472996 -283.123926) (xy 184.469036 -283.074872) (xy 183.180228 -283.074872)
			(xy 183.179733 -283.099479) (xy 183.171838 -283.148056) (xy 183.156254 -283.194737) (xy 183.133383 -283.238314)
			(xy 183.103818 -283.277658) (xy 183.068325 -283.31175) (xy 183.027822 -283.339706) (xy 182.98336 -283.360804)
			(xy 182.936089 -283.374496) (xy 182.887234 -283.380428) (xy 182.838059 -283.378447) (xy 182.78984 -283.368603)
			(xy 182.743824 -283.351151) (xy 182.701203 -283.326544) (xy 182.663082 -283.295419) (xy 182.630447 -283.258582)
			(xy 182.604144 -283.216986) (xy 182.584853 -283.17171) (xy 182.573076 -283.123926) (xy 182.569116 -283.074872)
			(xy 182.230268 -283.074872) (xy 182.229773 -283.099479) (xy 182.221878 -283.148056) (xy 182.206294 -283.194737)
			(xy 182.183423 -283.238314) (xy 182.153858 -283.277658) (xy 182.118365 -283.31175) (xy 182.077862 -283.339706)
			(xy 182.0334 -283.360804) (xy 181.986129 -283.374496) (xy 181.937274 -283.380428) (xy 181.888099 -283.378447)
			(xy 181.83988 -283.368603) (xy 181.793864 -283.351151) (xy 181.751243 -283.326544) (xy 181.713122 -283.295419)
			(xy 181.680487 -283.258582) (xy 181.654184 -283.216986) (xy 181.634893 -283.17171) (xy 181.623116 -283.123926)
			(xy 181.619156 -283.074872) (xy 181.280308 -283.074872) (xy 181.279813 -283.099479) (xy 181.271918 -283.148056)
			(xy 181.256334 -283.194737) (xy 181.233463 -283.238314) (xy 181.203898 -283.277658) (xy 181.168405 -283.31175)
			(xy 181.127902 -283.339706) (xy 181.08344 -283.360804) (xy 181.036169 -283.374496) (xy 180.987314 -283.380428)
			(xy 180.938139 -283.378447) (xy 180.88992 -283.368603) (xy 180.843904 -283.351151) (xy 180.801283 -283.326544)
			(xy 180.763162 -283.295419) (xy 180.730527 -283.258582) (xy 180.704224 -283.216986) (xy 180.684933 -283.17171)
			(xy 180.673156 -283.123926) (xy 180.669196 -283.074872) (xy 180.330348 -283.074872) (xy 180.329853 -283.099479)
			(xy 180.321958 -283.148056) (xy 180.306374 -283.194737) (xy 180.283503 -283.238314) (xy 180.253938 -283.277658)
			(xy 180.218445 -283.31175) (xy 180.177942 -283.339706) (xy 180.13348 -283.360804) (xy 180.086209 -283.374496)
			(xy 180.037354 -283.380428) (xy 179.988179 -283.378447) (xy 179.93996 -283.368603) (xy 179.893944 -283.351151)
			(xy 179.851323 -283.326544) (xy 179.813202 -283.295419) (xy 179.780567 -283.258582) (xy 179.754264 -283.216986)
			(xy 179.734973 -283.17171) (xy 179.723196 -283.123926) (xy 179.719236 -283.074872) (xy 179.380388 -283.074872)
			(xy 179.379893 -283.099479) (xy 179.371998 -283.148056) (xy 179.356414 -283.194737) (xy 179.333543 -283.238314)
			(xy 179.303978 -283.277658) (xy 179.268485 -283.31175) (xy 179.227982 -283.339706) (xy 179.18352 -283.360804)
			(xy 179.136249 -283.374496) (xy 179.087394 -283.380428) (xy 179.038219 -283.378447) (xy 178.99 -283.368603)
			(xy 178.943984 -283.351151) (xy 178.901363 -283.326544) (xy 178.863242 -283.295419) (xy 178.830607 -283.258582)
			(xy 178.804304 -283.216986) (xy 178.785013 -283.17171) (xy 178.773236 -283.123926) (xy 178.769276 -283.074872)
			(xy 178.430174 -283.074872) (xy 178.429679 -283.099479) (xy 178.421784 -283.148056) (xy 178.4062 -283.194737)
			(xy 178.383329 -283.238314) (xy 178.353764 -283.277658) (xy 178.318271 -283.31175) (xy 178.277768 -283.339706)
			(xy 178.233306 -283.360804) (xy 178.186035 -283.374496) (xy 178.13718 -283.380428) (xy 178.088005 -283.378447)
			(xy 178.039786 -283.368603) (xy 177.99377 -283.351151) (xy 177.951149 -283.326544) (xy 177.913028 -283.295419)
			(xy 177.880393 -283.258582) (xy 177.85409 -283.216986) (xy 177.834799 -283.17171) (xy 177.823022 -283.123926)
			(xy 177.819062 -283.074872) (xy 177.480214 -283.074872) (xy 177.479719 -283.099479) (xy 177.471824 -283.148056)
			(xy 177.45624 -283.194737) (xy 177.433369 -283.238314) (xy 177.403804 -283.277658) (xy 177.368311 -283.31175)
			(xy 177.327808 -283.339706) (xy 177.283346 -283.360804) (xy 177.236075 -283.374496) (xy 177.18722 -283.380428)
			(xy 177.138045 -283.378447) (xy 177.089826 -283.368603) (xy 177.04381 -283.351151) (xy 177.001189 -283.326544)
			(xy 176.963068 -283.295419) (xy 176.930433 -283.258582) (xy 176.90413 -283.216986) (xy 176.884839 -283.17171)
			(xy 176.873062 -283.123926) (xy 176.869102 -283.074872) (xy 176.530254 -283.074872) (xy 176.529759 -283.099479)
			(xy 176.521864 -283.148056) (xy 176.50628 -283.194737) (xy 176.483409 -283.238314) (xy 176.453844 -283.277658)
			(xy 176.418351 -283.31175) (xy 176.377848 -283.339706) (xy 176.333386 -283.360804) (xy 176.286115 -283.374496)
			(xy 176.23726 -283.380428) (xy 176.188085 -283.378447) (xy 176.139866 -283.368603) (xy 176.09385 -283.351151)
			(xy 176.051229 -283.326544) (xy 176.013108 -283.295419) (xy 175.980473 -283.258582) (xy 175.95417 -283.216986)
			(xy 175.934879 -283.17171) (xy 175.923102 -283.123926) (xy 175.919142 -283.074872) (xy 174.630334 -283.074872)
			(xy 174.629839 -283.099479) (xy 174.621944 -283.148056) (xy 174.60636 -283.194737) (xy 174.583489 -283.238314)
			(xy 174.553924 -283.277658) (xy 174.518431 -283.31175) (xy 174.477928 -283.339706) (xy 174.433466 -283.360804)
			(xy 174.386195 -283.374496) (xy 174.33734 -283.380428) (xy 174.288165 -283.378447) (xy 174.239946 -283.368603)
			(xy 174.19393 -283.351151) (xy 174.151309 -283.326544) (xy 174.113188 -283.295419) (xy 174.080553 -283.258582)
			(xy 174.05425 -283.216986) (xy 174.034959 -283.17171) (xy 174.023182 -283.123926) (xy 174.019222 -283.074872)
			(xy 173.680374 -283.074872) (xy 173.679879 -283.099479) (xy 173.671984 -283.148056) (xy 173.6564 -283.194737)
			(xy 173.633529 -283.238314) (xy 173.603964 -283.277658) (xy 173.568471 -283.31175) (xy 173.527968 -283.339706)
			(xy 173.483506 -283.360804) (xy 173.436235 -283.374496) (xy 173.38738 -283.380428) (xy 173.338205 -283.378447)
			(xy 173.289986 -283.368603) (xy 173.24397 -283.351151) (xy 173.201349 -283.326544) (xy 173.163228 -283.295419)
			(xy 173.130593 -283.258582) (xy 173.10429 -283.216986) (xy 173.084999 -283.17171) (xy 173.073222 -283.123926)
			(xy 173.069262 -283.074872) (xy 172.730414 -283.074872) (xy 172.729919 -283.099479) (xy 172.722024 -283.148056)
			(xy 172.70644 -283.194737) (xy 172.683569 -283.238314) (xy 172.654004 -283.277658) (xy 172.618511 -283.31175)
			(xy 172.578008 -283.339706) (xy 172.533546 -283.360804) (xy 172.486275 -283.374496) (xy 172.43742 -283.380428)
			(xy 172.388245 -283.378447) (xy 172.340026 -283.368603) (xy 172.29401 -283.351151) (xy 172.251389 -283.326544)
			(xy 172.213268 -283.295419) (xy 172.180633 -283.258582) (xy 172.15433 -283.216986) (xy 172.135039 -283.17171)
			(xy 172.123262 -283.123926) (xy 172.119302 -283.074872) (xy 171.7802 -283.074872) (xy 171.779705 -283.099479)
			(xy 171.77181 -283.148056) (xy 171.756226 -283.194737) (xy 171.733355 -283.238314) (xy 171.70379 -283.277658)
			(xy 171.668297 -283.31175) (xy 171.627794 -283.339706) (xy 171.583332 -283.360804) (xy 171.536061 -283.374496)
			(xy 171.487206 -283.380428) (xy 171.438031 -283.378447) (xy 171.389812 -283.368603) (xy 171.343796 -283.351151)
			(xy 171.301175 -283.326544) (xy 171.263054 -283.295419) (xy 171.230419 -283.258582) (xy 171.204116 -283.216986)
			(xy 171.184825 -283.17171) (xy 171.173048 -283.123926) (xy 171.169088 -283.074872) (xy 170.83024 -283.074872)
			(xy 170.829745 -283.099479) (xy 170.82185 -283.148056) (xy 170.806266 -283.194737) (xy 170.783395 -283.238314)
			(xy 170.75383 -283.277658) (xy 170.718337 -283.31175) (xy 170.677834 -283.339706) (xy 170.633372 -283.360804)
			(xy 170.586101 -283.374496) (xy 170.537246 -283.380428) (xy 170.488071 -283.378447) (xy 170.439852 -283.368603)
			(xy 170.393836 -283.351151) (xy 170.351215 -283.326544) (xy 170.313094 -283.295419) (xy 170.280459 -283.258582)
			(xy 170.254156 -283.216986) (xy 170.234865 -283.17171) (xy 170.223088 -283.123926) (xy 170.219128 -283.074872)
			(xy 169.88028 -283.074872) (xy 169.879785 -283.099479) (xy 169.87189 -283.148056) (xy 169.856306 -283.194737)
			(xy 169.833435 -283.238314) (xy 169.80387 -283.277658) (xy 169.768377 -283.31175) (xy 169.727874 -283.339706)
			(xy 169.683412 -283.360804) (xy 169.636141 -283.374496) (xy 169.587286 -283.380428) (xy 169.538111 -283.378447)
			(xy 169.489892 -283.368603) (xy 169.443876 -283.351151) (xy 169.401255 -283.326544) (xy 169.363134 -283.295419)
			(xy 169.330499 -283.258582) (xy 169.304196 -283.216986) (xy 169.284905 -283.17171) (xy 169.273128 -283.123926)
			(xy 169.269168 -283.074872) (xy 168.93032 -283.074872) (xy 168.929825 -283.099479) (xy 168.92193 -283.148056)
			(xy 168.906346 -283.194737) (xy 168.883475 -283.238314) (xy 168.85391 -283.277658) (xy 168.818417 -283.31175)
			(xy 168.777914 -283.339706) (xy 168.733452 -283.360804) (xy 168.686181 -283.374496) (xy 168.637326 -283.380428)
			(xy 168.588151 -283.378447) (xy 168.539932 -283.368603) (xy 168.493916 -283.351151) (xy 168.451295 -283.326544)
			(xy 168.413174 -283.295419) (xy 168.380539 -283.258582) (xy 168.354236 -283.216986) (xy 168.334945 -283.17171)
			(xy 168.323168 -283.123926) (xy 168.319208 -283.074872) (xy 167.98036 -283.074872) (xy 167.979865 -283.099479)
			(xy 167.97197 -283.148056) (xy 167.956386 -283.194737) (xy 167.933515 -283.238314) (xy 167.90395 -283.277658)
			(xy 167.868457 -283.31175) (xy 167.827954 -283.339706) (xy 167.783492 -283.360804) (xy 167.736221 -283.374496)
			(xy 167.687366 -283.380428) (xy 167.638191 -283.378447) (xy 167.589972 -283.368603) (xy 167.543956 -283.351151)
			(xy 167.501335 -283.326544) (xy 167.463214 -283.295419) (xy 167.430579 -283.258582) (xy 167.404276 -283.216986)
			(xy 167.384985 -283.17171) (xy 167.373208 -283.123926) (xy 167.369248 -283.074872) (xy 167.0304 -283.074872)
			(xy 167.029905 -283.099479) (xy 167.02201 -283.148056) (xy 167.006426 -283.194737) (xy 166.983555 -283.238314)
			(xy 166.95399 -283.277658) (xy 166.918497 -283.31175) (xy 166.877994 -283.339706) (xy 166.833532 -283.360804)
			(xy 166.786261 -283.374496) (xy 166.737406 -283.380428) (xy 166.688231 -283.378447) (xy 166.640012 -283.368603)
			(xy 166.593996 -283.351151) (xy 166.551375 -283.326544) (xy 166.513254 -283.295419) (xy 166.480619 -283.258582)
			(xy 166.454316 -283.216986) (xy 166.435025 -283.17171) (xy 166.423248 -283.123926) (xy 166.419288 -283.074872)
			(xy 166.080186 -283.074872) (xy 166.079691 -283.099479) (xy 166.071796 -283.148056) (xy 166.056212 -283.194737)
			(xy 166.033341 -283.238314) (xy 166.003776 -283.277658) (xy 165.968283 -283.31175) (xy 165.92778 -283.339706)
			(xy 165.883318 -283.360804) (xy 165.836047 -283.374496) (xy 165.787192 -283.380428) (xy 165.738017 -283.378447)
			(xy 165.689798 -283.368603) (xy 165.643782 -283.351151) (xy 165.601161 -283.326544) (xy 165.56304 -283.295419)
			(xy 165.530405 -283.258582) (xy 165.504102 -283.216986) (xy 165.484811 -283.17171) (xy 165.473034 -283.123926)
			(xy 165.469074 -283.074872) (xy 165.130226 -283.074872) (xy 165.129731 -283.099479) (xy 165.121836 -283.148056)
			(xy 165.106252 -283.194737) (xy 165.083381 -283.238314) (xy 165.053816 -283.277658) (xy 165.018323 -283.31175)
			(xy 164.97782 -283.339706) (xy 164.933358 -283.360804) (xy 164.886087 -283.374496) (xy 164.837232 -283.380428)
			(xy 164.788057 -283.378447) (xy 164.739838 -283.368603) (xy 164.693822 -283.351151) (xy 164.651201 -283.326544)
			(xy 164.61308 -283.295419) (xy 164.580445 -283.258582) (xy 164.554142 -283.216986) (xy 164.534851 -283.17171)
			(xy 164.523074 -283.123926) (xy 164.519114 -283.074872) (xy 164.180266 -283.074872) (xy 164.179771 -283.099479)
			(xy 164.171876 -283.148056) (xy 164.156292 -283.194737) (xy 164.133421 -283.238314) (xy 164.103856 -283.277658)
			(xy 164.068363 -283.31175) (xy 164.02786 -283.339706) (xy 163.983398 -283.360804) (xy 163.936127 -283.374496)
			(xy 163.887272 -283.380428) (xy 163.838097 -283.378447) (xy 163.789878 -283.368603) (xy 163.743862 -283.351151)
			(xy 163.701241 -283.326544) (xy 163.66312 -283.295419) (xy 163.630485 -283.258582) (xy 163.604182 -283.216986)
			(xy 163.584891 -283.17171) (xy 163.573114 -283.123926) (xy 163.569154 -283.074872) (xy 163.230306 -283.074872)
			(xy 163.229811 -283.099479) (xy 163.221916 -283.148056) (xy 163.206332 -283.194737) (xy 163.183461 -283.238314)
			(xy 163.153896 -283.277658) (xy 163.118403 -283.31175) (xy 163.0779 -283.339706) (xy 163.033438 -283.360804)
			(xy 162.986167 -283.374496) (xy 162.937312 -283.380428) (xy 162.888137 -283.378447) (xy 162.839918 -283.368603)
			(xy 162.793902 -283.351151) (xy 162.751281 -283.326544) (xy 162.71316 -283.295419) (xy 162.680525 -283.258582)
			(xy 162.654222 -283.216986) (xy 162.634931 -283.17171) (xy 162.623154 -283.123926) (xy 162.619194 -283.074872)
			(xy 162.280346 -283.074872) (xy 162.279851 -283.099479) (xy 162.271956 -283.148056) (xy 162.256372 -283.194737)
			(xy 162.233501 -283.238314) (xy 162.203936 -283.277658) (xy 162.168443 -283.31175) (xy 162.12794 -283.339706)
			(xy 162.083478 -283.360804) (xy 162.036207 -283.374496) (xy 161.987352 -283.380428) (xy 161.938177 -283.378447)
			(xy 161.889958 -283.368603) (xy 161.843942 -283.351151) (xy 161.801321 -283.326544) (xy 161.7632 -283.295419)
			(xy 161.730565 -283.258582) (xy 161.704262 -283.216986) (xy 161.684971 -283.17171) (xy 161.673194 -283.123926)
			(xy 161.669234 -283.074872) (xy 161.330386 -283.074872) (xy 161.329891 -283.099479) (xy 161.321996 -283.148056)
			(xy 161.306412 -283.194737) (xy 161.283541 -283.238314) (xy 161.253976 -283.277658) (xy 161.218483 -283.31175)
			(xy 161.17798 -283.339706) (xy 161.133518 -283.360804) (xy 161.086247 -283.374496) (xy 161.037392 -283.380428)
			(xy 160.988217 -283.378447) (xy 160.939998 -283.368603) (xy 160.893982 -283.351151) (xy 160.851361 -283.326544)
			(xy 160.81324 -283.295419) (xy 160.780605 -283.258582) (xy 160.754302 -283.216986) (xy 160.735011 -283.17171)
			(xy 160.723234 -283.123926) (xy 160.719274 -283.074872) (xy 160.380172 -283.074872) (xy 160.379677 -283.099479)
			(xy 160.371782 -283.148056) (xy 160.356198 -283.194737) (xy 160.333327 -283.238314) (xy 160.303762 -283.277658)
			(xy 160.268269 -283.31175) (xy 160.227766 -283.339706) (xy 160.183304 -283.360804) (xy 160.136033 -283.374496)
			(xy 160.087178 -283.380428) (xy 160.038003 -283.378447) (xy 159.989784 -283.368603) (xy 159.943768 -283.351151)
			(xy 159.901147 -283.326544) (xy 159.863026 -283.295419) (xy 159.830391 -283.258582) (xy 159.804088 -283.216986)
			(xy 159.784797 -283.17171) (xy 159.77302 -283.123926) (xy 159.76906 -283.074872) (xy 159.430212 -283.074872)
			(xy 159.429717 -283.099479) (xy 159.421822 -283.148056) (xy 159.406238 -283.194737) (xy 159.383367 -283.238314)
			(xy 159.353802 -283.277658) (xy 159.318309 -283.31175) (xy 159.277806 -283.339706) (xy 159.233344 -283.360804)
			(xy 159.186073 -283.374496) (xy 159.137218 -283.380428) (xy 159.088043 -283.378447) (xy 159.039824 -283.368603)
			(xy 158.993808 -283.351151) (xy 158.951187 -283.326544) (xy 158.913066 -283.295419) (xy 158.880431 -283.258582)
			(xy 158.854128 -283.216986) (xy 158.834837 -283.17171) (xy 158.82306 -283.123926) (xy 158.8191 -283.074872)
			(xy 158.480252 -283.074872) (xy 158.479757 -283.099479) (xy 158.471862 -283.148056) (xy 158.456278 -283.194737)
			(xy 158.433407 -283.238314) (xy 158.403842 -283.277658) (xy 158.368349 -283.31175) (xy 158.327846 -283.339706)
			(xy 158.283384 -283.360804) (xy 158.236113 -283.374496) (xy 158.187258 -283.380428) (xy 158.138083 -283.378447)
			(xy 158.089864 -283.368603) (xy 158.043848 -283.351151) (xy 158.001227 -283.326544) (xy 157.963106 -283.295419)
			(xy 157.930471 -283.258582) (xy 157.904168 -283.216986) (xy 157.884877 -283.17171) (xy 157.8731 -283.123926)
			(xy 157.86914 -283.074872) (xy 157.530292 -283.074872) (xy 157.529797 -283.099479) (xy 157.521902 -283.148056)
			(xy 157.506318 -283.194737) (xy 157.483447 -283.238314) (xy 157.453882 -283.277658) (xy 157.418389 -283.31175)
			(xy 157.377886 -283.339706) (xy 157.333424 -283.360804) (xy 157.286153 -283.374496) (xy 157.237298 -283.380428)
			(xy 157.188123 -283.378447) (xy 157.139904 -283.368603) (xy 157.093888 -283.351151) (xy 157.051267 -283.326544)
			(xy 157.013146 -283.295419) (xy 156.980511 -283.258582) (xy 156.954208 -283.216986) (xy 156.934917 -283.17171)
			(xy 156.92314 -283.123926) (xy 156.91918 -283.074872) (xy 156.580332 -283.074872) (xy 156.579837 -283.099479)
			(xy 156.571942 -283.148056) (xy 156.556358 -283.194737) (xy 156.533487 -283.238314) (xy 156.503922 -283.277658)
			(xy 156.468429 -283.31175) (xy 156.427926 -283.339706) (xy 156.383464 -283.360804) (xy 156.336193 -283.374496)
			(xy 156.287338 -283.380428) (xy 156.238163 -283.378447) (xy 156.189944 -283.368603) (xy 156.143928 -283.351151)
			(xy 156.101307 -283.326544) (xy 156.063186 -283.295419) (xy 156.030551 -283.258582) (xy 156.004248 -283.216986)
			(xy 155.984957 -283.17171) (xy 155.97318 -283.123926) (xy 155.96922 -283.074872) (xy 155.630372 -283.074872)
			(xy 155.629877 -283.099479) (xy 155.621982 -283.148056) (xy 155.606398 -283.194737) (xy 155.583527 -283.238314)
			(xy 155.553962 -283.277658) (xy 155.518469 -283.31175) (xy 155.477966 -283.339706) (xy 155.433504 -283.360804)
			(xy 155.386233 -283.374496) (xy 155.337378 -283.380428) (xy 155.288203 -283.378447) (xy 155.239984 -283.368603)
			(xy 155.193968 -283.351151) (xy 155.151347 -283.326544) (xy 155.113226 -283.295419) (xy 155.080591 -283.258582)
			(xy 155.054288 -283.216986) (xy 155.034997 -283.17171) (xy 155.02322 -283.123926) (xy 155.01926 -283.074872)
			(xy 154.680412 -283.074872) (xy 154.679917 -283.099479) (xy 154.672022 -283.148056) (xy 154.656438 -283.194737)
			(xy 154.633567 -283.238314) (xy 154.604002 -283.277658) (xy 154.568509 -283.31175) (xy 154.528006 -283.339706)
			(xy 154.483544 -283.360804) (xy 154.436273 -283.374496) (xy 154.387418 -283.380428) (xy 154.338243 -283.378447)
			(xy 154.290024 -283.368603) (xy 154.244008 -283.351151) (xy 154.201387 -283.326544) (xy 154.163266 -283.295419)
			(xy 154.130631 -283.258582) (xy 154.104328 -283.216986) (xy 154.085037 -283.17171) (xy 154.07326 -283.123926)
			(xy 154.0693 -283.074872) (xy 153.730198 -283.074872) (xy 153.729703 -283.099479) (xy 153.721808 -283.148056)
			(xy 153.706224 -283.194737) (xy 153.683353 -283.238314) (xy 153.653788 -283.277658) (xy 153.618295 -283.31175)
			(xy 153.577792 -283.339706) (xy 153.53333 -283.360804) (xy 153.486059 -283.374496) (xy 153.437204 -283.380428)
			(xy 153.388029 -283.378447) (xy 153.33981 -283.368603) (xy 153.293794 -283.351151) (xy 153.251173 -283.326544)
			(xy 153.213052 -283.295419) (xy 153.180417 -283.258582) (xy 153.154114 -283.216986) (xy 153.134823 -283.17171)
			(xy 153.123046 -283.123926) (xy 153.119086 -283.074872) (xy 152.780238 -283.074872) (xy 152.779743 -283.099479)
			(xy 152.771848 -283.148056) (xy 152.756264 -283.194737) (xy 152.733393 -283.238314) (xy 152.703828 -283.277658)
			(xy 152.668335 -283.31175) (xy 152.627832 -283.339706) (xy 152.58337 -283.360804) (xy 152.536099 -283.374496)
			(xy 152.487244 -283.380428) (xy 152.438069 -283.378447) (xy 152.38985 -283.368603) (xy 152.343834 -283.351151)
			(xy 152.301213 -283.326544) (xy 152.263092 -283.295419) (xy 152.230457 -283.258582) (xy 152.204154 -283.216986)
			(xy 152.184863 -283.17171) (xy 152.173086 -283.123926) (xy 152.169126 -283.074872) (xy 148.207845 -283.074872)
			(xy 148.21207 -283.104263) (xy 148.212556 -283.131514) (xy 148.212006 -283.160896) (xy 148.202975 -283.218961)
			(xy 148.185143 -283.274954) (xy 148.158933 -283.327549) (xy 148.124966 -283.375501) (xy 148.084044 -283.417674)
			(xy 148.060918 -283.435806) (xy 148.05152 -283.443172) (xy 148.041106 -283.463746) (xy 148.039582 -283.567632)
			(xy 148.049488 -283.588714) (xy 148.058632 -283.59608) (xy 148.080459 -283.614309) (xy 148.118999 -283.656124)
			(xy 148.150908 -283.703195) (xy 148.175478 -283.75448) (xy 148.192166 -283.808843) (xy 148.200603 -283.865081)
			(xy 148.201126 -283.893514) (xy 148.8346 -283.893514) (xy 148.838671 -283.837892) (xy 148.850797 -283.783455)
			(xy 148.87072 -283.731364) (xy 148.898016 -283.682729) (xy 148.932102 -283.638586) (xy 148.972251 -283.599877)
			(xy 149.017609 -283.567426) (xy 149.067209 -283.541925) (xy 149.119993 -283.523918) (xy 149.174836 -283.513788)
			(xy 149.23057 -283.511751) (xy 149.286007 -283.517851) (xy 149.339964 -283.531957) (xy 149.391293 -283.553769)
			(xy 149.438899 -283.582823) (xy 149.481767 -283.618498) (xy 149.518984 -283.660035) (xy 149.549757 -283.706548)
			(xy 149.573429 -283.757045) (xy 149.589497 -283.810452) (xy 149.597617 -283.865628) (xy 149.598126 -283.893514)
			(xy 149.72106 -283.893514) (xy 149.725131 -283.837892) (xy 149.737257 -283.783455) (xy 149.75718 -283.731364)
			(xy 149.784476 -283.682729) (xy 149.818562 -283.638586) (xy 149.858711 -283.599877) (xy 149.904069 -283.567426)
			(xy 149.953669 -283.541925) (xy 150.006453 -283.523918) (xy 150.061296 -283.513788) (xy 150.11703 -283.511751)
			(xy 150.172467 -283.517851) (xy 150.226424 -283.531957) (xy 150.268535 -283.549852) (xy 189.69407 -283.549852)
			(xy 189.69803 -283.500798) (xy 189.709807 -283.453014) (xy 189.729098 -283.407738) (xy 189.755401 -283.366142)
			(xy 189.788036 -283.329305) (xy 189.826157 -283.29818) (xy 189.868778 -283.273573) (xy 189.914794 -283.256121)
			(xy 189.963013 -283.246277) (xy 190.012188 -283.244296) (xy 190.061043 -283.250228) (xy 190.108314 -283.26392)
			(xy 190.152776 -283.285018) (xy 190.193279 -283.312974) (xy 190.228772 -283.347066) (xy 190.258337 -283.38641)
			(xy 190.281208 -283.429987) (xy 190.296792 -283.476668) (xy 190.304687 -283.525245) (xy 190.305182 -283.549852)
			(xy 190.304687 -283.574459) (xy 190.304508 -283.57556) (xy 190.623186 -283.57556) (xy 190.623186 -283.524144)
			(xy 190.631229 -283.473362) (xy 190.647117 -283.424463) (xy 190.67046 -283.378651) (xy 190.700681 -283.337055)
			(xy 190.737037 -283.300699) (xy 190.778633 -283.270478) (xy 190.824445 -283.247135) (xy 190.873344 -283.231247)
			(xy 190.924126 -283.223204) (xy 190.975542 -283.223204) (xy 191.026324 -283.231247) (xy 191.075223 -283.247135)
			(xy 191.121035 -283.270478) (xy 191.162631 -283.300699) (xy 191.198987 -283.337055) (xy 191.229208 -283.378651)
			(xy 191.252551 -283.424463) (xy 191.268439 -283.473362) (xy 191.276482 -283.524144) (xy 191.276986 -283.549852)
			(xy 191.276482 -283.57556) (xy 191.5734 -283.57556) (xy 191.5734 -283.524144) (xy 191.581443 -283.473362)
			(xy 191.597331 -283.424463) (xy 191.620674 -283.378651) (xy 191.650895 -283.337055) (xy 191.687251 -283.300699)
			(xy 191.728847 -283.270478) (xy 191.774659 -283.247135) (xy 191.823558 -283.231247) (xy 191.87434 -283.223204)
			(xy 191.925756 -283.223204) (xy 191.976538 -283.231247) (xy 192.025437 -283.247135) (xy 192.071249 -283.270478)
			(xy 192.112845 -283.300699) (xy 192.149201 -283.337055) (xy 192.179422 -283.378651) (xy 192.202765 -283.424463)
			(xy 192.218653 -283.473362) (xy 192.226696 -283.524144) (xy 192.2272 -283.549852) (xy 192.544204 -283.549852)
			(xy 192.548164 -283.500798) (xy 192.559941 -283.453014) (xy 192.579232 -283.407738) (xy 192.605535 -283.366142)
			(xy 192.63817 -283.329305) (xy 192.676291 -283.29818) (xy 192.718912 -283.273573) (xy 192.764928 -283.256121)
			(xy 192.813147 -283.246277) (xy 192.862322 -283.244296) (xy 192.911177 -283.250228) (xy 192.958448 -283.26392)
			(xy 193.00291 -283.285018) (xy 193.043413 -283.312974) (xy 193.078906 -283.347066) (xy 193.108471 -283.38641)
			(xy 193.131342 -283.429987) (xy 193.146926 -283.476668) (xy 193.154821 -283.525245) (xy 193.155316 -283.549852)
			(xy 193.494164 -283.549852) (xy 193.498124 -283.500798) (xy 193.509901 -283.453014) (xy 193.529192 -283.407738)
			(xy 193.555495 -283.366142) (xy 193.58813 -283.329305) (xy 193.626251 -283.29818) (xy 193.668872 -283.273573)
			(xy 193.714888 -283.256121) (xy 193.763107 -283.246277) (xy 193.812282 -283.244296) (xy 193.861137 -283.250228)
			(xy 193.908408 -283.26392) (xy 193.95287 -283.285018) (xy 193.993373 -283.312974) (xy 194.028866 -283.347066)
			(xy 194.058431 -283.38641) (xy 194.081302 -283.429987) (xy 194.096886 -283.476668) (xy 194.104781 -283.525245)
			(xy 194.105276 -283.549852) (xy 194.444124 -283.549852) (xy 194.448084 -283.500798) (xy 194.459861 -283.453014)
			(xy 194.479152 -283.407738) (xy 194.505455 -283.366142) (xy 194.53809 -283.329305) (xy 194.576211 -283.29818)
			(xy 194.618832 -283.273573) (xy 194.664848 -283.256121) (xy 194.713067 -283.246277) (xy 194.762242 -283.244296)
			(xy 194.811097 -283.250228) (xy 194.858368 -283.26392) (xy 194.90283 -283.285018) (xy 194.943333 -283.312974)
			(xy 194.978826 -283.347066) (xy 195.008391 -283.38641) (xy 195.031262 -283.429987) (xy 195.046846 -283.476668)
			(xy 195.054741 -283.525245) (xy 195.055236 -283.549852) (xy 195.394084 -283.549852) (xy 195.398044 -283.500798)
			(xy 195.409821 -283.453014) (xy 195.429112 -283.407738) (xy 195.455415 -283.366142) (xy 195.48805 -283.329305)
			(xy 195.526171 -283.29818) (xy 195.568792 -283.273573) (xy 195.614808 -283.256121) (xy 195.663027 -283.246277)
			(xy 195.712202 -283.244296) (xy 195.761057 -283.250228) (xy 195.808328 -283.26392) (xy 195.85279 -283.285018)
			(xy 195.893293 -283.312974) (xy 195.928786 -283.347066) (xy 195.958351 -283.38641) (xy 195.981222 -283.429987)
			(xy 195.996806 -283.476668) (xy 196.004701 -283.525245) (xy 196.005196 -283.549852) (xy 196.344044 -283.549852)
			(xy 196.348004 -283.500798) (xy 196.359781 -283.453014) (xy 196.379072 -283.407738) (xy 196.405375 -283.366142)
			(xy 196.43801 -283.329305) (xy 196.476131 -283.29818) (xy 196.518752 -283.273573) (xy 196.564768 -283.256121)
			(xy 196.612987 -283.246277) (xy 196.662162 -283.244296) (xy 196.711017 -283.250228) (xy 196.758288 -283.26392)
			(xy 196.80275 -283.285018) (xy 196.843253 -283.312974) (xy 196.878746 -283.347066) (xy 196.908311 -283.38641)
			(xy 196.931182 -283.429987) (xy 196.946766 -283.476668) (xy 196.954661 -283.525245) (xy 196.955156 -283.549852)
			(xy 196.954661 -283.574459) (xy 196.954482 -283.57556) (xy 197.273414 -283.57556) (xy 197.273414 -283.524144)
			(xy 197.281457 -283.473362) (xy 197.297345 -283.424463) (xy 197.320688 -283.378651) (xy 197.350909 -283.337055)
			(xy 197.387265 -283.300699) (xy 197.428861 -283.270478) (xy 197.474673 -283.247135) (xy 197.523572 -283.231247)
			(xy 197.574354 -283.223204) (xy 197.62577 -283.223204) (xy 197.676552 -283.231247) (xy 197.725451 -283.247135)
			(xy 197.771263 -283.270478) (xy 197.812859 -283.300699) (xy 197.849215 -283.337055) (xy 197.879436 -283.378651)
			(xy 197.902779 -283.424463) (xy 197.918667 -283.473362) (xy 197.92671 -283.524144) (xy 197.927214 -283.549852)
			(xy 197.92671 -283.57556) (xy 198.223374 -283.57556) (xy 198.223374 -283.524144) (xy 198.231417 -283.473362)
			(xy 198.247305 -283.424463) (xy 198.270648 -283.378651) (xy 198.300869 -283.337055) (xy 198.337225 -283.300699)
			(xy 198.378821 -283.270478) (xy 198.424633 -283.247135) (xy 198.473532 -283.231247) (xy 198.524314 -283.223204)
			(xy 198.57573 -283.223204) (xy 198.626512 -283.231247) (xy 198.675411 -283.247135) (xy 198.721223 -283.270478)
			(xy 198.762819 -283.300699) (xy 198.799175 -283.337055) (xy 198.829396 -283.378651) (xy 198.852739 -283.424463)
			(xy 198.868627 -283.473362) (xy 198.87667 -283.524144) (xy 198.877174 -283.549852) (xy 198.877169 -283.550106)
			(xy 199.194432 -283.550106) (xy 199.198392 -283.501052) (xy 199.210169 -283.453268) (xy 199.22946 -283.407992)
			(xy 199.255763 -283.366396) (xy 199.288398 -283.329559) (xy 199.326519 -283.298434) (xy 199.36914 -283.273827)
			(xy 199.415156 -283.256375) (xy 199.463375 -283.246531) (xy 199.51255 -283.24455) (xy 199.561405 -283.250482)
			(xy 199.608676 -283.264174) (xy 199.653138 -283.285272) (xy 199.693641 -283.313228) (xy 199.729134 -283.34732)
			(xy 199.758699 -283.386664) (xy 199.78157 -283.430241) (xy 199.797154 -283.476922) (xy 199.805049 -283.525499)
			(xy 199.805544 -283.550106) (xy 199.805444 -283.555057) (xy 209.894309 -283.555057) (xy 209.894309 -283.500543)
			(xy 209.902068 -283.446583) (xy 209.917427 -283.394277) (xy 209.940074 -283.344689) (xy 209.969548 -283.298829)
			(xy 210.005248 -283.257631) (xy 210.046449 -283.221933) (xy 210.09231 -283.192462) (xy 210.1419 -283.169818)
			(xy 210.194207 -283.154462) (xy 210.248167 -283.146707) (xy 210.275424 -283.146246) (xy 210.302795 -283.146687)
			(xy 210.356976 -283.154509) (xy 210.40948 -283.170003) (xy 210.459226 -283.192851) (xy 210.505192 -283.222582)
			(xy 210.526122 -283.240226) (xy 210.533234 -283.246322) (xy 210.550252 -283.252672) (xy 210.635596 -283.252672)
			(xy 210.652614 -283.246322) (xy 210.659726 -283.240226) (xy 210.680679 -283.222612) (xy 210.726645 -283.192896)
			(xy 210.776388 -283.170054) (xy 210.828884 -283.154558) (xy 210.883056 -283.146723) (xy 210.910424 -283.146246)
			(xy 210.937671 -283.146826) (xy 210.991609 -283.154584) (xy 211.043895 -283.169939) (xy 211.093463 -283.192579)
			(xy 211.139305 -283.222043) (xy 211.180487 -283.25773) (xy 211.216172 -283.298914) (xy 211.245632 -283.344758)
			(xy 211.268269 -283.394328) (xy 211.283621 -283.446614) (xy 211.291376 -283.500553) (xy 211.291376 -283.555047)
			(xy 211.283621 -283.608986) (xy 211.268269 -283.661272) (xy 211.245632 -283.710842) (xy 211.216172 -283.756686)
			(xy 211.180487 -283.79787) (xy 211.139305 -283.833557) (xy 211.093463 -283.863021) (xy 211.043895 -283.885661)
			(xy 210.991609 -283.901016) (xy 210.937671 -283.908774) (xy 210.910424 -283.909262) (xy 210.883054 -283.908791)
			(xy 210.828875 -283.900976) (xy 210.776371 -283.885488) (xy 210.726624 -283.862648) (xy 210.680657 -283.832923)
			(xy 210.659726 -283.815282) (xy 210.652614 -283.809186) (xy 210.635596 -283.802836) (xy 210.550252 -283.802836)
			(xy 210.533234 -283.809186) (xy 210.526122 -283.815282) (xy 210.50519 -283.832921) (xy 210.459218 -283.862634)
			(xy 210.40947 -283.88547) (xy 210.356969 -283.900961) (xy 210.302793 -283.908788) (xy 210.275424 -283.909262)
			(xy 210.248167 -283.908893) (xy 210.194207 -283.901138) (xy 210.1419 -283.885782) (xy 210.09231 -283.863138)
			(xy 210.046449 -283.833667) (xy 210.005248 -283.797969) (xy 209.969548 -283.756771) (xy 209.940074 -283.710911)
			(xy 209.917427 -283.661323) (xy 209.902068 -283.609017) (xy 209.894309 -283.555057) (xy 199.805444 -283.555057)
			(xy 199.805049 -283.574713) (xy 199.797154 -283.62329) (xy 199.78157 -283.669971) (xy 199.758699 -283.713548)
			(xy 199.729134 -283.752892) (xy 199.693641 -283.786984) (xy 199.653138 -283.81494) (xy 199.608676 -283.836038)
			(xy 199.561405 -283.84973) (xy 199.51255 -283.855662) (xy 199.463375 -283.853681) (xy 199.415156 -283.843837)
			(xy 199.36914 -283.826385) (xy 199.326519 -283.801778) (xy 199.288398 -283.770653) (xy 199.255763 -283.733816)
			(xy 199.22946 -283.69222) (xy 199.210169 -283.646944) (xy 199.198392 -283.59916) (xy 199.194432 -283.550106)
			(xy 198.877169 -283.550106) (xy 198.87667 -283.57556) (xy 198.868627 -283.626342) (xy 198.852739 -283.675241)
			(xy 198.829396 -283.721053) (xy 198.799175 -283.762649) (xy 198.762819 -283.799005) (xy 198.721223 -283.829226)
			(xy 198.675411 -283.852569) (xy 198.626512 -283.868457) (xy 198.57573 -283.8765) (xy 198.524314 -283.8765)
			(xy 198.473532 -283.868457) (xy 198.424633 -283.852569) (xy 198.378821 -283.829226) (xy 198.337225 -283.799005)
			(xy 198.300869 -283.762649) (xy 198.270648 -283.721053) (xy 198.247305 -283.675241) (xy 198.231417 -283.626342)
			(xy 198.223374 -283.57556) (xy 197.92671 -283.57556) (xy 197.918667 -283.626342) (xy 197.902779 -283.675241)
			(xy 197.879436 -283.721053) (xy 197.849215 -283.762649) (xy 197.812859 -283.799005) (xy 197.771263 -283.829226)
			(xy 197.725451 -283.852569) (xy 197.676552 -283.868457) (xy 197.62577 -283.8765) (xy 197.574354 -283.8765)
			(xy 197.523572 -283.868457) (xy 197.474673 -283.852569) (xy 197.428861 -283.829226) (xy 197.387265 -283.799005)
			(xy 197.350909 -283.762649) (xy 197.320688 -283.721053) (xy 197.297345 -283.675241) (xy 197.281457 -283.626342)
			(xy 197.273414 -283.57556) (xy 196.954482 -283.57556) (xy 196.946766 -283.623036) (xy 196.931182 -283.669717)
			(xy 196.908311 -283.713294) (xy 196.878746 -283.752638) (xy 196.843253 -283.78673) (xy 196.80275 -283.814686)
			(xy 196.758288 -283.835784) (xy 196.711017 -283.849476) (xy 196.662162 -283.855408) (xy 196.612987 -283.853427)
			(xy 196.564768 -283.843583) (xy 196.518752 -283.826131) (xy 196.476131 -283.801524) (xy 196.43801 -283.770399)
			(xy 196.405375 -283.733562) (xy 196.379072 -283.691966) (xy 196.359781 -283.64669) (xy 196.348004 -283.598906)
			(xy 196.344044 -283.549852) (xy 196.005196 -283.549852) (xy 196.004701 -283.574459) (xy 195.996806 -283.623036)
			(xy 195.981222 -283.669717) (xy 195.958351 -283.713294) (xy 195.928786 -283.752638) (xy 195.893293 -283.78673)
			(xy 195.85279 -283.814686) (xy 195.808328 -283.835784) (xy 195.761057 -283.849476) (xy 195.712202 -283.855408)
			(xy 195.663027 -283.853427) (xy 195.614808 -283.843583) (xy 195.568792 -283.826131) (xy 195.526171 -283.801524)
			(xy 195.48805 -283.770399) (xy 195.455415 -283.733562) (xy 195.429112 -283.691966) (xy 195.409821 -283.64669)
			(xy 195.398044 -283.598906) (xy 195.394084 -283.549852) (xy 195.055236 -283.549852) (xy 195.054741 -283.574459)
			(xy 195.046846 -283.623036) (xy 195.031262 -283.669717) (xy 195.008391 -283.713294) (xy 194.978826 -283.752638)
			(xy 194.943333 -283.78673) (xy 194.90283 -283.814686) (xy 194.858368 -283.835784) (xy 194.811097 -283.849476)
			(xy 194.762242 -283.855408) (xy 194.713067 -283.853427) (xy 194.664848 -283.843583) (xy 194.618832 -283.826131)
			(xy 194.576211 -283.801524) (xy 194.53809 -283.770399) (xy 194.505455 -283.733562) (xy 194.479152 -283.691966)
			(xy 194.459861 -283.64669) (xy 194.448084 -283.598906) (xy 194.444124 -283.549852) (xy 194.105276 -283.549852)
			(xy 194.104781 -283.574459) (xy 194.096886 -283.623036) (xy 194.081302 -283.669717) (xy 194.058431 -283.713294)
			(xy 194.028866 -283.752638) (xy 193.993373 -283.78673) (xy 193.95287 -283.814686) (xy 193.908408 -283.835784)
			(xy 193.861137 -283.849476) (xy 193.812282 -283.855408) (xy 193.763107 -283.853427) (xy 193.714888 -283.843583)
			(xy 193.668872 -283.826131) (xy 193.626251 -283.801524) (xy 193.58813 -283.770399) (xy 193.555495 -283.733562)
			(xy 193.529192 -283.691966) (xy 193.509901 -283.64669) (xy 193.498124 -283.598906) (xy 193.494164 -283.549852)
			(xy 193.155316 -283.549852) (xy 193.154821 -283.574459) (xy 193.146926 -283.623036) (xy 193.131342 -283.669717)
			(xy 193.108471 -283.713294) (xy 193.078906 -283.752638) (xy 193.043413 -283.78673) (xy 193.00291 -283.814686)
			(xy 192.958448 -283.835784) (xy 192.911177 -283.849476) (xy 192.862322 -283.855408) (xy 192.813147 -283.853427)
			(xy 192.764928 -283.843583) (xy 192.718912 -283.826131) (xy 192.676291 -283.801524) (xy 192.63817 -283.770399)
			(xy 192.605535 -283.733562) (xy 192.579232 -283.691966) (xy 192.559941 -283.64669) (xy 192.548164 -283.598906)
			(xy 192.544204 -283.549852) (xy 192.2272 -283.549852) (xy 192.226696 -283.57556) (xy 192.218653 -283.626342)
			(xy 192.202765 -283.675241) (xy 192.179422 -283.721053) (xy 192.149201 -283.762649) (xy 192.112845 -283.799005)
			(xy 192.071249 -283.829226) (xy 192.025437 -283.852569) (xy 191.976538 -283.868457) (xy 191.925756 -283.8765)
			(xy 191.87434 -283.8765) (xy 191.823558 -283.868457) (xy 191.774659 -283.852569) (xy 191.728847 -283.829226)
			(xy 191.687251 -283.799005) (xy 191.650895 -283.762649) (xy 191.620674 -283.721053) (xy 191.597331 -283.675241)
			(xy 191.581443 -283.626342) (xy 191.5734 -283.57556) (xy 191.276482 -283.57556) (xy 191.268439 -283.626342)
			(xy 191.252551 -283.675241) (xy 191.229208 -283.721053) (xy 191.198987 -283.762649) (xy 191.162631 -283.799005)
			(xy 191.121035 -283.829226) (xy 191.075223 -283.852569) (xy 191.026324 -283.868457) (xy 190.975542 -283.8765)
			(xy 190.924126 -283.8765) (xy 190.873344 -283.868457) (xy 190.824445 -283.852569) (xy 190.778633 -283.829226)
			(xy 190.737037 -283.799005) (xy 190.700681 -283.762649) (xy 190.67046 -283.721053) (xy 190.647117 -283.675241)
			(xy 190.631229 -283.626342) (xy 190.623186 -283.57556) (xy 190.304508 -283.57556) (xy 190.296792 -283.623036)
			(xy 190.281208 -283.669717) (xy 190.258337 -283.713294) (xy 190.228772 -283.752638) (xy 190.193279 -283.78673)
			(xy 190.152776 -283.814686) (xy 190.108314 -283.835784) (xy 190.061043 -283.849476) (xy 190.012188 -283.855408)
			(xy 189.963013 -283.853427) (xy 189.914794 -283.843583) (xy 189.868778 -283.826131) (xy 189.826157 -283.801524)
			(xy 189.788036 -283.770399) (xy 189.755401 -283.733562) (xy 189.729098 -283.691966) (xy 189.709807 -283.64669)
			(xy 189.69803 -283.598906) (xy 189.69407 -283.549852) (xy 150.268535 -283.549852) (xy 150.277753 -283.553769)
			(xy 150.325359 -283.582823) (xy 150.368227 -283.618498) (xy 150.405444 -283.660035) (xy 150.436217 -283.706548)
			(xy 150.459889 -283.757045) (xy 150.475957 -283.810452) (xy 150.484077 -283.865628) (xy 150.484586 -283.893514)
			(xy 150.484077 -283.9214) (xy 150.475957 -283.976576) (xy 150.461439 -284.024832) (xy 152.169126 -284.024832)
			(xy 152.173086 -283.975778) (xy 152.184863 -283.927994) (xy 152.204154 -283.882718) (xy 152.230457 -283.841122)
			(xy 152.263092 -283.804285) (xy 152.301213 -283.77316) (xy 152.343834 -283.748553) (xy 152.38985 -283.731101)
			(xy 152.438069 -283.721257) (xy 152.487244 -283.719276) (xy 152.536099 -283.725208) (xy 152.58337 -283.7389)
			(xy 152.627832 -283.759998) (xy 152.668335 -283.787954) (xy 152.703828 -283.822046) (xy 152.733393 -283.86139)
			(xy 152.756264 -283.904967) (xy 152.771848 -283.951648) (xy 152.779743 -284.000225) (xy 152.780238 -284.024832)
			(xy 153.119086 -284.024832) (xy 153.123046 -283.975778) (xy 153.134823 -283.927994) (xy 153.154114 -283.882718)
			(xy 153.180417 -283.841122) (xy 153.213052 -283.804285) (xy 153.251173 -283.77316) (xy 153.293794 -283.748553)
			(xy 153.33981 -283.731101) (xy 153.388029 -283.721257) (xy 153.437204 -283.719276) (xy 153.486059 -283.725208)
			(xy 153.53333 -283.7389) (xy 153.577792 -283.759998) (xy 153.618295 -283.787954) (xy 153.653788 -283.822046)
			(xy 153.683353 -283.86139) (xy 153.706224 -283.904967) (xy 153.721808 -283.951648) (xy 153.729703 -284.000225)
			(xy 153.730198 -284.024832) (xy 154.0693 -284.024832) (xy 154.07326 -283.975778) (xy 154.085037 -283.927994)
			(xy 154.104328 -283.882718) (xy 154.130631 -283.841122) (xy 154.163266 -283.804285) (xy 154.201387 -283.77316)
			(xy 154.244008 -283.748553) (xy 154.290024 -283.731101) (xy 154.338243 -283.721257) (xy 154.387418 -283.719276)
			(xy 154.436273 -283.725208) (xy 154.483544 -283.7389) (xy 154.528006 -283.759998) (xy 154.568509 -283.787954)
			(xy 154.604002 -283.822046) (xy 154.633567 -283.86139) (xy 154.656438 -283.904967) (xy 154.672022 -283.951648)
			(xy 154.679917 -284.000225) (xy 154.680412 -284.024832) (xy 155.01926 -284.024832) (xy 155.02322 -283.975778)
			(xy 155.034997 -283.927994) (xy 155.054288 -283.882718) (xy 155.080591 -283.841122) (xy 155.113226 -283.804285)
			(xy 155.151347 -283.77316) (xy 155.193968 -283.748553) (xy 155.239984 -283.731101) (xy 155.288203 -283.721257)
			(xy 155.337378 -283.719276) (xy 155.386233 -283.725208) (xy 155.433504 -283.7389) (xy 155.477966 -283.759998)
			(xy 155.518469 -283.787954) (xy 155.553962 -283.822046) (xy 155.583527 -283.86139) (xy 155.606398 -283.904967)
			(xy 155.621982 -283.951648) (xy 155.629877 -284.000225) (xy 155.630372 -284.024832) (xy 155.96922 -284.024832)
			(xy 155.97318 -283.975778) (xy 155.984957 -283.927994) (xy 156.004248 -283.882718) (xy 156.030551 -283.841122)
			(xy 156.063186 -283.804285) (xy 156.101307 -283.77316) (xy 156.143928 -283.748553) (xy 156.189944 -283.731101)
			(xy 156.238163 -283.721257) (xy 156.287338 -283.719276) (xy 156.336193 -283.725208) (xy 156.383464 -283.7389)
			(xy 156.427926 -283.759998) (xy 156.468429 -283.787954) (xy 156.503922 -283.822046) (xy 156.533487 -283.86139)
			(xy 156.556358 -283.904967) (xy 156.571942 -283.951648) (xy 156.579837 -284.000225) (xy 156.580332 -284.024832)
			(xy 158.8191 -284.024832) (xy 158.82306 -283.975778) (xy 158.834837 -283.927994) (xy 158.854128 -283.882718)
			(xy 158.880431 -283.841122) (xy 158.913066 -283.804285) (xy 158.951187 -283.77316) (xy 158.993808 -283.748553)
			(xy 159.039824 -283.731101) (xy 159.088043 -283.721257) (xy 159.137218 -283.719276) (xy 159.186073 -283.725208)
			(xy 159.233344 -283.7389) (xy 159.277806 -283.759998) (xy 159.318309 -283.787954) (xy 159.353802 -283.822046)
			(xy 159.383367 -283.86139) (xy 159.406238 -283.904967) (xy 159.421822 -283.951648) (xy 159.429717 -284.000225)
			(xy 159.430212 -284.024832) (xy 159.76906 -284.024832) (xy 159.77302 -283.975778) (xy 159.784797 -283.927994)
			(xy 159.804088 -283.882718) (xy 159.830391 -283.841122) (xy 159.863026 -283.804285) (xy 159.901147 -283.77316)
			(xy 159.943768 -283.748553) (xy 159.989784 -283.731101) (xy 160.038003 -283.721257) (xy 160.087178 -283.719276)
			(xy 160.136033 -283.725208) (xy 160.183304 -283.7389) (xy 160.227766 -283.759998) (xy 160.268269 -283.787954)
			(xy 160.303762 -283.822046) (xy 160.333327 -283.86139) (xy 160.356198 -283.904967) (xy 160.371782 -283.951648)
			(xy 160.379677 -284.000225) (xy 160.380172 -284.024832) (xy 160.719274 -284.024832) (xy 160.723234 -283.975778)
			(xy 160.735011 -283.927994) (xy 160.754302 -283.882718) (xy 160.780605 -283.841122) (xy 160.81324 -283.804285)
			(xy 160.851361 -283.77316) (xy 160.893982 -283.748553) (xy 160.939998 -283.731101) (xy 160.988217 -283.721257)
			(xy 161.037392 -283.719276) (xy 161.086247 -283.725208) (xy 161.133518 -283.7389) (xy 161.17798 -283.759998)
			(xy 161.218483 -283.787954) (xy 161.253976 -283.822046) (xy 161.283541 -283.86139) (xy 161.306412 -283.904967)
			(xy 161.321996 -283.951648) (xy 161.329891 -284.000225) (xy 161.330386 -284.024832) (xy 161.669234 -284.024832)
			(xy 161.673194 -283.975778) (xy 161.684971 -283.927994) (xy 161.704262 -283.882718) (xy 161.730565 -283.841122)
			(xy 161.7632 -283.804285) (xy 161.801321 -283.77316) (xy 161.843942 -283.748553) (xy 161.889958 -283.731101)
			(xy 161.938177 -283.721257) (xy 161.987352 -283.719276) (xy 162.036207 -283.725208) (xy 162.083478 -283.7389)
			(xy 162.12794 -283.759998) (xy 162.168443 -283.787954) (xy 162.203936 -283.822046) (xy 162.233501 -283.86139)
			(xy 162.256372 -283.904967) (xy 162.271956 -283.951648) (xy 162.279851 -284.000225) (xy 162.280346 -284.024832)
			(xy 162.619194 -284.024832) (xy 162.623154 -283.975778) (xy 162.634931 -283.927994) (xy 162.654222 -283.882718)
			(xy 162.680525 -283.841122) (xy 162.71316 -283.804285) (xy 162.751281 -283.77316) (xy 162.793902 -283.748553)
			(xy 162.839918 -283.731101) (xy 162.888137 -283.721257) (xy 162.937312 -283.719276) (xy 162.986167 -283.725208)
			(xy 163.033438 -283.7389) (xy 163.0779 -283.759998) (xy 163.118403 -283.787954) (xy 163.153896 -283.822046)
			(xy 163.183461 -283.86139) (xy 163.206332 -283.904967) (xy 163.221916 -283.951648) (xy 163.229811 -284.000225)
			(xy 163.230306 -284.024832) (xy 163.569154 -284.024832) (xy 163.573114 -283.975778) (xy 163.584891 -283.927994)
			(xy 163.604182 -283.882718) (xy 163.630485 -283.841122) (xy 163.66312 -283.804285) (xy 163.701241 -283.77316)
			(xy 163.743862 -283.748553) (xy 163.789878 -283.731101) (xy 163.838097 -283.721257) (xy 163.887272 -283.719276)
			(xy 163.936127 -283.725208) (xy 163.983398 -283.7389) (xy 164.02786 -283.759998) (xy 164.068363 -283.787954)
			(xy 164.103856 -283.822046) (xy 164.133421 -283.86139) (xy 164.156292 -283.904967) (xy 164.171876 -283.951648)
			(xy 164.179771 -284.000225) (xy 164.180266 -284.024832) (xy 164.519114 -284.024832) (xy 164.523074 -283.975778)
			(xy 164.534851 -283.927994) (xy 164.554142 -283.882718) (xy 164.580445 -283.841122) (xy 164.61308 -283.804285)
			(xy 164.651201 -283.77316) (xy 164.693822 -283.748553) (xy 164.739838 -283.731101) (xy 164.788057 -283.721257)
			(xy 164.837232 -283.719276) (xy 164.886087 -283.725208) (xy 164.933358 -283.7389) (xy 164.97782 -283.759998)
			(xy 165.018323 -283.787954) (xy 165.053816 -283.822046) (xy 165.083381 -283.86139) (xy 165.106252 -283.904967)
			(xy 165.121836 -283.951648) (xy 165.129731 -284.000225) (xy 165.130226 -284.024832) (xy 165.469074 -284.024832)
			(xy 165.473034 -283.975778) (xy 165.484811 -283.927994) (xy 165.504102 -283.882718) (xy 165.530405 -283.841122)
			(xy 165.56304 -283.804285) (xy 165.601161 -283.77316) (xy 165.643782 -283.748553) (xy 165.689798 -283.731101)
			(xy 165.738017 -283.721257) (xy 165.787192 -283.719276) (xy 165.836047 -283.725208) (xy 165.883318 -283.7389)
			(xy 165.92778 -283.759998) (xy 165.968283 -283.787954) (xy 166.003776 -283.822046) (xy 166.033341 -283.86139)
			(xy 166.056212 -283.904967) (xy 166.071796 -283.951648) (xy 166.079691 -284.000225) (xy 166.080186 -284.024832)
			(xy 166.419288 -284.024832) (xy 166.423248 -283.975778) (xy 166.435025 -283.927994) (xy 166.454316 -283.882718)
			(xy 166.480619 -283.841122) (xy 166.513254 -283.804285) (xy 166.551375 -283.77316) (xy 166.593996 -283.748553)
			(xy 166.640012 -283.731101) (xy 166.688231 -283.721257) (xy 166.737406 -283.719276) (xy 166.786261 -283.725208)
			(xy 166.833532 -283.7389) (xy 166.877994 -283.759998) (xy 166.918497 -283.787954) (xy 166.95399 -283.822046)
			(xy 166.983555 -283.86139) (xy 167.006426 -283.904967) (xy 167.02201 -283.951648) (xy 167.029905 -284.000225)
			(xy 167.0304 -284.024832) (xy 167.369248 -284.024832) (xy 167.373208 -283.975778) (xy 167.384985 -283.927994)
			(xy 167.404276 -283.882718) (xy 167.430579 -283.841122) (xy 167.463214 -283.804285) (xy 167.501335 -283.77316)
			(xy 167.543956 -283.748553) (xy 167.589972 -283.731101) (xy 167.638191 -283.721257) (xy 167.687366 -283.719276)
			(xy 167.736221 -283.725208) (xy 167.783492 -283.7389) (xy 167.827954 -283.759998) (xy 167.868457 -283.787954)
			(xy 167.90395 -283.822046) (xy 167.933515 -283.86139) (xy 167.956386 -283.904967) (xy 167.97197 -283.951648)
			(xy 167.979865 -284.000225) (xy 167.98036 -284.024832) (xy 168.319208 -284.024832) (xy 168.323168 -283.975778)
			(xy 168.334945 -283.927994) (xy 168.354236 -283.882718) (xy 168.380539 -283.841122) (xy 168.413174 -283.804285)
			(xy 168.451295 -283.77316) (xy 168.493916 -283.748553) (xy 168.539932 -283.731101) (xy 168.588151 -283.721257)
			(xy 168.637326 -283.719276) (xy 168.686181 -283.725208) (xy 168.733452 -283.7389) (xy 168.777914 -283.759998)
			(xy 168.818417 -283.787954) (xy 168.85391 -283.822046) (xy 168.883475 -283.86139) (xy 168.906346 -283.904967)
			(xy 168.92193 -283.951648) (xy 168.929825 -284.000225) (xy 168.93032 -284.024832) (xy 169.269168 -284.024832)
			(xy 169.273128 -283.975778) (xy 169.284905 -283.927994) (xy 169.304196 -283.882718) (xy 169.330499 -283.841122)
			(xy 169.363134 -283.804285) (xy 169.401255 -283.77316) (xy 169.443876 -283.748553) (xy 169.489892 -283.731101)
			(xy 169.538111 -283.721257) (xy 169.587286 -283.719276) (xy 169.636141 -283.725208) (xy 169.683412 -283.7389)
			(xy 169.727874 -283.759998) (xy 169.768377 -283.787954) (xy 169.80387 -283.822046) (xy 169.833435 -283.86139)
			(xy 169.856306 -283.904967) (xy 169.87189 -283.951648) (xy 169.879785 -284.000225) (xy 169.88028 -284.024832)
			(xy 170.219128 -284.024832) (xy 170.223088 -283.975778) (xy 170.234865 -283.927994) (xy 170.254156 -283.882718)
			(xy 170.280459 -283.841122) (xy 170.313094 -283.804285) (xy 170.351215 -283.77316) (xy 170.393836 -283.748553)
			(xy 170.439852 -283.731101) (xy 170.488071 -283.721257) (xy 170.537246 -283.719276) (xy 170.586101 -283.725208)
			(xy 170.633372 -283.7389) (xy 170.677834 -283.759998) (xy 170.718337 -283.787954) (xy 170.75383 -283.822046)
			(xy 170.783395 -283.86139) (xy 170.806266 -283.904967) (xy 170.82185 -283.951648) (xy 170.829745 -284.000225)
			(xy 170.83024 -284.024832) (xy 171.169088 -284.024832) (xy 171.173048 -283.975778) (xy 171.184825 -283.927994)
			(xy 171.204116 -283.882718) (xy 171.230419 -283.841122) (xy 171.263054 -283.804285) (xy 171.301175 -283.77316)
			(xy 171.343796 -283.748553) (xy 171.389812 -283.731101) (xy 171.438031 -283.721257) (xy 171.487206 -283.719276)
			(xy 171.536061 -283.725208) (xy 171.583332 -283.7389) (xy 171.627794 -283.759998) (xy 171.668297 -283.787954)
			(xy 171.70379 -283.822046) (xy 171.733355 -283.86139) (xy 171.756226 -283.904967) (xy 171.77181 -283.951648)
			(xy 171.779705 -284.000225) (xy 171.7802 -284.024832) (xy 172.119048 -284.024832) (xy 172.123008 -283.975778)
			(xy 172.134785 -283.927994) (xy 172.154076 -283.882718) (xy 172.180379 -283.841122) (xy 172.213014 -283.804285)
			(xy 172.251135 -283.77316) (xy 172.293756 -283.748553) (xy 172.339772 -283.731101) (xy 172.387991 -283.721257)
			(xy 172.437166 -283.719276) (xy 172.486021 -283.725208) (xy 172.533292 -283.7389) (xy 172.577754 -283.759998)
			(xy 172.618257 -283.787954) (xy 172.65375 -283.822046) (xy 172.683315 -283.86139) (xy 172.706186 -283.904967)
			(xy 172.72177 -283.951648) (xy 172.729665 -284.000225) (xy 172.73016 -284.024832) (xy 173.069262 -284.024832)
			(xy 173.073222 -283.975778) (xy 173.084999 -283.927994) (xy 173.10429 -283.882718) (xy 173.130593 -283.841122)
			(xy 173.163228 -283.804285) (xy 173.201349 -283.77316) (xy 173.24397 -283.748553) (xy 173.289986 -283.731101)
			(xy 173.338205 -283.721257) (xy 173.38738 -283.719276) (xy 173.436235 -283.725208) (xy 173.483506 -283.7389)
			(xy 173.527968 -283.759998) (xy 173.568471 -283.787954) (xy 173.603964 -283.822046) (xy 173.633529 -283.86139)
			(xy 173.6564 -283.904967) (xy 173.671984 -283.951648) (xy 173.679879 -284.000225) (xy 173.680374 -284.024832)
			(xy 174.019222 -284.024832) (xy 174.023182 -283.975778) (xy 174.034959 -283.927994) (xy 174.05425 -283.882718)
			(xy 174.080553 -283.841122) (xy 174.113188 -283.804285) (xy 174.151309 -283.77316) (xy 174.19393 -283.748553)
			(xy 174.239946 -283.731101) (xy 174.288165 -283.721257) (xy 174.33734 -283.719276) (xy 174.386195 -283.725208)
			(xy 174.433466 -283.7389) (xy 174.477928 -283.759998) (xy 174.518431 -283.787954) (xy 174.553924 -283.822046)
			(xy 174.583489 -283.86139) (xy 174.60636 -283.904967) (xy 174.621944 -283.951648) (xy 174.629839 -284.000225)
			(xy 174.630334 -284.024832) (xy 175.919142 -284.024832) (xy 175.923102 -283.975778) (xy 175.934879 -283.927994)
			(xy 175.95417 -283.882718) (xy 175.980473 -283.841122) (xy 176.013108 -283.804285) (xy 176.051229 -283.77316)
			(xy 176.09385 -283.748553) (xy 176.139866 -283.731101) (xy 176.188085 -283.721257) (xy 176.23726 -283.719276)
			(xy 176.286115 -283.725208) (xy 176.333386 -283.7389) (xy 176.377848 -283.759998) (xy 176.418351 -283.787954)
			(xy 176.453844 -283.822046) (xy 176.483409 -283.86139) (xy 176.50628 -283.904967) (xy 176.521864 -283.951648)
			(xy 176.529759 -284.000225) (xy 176.530254 -284.024832) (xy 176.869102 -284.024832) (xy 176.873062 -283.975778)
			(xy 176.884839 -283.927994) (xy 176.90413 -283.882718) (xy 176.930433 -283.841122) (xy 176.963068 -283.804285)
			(xy 177.001189 -283.77316) (xy 177.04381 -283.748553) (xy 177.089826 -283.731101) (xy 177.138045 -283.721257)
			(xy 177.18722 -283.719276) (xy 177.236075 -283.725208) (xy 177.283346 -283.7389) (xy 177.327808 -283.759998)
			(xy 177.368311 -283.787954) (xy 177.403804 -283.822046) (xy 177.433369 -283.86139) (xy 177.45624 -283.904967)
			(xy 177.471824 -283.951648) (xy 177.479719 -284.000225) (xy 177.480214 -284.024832) (xy 177.819062 -284.024832)
			(xy 177.823022 -283.975778) (xy 177.834799 -283.927994) (xy 177.85409 -283.882718) (xy 177.880393 -283.841122)
			(xy 177.913028 -283.804285) (xy 177.951149 -283.77316) (xy 177.99377 -283.748553) (xy 178.039786 -283.731101)
			(xy 178.088005 -283.721257) (xy 178.13718 -283.719276) (xy 178.186035 -283.725208) (xy 178.233306 -283.7389)
			(xy 178.277768 -283.759998) (xy 178.318271 -283.787954) (xy 178.353764 -283.822046) (xy 178.383329 -283.86139)
			(xy 178.4062 -283.904967) (xy 178.421784 -283.951648) (xy 178.429679 -284.000225) (xy 178.430174 -284.024832)
			(xy 178.769276 -284.024832) (xy 178.773236 -283.975778) (xy 178.785013 -283.927994) (xy 178.804304 -283.882718)
			(xy 178.830607 -283.841122) (xy 178.863242 -283.804285) (xy 178.901363 -283.77316) (xy 178.943984 -283.748553)
			(xy 178.99 -283.731101) (xy 179.038219 -283.721257) (xy 179.087394 -283.719276) (xy 179.136249 -283.725208)
			(xy 179.18352 -283.7389) (xy 179.227982 -283.759998) (xy 179.268485 -283.787954) (xy 179.303978 -283.822046)
			(xy 179.333543 -283.86139) (xy 179.356414 -283.904967) (xy 179.371998 -283.951648) (xy 179.379893 -284.000225)
			(xy 179.380388 -284.024832) (xy 179.719236 -284.024832) (xy 179.723196 -283.975778) (xy 179.734973 -283.927994)
			(xy 179.754264 -283.882718) (xy 179.780567 -283.841122) (xy 179.813202 -283.804285) (xy 179.851323 -283.77316)
			(xy 179.893944 -283.748553) (xy 179.93996 -283.731101) (xy 179.988179 -283.721257) (xy 180.037354 -283.719276)
			(xy 180.086209 -283.725208) (xy 180.13348 -283.7389) (xy 180.177942 -283.759998) (xy 180.218445 -283.787954)
			(xy 180.253938 -283.822046) (xy 180.283503 -283.86139) (xy 180.306374 -283.904967) (xy 180.321958 -283.951648)
			(xy 180.329853 -284.000225) (xy 180.330348 -284.024832) (xy 180.669196 -284.024832) (xy 180.673156 -283.975778)
			(xy 180.684933 -283.927994) (xy 180.704224 -283.882718) (xy 180.730527 -283.841122) (xy 180.763162 -283.804285)
			(xy 180.801283 -283.77316) (xy 180.843904 -283.748553) (xy 180.88992 -283.731101) (xy 180.938139 -283.721257)
			(xy 180.987314 -283.719276) (xy 181.036169 -283.725208) (xy 181.08344 -283.7389) (xy 181.127902 -283.759998)
			(xy 181.168405 -283.787954) (xy 181.203898 -283.822046) (xy 181.233463 -283.86139) (xy 181.256334 -283.904967)
			(xy 181.271918 -283.951648) (xy 181.279813 -284.000225) (xy 181.280308 -284.024832) (xy 181.619156 -284.024832)
			(xy 181.623116 -283.975778) (xy 181.634893 -283.927994) (xy 181.654184 -283.882718) (xy 181.680487 -283.841122)
			(xy 181.713122 -283.804285) (xy 181.751243 -283.77316) (xy 181.793864 -283.748553) (xy 181.83988 -283.731101)
			(xy 181.888099 -283.721257) (xy 181.937274 -283.719276) (xy 181.986129 -283.725208) (xy 182.0334 -283.7389)
			(xy 182.077862 -283.759998) (xy 182.118365 -283.787954) (xy 182.153858 -283.822046) (xy 182.183423 -283.86139)
			(xy 182.206294 -283.904967) (xy 182.221878 -283.951648) (xy 182.229773 -284.000225) (xy 182.230268 -284.024832)
			(xy 182.569116 -284.024832) (xy 182.573076 -283.975778) (xy 182.584853 -283.927994) (xy 182.604144 -283.882718)
			(xy 182.630447 -283.841122) (xy 182.663082 -283.804285) (xy 182.701203 -283.77316) (xy 182.743824 -283.748553)
			(xy 182.78984 -283.731101) (xy 182.838059 -283.721257) (xy 182.887234 -283.719276) (xy 182.936089 -283.725208)
			(xy 182.98336 -283.7389) (xy 183.027822 -283.759998) (xy 183.068325 -283.787954) (xy 183.103818 -283.822046)
			(xy 183.133383 -283.86139) (xy 183.156254 -283.904967) (xy 183.171838 -283.951648) (xy 183.179733 -284.000225)
			(xy 183.180228 -284.024832) (xy 184.469036 -284.024832) (xy 184.472996 -283.975778) (xy 184.484773 -283.927994)
			(xy 184.504064 -283.882718) (xy 184.530367 -283.841122) (xy 184.563002 -283.804285) (xy 184.601123 -283.77316)
			(xy 184.643744 -283.748553) (xy 184.68976 -283.731101) (xy 184.737979 -283.721257) (xy 184.787154 -283.719276)
			(xy 184.836009 -283.725208) (xy 184.88328 -283.7389) (xy 184.927742 -283.759998) (xy 184.968245 -283.787954)
			(xy 185.003738 -283.822046) (xy 185.033303 -283.86139) (xy 185.056174 -283.904967) (xy 185.071758 -283.951648)
			(xy 185.079653 -284.000225) (xy 185.080148 -284.024832) (xy 185.41925 -284.024832) (xy 185.42321 -283.975778)
			(xy 185.434987 -283.927994) (xy 185.454278 -283.882718) (xy 185.480581 -283.841122) (xy 185.513216 -283.804285)
			(xy 185.551337 -283.77316) (xy 185.593958 -283.748553) (xy 185.639974 -283.731101) (xy 185.688193 -283.721257)
			(xy 185.737368 -283.719276) (xy 185.786223 -283.725208) (xy 185.833494 -283.7389) (xy 185.877956 -283.759998)
			(xy 185.918459 -283.787954) (xy 185.953952 -283.822046) (xy 185.983517 -283.86139) (xy 186.006388 -283.904967)
			(xy 186.021972 -283.951648) (xy 186.029867 -284.000225) (xy 186.030362 -284.024832) (xy 186.36921 -284.024832)
			(xy 186.37317 -283.975778) (xy 186.384947 -283.927994) (xy 186.404238 -283.882718) (xy 186.430541 -283.841122)
			(xy 186.463176 -283.804285) (xy 186.501297 -283.77316) (xy 186.543918 -283.748553) (xy 186.589934 -283.731101)
			(xy 186.638153 -283.721257) (xy 186.687328 -283.719276) (xy 186.736183 -283.725208) (xy 186.783454 -283.7389)
			(xy 186.827916 -283.759998) (xy 186.868419 -283.787954) (xy 186.903912 -283.822046) (xy 186.933477 -283.86139)
			(xy 186.956348 -283.904967) (xy 186.971932 -283.951648) (xy 186.979827 -284.000225) (xy 186.980322 -284.024832)
			(xy 186.979827 -284.049439) (xy 186.971932 -284.098016) (xy 186.956348 -284.144697) (xy 186.933477 -284.188274)
			(xy 186.903912 -284.227618) (xy 186.868419 -284.26171) (xy 186.827916 -284.289666) (xy 186.783454 -284.310764)
			(xy 186.736183 -284.324456) (xy 186.687328 -284.330388) (xy 186.638153 -284.328407) (xy 186.589934 -284.318563)
			(xy 186.543918 -284.301111) (xy 186.501297 -284.276504) (xy 186.463176 -284.245379) (xy 186.430541 -284.208542)
			(xy 186.404238 -284.166946) (xy 186.384947 -284.12167) (xy 186.37317 -284.073886) (xy 186.36921 -284.024832)
			(xy 186.030362 -284.024832) (xy 186.029867 -284.049439) (xy 186.021972 -284.098016) (xy 186.006388 -284.144697)
			(xy 185.983517 -284.188274) (xy 185.953952 -284.227618) (xy 185.918459 -284.26171) (xy 185.877956 -284.289666)
			(xy 185.833494 -284.310764) (xy 185.786223 -284.324456) (xy 185.737368 -284.330388) (xy 185.688193 -284.328407)
			(xy 185.639974 -284.318563) (xy 185.593958 -284.301111) (xy 185.551337 -284.276504) (xy 185.513216 -284.245379)
			(xy 185.480581 -284.208542) (xy 185.454278 -284.166946) (xy 185.434987 -284.12167) (xy 185.42321 -284.073886)
			(xy 185.41925 -284.024832) (xy 185.080148 -284.024832) (xy 185.079653 -284.049439) (xy 185.071758 -284.098016)
			(xy 185.056174 -284.144697) (xy 185.033303 -284.188274) (xy 185.003738 -284.227618) (xy 184.968245 -284.26171)
			(xy 184.927742 -284.289666) (xy 184.88328 -284.310764) (xy 184.836009 -284.324456) (xy 184.787154 -284.330388)
			(xy 184.737979 -284.328407) (xy 184.68976 -284.318563) (xy 184.643744 -284.301111) (xy 184.601123 -284.276504)
			(xy 184.563002 -284.245379) (xy 184.530367 -284.208542) (xy 184.504064 -284.166946) (xy 184.484773 -284.12167)
			(xy 184.472996 -284.073886) (xy 184.469036 -284.024832) (xy 183.180228 -284.024832) (xy 183.179733 -284.049439)
			(xy 183.171838 -284.098016) (xy 183.156254 -284.144697) (xy 183.133383 -284.188274) (xy 183.103818 -284.227618)
			(xy 183.068325 -284.26171) (xy 183.027822 -284.289666) (xy 182.98336 -284.310764) (xy 182.936089 -284.324456)
			(xy 182.887234 -284.330388) (xy 182.838059 -284.328407) (xy 182.78984 -284.318563) (xy 182.743824 -284.301111)
			(xy 182.701203 -284.276504) (xy 182.663082 -284.245379) (xy 182.630447 -284.208542) (xy 182.604144 -284.166946)
			(xy 182.584853 -284.12167) (xy 182.573076 -284.073886) (xy 182.569116 -284.024832) (xy 182.230268 -284.024832)
			(xy 182.229773 -284.049439) (xy 182.221878 -284.098016) (xy 182.206294 -284.144697) (xy 182.183423 -284.188274)
			(xy 182.153858 -284.227618) (xy 182.118365 -284.26171) (xy 182.077862 -284.289666) (xy 182.0334 -284.310764)
			(xy 181.986129 -284.324456) (xy 181.937274 -284.330388) (xy 181.888099 -284.328407) (xy 181.83988 -284.318563)
			(xy 181.793864 -284.301111) (xy 181.751243 -284.276504) (xy 181.713122 -284.245379) (xy 181.680487 -284.208542)
			(xy 181.654184 -284.166946) (xy 181.634893 -284.12167) (xy 181.623116 -284.073886) (xy 181.619156 -284.024832)
			(xy 181.280308 -284.024832) (xy 181.279813 -284.049439) (xy 181.271918 -284.098016) (xy 181.256334 -284.144697)
			(xy 181.233463 -284.188274) (xy 181.203898 -284.227618) (xy 181.168405 -284.26171) (xy 181.127902 -284.289666)
			(xy 181.08344 -284.310764) (xy 181.036169 -284.324456) (xy 180.987314 -284.330388) (xy 180.938139 -284.328407)
			(xy 180.88992 -284.318563) (xy 180.843904 -284.301111) (xy 180.801283 -284.276504) (xy 180.763162 -284.245379)
			(xy 180.730527 -284.208542) (xy 180.704224 -284.166946) (xy 180.684933 -284.12167) (xy 180.673156 -284.073886)
			(xy 180.669196 -284.024832) (xy 180.330348 -284.024832) (xy 180.329853 -284.049439) (xy 180.321958 -284.098016)
			(xy 180.306374 -284.144697) (xy 180.283503 -284.188274) (xy 180.253938 -284.227618) (xy 180.218445 -284.26171)
			(xy 180.177942 -284.289666) (xy 180.13348 -284.310764) (xy 180.086209 -284.324456) (xy 180.037354 -284.330388)
			(xy 179.988179 -284.328407) (xy 179.93996 -284.318563) (xy 179.893944 -284.301111) (xy 179.851323 -284.276504)
			(xy 179.813202 -284.245379) (xy 179.780567 -284.208542) (xy 179.754264 -284.166946) (xy 179.734973 -284.12167)
			(xy 179.723196 -284.073886) (xy 179.719236 -284.024832) (xy 179.380388 -284.024832) (xy 179.379893 -284.049439)
			(xy 179.371998 -284.098016) (xy 179.356414 -284.144697) (xy 179.333543 -284.188274) (xy 179.303978 -284.227618)
			(xy 179.268485 -284.26171) (xy 179.227982 -284.289666) (xy 179.18352 -284.310764) (xy 179.136249 -284.324456)
			(xy 179.087394 -284.330388) (xy 179.038219 -284.328407) (xy 178.99 -284.318563) (xy 178.943984 -284.301111)
			(xy 178.901363 -284.276504) (xy 178.863242 -284.245379) (xy 178.830607 -284.208542) (xy 178.804304 -284.166946)
			(xy 178.785013 -284.12167) (xy 178.773236 -284.073886) (xy 178.769276 -284.024832) (xy 178.430174 -284.024832)
			(xy 178.429679 -284.049439) (xy 178.421784 -284.098016) (xy 178.4062 -284.144697) (xy 178.383329 -284.188274)
			(xy 178.353764 -284.227618) (xy 178.318271 -284.26171) (xy 178.277768 -284.289666) (xy 178.233306 -284.310764)
			(xy 178.186035 -284.324456) (xy 178.13718 -284.330388) (xy 178.088005 -284.328407) (xy 178.039786 -284.318563)
			(xy 177.99377 -284.301111) (xy 177.951149 -284.276504) (xy 177.913028 -284.245379) (xy 177.880393 -284.208542)
			(xy 177.85409 -284.166946) (xy 177.834799 -284.12167) (xy 177.823022 -284.073886) (xy 177.819062 -284.024832)
			(xy 177.480214 -284.024832) (xy 177.479719 -284.049439) (xy 177.471824 -284.098016) (xy 177.45624 -284.144697)
			(xy 177.433369 -284.188274) (xy 177.403804 -284.227618) (xy 177.368311 -284.26171) (xy 177.327808 -284.289666)
			(xy 177.283346 -284.310764) (xy 177.236075 -284.324456) (xy 177.18722 -284.330388) (xy 177.138045 -284.328407)
			(xy 177.089826 -284.318563) (xy 177.04381 -284.301111) (xy 177.001189 -284.276504) (xy 176.963068 -284.245379)
			(xy 176.930433 -284.208542) (xy 176.90413 -284.166946) (xy 176.884839 -284.12167) (xy 176.873062 -284.073886)
			(xy 176.869102 -284.024832) (xy 176.530254 -284.024832) (xy 176.529759 -284.049439) (xy 176.521864 -284.098016)
			(xy 176.50628 -284.144697) (xy 176.483409 -284.188274) (xy 176.453844 -284.227618) (xy 176.418351 -284.26171)
			(xy 176.377848 -284.289666) (xy 176.333386 -284.310764) (xy 176.286115 -284.324456) (xy 176.23726 -284.330388)
			(xy 176.188085 -284.328407) (xy 176.139866 -284.318563) (xy 176.09385 -284.301111) (xy 176.051229 -284.276504)
			(xy 176.013108 -284.245379) (xy 175.980473 -284.208542) (xy 175.95417 -284.166946) (xy 175.934879 -284.12167)
			(xy 175.923102 -284.073886) (xy 175.919142 -284.024832) (xy 174.630334 -284.024832) (xy 174.629839 -284.049439)
			(xy 174.621944 -284.098016) (xy 174.60636 -284.144697) (xy 174.583489 -284.188274) (xy 174.553924 -284.227618)
			(xy 174.518431 -284.26171) (xy 174.477928 -284.289666) (xy 174.433466 -284.310764) (xy 174.386195 -284.324456)
			(xy 174.33734 -284.330388) (xy 174.288165 -284.328407) (xy 174.239946 -284.318563) (xy 174.19393 -284.301111)
			(xy 174.151309 -284.276504) (xy 174.113188 -284.245379) (xy 174.080553 -284.208542) (xy 174.05425 -284.166946)
			(xy 174.034959 -284.12167) (xy 174.023182 -284.073886) (xy 174.019222 -284.024832) (xy 173.680374 -284.024832)
			(xy 173.679879 -284.049439) (xy 173.671984 -284.098016) (xy 173.6564 -284.144697) (xy 173.633529 -284.188274)
			(xy 173.603964 -284.227618) (xy 173.568471 -284.26171) (xy 173.527968 -284.289666) (xy 173.483506 -284.310764)
			(xy 173.436235 -284.324456) (xy 173.38738 -284.330388) (xy 173.338205 -284.328407) (xy 173.289986 -284.318563)
			(xy 173.24397 -284.301111) (xy 173.201349 -284.276504) (xy 173.163228 -284.245379) (xy 173.130593 -284.208542)
			(xy 173.10429 -284.166946) (xy 173.084999 -284.12167) (xy 173.073222 -284.073886) (xy 173.069262 -284.024832)
			(xy 172.73016 -284.024832) (xy 172.729665 -284.049439) (xy 172.72177 -284.098016) (xy 172.706186 -284.144697)
			(xy 172.683315 -284.188274) (xy 172.65375 -284.227618) (xy 172.618257 -284.26171) (xy 172.577754 -284.289666)
			(xy 172.533292 -284.310764) (xy 172.486021 -284.324456) (xy 172.437166 -284.330388) (xy 172.387991 -284.328407)
			(xy 172.339772 -284.318563) (xy 172.293756 -284.301111) (xy 172.251135 -284.276504) (xy 172.213014 -284.245379)
			(xy 172.180379 -284.208542) (xy 172.154076 -284.166946) (xy 172.134785 -284.12167) (xy 172.123008 -284.073886)
			(xy 172.119048 -284.024832) (xy 171.7802 -284.024832) (xy 171.779705 -284.049439) (xy 171.77181 -284.098016)
			(xy 171.756226 -284.144697) (xy 171.733355 -284.188274) (xy 171.70379 -284.227618) (xy 171.668297 -284.26171)
			(xy 171.627794 -284.289666) (xy 171.583332 -284.310764) (xy 171.536061 -284.324456) (xy 171.487206 -284.330388)
			(xy 171.438031 -284.328407) (xy 171.389812 -284.318563) (xy 171.343796 -284.301111) (xy 171.301175 -284.276504)
			(xy 171.263054 -284.245379) (xy 171.230419 -284.208542) (xy 171.204116 -284.166946) (xy 171.184825 -284.12167)
			(xy 171.173048 -284.073886) (xy 171.169088 -284.024832) (xy 170.83024 -284.024832) (xy 170.829745 -284.049439)
			(xy 170.82185 -284.098016) (xy 170.806266 -284.144697) (xy 170.783395 -284.188274) (xy 170.75383 -284.227618)
			(xy 170.718337 -284.26171) (xy 170.677834 -284.289666) (xy 170.633372 -284.310764) (xy 170.586101 -284.324456)
			(xy 170.537246 -284.330388) (xy 170.488071 -284.328407) (xy 170.439852 -284.318563) (xy 170.393836 -284.301111)
			(xy 170.351215 -284.276504) (xy 170.313094 -284.245379) (xy 170.280459 -284.208542) (xy 170.254156 -284.166946)
			(xy 170.234865 -284.12167) (xy 170.223088 -284.073886) (xy 170.219128 -284.024832) (xy 169.88028 -284.024832)
			(xy 169.879785 -284.049439) (xy 169.87189 -284.098016) (xy 169.856306 -284.144697) (xy 169.833435 -284.188274)
			(xy 169.80387 -284.227618) (xy 169.768377 -284.26171) (xy 169.727874 -284.289666) (xy 169.683412 -284.310764)
			(xy 169.636141 -284.324456) (xy 169.587286 -284.330388) (xy 169.538111 -284.328407) (xy 169.489892 -284.318563)
			(xy 169.443876 -284.301111) (xy 169.401255 -284.276504) (xy 169.363134 -284.245379) (xy 169.330499 -284.208542)
			(xy 169.304196 -284.166946) (xy 169.284905 -284.12167) (xy 169.273128 -284.073886) (xy 169.269168 -284.024832)
			(xy 168.93032 -284.024832) (xy 168.929825 -284.049439) (xy 168.92193 -284.098016) (xy 168.906346 -284.144697)
			(xy 168.883475 -284.188274) (xy 168.85391 -284.227618) (xy 168.818417 -284.26171) (xy 168.777914 -284.289666)
			(xy 168.733452 -284.310764) (xy 168.686181 -284.324456) (xy 168.637326 -284.330388) (xy 168.588151 -284.328407)
			(xy 168.539932 -284.318563) (xy 168.493916 -284.301111) (xy 168.451295 -284.276504) (xy 168.413174 -284.245379)
			(xy 168.380539 -284.208542) (xy 168.354236 -284.166946) (xy 168.334945 -284.12167) (xy 168.323168 -284.073886)
			(xy 168.319208 -284.024832) (xy 167.98036 -284.024832) (xy 167.979865 -284.049439) (xy 167.97197 -284.098016)
			(xy 167.956386 -284.144697) (xy 167.933515 -284.188274) (xy 167.90395 -284.227618) (xy 167.868457 -284.26171)
			(xy 167.827954 -284.289666) (xy 167.783492 -284.310764) (xy 167.736221 -284.324456) (xy 167.687366 -284.330388)
			(xy 167.638191 -284.328407) (xy 167.589972 -284.318563) (xy 167.543956 -284.301111) (xy 167.501335 -284.276504)
			(xy 167.463214 -284.245379) (xy 167.430579 -284.208542) (xy 167.404276 -284.166946) (xy 167.384985 -284.12167)
			(xy 167.373208 -284.073886) (xy 167.369248 -284.024832) (xy 167.0304 -284.024832) (xy 167.029905 -284.049439)
			(xy 167.02201 -284.098016) (xy 167.006426 -284.144697) (xy 166.983555 -284.188274) (xy 166.95399 -284.227618)
			(xy 166.918497 -284.26171) (xy 166.877994 -284.289666) (xy 166.833532 -284.310764) (xy 166.786261 -284.324456)
			(xy 166.737406 -284.330388) (xy 166.688231 -284.328407) (xy 166.640012 -284.318563) (xy 166.593996 -284.301111)
			(xy 166.551375 -284.276504) (xy 166.513254 -284.245379) (xy 166.480619 -284.208542) (xy 166.454316 -284.166946)
			(xy 166.435025 -284.12167) (xy 166.423248 -284.073886) (xy 166.419288 -284.024832) (xy 166.080186 -284.024832)
			(xy 166.079691 -284.049439) (xy 166.071796 -284.098016) (xy 166.056212 -284.144697) (xy 166.033341 -284.188274)
			(xy 166.003776 -284.227618) (xy 165.968283 -284.26171) (xy 165.92778 -284.289666) (xy 165.883318 -284.310764)
			(xy 165.836047 -284.324456) (xy 165.787192 -284.330388) (xy 165.738017 -284.328407) (xy 165.689798 -284.318563)
			(xy 165.643782 -284.301111) (xy 165.601161 -284.276504) (xy 165.56304 -284.245379) (xy 165.530405 -284.208542)
			(xy 165.504102 -284.166946) (xy 165.484811 -284.12167) (xy 165.473034 -284.073886) (xy 165.469074 -284.024832)
			(xy 165.130226 -284.024832) (xy 165.129731 -284.049439) (xy 165.121836 -284.098016) (xy 165.106252 -284.144697)
			(xy 165.083381 -284.188274) (xy 165.053816 -284.227618) (xy 165.018323 -284.26171) (xy 164.97782 -284.289666)
			(xy 164.933358 -284.310764) (xy 164.886087 -284.324456) (xy 164.837232 -284.330388) (xy 164.788057 -284.328407)
			(xy 164.739838 -284.318563) (xy 164.693822 -284.301111) (xy 164.651201 -284.276504) (xy 164.61308 -284.245379)
			(xy 164.580445 -284.208542) (xy 164.554142 -284.166946) (xy 164.534851 -284.12167) (xy 164.523074 -284.073886)
			(xy 164.519114 -284.024832) (xy 164.180266 -284.024832) (xy 164.179771 -284.049439) (xy 164.171876 -284.098016)
			(xy 164.156292 -284.144697) (xy 164.133421 -284.188274) (xy 164.103856 -284.227618) (xy 164.068363 -284.26171)
			(xy 164.02786 -284.289666) (xy 163.983398 -284.310764) (xy 163.936127 -284.324456) (xy 163.887272 -284.330388)
			(xy 163.838097 -284.328407) (xy 163.789878 -284.318563) (xy 163.743862 -284.301111) (xy 163.701241 -284.276504)
			(xy 163.66312 -284.245379) (xy 163.630485 -284.208542) (xy 163.604182 -284.166946) (xy 163.584891 -284.12167)
			(xy 163.573114 -284.073886) (xy 163.569154 -284.024832) (xy 163.230306 -284.024832) (xy 163.229811 -284.049439)
			(xy 163.221916 -284.098016) (xy 163.206332 -284.144697) (xy 163.183461 -284.188274) (xy 163.153896 -284.227618)
			(xy 163.118403 -284.26171) (xy 163.0779 -284.289666) (xy 163.033438 -284.310764) (xy 162.986167 -284.324456)
			(xy 162.937312 -284.330388) (xy 162.888137 -284.328407) (xy 162.839918 -284.318563) (xy 162.793902 -284.301111)
			(xy 162.751281 -284.276504) (xy 162.71316 -284.245379) (xy 162.680525 -284.208542) (xy 162.654222 -284.166946)
			(xy 162.634931 -284.12167) (xy 162.623154 -284.073886) (xy 162.619194 -284.024832) (xy 162.280346 -284.024832)
			(xy 162.279851 -284.049439) (xy 162.271956 -284.098016) (xy 162.256372 -284.144697) (xy 162.233501 -284.188274)
			(xy 162.203936 -284.227618) (xy 162.168443 -284.26171) (xy 162.12794 -284.289666) (xy 162.083478 -284.310764)
			(xy 162.036207 -284.324456) (xy 161.987352 -284.330388) (xy 161.938177 -284.328407) (xy 161.889958 -284.318563)
			(xy 161.843942 -284.301111) (xy 161.801321 -284.276504) (xy 161.7632 -284.245379) (xy 161.730565 -284.208542)
			(xy 161.704262 -284.166946) (xy 161.684971 -284.12167) (xy 161.673194 -284.073886) (xy 161.669234 -284.024832)
			(xy 161.330386 -284.024832) (xy 161.329891 -284.049439) (xy 161.321996 -284.098016) (xy 161.306412 -284.144697)
			(xy 161.283541 -284.188274) (xy 161.253976 -284.227618) (xy 161.218483 -284.26171) (xy 161.17798 -284.289666)
			(xy 161.133518 -284.310764) (xy 161.086247 -284.324456) (xy 161.037392 -284.330388) (xy 160.988217 -284.328407)
			(xy 160.939998 -284.318563) (xy 160.893982 -284.301111) (xy 160.851361 -284.276504) (xy 160.81324 -284.245379)
			(xy 160.780605 -284.208542) (xy 160.754302 -284.166946) (xy 160.735011 -284.12167) (xy 160.723234 -284.073886)
			(xy 160.719274 -284.024832) (xy 160.380172 -284.024832) (xy 160.379677 -284.049439) (xy 160.371782 -284.098016)
			(xy 160.356198 -284.144697) (xy 160.333327 -284.188274) (xy 160.303762 -284.227618) (xy 160.268269 -284.26171)
			(xy 160.227766 -284.289666) (xy 160.183304 -284.310764) (xy 160.136033 -284.324456) (xy 160.087178 -284.330388)
			(xy 160.038003 -284.328407) (xy 159.989784 -284.318563) (xy 159.943768 -284.301111) (xy 159.901147 -284.276504)
			(xy 159.863026 -284.245379) (xy 159.830391 -284.208542) (xy 159.804088 -284.166946) (xy 159.784797 -284.12167)
			(xy 159.77302 -284.073886) (xy 159.76906 -284.024832) (xy 159.430212 -284.024832) (xy 159.429717 -284.049439)
			(xy 159.421822 -284.098016) (xy 159.406238 -284.144697) (xy 159.383367 -284.188274) (xy 159.353802 -284.227618)
			(xy 159.318309 -284.26171) (xy 159.277806 -284.289666) (xy 159.233344 -284.310764) (xy 159.186073 -284.324456)
			(xy 159.137218 -284.330388) (xy 159.088043 -284.328407) (xy 159.039824 -284.318563) (xy 158.993808 -284.301111)
			(xy 158.951187 -284.276504) (xy 158.913066 -284.245379) (xy 158.880431 -284.208542) (xy 158.854128 -284.166946)
			(xy 158.834837 -284.12167) (xy 158.82306 -284.073886) (xy 158.8191 -284.024832) (xy 156.580332 -284.024832)
			(xy 156.579837 -284.049439) (xy 156.571942 -284.098016) (xy 156.556358 -284.144697) (xy 156.533487 -284.188274)
			(xy 156.503922 -284.227618) (xy 156.468429 -284.26171) (xy 156.427926 -284.289666) (xy 156.383464 -284.310764)
			(xy 156.336193 -284.324456) (xy 156.287338 -284.330388) (xy 156.238163 -284.328407) (xy 156.189944 -284.318563)
			(xy 156.143928 -284.301111) (xy 156.101307 -284.276504) (xy 156.063186 -284.245379) (xy 156.030551 -284.208542)
			(xy 156.004248 -284.166946) (xy 155.984957 -284.12167) (xy 155.97318 -284.073886) (xy 155.96922 -284.024832)
			(xy 155.630372 -284.024832) (xy 155.629877 -284.049439) (xy 155.621982 -284.098016) (xy 155.606398 -284.144697)
			(xy 155.583527 -284.188274) (xy 155.553962 -284.227618) (xy 155.518469 -284.26171) (xy 155.477966 -284.289666)
			(xy 155.433504 -284.310764) (xy 155.386233 -284.324456) (xy 155.337378 -284.330388) (xy 155.288203 -284.328407)
			(xy 155.239984 -284.318563) (xy 155.193968 -284.301111) (xy 155.151347 -284.276504) (xy 155.113226 -284.245379)
			(xy 155.080591 -284.208542) (xy 155.054288 -284.166946) (xy 155.034997 -284.12167) (xy 155.02322 -284.073886)
			(xy 155.01926 -284.024832) (xy 154.680412 -284.024832) (xy 154.679917 -284.049439) (xy 154.672022 -284.098016)
			(xy 154.656438 -284.144697) (xy 154.633567 -284.188274) (xy 154.604002 -284.227618) (xy 154.568509 -284.26171)
			(xy 154.528006 -284.289666) (xy 154.483544 -284.310764) (xy 154.436273 -284.324456) (xy 154.387418 -284.330388)
			(xy 154.338243 -284.328407) (xy 154.290024 -284.318563) (xy 154.244008 -284.301111) (xy 154.201387 -284.276504)
			(xy 154.163266 -284.245379) (xy 154.130631 -284.208542) (xy 154.104328 -284.166946) (xy 154.085037 -284.12167)
			(xy 154.07326 -284.073886) (xy 154.0693 -284.024832) (xy 153.730198 -284.024832) (xy 153.729703 -284.049439)
			(xy 153.721808 -284.098016) (xy 153.706224 -284.144697) (xy 153.683353 -284.188274) (xy 153.653788 -284.227618)
			(xy 153.618295 -284.26171) (xy 153.577792 -284.289666) (xy 153.53333 -284.310764) (xy 153.486059 -284.324456)
			(xy 153.437204 -284.330388) (xy 153.388029 -284.328407) (xy 153.33981 -284.318563) (xy 153.293794 -284.301111)
			(xy 153.251173 -284.276504) (xy 153.213052 -284.245379) (xy 153.180417 -284.208542) (xy 153.154114 -284.166946)
			(xy 153.134823 -284.12167) (xy 153.123046 -284.073886) (xy 153.119086 -284.024832) (xy 152.780238 -284.024832)
			(xy 152.779743 -284.049439) (xy 152.771848 -284.098016) (xy 152.756264 -284.144697) (xy 152.733393 -284.188274)
			(xy 152.703828 -284.227618) (xy 152.668335 -284.26171) (xy 152.627832 -284.289666) (xy 152.58337 -284.310764)
			(xy 152.536099 -284.324456) (xy 152.487244 -284.330388) (xy 152.438069 -284.328407) (xy 152.38985 -284.318563)
			(xy 152.343834 -284.301111) (xy 152.301213 -284.276504) (xy 152.263092 -284.245379) (xy 152.230457 -284.208542)
			(xy 152.204154 -284.166946) (xy 152.184863 -284.12167) (xy 152.173086 -284.073886) (xy 152.169126 -284.024832)
			(xy 150.461439 -284.024832) (xy 150.459889 -284.029983) (xy 150.436217 -284.08048) (xy 150.405444 -284.126993)
			(xy 150.368227 -284.16853) (xy 150.325359 -284.204205) (xy 150.277753 -284.233259) (xy 150.226424 -284.255071)
			(xy 150.172467 -284.269177) (xy 150.11703 -284.275277) (xy 150.061296 -284.27324) (xy 150.006453 -284.26311)
			(xy 149.953669 -284.245103) (xy 149.904069 -284.219602) (xy 149.858711 -284.187151) (xy 149.818562 -284.148442)
			(xy 149.784476 -284.104299) (xy 149.75718 -284.055664) (xy 149.737257 -284.003573) (xy 149.725131 -283.949136)
			(xy 149.72106 -283.893514) (xy 149.598126 -283.893514) (xy 149.597617 -283.9214) (xy 149.589497 -283.976576)
			(xy 149.573429 -284.029983) (xy 149.549757 -284.08048) (xy 149.518984 -284.126993) (xy 149.481767 -284.16853)
			(xy 149.438899 -284.204205) (xy 149.391293 -284.233259) (xy 149.339964 -284.255071) (xy 149.286007 -284.269177)
			(xy 149.23057 -284.275277) (xy 149.174836 -284.27324) (xy 149.119993 -284.26311) (xy 149.067209 -284.245103)
			(xy 149.017609 -284.219602) (xy 148.972251 -284.187151) (xy 148.932102 -284.148442) (xy 148.898016 -284.104299)
			(xy 148.87072 -284.055664) (xy 148.850797 -284.003573) (xy 148.838671 -283.949136) (xy 148.8346 -283.893514)
			(xy 148.201126 -283.893514) (xy 148.20064 -283.920765) (xy 148.192884 -283.974713) (xy 148.177529 -284.027008)
			(xy 148.154887 -284.076585) (xy 148.125421 -284.122435) (xy 148.08973 -284.163626) (xy 148.048539 -284.199317)
			(xy 148.002689 -284.228783) (xy 147.953112 -284.251425) (xy 147.900817 -284.26678) (xy 147.846869 -284.274536)
			(xy 147.792367 -284.274536) (xy 147.738419 -284.26678) (xy 147.686124 -284.251425) (xy 147.636547 -284.228783)
			(xy 147.590697 -284.199317) (xy 147.549506 -284.163626) (xy 147.513815 -284.122435) (xy 147.484349 -284.076585)
			(xy 147.461707 -284.027008) (xy 147.446352 -283.974713) (xy 147.438596 -283.920765) (xy 147.43811 -283.893514)
			(xy 136.94918 -283.893514) (xy 136.94918 -284.499812) (xy 189.69407 -284.499812) (xy 189.69803 -284.450758)
			(xy 189.709807 -284.402974) (xy 189.729098 -284.357698) (xy 189.755401 -284.316102) (xy 189.788036 -284.279265)
			(xy 189.826157 -284.24814) (xy 189.868778 -284.223533) (xy 189.914794 -284.206081) (xy 189.963013 -284.196237)
			(xy 190.012188 -284.194256) (xy 190.061043 -284.200188) (xy 190.108314 -284.21388) (xy 190.152776 -284.234978)
			(xy 190.193279 -284.262934) (xy 190.228772 -284.297026) (xy 190.258337 -284.33637) (xy 190.281208 -284.379947)
			(xy 190.296792 -284.426628) (xy 190.304687 -284.475205) (xy 190.305182 -284.499812) (xy 190.64403 -284.499812)
			(xy 190.64799 -284.450758) (xy 190.659767 -284.402974) (xy 190.679058 -284.357698) (xy 190.705361 -284.316102)
			(xy 190.737996 -284.279265) (xy 190.776117 -284.24814) (xy 190.818738 -284.223533) (xy 190.864754 -284.206081)
			(xy 190.912973 -284.196237) (xy 190.962148 -284.194256) (xy 191.011003 -284.200188) (xy 191.058274 -284.21388)
			(xy 191.102736 -284.234978) (xy 191.143239 -284.262934) (xy 191.178732 -284.297026) (xy 191.208297 -284.33637)
			(xy 191.231168 -284.379947) (xy 191.246752 -284.426628) (xy 191.254647 -284.475205) (xy 191.255142 -284.499812)
			(xy 191.594244 -284.499812) (xy 191.598204 -284.450758) (xy 191.609981 -284.402974) (xy 191.629272 -284.357698)
			(xy 191.655575 -284.316102) (xy 191.68821 -284.279265) (xy 191.726331 -284.24814) (xy 191.768952 -284.223533)
			(xy 191.814968 -284.206081) (xy 191.863187 -284.196237) (xy 191.912362 -284.194256) (xy 191.961217 -284.200188)
			(xy 192.008488 -284.21388) (xy 192.05295 -284.234978) (xy 192.093453 -284.262934) (xy 192.128946 -284.297026)
			(xy 192.158511 -284.33637) (xy 192.181382 -284.379947) (xy 192.196966 -284.426628) (xy 192.204861 -284.475205)
			(xy 192.205356 -284.499812) (xy 192.204861 -284.524419) (xy 192.204682 -284.52552) (xy 192.52336 -284.52552)
			(xy 192.52336 -284.474104) (xy 192.531403 -284.423322) (xy 192.547291 -284.374423) (xy 192.570634 -284.328611)
			(xy 192.600855 -284.287015) (xy 192.637211 -284.250659) (xy 192.678807 -284.220438) (xy 192.724619 -284.197095)
			(xy 192.773518 -284.181207) (xy 192.8243 -284.173164) (xy 192.875716 -284.173164) (xy 192.926498 -284.181207)
			(xy 192.975397 -284.197095) (xy 193.021209 -284.220438) (xy 193.062805 -284.250659) (xy 193.099161 -284.287015)
			(xy 193.129382 -284.328611) (xy 193.152725 -284.374423) (xy 193.168613 -284.423322) (xy 193.176656 -284.474104)
			(xy 193.17716 -284.499812) (xy 193.176656 -284.52552) (xy 193.47332 -284.52552) (xy 193.47332 -284.474104)
			(xy 193.481363 -284.423322) (xy 193.497251 -284.374423) (xy 193.520594 -284.328611) (xy 193.550815 -284.287015)
			(xy 193.587171 -284.250659) (xy 193.628767 -284.220438) (xy 193.674579 -284.197095) (xy 193.723478 -284.181207)
			(xy 193.77426 -284.173164) (xy 193.825676 -284.173164) (xy 193.876458 -284.181207) (xy 193.925357 -284.197095)
			(xy 193.971169 -284.220438) (xy 194.012765 -284.250659) (xy 194.049121 -284.287015) (xy 194.079342 -284.328611)
			(xy 194.102685 -284.374423) (xy 194.118573 -284.423322) (xy 194.126616 -284.474104) (xy 194.12712 -284.499812)
			(xy 194.444124 -284.499812) (xy 194.448084 -284.450758) (xy 194.459861 -284.402974) (xy 194.479152 -284.357698)
			(xy 194.505455 -284.316102) (xy 194.53809 -284.279265) (xy 194.576211 -284.24814) (xy 194.618832 -284.223533)
			(xy 194.664848 -284.206081) (xy 194.713067 -284.196237) (xy 194.762242 -284.194256) (xy 194.811097 -284.200188)
			(xy 194.858368 -284.21388) (xy 194.90283 -284.234978) (xy 194.943333 -284.262934) (xy 194.978826 -284.297026)
			(xy 195.008391 -284.33637) (xy 195.031262 -284.379947) (xy 195.046846 -284.426628) (xy 195.054741 -284.475205)
			(xy 195.055236 -284.499812) (xy 195.054741 -284.524419) (xy 195.054562 -284.52552) (xy 195.37324 -284.52552)
			(xy 195.37324 -284.474104) (xy 195.381283 -284.423322) (xy 195.397171 -284.374423) (xy 195.420514 -284.328611)
			(xy 195.450735 -284.287015) (xy 195.487091 -284.250659) (xy 195.528687 -284.220438) (xy 195.574499 -284.197095)
			(xy 195.623398 -284.181207) (xy 195.67418 -284.173164) (xy 195.725596 -284.173164) (xy 195.776378 -284.181207)
			(xy 195.825277 -284.197095) (xy 195.871089 -284.220438) (xy 195.912685 -284.250659) (xy 195.949041 -284.287015)
			(xy 195.979262 -284.328611) (xy 196.002605 -284.374423) (xy 196.018493 -284.423322) (xy 196.026536 -284.474104)
			(xy 196.02704 -284.499812) (xy 196.026536 -284.52552) (xy 196.3232 -284.52552) (xy 196.3232 -284.474104)
			(xy 196.331243 -284.423322) (xy 196.347131 -284.374423) (xy 196.370474 -284.328611) (xy 196.400695 -284.287015)
			(xy 196.437051 -284.250659) (xy 196.478647 -284.220438) (xy 196.524459 -284.197095) (xy 196.573358 -284.181207)
			(xy 196.62414 -284.173164) (xy 196.675556 -284.173164) (xy 196.726338 -284.181207) (xy 196.775237 -284.197095)
			(xy 196.821049 -284.220438) (xy 196.862645 -284.250659) (xy 196.899001 -284.287015) (xy 196.929222 -284.328611)
			(xy 196.952565 -284.374423) (xy 196.968453 -284.423322) (xy 196.976496 -284.474104) (xy 196.977 -284.499812)
			(xy 197.294258 -284.499812) (xy 197.298218 -284.450758) (xy 197.309995 -284.402974) (xy 197.329286 -284.357698)
			(xy 197.355589 -284.316102) (xy 197.388224 -284.279265) (xy 197.426345 -284.24814) (xy 197.468966 -284.223533)
			(xy 197.514982 -284.206081) (xy 197.563201 -284.196237) (xy 197.612376 -284.194256) (xy 197.661231 -284.200188)
			(xy 197.708502 -284.21388) (xy 197.752964 -284.234978) (xy 197.793467 -284.262934) (xy 197.82896 -284.297026)
			(xy 197.858525 -284.33637) (xy 197.881396 -284.379947) (xy 197.89698 -284.426628) (xy 197.904875 -284.475205)
			(xy 197.90537 -284.499812) (xy 198.244218 -284.499812) (xy 198.248178 -284.450758) (xy 198.259955 -284.402974)
			(xy 198.279246 -284.357698) (xy 198.305549 -284.316102) (xy 198.338184 -284.279265) (xy 198.376305 -284.24814)
			(xy 198.418926 -284.223533) (xy 198.464942 -284.206081) (xy 198.513161 -284.196237) (xy 198.562336 -284.194256)
			(xy 198.611191 -284.200188) (xy 198.658462 -284.21388) (xy 198.702924 -284.234978) (xy 198.743427 -284.262934)
			(xy 198.77892 -284.297026) (xy 198.808485 -284.33637) (xy 198.831356 -284.379947) (xy 198.84694 -284.426628)
			(xy 198.854835 -284.475205) (xy 198.85533 -284.499812) (xy 198.854835 -284.524419) (xy 198.84694 -284.572996)
			(xy 198.831356 -284.619677) (xy 198.824812 -284.632146) (xy 210.027772 -284.632146) (xy 210.031843 -284.576524)
			(xy 210.043969 -284.522087) (xy 210.063892 -284.469996) (xy 210.091188 -284.421361) (xy 210.125274 -284.377218)
			(xy 210.165423 -284.338509) (xy 210.210781 -284.306058) (xy 210.260381 -284.280557) (xy 210.313165 -284.26255)
			(xy 210.368008 -284.25242) (xy 210.423742 -284.250383) (xy 210.479179 -284.256483) (xy 210.533136 -284.270589)
			(xy 210.584465 -284.292401) (xy 210.632071 -284.321455) (xy 210.674939 -284.35713) (xy 210.712156 -284.398667)
			(xy 210.742929 -284.44518) (xy 210.766601 -284.495677) (xy 210.782669 -284.549084) (xy 210.790789 -284.60426)
			(xy 210.791298 -284.632146) (xy 210.790789 -284.660032) (xy 210.782669 -284.715208) (xy 210.766601 -284.768615)
			(xy 210.742929 -284.819112) (xy 210.712156 -284.865625) (xy 210.674939 -284.907162) (xy 210.632071 -284.942837)
			(xy 210.584465 -284.971891) (xy 210.533136 -284.993703) (xy 210.479179 -285.007809) (xy 210.423742 -285.013909)
			(xy 210.368008 -285.011872) (xy 210.313165 -285.001742) (xy 210.260381 -284.983735) (xy 210.210781 -284.958234)
			(xy 210.165423 -284.925783) (xy 210.125274 -284.887074) (xy 210.091188 -284.842931) (xy 210.063892 -284.794296)
			(xy 210.043969 -284.742205) (xy 210.031843 -284.687768) (xy 210.027772 -284.632146) (xy 198.824812 -284.632146)
			(xy 198.808485 -284.663254) (xy 198.77892 -284.702598) (xy 198.743427 -284.73669) (xy 198.702924 -284.764646)
			(xy 198.658462 -284.785744) (xy 198.611191 -284.799436) (xy 198.562336 -284.805368) (xy 198.513161 -284.803387)
			(xy 198.464942 -284.793543) (xy 198.418926 -284.776091) (xy 198.376305 -284.751484) (xy 198.338184 -284.720359)
			(xy 198.305549 -284.683522) (xy 198.279246 -284.641926) (xy 198.259955 -284.59665) (xy 198.248178 -284.548866)
			(xy 198.244218 -284.499812) (xy 197.90537 -284.499812) (xy 197.904875 -284.524419) (xy 197.89698 -284.572996)
			(xy 197.881396 -284.619677) (xy 197.858525 -284.663254) (xy 197.82896 -284.702598) (xy 197.793467 -284.73669)
			(xy 197.752964 -284.764646) (xy 197.708502 -284.785744) (xy 197.661231 -284.799436) (xy 197.612376 -284.805368)
			(xy 197.563201 -284.803387) (xy 197.514982 -284.793543) (xy 197.468966 -284.776091) (xy 197.426345 -284.751484)
			(xy 197.388224 -284.720359) (xy 197.355589 -284.683522) (xy 197.329286 -284.641926) (xy 197.309995 -284.59665)
			(xy 197.298218 -284.548866) (xy 197.294258 -284.499812) (xy 196.977 -284.499812) (xy 196.976496 -284.52552)
			(xy 196.968453 -284.576302) (xy 196.952565 -284.625201) (xy 196.929222 -284.671013) (xy 196.899001 -284.712609)
			(xy 196.862645 -284.748965) (xy 196.821049 -284.779186) (xy 196.775237 -284.802529) (xy 196.726338 -284.818417)
			(xy 196.675556 -284.82646) (xy 196.62414 -284.82646) (xy 196.573358 -284.818417) (xy 196.524459 -284.802529)
			(xy 196.478647 -284.779186) (xy 196.437051 -284.748965) (xy 196.400695 -284.712609) (xy 196.370474 -284.671013)
			(xy 196.347131 -284.625201) (xy 196.331243 -284.576302) (xy 196.3232 -284.52552) (xy 196.026536 -284.52552)
			(xy 196.018493 -284.576302) (xy 196.002605 -284.625201) (xy 195.979262 -284.671013) (xy 195.949041 -284.712609)
			(xy 195.912685 -284.748965) (xy 195.871089 -284.779186) (xy 195.825277 -284.802529) (xy 195.776378 -284.818417)
			(xy 195.725596 -284.82646) (xy 195.67418 -284.82646) (xy 195.623398 -284.818417) (xy 195.574499 -284.802529)
			(xy 195.528687 -284.779186) (xy 195.487091 -284.748965) (xy 195.450735 -284.712609) (xy 195.420514 -284.671013)
			(xy 195.397171 -284.625201) (xy 195.381283 -284.576302) (xy 195.37324 -284.52552) (xy 195.054562 -284.52552)
			(xy 195.046846 -284.572996) (xy 195.031262 -284.619677) (xy 195.008391 -284.663254) (xy 194.978826 -284.702598)
			(xy 194.943333 -284.73669) (xy 194.90283 -284.764646) (xy 194.858368 -284.785744) (xy 194.811097 -284.799436)
			(xy 194.762242 -284.805368) (xy 194.713067 -284.803387) (xy 194.664848 -284.793543) (xy 194.618832 -284.776091)
			(xy 194.576211 -284.751484) (xy 194.53809 -284.720359) (xy 194.505455 -284.683522) (xy 194.479152 -284.641926)
			(xy 194.459861 -284.59665) (xy 194.448084 -284.548866) (xy 194.444124 -284.499812) (xy 194.12712 -284.499812)
			(xy 194.126616 -284.52552) (xy 194.118573 -284.576302) (xy 194.102685 -284.625201) (xy 194.079342 -284.671013)
			(xy 194.049121 -284.712609) (xy 194.012765 -284.748965) (xy 193.971169 -284.779186) (xy 193.925357 -284.802529)
			(xy 193.876458 -284.818417) (xy 193.825676 -284.82646) (xy 193.77426 -284.82646) (xy 193.723478 -284.818417)
			(xy 193.674579 -284.802529) (xy 193.628767 -284.779186) (xy 193.587171 -284.748965) (xy 193.550815 -284.712609)
			(xy 193.520594 -284.671013) (xy 193.497251 -284.625201) (xy 193.481363 -284.576302) (xy 193.47332 -284.52552)
			(xy 193.176656 -284.52552) (xy 193.168613 -284.576302) (xy 193.152725 -284.625201) (xy 193.129382 -284.671013)
			(xy 193.099161 -284.712609) (xy 193.062805 -284.748965) (xy 193.021209 -284.779186) (xy 192.975397 -284.802529)
			(xy 192.926498 -284.818417) (xy 192.875716 -284.82646) (xy 192.8243 -284.82646) (xy 192.773518 -284.818417)
			(xy 192.724619 -284.802529) (xy 192.678807 -284.779186) (xy 192.637211 -284.748965) (xy 192.600855 -284.712609)
			(xy 192.570634 -284.671013) (xy 192.547291 -284.625201) (xy 192.531403 -284.576302) (xy 192.52336 -284.52552)
			(xy 192.204682 -284.52552) (xy 192.196966 -284.572996) (xy 192.181382 -284.619677) (xy 192.158511 -284.663254)
			(xy 192.128946 -284.702598) (xy 192.093453 -284.73669) (xy 192.05295 -284.764646) (xy 192.008488 -284.785744)
			(xy 191.961217 -284.799436) (xy 191.912362 -284.805368) (xy 191.863187 -284.803387) (xy 191.814968 -284.793543)
			(xy 191.768952 -284.776091) (xy 191.726331 -284.751484) (xy 191.68821 -284.720359) (xy 191.655575 -284.683522)
			(xy 191.629272 -284.641926) (xy 191.609981 -284.59665) (xy 191.598204 -284.548866) (xy 191.594244 -284.499812)
			(xy 191.255142 -284.499812) (xy 191.254647 -284.524419) (xy 191.246752 -284.572996) (xy 191.231168 -284.619677)
			(xy 191.208297 -284.663254) (xy 191.178732 -284.702598) (xy 191.143239 -284.73669) (xy 191.102736 -284.764646)
			(xy 191.058274 -284.785744) (xy 191.011003 -284.799436) (xy 190.962148 -284.805368) (xy 190.912973 -284.803387)
			(xy 190.864754 -284.793543) (xy 190.818738 -284.776091) (xy 190.776117 -284.751484) (xy 190.737996 -284.720359)
			(xy 190.705361 -284.683522) (xy 190.679058 -284.641926) (xy 190.659767 -284.59665) (xy 190.64799 -284.548866)
			(xy 190.64403 -284.499812) (xy 190.305182 -284.499812) (xy 190.304687 -284.524419) (xy 190.296792 -284.572996)
			(xy 190.281208 -284.619677) (xy 190.258337 -284.663254) (xy 190.228772 -284.702598) (xy 190.193279 -284.73669)
			(xy 190.152776 -284.764646) (xy 190.108314 -284.785744) (xy 190.061043 -284.799436) (xy 190.012188 -284.805368)
			(xy 189.963013 -284.803387) (xy 189.914794 -284.793543) (xy 189.868778 -284.776091) (xy 189.826157 -284.751484)
			(xy 189.788036 -284.720359) (xy 189.755401 -284.683522) (xy 189.729098 -284.641926) (xy 189.709807 -284.59665)
			(xy 189.69803 -284.548866) (xy 189.69407 -284.499812) (xy 136.94918 -284.499812) (xy 136.94918 -285.029656)
			(xy 141.911576 -285.029656) (xy 141.915647 -284.974034) (xy 141.927773 -284.919597) (xy 141.947696 -284.867506)
			(xy 141.974992 -284.818871) (xy 142.009078 -284.774728) (xy 142.049227 -284.736019) (xy 142.094585 -284.703568)
			(xy 142.144185 -284.678067) (xy 142.196969 -284.66006) (xy 142.251812 -284.64993) (xy 142.307546 -284.647893)
			(xy 142.362983 -284.653993) (xy 142.41694 -284.668099) (xy 142.468269 -284.689911) (xy 142.515875 -284.718965)
			(xy 142.558743 -284.75464) (xy 142.59596 -284.796177) (xy 142.626733 -284.84269) (xy 142.650405 -284.893187)
			(xy 142.666473 -284.946594) (xy 142.674593 -285.00177) (xy 142.675102 -285.029656) (xy 143.396714 -285.029656)
			(xy 143.400785 -284.974034) (xy 143.412911 -284.919597) (xy 143.432834 -284.867506) (xy 143.46013 -284.818871)
			(xy 143.494216 -284.774728) (xy 143.534365 -284.736019) (xy 143.579723 -284.703568) (xy 143.629323 -284.678067)
			(xy 143.682107 -284.66006) (xy 143.73695 -284.64993) (xy 143.792684 -284.647893) (xy 143.848121 -284.653993)
			(xy 143.902078 -284.668099) (xy 143.953407 -284.689911) (xy 144.001013 -284.718965) (xy 144.043881 -284.75464)
			(xy 144.081098 -284.796177) (xy 144.111871 -284.84269) (xy 144.135543 -284.893187) (xy 144.151611 -284.946594)
			(xy 144.155761 -284.974792) (xy 152.169126 -284.974792) (xy 152.173086 -284.925738) (xy 152.184863 -284.877954)
			(xy 152.204154 -284.832678) (xy 152.230457 -284.791082) (xy 152.263092 -284.754245) (xy 152.301213 -284.72312)
			(xy 152.343834 -284.698513) (xy 152.38985 -284.681061) (xy 152.438069 -284.671217) (xy 152.487244 -284.669236)
			(xy 152.536099 -284.675168) (xy 152.58337 -284.68886) (xy 152.627832 -284.709958) (xy 152.668335 -284.737914)
			(xy 152.703828 -284.772006) (xy 152.733393 -284.81135) (xy 152.756264 -284.854927) (xy 152.771848 -284.901608)
			(xy 152.779743 -284.950185) (xy 152.780238 -284.974792) (xy 153.119086 -284.974792) (xy 153.123046 -284.925738)
			(xy 153.134823 -284.877954) (xy 153.154114 -284.832678) (xy 153.180417 -284.791082) (xy 153.213052 -284.754245)
			(xy 153.251173 -284.72312) (xy 153.293794 -284.698513) (xy 153.33981 -284.681061) (xy 153.388029 -284.671217)
			(xy 153.437204 -284.669236) (xy 153.486059 -284.675168) (xy 153.53333 -284.68886) (xy 153.577792 -284.709958)
			(xy 153.618295 -284.737914) (xy 153.653788 -284.772006) (xy 153.683353 -284.81135) (xy 153.706224 -284.854927)
			(xy 153.721808 -284.901608) (xy 153.729703 -284.950185) (xy 153.730198 -284.974792) (xy 154.0693 -284.974792)
			(xy 154.07326 -284.925738) (xy 154.085037 -284.877954) (xy 154.104328 -284.832678) (xy 154.130631 -284.791082)
			(xy 154.163266 -284.754245) (xy 154.201387 -284.72312) (xy 154.244008 -284.698513) (xy 154.290024 -284.681061)
			(xy 154.338243 -284.671217) (xy 154.387418 -284.669236) (xy 154.436273 -284.675168) (xy 154.483544 -284.68886)
			(xy 154.528006 -284.709958) (xy 154.568509 -284.737914) (xy 154.604002 -284.772006) (xy 154.633567 -284.81135)
			(xy 154.656438 -284.854927) (xy 154.672022 -284.901608) (xy 154.679917 -284.950185) (xy 154.680412 -284.974792)
			(xy 155.01926 -284.974792) (xy 155.02322 -284.925738) (xy 155.034997 -284.877954) (xy 155.054288 -284.832678)
			(xy 155.080591 -284.791082) (xy 155.113226 -284.754245) (xy 155.151347 -284.72312) (xy 155.193968 -284.698513)
			(xy 155.239984 -284.681061) (xy 155.288203 -284.671217) (xy 155.337378 -284.669236) (xy 155.386233 -284.675168)
			(xy 155.433504 -284.68886) (xy 155.477966 -284.709958) (xy 155.518469 -284.737914) (xy 155.553962 -284.772006)
			(xy 155.583527 -284.81135) (xy 155.606398 -284.854927) (xy 155.621982 -284.901608) (xy 155.629877 -284.950185)
			(xy 155.630372 -284.974792) (xy 155.96922 -284.974792) (xy 155.97318 -284.925738) (xy 155.984957 -284.877954)
			(xy 156.004248 -284.832678) (xy 156.030551 -284.791082) (xy 156.063186 -284.754245) (xy 156.101307 -284.72312)
			(xy 156.143928 -284.698513) (xy 156.189944 -284.681061) (xy 156.238163 -284.671217) (xy 156.287338 -284.669236)
			(xy 156.336193 -284.675168) (xy 156.383464 -284.68886) (xy 156.427926 -284.709958) (xy 156.468429 -284.737914)
			(xy 156.503922 -284.772006) (xy 156.533487 -284.81135) (xy 156.556358 -284.854927) (xy 156.571942 -284.901608)
			(xy 156.579837 -284.950185) (xy 156.580332 -284.974792) (xy 158.8191 -284.974792) (xy 158.82306 -284.925738)
			(xy 158.834837 -284.877954) (xy 158.854128 -284.832678) (xy 158.880431 -284.791082) (xy 158.913066 -284.754245)
			(xy 158.951187 -284.72312) (xy 158.993808 -284.698513) (xy 159.039824 -284.681061) (xy 159.088043 -284.671217)
			(xy 159.137218 -284.669236) (xy 159.186073 -284.675168) (xy 159.233344 -284.68886) (xy 159.277806 -284.709958)
			(xy 159.318309 -284.737914) (xy 159.353802 -284.772006) (xy 159.383367 -284.81135) (xy 159.406238 -284.854927)
			(xy 159.421822 -284.901608) (xy 159.429717 -284.950185) (xy 159.430212 -284.974792) (xy 160.719274 -284.974792)
			(xy 160.723234 -284.925738) (xy 160.735011 -284.877954) (xy 160.754302 -284.832678) (xy 160.780605 -284.791082)
			(xy 160.81324 -284.754245) (xy 160.851361 -284.72312) (xy 160.893982 -284.698513) (xy 160.939998 -284.681061)
			(xy 160.988217 -284.671217) (xy 161.037392 -284.669236) (xy 161.086247 -284.675168) (xy 161.133518 -284.68886)
			(xy 161.17798 -284.709958) (xy 161.218483 -284.737914) (xy 161.253976 -284.772006) (xy 161.283541 -284.81135)
			(xy 161.306412 -284.854927) (xy 161.321996 -284.901608) (xy 161.329891 -284.950185) (xy 161.330386 -284.974792)
			(xy 161.669234 -284.974792) (xy 161.673194 -284.925738) (xy 161.684971 -284.877954) (xy 161.704262 -284.832678)
			(xy 161.730565 -284.791082) (xy 161.7632 -284.754245) (xy 161.801321 -284.72312) (xy 161.843942 -284.698513)
			(xy 161.889958 -284.681061) (xy 161.938177 -284.671217) (xy 161.987352 -284.669236) (xy 162.036207 -284.675168)
			(xy 162.083478 -284.68886) (xy 162.12794 -284.709958) (xy 162.168443 -284.737914) (xy 162.203936 -284.772006)
			(xy 162.233501 -284.81135) (xy 162.256372 -284.854927) (xy 162.271956 -284.901608) (xy 162.279851 -284.950185)
			(xy 162.280346 -284.974792) (xy 162.619194 -284.974792) (xy 162.623154 -284.925738) (xy 162.634931 -284.877954)
			(xy 162.654222 -284.832678) (xy 162.680525 -284.791082) (xy 162.71316 -284.754245) (xy 162.751281 -284.72312)
			(xy 162.793902 -284.698513) (xy 162.839918 -284.681061) (xy 162.888137 -284.671217) (xy 162.937312 -284.669236)
			(xy 162.986167 -284.675168) (xy 163.033438 -284.68886) (xy 163.0779 -284.709958) (xy 163.118403 -284.737914)
			(xy 163.153896 -284.772006) (xy 163.183461 -284.81135) (xy 163.206332 -284.854927) (xy 163.221916 -284.901608)
			(xy 163.229811 -284.950185) (xy 163.230306 -284.974792) (xy 163.569154 -284.974792) (xy 163.573114 -284.925738)
			(xy 163.584891 -284.877954) (xy 163.604182 -284.832678) (xy 163.630485 -284.791082) (xy 163.66312 -284.754245)
			(xy 163.701241 -284.72312) (xy 163.743862 -284.698513) (xy 163.789878 -284.681061) (xy 163.838097 -284.671217)
			(xy 163.887272 -284.669236) (xy 163.936127 -284.675168) (xy 163.983398 -284.68886) (xy 164.02786 -284.709958)
			(xy 164.068363 -284.737914) (xy 164.103856 -284.772006) (xy 164.133421 -284.81135) (xy 164.156292 -284.854927)
			(xy 164.171876 -284.901608) (xy 164.179771 -284.950185) (xy 164.180266 -284.974792) (xy 164.519114 -284.974792)
			(xy 164.523074 -284.925738) (xy 164.534851 -284.877954) (xy 164.554142 -284.832678) (xy 164.580445 -284.791082)
			(xy 164.61308 -284.754245) (xy 164.651201 -284.72312) (xy 164.693822 -284.698513) (xy 164.739838 -284.681061)
			(xy 164.788057 -284.671217) (xy 164.837232 -284.669236) (xy 164.886087 -284.675168) (xy 164.933358 -284.68886)
			(xy 164.97782 -284.709958) (xy 165.018323 -284.737914) (xy 165.053816 -284.772006) (xy 165.083381 -284.81135)
			(xy 165.106252 -284.854927) (xy 165.121836 -284.901608) (xy 165.129731 -284.950185) (xy 165.130226 -284.974792)
			(xy 165.469074 -284.974792) (xy 165.473034 -284.925738) (xy 165.484811 -284.877954) (xy 165.504102 -284.832678)
			(xy 165.530405 -284.791082) (xy 165.56304 -284.754245) (xy 165.601161 -284.72312) (xy 165.643782 -284.698513)
			(xy 165.689798 -284.681061) (xy 165.738017 -284.671217) (xy 165.787192 -284.669236) (xy 165.836047 -284.675168)
			(xy 165.883318 -284.68886) (xy 165.92778 -284.709958) (xy 165.968283 -284.737914) (xy 166.003776 -284.772006)
			(xy 166.033341 -284.81135) (xy 166.056212 -284.854927) (xy 166.071796 -284.901608) (xy 166.079691 -284.950185)
			(xy 166.080186 -284.974792) (xy 166.419288 -284.974792) (xy 166.423248 -284.925738) (xy 166.435025 -284.877954)
			(xy 166.454316 -284.832678) (xy 166.480619 -284.791082) (xy 166.513254 -284.754245) (xy 166.551375 -284.72312)
			(xy 166.593996 -284.698513) (xy 166.640012 -284.681061) (xy 166.688231 -284.671217) (xy 166.737406 -284.669236)
			(xy 166.786261 -284.675168) (xy 166.833532 -284.68886) (xy 166.877994 -284.709958) (xy 166.918497 -284.737914)
			(xy 166.95399 -284.772006) (xy 166.983555 -284.81135) (xy 167.006426 -284.854927) (xy 167.02201 -284.901608)
			(xy 167.029905 -284.950185) (xy 167.0304 -284.974792) (xy 167.369248 -284.974792) (xy 167.373208 -284.925738)
			(xy 167.384985 -284.877954) (xy 167.404276 -284.832678) (xy 167.430579 -284.791082) (xy 167.463214 -284.754245)
			(xy 167.501335 -284.72312) (xy 167.543956 -284.698513) (xy 167.589972 -284.681061) (xy 167.638191 -284.671217)
			(xy 167.687366 -284.669236) (xy 167.736221 -284.675168) (xy 167.783492 -284.68886) (xy 167.827954 -284.709958)
			(xy 167.868457 -284.737914) (xy 167.90395 -284.772006) (xy 167.933515 -284.81135) (xy 167.956386 -284.854927)
			(xy 167.97197 -284.901608) (xy 167.979865 -284.950185) (xy 167.98036 -284.974792) (xy 168.319208 -284.974792)
			(xy 168.323168 -284.925738) (xy 168.334945 -284.877954) (xy 168.354236 -284.832678) (xy 168.380539 -284.791082)
			(xy 168.413174 -284.754245) (xy 168.451295 -284.72312) (xy 168.493916 -284.698513) (xy 168.539932 -284.681061)
			(xy 168.588151 -284.671217) (xy 168.637326 -284.669236) (xy 168.686181 -284.675168) (xy 168.733452 -284.68886)
			(xy 168.777914 -284.709958) (xy 168.818417 -284.737914) (xy 168.85391 -284.772006) (xy 168.883475 -284.81135)
			(xy 168.906346 -284.854927) (xy 168.92193 -284.901608) (xy 168.929825 -284.950185) (xy 168.93032 -284.974792)
			(xy 169.269168 -284.974792) (xy 169.273128 -284.925738) (xy 169.284905 -284.877954) (xy 169.304196 -284.832678)
			(xy 169.330499 -284.791082) (xy 169.363134 -284.754245) (xy 169.401255 -284.72312) (xy 169.443876 -284.698513)
			(xy 169.489892 -284.681061) (xy 169.538111 -284.671217) (xy 169.587286 -284.669236) (xy 169.636141 -284.675168)
			(xy 169.683412 -284.68886) (xy 169.727874 -284.709958) (xy 169.768377 -284.737914) (xy 169.80387 -284.772006)
			(xy 169.833435 -284.81135) (xy 169.856306 -284.854927) (xy 169.87189 -284.901608) (xy 169.879785 -284.950185)
			(xy 169.88028 -284.974792) (xy 170.219128 -284.974792) (xy 170.223088 -284.925738) (xy 170.234865 -284.877954)
			(xy 170.254156 -284.832678) (xy 170.280459 -284.791082) (xy 170.313094 -284.754245) (xy 170.351215 -284.72312)
			(xy 170.393836 -284.698513) (xy 170.439852 -284.681061) (xy 170.488071 -284.671217) (xy 170.537246 -284.669236)
			(xy 170.586101 -284.675168) (xy 170.633372 -284.68886) (xy 170.677834 -284.709958) (xy 170.718337 -284.737914)
			(xy 170.75383 -284.772006) (xy 170.783395 -284.81135) (xy 170.806266 -284.854927) (xy 170.82185 -284.901608)
			(xy 170.829745 -284.950185) (xy 170.83024 -284.974792) (xy 171.169088 -284.974792) (xy 171.173048 -284.925738)
			(xy 171.184825 -284.877954) (xy 171.204116 -284.832678) (xy 171.230419 -284.791082) (xy 171.263054 -284.754245)
			(xy 171.301175 -284.72312) (xy 171.343796 -284.698513) (xy 171.389812 -284.681061) (xy 171.438031 -284.671217)
			(xy 171.487206 -284.669236) (xy 171.536061 -284.675168) (xy 171.583332 -284.68886) (xy 171.627794 -284.709958)
			(xy 171.668297 -284.737914) (xy 171.70379 -284.772006) (xy 171.733355 -284.81135) (xy 171.756226 -284.854927)
			(xy 171.77181 -284.901608) (xy 171.779705 -284.950185) (xy 171.7802 -284.974792) (xy 172.119048 -284.974792)
			(xy 172.123008 -284.925738) (xy 172.134785 -284.877954) (xy 172.154076 -284.832678) (xy 172.180379 -284.791082)
			(xy 172.213014 -284.754245) (xy 172.251135 -284.72312) (xy 172.293756 -284.698513) (xy 172.339772 -284.681061)
			(xy 172.387991 -284.671217) (xy 172.437166 -284.669236) (xy 172.486021 -284.675168) (xy 172.533292 -284.68886)
			(xy 172.577754 -284.709958) (xy 172.618257 -284.737914) (xy 172.65375 -284.772006) (xy 172.683315 -284.81135)
			(xy 172.706186 -284.854927) (xy 172.72177 -284.901608) (xy 172.729665 -284.950185) (xy 172.73016 -284.974792)
			(xy 173.069262 -284.974792) (xy 173.073222 -284.925738) (xy 173.084999 -284.877954) (xy 173.10429 -284.832678)
			(xy 173.130593 -284.791082) (xy 173.163228 -284.754245) (xy 173.201349 -284.72312) (xy 173.24397 -284.698513)
			(xy 173.289986 -284.681061) (xy 173.338205 -284.671217) (xy 173.38738 -284.669236) (xy 173.436235 -284.675168)
			(xy 173.483506 -284.68886) (xy 173.527968 -284.709958) (xy 173.568471 -284.737914) (xy 173.603964 -284.772006)
			(xy 173.633529 -284.81135) (xy 173.6564 -284.854927) (xy 173.671984 -284.901608) (xy 173.679879 -284.950185)
			(xy 173.680374 -284.974792) (xy 174.019222 -284.974792) (xy 174.023182 -284.925738) (xy 174.034959 -284.877954)
			(xy 174.05425 -284.832678) (xy 174.080553 -284.791082) (xy 174.113188 -284.754245) (xy 174.151309 -284.72312)
			(xy 174.19393 -284.698513) (xy 174.239946 -284.681061) (xy 174.288165 -284.671217) (xy 174.33734 -284.669236)
			(xy 174.386195 -284.675168) (xy 174.433466 -284.68886) (xy 174.477928 -284.709958) (xy 174.518431 -284.737914)
			(xy 174.553924 -284.772006) (xy 174.583489 -284.81135) (xy 174.60636 -284.854927) (xy 174.621944 -284.901608)
			(xy 174.629839 -284.950185) (xy 174.630334 -284.974792) (xy 175.919142 -284.974792) (xy 175.923102 -284.925738)
			(xy 175.934879 -284.877954) (xy 175.95417 -284.832678) (xy 175.980473 -284.791082) (xy 176.013108 -284.754245)
			(xy 176.051229 -284.72312) (xy 176.09385 -284.698513) (xy 176.139866 -284.681061) (xy 176.188085 -284.671217)
			(xy 176.23726 -284.669236) (xy 176.286115 -284.675168) (xy 176.333386 -284.68886) (xy 176.377848 -284.709958)
			(xy 176.418351 -284.737914) (xy 176.453844 -284.772006) (xy 176.483409 -284.81135) (xy 176.50628 -284.854927)
			(xy 176.521864 -284.901608) (xy 176.529759 -284.950185) (xy 176.530254 -284.974792) (xy 176.869102 -284.974792)
			(xy 176.873062 -284.925738) (xy 176.884839 -284.877954) (xy 176.90413 -284.832678) (xy 176.930433 -284.791082)
			(xy 176.963068 -284.754245) (xy 177.001189 -284.72312) (xy 177.04381 -284.698513) (xy 177.089826 -284.681061)
			(xy 177.138045 -284.671217) (xy 177.18722 -284.669236) (xy 177.236075 -284.675168) (xy 177.283346 -284.68886)
			(xy 177.327808 -284.709958) (xy 177.368311 -284.737914) (xy 177.403804 -284.772006) (xy 177.433369 -284.81135)
			(xy 177.45624 -284.854927) (xy 177.471824 -284.901608) (xy 177.479719 -284.950185) (xy 177.480214 -284.974792)
			(xy 177.819062 -284.974792) (xy 177.823022 -284.925738) (xy 177.834799 -284.877954) (xy 177.85409 -284.832678)
			(xy 177.880393 -284.791082) (xy 177.913028 -284.754245) (xy 177.951149 -284.72312) (xy 177.99377 -284.698513)
			(xy 178.039786 -284.681061) (xy 178.088005 -284.671217) (xy 178.13718 -284.669236) (xy 178.186035 -284.675168)
			(xy 178.233306 -284.68886) (xy 178.277768 -284.709958) (xy 178.318271 -284.737914) (xy 178.353764 -284.772006)
			(xy 178.383329 -284.81135) (xy 178.4062 -284.854927) (xy 178.421784 -284.901608) (xy 178.429679 -284.950185)
			(xy 178.430174 -284.974792) (xy 178.769276 -284.974792) (xy 178.773236 -284.925738) (xy 178.785013 -284.877954)
			(xy 178.804304 -284.832678) (xy 178.830607 -284.791082) (xy 178.863242 -284.754245) (xy 178.901363 -284.72312)
			(xy 178.943984 -284.698513) (xy 178.99 -284.681061) (xy 179.038219 -284.671217) (xy 179.087394 -284.669236)
			(xy 179.136249 -284.675168) (xy 179.18352 -284.68886) (xy 179.227982 -284.709958) (xy 179.268485 -284.737914)
			(xy 179.303978 -284.772006) (xy 179.333543 -284.81135) (xy 179.356414 -284.854927) (xy 179.371998 -284.901608)
			(xy 179.379893 -284.950185) (xy 179.380388 -284.974792) (xy 179.719236 -284.974792) (xy 179.723196 -284.925738)
			(xy 179.734973 -284.877954) (xy 179.754264 -284.832678) (xy 179.780567 -284.791082) (xy 179.813202 -284.754245)
			(xy 179.851323 -284.72312) (xy 179.893944 -284.698513) (xy 179.93996 -284.681061) (xy 179.988179 -284.671217)
			(xy 180.037354 -284.669236) (xy 180.086209 -284.675168) (xy 180.13348 -284.68886) (xy 180.177942 -284.709958)
			(xy 180.218445 -284.737914) (xy 180.253938 -284.772006) (xy 180.283503 -284.81135) (xy 180.306374 -284.854927)
			(xy 180.321958 -284.901608) (xy 180.329853 -284.950185) (xy 180.330348 -284.974792) (xy 180.669196 -284.974792)
			(xy 180.673156 -284.925738) (xy 180.684933 -284.877954) (xy 180.704224 -284.832678) (xy 180.730527 -284.791082)
			(xy 180.763162 -284.754245) (xy 180.801283 -284.72312) (xy 180.843904 -284.698513) (xy 180.88992 -284.681061)
			(xy 180.938139 -284.671217) (xy 180.987314 -284.669236) (xy 181.036169 -284.675168) (xy 181.08344 -284.68886)
			(xy 181.127902 -284.709958) (xy 181.168405 -284.737914) (xy 181.203898 -284.772006) (xy 181.233463 -284.81135)
			(xy 181.256334 -284.854927) (xy 181.271918 -284.901608) (xy 181.279813 -284.950185) (xy 181.280308 -284.974792)
			(xy 181.619156 -284.974792) (xy 181.623116 -284.925738) (xy 181.634893 -284.877954) (xy 181.654184 -284.832678)
			(xy 181.680487 -284.791082) (xy 181.713122 -284.754245) (xy 181.751243 -284.72312) (xy 181.793864 -284.698513)
			(xy 181.83988 -284.681061) (xy 181.888099 -284.671217) (xy 181.937274 -284.669236) (xy 181.986129 -284.675168)
			(xy 182.0334 -284.68886) (xy 182.077862 -284.709958) (xy 182.118365 -284.737914) (xy 182.153858 -284.772006)
			(xy 182.183423 -284.81135) (xy 182.206294 -284.854927) (xy 182.221878 -284.901608) (xy 182.229773 -284.950185)
			(xy 182.230268 -284.974792) (xy 182.569116 -284.974792) (xy 182.573076 -284.925738) (xy 182.584853 -284.877954)
			(xy 182.604144 -284.832678) (xy 182.630447 -284.791082) (xy 182.663082 -284.754245) (xy 182.701203 -284.72312)
			(xy 182.743824 -284.698513) (xy 182.78984 -284.681061) (xy 182.838059 -284.671217) (xy 182.887234 -284.669236)
			(xy 182.936089 -284.675168) (xy 182.98336 -284.68886) (xy 183.027822 -284.709958) (xy 183.068325 -284.737914)
			(xy 183.103818 -284.772006) (xy 183.133383 -284.81135) (xy 183.156254 -284.854927) (xy 183.171838 -284.901608)
			(xy 183.179733 -284.950185) (xy 183.180228 -284.974792) (xy 183.519076 -284.974792) (xy 183.523036 -284.925738)
			(xy 183.534813 -284.877954) (xy 183.554104 -284.832678) (xy 183.580407 -284.791082) (xy 183.613042 -284.754245)
			(xy 183.651163 -284.72312) (xy 183.693784 -284.698513) (xy 183.7398 -284.681061) (xy 183.788019 -284.671217)
			(xy 183.837194 -284.669236) (xy 183.886049 -284.675168) (xy 183.93332 -284.68886) (xy 183.977782 -284.709958)
			(xy 184.018285 -284.737914) (xy 184.053778 -284.772006) (xy 184.083343 -284.81135) (xy 184.106214 -284.854927)
			(xy 184.121798 -284.901608) (xy 184.129693 -284.950185) (xy 184.130188 -284.974792) (xy 184.469036 -284.974792)
			(xy 184.472996 -284.925738) (xy 184.484773 -284.877954) (xy 184.504064 -284.832678) (xy 184.530367 -284.791082)
			(xy 184.563002 -284.754245) (xy 184.601123 -284.72312) (xy 184.643744 -284.698513) (xy 184.68976 -284.681061)
			(xy 184.737979 -284.671217) (xy 184.787154 -284.669236) (xy 184.836009 -284.675168) (xy 184.88328 -284.68886)
			(xy 184.927742 -284.709958) (xy 184.968245 -284.737914) (xy 185.003738 -284.772006) (xy 185.033303 -284.81135)
			(xy 185.056174 -284.854927) (xy 185.071758 -284.901608) (xy 185.079653 -284.950185) (xy 185.080148 -284.974792)
			(xy 185.41925 -284.974792) (xy 185.42321 -284.925738) (xy 185.434987 -284.877954) (xy 185.454278 -284.832678)
			(xy 185.480581 -284.791082) (xy 185.513216 -284.754245) (xy 185.551337 -284.72312) (xy 185.593958 -284.698513)
			(xy 185.639974 -284.681061) (xy 185.688193 -284.671217) (xy 185.737368 -284.669236) (xy 185.786223 -284.675168)
			(xy 185.833494 -284.68886) (xy 185.877956 -284.709958) (xy 185.918459 -284.737914) (xy 185.953952 -284.772006)
			(xy 185.983517 -284.81135) (xy 186.006388 -284.854927) (xy 186.021972 -284.901608) (xy 186.029867 -284.950185)
			(xy 186.030362 -284.974792) (xy 186.36921 -284.974792) (xy 186.37317 -284.925738) (xy 186.384947 -284.877954)
			(xy 186.404238 -284.832678) (xy 186.430541 -284.791082) (xy 186.463176 -284.754245) (xy 186.501297 -284.72312)
			(xy 186.543918 -284.698513) (xy 186.589934 -284.681061) (xy 186.638153 -284.671217) (xy 186.687328 -284.669236)
			(xy 186.736183 -284.675168) (xy 186.783454 -284.68886) (xy 186.827916 -284.709958) (xy 186.868419 -284.737914)
			(xy 186.903912 -284.772006) (xy 186.933477 -284.81135) (xy 186.956348 -284.854927) (xy 186.971932 -284.901608)
			(xy 186.979827 -284.950185) (xy 186.980322 -284.974792) (xy 186.979827 -284.999399) (xy 186.971932 -285.047976)
			(xy 186.956348 -285.094657) (xy 186.933477 -285.138234) (xy 186.903912 -285.177578) (xy 186.868419 -285.21167)
			(xy 186.827916 -285.239626) (xy 186.783454 -285.260724) (xy 186.736183 -285.274416) (xy 186.687328 -285.280348)
			(xy 186.638153 -285.278367) (xy 186.589934 -285.268523) (xy 186.543918 -285.251071) (xy 186.501297 -285.226464)
			(xy 186.463176 -285.195339) (xy 186.430541 -285.158502) (xy 186.404238 -285.116906) (xy 186.384947 -285.07163)
			(xy 186.37317 -285.023846) (xy 186.36921 -284.974792) (xy 186.030362 -284.974792) (xy 186.029867 -284.999399)
			(xy 186.021972 -285.047976) (xy 186.006388 -285.094657) (xy 185.983517 -285.138234) (xy 185.953952 -285.177578)
			(xy 185.918459 -285.21167) (xy 185.877956 -285.239626) (xy 185.833494 -285.260724) (xy 185.786223 -285.274416)
			(xy 185.737368 -285.280348) (xy 185.688193 -285.278367) (xy 185.639974 -285.268523) (xy 185.593958 -285.251071)
			(xy 185.551337 -285.226464) (xy 185.513216 -285.195339) (xy 185.480581 -285.158502) (xy 185.454278 -285.116906)
			(xy 185.434987 -285.07163) (xy 185.42321 -285.023846) (xy 185.41925 -284.974792) (xy 185.080148 -284.974792)
			(xy 185.079653 -284.999399) (xy 185.071758 -285.047976) (xy 185.056174 -285.094657) (xy 185.033303 -285.138234)
			(xy 185.003738 -285.177578) (xy 184.968245 -285.21167) (xy 184.927742 -285.239626) (xy 184.88328 -285.260724)
			(xy 184.836009 -285.274416) (xy 184.787154 -285.280348) (xy 184.737979 -285.278367) (xy 184.68976 -285.268523)
			(xy 184.643744 -285.251071) (xy 184.601123 -285.226464) (xy 184.563002 -285.195339) (xy 184.530367 -285.158502)
			(xy 184.504064 -285.116906) (xy 184.484773 -285.07163) (xy 184.472996 -285.023846) (xy 184.469036 -284.974792)
			(xy 184.130188 -284.974792) (xy 184.129693 -284.999399) (xy 184.121798 -285.047976) (xy 184.106214 -285.094657)
			(xy 184.083343 -285.138234) (xy 184.053778 -285.177578) (xy 184.018285 -285.21167) (xy 183.977782 -285.239626)
			(xy 183.93332 -285.260724) (xy 183.886049 -285.274416) (xy 183.837194 -285.280348) (xy 183.788019 -285.278367)
			(xy 183.7398 -285.268523) (xy 183.693784 -285.251071) (xy 183.651163 -285.226464) (xy 183.613042 -285.195339)
			(xy 183.580407 -285.158502) (xy 183.554104 -285.116906) (xy 183.534813 -285.07163) (xy 183.523036 -285.023846)
			(xy 183.519076 -284.974792) (xy 183.180228 -284.974792) (xy 183.179733 -284.999399) (xy 183.171838 -285.047976)
			(xy 183.156254 -285.094657) (xy 183.133383 -285.138234) (xy 183.103818 -285.177578) (xy 183.068325 -285.21167)
			(xy 183.027822 -285.239626) (xy 182.98336 -285.260724) (xy 182.936089 -285.274416) (xy 182.887234 -285.280348)
			(xy 182.838059 -285.278367) (xy 182.78984 -285.268523) (xy 182.743824 -285.251071) (xy 182.701203 -285.226464)
			(xy 182.663082 -285.195339) (xy 182.630447 -285.158502) (xy 182.604144 -285.116906) (xy 182.584853 -285.07163)
			(xy 182.573076 -285.023846) (xy 182.569116 -284.974792) (xy 182.230268 -284.974792) (xy 182.229773 -284.999399)
			(xy 182.221878 -285.047976) (xy 182.206294 -285.094657) (xy 182.183423 -285.138234) (xy 182.153858 -285.177578)
			(xy 182.118365 -285.21167) (xy 182.077862 -285.239626) (xy 182.0334 -285.260724) (xy 181.986129 -285.274416)
			(xy 181.937274 -285.280348) (xy 181.888099 -285.278367) (xy 181.83988 -285.268523) (xy 181.793864 -285.251071)
			(xy 181.751243 -285.226464) (xy 181.713122 -285.195339) (xy 181.680487 -285.158502) (xy 181.654184 -285.116906)
			(xy 181.634893 -285.07163) (xy 181.623116 -285.023846) (xy 181.619156 -284.974792) (xy 181.280308 -284.974792)
			(xy 181.279813 -284.999399) (xy 181.271918 -285.047976) (xy 181.256334 -285.094657) (xy 181.233463 -285.138234)
			(xy 181.203898 -285.177578) (xy 181.168405 -285.21167) (xy 181.127902 -285.239626) (xy 181.08344 -285.260724)
			(xy 181.036169 -285.274416) (xy 180.987314 -285.280348) (xy 180.938139 -285.278367) (xy 180.88992 -285.268523)
			(xy 180.843904 -285.251071) (xy 180.801283 -285.226464) (xy 180.763162 -285.195339) (xy 180.730527 -285.158502)
			(xy 180.704224 -285.116906) (xy 180.684933 -285.07163) (xy 180.673156 -285.023846) (xy 180.669196 -284.974792)
			(xy 180.330348 -284.974792) (xy 180.329853 -284.999399) (xy 180.321958 -285.047976) (xy 180.306374 -285.094657)
			(xy 180.283503 -285.138234) (xy 180.253938 -285.177578) (xy 180.218445 -285.21167) (xy 180.177942 -285.239626)
			(xy 180.13348 -285.260724) (xy 180.086209 -285.274416) (xy 180.037354 -285.280348) (xy 179.988179 -285.278367)
			(xy 179.93996 -285.268523) (xy 179.893944 -285.251071) (xy 179.851323 -285.226464) (xy 179.813202 -285.195339)
			(xy 179.780567 -285.158502) (xy 179.754264 -285.116906) (xy 179.734973 -285.07163) (xy 179.723196 -285.023846)
			(xy 179.719236 -284.974792) (xy 179.380388 -284.974792) (xy 179.379893 -284.999399) (xy 179.371998 -285.047976)
			(xy 179.356414 -285.094657) (xy 179.333543 -285.138234) (xy 179.303978 -285.177578) (xy 179.268485 -285.21167)
			(xy 179.227982 -285.239626) (xy 179.18352 -285.260724) (xy 179.136249 -285.274416) (xy 179.087394 -285.280348)
			(xy 179.038219 -285.278367) (xy 178.99 -285.268523) (xy 178.943984 -285.251071) (xy 178.901363 -285.226464)
			(xy 178.863242 -285.195339) (xy 178.830607 -285.158502) (xy 178.804304 -285.116906) (xy 178.785013 -285.07163)
			(xy 178.773236 -285.023846) (xy 178.769276 -284.974792) (xy 178.430174 -284.974792) (xy 178.429679 -284.999399)
			(xy 178.421784 -285.047976) (xy 178.4062 -285.094657) (xy 178.383329 -285.138234) (xy 178.353764 -285.177578)
			(xy 178.318271 -285.21167) (xy 178.277768 -285.239626) (xy 178.233306 -285.260724) (xy 178.186035 -285.274416)
			(xy 178.13718 -285.280348) (xy 178.088005 -285.278367) (xy 178.039786 -285.268523) (xy 177.99377 -285.251071)
			(xy 177.951149 -285.226464) (xy 177.913028 -285.195339) (xy 177.880393 -285.158502) (xy 177.85409 -285.116906)
			(xy 177.834799 -285.07163) (xy 177.823022 -285.023846) (xy 177.819062 -284.974792) (xy 177.480214 -284.974792)
			(xy 177.479719 -284.999399) (xy 177.471824 -285.047976) (xy 177.45624 -285.094657) (xy 177.433369 -285.138234)
			(xy 177.403804 -285.177578) (xy 177.368311 -285.21167) (xy 177.327808 -285.239626) (xy 177.283346 -285.260724)
			(xy 177.236075 -285.274416) (xy 177.18722 -285.280348) (xy 177.138045 -285.278367) (xy 177.089826 -285.268523)
			(xy 177.04381 -285.251071) (xy 177.001189 -285.226464) (xy 176.963068 -285.195339) (xy 176.930433 -285.158502)
			(xy 176.90413 -285.116906) (xy 176.884839 -285.07163) (xy 176.873062 -285.023846) (xy 176.869102 -284.974792)
			(xy 176.530254 -284.974792) (xy 176.529759 -284.999399) (xy 176.521864 -285.047976) (xy 176.50628 -285.094657)
			(xy 176.483409 -285.138234) (xy 176.453844 -285.177578) (xy 176.418351 -285.21167) (xy 176.377848 -285.239626)
			(xy 176.333386 -285.260724) (xy 176.286115 -285.274416) (xy 176.23726 -285.280348) (xy 176.188085 -285.278367)
			(xy 176.139866 -285.268523) (xy 176.09385 -285.251071) (xy 176.051229 -285.226464) (xy 176.013108 -285.195339)
			(xy 175.980473 -285.158502) (xy 175.95417 -285.116906) (xy 175.934879 -285.07163) (xy 175.923102 -285.023846)
			(xy 175.919142 -284.974792) (xy 174.630334 -284.974792) (xy 174.629839 -284.999399) (xy 174.621944 -285.047976)
			(xy 174.60636 -285.094657) (xy 174.583489 -285.138234) (xy 174.553924 -285.177578) (xy 174.518431 -285.21167)
			(xy 174.477928 -285.239626) (xy 174.433466 -285.260724) (xy 174.386195 -285.274416) (xy 174.33734 -285.280348)
			(xy 174.288165 -285.278367) (xy 174.239946 -285.268523) (xy 174.19393 -285.251071) (xy 174.151309 -285.226464)
			(xy 174.113188 -285.195339) (xy 174.080553 -285.158502) (xy 174.05425 -285.116906) (xy 174.034959 -285.07163)
			(xy 174.023182 -285.023846) (xy 174.019222 -284.974792) (xy 173.680374 -284.974792) (xy 173.679879 -284.999399)
			(xy 173.671984 -285.047976) (xy 173.6564 -285.094657) (xy 173.633529 -285.138234) (xy 173.603964 -285.177578)
			(xy 173.568471 -285.21167) (xy 173.527968 -285.239626) (xy 173.483506 -285.260724) (xy 173.436235 -285.274416)
			(xy 173.38738 -285.280348) (xy 173.338205 -285.278367) (xy 173.289986 -285.268523) (xy 173.24397 -285.251071)
			(xy 173.201349 -285.226464) (xy 173.163228 -285.195339) (xy 173.130593 -285.158502) (xy 173.10429 -285.116906)
			(xy 173.084999 -285.07163) (xy 173.073222 -285.023846) (xy 173.069262 -284.974792) (xy 172.73016 -284.974792)
			(xy 172.729665 -284.999399) (xy 172.72177 -285.047976) (xy 172.706186 -285.094657) (xy 172.683315 -285.138234)
			(xy 172.65375 -285.177578) (xy 172.618257 -285.21167) (xy 172.577754 -285.239626) (xy 172.533292 -285.260724)
			(xy 172.486021 -285.274416) (xy 172.437166 -285.280348) (xy 172.387991 -285.278367) (xy 172.339772 -285.268523)
			(xy 172.293756 -285.251071) (xy 172.251135 -285.226464) (xy 172.213014 -285.195339) (xy 172.180379 -285.158502)
			(xy 172.154076 -285.116906) (xy 172.134785 -285.07163) (xy 172.123008 -285.023846) (xy 172.119048 -284.974792)
			(xy 171.7802 -284.974792) (xy 171.779705 -284.999399) (xy 171.77181 -285.047976) (xy 171.756226 -285.094657)
			(xy 171.733355 -285.138234) (xy 171.70379 -285.177578) (xy 171.668297 -285.21167) (xy 171.627794 -285.239626)
			(xy 171.583332 -285.260724) (xy 171.536061 -285.274416) (xy 171.487206 -285.280348) (xy 171.438031 -285.278367)
			(xy 171.389812 -285.268523) (xy 171.343796 -285.251071) (xy 171.301175 -285.226464) (xy 171.263054 -285.195339)
			(xy 171.230419 -285.158502) (xy 171.204116 -285.116906) (xy 171.184825 -285.07163) (xy 171.173048 -285.023846)
			(xy 171.169088 -284.974792) (xy 170.83024 -284.974792) (xy 170.829745 -284.999399) (xy 170.82185 -285.047976)
			(xy 170.806266 -285.094657) (xy 170.783395 -285.138234) (xy 170.75383 -285.177578) (xy 170.718337 -285.21167)
			(xy 170.677834 -285.239626) (xy 170.633372 -285.260724) (xy 170.586101 -285.274416) (xy 170.537246 -285.280348)
			(xy 170.488071 -285.278367) (xy 170.439852 -285.268523) (xy 170.393836 -285.251071) (xy 170.351215 -285.226464)
			(xy 170.313094 -285.195339) (xy 170.280459 -285.158502) (xy 170.254156 -285.116906) (xy 170.234865 -285.07163)
			(xy 170.223088 -285.023846) (xy 170.219128 -284.974792) (xy 169.88028 -284.974792) (xy 169.879785 -284.999399)
			(xy 169.87189 -285.047976) (xy 169.856306 -285.094657) (xy 169.833435 -285.138234) (xy 169.80387 -285.177578)
			(xy 169.768377 -285.21167) (xy 169.727874 -285.239626) (xy 169.683412 -285.260724) (xy 169.636141 -285.274416)
			(xy 169.587286 -285.280348) (xy 169.538111 -285.278367) (xy 169.489892 -285.268523) (xy 169.443876 -285.251071)
			(xy 169.401255 -285.226464) (xy 169.363134 -285.195339) (xy 169.330499 -285.158502) (xy 169.304196 -285.116906)
			(xy 169.284905 -285.07163) (xy 169.273128 -285.023846) (xy 169.269168 -284.974792) (xy 168.93032 -284.974792)
			(xy 168.929825 -284.999399) (xy 168.92193 -285.047976) (xy 168.906346 -285.094657) (xy 168.883475 -285.138234)
			(xy 168.85391 -285.177578) (xy 168.818417 -285.21167) (xy 168.777914 -285.239626) (xy 168.733452 -285.260724)
			(xy 168.686181 -285.274416) (xy 168.637326 -285.280348) (xy 168.588151 -285.278367) (xy 168.539932 -285.268523)
			(xy 168.493916 -285.251071) (xy 168.451295 -285.226464) (xy 168.413174 -285.195339) (xy 168.380539 -285.158502)
			(xy 168.354236 -285.116906) (xy 168.334945 -285.07163) (xy 168.323168 -285.023846) (xy 168.319208 -284.974792)
			(xy 167.98036 -284.974792) (xy 167.979865 -284.999399) (xy 167.97197 -285.047976) (xy 167.956386 -285.094657)
			(xy 167.933515 -285.138234) (xy 167.90395 -285.177578) (xy 167.868457 -285.21167) (xy 167.827954 -285.239626)
			(xy 167.783492 -285.260724) (xy 167.736221 -285.274416) (xy 167.687366 -285.280348) (xy 167.638191 -285.278367)
			(xy 167.589972 -285.268523) (xy 167.543956 -285.251071) (xy 167.501335 -285.226464) (xy 167.463214 -285.195339)
			(xy 167.430579 -285.158502) (xy 167.404276 -285.116906) (xy 167.384985 -285.07163) (xy 167.373208 -285.023846)
			(xy 167.369248 -284.974792) (xy 167.0304 -284.974792) (xy 167.029905 -284.999399) (xy 167.02201 -285.047976)
			(xy 167.006426 -285.094657) (xy 166.983555 -285.138234) (xy 166.95399 -285.177578) (xy 166.918497 -285.21167)
			(xy 166.877994 -285.239626) (xy 166.833532 -285.260724) (xy 166.786261 -285.274416) (xy 166.737406 -285.280348)
			(xy 166.688231 -285.278367) (xy 166.640012 -285.268523) (xy 166.593996 -285.251071) (xy 166.551375 -285.226464)
			(xy 166.513254 -285.195339) (xy 166.480619 -285.158502) (xy 166.454316 -285.116906) (xy 166.435025 -285.07163)
			(xy 166.423248 -285.023846) (xy 166.419288 -284.974792) (xy 166.080186 -284.974792) (xy 166.079691 -284.999399)
			(xy 166.071796 -285.047976) (xy 166.056212 -285.094657) (xy 166.033341 -285.138234) (xy 166.003776 -285.177578)
			(xy 165.968283 -285.21167) (xy 165.92778 -285.239626) (xy 165.883318 -285.260724) (xy 165.836047 -285.274416)
			(xy 165.787192 -285.280348) (xy 165.738017 -285.278367) (xy 165.689798 -285.268523) (xy 165.643782 -285.251071)
			(xy 165.601161 -285.226464) (xy 165.56304 -285.195339) (xy 165.530405 -285.158502) (xy 165.504102 -285.116906)
			(xy 165.484811 -285.07163) (xy 165.473034 -285.023846) (xy 165.469074 -284.974792) (xy 165.130226 -284.974792)
			(xy 165.129731 -284.999399) (xy 165.121836 -285.047976) (xy 165.106252 -285.094657) (xy 165.083381 -285.138234)
			(xy 165.053816 -285.177578) (xy 165.018323 -285.21167) (xy 164.97782 -285.239626) (xy 164.933358 -285.260724)
			(xy 164.886087 -285.274416) (xy 164.837232 -285.280348) (xy 164.788057 -285.278367) (xy 164.739838 -285.268523)
			(xy 164.693822 -285.251071) (xy 164.651201 -285.226464) (xy 164.61308 -285.195339) (xy 164.580445 -285.158502)
			(xy 164.554142 -285.116906) (xy 164.534851 -285.07163) (xy 164.523074 -285.023846) (xy 164.519114 -284.974792)
			(xy 164.180266 -284.974792) (xy 164.179771 -284.999399) (xy 164.171876 -285.047976) (xy 164.156292 -285.094657)
			(xy 164.133421 -285.138234) (xy 164.103856 -285.177578) (xy 164.068363 -285.21167) (xy 164.02786 -285.239626)
			(xy 163.983398 -285.260724) (xy 163.936127 -285.274416) (xy 163.887272 -285.280348) (xy 163.838097 -285.278367)
			(xy 163.789878 -285.268523) (xy 163.743862 -285.251071) (xy 163.701241 -285.226464) (xy 163.66312 -285.195339)
			(xy 163.630485 -285.158502) (xy 163.604182 -285.116906) (xy 163.584891 -285.07163) (xy 163.573114 -285.023846)
			(xy 163.569154 -284.974792) (xy 163.230306 -284.974792) (xy 163.229811 -284.999399) (xy 163.221916 -285.047976)
			(xy 163.206332 -285.094657) (xy 163.183461 -285.138234) (xy 163.153896 -285.177578) (xy 163.118403 -285.21167)
			(xy 163.0779 -285.239626) (xy 163.033438 -285.260724) (xy 162.986167 -285.274416) (xy 162.937312 -285.280348)
			(xy 162.888137 -285.278367) (xy 162.839918 -285.268523) (xy 162.793902 -285.251071) (xy 162.751281 -285.226464)
			(xy 162.71316 -285.195339) (xy 162.680525 -285.158502) (xy 162.654222 -285.116906) (xy 162.634931 -285.07163)
			(xy 162.623154 -285.023846) (xy 162.619194 -284.974792) (xy 162.280346 -284.974792) (xy 162.279851 -284.999399)
			(xy 162.271956 -285.047976) (xy 162.256372 -285.094657) (xy 162.233501 -285.138234) (xy 162.203936 -285.177578)
			(xy 162.168443 -285.21167) (xy 162.12794 -285.239626) (xy 162.083478 -285.260724) (xy 162.036207 -285.274416)
			(xy 161.987352 -285.280348) (xy 161.938177 -285.278367) (xy 161.889958 -285.268523) (xy 161.843942 -285.251071)
			(xy 161.801321 -285.226464) (xy 161.7632 -285.195339) (xy 161.730565 -285.158502) (xy 161.704262 -285.116906)
			(xy 161.684971 -285.07163) (xy 161.673194 -285.023846) (xy 161.669234 -284.974792) (xy 161.330386 -284.974792)
			(xy 161.329891 -284.999399) (xy 161.321996 -285.047976) (xy 161.306412 -285.094657) (xy 161.283541 -285.138234)
			(xy 161.253976 -285.177578) (xy 161.218483 -285.21167) (xy 161.17798 -285.239626) (xy 161.133518 -285.260724)
			(xy 161.086247 -285.274416) (xy 161.037392 -285.280348) (xy 160.988217 -285.278367) (xy 160.939998 -285.268523)
			(xy 160.893982 -285.251071) (xy 160.851361 -285.226464) (xy 160.81324 -285.195339) (xy 160.780605 -285.158502)
			(xy 160.754302 -285.116906) (xy 160.735011 -285.07163) (xy 160.723234 -285.023846) (xy 160.719274 -284.974792)
			(xy 159.430212 -284.974792) (xy 159.429717 -284.999399) (xy 159.421822 -285.047976) (xy 159.406238 -285.094657)
			(xy 159.383367 -285.138234) (xy 159.353802 -285.177578) (xy 159.318309 -285.21167) (xy 159.277806 -285.239626)
			(xy 159.233344 -285.260724) (xy 159.186073 -285.274416) (xy 159.137218 -285.280348) (xy 159.088043 -285.278367)
			(xy 159.039824 -285.268523) (xy 158.993808 -285.251071) (xy 158.951187 -285.226464) (xy 158.913066 -285.195339)
			(xy 158.880431 -285.158502) (xy 158.854128 -285.116906) (xy 158.834837 -285.07163) (xy 158.82306 -285.023846)
			(xy 158.8191 -284.974792) (xy 156.580332 -284.974792) (xy 156.579837 -284.999399) (xy 156.571942 -285.047976)
			(xy 156.556358 -285.094657) (xy 156.533487 -285.138234) (xy 156.503922 -285.177578) (xy 156.468429 -285.21167)
			(xy 156.427926 -285.239626) (xy 156.383464 -285.260724) (xy 156.336193 -285.274416) (xy 156.287338 -285.280348)
			(xy 156.238163 -285.278367) (xy 156.189944 -285.268523) (xy 156.143928 -285.251071) (xy 156.101307 -285.226464)
			(xy 156.063186 -285.195339) (xy 156.030551 -285.158502) (xy 156.004248 -285.116906) (xy 155.984957 -285.07163)
			(xy 155.97318 -285.023846) (xy 155.96922 -284.974792) (xy 155.630372 -284.974792) (xy 155.629877 -284.999399)
			(xy 155.621982 -285.047976) (xy 155.606398 -285.094657) (xy 155.583527 -285.138234) (xy 155.553962 -285.177578)
			(xy 155.518469 -285.21167) (xy 155.477966 -285.239626) (xy 155.433504 -285.260724) (xy 155.386233 -285.274416)
			(xy 155.337378 -285.280348) (xy 155.288203 -285.278367) (xy 155.239984 -285.268523) (xy 155.193968 -285.251071)
			(xy 155.151347 -285.226464) (xy 155.113226 -285.195339) (xy 155.080591 -285.158502) (xy 155.054288 -285.116906)
			(xy 155.034997 -285.07163) (xy 155.02322 -285.023846) (xy 155.01926 -284.974792) (xy 154.680412 -284.974792)
			(xy 154.679917 -284.999399) (xy 154.672022 -285.047976) (xy 154.656438 -285.094657) (xy 154.633567 -285.138234)
			(xy 154.604002 -285.177578) (xy 154.568509 -285.21167) (xy 154.528006 -285.239626) (xy 154.483544 -285.260724)
			(xy 154.436273 -285.274416) (xy 154.387418 -285.280348) (xy 154.338243 -285.278367) (xy 154.290024 -285.268523)
			(xy 154.244008 -285.251071) (xy 154.201387 -285.226464) (xy 154.163266 -285.195339) (xy 154.130631 -285.158502)
			(xy 154.104328 -285.116906) (xy 154.085037 -285.07163) (xy 154.07326 -285.023846) (xy 154.0693 -284.974792)
			(xy 153.730198 -284.974792) (xy 153.729703 -284.999399) (xy 153.721808 -285.047976) (xy 153.706224 -285.094657)
			(xy 153.683353 -285.138234) (xy 153.653788 -285.177578) (xy 153.618295 -285.21167) (xy 153.577792 -285.239626)
			(xy 153.53333 -285.260724) (xy 153.486059 -285.274416) (xy 153.437204 -285.280348) (xy 153.388029 -285.278367)
			(xy 153.33981 -285.268523) (xy 153.293794 -285.251071) (xy 153.251173 -285.226464) (xy 153.213052 -285.195339)
			(xy 153.180417 -285.158502) (xy 153.154114 -285.116906) (xy 153.134823 -285.07163) (xy 153.123046 -285.023846)
			(xy 153.119086 -284.974792) (xy 152.780238 -284.974792) (xy 152.779743 -284.999399) (xy 152.771848 -285.047976)
			(xy 152.756264 -285.094657) (xy 152.733393 -285.138234) (xy 152.703828 -285.177578) (xy 152.668335 -285.21167)
			(xy 152.627832 -285.239626) (xy 152.58337 -285.260724) (xy 152.536099 -285.274416) (xy 152.487244 -285.280348)
			(xy 152.438069 -285.278367) (xy 152.38985 -285.268523) (xy 152.343834 -285.251071) (xy 152.301213 -285.226464)
			(xy 152.263092 -285.195339) (xy 152.230457 -285.158502) (xy 152.204154 -285.116906) (xy 152.184863 -285.07163)
			(xy 152.173086 -285.023846) (xy 152.169126 -284.974792) (xy 144.155761 -284.974792) (xy 144.159731 -285.00177)
			(xy 144.16024 -285.029656) (xy 144.159731 -285.057542) (xy 144.151611 -285.112718) (xy 144.135543 -285.166125)
			(xy 144.111871 -285.216622) (xy 144.081098 -285.263135) (xy 144.043881 -285.304672) (xy 144.001013 -285.340347)
			(xy 143.953407 -285.369401) (xy 143.902078 -285.391213) (xy 143.848121 -285.405319) (xy 143.792684 -285.411419)
			(xy 143.73695 -285.409382) (xy 143.682107 -285.399252) (xy 143.629323 -285.381245) (xy 143.579723 -285.355744)
			(xy 143.534365 -285.323293) (xy 143.494216 -285.284584) (xy 143.46013 -285.240441) (xy 143.432834 -285.191806)
			(xy 143.412911 -285.139715) (xy 143.400785 -285.085278) (xy 143.396714 -285.029656) (xy 142.675102 -285.029656)
			(xy 142.674593 -285.057542) (xy 142.666473 -285.112718) (xy 142.650405 -285.166125) (xy 142.626733 -285.216622)
			(xy 142.59596 -285.263135) (xy 142.558743 -285.304672) (xy 142.515875 -285.340347) (xy 142.468269 -285.369401)
			(xy 142.41694 -285.391213) (xy 142.362983 -285.405319) (xy 142.307546 -285.411419) (xy 142.251812 -285.409382)
			(xy 142.196969 -285.399252) (xy 142.144185 -285.381245) (xy 142.094585 -285.355744) (xy 142.049227 -285.323293)
			(xy 142.009078 -285.284584) (xy 141.974992 -285.240441) (xy 141.947696 -285.191806) (xy 141.927773 -285.139715)
			(xy 141.915647 -285.085278) (xy 141.911576 -285.029656) (xy 136.94918 -285.029656) (xy 136.94918 -285.196788)
			(xy 136.949652 -285.20666) (xy 136.957111 -285.224943) (xy 136.963658 -285.232348) (xy 136.963912 -285.232602)
			(xy 137.730992 -285.999682) (xy 137.7315 -286.00019) (xy 137.738885 -286.006761) (xy 137.757184 -286.014189)
			(xy 137.76706 -286.014668) (xy 142.05966 -286.014668) (xy 142.07363 -286.012636) (xy 142.093188 -286.007048)
			(xy 142.098776 -286.003746) (xy 142.120976 -285.991064) (xy 142.168044 -285.971101) (xy 142.217357 -285.957604)
			(xy 142.26803 -285.950814) (xy 142.293594 -285.950406) (xy 142.319157 -285.950803) (xy 142.369829 -285.957604)
			(xy 142.419138 -285.971112) (xy 142.466201 -285.991084) (xy 142.488412 -286.003746) (xy 142.494 -286.007048)
			(xy 142.513558 -286.012636) (xy 142.527528 -286.014668) (xy 143.535146 -286.014668) (xy 143.549116 -286.012636)
			(xy 143.568674 -286.007048) (xy 143.574262 -286.003746) (xy 143.596461 -285.991063) (xy 143.643529 -285.971099)
			(xy 143.692842 -285.9576) (xy 143.743516 -285.950808) (xy 143.76908 -285.950406) (xy 143.794643 -285.950802)
			(xy 143.845316 -285.957601) (xy 143.894626 -285.971107) (xy 143.94169 -285.991078) (xy 143.963898 -286.003746)
			(xy 143.969486 -286.007048) (xy 143.989044 -286.012636) (xy 144.003014 -286.014668) (xy 144.424146 -286.014668)
			(xy 144.438116 -286.012636) (xy 144.457674 -286.007048) (xy 144.463262 -286.003746) (xy 144.485461 -285.991063)
			(xy 144.532529 -285.971099) (xy 144.581842 -285.9576) (xy 144.632516 -285.950808) (xy 144.65808 -285.950406)
			(xy 144.683643 -285.950802) (xy 144.734316 -285.957601) (xy 144.783626 -285.971107) (xy 144.83069 -285.991078)
			(xy 144.852898 -286.003746) (xy 144.858486 -286.007048) (xy 144.878044 -286.012636) (xy 144.892014 -286.014668)
			(xy 147.597114 -286.014668) (xy 147.611084 -286.012636) (xy 147.630642 -286.007048) (xy 147.63623 -286.003746)
			(xy 147.658429 -285.991062) (xy 147.705496 -285.971093) (xy 147.754809 -285.95759) (xy 147.805484 -285.950794)
			(xy 147.831048 -285.950406) (xy 147.856612 -285.9508) (xy 147.907286 -285.957595) (xy 147.956598 -285.971098)
			(xy 148.003665 -285.991066) (xy 148.025866 -286.003746) (xy 148.031454 -286.007048) (xy 148.051012 -286.012636)
			(xy 148.064982 -286.014668) (xy 152.068022 -286.014668) (xy 152.077811 -286.014226) (xy 152.095975 -286.00692)
			(xy 152.103328 -286.000444) (xy 152.161494 -285.944056) (xy 152.169368 -285.926022) (xy 152.169622 -285.916116)
			(xy 152.170808 -285.891328) (xy 152.180211 -285.842604) (xy 152.197367 -285.796041) (xy 152.221825 -285.752864)
			(xy 152.252942 -285.714208) (xy 152.289897 -285.681091) (xy 152.331721 -285.654384) (xy 152.377312 -285.634789)
			(xy 152.42547 -285.622823) (xy 152.47493 -285.618798) (xy 152.52439 -285.622823) (xy 152.572548 -285.634789)
			(xy 152.618139 -285.654384) (xy 152.659963 -285.681091) (xy 152.696918 -285.714208) (xy 152.728035 -285.752864)
			(xy 152.752493 -285.796041) (xy 152.769649 -285.842604) (xy 152.779052 -285.891328) (xy 152.780238 -285.916116)
			(xy 152.780492 -285.926022) (xy 152.788366 -285.944056) (xy 152.846532 -286.000444) (xy 152.853883 -286.006928)
			(xy 152.872046 -286.014248) (xy 152.881838 -286.014668) (xy 153.017982 -286.014668) (xy 153.027766 -286.014215)
			(xy 153.045916 -286.006894) (xy 153.053288 -286.000444) (xy 153.111454 -285.944056) (xy 153.119328 -285.926022)
			(xy 153.119582 -285.916116) (xy 153.120768 -285.891328) (xy 153.130171 -285.842604) (xy 153.147327 -285.796041)
			(xy 153.171785 -285.752864) (xy 153.202902 -285.714208) (xy 153.239857 -285.681091) (xy 153.281681 -285.654384)
			(xy 153.327272 -285.634789) (xy 153.37543 -285.622823) (xy 153.42489 -285.618798) (xy 153.47435 -285.622823)
			(xy 153.522508 -285.634789) (xy 153.568099 -285.654384) (xy 153.609923 -285.681091) (xy 153.646878 -285.714208)
			(xy 153.677995 -285.752864) (xy 153.702453 -285.796041) (xy 153.719609 -285.842604) (xy 153.729012 -285.891328)
			(xy 153.730198 -285.916116) (xy 153.730452 -285.926022) (xy 153.738326 -285.944056) (xy 153.796492 -286.000444)
			(xy 153.803841 -286.006934) (xy 153.822003 -286.014268) (xy 153.831798 -286.014668) (xy 153.968196 -286.014668)
			(xy 153.977979 -286.014213) (xy 153.996125 -286.006888) (xy 154.003502 -286.000444) (xy 154.061668 -285.944056)
			(xy 154.069542 -285.926022) (xy 154.069796 -285.916116) (xy 154.070982 -285.891328) (xy 154.080385 -285.842604)
			(xy 154.097541 -285.796041) (xy 154.121999 -285.752864) (xy 154.153116 -285.714208) (xy 154.190071 -285.681091)
			(xy 154.231895 -285.654384) (xy 154.277486 -285.634789) (xy 154.325644 -285.622823) (xy 154.375104 -285.618798)
			(xy 154.424564 -285.622823) (xy 154.472722 -285.634789) (xy 154.518313 -285.654384) (xy 154.560137 -285.681091)
			(xy 154.597092 -285.714208) (xy 154.628209 -285.752864) (xy 154.652667 -285.796041) (xy 154.669823 -285.842604)
			(xy 154.679226 -285.891328) (xy 154.680412 -285.916116) (xy 154.680666 -285.926022) (xy 154.68854 -285.944056)
			(xy 154.746706 -286.000444) (xy 154.754055 -286.006932) (xy 154.772218 -286.014261) (xy 154.782012 -286.014668)
			(xy 154.918156 -286.014668) (xy 154.927942 -286.01422) (xy 154.946098 -286.006905) (xy 154.953462 -286.000444)
			(xy 155.011628 -285.944056) (xy 155.019502 -285.926022) (xy 155.019756 -285.916116) (xy 155.020942 -285.891328)
			(xy 155.030345 -285.842604) (xy 155.047501 -285.796041) (xy 155.071959 -285.752864) (xy 155.103076 -285.714208)
			(xy 155.140031 -285.681091) (xy 155.181855 -285.654384) (xy 155.227446 -285.634789) (xy 155.275604 -285.622823)
			(xy 155.325064 -285.618798) (xy 155.374524 -285.622823) (xy 155.422682 -285.634789) (xy 155.468273 -285.654384)
			(xy 155.510097 -285.681091) (xy 155.547052 -285.714208) (xy 155.578169 -285.752864) (xy 155.602627 -285.796041)
			(xy 155.619783 -285.842604) (xy 155.629186 -285.891328) (xy 155.630372 -285.916116) (xy 155.630626 -285.926022)
			(xy 155.6385 -285.944056) (xy 155.696666 -286.000444) (xy 155.704018 -286.006922) (xy 155.722181 -286.01423)
			(xy 155.731972 -286.014668) (xy 155.868116 -286.014668) (xy 155.877993 -286.014208) (xy 155.896289 -286.006761)
			(xy 155.903676 -286.00019) (xy 155.961588 -285.944056) (xy 155.969462 -285.925768) (xy 155.96997 -285.915862)
			(xy 155.971067 -285.892336) (xy 155.979607 -285.846021) (xy 155.995167 -285.801569) (xy 156.017376 -285.760039)
			(xy 156.045705 -285.722416) (xy 156.079482 -285.689596) (xy 156.117903 -285.662359) (xy 156.160055 -285.641353)
			(xy 156.204935 -285.627077) (xy 156.251476 -285.619871) (xy 156.275024 -285.619444) (xy 156.300602 -285.619957)
			(xy 156.351045 -285.628469) (xy 156.399364 -285.645268) (xy 156.444207 -285.669884) (xy 156.484322 -285.701628)
			(xy 156.518586 -285.739613) (xy 156.546041 -285.782777) (xy 156.56592 -285.829913) (xy 156.577666 -285.879702)
			(xy 156.579824 -285.905194) (xy 156.580332 -285.9151) (xy 156.58846 -285.932118) (xy 156.646372 -285.986474)
			(xy 156.653661 -285.992761) (xy 156.671552 -285.999824) (xy 156.68117 -286.00019) (xy 156.818838 -286.00019)
			(xy 156.82845 -285.999783) (xy 156.84634 -285.992744) (xy 156.853636 -285.986474) (xy 156.911548 -285.932118)
			(xy 156.919676 -285.9151) (xy 156.920184 -285.905194) (xy 156.922218 -285.881052) (xy 156.932952 -285.833811)
			(xy 156.951008 -285.788857) (xy 156.975934 -285.747316) (xy 157.007105 -285.710231) (xy 157.043739 -285.678531)
			(xy 157.084918 -285.653012) (xy 157.129609 -285.634312) (xy 157.176691 -285.622901) (xy 157.224984 -285.619066)
			(xy 157.273277 -285.622901) (xy 157.320359 -285.634312) (xy 157.36505 -285.653012) (xy 157.406229 -285.678531)
			(xy 157.442863 -285.710231) (xy 157.474034 -285.747316) (xy 157.49896 -285.788857) (xy 157.517016 -285.833811)
			(xy 157.52775 -285.881052) (xy 157.529784 -285.905194) (xy 157.530292 -285.9151) (xy 157.53842 -285.932118)
			(xy 157.596332 -285.986474) (xy 157.603624 -285.992752) (xy 157.621515 -285.999793) (xy 157.63113 -286.00019)
			(xy 160.618932 -286.00019) (xy 160.628545 -285.999784) (xy 160.646436 -285.992747) (xy 160.65373 -285.986474)
			(xy 160.711642 -285.932118) (xy 160.71977 -285.9151) (xy 160.720278 -285.905194) (xy 160.722312 -285.881052)
			(xy 160.733046 -285.833811) (xy 160.751102 -285.788857) (xy 160.776028 -285.747316) (xy 160.807199 -285.710231)
			(xy 160.843833 -285.678531) (xy 160.885012 -285.653012) (xy 160.929703 -285.634312) (xy 160.976785 -285.622901)
			(xy 161.025078 -285.619066) (xy 161.073371 -285.622901) (xy 161.120453 -285.634312) (xy 161.165144 -285.653012)
			(xy 161.206323 -285.678531) (xy 161.242957 -285.710231) (xy 161.274128 -285.747316) (xy 161.299054 -285.788857)
			(xy 161.31711 -285.833811) (xy 161.327844 -285.881052) (xy 161.329878 -285.905194) (xy 161.330386 -285.9151)
			(xy 161.338514 -285.932118) (xy 161.396426 -285.986474) (xy 161.403718 -285.992753) (xy 161.421609 -285.999796)
			(xy 161.431224 -286.00019) (xy 161.568892 -286.00019) (xy 161.5785 -285.999773) (xy 161.596377 -285.992721)
			(xy 161.60369 -285.986474) (xy 161.661602 -285.932118) (xy 161.66973 -285.9151) (xy 161.670238 -285.905194)
			(xy 161.672272 -285.881052) (xy 161.683006 -285.833811) (xy 161.701062 -285.788857) (xy 161.725988 -285.747316)
			(xy 161.757159 -285.710231) (xy 161.793793 -285.678531) (xy 161.834972 -285.653012) (xy 161.879663 -285.634312)
			(xy 161.926745 -285.622901) (xy 161.975038 -285.619066) (xy 162.023331 -285.622901) (xy 162.070413 -285.634312)
			(xy 162.115104 -285.653012) (xy 162.156283 -285.678531) (xy 162.192917 -285.710231) (xy 162.224088 -285.747316)
			(xy 162.249014 -285.788857) (xy 162.26707 -285.833811) (xy 162.277804 -285.881052) (xy 162.279838 -285.905194)
			(xy 162.280346 -285.9151) (xy 162.288474 -285.932118) (xy 162.346386 -285.986474) (xy 162.353676 -285.992759)
			(xy 162.371567 -285.999816) (xy 162.381184 -286.00019) (xy 162.518852 -286.00019) (xy 162.528463 -285.99978)
			(xy 162.54635 -285.992738) (xy 162.55365 -285.986474) (xy 162.611562 -285.932118) (xy 162.61969 -285.9151)
			(xy 162.620198 -285.905194) (xy 162.622232 -285.881052) (xy 162.632966 -285.833811) (xy 162.651022 -285.788857)
			(xy 162.675948 -285.747316) (xy 162.707119 -285.710231) (xy 162.743753 -285.678531) (xy 162.784932 -285.653012)
			(xy 162.829623 -285.634312) (xy 162.876705 -285.622901) (xy 162.924998 -285.619066) (xy 162.973291 -285.622901)
			(xy 163.020373 -285.634312) (xy 163.065064 -285.653012) (xy 163.106243 -285.678531) (xy 163.142877 -285.710231)
			(xy 163.174048 -285.747316) (xy 163.198974 -285.788857) (xy 163.21703 -285.833811) (xy 163.227764 -285.881052)
			(xy 163.229798 -285.905194) (xy 163.230306 -285.9151) (xy 163.238434 -285.932118) (xy 163.296346 -285.986474)
			(xy 163.303639 -285.99275) (xy 163.32153 -285.999786) (xy 163.331144 -286.00019) (xy 163.468812 -286.00019)
			(xy 163.478419 -285.99977) (xy 163.496291 -285.992712) (xy 163.50361 -285.986474) (xy 163.561522 -285.932118)
			(xy 163.56965 -285.9151) (xy 163.570158 -285.905194) (xy 163.572192 -285.881052) (xy 163.582926 -285.833811)
			(xy 163.600982 -285.788857) (xy 163.625908 -285.747316) (xy 163.657079 -285.710231) (xy 163.693713 -285.678531)
			(xy 163.734892 -285.653012) (xy 163.779583 -285.634312) (xy 163.826665 -285.622901) (xy 163.874958 -285.619066)
			(xy 163.923251 -285.622901) (xy 163.970333 -285.634312) (xy 164.015024 -285.653012) (xy 164.056203 -285.678531)
			(xy 164.092837 -285.710231) (xy 164.124008 -285.747316) (xy 164.148934 -285.788857) (xy 164.16699 -285.833811)
			(xy 164.177724 -285.881052) (xy 164.179758 -285.905194) (xy 164.180266 -285.9151) (xy 164.188394 -285.932118)
			(xy 164.246306 -285.986474) (xy 164.253597 -285.992756) (xy 164.271488 -285.999806) (xy 164.281104 -286.00019)
			(xy 164.418772 -286.00019) (xy 164.428382 -285.999777) (xy 164.446264 -285.992729) (xy 164.45357 -285.986474)
			(xy 164.511482 -285.932118) (xy 164.51961 -285.9151) (xy 164.520118 -285.905194) (xy 164.522152 -285.881052)
			(xy 164.532886 -285.833811) (xy 164.550942 -285.788857) (xy 164.575868 -285.747316) (xy 164.607039 -285.710231)
			(xy 164.643673 -285.678531) (xy 164.684852 -285.653012) (xy 164.729543 -285.634312) (xy 164.776625 -285.622901)
			(xy 164.824918 -285.619066) (xy 164.873211 -285.622901) (xy 164.920293 -285.634312) (xy 164.964984 -285.653012)
			(xy 165.006163 -285.678531) (xy 165.042797 -285.710231) (xy 165.073968 -285.747316) (xy 165.098894 -285.788857)
			(xy 165.11695 -285.833811) (xy 165.127684 -285.881052) (xy 165.129718 -285.905194) (xy 165.130226 -285.9151)
			(xy 165.138354 -285.932118) (xy 165.196266 -285.986474) (xy 165.203555 -285.992762) (xy 165.221445 -285.999827)
			(xy 165.231064 -286.00019) (xy 165.368732 -286.00019) (xy 165.378345 -285.999784) (xy 165.396236 -285.992747)
			(xy 165.40353 -285.986474) (xy 165.461442 -285.932118) (xy 165.46957 -285.9151) (xy 165.470078 -285.905194)
			(xy 165.472112 -285.881052) (xy 165.482846 -285.833811) (xy 165.500902 -285.788857) (xy 165.525828 -285.747316)
			(xy 165.556999 -285.710231) (xy 165.593633 -285.678531) (xy 165.634812 -285.653012) (xy 165.679503 -285.634312)
			(xy 165.726585 -285.622901) (xy 165.774878 -285.619066) (xy 165.823171 -285.622901) (xy 165.870253 -285.634312)
			(xy 165.914944 -285.653012) (xy 165.956123 -285.678531) (xy 165.992757 -285.710231) (xy 166.023928 -285.747316)
			(xy 166.048854 -285.788857) (xy 166.06691 -285.833811) (xy 166.077644 -285.881052) (xy 166.079678 -285.905194)
			(xy 166.080186 -285.9151) (xy 166.088314 -285.932118) (xy 166.146226 -285.986474) (xy 166.153518 -285.992753)
			(xy 166.171409 -285.999796) (xy 166.181024 -286.00019) (xy 166.318946 -286.00019) (xy 166.328558 -285.999781)
			(xy 166.346446 -285.992741) (xy 166.353744 -285.986474) (xy 166.411656 -285.932118) (xy 166.419784 -285.9151)
			(xy 166.420292 -285.905194) (xy 166.422326 -285.881052) (xy 166.43306 -285.833811) (xy 166.451116 -285.788857)
			(xy 166.476042 -285.747316) (xy 166.507213 -285.710231) (xy 166.543847 -285.678531) (xy 166.585026 -285.653012)
			(xy 166.629717 -285.634312) (xy 166.676799 -285.622901) (xy 166.725092 -285.619066) (xy 166.773385 -285.622901)
			(xy 166.820467 -285.634312) (xy 166.865158 -285.653012) (xy 166.906337 -285.678531) (xy 166.942971 -285.710231)
			(xy 166.974142 -285.747316) (xy 166.999068 -285.788857) (xy 167.017124 -285.833811) (xy 167.027858 -285.881052)
			(xy 167.029892 -285.905194) (xy 167.0304 -285.9151) (xy 167.038528 -285.932118) (xy 167.09644 -285.986474)
			(xy 167.103733 -285.992751) (xy 167.121623 -285.999789) (xy 167.131238 -286.00019) (xy 167.268906 -286.00019)
			(xy 167.278513 -285.999771) (xy 167.296387 -285.992715) (xy 167.303704 -285.986474) (xy 167.361616 -285.932118)
			(xy 167.369744 -285.9151) (xy 167.370252 -285.905194) (xy 167.372286 -285.881052) (xy 167.38302 -285.833811)
			(xy 167.401076 -285.788857) (xy 167.426002 -285.747316) (xy 167.457173 -285.710231) (xy 167.493807 -285.678531)
			(xy 167.534986 -285.653012) (xy 167.579677 -285.634312) (xy 167.626759 -285.622901) (xy 167.675052 -285.619066)
			(xy 167.723345 -285.622901) (xy 167.770427 -285.634312) (xy 167.815118 -285.653012) (xy 167.856297 -285.678531)
			(xy 167.892931 -285.710231) (xy 167.924102 -285.747316) (xy 167.949028 -285.788857) (xy 167.967084 -285.833811)
			(xy 167.977818 -285.881052) (xy 167.979852 -285.905194) (xy 167.98036 -285.9151) (xy 167.988488 -285.932118)
			(xy 168.0464 -285.986474) (xy 168.053691 -285.992757) (xy 168.071581 -285.999809) (xy 168.081198 -286.00019)
			(xy 168.218866 -286.00019) (xy 168.228476 -285.999778) (xy 168.246359 -285.992732) (xy 168.253664 -285.986474)
			(xy 168.311576 -285.932118) (xy 168.319704 -285.9151) (xy 168.320212 -285.905194) (xy 168.322246 -285.881052)
			(xy 168.33298 -285.833811) (xy 168.351036 -285.788857) (xy 168.375962 -285.747316) (xy 168.407133 -285.710231)
			(xy 168.443767 -285.678531) (xy 168.484946 -285.653012) (xy 168.529637 -285.634312) (xy 168.576719 -285.622901)
			(xy 168.625012 -285.619066) (xy 168.673305 -285.622901) (xy 168.720387 -285.634312) (xy 168.765078 -285.653012)
			(xy 168.806257 -285.678531) (xy 168.842891 -285.710231) (xy 168.874062 -285.747316) (xy 168.898988 -285.788857)
			(xy 168.917044 -285.833811) (xy 168.927778 -285.881052) (xy 168.929812 -285.905194) (xy 168.93032 -285.9151)
			(xy 168.938448 -285.932118) (xy 168.99636 -285.986474) (xy 169.003649 -285.992763) (xy 169.021539 -285.99983)
			(xy 169.031158 -286.00019) (xy 169.168826 -286.00019) (xy 169.178439 -285.999785) (xy 169.196332 -285.992749)
			(xy 169.203624 -285.986474) (xy 169.261536 -285.932118) (xy 169.269664 -285.9151) (xy 169.270172 -285.905194)
			(xy 169.272206 -285.881052) (xy 169.28294 -285.833811) (xy 169.300996 -285.788857) (xy 169.325922 -285.747316)
			(xy 169.357093 -285.710231) (xy 169.393727 -285.678531) (xy 169.434906 -285.653012) (xy 169.479597 -285.634312)
			(xy 169.526679 -285.622901) (xy 169.574972 -285.619066) (xy 169.623265 -285.622901) (xy 169.670347 -285.634312)
			(xy 169.715038 -285.653012) (xy 169.756217 -285.678531) (xy 169.792851 -285.710231) (xy 169.824022 -285.747316)
			(xy 169.848948 -285.788857) (xy 169.867004 -285.833811) (xy 169.877738 -285.881052) (xy 169.879772 -285.905194)
			(xy 169.88028 -285.9151) (xy 169.888408 -285.932118) (xy 169.94632 -285.986474) (xy 169.953612 -285.992754)
			(xy 169.971502 -285.999799) (xy 169.981118 -286.00019) (xy 170.118786 -286.00019) (xy 170.128395 -285.999774)
			(xy 170.146273 -285.992723) (xy 170.153584 -285.986474) (xy 170.211496 -285.932118) (xy 170.219624 -285.9151)
			(xy 170.220132 -285.905194) (xy 170.222166 -285.881052) (xy 170.2329 -285.833811) (xy 170.250956 -285.788857)
			(xy 170.275882 -285.747316) (xy 170.307053 -285.710231) (xy 170.343687 -285.678531) (xy 170.384866 -285.653012)
			(xy 170.429557 -285.634312) (xy 170.476639 -285.622901) (xy 170.524932 -285.619066) (xy 170.573225 -285.622901)
			(xy 170.620307 -285.634312) (xy 170.664998 -285.653012) (xy 170.706177 -285.678531) (xy 170.742811 -285.710231)
			(xy 170.773982 -285.747316) (xy 170.798908 -285.788857) (xy 170.816964 -285.833811) (xy 170.827698 -285.881052)
			(xy 170.829732 -285.905194) (xy 170.83024 -285.9151) (xy 170.838368 -285.932118) (xy 170.89628 -285.986474)
			(xy 170.90357 -285.99276) (xy 170.92146 -285.999819) (xy 170.931078 -286.00019) (xy 171.068746 -286.00019)
			(xy 171.078358 -285.999781) (xy 171.096246 -285.992741) (xy 171.103544 -285.986474) (xy 171.161456 -285.932118)
			(xy 171.169584 -285.9151) (xy 171.170092 -285.905194) (xy 171.172126 -285.881052) (xy 171.18286 -285.833811)
			(xy 171.200916 -285.788857) (xy 171.225842 -285.747316) (xy 171.257013 -285.710231) (xy 171.293647 -285.678531)
			(xy 171.334826 -285.653012) (xy 171.379517 -285.634312) (xy 171.426599 -285.622901) (xy 171.474892 -285.619066)
			(xy 171.523185 -285.622901) (xy 171.570267 -285.634312) (xy 171.614958 -285.653012) (xy 171.656137 -285.678531)
			(xy 171.692771 -285.710231) (xy 171.723942 -285.747316) (xy 171.748868 -285.788857) (xy 171.766924 -285.833811)
			(xy 171.777658 -285.881052) (xy 171.779692 -285.905194) (xy 171.7802 -285.9151) (xy 171.788328 -285.932118)
			(xy 171.84624 -285.986474) (xy 171.853533 -285.992751) (xy 171.871423 -285.999789) (xy 171.881038 -286.00019)
			(xy 172.018706 -286.00019) (xy 172.028313 -285.999771) (xy 172.046187 -285.992715) (xy 172.053504 -285.986474)
			(xy 172.111416 -285.932118) (xy 172.119544 -285.9151) (xy 172.120052 -285.905194) (xy 172.122086 -285.881052)
			(xy 172.13282 -285.833811) (xy 172.150876 -285.788857) (xy 172.175802 -285.747316) (xy 172.206973 -285.710231)
			(xy 172.243607 -285.678531) (xy 172.284786 -285.653012) (xy 172.329477 -285.634312) (xy 172.376559 -285.622901)
			(xy 172.424852 -285.619066) (xy 172.473145 -285.622901) (xy 172.520227 -285.634312) (xy 172.564918 -285.653012)
			(xy 172.606097 -285.678531) (xy 172.642731 -285.710231) (xy 172.673902 -285.747316) (xy 172.698828 -285.788857)
			(xy 172.716884 -285.833811) (xy 172.727618 -285.881052) (xy 172.729652 -285.905194) (xy 172.73016 -285.9151)
			(xy 172.738288 -285.932118) (xy 172.7962 -285.986474) (xy 172.803491 -285.992757) (xy 172.821381 -285.999809)
			(xy 172.830998 -286.00019) (xy 172.96892 -286.00019) (xy 172.978526 -285.999768) (xy 172.996396 -285.992709)
			(xy 173.003718 -285.986474) (xy 173.06163 -285.932118) (xy 173.069758 -285.9151) (xy 173.070266 -285.905194)
			(xy 173.0723 -285.881052) (xy 173.083034 -285.833811) (xy 173.10109 -285.788857) (xy 173.126016 -285.747316)
			(xy 173.157187 -285.710231) (xy 173.193821 -285.678531) (xy 173.235 -285.653012) (xy 173.279691 -285.634312)
			(xy 173.326773 -285.622901) (xy 173.375066 -285.619066) (xy 173.423359 -285.622901) (xy 173.470441 -285.634312)
			(xy 173.515132 -285.653012) (xy 173.556311 -285.678531) (xy 173.592945 -285.710231) (xy 173.624116 -285.747316)
			(xy 173.649042 -285.788857) (xy 173.667098 -285.833811) (xy 173.677832 -285.881052) (xy 173.679866 -285.905194)
			(xy 173.680374 -285.9151) (xy 173.688502 -285.932118) (xy 173.746414 -285.986474) (xy 173.753705 -285.992755)
			(xy 173.771596 -285.999802) (xy 173.781212 -286.00019) (xy 173.91888 -286.00019) (xy 173.928489 -285.999775)
			(xy 173.946369 -285.992726) (xy 173.953678 -285.986474) (xy 174.01159 -285.932118) (xy 174.019718 -285.9151)
			(xy 174.020226 -285.905194) (xy 174.02226 -285.881052) (xy 174.032994 -285.833811) (xy 174.05105 -285.788857)
			(xy 174.075976 -285.747316) (xy 174.107147 -285.710231) (xy 174.143781 -285.678531) (xy 174.18496 -285.653012)
			(xy 174.229651 -285.634312) (xy 174.276733 -285.622901) (xy 174.325026 -285.619066) (xy 174.373319 -285.622901)
			(xy 174.420401 -285.634312) (xy 174.465092 -285.653012) (xy 174.506271 -285.678531) (xy 174.542905 -285.710231)
			(xy 174.574076 -285.747316) (xy 174.599002 -285.788857) (xy 174.617058 -285.833811) (xy 174.627792 -285.881052)
			(xy 174.629826 -285.905194) (xy 174.630334 -285.9151) (xy 174.638462 -285.932118) (xy 174.696374 -285.986474)
			(xy 174.703663 -285.992761) (xy 174.721554 -285.999823) (xy 174.731172 -286.00019) (xy 175.8188 -286.00019)
			(xy 175.828408 -285.999772) (xy 175.846283 -285.992717) (xy 175.853598 -285.986474) (xy 175.91151 -285.932118)
			(xy 175.919638 -285.9151) (xy 175.920146 -285.905194) (xy 175.92218 -285.881052) (xy 175.932914 -285.833811)
			(xy 175.95097 -285.788857) (xy 175.975896 -285.747316) (xy 176.007067 -285.710231) (xy 176.043701 -285.678531)
			(xy 176.08488 -285.653012) (xy 176.129571 -285.634312) (xy 176.176653 -285.622901) (xy 176.224946 -285.619066)
			(xy 176.273239 -285.622901) (xy 176.320321 -285.634312) (xy 176.365012 -285.653012) (xy 176.406191 -285.678531)
			(xy 176.442825 -285.710231) (xy 176.473996 -285.747316) (xy 176.498922 -285.788857) (xy 176.516978 -285.833811)
			(xy 176.527712 -285.881052) (xy 176.529746 -285.905194) (xy 176.530254 -285.9151) (xy 176.538382 -285.932118)
			(xy 176.596294 -285.986474) (xy 176.603585 -285.992758) (xy 176.621475 -285.999812) (xy 176.631092 -286.00019)
			(xy 176.76876 -286.00019) (xy 176.778371 -285.999779) (xy 176.796255 -285.992735) (xy 176.803558 -285.986474)
			(xy 176.86147 -285.932118) (xy 176.869598 -285.9151) (xy 176.870106 -285.905194) (xy 176.87214 -285.881052)
			(xy 176.882874 -285.833811) (xy 176.90093 -285.788857) (xy 176.925856 -285.747316) (xy 176.957027 -285.710231)
			(xy 176.993661 -285.678531) (xy 177.03484 -285.653012) (xy 177.079531 -285.634312) (xy 177.126613 -285.622901)
			(xy 177.174906 -285.619066) (xy 177.223199 -285.622901) (xy 177.270281 -285.634312) (xy 177.314972 -285.653012)
			(xy 177.356151 -285.678531) (xy 177.392785 -285.710231) (xy 177.423956 -285.747316) (xy 177.448882 -285.788857)
			(xy 177.466938 -285.833811) (xy 177.477672 -285.881052) (xy 177.479706 -285.905194) (xy 177.480214 -285.9151)
			(xy 177.488342 -285.932118) (xy 177.546254 -285.986474) (xy 177.553548 -285.992748) (xy 177.571438 -285.999782)
			(xy 177.581052 -286.00019) (xy 177.71872 -286.00019) (xy 177.728326 -285.999768) (xy 177.746196 -285.992709)
			(xy 177.753518 -285.986474) (xy 177.81143 -285.932118) (xy 177.819558 -285.9151) (xy 177.820066 -285.905194)
			(xy 177.8221 -285.881052) (xy 177.832834 -285.833811) (xy 177.85089 -285.788857) (xy 177.875816 -285.747316)
			(xy 177.906987 -285.710231) (xy 177.943621 -285.678531) (xy 177.9848 -285.653012) (xy 178.029491 -285.634312)
			(xy 178.076573 -285.622901) (xy 178.124866 -285.619066) (xy 178.173159 -285.622901) (xy 178.220241 -285.634312)
			(xy 178.264932 -285.653012) (xy 178.306111 -285.678531) (xy 178.342745 -285.710231) (xy 178.373916 -285.747316)
			(xy 178.398842 -285.788857) (xy 178.416898 -285.833811) (xy 178.427632 -285.881052) (xy 178.429666 -285.905194)
			(xy 178.430174 -285.9151) (xy 178.438302 -285.932118) (xy 178.496214 -285.986474) (xy 178.503505 -285.992755)
			(xy 178.521396 -285.999802) (xy 178.531012 -286.00019) (xy 178.668934 -286.00019) (xy 178.678546 -285.999783)
			(xy 178.696438 -285.992746) (xy 178.703732 -285.986474) (xy 178.761644 -285.932118) (xy 178.769772 -285.9151)
			(xy 178.77028 -285.905194) (xy 178.772314 -285.881052) (xy 178.783048 -285.833811) (xy 178.801104 -285.788857)
			(xy 178.82603 -285.747316) (xy 178.857201 -285.710231) (xy 178.893835 -285.678531) (xy 178.935014 -285.653012)
			(xy 178.979705 -285.634312) (xy 179.026787 -285.622901) (xy 179.07508 -285.619066) (xy 179.123373 -285.622901)
			(xy 179.170455 -285.634312) (xy 179.215146 -285.653012) (xy 179.256325 -285.678531) (xy 179.292959 -285.710231)
			(xy 179.32413 -285.747316) (xy 179.349056 -285.788857) (xy 179.367112 -285.833811) (xy 179.377846 -285.881052)
			(xy 179.37988 -285.905194) (xy 179.380388 -285.9151) (xy 179.388516 -285.932118) (xy 179.446428 -285.986474)
			(xy 179.45372 -285.992753) (xy 179.471611 -285.999795) (xy 179.481226 -286.00019) (xy 179.618894 -286.00019)
			(xy 179.628502 -285.999773) (xy 179.646379 -285.99272) (xy 179.653692 -285.986474) (xy 179.711604 -285.932118)
			(xy 179.719732 -285.9151) (xy 179.72024 -285.905194) (xy 179.722274 -285.881052) (xy 179.733008 -285.833811)
			(xy 179.751064 -285.788857) (xy 179.77599 -285.747316) (xy 179.807161 -285.710231) (xy 179.843795 -285.678531)
			(xy 179.884974 -285.653012) (xy 179.929665 -285.634312) (xy 179.976747 -285.622901) (xy 180.02504 -285.619066)
			(xy 180.073333 -285.622901) (xy 180.120415 -285.634312) (xy 180.165106 -285.653012) (xy 180.206285 -285.678531)
			(xy 180.242919 -285.710231) (xy 180.27409 -285.747316) (xy 180.299016 -285.788857) (xy 180.317072 -285.833811)
			(xy 180.327806 -285.881052) (xy 180.32984 -285.905194) (xy 180.330348 -285.9151) (xy 180.338476 -285.932118)
			(xy 180.396388 -285.986474) (xy 180.403678 -285.992758) (xy 180.421569 -285.999815) (xy 180.431186 -286.00019)
			(xy 180.568854 -286.00019) (xy 180.578465 -285.99978) (xy 180.596351 -285.992737) (xy 180.603652 -285.986474)
			(xy 180.661564 -285.932118) (xy 180.669692 -285.9151) (xy 180.6702 -285.905194) (xy 180.672234 -285.881052)
			(xy 180.682968 -285.833811) (xy 180.701024 -285.788857) (xy 180.72595 -285.747316) (xy 180.757121 -285.710231)
			(xy 180.793755 -285.678531) (xy 180.834934 -285.653012) (xy 180.879625 -285.634312) (xy 180.926707 -285.622901)
			(xy 180.975 -285.619066) (xy 181.023293 -285.622901) (xy 181.070375 -285.634312) (xy 181.115066 -285.653012)
			(xy 181.156245 -285.678531) (xy 181.192879 -285.710231) (xy 181.22405 -285.747316) (xy 181.248976 -285.788857)
			(xy 181.267032 -285.833811) (xy 181.277766 -285.881052) (xy 181.2798 -285.905194) (xy 181.280308 -285.9151)
			(xy 181.288436 -285.932118) (xy 181.346348 -285.986474) (xy 181.353641 -285.99275) (xy 181.371532 -285.999785)
			(xy 181.381146 -286.00019) (xy 181.518814 -286.00019) (xy 181.528421 -285.999769) (xy 181.546292 -285.992711)
			(xy 181.553612 -285.986474) (xy 181.611524 -285.932118) (xy 181.619652 -285.9151) (xy 181.62016 -285.905194)
			(xy 181.622194 -285.881052) (xy 181.632928 -285.833811) (xy 181.650984 -285.788857) (xy 181.67591 -285.747316)
			(xy 181.707081 -285.710231) (xy 181.743715 -285.678531) (xy 181.784894 -285.653012) (xy 181.829585 -285.634312)
			(xy 181.876667 -285.622901) (xy 181.92496 -285.619066) (xy 181.973253 -285.622901) (xy 182.020335 -285.634312)
			(xy 182.065026 -285.653012) (xy 182.106205 -285.678531) (xy 182.142839 -285.710231) (xy 182.17401 -285.747316)
			(xy 182.198936 -285.788857) (xy 182.216992 -285.833811) (xy 182.227726 -285.881052) (xy 182.22976 -285.905194)
			(xy 182.230268 -285.9151) (xy 182.238396 -285.932118) (xy 182.296308 -285.986474) (xy 182.303599 -285.992756)
			(xy 182.32149 -285.999805) (xy 182.331106 -286.00019) (xy 182.468774 -286.00019) (xy 182.478384 -285.999776)
			(xy 182.496265 -285.992729) (xy 182.503572 -285.986474) (xy 182.561484 -285.932118) (xy 182.569612 -285.9151)
			(xy 182.57012 -285.905194) (xy 182.572154 -285.881052) (xy 182.582888 -285.833811) (xy 182.600944 -285.788857)
			(xy 182.62587 -285.747316) (xy 182.657041 -285.710231) (xy 182.693675 -285.678531) (xy 182.734854 -285.653012)
			(xy 182.779545 -285.634312) (xy 182.826627 -285.622901) (xy 182.87492 -285.619066) (xy 182.923213 -285.622901)
			(xy 182.970295 -285.634312) (xy 183.014986 -285.653012) (xy 183.056165 -285.678531) (xy 183.092799 -285.710231)
			(xy 183.12397 -285.747316) (xy 183.148896 -285.788857) (xy 183.166952 -285.833811) (xy 183.177686 -285.881052)
			(xy 183.17972 -285.905194) (xy 183.180228 -285.9151) (xy 183.188356 -285.932118) (xy 183.246268 -285.986474)
			(xy 183.253557 -285.992762) (xy 183.271447 -285.999826) (xy 183.281066 -286.00019) (xy 183.418734 -286.00019)
			(xy 183.428346 -285.999783) (xy 183.446238 -285.992746) (xy 183.453532 -285.986474) (xy 183.511444 -285.932118)
			(xy 183.519572 -285.9151) (xy 183.52008 -285.905194) (xy 183.522114 -285.881052) (xy 183.532848 -285.833811)
			(xy 183.550904 -285.788857) (xy 183.57583 -285.747316) (xy 183.607001 -285.710231) (xy 183.643635 -285.678531)
			(xy 183.684814 -285.653012) (xy 183.729505 -285.634312) (xy 183.776587 -285.622901) (xy 183.82488 -285.619066)
			(xy 183.873173 -285.622901) (xy 183.920255 -285.634312) (xy 183.964946 -285.653012) (xy 184.006125 -285.678531)
			(xy 184.042759 -285.710231) (xy 184.07393 -285.747316) (xy 184.098856 -285.788857) (xy 184.116912 -285.833811)
			(xy 184.127646 -285.881052) (xy 184.12968 -285.905194) (xy 184.130188 -285.9151) (xy 184.138316 -285.932118)
			(xy 184.196228 -285.986474) (xy 184.20352 -285.992753) (xy 184.221411 -285.999795) (xy 184.231026 -286.00019)
			(xy 184.368694 -286.00019) (xy 184.378302 -285.999773) (xy 184.396179 -285.99272) (xy 184.403492 -285.986474)
			(xy 184.461404 -285.932118) (xy 184.469532 -285.9151) (xy 184.47004 -285.905194) (xy 184.472074 -285.881052)
			(xy 184.482808 -285.833811) (xy 184.500864 -285.788857) (xy 184.52579 -285.747316) (xy 184.556961 -285.710231)
			(xy 184.593595 -285.678531) (xy 184.634774 -285.653012) (xy 184.679465 -285.634312) (xy 184.726547 -285.622901)
			(xy 184.77484 -285.619066) (xy 184.823133 -285.622901) (xy 184.870215 -285.634312) (xy 184.914906 -285.653012)
			(xy 184.956085 -285.678531) (xy 184.992719 -285.710231) (xy 185.02389 -285.747316) (xy 185.048816 -285.788857)
			(xy 185.066872 -285.833811) (xy 185.077606 -285.881052) (xy 185.07964 -285.905194) (xy 185.080148 -285.9151)
			(xy 185.088276 -285.932118) (xy 185.146188 -285.986474) (xy 185.153478 -285.992758) (xy 185.171369 -285.999815)
			(xy 185.180986 -286.00019) (xy 185.318908 -286.00019) (xy 185.328515 -285.99977) (xy 185.346388 -285.992714)
			(xy 185.353706 -285.986474) (xy 185.411618 -285.932118) (xy 185.419746 -285.9151) (xy 185.420254 -285.905194)
			(xy 185.422435 -285.879709) (xy 185.434213 -285.829938) (xy 185.45411 -285.782821) (xy 185.481571 -285.739672)
			(xy 185.51583 -285.701695) (xy 185.555931 -285.66995) (xy 185.600757 -285.645321) (xy 185.649056 -285.628496)
			(xy 185.699481 -285.619943) (xy 185.725054 -285.619444) (xy 185.749049 -285.619911) (xy 185.796449 -285.627411)
			(xy 185.842092 -285.642234) (xy 185.884855 -285.664014) (xy 185.923684 -285.692216) (xy 185.957623 -285.726145)
			(xy 185.985836 -285.764965) (xy 186.00763 -285.807721) (xy 186.022467 -285.853359) (xy 186.029981 -285.900757)
			(xy 186.030362 -285.924752) (xy 186.0296 -285.945834) (xy 186.0296 -285.94939) (xy 186.030018 -285.959413)
			(xy 186.037686 -285.977933) (xy 186.051859 -285.992108) (xy 186.070377 -285.99978) (xy 186.0804 -286.00019)
			(xy 186.086496 -286.00019) (xy 186.112404 -286.010858) (xy 186.117032 -286.012631) (xy 186.126753 -286.01455)
			(xy 186.131708 -286.014668) (xy 186.268106 -286.014668) (xy 186.277896 -286.014229) (xy 186.296065 -286.006927)
			(xy 186.303412 -286.000444) (xy 186.361578 -285.944056) (xy 186.369452 -285.926022) (xy 186.369706 -285.916116)
			(xy 186.370892 -285.891328) (xy 186.380295 -285.842604) (xy 186.397451 -285.796041) (xy 186.421909 -285.752864)
			(xy 186.453026 -285.714208) (xy 186.489981 -285.681091) (xy 186.531805 -285.654384) (xy 186.577396 -285.634789)
			(xy 186.625554 -285.622823) (xy 186.675014 -285.618798) (xy 186.724474 -285.622823) (xy 186.772632 -285.634789)
			(xy 186.818223 -285.654384) (xy 186.860047 -285.681091) (xy 186.897002 -285.714208) (xy 186.928119 -285.752864)
			(xy 186.952577 -285.796041) (xy 186.969733 -285.842604) (xy 186.979136 -285.891328) (xy 186.980322 -285.916116)
			(xy 186.980576 -285.926022) (xy 186.98845 -285.944056) (xy 187.046616 -286.000444) (xy 187.053966 -286.00693)
			(xy 187.072129 -286.014256) (xy 187.081922 -286.014668) (xy 189.117986 -286.014668) (xy 189.12777 -286.014215)
			(xy 189.145918 -286.006892) (xy 189.153292 -286.000444) (xy 189.211458 -285.944056) (xy 189.219332 -285.926022)
			(xy 189.219586 -285.916116) (xy 189.220753 -285.892142) (xy 189.229633 -285.844974) (xy 189.245779 -285.799775)
			(xy 189.268793 -285.757657) (xy 189.29811 -285.719655) (xy 189.333008 -285.686705) (xy 189.372629 -285.659616)
			(xy 189.415998 -285.639055) (xy 189.462049 -285.625529) (xy 189.509648 -285.61937) (xy 189.557625 -285.620728)
			(xy 189.581282 -285.624778) (xy 189.593728 -285.627064) (xy 189.61735 -285.619698) (xy 189.69482 -285.542228)
			(xy 189.702186 -285.518606) (xy 189.6999 -285.50616) (xy 189.697416 -285.492195) (xy 189.694747 -285.463955)
			(xy 189.694566 -285.449772) (xy 189.695088 -285.424517) (xy 189.703401 -285.374695) (xy 189.719802 -285.326921)
			(xy 189.743843 -285.282498) (xy 189.774867 -285.242638) (xy 189.812029 -285.208428) (xy 189.854315 -285.180802)
			(xy 189.900571 -285.160512) (xy 189.949536 -285.148112) (xy 189.999874 -285.143941) (xy 190.050212 -285.148112)
			(xy 190.099177 -285.160512) (xy 190.145433 -285.180802) (xy 190.187719 -285.208428) (xy 190.224881 -285.242638)
			(xy 190.255905 -285.282498) (xy 190.279946 -285.326921) (xy 190.296347 -285.374695) (xy 190.30466 -285.424517)
			(xy 190.305182 -285.449772) (xy 190.305083 -285.458876) (xy 190.303938 -285.477049) (xy 190.302896 -285.486094)
			(xy 190.301626 -285.498286) (xy 190.3095 -285.520638) (xy 190.385954 -285.593536) (xy 190.40856 -285.600648)
			(xy 190.420498 -285.598616) (xy 190.433986 -285.596484) (xy 190.461199 -285.594192) (xy 190.474854 -285.594044)
			(xy 190.523368 -285.594044) (xy 190.534028 -285.593589) (xy 190.553499 -285.584908) (xy 190.56096 -285.57728)
			(xy 190.618872 -285.513526) (xy 190.625476 -285.493206) (xy 190.62446 -285.482284) (xy 190.622936 -285.449772)
			(xy 190.62344 -285.424084) (xy 190.631477 -285.373341) (xy 190.647353 -285.32448) (xy 190.670677 -285.278704)
			(xy 190.700874 -285.23714) (xy 190.737202 -285.200812) (xy 190.778766 -285.170615) (xy 190.824542 -285.147291)
			(xy 190.873403 -285.131415) (xy 190.924146 -285.123378) (xy 190.975522 -285.123378) (xy 191.026265 -285.131415)
			(xy 191.075126 -285.147291) (xy 191.120902 -285.170615) (xy 191.162466 -285.200812) (xy 191.198794 -285.23714)
			(xy 191.228991 -285.278704) (xy 191.252315 -285.32448) (xy 191.268191 -285.373341) (xy 191.276228 -285.424084)
			(xy 191.276732 -285.449772) (xy 191.275208 -285.482284) (xy 191.274192 -285.493206) (xy 191.280796 -285.513526)
			(xy 191.338708 -285.57728) (xy 191.346254 -285.584786) (xy 191.365673 -285.593439) (xy 191.3763 -285.594044)
			(xy 191.424814 -285.594044) (xy 191.434232 -285.594079) (xy 191.453039 -285.595095) (xy 191.462406 -285.596076)
			(xy 191.473836 -285.5976) (xy 191.49568 -285.58998) (xy 191.568324 -285.51759) (xy 191.576198 -285.496)
			(xy 191.574928 -285.48457) (xy 191.572896 -285.449772) (xy 191.5734 -285.424064) (xy 191.581443 -285.373282)
			(xy 191.597331 -285.324383) (xy 191.620674 -285.278571) (xy 191.650895 -285.236975) (xy 191.687251 -285.200619)
			(xy 191.728847 -285.170398) (xy 191.774659 -285.147055) (xy 191.823558 -285.131167) (xy 191.87434 -285.123124)
			(xy 191.925756 -285.123124) (xy 191.976538 -285.131167) (xy 192.025437 -285.147055) (xy 192.071249 -285.170398)
			(xy 192.112845 -285.200619) (xy 192.149201 -285.236975) (xy 192.179422 -285.278571) (xy 192.202765 -285.324383)
			(xy 192.218653 -285.373282) (xy 192.226696 -285.424064) (xy 192.2272 -285.449772) (xy 192.227006 -285.463495)
			(xy 192.224587 -285.490837) (xy 192.222374 -285.504382) (xy 192.220596 -285.51632) (xy 192.227454 -285.53918)
			(xy 192.301114 -285.615634) (xy 192.32372 -285.623508) (xy 192.335658 -285.621984) (xy 192.359581 -285.619354)
			(xy 192.407686 -285.620765) (xy 192.431416 -285.624778) (xy 192.443862 -285.627064) (xy 192.467484 -285.619698)
			(xy 192.544954 -285.542228) (xy 192.55232 -285.518606) (xy 192.550034 -285.50616) (xy 192.54755 -285.492195)
			(xy 192.54488 -285.463955) (xy 192.5447 -285.449772) (xy 192.545222 -285.424517) (xy 192.553535 -285.374695)
			(xy 192.569936 -285.326921) (xy 192.593977 -285.282498) (xy 192.625001 -285.242638) (xy 192.662163 -285.208428)
			(xy 192.704449 -285.180802) (xy 192.750705 -285.160512) (xy 192.79967 -285.148112) (xy 192.850008 -285.143941)
			(xy 192.900346 -285.148112) (xy 192.949311 -285.160512) (xy 192.995567 -285.180802) (xy 193.037853 -285.208428)
			(xy 193.075015 -285.242638) (xy 193.106039 -285.282498) (xy 193.13008 -285.326921) (xy 193.146481 -285.374695)
			(xy 193.154794 -285.424517) (xy 193.155316 -285.449772) (xy 193.155131 -285.463955) (xy 193.15246 -285.492194)
			(xy 193.149982 -285.50616) (xy 193.147696 -285.518606) (xy 193.155062 -285.542228) (xy 193.232532 -285.619698)
			(xy 193.256154 -285.627064) (xy 193.2686 -285.624778) (xy 193.296607 -285.620149) (xy 193.353369 -285.620149)
			(xy 193.381376 -285.624778) (xy 193.393822 -285.627064) (xy 193.417444 -285.619698) (xy 193.494914 -285.542228)
			(xy 193.50228 -285.518606) (xy 193.499994 -285.50616) (xy 193.49751 -285.492195) (xy 193.494841 -285.463955)
			(xy 193.49466 -285.449772) (xy 193.495182 -285.424517) (xy 193.503495 -285.374695) (xy 193.519896 -285.326921)
			(xy 193.543937 -285.282498) (xy 193.574961 -285.242638) (xy 193.612123 -285.208428) (xy 193.654409 -285.180802)
			(xy 193.700665 -285.160512) (xy 193.74963 -285.148112) (xy 193.799968 -285.143941) (xy 193.850306 -285.148112)
			(xy 193.899271 -285.160512) (xy 193.945527 -285.180802) (xy 193.987813 -285.208428) (xy 194.024975 -285.242638)
			(xy 194.055999 -285.282498) (xy 194.08004 -285.326921) (xy 194.096441 -285.374695) (xy 194.104754 -285.424517)
			(xy 194.105276 -285.449772) (xy 194.105091 -285.463955) (xy 194.102419 -285.492194) (xy 194.099942 -285.50616)
			(xy 194.097656 -285.518606) (xy 194.105022 -285.542228) (xy 194.182492 -285.619698) (xy 194.206114 -285.627064)
			(xy 194.21856 -285.624778) (xy 194.246567 -285.620149) (xy 194.303329 -285.620149) (xy 194.331336 -285.624778)
			(xy 194.343782 -285.627064) (xy 194.367404 -285.619698) (xy 194.444874 -285.542228) (xy 194.45224 -285.518606)
			(xy 194.449954 -285.50616) (xy 194.44747 -285.492195) (xy 194.4448 -285.463955) (xy 194.44462 -285.449772)
			(xy 194.445142 -285.424517) (xy 194.453455 -285.374695) (xy 194.469856 -285.326921) (xy 194.493897 -285.282498)
			(xy 194.524921 -285.242638) (xy 194.562083 -285.208428) (xy 194.604369 -285.180802) (xy 194.650625 -285.160512)
			(xy 194.69959 -285.148112) (xy 194.749928 -285.143941) (xy 194.800266 -285.148112) (xy 194.849231 -285.160512)
			(xy 194.895487 -285.180802) (xy 194.937773 -285.208428) (xy 194.974935 -285.242638) (xy 195.005959 -285.282498)
			(xy 195.03 -285.326921) (xy 195.046401 -285.374695) (xy 195.054714 -285.424517) (xy 195.055236 -285.449772)
			(xy 195.055051 -285.463955) (xy 195.05238 -285.492194) (xy 195.049902 -285.50616) (xy 195.047616 -285.518606)
			(xy 195.054982 -285.542228) (xy 195.132452 -285.619698) (xy 195.156074 -285.627064) (xy 195.16852 -285.624778)
			(xy 195.196527 -285.620149) (xy 195.253289 -285.620149) (xy 195.281296 -285.624778) (xy 195.293742 -285.627064)
			(xy 195.317364 -285.619698) (xy 195.394834 -285.542228) (xy 195.4022 -285.518606) (xy 195.399914 -285.50616)
			(xy 195.39743 -285.492195) (xy 195.394761 -285.463955) (xy 195.39458 -285.449772) (xy 195.395102 -285.424517)
			(xy 195.403415 -285.374695) (xy 195.419816 -285.326921) (xy 195.443857 -285.282498) (xy 195.474881 -285.242638)
			(xy 195.512043 -285.208428) (xy 195.554329 -285.180802) (xy 195.600585 -285.160512) (xy 195.64955 -285.148112)
			(xy 195.699888 -285.143941) (xy 195.750226 -285.148112) (xy 195.799191 -285.160512) (xy 195.845447 -285.180802)
			(xy 195.887733 -285.208428) (xy 195.924895 -285.242638) (xy 195.955919 -285.282498) (xy 195.97996 -285.326921)
			(xy 195.996361 -285.374695) (xy 196.004674 -285.424517) (xy 196.005196 -285.449772) (xy 196.005097 -285.458876)
			(xy 196.003952 -285.477049) (xy 196.00291 -285.486094) (xy 196.00164 -285.498286) (xy 196.009514 -285.520638)
			(xy 196.085968 -285.593536) (xy 196.108574 -285.600648) (xy 196.120512 -285.598616) (xy 196.134 -285.596484)
			(xy 196.161213 -285.594194) (xy 196.174868 -285.594044) (xy 196.245226 -285.594044) (xy 196.255916 -285.593478)
			(xy 196.275464 -285.584812) (xy 196.283072 -285.57728) (xy 196.34073 -285.513018) (xy 196.347334 -285.492698)
			(xy 196.346318 -285.481776) (xy 196.34454 -285.449772) (xy 196.345062 -285.424517) (xy 196.353375 -285.374695)
			(xy 196.369776 -285.326921) (xy 196.393817 -285.282498) (xy 196.424841 -285.242638) (xy 196.462003 -285.208428)
			(xy 196.504289 -285.180802) (xy 196.550545 -285.160512) (xy 196.59951 -285.148112) (xy 196.649848 -285.143941)
			(xy 196.700186 -285.148112) (xy 196.749151 -285.160512) (xy 196.795407 -285.180802) (xy 196.837693 -285.208428)
			(xy 196.874855 -285.242638) (xy 196.905879 -285.282498) (xy 196.92992 -285.326921) (xy 196.946321 -285.374695)
			(xy 196.954634 -285.424517) (xy 196.955156 -285.449772) (xy 196.953378 -285.481776) (xy 196.952362 -285.492698)
			(xy 196.958966 -285.513018) (xy 197.016624 -285.57728) (xy 197.024144 -285.584934) (xy 197.043748 -285.593604)
			(xy 197.05447 -285.594044) (xy 197.124828 -285.594044) (xy 197.134246 -285.59408) (xy 197.153053 -285.595096)
			(xy 197.16242 -285.596076) (xy 197.17385 -285.5976) (xy 197.195694 -285.58998) (xy 197.268338 -285.51759)
			(xy 197.276212 -285.496) (xy 197.274942 -285.48457) (xy 197.273164 -285.449772) (xy 197.273668 -285.424084)
			(xy 197.281705 -285.373341) (xy 197.297581 -285.32448) (xy 197.320905 -285.278704) (xy 197.351102 -285.23714)
			(xy 197.38743 -285.200812) (xy 197.428994 -285.170615) (xy 197.47477 -285.147291) (xy 197.523631 -285.131415)
			(xy 197.574374 -285.123378) (xy 197.62575 -285.123378) (xy 197.676493 -285.131415) (xy 197.725354 -285.147291)
			(xy 197.77113 -285.170615) (xy 197.812694 -285.200812) (xy 197.849022 -285.23714) (xy 197.879219 -285.278704)
			(xy 197.902543 -285.32448) (xy 197.918419 -285.373341) (xy 197.926456 -285.424084) (xy 197.92696 -285.449772)
			(xy 197.926834 -285.463491) (xy 197.924548 -285.490834) (xy 197.922388 -285.504382) (xy 197.92061 -285.51632)
			(xy 197.927468 -285.53918) (xy 198.001128 -285.615634) (xy 198.023734 -285.623508) (xy 198.035672 -285.621984)
			(xy 198.055295 -285.619746) (xy 198.094789 -285.619746) (xy 198.114412 -285.621984) (xy 198.12635 -285.623508)
			(xy 198.148956 -285.615634) (xy 198.222616 -285.53918) (xy 198.229474 -285.51632) (xy 198.227696 -285.504382)
			(xy 198.22556 -285.490831) (xy 198.223275 -285.46349) (xy 198.223124 -285.449772) (xy 198.223628 -285.424084)
			(xy 198.231665 -285.373341) (xy 198.247541 -285.32448) (xy 198.270865 -285.278704) (xy 198.301062 -285.23714)
			(xy 198.33739 -285.200812) (xy 198.378954 -285.170615) (xy 198.42473 -285.147291) (xy 198.473591 -285.131415)
			(xy 198.524334 -285.123378) (xy 198.57571 -285.123378) (xy 198.626453 -285.131415) (xy 198.675314 -285.147291)
			(xy 198.72109 -285.170615) (xy 198.762654 -285.200812) (xy 198.798982 -285.23714) (xy 198.829179 -285.278704)
			(xy 198.852503 -285.32448) (xy 198.868379 -285.373341) (xy 198.876416 -285.424084) (xy 198.87692 -285.449772)
			(xy 198.876794 -285.463491) (xy 198.874509 -285.490834) (xy 198.872348 -285.504382) (xy 198.87057 -285.51632)
			(xy 198.877428 -285.53918) (xy 198.951088 -285.615634) (xy 198.973694 -285.623508) (xy 198.985632 -285.621984)
			(xy 199.009555 -285.619352) (xy 199.057661 -285.620759) (xy 199.08139 -285.624778) (xy 199.09409 -285.627064)
			(xy 199.117712 -285.619698) (xy 199.195182 -285.542482) (xy 199.202548 -285.51886) (xy 199.200262 -285.50616)
			(xy 199.197787 -285.492258) (xy 199.195119 -285.464145) (xy 199.194928 -285.450026) (xy 199.195412 -285.425208)
			(xy 199.203438 -285.376226) (xy 199.219282 -285.329187) (xy 199.242528 -285.285332) (xy 199.272563 -285.245814)
			(xy 199.308595 -285.211677) (xy 199.349675 -285.183818) (xy 199.394721 -285.162973) (xy 199.442546 -285.149689)
			(xy 199.49189 -285.144318) (xy 199.541453 -285.147) (xy 199.589929 -285.157666) (xy 199.636041 -285.176033)
			(xy 199.678574 -285.201619) (xy 199.716408 -285.233748) (xy 199.748545 -285.271575) (xy 199.774139 -285.314103)
			(xy 199.792516 -285.360212) (xy 199.803191 -285.408686) (xy 199.805884 -285.458248) (xy 199.800523 -285.507593)
			(xy 199.787249 -285.555421) (xy 199.766412 -285.600471) (xy 199.738562 -285.641557) (xy 199.704432 -285.677596)
			(xy 199.664921 -285.707639) (xy 199.62107 -285.730893) (xy 199.574034 -285.746747) (xy 199.525054 -285.754783)
			(xy 199.500236 -285.755334) (xy 199.486053 -285.755149) (xy 199.457813 -285.752479) (xy 199.443848 -285.75)
			(xy 199.431148 -285.747714) (xy 199.407526 -285.75508) (xy 199.330056 -285.832296) (xy 199.322944 -285.855918)
			(xy 199.32523 -285.868618) (xy 199.327315 -285.880391) (xy 199.329862 -285.904168) (xy 199.33031 -285.916116)
			(xy 199.330564 -285.926022) (xy 199.338438 -285.944056) (xy 199.396604 -286.000444) (xy 199.403953 -286.006932)
			(xy 199.422116 -286.014262) (xy 199.43191 -286.014668) (xy 211.7471 -286.014668) (xy 211.757087 -286.01413)
			(xy 211.775516 -286.006413) (xy 211.782914 -285.999682) (xy 215.088216 -282.69438) (xy 215.110943 -282.672382)
			(xy 215.161148 -282.63391) (xy 215.215946 -282.602321) (xy 215.274398 -282.578156) (xy 215.335505 -282.561827)
			(xy 215.39822 -282.553616) (xy 215.429846 -282.553156) (xy 223.629474 -282.553156) (xy 223.639463 -282.552622)
			(xy 223.657897 -282.54491) (xy 223.665288 -282.53817) (xy 227.343462 -278.859742) (xy 227.366057 -278.837888)
			(xy 227.415923 -278.799613) (xy 227.470334 -278.768132) (xy 227.499164 -278.755602) (xy 227.510086 -278.75103)
			(xy 227.525072 -278.734012) (xy 227.553266 -278.634698) (xy 227.549456 -278.612092) (xy 227.542344 -278.602694)
			(xy 227.52546 -278.578201) (xy 227.498685 -278.525081) (xy 227.480475 -278.46845) (xy 227.471272 -278.40968)
			(xy 227.470716 -278.379936) (xy 227.471202 -278.352685) (xy 227.478958 -278.298737) (xy 227.494313 -278.246442)
			(xy 227.516955 -278.196865) (xy 227.546421 -278.151015) (xy 227.582112 -278.109824) (xy 227.623303 -278.074133)
			(xy 227.669153 -278.044667) (xy 227.71873 -278.022025) (xy 227.771025 -278.00667) (xy 227.824973 -277.998914)
			(xy 227.879475 -277.998914) (xy 227.933423 -278.00667) (xy 227.985718 -278.022025) (xy 228.035295 -278.044667)
			(xy 228.081145 -278.074133) (xy 228.122336 -278.109824) (xy 228.158027 -278.151015) (xy 228.187493 -278.196865)
			(xy 228.210135 -278.246442) (xy 228.22549 -278.298737) (xy 228.233246 -278.352685) (xy 228.233732 -278.379936)
			(xy 228.233323 -278.404367) (xy 228.227055 -278.452827) (xy 228.214663 -278.500094) (xy 228.19635 -278.545396)
			(xy 228.18471 -278.56688) (xy 228.178106 -278.578818) (xy 228.17836 -278.605742) (xy 228.229414 -278.693118)
			(xy 228.234233 -278.700554) (xy 228.247858 -278.711861) (xy 228.264504 -278.717895) (xy 228.273356 -278.718264)
			(xy 228.615748 -278.718264) (xy 228.6247 -278.717912) (xy 228.641512 -278.711755) (xy 228.655193 -278.700206)
			(xy 228.659944 -278.69261) (xy 228.710236 -278.60371) (xy 228.709982 -278.576532) (xy 228.70287 -278.564594)
			(xy 228.690027 -278.542309) (xy 228.669789 -278.495022) (xy 228.656087 -278.445446) (xy 228.649169 -278.394478)
			(xy 228.648768 -278.36876) (xy 228.649254 -278.341509) (xy 228.65701 -278.287561) (xy 228.672365 -278.235266)
			(xy 228.695007 -278.185689) (xy 228.724473 -278.139839) (xy 228.760164 -278.098648) (xy 228.801355 -278.062957)
			(xy 228.847205 -278.033491) (xy 228.896782 -278.010849) (xy 228.949077 -277.995494) (xy 229.003025 -277.987738)
			(xy 229.057527 -277.987738) (xy 229.111475 -277.995494) (xy 229.16377 -278.010849) (xy 229.213347 -278.033491)
			(xy 229.259197 -278.062957) (xy 229.300388 -278.098648) (xy 229.336079 -278.139839) (xy 229.365545 -278.185689)
			(xy 229.388187 -278.235266) (xy 229.403542 -278.287561) (xy 229.411298 -278.341509) (xy 229.411784 -278.36876)
			(xy 229.411365 -278.394478) (xy 229.40446 -278.445447) (xy 229.390768 -278.495027) (xy 229.370538 -278.542317)
			(xy 229.357682 -278.564594) (xy 229.35057 -278.576532) (xy 229.350316 -278.60371) (xy 229.400608 -278.69261)
			(xy 229.405335 -278.70023) (xy 229.419012 -278.711809) (xy 229.435843 -278.717957) (xy 229.444804 -278.718264)
			(xy 229.96398 -278.718264) (xy 229.97394 -278.717774) (xy 229.992358 -278.710179) (xy 229.999794 -278.703532)
			(xy 230.493316 -278.209756) (xy 230.501853 -278.201372) (xy 230.519642 -278.185362) (xy 230.528876 -278.177752)
			(xy 230.53675 -278.171402) (xy 230.546148 -278.153622) (xy 230.554784 -278.061166) (xy 230.548942 -278.042116)
			(xy 230.542338 -278.034242) (xy 230.525636 -278.013543) (xy 230.49752 -277.968396) (xy 230.475939 -277.919785)
			(xy 230.461312 -277.868649) (xy 230.45392 -277.815979) (xy 230.453438 -277.789386) (xy 230.453924 -277.762135)
			(xy 230.46168 -277.708187) (xy 230.477035 -277.655892) (xy 230.499677 -277.606315) (xy 230.529143 -277.560465)
			(xy 230.564834 -277.519274) (xy 230.606025 -277.483583) (xy 230.651875 -277.454117) (xy 230.701452 -277.431475)
			(xy 230.753747 -277.41612) (xy 230.807695 -277.408364) (xy 230.862197 -277.408364) (xy 230.916145 -277.41612)
			(xy 230.96844 -277.431475) (xy 231.018017 -277.454117) (xy 231.063867 -277.483583) (xy 231.105058 -277.519274)
			(xy 231.120119 -277.536656) (xy 232.472228 -277.536656) (xy 232.476299 -277.481034) (xy 232.488425 -277.426597)
			(xy 232.508348 -277.374506) (xy 232.535644 -277.325871) (xy 232.56973 -277.281728) (xy 232.609879 -277.243019)
			(xy 232.655237 -277.210568) (xy 232.704837 -277.185067) (xy 232.757621 -277.16706) (xy 232.812464 -277.15693)
			(xy 232.868198 -277.154893) (xy 232.923635 -277.160993) (xy 232.977592 -277.175099) (xy 233.028921 -277.196911)
			(xy 233.063289 -277.217886) (xy 236.252004 -277.217886) (xy 236.252461 -277.190515) (xy 236.260281 -277.136336)
			(xy 236.275772 -277.083833) (xy 236.298616 -277.034086) (xy 236.328342 -276.988119) (xy 236.345984 -276.967188)
			(xy 236.35208 -276.960076) (xy 236.35843 -276.943058) (xy 236.35843 -276.857714) (xy 236.35208 -276.840696)
			(xy 236.345984 -276.833584) (xy 236.328368 -276.812633) (xy 236.298654 -276.766665) (xy 236.275813 -276.716922)
			(xy 236.260317 -276.664426) (xy 236.252482 -276.610254) (xy 236.252004 -276.582886) (xy 236.252465 -276.555634)
			(xy 236.260224 -276.501685) (xy 236.275581 -276.449389) (xy 236.298225 -276.399811) (xy 236.327694 -276.35396)
			(xy 236.363388 -276.312769) (xy 236.404581 -276.277078) (xy 236.450433 -276.247612) (xy 236.500013 -276.224972)
			(xy 236.55231 -276.209618) (xy 236.60626 -276.201863) (xy 236.633512 -276.201378) (xy 236.662251 -276.2019)
			(xy 236.719078 -276.210524) (xy 236.773969 -276.227575) (xy 236.82568 -276.252667) (xy 236.873043 -276.285231)
			(xy 236.89437 -276.304502) (xy 236.901482 -276.311106) (xy 236.919008 -276.318218) (xy 237.008416 -276.318218)
			(xy 237.025942 -276.311106) (xy 237.033054 -276.304502) (xy 237.054381 -276.285232) (xy 237.101744 -276.252667)
			(xy 237.153455 -276.227576) (xy 237.208346 -276.210526) (xy 237.265173 -276.201904) (xy 237.322651 -276.201904)
			(xy 237.379478 -276.210526) (xy 237.434369 -276.227576) (xy 237.48608 -276.252667) (xy 237.533443 -276.285232)
			(xy 237.55477 -276.304502) (xy 237.561882 -276.311106) (xy 237.579408 -276.318218) (xy 237.668816 -276.318218)
			(xy 237.686342 -276.311106) (xy 237.693454 -276.304502) (xy 237.714781 -276.285232) (xy 237.762144 -276.252667)
			(xy 237.813855 -276.227576) (xy 237.868746 -276.210526) (xy 237.925573 -276.201904) (xy 237.983051 -276.201904)
			(xy 238.039878 -276.210526) (xy 238.094769 -276.227576) (xy 238.14648 -276.252667) (xy 238.193843 -276.285232)
			(xy 238.21517 -276.304502) (xy 238.222282 -276.311106) (xy 238.239808 -276.318218) (xy 238.329216 -276.318218)
			(xy 238.346742 -276.311106) (xy 238.353854 -276.304502) (xy 238.375186 -276.285237) (xy 238.422545 -276.252667)
			(xy 238.474256 -276.227573) (xy 238.529146 -276.210521) (xy 238.585973 -276.201899) (xy 238.614712 -276.201378)
			(xy 238.641963 -276.201867) (xy 238.69591 -276.209624) (xy 238.748204 -276.22498) (xy 238.79778 -276.247622)
			(xy 238.84363 -276.277088) (xy 238.884819 -276.312779) (xy 238.920511 -276.353969) (xy 238.930183 -276.369018)
			(xy 241.385088 -276.369018) (xy 241.389159 -276.313396) (xy 241.401285 -276.258959) (xy 241.421208 -276.206868)
			(xy 241.448504 -276.158233) (xy 241.48259 -276.11409) (xy 241.522739 -276.075381) (xy 241.568097 -276.04293)
			(xy 241.617697 -276.017429) (xy 241.670481 -275.999422) (xy 241.725324 -275.989292) (xy 241.781058 -275.987255)
			(xy 241.836495 -275.993355) (xy 241.890452 -276.007461) (xy 241.941781 -276.029273) (xy 241.989387 -276.058327)
			(xy 242.032255 -276.094002) (xy 242.069472 -276.135539) (xy 242.100245 -276.182052) (xy 242.123917 -276.232549)
			(xy 242.139985 -276.285956) (xy 242.148105 -276.341132) (xy 242.148614 -276.369018) (xy 242.148105 -276.396904)
			(xy 242.139985 -276.45208) (xy 242.123917 -276.505487) (xy 242.117401 -276.519386) (xy 246.703086 -276.519386)
			(xy 246.707157 -276.463764) (xy 246.719283 -276.409327) (xy 246.739206 -276.357236) (xy 246.766502 -276.308601)
			(xy 246.800588 -276.264458) (xy 246.840737 -276.225749) (xy 246.886095 -276.193298) (xy 246.935695 -276.167797)
			(xy 246.988479 -276.14979) (xy 247.043322 -276.13966) (xy 247.099056 -276.137623) (xy 247.154493 -276.143723)
			(xy 247.20845 -276.157829) (xy 247.259779 -276.179641) (xy 247.307385 -276.208695) (xy 247.350253 -276.24437)
			(xy 247.38747 -276.285907) (xy 247.418243 -276.33242) (xy 247.441915 -276.382917) (xy 247.457983 -276.436324)
			(xy 247.466103 -276.4915) (xy 247.466612 -276.519386) (xy 248.722386 -276.519386) (xy 248.726457 -276.463764)
			(xy 248.738583 -276.409327) (xy 248.758506 -276.357236) (xy 248.785802 -276.308601) (xy 248.819888 -276.264458)
			(xy 248.860037 -276.225749) (xy 248.905395 -276.193298) (xy 248.954995 -276.167797) (xy 249.007779 -276.14979)
			(xy 249.062622 -276.13966) (xy 249.118356 -276.137623) (xy 249.173793 -276.143723) (xy 249.22775 -276.157829)
			(xy 249.279079 -276.179641) (xy 249.326685 -276.208695) (xy 249.369553 -276.24437) (xy 249.40677 -276.285907)
			(xy 249.437543 -276.33242) (xy 249.461215 -276.382917) (xy 249.473845 -276.424898) (xy 268.26897 -276.424898)
			(xy 268.27293 -276.375844) (xy 268.284707 -276.32806) (xy 268.303998 -276.282784) (xy 268.330301 -276.241188)
			(xy 268.362936 -276.204351) (xy 268.401057 -276.173226) (xy 268.443678 -276.148619) (xy 268.489694 -276.131167)
			(xy 268.537913 -276.121323) (xy 268.587088 -276.119342) (xy 268.635943 -276.125274) (xy 268.683214 -276.138966)
			(xy 268.727676 -276.160064) (xy 268.768179 -276.18802) (xy 268.803672 -276.222112) (xy 268.833237 -276.261456)
			(xy 268.856108 -276.305033) (xy 268.871692 -276.351714) (xy 268.879587 -276.400291) (xy 268.880082 -276.424898)
			(xy 269.21893 -276.424898) (xy 269.22289 -276.375844) (xy 269.234667 -276.32806) (xy 269.253958 -276.282784)
			(xy 269.280261 -276.241188) (xy 269.312896 -276.204351) (xy 269.351017 -276.173226) (xy 269.393638 -276.148619)
			(xy 269.439654 -276.131167) (xy 269.487873 -276.121323) (xy 269.537048 -276.119342) (xy 269.585903 -276.125274)
			(xy 269.633174 -276.138966) (xy 269.677636 -276.160064) (xy 269.718139 -276.18802) (xy 269.753632 -276.222112)
			(xy 269.783197 -276.261456) (xy 269.806068 -276.305033) (xy 269.821652 -276.351714) (xy 269.829547 -276.400291)
			(xy 269.830042 -276.424898) (xy 270.169144 -276.424898) (xy 270.173104 -276.375844) (xy 270.184881 -276.32806)
			(xy 270.204172 -276.282784) (xy 270.230475 -276.241188) (xy 270.26311 -276.204351) (xy 270.301231 -276.173226)
			(xy 270.343852 -276.148619) (xy 270.389868 -276.131167) (xy 270.438087 -276.121323) (xy 270.487262 -276.119342)
			(xy 270.536117 -276.125274) (xy 270.583388 -276.138966) (xy 270.62785 -276.160064) (xy 270.668353 -276.18802)
			(xy 270.703846 -276.222112) (xy 270.733411 -276.261456) (xy 270.756282 -276.305033) (xy 270.771866 -276.351714)
			(xy 270.779761 -276.400291) (xy 270.780256 -276.424898) (xy 271.119104 -276.424898) (xy 271.123064 -276.375844)
			(xy 271.134841 -276.32806) (xy 271.154132 -276.282784) (xy 271.180435 -276.241188) (xy 271.21307 -276.204351)
			(xy 271.251191 -276.173226) (xy 271.293812 -276.148619) (xy 271.339828 -276.131167) (xy 271.388047 -276.121323)
			(xy 271.437222 -276.119342) (xy 271.486077 -276.125274) (xy 271.533348 -276.138966) (xy 271.57781 -276.160064)
			(xy 271.618313 -276.18802) (xy 271.653806 -276.222112) (xy 271.683371 -276.261456) (xy 271.706242 -276.305033)
			(xy 271.721826 -276.351714) (xy 271.729721 -276.400291) (xy 271.730216 -276.424898) (xy 272.069064 -276.424898)
			(xy 272.073024 -276.375844) (xy 272.084801 -276.32806) (xy 272.104092 -276.282784) (xy 272.130395 -276.241188)
			(xy 272.16303 -276.204351) (xy 272.201151 -276.173226) (xy 272.243772 -276.148619) (xy 272.289788 -276.131167)
			(xy 272.338007 -276.121323) (xy 272.387182 -276.119342) (xy 272.436037 -276.125274) (xy 272.483308 -276.138966)
			(xy 272.52777 -276.160064) (xy 272.568273 -276.18802) (xy 272.603766 -276.222112) (xy 272.633331 -276.261456)
			(xy 272.656202 -276.305033) (xy 272.671786 -276.351714) (xy 272.679681 -276.400291) (xy 272.680176 -276.424898)
			(xy 273.019024 -276.424898) (xy 273.022984 -276.375844) (xy 273.034761 -276.32806) (xy 273.054052 -276.282784)
			(xy 273.080355 -276.241188) (xy 273.11299 -276.204351) (xy 273.151111 -276.173226) (xy 273.193732 -276.148619)
			(xy 273.239748 -276.131167) (xy 273.287967 -276.121323) (xy 273.337142 -276.119342) (xy 273.385997 -276.125274)
			(xy 273.433268 -276.138966) (xy 273.47773 -276.160064) (xy 273.518233 -276.18802) (xy 273.553726 -276.222112)
			(xy 273.583291 -276.261456) (xy 273.606162 -276.305033) (xy 273.621746 -276.351714) (xy 273.629641 -276.400291)
			(xy 273.630136 -276.424898) (xy 273.968984 -276.424898) (xy 273.972944 -276.375844) (xy 273.984721 -276.32806)
			(xy 274.004012 -276.282784) (xy 274.030315 -276.241188) (xy 274.06295 -276.204351) (xy 274.101071 -276.173226)
			(xy 274.143692 -276.148619) (xy 274.189708 -276.131167) (xy 274.237927 -276.121323) (xy 274.287102 -276.119342)
			(xy 274.335957 -276.125274) (xy 274.383228 -276.138966) (xy 274.42769 -276.160064) (xy 274.468193 -276.18802)
			(xy 274.503686 -276.222112) (xy 274.533251 -276.261456) (xy 274.556122 -276.305033) (xy 274.571706 -276.351714)
			(xy 274.579601 -276.400291) (xy 274.580096 -276.424898) (xy 274.918944 -276.424898) (xy 274.922904 -276.375844)
			(xy 274.934681 -276.32806) (xy 274.953972 -276.282784) (xy 274.980275 -276.241188) (xy 275.01291 -276.204351)
			(xy 275.051031 -276.173226) (xy 275.093652 -276.148619) (xy 275.139668 -276.131167) (xy 275.187887 -276.121323)
			(xy 275.237062 -276.119342) (xy 275.285917 -276.125274) (xy 275.333188 -276.138966) (xy 275.37765 -276.160064)
			(xy 275.418153 -276.18802) (xy 275.453646 -276.222112) (xy 275.483211 -276.261456) (xy 275.506082 -276.305033)
			(xy 275.521666 -276.351714) (xy 275.529561 -276.400291) (xy 275.530056 -276.424898) (xy 275.529561 -276.449505)
			(xy 275.521666 -276.498082) (xy 275.506082 -276.544763) (xy 275.483211 -276.58834) (xy 275.453646 -276.627684)
			(xy 275.418153 -276.661776) (xy 275.37765 -276.689732) (xy 275.333188 -276.71083) (xy 275.285917 -276.724522)
			(xy 275.237062 -276.730454) (xy 275.187887 -276.728473) (xy 275.139668 -276.718629) (xy 275.093652 -276.701177)
			(xy 275.051031 -276.67657) (xy 275.01291 -276.645445) (xy 274.980275 -276.608608) (xy 274.953972 -276.567012)
			(xy 274.934681 -276.521736) (xy 274.922904 -276.473952) (xy 274.918944 -276.424898) (xy 274.580096 -276.424898)
			(xy 274.579601 -276.449505) (xy 274.571706 -276.498082) (xy 274.556122 -276.544763) (xy 274.533251 -276.58834)
			(xy 274.503686 -276.627684) (xy 274.468193 -276.661776) (xy 274.42769 -276.689732) (xy 274.383228 -276.71083)
			(xy 274.335957 -276.724522) (xy 274.287102 -276.730454) (xy 274.237927 -276.728473) (xy 274.189708 -276.718629)
			(xy 274.143692 -276.701177) (xy 274.101071 -276.67657) (xy 274.06295 -276.645445) (xy 274.030315 -276.608608)
			(xy 274.004012 -276.567012) (xy 273.984721 -276.521736) (xy 273.972944 -276.473952) (xy 273.968984 -276.424898)
			(xy 273.630136 -276.424898) (xy 273.629641 -276.449505) (xy 273.621746 -276.498082) (xy 273.606162 -276.544763)
			(xy 273.583291 -276.58834) (xy 273.553726 -276.627684) (xy 273.518233 -276.661776) (xy 273.47773 -276.689732)
			(xy 273.433268 -276.71083) (xy 273.385997 -276.724522) (xy 273.337142 -276.730454) (xy 273.287967 -276.728473)
			(xy 273.239748 -276.718629) (xy 273.193732 -276.701177) (xy 273.151111 -276.67657) (xy 273.11299 -276.645445)
			(xy 273.080355 -276.608608) (xy 273.054052 -276.567012) (xy 273.034761 -276.521736) (xy 273.022984 -276.473952)
			(xy 273.019024 -276.424898) (xy 272.680176 -276.424898) (xy 272.679681 -276.449505) (xy 272.671786 -276.498082)
			(xy 272.656202 -276.544763) (xy 272.633331 -276.58834) (xy 272.603766 -276.627684) (xy 272.568273 -276.661776)
			(xy 272.52777 -276.689732) (xy 272.483308 -276.71083) (xy 272.436037 -276.724522) (xy 272.387182 -276.730454)
			(xy 272.338007 -276.728473) (xy 272.289788 -276.718629) (xy 272.243772 -276.701177) (xy 272.201151 -276.67657)
			(xy 272.16303 -276.645445) (xy 272.130395 -276.608608) (xy 272.104092 -276.567012) (xy 272.084801 -276.521736)
			(xy 272.073024 -276.473952) (xy 272.069064 -276.424898) (xy 271.730216 -276.424898) (xy 271.729721 -276.449505)
			(xy 271.721826 -276.498082) (xy 271.706242 -276.544763) (xy 271.683371 -276.58834) (xy 271.653806 -276.627684)
			(xy 271.618313 -276.661776) (xy 271.57781 -276.689732) (xy 271.533348 -276.71083) (xy 271.486077 -276.724522)
			(xy 271.437222 -276.730454) (xy 271.388047 -276.728473) (xy 271.339828 -276.718629) (xy 271.293812 -276.701177)
			(xy 271.251191 -276.67657) (xy 271.21307 -276.645445) (xy 271.180435 -276.608608) (xy 271.154132 -276.567012)
			(xy 271.134841 -276.521736) (xy 271.123064 -276.473952) (xy 271.119104 -276.424898) (xy 270.780256 -276.424898)
			(xy 270.779761 -276.449505) (xy 270.771866 -276.498082) (xy 270.756282 -276.544763) (xy 270.733411 -276.58834)
			(xy 270.703846 -276.627684) (xy 270.668353 -276.661776) (xy 270.62785 -276.689732) (xy 270.583388 -276.71083)
			(xy 270.536117 -276.724522) (xy 270.487262 -276.730454) (xy 270.438087 -276.728473) (xy 270.389868 -276.718629)
			(xy 270.343852 -276.701177) (xy 270.301231 -276.67657) (xy 270.26311 -276.645445) (xy 270.230475 -276.608608)
			(xy 270.204172 -276.567012) (xy 270.184881 -276.521736) (xy 270.173104 -276.473952) (xy 270.169144 -276.424898)
			(xy 269.830042 -276.424898) (xy 269.829547 -276.449505) (xy 269.821652 -276.498082) (xy 269.806068 -276.544763)
			(xy 269.783197 -276.58834) (xy 269.753632 -276.627684) (xy 269.718139 -276.661776) (xy 269.677636 -276.689732)
			(xy 269.633174 -276.71083) (xy 269.585903 -276.724522) (xy 269.537048 -276.730454) (xy 269.487873 -276.728473)
			(xy 269.439654 -276.718629) (xy 269.393638 -276.701177) (xy 269.351017 -276.67657) (xy 269.312896 -276.645445)
			(xy 269.280261 -276.608608) (xy 269.253958 -276.567012) (xy 269.234667 -276.521736) (xy 269.22289 -276.473952)
			(xy 269.21893 -276.424898) (xy 268.880082 -276.424898) (xy 268.879587 -276.449505) (xy 268.871692 -276.498082)
			(xy 268.856108 -276.544763) (xy 268.833237 -276.58834) (xy 268.803672 -276.627684) (xy 268.768179 -276.661776)
			(xy 268.727676 -276.689732) (xy 268.683214 -276.71083) (xy 268.635943 -276.724522) (xy 268.587088 -276.730454)
			(xy 268.537913 -276.728473) (xy 268.489694 -276.718629) (xy 268.443678 -276.701177) (xy 268.401057 -276.67657)
			(xy 268.362936 -276.645445) (xy 268.330301 -276.608608) (xy 268.303998 -276.567012) (xy 268.284707 -276.521736)
			(xy 268.27293 -276.473952) (xy 268.26897 -276.424898) (xy 249.473845 -276.424898) (xy 249.477283 -276.436324)
			(xy 249.485403 -276.4915) (xy 249.485912 -276.519386) (xy 249.485403 -276.547272) (xy 249.477283 -276.602448)
			(xy 249.461215 -276.655855) (xy 249.437543 -276.706352) (xy 249.40677 -276.752865) (xy 249.369553 -276.794402)
			(xy 249.326685 -276.830077) (xy 249.279079 -276.859131) (xy 249.22775 -276.880943) (xy 249.173793 -276.895049)
			(xy 249.129907 -276.899878) (xy 276.343884 -276.899878) (xy 276.347844 -276.850824) (xy 276.359621 -276.80304)
			(xy 276.378912 -276.757764) (xy 276.405215 -276.716168) (xy 276.43785 -276.679331) (xy 276.475971 -276.648206)
			(xy 276.518592 -276.623599) (xy 276.564608 -276.606147) (xy 276.612827 -276.596303) (xy 276.662002 -276.594322)
			(xy 276.710857 -276.600254) (xy 276.758128 -276.613946) (xy 276.80259 -276.635044) (xy 276.843093 -276.663)
			(xy 276.878586 -276.697092) (xy 276.908151 -276.736436) (xy 276.931022 -276.780013) (xy 276.946606 -276.826694)
			(xy 276.954501 -276.875271) (xy 276.954996 -276.899878) (xy 277.294098 -276.899878) (xy 277.298058 -276.850824)
			(xy 277.309835 -276.80304) (xy 277.329126 -276.757764) (xy 277.355429 -276.716168) (xy 277.388064 -276.679331)
			(xy 277.426185 -276.648206) (xy 277.468806 -276.623599) (xy 277.514822 -276.606147) (xy 277.563041 -276.596303)
			(xy 277.612216 -276.594322) (xy 277.661071 -276.600254) (xy 277.708342 -276.613946) (xy 277.752804 -276.635044)
			(xy 277.793307 -276.663) (xy 277.8288 -276.697092) (xy 277.858365 -276.736436) (xy 277.881236 -276.780013)
			(xy 277.89682 -276.826694) (xy 277.904715 -276.875271) (xy 277.90521 -276.899878) (xy 278.244058 -276.899878)
			(xy 278.248018 -276.850824) (xy 278.259795 -276.80304) (xy 278.279086 -276.757764) (xy 278.305389 -276.716168)
			(xy 278.338024 -276.679331) (xy 278.376145 -276.648206) (xy 278.418766 -276.623599) (xy 278.464782 -276.606147)
			(xy 278.513001 -276.596303) (xy 278.562176 -276.594322) (xy 278.611031 -276.600254) (xy 278.658302 -276.613946)
			(xy 278.702764 -276.635044) (xy 278.743267 -276.663) (xy 278.77876 -276.697092) (xy 278.808325 -276.736436)
			(xy 278.831196 -276.780013) (xy 278.84678 -276.826694) (xy 278.854675 -276.875271) (xy 278.85517 -276.899878)
			(xy 279.194018 -276.899878) (xy 279.197978 -276.850824) (xy 279.209755 -276.80304) (xy 279.229046 -276.757764)
			(xy 279.255349 -276.716168) (xy 279.287984 -276.679331) (xy 279.326105 -276.648206) (xy 279.368726 -276.623599)
			(xy 279.414742 -276.606147) (xy 279.462961 -276.596303) (xy 279.512136 -276.594322) (xy 279.560991 -276.600254)
			(xy 279.608262 -276.613946) (xy 279.652724 -276.635044) (xy 279.693227 -276.663) (xy 279.72872 -276.697092)
			(xy 279.758285 -276.736436) (xy 279.781156 -276.780013) (xy 279.79674 -276.826694) (xy 279.804635 -276.875271)
			(xy 279.80513 -276.899878) (xy 280.143978 -276.899878) (xy 280.147938 -276.850824) (xy 280.159715 -276.80304)
			(xy 280.179006 -276.757764) (xy 280.205309 -276.716168) (xy 280.237944 -276.679331) (xy 280.276065 -276.648206)
			(xy 280.318686 -276.623599) (xy 280.364702 -276.606147) (xy 280.412921 -276.596303) (xy 280.462096 -276.594322)
			(xy 280.510951 -276.600254) (xy 280.558222 -276.613946) (xy 280.602684 -276.635044) (xy 280.643187 -276.663)
			(xy 280.67868 -276.697092) (xy 280.708245 -276.736436) (xy 280.731116 -276.780013) (xy 280.7467 -276.826694)
			(xy 280.754595 -276.875271) (xy 280.75509 -276.899878) (xy 281.093938 -276.899878) (xy 281.097898 -276.850824)
			(xy 281.109675 -276.80304) (xy 281.128966 -276.757764) (xy 281.155269 -276.716168) (xy 281.187904 -276.679331)
			(xy 281.226025 -276.648206) (xy 281.268646 -276.623599) (xy 281.314662 -276.606147) (xy 281.362881 -276.596303)
			(xy 281.412056 -276.594322) (xy 281.460911 -276.600254) (xy 281.508182 -276.613946) (xy 281.552644 -276.635044)
			(xy 281.593147 -276.663) (xy 281.62864 -276.697092) (xy 281.658205 -276.736436) (xy 281.681076 -276.780013)
			(xy 281.69666 -276.826694) (xy 281.704555 -276.875271) (xy 281.70505 -276.899878) (xy 282.043898 -276.899878)
			(xy 282.047858 -276.850824) (xy 282.059635 -276.80304) (xy 282.078926 -276.757764) (xy 282.105229 -276.716168)
			(xy 282.137864 -276.679331) (xy 282.175985 -276.648206) (xy 282.218606 -276.623599) (xy 282.264622 -276.606147)
			(xy 282.312841 -276.596303) (xy 282.362016 -276.594322) (xy 282.410871 -276.600254) (xy 282.458142 -276.613946)
			(xy 282.502604 -276.635044) (xy 282.543107 -276.663) (xy 282.5786 -276.697092) (xy 282.608165 -276.736436)
			(xy 282.631036 -276.780013) (xy 282.64662 -276.826694) (xy 282.654515 -276.875271) (xy 282.65501 -276.899878)
			(xy 282.994112 -276.899878) (xy 282.998072 -276.850824) (xy 283.009849 -276.80304) (xy 283.02914 -276.757764)
			(xy 283.055443 -276.716168) (xy 283.088078 -276.679331) (xy 283.126199 -276.648206) (xy 283.16882 -276.623599)
			(xy 283.214836 -276.606147) (xy 283.263055 -276.596303) (xy 283.31223 -276.594322) (xy 283.361085 -276.600254)
			(xy 283.408356 -276.613946) (xy 283.452818 -276.635044) (xy 283.493321 -276.663) (xy 283.528814 -276.697092)
			(xy 283.558379 -276.736436) (xy 283.58125 -276.780013) (xy 283.596834 -276.826694) (xy 283.604729 -276.875271)
			(xy 283.605224 -276.899878) (xy 283.944072 -276.899878) (xy 283.948032 -276.850824) (xy 283.959809 -276.80304)
			(xy 283.9791 -276.757764) (xy 284.005403 -276.716168) (xy 284.038038 -276.679331) (xy 284.076159 -276.648206)
			(xy 284.11878 -276.623599) (xy 284.164796 -276.606147) (xy 284.213015 -276.596303) (xy 284.26219 -276.594322)
			(xy 284.311045 -276.600254) (xy 284.358316 -276.613946) (xy 284.402778 -276.635044) (xy 284.443281 -276.663)
			(xy 284.478774 -276.697092) (xy 284.508339 -276.736436) (xy 284.53121 -276.780013) (xy 284.546794 -276.826694)
			(xy 284.554689 -276.875271) (xy 284.555184 -276.899878) (xy 284.894032 -276.899878) (xy 284.897992 -276.850824)
			(xy 284.909769 -276.80304) (xy 284.92906 -276.757764) (xy 284.955363 -276.716168) (xy 284.987998 -276.679331)
			(xy 285.026119 -276.648206) (xy 285.06874 -276.623599) (xy 285.114756 -276.606147) (xy 285.162975 -276.596303)
			(xy 285.21215 -276.594322) (xy 285.261005 -276.600254) (xy 285.308276 -276.613946) (xy 285.352738 -276.635044)
			(xy 285.393241 -276.663) (xy 285.428734 -276.697092) (xy 285.458299 -276.736436) (xy 285.48117 -276.780013)
			(xy 285.496754 -276.826694) (xy 285.504649 -276.875271) (xy 285.505144 -276.899878) (xy 285.843992 -276.899878)
			(xy 285.847952 -276.850824) (xy 285.859729 -276.80304) (xy 285.87902 -276.757764) (xy 285.905323 -276.716168)
			(xy 285.937958 -276.679331) (xy 285.976079 -276.648206) (xy 286.0187 -276.623599) (xy 286.064716 -276.606147)
			(xy 286.112935 -276.596303) (xy 286.16211 -276.594322) (xy 286.210965 -276.600254) (xy 286.258236 -276.613946)
			(xy 286.302698 -276.635044) (xy 286.343201 -276.663) (xy 286.378694 -276.697092) (xy 286.408259 -276.736436)
			(xy 286.43113 -276.780013) (xy 286.446714 -276.826694) (xy 286.454609 -276.875271) (xy 286.455104 -276.899878)
			(xy 286.793952 -276.899878) (xy 286.797912 -276.850824) (xy 286.809689 -276.80304) (xy 286.82898 -276.757764)
			(xy 286.855283 -276.716168) (xy 286.887918 -276.679331) (xy 286.926039 -276.648206) (xy 286.96866 -276.623599)
			(xy 287.014676 -276.606147) (xy 287.062895 -276.596303) (xy 287.11207 -276.594322) (xy 287.160925 -276.600254)
			(xy 287.208196 -276.613946) (xy 287.252658 -276.635044) (xy 287.293161 -276.663) (xy 287.328654 -276.697092)
			(xy 287.358219 -276.736436) (xy 287.38109 -276.780013) (xy 287.396674 -276.826694) (xy 287.404569 -276.875271)
			(xy 287.405064 -276.899878) (xy 287.743912 -276.899878) (xy 287.747872 -276.850824) (xy 287.759649 -276.80304)
			(xy 287.77894 -276.757764) (xy 287.805243 -276.716168) (xy 287.837878 -276.679331) (xy 287.875999 -276.648206)
			(xy 287.91862 -276.623599) (xy 287.964636 -276.606147) (xy 288.012855 -276.596303) (xy 288.06203 -276.594322)
			(xy 288.110885 -276.600254) (xy 288.158156 -276.613946) (xy 288.202618 -276.635044) (xy 288.243121 -276.663)
			(xy 288.278614 -276.697092) (xy 288.308179 -276.736436) (xy 288.33105 -276.780013) (xy 288.346634 -276.826694)
			(xy 288.354529 -276.875271) (xy 288.355024 -276.899878) (xy 288.694126 -276.899878) (xy 288.698086 -276.850824)
			(xy 288.709863 -276.80304) (xy 288.729154 -276.757764) (xy 288.755457 -276.716168) (xy 288.788092 -276.679331)
			(xy 288.826213 -276.648206) (xy 288.868834 -276.623599) (xy 288.91485 -276.606147) (xy 288.963069 -276.596303)
			(xy 289.012244 -276.594322) (xy 289.061099 -276.600254) (xy 289.10837 -276.613946) (xy 289.152832 -276.635044)
			(xy 289.193335 -276.663) (xy 289.228828 -276.697092) (xy 289.258393 -276.736436) (xy 289.281264 -276.780013)
			(xy 289.296848 -276.826694) (xy 289.304743 -276.875271) (xy 289.305238 -276.899878) (xy 289.644086 -276.899878)
			(xy 289.648046 -276.850824) (xy 289.659823 -276.80304) (xy 289.679114 -276.757764) (xy 289.705417 -276.716168)
			(xy 289.738052 -276.679331) (xy 289.776173 -276.648206) (xy 289.818794 -276.623599) (xy 289.86481 -276.606147)
			(xy 289.913029 -276.596303) (xy 289.962204 -276.594322) (xy 290.011059 -276.600254) (xy 290.05833 -276.613946)
			(xy 290.102792 -276.635044) (xy 290.143295 -276.663) (xy 290.178788 -276.697092) (xy 290.208353 -276.736436)
			(xy 290.231224 -276.780013) (xy 290.246808 -276.826694) (xy 290.254703 -276.875271) (xy 290.255198 -276.899878)
			(xy 290.594046 -276.899878) (xy 290.598006 -276.850824) (xy 290.609783 -276.80304) (xy 290.629074 -276.757764)
			(xy 290.655377 -276.716168) (xy 290.688012 -276.679331) (xy 290.726133 -276.648206) (xy 290.768754 -276.623599)
			(xy 290.81477 -276.606147) (xy 290.862989 -276.596303) (xy 290.912164 -276.594322) (xy 290.961019 -276.600254)
			(xy 291.00829 -276.613946) (xy 291.052752 -276.635044) (xy 291.093255 -276.663) (xy 291.128748 -276.697092)
			(xy 291.158313 -276.736436) (xy 291.181184 -276.780013) (xy 291.196768 -276.826694) (xy 291.204663 -276.875271)
			(xy 291.205158 -276.899878) (xy 291.544006 -276.899878) (xy 291.547966 -276.850824) (xy 291.559743 -276.80304)
			(xy 291.579034 -276.757764) (xy 291.605337 -276.716168) (xy 291.637972 -276.679331) (xy 291.676093 -276.648206)
			(xy 291.718714 -276.623599) (xy 291.76473 -276.606147) (xy 291.812949 -276.596303) (xy 291.862124 -276.594322)
			(xy 291.910979 -276.600254) (xy 291.95825 -276.613946) (xy 292.002712 -276.635044) (xy 292.043215 -276.663)
			(xy 292.078708 -276.697092) (xy 292.108273 -276.736436) (xy 292.131144 -276.780013) (xy 292.146728 -276.826694)
			(xy 292.154623 -276.875271) (xy 292.155118 -276.899878) (xy 292.493966 -276.899878) (xy 292.497926 -276.850824)
			(xy 292.509703 -276.80304) (xy 292.528994 -276.757764) (xy 292.555297 -276.716168) (xy 292.587932 -276.679331)
			(xy 292.626053 -276.648206) (xy 292.668674 -276.623599) (xy 292.71469 -276.606147) (xy 292.762909 -276.596303)
			(xy 292.812084 -276.594322) (xy 292.860939 -276.600254) (xy 292.90821 -276.613946) (xy 292.952672 -276.635044)
			(xy 292.993175 -276.663) (xy 293.028668 -276.697092) (xy 293.058233 -276.736436) (xy 293.081104 -276.780013)
			(xy 293.096688 -276.826694) (xy 293.104583 -276.875271) (xy 293.105078 -276.899878) (xy 293.443926 -276.899878)
			(xy 293.447886 -276.850824) (xy 293.459663 -276.80304) (xy 293.478954 -276.757764) (xy 293.505257 -276.716168)
			(xy 293.537892 -276.679331) (xy 293.576013 -276.648206) (xy 293.618634 -276.623599) (xy 293.66465 -276.606147)
			(xy 293.712869 -276.596303) (xy 293.762044 -276.594322) (xy 293.810899 -276.600254) (xy 293.85817 -276.613946)
			(xy 293.902632 -276.635044) (xy 293.943135 -276.663) (xy 293.978628 -276.697092) (xy 294.008193 -276.736436)
			(xy 294.031064 -276.780013) (xy 294.046648 -276.826694) (xy 294.054543 -276.875271) (xy 294.055038 -276.899878)
			(xy 294.393886 -276.899878) (xy 294.397846 -276.850824) (xy 294.409623 -276.80304) (xy 294.428914 -276.757764)
			(xy 294.455217 -276.716168) (xy 294.487852 -276.679331) (xy 294.525973 -276.648206) (xy 294.568594 -276.623599)
			(xy 294.61461 -276.606147) (xy 294.662829 -276.596303) (xy 294.712004 -276.594322) (xy 294.760859 -276.600254)
			(xy 294.80813 -276.613946) (xy 294.852592 -276.635044) (xy 294.893095 -276.663) (xy 294.928588 -276.697092)
			(xy 294.958153 -276.736436) (xy 294.981024 -276.780013) (xy 294.996608 -276.826694) (xy 295.004503 -276.875271)
			(xy 295.004998 -276.899878) (xy 295.3441 -276.899878) (xy 295.34806 -276.850824) (xy 295.359837 -276.80304)
			(xy 295.379128 -276.757764) (xy 295.405431 -276.716168) (xy 295.438066 -276.679331) (xy 295.476187 -276.648206)
			(xy 295.518808 -276.623599) (xy 295.564824 -276.606147) (xy 295.613043 -276.596303) (xy 295.662218 -276.594322)
			(xy 295.711073 -276.600254) (xy 295.758344 -276.613946) (xy 295.802806 -276.635044) (xy 295.843309 -276.663)
			(xy 295.878802 -276.697092) (xy 295.908367 -276.736436) (xy 295.931238 -276.780013) (xy 295.946822 -276.826694)
			(xy 295.954717 -276.875271) (xy 295.955212 -276.899878) (xy 296.29406 -276.899878) (xy 296.29802 -276.850824)
			(xy 296.309797 -276.80304) (xy 296.329088 -276.757764) (xy 296.355391 -276.716168) (xy 296.388026 -276.679331)
			(xy 296.426147 -276.648206) (xy 296.468768 -276.623599) (xy 296.514784 -276.606147) (xy 296.563003 -276.596303)
			(xy 296.612178 -276.594322) (xy 296.661033 -276.600254) (xy 296.708304 -276.613946) (xy 296.752766 -276.635044)
			(xy 296.793269 -276.663) (xy 296.828762 -276.697092) (xy 296.858327 -276.736436) (xy 296.881198 -276.780013)
			(xy 296.896782 -276.826694) (xy 296.904677 -276.875271) (xy 296.905172 -276.899878) (xy 297.24402 -276.899878)
			(xy 297.24798 -276.850824) (xy 297.259757 -276.80304) (xy 297.279048 -276.757764) (xy 297.305351 -276.716168)
			(xy 297.337986 -276.679331) (xy 297.376107 -276.648206) (xy 297.418728 -276.623599) (xy 297.464744 -276.606147)
			(xy 297.512963 -276.596303) (xy 297.562138 -276.594322) (xy 297.610993 -276.600254) (xy 297.658264 -276.613946)
			(xy 297.702726 -276.635044) (xy 297.743229 -276.663) (xy 297.778722 -276.697092) (xy 297.808287 -276.736436)
			(xy 297.831158 -276.780013) (xy 297.846742 -276.826694) (xy 297.854637 -276.875271) (xy 297.855132 -276.899878)
			(xy 298.19398 -276.899878) (xy 298.19794 -276.850824) (xy 298.209717 -276.80304) (xy 298.229008 -276.757764)
			(xy 298.255311 -276.716168) (xy 298.287946 -276.679331) (xy 298.326067 -276.648206) (xy 298.368688 -276.623599)
			(xy 298.414704 -276.606147) (xy 298.462923 -276.596303) (xy 298.512098 -276.594322) (xy 298.560953 -276.600254)
			(xy 298.608224 -276.613946) (xy 298.652686 -276.635044) (xy 298.693189 -276.663) (xy 298.728682 -276.697092)
			(xy 298.758247 -276.736436) (xy 298.781118 -276.780013) (xy 298.796702 -276.826694) (xy 298.804597 -276.875271)
			(xy 298.805092 -276.899878) (xy 299.14394 -276.899878) (xy 299.1479 -276.850824) (xy 299.159677 -276.80304)
			(xy 299.178968 -276.757764) (xy 299.205271 -276.716168) (xy 299.237906 -276.679331) (xy 299.276027 -276.648206)
			(xy 299.318648 -276.623599) (xy 299.364664 -276.606147) (xy 299.412883 -276.596303) (xy 299.462058 -276.594322)
			(xy 299.510913 -276.600254) (xy 299.558184 -276.613946) (xy 299.602646 -276.635044) (xy 299.643149 -276.663)
			(xy 299.678642 -276.697092) (xy 299.708207 -276.736436) (xy 299.731078 -276.780013) (xy 299.746662 -276.826694)
			(xy 299.754557 -276.875271) (xy 299.755052 -276.899878) (xy 300.0939 -276.899878) (xy 300.09786 -276.850824)
			(xy 300.109637 -276.80304) (xy 300.128928 -276.757764) (xy 300.155231 -276.716168) (xy 300.187866 -276.679331)
			(xy 300.225987 -276.648206) (xy 300.268608 -276.623599) (xy 300.314624 -276.606147) (xy 300.362843 -276.596303)
			(xy 300.412018 -276.594322) (xy 300.460873 -276.600254) (xy 300.508144 -276.613946) (xy 300.552606 -276.635044)
			(xy 300.593109 -276.663) (xy 300.628602 -276.697092) (xy 300.658167 -276.736436) (xy 300.681038 -276.780013)
			(xy 300.696622 -276.826694) (xy 300.704517 -276.875271) (xy 300.705012 -276.899878) (xy 301.044114 -276.899878)
			(xy 301.048074 -276.850824) (xy 301.059851 -276.80304) (xy 301.079142 -276.757764) (xy 301.105445 -276.716168)
			(xy 301.13808 -276.679331) (xy 301.176201 -276.648206) (xy 301.218822 -276.623599) (xy 301.264838 -276.606147)
			(xy 301.313057 -276.596303) (xy 301.362232 -276.594322) (xy 301.411087 -276.600254) (xy 301.458358 -276.613946)
			(xy 301.50282 -276.635044) (xy 301.543323 -276.663) (xy 301.578816 -276.697092) (xy 301.608381 -276.736436)
			(xy 301.631252 -276.780013) (xy 301.646836 -276.826694) (xy 301.654731 -276.875271) (xy 301.655226 -276.899878)
			(xy 301.994074 -276.899878) (xy 301.998034 -276.850824) (xy 302.009811 -276.80304) (xy 302.029102 -276.757764)
			(xy 302.055405 -276.716168) (xy 302.08804 -276.679331) (xy 302.126161 -276.648206) (xy 302.168782 -276.623599)
			(xy 302.214798 -276.606147) (xy 302.263017 -276.596303) (xy 302.312192 -276.594322) (xy 302.361047 -276.600254)
			(xy 302.408318 -276.613946) (xy 302.45278 -276.635044) (xy 302.493283 -276.663) (xy 302.528776 -276.697092)
			(xy 302.558341 -276.736436) (xy 302.581212 -276.780013) (xy 302.596796 -276.826694) (xy 302.604691 -276.875271)
			(xy 302.605186 -276.899878) (xy 302.944034 -276.899878) (xy 302.947994 -276.850824) (xy 302.959771 -276.80304)
			(xy 302.979062 -276.757764) (xy 303.005365 -276.716168) (xy 303.038 -276.679331) (xy 303.076121 -276.648206)
			(xy 303.118742 -276.623599) (xy 303.164758 -276.606147) (xy 303.212977 -276.596303) (xy 303.262152 -276.594322)
			(xy 303.311007 -276.600254) (xy 303.358278 -276.613946) (xy 303.40274 -276.635044) (xy 303.443243 -276.663)
			(xy 303.478736 -276.697092) (xy 303.508301 -276.736436) (xy 303.531172 -276.780013) (xy 303.546756 -276.826694)
			(xy 303.554651 -276.875271) (xy 303.555146 -276.899878) (xy 303.893994 -276.899878) (xy 303.897954 -276.850824)
			(xy 303.909731 -276.80304) (xy 303.929022 -276.757764) (xy 303.955325 -276.716168) (xy 303.98796 -276.679331)
			(xy 304.026081 -276.648206) (xy 304.068702 -276.623599) (xy 304.114718 -276.606147) (xy 304.162937 -276.596303)
			(xy 304.212112 -276.594322) (xy 304.260967 -276.600254) (xy 304.308238 -276.613946) (xy 304.3527 -276.635044)
			(xy 304.393203 -276.663) (xy 304.428696 -276.697092) (xy 304.458261 -276.736436) (xy 304.481132 -276.780013)
			(xy 304.496716 -276.826694) (xy 304.504611 -276.875271) (xy 304.505106 -276.899878) (xy 304.843954 -276.899878)
			(xy 304.847914 -276.850824) (xy 304.859691 -276.80304) (xy 304.878982 -276.757764) (xy 304.905285 -276.716168)
			(xy 304.93792 -276.679331) (xy 304.976041 -276.648206) (xy 305.018662 -276.623599) (xy 305.064678 -276.606147)
			(xy 305.112897 -276.596303) (xy 305.162072 -276.594322) (xy 305.210927 -276.600254) (xy 305.258198 -276.613946)
			(xy 305.30266 -276.635044) (xy 305.343163 -276.663) (xy 305.378656 -276.697092) (xy 305.408221 -276.736436)
			(xy 305.431092 -276.780013) (xy 305.446676 -276.826694) (xy 305.454571 -276.875271) (xy 305.455066 -276.899878)
			(xy 305.79366 -276.899878) (xy 305.79762 -276.850824) (xy 305.809397 -276.80304) (xy 305.828688 -276.757764)
			(xy 305.854991 -276.716168) (xy 305.887626 -276.679331) (xy 305.925747 -276.648206) (xy 305.968368 -276.623599)
			(xy 306.014384 -276.606147) (xy 306.062603 -276.596303) (xy 306.111778 -276.594322) (xy 306.160633 -276.600254)
			(xy 306.207904 -276.613946) (xy 306.252366 -276.635044) (xy 306.292869 -276.663) (xy 306.328362 -276.697092)
			(xy 306.357927 -276.736436) (xy 306.380798 -276.780013) (xy 306.396382 -276.826694) (xy 306.404277 -276.875271)
			(xy 306.404772 -276.899878) (xy 306.743874 -276.899878) (xy 306.747834 -276.850824) (xy 306.759611 -276.80304)
			(xy 306.778902 -276.757764) (xy 306.805205 -276.716168) (xy 306.83784 -276.679331) (xy 306.875961 -276.648206)
			(xy 306.918582 -276.623599) (xy 306.964598 -276.606147) (xy 307.012817 -276.596303) (xy 307.061992 -276.594322)
			(xy 307.110847 -276.600254) (xy 307.158118 -276.613946) (xy 307.20258 -276.635044) (xy 307.243083 -276.663)
			(xy 307.278576 -276.697092) (xy 307.308141 -276.736436) (xy 307.331012 -276.780013) (xy 307.346596 -276.826694)
			(xy 307.354491 -276.875271) (xy 307.354986 -276.899878) (xy 307.693834 -276.899878) (xy 307.697794 -276.850824)
			(xy 307.709571 -276.80304) (xy 307.728862 -276.757764) (xy 307.755165 -276.716168) (xy 307.7878 -276.679331)
			(xy 307.825921 -276.648206) (xy 307.868542 -276.623599) (xy 307.914558 -276.606147) (xy 307.962777 -276.596303)
			(xy 308.011952 -276.594322) (xy 308.060807 -276.600254) (xy 308.108078 -276.613946) (xy 308.15254 -276.635044)
			(xy 308.193043 -276.663) (xy 308.228536 -276.697092) (xy 308.258101 -276.736436) (xy 308.280972 -276.780013)
			(xy 308.296556 -276.826694) (xy 308.304451 -276.875271) (xy 308.304946 -276.899878) (xy 308.643794 -276.899878)
			(xy 308.647754 -276.850824) (xy 308.659531 -276.80304) (xy 308.678822 -276.757764) (xy 308.705125 -276.716168)
			(xy 308.73776 -276.679331) (xy 308.775881 -276.648206) (xy 308.818502 -276.623599) (xy 308.864518 -276.606147)
			(xy 308.912737 -276.596303) (xy 308.961912 -276.594322) (xy 309.010767 -276.600254) (xy 309.058038 -276.613946)
			(xy 309.1025 -276.635044) (xy 309.143003 -276.663) (xy 309.178496 -276.697092) (xy 309.208061 -276.736436)
			(xy 309.230932 -276.780013) (xy 309.246516 -276.826694) (xy 309.254411 -276.875271) (xy 309.254906 -276.899878)
			(xy 309.593754 -276.899878) (xy 309.597714 -276.850824) (xy 309.609491 -276.80304) (xy 309.628782 -276.757764)
			(xy 309.655085 -276.716168) (xy 309.68772 -276.679331) (xy 309.725841 -276.648206) (xy 309.768462 -276.623599)
			(xy 309.814478 -276.606147) (xy 309.862697 -276.596303) (xy 309.911872 -276.594322) (xy 309.960727 -276.600254)
			(xy 310.007998 -276.613946) (xy 310.05246 -276.635044) (xy 310.092963 -276.663) (xy 310.128456 -276.697092)
			(xy 310.158021 -276.736436) (xy 310.180892 -276.780013) (xy 310.196476 -276.826694) (xy 310.204371 -276.875271)
			(xy 310.204866 -276.899878) (xy 310.543714 -276.899878) (xy 310.547674 -276.850824) (xy 310.559451 -276.80304)
			(xy 310.578742 -276.757764) (xy 310.605045 -276.716168) (xy 310.63768 -276.679331) (xy 310.675801 -276.648206)
			(xy 310.718422 -276.623599) (xy 310.764438 -276.606147) (xy 310.812657 -276.596303) (xy 310.861832 -276.594322)
			(xy 310.910687 -276.600254) (xy 310.957958 -276.613946) (xy 311.00242 -276.635044) (xy 311.042923 -276.663)
			(xy 311.078416 -276.697092) (xy 311.107981 -276.736436) (xy 311.130852 -276.780013) (xy 311.146436 -276.826694)
			(xy 311.154331 -276.875271) (xy 311.154826 -276.899878) (xy 311.493674 -276.899878) (xy 311.497634 -276.850824)
			(xy 311.509411 -276.80304) (xy 311.528702 -276.757764) (xy 311.555005 -276.716168) (xy 311.58764 -276.679331)
			(xy 311.625761 -276.648206) (xy 311.668382 -276.623599) (xy 311.714398 -276.606147) (xy 311.762617 -276.596303)
			(xy 311.811792 -276.594322) (xy 311.860647 -276.600254) (xy 311.907918 -276.613946) (xy 311.95238 -276.635044)
			(xy 311.992883 -276.663) (xy 312.028376 -276.697092) (xy 312.057941 -276.736436) (xy 312.080812 -276.780013)
			(xy 312.096396 -276.826694) (xy 312.104291 -276.875271) (xy 312.104786 -276.899878) (xy 312.443888 -276.899878)
			(xy 312.447848 -276.850824) (xy 312.459625 -276.80304) (xy 312.478916 -276.757764) (xy 312.505219 -276.716168)
			(xy 312.537854 -276.679331) (xy 312.575975 -276.648206) (xy 312.618596 -276.623599) (xy 312.664612 -276.606147)
			(xy 312.712831 -276.596303) (xy 312.762006 -276.594322) (xy 312.810861 -276.600254) (xy 312.858132 -276.613946)
			(xy 312.902594 -276.635044) (xy 312.943097 -276.663) (xy 312.97859 -276.697092) (xy 313.008155 -276.736436)
			(xy 313.031026 -276.780013) (xy 313.04661 -276.826694) (xy 313.054505 -276.875271) (xy 313.055 -276.899878)
			(xy 313.054505 -276.924485) (xy 313.054326 -276.925586) (xy 313.373258 -276.925586) (xy 313.373258 -276.87417)
			(xy 313.381301 -276.823388) (xy 313.397189 -276.774489) (xy 313.420532 -276.728677) (xy 313.450753 -276.687081)
			(xy 313.487109 -276.650725) (xy 313.528705 -276.620504) (xy 313.574517 -276.597161) (xy 313.623416 -276.581273)
			(xy 313.674198 -276.57323) (xy 313.725614 -276.57323) (xy 313.776396 -276.581273) (xy 313.825295 -276.597161)
			(xy 313.871107 -276.620504) (xy 313.912703 -276.650725) (xy 313.949059 -276.687081) (xy 313.97928 -276.728677)
			(xy 314.002623 -276.774489) (xy 314.018511 -276.823388) (xy 314.026554 -276.87417) (xy 314.027058 -276.899878)
			(xy 314.026554 -276.925586) (xy 314.323218 -276.925586) (xy 314.323218 -276.87417) (xy 314.331261 -276.823388)
			(xy 314.347149 -276.774489) (xy 314.370492 -276.728677) (xy 314.400713 -276.687081) (xy 314.437069 -276.650725)
			(xy 314.478665 -276.620504) (xy 314.524477 -276.597161) (xy 314.573376 -276.581273) (xy 314.624158 -276.57323)
			(xy 314.675574 -276.57323) (xy 314.726356 -276.581273) (xy 314.775255 -276.597161) (xy 314.821067 -276.620504)
			(xy 314.862663 -276.650725) (xy 314.899019 -276.687081) (xy 314.92924 -276.728677) (xy 314.952583 -276.774489)
			(xy 314.968471 -276.823388) (xy 314.976514 -276.87417) (xy 314.977018 -276.899878) (xy 314.977013 -276.900132)
			(xy 315.294276 -276.900132) (xy 315.298236 -276.851078) (xy 315.310013 -276.803294) (xy 315.329304 -276.758018)
			(xy 315.355607 -276.716422) (xy 315.388242 -276.679585) (xy 315.426363 -276.64846) (xy 315.468984 -276.623853)
			(xy 315.515 -276.606401) (xy 315.563219 -276.596557) (xy 315.612394 -276.594576) (xy 315.661249 -276.600508)
			(xy 315.70852 -276.6142) (xy 315.752982 -276.635298) (xy 315.793485 -276.663254) (xy 315.828978 -276.697346)
			(xy 315.858543 -276.73669) (xy 315.881414 -276.780267) (xy 315.896998 -276.826948) (xy 315.904893 -276.875525)
			(xy 315.905388 -276.900132) (xy 315.904893 -276.924739) (xy 315.896998 -276.973316) (xy 315.881414 -277.019997)
			(xy 315.858543 -277.063574) (xy 315.828978 -277.102918) (xy 315.793485 -277.13701) (xy 315.752982 -277.164966)
			(xy 315.70852 -277.186064) (xy 315.661249 -277.199756) (xy 315.612394 -277.205688) (xy 315.563219 -277.203707)
			(xy 315.515 -277.193863) (xy 315.468984 -277.176411) (xy 315.426363 -277.151804) (xy 315.388242 -277.120679)
			(xy 315.355607 -277.083842) (xy 315.329304 -277.042246) (xy 315.310013 -276.99697) (xy 315.298236 -276.949186)
			(xy 315.294276 -276.900132) (xy 314.977013 -276.900132) (xy 314.976514 -276.925586) (xy 314.968471 -276.976368)
			(xy 314.952583 -277.025267) (xy 314.92924 -277.071079) (xy 314.899019 -277.112675) (xy 314.862663 -277.149031)
			(xy 314.821067 -277.179252) (xy 314.775255 -277.202595) (xy 314.726356 -277.218483) (xy 314.675574 -277.226526)
			(xy 314.624158 -277.226526) (xy 314.573376 -277.218483) (xy 314.524477 -277.202595) (xy 314.478665 -277.179252)
			(xy 314.437069 -277.149031) (xy 314.400713 -277.112675) (xy 314.370492 -277.071079) (xy 314.347149 -277.025267)
			(xy 314.331261 -276.976368) (xy 314.323218 -276.925586) (xy 314.026554 -276.925586) (xy 314.018511 -276.976368)
			(xy 314.002623 -277.025267) (xy 313.97928 -277.071079) (xy 313.949059 -277.112675) (xy 313.912703 -277.149031)
			(xy 313.871107 -277.179252) (xy 313.825295 -277.202595) (xy 313.776396 -277.218483) (xy 313.725614 -277.226526)
			(xy 313.674198 -277.226526) (xy 313.623416 -277.218483) (xy 313.574517 -277.202595) (xy 313.528705 -277.179252)
			(xy 313.487109 -277.149031) (xy 313.450753 -277.112675) (xy 313.420532 -277.071079) (xy 313.397189 -277.025267)
			(xy 313.381301 -276.976368) (xy 313.373258 -276.925586) (xy 313.054326 -276.925586) (xy 313.04661 -276.973062)
			(xy 313.031026 -277.019743) (xy 313.008155 -277.06332) (xy 312.97859 -277.102664) (xy 312.943097 -277.136756)
			(xy 312.902594 -277.164712) (xy 312.858132 -277.18581) (xy 312.810861 -277.199502) (xy 312.762006 -277.205434)
			(xy 312.712831 -277.203453) (xy 312.664612 -277.193609) (xy 312.618596 -277.176157) (xy 312.575975 -277.15155)
			(xy 312.537854 -277.120425) (xy 312.505219 -277.083588) (xy 312.478916 -277.041992) (xy 312.459625 -276.996716)
			(xy 312.447848 -276.948932) (xy 312.443888 -276.899878) (xy 312.104786 -276.899878) (xy 312.104291 -276.924485)
			(xy 312.096396 -276.973062) (xy 312.080812 -277.019743) (xy 312.057941 -277.06332) (xy 312.028376 -277.102664)
			(xy 311.992883 -277.136756) (xy 311.95238 -277.164712) (xy 311.907918 -277.18581) (xy 311.860647 -277.199502)
			(xy 311.811792 -277.205434) (xy 311.762617 -277.203453) (xy 311.714398 -277.193609) (xy 311.668382 -277.176157)
			(xy 311.625761 -277.15155) (xy 311.58764 -277.120425) (xy 311.555005 -277.083588) (xy 311.528702 -277.041992)
			(xy 311.509411 -276.996716) (xy 311.497634 -276.948932) (xy 311.493674 -276.899878) (xy 311.154826 -276.899878)
			(xy 311.154331 -276.924485) (xy 311.146436 -276.973062) (xy 311.130852 -277.019743) (xy 311.107981 -277.06332)
			(xy 311.078416 -277.102664) (xy 311.042923 -277.136756) (xy 311.00242 -277.164712) (xy 310.957958 -277.18581)
			(xy 310.910687 -277.199502) (xy 310.861832 -277.205434) (xy 310.812657 -277.203453) (xy 310.764438 -277.193609)
			(xy 310.718422 -277.176157) (xy 310.675801 -277.15155) (xy 310.63768 -277.120425) (xy 310.605045 -277.083588)
			(xy 310.578742 -277.041992) (xy 310.559451 -276.996716) (xy 310.547674 -276.948932) (xy 310.543714 -276.899878)
			(xy 310.204866 -276.899878) (xy 310.204371 -276.924485) (xy 310.196476 -276.973062) (xy 310.180892 -277.019743)
			(xy 310.158021 -277.06332) (xy 310.128456 -277.102664) (xy 310.092963 -277.136756) (xy 310.05246 -277.164712)
			(xy 310.007998 -277.18581) (xy 309.960727 -277.199502) (xy 309.911872 -277.205434) (xy 309.862697 -277.203453)
			(xy 309.814478 -277.193609) (xy 309.768462 -277.176157) (xy 309.725841 -277.15155) (xy 309.68772 -277.120425)
			(xy 309.655085 -277.083588) (xy 309.628782 -277.041992) (xy 309.609491 -276.996716) (xy 309.597714 -276.948932)
			(xy 309.593754 -276.899878) (xy 309.254906 -276.899878) (xy 309.254411 -276.924485) (xy 309.246516 -276.973062)
			(xy 309.230932 -277.019743) (xy 309.208061 -277.06332) (xy 309.178496 -277.102664) (xy 309.143003 -277.136756)
			(xy 309.1025 -277.164712) (xy 309.058038 -277.18581) (xy 309.010767 -277.199502) (xy 308.961912 -277.205434)
			(xy 308.912737 -277.203453) (xy 308.864518 -277.193609) (xy 308.818502 -277.176157) (xy 308.775881 -277.15155)
			(xy 308.73776 -277.120425) (xy 308.705125 -277.083588) (xy 308.678822 -277.041992) (xy 308.659531 -276.996716)
			(xy 308.647754 -276.948932) (xy 308.643794 -276.899878) (xy 308.304946 -276.899878) (xy 308.304451 -276.924485)
			(xy 308.296556 -276.973062) (xy 308.280972 -277.019743) (xy 308.258101 -277.06332) (xy 308.228536 -277.102664)
			(xy 308.193043 -277.136756) (xy 308.15254 -277.164712) (xy 308.108078 -277.18581) (xy 308.060807 -277.199502)
			(xy 308.011952 -277.205434) (xy 307.962777 -277.203453) (xy 307.914558 -277.193609) (xy 307.868542 -277.176157)
			(xy 307.825921 -277.15155) (xy 307.7878 -277.120425) (xy 307.755165 -277.083588) (xy 307.728862 -277.041992)
			(xy 307.709571 -276.996716) (xy 307.697794 -276.948932) (xy 307.693834 -276.899878) (xy 307.354986 -276.899878)
			(xy 307.354491 -276.924485) (xy 307.346596 -276.973062) (xy 307.331012 -277.019743) (xy 307.308141 -277.06332)
			(xy 307.278576 -277.102664) (xy 307.243083 -277.136756) (xy 307.20258 -277.164712) (xy 307.158118 -277.18581)
			(xy 307.110847 -277.199502) (xy 307.061992 -277.205434) (xy 307.012817 -277.203453) (xy 306.964598 -277.193609)
			(xy 306.918582 -277.176157) (xy 306.875961 -277.15155) (xy 306.83784 -277.120425) (xy 306.805205 -277.083588)
			(xy 306.778902 -277.041992) (xy 306.759611 -276.996716) (xy 306.747834 -276.948932) (xy 306.743874 -276.899878)
			(xy 306.404772 -276.899878) (xy 306.404277 -276.924485) (xy 306.396382 -276.973062) (xy 306.380798 -277.019743)
			(xy 306.357927 -277.06332) (xy 306.328362 -277.102664) (xy 306.292869 -277.136756) (xy 306.252366 -277.164712)
			(xy 306.207904 -277.18581) (xy 306.160633 -277.199502) (xy 306.111778 -277.205434) (xy 306.062603 -277.203453)
			(xy 306.014384 -277.193609) (xy 305.968368 -277.176157) (xy 305.925747 -277.15155) (xy 305.887626 -277.120425)
			(xy 305.854991 -277.083588) (xy 305.828688 -277.041992) (xy 305.809397 -276.996716) (xy 305.79762 -276.948932)
			(xy 305.79366 -276.899878) (xy 305.455066 -276.899878) (xy 305.454571 -276.924485) (xy 305.446676 -276.973062)
			(xy 305.431092 -277.019743) (xy 305.408221 -277.06332) (xy 305.378656 -277.102664) (xy 305.343163 -277.136756)
			(xy 305.30266 -277.164712) (xy 305.258198 -277.18581) (xy 305.210927 -277.199502) (xy 305.162072 -277.205434)
			(xy 305.112897 -277.203453) (xy 305.064678 -277.193609) (xy 305.018662 -277.176157) (xy 304.976041 -277.15155)
			(xy 304.93792 -277.120425) (xy 304.905285 -277.083588) (xy 304.878982 -277.041992) (xy 304.859691 -276.996716)
			(xy 304.847914 -276.948932) (xy 304.843954 -276.899878) (xy 304.505106 -276.899878) (xy 304.504611 -276.924485)
			(xy 304.496716 -276.973062) (xy 304.481132 -277.019743) (xy 304.458261 -277.06332) (xy 304.428696 -277.102664)
			(xy 304.393203 -277.136756) (xy 304.3527 -277.164712) (xy 304.308238 -277.18581) (xy 304.260967 -277.199502)
			(xy 304.212112 -277.205434) (xy 304.162937 -277.203453) (xy 304.114718 -277.193609) (xy 304.068702 -277.176157)
			(xy 304.026081 -277.15155) (xy 303.98796 -277.120425) (xy 303.955325 -277.083588) (xy 303.929022 -277.041992)
			(xy 303.909731 -276.996716) (xy 303.897954 -276.948932) (xy 303.893994 -276.899878) (xy 303.555146 -276.899878)
			(xy 303.554651 -276.924485) (xy 303.546756 -276.973062) (xy 303.531172 -277.019743) (xy 303.508301 -277.06332)
			(xy 303.478736 -277.102664) (xy 303.443243 -277.136756) (xy 303.40274 -277.164712) (xy 303.358278 -277.18581)
			(xy 303.311007 -277.199502) (xy 303.262152 -277.205434) (xy 303.212977 -277.203453) (xy 303.164758 -277.193609)
			(xy 303.118742 -277.176157) (xy 303.076121 -277.15155) (xy 303.038 -277.120425) (xy 303.005365 -277.083588)
			(xy 302.979062 -277.041992) (xy 302.959771 -276.996716) (xy 302.947994 -276.948932) (xy 302.944034 -276.899878)
			(xy 302.605186 -276.899878) (xy 302.604691 -276.924485) (xy 302.596796 -276.973062) (xy 302.581212 -277.019743)
			(xy 302.558341 -277.06332) (xy 302.528776 -277.102664) (xy 302.493283 -277.136756) (xy 302.45278 -277.164712)
			(xy 302.408318 -277.18581) (xy 302.361047 -277.199502) (xy 302.312192 -277.205434) (xy 302.263017 -277.203453)
			(xy 302.214798 -277.193609) (xy 302.168782 -277.176157) (xy 302.126161 -277.15155) (xy 302.08804 -277.120425)
			(xy 302.055405 -277.083588) (xy 302.029102 -277.041992) (xy 302.009811 -276.996716) (xy 301.998034 -276.948932)
			(xy 301.994074 -276.899878) (xy 301.655226 -276.899878) (xy 301.654731 -276.924485) (xy 301.646836 -276.973062)
			(xy 301.631252 -277.019743) (xy 301.608381 -277.06332) (xy 301.578816 -277.102664) (xy 301.543323 -277.136756)
			(xy 301.50282 -277.164712) (xy 301.458358 -277.18581) (xy 301.411087 -277.199502) (xy 301.362232 -277.205434)
			(xy 301.313057 -277.203453) (xy 301.264838 -277.193609) (xy 301.218822 -277.176157) (xy 301.176201 -277.15155)
			(xy 301.13808 -277.120425) (xy 301.105445 -277.083588) (xy 301.079142 -277.041992) (xy 301.059851 -276.996716)
			(xy 301.048074 -276.948932) (xy 301.044114 -276.899878) (xy 300.705012 -276.899878) (xy 300.704517 -276.924485)
			(xy 300.696622 -276.973062) (xy 300.681038 -277.019743) (xy 300.658167 -277.06332) (xy 300.628602 -277.102664)
			(xy 300.593109 -277.136756) (xy 300.552606 -277.164712) (xy 300.508144 -277.18581) (xy 300.460873 -277.199502)
			(xy 300.412018 -277.205434) (xy 300.362843 -277.203453) (xy 300.314624 -277.193609) (xy 300.268608 -277.176157)
			(xy 300.225987 -277.15155) (xy 300.187866 -277.120425) (xy 300.155231 -277.083588) (xy 300.128928 -277.041992)
			(xy 300.109637 -276.996716) (xy 300.09786 -276.948932) (xy 300.0939 -276.899878) (xy 299.755052 -276.899878)
			(xy 299.754557 -276.924485) (xy 299.746662 -276.973062) (xy 299.731078 -277.019743) (xy 299.708207 -277.06332)
			(xy 299.678642 -277.102664) (xy 299.643149 -277.136756) (xy 299.602646 -277.164712) (xy 299.558184 -277.18581)
			(xy 299.510913 -277.199502) (xy 299.462058 -277.205434) (xy 299.412883 -277.203453) (xy 299.364664 -277.193609)
			(xy 299.318648 -277.176157) (xy 299.276027 -277.15155) (xy 299.237906 -277.120425) (xy 299.205271 -277.083588)
			(xy 299.178968 -277.041992) (xy 299.159677 -276.996716) (xy 299.1479 -276.948932) (xy 299.14394 -276.899878)
			(xy 298.805092 -276.899878) (xy 298.804597 -276.924485) (xy 298.796702 -276.973062) (xy 298.781118 -277.019743)
			(xy 298.758247 -277.06332) (xy 298.728682 -277.102664) (xy 298.693189 -277.136756) (xy 298.652686 -277.164712)
			(xy 298.608224 -277.18581) (xy 298.560953 -277.199502) (xy 298.512098 -277.205434) (xy 298.462923 -277.203453)
			(xy 298.414704 -277.193609) (xy 298.368688 -277.176157) (xy 298.326067 -277.15155) (xy 298.287946 -277.120425)
			(xy 298.255311 -277.083588) (xy 298.229008 -277.041992) (xy 298.209717 -276.996716) (xy 298.19794 -276.948932)
			(xy 298.19398 -276.899878) (xy 297.855132 -276.899878) (xy 297.854637 -276.924485) (xy 297.846742 -276.973062)
			(xy 297.831158 -277.019743) (xy 297.808287 -277.06332) (xy 297.778722 -277.102664) (xy 297.743229 -277.136756)
			(xy 297.702726 -277.164712) (xy 297.658264 -277.18581) (xy 297.610993 -277.199502) (xy 297.562138 -277.205434)
			(xy 297.512963 -277.203453) (xy 297.464744 -277.193609) (xy 297.418728 -277.176157) (xy 297.376107 -277.15155)
			(xy 297.337986 -277.120425) (xy 297.305351 -277.083588) (xy 297.279048 -277.041992) (xy 297.259757 -276.996716)
			(xy 297.24798 -276.948932) (xy 297.24402 -276.899878) (xy 296.905172 -276.899878) (xy 296.904677 -276.924485)
			(xy 296.896782 -276.973062) (xy 296.881198 -277.019743) (xy 296.858327 -277.06332) (xy 296.828762 -277.102664)
			(xy 296.793269 -277.136756) (xy 296.752766 -277.164712) (xy 296.708304 -277.18581) (xy 296.661033 -277.199502)
			(xy 296.612178 -277.205434) (xy 296.563003 -277.203453) (xy 296.514784 -277.193609) (xy 296.468768 -277.176157)
			(xy 296.426147 -277.15155) (xy 296.388026 -277.120425) (xy 296.355391 -277.083588) (xy 296.329088 -277.041992)
			(xy 296.309797 -276.996716) (xy 296.29802 -276.948932) (xy 296.29406 -276.899878) (xy 295.955212 -276.899878)
			(xy 295.954717 -276.924485) (xy 295.946822 -276.973062) (xy 295.931238 -277.019743) (xy 295.908367 -277.06332)
			(xy 295.878802 -277.102664) (xy 295.843309 -277.136756) (xy 295.802806 -277.164712) (xy 295.758344 -277.18581)
			(xy 295.711073 -277.199502) (xy 295.662218 -277.205434) (xy 295.613043 -277.203453) (xy 295.564824 -277.193609)
			(xy 295.518808 -277.176157) (xy 295.476187 -277.15155) (xy 295.438066 -277.120425) (xy 295.405431 -277.083588)
			(xy 295.379128 -277.041992) (xy 295.359837 -276.996716) (xy 295.34806 -276.948932) (xy 295.3441 -276.899878)
			(xy 295.004998 -276.899878) (xy 295.004503 -276.924485) (xy 294.996608 -276.973062) (xy 294.981024 -277.019743)
			(xy 294.958153 -277.06332) (xy 294.928588 -277.102664) (xy 294.893095 -277.136756) (xy 294.852592 -277.164712)
			(xy 294.80813 -277.18581) (xy 294.760859 -277.199502) (xy 294.712004 -277.205434) (xy 294.662829 -277.203453)
			(xy 294.61461 -277.193609) (xy 294.568594 -277.176157) (xy 294.525973 -277.15155) (xy 294.487852 -277.120425)
			(xy 294.455217 -277.083588) (xy 294.428914 -277.041992) (xy 294.409623 -276.996716) (xy 294.397846 -276.948932)
			(xy 294.393886 -276.899878) (xy 294.055038 -276.899878) (xy 294.054543 -276.924485) (xy 294.046648 -276.973062)
			(xy 294.031064 -277.019743) (xy 294.008193 -277.06332) (xy 293.978628 -277.102664) (xy 293.943135 -277.136756)
			(xy 293.902632 -277.164712) (xy 293.85817 -277.18581) (xy 293.810899 -277.199502) (xy 293.762044 -277.205434)
			(xy 293.712869 -277.203453) (xy 293.66465 -277.193609) (xy 293.618634 -277.176157) (xy 293.576013 -277.15155)
			(xy 293.537892 -277.120425) (xy 293.505257 -277.083588) (xy 293.478954 -277.041992) (xy 293.459663 -276.996716)
			(xy 293.447886 -276.948932) (xy 293.443926 -276.899878) (xy 293.105078 -276.899878) (xy 293.104583 -276.924485)
			(xy 293.096688 -276.973062) (xy 293.081104 -277.019743) (xy 293.058233 -277.06332) (xy 293.028668 -277.102664)
			(xy 292.993175 -277.136756) (xy 292.952672 -277.164712) (xy 292.90821 -277.18581) (xy 292.860939 -277.199502)
			(xy 292.812084 -277.205434) (xy 292.762909 -277.203453) (xy 292.71469 -277.193609) (xy 292.668674 -277.176157)
			(xy 292.626053 -277.15155) (xy 292.587932 -277.120425) (xy 292.555297 -277.083588) (xy 292.528994 -277.041992)
			(xy 292.509703 -276.996716) (xy 292.497926 -276.948932) (xy 292.493966 -276.899878) (xy 292.155118 -276.899878)
			(xy 292.154623 -276.924485) (xy 292.146728 -276.973062) (xy 292.131144 -277.019743) (xy 292.108273 -277.06332)
			(xy 292.078708 -277.102664) (xy 292.043215 -277.136756) (xy 292.002712 -277.164712) (xy 291.95825 -277.18581)
			(xy 291.910979 -277.199502) (xy 291.862124 -277.205434) (xy 291.812949 -277.203453) (xy 291.76473 -277.193609)
			(xy 291.718714 -277.176157) (xy 291.676093 -277.15155) (xy 291.637972 -277.120425) (xy 291.605337 -277.083588)
			(xy 291.579034 -277.041992) (xy 291.559743 -276.996716) (xy 291.547966 -276.948932) (xy 291.544006 -276.899878)
			(xy 291.205158 -276.899878) (xy 291.204663 -276.924485) (xy 291.196768 -276.973062) (xy 291.181184 -277.019743)
			(xy 291.158313 -277.06332) (xy 291.128748 -277.102664) (xy 291.093255 -277.136756) (xy 291.052752 -277.164712)
			(xy 291.00829 -277.18581) (xy 290.961019 -277.199502) (xy 290.912164 -277.205434) (xy 290.862989 -277.203453)
			(xy 290.81477 -277.193609) (xy 290.768754 -277.176157) (xy 290.726133 -277.15155) (xy 290.688012 -277.120425)
			(xy 290.655377 -277.083588) (xy 290.629074 -277.041992) (xy 290.609783 -276.996716) (xy 290.598006 -276.948932)
			(xy 290.594046 -276.899878) (xy 290.255198 -276.899878) (xy 290.254703 -276.924485) (xy 290.246808 -276.973062)
			(xy 290.231224 -277.019743) (xy 290.208353 -277.06332) (xy 290.178788 -277.102664) (xy 290.143295 -277.136756)
			(xy 290.102792 -277.164712) (xy 290.05833 -277.18581) (xy 290.011059 -277.199502) (xy 289.962204 -277.205434)
			(xy 289.913029 -277.203453) (xy 289.86481 -277.193609) (xy 289.818794 -277.176157) (xy 289.776173 -277.15155)
			(xy 289.738052 -277.120425) (xy 289.705417 -277.083588) (xy 289.679114 -277.041992) (xy 289.659823 -276.996716)
			(xy 289.648046 -276.948932) (xy 289.644086 -276.899878) (xy 289.305238 -276.899878) (xy 289.304743 -276.924485)
			(xy 289.296848 -276.973062) (xy 289.281264 -277.019743) (xy 289.258393 -277.06332) (xy 289.228828 -277.102664)
			(xy 289.193335 -277.136756) (xy 289.152832 -277.164712) (xy 289.10837 -277.18581) (xy 289.061099 -277.199502)
			(xy 289.012244 -277.205434) (xy 288.963069 -277.203453) (xy 288.91485 -277.193609) (xy 288.868834 -277.176157)
			(xy 288.826213 -277.15155) (xy 288.788092 -277.120425) (xy 288.755457 -277.083588) (xy 288.729154 -277.041992)
			(xy 288.709863 -276.996716) (xy 288.698086 -276.948932) (xy 288.694126 -276.899878) (xy 288.355024 -276.899878)
			(xy 288.354529 -276.924485) (xy 288.346634 -276.973062) (xy 288.33105 -277.019743) (xy 288.308179 -277.06332)
			(xy 288.278614 -277.102664) (xy 288.243121 -277.136756) (xy 288.202618 -277.164712) (xy 288.158156 -277.18581)
			(xy 288.110885 -277.199502) (xy 288.06203 -277.205434) (xy 288.012855 -277.203453) (xy 287.964636 -277.193609)
			(xy 287.91862 -277.176157) (xy 287.875999 -277.15155) (xy 287.837878 -277.120425) (xy 287.805243 -277.083588)
			(xy 287.77894 -277.041992) (xy 287.759649 -276.996716) (xy 287.747872 -276.948932) (xy 287.743912 -276.899878)
			(xy 287.405064 -276.899878) (xy 287.404569 -276.924485) (xy 287.396674 -276.973062) (xy 287.38109 -277.019743)
			(xy 287.358219 -277.06332) (xy 287.328654 -277.102664) (xy 287.293161 -277.136756) (xy 287.252658 -277.164712)
			(xy 287.208196 -277.18581) (xy 287.160925 -277.199502) (xy 287.11207 -277.205434) (xy 287.062895 -277.203453)
			(xy 287.014676 -277.193609) (xy 286.96866 -277.176157) (xy 286.926039 -277.15155) (xy 286.887918 -277.120425)
			(xy 286.855283 -277.083588) (xy 286.82898 -277.041992) (xy 286.809689 -276.996716) (xy 286.797912 -276.948932)
			(xy 286.793952 -276.899878) (xy 286.455104 -276.899878) (xy 286.454609 -276.924485) (xy 286.446714 -276.973062)
			(xy 286.43113 -277.019743) (xy 286.408259 -277.06332) (xy 286.378694 -277.102664) (xy 286.343201 -277.136756)
			(xy 286.302698 -277.164712) (xy 286.258236 -277.18581) (xy 286.210965 -277.199502) (xy 286.16211 -277.205434)
			(xy 286.112935 -277.203453) (xy 286.064716 -277.193609) (xy 286.0187 -277.176157) (xy 285.976079 -277.15155)
			(xy 285.937958 -277.120425) (xy 285.905323 -277.083588) (xy 285.87902 -277.041992) (xy 285.859729 -276.996716)
			(xy 285.847952 -276.948932) (xy 285.843992 -276.899878) (xy 285.505144 -276.899878) (xy 285.504649 -276.924485)
			(xy 285.496754 -276.973062) (xy 285.48117 -277.019743) (xy 285.458299 -277.06332) (xy 285.428734 -277.102664)
			(xy 285.393241 -277.136756) (xy 285.352738 -277.164712) (xy 285.308276 -277.18581) (xy 285.261005 -277.199502)
			(xy 285.21215 -277.205434) (xy 285.162975 -277.203453) (xy 285.114756 -277.193609) (xy 285.06874 -277.176157)
			(xy 285.026119 -277.15155) (xy 284.987998 -277.120425) (xy 284.955363 -277.083588) (xy 284.92906 -277.041992)
			(xy 284.909769 -276.996716) (xy 284.897992 -276.948932) (xy 284.894032 -276.899878) (xy 284.555184 -276.899878)
			(xy 284.554689 -276.924485) (xy 284.546794 -276.973062) (xy 284.53121 -277.019743) (xy 284.508339 -277.06332)
			(xy 284.478774 -277.102664) (xy 284.443281 -277.136756) (xy 284.402778 -277.164712) (xy 284.358316 -277.18581)
			(xy 284.311045 -277.199502) (xy 284.26219 -277.205434) (xy 284.213015 -277.203453) (xy 284.164796 -277.193609)
			(xy 284.11878 -277.176157) (xy 284.076159 -277.15155) (xy 284.038038 -277.120425) (xy 284.005403 -277.083588)
			(xy 283.9791 -277.041992) (xy 283.959809 -276.996716) (xy 283.948032 -276.948932) (xy 283.944072 -276.899878)
			(xy 283.605224 -276.899878) (xy 283.604729 -276.924485) (xy 283.596834 -276.973062) (xy 283.58125 -277.019743)
			(xy 283.558379 -277.06332) (xy 283.528814 -277.102664) (xy 283.493321 -277.136756) (xy 283.452818 -277.164712)
			(xy 283.408356 -277.18581) (xy 283.361085 -277.199502) (xy 283.31223 -277.205434) (xy 283.263055 -277.203453)
			(xy 283.214836 -277.193609) (xy 283.16882 -277.176157) (xy 283.126199 -277.15155) (xy 283.088078 -277.120425)
			(xy 283.055443 -277.083588) (xy 283.02914 -277.041992) (xy 283.009849 -276.996716) (xy 282.998072 -276.948932)
			(xy 282.994112 -276.899878) (xy 282.65501 -276.899878) (xy 282.654515 -276.924485) (xy 282.64662 -276.973062)
			(xy 282.631036 -277.019743) (xy 282.608165 -277.06332) (xy 282.5786 -277.102664) (xy 282.543107 -277.136756)
			(xy 282.502604 -277.164712) (xy 282.458142 -277.18581) (xy 282.410871 -277.199502) (xy 282.362016 -277.205434)
			(xy 282.312841 -277.203453) (xy 282.264622 -277.193609) (xy 282.218606 -277.176157) (xy 282.175985 -277.15155)
			(xy 282.137864 -277.120425) (xy 282.105229 -277.083588) (xy 282.078926 -277.041992) (xy 282.059635 -276.996716)
			(xy 282.047858 -276.948932) (xy 282.043898 -276.899878) (xy 281.70505 -276.899878) (xy 281.704555 -276.924485)
			(xy 281.69666 -276.973062) (xy 281.681076 -277.019743) (xy 281.658205 -277.06332) (xy 281.62864 -277.102664)
			(xy 281.593147 -277.136756) (xy 281.552644 -277.164712) (xy 281.508182 -277.18581) (xy 281.460911 -277.199502)
			(xy 281.412056 -277.205434) (xy 281.362881 -277.203453) (xy 281.314662 -277.193609) (xy 281.268646 -277.176157)
			(xy 281.226025 -277.15155) (xy 281.187904 -277.120425) (xy 281.155269 -277.083588) (xy 281.128966 -277.041992)
			(xy 281.109675 -276.996716) (xy 281.097898 -276.948932) (xy 281.093938 -276.899878) (xy 280.75509 -276.899878)
			(xy 280.754595 -276.924485) (xy 280.7467 -276.973062) (xy 280.731116 -277.019743) (xy 280.708245 -277.06332)
			(xy 280.67868 -277.102664) (xy 280.643187 -277.136756) (xy 280.602684 -277.164712) (xy 280.558222 -277.18581)
			(xy 280.510951 -277.199502) (xy 280.462096 -277.205434) (xy 280.412921 -277.203453) (xy 280.364702 -277.193609)
			(xy 280.318686 -277.176157) (xy 280.276065 -277.15155) (xy 280.237944 -277.120425) (xy 280.205309 -277.083588)
			(xy 280.179006 -277.041992) (xy 280.159715 -276.996716) (xy 280.147938 -276.948932) (xy 280.143978 -276.899878)
			(xy 279.80513 -276.899878) (xy 279.804635 -276.924485) (xy 279.79674 -276.973062) (xy 279.781156 -277.019743)
			(xy 279.758285 -277.06332) (xy 279.72872 -277.102664) (xy 279.693227 -277.136756) (xy 279.652724 -277.164712)
			(xy 279.608262 -277.18581) (xy 279.560991 -277.199502) (xy 279.512136 -277.205434) (xy 279.462961 -277.203453)
			(xy 279.414742 -277.193609) (xy 279.368726 -277.176157) (xy 279.326105 -277.15155) (xy 279.287984 -277.120425)
			(xy 279.255349 -277.083588) (xy 279.229046 -277.041992) (xy 279.209755 -276.996716) (xy 279.197978 -276.948932)
			(xy 279.194018 -276.899878) (xy 278.85517 -276.899878) (xy 278.854675 -276.924485) (xy 278.84678 -276.973062)
			(xy 278.831196 -277.019743) (xy 278.808325 -277.06332) (xy 278.77876 -277.102664) (xy 278.743267 -277.136756)
			(xy 278.702764 -277.164712) (xy 278.658302 -277.18581) (xy 278.611031 -277.199502) (xy 278.562176 -277.205434)
			(xy 278.513001 -277.203453) (xy 278.464782 -277.193609) (xy 278.418766 -277.176157) (xy 278.376145 -277.15155)
			(xy 278.338024 -277.120425) (xy 278.305389 -277.083588) (xy 278.279086 -277.041992) (xy 278.259795 -276.996716)
			(xy 278.248018 -276.948932) (xy 278.244058 -276.899878) (xy 277.90521 -276.899878) (xy 277.904715 -276.924485)
			(xy 277.89682 -276.973062) (xy 277.881236 -277.019743) (xy 277.858365 -277.06332) (xy 277.8288 -277.102664)
			(xy 277.793307 -277.136756) (xy 277.752804 -277.164712) (xy 277.708342 -277.18581) (xy 277.661071 -277.199502)
			(xy 277.612216 -277.205434) (xy 277.563041 -277.203453) (xy 277.514822 -277.193609) (xy 277.468806 -277.176157)
			(xy 277.426185 -277.15155) (xy 277.388064 -277.120425) (xy 277.355429 -277.083588) (xy 277.329126 -277.041992)
			(xy 277.309835 -276.996716) (xy 277.298058 -276.948932) (xy 277.294098 -276.899878) (xy 276.954996 -276.899878)
			(xy 276.954501 -276.924485) (xy 276.946606 -276.973062) (xy 276.931022 -277.019743) (xy 276.908151 -277.06332)
			(xy 276.878586 -277.102664) (xy 276.843093 -277.136756) (xy 276.80259 -277.164712) (xy 276.758128 -277.18581)
			(xy 276.710857 -277.199502) (xy 276.662002 -277.205434) (xy 276.612827 -277.203453) (xy 276.564608 -277.193609)
			(xy 276.518592 -277.176157) (xy 276.475971 -277.15155) (xy 276.43785 -277.120425) (xy 276.405215 -277.083588)
			(xy 276.378912 -277.041992) (xy 276.359621 -276.996716) (xy 276.347844 -276.948932) (xy 276.343884 -276.899878)
			(xy 249.129907 -276.899878) (xy 249.118356 -276.901149) (xy 249.062622 -276.899112) (xy 249.007779 -276.888982)
			(xy 248.954995 -276.870975) (xy 248.905395 -276.845474) (xy 248.860037 -276.813023) (xy 248.819888 -276.774314)
			(xy 248.785802 -276.730171) (xy 248.758506 -276.681536) (xy 248.738583 -276.629445) (xy 248.726457 -276.575008)
			(xy 248.722386 -276.519386) (xy 247.466612 -276.519386) (xy 247.466103 -276.547272) (xy 247.457983 -276.602448)
			(xy 247.441915 -276.655855) (xy 247.418243 -276.706352) (xy 247.38747 -276.752865) (xy 247.350253 -276.794402)
			(xy 247.307385 -276.830077) (xy 247.259779 -276.859131) (xy 247.20845 -276.880943) (xy 247.154493 -276.895049)
			(xy 247.099056 -276.901149) (xy 247.043322 -276.899112) (xy 246.988479 -276.888982) (xy 246.935695 -276.870975)
			(xy 246.886095 -276.845474) (xy 246.840737 -276.813023) (xy 246.800588 -276.774314) (xy 246.766502 -276.730171)
			(xy 246.739206 -276.681536) (xy 246.719283 -276.629445) (xy 246.707157 -276.575008) (xy 246.703086 -276.519386)
			(xy 242.117401 -276.519386) (xy 242.100245 -276.555984) (xy 242.069472 -276.602497) (xy 242.032255 -276.644034)
			(xy 241.989387 -276.679709) (xy 241.941781 -276.708763) (xy 241.890452 -276.730575) (xy 241.836495 -276.744681)
			(xy 241.781058 -276.750781) (xy 241.725324 -276.748744) (xy 241.670481 -276.738614) (xy 241.617697 -276.720607)
			(xy 241.568097 -276.695106) (xy 241.522739 -276.662655) (xy 241.48259 -276.623946) (xy 241.448504 -276.579803)
			(xy 241.421208 -276.531168) (xy 241.401285 -276.479077) (xy 241.389159 -276.42464) (xy 241.385088 -276.369018)
			(xy 238.930183 -276.369018) (xy 238.949977 -276.399818) (xy 238.972619 -276.449394) (xy 238.987975 -276.501688)
			(xy 238.995733 -276.555635) (xy 238.99622 -276.582886) (xy 238.995765 -276.610257) (xy 238.987948 -276.664437)
			(xy 238.972457 -276.716941) (xy 238.949612 -276.766688) (xy 238.919884 -276.812654) (xy 238.90224 -276.833584)
			(xy 238.896144 -276.840696) (xy 238.889794 -276.857714) (xy 238.889794 -276.943058) (xy 238.896144 -276.960076)
			(xy 238.90224 -276.967188) (xy 238.919894 -276.988108) (xy 238.949602 -277.034085) (xy 238.972435 -277.083836)
			(xy 238.987922 -277.136339) (xy 238.995748 -277.190516) (xy 238.996141 -277.213314) (xy 243.720364 -277.213314)
			(xy 243.724435 -277.157692) (xy 243.736561 -277.103255) (xy 243.756484 -277.051164) (xy 243.78378 -277.002529)
			(xy 243.817866 -276.958386) (xy 243.858015 -276.919677) (xy 243.903373 -276.887226) (xy 243.952973 -276.861725)
			(xy 244.005757 -276.843718) (xy 244.0606 -276.833588) (xy 244.116334 -276.831551) (xy 244.171771 -276.837651)
			(xy 244.225728 -276.851757) (xy 244.277057 -276.873569) (xy 244.324663 -276.902623) (xy 244.367531 -276.938298)
			(xy 244.404748 -276.979835) (xy 244.435521 -277.026348) (xy 244.459193 -277.076845) (xy 244.475261 -277.130252)
			(xy 244.483381 -277.185428) (xy 244.483681 -277.201884) (xy 244.909846 -277.201884) (xy 244.913917 -277.146262)
			(xy 244.926043 -277.091825) (xy 244.945966 -277.039734) (xy 244.973262 -276.991099) (xy 245.007348 -276.946956)
			(xy 245.047497 -276.908247) (xy 245.092855 -276.875796) (xy 245.142455 -276.850295) (xy 245.195239 -276.832288)
			(xy 245.250082 -276.822158) (xy 245.305816 -276.820121) (xy 245.361253 -276.826221) (xy 245.41521 -276.840327)
			(xy 245.466539 -276.862139) (xy 245.514145 -276.891193) (xy 245.557013 -276.926868) (xy 245.59423 -276.968405)
			(xy 245.625003 -277.014918) (xy 245.648675 -277.065415) (xy 245.664743 -277.118822) (xy 245.672863 -277.173998)
			(xy 245.673372 -277.201884) (xy 245.672863 -277.22977) (xy 245.664743 -277.284946) (xy 245.648675 -277.338353)
			(xy 245.625003 -277.38885) (xy 245.59423 -277.435363) (xy 245.557013 -277.4769) (xy 245.514145 -277.512575)
			(xy 245.466539 -277.541629) (xy 245.41521 -277.563441) (xy 245.361253 -277.577547) (xy 245.305816 -277.583647)
			(xy 245.250082 -277.58161) (xy 245.195239 -277.57148) (xy 245.142455 -277.553473) (xy 245.092855 -277.527972)
			(xy 245.047497 -277.495521) (xy 245.007348 -277.456812) (xy 244.973262 -277.412669) (xy 244.945966 -277.364034)
			(xy 244.926043 -277.311943) (xy 244.913917 -277.257506) (xy 244.909846 -277.201884) (xy 244.483681 -277.201884)
			(xy 244.48389 -277.213314) (xy 244.483381 -277.2412) (xy 244.475261 -277.296376) (xy 244.459193 -277.349783)
			(xy 244.435521 -277.40028) (xy 244.404748 -277.446793) (xy 244.367531 -277.48833) (xy 244.324663 -277.524005)
			(xy 244.277057 -277.553059) (xy 244.225728 -277.574871) (xy 244.171771 -277.588977) (xy 244.116334 -277.595077)
			(xy 244.0606 -277.59304) (xy 244.005757 -277.58291) (xy 243.952973 -277.564903) (xy 243.903373 -277.539402)
			(xy 243.858015 -277.506951) (xy 243.817866 -277.468242) (xy 243.78378 -277.424099) (xy 243.756484 -277.375464)
			(xy 243.736561 -277.323373) (xy 243.724435 -277.268936) (xy 243.720364 -277.213314) (xy 238.996141 -277.213314)
			(xy 238.99622 -277.217886) (xy 238.995732 -277.245138) (xy 238.987977 -277.299087) (xy 238.972623 -277.351384)
			(xy 238.949983 -277.400963) (xy 238.920518 -277.446816) (xy 238.884827 -277.488008) (xy 238.843637 -277.523702)
			(xy 238.797786 -277.553171) (xy 238.748208 -277.575814) (xy 238.695913 -277.591171) (xy 238.641964 -277.59893)
			(xy 238.614712 -277.599394) (xy 238.585973 -277.598865) (xy 238.529146 -277.590244) (xy 238.474255 -277.573195)
			(xy 238.422543 -277.548105) (xy 238.375181 -277.51554) (xy 238.353854 -277.49627) (xy 238.346742 -277.489666)
			(xy 238.329216 -277.482554) (xy 238.239808 -277.482554) (xy 238.222282 -277.489666) (xy 238.21517 -277.49627)
			(xy 238.193843 -277.51554) (xy 238.14648 -277.548105) (xy 238.094769 -277.573196) (xy 238.039878 -277.590246)
			(xy 237.983051 -277.598868) (xy 237.925573 -277.598868) (xy 237.868746 -277.590246) (xy 237.813855 -277.573196)
			(xy 237.762144 -277.548105) (xy 237.714781 -277.51554) (xy 237.693454 -277.49627) (xy 237.686342 -277.489666)
			(xy 237.668816 -277.482554) (xy 237.579408 -277.482554) (xy 237.561882 -277.489666) (xy 237.55477 -277.49627)
			(xy 237.533443 -277.51554) (xy 237.48608 -277.548105) (xy 237.434369 -277.573196) (xy 237.379478 -277.590246)
			(xy 237.322651 -277.598868) (xy 237.265173 -277.598868) (xy 237.208346 -277.590246) (xy 237.153455 -277.573196)
			(xy 237.101744 -277.548105) (xy 237.054381 -277.51554) (xy 237.033054 -277.49627) (xy 237.025942 -277.489666)
			(xy 237.008416 -277.482554) (xy 236.919008 -277.482554) (xy 236.901482 -277.489666) (xy 236.89437 -277.49627)
			(xy 236.873039 -277.515536) (xy 236.825678 -277.548103) (xy 236.773967 -277.573196) (xy 236.719077 -277.590248)
			(xy 236.662251 -277.598872) (xy 236.633512 -277.599394) (xy 236.606259 -277.598933) (xy 236.552307 -277.591178)
			(xy 236.500008 -277.575823) (xy 236.450427 -277.55318) (xy 236.404573 -277.523712) (xy 236.36338 -277.488018)
			(xy 236.327686 -277.446825) (xy 236.298219 -277.400971) (xy 236.275577 -277.35139) (xy 236.260222 -277.299091)
			(xy 236.252466 -277.245139) (xy 236.252004 -277.217886) (xy 233.063289 -277.217886) (xy 233.076527 -277.225965)
			(xy 233.119395 -277.26164) (xy 233.156612 -277.303177) (xy 233.187385 -277.34969) (xy 233.211057 -277.400187)
			(xy 233.227125 -277.453594) (xy 233.235245 -277.50877) (xy 233.235754 -277.536656) (xy 233.235245 -277.564542)
			(xy 233.227125 -277.619718) (xy 233.211057 -277.673125) (xy 233.187385 -277.723622) (xy 233.156612 -277.770135)
			(xy 233.119395 -277.811672) (xy 233.076527 -277.847347) (xy 233.028921 -277.876401) (xy 232.977592 -277.898213)
			(xy 232.923635 -277.912319) (xy 232.868198 -277.918419) (xy 232.812464 -277.916382) (xy 232.757621 -277.906252)
			(xy 232.704837 -277.888245) (xy 232.655237 -277.862744) (xy 232.609879 -277.830293) (xy 232.56973 -277.791584)
			(xy 232.535644 -277.747441) (xy 232.508348 -277.698806) (xy 232.488425 -277.646715) (xy 232.476299 -277.592278)
			(xy 232.472228 -277.536656) (xy 231.120119 -277.536656) (xy 231.140749 -277.560465) (xy 231.170215 -277.606315)
			(xy 231.192857 -277.655892) (xy 231.208212 -277.708187) (xy 231.215968 -277.762135) (xy 231.216454 -277.789386)
			(xy 231.215994 -277.81598) (xy 231.208609 -277.868654) (xy 231.193979 -277.919791) (xy 231.172388 -277.968401)
			(xy 231.144255 -278.01354) (xy 231.127554 -278.034242) (xy 231.12095 -278.042116) (xy 231.115108 -278.061166)
			(xy 231.123744 -278.153622) (xy 231.133142 -278.171402) (xy 231.141016 -278.177752) (xy 231.16432 -278.197465)
			(xy 231.198294 -278.233378) (xy 242.19611 -278.233378) (xy 242.200181 -278.177756) (xy 242.212307 -278.123319)
			(xy 242.23223 -278.071228) (xy 242.259526 -278.022593) (xy 242.293612 -277.97845) (xy 242.333761 -277.939741)
			(xy 242.379119 -277.90729) (xy 242.428719 -277.881789) (xy 242.481503 -277.863782) (xy 242.536346 -277.853652)
			(xy 242.59208 -277.851615) (xy 242.647517 -277.857715) (xy 242.701474 -277.871821) (xy 242.752803 -277.893633)
			(xy 242.800409 -277.922687) (xy 242.843277 -277.958362) (xy 242.880494 -277.999899) (xy 242.911267 -278.046412)
			(xy 242.934939 -278.096909) (xy 242.951007 -278.150316) (xy 242.959127 -278.205492) (xy 242.959636 -278.233378)
			(xy 242.959127 -278.261264) (xy 242.951007 -278.31644) (xy 242.934939 -278.369847) (xy 242.911267 -278.420344)
			(xy 242.880494 -278.466857) (xy 242.843277 -278.508394) (xy 242.800409 -278.544069) (xy 242.752803 -278.573123)
			(xy 242.701474 -278.594935) (xy 242.647517 -278.609041) (xy 242.59208 -278.615141) (xy 242.536346 -278.613104)
			(xy 242.481503 -278.602974) (xy 242.428719 -278.584967) (xy 242.379119 -278.559466) (xy 242.333761 -278.527015)
			(xy 242.293612 -278.488306) (xy 242.259526 -278.444163) (xy 242.23223 -278.395528) (xy 242.212307 -278.343437)
			(xy 242.200181 -278.289) (xy 242.19611 -278.233378) (xy 231.198294 -278.233378) (xy 231.206267 -278.241806)
			(xy 231.242294 -278.291078) (xy 231.271828 -278.344496) (xy 231.294397 -278.401209) (xy 231.309642 -278.460313)
			(xy 231.31732 -278.520867) (xy 231.3178 -278.551386) (xy 231.317298 -278.583008) (xy 231.309076 -278.645716)
			(xy 231.292745 -278.706816) (xy 231.268584 -278.765263) (xy 231.237005 -278.820059) (xy 231.198548 -278.870268)
			(xy 231.176576 -278.893016) (xy 230.996744 -279.072594) (xy 230.988747 -279.081403) (xy 230.981181 -279.103928)
			(xy 230.982266 -279.115774) (xy 230.995474 -279.20823) (xy 231.008682 -279.227534) (xy 231.01935 -279.233376)
			(xy 231.044538 -279.247907) (xy 231.090589 -279.283411) (xy 231.130716 -279.325494) (xy 231.163992 -279.373179)
			(xy 231.189644 -279.425363) (xy 231.207078 -279.480836) (xy 231.215891 -279.538312) (xy 231.216454 -279.567386)
			(xy 231.215969 -279.594639) (xy 231.208215 -279.648591) (xy 231.192861 -279.70089) (xy 231.170221 -279.750472)
			(xy 231.140756 -279.796327) (xy 231.105065 -279.837523) (xy 231.063875 -279.87322) (xy 231.018024 -279.902693)
			(xy 230.968446 -279.92534) (xy 230.91615 -279.940702) (xy 230.862199 -279.948465) (xy 230.834946 -279.948894)
			(xy 230.806708 -279.94838) (xy 230.750849 -279.940048) (xy 230.696828 -279.923574) (xy 230.645825 -279.899317)
			(xy 230.598955 -279.867809) (xy 230.557241 -279.829736) (xy 230.521594 -279.78593) (xy 230.492793 -279.737349)
			(xy 230.481632 -279.711404) (xy 230.477822 -279.702006) (xy 230.46436 -279.688036) (xy 230.381048 -279.65146)
			(xy 230.361744 -279.650952) (xy 230.352346 -279.654508) (xy 230.325469 -279.663988) (xy 230.270053 -279.677312)
			(xy 230.213457 -279.684042) (xy 230.18496 -279.68448) (xy 227.906072 -279.68448) (xy 227.896106 -279.684959)
			(xy 227.87767 -279.692534) (xy 227.870258 -279.699212) (xy 227.068962 -280.500582) (xy 228.815644 -280.500582)
			(xy 228.819715 -280.44496) (xy 228.831841 -280.390523) (xy 228.851764 -280.338432) (xy 228.87906 -280.289797)
			(xy 228.913146 -280.245654) (xy 228.953295 -280.206945) (xy 228.998653 -280.174494) (xy 229.048253 -280.148993)
			(xy 229.101037 -280.130986) (xy 229.15588 -280.120856) (xy 229.211614 -280.118819) (xy 229.267051 -280.124919)
			(xy 229.321008 -280.139025) (xy 229.372337 -280.160837) (xy 229.419943 -280.189891) (xy 229.462811 -280.225566)
			(xy 229.500028 -280.267103) (xy 229.530801 -280.313616) (xy 229.554473 -280.364113) (xy 229.570541 -280.41752)
			(xy 229.578661 -280.472696) (xy 229.57917 -280.500582) (xy 229.578661 -280.528468) (xy 229.570579 -280.583386)
			(xy 232.472738 -280.583386) (xy 232.473168 -280.557487) (xy 232.480174 -280.506166) (xy 232.494054 -280.456263)
			(xy 232.514554 -280.408695) (xy 232.541298 -280.364335) (xy 232.573793 -280.323999) (xy 232.611444 -280.288427)
			(xy 232.63225 -280.272998) (xy 232.640886 -280.266902) (xy 232.651808 -280.248868) (xy 232.664254 -280.154126)
			(xy 232.658412 -280.13406) (xy 232.651554 -280.125932) (xy 232.635122 -280.105354) (xy 232.607523 -280.060505)
			(xy 232.586365 -280.012282) (xy 232.572049 -279.961605) (xy 232.56485 -279.909439) (xy 232.564432 -279.883108)
			(xy 232.564863 -279.856895) (xy 232.572035 -279.804963) (xy 232.586246 -279.754501) (xy 232.607228 -279.706458)
			(xy 232.634586 -279.661737) (xy 232.667806 -279.621181) (xy 232.706263 -279.585552) (xy 232.7275 -279.57018)
			(xy 232.738676 -279.56256) (xy 232.750106 -279.538684) (xy 232.741978 -279.424384) (xy 232.727246 -279.402286)
			(xy 232.715054 -279.39619) (xy 232.691687 -279.383966) (xy 232.64826 -279.354051) (xy 232.609369 -279.318436)
			(xy 232.575758 -279.277802) (xy 232.548067 -279.232923) (xy 232.526826 -279.184655) (xy 232.51244 -279.133922)
			(xy 232.505183 -279.081689) (xy 232.504742 -279.055322) (xy 232.505228 -279.028071) (xy 232.512984 -278.974123)
			(xy 232.528339 -278.921828) (xy 232.550981 -278.872251) (xy 232.580447 -278.826401) (xy 232.616138 -278.78521)
			(xy 232.657329 -278.749519) (xy 232.703179 -278.720053) (xy 232.752756 -278.697411) (xy 232.805051 -278.682056)
			(xy 232.858999 -278.6743) (xy 232.913501 -278.6743) (xy 232.967449 -278.682056) (xy 233.019744 -278.697411)
			(xy 233.069321 -278.720053) (xy 233.115171 -278.749519) (xy 233.156362 -278.78521) (xy 233.192053 -278.826401)
			(xy 233.221519 -278.872251) (xy 233.244161 -278.921828) (xy 233.259516 -278.974123) (xy 233.267272 -279.028071)
			(xy 233.267758 -279.055322) (xy 233.267382 -279.075896) (xy 240.6302 -279.075896) (xy 240.634271 -279.020274)
			(xy 240.646397 -278.965837) (xy 240.66632 -278.913746) (xy 240.693616 -278.865111) (xy 240.727702 -278.820968)
			(xy 240.767851 -278.782259) (xy 240.813209 -278.749808) (xy 240.862809 -278.724307) (xy 240.915593 -278.7063)
			(xy 240.970436 -278.69617) (xy 241.02617 -278.694133) (xy 241.081607 -278.700233) (xy 241.135564 -278.714339)
			(xy 241.186893 -278.736151) (xy 241.234499 -278.765205) (xy 241.277367 -278.80088) (xy 241.314584 -278.842417)
			(xy 241.345357 -278.88893) (xy 241.369029 -278.939427) (xy 241.385097 -278.992834) (xy 241.393217 -279.04801)
			(xy 241.393726 -279.075896) (xy 241.393217 -279.103782) (xy 241.385097 -279.158958) (xy 241.369029 -279.212365)
			(xy 241.345357 -279.262862) (xy 241.314584 -279.309375) (xy 241.277367 -279.350912) (xy 241.234499 -279.386587)
			(xy 241.186893 -279.415641) (xy 241.135564 -279.437453) (xy 241.081607 -279.451559) (xy 241.02617 -279.457659)
			(xy 240.970436 -279.455622) (xy 240.915593 -279.445492) (xy 240.862809 -279.427485) (xy 240.813209 -279.401984)
			(xy 240.767851 -279.369533) (xy 240.727702 -279.330824) (xy 240.693616 -279.286681) (xy 240.66632 -279.238046)
			(xy 240.646397 -279.185955) (xy 240.634271 -279.131518) (xy 240.6302 -279.075896) (xy 233.267382 -279.075896)
			(xy 233.267279 -279.081533) (xy 233.260116 -279.133463) (xy 233.245914 -279.183925) (xy 233.22494 -279.231968)
			(xy 233.197589 -279.276689) (xy 233.164375 -279.317247) (xy 233.125924 -279.352877) (xy 233.10469 -279.36825)
			(xy 233.093514 -279.37587) (xy 233.082084 -279.399746) (xy 233.090212 -279.514046) (xy 233.104944 -279.536144)
			(xy 233.117136 -279.54224) (xy 233.140513 -279.554446) (xy 233.183941 -279.584363) (xy 233.222833 -279.61998)
			(xy 233.256443 -279.660617) (xy 233.284133 -279.705499) (xy 233.305372 -279.753769) (xy 233.319756 -279.804505)
			(xy 233.327009 -279.85674) (xy 233.327448 -279.883108) (xy 233.327019 -279.909007) (xy 233.320014 -279.960329)
			(xy 233.306134 -280.010232) (xy 233.285634 -280.0578) (xy 233.259565 -280.10104) (xy 240.634264 -280.10104)
			(xy 240.638335 -280.045418) (xy 240.650461 -279.990981) (xy 240.670384 -279.93889) (xy 240.69768 -279.890255)
			(xy 240.731766 -279.846112) (xy 240.771915 -279.807403) (xy 240.817273 -279.774952) (xy 240.866873 -279.749451)
			(xy 240.919657 -279.731444) (xy 240.9745 -279.721314) (xy 241.030234 -279.719277) (xy 241.085671 -279.725377)
			(xy 241.139628 -279.739483) (xy 241.190957 -279.761295) (xy 241.238563 -279.790349) (xy 241.281431 -279.826024)
			(xy 241.318648 -279.867561) (xy 241.349421 -279.914074) (xy 241.373093 -279.964571) (xy 241.389161 -280.017978)
			(xy 241.397281 -280.073154) (xy 241.39779 -280.10104) (xy 242.552728 -280.10104) (xy 242.553192 -280.069415)
			(xy 242.561404 -280.0067) (xy 242.577732 -279.945593) (xy 242.601897 -279.887141) (xy 242.633484 -279.832343)
			(xy 242.671955 -279.782137) (xy 242.693952 -279.75941) (xy 243.59362 -278.859742) (xy 243.616212 -278.837885)
			(xy 243.666086 -278.799621) (xy 243.720498 -278.768145) (xy 243.749322 -278.755602) (xy 243.760244 -278.75103)
			(xy 243.77523 -278.734012) (xy 243.803424 -278.634698) (xy 243.799614 -278.612092) (xy 243.792502 -278.602694)
			(xy 243.775618 -278.5782) (xy 243.748833 -278.525084) (xy 243.730621 -278.468452) (xy 243.721424 -278.40968)
			(xy 243.720874 -278.379936) (xy 243.72136 -278.352685) (xy 243.729116 -278.298737) (xy 243.744471 -278.246442)
			(xy 243.767113 -278.196865) (xy 243.796579 -278.151015) (xy 243.83227 -278.109824) (xy 243.873461 -278.074133)
			(xy 243.919311 -278.044667) (xy 243.968888 -278.022025) (xy 244.021183 -278.00667) (xy 244.075131 -277.998914)
			(xy 244.129633 -277.998914) (xy 244.183581 -278.00667) (xy 244.235876 -278.022025) (xy 244.285453 -278.044667)
			(xy 244.331303 -278.074133) (xy 244.372494 -278.109824) (xy 244.408185 -278.151015) (xy 244.437651 -278.196865)
			(xy 244.460293 -278.246442) (xy 244.475648 -278.298737) (xy 244.483404 -278.352685) (xy 244.48389 -278.379936)
			(xy 244.483522 -278.404371) (xy 244.477277 -278.45284) (xy 244.46488 -278.500111) (xy 244.446536 -278.545407)
			(xy 244.434868 -278.56688) (xy 244.428264 -278.578818) (xy 244.428518 -278.605742) (xy 244.479572 -278.693118)
			(xy 244.484299 -278.700636) (xy 244.497926 -278.71201) (xy 244.514637 -278.71799) (xy 244.523514 -278.718264)
			(xy 244.865906 -278.718264) (xy 244.874867 -278.717964) (xy 244.891699 -278.711812) (xy 244.905375 -278.700231)
			(xy 244.910102 -278.69261) (xy 244.960394 -278.60371) (xy 244.96014 -278.576532) (xy 244.953028 -278.564594)
			(xy 244.940173 -278.542316) (xy 244.919943 -278.495026) (xy 244.906251 -278.445447) (xy 244.899345 -278.394478)
			(xy 244.898926 -278.36876) (xy 244.899412 -278.341509) (xy 244.907168 -278.287561) (xy 244.922523 -278.235266)
			(xy 244.945165 -278.185689) (xy 244.974631 -278.139839) (xy 245.010322 -278.098648) (xy 245.051513 -278.062957)
			(xy 245.097363 -278.033491) (xy 245.14694 -278.010849) (xy 245.199235 -277.995494) (xy 245.253183 -277.987738)
			(xy 245.307685 -277.987738) (xy 245.361633 -277.995494) (xy 245.413928 -278.010849) (xy 245.463505 -278.033491)
			(xy 245.509355 -278.062957) (xy 245.550546 -278.098648) (xy 245.586237 -278.139839) (xy 245.615703 -278.185689)
			(xy 245.638345 -278.235266) (xy 245.6537 -278.287561) (xy 245.661456 -278.341509) (xy 245.661942 -278.36876)
			(xy 245.66154 -278.394478) (xy 245.654622 -278.445445) (xy 245.64092 -278.495022) (xy 245.620682 -278.542308)
			(xy 245.60784 -278.564594) (xy 245.600728 -278.576532) (xy 245.600474 -278.60371) (xy 245.650766 -278.69261)
			(xy 245.65551 -278.70021) (xy 245.669194 -278.711759) (xy 245.686009 -278.717913) (xy 245.694962 -278.718264)
			(xy 246.214138 -278.718264) (xy 246.224108 -278.717817) (xy 246.242544 -278.710221) (xy 246.249952 -278.703532)
			(xy 246.743474 -278.209756) (xy 246.752014 -278.201374) (xy 246.769802 -278.185365) (xy 246.779034 -278.177752)
			(xy 246.786908 -278.171402) (xy 246.796306 -278.153622) (xy 246.804942 -278.061166) (xy 246.7991 -278.042116)
			(xy 246.792496 -278.034242) (xy 246.775803 -278.013534) (xy 246.747667 -277.968397) (xy 246.726074 -277.919789)
			(xy 246.711442 -277.868653) (xy 246.704056 -277.81598) (xy 246.703596 -277.789386) (xy 246.704082 -277.762135)
			(xy 246.711838 -277.708187) (xy 246.727193 -277.655892) (xy 246.749835 -277.606315) (xy 246.779301 -277.560465)
			(xy 246.814992 -277.519274) (xy 246.856183 -277.483583) (xy 246.902033 -277.454117) (xy 246.95161 -277.431475)
			(xy 247.003905 -277.41612) (xy 247.057853 -277.408364) (xy 247.112355 -277.408364) (xy 247.166303 -277.41612)
			(xy 247.218598 -277.431475) (xy 247.268175 -277.454117) (xy 247.314025 -277.483583) (xy 247.355216 -277.519274)
			(xy 247.370277 -277.536656) (xy 248.722386 -277.536656) (xy 248.726457 -277.481034) (xy 248.738583 -277.426597)
			(xy 248.758506 -277.374506) (xy 248.785802 -277.325871) (xy 248.819888 -277.281728) (xy 248.860037 -277.243019)
			(xy 248.905395 -277.210568) (xy 248.954995 -277.185067) (xy 249.007779 -277.16706) (xy 249.062622 -277.15693)
			(xy 249.118356 -277.154893) (xy 249.173793 -277.160993) (xy 249.22775 -277.175099) (xy 249.279079 -277.196911)
			(xy 249.326685 -277.225965) (xy 249.369553 -277.26164) (xy 249.40677 -277.303177) (xy 249.437543 -277.34969)
			(xy 249.449341 -277.374858) (xy 268.26897 -277.374858) (xy 268.27293 -277.325804) (xy 268.284707 -277.27802)
			(xy 268.303998 -277.232744) (xy 268.330301 -277.191148) (xy 268.362936 -277.154311) (xy 268.401057 -277.123186)
			(xy 268.443678 -277.098579) (xy 268.489694 -277.081127) (xy 268.537913 -277.071283) (xy 268.587088 -277.069302)
			(xy 268.635943 -277.075234) (xy 268.683214 -277.088926) (xy 268.727676 -277.110024) (xy 268.768179 -277.13798)
			(xy 268.803672 -277.172072) (xy 268.833237 -277.211416) (xy 268.856108 -277.254993) (xy 268.871692 -277.301674)
			(xy 268.879587 -277.350251) (xy 268.880082 -277.374858) (xy 269.21893 -277.374858) (xy 269.22289 -277.325804)
			(xy 269.234667 -277.27802) (xy 269.253958 -277.232744) (xy 269.280261 -277.191148) (xy 269.312896 -277.154311)
			(xy 269.351017 -277.123186) (xy 269.393638 -277.098579) (xy 269.439654 -277.081127) (xy 269.487873 -277.071283)
			(xy 269.537048 -277.069302) (xy 269.585903 -277.075234) (xy 269.633174 -277.088926) (xy 269.677636 -277.110024)
			(xy 269.718139 -277.13798) (xy 269.753632 -277.172072) (xy 269.783197 -277.211416) (xy 269.806068 -277.254993)
			(xy 269.821652 -277.301674) (xy 269.829547 -277.350251) (xy 269.830042 -277.374858) (xy 270.169144 -277.374858)
			(xy 270.173104 -277.325804) (xy 270.184881 -277.27802) (xy 270.204172 -277.232744) (xy 270.230475 -277.191148)
			(xy 270.26311 -277.154311) (xy 270.301231 -277.123186) (xy 270.343852 -277.098579) (xy 270.389868 -277.081127)
			(xy 270.438087 -277.071283) (xy 270.487262 -277.069302) (xy 270.536117 -277.075234) (xy 270.583388 -277.088926)
			(xy 270.62785 -277.110024) (xy 270.668353 -277.13798) (xy 270.703846 -277.172072) (xy 270.733411 -277.211416)
			(xy 270.756282 -277.254993) (xy 270.771866 -277.301674) (xy 270.779761 -277.350251) (xy 270.780256 -277.374858)
			(xy 271.119104 -277.374858) (xy 271.123064 -277.325804) (xy 271.134841 -277.27802) (xy 271.154132 -277.232744)
			(xy 271.180435 -277.191148) (xy 271.21307 -277.154311) (xy 271.251191 -277.123186) (xy 271.293812 -277.098579)
			(xy 271.339828 -277.081127) (xy 271.388047 -277.071283) (xy 271.437222 -277.069302) (xy 271.486077 -277.075234)
			(xy 271.533348 -277.088926) (xy 271.57781 -277.110024) (xy 271.618313 -277.13798) (xy 271.653806 -277.172072)
			(xy 271.683371 -277.211416) (xy 271.706242 -277.254993) (xy 271.721826 -277.301674) (xy 271.729721 -277.350251)
			(xy 271.730216 -277.374858) (xy 272.069064 -277.374858) (xy 272.073024 -277.325804) (xy 272.084801 -277.27802)
			(xy 272.104092 -277.232744) (xy 272.130395 -277.191148) (xy 272.16303 -277.154311) (xy 272.201151 -277.123186)
			(xy 272.243772 -277.098579) (xy 272.289788 -277.081127) (xy 272.338007 -277.071283) (xy 272.387182 -277.069302)
			(xy 272.436037 -277.075234) (xy 272.483308 -277.088926) (xy 272.52777 -277.110024) (xy 272.568273 -277.13798)
			(xy 272.603766 -277.172072) (xy 272.633331 -277.211416) (xy 272.656202 -277.254993) (xy 272.671786 -277.301674)
			(xy 272.679681 -277.350251) (xy 272.680176 -277.374858) (xy 273.019024 -277.374858) (xy 273.022984 -277.325804)
			(xy 273.034761 -277.27802) (xy 273.054052 -277.232744) (xy 273.080355 -277.191148) (xy 273.11299 -277.154311)
			(xy 273.151111 -277.123186) (xy 273.193732 -277.098579) (xy 273.239748 -277.081127) (xy 273.287967 -277.071283)
			(xy 273.337142 -277.069302) (xy 273.385997 -277.075234) (xy 273.433268 -277.088926) (xy 273.47773 -277.110024)
			(xy 273.518233 -277.13798) (xy 273.553726 -277.172072) (xy 273.583291 -277.211416) (xy 273.606162 -277.254993)
			(xy 273.621746 -277.301674) (xy 273.629641 -277.350251) (xy 273.630136 -277.374858) (xy 273.968984 -277.374858)
			(xy 273.972944 -277.325804) (xy 273.984721 -277.27802) (xy 274.004012 -277.232744) (xy 274.030315 -277.191148)
			(xy 274.06295 -277.154311) (xy 274.101071 -277.123186) (xy 274.143692 -277.098579) (xy 274.189708 -277.081127)
			(xy 274.237927 -277.071283) (xy 274.287102 -277.069302) (xy 274.335957 -277.075234) (xy 274.383228 -277.088926)
			(xy 274.42769 -277.110024) (xy 274.468193 -277.13798) (xy 274.503686 -277.172072) (xy 274.533251 -277.211416)
			(xy 274.556122 -277.254993) (xy 274.571706 -277.301674) (xy 274.579601 -277.350251) (xy 274.580096 -277.374858)
			(xy 274.918944 -277.374858) (xy 274.922904 -277.325804) (xy 274.934681 -277.27802) (xy 274.953972 -277.232744)
			(xy 274.980275 -277.191148) (xy 275.01291 -277.154311) (xy 275.051031 -277.123186) (xy 275.093652 -277.098579)
			(xy 275.139668 -277.081127) (xy 275.187887 -277.071283) (xy 275.237062 -277.069302) (xy 275.285917 -277.075234)
			(xy 275.333188 -277.088926) (xy 275.37765 -277.110024) (xy 275.418153 -277.13798) (xy 275.453646 -277.172072)
			(xy 275.483211 -277.211416) (xy 275.506082 -277.254993) (xy 275.521666 -277.301674) (xy 275.529561 -277.350251)
			(xy 275.530056 -277.374858) (xy 275.529561 -277.399465) (xy 275.521666 -277.448042) (xy 275.506082 -277.494723)
			(xy 275.483211 -277.5383) (xy 275.453646 -277.577644) (xy 275.418153 -277.611736) (xy 275.37765 -277.639692)
			(xy 275.333188 -277.66079) (xy 275.285917 -277.674482) (xy 275.237062 -277.680414) (xy 275.187887 -277.678433)
			(xy 275.139668 -277.668589) (xy 275.093652 -277.651137) (xy 275.051031 -277.62653) (xy 275.01291 -277.595405)
			(xy 274.980275 -277.558568) (xy 274.953972 -277.516972) (xy 274.934681 -277.471696) (xy 274.922904 -277.423912)
			(xy 274.918944 -277.374858) (xy 274.580096 -277.374858) (xy 274.579601 -277.399465) (xy 274.571706 -277.448042)
			(xy 274.556122 -277.494723) (xy 274.533251 -277.5383) (xy 274.503686 -277.577644) (xy 274.468193 -277.611736)
			(xy 274.42769 -277.639692) (xy 274.383228 -277.66079) (xy 274.335957 -277.674482) (xy 274.287102 -277.680414)
			(xy 274.237927 -277.678433) (xy 274.189708 -277.668589) (xy 274.143692 -277.651137) (xy 274.101071 -277.62653)
			(xy 274.06295 -277.595405) (xy 274.030315 -277.558568) (xy 274.004012 -277.516972) (xy 273.984721 -277.471696)
			(xy 273.972944 -277.423912) (xy 273.968984 -277.374858) (xy 273.630136 -277.374858) (xy 273.629641 -277.399465)
			(xy 273.621746 -277.448042) (xy 273.606162 -277.494723) (xy 273.583291 -277.5383) (xy 273.553726 -277.577644)
			(xy 273.518233 -277.611736) (xy 273.47773 -277.639692) (xy 273.433268 -277.66079) (xy 273.385997 -277.674482)
			(xy 273.337142 -277.680414) (xy 273.287967 -277.678433) (xy 273.239748 -277.668589) (xy 273.193732 -277.651137)
			(xy 273.151111 -277.62653) (xy 273.11299 -277.595405) (xy 273.080355 -277.558568) (xy 273.054052 -277.516972)
			(xy 273.034761 -277.471696) (xy 273.022984 -277.423912) (xy 273.019024 -277.374858) (xy 272.680176 -277.374858)
			(xy 272.679681 -277.399465) (xy 272.671786 -277.448042) (xy 272.656202 -277.494723) (xy 272.633331 -277.5383)
			(xy 272.603766 -277.577644) (xy 272.568273 -277.611736) (xy 272.52777 -277.639692) (xy 272.483308 -277.66079)
			(xy 272.436037 -277.674482) (xy 272.387182 -277.680414) (xy 272.338007 -277.678433) (xy 272.289788 -277.668589)
			(xy 272.243772 -277.651137) (xy 272.201151 -277.62653) (xy 272.16303 -277.595405) (xy 272.130395 -277.558568)
			(xy 272.104092 -277.516972) (xy 272.084801 -277.471696) (xy 272.073024 -277.423912) (xy 272.069064 -277.374858)
			(xy 271.730216 -277.374858) (xy 271.729721 -277.399465) (xy 271.721826 -277.448042) (xy 271.706242 -277.494723)
			(xy 271.683371 -277.5383) (xy 271.653806 -277.577644) (xy 271.618313 -277.611736) (xy 271.57781 -277.639692)
			(xy 271.533348 -277.66079) (xy 271.486077 -277.674482) (xy 271.437222 -277.680414) (xy 271.388047 -277.678433)
			(xy 271.339828 -277.668589) (xy 271.293812 -277.651137) (xy 271.251191 -277.62653) (xy 271.21307 -277.595405)
			(xy 271.180435 -277.558568) (xy 271.154132 -277.516972) (xy 271.134841 -277.471696) (xy 271.123064 -277.423912)
			(xy 271.119104 -277.374858) (xy 270.780256 -277.374858) (xy 270.779761 -277.399465) (xy 270.771866 -277.448042)
			(xy 270.756282 -277.494723) (xy 270.733411 -277.5383) (xy 270.703846 -277.577644) (xy 270.668353 -277.611736)
			(xy 270.62785 -277.639692) (xy 270.583388 -277.66079) (xy 270.536117 -277.674482) (xy 270.487262 -277.680414)
			(xy 270.438087 -277.678433) (xy 270.389868 -277.668589) (xy 270.343852 -277.651137) (xy 270.301231 -277.62653)
			(xy 270.26311 -277.595405) (xy 270.230475 -277.558568) (xy 270.204172 -277.516972) (xy 270.184881 -277.471696)
			(xy 270.173104 -277.423912) (xy 270.169144 -277.374858) (xy 269.830042 -277.374858) (xy 269.829547 -277.399465)
			(xy 269.821652 -277.448042) (xy 269.806068 -277.494723) (xy 269.783197 -277.5383) (xy 269.753632 -277.577644)
			(xy 269.718139 -277.611736) (xy 269.677636 -277.639692) (xy 269.633174 -277.66079) (xy 269.585903 -277.674482)
			(xy 269.537048 -277.680414) (xy 269.487873 -277.678433) (xy 269.439654 -277.668589) (xy 269.393638 -277.651137)
			(xy 269.351017 -277.62653) (xy 269.312896 -277.595405) (xy 269.280261 -277.558568) (xy 269.253958 -277.516972)
			(xy 269.234667 -277.471696) (xy 269.22289 -277.423912) (xy 269.21893 -277.374858) (xy 268.880082 -277.374858)
			(xy 268.879587 -277.399465) (xy 268.871692 -277.448042) (xy 268.856108 -277.494723) (xy 268.833237 -277.5383)
			(xy 268.803672 -277.577644) (xy 268.768179 -277.611736) (xy 268.727676 -277.639692) (xy 268.683214 -277.66079)
			(xy 268.635943 -277.674482) (xy 268.587088 -277.680414) (xy 268.537913 -277.678433) (xy 268.489694 -277.668589)
			(xy 268.443678 -277.651137) (xy 268.401057 -277.62653) (xy 268.362936 -277.595405) (xy 268.330301 -277.558568)
			(xy 268.303998 -277.516972) (xy 268.284707 -277.471696) (xy 268.27293 -277.423912) (xy 268.26897 -277.374858)
			(xy 249.449341 -277.374858) (xy 249.461215 -277.400187) (xy 249.477283 -277.453594) (xy 249.485403 -277.50877)
			(xy 249.485912 -277.536656) (xy 249.485403 -277.564542) (xy 249.477283 -277.619718) (xy 249.461215 -277.673125)
			(xy 249.437543 -277.723622) (xy 249.40677 -277.770135) (xy 249.369553 -277.811672) (xy 249.326685 -277.847347)
			(xy 249.28048 -277.875546) (xy 276.32304 -277.875546) (xy 276.32304 -277.82413) (xy 276.331083 -277.773348)
			(xy 276.346971 -277.724449) (xy 276.370314 -277.678637) (xy 276.400535 -277.637041) (xy 276.436891 -277.600685)
			(xy 276.478487 -277.570464) (xy 276.524299 -277.547121) (xy 276.573198 -277.531233) (xy 276.62398 -277.52319)
			(xy 276.675396 -277.52319) (xy 276.726178 -277.531233) (xy 276.775077 -277.547121) (xy 276.820889 -277.570464)
			(xy 276.862485 -277.600685) (xy 276.898841 -277.637041) (xy 276.929062 -277.678637) (xy 276.952405 -277.724449)
			(xy 276.968293 -277.773348) (xy 276.976336 -277.82413) (xy 276.97684 -277.849838) (xy 277.294098 -277.849838)
			(xy 277.298058 -277.800784) (xy 277.309835 -277.753) (xy 277.329126 -277.707724) (xy 277.355429 -277.666128)
			(xy 277.388064 -277.629291) (xy 277.426185 -277.598166) (xy 277.468806 -277.573559) (xy 277.514822 -277.556107)
			(xy 277.563041 -277.546263) (xy 277.612216 -277.544282) (xy 277.661071 -277.550214) (xy 277.708342 -277.563906)
			(xy 277.752804 -277.585004) (xy 277.793307 -277.61296) (xy 277.8288 -277.647052) (xy 277.858365 -277.686396)
			(xy 277.881236 -277.729973) (xy 277.89682 -277.776654) (xy 277.904715 -277.825231) (xy 277.90521 -277.849838)
			(xy 277.904715 -277.874445) (xy 277.904536 -277.875546) (xy 278.223214 -277.875546) (xy 278.223214 -277.82413)
			(xy 278.231257 -277.773348) (xy 278.247145 -277.724449) (xy 278.270488 -277.678637) (xy 278.300709 -277.637041)
			(xy 278.337065 -277.600685) (xy 278.378661 -277.570464) (xy 278.424473 -277.547121) (xy 278.473372 -277.531233)
			(xy 278.524154 -277.52319) (xy 278.57557 -277.52319) (xy 278.626352 -277.531233) (xy 278.675251 -277.547121)
			(xy 278.721063 -277.570464) (xy 278.762659 -277.600685) (xy 278.799015 -277.637041) (xy 278.829236 -277.678637)
			(xy 278.852579 -277.724449) (xy 278.868467 -277.773348) (xy 278.87651 -277.82413) (xy 278.877014 -277.849838)
			(xy 279.194018 -277.849838) (xy 279.197978 -277.800784) (xy 279.209755 -277.753) (xy 279.229046 -277.707724)
			(xy 279.255349 -277.666128) (xy 279.287984 -277.629291) (xy 279.326105 -277.598166) (xy 279.368726 -277.573559)
			(xy 279.414742 -277.556107) (xy 279.462961 -277.546263) (xy 279.512136 -277.544282) (xy 279.560991 -277.550214)
			(xy 279.608262 -277.563906) (xy 279.652724 -277.585004) (xy 279.693227 -277.61296) (xy 279.72872 -277.647052)
			(xy 279.758285 -277.686396) (xy 279.781156 -277.729973) (xy 279.79674 -277.776654) (xy 279.804635 -277.825231)
			(xy 279.80513 -277.849838) (xy 279.804635 -277.874445) (xy 279.804456 -277.875546) (xy 280.123134 -277.875546)
			(xy 280.123134 -277.82413) (xy 280.131177 -277.773348) (xy 280.147065 -277.724449) (xy 280.170408 -277.678637)
			(xy 280.200629 -277.637041) (xy 280.236985 -277.600685) (xy 280.278581 -277.570464) (xy 280.324393 -277.547121)
			(xy 280.373292 -277.531233) (xy 280.424074 -277.52319) (xy 280.47549 -277.52319) (xy 280.526272 -277.531233)
			(xy 280.575171 -277.547121) (xy 280.620983 -277.570464) (xy 280.662579 -277.600685) (xy 280.698935 -277.637041)
			(xy 280.729156 -277.678637) (xy 280.752499 -277.724449) (xy 280.768387 -277.773348) (xy 280.77643 -277.82413)
			(xy 280.776934 -277.849838) (xy 281.093938 -277.849838) (xy 281.097898 -277.800784) (xy 281.109675 -277.753)
			(xy 281.128966 -277.707724) (xy 281.155269 -277.666128) (xy 281.187904 -277.629291) (xy 281.226025 -277.598166)
			(xy 281.268646 -277.573559) (xy 281.314662 -277.556107) (xy 281.362881 -277.546263) (xy 281.412056 -277.544282)
			(xy 281.460911 -277.550214) (xy 281.508182 -277.563906) (xy 281.552644 -277.585004) (xy 281.593147 -277.61296)
			(xy 281.62864 -277.647052) (xy 281.658205 -277.686396) (xy 281.681076 -277.729973) (xy 281.69666 -277.776654)
			(xy 281.704555 -277.825231) (xy 281.70505 -277.849838) (xy 281.704555 -277.874445) (xy 281.704376 -277.875546)
			(xy 282.023054 -277.875546) (xy 282.023054 -277.82413) (xy 282.031097 -277.773348) (xy 282.046985 -277.724449)
			(xy 282.070328 -277.678637) (xy 282.100549 -277.637041) (xy 282.136905 -277.600685) (xy 282.178501 -277.570464)
			(xy 282.224313 -277.547121) (xy 282.273212 -277.531233) (xy 282.323994 -277.52319) (xy 282.37541 -277.52319)
			(xy 282.426192 -277.531233) (xy 282.475091 -277.547121) (xy 282.520903 -277.570464) (xy 282.562499 -277.600685)
			(xy 282.598855 -277.637041) (xy 282.629076 -277.678637) (xy 282.652419 -277.724449) (xy 282.668307 -277.773348)
			(xy 282.67635 -277.82413) (xy 282.676854 -277.849838) (xy 282.994112 -277.849838) (xy 282.998072 -277.800784)
			(xy 283.009849 -277.753) (xy 283.02914 -277.707724) (xy 283.055443 -277.666128) (xy 283.088078 -277.629291)
			(xy 283.126199 -277.598166) (xy 283.16882 -277.573559) (xy 283.214836 -277.556107) (xy 283.263055 -277.546263)
			(xy 283.31223 -277.544282) (xy 283.361085 -277.550214) (xy 283.408356 -277.563906) (xy 283.452818 -277.585004)
			(xy 283.493321 -277.61296) (xy 283.528814 -277.647052) (xy 283.558379 -277.686396) (xy 283.58125 -277.729973)
			(xy 283.596834 -277.776654) (xy 283.604729 -277.825231) (xy 283.605224 -277.849838) (xy 283.604729 -277.874445)
			(xy 283.60455 -277.875546) (xy 283.923228 -277.875546) (xy 283.923228 -277.82413) (xy 283.931271 -277.773348)
			(xy 283.947159 -277.724449) (xy 283.970502 -277.678637) (xy 284.000723 -277.637041) (xy 284.037079 -277.600685)
			(xy 284.078675 -277.570464) (xy 284.124487 -277.547121) (xy 284.173386 -277.531233) (xy 284.224168 -277.52319)
			(xy 284.275584 -277.52319) (xy 284.326366 -277.531233) (xy 284.375265 -277.547121) (xy 284.421077 -277.570464)
			(xy 284.462673 -277.600685) (xy 284.499029 -277.637041) (xy 284.52925 -277.678637) (xy 284.552593 -277.724449)
			(xy 284.568481 -277.773348) (xy 284.576524 -277.82413) (xy 284.577028 -277.849838) (xy 284.894032 -277.849838)
			(xy 284.897992 -277.800784) (xy 284.909769 -277.753) (xy 284.92906 -277.707724) (xy 284.955363 -277.666128)
			(xy 284.987998 -277.629291) (xy 285.026119 -277.598166) (xy 285.06874 -277.573559) (xy 285.114756 -277.556107)
			(xy 285.162975 -277.546263) (xy 285.21215 -277.544282) (xy 285.261005 -277.550214) (xy 285.308276 -277.563906)
			(xy 285.352738 -277.585004) (xy 285.393241 -277.61296) (xy 285.428734 -277.647052) (xy 285.458299 -277.686396)
			(xy 285.48117 -277.729973) (xy 285.496754 -277.776654) (xy 285.504649 -277.825231) (xy 285.505144 -277.849838)
			(xy 285.504649 -277.874445) (xy 285.50447 -277.875546) (xy 285.823148 -277.875546) (xy 285.823148 -277.82413)
			(xy 285.831191 -277.773348) (xy 285.847079 -277.724449) (xy 285.870422 -277.678637) (xy 285.900643 -277.637041)
			(xy 285.936999 -277.600685) (xy 285.978595 -277.570464) (xy 286.024407 -277.547121) (xy 286.073306 -277.531233)
			(xy 286.124088 -277.52319) (xy 286.175504 -277.52319) (xy 286.226286 -277.531233) (xy 286.275185 -277.547121)
			(xy 286.320997 -277.570464) (xy 286.362593 -277.600685) (xy 286.398949 -277.637041) (xy 286.42917 -277.678637)
			(xy 286.452513 -277.724449) (xy 286.468401 -277.773348) (xy 286.476444 -277.82413) (xy 286.476948 -277.849838)
			(xy 286.793952 -277.849838) (xy 286.797912 -277.800784) (xy 286.809689 -277.753) (xy 286.82898 -277.707724)
			(xy 286.855283 -277.666128) (xy 286.887918 -277.629291) (xy 286.926039 -277.598166) (xy 286.96866 -277.573559)
			(xy 287.014676 -277.556107) (xy 287.062895 -277.546263) (xy 287.11207 -277.544282) (xy 287.160925 -277.550214)
			(xy 287.208196 -277.563906) (xy 287.252658 -277.585004) (xy 287.293161 -277.61296) (xy 287.328654 -277.647052)
			(xy 287.358219 -277.686396) (xy 287.38109 -277.729973) (xy 287.396674 -277.776654) (xy 287.404569 -277.825231)
			(xy 287.405064 -277.849838) (xy 287.404569 -277.874445) (xy 287.40439 -277.875546) (xy 287.723068 -277.875546)
			(xy 287.723068 -277.82413) (xy 287.731111 -277.773348) (xy 287.746999 -277.724449) (xy 287.770342 -277.678637)
			(xy 287.800563 -277.637041) (xy 287.836919 -277.600685) (xy 287.878515 -277.570464) (xy 287.924327 -277.547121)
			(xy 287.973226 -277.531233) (xy 288.024008 -277.52319) (xy 288.075424 -277.52319) (xy 288.126206 -277.531233)
			(xy 288.175105 -277.547121) (xy 288.220917 -277.570464) (xy 288.262513 -277.600685) (xy 288.298869 -277.637041)
			(xy 288.32909 -277.678637) (xy 288.352433 -277.724449) (xy 288.368321 -277.773348) (xy 288.376364 -277.82413)
			(xy 288.376868 -277.849838) (xy 288.694126 -277.849838) (xy 288.698086 -277.800784) (xy 288.709863 -277.753)
			(xy 288.729154 -277.707724) (xy 288.755457 -277.666128) (xy 288.788092 -277.629291) (xy 288.826213 -277.598166)
			(xy 288.868834 -277.573559) (xy 288.91485 -277.556107) (xy 288.963069 -277.546263) (xy 289.012244 -277.544282)
			(xy 289.061099 -277.550214) (xy 289.10837 -277.563906) (xy 289.152832 -277.585004) (xy 289.193335 -277.61296)
			(xy 289.228828 -277.647052) (xy 289.258393 -277.686396) (xy 289.281264 -277.729973) (xy 289.296848 -277.776654)
			(xy 289.304743 -277.825231) (xy 289.305238 -277.849838) (xy 289.304743 -277.874445) (xy 289.304564 -277.875546)
			(xy 289.623242 -277.875546) (xy 289.623242 -277.82413) (xy 289.631285 -277.773348) (xy 289.647173 -277.724449)
			(xy 289.670516 -277.678637) (xy 289.700737 -277.637041) (xy 289.737093 -277.600685) (xy 289.778689 -277.570464)
			(xy 289.824501 -277.547121) (xy 289.8734 -277.531233) (xy 289.924182 -277.52319) (xy 289.975598 -277.52319)
			(xy 290.02638 -277.531233) (xy 290.075279 -277.547121) (xy 290.121091 -277.570464) (xy 290.162687 -277.600685)
			(xy 290.199043 -277.637041) (xy 290.229264 -277.678637) (xy 290.252607 -277.724449) (xy 290.268495 -277.773348)
			(xy 290.276538 -277.82413) (xy 290.277042 -277.849838) (xy 290.594046 -277.849838) (xy 290.598006 -277.800784)
			(xy 290.609783 -277.753) (xy 290.629074 -277.707724) (xy 290.655377 -277.666128) (xy 290.688012 -277.629291)
			(xy 290.726133 -277.598166) (xy 290.768754 -277.573559) (xy 290.81477 -277.556107) (xy 290.862989 -277.546263)
			(xy 290.912164 -277.544282) (xy 290.961019 -277.550214) (xy 291.00829 -277.563906) (xy 291.052752 -277.585004)
			(xy 291.093255 -277.61296) (xy 291.128748 -277.647052) (xy 291.158313 -277.686396) (xy 291.181184 -277.729973)
			(xy 291.196768 -277.776654) (xy 291.204663 -277.825231) (xy 291.205158 -277.849838) (xy 291.204663 -277.874445)
			(xy 291.204484 -277.875546) (xy 291.522908 -277.875546) (xy 291.522908 -277.82413) (xy 291.530951 -277.773348)
			(xy 291.546839 -277.724449) (xy 291.570182 -277.678637) (xy 291.600403 -277.637041) (xy 291.636759 -277.600685)
			(xy 291.678355 -277.570464) (xy 291.724167 -277.547121) (xy 291.773066 -277.531233) (xy 291.823848 -277.52319)
			(xy 291.875264 -277.52319) (xy 291.926046 -277.531233) (xy 291.974945 -277.547121) (xy 292.020757 -277.570464)
			(xy 292.062353 -277.600685) (xy 292.098709 -277.637041) (xy 292.12893 -277.678637) (xy 292.152273 -277.724449)
			(xy 292.168161 -277.773348) (xy 292.176204 -277.82413) (xy 292.176708 -277.849838) (xy 292.493966 -277.849838)
			(xy 292.497926 -277.800784) (xy 292.509703 -277.753) (xy 292.528994 -277.707724) (xy 292.555297 -277.666128)
			(xy 292.587932 -277.629291) (xy 292.626053 -277.598166) (xy 292.668674 -277.573559) (xy 292.71469 -277.556107)
			(xy 292.762909 -277.546263) (xy 292.812084 -277.544282) (xy 292.860939 -277.550214) (xy 292.90821 -277.563906)
			(xy 292.952672 -277.585004) (xy 292.993175 -277.61296) (xy 293.028668 -277.647052) (xy 293.058233 -277.686396)
			(xy 293.081104 -277.729973) (xy 293.096688 -277.776654) (xy 293.104583 -277.825231) (xy 293.105078 -277.849838)
			(xy 293.104583 -277.874445) (xy 293.104404 -277.875546) (xy 293.422828 -277.875546) (xy 293.422828 -277.82413)
			(xy 293.430871 -277.773348) (xy 293.446759 -277.724449) (xy 293.470102 -277.678637) (xy 293.500323 -277.637041)
			(xy 293.536679 -277.600685) (xy 293.578275 -277.570464) (xy 293.624087 -277.547121) (xy 293.672986 -277.531233)
			(xy 293.723768 -277.52319) (xy 293.775184 -277.52319) (xy 293.825966 -277.531233) (xy 293.874865 -277.547121)
			(xy 293.920677 -277.570464) (xy 293.962273 -277.600685) (xy 293.998629 -277.637041) (xy 294.02885 -277.678637)
			(xy 294.052193 -277.724449) (xy 294.068081 -277.773348) (xy 294.076124 -277.82413) (xy 294.076628 -277.849838)
			(xy 294.393886 -277.849838) (xy 294.397846 -277.800784) (xy 294.409623 -277.753) (xy 294.428914 -277.707724)
			(xy 294.455217 -277.666128) (xy 294.487852 -277.629291) (xy 294.525973 -277.598166) (xy 294.568594 -277.573559)
			(xy 294.61461 -277.556107) (xy 294.662829 -277.546263) (xy 294.712004 -277.544282) (xy 294.760859 -277.550214)
			(xy 294.80813 -277.563906) (xy 294.852592 -277.585004) (xy 294.893095 -277.61296) (xy 294.928588 -277.647052)
			(xy 294.958153 -277.686396) (xy 294.981024 -277.729973) (xy 294.996608 -277.776654) (xy 295.004503 -277.825231)
			(xy 295.004998 -277.849838) (xy 295.004503 -277.874445) (xy 295.004324 -277.875546) (xy 295.323002 -277.875546)
			(xy 295.323002 -277.82413) (xy 295.331045 -277.773348) (xy 295.346933 -277.724449) (xy 295.370276 -277.678637)
			(xy 295.400497 -277.637041) (xy 295.436853 -277.600685) (xy 295.478449 -277.570464) (xy 295.524261 -277.547121)
			(xy 295.57316 -277.531233) (xy 295.623942 -277.52319) (xy 295.675358 -277.52319) (xy 295.72614 -277.531233)
			(xy 295.775039 -277.547121) (xy 295.820851 -277.570464) (xy 295.862447 -277.600685) (xy 295.898803 -277.637041)
			(xy 295.929024 -277.678637) (xy 295.952367 -277.724449) (xy 295.968255 -277.773348) (xy 295.976298 -277.82413)
			(xy 295.976802 -277.849838) (xy 296.29406 -277.849838) (xy 296.29802 -277.800784) (xy 296.309797 -277.753)
			(xy 296.329088 -277.707724) (xy 296.355391 -277.666128) (xy 296.388026 -277.629291) (xy 296.426147 -277.598166)
			(xy 296.468768 -277.573559) (xy 296.514784 -277.556107) (xy 296.563003 -277.546263) (xy 296.612178 -277.544282)
			(xy 296.661033 -277.550214) (xy 296.708304 -277.563906) (xy 296.752766 -277.585004) (xy 296.793269 -277.61296)
			(xy 296.828762 -277.647052) (xy 296.858327 -277.686396) (xy 296.881198 -277.729973) (xy 296.896782 -277.776654)
			(xy 296.904677 -277.825231) (xy 296.905172 -277.849838) (xy 296.904677 -277.874445) (xy 296.904498 -277.875546)
			(xy 297.222922 -277.875546) (xy 297.222922 -277.82413) (xy 297.230965 -277.773348) (xy 297.246853 -277.724449)
			(xy 297.270196 -277.678637) (xy 297.300417 -277.637041) (xy 297.336773 -277.600685) (xy 297.378369 -277.570464)
			(xy 297.424181 -277.547121) (xy 297.47308 -277.531233) (xy 297.523862 -277.52319) (xy 297.575278 -277.52319)
			(xy 297.62606 -277.531233) (xy 297.674959 -277.547121) (xy 297.720771 -277.570464) (xy 297.762367 -277.600685)
			(xy 297.798723 -277.637041) (xy 297.828944 -277.678637) (xy 297.852287 -277.724449) (xy 297.868175 -277.773348)
			(xy 297.876218 -277.82413) (xy 297.876722 -277.849838) (xy 298.19398 -277.849838) (xy 298.19794 -277.800784)
			(xy 298.209717 -277.753) (xy 298.229008 -277.707724) (xy 298.255311 -277.666128) (xy 298.287946 -277.629291)
			(xy 298.326067 -277.598166) (xy 298.368688 -277.573559) (xy 298.414704 -277.556107) (xy 298.462923 -277.546263)
			(xy 298.512098 -277.544282) (xy 298.560953 -277.550214) (xy 298.608224 -277.563906) (xy 298.652686 -277.585004)
			(xy 298.693189 -277.61296) (xy 298.728682 -277.647052) (xy 298.758247 -277.686396) (xy 298.781118 -277.729973)
			(xy 298.796702 -277.776654) (xy 298.804597 -277.825231) (xy 298.805092 -277.849838) (xy 298.804597 -277.874445)
			(xy 298.804418 -277.875546) (xy 299.122842 -277.875546) (xy 299.122842 -277.82413) (xy 299.130885 -277.773348)
			(xy 299.146773 -277.724449) (xy 299.170116 -277.678637) (xy 299.200337 -277.637041) (xy 299.236693 -277.600685)
			(xy 299.278289 -277.570464) (xy 299.324101 -277.547121) (xy 299.373 -277.531233) (xy 299.423782 -277.52319)
			(xy 299.475198 -277.52319) (xy 299.52598 -277.531233) (xy 299.574879 -277.547121) (xy 299.620691 -277.570464)
			(xy 299.662287 -277.600685) (xy 299.698643 -277.637041) (xy 299.728864 -277.678637) (xy 299.752207 -277.724449)
			(xy 299.768095 -277.773348) (xy 299.776138 -277.82413) (xy 299.776642 -277.849838) (xy 300.0939 -277.849838)
			(xy 300.09786 -277.800784) (xy 300.109637 -277.753) (xy 300.128928 -277.707724) (xy 300.155231 -277.666128)
			(xy 300.187866 -277.629291) (xy 300.225987 -277.598166) (xy 300.268608 -277.573559) (xy 300.314624 -277.556107)
			(xy 300.362843 -277.546263) (xy 300.412018 -277.544282) (xy 300.460873 -277.550214) (xy 300.508144 -277.563906)
			(xy 300.552606 -277.585004) (xy 300.593109 -277.61296) (xy 300.628602 -277.647052) (xy 300.658167 -277.686396)
			(xy 300.681038 -277.729973) (xy 300.696622 -277.776654) (xy 300.704517 -277.825231) (xy 300.705012 -277.849838)
			(xy 300.704517 -277.874445) (xy 300.704338 -277.875546) (xy 301.023016 -277.875546) (xy 301.023016 -277.82413)
			(xy 301.031059 -277.773348) (xy 301.046947 -277.724449) (xy 301.07029 -277.678637) (xy 301.100511 -277.637041)
			(xy 301.136867 -277.600685) (xy 301.178463 -277.570464) (xy 301.224275 -277.547121) (xy 301.273174 -277.531233)
			(xy 301.323956 -277.52319) (xy 301.375372 -277.52319) (xy 301.426154 -277.531233) (xy 301.475053 -277.547121)
			(xy 301.520865 -277.570464) (xy 301.562461 -277.600685) (xy 301.598817 -277.637041) (xy 301.629038 -277.678637)
			(xy 301.652381 -277.724449) (xy 301.668269 -277.773348) (xy 301.676312 -277.82413) (xy 301.676816 -277.849838)
			(xy 301.994074 -277.849838) (xy 301.998034 -277.800784) (xy 302.009811 -277.753) (xy 302.029102 -277.707724)
			(xy 302.055405 -277.666128) (xy 302.08804 -277.629291) (xy 302.126161 -277.598166) (xy 302.168782 -277.573559)
			(xy 302.214798 -277.556107) (xy 302.263017 -277.546263) (xy 302.312192 -277.544282) (xy 302.361047 -277.550214)
			(xy 302.408318 -277.563906) (xy 302.45278 -277.585004) (xy 302.493283 -277.61296) (xy 302.528776 -277.647052)
			(xy 302.558341 -277.686396) (xy 302.581212 -277.729973) (xy 302.596796 -277.776654) (xy 302.604691 -277.825231)
			(xy 302.605186 -277.849838) (xy 302.604691 -277.874445) (xy 302.604512 -277.875546) (xy 302.922936 -277.875546)
			(xy 302.922936 -277.82413) (xy 302.930979 -277.773348) (xy 302.946867 -277.724449) (xy 302.97021 -277.678637)
			(xy 303.000431 -277.637041) (xy 303.036787 -277.600685) (xy 303.078383 -277.570464) (xy 303.124195 -277.547121)
			(xy 303.173094 -277.531233) (xy 303.223876 -277.52319) (xy 303.275292 -277.52319) (xy 303.326074 -277.531233)
			(xy 303.374973 -277.547121) (xy 303.420785 -277.570464) (xy 303.462381 -277.600685) (xy 303.498737 -277.637041)
			(xy 303.528958 -277.678637) (xy 303.552301 -277.724449) (xy 303.568189 -277.773348) (xy 303.576232 -277.82413)
			(xy 303.576736 -277.849838) (xy 303.893994 -277.849838) (xy 303.897954 -277.800784) (xy 303.909731 -277.753)
			(xy 303.929022 -277.707724) (xy 303.955325 -277.666128) (xy 303.98796 -277.629291) (xy 304.026081 -277.598166)
			(xy 304.068702 -277.573559) (xy 304.114718 -277.556107) (xy 304.162937 -277.546263) (xy 304.212112 -277.544282)
			(xy 304.260967 -277.550214) (xy 304.308238 -277.563906) (xy 304.3527 -277.585004) (xy 304.393203 -277.61296)
			(xy 304.428696 -277.647052) (xy 304.458261 -277.686396) (xy 304.481132 -277.729973) (xy 304.496716 -277.776654)
			(xy 304.504611 -277.825231) (xy 304.505106 -277.849838) (xy 304.504611 -277.874445) (xy 304.504432 -277.875546)
			(xy 304.822856 -277.875546) (xy 304.822856 -277.82413) (xy 304.830899 -277.773348) (xy 304.846787 -277.724449)
			(xy 304.87013 -277.678637) (xy 304.900351 -277.637041) (xy 304.936707 -277.600685) (xy 304.978303 -277.570464)
			(xy 305.024115 -277.547121) (xy 305.073014 -277.531233) (xy 305.123796 -277.52319) (xy 305.175212 -277.52319)
			(xy 305.225994 -277.531233) (xy 305.274893 -277.547121) (xy 305.320705 -277.570464) (xy 305.362301 -277.600685)
			(xy 305.398657 -277.637041) (xy 305.428878 -277.678637) (xy 305.452221 -277.724449) (xy 305.468109 -277.773348)
			(xy 305.476152 -277.82413) (xy 305.476656 -277.849838) (xy 305.793914 -277.849838) (xy 305.797874 -277.800784)
			(xy 305.809651 -277.753) (xy 305.828942 -277.707724) (xy 305.855245 -277.666128) (xy 305.88788 -277.629291)
			(xy 305.926001 -277.598166) (xy 305.968622 -277.573559) (xy 306.014638 -277.556107) (xy 306.062857 -277.546263)
			(xy 306.112032 -277.544282) (xy 306.160887 -277.550214) (xy 306.208158 -277.563906) (xy 306.25262 -277.585004)
			(xy 306.293123 -277.61296) (xy 306.328616 -277.647052) (xy 306.358181 -277.686396) (xy 306.381052 -277.729973)
			(xy 306.396636 -277.776654) (xy 306.404531 -277.825231) (xy 306.405026 -277.849838) (xy 306.404531 -277.874445)
			(xy 306.404352 -277.875546) (xy 306.72303 -277.875546) (xy 306.72303 -277.82413) (xy 306.731073 -277.773348)
			(xy 306.746961 -277.724449) (xy 306.770304 -277.678637) (xy 306.800525 -277.637041) (xy 306.836881 -277.600685)
			(xy 306.878477 -277.570464) (xy 306.924289 -277.547121) (xy 306.973188 -277.531233) (xy 307.02397 -277.52319)
			(xy 307.075386 -277.52319) (xy 307.126168 -277.531233) (xy 307.175067 -277.547121) (xy 307.220879 -277.570464)
			(xy 307.262475 -277.600685) (xy 307.298831 -277.637041) (xy 307.329052 -277.678637) (xy 307.352395 -277.724449)
			(xy 307.368283 -277.773348) (xy 307.376326 -277.82413) (xy 307.37683 -277.849838) (xy 307.694088 -277.849838)
			(xy 307.698048 -277.800784) (xy 307.709825 -277.753) (xy 307.729116 -277.707724) (xy 307.755419 -277.666128)
			(xy 307.788054 -277.629291) (xy 307.826175 -277.598166) (xy 307.868796 -277.573559) (xy 307.914812 -277.556107)
			(xy 307.963031 -277.546263) (xy 308.012206 -277.544282) (xy 308.061061 -277.550214) (xy 308.108332 -277.563906)
			(xy 308.152794 -277.585004) (xy 308.193297 -277.61296) (xy 308.22879 -277.647052) (xy 308.258355 -277.686396)
			(xy 308.281226 -277.729973) (xy 308.29681 -277.776654) (xy 308.304705 -277.825231) (xy 308.3052 -277.849838)
			(xy 308.304705 -277.874445) (xy 308.304526 -277.875546) (xy 308.62295 -277.875546) (xy 308.62295 -277.82413)
			(xy 308.630993 -277.773348) (xy 308.646881 -277.724449) (xy 308.670224 -277.678637) (xy 308.700445 -277.637041)
			(xy 308.736801 -277.600685) (xy 308.778397 -277.570464) (xy 308.824209 -277.547121) (xy 308.873108 -277.531233)
			(xy 308.92389 -277.52319) (xy 308.975306 -277.52319) (xy 309.026088 -277.531233) (xy 309.074987 -277.547121)
			(xy 309.120799 -277.570464) (xy 309.162395 -277.600685) (xy 309.198751 -277.637041) (xy 309.228972 -277.678637)
			(xy 309.252315 -277.724449) (xy 309.268203 -277.773348) (xy 309.276246 -277.82413) (xy 309.27675 -277.849838)
			(xy 309.594008 -277.849838) (xy 309.597968 -277.800784) (xy 309.609745 -277.753) (xy 309.629036 -277.707724)
			(xy 309.655339 -277.666128) (xy 309.687974 -277.629291) (xy 309.726095 -277.598166) (xy 309.768716 -277.573559)
			(xy 309.814732 -277.556107) (xy 309.862951 -277.546263) (xy 309.912126 -277.544282) (xy 309.960981 -277.550214)
			(xy 310.008252 -277.563906) (xy 310.052714 -277.585004) (xy 310.093217 -277.61296) (xy 310.12871 -277.647052)
			(xy 310.158275 -277.686396) (xy 310.181146 -277.729973) (xy 310.19673 -277.776654) (xy 310.204625 -277.825231)
			(xy 310.20512 -277.849838) (xy 310.204625 -277.874445) (xy 310.204446 -277.875546) (xy 310.52287 -277.875546)
			(xy 310.52287 -277.82413) (xy 310.530913 -277.773348) (xy 310.546801 -277.724449) (xy 310.570144 -277.678637)
			(xy 310.600365 -277.637041) (xy 310.636721 -277.600685) (xy 310.678317 -277.570464) (xy 310.724129 -277.547121)
			(xy 310.773028 -277.531233) (xy 310.82381 -277.52319) (xy 310.875226 -277.52319) (xy 310.926008 -277.531233)
			(xy 310.974907 -277.547121) (xy 311.020719 -277.570464) (xy 311.062315 -277.600685) (xy 311.098671 -277.637041)
			(xy 311.128892 -277.678637) (xy 311.152235 -277.724449) (xy 311.168123 -277.773348) (xy 311.176166 -277.82413)
			(xy 311.17667 -277.849838) (xy 311.493928 -277.849838) (xy 311.497888 -277.800784) (xy 311.509665 -277.753)
			(xy 311.528956 -277.707724) (xy 311.555259 -277.666128) (xy 311.587894 -277.629291) (xy 311.626015 -277.598166)
			(xy 311.668636 -277.573559) (xy 311.714652 -277.556107) (xy 311.762871 -277.546263) (xy 311.812046 -277.544282)
			(xy 311.860901 -277.550214) (xy 311.908172 -277.563906) (xy 311.952634 -277.585004) (xy 311.993137 -277.61296)
			(xy 312.02863 -277.647052) (xy 312.058195 -277.686396) (xy 312.081066 -277.729973) (xy 312.09665 -277.776654)
			(xy 312.104545 -277.825231) (xy 312.10504 -277.849838) (xy 312.104545 -277.874445) (xy 312.104366 -277.875546)
			(xy 312.423044 -277.875546) (xy 312.423044 -277.82413) (xy 312.431087 -277.773348) (xy 312.446975 -277.724449)
			(xy 312.470318 -277.678637) (xy 312.500539 -277.637041) (xy 312.536895 -277.600685) (xy 312.578491 -277.570464)
			(xy 312.624303 -277.547121) (xy 312.673202 -277.531233) (xy 312.723984 -277.52319) (xy 312.7754 -277.52319)
			(xy 312.826182 -277.531233) (xy 312.875081 -277.547121) (xy 312.920893 -277.570464) (xy 312.962489 -277.600685)
			(xy 312.998845 -277.637041) (xy 313.029066 -277.678637) (xy 313.052409 -277.724449) (xy 313.068297 -277.773348)
			(xy 313.07634 -277.82413) (xy 313.076844 -277.849838) (xy 313.394102 -277.849838) (xy 313.398062 -277.800784)
			(xy 313.409839 -277.753) (xy 313.42913 -277.707724) (xy 313.455433 -277.666128) (xy 313.488068 -277.629291)
			(xy 313.526189 -277.598166) (xy 313.56881 -277.573559) (xy 313.614826 -277.556107) (xy 313.663045 -277.546263)
			(xy 313.71222 -277.544282) (xy 313.761075 -277.550214) (xy 313.808346 -277.563906) (xy 313.852808 -277.585004)
			(xy 313.893311 -277.61296) (xy 313.928804 -277.647052) (xy 313.958369 -277.686396) (xy 313.98124 -277.729973)
			(xy 313.996824 -277.776654) (xy 314.004719 -277.825231) (xy 314.005214 -277.849838) (xy 314.344062 -277.849838)
			(xy 314.348022 -277.800784) (xy 314.359799 -277.753) (xy 314.37909 -277.707724) (xy 314.405393 -277.666128)
			(xy 314.438028 -277.629291) (xy 314.476149 -277.598166) (xy 314.51877 -277.573559) (xy 314.564786 -277.556107)
			(xy 314.613005 -277.546263) (xy 314.66218 -277.544282) (xy 314.711035 -277.550214) (xy 314.758306 -277.563906)
			(xy 314.802768 -277.585004) (xy 314.843271 -277.61296) (xy 314.878764 -277.647052) (xy 314.908329 -277.686396)
			(xy 314.9312 -277.729973) (xy 314.946784 -277.776654) (xy 314.954679 -277.825231) (xy 314.955174 -277.849838)
			(xy 314.954679 -277.874445) (xy 314.946784 -277.923022) (xy 314.9312 -277.969703) (xy 314.908329 -278.01328)
			(xy 314.878764 -278.052624) (xy 314.843271 -278.086716) (xy 314.802768 -278.114672) (xy 314.758306 -278.13577)
			(xy 314.711035 -278.149462) (xy 314.66218 -278.155394) (xy 314.613005 -278.153413) (xy 314.564786 -278.143569)
			(xy 314.51877 -278.126117) (xy 314.476149 -278.10151) (xy 314.438028 -278.070385) (xy 314.405393 -278.033548)
			(xy 314.37909 -277.991952) (xy 314.359799 -277.946676) (xy 314.348022 -277.898892) (xy 314.344062 -277.849838)
			(xy 314.005214 -277.849838) (xy 314.004719 -277.874445) (xy 313.996824 -277.923022) (xy 313.98124 -277.969703)
			(xy 313.958369 -278.01328) (xy 313.928804 -278.052624) (xy 313.893311 -278.086716) (xy 313.852808 -278.114672)
			(xy 313.808346 -278.13577) (xy 313.761075 -278.149462) (xy 313.71222 -278.155394) (xy 313.663045 -278.153413)
			(xy 313.614826 -278.143569) (xy 313.56881 -278.126117) (xy 313.526189 -278.10151) (xy 313.488068 -278.070385)
			(xy 313.455433 -278.033548) (xy 313.42913 -277.991952) (xy 313.409839 -277.946676) (xy 313.398062 -277.898892)
			(xy 313.394102 -277.849838) (xy 313.076844 -277.849838) (xy 313.07634 -277.875546) (xy 313.068297 -277.926328)
			(xy 313.052409 -277.975227) (xy 313.029066 -278.021039) (xy 312.998845 -278.062635) (xy 312.962489 -278.098991)
			(xy 312.920893 -278.129212) (xy 312.875081 -278.152555) (xy 312.826182 -278.168443) (xy 312.7754 -278.176486)
			(xy 312.723984 -278.176486) (xy 312.673202 -278.168443) (xy 312.624303 -278.152555) (xy 312.578491 -278.129212)
			(xy 312.536895 -278.098991) (xy 312.500539 -278.062635) (xy 312.470318 -278.021039) (xy 312.446975 -277.975227)
			(xy 312.431087 -277.926328) (xy 312.423044 -277.875546) (xy 312.104366 -277.875546) (xy 312.09665 -277.923022)
			(xy 312.081066 -277.969703) (xy 312.058195 -278.01328) (xy 312.02863 -278.052624) (xy 311.993137 -278.086716)
			(xy 311.952634 -278.114672) (xy 311.908172 -278.13577) (xy 311.860901 -278.149462) (xy 311.812046 -278.155394)
			(xy 311.762871 -278.153413) (xy 311.714652 -278.143569) (xy 311.668636 -278.126117) (xy 311.626015 -278.10151)
			(xy 311.587894 -278.070385) (xy 311.555259 -278.033548) (xy 311.528956 -277.991952) (xy 311.509665 -277.946676)
			(xy 311.497888 -277.898892) (xy 311.493928 -277.849838) (xy 311.17667 -277.849838) (xy 311.176166 -277.875546)
			(xy 311.168123 -277.926328) (xy 311.152235 -277.975227) (xy 311.128892 -278.021039) (xy 311.098671 -278.062635)
			(xy 311.062315 -278.098991) (xy 311.020719 -278.129212) (xy 310.974907 -278.152555) (xy 310.926008 -278.168443)
			(xy 310.875226 -278.176486) (xy 310.82381 -278.176486) (xy 310.773028 -278.168443) (xy 310.724129 -278.152555)
			(xy 310.678317 -278.129212) (xy 310.636721 -278.098991) (xy 310.600365 -278.062635) (xy 310.570144 -278.021039)
			(xy 310.546801 -277.975227) (xy 310.530913 -277.926328) (xy 310.52287 -277.875546) (xy 310.204446 -277.875546)
			(xy 310.19673 -277.923022) (xy 310.181146 -277.969703) (xy 310.158275 -278.01328) (xy 310.12871 -278.052624)
			(xy 310.093217 -278.086716) (xy 310.052714 -278.114672) (xy 310.008252 -278.13577) (xy 309.960981 -278.149462)
			(xy 309.912126 -278.155394) (xy 309.862951 -278.153413) (xy 309.814732 -278.143569) (xy 309.768716 -278.126117)
			(xy 309.726095 -278.10151) (xy 309.687974 -278.070385) (xy 309.655339 -278.033548) (xy 309.629036 -277.991952)
			(xy 309.609745 -277.946676) (xy 309.597968 -277.898892) (xy 309.594008 -277.849838) (xy 309.27675 -277.849838)
			(xy 309.276246 -277.875546) (xy 309.268203 -277.926328) (xy 309.252315 -277.975227) (xy 309.228972 -278.021039)
			(xy 309.198751 -278.062635) (xy 309.162395 -278.098991) (xy 309.120799 -278.129212) (xy 309.074987 -278.152555)
			(xy 309.026088 -278.168443) (xy 308.975306 -278.176486) (xy 308.92389 -278.176486) (xy 308.873108 -278.168443)
			(xy 308.824209 -278.152555) (xy 308.778397 -278.129212) (xy 308.736801 -278.098991) (xy 308.700445 -278.062635)
			(xy 308.670224 -278.021039) (xy 308.646881 -277.975227) (xy 308.630993 -277.926328) (xy 308.62295 -277.875546)
			(xy 308.304526 -277.875546) (xy 308.29681 -277.923022) (xy 308.281226 -277.969703) (xy 308.258355 -278.01328)
			(xy 308.22879 -278.052624) (xy 308.193297 -278.086716) (xy 308.152794 -278.114672) (xy 308.108332 -278.13577)
			(xy 308.061061 -278.149462) (xy 308.012206 -278.155394) (xy 307.963031 -278.153413) (xy 307.914812 -278.143569)
			(xy 307.868796 -278.126117) (xy 307.826175 -278.10151) (xy 307.788054 -278.070385) (xy 307.755419 -278.033548)
			(xy 307.729116 -277.991952) (xy 307.709825 -277.946676) (xy 307.698048 -277.898892) (xy 307.694088 -277.849838)
			(xy 307.37683 -277.849838) (xy 307.376326 -277.875546) (xy 307.368283 -277.926328) (xy 307.352395 -277.975227)
			(xy 307.329052 -278.021039) (xy 307.298831 -278.062635) (xy 307.262475 -278.098991) (xy 307.220879 -278.129212)
			(xy 307.175067 -278.152555) (xy 307.126168 -278.168443) (xy 307.075386 -278.176486) (xy 307.02397 -278.176486)
			(xy 306.973188 -278.168443) (xy 306.924289 -278.152555) (xy 306.878477 -278.129212) (xy 306.836881 -278.098991)
			(xy 306.800525 -278.062635) (xy 306.770304 -278.021039) (xy 306.746961 -277.975227) (xy 306.731073 -277.926328)
			(xy 306.72303 -277.875546) (xy 306.404352 -277.875546) (xy 306.396636 -277.923022) (xy 306.381052 -277.969703)
			(xy 306.358181 -278.01328) (xy 306.328616 -278.052624) (xy 306.293123 -278.086716) (xy 306.25262 -278.114672)
			(xy 306.208158 -278.13577) (xy 306.160887 -278.149462) (xy 306.112032 -278.155394) (xy 306.062857 -278.153413)
			(xy 306.014638 -278.143569) (xy 305.968622 -278.126117) (xy 305.926001 -278.10151) (xy 305.88788 -278.070385)
			(xy 305.855245 -278.033548) (xy 305.828942 -277.991952) (xy 305.809651 -277.946676) (xy 305.797874 -277.898892)
			(xy 305.793914 -277.849838) (xy 305.476656 -277.849838) (xy 305.476152 -277.875546) (xy 305.468109 -277.926328)
			(xy 305.452221 -277.975227) (xy 305.428878 -278.021039) (xy 305.398657 -278.062635) (xy 305.362301 -278.098991)
			(xy 305.320705 -278.129212) (xy 305.274893 -278.152555) (xy 305.225994 -278.168443) (xy 305.175212 -278.176486)
			(xy 305.123796 -278.176486) (xy 305.073014 -278.168443) (xy 305.024115 -278.152555) (xy 304.978303 -278.129212)
			(xy 304.936707 -278.098991) (xy 304.900351 -278.062635) (xy 304.87013 -278.021039) (xy 304.846787 -277.975227)
			(xy 304.830899 -277.926328) (xy 304.822856 -277.875546) (xy 304.504432 -277.875546) (xy 304.496716 -277.923022)
			(xy 304.481132 -277.969703) (xy 304.458261 -278.01328) (xy 304.428696 -278.052624) (xy 304.393203 -278.086716)
			(xy 304.3527 -278.114672) (xy 304.308238 -278.13577) (xy 304.260967 -278.149462) (xy 304.212112 -278.155394)
			(xy 304.162937 -278.153413) (xy 304.114718 -278.143569) (xy 304.068702 -278.126117) (xy 304.026081 -278.10151)
			(xy 303.98796 -278.070385) (xy 303.955325 -278.033548) (xy 303.929022 -277.991952) (xy 303.909731 -277.946676)
			(xy 303.897954 -277.898892) (xy 303.893994 -277.849838) (xy 303.576736 -277.849838) (xy 303.576232 -277.875546)
			(xy 303.568189 -277.926328) (xy 303.552301 -277.975227) (xy 303.528958 -278.021039) (xy 303.498737 -278.062635)
			(xy 303.462381 -278.098991) (xy 303.420785 -278.129212) (xy 303.374973 -278.152555) (xy 303.326074 -278.168443)
			(xy 303.275292 -278.176486) (xy 303.223876 -278.176486) (xy 303.173094 -278.168443) (xy 303.124195 -278.152555)
			(xy 303.078383 -278.129212) (xy 303.036787 -278.098991) (xy 303.000431 -278.062635) (xy 302.97021 -278.021039)
			(xy 302.946867 -277.975227) (xy 302.930979 -277.926328) (xy 302.922936 -277.875546) (xy 302.604512 -277.875546)
			(xy 302.596796 -277.923022) (xy 302.581212 -277.969703) (xy 302.558341 -278.01328) (xy 302.528776 -278.052624)
			(xy 302.493283 -278.086716) (xy 302.45278 -278.114672) (xy 302.408318 -278.13577) (xy 302.361047 -278.149462)
			(xy 302.312192 -278.155394) (xy 302.263017 -278.153413) (xy 302.214798 -278.143569) (xy 302.168782 -278.126117)
			(xy 302.126161 -278.10151) (xy 302.08804 -278.070385) (xy 302.055405 -278.033548) (xy 302.029102 -277.991952)
			(xy 302.009811 -277.946676) (xy 301.998034 -277.898892) (xy 301.994074 -277.849838) (xy 301.676816 -277.849838)
			(xy 301.676312 -277.875546) (xy 301.668269 -277.926328) (xy 301.652381 -277.975227) (xy 301.629038 -278.021039)
			(xy 301.598817 -278.062635) (xy 301.562461 -278.098991) (xy 301.520865 -278.129212) (xy 301.475053 -278.152555)
			(xy 301.426154 -278.168443) (xy 301.375372 -278.176486) (xy 301.323956 -278.176486) (xy 301.273174 -278.168443)
			(xy 301.224275 -278.152555) (xy 301.178463 -278.129212) (xy 301.136867 -278.098991) (xy 301.100511 -278.062635)
			(xy 301.07029 -278.021039) (xy 301.046947 -277.975227) (xy 301.031059 -277.926328) (xy 301.023016 -277.875546)
			(xy 300.704338 -277.875546) (xy 300.696622 -277.923022) (xy 300.681038 -277.969703) (xy 300.658167 -278.01328)
			(xy 300.628602 -278.052624) (xy 300.593109 -278.086716) (xy 300.552606 -278.114672) (xy 300.508144 -278.13577)
			(xy 300.460873 -278.149462) (xy 300.412018 -278.155394) (xy 300.362843 -278.153413) (xy 300.314624 -278.143569)
			(xy 300.268608 -278.126117) (xy 300.225987 -278.10151) (xy 300.187866 -278.070385) (xy 300.155231 -278.033548)
			(xy 300.128928 -277.991952) (xy 300.109637 -277.946676) (xy 300.09786 -277.898892) (xy 300.0939 -277.849838)
			(xy 299.776642 -277.849838) (xy 299.776138 -277.875546) (xy 299.768095 -277.926328) (xy 299.752207 -277.975227)
			(xy 299.728864 -278.021039) (xy 299.698643 -278.062635) (xy 299.662287 -278.098991) (xy 299.620691 -278.129212)
			(xy 299.574879 -278.152555) (xy 299.52598 -278.168443) (xy 299.475198 -278.176486) (xy 299.423782 -278.176486)
			(xy 299.373 -278.168443) (xy 299.324101 -278.152555) (xy 299.278289 -278.129212) (xy 299.236693 -278.098991)
			(xy 299.200337 -278.062635) (xy 299.170116 -278.021039) (xy 299.146773 -277.975227) (xy 299.130885 -277.926328)
			(xy 299.122842 -277.875546) (xy 298.804418 -277.875546) (xy 298.796702 -277.923022) (xy 298.781118 -277.969703)
			(xy 298.758247 -278.01328) (xy 298.728682 -278.052624) (xy 298.693189 -278.086716) (xy 298.652686 -278.114672)
			(xy 298.608224 -278.13577) (xy 298.560953 -278.149462) (xy 298.512098 -278.155394) (xy 298.462923 -278.153413)
			(xy 298.414704 -278.143569) (xy 298.368688 -278.126117) (xy 298.326067 -278.10151) (xy 298.287946 -278.070385)
			(xy 298.255311 -278.033548) (xy 298.229008 -277.991952) (xy 298.209717 -277.946676) (xy 298.19794 -277.898892)
			(xy 298.19398 -277.849838) (xy 297.876722 -277.849838) (xy 297.876218 -277.875546) (xy 297.868175 -277.926328)
			(xy 297.852287 -277.975227) (xy 297.828944 -278.021039) (xy 297.798723 -278.062635) (xy 297.762367 -278.098991)
			(xy 297.720771 -278.129212) (xy 297.674959 -278.152555) (xy 297.62606 -278.168443) (xy 297.575278 -278.176486)
			(xy 297.523862 -278.176486) (xy 297.47308 -278.168443) (xy 297.424181 -278.152555) (xy 297.378369 -278.129212)
			(xy 297.336773 -278.098991) (xy 297.300417 -278.062635) (xy 297.270196 -278.021039) (xy 297.246853 -277.975227)
			(xy 297.230965 -277.926328) (xy 297.222922 -277.875546) (xy 296.904498 -277.875546) (xy 296.896782 -277.923022)
			(xy 296.881198 -277.969703) (xy 296.858327 -278.01328) (xy 296.828762 -278.052624) (xy 296.793269 -278.086716)
			(xy 296.752766 -278.114672) (xy 296.708304 -278.13577) (xy 296.661033 -278.149462) (xy 296.612178 -278.155394)
			(xy 296.563003 -278.153413) (xy 296.514784 -278.143569) (xy 296.468768 -278.126117) (xy 296.426147 -278.10151)
			(xy 296.388026 -278.070385) (xy 296.355391 -278.033548) (xy 296.329088 -277.991952) (xy 296.309797 -277.946676)
			(xy 296.29802 -277.898892) (xy 296.29406 -277.849838) (xy 295.976802 -277.849838) (xy 295.976298 -277.875546)
			(xy 295.968255 -277.926328) (xy 295.952367 -277.975227) (xy 295.929024 -278.021039) (xy 295.898803 -278.062635)
			(xy 295.862447 -278.098991) (xy 295.820851 -278.129212) (xy 295.775039 -278.152555) (xy 295.72614 -278.168443)
			(xy 295.675358 -278.176486) (xy 295.623942 -278.176486) (xy 295.57316 -278.168443) (xy 295.524261 -278.152555)
			(xy 295.478449 -278.129212) (xy 295.436853 -278.098991) (xy 295.400497 -278.062635) (xy 295.370276 -278.021039)
			(xy 295.346933 -277.975227) (xy 295.331045 -277.926328) (xy 295.323002 -277.875546) (xy 295.004324 -277.875546)
			(xy 294.996608 -277.923022) (xy 294.981024 -277.969703) (xy 294.958153 -278.01328) (xy 294.928588 -278.052624)
			(xy 294.893095 -278.086716) (xy 294.852592 -278.114672) (xy 294.80813 -278.13577) (xy 294.760859 -278.149462)
			(xy 294.712004 -278.155394) (xy 294.662829 -278.153413) (xy 294.61461 -278.143569) (xy 294.568594 -278.126117)
			(xy 294.525973 -278.10151) (xy 294.487852 -278.070385) (xy 294.455217 -278.033548) (xy 294.428914 -277.991952)
			(xy 294.409623 -277.946676) (xy 294.397846 -277.898892) (xy 294.393886 -277.849838) (xy 294.076628 -277.849838)
			(xy 294.076124 -277.875546) (xy 294.068081 -277.926328) (xy 294.052193 -277.975227) (xy 294.02885 -278.021039)
			(xy 293.998629 -278.062635) (xy 293.962273 -278.098991) (xy 293.920677 -278.129212) (xy 293.874865 -278.152555)
			(xy 293.825966 -278.168443) (xy 293.775184 -278.176486) (xy 293.723768 -278.176486) (xy 293.672986 -278.168443)
			(xy 293.624087 -278.152555) (xy 293.578275 -278.129212) (xy 293.536679 -278.098991) (xy 293.500323 -278.062635)
			(xy 293.470102 -278.021039) (xy 293.446759 -277.975227) (xy 293.430871 -277.926328) (xy 293.422828 -277.875546)
			(xy 293.104404 -277.875546) (xy 293.096688 -277.923022) (xy 293.081104 -277.969703) (xy 293.058233 -278.01328)
			(xy 293.028668 -278.052624) (xy 292.993175 -278.086716) (xy 292.952672 -278.114672) (xy 292.90821 -278.13577)
			(xy 292.860939 -278.149462) (xy 292.812084 -278.155394) (xy 292.762909 -278.153413) (xy 292.71469 -278.143569)
			(xy 292.668674 -278.126117) (xy 292.626053 -278.10151) (xy 292.587932 -278.070385) (xy 292.555297 -278.033548)
			(xy 292.528994 -277.991952) (xy 292.509703 -277.946676) (xy 292.497926 -277.898892) (xy 292.493966 -277.849838)
			(xy 292.176708 -277.849838) (xy 292.176204 -277.875546) (xy 292.168161 -277.926328) (xy 292.152273 -277.975227)
			(xy 292.12893 -278.021039) (xy 292.098709 -278.062635) (xy 292.062353 -278.098991) (xy 292.020757 -278.129212)
			(xy 291.974945 -278.152555) (xy 291.926046 -278.168443) (xy 291.875264 -278.176486) (xy 291.823848 -278.176486)
			(xy 291.773066 -278.168443) (xy 291.724167 -278.152555) (xy 291.678355 -278.129212) (xy 291.636759 -278.098991)
			(xy 291.600403 -278.062635) (xy 291.570182 -278.021039) (xy 291.546839 -277.975227) (xy 291.530951 -277.926328)
			(xy 291.522908 -277.875546) (xy 291.204484 -277.875546) (xy 291.196768 -277.923022) (xy 291.181184 -277.969703)
			(xy 291.158313 -278.01328) (xy 291.128748 -278.052624) (xy 291.093255 -278.086716) (xy 291.052752 -278.114672)
			(xy 291.00829 -278.13577) (xy 290.961019 -278.149462) (xy 290.912164 -278.155394) (xy 290.862989 -278.153413)
			(xy 290.81477 -278.143569) (xy 290.768754 -278.126117) (xy 290.726133 -278.10151) (xy 290.688012 -278.070385)
			(xy 290.655377 -278.033548) (xy 290.629074 -277.991952) (xy 290.609783 -277.946676) (xy 290.598006 -277.898892)
			(xy 290.594046 -277.849838) (xy 290.277042 -277.849838) (xy 290.276538 -277.875546) (xy 290.268495 -277.926328)
			(xy 290.252607 -277.975227) (xy 290.229264 -278.021039) (xy 290.199043 -278.062635) (xy 290.162687 -278.098991)
			(xy 290.121091 -278.129212) (xy 290.075279 -278.152555) (xy 290.02638 -278.168443) (xy 289.975598 -278.176486)
			(xy 289.924182 -278.176486) (xy 289.8734 -278.168443) (xy 289.824501 -278.152555) (xy 289.778689 -278.129212)
			(xy 289.737093 -278.098991) (xy 289.700737 -278.062635) (xy 289.670516 -278.021039) (xy 289.647173 -277.975227)
			(xy 289.631285 -277.926328) (xy 289.623242 -277.875546) (xy 289.304564 -277.875546) (xy 289.296848 -277.923022)
			(xy 289.281264 -277.969703) (xy 289.258393 -278.01328) (xy 289.228828 -278.052624) (xy 289.193335 -278.086716)
			(xy 289.152832 -278.114672) (xy 289.10837 -278.13577) (xy 289.061099 -278.149462) (xy 289.012244 -278.155394)
			(xy 288.963069 -278.153413) (xy 288.91485 -278.143569) (xy 288.868834 -278.126117) (xy 288.826213 -278.10151)
			(xy 288.788092 -278.070385) (xy 288.755457 -278.033548) (xy 288.729154 -277.991952) (xy 288.709863 -277.946676)
			(xy 288.698086 -277.898892) (xy 288.694126 -277.849838) (xy 288.376868 -277.849838) (xy 288.376364 -277.875546)
			(xy 288.368321 -277.926328) (xy 288.352433 -277.975227) (xy 288.32909 -278.021039) (xy 288.298869 -278.062635)
			(xy 288.262513 -278.098991) (xy 288.220917 -278.129212) (xy 288.175105 -278.152555) (xy 288.126206 -278.168443)
			(xy 288.075424 -278.176486) (xy 288.024008 -278.176486) (xy 287.973226 -278.168443) (xy 287.924327 -278.152555)
			(xy 287.878515 -278.129212) (xy 287.836919 -278.098991) (xy 287.800563 -278.062635) (xy 287.770342 -278.021039)
			(xy 287.746999 -277.975227) (xy 287.731111 -277.926328) (xy 287.723068 -277.875546) (xy 287.40439 -277.875546)
			(xy 287.396674 -277.923022) (xy 287.38109 -277.969703) (xy 287.358219 -278.01328) (xy 287.328654 -278.052624)
			(xy 287.293161 -278.086716) (xy 287.252658 -278.114672) (xy 287.208196 -278.13577) (xy 287.160925 -278.149462)
			(xy 287.11207 -278.155394) (xy 287.062895 -278.153413) (xy 287.014676 -278.143569) (xy 286.96866 -278.126117)
			(xy 286.926039 -278.10151) (xy 286.887918 -278.070385) (xy 286.855283 -278.033548) (xy 286.82898 -277.991952)
			(xy 286.809689 -277.946676) (xy 286.797912 -277.898892) (xy 286.793952 -277.849838) (xy 286.476948 -277.849838)
			(xy 286.476444 -277.875546) (xy 286.468401 -277.926328) (xy 286.452513 -277.975227) (xy 286.42917 -278.021039)
			(xy 286.398949 -278.062635) (xy 286.362593 -278.098991) (xy 286.320997 -278.129212) (xy 286.275185 -278.152555)
			(xy 286.226286 -278.168443) (xy 286.175504 -278.176486) (xy 286.124088 -278.176486) (xy 286.073306 -278.168443)
			(xy 286.024407 -278.152555) (xy 285.978595 -278.129212) (xy 285.936999 -278.098991) (xy 285.900643 -278.062635)
			(xy 285.870422 -278.021039) (xy 285.847079 -277.975227) (xy 285.831191 -277.926328) (xy 285.823148 -277.875546)
			(xy 285.50447 -277.875546) (xy 285.496754 -277.923022) (xy 285.48117 -277.969703) (xy 285.458299 -278.01328)
			(xy 285.428734 -278.052624) (xy 285.393241 -278.086716) (xy 285.352738 -278.114672) (xy 285.308276 -278.13577)
			(xy 285.261005 -278.149462) (xy 285.21215 -278.155394) (xy 285.162975 -278.153413) (xy 285.114756 -278.143569)
			(xy 285.06874 -278.126117) (xy 285.026119 -278.10151) (xy 284.987998 -278.070385) (xy 284.955363 -278.033548)
			(xy 284.92906 -277.991952) (xy 284.909769 -277.946676) (xy 284.897992 -277.898892) (xy 284.894032 -277.849838)
			(xy 284.577028 -277.849838) (xy 284.576524 -277.875546) (xy 284.568481 -277.926328) (xy 284.552593 -277.975227)
			(xy 284.52925 -278.021039) (xy 284.499029 -278.062635) (xy 284.462673 -278.098991) (xy 284.421077 -278.129212)
			(xy 284.375265 -278.152555) (xy 284.326366 -278.168443) (xy 284.275584 -278.176486) (xy 284.224168 -278.176486)
			(xy 284.173386 -278.168443) (xy 284.124487 -278.152555) (xy 284.078675 -278.129212) (xy 284.037079 -278.098991)
			(xy 284.000723 -278.062635) (xy 283.970502 -278.021039) (xy 283.947159 -277.975227) (xy 283.931271 -277.926328)
			(xy 283.923228 -277.875546) (xy 283.60455 -277.875546) (xy 283.596834 -277.923022) (xy 283.58125 -277.969703)
			(xy 283.558379 -278.01328) (xy 283.528814 -278.052624) (xy 283.493321 -278.086716) (xy 283.452818 -278.114672)
			(xy 283.408356 -278.13577) (xy 283.361085 -278.149462) (xy 283.31223 -278.155394) (xy 283.263055 -278.153413)
			(xy 283.214836 -278.143569) (xy 283.16882 -278.126117) (xy 283.126199 -278.10151) (xy 283.088078 -278.070385)
			(xy 283.055443 -278.033548) (xy 283.02914 -277.991952) (xy 283.009849 -277.946676) (xy 282.998072 -277.898892)
			(xy 282.994112 -277.849838) (xy 282.676854 -277.849838) (xy 282.67635 -277.875546) (xy 282.668307 -277.926328)
			(xy 282.652419 -277.975227) (xy 282.629076 -278.021039) (xy 282.598855 -278.062635) (xy 282.562499 -278.098991)
			(xy 282.520903 -278.129212) (xy 282.475091 -278.152555) (xy 282.426192 -278.168443) (xy 282.37541 -278.176486)
			(xy 282.323994 -278.176486) (xy 282.273212 -278.168443) (xy 282.224313 -278.152555) (xy 282.178501 -278.129212)
			(xy 282.136905 -278.098991) (xy 282.100549 -278.062635) (xy 282.070328 -278.021039) (xy 282.046985 -277.975227)
			(xy 282.031097 -277.926328) (xy 282.023054 -277.875546) (xy 281.704376 -277.875546) (xy 281.69666 -277.923022)
			(xy 281.681076 -277.969703) (xy 281.658205 -278.01328) (xy 281.62864 -278.052624) (xy 281.593147 -278.086716)
			(xy 281.552644 -278.114672) (xy 281.508182 -278.13577) (xy 281.460911 -278.149462) (xy 281.412056 -278.155394)
			(xy 281.362881 -278.153413) (xy 281.314662 -278.143569) (xy 281.268646 -278.126117) (xy 281.226025 -278.10151)
			(xy 281.187904 -278.070385) (xy 281.155269 -278.033548) (xy 281.128966 -277.991952) (xy 281.109675 -277.946676)
			(xy 281.097898 -277.898892) (xy 281.093938 -277.849838) (xy 280.776934 -277.849838) (xy 280.77643 -277.875546)
			(xy 280.768387 -277.926328) (xy 280.752499 -277.975227) (xy 280.729156 -278.021039) (xy 280.698935 -278.062635)
			(xy 280.662579 -278.098991) (xy 280.620983 -278.129212) (xy 280.575171 -278.152555) (xy 280.526272 -278.168443)
			(xy 280.47549 -278.176486) (xy 280.424074 -278.176486) (xy 280.373292 -278.168443) (xy 280.324393 -278.152555)
			(xy 280.278581 -278.129212) (xy 280.236985 -278.098991) (xy 280.200629 -278.062635) (xy 280.170408 -278.021039)
			(xy 280.147065 -277.975227) (xy 280.131177 -277.926328) (xy 280.123134 -277.875546) (xy 279.804456 -277.875546)
			(xy 279.79674 -277.923022) (xy 279.781156 -277.969703) (xy 279.758285 -278.01328) (xy 279.72872 -278.052624)
			(xy 279.693227 -278.086716) (xy 279.652724 -278.114672) (xy 279.608262 -278.13577) (xy 279.560991 -278.149462)
			(xy 279.512136 -278.155394) (xy 279.462961 -278.153413) (xy 279.414742 -278.143569) (xy 279.368726 -278.126117)
			(xy 279.326105 -278.10151) (xy 279.287984 -278.070385) (xy 279.255349 -278.033548) (xy 279.229046 -277.991952)
			(xy 279.209755 -277.946676) (xy 279.197978 -277.898892) (xy 279.194018 -277.849838) (xy 278.877014 -277.849838)
			(xy 278.87651 -277.875546) (xy 278.868467 -277.926328) (xy 278.852579 -277.975227) (xy 278.829236 -278.021039)
			(xy 278.799015 -278.062635) (xy 278.762659 -278.098991) (xy 278.721063 -278.129212) (xy 278.675251 -278.152555)
			(xy 278.626352 -278.168443) (xy 278.57557 -278.176486) (xy 278.524154 -278.176486) (xy 278.473372 -278.168443)
			(xy 278.424473 -278.152555) (xy 278.378661 -278.129212) (xy 278.337065 -278.098991) (xy 278.300709 -278.062635)
			(xy 278.270488 -278.021039) (xy 278.247145 -277.975227) (xy 278.231257 -277.926328) (xy 278.223214 -277.875546)
			(xy 277.904536 -277.875546) (xy 277.89682 -277.923022) (xy 277.881236 -277.969703) (xy 277.858365 -278.01328)
			(xy 277.8288 -278.052624) (xy 277.793307 -278.086716) (xy 277.752804 -278.114672) (xy 277.708342 -278.13577)
			(xy 277.661071 -278.149462) (xy 277.612216 -278.155394) (xy 277.563041 -278.153413) (xy 277.514822 -278.143569)
			(xy 277.468806 -278.126117) (xy 277.426185 -278.10151) (xy 277.388064 -278.070385) (xy 277.355429 -278.033548)
			(xy 277.329126 -277.991952) (xy 277.309835 -277.946676) (xy 277.298058 -277.898892) (xy 277.294098 -277.849838)
			(xy 276.97684 -277.849838) (xy 276.976336 -277.875546) (xy 276.968293 -277.926328) (xy 276.952405 -277.975227)
			(xy 276.929062 -278.021039) (xy 276.898841 -278.062635) (xy 276.862485 -278.098991) (xy 276.820889 -278.129212)
			(xy 276.775077 -278.152555) (xy 276.726178 -278.168443) (xy 276.675396 -278.176486) (xy 276.62398 -278.176486)
			(xy 276.573198 -278.168443) (xy 276.524299 -278.152555) (xy 276.478487 -278.129212) (xy 276.436891 -278.098991)
			(xy 276.400535 -278.062635) (xy 276.370314 -278.021039) (xy 276.346971 -277.975227) (xy 276.331083 -277.926328)
			(xy 276.32304 -277.875546) (xy 249.28048 -277.875546) (xy 249.279079 -277.876401) (xy 249.22775 -277.898213)
			(xy 249.173793 -277.912319) (xy 249.118356 -277.918419) (xy 249.062622 -277.916382) (xy 249.007779 -277.906252)
			(xy 248.954995 -277.888245) (xy 248.905395 -277.862744) (xy 248.860037 -277.830293) (xy 248.819888 -277.791584)
			(xy 248.785802 -277.747441) (xy 248.758506 -277.698806) (xy 248.738583 -277.646715) (xy 248.726457 -277.592278)
			(xy 248.722386 -277.536656) (xy 247.370277 -277.536656) (xy 247.390907 -277.560465) (xy 247.420373 -277.606315)
			(xy 247.443015 -277.655892) (xy 247.45837 -277.708187) (xy 247.466126 -277.762135) (xy 247.466612 -277.789386)
			(xy 247.466141 -277.81598) (xy 247.458749 -277.868651) (xy 247.44412 -277.919787) (xy 247.422536 -277.968398)
			(xy 247.394416 -278.013544) (xy 247.377712 -278.034242) (xy 247.371108 -278.042116) (xy 247.365266 -278.061166)
			(xy 247.373902 -278.153622) (xy 247.3833 -278.171402) (xy 247.391174 -278.177752) (xy 247.414481 -278.197476)
			(xy 247.456487 -278.241788) (xy 247.492569 -278.291043) (xy 247.511275 -278.324818) (xy 268.26897 -278.324818)
			(xy 268.27293 -278.275764) (xy 268.284707 -278.22798) (xy 268.303998 -278.182704) (xy 268.330301 -278.141108)
			(xy 268.362936 -278.104271) (xy 268.401057 -278.073146) (xy 268.443678 -278.048539) (xy 268.489694 -278.031087)
			(xy 268.537913 -278.021243) (xy 268.587088 -278.019262) (xy 268.635943 -278.025194) (xy 268.683214 -278.038886)
			(xy 268.727676 -278.059984) (xy 268.768179 -278.08794) (xy 268.803672 -278.122032) (xy 268.833237 -278.161376)
			(xy 268.856108 -278.204953) (xy 268.871692 -278.251634) (xy 268.879587 -278.300211) (xy 268.880082 -278.324818)
			(xy 269.21893 -278.324818) (xy 269.22289 -278.275764) (xy 269.234667 -278.22798) (xy 269.253958 -278.182704)
			(xy 269.280261 -278.141108) (xy 269.312896 -278.104271) (xy 269.351017 -278.073146) (xy 269.393638 -278.048539)
			(xy 269.439654 -278.031087) (xy 269.487873 -278.021243) (xy 269.537048 -278.019262) (xy 269.585903 -278.025194)
			(xy 269.633174 -278.038886) (xy 269.677636 -278.059984) (xy 269.718139 -278.08794) (xy 269.753632 -278.122032)
			(xy 269.783197 -278.161376) (xy 269.806068 -278.204953) (xy 269.821652 -278.251634) (xy 269.829547 -278.300211)
			(xy 269.830042 -278.324818) (xy 270.169144 -278.324818) (xy 270.173104 -278.275764) (xy 270.184881 -278.22798)
			(xy 270.204172 -278.182704) (xy 270.230475 -278.141108) (xy 270.26311 -278.104271) (xy 270.301231 -278.073146)
			(xy 270.343852 -278.048539) (xy 270.389868 -278.031087) (xy 270.438087 -278.021243) (xy 270.487262 -278.019262)
			(xy 270.536117 -278.025194) (xy 270.583388 -278.038886) (xy 270.62785 -278.059984) (xy 270.668353 -278.08794)
			(xy 270.703846 -278.122032) (xy 270.733411 -278.161376) (xy 270.756282 -278.204953) (xy 270.771866 -278.251634)
			(xy 270.779761 -278.300211) (xy 270.780256 -278.324818) (xy 271.119104 -278.324818) (xy 271.123064 -278.275764)
			(xy 271.134841 -278.22798) (xy 271.154132 -278.182704) (xy 271.180435 -278.141108) (xy 271.21307 -278.104271)
			(xy 271.251191 -278.073146) (xy 271.293812 -278.048539) (xy 271.339828 -278.031087) (xy 271.388047 -278.021243)
			(xy 271.437222 -278.019262) (xy 271.486077 -278.025194) (xy 271.533348 -278.038886) (xy 271.57781 -278.059984)
			(xy 271.618313 -278.08794) (xy 271.653806 -278.122032) (xy 271.683371 -278.161376) (xy 271.706242 -278.204953)
			(xy 271.721826 -278.251634) (xy 271.729721 -278.300211) (xy 271.730216 -278.324818) (xy 272.069064 -278.324818)
			(xy 272.073024 -278.275764) (xy 272.084801 -278.22798) (xy 272.104092 -278.182704) (xy 272.130395 -278.141108)
			(xy 272.16303 -278.104271) (xy 272.201151 -278.073146) (xy 272.243772 -278.048539) (xy 272.289788 -278.031087)
			(xy 272.338007 -278.021243) (xy 272.387182 -278.019262) (xy 272.436037 -278.025194) (xy 272.483308 -278.038886)
			(xy 272.52777 -278.059984) (xy 272.568273 -278.08794) (xy 272.603766 -278.122032) (xy 272.633331 -278.161376)
			(xy 272.656202 -278.204953) (xy 272.671786 -278.251634) (xy 272.679681 -278.300211) (xy 272.680176 -278.324818)
			(xy 273.019024 -278.324818) (xy 273.022984 -278.275764) (xy 273.034761 -278.22798) (xy 273.054052 -278.182704)
			(xy 273.080355 -278.141108) (xy 273.11299 -278.104271) (xy 273.151111 -278.073146) (xy 273.193732 -278.048539)
			(xy 273.239748 -278.031087) (xy 273.287967 -278.021243) (xy 273.337142 -278.019262) (xy 273.385997 -278.025194)
			(xy 273.433268 -278.038886) (xy 273.47773 -278.059984) (xy 273.518233 -278.08794) (xy 273.553726 -278.122032)
			(xy 273.583291 -278.161376) (xy 273.606162 -278.204953) (xy 273.621746 -278.251634) (xy 273.629641 -278.300211)
			(xy 273.630136 -278.324818) (xy 273.968984 -278.324818) (xy 273.972944 -278.275764) (xy 273.984721 -278.22798)
			(xy 274.004012 -278.182704) (xy 274.030315 -278.141108) (xy 274.06295 -278.104271) (xy 274.101071 -278.073146)
			(xy 274.143692 -278.048539) (xy 274.189708 -278.031087) (xy 274.237927 -278.021243) (xy 274.287102 -278.019262)
			(xy 274.335957 -278.025194) (xy 274.383228 -278.038886) (xy 274.42769 -278.059984) (xy 274.468193 -278.08794)
			(xy 274.503686 -278.122032) (xy 274.533251 -278.161376) (xy 274.556122 -278.204953) (xy 274.571706 -278.251634)
			(xy 274.579601 -278.300211) (xy 274.580096 -278.324818) (xy 274.918944 -278.324818) (xy 274.922904 -278.275764)
			(xy 274.934681 -278.22798) (xy 274.953972 -278.182704) (xy 274.980275 -278.141108) (xy 275.01291 -278.104271)
			(xy 275.051031 -278.073146) (xy 275.093652 -278.048539) (xy 275.139668 -278.031087) (xy 275.187887 -278.021243)
			(xy 275.237062 -278.019262) (xy 275.285917 -278.025194) (xy 275.333188 -278.038886) (xy 275.37765 -278.059984)
			(xy 275.418153 -278.08794) (xy 275.453646 -278.122032) (xy 275.483211 -278.161376) (xy 275.506082 -278.204953)
			(xy 275.521666 -278.251634) (xy 275.529561 -278.300211) (xy 275.530056 -278.324818) (xy 275.529561 -278.349425)
			(xy 275.521666 -278.398002) (xy 275.506082 -278.444683) (xy 275.483211 -278.48826) (xy 275.453646 -278.527604)
			(xy 275.418153 -278.561696) (xy 275.37765 -278.589652) (xy 275.333188 -278.61075) (xy 275.285917 -278.624442)
			(xy 275.237062 -278.630374) (xy 275.187887 -278.628393) (xy 275.139668 -278.618549) (xy 275.093652 -278.601097)
			(xy 275.051031 -278.57649) (xy 275.01291 -278.545365) (xy 274.980275 -278.508528) (xy 274.953972 -278.466932)
			(xy 274.934681 -278.421656) (xy 274.922904 -278.373872) (xy 274.918944 -278.324818) (xy 274.580096 -278.324818)
			(xy 274.579601 -278.349425) (xy 274.571706 -278.398002) (xy 274.556122 -278.444683) (xy 274.533251 -278.48826)
			(xy 274.503686 -278.527604) (xy 274.468193 -278.561696) (xy 274.42769 -278.589652) (xy 274.383228 -278.61075)
			(xy 274.335957 -278.624442) (xy 274.287102 -278.630374) (xy 274.237927 -278.628393) (xy 274.189708 -278.618549)
			(xy 274.143692 -278.601097) (xy 274.101071 -278.57649) (xy 274.06295 -278.545365) (xy 274.030315 -278.508528)
			(xy 274.004012 -278.466932) (xy 273.984721 -278.421656) (xy 273.972944 -278.373872) (xy 273.968984 -278.324818)
			(xy 273.630136 -278.324818) (xy 273.629641 -278.349425) (xy 273.621746 -278.398002) (xy 273.606162 -278.444683)
			(xy 273.583291 -278.48826) (xy 273.553726 -278.527604) (xy 273.518233 -278.561696) (xy 273.47773 -278.589652)
			(xy 273.433268 -278.61075) (xy 273.385997 -278.624442) (xy 273.337142 -278.630374) (xy 273.287967 -278.628393)
			(xy 273.239748 -278.618549) (xy 273.193732 -278.601097) (xy 273.151111 -278.57649) (xy 273.11299 -278.545365)
			(xy 273.080355 -278.508528) (xy 273.054052 -278.466932) (xy 273.034761 -278.421656) (xy 273.022984 -278.373872)
			(xy 273.019024 -278.324818) (xy 272.680176 -278.324818) (xy 272.679681 -278.349425) (xy 272.671786 -278.398002)
			(xy 272.656202 -278.444683) (xy 272.633331 -278.48826) (xy 272.603766 -278.527604) (xy 272.568273 -278.561696)
			(xy 272.52777 -278.589652) (xy 272.483308 -278.61075) (xy 272.436037 -278.624442) (xy 272.387182 -278.630374)
			(xy 272.338007 -278.628393) (xy 272.289788 -278.618549) (xy 272.243772 -278.601097) (xy 272.201151 -278.57649)
			(xy 272.16303 -278.545365) (xy 272.130395 -278.508528) (xy 272.104092 -278.466932) (xy 272.084801 -278.421656)
			(xy 272.073024 -278.373872) (xy 272.069064 -278.324818) (xy 271.730216 -278.324818) (xy 271.729721 -278.349425)
			(xy 271.721826 -278.398002) (xy 271.706242 -278.444683) (xy 271.683371 -278.48826) (xy 271.653806 -278.527604)
			(xy 271.618313 -278.561696) (xy 271.57781 -278.589652) (xy 271.533348 -278.61075) (xy 271.486077 -278.624442)
			(xy 271.437222 -278.630374) (xy 271.388047 -278.628393) (xy 271.339828 -278.618549) (xy 271.293812 -278.601097)
			(xy 271.251191 -278.57649) (xy 271.21307 -278.545365) (xy 271.180435 -278.508528) (xy 271.154132 -278.466932)
			(xy 271.134841 -278.421656) (xy 271.123064 -278.373872) (xy 271.119104 -278.324818) (xy 270.780256 -278.324818)
			(xy 270.779761 -278.349425) (xy 270.771866 -278.398002) (xy 270.756282 -278.444683) (xy 270.733411 -278.48826)
			(xy 270.703846 -278.527604) (xy 270.668353 -278.561696) (xy 270.62785 -278.589652) (xy 270.583388 -278.61075)
			(xy 270.536117 -278.624442) (xy 270.487262 -278.630374) (xy 270.438087 -278.628393) (xy 270.389868 -278.618549)
			(xy 270.343852 -278.601097) (xy 270.301231 -278.57649) (xy 270.26311 -278.545365) (xy 270.230475 -278.508528)
			(xy 270.204172 -278.466932) (xy 270.184881 -278.421656) (xy 270.173104 -278.373872) (xy 270.169144 -278.324818)
			(xy 269.830042 -278.324818) (xy 269.829547 -278.349425) (xy 269.821652 -278.398002) (xy 269.806068 -278.444683)
			(xy 269.783197 -278.48826) (xy 269.753632 -278.527604) (xy 269.718139 -278.561696) (xy 269.677636 -278.589652)
			(xy 269.633174 -278.61075) (xy 269.585903 -278.624442) (xy 269.537048 -278.630374) (xy 269.487873 -278.628393)
			(xy 269.439654 -278.618549) (xy 269.393638 -278.601097) (xy 269.351017 -278.57649) (xy 269.312896 -278.545365)
			(xy 269.280261 -278.508528) (xy 269.253958 -278.466932) (xy 269.234667 -278.421656) (xy 269.22289 -278.373872)
			(xy 269.21893 -278.324818) (xy 268.880082 -278.324818) (xy 268.879587 -278.349425) (xy 268.871692 -278.398002)
			(xy 268.856108 -278.444683) (xy 268.833237 -278.48826) (xy 268.803672 -278.527604) (xy 268.768179 -278.561696)
			(xy 268.727676 -278.589652) (xy 268.683214 -278.61075) (xy 268.635943 -278.624442) (xy 268.587088 -278.630374)
			(xy 268.537913 -278.628393) (xy 268.489694 -278.618549) (xy 268.443678 -278.601097) (xy 268.401057 -278.57649)
			(xy 268.362936 -278.545365) (xy 268.330301 -278.508528) (xy 268.303998 -278.466932) (xy 268.284707 -278.421656)
			(xy 268.27293 -278.373872) (xy 268.26897 -278.324818) (xy 247.511275 -278.324818) (xy 247.522152 -278.344456)
			(xy 247.544763 -278.401172) (xy 247.560041 -278.460287) (xy 247.567743 -278.520857) (xy 247.568212 -278.551386)
			(xy 247.56773 -278.58302) (xy 247.559483 -278.645748) (xy 247.543116 -278.706863) (xy 247.518907 -278.765316)
			(xy 247.487273 -278.820108) (xy 247.448755 -278.8703) (xy 247.426734 -278.893016) (xy 247.246902 -279.072594)
			(xy 247.238943 -279.081424) (xy 247.231388 -279.103932) (xy 247.232424 -279.115774) (xy 247.245632 -279.20823)
			(xy 247.25884 -279.227534) (xy 247.269508 -279.233376) (xy 247.294702 -279.247897) (xy 247.340746 -279.28341)
			(xy 247.38087 -279.325496) (xy 247.414145 -279.373183) (xy 247.4398 -279.425366) (xy 247.457241 -279.480837)
			(xy 247.466065 -279.538312) (xy 247.466612 -279.567386) (xy 247.466132 -279.594638) (xy 247.458377 -279.648588)
			(xy 247.443023 -279.700886) (xy 247.420382 -279.750466) (xy 247.390916 -279.796319) (xy 247.355224 -279.837511)
			(xy 247.314033 -279.873205) (xy 247.268181 -279.902673) (xy 247.218603 -279.925316) (xy 247.166306 -279.940673)
			(xy 247.112356 -279.94843) (xy 247.085104 -279.948894) (xy 247.056865 -279.948335) (xy 247.001003 -279.940022)
			(xy 246.946976 -279.923563) (xy 246.895968 -279.899318) (xy 246.849092 -279.867817) (xy 246.807373 -279.829747)
			(xy 246.771724 -279.785943) (xy 246.742923 -279.73736) (xy 246.73179 -279.711404) (xy 246.72798 -279.702006)
			(xy 246.714518 -279.688036) (xy 246.631206 -279.65146) (xy 246.611902 -279.650952) (xy 246.602504 -279.654508)
			(xy 246.575628 -279.663998) (xy 246.520217 -279.677348) (xy 246.463617 -279.684065) (xy 246.435118 -279.68448)
			(xy 244.15623 -279.68448) (xy 244.146262 -279.684951) (xy 244.127826 -279.692529) (xy 244.120416 -279.699212)
			(xy 243.377212 -280.44267) (xy 243.354463 -280.464653) (xy 243.307623 -280.500582) (xy 245.065802 -280.500582)
			(xy 245.069873 -280.44496) (xy 245.081999 -280.390523) (xy 245.101922 -280.338432) (xy 245.129218 -280.289797)
			(xy 245.163304 -280.245654) (xy 245.203453 -280.206945) (xy 245.248811 -280.174494) (xy 245.298411 -280.148993)
			(xy 245.351195 -280.130986) (xy 245.406038 -280.120856) (xy 245.461772 -280.118819) (xy 245.517209 -280.124919)
			(xy 245.571166 -280.139025) (xy 245.622495 -280.160837) (xy 245.670101 -280.189891) (xy 245.712969 -280.225566)
			(xy 245.750186 -280.267103) (xy 245.780959 -280.313616) (xy 245.804631 -280.364113) (xy 245.820699 -280.41752)
			(xy 245.828819 -280.472696) (xy 245.829328 -280.500582) (xy 245.828819 -280.528468) (xy 245.820737 -280.583386)
			(xy 248.722896 -280.583386) (xy 248.723344 -280.557488) (xy 248.730348 -280.506168) (xy 248.744227 -280.456266)
			(xy 248.764725 -280.408699) (xy 248.791465 -280.364339) (xy 248.823957 -280.324002) (xy 248.861604 -280.288428)
			(xy 248.882408 -280.272998) (xy 248.891044 -280.266902) (xy 248.901966 -280.248868) (xy 248.914412 -280.154126)
			(xy 248.90857 -280.13406) (xy 248.901712 -280.125932) (xy 248.885274 -280.105359) (xy 248.857678 -280.060508)
			(xy 248.836521 -280.012284) (xy 248.822206 -279.961606) (xy 248.815008 -279.909439) (xy 248.81459 -279.883108)
			(xy 248.814996 -279.856894) (xy 248.82217 -279.80496) (xy 248.836383 -279.754496) (xy 248.857368 -279.706452)
			(xy 248.884731 -279.661732) (xy 248.917956 -279.621177) (xy 248.956419 -279.58555) (xy 248.977658 -279.57018)
			(xy 248.988834 -279.56256) (xy 249.000264 -279.538684) (xy 248.992136 -279.424384) (xy 248.977404 -279.402286)
			(xy 248.965212 -279.39619) (xy 248.941836 -279.383984) (xy 248.89841 -279.354065) (xy 248.859521 -279.318446)
			(xy 248.825911 -279.277809) (xy 248.798222 -279.232927) (xy 248.776983 -279.184659) (xy 248.762597 -279.133923)
			(xy 248.755341 -279.08169) (xy 248.7549 -279.055322) (xy 248.755386 -279.028071) (xy 248.763142 -278.974123)
			(xy 248.778497 -278.921828) (xy 248.801139 -278.872251) (xy 248.830605 -278.826401) (xy 248.866296 -278.78521)
			(xy 248.907487 -278.749519) (xy 248.953337 -278.720053) (xy 249.002914 -278.697411) (xy 249.055209 -278.682056)
			(xy 249.109157 -278.6743) (xy 249.163659 -278.6743) (xy 249.217607 -278.682056) (xy 249.269902 -278.697411)
			(xy 249.319479 -278.720053) (xy 249.365329 -278.749519) (xy 249.40652 -278.78521) (xy 249.429284 -278.811482)
			(xy 250.954284 -278.811482) (xy 250.958355 -278.75586) (xy 250.970481 -278.701423) (xy 250.990404 -278.649332)
			(xy 251.0177 -278.600697) (xy 251.051786 -278.556554) (xy 251.091935 -278.517845) (xy 251.137293 -278.485394)
			(xy 251.186893 -278.459893) (xy 251.239677 -278.441886) (xy 251.29452 -278.431756) (xy 251.350254 -278.429719)
			(xy 251.405691 -278.435819) (xy 251.459648 -278.449925) (xy 251.510977 -278.471737) (xy 251.558583 -278.500791)
			(xy 251.601451 -278.536466) (xy 251.638668 -278.578003) (xy 251.669441 -278.624516) (xy 251.693113 -278.675013)
			(xy 251.709181 -278.72842) (xy 251.717301 -278.783596) (xy 251.71781 -278.811482) (xy 251.717554 -278.825506)
			(xy 276.32304 -278.825506) (xy 276.32304 -278.77409) (xy 276.331083 -278.723308) (xy 276.346971 -278.674409)
			(xy 276.370314 -278.628597) (xy 276.400535 -278.587001) (xy 276.436891 -278.550645) (xy 276.478487 -278.520424)
			(xy 276.524299 -278.497081) (xy 276.573198 -278.481193) (xy 276.62398 -278.47315) (xy 276.675396 -278.47315)
			(xy 276.726178 -278.481193) (xy 276.775077 -278.497081) (xy 276.820889 -278.520424) (xy 276.862485 -278.550645)
			(xy 276.898841 -278.587001) (xy 276.929062 -278.628597) (xy 276.952405 -278.674409) (xy 276.968293 -278.723308)
			(xy 276.976336 -278.77409) (xy 276.97684 -278.799798) (xy 277.294098 -278.799798) (xy 277.298058 -278.750744)
			(xy 277.309835 -278.70296) (xy 277.329126 -278.657684) (xy 277.355429 -278.616088) (xy 277.388064 -278.579251)
			(xy 277.426185 -278.548126) (xy 277.468806 -278.523519) (xy 277.514822 -278.506067) (xy 277.563041 -278.496223)
			(xy 277.612216 -278.494242) (xy 277.661071 -278.500174) (xy 277.708342 -278.513866) (xy 277.752804 -278.534964)
			(xy 277.793307 -278.56292) (xy 277.8288 -278.597012) (xy 277.858365 -278.636356) (xy 277.881236 -278.679933)
			(xy 277.89682 -278.726614) (xy 277.904715 -278.775191) (xy 277.90521 -278.799798) (xy 277.904715 -278.824405)
			(xy 277.904536 -278.825506) (xy 278.223214 -278.825506) (xy 278.223214 -278.77409) (xy 278.231257 -278.723308)
			(xy 278.247145 -278.674409) (xy 278.270488 -278.628597) (xy 278.300709 -278.587001) (xy 278.337065 -278.550645)
			(xy 278.378661 -278.520424) (xy 278.424473 -278.497081) (xy 278.473372 -278.481193) (xy 278.524154 -278.47315)
			(xy 278.57557 -278.47315) (xy 278.626352 -278.481193) (xy 278.675251 -278.497081) (xy 278.721063 -278.520424)
			(xy 278.762659 -278.550645) (xy 278.799015 -278.587001) (xy 278.829236 -278.628597) (xy 278.852579 -278.674409)
			(xy 278.868467 -278.723308) (xy 278.87651 -278.77409) (xy 278.877014 -278.799798) (xy 279.194018 -278.799798)
			(xy 279.197978 -278.750744) (xy 279.209755 -278.70296) (xy 279.229046 -278.657684) (xy 279.255349 -278.616088)
			(xy 279.287984 -278.579251) (xy 279.326105 -278.548126) (xy 279.368726 -278.523519) (xy 279.414742 -278.506067)
			(xy 279.462961 -278.496223) (xy 279.512136 -278.494242) (xy 279.560991 -278.500174) (xy 279.608262 -278.513866)
			(xy 279.652724 -278.534964) (xy 279.693227 -278.56292) (xy 279.72872 -278.597012) (xy 279.758285 -278.636356)
			(xy 279.781156 -278.679933) (xy 279.79674 -278.726614) (xy 279.804635 -278.775191) (xy 279.80513 -278.799798)
			(xy 279.804635 -278.824405) (xy 279.804456 -278.825506) (xy 280.123134 -278.825506) (xy 280.123134 -278.77409)
			(xy 280.131177 -278.723308) (xy 280.147065 -278.674409) (xy 280.170408 -278.628597) (xy 280.200629 -278.587001)
			(xy 280.236985 -278.550645) (xy 280.278581 -278.520424) (xy 280.324393 -278.497081) (xy 280.373292 -278.481193)
			(xy 280.424074 -278.47315) (xy 280.47549 -278.47315) (xy 280.526272 -278.481193) (xy 280.575171 -278.497081)
			(xy 280.620983 -278.520424) (xy 280.662579 -278.550645) (xy 280.698935 -278.587001) (xy 280.729156 -278.628597)
			(xy 280.752499 -278.674409) (xy 280.768387 -278.723308) (xy 280.77643 -278.77409) (xy 280.776934 -278.799798)
			(xy 281.093938 -278.799798) (xy 281.097898 -278.750744) (xy 281.109675 -278.70296) (xy 281.128966 -278.657684)
			(xy 281.155269 -278.616088) (xy 281.187904 -278.579251) (xy 281.226025 -278.548126) (xy 281.268646 -278.523519)
			(xy 281.314662 -278.506067) (xy 281.362881 -278.496223) (xy 281.412056 -278.494242) (xy 281.460911 -278.500174)
			(xy 281.508182 -278.513866) (xy 281.552644 -278.534964) (xy 281.593147 -278.56292) (xy 281.62864 -278.597012)
			(xy 281.658205 -278.636356) (xy 281.681076 -278.679933) (xy 281.69666 -278.726614) (xy 281.704555 -278.775191)
			(xy 281.70505 -278.799798) (xy 281.704555 -278.824405) (xy 281.704376 -278.825506) (xy 282.023054 -278.825506)
			(xy 282.023054 -278.77409) (xy 282.031097 -278.723308) (xy 282.046985 -278.674409) (xy 282.070328 -278.628597)
			(xy 282.100549 -278.587001) (xy 282.136905 -278.550645) (xy 282.178501 -278.520424) (xy 282.224313 -278.497081)
			(xy 282.273212 -278.481193) (xy 282.323994 -278.47315) (xy 282.37541 -278.47315) (xy 282.426192 -278.481193)
			(xy 282.475091 -278.497081) (xy 282.520903 -278.520424) (xy 282.562499 -278.550645) (xy 282.598855 -278.587001)
			(xy 282.629076 -278.628597) (xy 282.652419 -278.674409) (xy 282.668307 -278.723308) (xy 282.67635 -278.77409)
			(xy 282.676854 -278.799798) (xy 282.994112 -278.799798) (xy 282.998072 -278.750744) (xy 283.009849 -278.70296)
			(xy 283.02914 -278.657684) (xy 283.055443 -278.616088) (xy 283.088078 -278.579251) (xy 283.126199 -278.548126)
			(xy 283.16882 -278.523519) (xy 283.214836 -278.506067) (xy 283.263055 -278.496223) (xy 283.31223 -278.494242)
			(xy 283.361085 -278.500174) (xy 283.408356 -278.513866) (xy 283.452818 -278.534964) (xy 283.493321 -278.56292)
			(xy 283.528814 -278.597012) (xy 283.558379 -278.636356) (xy 283.58125 -278.679933) (xy 283.596834 -278.726614)
			(xy 283.604729 -278.775191) (xy 283.605224 -278.799798) (xy 283.604729 -278.824405) (xy 283.60455 -278.825506)
			(xy 283.923228 -278.825506) (xy 283.923228 -278.77409) (xy 283.931271 -278.723308) (xy 283.947159 -278.674409)
			(xy 283.970502 -278.628597) (xy 284.000723 -278.587001) (xy 284.037079 -278.550645) (xy 284.078675 -278.520424)
			(xy 284.124487 -278.497081) (xy 284.173386 -278.481193) (xy 284.224168 -278.47315) (xy 284.275584 -278.47315)
			(xy 284.326366 -278.481193) (xy 284.375265 -278.497081) (xy 284.421077 -278.520424) (xy 284.462673 -278.550645)
			(xy 284.499029 -278.587001) (xy 284.52925 -278.628597) (xy 284.552593 -278.674409) (xy 284.568481 -278.723308)
			(xy 284.576524 -278.77409) (xy 284.577028 -278.799798) (xy 284.894032 -278.799798) (xy 284.897992 -278.750744)
			(xy 284.909769 -278.70296) (xy 284.92906 -278.657684) (xy 284.955363 -278.616088) (xy 284.987998 -278.579251)
			(xy 285.026119 -278.548126) (xy 285.06874 -278.523519) (xy 285.114756 -278.506067) (xy 285.162975 -278.496223)
			(xy 285.21215 -278.494242) (xy 285.261005 -278.500174) (xy 285.308276 -278.513866) (xy 285.352738 -278.534964)
			(xy 285.393241 -278.56292) (xy 285.428734 -278.597012) (xy 285.458299 -278.636356) (xy 285.48117 -278.679933)
			(xy 285.496754 -278.726614) (xy 285.504649 -278.775191) (xy 285.505144 -278.799798) (xy 285.504649 -278.824405)
			(xy 285.50447 -278.825506) (xy 285.823148 -278.825506) (xy 285.823148 -278.77409) (xy 285.831191 -278.723308)
			(xy 285.847079 -278.674409) (xy 285.870422 -278.628597) (xy 285.900643 -278.587001) (xy 285.936999 -278.550645)
			(xy 285.978595 -278.520424) (xy 286.024407 -278.497081) (xy 286.073306 -278.481193) (xy 286.124088 -278.47315)
			(xy 286.175504 -278.47315) (xy 286.226286 -278.481193) (xy 286.275185 -278.497081) (xy 286.320997 -278.520424)
			(xy 286.362593 -278.550645) (xy 286.398949 -278.587001) (xy 286.42917 -278.628597) (xy 286.452513 -278.674409)
			(xy 286.468401 -278.723308) (xy 286.476444 -278.77409) (xy 286.476948 -278.799798) (xy 286.793952 -278.799798)
			(xy 286.797912 -278.750744) (xy 286.809689 -278.70296) (xy 286.82898 -278.657684) (xy 286.855283 -278.616088)
			(xy 286.887918 -278.579251) (xy 286.926039 -278.548126) (xy 286.96866 -278.523519) (xy 287.014676 -278.506067)
			(xy 287.062895 -278.496223) (xy 287.11207 -278.494242) (xy 287.160925 -278.500174) (xy 287.208196 -278.513866)
			(xy 287.252658 -278.534964) (xy 287.293161 -278.56292) (xy 287.328654 -278.597012) (xy 287.358219 -278.636356)
			(xy 287.38109 -278.679933) (xy 287.396674 -278.726614) (xy 287.404569 -278.775191) (xy 287.405064 -278.799798)
			(xy 287.404569 -278.824405) (xy 287.40439 -278.825506) (xy 287.723068 -278.825506) (xy 287.723068 -278.77409)
			(xy 287.731111 -278.723308) (xy 287.746999 -278.674409) (xy 287.770342 -278.628597) (xy 287.800563 -278.587001)
			(xy 287.836919 -278.550645) (xy 287.878515 -278.520424) (xy 287.924327 -278.497081) (xy 287.973226 -278.481193)
			(xy 288.024008 -278.47315) (xy 288.075424 -278.47315) (xy 288.126206 -278.481193) (xy 288.175105 -278.497081)
			(xy 288.220917 -278.520424) (xy 288.262513 -278.550645) (xy 288.298869 -278.587001) (xy 288.32909 -278.628597)
			(xy 288.352433 -278.674409) (xy 288.368321 -278.723308) (xy 288.376364 -278.77409) (xy 288.376868 -278.799798)
			(xy 288.694126 -278.799798) (xy 288.698086 -278.750744) (xy 288.709863 -278.70296) (xy 288.729154 -278.657684)
			(xy 288.755457 -278.616088) (xy 288.788092 -278.579251) (xy 288.826213 -278.548126) (xy 288.868834 -278.523519)
			(xy 288.91485 -278.506067) (xy 288.963069 -278.496223) (xy 289.012244 -278.494242) (xy 289.061099 -278.500174)
			(xy 289.10837 -278.513866) (xy 289.152832 -278.534964) (xy 289.193335 -278.56292) (xy 289.228828 -278.597012)
			(xy 289.258393 -278.636356) (xy 289.281264 -278.679933) (xy 289.296848 -278.726614) (xy 289.304743 -278.775191)
			(xy 289.305238 -278.799798) (xy 289.304743 -278.824405) (xy 289.304564 -278.825506) (xy 289.623242 -278.825506)
			(xy 289.623242 -278.77409) (xy 289.631285 -278.723308) (xy 289.647173 -278.674409) (xy 289.670516 -278.628597)
			(xy 289.700737 -278.587001) (xy 289.737093 -278.550645) (xy 289.778689 -278.520424) (xy 289.824501 -278.497081)
			(xy 289.8734 -278.481193) (xy 289.924182 -278.47315) (xy 289.975598 -278.47315) (xy 290.02638 -278.481193)
			(xy 290.075279 -278.497081) (xy 290.121091 -278.520424) (xy 290.162687 -278.550645) (xy 290.199043 -278.587001)
			(xy 290.229264 -278.628597) (xy 290.252607 -278.674409) (xy 290.268495 -278.723308) (xy 290.276538 -278.77409)
			(xy 290.277042 -278.799798) (xy 290.594046 -278.799798) (xy 290.598006 -278.750744) (xy 290.609783 -278.70296)
			(xy 290.629074 -278.657684) (xy 290.655377 -278.616088) (xy 290.688012 -278.579251) (xy 290.726133 -278.548126)
			(xy 290.768754 -278.523519) (xy 290.81477 -278.506067) (xy 290.862989 -278.496223) (xy 290.912164 -278.494242)
			(xy 290.961019 -278.500174) (xy 291.00829 -278.513866) (xy 291.052752 -278.534964) (xy 291.093255 -278.56292)
			(xy 291.128748 -278.597012) (xy 291.158313 -278.636356) (xy 291.181184 -278.679933) (xy 291.196768 -278.726614)
			(xy 291.204663 -278.775191) (xy 291.205158 -278.799798) (xy 291.204663 -278.824405) (xy 291.204484 -278.825506)
			(xy 291.522908 -278.825506) (xy 291.522908 -278.77409) (xy 291.530951 -278.723308) (xy 291.546839 -278.674409)
			(xy 291.570182 -278.628597) (xy 291.600403 -278.587001) (xy 291.636759 -278.550645) (xy 291.678355 -278.520424)
			(xy 291.724167 -278.497081) (xy 291.773066 -278.481193) (xy 291.823848 -278.47315) (xy 291.875264 -278.47315)
			(xy 291.926046 -278.481193) (xy 291.974945 -278.497081) (xy 292.020757 -278.520424) (xy 292.062353 -278.550645)
			(xy 292.098709 -278.587001) (xy 292.12893 -278.628597) (xy 292.152273 -278.674409) (xy 292.168161 -278.723308)
			(xy 292.176204 -278.77409) (xy 292.176708 -278.799798) (xy 292.493966 -278.799798) (xy 292.497926 -278.750744)
			(xy 292.509703 -278.70296) (xy 292.528994 -278.657684) (xy 292.555297 -278.616088) (xy 292.587932 -278.579251)
			(xy 292.626053 -278.548126) (xy 292.668674 -278.523519) (xy 292.71469 -278.506067) (xy 292.762909 -278.496223)
			(xy 292.812084 -278.494242) (xy 292.860939 -278.500174) (xy 292.90821 -278.513866) (xy 292.952672 -278.534964)
			(xy 292.993175 -278.56292) (xy 293.028668 -278.597012) (xy 293.058233 -278.636356) (xy 293.081104 -278.679933)
			(xy 293.096688 -278.726614) (xy 293.104583 -278.775191) (xy 293.105078 -278.799798) (xy 293.104583 -278.824405)
			(xy 293.104404 -278.825506) (xy 293.422828 -278.825506) (xy 293.422828 -278.77409) (xy 293.430871 -278.723308)
			(xy 293.446759 -278.674409) (xy 293.470102 -278.628597) (xy 293.500323 -278.587001) (xy 293.536679 -278.550645)
			(xy 293.578275 -278.520424) (xy 293.624087 -278.497081) (xy 293.672986 -278.481193) (xy 293.723768 -278.47315)
			(xy 293.775184 -278.47315) (xy 293.825966 -278.481193) (xy 293.874865 -278.497081) (xy 293.920677 -278.520424)
			(xy 293.962273 -278.550645) (xy 293.998629 -278.587001) (xy 294.02885 -278.628597) (xy 294.052193 -278.674409)
			(xy 294.068081 -278.723308) (xy 294.076124 -278.77409) (xy 294.076628 -278.799798) (xy 294.393886 -278.799798)
			(xy 294.397846 -278.750744) (xy 294.409623 -278.70296) (xy 294.428914 -278.657684) (xy 294.455217 -278.616088)
			(xy 294.487852 -278.579251) (xy 294.525973 -278.548126) (xy 294.568594 -278.523519) (xy 294.61461 -278.506067)
			(xy 294.662829 -278.496223) (xy 294.712004 -278.494242) (xy 294.760859 -278.500174) (xy 294.80813 -278.513866)
			(xy 294.852592 -278.534964) (xy 294.893095 -278.56292) (xy 294.928588 -278.597012) (xy 294.958153 -278.636356)
			(xy 294.981024 -278.679933) (xy 294.996608 -278.726614) (xy 295.004503 -278.775191) (xy 295.004998 -278.799798)
			(xy 295.004503 -278.824405) (xy 295.004324 -278.825506) (xy 295.323002 -278.825506) (xy 295.323002 -278.77409)
			(xy 295.331045 -278.723308) (xy 295.346933 -278.674409) (xy 295.370276 -278.628597) (xy 295.400497 -278.587001)
			(xy 295.436853 -278.550645) (xy 295.478449 -278.520424) (xy 295.524261 -278.497081) (xy 295.57316 -278.481193)
			(xy 295.623942 -278.47315) (xy 295.675358 -278.47315) (xy 295.72614 -278.481193) (xy 295.775039 -278.497081)
			(xy 295.820851 -278.520424) (xy 295.862447 -278.550645) (xy 295.898803 -278.587001) (xy 295.929024 -278.628597)
			(xy 295.952367 -278.674409) (xy 295.968255 -278.723308) (xy 295.976298 -278.77409) (xy 295.976802 -278.799798)
			(xy 296.29406 -278.799798) (xy 296.29802 -278.750744) (xy 296.309797 -278.70296) (xy 296.329088 -278.657684)
			(xy 296.355391 -278.616088) (xy 296.388026 -278.579251) (xy 296.426147 -278.548126) (xy 296.468768 -278.523519)
			(xy 296.514784 -278.506067) (xy 296.563003 -278.496223) (xy 296.612178 -278.494242) (xy 296.661033 -278.500174)
			(xy 296.708304 -278.513866) (xy 296.752766 -278.534964) (xy 296.793269 -278.56292) (xy 296.828762 -278.597012)
			(xy 296.858327 -278.636356) (xy 296.881198 -278.679933) (xy 296.896782 -278.726614) (xy 296.904677 -278.775191)
			(xy 296.905172 -278.799798) (xy 296.904677 -278.824405) (xy 296.904498 -278.825506) (xy 297.222922 -278.825506)
			(xy 297.222922 -278.77409) (xy 297.230965 -278.723308) (xy 297.246853 -278.674409) (xy 297.270196 -278.628597)
			(xy 297.300417 -278.587001) (xy 297.336773 -278.550645) (xy 297.378369 -278.520424) (xy 297.424181 -278.497081)
			(xy 297.47308 -278.481193) (xy 297.523862 -278.47315) (xy 297.575278 -278.47315) (xy 297.62606 -278.481193)
			(xy 297.674959 -278.497081) (xy 297.720771 -278.520424) (xy 297.762367 -278.550645) (xy 297.798723 -278.587001)
			(xy 297.828944 -278.628597) (xy 297.852287 -278.674409) (xy 297.868175 -278.723308) (xy 297.876218 -278.77409)
			(xy 297.876722 -278.799798) (xy 298.19398 -278.799798) (xy 298.19794 -278.750744) (xy 298.209717 -278.70296)
			(xy 298.229008 -278.657684) (xy 298.255311 -278.616088) (xy 298.287946 -278.579251) (xy 298.326067 -278.548126)
			(xy 298.368688 -278.523519) (xy 298.414704 -278.506067) (xy 298.462923 -278.496223) (xy 298.512098 -278.494242)
			(xy 298.560953 -278.500174) (xy 298.608224 -278.513866) (xy 298.652686 -278.534964) (xy 298.693189 -278.56292)
			(xy 298.728682 -278.597012) (xy 298.758247 -278.636356) (xy 298.781118 -278.679933) (xy 298.796702 -278.726614)
			(xy 298.804597 -278.775191) (xy 298.805092 -278.799798) (xy 298.804597 -278.824405) (xy 298.804418 -278.825506)
			(xy 299.122842 -278.825506) (xy 299.122842 -278.77409) (xy 299.130885 -278.723308) (xy 299.146773 -278.674409)
			(xy 299.170116 -278.628597) (xy 299.200337 -278.587001) (xy 299.236693 -278.550645) (xy 299.278289 -278.520424)
			(xy 299.324101 -278.497081) (xy 299.373 -278.481193) (xy 299.423782 -278.47315) (xy 299.475198 -278.47315)
			(xy 299.52598 -278.481193) (xy 299.574879 -278.497081) (xy 299.620691 -278.520424) (xy 299.662287 -278.550645)
			(xy 299.698643 -278.587001) (xy 299.728864 -278.628597) (xy 299.752207 -278.674409) (xy 299.768095 -278.723308)
			(xy 299.776138 -278.77409) (xy 299.776642 -278.799798) (xy 300.0939 -278.799798) (xy 300.09786 -278.750744)
			(xy 300.109637 -278.70296) (xy 300.128928 -278.657684) (xy 300.155231 -278.616088) (xy 300.187866 -278.579251)
			(xy 300.225987 -278.548126) (xy 300.268608 -278.523519) (xy 300.314624 -278.506067) (xy 300.362843 -278.496223)
			(xy 300.412018 -278.494242) (xy 300.460873 -278.500174) (xy 300.508144 -278.513866) (xy 300.552606 -278.534964)
			(xy 300.593109 -278.56292) (xy 300.628602 -278.597012) (xy 300.658167 -278.636356) (xy 300.681038 -278.679933)
			(xy 300.696622 -278.726614) (xy 300.704517 -278.775191) (xy 300.705012 -278.799798) (xy 300.704517 -278.824405)
			(xy 300.704338 -278.825506) (xy 301.023016 -278.825506) (xy 301.023016 -278.77409) (xy 301.031059 -278.723308)
			(xy 301.046947 -278.674409) (xy 301.07029 -278.628597) (xy 301.100511 -278.587001) (xy 301.136867 -278.550645)
			(xy 301.178463 -278.520424) (xy 301.224275 -278.497081) (xy 301.273174 -278.481193) (xy 301.323956 -278.47315)
			(xy 301.375372 -278.47315) (xy 301.426154 -278.481193) (xy 301.475053 -278.497081) (xy 301.520865 -278.520424)
			(xy 301.562461 -278.550645) (xy 301.598817 -278.587001) (xy 301.629038 -278.628597) (xy 301.652381 -278.674409)
			(xy 301.668269 -278.723308) (xy 301.676312 -278.77409) (xy 301.676816 -278.799798) (xy 301.994074 -278.799798)
			(xy 301.998034 -278.750744) (xy 302.009811 -278.70296) (xy 302.029102 -278.657684) (xy 302.055405 -278.616088)
			(xy 302.08804 -278.579251) (xy 302.126161 -278.548126) (xy 302.168782 -278.523519) (xy 302.214798 -278.506067)
			(xy 302.263017 -278.496223) (xy 302.312192 -278.494242) (xy 302.361047 -278.500174) (xy 302.408318 -278.513866)
			(xy 302.45278 -278.534964) (xy 302.493283 -278.56292) (xy 302.528776 -278.597012) (xy 302.558341 -278.636356)
			(xy 302.581212 -278.679933) (xy 302.596796 -278.726614) (xy 302.604691 -278.775191) (xy 302.605186 -278.799798)
			(xy 302.604691 -278.824405) (xy 302.604512 -278.825506) (xy 302.922936 -278.825506) (xy 302.922936 -278.77409)
			(xy 302.930979 -278.723308) (xy 302.946867 -278.674409) (xy 302.97021 -278.628597) (xy 303.000431 -278.587001)
			(xy 303.036787 -278.550645) (xy 303.078383 -278.520424) (xy 303.124195 -278.497081) (xy 303.173094 -278.481193)
			(xy 303.223876 -278.47315) (xy 303.275292 -278.47315) (xy 303.326074 -278.481193) (xy 303.374973 -278.497081)
			(xy 303.420785 -278.520424) (xy 303.462381 -278.550645) (xy 303.498737 -278.587001) (xy 303.528958 -278.628597)
			(xy 303.552301 -278.674409) (xy 303.568189 -278.723308) (xy 303.576232 -278.77409) (xy 303.576736 -278.799798)
			(xy 303.893994 -278.799798) (xy 303.897954 -278.750744) (xy 303.909731 -278.70296) (xy 303.929022 -278.657684)
			(xy 303.955325 -278.616088) (xy 303.98796 -278.579251) (xy 304.026081 -278.548126) (xy 304.068702 -278.523519)
			(xy 304.114718 -278.506067) (xy 304.162937 -278.496223) (xy 304.212112 -278.494242) (xy 304.260967 -278.500174)
			(xy 304.308238 -278.513866) (xy 304.3527 -278.534964) (xy 304.393203 -278.56292) (xy 304.428696 -278.597012)
			(xy 304.458261 -278.636356) (xy 304.481132 -278.679933) (xy 304.496716 -278.726614) (xy 304.504611 -278.775191)
			(xy 304.505106 -278.799798) (xy 304.504611 -278.824405) (xy 304.504432 -278.825506) (xy 304.822856 -278.825506)
			(xy 304.822856 -278.77409) (xy 304.830899 -278.723308) (xy 304.846787 -278.674409) (xy 304.87013 -278.628597)
			(xy 304.900351 -278.587001) (xy 304.936707 -278.550645) (xy 304.978303 -278.520424) (xy 305.024115 -278.497081)
			(xy 305.073014 -278.481193) (xy 305.123796 -278.47315) (xy 305.175212 -278.47315) (xy 305.225994 -278.481193)
			(xy 305.274893 -278.497081) (xy 305.320705 -278.520424) (xy 305.362301 -278.550645) (xy 305.398657 -278.587001)
			(xy 305.428878 -278.628597) (xy 305.452221 -278.674409) (xy 305.468109 -278.723308) (xy 305.476152 -278.77409)
			(xy 305.476656 -278.799798) (xy 305.793914 -278.799798) (xy 305.797874 -278.750744) (xy 305.809651 -278.70296)
			(xy 305.828942 -278.657684) (xy 305.855245 -278.616088) (xy 305.88788 -278.579251) (xy 305.926001 -278.548126)
			(xy 305.968622 -278.523519) (xy 306.014638 -278.506067) (xy 306.062857 -278.496223) (xy 306.112032 -278.494242)
			(xy 306.160887 -278.500174) (xy 306.208158 -278.513866) (xy 306.25262 -278.534964) (xy 306.293123 -278.56292)
			(xy 306.328616 -278.597012) (xy 306.358181 -278.636356) (xy 306.381052 -278.679933) (xy 306.396636 -278.726614)
			(xy 306.404531 -278.775191) (xy 306.405026 -278.799798) (xy 306.404531 -278.824405) (xy 306.404352 -278.825506)
			(xy 306.72303 -278.825506) (xy 306.72303 -278.77409) (xy 306.731073 -278.723308) (xy 306.746961 -278.674409)
			(xy 306.770304 -278.628597) (xy 306.800525 -278.587001) (xy 306.836881 -278.550645) (xy 306.878477 -278.520424)
			(xy 306.924289 -278.497081) (xy 306.973188 -278.481193) (xy 307.02397 -278.47315) (xy 307.075386 -278.47315)
			(xy 307.126168 -278.481193) (xy 307.175067 -278.497081) (xy 307.220879 -278.520424) (xy 307.262475 -278.550645)
			(xy 307.298831 -278.587001) (xy 307.329052 -278.628597) (xy 307.352395 -278.674409) (xy 307.368283 -278.723308)
			(xy 307.376326 -278.77409) (xy 307.37683 -278.799798) (xy 307.694088 -278.799798) (xy 307.698048 -278.750744)
			(xy 307.709825 -278.70296) (xy 307.729116 -278.657684) (xy 307.755419 -278.616088) (xy 307.788054 -278.579251)
			(xy 307.826175 -278.548126) (xy 307.868796 -278.523519) (xy 307.914812 -278.506067) (xy 307.963031 -278.496223)
			(xy 308.012206 -278.494242) (xy 308.061061 -278.500174) (xy 308.108332 -278.513866) (xy 308.152794 -278.534964)
			(xy 308.193297 -278.56292) (xy 308.22879 -278.597012) (xy 308.258355 -278.636356) (xy 308.281226 -278.679933)
			(xy 308.29681 -278.726614) (xy 308.304705 -278.775191) (xy 308.3052 -278.799798) (xy 308.304705 -278.824405)
			(xy 308.304526 -278.825506) (xy 308.62295 -278.825506) (xy 308.62295 -278.77409) (xy 308.630993 -278.723308)
			(xy 308.646881 -278.674409) (xy 308.670224 -278.628597) (xy 308.700445 -278.587001) (xy 308.736801 -278.550645)
			(xy 308.778397 -278.520424) (xy 308.824209 -278.497081) (xy 308.873108 -278.481193) (xy 308.92389 -278.47315)
			(xy 308.975306 -278.47315) (xy 309.026088 -278.481193) (xy 309.074987 -278.497081) (xy 309.120799 -278.520424)
			(xy 309.162395 -278.550645) (xy 309.198751 -278.587001) (xy 309.228972 -278.628597) (xy 309.252315 -278.674409)
			(xy 309.268203 -278.723308) (xy 309.276246 -278.77409) (xy 309.27675 -278.799798) (xy 309.594008 -278.799798)
			(xy 309.597968 -278.750744) (xy 309.609745 -278.70296) (xy 309.629036 -278.657684) (xy 309.655339 -278.616088)
			(xy 309.687974 -278.579251) (xy 309.726095 -278.548126) (xy 309.768716 -278.523519) (xy 309.814732 -278.506067)
			(xy 309.862951 -278.496223) (xy 309.912126 -278.494242) (xy 309.960981 -278.500174) (xy 310.008252 -278.513866)
			(xy 310.052714 -278.534964) (xy 310.093217 -278.56292) (xy 310.12871 -278.597012) (xy 310.158275 -278.636356)
			(xy 310.181146 -278.679933) (xy 310.19673 -278.726614) (xy 310.204625 -278.775191) (xy 310.20512 -278.799798)
			(xy 310.204625 -278.824405) (xy 310.204446 -278.825506) (xy 310.52287 -278.825506) (xy 310.52287 -278.77409)
			(xy 310.530913 -278.723308) (xy 310.546801 -278.674409) (xy 310.570144 -278.628597) (xy 310.600365 -278.587001)
			(xy 310.636721 -278.550645) (xy 310.678317 -278.520424) (xy 310.724129 -278.497081) (xy 310.773028 -278.481193)
			(xy 310.82381 -278.47315) (xy 310.875226 -278.47315) (xy 310.926008 -278.481193) (xy 310.974907 -278.497081)
			(xy 311.020719 -278.520424) (xy 311.062315 -278.550645) (xy 311.098671 -278.587001) (xy 311.128892 -278.628597)
			(xy 311.152235 -278.674409) (xy 311.168123 -278.723308) (xy 311.176166 -278.77409) (xy 311.17667 -278.799798)
			(xy 311.493928 -278.799798) (xy 311.497888 -278.750744) (xy 311.509665 -278.70296) (xy 311.528956 -278.657684)
			(xy 311.555259 -278.616088) (xy 311.587894 -278.579251) (xy 311.626015 -278.548126) (xy 311.668636 -278.523519)
			(xy 311.714652 -278.506067) (xy 311.762871 -278.496223) (xy 311.812046 -278.494242) (xy 311.860901 -278.500174)
			(xy 311.908172 -278.513866) (xy 311.952634 -278.534964) (xy 311.993137 -278.56292) (xy 312.02863 -278.597012)
			(xy 312.058195 -278.636356) (xy 312.081066 -278.679933) (xy 312.09665 -278.726614) (xy 312.104545 -278.775191)
			(xy 312.10504 -278.799798) (xy 312.104545 -278.824405) (xy 312.104366 -278.825506) (xy 312.423044 -278.825506)
			(xy 312.423044 -278.77409) (xy 312.431087 -278.723308) (xy 312.446975 -278.674409) (xy 312.470318 -278.628597)
			(xy 312.500539 -278.587001) (xy 312.536895 -278.550645) (xy 312.578491 -278.520424) (xy 312.624303 -278.497081)
			(xy 312.673202 -278.481193) (xy 312.723984 -278.47315) (xy 312.7754 -278.47315) (xy 312.826182 -278.481193)
			(xy 312.875081 -278.497081) (xy 312.920893 -278.520424) (xy 312.962489 -278.550645) (xy 312.998845 -278.587001)
			(xy 313.029066 -278.628597) (xy 313.052409 -278.674409) (xy 313.068297 -278.723308) (xy 313.07634 -278.77409)
			(xy 313.076844 -278.799798) (xy 313.394102 -278.799798) (xy 313.398062 -278.750744) (xy 313.409839 -278.70296)
			(xy 313.42913 -278.657684) (xy 313.455433 -278.616088) (xy 313.488068 -278.579251) (xy 313.526189 -278.548126)
			(xy 313.56881 -278.523519) (xy 313.614826 -278.506067) (xy 313.663045 -278.496223) (xy 313.71222 -278.494242)
			(xy 313.761075 -278.500174) (xy 313.808346 -278.513866) (xy 313.852808 -278.534964) (xy 313.893311 -278.56292)
			(xy 313.928804 -278.597012) (xy 313.958369 -278.636356) (xy 313.98124 -278.679933) (xy 313.996824 -278.726614)
			(xy 314.004719 -278.775191) (xy 314.005214 -278.799798) (xy 314.344062 -278.799798) (xy 314.348022 -278.750744)
			(xy 314.359799 -278.70296) (xy 314.37909 -278.657684) (xy 314.405393 -278.616088) (xy 314.438028 -278.579251)
			(xy 314.476149 -278.548126) (xy 314.51877 -278.523519) (xy 314.564786 -278.506067) (xy 314.613005 -278.496223)
			(xy 314.66218 -278.494242) (xy 314.711035 -278.500174) (xy 314.758306 -278.513866) (xy 314.802768 -278.534964)
			(xy 314.843271 -278.56292) (xy 314.878764 -278.597012) (xy 314.908329 -278.636356) (xy 314.9312 -278.679933)
			(xy 314.946784 -278.726614) (xy 314.954679 -278.775191) (xy 314.955174 -278.799798) (xy 314.954679 -278.824405)
			(xy 314.946784 -278.872982) (xy 314.9312 -278.919663) (xy 314.908329 -278.96324) (xy 314.878764 -279.002584)
			(xy 314.843271 -279.036676) (xy 314.802768 -279.064632) (xy 314.758306 -279.08573) (xy 314.711035 -279.099422)
			(xy 314.66218 -279.105354) (xy 314.613005 -279.103373) (xy 314.564786 -279.093529) (xy 314.51877 -279.076077)
			(xy 314.476149 -279.05147) (xy 314.438028 -279.020345) (xy 314.405393 -278.983508) (xy 314.37909 -278.941912)
			(xy 314.359799 -278.896636) (xy 314.348022 -278.848852) (xy 314.344062 -278.799798) (xy 314.005214 -278.799798)
			(xy 314.004719 -278.824405) (xy 313.996824 -278.872982) (xy 313.98124 -278.919663) (xy 313.958369 -278.96324)
			(xy 313.928804 -279.002584) (xy 313.893311 -279.036676) (xy 313.852808 -279.064632) (xy 313.808346 -279.08573)
			(xy 313.761075 -279.099422) (xy 313.71222 -279.105354) (xy 313.663045 -279.103373) (xy 313.614826 -279.093529)
			(xy 313.56881 -279.076077) (xy 313.526189 -279.05147) (xy 313.488068 -279.020345) (xy 313.455433 -278.983508)
			(xy 313.42913 -278.941912) (xy 313.409839 -278.896636) (xy 313.398062 -278.848852) (xy 313.394102 -278.799798)
			(xy 313.076844 -278.799798) (xy 313.07634 -278.825506) (xy 313.068297 -278.876288) (xy 313.052409 -278.925187)
			(xy 313.029066 -278.970999) (xy 312.998845 -279.012595) (xy 312.962489 -279.048951) (xy 312.920893 -279.079172)
			(xy 312.875081 -279.102515) (xy 312.826182 -279.118403) (xy 312.7754 -279.126446) (xy 312.723984 -279.126446)
			(xy 312.673202 -279.118403) (xy 312.624303 -279.102515) (xy 312.578491 -279.079172) (xy 312.536895 -279.048951)
			(xy 312.500539 -279.012595) (xy 312.470318 -278.970999) (xy 312.446975 -278.925187) (xy 312.431087 -278.876288)
			(xy 312.423044 -278.825506) (xy 312.104366 -278.825506) (xy 312.09665 -278.872982) (xy 312.081066 -278.919663)
			(xy 312.058195 -278.96324) (xy 312.02863 -279.002584) (xy 311.993137 -279.036676) (xy 311.952634 -279.064632)
			(xy 311.908172 -279.08573) (xy 311.860901 -279.099422) (xy 311.812046 -279.105354) (xy 311.762871 -279.103373)
			(xy 311.714652 -279.093529) (xy 311.668636 -279.076077) (xy 311.626015 -279.05147) (xy 311.587894 -279.020345)
			(xy 311.555259 -278.983508) (xy 311.528956 -278.941912) (xy 311.509665 -278.896636) (xy 311.497888 -278.848852)
			(xy 311.493928 -278.799798) (xy 311.17667 -278.799798) (xy 311.176166 -278.825506) (xy 311.168123 -278.876288)
			(xy 311.152235 -278.925187) (xy 311.128892 -278.970999) (xy 311.098671 -279.012595) (xy 311.062315 -279.048951)
			(xy 311.020719 -279.079172) (xy 310.974907 -279.102515) (xy 310.926008 -279.118403) (xy 310.875226 -279.126446)
			(xy 310.82381 -279.126446) (xy 310.773028 -279.118403) (xy 310.724129 -279.102515) (xy 310.678317 -279.079172)
			(xy 310.636721 -279.048951) (xy 310.600365 -279.012595) (xy 310.570144 -278.970999) (xy 310.546801 -278.925187)
			(xy 310.530913 -278.876288) (xy 310.52287 -278.825506) (xy 310.204446 -278.825506) (xy 310.19673 -278.872982)
			(xy 310.181146 -278.919663) (xy 310.158275 -278.96324) (xy 310.12871 -279.002584) (xy 310.093217 -279.036676)
			(xy 310.052714 -279.064632) (xy 310.008252 -279.08573) (xy 309.960981 -279.099422) (xy 309.912126 -279.105354)
			(xy 309.862951 -279.103373) (xy 309.814732 -279.093529) (xy 309.768716 -279.076077) (xy 309.726095 -279.05147)
			(xy 309.687974 -279.020345) (xy 309.655339 -278.983508) (xy 309.629036 -278.941912) (xy 309.609745 -278.896636)
			(xy 309.597968 -278.848852) (xy 309.594008 -278.799798) (xy 309.27675 -278.799798) (xy 309.276246 -278.825506)
			(xy 309.268203 -278.876288) (xy 309.252315 -278.925187) (xy 309.228972 -278.970999) (xy 309.198751 -279.012595)
			(xy 309.162395 -279.048951) (xy 309.120799 -279.079172) (xy 309.074987 -279.102515) (xy 309.026088 -279.118403)
			(xy 308.975306 -279.126446) (xy 308.92389 -279.126446) (xy 308.873108 -279.118403) (xy 308.824209 -279.102515)
			(xy 308.778397 -279.079172) (xy 308.736801 -279.048951) (xy 308.700445 -279.012595) (xy 308.670224 -278.970999)
			(xy 308.646881 -278.925187) (xy 308.630993 -278.876288) (xy 308.62295 -278.825506) (xy 308.304526 -278.825506)
			(xy 308.29681 -278.872982) (xy 308.281226 -278.919663) (xy 308.258355 -278.96324) (xy 308.22879 -279.002584)
			(xy 308.193297 -279.036676) (xy 308.152794 -279.064632) (xy 308.108332 -279.08573) (xy 308.061061 -279.099422)
			(xy 308.012206 -279.105354) (xy 307.963031 -279.103373) (xy 307.914812 -279.093529) (xy 307.868796 -279.076077)
			(xy 307.826175 -279.05147) (xy 307.788054 -279.020345) (xy 307.755419 -278.983508) (xy 307.729116 -278.941912)
			(xy 307.709825 -278.896636) (xy 307.698048 -278.848852) (xy 307.694088 -278.799798) (xy 307.37683 -278.799798)
			(xy 307.376326 -278.825506) (xy 307.368283 -278.876288) (xy 307.352395 -278.925187) (xy 307.329052 -278.970999)
			(xy 307.298831 -279.012595) (xy 307.262475 -279.048951) (xy 307.220879 -279.079172) (xy 307.175067 -279.102515)
			(xy 307.126168 -279.118403) (xy 307.075386 -279.126446) (xy 307.02397 -279.126446) (xy 306.973188 -279.118403)
			(xy 306.924289 -279.102515) (xy 306.878477 -279.079172) (xy 306.836881 -279.048951) (xy 306.800525 -279.012595)
			(xy 306.770304 -278.970999) (xy 306.746961 -278.925187) (xy 306.731073 -278.876288) (xy 306.72303 -278.825506)
			(xy 306.404352 -278.825506) (xy 306.396636 -278.872982) (xy 306.381052 -278.919663) (xy 306.358181 -278.96324)
			(xy 306.328616 -279.002584) (xy 306.293123 -279.036676) (xy 306.25262 -279.064632) (xy 306.208158 -279.08573)
			(xy 306.160887 -279.099422) (xy 306.112032 -279.105354) (xy 306.062857 -279.103373) (xy 306.014638 -279.093529)
			(xy 305.968622 -279.076077) (xy 305.926001 -279.05147) (xy 305.88788 -279.020345) (xy 305.855245 -278.983508)
			(xy 305.828942 -278.941912) (xy 305.809651 -278.896636) (xy 305.797874 -278.848852) (xy 305.793914 -278.799798)
			(xy 305.476656 -278.799798) (xy 305.476152 -278.825506) (xy 305.468109 -278.876288) (xy 305.452221 -278.925187)
			(xy 305.428878 -278.970999) (xy 305.398657 -279.012595) (xy 305.362301 -279.048951) (xy 305.320705 -279.079172)
			(xy 305.274893 -279.102515) (xy 305.225994 -279.118403) (xy 305.175212 -279.126446) (xy 305.123796 -279.126446)
			(xy 305.073014 -279.118403) (xy 305.024115 -279.102515) (xy 304.978303 -279.079172) (xy 304.936707 -279.048951)
			(xy 304.900351 -279.012595) (xy 304.87013 -278.970999) (xy 304.846787 -278.925187) (xy 304.830899 -278.876288)
			(xy 304.822856 -278.825506) (xy 304.504432 -278.825506) (xy 304.496716 -278.872982) (xy 304.481132 -278.919663)
			(xy 304.458261 -278.96324) (xy 304.428696 -279.002584) (xy 304.393203 -279.036676) (xy 304.3527 -279.064632)
			(xy 304.308238 -279.08573) (xy 304.260967 -279.099422) (xy 304.212112 -279.105354) (xy 304.162937 -279.103373)
			(xy 304.114718 -279.093529) (xy 304.068702 -279.076077) (xy 304.026081 -279.05147) (xy 303.98796 -279.020345)
			(xy 303.955325 -278.983508) (xy 303.929022 -278.941912) (xy 303.909731 -278.896636) (xy 303.897954 -278.848852)
			(xy 303.893994 -278.799798) (xy 303.576736 -278.799798) (xy 303.576232 -278.825506) (xy 303.568189 -278.876288)
			(xy 303.552301 -278.925187) (xy 303.528958 -278.970999) (xy 303.498737 -279.012595) (xy 303.462381 -279.048951)
			(xy 303.420785 -279.079172) (xy 303.374973 -279.102515) (xy 303.326074 -279.118403) (xy 303.275292 -279.126446)
			(xy 303.223876 -279.126446) (xy 303.173094 -279.118403) (xy 303.124195 -279.102515) (xy 303.078383 -279.079172)
			(xy 303.036787 -279.048951) (xy 303.000431 -279.012595) (xy 302.97021 -278.970999) (xy 302.946867 -278.925187)
			(xy 302.930979 -278.876288) (xy 302.922936 -278.825506) (xy 302.604512 -278.825506) (xy 302.596796 -278.872982)
			(xy 302.581212 -278.919663) (xy 302.558341 -278.96324) (xy 302.528776 -279.002584) (xy 302.493283 -279.036676)
			(xy 302.45278 -279.064632) (xy 302.408318 -279.08573) (xy 302.361047 -279.099422) (xy 302.312192 -279.105354)
			(xy 302.263017 -279.103373) (xy 302.214798 -279.093529) (xy 302.168782 -279.076077) (xy 302.126161 -279.05147)
			(xy 302.08804 -279.020345) (xy 302.055405 -278.983508) (xy 302.029102 -278.941912) (xy 302.009811 -278.896636)
			(xy 301.998034 -278.848852) (xy 301.994074 -278.799798) (xy 301.676816 -278.799798) (xy 301.676312 -278.825506)
			(xy 301.668269 -278.876288) (xy 301.652381 -278.925187) (xy 301.629038 -278.970999) (xy 301.598817 -279.012595)
			(xy 301.562461 -279.048951) (xy 301.520865 -279.079172) (xy 301.475053 -279.102515) (xy 301.426154 -279.118403)
			(xy 301.375372 -279.126446) (xy 301.323956 -279.126446) (xy 301.273174 -279.118403) (xy 301.224275 -279.102515)
			(xy 301.178463 -279.079172) (xy 301.136867 -279.048951) (xy 301.100511 -279.012595) (xy 301.07029 -278.970999)
			(xy 301.046947 -278.925187) (xy 301.031059 -278.876288) (xy 301.023016 -278.825506) (xy 300.704338 -278.825506)
			(xy 300.696622 -278.872982) (xy 300.681038 -278.919663) (xy 300.658167 -278.96324) (xy 300.628602 -279.002584)
			(xy 300.593109 -279.036676) (xy 300.552606 -279.064632) (xy 300.508144 -279.08573) (xy 300.460873 -279.099422)
			(xy 300.412018 -279.105354) (xy 300.362843 -279.103373) (xy 300.314624 -279.093529) (xy 300.268608 -279.076077)
			(xy 300.225987 -279.05147) (xy 300.187866 -279.020345) (xy 300.155231 -278.983508) (xy 300.128928 -278.941912)
			(xy 300.109637 -278.896636) (xy 300.09786 -278.848852) (xy 300.0939 -278.799798) (xy 299.776642 -278.799798)
			(xy 299.776138 -278.825506) (xy 299.768095 -278.876288) (xy 299.752207 -278.925187) (xy 299.728864 -278.970999)
			(xy 299.698643 -279.012595) (xy 299.662287 -279.048951) (xy 299.620691 -279.079172) (xy 299.574879 -279.102515)
			(xy 299.52598 -279.118403) (xy 299.475198 -279.126446) (xy 299.423782 -279.126446) (xy 299.373 -279.118403)
			(xy 299.324101 -279.102515) (xy 299.278289 -279.079172) (xy 299.236693 -279.048951) (xy 299.200337 -279.012595)
			(xy 299.170116 -278.970999) (xy 299.146773 -278.925187) (xy 299.130885 -278.876288) (xy 299.122842 -278.825506)
			(xy 298.804418 -278.825506) (xy 298.796702 -278.872982) (xy 298.781118 -278.919663) (xy 298.758247 -278.96324)
			(xy 298.728682 -279.002584) (xy 298.693189 -279.036676) (xy 298.652686 -279.064632) (xy 298.608224 -279.08573)
			(xy 298.560953 -279.099422) (xy 298.512098 -279.105354) (xy 298.462923 -279.103373) (xy 298.414704 -279.093529)
			(xy 298.368688 -279.076077) (xy 298.326067 -279.05147) (xy 298.287946 -279.020345) (xy 298.255311 -278.983508)
			(xy 298.229008 -278.941912) (xy 298.209717 -278.896636) (xy 298.19794 -278.848852) (xy 298.19398 -278.799798)
			(xy 297.876722 -278.799798) (xy 297.876218 -278.825506) (xy 297.868175 -278.876288) (xy 297.852287 -278.925187)
			(xy 297.828944 -278.970999) (xy 297.798723 -279.012595) (xy 297.762367 -279.048951) (xy 297.720771 -279.079172)
			(xy 297.674959 -279.102515) (xy 297.62606 -279.118403) (xy 297.575278 -279.126446) (xy 297.523862 -279.126446)
			(xy 297.47308 -279.118403) (xy 297.424181 -279.102515) (xy 297.378369 -279.079172) (xy 297.336773 -279.048951)
			(xy 297.300417 -279.012595) (xy 297.270196 -278.970999) (xy 297.246853 -278.925187) (xy 297.230965 -278.876288)
			(xy 297.222922 -278.825506) (xy 296.904498 -278.825506) (xy 296.896782 -278.872982) (xy 296.881198 -278.919663)
			(xy 296.858327 -278.96324) (xy 296.828762 -279.002584) (xy 296.793269 -279.036676) (xy 296.752766 -279.064632)
			(xy 296.708304 -279.08573) (xy 296.661033 -279.099422) (xy 296.612178 -279.105354) (xy 296.563003 -279.103373)
			(xy 296.514784 -279.093529) (xy 296.468768 -279.076077) (xy 296.426147 -279.05147) (xy 296.388026 -279.020345)
			(xy 296.355391 -278.983508) (xy 296.329088 -278.941912) (xy 296.309797 -278.896636) (xy 296.29802 -278.848852)
			(xy 296.29406 -278.799798) (xy 295.976802 -278.799798) (xy 295.976298 -278.825506) (xy 295.968255 -278.876288)
			(xy 295.952367 -278.925187) (xy 295.929024 -278.970999) (xy 295.898803 -279.012595) (xy 295.862447 -279.048951)
			(xy 295.820851 -279.079172) (xy 295.775039 -279.102515) (xy 295.72614 -279.118403) (xy 295.675358 -279.126446)
			(xy 295.623942 -279.126446) (xy 295.57316 -279.118403) (xy 295.524261 -279.102515) (xy 295.478449 -279.079172)
			(xy 295.436853 -279.048951) (xy 295.400497 -279.012595) (xy 295.370276 -278.970999) (xy 295.346933 -278.925187)
			(xy 295.331045 -278.876288) (xy 295.323002 -278.825506) (xy 295.004324 -278.825506) (xy 294.996608 -278.872982)
			(xy 294.981024 -278.919663) (xy 294.958153 -278.96324) (xy 294.928588 -279.002584) (xy 294.893095 -279.036676)
			(xy 294.852592 -279.064632) (xy 294.80813 -279.08573) (xy 294.760859 -279.099422) (xy 294.712004 -279.105354)
			(xy 294.662829 -279.103373) (xy 294.61461 -279.093529) (xy 294.568594 -279.076077) (xy 294.525973 -279.05147)
			(xy 294.487852 -279.020345) (xy 294.455217 -278.983508) (xy 294.428914 -278.941912) (xy 294.409623 -278.896636)
			(xy 294.397846 -278.848852) (xy 294.393886 -278.799798) (xy 294.076628 -278.799798) (xy 294.076124 -278.825506)
			(xy 294.068081 -278.876288) (xy 294.052193 -278.925187) (xy 294.02885 -278.970999) (xy 293.998629 -279.012595)
			(xy 293.962273 -279.048951) (xy 293.920677 -279.079172) (xy 293.874865 -279.102515) (xy 293.825966 -279.118403)
			(xy 293.775184 -279.126446) (xy 293.723768 -279.126446) (xy 293.672986 -279.118403) (xy 293.624087 -279.102515)
			(xy 293.578275 -279.079172) (xy 293.536679 -279.048951) (xy 293.500323 -279.012595) (xy 293.470102 -278.970999)
			(xy 293.446759 -278.925187) (xy 293.430871 -278.876288) (xy 293.422828 -278.825506) (xy 293.104404 -278.825506)
			(xy 293.096688 -278.872982) (xy 293.081104 -278.919663) (xy 293.058233 -278.96324) (xy 293.028668 -279.002584)
			(xy 292.993175 -279.036676) (xy 292.952672 -279.064632) (xy 292.90821 -279.08573) (xy 292.860939 -279.099422)
			(xy 292.812084 -279.105354) (xy 292.762909 -279.103373) (xy 292.71469 -279.093529) (xy 292.668674 -279.076077)
			(xy 292.626053 -279.05147) (xy 292.587932 -279.020345) (xy 292.555297 -278.983508) (xy 292.528994 -278.941912)
			(xy 292.509703 -278.896636) (xy 292.497926 -278.848852) (xy 292.493966 -278.799798) (xy 292.176708 -278.799798)
			(xy 292.176204 -278.825506) (xy 292.168161 -278.876288) (xy 292.152273 -278.925187) (xy 292.12893 -278.970999)
			(xy 292.098709 -279.012595) (xy 292.062353 -279.048951) (xy 292.020757 -279.079172) (xy 291.974945 -279.102515)
			(xy 291.926046 -279.118403) (xy 291.875264 -279.126446) (xy 291.823848 -279.126446) (xy 291.773066 -279.118403)
			(xy 291.724167 -279.102515) (xy 291.678355 -279.079172) (xy 291.636759 -279.048951) (xy 291.600403 -279.012595)
			(xy 291.570182 -278.970999) (xy 291.546839 -278.925187) (xy 291.530951 -278.876288) (xy 291.522908 -278.825506)
			(xy 291.204484 -278.825506) (xy 291.196768 -278.872982) (xy 291.181184 -278.919663) (xy 291.158313 -278.96324)
			(xy 291.128748 -279.002584) (xy 291.093255 -279.036676) (xy 291.052752 -279.064632) (xy 291.00829 -279.08573)
			(xy 290.961019 -279.099422) (xy 290.912164 -279.105354) (xy 290.862989 -279.103373) (xy 290.81477 -279.093529)
			(xy 290.768754 -279.076077) (xy 290.726133 -279.05147) (xy 290.688012 -279.020345) (xy 290.655377 -278.983508)
			(xy 290.629074 -278.941912) (xy 290.609783 -278.896636) (xy 290.598006 -278.848852) (xy 290.594046 -278.799798)
			(xy 290.277042 -278.799798) (xy 290.276538 -278.825506) (xy 290.268495 -278.876288) (xy 290.252607 -278.925187)
			(xy 290.229264 -278.970999) (xy 290.199043 -279.012595) (xy 290.162687 -279.048951) (xy 290.121091 -279.079172)
			(xy 290.075279 -279.102515) (xy 290.02638 -279.118403) (xy 289.975598 -279.126446) (xy 289.924182 -279.126446)
			(xy 289.8734 -279.118403) (xy 289.824501 -279.102515) (xy 289.778689 -279.079172) (xy 289.737093 -279.048951)
			(xy 289.700737 -279.012595) (xy 289.670516 -278.970999) (xy 289.647173 -278.925187) (xy 289.631285 -278.876288)
			(xy 289.623242 -278.825506) (xy 289.304564 -278.825506) (xy 289.296848 -278.872982) (xy 289.281264 -278.919663)
			(xy 289.258393 -278.96324) (xy 289.228828 -279.002584) (xy 289.193335 -279.036676) (xy 289.152832 -279.064632)
			(xy 289.10837 -279.08573) (xy 289.061099 -279.099422) (xy 289.012244 -279.105354) (xy 288.963069 -279.103373)
			(xy 288.91485 -279.093529) (xy 288.868834 -279.076077) (xy 288.826213 -279.05147) (xy 288.788092 -279.020345)
			(xy 288.755457 -278.983508) (xy 288.729154 -278.941912) (xy 288.709863 -278.896636) (xy 288.698086 -278.848852)
			(xy 288.694126 -278.799798) (xy 288.376868 -278.799798) (xy 288.376364 -278.825506) (xy 288.368321 -278.876288)
			(xy 288.352433 -278.925187) (xy 288.32909 -278.970999) (xy 288.298869 -279.012595) (xy 288.262513 -279.048951)
			(xy 288.220917 -279.079172) (xy 288.175105 -279.102515) (xy 288.126206 -279.118403) (xy 288.075424 -279.126446)
			(xy 288.024008 -279.126446) (xy 287.973226 -279.118403) (xy 287.924327 -279.102515) (xy 287.878515 -279.079172)
			(xy 287.836919 -279.048951) (xy 287.800563 -279.012595) (xy 287.770342 -278.970999) (xy 287.746999 -278.925187)
			(xy 287.731111 -278.876288) (xy 287.723068 -278.825506) (xy 287.40439 -278.825506) (xy 287.396674 -278.872982)
			(xy 287.38109 -278.919663) (xy 287.358219 -278.96324) (xy 287.328654 -279.002584) (xy 287.293161 -279.036676)
			(xy 287.252658 -279.064632) (xy 287.208196 -279.08573) (xy 287.160925 -279.099422) (xy 287.11207 -279.105354)
			(xy 287.062895 -279.103373) (xy 287.014676 -279.093529) (xy 286.96866 -279.076077) (xy 286.926039 -279.05147)
			(xy 286.887918 -279.020345) (xy 286.855283 -278.983508) (xy 286.82898 -278.941912) (xy 286.809689 -278.896636)
			(xy 286.797912 -278.848852) (xy 286.793952 -278.799798) (xy 286.476948 -278.799798) (xy 286.476444 -278.825506)
			(xy 286.468401 -278.876288) (xy 286.452513 -278.925187) (xy 286.42917 -278.970999) (xy 286.398949 -279.012595)
			(xy 286.362593 -279.048951) (xy 286.320997 -279.079172) (xy 286.275185 -279.102515) (xy 286.226286 -279.118403)
			(xy 286.175504 -279.126446) (xy 286.124088 -279.126446) (xy 286.073306 -279.118403) (xy 286.024407 -279.102515)
			(xy 285.978595 -279.079172) (xy 285.936999 -279.048951) (xy 285.900643 -279.012595) (xy 285.870422 -278.970999)
			(xy 285.847079 -278.925187) (xy 285.831191 -278.876288) (xy 285.823148 -278.825506) (xy 285.50447 -278.825506)
			(xy 285.496754 -278.872982) (xy 285.48117 -278.919663) (xy 285.458299 -278.96324) (xy 285.428734 -279.002584)
			(xy 285.393241 -279.036676) (xy 285.352738 -279.064632) (xy 285.308276 -279.08573) (xy 285.261005 -279.099422)
			(xy 285.21215 -279.105354) (xy 285.162975 -279.103373) (xy 285.114756 -279.093529) (xy 285.06874 -279.076077)
			(xy 285.026119 -279.05147) (xy 284.987998 -279.020345) (xy 284.955363 -278.983508) (xy 284.92906 -278.941912)
			(xy 284.909769 -278.896636) (xy 284.897992 -278.848852) (xy 284.894032 -278.799798) (xy 284.577028 -278.799798)
			(xy 284.576524 -278.825506) (xy 284.568481 -278.876288) (xy 284.552593 -278.925187) (xy 284.52925 -278.970999)
			(xy 284.499029 -279.012595) (xy 284.462673 -279.048951) (xy 284.421077 -279.079172) (xy 284.375265 -279.102515)
			(xy 284.326366 -279.118403) (xy 284.275584 -279.126446) (xy 284.224168 -279.126446) (xy 284.173386 -279.118403)
			(xy 284.124487 -279.102515) (xy 284.078675 -279.079172) (xy 284.037079 -279.048951) (xy 284.000723 -279.012595)
			(xy 283.970502 -278.970999) (xy 283.947159 -278.925187) (xy 283.931271 -278.876288) (xy 283.923228 -278.825506)
			(xy 283.60455 -278.825506) (xy 283.596834 -278.872982) (xy 283.58125 -278.919663) (xy 283.558379 -278.96324)
			(xy 283.528814 -279.002584) (xy 283.493321 -279.036676) (xy 283.452818 -279.064632) (xy 283.408356 -279.08573)
			(xy 283.361085 -279.099422) (xy 283.31223 -279.105354) (xy 283.263055 -279.103373) (xy 283.214836 -279.093529)
			(xy 283.16882 -279.076077) (xy 283.126199 -279.05147) (xy 283.088078 -279.020345) (xy 283.055443 -278.983508)
			(xy 283.02914 -278.941912) (xy 283.009849 -278.896636) (xy 282.998072 -278.848852) (xy 282.994112 -278.799798)
			(xy 282.676854 -278.799798) (xy 282.67635 -278.825506) (xy 282.668307 -278.876288) (xy 282.652419 -278.925187)
			(xy 282.629076 -278.970999) (xy 282.598855 -279.012595) (xy 282.562499 -279.048951) (xy 282.520903 -279.079172)
			(xy 282.475091 -279.102515) (xy 282.426192 -279.118403) (xy 282.37541 -279.126446) (xy 282.323994 -279.126446)
			(xy 282.273212 -279.118403) (xy 282.224313 -279.102515) (xy 282.178501 -279.079172) (xy 282.136905 -279.048951)
			(xy 282.100549 -279.012595) (xy 282.070328 -278.970999) (xy 282.046985 -278.925187) (xy 282.031097 -278.876288)
			(xy 282.023054 -278.825506) (xy 281.704376 -278.825506) (xy 281.69666 -278.872982) (xy 281.681076 -278.919663)
			(xy 281.658205 -278.96324) (xy 281.62864 -279.002584) (xy 281.593147 -279.036676) (xy 281.552644 -279.064632)
			(xy 281.508182 -279.08573) (xy 281.460911 -279.099422) (xy 281.412056 -279.105354) (xy 281.362881 -279.103373)
			(xy 281.314662 -279.093529) (xy 281.268646 -279.076077) (xy 281.226025 -279.05147) (xy 281.187904 -279.020345)
			(xy 281.155269 -278.983508) (xy 281.128966 -278.941912) (xy 281.109675 -278.896636) (xy 281.097898 -278.848852)
			(xy 281.093938 -278.799798) (xy 280.776934 -278.799798) (xy 280.77643 -278.825506) (xy 280.768387 -278.876288)
			(xy 280.752499 -278.925187) (xy 280.729156 -278.970999) (xy 280.698935 -279.012595) (xy 280.662579 -279.048951)
			(xy 280.620983 -279.079172) (xy 280.575171 -279.102515) (xy 280.526272 -279.118403) (xy 280.47549 -279.126446)
			(xy 280.424074 -279.126446) (xy 280.373292 -279.118403) (xy 280.324393 -279.102515) (xy 280.278581 -279.079172)
			(xy 280.236985 -279.048951) (xy 280.200629 -279.012595) (xy 280.170408 -278.970999) (xy 280.147065 -278.925187)
			(xy 280.131177 -278.876288) (xy 280.123134 -278.825506) (xy 279.804456 -278.825506) (xy 279.79674 -278.872982)
			(xy 279.781156 -278.919663) (xy 279.758285 -278.96324) (xy 279.72872 -279.002584) (xy 279.693227 -279.036676)
			(xy 279.652724 -279.064632) (xy 279.608262 -279.08573) (xy 279.560991 -279.099422) (xy 279.512136 -279.105354)
			(xy 279.462961 -279.103373) (xy 279.414742 -279.093529) (xy 279.368726 -279.076077) (xy 279.326105 -279.05147)
			(xy 279.287984 -279.020345) (xy 279.255349 -278.983508) (xy 279.229046 -278.941912) (xy 279.209755 -278.896636)
			(xy 279.197978 -278.848852) (xy 279.194018 -278.799798) (xy 278.877014 -278.799798) (xy 278.87651 -278.825506)
			(xy 278.868467 -278.876288) (xy 278.852579 -278.925187) (xy 278.829236 -278.970999) (xy 278.799015 -279.012595)
			(xy 278.762659 -279.048951) (xy 278.721063 -279.079172) (xy 278.675251 -279.102515) (xy 278.626352 -279.118403)
			(xy 278.57557 -279.126446) (xy 278.524154 -279.126446) (xy 278.473372 -279.118403) (xy 278.424473 -279.102515)
			(xy 278.378661 -279.079172) (xy 278.337065 -279.048951) (xy 278.300709 -279.012595) (xy 278.270488 -278.970999)
			(xy 278.247145 -278.925187) (xy 278.231257 -278.876288) (xy 278.223214 -278.825506) (xy 277.904536 -278.825506)
			(xy 277.89682 -278.872982) (xy 277.881236 -278.919663) (xy 277.858365 -278.96324) (xy 277.8288 -279.002584)
			(xy 277.793307 -279.036676) (xy 277.752804 -279.064632) (xy 277.708342 -279.08573) (xy 277.661071 -279.099422)
			(xy 277.612216 -279.105354) (xy 277.563041 -279.103373) (xy 277.514822 -279.093529) (xy 277.468806 -279.076077)
			(xy 277.426185 -279.05147) (xy 277.388064 -279.020345) (xy 277.355429 -278.983508) (xy 277.329126 -278.941912)
			(xy 277.309835 -278.896636) (xy 277.298058 -278.848852) (xy 277.294098 -278.799798) (xy 276.97684 -278.799798)
			(xy 276.976336 -278.825506) (xy 276.968293 -278.876288) (xy 276.952405 -278.925187) (xy 276.929062 -278.970999)
			(xy 276.898841 -279.012595) (xy 276.862485 -279.048951) (xy 276.820889 -279.079172) (xy 276.775077 -279.102515)
			(xy 276.726178 -279.118403) (xy 276.675396 -279.126446) (xy 276.62398 -279.126446) (xy 276.573198 -279.118403)
			(xy 276.524299 -279.102515) (xy 276.478487 -279.079172) (xy 276.436891 -279.048951) (xy 276.400535 -279.012595)
			(xy 276.370314 -278.970999) (xy 276.346971 -278.925187) (xy 276.331083 -278.876288) (xy 276.32304 -278.825506)
			(xy 251.717554 -278.825506) (xy 251.717301 -278.839368) (xy 251.709181 -278.894544) (xy 251.693113 -278.947951)
			(xy 251.669441 -278.998448) (xy 251.638668 -279.044961) (xy 251.601451 -279.086498) (xy 251.558583 -279.122173)
			(xy 251.510977 -279.151227) (xy 251.459648 -279.173039) (xy 251.405691 -279.187145) (xy 251.350254 -279.193245)
			(xy 251.29452 -279.191208) (xy 251.239677 -279.181078) (xy 251.186893 -279.163071) (xy 251.137293 -279.13757)
			(xy 251.091935 -279.105119) (xy 251.051786 -279.06641) (xy 251.0177 -279.022267) (xy 250.990404 -278.973632)
			(xy 250.970481 -278.921541) (xy 250.958355 -278.867104) (xy 250.954284 -278.811482) (xy 249.429284 -278.811482)
			(xy 249.442211 -278.826401) (xy 249.471677 -278.872251) (xy 249.494319 -278.921828) (xy 249.509674 -278.974123)
			(xy 249.51743 -279.028071) (xy 249.517916 -279.055322) (xy 249.517455 -279.081534) (xy 249.510291 -279.133466)
			(xy 249.496087 -279.183928) (xy 249.47511 -279.231972) (xy 249.448927 -279.274778) (xy 268.26897 -279.274778)
			(xy 268.27293 -279.225724) (xy 268.284707 -279.17794) (xy 268.303998 -279.132664) (xy 268.330301 -279.091068)
			(xy 268.362936 -279.054231) (xy 268.401057 -279.023106) (xy 268.443678 -278.998499) (xy 268.489694 -278.981047)
			(xy 268.537913 -278.971203) (xy 268.587088 -278.969222) (xy 268.635943 -278.975154) (xy 268.683214 -278.988846)
			(xy 268.727676 -279.009944) (xy 268.768179 -279.0379) (xy 268.803672 -279.071992) (xy 268.833237 -279.111336)
			(xy 268.856108 -279.154913) (xy 268.871692 -279.201594) (xy 268.879587 -279.250171) (xy 268.880082 -279.274778)
			(xy 269.21893 -279.274778) (xy 269.22289 -279.225724) (xy 269.234667 -279.17794) (xy 269.253958 -279.132664)
			(xy 269.280261 -279.091068) (xy 269.312896 -279.054231) (xy 269.351017 -279.023106) (xy 269.393638 -278.998499)
			(xy 269.439654 -278.981047) (xy 269.487873 -278.971203) (xy 269.537048 -278.969222) (xy 269.585903 -278.975154)
			(xy 269.633174 -278.988846) (xy 269.677636 -279.009944) (xy 269.718139 -279.0379) (xy 269.753632 -279.071992)
			(xy 269.783197 -279.111336) (xy 269.806068 -279.154913) (xy 269.821652 -279.201594) (xy 269.829547 -279.250171)
			(xy 269.830042 -279.274778) (xy 270.169144 -279.274778) (xy 270.173104 -279.225724) (xy 270.184881 -279.17794)
			(xy 270.204172 -279.132664) (xy 270.230475 -279.091068) (xy 270.26311 -279.054231) (xy 270.301231 -279.023106)
			(xy 270.343852 -278.998499) (xy 270.389868 -278.981047) (xy 270.438087 -278.971203) (xy 270.487262 -278.969222)
			(xy 270.536117 -278.975154) (xy 270.583388 -278.988846) (xy 270.62785 -279.009944) (xy 270.668353 -279.0379)
			(xy 270.703846 -279.071992) (xy 270.733411 -279.111336) (xy 270.756282 -279.154913) (xy 270.771866 -279.201594)
			(xy 270.779761 -279.250171) (xy 270.780256 -279.274778) (xy 271.119104 -279.274778) (xy 271.123064 -279.225724)
			(xy 271.134841 -279.17794) (xy 271.154132 -279.132664) (xy 271.180435 -279.091068) (xy 271.21307 -279.054231)
			(xy 271.251191 -279.023106) (xy 271.293812 -278.998499) (xy 271.339828 -278.981047) (xy 271.388047 -278.971203)
			(xy 271.437222 -278.969222) (xy 271.486077 -278.975154) (xy 271.533348 -278.988846) (xy 271.57781 -279.009944)
			(xy 271.618313 -279.0379) (xy 271.653806 -279.071992) (xy 271.683371 -279.111336) (xy 271.706242 -279.154913)
			(xy 271.721826 -279.201594) (xy 271.729721 -279.250171) (xy 271.730216 -279.274778) (xy 272.069064 -279.274778)
			(xy 272.073024 -279.225724) (xy 272.084801 -279.17794) (xy 272.104092 -279.132664) (xy 272.130395 -279.091068)
			(xy 272.16303 -279.054231) (xy 272.201151 -279.023106) (xy 272.243772 -278.998499) (xy 272.289788 -278.981047)
			(xy 272.338007 -278.971203) (xy 272.387182 -278.969222) (xy 272.436037 -278.975154) (xy 272.483308 -278.988846)
			(xy 272.52777 -279.009944) (xy 272.568273 -279.0379) (xy 272.603766 -279.071992) (xy 272.633331 -279.111336)
			(xy 272.656202 -279.154913) (xy 272.671786 -279.201594) (xy 272.679681 -279.250171) (xy 272.680176 -279.274778)
			(xy 273.019024 -279.274778) (xy 273.022984 -279.225724) (xy 273.034761 -279.17794) (xy 273.054052 -279.132664)
			(xy 273.080355 -279.091068) (xy 273.11299 -279.054231) (xy 273.151111 -279.023106) (xy 273.193732 -278.998499)
			(xy 273.239748 -278.981047) (xy 273.287967 -278.971203) (xy 273.337142 -278.969222) (xy 273.385997 -278.975154)
			(xy 273.433268 -278.988846) (xy 273.47773 -279.009944) (xy 273.518233 -279.0379) (xy 273.553726 -279.071992)
			(xy 273.583291 -279.111336) (xy 273.606162 -279.154913) (xy 273.621746 -279.201594) (xy 273.629641 -279.250171)
			(xy 273.630136 -279.274778) (xy 273.968984 -279.274778) (xy 273.972944 -279.225724) (xy 273.984721 -279.17794)
			(xy 274.004012 -279.132664) (xy 274.030315 -279.091068) (xy 274.06295 -279.054231) (xy 274.101071 -279.023106)
			(xy 274.143692 -278.998499) (xy 274.189708 -278.981047) (xy 274.237927 -278.971203) (xy 274.287102 -278.969222)
			(xy 274.335957 -278.975154) (xy 274.383228 -278.988846) (xy 274.42769 -279.009944) (xy 274.468193 -279.0379)
			(xy 274.503686 -279.071992) (xy 274.533251 -279.111336) (xy 274.556122 -279.154913) (xy 274.571706 -279.201594)
			(xy 274.579601 -279.250171) (xy 274.580096 -279.274778) (xy 274.918944 -279.274778) (xy 274.922904 -279.225724)
			(xy 274.934681 -279.17794) (xy 274.953972 -279.132664) (xy 274.980275 -279.091068) (xy 275.01291 -279.054231)
			(xy 275.051031 -279.023106) (xy 275.093652 -278.998499) (xy 275.139668 -278.981047) (xy 275.187887 -278.971203)
			(xy 275.237062 -278.969222) (xy 275.285917 -278.975154) (xy 275.333188 -278.988846) (xy 275.37765 -279.009944)
			(xy 275.418153 -279.0379) (xy 275.453646 -279.071992) (xy 275.483211 -279.111336) (xy 275.506082 -279.154913)
			(xy 275.521666 -279.201594) (xy 275.529561 -279.250171) (xy 275.530056 -279.274778) (xy 275.529561 -279.299385)
			(xy 275.521666 -279.347962) (xy 275.506082 -279.394643) (xy 275.483211 -279.43822) (xy 275.453646 -279.477564)
			(xy 275.418153 -279.511656) (xy 275.37765 -279.539612) (xy 275.333188 -279.56071) (xy 275.285917 -279.574402)
			(xy 275.237062 -279.580334) (xy 275.187887 -279.578353) (xy 275.139668 -279.568509) (xy 275.093652 -279.551057)
			(xy 275.051031 -279.52645) (xy 275.01291 -279.495325) (xy 274.980275 -279.458488) (xy 274.953972 -279.416892)
			(xy 274.934681 -279.371616) (xy 274.922904 -279.323832) (xy 274.918944 -279.274778) (xy 274.580096 -279.274778)
			(xy 274.579601 -279.299385) (xy 274.571706 -279.347962) (xy 274.556122 -279.394643) (xy 274.533251 -279.43822)
			(xy 274.503686 -279.477564) (xy 274.468193 -279.511656) (xy 274.42769 -279.539612) (xy 274.383228 -279.56071)
			(xy 274.335957 -279.574402) (xy 274.287102 -279.580334) (xy 274.237927 -279.578353) (xy 274.189708 -279.568509)
			(xy 274.143692 -279.551057) (xy 274.101071 -279.52645) (xy 274.06295 -279.495325) (xy 274.030315 -279.458488)
			(xy 274.004012 -279.416892) (xy 273.984721 -279.371616) (xy 273.972944 -279.323832) (xy 273.968984 -279.274778)
			(xy 273.630136 -279.274778) (xy 273.629641 -279.299385) (xy 273.621746 -279.347962) (xy 273.606162 -279.394643)
			(xy 273.583291 -279.43822) (xy 273.553726 -279.477564) (xy 273.518233 -279.511656) (xy 273.47773 -279.539612)
			(xy 273.433268 -279.56071) (xy 273.385997 -279.574402) (xy 273.337142 -279.580334) (xy 273.287967 -279.578353)
			(xy 273.239748 -279.568509) (xy 273.193732 -279.551057) (xy 273.151111 -279.52645) (xy 273.11299 -279.495325)
			(xy 273.080355 -279.458488) (xy 273.054052 -279.416892) (xy 273.034761 -279.371616) (xy 273.022984 -279.323832)
			(xy 273.019024 -279.274778) (xy 272.680176 -279.274778) (xy 272.679681 -279.299385) (xy 272.671786 -279.347962)
			(xy 272.656202 -279.394643) (xy 272.633331 -279.43822) (xy 272.603766 -279.477564) (xy 272.568273 -279.511656)
			(xy 272.52777 -279.539612) (xy 272.483308 -279.56071) (xy 272.436037 -279.574402) (xy 272.387182 -279.580334)
			(xy 272.338007 -279.578353) (xy 272.289788 -279.568509) (xy 272.243772 -279.551057) (xy 272.201151 -279.52645)
			(xy 272.16303 -279.495325) (xy 272.130395 -279.458488) (xy 272.104092 -279.416892) (xy 272.084801 -279.371616)
			(xy 272.073024 -279.323832) (xy 272.069064 -279.274778) (xy 271.730216 -279.274778) (xy 271.729721 -279.299385)
			(xy 271.721826 -279.347962) (xy 271.706242 -279.394643) (xy 271.683371 -279.43822) (xy 271.653806 -279.477564)
			(xy 271.618313 -279.511656) (xy 271.57781 -279.539612) (xy 271.533348 -279.56071) (xy 271.486077 -279.574402)
			(xy 271.437222 -279.580334) (xy 271.388047 -279.578353) (xy 271.339828 -279.568509) (xy 271.293812 -279.551057)
			(xy 271.251191 -279.52645) (xy 271.21307 -279.495325) (xy 271.180435 -279.458488) (xy 271.154132 -279.416892)
			(xy 271.134841 -279.371616) (xy 271.123064 -279.323832) (xy 271.119104 -279.274778) (xy 270.780256 -279.274778)
			(xy 270.779761 -279.299385) (xy 270.771866 -279.347962) (xy 270.756282 -279.394643) (xy 270.733411 -279.43822)
			(xy 270.703846 -279.477564) (xy 270.668353 -279.511656) (xy 270.62785 -279.539612) (xy 270.583388 -279.56071)
			(xy 270.536117 -279.574402) (xy 270.487262 -279.580334) (xy 270.438087 -279.578353) (xy 270.389868 -279.568509)
			(xy 270.343852 -279.551057) (xy 270.301231 -279.52645) (xy 270.26311 -279.495325) (xy 270.230475 -279.458488)
			(xy 270.204172 -279.416892) (xy 270.184881 -279.371616) (xy 270.173104 -279.323832) (xy 270.169144 -279.274778)
			(xy 269.830042 -279.274778) (xy 269.829547 -279.299385) (xy 269.821652 -279.347962) (xy 269.806068 -279.394643)
			(xy 269.783197 -279.43822) (xy 269.753632 -279.477564) (xy 269.718139 -279.511656) (xy 269.677636 -279.539612)
			(xy 269.633174 -279.56071) (xy 269.585903 -279.574402) (xy 269.537048 -279.580334) (xy 269.487873 -279.578353)
			(xy 269.439654 -279.568509) (xy 269.393638 -279.551057) (xy 269.351017 -279.52645) (xy 269.312896 -279.495325)
			(xy 269.280261 -279.458488) (xy 269.253958 -279.416892) (xy 269.234667 -279.371616) (xy 269.22289 -279.323832)
			(xy 269.21893 -279.274778) (xy 268.880082 -279.274778) (xy 268.879587 -279.299385) (xy 268.871692 -279.347962)
			(xy 268.856108 -279.394643) (xy 268.833237 -279.43822) (xy 268.803672 -279.477564) (xy 268.768179 -279.511656)
			(xy 268.727676 -279.539612) (xy 268.683214 -279.56071) (xy 268.635943 -279.574402) (xy 268.587088 -279.580334)
			(xy 268.537913 -279.578353) (xy 268.489694 -279.568509) (xy 268.443678 -279.551057) (xy 268.401057 -279.52645)
			(xy 268.362936 -279.495325) (xy 268.330301 -279.458488) (xy 268.303998 -279.416892) (xy 268.284707 -279.371616)
			(xy 268.27293 -279.323832) (xy 268.26897 -279.274778) (xy 249.448927 -279.274778) (xy 249.447756 -279.276693)
			(xy 249.414539 -279.31725) (xy 249.376084 -279.352879) (xy 249.354848 -279.36825) (xy 249.343672 -279.37587)
			(xy 249.332242 -279.399746) (xy 249.34037 -279.514046) (xy 249.355102 -279.536144) (xy 249.367294 -279.54224)
			(xy 249.390684 -279.554421) (xy 249.434111 -279.584344) (xy 249.472999 -279.619966) (xy 249.506608 -279.660607)
			(xy 249.534295 -279.705492) (xy 249.555532 -279.753764) (xy 249.569914 -279.804503) (xy 249.577167 -279.856739)
			(xy 249.577606 -279.883108) (xy 249.577153 -279.909006) (xy 249.574136 -279.931114) (xy 258.01142 -279.931114)
			(xy 258.015491 -279.875492) (xy 258.027617 -279.821055) (xy 258.04754 -279.768964) (xy 258.074836 -279.720329)
			(xy 258.108922 -279.676186) (xy 258.149071 -279.637477) (xy 258.194429 -279.605026) (xy 258.244029 -279.579525)
			(xy 258.296813 -279.561518) (xy 258.351656 -279.551388) (xy 258.40739 -279.549351) (xy 258.462827 -279.555451)
			(xy 258.516784 -279.569557) (xy 258.568113 -279.591369) (xy 258.615719 -279.620423) (xy 258.658587 -279.656098)
			(xy 258.695804 -279.697635) (xy 258.726577 -279.744148) (xy 258.750249 -279.794645) (xy 258.766317 -279.848052)
			(xy 258.774437 -279.903228) (xy 258.774946 -279.931114) (xy 259.486906 -279.931114) (xy 259.490977 -279.875492)
			(xy 259.503103 -279.821055) (xy 259.523026 -279.768964) (xy 259.550322 -279.720329) (xy 259.584408 -279.676186)
			(xy 259.624557 -279.637477) (xy 259.669915 -279.605026) (xy 259.719515 -279.579525) (xy 259.772299 -279.561518)
			(xy 259.827142 -279.551388) (xy 259.882876 -279.549351) (xy 259.938313 -279.555451) (xy 259.99227 -279.569557)
			(xy 260.043599 -279.591369) (xy 260.091205 -279.620423) (xy 260.134073 -279.656098) (xy 260.17129 -279.697635)
			(xy 260.202063 -279.744148) (xy 260.225735 -279.794645) (xy 260.241803 -279.848052) (xy 260.249923 -279.903228)
			(xy 260.250432 -279.931114) (xy 260.249923 -279.959) (xy 260.241803 -280.014176) (xy 260.228584 -280.058114)
			(xy 260.375906 -280.058114) (xy 260.379977 -280.002492) (xy 260.392103 -279.948055) (xy 260.412026 -279.895964)
			(xy 260.439322 -279.847329) (xy 260.473408 -279.803186) (xy 260.513557 -279.764477) (xy 260.558915 -279.732026)
			(xy 260.608515 -279.706525) (xy 260.661299 -279.688518) (xy 260.716142 -279.678388) (xy 260.771876 -279.676351)
			(xy 260.827313 -279.682451) (xy 260.88127 -279.696557) (xy 260.932599 -279.718369) (xy 260.980205 -279.747423)
			(xy 261.023073 -279.783098) (xy 261.06029 -279.824635) (xy 261.091063 -279.871148) (xy 261.114735 -279.921645)
			(xy 261.130803 -279.975052) (xy 261.138923 -280.030228) (xy 261.139432 -280.058114) (xy 261.138923 -280.086)
			(xy 261.130803 -280.141176) (xy 261.114735 -280.194583) (xy 261.091063 -280.24508) (xy 261.06029 -280.291593)
			(xy 261.023073 -280.33313) (xy 260.980205 -280.368805) (xy 260.932599 -280.397859) (xy 260.88127 -280.419671)
			(xy 260.827313 -280.433777) (xy 260.771876 -280.439877) (xy 260.716142 -280.43784) (xy 260.661299 -280.42771)
			(xy 260.608515 -280.409703) (xy 260.558915 -280.384202) (xy 260.513557 -280.351751) (xy 260.473408 -280.313042)
			(xy 260.439322 -280.268899) (xy 260.412026 -280.220264) (xy 260.392103 -280.168173) (xy 260.379977 -280.113736)
			(xy 260.375906 -280.058114) (xy 260.228584 -280.058114) (xy 260.225735 -280.067583) (xy 260.202063 -280.11808)
			(xy 260.17129 -280.164593) (xy 260.134073 -280.20613) (xy 260.091205 -280.241805) (xy 260.043599 -280.270859)
			(xy 259.99227 -280.292671) (xy 259.938313 -280.306777) (xy 259.882876 -280.312877) (xy 259.827142 -280.31084)
			(xy 259.772299 -280.30071) (xy 259.719515 -280.282703) (xy 259.669915 -280.257202) (xy 259.624557 -280.224751)
			(xy 259.584408 -280.186042) (xy 259.550322 -280.141899) (xy 259.523026 -280.093264) (xy 259.503103 -280.041173)
			(xy 259.490977 -279.986736) (xy 259.486906 -279.931114) (xy 258.774946 -279.931114) (xy 258.774437 -279.959)
			(xy 258.766317 -280.014176) (xy 258.750249 -280.067583) (xy 258.726577 -280.11808) (xy 258.695804 -280.164593)
			(xy 258.658587 -280.20613) (xy 258.615719 -280.241805) (xy 258.568113 -280.270859) (xy 258.516784 -280.292671)
			(xy 258.462827 -280.306777) (xy 258.40739 -280.312877) (xy 258.351656 -280.31084) (xy 258.296813 -280.30071)
			(xy 258.244029 -280.282703) (xy 258.194429 -280.257202) (xy 258.149071 -280.224751) (xy 258.108922 -280.186042)
			(xy 258.074836 -280.141899) (xy 258.04754 -280.093264) (xy 258.027617 -280.041173) (xy 258.015491 -279.986736)
			(xy 258.01142 -279.931114) (xy 249.574136 -279.931114) (xy 249.570149 -279.960326) (xy 249.556271 -280.010227)
			(xy 249.535775 -280.057795) (xy 249.509035 -280.102154) (xy 249.476544 -280.142491) (xy 249.438897 -280.178066)
			(xy 249.418094 -280.193496) (xy 249.409458 -280.199592) (xy 249.398536 -280.217626) (xy 249.38609 -280.312368)
			(xy 249.391932 -280.332434) (xy 249.39879 -280.340562) (xy 249.415225 -280.361137) (xy 249.442822 -280.405988)
			(xy 249.46398 -280.454211) (xy 249.478295 -280.504889) (xy 249.485494 -280.557055) (xy 249.485912 -280.583386)
			(xy 249.485426 -280.610637) (xy 249.47767 -280.664585) (xy 249.469293 -280.693114) (xy 263.537954 -280.693114)
			(xy 263.53852 -280.663733) (xy 263.547548 -280.605668) (xy 263.565376 -280.549675) (xy 263.591583 -280.49708)
			(xy 263.625547 -280.449128) (xy 263.666466 -280.406954) (xy 263.689592 -280.388822) (xy 263.69899 -280.381456)
			(xy 263.709404 -280.360882) (xy 263.710928 -280.256996) (xy 263.701022 -280.235914) (xy 263.691878 -280.228548)
			(xy 263.670018 -280.210356) (xy 263.63148 -280.168533) (xy 263.599575 -280.121455) (xy 263.57501 -280.070163)
			(xy 263.558329 -280.015793) (xy 263.549902 -279.95955) (xy 263.549384 -279.931114) (xy 263.54987 -279.903863)
			(xy 263.557626 -279.849915) (xy 263.572981 -279.79762) (xy 263.595623 -279.748043) (xy 263.625089 -279.702193)
			(xy 263.66078 -279.661002) (xy 263.701971 -279.625311) (xy 263.747821 -279.595845) (xy 263.797398 -279.573203)
			(xy 263.849693 -279.557848) (xy 263.903641 -279.550092) (xy 263.958143 -279.550092) (xy 264.012091 -279.557848)
			(xy 264.064386 -279.573203) (xy 264.113963 -279.595845) (xy 264.159813 -279.625311) (xy 264.201004 -279.661002)
			(xy 264.236695 -279.702193) (xy 264.266161 -279.748043) (xy 264.266944 -279.749758) (xy 276.343884 -279.749758)
			(xy 276.347844 -279.700704) (xy 276.359621 -279.65292) (xy 276.378912 -279.607644) (xy 276.405215 -279.566048)
			(xy 276.43785 -279.529211) (xy 276.475971 -279.498086) (xy 276.518592 -279.473479) (xy 276.564608 -279.456027)
			(xy 276.612827 -279.446183) (xy 276.662002 -279.444202) (xy 276.710857 -279.450134) (xy 276.758128 -279.463826)
			(xy 276.80259 -279.484924) (xy 276.843093 -279.51288) (xy 276.878586 -279.546972) (xy 276.908151 -279.586316)
			(xy 276.931022 -279.629893) (xy 276.946606 -279.676574) (xy 276.954501 -279.725151) (xy 276.954996 -279.749758)
			(xy 276.954501 -279.774365) (xy 276.954363 -279.775212) (xy 277.273254 -279.775212) (xy 277.273254 -279.723796)
			(xy 277.281297 -279.673014) (xy 277.297185 -279.624115) (xy 277.320528 -279.578303) (xy 277.350749 -279.536707)
			(xy 277.387105 -279.500351) (xy 277.428701 -279.47013) (xy 277.474513 -279.446787) (xy 277.523412 -279.430899)
			(xy 277.574194 -279.422856) (xy 277.62561 -279.422856) (xy 277.676392 -279.430899) (xy 277.725291 -279.446787)
			(xy 277.771103 -279.47013) (xy 277.812699 -279.500351) (xy 277.849055 -279.536707) (xy 277.879276 -279.578303)
			(xy 277.902619 -279.624115) (xy 277.918507 -279.673014) (xy 277.92655 -279.723796) (xy 277.927054 -279.749504)
			(xy 277.927049 -279.749758) (xy 278.244058 -279.749758) (xy 278.248018 -279.700704) (xy 278.259795 -279.65292)
			(xy 278.279086 -279.607644) (xy 278.305389 -279.566048) (xy 278.338024 -279.529211) (xy 278.376145 -279.498086)
			(xy 278.418766 -279.473479) (xy 278.464782 -279.456027) (xy 278.513001 -279.446183) (xy 278.562176 -279.444202)
			(xy 278.611031 -279.450134) (xy 278.658302 -279.463826) (xy 278.702764 -279.484924) (xy 278.743267 -279.51288)
			(xy 278.77876 -279.546972) (xy 278.808325 -279.586316) (xy 278.831196 -279.629893) (xy 278.84678 -279.676574)
			(xy 278.854675 -279.725151) (xy 278.85517 -279.749758) (xy 278.854675 -279.774365) (xy 278.854537 -279.775212)
			(xy 279.173174 -279.775212) (xy 279.173174 -279.723796) (xy 279.181217 -279.673014) (xy 279.197105 -279.624115)
			(xy 279.220448 -279.578303) (xy 279.250669 -279.536707) (xy 279.287025 -279.500351) (xy 279.328621 -279.47013)
			(xy 279.374433 -279.446787) (xy 279.423332 -279.430899) (xy 279.474114 -279.422856) (xy 279.52553 -279.422856)
			(xy 279.576312 -279.430899) (xy 279.625211 -279.446787) (xy 279.671023 -279.47013) (xy 279.712619 -279.500351)
			(xy 279.748975 -279.536707) (xy 279.779196 -279.578303) (xy 279.802539 -279.624115) (xy 279.818427 -279.673014)
			(xy 279.82647 -279.723796) (xy 279.826974 -279.749504) (xy 279.826969 -279.749758) (xy 280.143978 -279.749758)
			(xy 280.147938 -279.700704) (xy 280.159715 -279.65292) (xy 280.179006 -279.607644) (xy 280.205309 -279.566048)
			(xy 280.237944 -279.529211) (xy 280.276065 -279.498086) (xy 280.318686 -279.473479) (xy 280.364702 -279.456027)
			(xy 280.412921 -279.446183) (xy 280.462096 -279.444202) (xy 280.510951 -279.450134) (xy 280.558222 -279.463826)
			(xy 280.602684 -279.484924) (xy 280.643187 -279.51288) (xy 280.67868 -279.546972) (xy 280.708245 -279.586316)
			(xy 280.731116 -279.629893) (xy 280.7467 -279.676574) (xy 280.754595 -279.725151) (xy 280.75509 -279.749758)
			(xy 280.754595 -279.774365) (xy 280.754457 -279.775212) (xy 281.073094 -279.775212) (xy 281.073094 -279.723796)
			(xy 281.081137 -279.673014) (xy 281.097025 -279.624115) (xy 281.120368 -279.578303) (xy 281.150589 -279.536707)
			(xy 281.186945 -279.500351) (xy 281.228541 -279.47013) (xy 281.274353 -279.446787) (xy 281.323252 -279.430899)
			(xy 281.374034 -279.422856) (xy 281.42545 -279.422856) (xy 281.476232 -279.430899) (xy 281.525131 -279.446787)
			(xy 281.570943 -279.47013) (xy 281.612539 -279.500351) (xy 281.648895 -279.536707) (xy 281.679116 -279.578303)
			(xy 281.702459 -279.624115) (xy 281.718347 -279.673014) (xy 281.72639 -279.723796) (xy 281.726894 -279.749504)
			(xy 281.726889 -279.749758) (xy 282.043898 -279.749758) (xy 282.047858 -279.700704) (xy 282.059635 -279.65292)
			(xy 282.078926 -279.607644) (xy 282.105229 -279.566048) (xy 282.137864 -279.529211) (xy 282.175985 -279.498086)
			(xy 282.218606 -279.473479) (xy 282.264622 -279.456027) (xy 282.312841 -279.446183) (xy 282.362016 -279.444202)
			(xy 282.410871 -279.450134) (xy 282.458142 -279.463826) (xy 282.502604 -279.484924) (xy 282.543107 -279.51288)
			(xy 282.5786 -279.546972) (xy 282.608165 -279.586316) (xy 282.631036 -279.629893) (xy 282.64662 -279.676574)
			(xy 282.654515 -279.725151) (xy 282.65501 -279.749758) (xy 282.654515 -279.774365) (xy 282.654377 -279.775212)
			(xy 282.973268 -279.775212) (xy 282.973268 -279.723796) (xy 282.981311 -279.673014) (xy 282.997199 -279.624115)
			(xy 283.020542 -279.578303) (xy 283.050763 -279.536707) (xy 283.087119 -279.500351) (xy 283.128715 -279.47013)
			(xy 283.174527 -279.446787) (xy 283.223426 -279.430899) (xy 283.274208 -279.422856) (xy 283.325624 -279.422856)
			(xy 283.376406 -279.430899) (xy 283.425305 -279.446787) (xy 283.471117 -279.47013) (xy 283.512713 -279.500351)
			(xy 283.549069 -279.536707) (xy 283.57929 -279.578303) (xy 283.602633 -279.624115) (xy 283.618521 -279.673014)
			(xy 283.626564 -279.723796) (xy 283.627068 -279.749504) (xy 283.627063 -279.749758) (xy 283.944072 -279.749758)
			(xy 283.948032 -279.700704) (xy 283.959809 -279.65292) (xy 283.9791 -279.607644) (xy 284.005403 -279.566048)
			(xy 284.038038 -279.529211) (xy 284.076159 -279.498086) (xy 284.11878 -279.473479) (xy 284.164796 -279.456027)
			(xy 284.213015 -279.446183) (xy 284.26219 -279.444202) (xy 284.311045 -279.450134) (xy 284.358316 -279.463826)
			(xy 284.402778 -279.484924) (xy 284.443281 -279.51288) (xy 284.478774 -279.546972) (xy 284.508339 -279.586316)
			(xy 284.53121 -279.629893) (xy 284.546794 -279.676574) (xy 284.554689 -279.725151) (xy 284.555184 -279.749758)
			(xy 284.554689 -279.774365) (xy 284.554551 -279.775212) (xy 284.873188 -279.775212) (xy 284.873188 -279.723796)
			(xy 284.881231 -279.673014) (xy 284.897119 -279.624115) (xy 284.920462 -279.578303) (xy 284.950683 -279.536707)
			(xy 284.987039 -279.500351) (xy 285.028635 -279.47013) (xy 285.074447 -279.446787) (xy 285.123346 -279.430899)
			(xy 285.174128 -279.422856) (xy 285.225544 -279.422856) (xy 285.276326 -279.430899) (xy 285.325225 -279.446787)
			(xy 285.371037 -279.47013) (xy 285.412633 -279.500351) (xy 285.448989 -279.536707) (xy 285.47921 -279.578303)
			(xy 285.502553 -279.624115) (xy 285.518441 -279.673014) (xy 285.526484 -279.723796) (xy 285.526988 -279.749504)
			(xy 285.526983 -279.749758) (xy 285.843992 -279.749758) (xy 285.847952 -279.700704) (xy 285.859729 -279.65292)
			(xy 285.87902 -279.607644) (xy 285.905323 -279.566048) (xy 285.937958 -279.529211) (xy 285.976079 -279.498086)
			(xy 286.0187 -279.473479) (xy 286.064716 -279.456027) (xy 286.112935 -279.446183) (xy 286.16211 -279.444202)
			(xy 286.210965 -279.450134) (xy 286.258236 -279.463826) (xy 286.302698 -279.484924) (xy 286.343201 -279.51288)
			(xy 286.378694 -279.546972) (xy 286.408259 -279.586316) (xy 286.43113 -279.629893) (xy 286.446714 -279.676574)
			(xy 286.454609 -279.725151) (xy 286.455104 -279.749758) (xy 286.454609 -279.774365) (xy 286.454471 -279.775212)
			(xy 286.773108 -279.775212) (xy 286.773108 -279.723796) (xy 286.781151 -279.673014) (xy 286.797039 -279.624115)
			(xy 286.820382 -279.578303) (xy 286.850603 -279.536707) (xy 286.886959 -279.500351) (xy 286.928555 -279.47013)
			(xy 286.974367 -279.446787) (xy 287.023266 -279.430899) (xy 287.074048 -279.422856) (xy 287.125464 -279.422856)
			(xy 287.176246 -279.430899) (xy 287.225145 -279.446787) (xy 287.270957 -279.47013) (xy 287.312553 -279.500351)
			(xy 287.348909 -279.536707) (xy 287.37913 -279.578303) (xy 287.402473 -279.624115) (xy 287.418361 -279.673014)
			(xy 287.426404 -279.723796) (xy 287.426908 -279.749504) (xy 287.426903 -279.749758) (xy 287.743912 -279.749758)
			(xy 287.747872 -279.700704) (xy 287.759649 -279.65292) (xy 287.77894 -279.607644) (xy 287.805243 -279.566048)
			(xy 287.837878 -279.529211) (xy 287.875999 -279.498086) (xy 287.91862 -279.473479) (xy 287.964636 -279.456027)
			(xy 288.012855 -279.446183) (xy 288.06203 -279.444202) (xy 288.110885 -279.450134) (xy 288.158156 -279.463826)
			(xy 288.202618 -279.484924) (xy 288.243121 -279.51288) (xy 288.278614 -279.546972) (xy 288.308179 -279.586316)
			(xy 288.33105 -279.629893) (xy 288.346634 -279.676574) (xy 288.354529 -279.725151) (xy 288.355024 -279.749758)
			(xy 288.354529 -279.774365) (xy 288.354391 -279.775212) (xy 288.673028 -279.775212) (xy 288.673028 -279.723796)
			(xy 288.681071 -279.673014) (xy 288.696959 -279.624115) (xy 288.720302 -279.578303) (xy 288.750523 -279.536707)
			(xy 288.786879 -279.500351) (xy 288.828475 -279.47013) (xy 288.874287 -279.446787) (xy 288.923186 -279.430899)
			(xy 288.973968 -279.422856) (xy 289.025384 -279.422856) (xy 289.076166 -279.430899) (xy 289.125065 -279.446787)
			(xy 289.170877 -279.47013) (xy 289.212473 -279.500351) (xy 289.248829 -279.536707) (xy 289.27905 -279.578303)
			(xy 289.302393 -279.624115) (xy 289.318281 -279.673014) (xy 289.326324 -279.723796) (xy 289.326828 -279.749504)
			(xy 289.326823 -279.749758) (xy 289.644086 -279.749758) (xy 289.648046 -279.700704) (xy 289.659823 -279.65292)
			(xy 289.679114 -279.607644) (xy 289.705417 -279.566048) (xy 289.738052 -279.529211) (xy 289.776173 -279.498086)
			(xy 289.818794 -279.473479) (xy 289.86481 -279.456027) (xy 289.913029 -279.446183) (xy 289.962204 -279.444202)
			(xy 290.011059 -279.450134) (xy 290.05833 -279.463826) (xy 290.102792 -279.484924) (xy 290.143295 -279.51288)
			(xy 290.178788 -279.546972) (xy 290.208353 -279.586316) (xy 290.231224 -279.629893) (xy 290.246808 -279.676574)
			(xy 290.254703 -279.725151) (xy 290.255198 -279.749758) (xy 290.254703 -279.774365) (xy 290.254565 -279.775212)
			(xy 290.573202 -279.775212) (xy 290.573202 -279.723796) (xy 290.581245 -279.673014) (xy 290.597133 -279.624115)
			(xy 290.620476 -279.578303) (xy 290.650697 -279.536707) (xy 290.687053 -279.500351) (xy 290.728649 -279.47013)
			(xy 290.774461 -279.446787) (xy 290.82336 -279.430899) (xy 290.874142 -279.422856) (xy 290.925558 -279.422856)
			(xy 290.97634 -279.430899) (xy 291.025239 -279.446787) (xy 291.071051 -279.47013) (xy 291.112647 -279.500351)
			(xy 291.149003 -279.536707) (xy 291.179224 -279.578303) (xy 291.202567 -279.624115) (xy 291.218455 -279.673014)
			(xy 291.226498 -279.723796) (xy 291.227002 -279.749504) (xy 291.226997 -279.749758) (xy 291.544006 -279.749758)
			(xy 291.547966 -279.700704) (xy 291.559743 -279.65292) (xy 291.579034 -279.607644) (xy 291.605337 -279.566048)
			(xy 291.637972 -279.529211) (xy 291.676093 -279.498086) (xy 291.718714 -279.473479) (xy 291.76473 -279.456027)
			(xy 291.812949 -279.446183) (xy 291.862124 -279.444202) (xy 291.910979 -279.450134) (xy 291.95825 -279.463826)
			(xy 292.002712 -279.484924) (xy 292.043215 -279.51288) (xy 292.078708 -279.546972) (xy 292.108273 -279.586316)
			(xy 292.131144 -279.629893) (xy 292.146728 -279.676574) (xy 292.154623 -279.725151) (xy 292.155118 -279.749758)
			(xy 292.154623 -279.774365) (xy 292.154485 -279.775212) (xy 292.473122 -279.775212) (xy 292.473122 -279.723796)
			(xy 292.481165 -279.673014) (xy 292.497053 -279.624115) (xy 292.520396 -279.578303) (xy 292.550617 -279.536707)
			(xy 292.586973 -279.500351) (xy 292.628569 -279.47013) (xy 292.674381 -279.446787) (xy 292.72328 -279.430899)
			(xy 292.774062 -279.422856) (xy 292.825478 -279.422856) (xy 292.87626 -279.430899) (xy 292.925159 -279.446787)
			(xy 292.970971 -279.47013) (xy 293.012567 -279.500351) (xy 293.048923 -279.536707) (xy 293.079144 -279.578303)
			(xy 293.102487 -279.624115) (xy 293.118375 -279.673014) (xy 293.126418 -279.723796) (xy 293.126922 -279.749504)
			(xy 293.126917 -279.749758) (xy 293.443926 -279.749758) (xy 293.447886 -279.700704) (xy 293.459663 -279.65292)
			(xy 293.478954 -279.607644) (xy 293.505257 -279.566048) (xy 293.537892 -279.529211) (xy 293.576013 -279.498086)
			(xy 293.618634 -279.473479) (xy 293.66465 -279.456027) (xy 293.712869 -279.446183) (xy 293.762044 -279.444202)
			(xy 293.810899 -279.450134) (xy 293.85817 -279.463826) (xy 293.902632 -279.484924) (xy 293.943135 -279.51288)
			(xy 293.978628 -279.546972) (xy 294.008193 -279.586316) (xy 294.031064 -279.629893) (xy 294.046648 -279.676574)
			(xy 294.054543 -279.725151) (xy 294.055038 -279.749758) (xy 294.054543 -279.774365) (xy 294.054405 -279.775212)
			(xy 294.373042 -279.775212) (xy 294.373042 -279.723796) (xy 294.381085 -279.673014) (xy 294.396973 -279.624115)
			(xy 294.420316 -279.578303) (xy 294.450537 -279.536707) (xy 294.486893 -279.500351) (xy 294.528489 -279.47013)
			(xy 294.574301 -279.446787) (xy 294.6232 -279.430899) (xy 294.673982 -279.422856) (xy 294.725398 -279.422856)
			(xy 294.77618 -279.430899) (xy 294.825079 -279.446787) (xy 294.870891 -279.47013) (xy 294.912487 -279.500351)
			(xy 294.948843 -279.536707) (xy 294.979064 -279.578303) (xy 295.002407 -279.624115) (xy 295.018295 -279.673014)
			(xy 295.026338 -279.723796) (xy 295.026842 -279.749504) (xy 295.026837 -279.749758) (xy 295.3441 -279.749758)
			(xy 295.34806 -279.700704) (xy 295.359837 -279.65292) (xy 295.379128 -279.607644) (xy 295.405431 -279.566048)
			(xy 295.438066 -279.529211) (xy 295.476187 -279.498086) (xy 295.518808 -279.473479) (xy 295.564824 -279.456027)
			(xy 295.613043 -279.446183) (xy 295.662218 -279.444202) (xy 295.711073 -279.450134) (xy 295.758344 -279.463826)
			(xy 295.802806 -279.484924) (xy 295.843309 -279.51288) (xy 295.878802 -279.546972) (xy 295.908367 -279.586316)
			(xy 295.931238 -279.629893) (xy 295.946822 -279.676574) (xy 295.954717 -279.725151) (xy 295.955212 -279.749758)
			(xy 295.954717 -279.774365) (xy 295.954579 -279.775212) (xy 296.273216 -279.775212) (xy 296.273216 -279.723796)
			(xy 296.281259 -279.673014) (xy 296.297147 -279.624115) (xy 296.32049 -279.578303) (xy 296.350711 -279.536707)
			(xy 296.387067 -279.500351) (xy 296.428663 -279.47013) (xy 296.474475 -279.446787) (xy 296.523374 -279.430899)
			(xy 296.574156 -279.422856) (xy 296.625572 -279.422856) (xy 296.676354 -279.430899) (xy 296.725253 -279.446787)
			(xy 296.771065 -279.47013) (xy 296.812661 -279.500351) (xy 296.849017 -279.536707) (xy 296.879238 -279.578303)
			(xy 296.902581 -279.624115) (xy 296.918469 -279.673014) (xy 296.926512 -279.723796) (xy 296.927016 -279.749504)
			(xy 296.927011 -279.749758) (xy 297.24402 -279.749758) (xy 297.24798 -279.700704) (xy 297.259757 -279.65292)
			(xy 297.279048 -279.607644) (xy 297.305351 -279.566048) (xy 297.337986 -279.529211) (xy 297.376107 -279.498086)
			(xy 297.418728 -279.473479) (xy 297.464744 -279.456027) (xy 297.512963 -279.446183) (xy 297.562138 -279.444202)
			(xy 297.610993 -279.450134) (xy 297.658264 -279.463826) (xy 297.702726 -279.484924) (xy 297.743229 -279.51288)
			(xy 297.778722 -279.546972) (xy 297.808287 -279.586316) (xy 297.831158 -279.629893) (xy 297.846742 -279.676574)
			(xy 297.854637 -279.725151) (xy 297.855132 -279.749758) (xy 297.854637 -279.774365) (xy 297.854499 -279.775212)
			(xy 298.173136 -279.775212) (xy 298.173136 -279.723796) (xy 298.181179 -279.673014) (xy 298.197067 -279.624115)
			(xy 298.22041 -279.578303) (xy 298.250631 -279.536707) (xy 298.286987 -279.500351) (xy 298.328583 -279.47013)
			(xy 298.374395 -279.446787) (xy 298.423294 -279.430899) (xy 298.474076 -279.422856) (xy 298.525492 -279.422856)
			(xy 298.576274 -279.430899) (xy 298.625173 -279.446787) (xy 298.670985 -279.47013) (xy 298.712581 -279.500351)
			(xy 298.748937 -279.536707) (xy 298.779158 -279.578303) (xy 298.802501 -279.624115) (xy 298.818389 -279.673014)
			(xy 298.826432 -279.723796) (xy 298.826936 -279.749504) (xy 298.826931 -279.749758) (xy 299.14394 -279.749758)
			(xy 299.1479 -279.700704) (xy 299.159677 -279.65292) (xy 299.178968 -279.607644) (xy 299.205271 -279.566048)
			(xy 299.237906 -279.529211) (xy 299.276027 -279.498086) (xy 299.318648 -279.473479) (xy 299.364664 -279.456027)
			(xy 299.412883 -279.446183) (xy 299.462058 -279.444202) (xy 299.510913 -279.450134) (xy 299.558184 -279.463826)
			(xy 299.602646 -279.484924) (xy 299.643149 -279.51288) (xy 299.678642 -279.546972) (xy 299.708207 -279.586316)
			(xy 299.731078 -279.629893) (xy 299.746662 -279.676574) (xy 299.754557 -279.725151) (xy 299.755052 -279.749758)
			(xy 299.754557 -279.774365) (xy 299.754419 -279.775212) (xy 300.073056 -279.775212) (xy 300.073056 -279.723796)
			(xy 300.081099 -279.673014) (xy 300.096987 -279.624115) (xy 300.12033 -279.578303) (xy 300.150551 -279.536707)
			(xy 300.186907 -279.500351) (xy 300.228503 -279.47013) (xy 300.274315 -279.446787) (xy 300.323214 -279.430899)
			(xy 300.373996 -279.422856) (xy 300.425412 -279.422856) (xy 300.476194 -279.430899) (xy 300.525093 -279.446787)
			(xy 300.570905 -279.47013) (xy 300.612501 -279.500351) (xy 300.648857 -279.536707) (xy 300.679078 -279.578303)
			(xy 300.702421 -279.624115) (xy 300.718309 -279.673014) (xy 300.726352 -279.723796) (xy 300.726856 -279.749504)
			(xy 300.726851 -279.749758) (xy 301.044114 -279.749758) (xy 301.048074 -279.700704) (xy 301.059851 -279.65292)
			(xy 301.079142 -279.607644) (xy 301.105445 -279.566048) (xy 301.13808 -279.529211) (xy 301.176201 -279.498086)
			(xy 301.218822 -279.473479) (xy 301.264838 -279.456027) (xy 301.313057 -279.446183) (xy 301.362232 -279.444202)
			(xy 301.411087 -279.450134) (xy 301.458358 -279.463826) (xy 301.50282 -279.484924) (xy 301.543323 -279.51288)
			(xy 301.578816 -279.546972) (xy 301.608381 -279.586316) (xy 301.631252 -279.629893) (xy 301.646836 -279.676574)
			(xy 301.654731 -279.725151) (xy 301.655226 -279.749758) (xy 301.654731 -279.774365) (xy 301.654593 -279.775212)
			(xy 301.97323 -279.775212) (xy 301.97323 -279.723796) (xy 301.981273 -279.673014) (xy 301.997161 -279.624115)
			(xy 302.020504 -279.578303) (xy 302.050725 -279.536707) (xy 302.087081 -279.500351) (xy 302.128677 -279.47013)
			(xy 302.174489 -279.446787) (xy 302.223388 -279.430899) (xy 302.27417 -279.422856) (xy 302.325586 -279.422856)
			(xy 302.376368 -279.430899) (xy 302.425267 -279.446787) (xy 302.471079 -279.47013) (xy 302.512675 -279.500351)
			(xy 302.549031 -279.536707) (xy 302.579252 -279.578303) (xy 302.602595 -279.624115) (xy 302.618483 -279.673014)
			(xy 302.626526 -279.723796) (xy 302.62703 -279.749504) (xy 302.627025 -279.749758) (xy 302.944034 -279.749758)
			(xy 302.947994 -279.700704) (xy 302.959771 -279.65292) (xy 302.979062 -279.607644) (xy 303.005365 -279.566048)
			(xy 303.038 -279.529211) (xy 303.076121 -279.498086) (xy 303.118742 -279.473479) (xy 303.164758 -279.456027)
			(xy 303.212977 -279.446183) (xy 303.262152 -279.444202) (xy 303.311007 -279.450134) (xy 303.358278 -279.463826)
			(xy 303.40274 -279.484924) (xy 303.443243 -279.51288) (xy 303.478736 -279.546972) (xy 303.508301 -279.586316)
			(xy 303.531172 -279.629893) (xy 303.546756 -279.676574) (xy 303.554651 -279.725151) (xy 303.555146 -279.749758)
			(xy 303.554651 -279.774365) (xy 303.554513 -279.775212) (xy 303.87315 -279.775212) (xy 303.87315 -279.723796)
			(xy 303.881193 -279.673014) (xy 303.897081 -279.624115) (xy 303.920424 -279.578303) (xy 303.950645 -279.536707)
			(xy 303.987001 -279.500351) (xy 304.028597 -279.47013) (xy 304.074409 -279.446787) (xy 304.123308 -279.430899)
			(xy 304.17409 -279.422856) (xy 304.225506 -279.422856) (xy 304.276288 -279.430899) (xy 304.325187 -279.446787)
			(xy 304.370999 -279.47013) (xy 304.412595 -279.500351) (xy 304.448951 -279.536707) (xy 304.479172 -279.578303)
			(xy 304.502515 -279.624115) (xy 304.518403 -279.673014) (xy 304.526446 -279.723796) (xy 304.52695 -279.749504)
			(xy 304.526945 -279.749758) (xy 304.843954 -279.749758) (xy 304.847914 -279.700704) (xy 304.859691 -279.65292)
			(xy 304.878982 -279.607644) (xy 304.905285 -279.566048) (xy 304.93792 -279.529211) (xy 304.976041 -279.498086)
			(xy 305.018662 -279.473479) (xy 305.064678 -279.456027) (xy 305.112897 -279.446183) (xy 305.162072 -279.444202)
			(xy 305.210927 -279.450134) (xy 305.258198 -279.463826) (xy 305.30266 -279.484924) (xy 305.343163 -279.51288)
			(xy 305.378656 -279.546972) (xy 305.408221 -279.586316) (xy 305.431092 -279.629893) (xy 305.446676 -279.676574)
			(xy 305.454571 -279.725151) (xy 305.455066 -279.749758) (xy 305.454571 -279.774365) (xy 305.454433 -279.775212)
			(xy 305.77307 -279.775212) (xy 305.77307 -279.723796) (xy 305.781113 -279.673014) (xy 305.797001 -279.624115)
			(xy 305.820344 -279.578303) (xy 305.850565 -279.536707) (xy 305.886921 -279.500351) (xy 305.928517 -279.47013)
			(xy 305.974329 -279.446787) (xy 306.023228 -279.430899) (xy 306.07401 -279.422856) (xy 306.125426 -279.422856)
			(xy 306.176208 -279.430899) (xy 306.225107 -279.446787) (xy 306.270919 -279.47013) (xy 306.312515 -279.500351)
			(xy 306.348871 -279.536707) (xy 306.379092 -279.578303) (xy 306.402435 -279.624115) (xy 306.418323 -279.673014)
			(xy 306.426366 -279.723796) (xy 306.42687 -279.749504) (xy 306.426865 -279.749758) (xy 306.743874 -279.749758)
			(xy 306.747834 -279.700704) (xy 306.759611 -279.65292) (xy 306.778902 -279.607644) (xy 306.805205 -279.566048)
			(xy 306.83784 -279.529211) (xy 306.875961 -279.498086) (xy 306.918582 -279.473479) (xy 306.964598 -279.456027)
			(xy 307.012817 -279.446183) (xy 307.061992 -279.444202) (xy 307.110847 -279.450134) (xy 307.158118 -279.463826)
			(xy 307.20258 -279.484924) (xy 307.243083 -279.51288) (xy 307.278576 -279.546972) (xy 307.308141 -279.586316)
			(xy 307.331012 -279.629893) (xy 307.346596 -279.676574) (xy 307.354491 -279.725151) (xy 307.354986 -279.749758)
			(xy 307.354491 -279.774365) (xy 307.354353 -279.775212) (xy 307.673244 -279.775212) (xy 307.673244 -279.723796)
			(xy 307.681287 -279.673014) (xy 307.697175 -279.624115) (xy 307.720518 -279.578303) (xy 307.750739 -279.536707)
			(xy 307.787095 -279.500351) (xy 307.828691 -279.47013) (xy 307.874503 -279.446787) (xy 307.923402 -279.430899)
			(xy 307.974184 -279.422856) (xy 308.0256 -279.422856) (xy 308.076382 -279.430899) (xy 308.125281 -279.446787)
			(xy 308.171093 -279.47013) (xy 308.212689 -279.500351) (xy 308.249045 -279.536707) (xy 308.279266 -279.578303)
			(xy 308.302609 -279.624115) (xy 308.318497 -279.673014) (xy 308.32654 -279.723796) (xy 308.327044 -279.749504)
			(xy 308.327039 -279.749758) (xy 308.644048 -279.749758) (xy 308.648008 -279.700704) (xy 308.659785 -279.65292)
			(xy 308.679076 -279.607644) (xy 308.705379 -279.566048) (xy 308.738014 -279.529211) (xy 308.776135 -279.498086)
			(xy 308.818756 -279.473479) (xy 308.864772 -279.456027) (xy 308.912991 -279.446183) (xy 308.962166 -279.444202)
			(xy 309.011021 -279.450134) (xy 309.058292 -279.463826) (xy 309.102754 -279.484924) (xy 309.143257 -279.51288)
			(xy 309.17875 -279.546972) (xy 309.208315 -279.586316) (xy 309.231186 -279.629893) (xy 309.24677 -279.676574)
			(xy 309.254665 -279.725151) (xy 309.25516 -279.749758) (xy 309.254665 -279.774365) (xy 309.254527 -279.775212)
			(xy 309.573164 -279.775212) (xy 309.573164 -279.723796) (xy 309.581207 -279.673014) (xy 309.597095 -279.624115)
			(xy 309.620438 -279.578303) (xy 309.650659 -279.536707) (xy 309.687015 -279.500351) (xy 309.728611 -279.47013)
			(xy 309.774423 -279.446787) (xy 309.823322 -279.430899) (xy 309.874104 -279.422856) (xy 309.92552 -279.422856)
			(xy 309.976302 -279.430899) (xy 310.025201 -279.446787) (xy 310.071013 -279.47013) (xy 310.112609 -279.500351)
			(xy 310.148965 -279.536707) (xy 310.179186 -279.578303) (xy 310.202529 -279.624115) (xy 310.218417 -279.673014)
			(xy 310.22646 -279.723796) (xy 310.226964 -279.749504) (xy 310.226959 -279.749758) (xy 310.543968 -279.749758)
			(xy 310.547928 -279.700704) (xy 310.559705 -279.65292) (xy 310.578996 -279.607644) (xy 310.605299 -279.566048)
			(xy 310.637934 -279.529211) (xy 310.676055 -279.498086) (xy 310.718676 -279.473479) (xy 310.764692 -279.456027)
			(xy 310.812911 -279.446183) (xy 310.862086 -279.444202) (xy 310.910941 -279.450134) (xy 310.958212 -279.463826)
			(xy 311.002674 -279.484924) (xy 311.043177 -279.51288) (xy 311.07867 -279.546972) (xy 311.108235 -279.586316)
			(xy 311.131106 -279.629893) (xy 311.14669 -279.676574) (xy 311.154585 -279.725151) (xy 311.15508 -279.749758)
			(xy 311.154585 -279.774365) (xy 311.154406 -279.775466) (xy 311.473084 -279.775466) (xy 311.473084 -279.72405)
			(xy 311.481127 -279.673268) (xy 311.497015 -279.624369) (xy 311.520358 -279.578557) (xy 311.550579 -279.536961)
			(xy 311.586935 -279.500605) (xy 311.628531 -279.470384) (xy 311.674343 -279.447041) (xy 311.723242 -279.431153)
			(xy 311.774024 -279.42311) (xy 311.82544 -279.42311) (xy 311.876222 -279.431153) (xy 311.925121 -279.447041)
			(xy 311.970933 -279.470384) (xy 312.012529 -279.500605) (xy 312.048885 -279.536961) (xy 312.079106 -279.578557)
			(xy 312.102449 -279.624369) (xy 312.118337 -279.673268) (xy 312.12638 -279.72405) (xy 312.126884 -279.749758)
			(xy 312.443888 -279.749758) (xy 312.447848 -279.700704) (xy 312.459625 -279.65292) (xy 312.478916 -279.607644)
			(xy 312.505219 -279.566048) (xy 312.537854 -279.529211) (xy 312.575975 -279.498086) (xy 312.618596 -279.473479)
			(xy 312.664612 -279.456027) (xy 312.712831 -279.446183) (xy 312.762006 -279.444202) (xy 312.810861 -279.450134)
			(xy 312.858132 -279.463826) (xy 312.902594 -279.484924) (xy 312.943097 -279.51288) (xy 312.97859 -279.546972)
			(xy 313.008155 -279.586316) (xy 313.031026 -279.629893) (xy 313.04661 -279.676574) (xy 313.054505 -279.725151)
			(xy 313.055 -279.749758) (xy 313.054505 -279.774365) (xy 313.054326 -279.775466) (xy 313.373258 -279.775466)
			(xy 313.373258 -279.72405) (xy 313.381301 -279.673268) (xy 313.397189 -279.624369) (xy 313.420532 -279.578557)
			(xy 313.450753 -279.536961) (xy 313.487109 -279.500605) (xy 313.528705 -279.470384) (xy 313.574517 -279.447041)
			(xy 313.623416 -279.431153) (xy 313.674198 -279.42311) (xy 313.725614 -279.42311) (xy 313.776396 -279.431153)
			(xy 313.825295 -279.447041) (xy 313.871107 -279.470384) (xy 313.912703 -279.500605) (xy 313.949059 -279.536961)
			(xy 313.97928 -279.578557) (xy 314.002623 -279.624369) (xy 314.018511 -279.673268) (xy 314.026554 -279.72405)
			(xy 314.027058 -279.749758) (xy 314.026554 -279.775466) (xy 314.323218 -279.775466) (xy 314.323218 -279.72405)
			(xy 314.331261 -279.673268) (xy 314.347149 -279.624369) (xy 314.370492 -279.578557) (xy 314.400713 -279.536961)
			(xy 314.437069 -279.500605) (xy 314.478665 -279.470384) (xy 314.524477 -279.447041) (xy 314.573376 -279.431153)
			(xy 314.624158 -279.42311) (xy 314.675574 -279.42311) (xy 314.726356 -279.431153) (xy 314.775255 -279.447041)
			(xy 314.821067 -279.470384) (xy 314.862663 -279.500605) (xy 314.899019 -279.536961) (xy 314.92924 -279.578557)
			(xy 314.952583 -279.624369) (xy 314.968471 -279.673268) (xy 314.976514 -279.72405) (xy 314.977018 -279.749758)
			(xy 314.977013 -279.750012) (xy 315.294276 -279.750012) (xy 315.298236 -279.700958) (xy 315.310013 -279.653174)
			(xy 315.329304 -279.607898) (xy 315.355607 -279.566302) (xy 315.388242 -279.529465) (xy 315.426363 -279.49834)
			(xy 315.468984 -279.473733) (xy 315.515 -279.456281) (xy 315.563219 -279.446437) (xy 315.612394 -279.444456)
			(xy 315.661249 -279.450388) (xy 315.70852 -279.46408) (xy 315.752982 -279.485178) (xy 315.793485 -279.513134)
			(xy 315.828978 -279.547226) (xy 315.858543 -279.58657) (xy 315.881414 -279.630147) (xy 315.896998 -279.676828)
			(xy 315.904893 -279.725405) (xy 315.905388 -279.750012) (xy 315.904893 -279.774619) (xy 315.896998 -279.823196)
			(xy 315.881414 -279.869877) (xy 315.858543 -279.913454) (xy 315.828978 -279.952798) (xy 315.793485 -279.98689)
			(xy 315.752982 -280.014846) (xy 315.70852 -280.035944) (xy 315.661249 -280.049636) (xy 315.612394 -280.055568)
			(xy 315.563219 -280.053587) (xy 315.515 -280.043743) (xy 315.468984 -280.026291) (xy 315.426363 -280.001684)
			(xy 315.388242 -279.970559) (xy 315.355607 -279.933722) (xy 315.329304 -279.892126) (xy 315.310013 -279.84685)
			(xy 315.298236 -279.799066) (xy 315.294276 -279.750012) (xy 314.977013 -279.750012) (xy 314.976514 -279.775466)
			(xy 314.968471 -279.826248) (xy 314.952583 -279.875147) (xy 314.92924 -279.920959) (xy 314.899019 -279.962555)
			(xy 314.862663 -279.998911) (xy 314.821067 -280.029132) (xy 314.775255 -280.052475) (xy 314.726356 -280.068363)
			(xy 314.675574 -280.076406) (xy 314.624158 -280.076406) (xy 314.573376 -280.068363) (xy 314.524477 -280.052475)
			(xy 314.478665 -280.029132) (xy 314.437069 -279.998911) (xy 314.400713 -279.962555) (xy 314.370492 -279.920959)
			(xy 314.347149 -279.875147) (xy 314.331261 -279.826248) (xy 314.323218 -279.775466) (xy 314.026554 -279.775466)
			(xy 314.018511 -279.826248) (xy 314.002623 -279.875147) (xy 313.97928 -279.920959) (xy 313.949059 -279.962555)
			(xy 313.912703 -279.998911) (xy 313.871107 -280.029132) (xy 313.825295 -280.052475) (xy 313.776396 -280.068363)
			(xy 313.725614 -280.076406) (xy 313.674198 -280.076406) (xy 313.623416 -280.068363) (xy 313.574517 -280.052475)
			(xy 313.528705 -280.029132) (xy 313.487109 -279.998911) (xy 313.450753 -279.962555) (xy 313.420532 -279.920959)
			(xy 313.397189 -279.875147) (xy 313.381301 -279.826248) (xy 313.373258 -279.775466) (xy 313.054326 -279.775466)
			(xy 313.04661 -279.822942) (xy 313.031026 -279.869623) (xy 313.008155 -279.9132) (xy 312.97859 -279.952544)
			(xy 312.943097 -279.986636) (xy 312.902594 -280.014592) (xy 312.858132 -280.03569) (xy 312.810861 -280.049382)
			(xy 312.762006 -280.055314) (xy 312.712831 -280.053333) (xy 312.664612 -280.043489) (xy 312.618596 -280.026037)
			(xy 312.575975 -280.00143) (xy 312.537854 -279.970305) (xy 312.505219 -279.933468) (xy 312.478916 -279.891872)
			(xy 312.459625 -279.846596) (xy 312.447848 -279.798812) (xy 312.443888 -279.749758) (xy 312.126884 -279.749758)
			(xy 312.12638 -279.775466) (xy 312.118337 -279.826248) (xy 312.102449 -279.875147) (xy 312.079106 -279.920959)
			(xy 312.048885 -279.962555) (xy 312.012529 -279.998911) (xy 311.970933 -280.029132) (xy 311.925121 -280.052475)
			(xy 311.876222 -280.068363) (xy 311.82544 -280.076406) (xy 311.774024 -280.076406) (xy 311.723242 -280.068363)
			(xy 311.674343 -280.052475) (xy 311.628531 -280.029132) (xy 311.586935 -279.998911) (xy 311.550579 -279.962555)
			(xy 311.520358 -279.920959) (xy 311.497015 -279.875147) (xy 311.481127 -279.826248) (xy 311.473084 -279.775466)
			(xy 311.154406 -279.775466) (xy 311.14669 -279.822942) (xy 311.131106 -279.869623) (xy 311.108235 -279.9132)
			(xy 311.07867 -279.952544) (xy 311.043177 -279.986636) (xy 311.002674 -280.014592) (xy 310.958212 -280.03569)
			(xy 310.910941 -280.049382) (xy 310.862086 -280.055314) (xy 310.812911 -280.053333) (xy 310.764692 -280.043489)
			(xy 310.718676 -280.026037) (xy 310.676055 -280.00143) (xy 310.637934 -279.970305) (xy 310.605299 -279.933468)
			(xy 310.578996 -279.891872) (xy 310.559705 -279.846596) (xy 310.547928 -279.798812) (xy 310.543968 -279.749758)
			(xy 310.226959 -279.749758) (xy 310.22646 -279.775212) (xy 310.218417 -279.825994) (xy 310.202529 -279.874893)
			(xy 310.179186 -279.920705) (xy 310.148965 -279.962301) (xy 310.112609 -279.998657) (xy 310.071013 -280.028878)
			(xy 310.025201 -280.052221) (xy 309.976302 -280.068109) (xy 309.92552 -280.076152) (xy 309.874104 -280.076152)
			(xy 309.823322 -280.068109) (xy 309.774423 -280.052221) (xy 309.728611 -280.028878) (xy 309.687015 -279.998657)
			(xy 309.650659 -279.962301) (xy 309.620438 -279.920705) (xy 309.597095 -279.874893) (xy 309.581207 -279.825994)
			(xy 309.573164 -279.775212) (xy 309.254527 -279.775212) (xy 309.24677 -279.822942) (xy 309.231186 -279.869623)
			(xy 309.208315 -279.9132) (xy 309.17875 -279.952544) (xy 309.143257 -279.986636) (xy 309.102754 -280.014592)
			(xy 309.058292 -280.03569) (xy 309.011021 -280.049382) (xy 308.962166 -280.055314) (xy 308.912991 -280.053333)
			(xy 308.864772 -280.043489) (xy 308.818756 -280.026037) (xy 308.776135 -280.00143) (xy 308.738014 -279.970305)
			(xy 308.705379 -279.933468) (xy 308.679076 -279.891872) (xy 308.659785 -279.846596) (xy 308.648008 -279.798812)
			(xy 308.644048 -279.749758) (xy 308.327039 -279.749758) (xy 308.32654 -279.775212) (xy 308.318497 -279.825994)
			(xy 308.302609 -279.874893) (xy 308.279266 -279.920705) (xy 308.249045 -279.962301) (xy 308.212689 -279.998657)
			(xy 308.171093 -280.028878) (xy 308.125281 -280.052221) (xy 308.076382 -280.068109) (xy 308.0256 -280.076152)
			(xy 307.974184 -280.076152) (xy 307.923402 -280.068109) (xy 307.874503 -280.052221) (xy 307.828691 -280.028878)
			(xy 307.787095 -279.998657) (xy 307.750739 -279.962301) (xy 307.720518 -279.920705) (xy 307.697175 -279.874893)
			(xy 307.681287 -279.825994) (xy 307.673244 -279.775212) (xy 307.354353 -279.775212) (xy 307.346596 -279.822942)
			(xy 307.331012 -279.869623) (xy 307.308141 -279.9132) (xy 307.278576 -279.952544) (xy 307.243083 -279.986636)
			(xy 307.20258 -280.014592) (xy 307.158118 -280.03569) (xy 307.110847 -280.049382) (xy 307.061992 -280.055314)
			(xy 307.012817 -280.053333) (xy 306.964598 -280.043489) (xy 306.918582 -280.026037) (xy 306.875961 -280.00143)
			(xy 306.83784 -279.970305) (xy 306.805205 -279.933468) (xy 306.778902 -279.891872) (xy 306.759611 -279.846596)
			(xy 306.747834 -279.798812) (xy 306.743874 -279.749758) (xy 306.426865 -279.749758) (xy 306.426366 -279.775212)
			(xy 306.418323 -279.825994) (xy 306.402435 -279.874893) (xy 306.379092 -279.920705) (xy 306.348871 -279.962301)
			(xy 306.312515 -279.998657) (xy 306.270919 -280.028878) (xy 306.225107 -280.052221) (xy 306.176208 -280.068109)
			(xy 306.125426 -280.076152) (xy 306.07401 -280.076152) (xy 306.023228 -280.068109) (xy 305.974329 -280.052221)
			(xy 305.928517 -280.028878) (xy 305.886921 -279.998657) (xy 305.850565 -279.962301) (xy 305.820344 -279.920705)
			(xy 305.797001 -279.874893) (xy 305.781113 -279.825994) (xy 305.77307 -279.775212) (xy 305.454433 -279.775212)
			(xy 305.446676 -279.822942) (xy 305.431092 -279.869623) (xy 305.408221 -279.9132) (xy 305.378656 -279.952544)
			(xy 305.343163 -279.986636) (xy 305.30266 -280.014592) (xy 305.258198 -280.03569) (xy 305.210927 -280.049382)
			(xy 305.162072 -280.055314) (xy 305.112897 -280.053333) (xy 305.064678 -280.043489) (xy 305.018662 -280.026037)
			(xy 304.976041 -280.00143) (xy 304.93792 -279.970305) (xy 304.905285 -279.933468) (xy 304.878982 -279.891872)
			(xy 304.859691 -279.846596) (xy 304.847914 -279.798812) (xy 304.843954 -279.749758) (xy 304.526945 -279.749758)
			(xy 304.526446 -279.775212) (xy 304.518403 -279.825994) (xy 304.502515 -279.874893) (xy 304.479172 -279.920705)
			(xy 304.448951 -279.962301) (xy 304.412595 -279.998657) (xy 304.370999 -280.028878) (xy 304.325187 -280.052221)
			(xy 304.276288 -280.068109) (xy 304.225506 -280.076152) (xy 304.17409 -280.076152) (xy 304.123308 -280.068109)
			(xy 304.074409 -280.052221) (xy 304.028597 -280.028878) (xy 303.987001 -279.998657) (xy 303.950645 -279.962301)
			(xy 303.920424 -279.920705) (xy 303.897081 -279.874893) (xy 303.881193 -279.825994) (xy 303.87315 -279.775212)
			(xy 303.554513 -279.775212) (xy 303.546756 -279.822942) (xy 303.531172 -279.869623) (xy 303.508301 -279.9132)
			(xy 303.478736 -279.952544) (xy 303.443243 -279.986636) (xy 303.40274 -280.014592) (xy 303.358278 -280.03569)
			(xy 303.311007 -280.049382) (xy 303.262152 -280.055314) (xy 303.212977 -280.053333) (xy 303.164758 -280.043489)
			(xy 303.118742 -280.026037) (xy 303.076121 -280.00143) (xy 303.038 -279.970305) (xy 303.005365 -279.933468)
			(xy 302.979062 -279.891872) (xy 302.959771 -279.846596) (xy 302.947994 -279.798812) (xy 302.944034 -279.749758)
			(xy 302.627025 -279.749758) (xy 302.626526 -279.775212) (xy 302.618483 -279.825994) (xy 302.602595 -279.874893)
			(xy 302.579252 -279.920705) (xy 302.549031 -279.962301) (xy 302.512675 -279.998657) (xy 302.471079 -280.028878)
			(xy 302.425267 -280.052221) (xy 302.376368 -280.068109) (xy 302.325586 -280.076152) (xy 302.27417 -280.076152)
			(xy 302.223388 -280.068109) (xy 302.174489 -280.052221) (xy 302.128677 -280.028878) (xy 302.087081 -279.998657)
			(xy 302.050725 -279.962301) (xy 302.020504 -279.920705) (xy 301.997161 -279.874893) (xy 301.981273 -279.825994)
			(xy 301.97323 -279.775212) (xy 301.654593 -279.775212) (xy 301.646836 -279.822942) (xy 301.631252 -279.869623)
			(xy 301.608381 -279.9132) (xy 301.578816 -279.952544) (xy 301.543323 -279.986636) (xy 301.50282 -280.014592)
			(xy 301.458358 -280.03569) (xy 301.411087 -280.049382) (xy 301.362232 -280.055314) (xy 301.313057 -280.053333)
			(xy 301.264838 -280.043489) (xy 301.218822 -280.026037) (xy 301.176201 -280.00143) (xy 301.13808 -279.970305)
			(xy 301.105445 -279.933468) (xy 301.079142 -279.891872) (xy 301.059851 -279.846596) (xy 301.048074 -279.798812)
			(xy 301.044114 -279.749758) (xy 300.726851 -279.749758) (xy 300.726352 -279.775212) (xy 300.718309 -279.825994)
			(xy 300.702421 -279.874893) (xy 300.679078 -279.920705) (xy 300.648857 -279.962301) (xy 300.612501 -279.998657)
			(xy 300.570905 -280.028878) (xy 300.525093 -280.052221) (xy 300.476194 -280.068109) (xy 300.425412 -280.076152)
			(xy 300.373996 -280.076152) (xy 300.323214 -280.068109) (xy 300.274315 -280.052221) (xy 300.228503 -280.028878)
			(xy 300.186907 -279.998657) (xy 300.150551 -279.962301) (xy 300.12033 -279.920705) (xy 300.096987 -279.874893)
			(xy 300.081099 -279.825994) (xy 300.073056 -279.775212) (xy 299.754419 -279.775212) (xy 299.746662 -279.822942)
			(xy 299.731078 -279.869623) (xy 299.708207 -279.9132) (xy 299.678642 -279.952544) (xy 299.643149 -279.986636)
			(xy 299.602646 -280.014592) (xy 299.558184 -280.03569) (xy 299.510913 -280.049382) (xy 299.462058 -280.055314)
			(xy 299.412883 -280.053333) (xy 299.364664 -280.043489) (xy 299.318648 -280.026037) (xy 299.276027 -280.00143)
			(xy 299.237906 -279.970305) (xy 299.205271 -279.933468) (xy 299.178968 -279.891872) (xy 299.159677 -279.846596)
			(xy 299.1479 -279.798812) (xy 299.14394 -279.749758) (xy 298.826931 -279.749758) (xy 298.826432 -279.775212)
			(xy 298.818389 -279.825994) (xy 298.802501 -279.874893) (xy 298.779158 -279.920705) (xy 298.748937 -279.962301)
			(xy 298.712581 -279.998657) (xy 298.670985 -280.028878) (xy 298.625173 -280.052221) (xy 298.576274 -280.068109)
			(xy 298.525492 -280.076152) (xy 298.474076 -280.076152) (xy 298.423294 -280.068109) (xy 298.374395 -280.052221)
			(xy 298.328583 -280.028878) (xy 298.286987 -279.998657) (xy 298.250631 -279.962301) (xy 298.22041 -279.920705)
			(xy 298.197067 -279.874893) (xy 298.181179 -279.825994) (xy 298.173136 -279.775212) (xy 297.854499 -279.775212)
			(xy 297.846742 -279.822942) (xy 297.831158 -279.869623) (xy 297.808287 -279.9132) (xy 297.778722 -279.952544)
			(xy 297.743229 -279.986636) (xy 297.702726 -280.014592) (xy 297.658264 -280.03569) (xy 297.610993 -280.049382)
			(xy 297.562138 -280.055314) (xy 297.512963 -280.053333) (xy 297.464744 -280.043489) (xy 297.418728 -280.026037)
			(xy 297.376107 -280.00143) (xy 297.337986 -279.970305) (xy 297.305351 -279.933468) (xy 297.279048 -279.891872)
			(xy 297.259757 -279.846596) (xy 297.24798 -279.798812) (xy 297.24402 -279.749758) (xy 296.927011 -279.749758)
			(xy 296.926512 -279.775212) (xy 296.918469 -279.825994) (xy 296.902581 -279.874893) (xy 296.879238 -279.920705)
			(xy 296.849017 -279.962301) (xy 296.812661 -279.998657) (xy 296.771065 -280.028878) (xy 296.725253 -280.052221)
			(xy 296.676354 -280.068109) (xy 296.625572 -280.076152) (xy 296.574156 -280.076152) (xy 296.523374 -280.068109)
			(xy 296.474475 -280.052221) (xy 296.428663 -280.028878) (xy 296.387067 -279.998657) (xy 296.350711 -279.962301)
			(xy 296.32049 -279.920705) (xy 296.297147 -279.874893) (xy 296.281259 -279.825994) (xy 296.273216 -279.775212)
			(xy 295.954579 -279.775212) (xy 295.946822 -279.822942) (xy 295.931238 -279.869623) (xy 295.908367 -279.9132)
			(xy 295.878802 -279.952544) (xy 295.843309 -279.986636) (xy 295.802806 -280.014592) (xy 295.758344 -280.03569)
			(xy 295.711073 -280.049382) (xy 295.662218 -280.055314) (xy 295.613043 -280.053333) (xy 295.564824 -280.043489)
			(xy 295.518808 -280.026037) (xy 295.476187 -280.00143) (xy 295.438066 -279.970305) (xy 295.405431 -279.933468)
			(xy 295.379128 -279.891872) (xy 295.359837 -279.846596) (xy 295.34806 -279.798812) (xy 295.3441 -279.749758)
			(xy 295.026837 -279.749758) (xy 295.026338 -279.775212) (xy 295.018295 -279.825994) (xy 295.002407 -279.874893)
			(xy 294.979064 -279.920705) (xy 294.948843 -279.962301) (xy 294.912487 -279.998657) (xy 294.870891 -280.028878)
			(xy 294.825079 -280.052221) (xy 294.77618 -280.068109) (xy 294.725398 -280.076152) (xy 294.673982 -280.076152)
			(xy 294.6232 -280.068109) (xy 294.574301 -280.052221) (xy 294.528489 -280.028878) (xy 294.486893 -279.998657)
			(xy 294.450537 -279.962301) (xy 294.420316 -279.920705) (xy 294.396973 -279.874893) (xy 294.381085 -279.825994)
			(xy 294.373042 -279.775212) (xy 294.054405 -279.775212) (xy 294.046648 -279.822942) (xy 294.031064 -279.869623)
			(xy 294.008193 -279.9132) (xy 293.978628 -279.952544) (xy 293.943135 -279.986636) (xy 293.902632 -280.014592)
			(xy 293.85817 -280.03569) (xy 293.810899 -280.049382) (xy 293.762044 -280.055314) (xy 293.712869 -280.053333)
			(xy 293.66465 -280.043489) (xy 293.618634 -280.026037) (xy 293.576013 -280.00143) (xy 293.537892 -279.970305)
			(xy 293.505257 -279.933468) (xy 293.478954 -279.891872) (xy 293.459663 -279.846596) (xy 293.447886 -279.798812)
			(xy 293.443926 -279.749758) (xy 293.126917 -279.749758) (xy 293.126418 -279.775212) (xy 293.118375 -279.825994)
			(xy 293.102487 -279.874893) (xy 293.079144 -279.920705) (xy 293.048923 -279.962301) (xy 293.012567 -279.998657)
			(xy 292.970971 -280.028878) (xy 292.925159 -280.052221) (xy 292.87626 -280.068109) (xy 292.825478 -280.076152)
			(xy 292.774062 -280.076152) (xy 292.72328 -280.068109) (xy 292.674381 -280.052221) (xy 292.628569 -280.028878)
			(xy 292.586973 -279.998657) (xy 292.550617 -279.962301) (xy 292.520396 -279.920705) (xy 292.497053 -279.874893)
			(xy 292.481165 -279.825994) (xy 292.473122 -279.775212) (xy 292.154485 -279.775212) (xy 292.146728 -279.822942)
			(xy 292.131144 -279.869623) (xy 292.108273 -279.9132) (xy 292.078708 -279.952544) (xy 292.043215 -279.986636)
			(xy 292.002712 -280.014592) (xy 291.95825 -280.03569) (xy 291.910979 -280.049382) (xy 291.862124 -280.055314)
			(xy 291.812949 -280.053333) (xy 291.76473 -280.043489) (xy 291.718714 -280.026037) (xy 291.676093 -280.00143)
			(xy 291.637972 -279.970305) (xy 291.605337 -279.933468) (xy 291.579034 -279.891872) (xy 291.559743 -279.846596)
			(xy 291.547966 -279.798812) (xy 291.544006 -279.749758) (xy 291.226997 -279.749758) (xy 291.226498 -279.775212)
			(xy 291.218455 -279.825994) (xy 291.202567 -279.874893) (xy 291.179224 -279.920705) (xy 291.149003 -279.962301)
			(xy 291.112647 -279.998657) (xy 291.071051 -280.028878) (xy 291.025239 -280.052221) (xy 290.97634 -280.068109)
			(xy 290.925558 -280.076152) (xy 290.874142 -280.076152) (xy 290.82336 -280.068109) (xy 290.774461 -280.052221)
			(xy 290.728649 -280.028878) (xy 290.687053 -279.998657) (xy 290.650697 -279.962301) (xy 290.620476 -279.920705)
			(xy 290.597133 -279.874893) (xy 290.581245 -279.825994) (xy 290.573202 -279.775212) (xy 290.254565 -279.775212)
			(xy 290.246808 -279.822942) (xy 290.231224 -279.869623) (xy 290.208353 -279.9132) (xy 290.178788 -279.952544)
			(xy 290.143295 -279.986636) (xy 290.102792 -280.014592) (xy 290.05833 -280.03569) (xy 290.011059 -280.049382)
			(xy 289.962204 -280.055314) (xy 289.913029 -280.053333) (xy 289.86481 -280.043489) (xy 289.818794 -280.026037)
			(xy 289.776173 -280.00143) (xy 289.738052 -279.970305) (xy 289.705417 -279.933468) (xy 289.679114 -279.891872)
			(xy 289.659823 -279.846596) (xy 289.648046 -279.798812) (xy 289.644086 -279.749758) (xy 289.326823 -279.749758)
			(xy 289.326324 -279.775212) (xy 289.318281 -279.825994) (xy 289.302393 -279.874893) (xy 289.27905 -279.920705)
			(xy 289.248829 -279.962301) (xy 289.212473 -279.998657) (xy 289.170877 -280.028878) (xy 289.125065 -280.052221)
			(xy 289.076166 -280.068109) (xy 289.025384 -280.076152) (xy 288.973968 -280.076152) (xy 288.923186 -280.068109)
			(xy 288.874287 -280.052221) (xy 288.828475 -280.028878) (xy 288.786879 -279.998657) (xy 288.750523 -279.962301)
			(xy 288.720302 -279.920705) (xy 288.696959 -279.874893) (xy 288.681071 -279.825994) (xy 288.673028 -279.775212)
			(xy 288.354391 -279.775212) (xy 288.346634 -279.822942) (xy 288.33105 -279.869623) (xy 288.308179 -279.9132)
			(xy 288.278614 -279.952544) (xy 288.243121 -279.986636) (xy 288.202618 -280.014592) (xy 288.158156 -280.03569)
			(xy 288.110885 -280.049382) (xy 288.06203 -280.055314) (xy 288.012855 -280.053333) (xy 287.964636 -280.043489)
			(xy 287.91862 -280.026037) (xy 287.875999 -280.00143) (xy 287.837878 -279.970305) (xy 287.805243 -279.933468)
			(xy 287.77894 -279.891872) (xy 287.759649 -279.846596) (xy 287.747872 -279.798812) (xy 287.743912 -279.749758)
			(xy 287.426903 -279.749758) (xy 287.426404 -279.775212) (xy 287.418361 -279.825994) (xy 287.402473 -279.874893)
			(xy 287.37913 -279.920705) (xy 287.348909 -279.962301) (xy 287.312553 -279.998657) (xy 287.270957 -280.028878)
			(xy 287.225145 -280.052221) (xy 287.176246 -280.068109) (xy 287.125464 -280.076152) (xy 287.074048 -280.076152)
			(xy 287.023266 -280.068109) (xy 286.974367 -280.052221) (xy 286.928555 -280.028878) (xy 286.886959 -279.998657)
			(xy 286.850603 -279.962301) (xy 286.820382 -279.920705) (xy 286.797039 -279.874893) (xy 286.781151 -279.825994)
			(xy 286.773108 -279.775212) (xy 286.454471 -279.775212) (xy 286.446714 -279.822942) (xy 286.43113 -279.869623)
			(xy 286.408259 -279.9132) (xy 286.378694 -279.952544) (xy 286.343201 -279.986636) (xy 286.302698 -280.014592)
			(xy 286.258236 -280.03569) (xy 286.210965 -280.049382) (xy 286.16211 -280.055314) (xy 286.112935 -280.053333)
			(xy 286.064716 -280.043489) (xy 286.0187 -280.026037) (xy 285.976079 -280.00143) (xy 285.937958 -279.970305)
			(xy 285.905323 -279.933468) (xy 285.87902 -279.891872) (xy 285.859729 -279.846596) (xy 285.847952 -279.798812)
			(xy 285.843992 -279.749758) (xy 285.526983 -279.749758) (xy 285.526484 -279.775212) (xy 285.518441 -279.825994)
			(xy 285.502553 -279.874893) (xy 285.47921 -279.920705) (xy 285.448989 -279.962301) (xy 285.412633 -279.998657)
			(xy 285.371037 -280.028878) (xy 285.325225 -280.052221) (xy 285.276326 -280.068109) (xy 285.225544 -280.076152)
			(xy 285.174128 -280.076152) (xy 285.123346 -280.068109) (xy 285.074447 -280.052221) (xy 285.028635 -280.028878)
			(xy 284.987039 -279.998657) (xy 284.950683 -279.962301) (xy 284.920462 -279.920705) (xy 284.897119 -279.874893)
			(xy 284.881231 -279.825994) (xy 284.873188 -279.775212) (xy 284.554551 -279.775212) (xy 284.546794 -279.822942)
			(xy 284.53121 -279.869623) (xy 284.508339 -279.9132) (xy 284.478774 -279.952544) (xy 284.443281 -279.986636)
			(xy 284.402778 -280.014592) (xy 284.358316 -280.03569) (xy 284.311045 -280.049382) (xy 284.26219 -280.055314)
			(xy 284.213015 -280.053333) (xy 284.164796 -280.043489) (xy 284.11878 -280.026037) (xy 284.076159 -280.00143)
			(xy 284.038038 -279.970305) (xy 284.005403 -279.933468) (xy 283.9791 -279.891872) (xy 283.959809 -279.846596)
			(xy 283.948032 -279.798812) (xy 283.944072 -279.749758) (xy 283.627063 -279.749758) (xy 283.626564 -279.775212)
			(xy 283.618521 -279.825994) (xy 283.602633 -279.874893) (xy 283.57929 -279.920705) (xy 283.549069 -279.962301)
			(xy 283.512713 -279.998657) (xy 283.471117 -280.028878) (xy 283.425305 -280.052221) (xy 283.376406 -280.068109)
			(xy 283.325624 -280.076152) (xy 283.274208 -280.076152) (xy 283.223426 -280.068109) (xy 283.174527 -280.052221)
			(xy 283.128715 -280.028878) (xy 283.087119 -279.998657) (xy 283.050763 -279.962301) (xy 283.020542 -279.920705)
			(xy 282.997199 -279.874893) (xy 282.981311 -279.825994) (xy 282.973268 -279.775212) (xy 282.654377 -279.775212)
			(xy 282.64662 -279.822942) (xy 282.631036 -279.869623) (xy 282.608165 -279.9132) (xy 282.5786 -279.952544)
			(xy 282.543107 -279.986636) (xy 282.502604 -280.014592) (xy 282.458142 -280.03569) (xy 282.410871 -280.049382)
			(xy 282.362016 -280.055314) (xy 282.312841 -280.053333) (xy 282.264622 -280.043489) (xy 282.218606 -280.026037)
			(xy 282.175985 -280.00143) (xy 282.137864 -279.970305) (xy 282.105229 -279.933468) (xy 282.078926 -279.891872)
			(xy 282.059635 -279.846596) (xy 282.047858 -279.798812) (xy 282.043898 -279.749758) (xy 281.726889 -279.749758)
			(xy 281.72639 -279.775212) (xy 281.718347 -279.825994) (xy 281.702459 -279.874893) (xy 281.679116 -279.920705)
			(xy 281.648895 -279.962301) (xy 281.612539 -279.998657) (xy 281.570943 -280.028878) (xy 281.525131 -280.052221)
			(xy 281.476232 -280.068109) (xy 281.42545 -280.076152) (xy 281.374034 -280.076152) (xy 281.323252 -280.068109)
			(xy 281.274353 -280.052221) (xy 281.228541 -280.028878) (xy 281.186945 -279.998657) (xy 281.150589 -279.962301)
			(xy 281.120368 -279.920705) (xy 281.097025 -279.874893) (xy 281.081137 -279.825994) (xy 281.073094 -279.775212)
			(xy 280.754457 -279.775212) (xy 280.7467 -279.822942) (xy 280.731116 -279.869623) (xy 280.708245 -279.9132)
			(xy 280.67868 -279.952544) (xy 280.643187 -279.986636) (xy 280.602684 -280.014592) (xy 280.558222 -280.03569)
			(xy 280.510951 -280.049382) (xy 280.462096 -280.055314) (xy 280.412921 -280.053333) (xy 280.364702 -280.043489)
			(xy 280.318686 -280.026037) (xy 280.276065 -280.00143) (xy 280.237944 -279.970305) (xy 280.205309 -279.933468)
			(xy 280.179006 -279.891872) (xy 280.159715 -279.846596) (xy 280.147938 -279.798812) (xy 280.143978 -279.749758)
			(xy 279.826969 -279.749758) (xy 279.82647 -279.775212) (xy 279.818427 -279.825994) (xy 279.802539 -279.874893)
			(xy 279.779196 -279.920705) (xy 279.748975 -279.962301) (xy 279.712619 -279.998657) (xy 279.671023 -280.028878)
			(xy 279.625211 -280.052221) (xy 279.576312 -280.068109) (xy 279.52553 -280.076152) (xy 279.474114 -280.076152)
			(xy 279.423332 -280.068109) (xy 279.374433 -280.052221) (xy 279.328621 -280.028878) (xy 279.287025 -279.998657)
			(xy 279.250669 -279.962301) (xy 279.220448 -279.920705) (xy 279.197105 -279.874893) (xy 279.181217 -279.825994)
			(xy 279.173174 -279.775212) (xy 278.854537 -279.775212) (xy 278.84678 -279.822942) (xy 278.831196 -279.869623)
			(xy 278.808325 -279.9132) (xy 278.77876 -279.952544) (xy 278.743267 -279.986636) (xy 278.702764 -280.014592)
			(xy 278.658302 -280.03569) (xy 278.611031 -280.049382) (xy 278.562176 -280.055314) (xy 278.513001 -280.053333)
			(xy 278.464782 -280.043489) (xy 278.418766 -280.026037) (xy 278.376145 -280.00143) (xy 278.338024 -279.970305)
			(xy 278.305389 -279.933468) (xy 278.279086 -279.891872) (xy 278.259795 -279.846596) (xy 278.248018 -279.798812)
			(xy 278.244058 -279.749758) (xy 277.927049 -279.749758) (xy 277.92655 -279.775212) (xy 277.918507 -279.825994)
			(xy 277.902619 -279.874893) (xy 277.879276 -279.920705) (xy 277.849055 -279.962301) (xy 277.812699 -279.998657)
			(xy 277.771103 -280.028878) (xy 277.725291 -280.052221) (xy 277.676392 -280.068109) (xy 277.62561 -280.076152)
			(xy 277.574194 -280.076152) (xy 277.523412 -280.068109) (xy 277.474513 -280.052221) (xy 277.428701 -280.028878)
			(xy 277.387105 -279.998657) (xy 277.350749 -279.962301) (xy 277.320528 -279.920705) (xy 277.297185 -279.874893)
			(xy 277.281297 -279.825994) (xy 277.273254 -279.775212) (xy 276.954363 -279.775212) (xy 276.946606 -279.822942)
			(xy 276.931022 -279.869623) (xy 276.908151 -279.9132) (xy 276.878586 -279.952544) (xy 276.843093 -279.986636)
			(xy 276.80259 -280.014592) (xy 276.758128 -280.03569) (xy 276.710857 -280.049382) (xy 276.662002 -280.055314)
			(xy 276.612827 -280.053333) (xy 276.564608 -280.043489) (xy 276.518592 -280.026037) (xy 276.475971 -280.00143)
			(xy 276.43785 -279.970305) (xy 276.405215 -279.933468) (xy 276.378912 -279.891872) (xy 276.359621 -279.846596)
			(xy 276.347844 -279.798812) (xy 276.343884 -279.749758) (xy 264.266944 -279.749758) (xy 264.288803 -279.79762)
			(xy 264.304158 -279.849915) (xy 264.311914 -279.903863) (xy 264.3124 -279.931114) (xy 264.311872 -279.960497)
			(xy 264.302839 -280.018564) (xy 264.285005 -280.074559) (xy 264.258791 -280.127154) (xy 264.224818 -280.175105)
			(xy 264.183891 -280.217276) (xy 264.174371 -280.224738) (xy 268.26897 -280.224738) (xy 268.27293 -280.175684)
			(xy 268.284707 -280.1279) (xy 268.303998 -280.082624) (xy 268.330301 -280.041028) (xy 268.362936 -280.004191)
			(xy 268.401057 -279.973066) (xy 268.443678 -279.948459) (xy 268.489694 -279.931007) (xy 268.537913 -279.921163)
			(xy 268.587088 -279.919182) (xy 268.635943 -279.925114) (xy 268.683214 -279.938806) (xy 268.727676 -279.959904)
			(xy 268.768179 -279.98786) (xy 268.803672 -280.021952) (xy 268.833237 -280.061296) (xy 268.856108 -280.104873)
			(xy 268.871692 -280.151554) (xy 268.879587 -280.200131) (xy 268.880082 -280.224738) (xy 269.21893 -280.224738)
			(xy 269.22289 -280.175684) (xy 269.234667 -280.1279) (xy 269.253958 -280.082624) (xy 269.280261 -280.041028)
			(xy 269.312896 -280.004191) (xy 269.351017 -279.973066) (xy 269.393638 -279.948459) (xy 269.439654 -279.931007)
			(xy 269.487873 -279.921163) (xy 269.537048 -279.919182) (xy 269.585903 -279.925114) (xy 269.633174 -279.938806)
			(xy 269.677636 -279.959904) (xy 269.718139 -279.98786) (xy 269.753632 -280.021952) (xy 269.783197 -280.061296)
			(xy 269.806068 -280.104873) (xy 269.821652 -280.151554) (xy 269.829547 -280.200131) (xy 269.830042 -280.224738)
			(xy 270.169144 -280.224738) (xy 270.173104 -280.175684) (xy 270.184881 -280.1279) (xy 270.204172 -280.082624)
			(xy 270.230475 -280.041028) (xy 270.26311 -280.004191) (xy 270.301231 -279.973066) (xy 270.343852 -279.948459)
			(xy 270.389868 -279.931007) (xy 270.438087 -279.921163) (xy 270.487262 -279.919182) (xy 270.536117 -279.925114)
			(xy 270.583388 -279.938806) (xy 270.62785 -279.959904) (xy 270.668353 -279.98786) (xy 270.703846 -280.021952)
			(xy 270.733411 -280.061296) (xy 270.756282 -280.104873) (xy 270.771866 -280.151554) (xy 270.779761 -280.200131)
			(xy 270.780256 -280.224738) (xy 271.119104 -280.224738) (xy 271.123064 -280.175684) (xy 271.134841 -280.1279)
			(xy 271.154132 -280.082624) (xy 271.180435 -280.041028) (xy 271.21307 -280.004191) (xy 271.251191 -279.973066)
			(xy 271.293812 -279.948459) (xy 271.339828 -279.931007) (xy 271.388047 -279.921163) (xy 271.437222 -279.919182)
			(xy 271.486077 -279.925114) (xy 271.533348 -279.938806) (xy 271.57781 -279.959904) (xy 271.618313 -279.98786)
			(xy 271.653806 -280.021952) (xy 271.683371 -280.061296) (xy 271.706242 -280.104873) (xy 271.721826 -280.151554)
			(xy 271.729721 -280.200131) (xy 271.730216 -280.224738) (xy 272.069064 -280.224738) (xy 272.073024 -280.175684)
			(xy 272.084801 -280.1279) (xy 272.104092 -280.082624) (xy 272.130395 -280.041028) (xy 272.16303 -280.004191)
			(xy 272.201151 -279.973066) (xy 272.243772 -279.948459) (xy 272.289788 -279.931007) (xy 272.338007 -279.921163)
			(xy 272.387182 -279.919182) (xy 272.436037 -279.925114) (xy 272.483308 -279.938806) (xy 272.52777 -279.959904)
			(xy 272.568273 -279.98786) (xy 272.603766 -280.021952) (xy 272.633331 -280.061296) (xy 272.656202 -280.104873)
			(xy 272.671786 -280.151554) (xy 272.679681 -280.200131) (xy 272.680176 -280.224738) (xy 273.019024 -280.224738)
			(xy 273.022984 -280.175684) (xy 273.034761 -280.1279) (xy 273.054052 -280.082624) (xy 273.080355 -280.041028)
			(xy 273.11299 -280.004191) (xy 273.151111 -279.973066) (xy 273.193732 -279.948459) (xy 273.239748 -279.931007)
			(xy 273.287967 -279.921163) (xy 273.337142 -279.919182) (xy 273.385997 -279.925114) (xy 273.433268 -279.938806)
			(xy 273.47773 -279.959904) (xy 273.518233 -279.98786) (xy 273.553726 -280.021952) (xy 273.583291 -280.061296)
			(xy 273.606162 -280.104873) (xy 273.621746 -280.151554) (xy 273.629641 -280.200131) (xy 273.630136 -280.224738)
			(xy 273.968984 -280.224738) (xy 273.972944 -280.175684) (xy 273.984721 -280.1279) (xy 274.004012 -280.082624)
			(xy 274.030315 -280.041028) (xy 274.06295 -280.004191) (xy 274.101071 -279.973066) (xy 274.143692 -279.948459)
			(xy 274.189708 -279.931007) (xy 274.237927 -279.921163) (xy 274.287102 -279.919182) (xy 274.335957 -279.925114)
			(xy 274.383228 -279.938806) (xy 274.42769 -279.959904) (xy 274.468193 -279.98786) (xy 274.503686 -280.021952)
			(xy 274.533251 -280.061296) (xy 274.556122 -280.104873) (xy 274.571706 -280.151554) (xy 274.579601 -280.200131)
			(xy 274.580096 -280.224738) (xy 274.918944 -280.224738) (xy 274.922904 -280.175684) (xy 274.934681 -280.1279)
			(xy 274.953972 -280.082624) (xy 274.980275 -280.041028) (xy 275.01291 -280.004191) (xy 275.051031 -279.973066)
			(xy 275.093652 -279.948459) (xy 275.139668 -279.931007) (xy 275.187887 -279.921163) (xy 275.237062 -279.919182)
			(xy 275.285917 -279.925114) (xy 275.333188 -279.938806) (xy 275.37765 -279.959904) (xy 275.418153 -279.98786)
			(xy 275.453646 -280.021952) (xy 275.483211 -280.061296) (xy 275.506082 -280.104873) (xy 275.521666 -280.151554)
			(xy 275.529561 -280.200131) (xy 275.530056 -280.224738) (xy 275.529561 -280.249345) (xy 275.521666 -280.297922)
			(xy 275.506082 -280.344603) (xy 275.483211 -280.38818) (xy 275.453646 -280.427524) (xy 275.418153 -280.461616)
			(xy 275.37765 -280.489572) (xy 275.333188 -280.51067) (xy 275.285917 -280.524362) (xy 275.237062 -280.530294)
			(xy 275.187887 -280.528313) (xy 275.139668 -280.518469) (xy 275.093652 -280.501017) (xy 275.051031 -280.47641)
			(xy 275.01291 -280.445285) (xy 274.980275 -280.408448) (xy 274.953972 -280.366852) (xy 274.934681 -280.321576)
			(xy 274.922904 -280.273792) (xy 274.918944 -280.224738) (xy 274.580096 -280.224738) (xy 274.579601 -280.249345)
			(xy 274.571706 -280.297922) (xy 274.556122 -280.344603) (xy 274.533251 -280.38818) (xy 274.503686 -280.427524)
			(xy 274.468193 -280.461616) (xy 274.42769 -280.489572) (xy 274.383228 -280.51067) (xy 274.335957 -280.524362)
			(xy 274.287102 -280.530294) (xy 274.237927 -280.528313) (xy 274.189708 -280.518469) (xy 274.143692 -280.501017)
			(xy 274.101071 -280.47641) (xy 274.06295 -280.445285) (xy 274.030315 -280.408448) (xy 274.004012 -280.366852)
			(xy 273.984721 -280.321576) (xy 273.972944 -280.273792) (xy 273.968984 -280.224738) (xy 273.630136 -280.224738)
			(xy 273.629641 -280.249345) (xy 273.621746 -280.297922) (xy 273.606162 -280.344603) (xy 273.583291 -280.38818)
			(xy 273.553726 -280.427524) (xy 273.518233 -280.461616) (xy 273.47773 -280.489572) (xy 273.433268 -280.51067)
			(xy 273.385997 -280.524362) (xy 273.337142 -280.530294) (xy 273.287967 -280.528313) (xy 273.239748 -280.518469)
			(xy 273.193732 -280.501017) (xy 273.151111 -280.47641) (xy 273.11299 -280.445285) (xy 273.080355 -280.408448)
			(xy 273.054052 -280.366852) (xy 273.034761 -280.321576) (xy 273.022984 -280.273792) (xy 273.019024 -280.224738)
			(xy 272.680176 -280.224738) (xy 272.679681 -280.249345) (xy 272.671786 -280.297922) (xy 272.656202 -280.344603)
			(xy 272.633331 -280.38818) (xy 272.603766 -280.427524) (xy 272.568273 -280.461616) (xy 272.52777 -280.489572)
			(xy 272.483308 -280.51067) (xy 272.436037 -280.524362) (xy 272.387182 -280.530294) (xy 272.338007 -280.528313)
			(xy 272.289788 -280.518469) (xy 272.243772 -280.501017) (xy 272.201151 -280.47641) (xy 272.16303 -280.445285)
			(xy 272.130395 -280.408448) (xy 272.104092 -280.366852) (xy 272.084801 -280.321576) (xy 272.073024 -280.273792)
			(xy 272.069064 -280.224738) (xy 271.730216 -280.224738) (xy 271.729721 -280.249345) (xy 271.721826 -280.297922)
			(xy 271.706242 -280.344603) (xy 271.683371 -280.38818) (xy 271.653806 -280.427524) (xy 271.618313 -280.461616)
			(xy 271.57781 -280.489572) (xy 271.533348 -280.51067) (xy 271.486077 -280.524362) (xy 271.437222 -280.530294)
			(xy 271.388047 -280.528313) (xy 271.339828 -280.518469) (xy 271.293812 -280.501017) (xy 271.251191 -280.47641)
			(xy 271.21307 -280.445285) (xy 271.180435 -280.408448) (xy 271.154132 -280.366852) (xy 271.134841 -280.321576)
			(xy 271.123064 -280.273792) (xy 271.119104 -280.224738) (xy 270.780256 -280.224738) (xy 270.779761 -280.249345)
			(xy 270.771866 -280.297922) (xy 270.756282 -280.344603) (xy 270.733411 -280.38818) (xy 270.703846 -280.427524)
			(xy 270.668353 -280.461616) (xy 270.62785 -280.489572) (xy 270.583388 -280.51067) (xy 270.536117 -280.524362)
			(xy 270.487262 -280.530294) (xy 270.438087 -280.528313) (xy 270.389868 -280.518469) (xy 270.343852 -280.501017)
			(xy 270.301231 -280.47641) (xy 270.26311 -280.445285) (xy 270.230475 -280.408448) (xy 270.204172 -280.366852)
			(xy 270.184881 -280.321576) (xy 270.173104 -280.273792) (xy 270.169144 -280.224738) (xy 269.830042 -280.224738)
			(xy 269.829547 -280.249345) (xy 269.821652 -280.297922) (xy 269.806068 -280.344603) (xy 269.783197 -280.38818)
			(xy 269.753632 -280.427524) (xy 269.718139 -280.461616) (xy 269.677636 -280.489572) (xy 269.633174 -280.51067)
			(xy 269.585903 -280.524362) (xy 269.537048 -280.530294) (xy 269.487873 -280.528313) (xy 269.439654 -280.518469)
			(xy 269.393638 -280.501017) (xy 269.351017 -280.47641) (xy 269.312896 -280.445285) (xy 269.280261 -280.408448)
			(xy 269.253958 -280.366852) (xy 269.234667 -280.321576) (xy 269.22289 -280.273792) (xy 269.21893 -280.224738)
			(xy 268.880082 -280.224738) (xy 268.879587 -280.249345) (xy 268.871692 -280.297922) (xy 268.856108 -280.344603)
			(xy 268.833237 -280.38818) (xy 268.803672 -280.427524) (xy 268.768179 -280.461616) (xy 268.727676 -280.489572)
			(xy 268.683214 -280.51067) (xy 268.635943 -280.524362) (xy 268.587088 -280.530294) (xy 268.537913 -280.528313)
			(xy 268.489694 -280.518469) (xy 268.443678 -280.501017) (xy 268.401057 -280.47641) (xy 268.362936 -280.445285)
			(xy 268.330301 -280.408448) (xy 268.303998 -280.366852) (xy 268.284707 -280.321576) (xy 268.27293 -280.273792)
			(xy 268.26897 -280.224738) (xy 264.174371 -280.224738) (xy 264.160762 -280.235406) (xy 264.151364 -280.242772)
			(xy 264.14095 -280.263346) (xy 264.139426 -280.367232) (xy 264.149332 -280.388314) (xy 264.158476 -280.39568)
			(xy 264.180292 -280.413923) (xy 264.218835 -280.455733) (xy 264.250747 -280.502801) (xy 264.275319 -280.554084)
			(xy 264.292009 -280.608445) (xy 264.300447 -280.664681) (xy 264.30097 -280.693114) (xy 264.934444 -280.693114)
			(xy 264.938515 -280.637492) (xy 264.950641 -280.583055) (xy 264.970564 -280.530964) (xy 264.99786 -280.482329)
			(xy 265.031946 -280.438186) (xy 265.072095 -280.399477) (xy 265.117453 -280.367026) (xy 265.167053 -280.341525)
			(xy 265.219837 -280.323518) (xy 265.27468 -280.313388) (xy 265.330414 -280.311351) (xy 265.385851 -280.317451)
			(xy 265.439808 -280.331557) (xy 265.491137 -280.353369) (xy 265.538743 -280.382423) (xy 265.581611 -280.418098)
			(xy 265.618828 -280.459635) (xy 265.649601 -280.506148) (xy 265.673273 -280.556645) (xy 265.689341 -280.610052)
			(xy 265.697461 -280.665228) (xy 265.69797 -280.693114) (xy 265.820904 -280.693114) (xy 265.824975 -280.637492)
			(xy 265.837101 -280.583055) (xy 265.857024 -280.530964) (xy 265.88432 -280.482329) (xy 265.918406 -280.438186)
			(xy 265.958555 -280.399477) (xy 266.003913 -280.367026) (xy 266.053513 -280.341525) (xy 266.106297 -280.323518)
			(xy 266.16114 -280.313388) (xy 266.216874 -280.311351) (xy 266.272311 -280.317451) (xy 266.326268 -280.331557)
			(xy 266.377597 -280.353369) (xy 266.425203 -280.382423) (xy 266.468071 -280.418098) (xy 266.505288 -280.459635)
			(xy 266.536061 -280.506148) (xy 266.559733 -280.556645) (xy 266.575801 -280.610052) (xy 266.583921 -280.665228)
			(xy 266.58443 -280.693114) (xy 266.583921 -280.721) (xy 266.575801 -280.776176) (xy 266.559733 -280.829583)
			(xy 266.536061 -280.88008) (xy 266.505288 -280.926593) (xy 266.468071 -280.96813) (xy 266.425203 -281.003805)
			(xy 266.377597 -281.032859) (xy 266.326268 -281.054671) (xy 266.272311 -281.068777) (xy 266.216874 -281.074877)
			(xy 266.16114 -281.07284) (xy 266.106297 -281.06271) (xy 266.053513 -281.044703) (xy 266.003913 -281.019202)
			(xy 265.958555 -280.986751) (xy 265.918406 -280.948042) (xy 265.88432 -280.903899) (xy 265.857024 -280.855264)
			(xy 265.837101 -280.803173) (xy 265.824975 -280.748736) (xy 265.820904 -280.693114) (xy 265.69797 -280.693114)
			(xy 265.697461 -280.721) (xy 265.689341 -280.776176) (xy 265.673273 -280.829583) (xy 265.649601 -280.88008)
			(xy 265.618828 -280.926593) (xy 265.581611 -280.96813) (xy 265.538743 -281.003805) (xy 265.491137 -281.032859)
			(xy 265.439808 -281.054671) (xy 265.385851 -281.068777) (xy 265.330414 -281.074877) (xy 265.27468 -281.07284)
			(xy 265.219837 -281.06271) (xy 265.167053 -281.044703) (xy 265.117453 -281.019202) (xy 265.072095 -280.986751)
			(xy 265.031946 -280.948042) (xy 264.99786 -280.903899) (xy 264.970564 -280.855264) (xy 264.950641 -280.803173)
			(xy 264.938515 -280.748736) (xy 264.934444 -280.693114) (xy 264.30097 -280.693114) (xy 264.300484 -280.720365)
			(xy 264.292728 -280.774313) (xy 264.277373 -280.826608) (xy 264.254731 -280.876185) (xy 264.225265 -280.922035)
			(xy 264.189574 -280.963226) (xy 264.148383 -280.998917) (xy 264.102533 -281.028383) (xy 264.052956 -281.051025)
			(xy 264.000661 -281.06638) (xy 263.946713 -281.074136) (xy 263.892211 -281.074136) (xy 263.838263 -281.06638)
			(xy 263.785968 -281.051025) (xy 263.736391 -281.028383) (xy 263.690541 -280.998917) (xy 263.64935 -280.963226)
			(xy 263.613659 -280.922035) (xy 263.584193 -280.876185) (xy 263.561551 -280.826608) (xy 263.546196 -280.774313)
			(xy 263.53844 -280.720365) (xy 263.537954 -280.693114) (xy 249.469293 -280.693114) (xy 249.462315 -280.71688)
			(xy 249.439673 -280.766457) (xy 249.410207 -280.812307) (xy 249.374516 -280.853498) (xy 249.333325 -280.889189)
			(xy 249.287475 -280.918655) (xy 249.237898 -280.941297) (xy 249.185603 -280.956652) (xy 249.131655 -280.964408)
			(xy 249.077153 -280.964408) (xy 249.023205 -280.956652) (xy 248.97091 -280.941297) (xy 248.921333 -280.918655)
			(xy 248.875483 -280.889189) (xy 248.834292 -280.853498) (xy 248.798601 -280.812307) (xy 248.769135 -280.766457)
			(xy 248.746493 -280.71688) (xy 248.731138 -280.664585) (xy 248.723382 -280.610637) (xy 248.722896 -280.583386)
			(xy 245.820737 -280.583386) (xy 245.820699 -280.583644) (xy 245.804631 -280.637051) (xy 245.780959 -280.687548)
			(xy 245.750186 -280.734061) (xy 245.712969 -280.775598) (xy 245.670101 -280.811273) (xy 245.622495 -280.840327)
			(xy 245.571166 -280.862139) (xy 245.517209 -280.876245) (xy 245.461772 -280.882345) (xy 245.406038 -280.880308)
			(xy 245.351195 -280.870178) (xy 245.298411 -280.852171) (xy 245.248811 -280.82667) (xy 245.203453 -280.794219)
			(xy 245.163304 -280.75551) (xy 245.129218 -280.711367) (xy 245.101922 -280.662732) (xy 245.081999 -280.610641)
			(xy 245.069873 -280.556204) (xy 245.065802 -280.500582) (xy 243.307623 -280.500582) (xy 243.304269 -280.503155)
			(xy 243.249481 -280.53478) (xy 243.191035 -280.558987) (xy 243.129931 -280.575363) (xy 243.067212 -280.583626)
			(xy 243.035582 -280.584148) (xy 243.003955 -280.583676) (xy 242.941244 -280.575415) (xy 242.880147 -280.559036)
			(xy 242.821713 -280.53482) (xy 242.76694 -280.503182) (xy 242.716767 -280.464664) (xy 242.672053 -280.419924)
			(xy 242.633563 -280.369729) (xy 242.601957 -280.314938) (xy 242.577775 -280.256489) (xy 242.561431 -280.195384)
			(xy 242.553206 -280.132667) (xy 242.552728 -280.10104) (xy 241.39779 -280.10104) (xy 241.397281 -280.128926)
			(xy 241.389161 -280.184102) (xy 241.373093 -280.237509) (xy 241.349421 -280.288006) (xy 241.318648 -280.334519)
			(xy 241.281431 -280.376056) (xy 241.238563 -280.411731) (xy 241.190957 -280.440785) (xy 241.139628 -280.462597)
			(xy 241.085671 -280.476703) (xy 241.030234 -280.482803) (xy 240.9745 -280.480766) (xy 240.919657 -280.470636)
			(xy 240.866873 -280.452629) (xy 240.817273 -280.427128) (xy 240.771915 -280.394677) (xy 240.731766 -280.355968)
			(xy 240.69768 -280.311825) (xy 240.670384 -280.26319) (xy 240.650461 -280.211099) (xy 240.638335 -280.156662)
			(xy 240.634264 -280.10104) (xy 233.259565 -280.10104) (xy 233.25889 -280.10216) (xy 233.226394 -280.142496)
			(xy 233.188742 -280.178067) (xy 233.167936 -280.193496) (xy 233.1593 -280.199592) (xy 233.148378 -280.217626)
			(xy 233.135932 -280.312368) (xy 233.141774 -280.332434) (xy 233.148632 -280.340562) (xy 233.165059 -280.361144)
			(xy 233.192659 -280.405992) (xy 233.213819 -280.454213) (xy 233.228136 -280.50489) (xy 233.235336 -280.557056)
			(xy 233.235754 -280.583386) (xy 233.235268 -280.610637) (xy 233.227512 -280.664585) (xy 233.212157 -280.71688)
			(xy 233.189515 -280.766457) (xy 233.160049 -280.812307) (xy 233.124358 -280.853498) (xy 233.083167 -280.889189)
			(xy 233.037317 -280.918655) (xy 232.98774 -280.941297) (xy 232.935445 -280.956652) (xy 232.881497 -280.964408)
			(xy 232.826995 -280.964408) (xy 232.773047 -280.956652) (xy 232.720752 -280.941297) (xy 232.671175 -280.918655)
			(xy 232.625325 -280.889189) (xy 232.584134 -280.853498) (xy 232.548443 -280.812307) (xy 232.518977 -280.766457)
			(xy 232.496335 -280.71688) (xy 232.48098 -280.664585) (xy 232.473224 -280.610637) (xy 232.472738 -280.583386)
			(xy 229.570579 -280.583386) (xy 229.570541 -280.583644) (xy 229.554473 -280.637051) (xy 229.530801 -280.687548)
			(xy 229.500028 -280.734061) (xy 229.462811 -280.775598) (xy 229.419943 -280.811273) (xy 229.372337 -280.840327)
			(xy 229.321008 -280.862139) (xy 229.267051 -280.876245) (xy 229.211614 -280.882345) (xy 229.15588 -280.880308)
			(xy 229.101037 -280.870178) (xy 229.048253 -280.852171) (xy 228.998653 -280.82667) (xy 228.953295 -280.794219)
			(xy 228.913146 -280.75551) (xy 228.87906 -280.711367) (xy 228.851764 -280.662732) (xy 228.831841 -280.610641)
			(xy 228.819715 -280.556204) (xy 228.815644 -280.500582) (xy 227.068962 -280.500582) (xy 226.019532 -281.55011)
			(xy 250.225812 -281.55011) (xy 250.229883 -281.494488) (xy 250.242009 -281.440051) (xy 250.261932 -281.38796)
			(xy 250.289228 -281.339325) (xy 250.323314 -281.295182) (xy 250.363463 -281.256473) (xy 250.408821 -281.224022)
			(xy 250.458421 -281.198521) (xy 250.511205 -281.180514) (xy 250.566048 -281.170384) (xy 250.621782 -281.168347)
			(xy 250.677219 -281.174447) (xy 250.679151 -281.174952) (xy 268.26897 -281.174952) (xy 268.27293 -281.125898)
			(xy 268.284707 -281.078114) (xy 268.303998 -281.032838) (xy 268.330301 -280.991242) (xy 268.362936 -280.954405)
			(xy 268.401057 -280.92328) (xy 268.443678 -280.898673) (xy 268.489694 -280.881221) (xy 268.537913 -280.871377)
			(xy 268.587088 -280.869396) (xy 268.635943 -280.875328) (xy 268.683214 -280.88902) (xy 268.727676 -280.910118)
			(xy 268.768179 -280.938074) (xy 268.803672 -280.972166) (xy 268.833237 -281.01151) (xy 268.856108 -281.055087)
			(xy 268.871692 -281.101768) (xy 268.879587 -281.150345) (xy 268.880082 -281.174952) (xy 269.21893 -281.174952)
			(xy 269.22289 -281.125898) (xy 269.234667 -281.078114) (xy 269.253958 -281.032838) (xy 269.280261 -280.991242)
			(xy 269.312896 -280.954405) (xy 269.351017 -280.92328) (xy 269.393638 -280.898673) (xy 269.439654 -280.881221)
			(xy 269.487873 -280.871377) (xy 269.537048 -280.869396) (xy 269.585903 -280.875328) (xy 269.633174 -280.88902)
			(xy 269.677636 -280.910118) (xy 269.718139 -280.938074) (xy 269.753632 -280.972166) (xy 269.783197 -281.01151)
			(xy 269.806068 -281.055087) (xy 269.821652 -281.101768) (xy 269.829547 -281.150345) (xy 269.830042 -281.174952)
			(xy 270.169144 -281.174952) (xy 270.173104 -281.125898) (xy 270.184881 -281.078114) (xy 270.204172 -281.032838)
			(xy 270.230475 -280.991242) (xy 270.26311 -280.954405) (xy 270.301231 -280.92328) (xy 270.343852 -280.898673)
			(xy 270.389868 -280.881221) (xy 270.438087 -280.871377) (xy 270.487262 -280.869396) (xy 270.536117 -280.875328)
			(xy 270.583388 -280.88902) (xy 270.62785 -280.910118) (xy 270.668353 -280.938074) (xy 270.703846 -280.972166)
			(xy 270.733411 -281.01151) (xy 270.756282 -281.055087) (xy 270.771866 -281.101768) (xy 270.779761 -281.150345)
			(xy 270.780256 -281.174952) (xy 271.119104 -281.174952) (xy 271.123064 -281.125898) (xy 271.134841 -281.078114)
			(xy 271.154132 -281.032838) (xy 271.180435 -280.991242) (xy 271.21307 -280.954405) (xy 271.251191 -280.92328)
			(xy 271.293812 -280.898673) (xy 271.339828 -280.881221) (xy 271.388047 -280.871377) (xy 271.437222 -280.869396)
			(xy 271.486077 -280.875328) (xy 271.533348 -280.88902) (xy 271.57781 -280.910118) (xy 271.618313 -280.938074)
			(xy 271.653806 -280.972166) (xy 271.683371 -281.01151) (xy 271.706242 -281.055087) (xy 271.721826 -281.101768)
			(xy 271.729721 -281.150345) (xy 271.730216 -281.174952) (xy 272.069064 -281.174952) (xy 272.073024 -281.125898)
			(xy 272.084801 -281.078114) (xy 272.104092 -281.032838) (xy 272.130395 -280.991242) (xy 272.16303 -280.954405)
			(xy 272.201151 -280.92328) (xy 272.243772 -280.898673) (xy 272.289788 -280.881221) (xy 272.338007 -280.871377)
			(xy 272.387182 -280.869396) (xy 272.436037 -280.875328) (xy 272.483308 -280.88902) (xy 272.52777 -280.910118)
			(xy 272.568273 -280.938074) (xy 272.603766 -280.972166) (xy 272.633331 -281.01151) (xy 272.656202 -281.055087)
			(xy 272.671786 -281.101768) (xy 272.679681 -281.150345) (xy 272.680176 -281.174952) (xy 273.019024 -281.174952)
			(xy 273.022984 -281.125898) (xy 273.034761 -281.078114) (xy 273.054052 -281.032838) (xy 273.080355 -280.991242)
			(xy 273.11299 -280.954405) (xy 273.151111 -280.92328) (xy 273.193732 -280.898673) (xy 273.239748 -280.881221)
			(xy 273.287967 -280.871377) (xy 273.337142 -280.869396) (xy 273.385997 -280.875328) (xy 273.433268 -280.88902)
			(xy 273.47773 -280.910118) (xy 273.518233 -280.938074) (xy 273.553726 -280.972166) (xy 273.583291 -281.01151)
			(xy 273.606162 -281.055087) (xy 273.621746 -281.101768) (xy 273.629641 -281.150345) (xy 273.630136 -281.174952)
			(xy 273.968984 -281.174952) (xy 273.972944 -281.125898) (xy 273.984721 -281.078114) (xy 274.004012 -281.032838)
			(xy 274.030315 -280.991242) (xy 274.06295 -280.954405) (xy 274.101071 -280.92328) (xy 274.143692 -280.898673)
			(xy 274.189708 -280.881221) (xy 274.237927 -280.871377) (xy 274.287102 -280.869396) (xy 274.335957 -280.875328)
			(xy 274.383228 -280.88902) (xy 274.42769 -280.910118) (xy 274.468193 -280.938074) (xy 274.503686 -280.972166)
			(xy 274.533251 -281.01151) (xy 274.556122 -281.055087) (xy 274.571706 -281.101768) (xy 274.579601 -281.150345)
			(xy 274.580096 -281.174952) (xy 274.918944 -281.174952) (xy 274.922904 -281.125898) (xy 274.934681 -281.078114)
			(xy 274.953972 -281.032838) (xy 274.980275 -280.991242) (xy 275.01291 -280.954405) (xy 275.051031 -280.92328)
			(xy 275.093652 -280.898673) (xy 275.139668 -280.881221) (xy 275.187887 -280.871377) (xy 275.237062 -280.869396)
			(xy 275.285917 -280.875328) (xy 275.333188 -280.88902) (xy 275.37765 -280.910118) (xy 275.418153 -280.938074)
			(xy 275.453646 -280.972166) (xy 275.483211 -281.01151) (xy 275.506082 -281.055087) (xy 275.521666 -281.101768)
			(xy 275.529561 -281.150345) (xy 275.530056 -281.174952) (xy 275.530055 -281.175) (xy 275.868792 -281.175)
			(xy 275.872964 -281.124648) (xy 275.885367 -281.07567) (xy 275.905663 -281.029402) (xy 275.933298 -280.987105)
			(xy 275.967517 -280.949933) (xy 276.007388 -280.918901) (xy 276.051824 -280.894855) (xy 276.099611 -280.878451)
			(xy 276.149446 -280.870136) (xy 276.174708 -280.869644) (xy 276.188891 -280.869819) (xy 276.217131 -280.872492)
			(xy 276.231096 -280.874978) (xy 276.243542 -280.877264) (xy 276.267418 -280.869898) (xy 276.344634 -280.792682)
			(xy 276.352 -280.768552) (xy 276.349714 -280.75636) (xy 276.347226 -280.742332) (xy 276.344556 -280.713964)
			(xy 276.34438 -280.699718) (xy 276.344859 -280.674895) (xy 276.352888 -280.625903) (xy 276.368737 -280.578855)
			(xy 276.391989 -280.534992) (xy 276.422032 -280.495468) (xy 276.458073 -280.461325) (xy 276.499163 -280.433463)
			(xy 276.544219 -280.412616) (xy 276.592055 -280.399332) (xy 276.64141 -280.393963) (xy 276.690983 -280.39665)
			(xy 276.739468 -280.407321) (xy 276.785588 -280.425696) (xy 276.828127 -280.45129) (xy 276.865966 -280.48343)
			(xy 276.898106 -280.521268) (xy 276.923701 -280.563807) (xy 276.942077 -280.609927) (xy 276.952749 -280.658412)
			(xy 276.955437 -280.707984) (xy 276.95354 -280.725426) (xy 277.273254 -280.725426) (xy 277.273254 -280.67401)
			(xy 277.281297 -280.623228) (xy 277.297185 -280.574329) (xy 277.320528 -280.528517) (xy 277.350749 -280.486921)
			(xy 277.387105 -280.450565) (xy 277.428701 -280.420344) (xy 277.474513 -280.397001) (xy 277.523412 -280.381113)
			(xy 277.574194 -280.37307) (xy 277.62561 -280.37307) (xy 277.676392 -280.381113) (xy 277.725291 -280.397001)
			(xy 277.771103 -280.420344) (xy 277.812699 -280.450565) (xy 277.849055 -280.486921) (xy 277.879276 -280.528517)
			(xy 277.902619 -280.574329) (xy 277.918507 -280.623228) (xy 277.92655 -280.67401) (xy 277.927054 -280.699718)
			(xy 278.244058 -280.699718) (xy 278.248018 -280.650664) (xy 278.259795 -280.60288) (xy 278.279086 -280.557604)
			(xy 278.305389 -280.516008) (xy 278.338024 -280.479171) (xy 278.376145 -280.448046) (xy 278.418766 -280.423439)
			(xy 278.464782 -280.405987) (xy 278.513001 -280.396143) (xy 278.562176 -280.394162) (xy 278.611031 -280.400094)
			(xy 278.658302 -280.413786) (xy 278.702764 -280.434884) (xy 278.743267 -280.46284) (xy 278.77876 -280.496932)
			(xy 278.808325 -280.536276) (xy 278.831196 -280.579853) (xy 278.84678 -280.626534) (xy 278.854675 -280.675111)
			(xy 278.85517 -280.699718) (xy 278.854675 -280.724325) (xy 278.854496 -280.725426) (xy 279.173174 -280.725426)
			(xy 279.173174 -280.67401) (xy 279.181217 -280.623228) (xy 279.197105 -280.574329) (xy 279.220448 -280.528517)
			(xy 279.250669 -280.486921) (xy 279.287025 -280.450565) (xy 279.328621 -280.420344) (xy 279.374433 -280.397001)
			(xy 279.423332 -280.381113) (xy 279.474114 -280.37307) (xy 279.52553 -280.37307) (xy 279.576312 -280.381113)
			(xy 279.625211 -280.397001) (xy 279.671023 -280.420344) (xy 279.712619 -280.450565) (xy 279.748975 -280.486921)
			(xy 279.779196 -280.528517) (xy 279.802539 -280.574329) (xy 279.818427 -280.623228) (xy 279.82647 -280.67401)
			(xy 279.826974 -280.699718) (xy 280.143978 -280.699718) (xy 280.147938 -280.650664) (xy 280.159715 -280.60288)
			(xy 280.179006 -280.557604) (xy 280.205309 -280.516008) (xy 280.237944 -280.479171) (xy 280.276065 -280.448046)
			(xy 280.318686 -280.423439) (xy 280.364702 -280.405987) (xy 280.412921 -280.396143) (xy 280.462096 -280.394162)
			(xy 280.510951 -280.400094) (xy 280.558222 -280.413786) (xy 280.602684 -280.434884) (xy 280.643187 -280.46284)
			(xy 280.67868 -280.496932) (xy 280.708245 -280.536276) (xy 280.731116 -280.579853) (xy 280.7467 -280.626534)
			(xy 280.754595 -280.675111) (xy 280.75509 -280.699718) (xy 280.754595 -280.724325) (xy 280.754416 -280.725426)
			(xy 281.073094 -280.725426) (xy 281.073094 -280.67401) (xy 281.081137 -280.623228) (xy 281.097025 -280.574329)
			(xy 281.120368 -280.528517) (xy 281.150589 -280.486921) (xy 281.186945 -280.450565) (xy 281.228541 -280.420344)
			(xy 281.274353 -280.397001) (xy 281.323252 -280.381113) (xy 281.374034 -280.37307) (xy 281.42545 -280.37307)
			(xy 281.476232 -280.381113) (xy 281.525131 -280.397001) (xy 281.570943 -280.420344) (xy 281.612539 -280.450565)
			(xy 281.648895 -280.486921) (xy 281.679116 -280.528517) (xy 281.702459 -280.574329) (xy 281.718347 -280.623228)
			(xy 281.72639 -280.67401) (xy 281.726894 -280.699718) (xy 282.043898 -280.699718) (xy 282.047858 -280.650664)
			(xy 282.059635 -280.60288) (xy 282.078926 -280.557604) (xy 282.105229 -280.516008) (xy 282.137864 -280.479171)
			(xy 282.175985 -280.448046) (xy 282.218606 -280.423439) (xy 282.264622 -280.405987) (xy 282.312841 -280.396143)
			(xy 282.362016 -280.394162) (xy 282.410871 -280.400094) (xy 282.458142 -280.413786) (xy 282.502604 -280.434884)
			(xy 282.543107 -280.46284) (xy 282.5786 -280.496932) (xy 282.608165 -280.536276) (xy 282.631036 -280.579853)
			(xy 282.64662 -280.626534) (xy 282.654515 -280.675111) (xy 282.65501 -280.699718) (xy 282.654515 -280.724325)
			(xy 282.654336 -280.725426) (xy 282.973268 -280.725426) (xy 282.973268 -280.67401) (xy 282.981311 -280.623228)
			(xy 282.997199 -280.574329) (xy 283.020542 -280.528517) (xy 283.050763 -280.486921) (xy 283.087119 -280.450565)
			(xy 283.128715 -280.420344) (xy 283.174527 -280.397001) (xy 283.223426 -280.381113) (xy 283.274208 -280.37307)
			(xy 283.325624 -280.37307) (xy 283.376406 -280.381113) (xy 283.425305 -280.397001) (xy 283.471117 -280.420344)
			(xy 283.512713 -280.450565) (xy 283.549069 -280.486921) (xy 283.57929 -280.528517) (xy 283.602633 -280.574329)
			(xy 283.618521 -280.623228) (xy 283.626564 -280.67401) (xy 283.627068 -280.699718) (xy 283.944072 -280.699718)
			(xy 283.948032 -280.650664) (xy 283.959809 -280.60288) (xy 283.9791 -280.557604) (xy 284.005403 -280.516008)
			(xy 284.038038 -280.479171) (xy 284.076159 -280.448046) (xy 284.11878 -280.423439) (xy 284.164796 -280.405987)
			(xy 284.213015 -280.396143) (xy 284.26219 -280.394162) (xy 284.311045 -280.400094) (xy 284.358316 -280.413786)
			(xy 284.402778 -280.434884) (xy 284.443281 -280.46284) (xy 284.478774 -280.496932) (xy 284.508339 -280.536276)
			(xy 284.53121 -280.579853) (xy 284.546794 -280.626534) (xy 284.554689 -280.675111) (xy 284.555184 -280.699718)
			(xy 284.554689 -280.724325) (xy 284.55451 -280.725426) (xy 284.873188 -280.725426) (xy 284.873188 -280.67401)
			(xy 284.881231 -280.623228) (xy 284.897119 -280.574329) (xy 284.920462 -280.528517) (xy 284.950683 -280.486921)
			(xy 284.987039 -280.450565) (xy 285.028635 -280.420344) (xy 285.074447 -280.397001) (xy 285.123346 -280.381113)
			(xy 285.174128 -280.37307) (xy 285.225544 -280.37307) (xy 285.276326 -280.381113) (xy 285.325225 -280.397001)
			(xy 285.371037 -280.420344) (xy 285.412633 -280.450565) (xy 285.448989 -280.486921) (xy 285.47921 -280.528517)
			(xy 285.502553 -280.574329) (xy 285.518441 -280.623228) (xy 285.526484 -280.67401) (xy 285.526988 -280.699718)
			(xy 285.843992 -280.699718) (xy 285.847952 -280.650664) (xy 285.859729 -280.60288) (xy 285.87902 -280.557604)
			(xy 285.905323 -280.516008) (xy 285.937958 -280.479171) (xy 285.976079 -280.448046) (xy 286.0187 -280.423439)
			(xy 286.064716 -280.405987) (xy 286.112935 -280.396143) (xy 286.16211 -280.394162) (xy 286.210965 -280.400094)
			(xy 286.258236 -280.413786) (xy 286.302698 -280.434884) (xy 286.343201 -280.46284) (xy 286.378694 -280.496932)
			(xy 286.408259 -280.536276) (xy 286.43113 -280.579853) (xy 286.446714 -280.626534) (xy 286.454609 -280.675111)
			(xy 286.455104 -280.699718) (xy 286.454609 -280.724325) (xy 286.45443 -280.725426) (xy 286.773108 -280.725426)
			(xy 286.773108 -280.67401) (xy 286.781151 -280.623228) (xy 286.797039 -280.574329) (xy 286.820382 -280.528517)
			(xy 286.850603 -280.486921) (xy 286.886959 -280.450565) (xy 286.928555 -280.420344) (xy 286.974367 -280.397001)
			(xy 287.023266 -280.381113) (xy 287.074048 -280.37307) (xy 287.125464 -280.37307) (xy 287.176246 -280.381113)
			(xy 287.225145 -280.397001) (xy 287.270957 -280.420344) (xy 287.312553 -280.450565) (xy 287.348909 -280.486921)
			(xy 287.37913 -280.528517) (xy 287.402473 -280.574329) (xy 287.418361 -280.623228) (xy 287.426404 -280.67401)
			(xy 287.426908 -280.699718) (xy 287.743912 -280.699718) (xy 287.747872 -280.650664) (xy 287.759649 -280.60288)
			(xy 287.77894 -280.557604) (xy 287.805243 -280.516008) (xy 287.837878 -280.479171) (xy 287.875999 -280.448046)
			(xy 287.91862 -280.423439) (xy 287.964636 -280.405987) (xy 288.012855 -280.396143) (xy 288.06203 -280.394162)
			(xy 288.110885 -280.400094) (xy 288.158156 -280.413786) (xy 288.202618 -280.434884) (xy 288.243121 -280.46284)
			(xy 288.278614 -280.496932) (xy 288.308179 -280.536276) (xy 288.33105 -280.579853) (xy 288.346634 -280.626534)
			(xy 288.354529 -280.675111) (xy 288.355024 -280.699718) (xy 288.354529 -280.724325) (xy 288.35435 -280.725426)
			(xy 288.673028 -280.725426) (xy 288.673028 -280.67401) (xy 288.681071 -280.623228) (xy 288.696959 -280.574329)
			(xy 288.720302 -280.528517) (xy 288.750523 -280.486921) (xy 288.786879 -280.450565) (xy 288.828475 -280.420344)
			(xy 288.874287 -280.397001) (xy 288.923186 -280.381113) (xy 288.973968 -280.37307) (xy 289.025384 -280.37307)
			(xy 289.076166 -280.381113) (xy 289.125065 -280.397001) (xy 289.170877 -280.420344) (xy 289.212473 -280.450565)
			(xy 289.248829 -280.486921) (xy 289.27905 -280.528517) (xy 289.302393 -280.574329) (xy 289.318281 -280.623228)
			(xy 289.326324 -280.67401) (xy 289.326828 -280.699718) (xy 289.644086 -280.699718) (xy 289.648046 -280.650664)
			(xy 289.659823 -280.60288) (xy 289.679114 -280.557604) (xy 289.705417 -280.516008) (xy 289.738052 -280.479171)
			(xy 289.776173 -280.448046) (xy 289.818794 -280.423439) (xy 289.86481 -280.405987) (xy 289.913029 -280.396143)
			(xy 289.962204 -280.394162) (xy 290.011059 -280.400094) (xy 290.05833 -280.413786) (xy 290.102792 -280.434884)
			(xy 290.143295 -280.46284) (xy 290.178788 -280.496932) (xy 290.208353 -280.536276) (xy 290.231224 -280.579853)
			(xy 290.246808 -280.626534) (xy 290.254703 -280.675111) (xy 290.255198 -280.699718) (xy 290.254703 -280.724325)
			(xy 290.254524 -280.725426) (xy 290.573202 -280.725426) (xy 290.573202 -280.67401) (xy 290.581245 -280.623228)
			(xy 290.597133 -280.574329) (xy 290.620476 -280.528517) (xy 290.650697 -280.486921) (xy 290.687053 -280.450565)
			(xy 290.728649 -280.420344) (xy 290.774461 -280.397001) (xy 290.82336 -280.381113) (xy 290.874142 -280.37307)
			(xy 290.925558 -280.37307) (xy 290.97634 -280.381113) (xy 291.025239 -280.397001) (xy 291.071051 -280.420344)
			(xy 291.112647 -280.450565) (xy 291.149003 -280.486921) (xy 291.179224 -280.528517) (xy 291.202567 -280.574329)
			(xy 291.218455 -280.623228) (xy 291.226498 -280.67401) (xy 291.227002 -280.699718) (xy 291.544006 -280.699718)
			(xy 291.547966 -280.650664) (xy 291.559743 -280.60288) (xy 291.579034 -280.557604) (xy 291.605337 -280.516008)
			(xy 291.637972 -280.479171) (xy 291.676093 -280.448046) (xy 291.718714 -280.423439) (xy 291.76473 -280.405987)
			(xy 291.812949 -280.396143) (xy 291.862124 -280.394162) (xy 291.910979 -280.400094) (xy 291.95825 -280.413786)
			(xy 292.002712 -280.434884) (xy 292.043215 -280.46284) (xy 292.078708 -280.496932) (xy 292.108273 -280.536276)
			(xy 292.131144 -280.579853) (xy 292.146728 -280.626534) (xy 292.154623 -280.675111) (xy 292.155118 -280.699718)
			(xy 292.154623 -280.724325) (xy 292.154444 -280.725426) (xy 292.473122 -280.725426) (xy 292.473122 -280.67401)
			(xy 292.481165 -280.623228) (xy 292.497053 -280.574329) (xy 292.520396 -280.528517) (xy 292.550617 -280.486921)
			(xy 292.586973 -280.450565) (xy 292.628569 -280.420344) (xy 292.674381 -280.397001) (xy 292.72328 -280.381113)
			(xy 292.774062 -280.37307) (xy 292.825478 -280.37307) (xy 292.87626 -280.381113) (xy 292.925159 -280.397001)
			(xy 292.970971 -280.420344) (xy 293.012567 -280.450565) (xy 293.048923 -280.486921) (xy 293.079144 -280.528517)
			(xy 293.102487 -280.574329) (xy 293.118375 -280.623228) (xy 293.126418 -280.67401) (xy 293.126922 -280.699718)
			(xy 293.443926 -280.699718) (xy 293.447886 -280.650664) (xy 293.459663 -280.60288) (xy 293.478954 -280.557604)
			(xy 293.505257 -280.516008) (xy 293.537892 -280.479171) (xy 293.576013 -280.448046) (xy 293.618634 -280.423439)
			(xy 293.66465 -280.405987) (xy 293.712869 -280.396143) (xy 293.762044 -280.394162) (xy 293.810899 -280.400094)
			(xy 293.85817 -280.413786) (xy 293.902632 -280.434884) (xy 293.943135 -280.46284) (xy 293.978628 -280.496932)
			(xy 294.008193 -280.536276) (xy 294.031064 -280.579853) (xy 294.046648 -280.626534) (xy 294.054543 -280.675111)
			(xy 294.055038 -280.699718) (xy 294.054543 -280.724325) (xy 294.054364 -280.725426) (xy 294.373042 -280.725426)
			(xy 294.373042 -280.67401) (xy 294.381085 -280.623228) (xy 294.396973 -280.574329) (xy 294.420316 -280.528517)
			(xy 294.450537 -280.486921) (xy 294.486893 -280.450565) (xy 294.528489 -280.420344) (xy 294.574301 -280.397001)
			(xy 294.6232 -280.381113) (xy 294.673982 -280.37307) (xy 294.725398 -280.37307) (xy 294.77618 -280.381113)
			(xy 294.825079 -280.397001) (xy 294.870891 -280.420344) (xy 294.912487 -280.450565) (xy 294.948843 -280.486921)
			(xy 294.979064 -280.528517) (xy 295.002407 -280.574329) (xy 295.018295 -280.623228) (xy 295.026338 -280.67401)
			(xy 295.026842 -280.699718) (xy 295.3441 -280.699718) (xy 295.34806 -280.650664) (xy 295.359837 -280.60288)
			(xy 295.379128 -280.557604) (xy 295.405431 -280.516008) (xy 295.438066 -280.479171) (xy 295.476187 -280.448046)
			(xy 295.518808 -280.423439) (xy 295.564824 -280.405987) (xy 295.613043 -280.396143) (xy 295.662218 -280.394162)
			(xy 295.711073 -280.400094) (xy 295.758344 -280.413786) (xy 295.802806 -280.434884) (xy 295.843309 -280.46284)
			(xy 295.878802 -280.496932) (xy 295.908367 -280.536276) (xy 295.931238 -280.579853) (xy 295.946822 -280.626534)
			(xy 295.954717 -280.675111) (xy 295.955212 -280.699718) (xy 295.954717 -280.724325) (xy 295.954538 -280.725426)
			(xy 296.273216 -280.725426) (xy 296.273216 -280.67401) (xy 296.281259 -280.623228) (xy 296.297147 -280.574329)
			(xy 296.32049 -280.528517) (xy 296.350711 -280.486921) (xy 296.387067 -280.450565) (xy 296.428663 -280.420344)
			(xy 296.474475 -280.397001) (xy 296.523374 -280.381113) (xy 296.574156 -280.37307) (xy 296.625572 -280.37307)
			(xy 296.676354 -280.381113) (xy 296.725253 -280.397001) (xy 296.771065 -280.420344) (xy 296.812661 -280.450565)
			(xy 296.849017 -280.486921) (xy 296.879238 -280.528517) (xy 296.902581 -280.574329) (xy 296.918469 -280.623228)
			(xy 296.926512 -280.67401) (xy 296.927016 -280.699718) (xy 297.24402 -280.699718) (xy 297.24798 -280.650664)
			(xy 297.259757 -280.60288) (xy 297.279048 -280.557604) (xy 297.305351 -280.516008) (xy 297.337986 -280.479171)
			(xy 297.376107 -280.448046) (xy 297.418728 -280.423439) (xy 297.464744 -280.405987) (xy 297.512963 -280.396143)
			(xy 297.562138 -280.394162) (xy 297.610993 -280.400094) (xy 297.658264 -280.413786) (xy 297.702726 -280.434884)
			(xy 297.743229 -280.46284) (xy 297.778722 -280.496932) (xy 297.808287 -280.536276) (xy 297.831158 -280.579853)
			(xy 297.846742 -280.626534) (xy 297.854637 -280.675111) (xy 297.855132 -280.699718) (xy 297.854637 -280.724325)
			(xy 297.854458 -280.725426) (xy 298.173136 -280.725426) (xy 298.173136 -280.67401) (xy 298.181179 -280.623228)
			(xy 298.197067 -280.574329) (xy 298.22041 -280.528517) (xy 298.250631 -280.486921) (xy 298.286987 -280.450565)
			(xy 298.328583 -280.420344) (xy 298.374395 -280.397001) (xy 298.423294 -280.381113) (xy 298.474076 -280.37307)
			(xy 298.525492 -280.37307) (xy 298.576274 -280.381113) (xy 298.625173 -280.397001) (xy 298.670985 -280.420344)
			(xy 298.712581 -280.450565) (xy 298.748937 -280.486921) (xy 298.779158 -280.528517) (xy 298.802501 -280.574329)
			(xy 298.818389 -280.623228) (xy 298.826432 -280.67401) (xy 298.826936 -280.699718) (xy 299.14394 -280.699718)
			(xy 299.1479 -280.650664) (xy 299.159677 -280.60288) (xy 299.178968 -280.557604) (xy 299.205271 -280.516008)
			(xy 299.237906 -280.479171) (xy 299.276027 -280.448046) (xy 299.318648 -280.423439) (xy 299.364664 -280.405987)
			(xy 299.412883 -280.396143) (xy 299.462058 -280.394162) (xy 299.510913 -280.400094) (xy 299.558184 -280.413786)
			(xy 299.602646 -280.434884) (xy 299.643149 -280.46284) (xy 299.678642 -280.496932) (xy 299.708207 -280.536276)
			(xy 299.731078 -280.579853) (xy 299.746662 -280.626534) (xy 299.754557 -280.675111) (xy 299.755052 -280.699718)
			(xy 299.754557 -280.724325) (xy 299.754378 -280.725426) (xy 300.073056 -280.725426) (xy 300.073056 -280.67401)
			(xy 300.081099 -280.623228) (xy 300.096987 -280.574329) (xy 300.12033 -280.528517) (xy 300.150551 -280.486921)
			(xy 300.186907 -280.450565) (xy 300.228503 -280.420344) (xy 300.274315 -280.397001) (xy 300.323214 -280.381113)
			(xy 300.373996 -280.37307) (xy 300.425412 -280.37307) (xy 300.476194 -280.381113) (xy 300.525093 -280.397001)
			(xy 300.570905 -280.420344) (xy 300.612501 -280.450565) (xy 300.648857 -280.486921) (xy 300.679078 -280.528517)
			(xy 300.702421 -280.574329) (xy 300.718309 -280.623228) (xy 300.726352 -280.67401) (xy 300.726856 -280.699718)
			(xy 301.044114 -280.699718) (xy 301.048074 -280.650664) (xy 301.059851 -280.60288) (xy 301.079142 -280.557604)
			(xy 301.105445 -280.516008) (xy 301.13808 -280.479171) (xy 301.176201 -280.448046) (xy 301.218822 -280.423439)
			(xy 301.264838 -280.405987) (xy 301.313057 -280.396143) (xy 301.362232 -280.394162) (xy 301.411087 -280.400094)
			(xy 301.458358 -280.413786) (xy 301.50282 -280.434884) (xy 301.543323 -280.46284) (xy 301.578816 -280.496932)
			(xy 301.608381 -280.536276) (xy 301.631252 -280.579853) (xy 301.646836 -280.626534) (xy 301.654731 -280.675111)
			(xy 301.655226 -280.699718) (xy 301.654731 -280.724325) (xy 301.654552 -280.725426) (xy 301.97323 -280.725426)
			(xy 301.97323 -280.67401) (xy 301.981273 -280.623228) (xy 301.997161 -280.574329) (xy 302.020504 -280.528517)
			(xy 302.050725 -280.486921) (xy 302.087081 -280.450565) (xy 302.128677 -280.420344) (xy 302.174489 -280.397001)
			(xy 302.223388 -280.381113) (xy 302.27417 -280.37307) (xy 302.325586 -280.37307) (xy 302.376368 -280.381113)
			(xy 302.425267 -280.397001) (xy 302.471079 -280.420344) (xy 302.512675 -280.450565) (xy 302.549031 -280.486921)
			(xy 302.579252 -280.528517) (xy 302.602595 -280.574329) (xy 302.618483 -280.623228) (xy 302.626526 -280.67401)
			(xy 302.62703 -280.699718) (xy 302.944034 -280.699718) (xy 302.947994 -280.650664) (xy 302.959771 -280.60288)
			(xy 302.979062 -280.557604) (xy 303.005365 -280.516008) (xy 303.038 -280.479171) (xy 303.076121 -280.448046)
			(xy 303.118742 -280.423439) (xy 303.164758 -280.405987) (xy 303.212977 -280.396143) (xy 303.262152 -280.394162)
			(xy 303.311007 -280.400094) (xy 303.358278 -280.413786) (xy 303.40274 -280.434884) (xy 303.443243 -280.46284)
			(xy 303.478736 -280.496932) (xy 303.508301 -280.536276) (xy 303.531172 -280.579853) (xy 303.546756 -280.626534)
			(xy 303.554651 -280.675111) (xy 303.555146 -280.699718) (xy 303.554651 -280.724325) (xy 303.554472 -280.725426)
			(xy 303.87315 -280.725426) (xy 303.87315 -280.67401) (xy 303.881193 -280.623228) (xy 303.897081 -280.574329)
			(xy 303.920424 -280.528517) (xy 303.950645 -280.486921) (xy 303.987001 -280.450565) (xy 304.028597 -280.420344)
			(xy 304.074409 -280.397001) (xy 304.123308 -280.381113) (xy 304.17409 -280.37307) (xy 304.225506 -280.37307)
			(xy 304.276288 -280.381113) (xy 304.325187 -280.397001) (xy 304.370999 -280.420344) (xy 304.412595 -280.450565)
			(xy 304.448951 -280.486921) (xy 304.479172 -280.528517) (xy 304.502515 -280.574329) (xy 304.518403 -280.623228)
			(xy 304.526446 -280.67401) (xy 304.52695 -280.699718) (xy 304.843954 -280.699718) (xy 304.847914 -280.650664)
			(xy 304.859691 -280.60288) (xy 304.878982 -280.557604) (xy 304.905285 -280.516008) (xy 304.93792 -280.479171)
			(xy 304.976041 -280.448046) (xy 305.018662 -280.423439) (xy 305.064678 -280.405987) (xy 305.112897 -280.396143)
			(xy 305.162072 -280.394162) (xy 305.210927 -280.400094) (xy 305.258198 -280.413786) (xy 305.30266 -280.434884)
			(xy 305.343163 -280.46284) (xy 305.378656 -280.496932) (xy 305.408221 -280.536276) (xy 305.431092 -280.579853)
			(xy 305.446676 -280.626534) (xy 305.454571 -280.675111) (xy 305.455066 -280.699718) (xy 305.454571 -280.724325)
			(xy 305.454392 -280.725426) (xy 305.77307 -280.725426) (xy 305.77307 -280.67401) (xy 305.781113 -280.623228)
			(xy 305.797001 -280.574329) (xy 305.820344 -280.528517) (xy 305.850565 -280.486921) (xy 305.886921 -280.450565)
			(xy 305.928517 -280.420344) (xy 305.974329 -280.397001) (xy 306.023228 -280.381113) (xy 306.07401 -280.37307)
			(xy 306.125426 -280.37307) (xy 306.176208 -280.381113) (xy 306.225107 -280.397001) (xy 306.270919 -280.420344)
			(xy 306.312515 -280.450565) (xy 306.348871 -280.486921) (xy 306.379092 -280.528517) (xy 306.402435 -280.574329)
			(xy 306.418323 -280.623228) (xy 306.426366 -280.67401) (xy 306.42687 -280.699718) (xy 306.744128 -280.699718)
			(xy 306.748088 -280.650664) (xy 306.759865 -280.60288) (xy 306.779156 -280.557604) (xy 306.805459 -280.516008)
			(xy 306.838094 -280.479171) (xy 306.876215 -280.448046) (xy 306.918836 -280.423439) (xy 306.964852 -280.405987)
			(xy 307.013071 -280.396143) (xy 307.062246 -280.394162) (xy 307.111101 -280.400094) (xy 307.158372 -280.413786)
			(xy 307.202834 -280.434884) (xy 307.243337 -280.46284) (xy 307.27883 -280.496932) (xy 307.308395 -280.536276)
			(xy 307.331266 -280.579853) (xy 307.34685 -280.626534) (xy 307.354745 -280.675111) (xy 307.35524 -280.699718)
			(xy 307.354745 -280.724325) (xy 307.354566 -280.725426) (xy 307.673244 -280.725426) (xy 307.673244 -280.67401)
			(xy 307.681287 -280.623228) (xy 307.697175 -280.574329) (xy 307.720518 -280.528517) (xy 307.750739 -280.486921)
			(xy 307.787095 -280.450565) (xy 307.828691 -280.420344) (xy 307.874503 -280.397001) (xy 307.923402 -280.381113)
			(xy 307.974184 -280.37307) (xy 308.0256 -280.37307) (xy 308.076382 -280.381113) (xy 308.125281 -280.397001)
			(xy 308.171093 -280.420344) (xy 308.212689 -280.450565) (xy 308.249045 -280.486921) (xy 308.279266 -280.528517)
			(xy 308.302609 -280.574329) (xy 308.318497 -280.623228) (xy 308.32654 -280.67401) (xy 308.327044 -280.699718)
			(xy 308.644048 -280.699718) (xy 308.648008 -280.650664) (xy 308.659785 -280.60288) (xy 308.679076 -280.557604)
			(xy 308.705379 -280.516008) (xy 308.738014 -280.479171) (xy 308.776135 -280.448046) (xy 308.818756 -280.423439)
			(xy 308.864772 -280.405987) (xy 308.912991 -280.396143) (xy 308.962166 -280.394162) (xy 309.011021 -280.400094)
			(xy 309.058292 -280.413786) (xy 309.102754 -280.434884) (xy 309.143257 -280.46284) (xy 309.17875 -280.496932)
			(xy 309.208315 -280.536276) (xy 309.231186 -280.579853) (xy 309.24677 -280.626534) (xy 309.254665 -280.675111)
			(xy 309.25516 -280.699718) (xy 309.254665 -280.724325) (xy 309.254486 -280.725426) (xy 309.573164 -280.725426)
			(xy 309.573164 -280.67401) (xy 309.581207 -280.623228) (xy 309.597095 -280.574329) (xy 309.620438 -280.528517)
			(xy 309.650659 -280.486921) (xy 309.687015 -280.450565) (xy 309.728611 -280.420344) (xy 309.774423 -280.397001)
			(xy 309.823322 -280.381113) (xy 309.874104 -280.37307) (xy 309.92552 -280.37307) (xy 309.976302 -280.381113)
			(xy 310.025201 -280.397001) (xy 310.071013 -280.420344) (xy 310.112609 -280.450565) (xy 310.148965 -280.486921)
			(xy 310.179186 -280.528517) (xy 310.202529 -280.574329) (xy 310.218417 -280.623228) (xy 310.22646 -280.67401)
			(xy 310.226964 -280.699718) (xy 310.543968 -280.699718) (xy 310.547928 -280.650664) (xy 310.559705 -280.60288)
			(xy 310.578996 -280.557604) (xy 310.605299 -280.516008) (xy 310.637934 -280.479171) (xy 310.676055 -280.448046)
			(xy 310.718676 -280.423439) (xy 310.764692 -280.405987) (xy 310.812911 -280.396143) (xy 310.862086 -280.394162)
			(xy 310.910941 -280.400094) (xy 310.958212 -280.413786) (xy 311.002674 -280.434884) (xy 311.043177 -280.46284)
			(xy 311.07867 -280.496932) (xy 311.108235 -280.536276) (xy 311.131106 -280.579853) (xy 311.14669 -280.626534)
			(xy 311.154585 -280.675111) (xy 311.15508 -280.699718) (xy 311.154585 -280.724325) (xy 311.154406 -280.725426)
			(xy 311.473084 -280.725426) (xy 311.473084 -280.67401) (xy 311.481127 -280.623228) (xy 311.497015 -280.574329)
			(xy 311.520358 -280.528517) (xy 311.550579 -280.486921) (xy 311.586935 -280.450565) (xy 311.628531 -280.420344)
			(xy 311.674343 -280.397001) (xy 311.723242 -280.381113) (xy 311.774024 -280.37307) (xy 311.82544 -280.37307)
			(xy 311.876222 -280.381113) (xy 311.925121 -280.397001) (xy 311.970933 -280.420344) (xy 312.012529 -280.450565)
			(xy 312.048885 -280.486921) (xy 312.079106 -280.528517) (xy 312.102449 -280.574329) (xy 312.118337 -280.623228)
			(xy 312.12638 -280.67401) (xy 312.126884 -280.699718) (xy 312.444142 -280.699718) (xy 312.448102 -280.650664)
			(xy 312.459879 -280.60288) (xy 312.47917 -280.557604) (xy 312.505473 -280.516008) (xy 312.538108 -280.479171)
			(xy 312.576229 -280.448046) (xy 312.61885 -280.423439) (xy 312.664866 -280.405987) (xy 312.713085 -280.396143)
			(xy 312.76226 -280.394162) (xy 312.811115 -280.400094) (xy 312.858386 -280.413786) (xy 312.902848 -280.434884)
			(xy 312.943351 -280.46284) (xy 312.978844 -280.496932) (xy 313.008409 -280.536276) (xy 313.03128 -280.579853)
			(xy 313.046864 -280.626534) (xy 313.054759 -280.675111) (xy 313.055254 -280.699718) (xy 313.394102 -280.699718)
			(xy 313.398062 -280.650664) (xy 313.409839 -280.60288) (xy 313.42913 -280.557604) (xy 313.455433 -280.516008)
			(xy 313.488068 -280.479171) (xy 313.526189 -280.448046) (xy 313.56881 -280.423439) (xy 313.614826 -280.405987)
			(xy 313.663045 -280.396143) (xy 313.71222 -280.394162) (xy 313.761075 -280.400094) (xy 313.808346 -280.413786)
			(xy 313.852808 -280.434884) (xy 313.893311 -280.46284) (xy 313.928804 -280.496932) (xy 313.958369 -280.536276)
			(xy 313.98124 -280.579853) (xy 313.996824 -280.626534) (xy 314.004719 -280.675111) (xy 314.005214 -280.699718)
			(xy 314.344062 -280.699718) (xy 314.348022 -280.650664) (xy 314.359799 -280.60288) (xy 314.37909 -280.557604)
			(xy 314.405393 -280.516008) (xy 314.438028 -280.479171) (xy 314.476149 -280.448046) (xy 314.51877 -280.423439)
			(xy 314.564786 -280.405987) (xy 314.613005 -280.396143) (xy 314.66218 -280.394162) (xy 314.711035 -280.400094)
			(xy 314.758306 -280.413786) (xy 314.802768 -280.434884) (xy 314.843271 -280.46284) (xy 314.878764 -280.496932)
			(xy 314.908329 -280.536276) (xy 314.9312 -280.579853) (xy 314.946784 -280.626534) (xy 314.954679 -280.675111)
			(xy 314.955174 -280.699718) (xy 314.954679 -280.724325) (xy 314.946784 -280.772902) (xy 314.9312 -280.819583)
			(xy 314.908329 -280.86316) (xy 314.878764 -280.902504) (xy 314.843271 -280.936596) (xy 314.802768 -280.964552)
			(xy 314.758306 -280.98565) (xy 314.711035 -280.999342) (xy 314.66218 -281.005274) (xy 314.613005 -281.003293)
			(xy 314.564786 -280.993449) (xy 314.51877 -280.975997) (xy 314.476149 -280.95139) (xy 314.438028 -280.920265)
			(xy 314.405393 -280.883428) (xy 314.37909 -280.841832) (xy 314.359799 -280.796556) (xy 314.348022 -280.748772)
			(xy 314.344062 -280.699718) (xy 314.005214 -280.699718) (xy 314.004719 -280.724325) (xy 313.996824 -280.772902)
			(xy 313.98124 -280.819583) (xy 313.958369 -280.86316) (xy 313.928804 -280.902504) (xy 313.893311 -280.936596)
			(xy 313.852808 -280.964552) (xy 313.808346 -280.98565) (xy 313.761075 -280.999342) (xy 313.71222 -281.005274)
			(xy 313.663045 -281.003293) (xy 313.614826 -280.993449) (xy 313.56881 -280.975997) (xy 313.526189 -280.95139)
			(xy 313.488068 -280.920265) (xy 313.455433 -280.883428) (xy 313.42913 -280.841832) (xy 313.409839 -280.796556)
			(xy 313.398062 -280.748772) (xy 313.394102 -280.699718) (xy 313.055254 -280.699718) (xy 313.054759 -280.724325)
			(xy 313.046864 -280.772902) (xy 313.03128 -280.819583) (xy 313.008409 -280.86316) (xy 312.978844 -280.902504)
			(xy 312.943351 -280.936596) (xy 312.902848 -280.964552) (xy 312.858386 -280.98565) (xy 312.811115 -280.999342)
			(xy 312.76226 -281.005274) (xy 312.713085 -281.003293) (xy 312.664866 -280.993449) (xy 312.61885 -280.975997)
			(xy 312.576229 -280.95139) (xy 312.538108 -280.920265) (xy 312.505473 -280.883428) (xy 312.47917 -280.841832)
			(xy 312.459879 -280.796556) (xy 312.448102 -280.748772) (xy 312.444142 -280.699718) (xy 312.126884 -280.699718)
			(xy 312.12638 -280.725426) (xy 312.118337 -280.776208) (xy 312.102449 -280.825107) (xy 312.079106 -280.870919)
			(xy 312.048885 -280.912515) (xy 312.012529 -280.948871) (xy 311.970933 -280.979092) (xy 311.925121 -281.002435)
			(xy 311.876222 -281.018323) (xy 311.82544 -281.026366) (xy 311.774024 -281.026366) (xy 311.723242 -281.018323)
			(xy 311.674343 -281.002435) (xy 311.628531 -280.979092) (xy 311.586935 -280.948871) (xy 311.550579 -280.912515)
			(xy 311.520358 -280.870919) (xy 311.497015 -280.825107) (xy 311.481127 -280.776208) (xy 311.473084 -280.725426)
			(xy 311.154406 -280.725426) (xy 311.14669 -280.772902) (xy 311.131106 -280.819583) (xy 311.108235 -280.86316)
			(xy 311.07867 -280.902504) (xy 311.043177 -280.936596) (xy 311.002674 -280.964552) (xy 310.958212 -280.98565)
			(xy 310.910941 -280.999342) (xy 310.862086 -281.005274) (xy 310.812911 -281.003293) (xy 310.764692 -280.993449)
			(xy 310.718676 -280.975997) (xy 310.676055 -280.95139) (xy 310.637934 -280.920265) (xy 310.605299 -280.883428)
			(xy 310.578996 -280.841832) (xy 310.559705 -280.796556) (xy 310.547928 -280.748772) (xy 310.543968 -280.699718)
			(xy 310.226964 -280.699718) (xy 310.22646 -280.725426) (xy 310.218417 -280.776208) (xy 310.202529 -280.825107)
			(xy 310.179186 -280.870919) (xy 310.148965 -280.912515) (xy 310.112609 -280.948871) (xy 310.071013 -280.979092)
			(xy 310.025201 -281.002435) (xy 309.976302 -281.018323) (xy 309.92552 -281.026366) (xy 309.874104 -281.026366)
			(xy 309.823322 -281.018323) (xy 309.774423 -281.002435) (xy 309.728611 -280.979092) (xy 309.687015 -280.948871)
			(xy 309.650659 -280.912515) (xy 309.620438 -280.870919) (xy 309.597095 -280.825107) (xy 309.581207 -280.776208)
			(xy 309.573164 -280.725426) (xy 309.254486 -280.725426) (xy 309.24677 -280.772902) (xy 309.231186 -280.819583)
			(xy 309.208315 -280.86316) (xy 309.17875 -280.902504) (xy 309.143257 -280.936596) (xy 309.102754 -280.964552)
			(xy 309.058292 -280.98565) (xy 309.011021 -280.999342) (xy 308.962166 -281.005274) (xy 308.912991 -281.003293)
			(xy 308.864772 -280.993449) (xy 308.818756 -280.975997) (xy 308.776135 -280.95139) (xy 308.738014 -280.920265)
			(xy 308.705379 -280.883428) (xy 308.679076 -280.841832) (xy 308.659785 -280.796556) (xy 308.648008 -280.748772)
			(xy 308.644048 -280.699718) (xy 308.327044 -280.699718) (xy 308.32654 -280.725426) (xy 308.318497 -280.776208)
			(xy 308.302609 -280.825107) (xy 308.279266 -280.870919) (xy 308.249045 -280.912515) (xy 308.212689 -280.948871)
			(xy 308.171093 -280.979092) (xy 308.125281 -281.002435) (xy 308.076382 -281.018323) (xy 308.0256 -281.026366)
			(xy 307.974184 -281.026366) (xy 307.923402 -281.018323) (xy 307.874503 -281.002435) (xy 307.828691 -280.979092)
			(xy 307.787095 -280.948871) (xy 307.750739 -280.912515) (xy 307.720518 -280.870919) (xy 307.697175 -280.825107)
			(xy 307.681287 -280.776208) (xy 307.673244 -280.725426) (xy 307.354566 -280.725426) (xy 307.34685 -280.772902)
			(xy 307.331266 -280.819583) (xy 307.308395 -280.86316) (xy 307.27883 -280.902504) (xy 307.243337 -280.936596)
			(xy 307.202834 -280.964552) (xy 307.158372 -280.98565) (xy 307.111101 -280.999342) (xy 307.062246 -281.005274)
			(xy 307.013071 -281.003293) (xy 306.964852 -280.993449) (xy 306.918836 -280.975997) (xy 306.876215 -280.95139)
			(xy 306.838094 -280.920265) (xy 306.805459 -280.883428) (xy 306.779156 -280.841832) (xy 306.759865 -280.796556)
			(xy 306.748088 -280.748772) (xy 306.744128 -280.699718) (xy 306.42687 -280.699718) (xy 306.426366 -280.725426)
			(xy 306.418323 -280.776208) (xy 306.402435 -280.825107) (xy 306.379092 -280.870919) (xy 306.348871 -280.912515)
			(xy 306.312515 -280.948871) (xy 306.270919 -280.979092) (xy 306.225107 -281.002435) (xy 306.176208 -281.018323)
			(xy 306.125426 -281.026366) (xy 306.07401 -281.026366) (xy 306.023228 -281.018323) (xy 305.974329 -281.002435)
			(xy 305.928517 -280.979092) (xy 305.886921 -280.948871) (xy 305.850565 -280.912515) (xy 305.820344 -280.870919)
			(xy 305.797001 -280.825107) (xy 305.781113 -280.776208) (xy 305.77307 -280.725426) (xy 305.454392 -280.725426)
			(xy 305.446676 -280.772902) (xy 305.431092 -280.819583) (xy 305.408221 -280.86316) (xy 305.378656 -280.902504)
			(xy 305.343163 -280.936596) (xy 305.30266 -280.964552) (xy 305.258198 -280.98565) (xy 305.210927 -280.999342)
			(xy 305.162072 -281.005274) (xy 305.112897 -281.003293) (xy 305.064678 -280.993449) (xy 305.018662 -280.975997)
			(xy 304.976041 -280.95139) (xy 304.93792 -280.920265) (xy 304.905285 -280.883428) (xy 304.878982 -280.841832)
			(xy 304.859691 -280.796556) (xy 304.847914 -280.748772) (xy 304.843954 -280.699718) (xy 304.52695 -280.699718)
			(xy 304.526446 -280.725426) (xy 304.518403 -280.776208) (xy 304.502515 -280.825107) (xy 304.479172 -280.870919)
			(xy 304.448951 -280.912515) (xy 304.412595 -280.948871) (xy 304.370999 -280.979092) (xy 304.325187 -281.002435)
			(xy 304.276288 -281.018323) (xy 304.225506 -281.026366) (xy 304.17409 -281.026366) (xy 304.123308 -281.018323)
			(xy 304.074409 -281.002435) (xy 304.028597 -280.979092) (xy 303.987001 -280.948871) (xy 303.950645 -280.912515)
			(xy 303.920424 -280.870919) (xy 303.897081 -280.825107) (xy 303.881193 -280.776208) (xy 303.87315 -280.725426)
			(xy 303.554472 -280.725426) (xy 303.546756 -280.772902) (xy 303.531172 -280.819583) (xy 303.508301 -280.86316)
			(xy 303.478736 -280.902504) (xy 303.443243 -280.936596) (xy 303.40274 -280.964552) (xy 303.358278 -280.98565)
			(xy 303.311007 -280.999342) (xy 303.262152 -281.005274) (xy 303.212977 -281.003293) (xy 303.164758 -280.993449)
			(xy 303.118742 -280.975997) (xy 303.076121 -280.95139) (xy 303.038 -280.920265) (xy 303.005365 -280.883428)
			(xy 302.979062 -280.841832) (xy 302.959771 -280.796556) (xy 302.947994 -280.748772) (xy 302.944034 -280.699718)
			(xy 302.62703 -280.699718) (xy 302.626526 -280.725426) (xy 302.618483 -280.776208) (xy 302.602595 -280.825107)
			(xy 302.579252 -280.870919) (xy 302.549031 -280.912515) (xy 302.512675 -280.948871) (xy 302.471079 -280.979092)
			(xy 302.425267 -281.002435) (xy 302.376368 -281.018323) (xy 302.325586 -281.026366) (xy 302.27417 -281.026366)
			(xy 302.223388 -281.018323) (xy 302.174489 -281.002435) (xy 302.128677 -280.979092) (xy 302.087081 -280.948871)
			(xy 302.050725 -280.912515) (xy 302.020504 -280.870919) (xy 301.997161 -280.825107) (xy 301.981273 -280.776208)
			(xy 301.97323 -280.725426) (xy 301.654552 -280.725426) (xy 301.646836 -280.772902) (xy 301.631252 -280.819583)
			(xy 301.608381 -280.86316) (xy 301.578816 -280.902504) (xy 301.543323 -280.936596) (xy 301.50282 -280.964552)
			(xy 301.458358 -280.98565) (xy 301.411087 -280.999342) (xy 301.362232 -281.005274) (xy 301.313057 -281.003293)
			(xy 301.264838 -280.993449) (xy 301.218822 -280.975997) (xy 301.176201 -280.95139) (xy 301.13808 -280.920265)
			(xy 301.105445 -280.883428) (xy 301.079142 -280.841832) (xy 301.059851 -280.796556) (xy 301.048074 -280.748772)
			(xy 301.044114 -280.699718) (xy 300.726856 -280.699718) (xy 300.726352 -280.725426) (xy 300.718309 -280.776208)
			(xy 300.702421 -280.825107) (xy 300.679078 -280.870919) (xy 300.648857 -280.912515) (xy 300.612501 -280.948871)
			(xy 300.570905 -280.979092) (xy 300.525093 -281.002435) (xy 300.476194 -281.018323) (xy 300.425412 -281.026366)
			(xy 300.373996 -281.026366) (xy 300.323214 -281.018323) (xy 300.274315 -281.002435) (xy 300.228503 -280.979092)
			(xy 300.186907 -280.948871) (xy 300.150551 -280.912515) (xy 300.12033 -280.870919) (xy 300.096987 -280.825107)
			(xy 300.081099 -280.776208) (xy 300.073056 -280.725426) (xy 299.754378 -280.725426) (xy 299.746662 -280.772902)
			(xy 299.731078 -280.819583) (xy 299.708207 -280.86316) (xy 299.678642 -280.902504) (xy 299.643149 -280.936596)
			(xy 299.602646 -280.964552) (xy 299.558184 -280.98565) (xy 299.510913 -280.999342) (xy 299.462058 -281.005274)
			(xy 299.412883 -281.003293) (xy 299.364664 -280.993449) (xy 299.318648 -280.975997) (xy 299.276027 -280.95139)
			(xy 299.237906 -280.920265) (xy 299.205271 -280.883428) (xy 299.178968 -280.841832) (xy 299.159677 -280.796556)
			(xy 299.1479 -280.748772) (xy 299.14394 -280.699718) (xy 298.826936 -280.699718) (xy 298.826432 -280.725426)
			(xy 298.818389 -280.776208) (xy 298.802501 -280.825107) (xy 298.779158 -280.870919) (xy 298.748937 -280.912515)
			(xy 298.712581 -280.948871) (xy 298.670985 -280.979092) (xy 298.625173 -281.002435) (xy 298.576274 -281.018323)
			(xy 298.525492 -281.026366) (xy 298.474076 -281.026366) (xy 298.423294 -281.018323) (xy 298.374395 -281.002435)
			(xy 298.328583 -280.979092) (xy 298.286987 -280.948871) (xy 298.250631 -280.912515) (xy 298.22041 -280.870919)
			(xy 298.197067 -280.825107) (xy 298.181179 -280.776208) (xy 298.173136 -280.725426) (xy 297.854458 -280.725426)
			(xy 297.846742 -280.772902) (xy 297.831158 -280.819583) (xy 297.808287 -280.86316) (xy 297.778722 -280.902504)
			(xy 297.743229 -280.936596) (xy 297.702726 -280.964552) (xy 297.658264 -280.98565) (xy 297.610993 -280.999342)
			(xy 297.562138 -281.005274) (xy 297.512963 -281.003293) (xy 297.464744 -280.993449) (xy 297.418728 -280.975997)
			(xy 297.376107 -280.95139) (xy 297.337986 -280.920265) (xy 297.305351 -280.883428) (xy 297.279048 -280.841832)
			(xy 297.259757 -280.796556) (xy 297.24798 -280.748772) (xy 297.24402 -280.699718) (xy 296.927016 -280.699718)
			(xy 296.926512 -280.725426) (xy 296.918469 -280.776208) (xy 296.902581 -280.825107) (xy 296.879238 -280.870919)
			(xy 296.849017 -280.912515) (xy 296.812661 -280.948871) (xy 296.771065 -280.979092) (xy 296.725253 -281.002435)
			(xy 296.676354 -281.018323) (xy 296.625572 -281.026366) (xy 296.574156 -281.026366) (xy 296.523374 -281.018323)
			(xy 296.474475 -281.002435) (xy 296.428663 -280.979092) (xy 296.387067 -280.948871) (xy 296.350711 -280.912515)
			(xy 296.32049 -280.870919) (xy 296.297147 -280.825107) (xy 296.281259 -280.776208) (xy 296.273216 -280.725426)
			(xy 295.954538 -280.725426) (xy 295.946822 -280.772902) (xy 295.931238 -280.819583) (xy 295.908367 -280.86316)
			(xy 295.878802 -280.902504) (xy 295.843309 -280.936596) (xy 295.802806 -280.964552) (xy 295.758344 -280.98565)
			(xy 295.711073 -280.999342) (xy 295.662218 -281.005274) (xy 295.613043 -281.003293) (xy 295.564824 -280.993449)
			(xy 295.518808 -280.975997) (xy 295.476187 -280.95139) (xy 295.438066 -280.920265) (xy 295.405431 -280.883428)
			(xy 295.379128 -280.841832) (xy 295.359837 -280.796556) (xy 295.34806 -280.748772) (xy 295.3441 -280.699718)
			(xy 295.026842 -280.699718) (xy 295.026338 -280.725426) (xy 295.018295 -280.776208) (xy 295.002407 -280.825107)
			(xy 294.979064 -280.870919) (xy 294.948843 -280.912515) (xy 294.912487 -280.948871) (xy 294.870891 -280.979092)
			(xy 294.825079 -281.002435) (xy 294.77618 -281.018323) (xy 294.725398 -281.026366) (xy 294.673982 -281.026366)
			(xy 294.6232 -281.018323) (xy 294.574301 -281.002435) (xy 294.528489 -280.979092) (xy 294.486893 -280.948871)
			(xy 294.450537 -280.912515) (xy 294.420316 -280.870919) (xy 294.396973 -280.825107) (xy 294.381085 -280.776208)
			(xy 294.373042 -280.725426) (xy 294.054364 -280.725426) (xy 294.046648 -280.772902) (xy 294.031064 -280.819583)
			(xy 294.008193 -280.86316) (xy 293.978628 -280.902504) (xy 293.943135 -280.936596) (xy 293.902632 -280.964552)
			(xy 293.85817 -280.98565) (xy 293.810899 -280.999342) (xy 293.762044 -281.005274) (xy 293.712869 -281.003293)
			(xy 293.66465 -280.993449) (xy 293.618634 -280.975997) (xy 293.576013 -280.95139) (xy 293.537892 -280.920265)
			(xy 293.505257 -280.883428) (xy 293.478954 -280.841832) (xy 293.459663 -280.796556) (xy 293.447886 -280.748772)
			(xy 293.443926 -280.699718) (xy 293.126922 -280.699718) (xy 293.126418 -280.725426) (xy 293.118375 -280.776208)
			(xy 293.102487 -280.825107) (xy 293.079144 -280.870919) (xy 293.048923 -280.912515) (xy 293.012567 -280.948871)
			(xy 292.970971 -280.979092) (xy 292.925159 -281.002435) (xy 292.87626 -281.018323) (xy 292.825478 -281.026366)
			(xy 292.774062 -281.026366) (xy 292.72328 -281.018323) (xy 292.674381 -281.002435) (xy 292.628569 -280.979092)
			(xy 292.586973 -280.948871) (xy 292.550617 -280.912515) (xy 292.520396 -280.870919) (xy 292.497053 -280.825107)
			(xy 292.481165 -280.776208) (xy 292.473122 -280.725426) (xy 292.154444 -280.725426) (xy 292.146728 -280.772902)
			(xy 292.131144 -280.819583) (xy 292.108273 -280.86316) (xy 292.078708 -280.902504) (xy 292.043215 -280.936596)
			(xy 292.002712 -280.964552) (xy 291.95825 -280.98565) (xy 291.910979 -280.999342) (xy 291.862124 -281.005274)
			(xy 291.812949 -281.003293) (xy 291.76473 -280.993449) (xy 291.718714 -280.975997) (xy 291.676093 -280.95139)
			(xy 291.637972 -280.920265) (xy 291.605337 -280.883428) (xy 291.579034 -280.841832) (xy 291.559743 -280.796556)
			(xy 291.547966 -280.748772) (xy 291.544006 -280.699718) (xy 291.227002 -280.699718) (xy 291.226498 -280.725426)
			(xy 291.218455 -280.776208) (xy 291.202567 -280.825107) (xy 291.179224 -280.870919) (xy 291.149003 -280.912515)
			(xy 291.112647 -280.948871) (xy 291.071051 -280.979092) (xy 291.025239 -281.002435) (xy 290.97634 -281.018323)
			(xy 290.925558 -281.026366) (xy 290.874142 -281.026366) (xy 290.82336 -281.018323) (xy 290.774461 -281.002435)
			(xy 290.728649 -280.979092) (xy 290.687053 -280.948871) (xy 290.650697 -280.912515) (xy 290.620476 -280.870919)
			(xy 290.597133 -280.825107) (xy 290.581245 -280.776208) (xy 290.573202 -280.725426) (xy 290.254524 -280.725426)
			(xy 290.246808 -280.772902) (xy 290.231224 -280.819583) (xy 290.208353 -280.86316) (xy 290.178788 -280.902504)
			(xy 290.143295 -280.936596) (xy 290.102792 -280.964552) (xy 290.05833 -280.98565) (xy 290.011059 -280.999342)
			(xy 289.962204 -281.005274) (xy 289.913029 -281.003293) (xy 289.86481 -280.993449) (xy 289.818794 -280.975997)
			(xy 289.776173 -280.95139) (xy 289.738052 -280.920265) (xy 289.705417 -280.883428) (xy 289.679114 -280.841832)
			(xy 289.659823 -280.796556) (xy 289.648046 -280.748772) (xy 289.644086 -280.699718) (xy 289.326828 -280.699718)
			(xy 289.326324 -280.725426) (xy 289.318281 -280.776208) (xy 289.302393 -280.825107) (xy 289.27905 -280.870919)
			(xy 289.248829 -280.912515) (xy 289.212473 -280.948871) (xy 289.170877 -280.979092) (xy 289.125065 -281.002435)
			(xy 289.076166 -281.018323) (xy 289.025384 -281.026366) (xy 288.973968 -281.026366) (xy 288.923186 -281.018323)
			(xy 288.874287 -281.002435) (xy 288.828475 -280.979092) (xy 288.786879 -280.948871) (xy 288.750523 -280.912515)
			(xy 288.720302 -280.870919) (xy 288.696959 -280.825107) (xy 288.681071 -280.776208) (xy 288.673028 -280.725426)
			(xy 288.35435 -280.725426) (xy 288.346634 -280.772902) (xy 288.33105 -280.819583) (xy 288.308179 -280.86316)
			(xy 288.278614 -280.902504) (xy 288.243121 -280.936596) (xy 288.202618 -280.964552) (xy 288.158156 -280.98565)
			(xy 288.110885 -280.999342) (xy 288.06203 -281.005274) (xy 288.012855 -281.003293) (xy 287.964636 -280.993449)
			(xy 287.91862 -280.975997) (xy 287.875999 -280.95139) (xy 287.837878 -280.920265) (xy 287.805243 -280.883428)
			(xy 287.77894 -280.841832) (xy 287.759649 -280.796556) (xy 287.747872 -280.748772) (xy 287.743912 -280.699718)
			(xy 287.426908 -280.699718) (xy 287.426404 -280.725426) (xy 287.418361 -280.776208) (xy 287.402473 -280.825107)
			(xy 287.37913 -280.870919) (xy 287.348909 -280.912515) (xy 287.312553 -280.948871) (xy 287.270957 -280.979092)
			(xy 287.225145 -281.002435) (xy 287.176246 -281.018323) (xy 287.125464 -281.026366) (xy 287.074048 -281.026366)
			(xy 287.023266 -281.018323) (xy 286.974367 -281.002435) (xy 286.928555 -280.979092) (xy 286.886959 -280.948871)
			(xy 286.850603 -280.912515) (xy 286.820382 -280.870919) (xy 286.797039 -280.825107) (xy 286.781151 -280.776208)
			(xy 286.773108 -280.725426) (xy 286.45443 -280.725426) (xy 286.446714 -280.772902) (xy 286.43113 -280.819583)
			(xy 286.408259 -280.86316) (xy 286.378694 -280.902504) (xy 286.343201 -280.936596) (xy 286.302698 -280.964552)
			(xy 286.258236 -280.98565) (xy 286.210965 -280.999342) (xy 286.16211 -281.005274) (xy 286.112935 -281.003293)
			(xy 286.064716 -280.993449) (xy 286.0187 -280.975997) (xy 285.976079 -280.95139) (xy 285.937958 -280.920265)
			(xy 285.905323 -280.883428) (xy 285.87902 -280.841832) (xy 285.859729 -280.796556) (xy 285.847952 -280.748772)
			(xy 285.843992 -280.699718) (xy 285.526988 -280.699718) (xy 285.526484 -280.725426) (xy 285.518441 -280.776208)
			(xy 285.502553 -280.825107) (xy 285.47921 -280.870919) (xy 285.448989 -280.912515) (xy 285.412633 -280.948871)
			(xy 285.371037 -280.979092) (xy 285.325225 -281.002435) (xy 285.276326 -281.018323) (xy 285.225544 -281.026366)
			(xy 285.174128 -281.026366) (xy 285.123346 -281.018323) (xy 285.074447 -281.002435) (xy 285.028635 -280.979092)
			(xy 284.987039 -280.948871) (xy 284.950683 -280.912515) (xy 284.920462 -280.870919) (xy 284.897119 -280.825107)
			(xy 284.881231 -280.776208) (xy 284.873188 -280.725426) (xy 284.55451 -280.725426) (xy 284.546794 -280.772902)
			(xy 284.53121 -280.819583) (xy 284.508339 -280.86316) (xy 284.478774 -280.902504) (xy 284.443281 -280.936596)
			(xy 284.402778 -280.964552) (xy 284.358316 -280.98565) (xy 284.311045 -280.999342) (xy 284.26219 -281.005274)
			(xy 284.213015 -281.003293) (xy 284.164796 -280.993449) (xy 284.11878 -280.975997) (xy 284.076159 -280.95139)
			(xy 284.038038 -280.920265) (xy 284.005403 -280.883428) (xy 283.9791 -280.841832) (xy 283.959809 -280.796556)
			(xy 283.948032 -280.748772) (xy 283.944072 -280.699718) (xy 283.627068 -280.699718) (xy 283.626564 -280.725426)
			(xy 283.618521 -280.776208) (xy 283.602633 -280.825107) (xy 283.57929 -280.870919) (xy 283.549069 -280.912515)
			(xy 283.512713 -280.948871) (xy 283.471117 -280.979092) (xy 283.425305 -281.002435) (xy 283.376406 -281.018323)
			(xy 283.325624 -281.026366) (xy 283.274208 -281.026366) (xy 283.223426 -281.018323) (xy 283.174527 -281.002435)
			(xy 283.128715 -280.979092) (xy 283.087119 -280.948871) (xy 283.050763 -280.912515) (xy 283.020542 -280.870919)
			(xy 282.997199 -280.825107) (xy 282.981311 -280.776208) (xy 282.973268 -280.725426) (xy 282.654336 -280.725426)
			(xy 282.64662 -280.772902) (xy 282.631036 -280.819583) (xy 282.608165 -280.86316) (xy 282.5786 -280.902504)
			(xy 282.543107 -280.936596) (xy 282.502604 -280.964552) (xy 282.458142 -280.98565) (xy 282.410871 -280.999342)
			(xy 282.362016 -281.005274) (xy 282.312841 -281.003293) (xy 282.264622 -280.993449) (xy 282.218606 -280.975997)
			(xy 282.175985 -280.95139) (xy 282.137864 -280.920265) (xy 282.105229 -280.883428) (xy 282.078926 -280.841832)
			(xy 282.059635 -280.796556) (xy 282.047858 -280.748772) (xy 282.043898 -280.699718) (xy 281.726894 -280.699718)
			(xy 281.72639 -280.725426) (xy 281.718347 -280.776208) (xy 281.702459 -280.825107) (xy 281.679116 -280.870919)
			(xy 281.648895 -280.912515) (xy 281.612539 -280.948871) (xy 281.570943 -280.979092) (xy 281.525131 -281.002435)
			(xy 281.476232 -281.018323) (xy 281.42545 -281.026366) (xy 281.374034 -281.026366) (xy 281.323252 -281.018323)
			(xy 281.274353 -281.002435) (xy 281.228541 -280.979092) (xy 281.186945 -280.948871) (xy 281.150589 -280.912515)
			(xy 281.120368 -280.870919) (xy 281.097025 -280.825107) (xy 281.081137 -280.776208) (xy 281.073094 -280.725426)
			(xy 280.754416 -280.725426) (xy 280.7467 -280.772902) (xy 280.731116 -280.819583) (xy 280.708245 -280.86316)
			(xy 280.67868 -280.902504) (xy 280.643187 -280.936596) (xy 280.602684 -280.964552) (xy 280.558222 -280.98565)
			(xy 280.510951 -280.999342) (xy 280.462096 -281.005274) (xy 280.412921 -281.003293) (xy 280.364702 -280.993449)
			(xy 280.318686 -280.975997) (xy 280.276065 -280.95139) (xy 280.237944 -280.920265) (xy 280.205309 -280.883428)
			(xy 280.179006 -280.841832) (xy 280.159715 -280.796556) (xy 280.147938 -280.748772) (xy 280.143978 -280.699718)
			(xy 279.826974 -280.699718) (xy 279.82647 -280.725426) (xy 279.818427 -280.776208) (xy 279.802539 -280.825107)
			(xy 279.779196 -280.870919) (xy 279.748975 -280.912515) (xy 279.712619 -280.948871) (xy 279.671023 -280.979092)
			(xy 279.625211 -281.002435) (xy 279.576312 -281.018323) (xy 279.52553 -281.026366) (xy 279.474114 -281.026366)
			(xy 279.423332 -281.018323) (xy 279.374433 -281.002435) (xy 279.328621 -280.979092) (xy 279.287025 -280.948871)
			(xy 279.250669 -280.912515) (xy 279.220448 -280.870919) (xy 279.197105 -280.825107) (xy 279.181217 -280.776208)
			(xy 279.173174 -280.725426) (xy 278.854496 -280.725426) (xy 278.84678 -280.772902) (xy 278.831196 -280.819583)
			(xy 278.808325 -280.86316) (xy 278.77876 -280.902504) (xy 278.743267 -280.936596) (xy 278.702764 -280.964552)
			(xy 278.658302 -280.98565) (xy 278.611031 -280.999342) (xy 278.562176 -281.005274) (xy 278.513001 -281.003293)
			(xy 278.464782 -280.993449) (xy 278.418766 -280.975997) (xy 278.376145 -280.95139) (xy 278.338024 -280.920265)
			(xy 278.305389 -280.883428) (xy 278.279086 -280.841832) (xy 278.259795 -280.796556) (xy 278.248018 -280.748772)
			(xy 278.244058 -280.699718) (xy 277.927054 -280.699718) (xy 277.92655 -280.725426) (xy 277.918507 -280.776208)
			(xy 277.902619 -280.825107) (xy 277.879276 -280.870919) (xy 277.849055 -280.912515) (xy 277.812699 -280.948871)
			(xy 277.771103 -280.979092) (xy 277.725291 -281.002435) (xy 277.676392 -281.018323) (xy 277.62561 -281.026366)
			(xy 277.574194 -281.026366) (xy 277.523412 -281.018323) (xy 277.474513 -281.002435) (xy 277.428701 -280.979092)
			(xy 277.387105 -280.948871) (xy 277.350749 -280.912515) (xy 277.320528 -280.870919) (xy 277.297185 -280.825107)
			(xy 277.281297 -280.776208) (xy 277.273254 -280.725426) (xy 276.95354 -280.725426) (xy 276.950069 -280.757339)
			(xy 276.936787 -280.805175) (xy 276.91594 -280.850232) (xy 276.888079 -280.891322) (xy 276.853937 -280.927364)
			(xy 276.814413 -280.957407) (xy 276.77055 -280.980661) (xy 276.723503 -280.996511) (xy 276.674511 -281.004541)
			(xy 276.649688 -281.005026) (xy 276.635505 -281.004851) (xy 276.607265 -281.002178) (xy 276.5933 -280.999692)
			(xy 276.580854 -280.997406) (xy 276.556978 -281.004772) (xy 276.479762 -281.081988) (xy 276.472396 -281.106118)
			(xy 276.474682 -281.11831) (xy 276.477166 -281.132339) (xy 276.479838 -281.160706) (xy 276.480016 -281.174952)
			(xy 276.479833 -281.189135) (xy 276.477165 -281.217375) (xy 276.474682 -281.23134) (xy 276.472396 -281.243786)
			(xy 276.479762 -281.267408) (xy 276.557232 -281.344878) (xy 276.580854 -281.352244) (xy 276.5933 -281.349958)
			(xy 276.607267 -281.347486) (xy 276.635506 -281.344811) (xy 276.649688 -281.344624) (xy 276.673682 -281.345049)
			(xy 276.721081 -281.352555) (xy 276.766721 -281.367384) (xy 276.809479 -281.389171) (xy 276.848302 -281.417379)
			(xy 276.882234 -281.451313) (xy 276.91044 -281.490138) (xy 276.932223 -281.532898) (xy 276.947049 -281.578539)
			(xy 276.954552 -281.625938) (xy 276.954996 -281.649932) (xy 276.954824 -281.664115) (xy 276.952149 -281.692355)
			(xy 276.949662 -281.70632) (xy 276.947376 -281.718766) (xy 276.954742 -281.742642) (xy 277.031958 -281.819858)
			(xy 277.056088 -281.827224) (xy 277.06828 -281.824938) (xy 277.08231 -281.822458) (xy 277.110676 -281.819783)
			(xy 277.124922 -281.819604) (xy 277.139105 -281.819777) (xy 277.167345 -281.822452) (xy 277.18131 -281.824938)
			(xy 277.193756 -281.827224) (xy 277.217378 -281.819858) (xy 277.294848 -281.742388) (xy 277.302214 -281.718766)
			(xy 277.299928 -281.70632) (xy 277.297445 -281.692355) (xy 277.294777 -281.664115) (xy 277.294594 -281.649932)
			(xy 277.295116 -281.624677) (xy 277.303429 -281.574855) (xy 277.31983 -281.527081) (xy 277.343871 -281.482658)
			(xy 277.374895 -281.442798) (xy 277.412057 -281.408588) (xy 277.454343 -281.380962) (xy 277.500599 -281.360672)
			(xy 277.549564 -281.348272) (xy 277.599902 -281.344101) (xy 277.65024 -281.348272) (xy 277.699205 -281.360672)
			(xy 277.745461 -281.380962) (xy 277.787747 -281.408588) (xy 277.824909 -281.442798) (xy 277.855933 -281.482658)
			(xy 277.879974 -281.527081) (xy 277.896375 -281.574855) (xy 277.904688 -281.624677) (xy 277.90521 -281.649932)
			(xy 277.905038 -281.664115) (xy 277.902363 -281.692355) (xy 277.899876 -281.70632) (xy 277.89759 -281.718766)
			(xy 277.904956 -281.742388) (xy 277.982426 -281.819858) (xy 278.006048 -281.827224) (xy 278.018494 -281.824938)
			(xy 278.032461 -281.822467) (xy 278.0607 -281.819791) (xy 278.074882 -281.819604) (xy 278.089065 -281.819783)
			(xy 278.117305 -281.822453) (xy 278.13127 -281.824938) (xy 278.143716 -281.827224) (xy 278.167338 -281.819858)
			(xy 278.244808 -281.742388) (xy 278.252174 -281.718766) (xy 278.249888 -281.70632) (xy 278.247404 -281.692355)
			(xy 278.244737 -281.664115) (xy 278.244554 -281.649932) (xy 278.245043 -281.625107) (xy 278.253071 -281.576111)
			(xy 278.26892 -281.52906) (xy 278.292173 -281.485192) (xy 278.322216 -281.445664) (xy 278.358259 -281.411518)
			(xy 278.399352 -281.383653) (xy 278.444411 -281.362804) (xy 278.49225 -281.349519) (xy 278.541608 -281.344149)
			(xy 278.591185 -281.346836) (xy 278.639674 -281.357508) (xy 278.685797 -281.375885) (xy 278.728339 -281.401482)
			(xy 278.76618 -281.433624) (xy 278.798322 -281.471466) (xy 278.823918 -281.514009) (xy 278.842293 -281.560132)
			(xy 278.852965 -281.608621) (xy 278.855202 -281.649932) (xy 279.194018 -281.649932) (xy 279.197978 -281.600878)
			(xy 279.209755 -281.553094) (xy 279.229046 -281.507818) (xy 279.255349 -281.466222) (xy 279.287984 -281.429385)
			(xy 279.326105 -281.39826) (xy 279.368726 -281.373653) (xy 279.414742 -281.356201) (xy 279.462961 -281.346357)
			(xy 279.512136 -281.344376) (xy 279.560991 -281.350308) (xy 279.608262 -281.364) (xy 279.652724 -281.385098)
			(xy 279.693227 -281.413054) (xy 279.72872 -281.447146) (xy 279.758285 -281.48649) (xy 279.781156 -281.530067)
			(xy 279.79674 -281.576748) (xy 279.804635 -281.625325) (xy 279.80513 -281.649932) (xy 280.143978 -281.649932)
			(xy 280.147938 -281.600878) (xy 280.159715 -281.553094) (xy 280.179006 -281.507818) (xy 280.205309 -281.466222)
			(xy 280.237944 -281.429385) (xy 280.276065 -281.39826) (xy 280.318686 -281.373653) (xy 280.364702 -281.356201)
			(xy 280.412921 -281.346357) (xy 280.462096 -281.344376) (xy 280.510951 -281.350308) (xy 280.558222 -281.364)
			(xy 280.602684 -281.385098) (xy 280.643187 -281.413054) (xy 280.67868 -281.447146) (xy 280.708245 -281.48649)
			(xy 280.731116 -281.530067) (xy 280.7467 -281.576748) (xy 280.754595 -281.625325) (xy 280.75509 -281.649932)
			(xy 281.093938 -281.649932) (xy 281.097898 -281.600878) (xy 281.109675 -281.553094) (xy 281.128966 -281.507818)
			(xy 281.155269 -281.466222) (xy 281.187904 -281.429385) (xy 281.226025 -281.39826) (xy 281.268646 -281.373653)
			(xy 281.314662 -281.356201) (xy 281.362881 -281.346357) (xy 281.412056 -281.344376) (xy 281.460911 -281.350308)
			(xy 281.508182 -281.364) (xy 281.552644 -281.385098) (xy 281.593147 -281.413054) (xy 281.62864 -281.447146)
			(xy 281.658205 -281.48649) (xy 281.681076 -281.530067) (xy 281.69666 -281.576748) (xy 281.704555 -281.625325)
			(xy 281.70505 -281.649932) (xy 282.043898 -281.649932) (xy 282.047858 -281.600878) (xy 282.059635 -281.553094)
			(xy 282.078926 -281.507818) (xy 282.105229 -281.466222) (xy 282.137864 -281.429385) (xy 282.175985 -281.39826)
			(xy 282.218606 -281.373653) (xy 282.264622 -281.356201) (xy 282.312841 -281.346357) (xy 282.362016 -281.344376)
			(xy 282.410871 -281.350308) (xy 282.458142 -281.364) (xy 282.502604 -281.385098) (xy 282.543107 -281.413054)
			(xy 282.5786 -281.447146) (xy 282.608165 -281.48649) (xy 282.631036 -281.530067) (xy 282.64662 -281.576748)
			(xy 282.654515 -281.625325) (xy 282.65501 -281.649932) (xy 282.994112 -281.649932) (xy 282.998072 -281.600878)
			(xy 283.009849 -281.553094) (xy 283.02914 -281.507818) (xy 283.055443 -281.466222) (xy 283.088078 -281.429385)
			(xy 283.126199 -281.39826) (xy 283.16882 -281.373653) (xy 283.214836 -281.356201) (xy 283.263055 -281.346357)
			(xy 283.31223 -281.344376) (xy 283.361085 -281.350308) (xy 283.408356 -281.364) (xy 283.452818 -281.385098)
			(xy 283.493321 -281.413054) (xy 283.528814 -281.447146) (xy 283.558379 -281.48649) (xy 283.58125 -281.530067)
			(xy 283.596834 -281.576748) (xy 283.604729 -281.625325) (xy 283.605224 -281.649932) (xy 283.944072 -281.649932)
			(xy 283.948032 -281.600878) (xy 283.959809 -281.553094) (xy 283.9791 -281.507818) (xy 284.005403 -281.466222)
			(xy 284.038038 -281.429385) (xy 284.076159 -281.39826) (xy 284.11878 -281.373653) (xy 284.164796 -281.356201)
			(xy 284.213015 -281.346357) (xy 284.26219 -281.344376) (xy 284.311045 -281.350308) (xy 284.358316 -281.364)
			(xy 284.402778 -281.385098) (xy 284.443281 -281.413054) (xy 284.478774 -281.447146) (xy 284.508339 -281.48649)
			(xy 284.53121 -281.530067) (xy 284.546794 -281.576748) (xy 284.554689 -281.625325) (xy 284.555184 -281.649932)
			(xy 284.894032 -281.649932) (xy 284.897992 -281.600878) (xy 284.909769 -281.553094) (xy 284.92906 -281.507818)
			(xy 284.955363 -281.466222) (xy 284.987998 -281.429385) (xy 285.026119 -281.39826) (xy 285.06874 -281.373653)
			(xy 285.114756 -281.356201) (xy 285.162975 -281.346357) (xy 285.21215 -281.344376) (xy 285.261005 -281.350308)
			(xy 285.308276 -281.364) (xy 285.352738 -281.385098) (xy 285.393241 -281.413054) (xy 285.428734 -281.447146)
			(xy 285.458299 -281.48649) (xy 285.48117 -281.530067) (xy 285.496754 -281.576748) (xy 285.504649 -281.625325)
			(xy 285.505144 -281.649932) (xy 285.843992 -281.649932) (xy 285.847952 -281.600878) (xy 285.859729 -281.553094)
			(xy 285.87902 -281.507818) (xy 285.905323 -281.466222) (xy 285.937958 -281.429385) (xy 285.976079 -281.39826)
			(xy 286.0187 -281.373653) (xy 286.064716 -281.356201) (xy 286.112935 -281.346357) (xy 286.16211 -281.344376)
			(xy 286.210965 -281.350308) (xy 286.258236 -281.364) (xy 286.302698 -281.385098) (xy 286.343201 -281.413054)
			(xy 286.378694 -281.447146) (xy 286.408259 -281.48649) (xy 286.43113 -281.530067) (xy 286.446714 -281.576748)
			(xy 286.454609 -281.625325) (xy 286.455104 -281.649932) (xy 286.793952 -281.649932) (xy 286.797912 -281.600878)
			(xy 286.809689 -281.553094) (xy 286.82898 -281.507818) (xy 286.855283 -281.466222) (xy 286.887918 -281.429385)
			(xy 286.926039 -281.39826) (xy 286.96866 -281.373653) (xy 287.014676 -281.356201) (xy 287.062895 -281.346357)
			(xy 287.11207 -281.344376) (xy 287.160925 -281.350308) (xy 287.208196 -281.364) (xy 287.252658 -281.385098)
			(xy 287.293161 -281.413054) (xy 287.328654 -281.447146) (xy 287.358219 -281.48649) (xy 287.38109 -281.530067)
			(xy 287.396674 -281.576748) (xy 287.404569 -281.625325) (xy 287.405064 -281.649932) (xy 287.743912 -281.649932)
			(xy 287.747872 -281.600878) (xy 287.759649 -281.553094) (xy 287.77894 -281.507818) (xy 287.805243 -281.466222)
			(xy 287.837878 -281.429385) (xy 287.875999 -281.39826) (xy 287.91862 -281.373653) (xy 287.964636 -281.356201)
			(xy 288.012855 -281.346357) (xy 288.06203 -281.344376) (xy 288.110885 -281.350308) (xy 288.158156 -281.364)
			(xy 288.202618 -281.385098) (xy 288.243121 -281.413054) (xy 288.278614 -281.447146) (xy 288.308179 -281.48649)
			(xy 288.33105 -281.530067) (xy 288.346634 -281.576748) (xy 288.354529 -281.625325) (xy 288.355024 -281.649932)
			(xy 288.694126 -281.649932) (xy 288.698086 -281.600878) (xy 288.709863 -281.553094) (xy 288.729154 -281.507818)
			(xy 288.755457 -281.466222) (xy 288.788092 -281.429385) (xy 288.826213 -281.39826) (xy 288.868834 -281.373653)
			(xy 288.91485 -281.356201) (xy 288.963069 -281.346357) (xy 289.012244 -281.344376) (xy 289.061099 -281.350308)
			(xy 289.10837 -281.364) (xy 289.152832 -281.385098) (xy 289.193335 -281.413054) (xy 289.228828 -281.447146)
			(xy 289.258393 -281.48649) (xy 289.281264 -281.530067) (xy 289.296848 -281.576748) (xy 289.304743 -281.625325)
			(xy 289.305238 -281.649932) (xy 289.644086 -281.649932) (xy 289.648046 -281.600878) (xy 289.659823 -281.553094)
			(xy 289.679114 -281.507818) (xy 289.705417 -281.466222) (xy 289.738052 -281.429385) (xy 289.776173 -281.39826)
			(xy 289.818794 -281.373653) (xy 289.86481 -281.356201) (xy 289.913029 -281.346357) (xy 289.962204 -281.344376)
			(xy 290.011059 -281.350308) (xy 290.05833 -281.364) (xy 290.102792 -281.385098) (xy 290.143295 -281.413054)
			(xy 290.178788 -281.447146) (xy 290.208353 -281.48649) (xy 290.231224 -281.530067) (xy 290.246808 -281.576748)
			(xy 290.254703 -281.625325) (xy 290.255198 -281.649932) (xy 290.594046 -281.649932) (xy 290.598006 -281.600878)
			(xy 290.609783 -281.553094) (xy 290.629074 -281.507818) (xy 290.655377 -281.466222) (xy 290.688012 -281.429385)
			(xy 290.726133 -281.39826) (xy 290.768754 -281.373653) (xy 290.81477 -281.356201) (xy 290.862989 -281.346357)
			(xy 290.912164 -281.344376) (xy 290.961019 -281.350308) (xy 291.00829 -281.364) (xy 291.052752 -281.385098)
			(xy 291.093255 -281.413054) (xy 291.128748 -281.447146) (xy 291.158313 -281.48649) (xy 291.181184 -281.530067)
			(xy 291.196768 -281.576748) (xy 291.204663 -281.625325) (xy 291.205158 -281.649932) (xy 291.544006 -281.649932)
			(xy 291.547966 -281.600878) (xy 291.559743 -281.553094) (xy 291.579034 -281.507818) (xy 291.605337 -281.466222)
			(xy 291.637972 -281.429385) (xy 291.676093 -281.39826) (xy 291.718714 -281.373653) (xy 291.76473 -281.356201)
			(xy 291.812949 -281.346357) (xy 291.862124 -281.344376) (xy 291.910979 -281.350308) (xy 291.95825 -281.364)
			(xy 292.002712 -281.385098) (xy 292.043215 -281.413054) (xy 292.078708 -281.447146) (xy 292.108273 -281.48649)
			(xy 292.131144 -281.530067) (xy 292.146728 -281.576748) (xy 292.154623 -281.625325) (xy 292.155118 -281.649932)
			(xy 292.493966 -281.649932) (xy 292.497926 -281.600878) (xy 292.509703 -281.553094) (xy 292.528994 -281.507818)
			(xy 292.555297 -281.466222) (xy 292.587932 -281.429385) (xy 292.626053 -281.39826) (xy 292.668674 -281.373653)
			(xy 292.71469 -281.356201) (xy 292.762909 -281.346357) (xy 292.812084 -281.344376) (xy 292.860939 -281.350308)
			(xy 292.90821 -281.364) (xy 292.952672 -281.385098) (xy 292.993175 -281.413054) (xy 293.028668 -281.447146)
			(xy 293.058233 -281.48649) (xy 293.081104 -281.530067) (xy 293.096688 -281.576748) (xy 293.104583 -281.625325)
			(xy 293.105078 -281.649932) (xy 293.443926 -281.649932) (xy 293.447886 -281.600878) (xy 293.459663 -281.553094)
			(xy 293.478954 -281.507818) (xy 293.505257 -281.466222) (xy 293.537892 -281.429385) (xy 293.576013 -281.39826)
			(xy 293.618634 -281.373653) (xy 293.66465 -281.356201) (xy 293.712869 -281.346357) (xy 293.762044 -281.344376)
			(xy 293.810899 -281.350308) (xy 293.85817 -281.364) (xy 293.902632 -281.385098) (xy 293.943135 -281.413054)
			(xy 293.978628 -281.447146) (xy 294.008193 -281.48649) (xy 294.031064 -281.530067) (xy 294.046648 -281.576748)
			(xy 294.054543 -281.625325) (xy 294.055038 -281.649932) (xy 294.393886 -281.649932) (xy 294.397846 -281.600878)
			(xy 294.409623 -281.553094) (xy 294.428914 -281.507818) (xy 294.455217 -281.466222) (xy 294.487852 -281.429385)
			(xy 294.525973 -281.39826) (xy 294.568594 -281.373653) (xy 294.61461 -281.356201) (xy 294.662829 -281.346357)
			(xy 294.712004 -281.344376) (xy 294.760859 -281.350308) (xy 294.80813 -281.364) (xy 294.852592 -281.385098)
			(xy 294.893095 -281.413054) (xy 294.928588 -281.447146) (xy 294.958153 -281.48649) (xy 294.981024 -281.530067)
			(xy 294.996608 -281.576748) (xy 295.004503 -281.625325) (xy 295.004998 -281.649932) (xy 295.3441 -281.649932)
			(xy 295.34806 -281.600878) (xy 295.359837 -281.553094) (xy 295.379128 -281.507818) (xy 295.405431 -281.466222)
			(xy 295.438066 -281.429385) (xy 295.476187 -281.39826) (xy 295.518808 -281.373653) (xy 295.564824 -281.356201)
			(xy 295.613043 -281.346357) (xy 295.662218 -281.344376) (xy 295.711073 -281.350308) (xy 295.758344 -281.364)
			(xy 295.802806 -281.385098) (xy 295.843309 -281.413054) (xy 295.878802 -281.447146) (xy 295.908367 -281.48649)
			(xy 295.931238 -281.530067) (xy 295.946822 -281.576748) (xy 295.954717 -281.625325) (xy 295.955212 -281.649932)
			(xy 296.29406 -281.649932) (xy 296.29802 -281.600878) (xy 296.309797 -281.553094) (xy 296.329088 -281.507818)
			(xy 296.355391 -281.466222) (xy 296.388026 -281.429385) (xy 296.426147 -281.39826) (xy 296.468768 -281.373653)
			(xy 296.514784 -281.356201) (xy 296.563003 -281.346357) (xy 296.612178 -281.344376) (xy 296.661033 -281.350308)
			(xy 296.708304 -281.364) (xy 296.752766 -281.385098) (xy 296.793269 -281.413054) (xy 296.828762 -281.447146)
			(xy 296.858327 -281.48649) (xy 296.881198 -281.530067) (xy 296.896782 -281.576748) (xy 296.904677 -281.625325)
			(xy 296.905172 -281.649932) (xy 297.24402 -281.649932) (xy 297.24798 -281.600878) (xy 297.259757 -281.553094)
			(xy 297.279048 -281.507818) (xy 297.305351 -281.466222) (xy 297.337986 -281.429385) (xy 297.376107 -281.39826)
			(xy 297.418728 -281.373653) (xy 297.464744 -281.356201) (xy 297.512963 -281.346357) (xy 297.562138 -281.344376)
			(xy 297.610993 -281.350308) (xy 297.658264 -281.364) (xy 297.702726 -281.385098) (xy 297.743229 -281.413054)
			(xy 297.778722 -281.447146) (xy 297.808287 -281.48649) (xy 297.831158 -281.530067) (xy 297.846742 -281.576748)
			(xy 297.854637 -281.625325) (xy 297.855132 -281.649932) (xy 298.19398 -281.649932) (xy 298.19794 -281.600878)
			(xy 298.209717 -281.553094) (xy 298.229008 -281.507818) (xy 298.255311 -281.466222) (xy 298.287946 -281.429385)
			(xy 298.326067 -281.39826) (xy 298.368688 -281.373653) (xy 298.414704 -281.356201) (xy 298.462923 -281.346357)
			(xy 298.512098 -281.344376) (xy 298.560953 -281.350308) (xy 298.608224 -281.364) (xy 298.652686 -281.385098)
			(xy 298.693189 -281.413054) (xy 298.728682 -281.447146) (xy 298.758247 -281.48649) (xy 298.781118 -281.530067)
			(xy 298.796702 -281.576748) (xy 298.804597 -281.625325) (xy 298.805092 -281.649932) (xy 299.14394 -281.649932)
			(xy 299.1479 -281.600878) (xy 299.159677 -281.553094) (xy 299.178968 -281.507818) (xy 299.205271 -281.466222)
			(xy 299.237906 -281.429385) (xy 299.276027 -281.39826) (xy 299.318648 -281.373653) (xy 299.364664 -281.356201)
			(xy 299.412883 -281.346357) (xy 299.462058 -281.344376) (xy 299.510913 -281.350308) (xy 299.558184 -281.364)
			(xy 299.602646 -281.385098) (xy 299.643149 -281.413054) (xy 299.678642 -281.447146) (xy 299.708207 -281.48649)
			(xy 299.731078 -281.530067) (xy 299.746662 -281.576748) (xy 299.754557 -281.625325) (xy 299.755052 -281.649932)
			(xy 300.0939 -281.649932) (xy 300.09786 -281.600878) (xy 300.109637 -281.553094) (xy 300.128928 -281.507818)
			(xy 300.155231 -281.466222) (xy 300.187866 -281.429385) (xy 300.225987 -281.39826) (xy 300.268608 -281.373653)
			(xy 300.314624 -281.356201) (xy 300.362843 -281.346357) (xy 300.412018 -281.344376) (xy 300.460873 -281.350308)
			(xy 300.508144 -281.364) (xy 300.552606 -281.385098) (xy 300.593109 -281.413054) (xy 300.628602 -281.447146)
			(xy 300.658167 -281.48649) (xy 300.681038 -281.530067) (xy 300.696622 -281.576748) (xy 300.704517 -281.625325)
			(xy 300.705012 -281.649932) (xy 301.044114 -281.649932) (xy 301.048074 -281.600878) (xy 301.059851 -281.553094)
			(xy 301.079142 -281.507818) (xy 301.105445 -281.466222) (xy 301.13808 -281.429385) (xy 301.176201 -281.39826)
			(xy 301.218822 -281.373653) (xy 301.264838 -281.356201) (xy 301.313057 -281.346357) (xy 301.362232 -281.344376)
			(xy 301.411087 -281.350308) (xy 301.458358 -281.364) (xy 301.50282 -281.385098) (xy 301.543323 -281.413054)
			(xy 301.578816 -281.447146) (xy 301.608381 -281.48649) (xy 301.631252 -281.530067) (xy 301.646836 -281.576748)
			(xy 301.654731 -281.625325) (xy 301.655226 -281.649932) (xy 301.994074 -281.649932) (xy 301.998034 -281.600878)
			(xy 302.009811 -281.553094) (xy 302.029102 -281.507818) (xy 302.055405 -281.466222) (xy 302.08804 -281.429385)
			(xy 302.126161 -281.39826) (xy 302.168782 -281.373653) (xy 302.214798 -281.356201) (xy 302.263017 -281.346357)
			(xy 302.312192 -281.344376) (xy 302.361047 -281.350308) (xy 302.408318 -281.364) (xy 302.45278 -281.385098)
			(xy 302.493283 -281.413054) (xy 302.528776 -281.447146) (xy 302.558341 -281.48649) (xy 302.581212 -281.530067)
			(xy 302.596796 -281.576748) (xy 302.604691 -281.625325) (xy 302.605186 -281.649932) (xy 302.944034 -281.649932)
			(xy 302.947994 -281.600878) (xy 302.959771 -281.553094) (xy 302.979062 -281.507818) (xy 303.005365 -281.466222)
			(xy 303.038 -281.429385) (xy 303.076121 -281.39826) (xy 303.118742 -281.373653) (xy 303.164758 -281.356201)
			(xy 303.212977 -281.346357) (xy 303.262152 -281.344376) (xy 303.311007 -281.350308) (xy 303.358278 -281.364)
			(xy 303.40274 -281.385098) (xy 303.443243 -281.413054) (xy 303.478736 -281.447146) (xy 303.508301 -281.48649)
			(xy 303.531172 -281.530067) (xy 303.546756 -281.576748) (xy 303.554651 -281.625325) (xy 303.555146 -281.649932)
			(xy 303.893994 -281.649932) (xy 303.897954 -281.600878) (xy 303.909731 -281.553094) (xy 303.929022 -281.507818)
			(xy 303.955325 -281.466222) (xy 303.98796 -281.429385) (xy 304.026081 -281.39826) (xy 304.068702 -281.373653)
			(xy 304.114718 -281.356201) (xy 304.162937 -281.346357) (xy 304.212112 -281.344376) (xy 304.260967 -281.350308)
			(xy 304.308238 -281.364) (xy 304.3527 -281.385098) (xy 304.393203 -281.413054) (xy 304.428696 -281.447146)
			(xy 304.458261 -281.48649) (xy 304.481132 -281.530067) (xy 304.496716 -281.576748) (xy 304.504611 -281.625325)
			(xy 304.505106 -281.649932) (xy 304.843954 -281.649932) (xy 304.847914 -281.600878) (xy 304.859691 -281.553094)
			(xy 304.878982 -281.507818) (xy 304.905285 -281.466222) (xy 304.93792 -281.429385) (xy 304.976041 -281.39826)
			(xy 305.018662 -281.373653) (xy 305.064678 -281.356201) (xy 305.112897 -281.346357) (xy 305.162072 -281.344376)
			(xy 305.210927 -281.350308) (xy 305.258198 -281.364) (xy 305.30266 -281.385098) (xy 305.343163 -281.413054)
			(xy 305.378656 -281.447146) (xy 305.408221 -281.48649) (xy 305.431092 -281.530067) (xy 305.446676 -281.576748)
			(xy 305.454571 -281.625325) (xy 305.455066 -281.649932) (xy 305.793914 -281.649932) (xy 305.797874 -281.600878)
			(xy 305.809651 -281.553094) (xy 305.828942 -281.507818) (xy 305.855245 -281.466222) (xy 305.88788 -281.429385)
			(xy 305.926001 -281.39826) (xy 305.968622 -281.373653) (xy 306.014638 -281.356201) (xy 306.062857 -281.346357)
			(xy 306.112032 -281.344376) (xy 306.160887 -281.350308) (xy 306.208158 -281.364) (xy 306.25262 -281.385098)
			(xy 306.293123 -281.413054) (xy 306.328616 -281.447146) (xy 306.358181 -281.48649) (xy 306.381052 -281.530067)
			(xy 306.396636 -281.576748) (xy 306.404531 -281.625325) (xy 306.405026 -281.649932) (xy 306.744128 -281.649932)
			(xy 306.748088 -281.600878) (xy 306.759865 -281.553094) (xy 306.779156 -281.507818) (xy 306.805459 -281.466222)
			(xy 306.838094 -281.429385) (xy 306.876215 -281.39826) (xy 306.918836 -281.373653) (xy 306.964852 -281.356201)
			(xy 307.013071 -281.346357) (xy 307.062246 -281.344376) (xy 307.111101 -281.350308) (xy 307.158372 -281.364)
			(xy 307.202834 -281.385098) (xy 307.243337 -281.413054) (xy 307.27883 -281.447146) (xy 307.308395 -281.48649)
			(xy 307.331266 -281.530067) (xy 307.34685 -281.576748) (xy 307.354745 -281.625325) (xy 307.35524 -281.649932)
			(xy 307.694088 -281.649932) (xy 307.698048 -281.600878) (xy 307.709825 -281.553094) (xy 307.729116 -281.507818)
			(xy 307.755419 -281.466222) (xy 307.788054 -281.429385) (xy 307.826175 -281.39826) (xy 307.868796 -281.373653)
			(xy 307.914812 -281.356201) (xy 307.963031 -281.346357) (xy 308.012206 -281.344376) (xy 308.061061 -281.350308)
			(xy 308.108332 -281.364) (xy 308.152794 -281.385098) (xy 308.193297 -281.413054) (xy 308.22879 -281.447146)
			(xy 308.258355 -281.48649) (xy 308.281226 -281.530067) (xy 308.29681 -281.576748) (xy 308.304705 -281.625325)
			(xy 308.3052 -281.649932) (xy 308.644048 -281.649932) (xy 308.648008 -281.600878) (xy 308.659785 -281.553094)
			(xy 308.679076 -281.507818) (xy 308.705379 -281.466222) (xy 308.738014 -281.429385) (xy 308.776135 -281.39826)
			(xy 308.818756 -281.373653) (xy 308.864772 -281.356201) (xy 308.912991 -281.346357) (xy 308.962166 -281.344376)
			(xy 309.011021 -281.350308) (xy 309.058292 -281.364) (xy 309.102754 -281.385098) (xy 309.143257 -281.413054)
			(xy 309.17875 -281.447146) (xy 309.208315 -281.48649) (xy 309.231186 -281.530067) (xy 309.24677 -281.576748)
			(xy 309.254665 -281.625325) (xy 309.255155 -281.649678) (xy 309.593754 -281.649678) (xy 309.597714 -281.600624)
			(xy 309.609491 -281.55284) (xy 309.628782 -281.507564) (xy 309.655085 -281.465968) (xy 309.68772 -281.429131)
			(xy 309.725841 -281.398006) (xy 309.768462 -281.373399) (xy 309.814478 -281.355947) (xy 309.862697 -281.346103)
			(xy 309.911872 -281.344122) (xy 309.960727 -281.350054) (xy 310.007998 -281.363746) (xy 310.05246 -281.384844)
			(xy 310.092963 -281.4128) (xy 310.128456 -281.446892) (xy 310.158021 -281.486236) (xy 310.180892 -281.529813)
			(xy 310.196476 -281.576494) (xy 310.204371 -281.625071) (xy 310.204866 -281.649678) (xy 310.204861 -281.649932)
			(xy 310.543714 -281.649932) (xy 310.547674 -281.600878) (xy 310.559451 -281.553094) (xy 310.578742 -281.507818)
			(xy 310.605045 -281.466222) (xy 310.63768 -281.429385) (xy 310.675801 -281.39826) (xy 310.718422 -281.373653)
			(xy 310.764438 -281.356201) (xy 310.812657 -281.346357) (xy 310.861832 -281.344376) (xy 310.910687 -281.350308)
			(xy 310.957958 -281.364) (xy 311.00242 -281.385098) (xy 311.042923 -281.413054) (xy 311.078416 -281.447146)
			(xy 311.107981 -281.48649) (xy 311.130852 -281.530067) (xy 311.146436 -281.576748) (xy 311.154331 -281.625325)
			(xy 311.154826 -281.649932) (xy 311.493928 -281.649932) (xy 311.497888 -281.600878) (xy 311.509665 -281.553094)
			(xy 311.528956 -281.507818) (xy 311.555259 -281.466222) (xy 311.587894 -281.429385) (xy 311.626015 -281.39826)
			(xy 311.668636 -281.373653) (xy 311.714652 -281.356201) (xy 311.762871 -281.346357) (xy 311.812046 -281.344376)
			(xy 311.860901 -281.350308) (xy 311.908172 -281.364) (xy 311.952634 -281.385098) (xy 311.993137 -281.413054)
			(xy 312.02863 -281.447146) (xy 312.058195 -281.48649) (xy 312.081066 -281.530067) (xy 312.09665 -281.576748)
			(xy 312.104545 -281.625325) (xy 312.10504 -281.649932) (xy 312.443888 -281.649932) (xy 312.447848 -281.600878)
			(xy 312.459625 -281.553094) (xy 312.478916 -281.507818) (xy 312.505219 -281.466222) (xy 312.537854 -281.429385)
			(xy 312.575975 -281.39826) (xy 312.618596 -281.373653) (xy 312.664612 -281.356201) (xy 312.712831 -281.346357)
			(xy 312.762006 -281.344376) (xy 312.810861 -281.350308) (xy 312.858132 -281.364) (xy 312.902594 -281.385098)
			(xy 312.943097 -281.413054) (xy 312.97859 -281.447146) (xy 313.008155 -281.48649) (xy 313.031026 -281.530067)
			(xy 313.04661 -281.576748) (xy 313.054505 -281.625325) (xy 313.055 -281.649932) (xy 313.054505 -281.674539)
			(xy 313.054326 -281.67564) (xy 313.373258 -281.67564) (xy 313.373258 -281.624224) (xy 313.381301 -281.573442)
			(xy 313.397189 -281.524543) (xy 313.420532 -281.478731) (xy 313.450753 -281.437135) (xy 313.487109 -281.400779)
			(xy 313.528705 -281.370558) (xy 313.574517 -281.347215) (xy 313.623416 -281.331327) (xy 313.674198 -281.323284)
			(xy 313.725614 -281.323284) (xy 313.776396 -281.331327) (xy 313.825295 -281.347215) (xy 313.871107 -281.370558)
			(xy 313.912703 -281.400779) (xy 313.949059 -281.437135) (xy 313.97928 -281.478731) (xy 314.002623 -281.524543)
			(xy 314.018511 -281.573442) (xy 314.026554 -281.624224) (xy 314.027058 -281.649932) (xy 314.026554 -281.67564)
			(xy 314.323218 -281.67564) (xy 314.323218 -281.624224) (xy 314.331261 -281.573442) (xy 314.347149 -281.524543)
			(xy 314.370492 -281.478731) (xy 314.400713 -281.437135) (xy 314.437069 -281.400779) (xy 314.478665 -281.370558)
			(xy 314.524477 -281.347215) (xy 314.573376 -281.331327) (xy 314.624158 -281.323284) (xy 314.675574 -281.323284)
			(xy 314.726356 -281.331327) (xy 314.775255 -281.347215) (xy 314.821067 -281.370558) (xy 314.862663 -281.400779)
			(xy 314.899019 -281.437135) (xy 314.92924 -281.478731) (xy 314.952583 -281.524543) (xy 314.968471 -281.573442)
			(xy 314.976514 -281.624224) (xy 314.977018 -281.649932) (xy 314.977013 -281.650186) (xy 315.294276 -281.650186)
			(xy 315.298236 -281.601132) (xy 315.310013 -281.553348) (xy 315.329304 -281.508072) (xy 315.355607 -281.466476)
			(xy 315.388242 -281.429639) (xy 315.426363 -281.398514) (xy 315.468984 -281.373907) (xy 315.515 -281.356455)
			(xy 315.563219 -281.346611) (xy 315.612394 -281.34463) (xy 315.661249 -281.350562) (xy 315.70852 -281.364254)
			(xy 315.752982 -281.385352) (xy 315.793485 -281.413308) (xy 315.828978 -281.4474) (xy 315.858543 -281.486744)
			(xy 315.881414 -281.530321) (xy 315.896998 -281.577002) (xy 315.904893 -281.625579) (xy 315.905388 -281.650186)
			(xy 315.904893 -281.674793) (xy 315.896998 -281.72337) (xy 315.881414 -281.770051) (xy 315.858543 -281.813628)
			(xy 315.828978 -281.852972) (xy 315.793485 -281.887064) (xy 315.752982 -281.91502) (xy 315.70852 -281.936118)
			(xy 315.661249 -281.94981) (xy 315.612394 -281.955742) (xy 315.563219 -281.953761) (xy 315.515 -281.943917)
			(xy 315.468984 -281.926465) (xy 315.426363 -281.901858) (xy 315.388242 -281.870733) (xy 315.355607 -281.833896)
			(xy 315.329304 -281.7923) (xy 315.310013 -281.747024) (xy 315.298236 -281.69924) (xy 315.294276 -281.650186)
			(xy 314.977013 -281.650186) (xy 314.976514 -281.67564) (xy 314.968471 -281.726422) (xy 314.952583 -281.775321)
			(xy 314.92924 -281.821133) (xy 314.899019 -281.862729) (xy 314.862663 -281.899085) (xy 314.821067 -281.929306)
			(xy 314.775255 -281.952649) (xy 314.726356 -281.968537) (xy 314.675574 -281.97658) (xy 314.624158 -281.97658)
			(xy 314.573376 -281.968537) (xy 314.524477 -281.952649) (xy 314.478665 -281.929306) (xy 314.437069 -281.899085)
			(xy 314.400713 -281.862729) (xy 314.370492 -281.821133) (xy 314.347149 -281.775321) (xy 314.331261 -281.726422)
			(xy 314.323218 -281.67564) (xy 314.026554 -281.67564) (xy 314.018511 -281.726422) (xy 314.002623 -281.775321)
			(xy 313.97928 -281.821133) (xy 313.949059 -281.862729) (xy 313.912703 -281.899085) (xy 313.871107 -281.929306)
			(xy 313.825295 -281.952649) (xy 313.776396 -281.968537) (xy 313.725614 -281.97658) (xy 313.674198 -281.97658)
			(xy 313.623416 -281.968537) (xy 313.574517 -281.952649) (xy 313.528705 -281.929306) (xy 313.487109 -281.899085)
			(xy 313.450753 -281.862729) (xy 313.420532 -281.821133) (xy 313.397189 -281.775321) (xy 313.381301 -281.726422)
			(xy 313.373258 -281.67564) (xy 313.054326 -281.67564) (xy 313.04661 -281.723116) (xy 313.031026 -281.769797)
			(xy 313.008155 -281.813374) (xy 312.97859 -281.852718) (xy 312.943097 -281.88681) (xy 312.902594 -281.914766)
			(xy 312.858132 -281.935864) (xy 312.810861 -281.949556) (xy 312.762006 -281.955488) (xy 312.712831 -281.953507)
			(xy 312.664612 -281.943663) (xy 312.618596 -281.926211) (xy 312.575975 -281.901604) (xy 312.537854 -281.870479)
			(xy 312.505219 -281.833642) (xy 312.478916 -281.792046) (xy 312.459625 -281.74677) (xy 312.447848 -281.698986)
			(xy 312.443888 -281.649932) (xy 312.10504 -281.649932) (xy 312.104545 -281.674539) (xy 312.09665 -281.723116)
			(xy 312.081066 -281.769797) (xy 312.058195 -281.813374) (xy 312.02863 -281.852718) (xy 311.993137 -281.88681)
			(xy 311.952634 -281.914766) (xy 311.908172 -281.935864) (xy 311.860901 -281.949556) (xy 311.812046 -281.955488)
			(xy 311.762871 -281.953507) (xy 311.714652 -281.943663) (xy 311.668636 -281.926211) (xy 311.626015 -281.901604)
			(xy 311.587894 -281.870479) (xy 311.555259 -281.833642) (xy 311.528956 -281.792046) (xy 311.509665 -281.74677)
			(xy 311.497888 -281.698986) (xy 311.493928 -281.649932) (xy 311.154826 -281.649932) (xy 311.154331 -281.674539)
			(xy 311.146436 -281.723116) (xy 311.130852 -281.769797) (xy 311.107981 -281.813374) (xy 311.078416 -281.852718)
			(xy 311.042923 -281.88681) (xy 311.00242 -281.914766) (xy 310.957958 -281.935864) (xy 310.910687 -281.949556)
			(xy 310.861832 -281.955488) (xy 310.812657 -281.953507) (xy 310.764438 -281.943663) (xy 310.718422 -281.926211)
			(xy 310.675801 -281.901604) (xy 310.63768 -281.870479) (xy 310.605045 -281.833642) (xy 310.578742 -281.792046)
			(xy 310.559451 -281.74677) (xy 310.547674 -281.698986) (xy 310.543714 -281.649932) (xy 310.204861 -281.649932)
			(xy 310.204371 -281.674285) (xy 310.196476 -281.722862) (xy 310.180892 -281.769543) (xy 310.158021 -281.81312)
			(xy 310.128456 -281.852464) (xy 310.092963 -281.886556) (xy 310.05246 -281.914512) (xy 310.007998 -281.93561)
			(xy 309.960727 -281.949302) (xy 309.911872 -281.955234) (xy 309.862697 -281.953253) (xy 309.814478 -281.943409)
			(xy 309.768462 -281.925957) (xy 309.725841 -281.90135) (xy 309.68772 -281.870225) (xy 309.655085 -281.833388)
			(xy 309.628782 -281.791792) (xy 309.609491 -281.746516) (xy 309.597714 -281.698732) (xy 309.593754 -281.649678)
			(xy 309.255155 -281.649678) (xy 309.25516 -281.649932) (xy 309.254665 -281.674539) (xy 309.24677 -281.723116)
			(xy 309.231186 -281.769797) (xy 309.208315 -281.813374) (xy 309.17875 -281.852718) (xy 309.143257 -281.88681)
			(xy 309.102754 -281.914766) (xy 309.058292 -281.935864) (xy 309.011021 -281.949556) (xy 308.962166 -281.955488)
			(xy 308.912991 -281.953507) (xy 308.864772 -281.943663) (xy 308.818756 -281.926211) (xy 308.776135 -281.901604)
			(xy 308.738014 -281.870479) (xy 308.705379 -281.833642) (xy 308.679076 -281.792046) (xy 308.659785 -281.74677)
			(xy 308.648008 -281.698986) (xy 308.644048 -281.649932) (xy 308.3052 -281.649932) (xy 308.304705 -281.674539)
			(xy 308.29681 -281.723116) (xy 308.281226 -281.769797) (xy 308.258355 -281.813374) (xy 308.22879 -281.852718)
			(xy 308.193297 -281.88681) (xy 308.152794 -281.914766) (xy 308.108332 -281.935864) (xy 308.061061 -281.949556)
			(xy 308.012206 -281.955488) (xy 307.963031 -281.953507) (xy 307.914812 -281.943663) (xy 307.868796 -281.926211)
			(xy 307.826175 -281.901604) (xy 307.788054 -281.870479) (xy 307.755419 -281.833642) (xy 307.729116 -281.792046)
			(xy 307.709825 -281.74677) (xy 307.698048 -281.698986) (xy 307.694088 -281.649932) (xy 307.35524 -281.649932)
			(xy 307.354745 -281.674539) (xy 307.34685 -281.723116) (xy 307.331266 -281.769797) (xy 307.308395 -281.813374)
			(xy 307.27883 -281.852718) (xy 307.243337 -281.88681) (xy 307.202834 -281.914766) (xy 307.158372 -281.935864)
			(xy 307.111101 -281.949556) (xy 307.062246 -281.955488) (xy 307.013071 -281.953507) (xy 306.964852 -281.943663)
			(xy 306.918836 -281.926211) (xy 306.876215 -281.901604) (xy 306.838094 -281.870479) (xy 306.805459 -281.833642)
			(xy 306.779156 -281.792046) (xy 306.759865 -281.74677) (xy 306.748088 -281.698986) (xy 306.744128 -281.649932)
			(xy 306.405026 -281.649932) (xy 306.404531 -281.674539) (xy 306.396636 -281.723116) (xy 306.381052 -281.769797)
			(xy 306.358181 -281.813374) (xy 306.328616 -281.852718) (xy 306.293123 -281.88681) (xy 306.25262 -281.914766)
			(xy 306.208158 -281.935864) (xy 306.160887 -281.949556) (xy 306.112032 -281.955488) (xy 306.062857 -281.953507)
			(xy 306.014638 -281.943663) (xy 305.968622 -281.926211) (xy 305.926001 -281.901604) (xy 305.88788 -281.870479)
			(xy 305.855245 -281.833642) (xy 305.828942 -281.792046) (xy 305.809651 -281.74677) (xy 305.797874 -281.698986)
			(xy 305.793914 -281.649932) (xy 305.455066 -281.649932) (xy 305.454571 -281.674539) (xy 305.446676 -281.723116)
			(xy 305.431092 -281.769797) (xy 305.408221 -281.813374) (xy 305.378656 -281.852718) (xy 305.343163 -281.88681)
			(xy 305.30266 -281.914766) (xy 305.258198 -281.935864) (xy 305.210927 -281.949556) (xy 305.162072 -281.955488)
			(xy 305.112897 -281.953507) (xy 305.064678 -281.943663) (xy 305.018662 -281.926211) (xy 304.976041 -281.901604)
			(xy 304.93792 -281.870479) (xy 304.905285 -281.833642) (xy 304.878982 -281.792046) (xy 304.859691 -281.74677)
			(xy 304.847914 -281.698986) (xy 304.843954 -281.649932) (xy 304.505106 -281.649932) (xy 304.504611 -281.674539)
			(xy 304.496716 -281.723116) (xy 304.481132 -281.769797) (xy 304.458261 -281.813374) (xy 304.428696 -281.852718)
			(xy 304.393203 -281.88681) (xy 304.3527 -281.914766) (xy 304.308238 -281.935864) (xy 304.260967 -281.949556)
			(xy 304.212112 -281.955488) (xy 304.162937 -281.953507) (xy 304.114718 -281.943663) (xy 304.068702 -281.926211)
			(xy 304.026081 -281.901604) (xy 303.98796 -281.870479) (xy 303.955325 -281.833642) (xy 303.929022 -281.792046)
			(xy 303.909731 -281.74677) (xy 303.897954 -281.698986) (xy 303.893994 -281.649932) (xy 303.555146 -281.649932)
			(xy 303.554651 -281.674539) (xy 303.546756 -281.723116) (xy 303.531172 -281.769797) (xy 303.508301 -281.813374)
			(xy 303.478736 -281.852718) (xy 303.443243 -281.88681) (xy 303.40274 -281.914766) (xy 303.358278 -281.935864)
			(xy 303.311007 -281.949556) (xy 303.262152 -281.955488) (xy 303.212977 -281.953507) (xy 303.164758 -281.943663)
			(xy 303.118742 -281.926211) (xy 303.076121 -281.901604) (xy 303.038 -281.870479) (xy 303.005365 -281.833642)
			(xy 302.979062 -281.792046) (xy 302.959771 -281.74677) (xy 302.947994 -281.698986) (xy 302.944034 -281.649932)
			(xy 302.605186 -281.649932) (xy 302.604691 -281.674539) (xy 302.596796 -281.723116) (xy 302.581212 -281.769797)
			(xy 302.558341 -281.813374) (xy 302.528776 -281.852718) (xy 302.493283 -281.88681) (xy 302.45278 -281.914766)
			(xy 302.408318 -281.935864) (xy 302.361047 -281.949556) (xy 302.312192 -281.955488) (xy 302.263017 -281.953507)
			(xy 302.214798 -281.943663) (xy 302.168782 -281.926211) (xy 302.126161 -281.901604) (xy 302.08804 -281.870479)
			(xy 302.055405 -281.833642) (xy 302.029102 -281.792046) (xy 302.009811 -281.74677) (xy 301.998034 -281.698986)
			(xy 301.994074 -281.649932) (xy 301.655226 -281.649932) (xy 301.654731 -281.674539) (xy 301.646836 -281.723116)
			(xy 301.631252 -281.769797) (xy 301.608381 -281.813374) (xy 301.578816 -281.852718) (xy 301.543323 -281.88681)
			(xy 301.50282 -281.914766) (xy 301.458358 -281.935864) (xy 301.411087 -281.949556) (xy 301.362232 -281.955488)
			(xy 301.313057 -281.953507) (xy 301.264838 -281.943663) (xy 301.218822 -281.926211) (xy 301.176201 -281.901604)
			(xy 301.13808 -281.870479) (xy 301.105445 -281.833642) (xy 301.079142 -281.792046) (xy 301.059851 -281.74677)
			(xy 301.048074 -281.698986) (xy 301.044114 -281.649932) (xy 300.705012 -281.649932) (xy 300.704517 -281.674539)
			(xy 300.696622 -281.723116) (xy 300.681038 -281.769797) (xy 300.658167 -281.813374) (xy 300.628602 -281.852718)
			(xy 300.593109 -281.88681) (xy 300.552606 -281.914766) (xy 300.508144 -281.935864) (xy 300.460873 -281.949556)
			(xy 300.412018 -281.955488) (xy 300.362843 -281.953507) (xy 300.314624 -281.943663) (xy 300.268608 -281.926211)
			(xy 300.225987 -281.901604) (xy 300.187866 -281.870479) (xy 300.155231 -281.833642) (xy 300.128928 -281.792046)
			(xy 300.109637 -281.74677) (xy 300.09786 -281.698986) (xy 300.0939 -281.649932) (xy 299.755052 -281.649932)
			(xy 299.754557 -281.674539) (xy 299.746662 -281.723116) (xy 299.731078 -281.769797) (xy 299.708207 -281.813374)
			(xy 299.678642 -281.852718) (xy 299.643149 -281.88681) (xy 299.602646 -281.914766) (xy 299.558184 -281.935864)
			(xy 299.510913 -281.949556) (xy 299.462058 -281.955488) (xy 299.412883 -281.953507) (xy 299.364664 -281.943663)
			(xy 299.318648 -281.926211) (xy 299.276027 -281.901604) (xy 299.237906 -281.870479) (xy 299.205271 -281.833642)
			(xy 299.178968 -281.792046) (xy 299.159677 -281.74677) (xy 299.1479 -281.698986) (xy 299.14394 -281.649932)
			(xy 298.805092 -281.649932) (xy 298.804597 -281.674539) (xy 298.796702 -281.723116) (xy 298.781118 -281.769797)
			(xy 298.758247 -281.813374) (xy 298.728682 -281.852718) (xy 298.693189 -281.88681) (xy 298.652686 -281.914766)
			(xy 298.608224 -281.935864) (xy 298.560953 -281.949556) (xy 298.512098 -281.955488) (xy 298.462923 -281.953507)
			(xy 298.414704 -281.943663) (xy 298.368688 -281.926211) (xy 298.326067 -281.901604) (xy 298.287946 -281.870479)
			(xy 298.255311 -281.833642) (xy 298.229008 -281.792046) (xy 298.209717 -281.74677) (xy 298.19794 -281.698986)
			(xy 298.19398 -281.649932) (xy 297.855132 -281.649932) (xy 297.854637 -281.674539) (xy 297.846742 -281.723116)
			(xy 297.831158 -281.769797) (xy 297.808287 -281.813374) (xy 297.778722 -281.852718) (xy 297.743229 -281.88681)
			(xy 297.702726 -281.914766) (xy 297.658264 -281.935864) (xy 297.610993 -281.949556) (xy 297.562138 -281.955488)
			(xy 297.512963 -281.953507) (xy 297.464744 -281.943663) (xy 297.418728 -281.926211) (xy 297.376107 -281.901604)
			(xy 297.337986 -281.870479) (xy 297.305351 -281.833642) (xy 297.279048 -281.792046) (xy 297.259757 -281.74677)
			(xy 297.24798 -281.698986) (xy 297.24402 -281.649932) (xy 296.905172 -281.649932) (xy 296.904677 -281.674539)
			(xy 296.896782 -281.723116) (xy 296.881198 -281.769797) (xy 296.858327 -281.813374) (xy 296.828762 -281.852718)
			(xy 296.793269 -281.88681) (xy 296.752766 -281.914766) (xy 296.708304 -281.935864) (xy 296.661033 -281.949556)
			(xy 296.612178 -281.955488) (xy 296.563003 -281.953507) (xy 296.514784 -281.943663) (xy 296.468768 -281.926211)
			(xy 296.426147 -281.901604) (xy 296.388026 -281.870479) (xy 296.355391 -281.833642) (xy 296.329088 -281.792046)
			(xy 296.309797 -281.74677) (xy 296.29802 -281.698986) (xy 296.29406 -281.649932) (xy 295.955212 -281.649932)
			(xy 295.954717 -281.674539) (xy 295.946822 -281.723116) (xy 295.931238 -281.769797) (xy 295.908367 -281.813374)
			(xy 295.878802 -281.852718) (xy 295.843309 -281.88681) (xy 295.802806 -281.914766) (xy 295.758344 -281.935864)
			(xy 295.711073 -281.949556) (xy 295.662218 -281.955488) (xy 295.613043 -281.953507) (xy 295.564824 -281.943663)
			(xy 295.518808 -281.926211) (xy 295.476187 -281.901604) (xy 295.438066 -281.870479) (xy 295.405431 -281.833642)
			(xy 295.379128 -281.792046) (xy 295.359837 -281.74677) (xy 295.34806 -281.698986) (xy 295.3441 -281.649932)
			(xy 295.004998 -281.649932) (xy 295.004503 -281.674539) (xy 294.996608 -281.723116) (xy 294.981024 -281.769797)
			(xy 294.958153 -281.813374) (xy 294.928588 -281.852718) (xy 294.893095 -281.88681) (xy 294.852592 -281.914766)
			(xy 294.80813 -281.935864) (xy 294.760859 -281.949556) (xy 294.712004 -281.955488) (xy 294.662829 -281.953507)
			(xy 294.61461 -281.943663) (xy 294.568594 -281.926211) (xy 294.525973 -281.901604) (xy 294.487852 -281.870479)
			(xy 294.455217 -281.833642) (xy 294.428914 -281.792046) (xy 294.409623 -281.74677) (xy 294.397846 -281.698986)
			(xy 294.393886 -281.649932) (xy 294.055038 -281.649932) (xy 294.054543 -281.674539) (xy 294.046648 -281.723116)
			(xy 294.031064 -281.769797) (xy 294.008193 -281.813374) (xy 293.978628 -281.852718) (xy 293.943135 -281.88681)
			(xy 293.902632 -281.914766) (xy 293.85817 -281.935864) (xy 293.810899 -281.949556) (xy 293.762044 -281.955488)
			(xy 293.712869 -281.953507) (xy 293.66465 -281.943663) (xy 293.618634 -281.926211) (xy 293.576013 -281.901604)
			(xy 293.537892 -281.870479) (xy 293.505257 -281.833642) (xy 293.478954 -281.792046) (xy 293.459663 -281.74677)
			(xy 293.447886 -281.698986) (xy 293.443926 -281.649932) (xy 293.105078 -281.649932) (xy 293.104583 -281.674539)
			(xy 293.096688 -281.723116) (xy 293.081104 -281.769797) (xy 293.058233 -281.813374) (xy 293.028668 -281.852718)
			(xy 292.993175 -281.88681) (xy 292.952672 -281.914766) (xy 292.90821 -281.935864) (xy 292.860939 -281.949556)
			(xy 292.812084 -281.955488) (xy 292.762909 -281.953507) (xy 292.71469 -281.943663) (xy 292.668674 -281.926211)
			(xy 292.626053 -281.901604) (xy 292.587932 -281.870479) (xy 292.555297 -281.833642) (xy 292.528994 -281.792046)
			(xy 292.509703 -281.74677) (xy 292.497926 -281.698986) (xy 292.493966 -281.649932) (xy 292.155118 -281.649932)
			(xy 292.154623 -281.674539) (xy 292.146728 -281.723116) (xy 292.131144 -281.769797) (xy 292.108273 -281.813374)
			(xy 292.078708 -281.852718) (xy 292.043215 -281.88681) (xy 292.002712 -281.914766) (xy 291.95825 -281.935864)
			(xy 291.910979 -281.949556) (xy 291.862124 -281.955488) (xy 291.812949 -281.953507) (xy 291.76473 -281.943663)
			(xy 291.718714 -281.926211) (xy 291.676093 -281.901604) (xy 291.637972 -281.870479) (xy 291.605337 -281.833642)
			(xy 291.579034 -281.792046) (xy 291.559743 -281.74677) (xy 291.547966 -281.698986) (xy 291.544006 -281.649932)
			(xy 291.205158 -281.649932) (xy 291.204663 -281.674539) (xy 291.196768 -281.723116) (xy 291.181184 -281.769797)
			(xy 291.158313 -281.813374) (xy 291.128748 -281.852718) (xy 291.093255 -281.88681) (xy 291.052752 -281.914766)
			(xy 291.00829 -281.935864) (xy 290.961019 -281.949556) (xy 290.912164 -281.955488) (xy 290.862989 -281.953507)
			(xy 290.81477 -281.943663) (xy 290.768754 -281.926211) (xy 290.726133 -281.901604) (xy 290.688012 -281.870479)
			(xy 290.655377 -281.833642) (xy 290.629074 -281.792046) (xy 290.609783 -281.74677) (xy 290.598006 -281.698986)
			(xy 290.594046 -281.649932) (xy 290.255198 -281.649932) (xy 290.254703 -281.674539) (xy 290.246808 -281.723116)
			(xy 290.231224 -281.769797) (xy 290.208353 -281.813374) (xy 290.178788 -281.852718) (xy 290.143295 -281.88681)
			(xy 290.102792 -281.914766) (xy 290.05833 -281.935864) (xy 290.011059 -281.949556) (xy 289.962204 -281.955488)
			(xy 289.913029 -281.953507) (xy 289.86481 -281.943663) (xy 289.818794 -281.926211) (xy 289.776173 -281.901604)
			(xy 289.738052 -281.870479) (xy 289.705417 -281.833642) (xy 289.679114 -281.792046) (xy 289.659823 -281.74677)
			(xy 289.648046 -281.698986) (xy 289.644086 -281.649932) (xy 289.305238 -281.649932) (xy 289.304743 -281.674539)
			(xy 289.296848 -281.723116) (xy 289.281264 -281.769797) (xy 289.258393 -281.813374) (xy 289.228828 -281.852718)
			(xy 289.193335 -281.88681) (xy 289.152832 -281.914766) (xy 289.10837 -281.935864) (xy 289.061099 -281.949556)
			(xy 289.012244 -281.955488) (xy 288.963069 -281.953507) (xy 288.91485 -281.943663) (xy 288.868834 -281.926211)
			(xy 288.826213 -281.901604) (xy 288.788092 -281.870479) (xy 288.755457 -281.833642) (xy 288.729154 -281.792046)
			(xy 288.709863 -281.74677) (xy 288.698086 -281.698986) (xy 288.694126 -281.649932) (xy 288.355024 -281.649932)
			(xy 288.354529 -281.674539) (xy 288.346634 -281.723116) (xy 288.33105 -281.769797) (xy 288.308179 -281.813374)
			(xy 288.278614 -281.852718) (xy 288.243121 -281.88681) (xy 288.202618 -281.914766) (xy 288.158156 -281.935864)
			(xy 288.110885 -281.949556) (xy 288.06203 -281.955488) (xy 288.012855 -281.953507) (xy 287.964636 -281.943663)
			(xy 287.91862 -281.926211) (xy 287.875999 -281.901604) (xy 287.837878 -281.870479) (xy 287.805243 -281.833642)
			(xy 287.77894 -281.792046) (xy 287.759649 -281.74677) (xy 287.747872 -281.698986) (xy 287.743912 -281.649932)
			(xy 287.405064 -281.649932) (xy 287.404569 -281.674539) (xy 287.396674 -281.723116) (xy 287.38109 -281.769797)
			(xy 287.358219 -281.813374) (xy 287.328654 -281.852718) (xy 287.293161 -281.88681) (xy 287.252658 -281.914766)
			(xy 287.208196 -281.935864) (xy 287.160925 -281.949556) (xy 287.11207 -281.955488) (xy 287.062895 -281.953507)
			(xy 287.014676 -281.943663) (xy 286.96866 -281.926211) (xy 286.926039 -281.901604) (xy 286.887918 -281.870479)
			(xy 286.855283 -281.833642) (xy 286.82898 -281.792046) (xy 286.809689 -281.74677) (xy 286.797912 -281.698986)
			(xy 286.793952 -281.649932) (xy 286.455104 -281.649932) (xy 286.454609 -281.674539) (xy 286.446714 -281.723116)
			(xy 286.43113 -281.769797) (xy 286.408259 -281.813374) (xy 286.378694 -281.852718) (xy 286.343201 -281.88681)
			(xy 286.302698 -281.914766) (xy 286.258236 -281.935864) (xy 286.210965 -281.949556) (xy 286.16211 -281.955488)
			(xy 286.112935 -281.953507) (xy 286.064716 -281.943663) (xy 286.0187 -281.926211) (xy 285.976079 -281.901604)
			(xy 285.937958 -281.870479) (xy 285.905323 -281.833642) (xy 285.87902 -281.792046) (xy 285.859729 -281.74677)
			(xy 285.847952 -281.698986) (xy 285.843992 -281.649932) (xy 285.505144 -281.649932) (xy 285.504649 -281.674539)
			(xy 285.496754 -281.723116) (xy 285.48117 -281.769797) (xy 285.458299 -281.813374) (xy 285.428734 -281.852718)
			(xy 285.393241 -281.88681) (xy 285.352738 -281.914766) (xy 285.308276 -281.935864) (xy 285.261005 -281.949556)
			(xy 285.21215 -281.955488) (xy 285.162975 -281.953507) (xy 285.114756 -281.943663) (xy 285.06874 -281.926211)
			(xy 285.026119 -281.901604) (xy 284.987998 -281.870479) (xy 284.955363 -281.833642) (xy 284.92906 -281.792046)
			(xy 284.909769 -281.74677) (xy 284.897992 -281.698986) (xy 284.894032 -281.649932) (xy 284.555184 -281.649932)
			(xy 284.554689 -281.674539) (xy 284.546794 -281.723116) (xy 284.53121 -281.769797) (xy 284.508339 -281.813374)
			(xy 284.478774 -281.852718) (xy 284.443281 -281.88681) (xy 284.402778 -281.914766) (xy 284.358316 -281.935864)
			(xy 284.311045 -281.949556) (xy 284.26219 -281.955488) (xy 284.213015 -281.953507) (xy 284.164796 -281.943663)
			(xy 284.11878 -281.926211) (xy 284.076159 -281.901604) (xy 284.038038 -281.870479) (xy 284.005403 -281.833642)
			(xy 283.9791 -281.792046) (xy 283.959809 -281.74677) (xy 283.948032 -281.698986) (xy 283.944072 -281.649932)
			(xy 283.605224 -281.649932) (xy 283.604729 -281.674539) (xy 283.596834 -281.723116) (xy 283.58125 -281.769797)
			(xy 283.558379 -281.813374) (xy 283.528814 -281.852718) (xy 283.493321 -281.88681) (xy 283.452818 -281.914766)
			(xy 283.408356 -281.935864) (xy 283.361085 -281.949556) (xy 283.31223 -281.955488) (xy 283.263055 -281.953507)
			(xy 283.214836 -281.943663) (xy 283.16882 -281.926211) (xy 283.126199 -281.901604) (xy 283.088078 -281.870479)
			(xy 283.055443 -281.833642) (xy 283.02914 -281.792046) (xy 283.009849 -281.74677) (xy 282.998072 -281.698986)
			(xy 282.994112 -281.649932) (xy 282.65501 -281.649932) (xy 282.654515 -281.674539) (xy 282.64662 -281.723116)
			(xy 282.631036 -281.769797) (xy 282.608165 -281.813374) (xy 282.5786 -281.852718) (xy 282.543107 -281.88681)
			(xy 282.502604 -281.914766) (xy 282.458142 -281.935864) (xy 282.410871 -281.949556) (xy 282.362016 -281.955488)
			(xy 282.312841 -281.953507) (xy 282.264622 -281.943663) (xy 282.218606 -281.926211) (xy 282.175985 -281.901604)
			(xy 282.137864 -281.870479) (xy 282.105229 -281.833642) (xy 282.078926 -281.792046) (xy 282.059635 -281.74677)
			(xy 282.047858 -281.698986) (xy 282.043898 -281.649932) (xy 281.70505 -281.649932) (xy 281.704555 -281.674539)
			(xy 281.69666 -281.723116) (xy 281.681076 -281.769797) (xy 281.658205 -281.813374) (xy 281.62864 -281.852718)
			(xy 281.593147 -281.88681) (xy 281.552644 -281.914766) (xy 281.508182 -281.935864) (xy 281.460911 -281.949556)
			(xy 281.412056 -281.955488) (xy 281.362881 -281.953507) (xy 281.314662 -281.943663) (xy 281.268646 -281.926211)
			(xy 281.226025 -281.901604) (xy 281.187904 -281.870479) (xy 281.155269 -281.833642) (xy 281.128966 -281.792046)
			(xy 281.109675 -281.74677) (xy 281.097898 -281.698986) (xy 281.093938 -281.649932) (xy 280.75509 -281.649932)
			(xy 280.754595 -281.674539) (xy 280.7467 -281.723116) (xy 280.731116 -281.769797) (xy 280.708245 -281.813374)
			(xy 280.67868 -281.852718) (xy 280.643187 -281.88681) (xy 280.602684 -281.914766) (xy 280.558222 -281.935864)
			(xy 280.510951 -281.949556) (xy 280.462096 -281.955488) (xy 280.412921 -281.953507) (xy 280.364702 -281.943663)
			(xy 280.318686 -281.926211) (xy 280.276065 -281.901604) (xy 280.237944 -281.870479) (xy 280.205309 -281.833642)
			(xy 280.179006 -281.792046) (xy 280.159715 -281.74677) (xy 280.147938 -281.698986) (xy 280.143978 -281.649932)
			(xy 279.80513 -281.649932) (xy 279.804635 -281.674539) (xy 279.79674 -281.723116) (xy 279.781156 -281.769797)
			(xy 279.758285 -281.813374) (xy 279.72872 -281.852718) (xy 279.693227 -281.88681) (xy 279.652724 -281.914766)
			(xy 279.608262 -281.935864) (xy 279.560991 -281.949556) (xy 279.512136 -281.955488) (xy 279.462961 -281.953507)
			(xy 279.414742 -281.943663) (xy 279.368726 -281.926211) (xy 279.326105 -281.901604) (xy 279.287984 -281.870479)
			(xy 279.255349 -281.833642) (xy 279.229046 -281.792046) (xy 279.209755 -281.74677) (xy 279.197978 -281.698986)
			(xy 279.194018 -281.649932) (xy 278.855202 -281.649932) (xy 278.85565 -281.658198) (xy 278.85028 -281.707556)
			(xy 278.836994 -281.755394) (xy 278.816144 -281.800453) (xy 278.788278 -281.841546) (xy 278.754131 -281.877588)
			(xy 278.714603 -281.907631) (xy 278.670735 -281.930882) (xy 278.623683 -281.94673) (xy 278.574687 -281.954757)
			(xy 278.549862 -281.95524) (xy 278.535679 -281.955068) (xy 278.507439 -281.952393) (xy 278.493474 -281.949906)
			(xy 278.481028 -281.94762) (xy 278.457406 -281.954986) (xy 278.379936 -282.032456) (xy 278.37257 -282.056078)
			(xy 278.374856 -282.068524) (xy 278.377331 -282.08249) (xy 278.380004 -282.11073) (xy 278.38019 -282.124912)
			(xy 278.379668 -282.150167) (xy 278.371355 -282.199989) (xy 278.354954 -282.247763) (xy 278.330913 -282.292186)
			(xy 278.299889 -282.332046) (xy 278.262727 -282.366256) (xy 278.220441 -282.393882) (xy 278.174185 -282.414172)
			(xy 278.12522 -282.426572) (xy 278.074882 -282.430743) (xy 278.024544 -282.426572) (xy 277.975579 -282.414172)
			(xy 277.929323 -282.393882) (xy 277.887037 -282.366256) (xy 277.849875 -282.332046) (xy 277.818851 -282.292186)
			(xy 277.79481 -282.247763) (xy 277.778409 -282.199989) (xy 277.770096 -282.150167) (xy 277.769574 -282.124912)
			(xy 277.769753 -282.110729) (xy 277.772423 -282.082489) (xy 277.774908 -282.068524) (xy 277.777194 -282.056078)
			(xy 277.769828 -282.032456) (xy 277.692358 -281.954986) (xy 277.668736 -281.94762) (xy 277.65629 -281.949906)
			(xy 277.642324 -281.95238) (xy 277.614084 -281.955053) (xy 277.599902 -281.95524) (xy 277.585719 -281.955063)
			(xy 277.557479 -281.952391) (xy 277.543514 -281.949906) (xy 277.531068 -281.94762) (xy 277.507446 -281.954986)
			(xy 277.429976 -282.032456) (xy 277.42261 -282.056078) (xy 277.424896 -282.068524) (xy 277.427372 -282.08249)
			(xy 277.430044 -282.110729) (xy 277.43023 -282.124912) (xy 277.429708 -282.150167) (xy 277.421395 -282.199989)
			(xy 277.404994 -282.247763) (xy 277.380953 -282.292186) (xy 277.349929 -282.332046) (xy 277.312767 -282.366256)
			(xy 277.270481 -282.393882) (xy 277.224225 -282.414172) (xy 277.17526 -282.426572) (xy 277.124922 -282.430743)
			(xy 277.074584 -282.426572) (xy 277.025619 -282.414172) (xy 276.979363 -282.393882) (xy 276.937077 -282.366256)
			(xy 276.899915 -282.332046) (xy 276.868891 -282.292186) (xy 276.84485 -282.247763) (xy 276.828449 -282.199989)
			(xy 276.820136 -282.150167) (xy 276.819614 -282.124912) (xy 276.819792 -282.110729) (xy 276.822463 -282.082489)
			(xy 276.824948 -282.068524) (xy 276.827234 -282.056078) (xy 276.819868 -282.032202) (xy 276.742652 -281.954986)
			(xy 276.718522 -281.94762) (xy 276.70633 -281.949906) (xy 276.692302 -281.952398) (xy 276.663934 -281.955065)
			(xy 276.649688 -281.95524) (xy 276.635505 -281.955064) (xy 276.607265 -281.952392) (xy 276.5933 -281.949906)
			(xy 276.580854 -281.94762) (xy 276.557232 -281.954986) (xy 276.479762 -282.032456) (xy 276.472396 -282.056078)
			(xy 276.474682 -282.068524) (xy 276.477158 -282.08249) (xy 276.47983 -282.11073) (xy 276.480016 -282.124912)
			(xy 276.479509 -282.149732) (xy 276.471476 -282.198717) (xy 276.455625 -282.245758) (xy 276.432371 -282.289614)
			(xy 276.402329 -282.329131) (xy 276.36629 -282.363266) (xy 276.325203 -282.391122) (xy 276.28015 -282.411964)
			(xy 276.23232 -282.425242) (xy 276.182971 -282.430607) (xy 276.133404 -282.427918) (xy 276.084925 -282.417245)
			(xy 276.038812 -282.39887) (xy 275.996279 -282.373277) (xy 275.958446 -282.34114) (xy 275.926311 -282.303305)
			(xy 275.900721 -282.26077) (xy 275.882349 -282.214656) (xy 275.871679 -282.166176) (xy 275.868993 -282.116609)
			(xy 275.874362 -282.067261) (xy 275.887643 -282.019431) (xy 275.908488 -281.97438) (xy 275.936346 -281.933295)
			(xy 275.970484 -281.897257) (xy 276.010003 -281.867218) (xy 276.053861 -281.843967) (xy 276.100902 -281.828119)
			(xy 276.149888 -281.820089) (xy 276.174708 -281.819604) (xy 276.188891 -281.819779) (xy 276.217131 -281.822452)
			(xy 276.231096 -281.824938) (xy 276.243542 -281.827224) (xy 276.267164 -281.819858) (xy 276.344634 -281.742388)
			(xy 276.352 -281.718766) (xy 276.349714 -281.70632) (xy 276.347231 -281.692355) (xy 276.344563 -281.664115)
			(xy 276.34438 -281.649932) (xy 276.344561 -281.635749) (xy 276.34723 -281.607509) (xy 276.349714 -281.593544)
			(xy 276.352 -281.581098) (xy 276.344634 -281.557476) (xy 276.267164 -281.480006) (xy 276.243542 -281.47264)
			(xy 276.231096 -281.474926) (xy 276.21713 -281.477399) (xy 276.18889 -281.480073) (xy 276.174708 -281.48026)
			(xy 276.149446 -281.479864) (xy 276.099611 -281.471549) (xy 276.051824 -281.455145) (xy 276.007388 -281.431099)
			(xy 275.967517 -281.400067) (xy 275.933298 -281.362895) (xy 275.905663 -281.320598) (xy 275.885367 -281.27433)
			(xy 275.872964 -281.225352) (xy 275.868792 -281.175) (xy 275.530055 -281.175) (xy 275.529561 -281.199559)
			(xy 275.521666 -281.248136) (xy 275.506082 -281.294817) (xy 275.483211 -281.338394) (xy 275.453646 -281.377738)
			(xy 275.418153 -281.41183) (xy 275.37765 -281.439786) (xy 275.333188 -281.460884) (xy 275.285917 -281.474576)
			(xy 275.237062 -281.480508) (xy 275.187887 -281.478527) (xy 275.139668 -281.468683) (xy 275.093652 -281.451231)
			(xy 275.051031 -281.426624) (xy 275.01291 -281.395499) (xy 274.980275 -281.358662) (xy 274.953972 -281.317066)
			(xy 274.934681 -281.27179) (xy 274.922904 -281.224006) (xy 274.918944 -281.174952) (xy 274.580096 -281.174952)
			(xy 274.579601 -281.199559) (xy 274.571706 -281.248136) (xy 274.556122 -281.294817) (xy 274.533251 -281.338394)
			(xy 274.503686 -281.377738) (xy 274.468193 -281.41183) (xy 274.42769 -281.439786) (xy 274.383228 -281.460884)
			(xy 274.335957 -281.474576) (xy 274.287102 -281.480508) (xy 274.237927 -281.478527) (xy 274.189708 -281.468683)
			(xy 274.143692 -281.451231) (xy 274.101071 -281.426624) (xy 274.06295 -281.395499) (xy 274.030315 -281.358662)
			(xy 274.004012 -281.317066) (xy 273.984721 -281.27179) (xy 273.972944 -281.224006) (xy 273.968984 -281.174952)
			(xy 273.630136 -281.174952) (xy 273.629641 -281.199559) (xy 273.621746 -281.248136) (xy 273.606162 -281.294817)
			(xy 273.583291 -281.338394) (xy 273.553726 -281.377738) (xy 273.518233 -281.41183) (xy 273.47773 -281.439786)
			(xy 273.433268 -281.460884) (xy 273.385997 -281.474576) (xy 273.337142 -281.480508) (xy 273.287967 -281.478527)
			(xy 273.239748 -281.468683) (xy 273.193732 -281.451231) (xy 273.151111 -281.426624) (xy 273.11299 -281.395499)
			(xy 273.080355 -281.358662) (xy 273.054052 -281.317066) (xy 273.034761 -281.27179) (xy 273.022984 -281.224006)
			(xy 273.019024 -281.174952) (xy 272.680176 -281.174952) (xy 272.679681 -281.199559) (xy 272.671786 -281.248136)
			(xy 272.656202 -281.294817) (xy 272.633331 -281.338394) (xy 272.603766 -281.377738) (xy 272.568273 -281.41183)
			(xy 272.52777 -281.439786) (xy 272.483308 -281.460884) (xy 272.436037 -281.474576) (xy 272.387182 -281.480508)
			(xy 272.338007 -281.478527) (xy 272.289788 -281.468683) (xy 272.243772 -281.451231) (xy 272.201151 -281.426624)
			(xy 272.16303 -281.395499) (xy 272.130395 -281.358662) (xy 272.104092 -281.317066) (xy 272.084801 -281.27179)
			(xy 272.073024 -281.224006) (xy 272.069064 -281.174952) (xy 271.730216 -281.174952) (xy 271.729721 -281.199559)
			(xy 271.721826 -281.248136) (xy 271.706242 -281.294817) (xy 271.683371 -281.338394) (xy 271.653806 -281.377738)
			(xy 271.618313 -281.41183) (xy 271.57781 -281.439786) (xy 271.533348 -281.460884) (xy 271.486077 -281.474576)
			(xy 271.437222 -281.480508) (xy 271.388047 -281.478527) (xy 271.339828 -281.468683) (xy 271.293812 -281.451231)
			(xy 271.251191 -281.426624) (xy 271.21307 -281.395499) (xy 271.180435 -281.358662) (xy 271.154132 -281.317066)
			(xy 271.134841 -281.27179) (xy 271.123064 -281.224006) (xy 271.119104 -281.174952) (xy 270.780256 -281.174952)
			(xy 270.779761 -281.199559) (xy 270.771866 -281.248136) (xy 270.756282 -281.294817) (xy 270.733411 -281.338394)
			(xy 270.703846 -281.377738) (xy 270.668353 -281.41183) (xy 270.62785 -281.439786) (xy 270.583388 -281.460884)
			(xy 270.536117 -281.474576) (xy 270.487262 -281.480508) (xy 270.438087 -281.478527) (xy 270.389868 -281.468683)
			(xy 270.343852 -281.451231) (xy 270.301231 -281.426624) (xy 270.26311 -281.395499) (xy 270.230475 -281.358662)
			(xy 270.204172 -281.317066) (xy 270.184881 -281.27179) (xy 270.173104 -281.224006) (xy 270.169144 -281.174952)
			(xy 269.830042 -281.174952) (xy 269.829547 -281.199559) (xy 269.821652 -281.248136) (xy 269.806068 -281.294817)
			(xy 269.783197 -281.338394) (xy 269.753632 -281.377738) (xy 269.718139 -281.41183) (xy 269.677636 -281.439786)
			(xy 269.633174 -281.460884) (xy 269.585903 -281.474576) (xy 269.537048 -281.480508) (xy 269.487873 -281.478527)
			(xy 269.439654 -281.468683) (xy 269.393638 -281.451231) (xy 269.351017 -281.426624) (xy 269.312896 -281.395499)
			(xy 269.280261 -281.358662) (xy 269.253958 -281.317066) (xy 269.234667 -281.27179) (xy 269.22289 -281.224006)
			(xy 269.21893 -281.174952) (xy 268.880082 -281.174952) (xy 268.879587 -281.199559) (xy 268.871692 -281.248136)
			(xy 268.856108 -281.294817) (xy 268.833237 -281.338394) (xy 268.803672 -281.377738) (xy 268.768179 -281.41183)
			(xy 268.727676 -281.439786) (xy 268.683214 -281.460884) (xy 268.635943 -281.474576) (xy 268.587088 -281.480508)
			(xy 268.537913 -281.478527) (xy 268.489694 -281.468683) (xy 268.443678 -281.451231) (xy 268.401057 -281.426624)
			(xy 268.362936 -281.395499) (xy 268.330301 -281.358662) (xy 268.303998 -281.317066) (xy 268.284707 -281.27179)
			(xy 268.27293 -281.224006) (xy 268.26897 -281.174952) (xy 250.679151 -281.174952) (xy 250.731176 -281.188553)
			(xy 250.782505 -281.210365) (xy 250.830111 -281.239419) (xy 250.872979 -281.275094) (xy 250.910196 -281.316631)
			(xy 250.940969 -281.363144) (xy 250.964641 -281.413641) (xy 250.980709 -281.467048) (xy 250.988829 -281.522224)
			(xy 250.989338 -281.55011) (xy 250.988829 -281.577996) (xy 250.980709 -281.633172) (xy 250.964641 -281.686579)
			(xy 250.940969 -281.737076) (xy 250.910196 -281.783589) (xy 250.872979 -281.825126) (xy 250.868016 -281.829256)
			(xy 258.01142 -281.829256) (xy 258.015491 -281.773634) (xy 258.027617 -281.719197) (xy 258.04754 -281.667106)
			(xy 258.074836 -281.618471) (xy 258.108922 -281.574328) (xy 258.149071 -281.535619) (xy 258.194429 -281.503168)
			(xy 258.244029 -281.477667) (xy 258.296813 -281.45966) (xy 258.351656 -281.44953) (xy 258.40739 -281.447493)
			(xy 258.462827 -281.453593) (xy 258.516784 -281.467699) (xy 258.568113 -281.489511) (xy 258.615719 -281.518565)
			(xy 258.658587 -281.55424) (xy 258.695804 -281.595777) (xy 258.726577 -281.64229) (xy 258.750249 -281.692787)
			(xy 258.766317 -281.746194) (xy 258.774437 -281.80137) (xy 258.774946 -281.829256) (xy 259.496558 -281.829256)
			(xy 259.500629 -281.773634) (xy 259.512755 -281.719197) (xy 259.532678 -281.667106) (xy 259.559974 -281.618471)
			(xy 259.59406 -281.574328) (xy 259.634209 -281.535619) (xy 259.679567 -281.503168) (xy 259.729167 -281.477667)
			(xy 259.781951 -281.45966) (xy 259.836794 -281.44953) (xy 259.892528 -281.447493) (xy 259.947965 -281.453593)
			(xy 260.001922 -281.467699) (xy 260.053251 -281.489511) (xy 260.100857 -281.518565) (xy 260.143725 -281.55424)
			(xy 260.180942 -281.595777) (xy 260.211715 -281.64229) (xy 260.235387 -281.692787) (xy 260.251455 -281.746194)
			(xy 260.259575 -281.80137) (xy 260.260084 -281.829256) (xy 260.259575 -281.857142) (xy 260.251455 -281.912318)
			(xy 260.235387 -281.965725) (xy 260.211715 -282.016222) (xy 260.180942 -282.062735) (xy 260.143725 -282.104272)
			(xy 260.118923 -282.124912) (xy 268.26897 -282.124912) (xy 268.27293 -282.075858) (xy 268.284707 -282.028074)
			(xy 268.303998 -281.982798) (xy 268.330301 -281.941202) (xy 268.362936 -281.904365) (xy 268.401057 -281.87324)
			(xy 268.443678 -281.848633) (xy 268.489694 -281.831181) (xy 268.537913 -281.821337) (xy 268.587088 -281.819356)
			(xy 268.635943 -281.825288) (xy 268.683214 -281.83898) (xy 268.727676 -281.860078) (xy 268.768179 -281.888034)
			(xy 268.803672 -281.922126) (xy 268.833237 -281.96147) (xy 268.856108 -282.005047) (xy 268.871692 -282.051728)
			(xy 268.879587 -282.100305) (xy 268.880082 -282.124912) (xy 269.21893 -282.124912) (xy 269.22289 -282.075858)
			(xy 269.234667 -282.028074) (xy 269.253958 -281.982798) (xy 269.280261 -281.941202) (xy 269.312896 -281.904365)
			(xy 269.351017 -281.87324) (xy 269.393638 -281.848633) (xy 269.439654 -281.831181) (xy 269.487873 -281.821337)
			(xy 269.537048 -281.819356) (xy 269.585903 -281.825288) (xy 269.633174 -281.83898) (xy 269.677636 -281.860078)
			(xy 269.718139 -281.888034) (xy 269.753632 -281.922126) (xy 269.783197 -281.96147) (xy 269.806068 -282.005047)
			(xy 269.821652 -282.051728) (xy 269.829547 -282.100305) (xy 269.830042 -282.124912) (xy 270.169144 -282.124912)
			(xy 270.173104 -282.075858) (xy 270.184881 -282.028074) (xy 270.204172 -281.982798) (xy 270.230475 -281.941202)
			(xy 270.26311 -281.904365) (xy 270.301231 -281.87324) (xy 270.343852 -281.848633) (xy 270.389868 -281.831181)
			(xy 270.438087 -281.821337) (xy 270.487262 -281.819356) (xy 270.536117 -281.825288) (xy 270.583388 -281.83898)
			(xy 270.62785 -281.860078) (xy 270.668353 -281.888034) (xy 270.703846 -281.922126) (xy 270.733411 -281.96147)
			(xy 270.756282 -282.005047) (xy 270.771866 -282.051728) (xy 270.779761 -282.100305) (xy 270.780256 -282.124912)
			(xy 271.119104 -282.124912) (xy 271.123064 -282.075858) (xy 271.134841 -282.028074) (xy 271.154132 -281.982798)
			(xy 271.180435 -281.941202) (xy 271.21307 -281.904365) (xy 271.251191 -281.87324) (xy 271.293812 -281.848633)
			(xy 271.339828 -281.831181) (xy 271.388047 -281.821337) (xy 271.437222 -281.819356) (xy 271.486077 -281.825288)
			(xy 271.533348 -281.83898) (xy 271.57781 -281.860078) (xy 271.618313 -281.888034) (xy 271.653806 -281.922126)
			(xy 271.683371 -281.96147) (xy 271.706242 -282.005047) (xy 271.721826 -282.051728) (xy 271.729721 -282.100305)
			(xy 271.730216 -282.124912) (xy 272.069064 -282.124912) (xy 272.073024 -282.075858) (xy 272.084801 -282.028074)
			(xy 272.104092 -281.982798) (xy 272.130395 -281.941202) (xy 272.16303 -281.904365) (xy 272.201151 -281.87324)
			(xy 272.243772 -281.848633) (xy 272.289788 -281.831181) (xy 272.338007 -281.821337) (xy 272.387182 -281.819356)
			(xy 272.436037 -281.825288) (xy 272.483308 -281.83898) (xy 272.52777 -281.860078) (xy 272.568273 -281.888034)
			(xy 272.603766 -281.922126) (xy 272.633331 -281.96147) (xy 272.656202 -282.005047) (xy 272.671786 -282.051728)
			(xy 272.679681 -282.100305) (xy 272.680176 -282.124912) (xy 273.019024 -282.124912) (xy 273.022984 -282.075858)
			(xy 273.034761 -282.028074) (xy 273.054052 -281.982798) (xy 273.080355 -281.941202) (xy 273.11299 -281.904365)
			(xy 273.151111 -281.87324) (xy 273.193732 -281.848633) (xy 273.239748 -281.831181) (xy 273.287967 -281.821337)
			(xy 273.337142 -281.819356) (xy 273.385997 -281.825288) (xy 273.433268 -281.83898) (xy 273.47773 -281.860078)
			(xy 273.518233 -281.888034) (xy 273.553726 -281.922126) (xy 273.583291 -281.96147) (xy 273.606162 -282.005047)
			(xy 273.621746 -282.051728) (xy 273.629641 -282.100305) (xy 273.630136 -282.124912) (xy 273.968984 -282.124912)
			(xy 273.972944 -282.075858) (xy 273.984721 -282.028074) (xy 274.004012 -281.982798) (xy 274.030315 -281.941202)
			(xy 274.06295 -281.904365) (xy 274.101071 -281.87324) (xy 274.143692 -281.848633) (xy 274.189708 -281.831181)
			(xy 274.237927 -281.821337) (xy 274.287102 -281.819356) (xy 274.335957 -281.825288) (xy 274.383228 -281.83898)
			(xy 274.42769 -281.860078) (xy 274.468193 -281.888034) (xy 274.503686 -281.922126) (xy 274.533251 -281.96147)
			(xy 274.556122 -282.005047) (xy 274.571706 -282.051728) (xy 274.579601 -282.100305) (xy 274.580096 -282.124912)
			(xy 274.918944 -282.124912) (xy 274.922904 -282.075858) (xy 274.934681 -282.028074) (xy 274.953972 -281.982798)
			(xy 274.980275 -281.941202) (xy 275.01291 -281.904365) (xy 275.051031 -281.87324) (xy 275.093652 -281.848633)
			(xy 275.139668 -281.831181) (xy 275.187887 -281.821337) (xy 275.237062 -281.819356) (xy 275.285917 -281.825288)
			(xy 275.333188 -281.83898) (xy 275.37765 -281.860078) (xy 275.418153 -281.888034) (xy 275.453646 -281.922126)
			(xy 275.483211 -281.96147) (xy 275.506082 -282.005047) (xy 275.521666 -282.051728) (xy 275.529561 -282.100305)
			(xy 275.530056 -282.124912) (xy 275.529561 -282.149519) (xy 275.521666 -282.198096) (xy 275.506082 -282.244777)
			(xy 275.483211 -282.288354) (xy 275.453646 -282.327698) (xy 275.418153 -282.36179) (xy 275.37765 -282.389746)
			(xy 275.333188 -282.410844) (xy 275.285917 -282.424536) (xy 275.237062 -282.430468) (xy 275.187887 -282.428487)
			(xy 275.139668 -282.418643) (xy 275.093652 -282.401191) (xy 275.051031 -282.376584) (xy 275.01291 -282.345459)
			(xy 274.980275 -282.308622) (xy 274.953972 -282.267026) (xy 274.934681 -282.22175) (xy 274.922904 -282.173966)
			(xy 274.918944 -282.124912) (xy 274.580096 -282.124912) (xy 274.579601 -282.149519) (xy 274.571706 -282.198096)
			(xy 274.556122 -282.244777) (xy 274.533251 -282.288354) (xy 274.503686 -282.327698) (xy 274.468193 -282.36179)
			(xy 274.42769 -282.389746) (xy 274.383228 -282.410844) (xy 274.335957 -282.424536) (xy 274.287102 -282.430468)
			(xy 274.237927 -282.428487) (xy 274.189708 -282.418643) (xy 274.143692 -282.401191) (xy 274.101071 -282.376584)
			(xy 274.06295 -282.345459) (xy 274.030315 -282.308622) (xy 274.004012 -282.267026) (xy 273.984721 -282.22175)
			(xy 273.972944 -282.173966) (xy 273.968984 -282.124912) (xy 273.630136 -282.124912) (xy 273.629641 -282.149519)
			(xy 273.621746 -282.198096) (xy 273.606162 -282.244777) (xy 273.583291 -282.288354) (xy 273.553726 -282.327698)
			(xy 273.518233 -282.36179) (xy 273.47773 -282.389746) (xy 273.433268 -282.410844) (xy 273.385997 -282.424536)
			(xy 273.337142 -282.430468) (xy 273.287967 -282.428487) (xy 273.239748 -282.418643) (xy 273.193732 -282.401191)
			(xy 273.151111 -282.376584) (xy 273.11299 -282.345459) (xy 273.080355 -282.308622) (xy 273.054052 -282.267026)
			(xy 273.034761 -282.22175) (xy 273.022984 -282.173966) (xy 273.019024 -282.124912) (xy 272.680176 -282.124912)
			(xy 272.679681 -282.149519) (xy 272.671786 -282.198096) (xy 272.656202 -282.244777) (xy 272.633331 -282.288354)
			(xy 272.603766 -282.327698) (xy 272.568273 -282.36179) (xy 272.52777 -282.389746) (xy 272.483308 -282.410844)
			(xy 272.436037 -282.424536) (xy 272.387182 -282.430468) (xy 272.338007 -282.428487) (xy 272.289788 -282.418643)
			(xy 272.243772 -282.401191) (xy 272.201151 -282.376584) (xy 272.16303 -282.345459) (xy 272.130395 -282.308622)
			(xy 272.104092 -282.267026) (xy 272.084801 -282.22175) (xy 272.073024 -282.173966) (xy 272.069064 -282.124912)
			(xy 271.730216 -282.124912) (xy 271.729721 -282.149519) (xy 271.721826 -282.198096) (xy 271.706242 -282.244777)
			(xy 271.683371 -282.288354) (xy 271.653806 -282.327698) (xy 271.618313 -282.36179) (xy 271.57781 -282.389746)
			(xy 271.533348 -282.410844) (xy 271.486077 -282.424536) (xy 271.437222 -282.430468) (xy 271.388047 -282.428487)
			(xy 271.339828 -282.418643) (xy 271.293812 -282.401191) (xy 271.251191 -282.376584) (xy 271.21307 -282.345459)
			(xy 271.180435 -282.308622) (xy 271.154132 -282.267026) (xy 271.134841 -282.22175) (xy 271.123064 -282.173966)
			(xy 271.119104 -282.124912) (xy 270.780256 -282.124912) (xy 270.779761 -282.149519) (xy 270.771866 -282.198096)
			(xy 270.756282 -282.244777) (xy 270.733411 -282.288354) (xy 270.703846 -282.327698) (xy 270.668353 -282.36179)
			(xy 270.62785 -282.389746) (xy 270.583388 -282.410844) (xy 270.536117 -282.424536) (xy 270.487262 -282.430468)
			(xy 270.438087 -282.428487) (xy 270.389868 -282.418643) (xy 270.343852 -282.401191) (xy 270.301231 -282.376584)
			(xy 270.26311 -282.345459) (xy 270.230475 -282.308622) (xy 270.204172 -282.267026) (xy 270.184881 -282.22175)
			(xy 270.173104 -282.173966) (xy 270.169144 -282.124912) (xy 269.830042 -282.124912) (xy 269.829547 -282.149519)
			(xy 269.821652 -282.198096) (xy 269.806068 -282.244777) (xy 269.783197 -282.288354) (xy 269.753632 -282.327698)
			(xy 269.718139 -282.36179) (xy 269.677636 -282.389746) (xy 269.633174 -282.410844) (xy 269.585903 -282.424536)
			(xy 269.537048 -282.430468) (xy 269.487873 -282.428487) (xy 269.439654 -282.418643) (xy 269.393638 -282.401191)
			(xy 269.351017 -282.376584) (xy 269.312896 -282.345459) (xy 269.280261 -282.308622) (xy 269.253958 -282.267026)
			(xy 269.234667 -282.22175) (xy 269.22289 -282.173966) (xy 269.21893 -282.124912) (xy 268.880082 -282.124912)
			(xy 268.879587 -282.149519) (xy 268.871692 -282.198096) (xy 268.856108 -282.244777) (xy 268.833237 -282.288354)
			(xy 268.803672 -282.327698) (xy 268.768179 -282.36179) (xy 268.727676 -282.389746) (xy 268.683214 -282.410844)
			(xy 268.635943 -282.424536) (xy 268.587088 -282.430468) (xy 268.537913 -282.428487) (xy 268.489694 -282.418643)
			(xy 268.443678 -282.401191) (xy 268.401057 -282.376584) (xy 268.362936 -282.345459) (xy 268.330301 -282.308622)
			(xy 268.303998 -282.267026) (xy 268.284707 -282.22175) (xy 268.27293 -282.173966) (xy 268.26897 -282.124912)
			(xy 260.118923 -282.124912) (xy 260.100857 -282.139947) (xy 260.053251 -282.169001) (xy 260.001922 -282.190813)
			(xy 259.947965 -282.204919) (xy 259.892528 -282.211019) (xy 259.836794 -282.208982) (xy 259.781951 -282.198852)
			(xy 259.729167 -282.180845) (xy 259.679567 -282.155344) (xy 259.634209 -282.122893) (xy 259.59406 -282.084184)
			(xy 259.559974 -282.040041) (xy 259.532678 -281.991406) (xy 259.512755 -281.939315) (xy 259.500629 -281.884878)
			(xy 259.496558 -281.829256) (xy 258.774946 -281.829256) (xy 258.774437 -281.857142) (xy 258.766317 -281.912318)
			(xy 258.750249 -281.965725) (xy 258.726577 -282.016222) (xy 258.695804 -282.062735) (xy 258.658587 -282.104272)
			(xy 258.615719 -282.139947) (xy 258.568113 -282.169001) (xy 258.516784 -282.190813) (xy 258.462827 -282.204919)
			(xy 258.40739 -282.211019) (xy 258.351656 -282.208982) (xy 258.296813 -282.198852) (xy 258.244029 -282.180845)
			(xy 258.194429 -282.155344) (xy 258.149071 -282.122893) (xy 258.108922 -282.084184) (xy 258.074836 -282.040041)
			(xy 258.04754 -281.991406) (xy 258.027617 -281.939315) (xy 258.015491 -281.884878) (xy 258.01142 -281.829256)
			(xy 250.868016 -281.829256) (xy 250.830111 -281.860801) (xy 250.782505 -281.889855) (xy 250.731176 -281.911667)
			(xy 250.677219 -281.925773) (xy 250.621782 -281.931873) (xy 250.566048 -281.929836) (xy 250.511205 -281.919706)
			(xy 250.458421 -281.901699) (xy 250.408821 -281.876198) (xy 250.363463 -281.843747) (xy 250.323314 -281.805038)
			(xy 250.289228 -281.760895) (xy 250.261932 -281.71226) (xy 250.242009 -281.660169) (xy 250.229883 -281.605732)
			(xy 250.225812 -281.55011) (xy 226.019532 -281.55011) (xy 225.136456 -282.433268) (xy 225.130161 -282.440163)
			(xy 225.122564 -282.457201) (xy 225.121537 -282.475828) (xy 225.12401 -282.48483) (xy 225.156268 -282.584652)
			(xy 225.178112 -282.603194) (xy 225.192336 -282.605226) (xy 225.220335 -282.610208) (xy 225.27455 -282.627371)
			(xy 225.325619 -282.652387) (xy 225.372412 -282.684703) (xy 225.393504 -282.703778) (xy 225.400616 -282.710382)
			(xy 225.418142 -282.717494) (xy 225.50755 -282.717494) (xy 225.525076 -282.710382) (xy 225.532188 -282.703778)
			(xy 225.553515 -282.684508) (xy 225.600878 -282.651943) (xy 225.652589 -282.626852) (xy 225.70748 -282.609802)
			(xy 225.764307 -282.60118) (xy 225.821785 -282.60118) (xy 225.878612 -282.609802) (xy 225.933503 -282.626852)
			(xy 225.985214 -282.651943) (xy 226.032577 -282.684508) (xy 226.053904 -282.703778) (xy 226.061016 -282.710382)
			(xy 226.078542 -282.717494) (xy 226.16795 -282.717494) (xy 226.185476 -282.710382) (xy 226.192588 -282.703778)
			(xy 226.213915 -282.684506) (xy 226.261277 -282.651938) (xy 226.312988 -282.626842) (xy 226.367879 -282.609787)
			(xy 226.424706 -282.601157) (xy 226.453446 -282.600654) (xy 226.483571 -282.601219) (xy 226.543074 -282.610685)
			(xy 226.600347 -282.629389) (xy 226.653967 -282.656867) (xy 226.702599 -282.692435) (xy 226.72421 -282.71343)
			(xy 226.731322 -282.720796) (xy 226.750118 -282.728416) (xy 226.842574 -282.728416) (xy 226.86137 -282.720796)
			(xy 226.868482 -282.71343) (xy 226.890108 -282.692454) (xy 226.938743 -282.656901) (xy 226.992361 -282.629431)
			(xy 227.049629 -282.610727) (xy 227.109124 -282.601253) (xy 227.139246 -282.600654) (xy 227.166498 -282.601143)
			(xy 227.220446 -282.608906) (xy 227.27274 -282.624266) (xy 227.322317 -282.646912) (xy 227.368166 -282.676383)
			(xy 227.409355 -282.712078) (xy 227.445045 -282.753271) (xy 227.47451 -282.799124) (xy 227.49715 -282.848703)
			(xy 227.512504 -282.900999) (xy 227.52026 -282.954948) (xy 227.52026 -283.009452) (xy 227.520259 -283.009457)
			(xy 228.998917 -283.009457) (xy 228.998917 -282.954943) (xy 229.006676 -282.900984) (xy 229.022035 -282.848678)
			(xy 229.044682 -282.79909) (xy 229.074156 -282.753231) (xy 229.109857 -282.712033) (xy 229.151058 -282.676336)
			(xy 229.19692 -282.646866) (xy 229.24651 -282.624223) (xy 229.298817 -282.608868) (xy 229.352777 -282.601115)
			(xy 229.380034 -282.600654) (xy 229.408773 -282.601169) (xy 229.4656 -282.609796) (xy 229.520491 -282.626849)
			(xy 229.572202 -282.651942) (xy 229.619565 -282.684507) (xy 229.640892 -282.703778) (xy 229.648004 -282.710382)
			(xy 229.66553 -282.717494) (xy 229.754938 -282.717494) (xy 229.772464 -282.710382) (xy 229.779576 -282.703778)
			(xy 229.800903 -282.684508) (xy 229.848266 -282.651943) (xy 229.899977 -282.626852) (xy 229.954868 -282.609802)
			(xy 230.011695 -282.60118) (xy 230.069173 -282.60118) (xy 230.126 -282.609802) (xy 230.180891 -282.626852)
			(xy 230.232602 -282.651943) (xy 230.279965 -282.684508) (xy 230.301292 -282.703778) (xy 230.308404 -282.710382)
			(xy 230.32593 -282.717494) (xy 230.415338 -282.717494) (xy 230.432864 -282.710382) (xy 230.439976 -282.703778)
			(xy 230.461295 -282.684498) (xy 230.508658 -282.651931) (xy 230.560372 -282.62684) (xy 230.615265 -282.609792)
			(xy 230.672094 -282.601173) (xy 230.700834 -282.600654) (xy 230.730958 -282.601202) (xy 230.790456 -282.610688)
			(xy 230.847724 -282.629405) (xy 230.901341 -282.656886) (xy 230.949974 -282.692449) (xy 230.971598 -282.71343)
			(xy 230.97871 -282.720796) (xy 230.997506 -282.728416) (xy 231.089962 -282.728416) (xy 231.108758 -282.720796)
			(xy 231.11587 -282.71343) (xy 231.13749 -282.692444) (xy 231.186119 -282.656875) (xy 231.239737 -282.629396)
			(xy 231.297009 -282.610689) (xy 231.356509 -282.601221) (xy 231.386634 -282.600654) (xy 231.413881 -282.601219)
			(xy 231.46782 -282.608978) (xy 231.520105 -282.624335) (xy 231.569673 -282.646975) (xy 231.615514 -282.67644)
			(xy 231.656696 -282.712128) (xy 231.692381 -282.753313) (xy 231.721841 -282.799157) (xy 231.744477 -282.848727)
			(xy 231.759829 -282.901014) (xy 231.767584 -282.954953) (xy 231.767584 -283.009447) (xy 231.767583 -283.009456)
			(xy 241.001717 -283.009456) (xy 241.001717 -282.954944) (xy 241.009475 -282.900988) (xy 241.024833 -282.848684)
			(xy 241.047478 -282.799099) (xy 241.076949 -282.753241) (xy 241.112647 -282.712044) (xy 241.153844 -282.676347)
			(xy 241.199702 -282.646876) (xy 241.249288 -282.624231) (xy 241.301591 -282.608874) (xy 241.355548 -282.601117)
			(xy 241.382804 -282.600654) (xy 241.411542 -282.601188) (xy 241.468369 -282.60981) (xy 241.523259 -282.626858)
			(xy 241.574971 -282.651947) (xy 241.622334 -282.684509) (xy 241.643662 -282.703778) (xy 241.650774 -282.710382)
			(xy 241.6683 -282.717494) (xy 241.757708 -282.717494) (xy 241.775234 -282.710382) (xy 241.782346 -282.703778)
			(xy 241.803673 -282.684508) (xy 241.851036 -282.651943) (xy 241.902747 -282.626852) (xy 241.957638 -282.609802)
			(xy 242.014465 -282.60118) (xy 242.071943 -282.60118) (xy 242.12877 -282.609802) (xy 242.183661 -282.626852)
			(xy 242.235372 -282.651943) (xy 242.282735 -282.684508) (xy 242.304062 -282.703778) (xy 242.311174 -282.710382)
			(xy 242.3287 -282.717494) (xy 242.418108 -282.717494) (xy 242.435634 -282.710382) (xy 242.442746 -282.703778)
			(xy 242.464077 -282.684512) (xy 242.511437 -282.651944) (xy 242.563148 -282.626849) (xy 242.618038 -282.609798)
			(xy 242.674865 -282.601175) (xy 242.703604 -282.600654) (xy 242.733728 -282.601221) (xy 242.793224 -282.610703)
			(xy 242.850492 -282.629414) (xy 242.904109 -282.656891) (xy 242.952743 -282.692451) (xy 242.974368 -282.71343)
			(xy 242.98148 -282.720796) (xy 243.000276 -282.728416) (xy 243.092732 -282.728416) (xy 243.111528 -282.720796)
			(xy 243.11864 -282.71343) (xy 243.140273 -282.692459) (xy 243.188899 -282.656888) (xy 243.242513 -282.629406)
			(xy 243.299782 -282.610696) (xy 243.35928 -282.601223) (xy 243.389404 -282.600654) (xy 243.416652 -282.601216)
			(xy 243.470594 -282.608973) (xy 243.522883 -282.624327) (xy 243.572455 -282.646966) (xy 243.6183 -282.676429)
			(xy 243.659486 -282.712117) (xy 243.695173 -282.753303) (xy 243.724636 -282.799149) (xy 243.747275 -282.848721)
			(xy 243.762628 -282.90101) (xy 243.770384 -282.954952) (xy 243.770384 -283.009448) (xy 243.770383 -283.009454)
			(xy 245.24914 -283.009454) (xy 245.24914 -282.954946) (xy 245.256897 -282.900994) (xy 245.272253 -282.848695)
			(xy 245.294896 -282.799113) (xy 245.324364 -282.753258) (xy 245.360059 -282.712064) (xy 245.401252 -282.676369)
			(xy 245.447106 -282.6469) (xy 245.496687 -282.624256) (xy 245.548986 -282.608899) (xy 245.602938 -282.60114)
			(xy 245.630192 -282.600654) (xy 245.65893 -282.601195) (xy 245.715756 -282.609815) (xy 245.770646 -282.626862)
			(xy 245.822358 -282.651949) (xy 245.869722 -282.68451) (xy 245.89105 -282.703778) (xy 245.898162 -282.710382)
			(xy 245.915688 -282.717494) (xy 246.005096 -282.717494) (xy 246.022622 -282.710382) (xy 246.029734 -282.703778)
			(xy 246.051061 -282.684508) (xy 246.098424 -282.651943) (xy 246.150135 -282.626852) (xy 246.205026 -282.609802)
			(xy 246.261853 -282.60118) (xy 246.319331 -282.60118) (xy 246.376158 -282.609802) (xy 246.431049 -282.626852)
			(xy 246.48276 -282.651943) (xy 246.530123 -282.684508) (xy 246.55145 -282.703778) (xy 246.558562 -282.710382)
			(xy 246.576088 -282.717494) (xy 246.665496 -282.717494) (xy 246.683022 -282.710382) (xy 246.690134 -282.703778)
			(xy 246.71147 -282.684518) (xy 246.758829 -282.651948) (xy 246.810538 -282.626853) (xy 246.865427 -282.6098)
			(xy 246.922253 -282.601176) (xy 246.950992 -282.600654) (xy 246.981115 -282.601229) (xy 247.040612 -282.610708)
			(xy 247.097879 -282.629418) (xy 247.151497 -282.656893) (xy 247.200131 -282.692451) (xy 247.221756 -282.71343)
			(xy 247.228868 -282.720796) (xy 247.247664 -282.728416) (xy 247.34012 -282.728416) (xy 247.358916 -282.720796)
			(xy 247.366028 -282.71343) (xy 247.387666 -282.692464) (xy 247.436291 -282.656893) (xy 247.489904 -282.62941)
			(xy 247.547171 -282.610698) (xy 247.606669 -282.601224) (xy 247.636792 -282.600654) (xy 247.664043 -282.601193)
			(xy 247.717989 -282.608948) (xy 247.770283 -282.624302) (xy 247.819859 -282.646942) (xy 247.865708 -282.676406)
			(xy 247.906898 -282.712097) (xy 247.942589 -282.753285) (xy 247.972055 -282.799134) (xy 247.994695 -282.84871)
			(xy 248.01005 -282.901003) (xy 248.017807 -282.954949) (xy 248.017807 -283.009451) (xy 248.01005 -283.063397)
			(xy 247.994695 -283.11569) (xy 247.987469 -283.131514) (xy 258.01142 -283.131514) (xy 258.015491 -283.075892)
			(xy 258.027617 -283.021455) (xy 258.04754 -282.969364) (xy 258.074836 -282.920729) (xy 258.108922 -282.876586)
			(xy 258.149071 -282.837877) (xy 258.194429 -282.805426) (xy 258.244029 -282.779925) (xy 258.296813 -282.761918)
			(xy 258.351656 -282.751788) (xy 258.40739 -282.749751) (xy 258.462827 -282.755851) (xy 258.516784 -282.769957)
			(xy 258.568113 -282.791769) (xy 258.615719 -282.820823) (xy 258.658587 -282.856498) (xy 258.695804 -282.898035)
			(xy 258.726577 -282.944548) (xy 258.750249 -282.995045) (xy 258.766317 -283.048452) (xy 258.774437 -283.103628)
			(xy 258.774946 -283.131514) (xy 259.486906 -283.131514) (xy 259.490977 -283.075892) (xy 259.503103 -283.021455)
			(xy 259.523026 -282.969364) (xy 259.550322 -282.920729) (xy 259.584408 -282.876586) (xy 259.624557 -282.837877)
			(xy 259.669915 -282.805426) (xy 259.719515 -282.779925) (xy 259.772299 -282.761918) (xy 259.827142 -282.751788)
			(xy 259.882876 -282.749751) (xy 259.938313 -282.755851) (xy 259.99227 -282.769957) (xy 260.043599 -282.791769)
			(xy 260.091205 -282.820823) (xy 260.134073 -282.856498) (xy 260.17129 -282.898035) (xy 260.202063 -282.944548)
			(xy 260.225735 -282.995045) (xy 260.241803 -283.048452) (xy 260.249923 -283.103628) (xy 260.250432 -283.131514)
			(xy 260.375906 -283.131514) (xy 260.379977 -283.075892) (xy 260.392103 -283.021455) (xy 260.412026 -282.969364)
			(xy 260.439322 -282.920729) (xy 260.473408 -282.876586) (xy 260.513557 -282.837877) (xy 260.558915 -282.805426)
			(xy 260.608515 -282.779925) (xy 260.661299 -282.761918) (xy 260.716142 -282.751788) (xy 260.771876 -282.749751)
			(xy 260.827313 -282.755851) (xy 260.88127 -282.769957) (xy 260.932599 -282.791769) (xy 260.980205 -282.820823)
			(xy 261.023073 -282.856498) (xy 261.06029 -282.898035) (xy 261.091063 -282.944548) (xy 261.114735 -282.995045)
			(xy 261.130803 -283.048452) (xy 261.138923 -283.103628) (xy 261.139432 -283.131514) (xy 261.138923 -283.1594)
			(xy 261.130803 -283.214576) (xy 261.114735 -283.267983) (xy 261.091063 -283.31848) (xy 261.06029 -283.364993)
			(xy 261.023073 -283.40653) (xy 260.980205 -283.442205) (xy 260.932599 -283.471259) (xy 260.88127 -283.493071)
			(xy 260.827313 -283.507177) (xy 260.771876 -283.513277) (xy 260.716142 -283.51124) (xy 260.661299 -283.50111)
			(xy 260.608515 -283.483103) (xy 260.558915 -283.457602) (xy 260.513557 -283.425151) (xy 260.473408 -283.386442)
			(xy 260.439322 -283.342299) (xy 260.412026 -283.293664) (xy 260.392103 -283.241573) (xy 260.379977 -283.187136)
			(xy 260.375906 -283.131514) (xy 260.250432 -283.131514) (xy 260.249923 -283.1594) (xy 260.241803 -283.214576)
			(xy 260.225735 -283.267983) (xy 260.202063 -283.31848) (xy 260.17129 -283.364993) (xy 260.134073 -283.40653)
			(xy 260.091205 -283.442205) (xy 260.043599 -283.471259) (xy 259.99227 -283.493071) (xy 259.938313 -283.507177)
			(xy 259.882876 -283.513277) (xy 259.827142 -283.51124) (xy 259.772299 -283.50111) (xy 259.719515 -283.483103)
			(xy 259.669915 -283.457602) (xy 259.624557 -283.425151) (xy 259.584408 -283.386442) (xy 259.550322 -283.342299)
			(xy 259.523026 -283.293664) (xy 259.503103 -283.241573) (xy 259.490977 -283.187136) (xy 259.486906 -283.131514)
			(xy 258.774946 -283.131514) (xy 258.774437 -283.1594) (xy 258.766317 -283.214576) (xy 258.750249 -283.267983)
			(xy 258.726577 -283.31848) (xy 258.695804 -283.364993) (xy 258.658587 -283.40653) (xy 258.615719 -283.442205)
			(xy 258.568113 -283.471259) (xy 258.516784 -283.493071) (xy 258.462827 -283.507177) (xy 258.40739 -283.513277)
			(xy 258.351656 -283.51124) (xy 258.296813 -283.50111) (xy 258.244029 -283.483103) (xy 258.194429 -283.457602)
			(xy 258.149071 -283.425151) (xy 258.108922 -283.386442) (xy 258.074836 -283.342299) (xy 258.04754 -283.293664)
			(xy 258.027617 -283.241573) (xy 258.015491 -283.187136) (xy 258.01142 -283.131514) (xy 247.987469 -283.131514)
			(xy 247.972055 -283.165266) (xy 247.942589 -283.211115) (xy 247.906898 -283.252303) (xy 247.865708 -283.287994)
			(xy 247.819859 -283.317458) (xy 247.770283 -283.340098) (xy 247.717989 -283.355452) (xy 247.664043 -283.363207)
			(xy 247.636792 -283.36367) (xy 247.606669 -283.363099) (xy 247.547173 -283.353617) (xy 247.489905 -283.334906)
			(xy 247.436288 -283.30743) (xy 247.387653 -283.271872) (xy 247.366028 -283.250894) (xy 247.358916 -283.243528)
			(xy 247.34012 -283.235908) (xy 247.247664 -283.235908) (xy 247.228868 -283.243528) (xy 247.221756 -283.250894)
			(xy 247.200129 -283.271871) (xy 247.151501 -283.30744) (xy 247.097885 -283.334921) (xy 247.040615 -283.35363)
			(xy 246.981116 -283.363101) (xy 246.950992 -283.36367) (xy 246.922254 -283.363132) (xy 246.865428 -283.35451)
			(xy 246.810538 -283.337462) (xy 246.758826 -283.312375) (xy 246.711462 -283.279814) (xy 246.690134 -283.260546)
			(xy 246.683022 -283.253942) (xy 246.665496 -283.24683) (xy 246.576088 -283.24683) (xy 246.558562 -283.253942)
			(xy 246.55145 -283.260546) (xy 246.530123 -283.279816) (xy 246.48276 -283.312381) (xy 246.431049 -283.337472)
			(xy 246.376158 -283.354522) (xy 246.319331 -283.363144) (xy 246.261853 -283.363144) (xy 246.205026 -283.354522)
			(xy 246.150135 -283.337472) (xy 246.098424 -283.312381) (xy 246.051061 -283.279816) (xy 246.029734 -283.260546)
			(xy 246.022622 -283.253942) (xy 246.005096 -283.24683) (xy 245.915688 -283.24683) (xy 245.898162 -283.253942)
			(xy 245.89105 -283.260546) (xy 245.869724 -283.279818) (xy 245.822362 -283.312385) (xy 245.77065 -283.337477)
			(xy 245.715759 -283.354527) (xy 245.658931 -283.36315) (xy 245.630192 -283.36367) (xy 245.602938 -283.36326)
			(xy 245.548986 -283.355501) (xy 245.496687 -283.340144) (xy 245.447106 -283.3175) (xy 245.401252 -283.288031)
			(xy 245.360059 -283.252336) (xy 245.324364 -283.211142) (xy 245.294896 -283.165287) (xy 245.272253 -283.115705)
			(xy 245.256897 -283.063406) (xy 245.24914 -283.009454) (xy 243.770383 -283.009454) (xy 243.762628 -283.06339)
			(xy 243.747275 -283.115679) (xy 243.724636 -283.165251) (xy 243.695173 -283.211097) (xy 243.659486 -283.252283)
			(xy 243.6183 -283.287971) (xy 243.572455 -283.317434) (xy 243.522883 -283.340073) (xy 243.470594 -283.355427)
			(xy 243.416652 -283.363184) (xy 243.389404 -283.36367) (xy 243.359281 -283.363091) (xy 243.299785 -283.353611)
			(xy 243.242518 -283.334902) (xy 243.1889 -283.307428) (xy 243.140265 -283.271872) (xy 243.11864 -283.250894)
			(xy 243.111528 -283.243528) (xy 243.092732 -283.235908) (xy 243.000276 -283.235908) (xy 242.98148 -283.243528)
			(xy 242.974368 -283.250894) (xy 242.952735 -283.271866) (xy 242.904109 -283.307435) (xy 242.850494 -283.334917)
			(xy 242.793226 -283.353627) (xy 242.733728 -283.363101) (xy 242.703604 -283.36367) (xy 242.674866 -283.363125)
			(xy 242.618041 -283.354505) (xy 242.563151 -283.337459) (xy 242.511439 -283.312372) (xy 242.464074 -283.279813)
			(xy 242.442746 -283.260546) (xy 242.435634 -283.253942) (xy 242.418108 -283.24683) (xy 242.3287 -283.24683)
			(xy 242.311174 -283.253942) (xy 242.304062 -283.260546) (xy 242.282735 -283.279816) (xy 242.235372 -283.312381)
			(xy 242.183661 -283.337472) (xy 242.12877 -283.354522) (xy 242.071943 -283.363144) (xy 242.014465 -283.363144)
			(xy 241.957638 -283.354522) (xy 241.902747 -283.337472) (xy 241.851036 -283.312381) (xy 241.803673 -283.279816)
			(xy 241.782346 -283.260546) (xy 241.775234 -283.253942) (xy 241.757708 -283.24683) (xy 241.6683 -283.24683)
			(xy 241.650774 -283.253942) (xy 241.643662 -283.260546) (xy 241.622331 -283.279812) (xy 241.57497 -283.31238)
			(xy 241.52326 -283.337473) (xy 241.46837 -283.354525) (xy 241.411543 -283.363149) (xy 241.382804 -283.36367)
			(xy 241.355548 -283.363283) (xy 241.301591 -283.355526) (xy 241.249288 -283.340169) (xy 241.199702 -283.317524)
			(xy 241.153844 -283.288053) (xy 241.112647 -283.252356) (xy 241.076949 -283.211159) (xy 241.047478 -283.165301)
			(xy 241.024833 -283.115716) (xy 241.009475 -283.063412) (xy 241.001717 -283.009456) (xy 231.767583 -283.009456)
			(xy 231.759829 -283.063386) (xy 231.744477 -283.115673) (xy 231.721841 -283.165243) (xy 231.692381 -283.211087)
			(xy 231.656696 -283.252272) (xy 231.615514 -283.28796) (xy 231.569673 -283.317425) (xy 231.520105 -283.340065)
			(xy 231.46782 -283.355422) (xy 231.413881 -283.363181) (xy 231.386634 -283.36367) (xy 231.356512 -283.363072)
			(xy 231.297017 -283.353597) (xy 231.239749 -283.334892) (xy 231.186132 -283.307422) (xy 231.137496 -283.27187)
			(xy 231.11587 -283.250894) (xy 231.108758 -283.243528) (xy 231.089962 -283.235908) (xy 230.997506 -283.235908)
			(xy 230.97871 -283.243528) (xy 230.971598 -283.250894) (xy 230.949996 -283.271899) (xy 230.901361 -283.307465)
			(xy 230.847739 -283.33494) (xy 230.790464 -283.353642) (xy 230.73096 -283.363106) (xy 230.700834 -283.36367)
			(xy 230.672095 -283.363168) (xy 230.615267 -283.354537) (xy 230.560377 -283.337481) (xy 230.508666 -283.312385)
			(xy 230.461303 -283.279817) (xy 230.439976 -283.260546) (xy 230.432864 -283.253942) (xy 230.415338 -283.24683)
			(xy 230.32593 -283.24683) (xy 230.308404 -283.253942) (xy 230.301292 -283.260546) (xy 230.279965 -283.279816)
			(xy 230.232602 -283.312381) (xy 230.180891 -283.337472) (xy 230.126 -283.354522) (xy 230.069173 -283.363144)
			(xy 230.011695 -283.363144) (xy 229.954868 -283.354522) (xy 229.899977 -283.337472) (xy 229.848266 -283.312381)
			(xy 229.800903 -283.279816) (xy 229.779576 -283.260546) (xy 229.772464 -283.253942) (xy 229.754938 -283.24683)
			(xy 229.66553 -283.24683) (xy 229.648004 -283.253942) (xy 229.640892 -283.260546) (xy 229.619549 -283.279798)
			(xy 229.572191 -283.312367) (xy 229.520484 -283.337464) (xy 229.465597 -283.354519) (xy 229.408772 -283.363147)
			(xy 229.380034 -283.36367) (xy 229.352777 -283.363285) (xy 229.298817 -283.355532) (xy 229.24651 -283.340177)
			(xy 229.19692 -283.317534) (xy 229.151058 -283.288064) (xy 229.109857 -283.252367) (xy 229.074156 -283.211169)
			(xy 229.044682 -283.16531) (xy 229.022035 -283.115722) (xy 229.006676 -283.063416) (xy 228.998917 -283.009457)
			(xy 227.520259 -283.009457) (xy 227.512504 -283.063401) (xy 227.49715 -283.115697) (xy 227.47451 -283.165276)
			(xy 227.445045 -283.211129) (xy 227.409355 -283.252322) (xy 227.368166 -283.288017) (xy 227.322317 -283.317488)
			(xy 227.27274 -283.340134) (xy 227.220446 -283.355494) (xy 227.166498 -283.363257) (xy 227.139246 -283.36367)
			(xy 227.109121 -283.363104) (xy 227.049619 -283.353638) (xy 226.992345 -283.334934) (xy 226.938725 -283.307456)
			(xy 226.890093 -283.27189) (xy 226.868482 -283.250894) (xy 226.86137 -283.243528) (xy 226.842574 -283.235908)
			(xy 226.750118 -283.235908) (xy 226.731322 -283.243528) (xy 226.72421 -283.250894) (xy 226.702584 -283.271869)
			(xy 226.653947 -283.307419) (xy 226.600329 -283.334886) (xy 226.543062 -283.353587) (xy 226.483568 -283.363059)
			(xy 226.453446 -283.36367) (xy 226.424706 -283.363152) (xy 226.367875 -283.354535) (xy 226.312981 -283.337489)
			(xy 226.261265 -283.3124) (xy 226.213899 -283.279836) (xy 226.192588 -283.260546) (xy 226.185476 -283.253942)
			(xy 226.16795 -283.24683) (xy 226.078542 -283.24683) (xy 226.061016 -283.253942) (xy 226.053904 -283.260546)
			(xy 226.032577 -283.279816) (xy 225.985214 -283.312381) (xy 225.933503 -283.337472) (xy 225.878612 -283.354522)
			(xy 225.821785 -283.363144) (xy 225.764307 -283.363144) (xy 225.70748 -283.354522) (xy 225.652589 -283.337472)
			(xy 225.600878 -283.312381) (xy 225.553515 -283.279816) (xy 225.532188 -283.260546) (xy 225.525076 -283.253942)
			(xy 225.50755 -283.24683) (xy 225.418142 -283.24683) (xy 225.400616 -283.253942) (xy 225.393504 -283.260546)
			(xy 225.372177 -283.279816) (xy 225.324814 -283.312381) (xy 225.273102 -283.337475) (xy 225.218212 -283.354528)
			(xy 225.161385 -283.363156) (xy 225.132646 -283.36367) (xy 225.105663 -283.363207) (xy 225.052234 -283.355609)
			(xy 225.000409 -283.34056) (xy 224.951222 -283.318359) (xy 224.905653 -283.289448) (xy 224.864612 -283.254406)
			(xy 224.828918 -283.21393) (xy 224.799283 -283.168829) (xy 224.776298 -283.120003) (xy 224.760423 -283.068425)
			(xy 224.75571 -283.041852) (xy 224.753678 -283.027628) (xy 224.735136 -283.005784) (xy 224.635314 -282.973526)
			(xy 224.62631 -282.971021) (xy 224.607664 -282.971998) (xy 224.590629 -282.979642) (xy 224.583752 -282.985972)
			(xy 224.192084 -283.37764) (xy 224.169357 -283.399637) (xy 224.119151 -283.438108) (xy 224.064353 -283.469695)
			(xy 224.005901 -283.49386) (xy 223.944794 -283.510187) (xy 223.882079 -283.518399) (xy 223.850454 -283.518864)
			(xy 215.650826 -283.518864) (xy 215.640836 -283.519396) (xy 215.622393 -283.527099) (xy 215.615012 -283.53385)
			(xy 215.255348 -283.893514) (xy 263.537954 -283.893514) (xy 263.53852 -283.864133) (xy 263.547548 -283.806068)
			(xy 263.565376 -283.750075) (xy 263.591583 -283.69748) (xy 263.625547 -283.649528) (xy 263.666466 -283.607354)
			(xy 263.689592 -283.589222) (xy 263.69899 -283.581856) (xy 263.709404 -283.561282) (xy 263.710928 -283.457396)
			(xy 263.701022 -283.436314) (xy 263.691878 -283.428948) (xy 263.670018 -283.410756) (xy 263.63148 -283.368933)
			(xy 263.599575 -283.321855) (xy 263.57501 -283.270563) (xy 263.558329 -283.216193) (xy 263.549902 -283.15995)
			(xy 263.549384 -283.131514) (xy 263.54987 -283.104263) (xy 263.557626 -283.050315) (xy 263.572981 -282.99802)
			(xy 263.595623 -282.948443) (xy 263.625089 -282.902593) (xy 263.66078 -282.861402) (xy 263.701971 -282.825711)
			(xy 263.747821 -282.796245) (xy 263.797398 -282.773603) (xy 263.849693 -282.758248) (xy 263.903641 -282.750492)
			(xy 263.958143 -282.750492) (xy 264.012091 -282.758248) (xy 264.064386 -282.773603) (xy 264.113963 -282.796245)
			(xy 264.159813 -282.825711) (xy 264.201004 -282.861402) (xy 264.236695 -282.902593) (xy 264.266161 -282.948443)
			(xy 264.288803 -282.99802) (xy 264.304158 -283.050315) (xy 264.307689 -283.074872) (xy 268.26897 -283.074872)
			(xy 268.27293 -283.025818) (xy 268.284707 -282.978034) (xy 268.303998 -282.932758) (xy 268.330301 -282.891162)
			(xy 268.362936 -282.854325) (xy 268.401057 -282.8232) (xy 268.443678 -282.798593) (xy 268.489694 -282.781141)
			(xy 268.537913 -282.771297) (xy 268.587088 -282.769316) (xy 268.635943 -282.775248) (xy 268.683214 -282.78894)
			(xy 268.727676 -282.810038) (xy 268.768179 -282.837994) (xy 268.803672 -282.872086) (xy 268.833237 -282.91143)
			(xy 268.856108 -282.955007) (xy 268.871692 -283.001688) (xy 268.879587 -283.050265) (xy 268.880082 -283.074872)
			(xy 269.21893 -283.074872) (xy 269.22289 -283.025818) (xy 269.234667 -282.978034) (xy 269.253958 -282.932758)
			(xy 269.280261 -282.891162) (xy 269.312896 -282.854325) (xy 269.351017 -282.8232) (xy 269.393638 -282.798593)
			(xy 269.439654 -282.781141) (xy 269.487873 -282.771297) (xy 269.537048 -282.769316) (xy 269.585903 -282.775248)
			(xy 269.633174 -282.78894) (xy 269.677636 -282.810038) (xy 269.718139 -282.837994) (xy 269.753632 -282.872086)
			(xy 269.783197 -282.91143) (xy 269.806068 -282.955007) (xy 269.821652 -283.001688) (xy 269.829547 -283.050265)
			(xy 269.830042 -283.074872) (xy 270.169144 -283.074872) (xy 270.173104 -283.025818) (xy 270.184881 -282.978034)
			(xy 270.204172 -282.932758) (xy 270.230475 -282.891162) (xy 270.26311 -282.854325) (xy 270.301231 -282.8232)
			(xy 270.343852 -282.798593) (xy 270.389868 -282.781141) (xy 270.438087 -282.771297) (xy 270.487262 -282.769316)
			(xy 270.536117 -282.775248) (xy 270.583388 -282.78894) (xy 270.62785 -282.810038) (xy 270.668353 -282.837994)
			(xy 270.703846 -282.872086) (xy 270.733411 -282.91143) (xy 270.756282 -282.955007) (xy 270.771866 -283.001688)
			(xy 270.779761 -283.050265) (xy 270.780256 -283.074872) (xy 271.119104 -283.074872) (xy 271.123064 -283.025818)
			(xy 271.134841 -282.978034) (xy 271.154132 -282.932758) (xy 271.180435 -282.891162) (xy 271.21307 -282.854325)
			(xy 271.251191 -282.8232) (xy 271.293812 -282.798593) (xy 271.339828 -282.781141) (xy 271.388047 -282.771297)
			(xy 271.437222 -282.769316) (xy 271.486077 -282.775248) (xy 271.533348 -282.78894) (xy 271.57781 -282.810038)
			(xy 271.618313 -282.837994) (xy 271.653806 -282.872086) (xy 271.683371 -282.91143) (xy 271.706242 -282.955007)
			(xy 271.721826 -283.001688) (xy 271.729721 -283.050265) (xy 271.730216 -283.074872) (xy 272.069064 -283.074872)
			(xy 272.073024 -283.025818) (xy 272.084801 -282.978034) (xy 272.104092 -282.932758) (xy 272.130395 -282.891162)
			(xy 272.16303 -282.854325) (xy 272.201151 -282.8232) (xy 272.243772 -282.798593) (xy 272.289788 -282.781141)
			(xy 272.338007 -282.771297) (xy 272.387182 -282.769316) (xy 272.436037 -282.775248) (xy 272.483308 -282.78894)
			(xy 272.52777 -282.810038) (xy 272.568273 -282.837994) (xy 272.603766 -282.872086) (xy 272.633331 -282.91143)
			(xy 272.656202 -282.955007) (xy 272.671786 -283.001688) (xy 272.679681 -283.050265) (xy 272.680176 -283.074872)
			(xy 273.019024 -283.074872) (xy 273.022984 -283.025818) (xy 273.034761 -282.978034) (xy 273.054052 -282.932758)
			(xy 273.080355 -282.891162) (xy 273.11299 -282.854325) (xy 273.151111 -282.8232) (xy 273.193732 -282.798593)
			(xy 273.239748 -282.781141) (xy 273.287967 -282.771297) (xy 273.337142 -282.769316) (xy 273.385997 -282.775248)
			(xy 273.433268 -282.78894) (xy 273.47773 -282.810038) (xy 273.518233 -282.837994) (xy 273.553726 -282.872086)
			(xy 273.583291 -282.91143) (xy 273.606162 -282.955007) (xy 273.621746 -283.001688) (xy 273.629641 -283.050265)
			(xy 273.630136 -283.074872) (xy 273.968984 -283.074872) (xy 273.972944 -283.025818) (xy 273.984721 -282.978034)
			(xy 274.004012 -282.932758) (xy 274.030315 -282.891162) (xy 274.06295 -282.854325) (xy 274.101071 -282.8232)
			(xy 274.143692 -282.798593) (xy 274.189708 -282.781141) (xy 274.237927 -282.771297) (xy 274.287102 -282.769316)
			(xy 274.335957 -282.775248) (xy 274.383228 -282.78894) (xy 274.42769 -282.810038) (xy 274.468193 -282.837994)
			(xy 274.503686 -282.872086) (xy 274.533251 -282.91143) (xy 274.556122 -282.955007) (xy 274.571706 -283.001688)
			(xy 274.579601 -283.050265) (xy 274.580096 -283.074872) (xy 274.918944 -283.074872) (xy 274.922904 -283.025818)
			(xy 274.934681 -282.978034) (xy 274.953972 -282.932758) (xy 274.980275 -282.891162) (xy 275.01291 -282.854325)
			(xy 275.051031 -282.8232) (xy 275.093652 -282.798593) (xy 275.139668 -282.781141) (xy 275.187887 -282.771297)
			(xy 275.237062 -282.769316) (xy 275.285917 -282.775248) (xy 275.333188 -282.78894) (xy 275.37765 -282.810038)
			(xy 275.418153 -282.837994) (xy 275.453646 -282.872086) (xy 275.483211 -282.91143) (xy 275.506082 -282.955007)
			(xy 275.521666 -283.001688) (xy 275.529561 -283.050265) (xy 275.530056 -283.074872) (xy 275.868904 -283.074872)
			(xy 275.872864 -283.025818) (xy 275.884641 -282.978034) (xy 275.903932 -282.932758) (xy 275.930235 -282.891162)
			(xy 275.96287 -282.854325) (xy 276.000991 -282.8232) (xy 276.043612 -282.798593) (xy 276.089628 -282.781141)
			(xy 276.137847 -282.771297) (xy 276.187022 -282.769316) (xy 276.235877 -282.775248) (xy 276.283148 -282.78894)
			(xy 276.32761 -282.810038) (xy 276.368113 -282.837994) (xy 276.403606 -282.872086) (xy 276.433171 -282.91143)
			(xy 276.456042 -282.955007) (xy 276.471626 -283.001688) (xy 276.479521 -283.050265) (xy 276.480016 -283.074872)
			(xy 276.819118 -283.074872) (xy 276.823078 -283.025818) (xy 276.834855 -282.978034) (xy 276.854146 -282.932758)
			(xy 276.880449 -282.891162) (xy 276.913084 -282.854325) (xy 276.951205 -282.8232) (xy 276.993826 -282.798593)
			(xy 277.039842 -282.781141) (xy 277.088061 -282.771297) (xy 277.137236 -282.769316) (xy 277.186091 -282.775248)
			(xy 277.233362 -282.78894) (xy 277.277824 -282.810038) (xy 277.318327 -282.837994) (xy 277.35382 -282.872086)
			(xy 277.383385 -282.91143) (xy 277.406256 -282.955007) (xy 277.42184 -283.001688) (xy 277.429735 -283.050265)
			(xy 277.43023 -283.074872) (xy 277.769078 -283.074872) (xy 277.773038 -283.025818) (xy 277.784815 -282.978034)
			(xy 277.804106 -282.932758) (xy 277.830409 -282.891162) (xy 277.863044 -282.854325) (xy 277.901165 -282.8232)
			(xy 277.943786 -282.798593) (xy 277.989802 -282.781141) (xy 278.038021 -282.771297) (xy 278.087196 -282.769316)
			(xy 278.136051 -282.775248) (xy 278.183322 -282.78894) (xy 278.227784 -282.810038) (xy 278.268287 -282.837994)
			(xy 278.30378 -282.872086) (xy 278.333345 -282.91143) (xy 278.356216 -282.955007) (xy 278.3718 -283.001688)
			(xy 278.379695 -283.050265) (xy 278.38019 -283.074872) (xy 278.719038 -283.074872) (xy 278.722998 -283.025818)
			(xy 278.734775 -282.978034) (xy 278.754066 -282.932758) (xy 278.780369 -282.891162) (xy 278.813004 -282.854325)
			(xy 278.851125 -282.8232) (xy 278.893746 -282.798593) (xy 278.939762 -282.781141) (xy 278.987981 -282.771297)
			(xy 279.037156 -282.769316) (xy 279.086011 -282.775248) (xy 279.133282 -282.78894) (xy 279.177744 -282.810038)
			(xy 279.218247 -282.837994) (xy 279.25374 -282.872086) (xy 279.283305 -282.91143) (xy 279.306176 -282.955007)
			(xy 279.32176 -283.001688) (xy 279.329655 -283.050265) (xy 279.33015 -283.074872) (xy 279.668998 -283.074872)
			(xy 279.672958 -283.025818) (xy 279.684735 -282.978034) (xy 279.704026 -282.932758) (xy 279.730329 -282.891162)
			(xy 279.762964 -282.854325) (xy 279.801085 -282.8232) (xy 279.843706 -282.798593) (xy 279.889722 -282.781141)
			(xy 279.937941 -282.771297) (xy 279.987116 -282.769316) (xy 280.035971 -282.775248) (xy 280.083242 -282.78894)
			(xy 280.127704 -282.810038) (xy 280.168207 -282.837994) (xy 280.2037 -282.872086) (xy 280.233265 -282.91143)
			(xy 280.256136 -282.955007) (xy 280.27172 -283.001688) (xy 280.279615 -283.050265) (xy 280.28011 -283.074872)
			(xy 280.618958 -283.074872) (xy 280.622918 -283.025818) (xy 280.634695 -282.978034) (xy 280.653986 -282.932758)
			(xy 280.680289 -282.891162) (xy 280.712924 -282.854325) (xy 280.751045 -282.8232) (xy 280.793666 -282.798593)
			(xy 280.839682 -282.781141) (xy 280.887901 -282.771297) (xy 280.937076 -282.769316) (xy 280.985931 -282.775248)
			(xy 281.033202 -282.78894) (xy 281.077664 -282.810038) (xy 281.118167 -282.837994) (xy 281.15366 -282.872086)
			(xy 281.183225 -282.91143) (xy 281.206096 -282.955007) (xy 281.22168 -283.001688) (xy 281.229575 -283.050265)
			(xy 281.23007 -283.074872) (xy 281.568918 -283.074872) (xy 281.572878 -283.025818) (xy 281.584655 -282.978034)
			(xy 281.603946 -282.932758) (xy 281.630249 -282.891162) (xy 281.662884 -282.854325) (xy 281.701005 -282.8232)
			(xy 281.743626 -282.798593) (xy 281.789642 -282.781141) (xy 281.837861 -282.771297) (xy 281.887036 -282.769316)
			(xy 281.935891 -282.775248) (xy 281.983162 -282.78894) (xy 282.027624 -282.810038) (xy 282.068127 -282.837994)
			(xy 282.10362 -282.872086) (xy 282.133185 -282.91143) (xy 282.156056 -282.955007) (xy 282.17164 -283.001688)
			(xy 282.179535 -283.050265) (xy 282.18003 -283.074872) (xy 282.519132 -283.074872) (xy 282.523092 -283.025818)
			(xy 282.534869 -282.978034) (xy 282.55416 -282.932758) (xy 282.580463 -282.891162) (xy 282.613098 -282.854325)
			(xy 282.651219 -282.8232) (xy 282.69384 -282.798593) (xy 282.739856 -282.781141) (xy 282.788075 -282.771297)
			(xy 282.83725 -282.769316) (xy 282.886105 -282.775248) (xy 282.933376 -282.78894) (xy 282.977838 -282.810038)
			(xy 283.018341 -282.837994) (xy 283.053834 -282.872086) (xy 283.083399 -282.91143) (xy 283.10627 -282.955007)
			(xy 283.121854 -283.001688) (xy 283.129749 -283.050265) (xy 283.130244 -283.074872) (xy 283.469092 -283.074872)
			(xy 283.473052 -283.025818) (xy 283.484829 -282.978034) (xy 283.50412 -282.932758) (xy 283.530423 -282.891162)
			(xy 283.563058 -282.854325) (xy 283.601179 -282.8232) (xy 283.6438 -282.798593) (xy 283.689816 -282.781141)
			(xy 283.738035 -282.771297) (xy 283.78721 -282.769316) (xy 283.836065 -282.775248) (xy 283.883336 -282.78894)
			(xy 283.927798 -282.810038) (xy 283.968301 -282.837994) (xy 284.003794 -282.872086) (xy 284.033359 -282.91143)
			(xy 284.05623 -282.955007) (xy 284.071814 -283.001688) (xy 284.079709 -283.050265) (xy 284.080204 -283.074872)
			(xy 284.419052 -283.074872) (xy 284.423012 -283.025818) (xy 284.434789 -282.978034) (xy 284.45408 -282.932758)
			(xy 284.480383 -282.891162) (xy 284.513018 -282.854325) (xy 284.551139 -282.8232) (xy 284.59376 -282.798593)
			(xy 284.639776 -282.781141) (xy 284.687995 -282.771297) (xy 284.73717 -282.769316) (xy 284.786025 -282.775248)
			(xy 284.833296 -282.78894) (xy 284.877758 -282.810038) (xy 284.918261 -282.837994) (xy 284.953754 -282.872086)
			(xy 284.983319 -282.91143) (xy 285.00619 -282.955007) (xy 285.021774 -283.001688) (xy 285.029669 -283.050265)
			(xy 285.030164 -283.074872) (xy 285.369012 -283.074872) (xy 285.372972 -283.025818) (xy 285.384749 -282.978034)
			(xy 285.40404 -282.932758) (xy 285.430343 -282.891162) (xy 285.462978 -282.854325) (xy 285.501099 -282.8232)
			(xy 285.54372 -282.798593) (xy 285.589736 -282.781141) (xy 285.637955 -282.771297) (xy 285.68713 -282.769316)
			(xy 285.735985 -282.775248) (xy 285.783256 -282.78894) (xy 285.827718 -282.810038) (xy 285.868221 -282.837994)
			(xy 285.903714 -282.872086) (xy 285.933279 -282.91143) (xy 285.95615 -282.955007) (xy 285.971734 -283.001688)
			(xy 285.979629 -283.050265) (xy 285.979958 -283.066643) (xy 286.319052 -283.066643) (xy 286.324416 -283.017287)
			(xy 286.337694 -282.969449) (xy 286.358536 -282.92439) (xy 286.386394 -282.883296) (xy 286.420533 -282.84725)
			(xy 286.460053 -282.817202) (xy 286.503915 -282.793944) (xy 286.550961 -282.778088) (xy 286.599953 -282.770052)
			(xy 286.624776 -282.769564) (xy 286.638959 -282.769744) (xy 286.667199 -282.772414) (xy 286.681164 -282.774898)
			(xy 286.69361 -282.777184) (xy 286.717232 -282.769818) (xy 286.794702 -282.692348) (xy 286.802068 -282.668726)
			(xy 286.799782 -282.65628) (xy 286.797307 -282.642314) (xy 286.794634 -282.614074) (xy 286.794448 -282.599892)
			(xy 286.79497 -282.574637) (xy 286.803283 -282.524815) (xy 286.819684 -282.477041) (xy 286.843725 -282.432618)
			(xy 286.874749 -282.392758) (xy 286.911911 -282.358548) (xy 286.954197 -282.330922) (xy 287.000453 -282.310632)
			(xy 287.049418 -282.298232) (xy 287.099756 -282.294061) (xy 287.150094 -282.298232) (xy 287.199059 -282.310632)
			(xy 287.245315 -282.330922) (xy 287.287601 -282.358548) (xy 287.324763 -282.392758) (xy 287.355787 -282.432618)
			(xy 287.379828 -282.477041) (xy 287.396229 -282.524815) (xy 287.404542 -282.574637) (xy 287.405064 -282.599892)
			(xy 306.743874 -282.599892) (xy 306.747834 -282.550838) (xy 306.759611 -282.503054) (xy 306.778902 -282.457778)
			(xy 306.805205 -282.416182) (xy 306.83784 -282.379345) (xy 306.875961 -282.34822) (xy 306.918582 -282.323613)
			(xy 306.964598 -282.306161) (xy 307.012817 -282.296317) (xy 307.061992 -282.294336) (xy 307.110847 -282.300268)
			(xy 307.158118 -282.31396) (xy 307.20258 -282.335058) (xy 307.243083 -282.363014) (xy 307.278576 -282.397106)
			(xy 307.308141 -282.43645) (xy 307.331012 -282.480027) (xy 307.346596 -282.526708) (xy 307.354491 -282.575285)
			(xy 307.354986 -282.599892) (xy 307.354491 -282.624499) (xy 307.354312 -282.6256) (xy 308.623204 -282.6256)
			(xy 308.623204 -282.574184) (xy 308.631247 -282.523402) (xy 308.647135 -282.474503) (xy 308.670478 -282.428691)
			(xy 308.700699 -282.387095) (xy 308.737055 -282.350739) (xy 308.778651 -282.320518) (xy 308.824463 -282.297175)
			(xy 308.873362 -282.281287) (xy 308.924144 -282.273244) (xy 308.97556 -282.273244) (xy 309.026342 -282.281287)
			(xy 309.075241 -282.297175) (xy 309.121053 -282.320518) (xy 309.162649 -282.350739) (xy 309.199005 -282.387095)
			(xy 309.229226 -282.428691) (xy 309.252569 -282.474503) (xy 309.268457 -282.523402) (xy 309.2765 -282.574184)
			(xy 309.277004 -282.599892) (xy 309.2765 -282.6256) (xy 309.573164 -282.6256) (xy 309.573164 -282.574184)
			(xy 309.581207 -282.523402) (xy 309.597095 -282.474503) (xy 309.620438 -282.428691) (xy 309.650659 -282.387095)
			(xy 309.687015 -282.350739) (xy 309.728611 -282.320518) (xy 309.774423 -282.297175) (xy 309.823322 -282.281287)
			(xy 309.874104 -282.273244) (xy 309.92552 -282.273244) (xy 309.976302 -282.281287) (xy 310.025201 -282.297175)
			(xy 310.071013 -282.320518) (xy 310.112609 -282.350739) (xy 310.148965 -282.387095) (xy 310.179186 -282.428691)
			(xy 310.202529 -282.474503) (xy 310.218417 -282.523402) (xy 310.22646 -282.574184) (xy 310.226964 -282.599892)
			(xy 310.543968 -282.599892) (xy 310.547928 -282.550838) (xy 310.559705 -282.503054) (xy 310.578996 -282.457778)
			(xy 310.605299 -282.416182) (xy 310.637934 -282.379345) (xy 310.676055 -282.34822) (xy 310.718676 -282.323613)
			(xy 310.764692 -282.306161) (xy 310.812911 -282.296317) (xy 310.862086 -282.294336) (xy 310.910941 -282.300268)
			(xy 310.958212 -282.31396) (xy 311.002674 -282.335058) (xy 311.043177 -282.363014) (xy 311.07867 -282.397106)
			(xy 311.108235 -282.43645) (xy 311.131106 -282.480027) (xy 311.14669 -282.526708) (xy 311.154585 -282.575285)
			(xy 311.15508 -282.599892) (xy 311.154585 -282.624499) (xy 311.154406 -282.6256) (xy 311.473084 -282.6256)
			(xy 311.473084 -282.574184) (xy 311.481127 -282.523402) (xy 311.497015 -282.474503) (xy 311.520358 -282.428691)
			(xy 311.550579 -282.387095) (xy 311.586935 -282.350739) (xy 311.628531 -282.320518) (xy 311.674343 -282.297175)
			(xy 311.723242 -282.281287) (xy 311.774024 -282.273244) (xy 311.82544 -282.273244) (xy 311.876222 -282.281287)
			(xy 311.925121 -282.297175) (xy 311.970933 -282.320518) (xy 312.012529 -282.350739) (xy 312.048885 -282.387095)
			(xy 312.079106 -282.428691) (xy 312.102449 -282.474503) (xy 312.118337 -282.523402) (xy 312.12638 -282.574184)
			(xy 312.126884 -282.599892) (xy 312.12638 -282.6256) (xy 312.423044 -282.6256) (xy 312.423044 -282.574184)
			(xy 312.431087 -282.523402) (xy 312.446975 -282.474503) (xy 312.470318 -282.428691) (xy 312.500539 -282.387095)
			(xy 312.536895 -282.350739) (xy 312.578491 -282.320518) (xy 312.624303 -282.297175) (xy 312.673202 -282.281287)
			(xy 312.723984 -282.273244) (xy 312.7754 -282.273244) (xy 312.826182 -282.281287) (xy 312.875081 -282.297175)
			(xy 312.920893 -282.320518) (xy 312.962489 -282.350739) (xy 312.998845 -282.387095) (xy 313.029066 -282.428691)
			(xy 313.052409 -282.474503) (xy 313.068297 -282.523402) (xy 313.07634 -282.574184) (xy 313.076844 -282.599892)
			(xy 313.394102 -282.599892) (xy 313.398062 -282.550838) (xy 313.409839 -282.503054) (xy 313.42913 -282.457778)
			(xy 313.455433 -282.416182) (xy 313.488068 -282.379345) (xy 313.526189 -282.34822) (xy 313.56881 -282.323613)
			(xy 313.614826 -282.306161) (xy 313.663045 -282.296317) (xy 313.71222 -282.294336) (xy 313.761075 -282.300268)
			(xy 313.808346 -282.31396) (xy 313.852808 -282.335058) (xy 313.893311 -282.363014) (xy 313.928804 -282.397106)
			(xy 313.958369 -282.43645) (xy 313.98124 -282.480027) (xy 313.996824 -282.526708) (xy 314.004719 -282.575285)
			(xy 314.005214 -282.599892) (xy 314.344062 -282.599892) (xy 314.348022 -282.550838) (xy 314.359799 -282.503054)
			(xy 314.37909 -282.457778) (xy 314.405393 -282.416182) (xy 314.438028 -282.379345) (xy 314.476149 -282.34822)
			(xy 314.51877 -282.323613) (xy 314.564786 -282.306161) (xy 314.613005 -282.296317) (xy 314.66218 -282.294336)
			(xy 314.711035 -282.300268) (xy 314.758306 -282.31396) (xy 314.802768 -282.335058) (xy 314.843271 -282.363014)
			(xy 314.878764 -282.397106) (xy 314.908329 -282.43645) (xy 314.9312 -282.480027) (xy 314.946784 -282.526708)
			(xy 314.954679 -282.575285) (xy 314.955174 -282.599892) (xy 314.954679 -282.624499) (xy 314.946784 -282.673076)
			(xy 314.9312 -282.719757) (xy 314.908329 -282.763334) (xy 314.878764 -282.802678) (xy 314.843271 -282.83677)
			(xy 314.802768 -282.864726) (xy 314.758306 -282.885824) (xy 314.711035 -282.899516) (xy 314.66218 -282.905448)
			(xy 314.613005 -282.903467) (xy 314.564786 -282.893623) (xy 314.51877 -282.876171) (xy 314.476149 -282.851564)
			(xy 314.438028 -282.820439) (xy 314.405393 -282.783602) (xy 314.37909 -282.742006) (xy 314.359799 -282.69673)
			(xy 314.348022 -282.648946) (xy 314.344062 -282.599892) (xy 314.005214 -282.599892) (xy 314.004719 -282.624499)
			(xy 313.996824 -282.673076) (xy 313.98124 -282.719757) (xy 313.958369 -282.763334) (xy 313.928804 -282.802678)
			(xy 313.893311 -282.83677) (xy 313.852808 -282.864726) (xy 313.808346 -282.885824) (xy 313.761075 -282.899516)
			(xy 313.71222 -282.905448) (xy 313.663045 -282.903467) (xy 313.614826 -282.893623) (xy 313.56881 -282.876171)
			(xy 313.526189 -282.851564) (xy 313.488068 -282.820439) (xy 313.455433 -282.783602) (xy 313.42913 -282.742006)
			(xy 313.409839 -282.69673) (xy 313.398062 -282.648946) (xy 313.394102 -282.599892) (xy 313.076844 -282.599892)
			(xy 313.07634 -282.6256) (xy 313.068297 -282.676382) (xy 313.052409 -282.725281) (xy 313.029066 -282.771093)
			(xy 312.998845 -282.812689) (xy 312.962489 -282.849045) (xy 312.920893 -282.879266) (xy 312.875081 -282.902609)
			(xy 312.826182 -282.918497) (xy 312.7754 -282.92654) (xy 312.723984 -282.92654) (xy 312.673202 -282.918497)
			(xy 312.624303 -282.902609) (xy 312.578491 -282.879266) (xy 312.536895 -282.849045) (xy 312.500539 -282.812689)
			(xy 312.470318 -282.771093) (xy 312.446975 -282.725281) (xy 312.431087 -282.676382) (xy 312.423044 -282.6256)
			(xy 312.12638 -282.6256) (xy 312.118337 -282.676382) (xy 312.102449 -282.725281) (xy 312.079106 -282.771093)
			(xy 312.048885 -282.812689) (xy 312.012529 -282.849045) (xy 311.970933 -282.879266) (xy 311.925121 -282.902609)
			(xy 311.876222 -282.918497) (xy 311.82544 -282.92654) (xy 311.774024 -282.92654) (xy 311.723242 -282.918497)
			(xy 311.674343 -282.902609) (xy 311.628531 -282.879266) (xy 311.586935 -282.849045) (xy 311.550579 -282.812689)
			(xy 311.520358 -282.771093) (xy 311.497015 -282.725281) (xy 311.481127 -282.676382) (xy 311.473084 -282.6256)
			(xy 311.154406 -282.6256) (xy 311.14669 -282.673076) (xy 311.131106 -282.719757) (xy 311.108235 -282.763334)
			(xy 311.07867 -282.802678) (xy 311.043177 -282.83677) (xy 311.002674 -282.864726) (xy 310.958212 -282.885824)
			(xy 310.910941 -282.899516) (xy 310.862086 -282.905448) (xy 310.812911 -282.903467) (xy 310.764692 -282.893623)
			(xy 310.718676 -282.876171) (xy 310.676055 -282.851564) (xy 310.637934 -282.820439) (xy 310.605299 -282.783602)
			(xy 310.578996 -282.742006) (xy 310.559705 -282.69673) (xy 310.547928 -282.648946) (xy 310.543968 -282.599892)
			(xy 310.226964 -282.599892) (xy 310.22646 -282.6256) (xy 310.218417 -282.676382) (xy 310.202529 -282.725281)
			(xy 310.179186 -282.771093) (xy 310.148965 -282.812689) (xy 310.112609 -282.849045) (xy 310.071013 -282.879266)
			(xy 310.025201 -282.902609) (xy 309.976302 -282.918497) (xy 309.92552 -282.92654) (xy 309.874104 -282.92654)
			(xy 309.823322 -282.918497) (xy 309.774423 -282.902609) (xy 309.728611 -282.879266) (xy 309.687015 -282.849045)
			(xy 309.650659 -282.812689) (xy 309.620438 -282.771093) (xy 309.597095 -282.725281) (xy 309.581207 -282.676382)
			(xy 309.573164 -282.6256) (xy 309.2765 -282.6256) (xy 309.268457 -282.676382) (xy 309.252569 -282.725281)
			(xy 309.229226 -282.771093) (xy 309.199005 -282.812689) (xy 309.162649 -282.849045) (xy 309.121053 -282.879266)
			(xy 309.075241 -282.902609) (xy 309.026342 -282.918497) (xy 308.97556 -282.92654) (xy 308.924144 -282.92654)
			(xy 308.873362 -282.918497) (xy 308.824463 -282.902609) (xy 308.778651 -282.879266) (xy 308.737055 -282.849045)
			(xy 308.700699 -282.812689) (xy 308.670478 -282.771093) (xy 308.647135 -282.725281) (xy 308.631247 -282.676382)
			(xy 308.623204 -282.6256) (xy 307.354312 -282.6256) (xy 307.346596 -282.673076) (xy 307.331012 -282.719757)
			(xy 307.308141 -282.763334) (xy 307.278576 -282.802678) (xy 307.243083 -282.83677) (xy 307.20258 -282.864726)
			(xy 307.158118 -282.885824) (xy 307.110847 -282.899516) (xy 307.061992 -282.905448) (xy 307.012817 -282.903467)
			(xy 306.964598 -282.893623) (xy 306.918582 -282.876171) (xy 306.875961 -282.851564) (xy 306.83784 -282.820439)
			(xy 306.805205 -282.783602) (xy 306.778902 -282.742006) (xy 306.759611 -282.69673) (xy 306.747834 -282.648946)
			(xy 306.743874 -282.599892) (xy 287.405064 -282.599892) (xy 287.404887 -282.614075) (xy 287.402215 -282.642315)
			(xy 287.39973 -282.65628) (xy 287.397444 -282.668726) (xy 287.40481 -282.692348) (xy 287.48228 -282.769818)
			(xy 287.505902 -282.777184) (xy 287.518348 -282.774898) (xy 287.532313 -282.772419) (xy 287.560553 -282.769749)
			(xy 287.574736 -282.769564) (xy 287.599554 -282.770117) (xy 287.648535 -282.778153) (xy 287.69557 -282.794007)
			(xy 287.739421 -282.817262) (xy 287.778932 -282.847304) (xy 287.813062 -282.883343) (xy 287.840913 -282.924429)
			(xy 287.861749 -282.96948) (xy 287.875023 -283.017307) (xy 287.880384 -283.066653) (xy 287.879937 -283.074872)
			(xy 288.219146 -283.074872) (xy 288.223106 -283.025818) (xy 288.234883 -282.978034) (xy 288.254174 -282.932758)
			(xy 288.280477 -282.891162) (xy 288.313112 -282.854325) (xy 288.351233 -282.8232) (xy 288.393854 -282.798593)
			(xy 288.43987 -282.781141) (xy 288.488089 -282.771297) (xy 288.537264 -282.769316) (xy 288.586119 -282.775248)
			(xy 288.63339 -282.78894) (xy 288.677852 -282.810038) (xy 288.718355 -282.837994) (xy 288.753848 -282.872086)
			(xy 288.783413 -282.91143) (xy 288.806284 -282.955007) (xy 288.821868 -283.001688) (xy 288.829763 -283.050265)
			(xy 288.830258 -283.074872) (xy 289.169106 -283.074872) (xy 289.173066 -283.025818) (xy 289.184843 -282.978034)
			(xy 289.204134 -282.932758) (xy 289.230437 -282.891162) (xy 289.263072 -282.854325) (xy 289.301193 -282.8232)
			(xy 289.343814 -282.798593) (xy 289.38983 -282.781141) (xy 289.438049 -282.771297) (xy 289.487224 -282.769316)
			(xy 289.536079 -282.775248) (xy 289.58335 -282.78894) (xy 289.627812 -282.810038) (xy 289.668315 -282.837994)
			(xy 289.703808 -282.872086) (xy 289.733373 -282.91143) (xy 289.756244 -282.955007) (xy 289.771828 -283.001688)
			(xy 289.779723 -283.050265) (xy 289.780218 -283.074872) (xy 290.119066 -283.074872) (xy 290.123026 -283.025818)
			(xy 290.134803 -282.978034) (xy 290.154094 -282.932758) (xy 290.180397 -282.891162) (xy 290.213032 -282.854325)
			(xy 290.251153 -282.8232) (xy 290.293774 -282.798593) (xy 290.33979 -282.781141) (xy 290.388009 -282.771297)
			(xy 290.437184 -282.769316) (xy 290.486039 -282.775248) (xy 290.53331 -282.78894) (xy 290.577772 -282.810038)
			(xy 290.618275 -282.837994) (xy 290.653768 -282.872086) (xy 290.683333 -282.91143) (xy 290.706204 -282.955007)
			(xy 290.721788 -283.001688) (xy 290.729683 -283.050265) (xy 290.730178 -283.074872) (xy 292.018986 -283.074872)
			(xy 292.022946 -283.025818) (xy 292.034723 -282.978034) (xy 292.054014 -282.932758) (xy 292.080317 -282.891162)
			(xy 292.112952 -282.854325) (xy 292.151073 -282.8232) (xy 292.193694 -282.798593) (xy 292.23971 -282.781141)
			(xy 292.287929 -282.771297) (xy 292.337104 -282.769316) (xy 292.385959 -282.775248) (xy 292.43323 -282.78894)
			(xy 292.477692 -282.810038) (xy 292.518195 -282.837994) (xy 292.553688 -282.872086) (xy 292.583253 -282.91143)
			(xy 292.606124 -282.955007) (xy 292.621708 -283.001688) (xy 292.629603 -283.050265) (xy 292.630098 -283.074872)
			(xy 292.968946 -283.074872) (xy 292.972906 -283.025818) (xy 292.984683 -282.978034) (xy 293.003974 -282.932758)
			(xy 293.030277 -282.891162) (xy 293.062912 -282.854325) (xy 293.101033 -282.8232) (xy 293.143654 -282.798593)
			(xy 293.18967 -282.781141) (xy 293.237889 -282.771297) (xy 293.287064 -282.769316) (xy 293.335919 -282.775248)
			(xy 293.38319 -282.78894) (xy 293.427652 -282.810038) (xy 293.468155 -282.837994) (xy 293.503648 -282.872086)
			(xy 293.533213 -282.91143) (xy 293.556084 -282.955007) (xy 293.571668 -283.001688) (xy 293.579563 -283.050265)
			(xy 293.580058 -283.074872) (xy 293.918906 -283.074872) (xy 293.922866 -283.025818) (xy 293.934643 -282.978034)
			(xy 293.953934 -282.932758) (xy 293.980237 -282.891162) (xy 294.012872 -282.854325) (xy 294.050993 -282.8232)
			(xy 294.093614 -282.798593) (xy 294.13963 -282.781141) (xy 294.187849 -282.771297) (xy 294.237024 -282.769316)
			(xy 294.285879 -282.775248) (xy 294.33315 -282.78894) (xy 294.377612 -282.810038) (xy 294.418115 -282.837994)
			(xy 294.453608 -282.872086) (xy 294.483173 -282.91143) (xy 294.506044 -282.955007) (xy 294.521628 -283.001688)
			(xy 294.529523 -283.050265) (xy 294.530018 -283.074872) (xy 294.86912 -283.074872) (xy 294.87308 -283.025818)
			(xy 294.884857 -282.978034) (xy 294.904148 -282.932758) (xy 294.930451 -282.891162) (xy 294.963086 -282.854325)
			(xy 295.001207 -282.8232) (xy 295.043828 -282.798593) (xy 295.089844 -282.781141) (xy 295.138063 -282.771297)
			(xy 295.187238 -282.769316) (xy 295.236093 -282.775248) (xy 295.283364 -282.78894) (xy 295.327826 -282.810038)
			(xy 295.368329 -282.837994) (xy 295.403822 -282.872086) (xy 295.433387 -282.91143) (xy 295.456258 -282.955007)
			(xy 295.471842 -283.001688) (xy 295.479737 -283.050265) (xy 295.480232 -283.074872) (xy 295.81908 -283.074872)
			(xy 295.82304 -283.025818) (xy 295.834817 -282.978034) (xy 295.854108 -282.932758) (xy 295.880411 -282.891162)
			(xy 295.913046 -282.854325) (xy 295.951167 -282.8232) (xy 295.993788 -282.798593) (xy 296.039804 -282.781141)
			(xy 296.088023 -282.771297) (xy 296.137198 -282.769316) (xy 296.186053 -282.775248) (xy 296.233324 -282.78894)
			(xy 296.277786 -282.810038) (xy 296.318289 -282.837994) (xy 296.353782 -282.872086) (xy 296.383347 -282.91143)
			(xy 296.406218 -282.955007) (xy 296.421802 -283.001688) (xy 296.429697 -283.050265) (xy 296.430192 -283.074872)
			(xy 296.76904 -283.074872) (xy 296.773 -283.025818) (xy 296.784777 -282.978034) (xy 296.804068 -282.932758)
			(xy 296.830371 -282.891162) (xy 296.863006 -282.854325) (xy 296.901127 -282.8232) (xy 296.943748 -282.798593)
			(xy 296.989764 -282.781141) (xy 297.037983 -282.771297) (xy 297.087158 -282.769316) (xy 297.136013 -282.775248)
			(xy 297.183284 -282.78894) (xy 297.227746 -282.810038) (xy 297.268249 -282.837994) (xy 297.303742 -282.872086)
			(xy 297.333307 -282.91143) (xy 297.356178 -282.955007) (xy 297.371762 -283.001688) (xy 297.379657 -283.050265)
			(xy 297.380152 -283.074872) (xy 297.719 -283.074872) (xy 297.72296 -283.025818) (xy 297.734737 -282.978034)
			(xy 297.754028 -282.932758) (xy 297.780331 -282.891162) (xy 297.812966 -282.854325) (xy 297.851087 -282.8232)
			(xy 297.893708 -282.798593) (xy 297.939724 -282.781141) (xy 297.987943 -282.771297) (xy 298.037118 -282.769316)
			(xy 298.085973 -282.775248) (xy 298.133244 -282.78894) (xy 298.177706 -282.810038) (xy 298.218209 -282.837994)
			(xy 298.253702 -282.872086) (xy 298.283267 -282.91143) (xy 298.306138 -282.955007) (xy 298.321722 -283.001688)
			(xy 298.329617 -283.050265) (xy 298.330112 -283.074872) (xy 298.66896 -283.074872) (xy 298.67292 -283.025818)
			(xy 298.684697 -282.978034) (xy 298.703988 -282.932758) (xy 298.730291 -282.891162) (xy 298.762926 -282.854325)
			(xy 298.801047 -282.8232) (xy 298.843668 -282.798593) (xy 298.889684 -282.781141) (xy 298.937903 -282.771297)
			(xy 298.987078 -282.769316) (xy 299.035933 -282.775248) (xy 299.083204 -282.78894) (xy 299.127666 -282.810038)
			(xy 299.168169 -282.837994) (xy 299.203662 -282.872086) (xy 299.233227 -282.91143) (xy 299.256098 -282.955007)
			(xy 299.271682 -283.001688) (xy 299.279577 -283.050265) (xy 299.280072 -283.074872) (xy 300.56888 -283.074872)
			(xy 300.57284 -283.025818) (xy 300.584617 -282.978034) (xy 300.603908 -282.932758) (xy 300.630211 -282.891162)
			(xy 300.662846 -282.854325) (xy 300.700967 -282.8232) (xy 300.743588 -282.798593) (xy 300.789604 -282.781141)
			(xy 300.837823 -282.771297) (xy 300.886998 -282.769316) (xy 300.935853 -282.775248) (xy 300.983124 -282.78894)
			(xy 301.027586 -282.810038) (xy 301.068089 -282.837994) (xy 301.103582 -282.872086) (xy 301.133147 -282.91143)
			(xy 301.156018 -282.955007) (xy 301.171602 -283.001688) (xy 301.179497 -283.050265) (xy 301.179992 -283.074872)
			(xy 301.519094 -283.074872) (xy 301.523054 -283.025818) (xy 301.534831 -282.978034) (xy 301.554122 -282.932758)
			(xy 301.580425 -282.891162) (xy 301.61306 -282.854325) (xy 301.651181 -282.8232) (xy 301.693802 -282.798593)
			(xy 301.739818 -282.781141) (xy 301.788037 -282.771297) (xy 301.837212 -282.769316) (xy 301.886067 -282.775248)
			(xy 301.933338 -282.78894) (xy 301.9778 -282.810038) (xy 302.018303 -282.837994) (xy 302.053796 -282.872086)
			(xy 302.083361 -282.91143) (xy 302.106232 -282.955007) (xy 302.121816 -283.001688) (xy 302.129711 -283.050265)
			(xy 302.130206 -283.074872) (xy 302.469054 -283.074872) (xy 302.473014 -283.025818) (xy 302.484791 -282.978034)
			(xy 302.504082 -282.932758) (xy 302.530385 -282.891162) (xy 302.56302 -282.854325) (xy 302.601141 -282.8232)
			(xy 302.643762 -282.798593) (xy 302.689778 -282.781141) (xy 302.737997 -282.771297) (xy 302.787172 -282.769316)
			(xy 302.836027 -282.775248) (xy 302.883298 -282.78894) (xy 302.92776 -282.810038) (xy 302.968263 -282.837994)
			(xy 303.003756 -282.872086) (xy 303.033321 -282.91143) (xy 303.056192 -282.955007) (xy 303.071776 -283.001688)
			(xy 303.079671 -283.050265) (xy 303.080166 -283.074872) (xy 303.419014 -283.074872) (xy 303.422974 -283.025818)
			(xy 303.434751 -282.978034) (xy 303.454042 -282.932758) (xy 303.480345 -282.891162) (xy 303.51298 -282.854325)
			(xy 303.551101 -282.8232) (xy 303.593722 -282.798593) (xy 303.639738 -282.781141) (xy 303.687957 -282.771297)
			(xy 303.737132 -282.769316) (xy 303.785987 -282.775248) (xy 303.833258 -282.78894) (xy 303.87772 -282.810038)
			(xy 303.918223 -282.837994) (xy 303.953716 -282.872086) (xy 303.983281 -282.91143) (xy 304.006152 -282.955007)
			(xy 304.021736 -283.001688) (xy 304.029631 -283.050265) (xy 304.030126 -283.074872) (xy 304.368974 -283.074872)
			(xy 304.372934 -283.025818) (xy 304.384711 -282.978034) (xy 304.404002 -282.932758) (xy 304.430305 -282.891162)
			(xy 304.46294 -282.854325) (xy 304.501061 -282.8232) (xy 304.543682 -282.798593) (xy 304.589698 -282.781141)
			(xy 304.637917 -282.771297) (xy 304.687092 -282.769316) (xy 304.735947 -282.775248) (xy 304.783218 -282.78894)
			(xy 304.82768 -282.810038) (xy 304.868183 -282.837994) (xy 304.903676 -282.872086) (xy 304.933241 -282.91143)
			(xy 304.956112 -282.955007) (xy 304.971696 -283.001688) (xy 304.979591 -283.050265) (xy 304.980086 -283.074872)
			(xy 304.979591 -283.099479) (xy 304.971696 -283.148056) (xy 304.956112 -283.194737) (xy 304.933241 -283.238314)
			(xy 304.903676 -283.277658) (xy 304.868183 -283.31175) (xy 304.82768 -283.339706) (xy 304.783218 -283.360804)
			(xy 304.735947 -283.374496) (xy 304.687092 -283.380428) (xy 304.637917 -283.378447) (xy 304.589698 -283.368603)
			(xy 304.543682 -283.351151) (xy 304.501061 -283.326544) (xy 304.46294 -283.295419) (xy 304.430305 -283.258582)
			(xy 304.404002 -283.216986) (xy 304.384711 -283.17171) (xy 304.372934 -283.123926) (xy 304.368974 -283.074872)
			(xy 304.030126 -283.074872) (xy 304.029631 -283.099479) (xy 304.021736 -283.148056) (xy 304.006152 -283.194737)
			(xy 303.983281 -283.238314) (xy 303.953716 -283.277658) (xy 303.918223 -283.31175) (xy 303.87772 -283.339706)
			(xy 303.833258 -283.360804) (xy 303.785987 -283.374496) (xy 303.737132 -283.380428) (xy 303.687957 -283.378447)
			(xy 303.639738 -283.368603) (xy 303.593722 -283.351151) (xy 303.551101 -283.326544) (xy 303.51298 -283.295419)
			(xy 303.480345 -283.258582) (xy 303.454042 -283.216986) (xy 303.434751 -283.17171) (xy 303.422974 -283.123926)
			(xy 303.419014 -283.074872) (xy 303.080166 -283.074872) (xy 303.079671 -283.099479) (xy 303.071776 -283.148056)
			(xy 303.056192 -283.194737) (xy 303.033321 -283.238314) (xy 303.003756 -283.277658) (xy 302.968263 -283.31175)
			(xy 302.92776 -283.339706) (xy 302.883298 -283.360804) (xy 302.836027 -283.374496) (xy 302.787172 -283.380428)
			(xy 302.737997 -283.378447) (xy 302.689778 -283.368603) (xy 302.643762 -283.351151) (xy 302.601141 -283.326544)
			(xy 302.56302 -283.295419) (xy 302.530385 -283.258582) (xy 302.504082 -283.216986) (xy 302.484791 -283.17171)
			(xy 302.473014 -283.123926) (xy 302.469054 -283.074872) (xy 302.130206 -283.074872) (xy 302.129711 -283.099479)
			(xy 302.121816 -283.148056) (xy 302.106232 -283.194737) (xy 302.083361 -283.238314) (xy 302.053796 -283.277658)
			(xy 302.018303 -283.31175) (xy 301.9778 -283.339706) (xy 301.933338 -283.360804) (xy 301.886067 -283.374496)
			(xy 301.837212 -283.380428) (xy 301.788037 -283.378447) (xy 301.739818 -283.368603) (xy 301.693802 -283.351151)
			(xy 301.651181 -283.326544) (xy 301.61306 -283.295419) (xy 301.580425 -283.258582) (xy 301.554122 -283.216986)
			(xy 301.534831 -283.17171) (xy 301.523054 -283.123926) (xy 301.519094 -283.074872) (xy 301.179992 -283.074872)
			(xy 301.179497 -283.099479) (xy 301.171602 -283.148056) (xy 301.156018 -283.194737) (xy 301.133147 -283.238314)
			(xy 301.103582 -283.277658) (xy 301.068089 -283.31175) (xy 301.027586 -283.339706) (xy 300.983124 -283.360804)
			(xy 300.935853 -283.374496) (xy 300.886998 -283.380428) (xy 300.837823 -283.378447) (xy 300.789604 -283.368603)
			(xy 300.743588 -283.351151) (xy 300.700967 -283.326544) (xy 300.662846 -283.295419) (xy 300.630211 -283.258582)
			(xy 300.603908 -283.216986) (xy 300.584617 -283.17171) (xy 300.57284 -283.123926) (xy 300.56888 -283.074872)
			(xy 299.280072 -283.074872) (xy 299.279577 -283.099479) (xy 299.271682 -283.148056) (xy 299.256098 -283.194737)
			(xy 299.233227 -283.238314) (xy 299.203662 -283.277658) (xy 299.168169 -283.31175) (xy 299.127666 -283.339706)
			(xy 299.083204 -283.360804) (xy 299.035933 -283.374496) (xy 298.987078 -283.380428) (xy 298.937903 -283.378447)
			(xy 298.889684 -283.368603) (xy 298.843668 -283.351151) (xy 298.801047 -283.326544) (xy 298.762926 -283.295419)
			(xy 298.730291 -283.258582) (xy 298.703988 -283.216986) (xy 298.684697 -283.17171) (xy 298.67292 -283.123926)
			(xy 298.66896 -283.074872) (xy 298.330112 -283.074872) (xy 298.329617 -283.099479) (xy 298.321722 -283.148056)
			(xy 298.306138 -283.194737) (xy 298.283267 -283.238314) (xy 298.253702 -283.277658) (xy 298.218209 -283.31175)
			(xy 298.177706 -283.339706) (xy 298.133244 -283.360804) (xy 298.085973 -283.374496) (xy 298.037118 -283.380428)
			(xy 297.987943 -283.378447) (xy 297.939724 -283.368603) (xy 297.893708 -283.351151) (xy 297.851087 -283.326544)
			(xy 297.812966 -283.295419) (xy 297.780331 -283.258582) (xy 297.754028 -283.216986) (xy 297.734737 -283.17171)
			(xy 297.72296 -283.123926) (xy 297.719 -283.074872) (xy 297.380152 -283.074872) (xy 297.379657 -283.099479)
			(xy 297.371762 -283.148056) (xy 297.356178 -283.194737) (xy 297.333307 -283.238314) (xy 297.303742 -283.277658)
			(xy 297.268249 -283.31175) (xy 297.227746 -283.339706) (xy 297.183284 -283.360804) (xy 297.136013 -283.374496)
			(xy 297.087158 -283.380428) (xy 297.037983 -283.378447) (xy 296.989764 -283.368603) (xy 296.943748 -283.351151)
			(xy 296.901127 -283.326544) (xy 296.863006 -283.295419) (xy 296.830371 -283.258582) (xy 296.804068 -283.216986)
			(xy 296.784777 -283.17171) (xy 296.773 -283.123926) (xy 296.76904 -283.074872) (xy 296.430192 -283.074872)
			(xy 296.429697 -283.099479) (xy 296.421802 -283.148056) (xy 296.406218 -283.194737) (xy 296.383347 -283.238314)
			(xy 296.353782 -283.277658) (xy 296.318289 -283.31175) (xy 296.277786 -283.339706) (xy 296.233324 -283.360804)
			(xy 296.186053 -283.374496) (xy 296.137198 -283.380428) (xy 296.088023 -283.378447) (xy 296.039804 -283.368603)
			(xy 295.993788 -283.351151) (xy 295.951167 -283.326544) (xy 295.913046 -283.295419) (xy 295.880411 -283.258582)
			(xy 295.854108 -283.216986) (xy 295.834817 -283.17171) (xy 295.82304 -283.123926) (xy 295.81908 -283.074872)
			(xy 295.480232 -283.074872) (xy 295.479737 -283.099479) (xy 295.471842 -283.148056) (xy 295.456258 -283.194737)
			(xy 295.433387 -283.238314) (xy 295.403822 -283.277658) (xy 295.368329 -283.31175) (xy 295.327826 -283.339706)
			(xy 295.283364 -283.360804) (xy 295.236093 -283.374496) (xy 295.187238 -283.380428) (xy 295.138063 -283.378447)
			(xy 295.089844 -283.368603) (xy 295.043828 -283.351151) (xy 295.001207 -283.326544) (xy 294.963086 -283.295419)
			(xy 294.930451 -283.258582) (xy 294.904148 -283.216986) (xy 294.884857 -283.17171) (xy 294.87308 -283.123926)
			(xy 294.86912 -283.074872) (xy 294.530018 -283.074872) (xy 294.529523 -283.099479) (xy 294.521628 -283.148056)
			(xy 294.506044 -283.194737) (xy 294.483173 -283.238314) (xy 294.453608 -283.277658) (xy 294.418115 -283.31175)
			(xy 294.377612 -283.339706) (xy 294.33315 -283.360804) (xy 294.285879 -283.374496) (xy 294.237024 -283.380428)
			(xy 294.187849 -283.378447) (xy 294.13963 -283.368603) (xy 294.093614 -283.351151) (xy 294.050993 -283.326544)
			(xy 294.012872 -283.295419) (xy 293.980237 -283.258582) (xy 293.953934 -283.216986) (xy 293.934643 -283.17171)
			(xy 293.922866 -283.123926) (xy 293.918906 -283.074872) (xy 293.580058 -283.074872) (xy 293.579563 -283.099479)
			(xy 293.571668 -283.148056) (xy 293.556084 -283.194737) (xy 293.533213 -283.238314) (xy 293.503648 -283.277658)
			(xy 293.468155 -283.31175) (xy 293.427652 -283.339706) (xy 293.38319 -283.360804) (xy 293.335919 -283.374496)
			(xy 293.287064 -283.380428) (xy 293.237889 -283.378447) (xy 293.18967 -283.368603) (xy 293.143654 -283.351151)
			(xy 293.101033 -283.326544) (xy 293.062912 -283.295419) (xy 293.030277 -283.258582) (xy 293.003974 -283.216986)
			(xy 292.984683 -283.17171) (xy 292.972906 -283.123926) (xy 292.968946 -283.074872) (xy 292.630098 -283.074872)
			(xy 292.629603 -283.099479) (xy 292.621708 -283.148056) (xy 292.606124 -283.194737) (xy 292.583253 -283.238314)
			(xy 292.553688 -283.277658) (xy 292.518195 -283.31175) (xy 292.477692 -283.339706) (xy 292.43323 -283.360804)
			(xy 292.385959 -283.374496) (xy 292.337104 -283.380428) (xy 292.287929 -283.378447) (xy 292.23971 -283.368603)
			(xy 292.193694 -283.351151) (xy 292.151073 -283.326544) (xy 292.112952 -283.295419) (xy 292.080317 -283.258582)
			(xy 292.054014 -283.216986) (xy 292.034723 -283.17171) (xy 292.022946 -283.123926) (xy 292.018986 -283.074872)
			(xy 290.730178 -283.074872) (xy 290.729683 -283.099479) (xy 290.721788 -283.148056) (xy 290.706204 -283.194737)
			(xy 290.683333 -283.238314) (xy 290.653768 -283.277658) (xy 290.618275 -283.31175) (xy 290.577772 -283.339706)
			(xy 290.53331 -283.360804) (xy 290.486039 -283.374496) (xy 290.437184 -283.380428) (xy 290.388009 -283.378447)
			(xy 290.33979 -283.368603) (xy 290.293774 -283.351151) (xy 290.251153 -283.326544) (xy 290.213032 -283.295419)
			(xy 290.180397 -283.258582) (xy 290.154094 -283.216986) (xy 290.134803 -283.17171) (xy 290.123026 -283.123926)
			(xy 290.119066 -283.074872) (xy 289.780218 -283.074872) (xy 289.779723 -283.099479) (xy 289.771828 -283.148056)
			(xy 289.756244 -283.194737) (xy 289.733373 -283.238314) (xy 289.703808 -283.277658) (xy 289.668315 -283.31175)
			(xy 289.627812 -283.339706) (xy 289.58335 -283.360804) (xy 289.536079 -283.374496) (xy 289.487224 -283.380428)
			(xy 289.438049 -283.378447) (xy 289.38983 -283.368603) (xy 289.343814 -283.351151) (xy 289.301193 -283.326544)
			(xy 289.263072 -283.295419) (xy 289.230437 -283.258582) (xy 289.204134 -283.216986) (xy 289.184843 -283.17171)
			(xy 289.173066 -283.123926) (xy 289.169106 -283.074872) (xy 288.830258 -283.074872) (xy 288.829763 -283.099479)
			(xy 288.821868 -283.148056) (xy 288.806284 -283.194737) (xy 288.783413 -283.238314) (xy 288.753848 -283.277658)
			(xy 288.718355 -283.31175) (xy 288.677852 -283.339706) (xy 288.63339 -283.360804) (xy 288.586119 -283.374496)
			(xy 288.537264 -283.380428) (xy 288.488089 -283.378447) (xy 288.43987 -283.368603) (xy 288.393854 -283.351151)
			(xy 288.351233 -283.326544) (xy 288.313112 -283.295419) (xy 288.280477 -283.258582) (xy 288.254174 -283.216986)
			(xy 288.234883 -283.17171) (xy 288.223106 -283.123926) (xy 288.219146 -283.074872) (xy 287.879937 -283.074872)
			(xy 287.877691 -283.116215) (xy 287.867016 -283.164689) (xy 287.848639 -283.210798) (xy 287.823044 -283.253325)
			(xy 287.790907 -283.291152) (xy 287.753073 -283.323282) (xy 287.71054 -283.348867) (xy 287.664428 -283.367235)
			(xy 287.615952 -283.3779) (xy 287.566389 -283.380582) (xy 287.517045 -283.375211) (xy 287.469219 -283.361927)
			(xy 287.424173 -283.341081) (xy 287.383093 -283.313222) (xy 287.347061 -283.279084) (xy 287.317027 -283.239567)
			(xy 287.293781 -283.195711) (xy 287.277937 -283.148672) (xy 287.269911 -283.09969) (xy 287.269428 -283.074872)
			(xy 287.2696 -283.060689) (xy 287.272275 -283.032449) (xy 287.274762 -283.018484) (xy 287.277048 -283.006038)
			(xy 287.269682 -282.982416) (xy 287.192212 -282.904946) (xy 287.16859 -282.89758) (xy 287.156144 -282.899866)
			(xy 287.142179 -282.902346) (xy 287.113939 -282.905015) (xy 287.099756 -282.9052) (xy 287.085573 -282.905016)
			(xy 287.057333 -282.902349) (xy 287.043368 -282.899866) (xy 287.030922 -282.89758) (xy 287.0073 -282.904946)
			(xy 286.92983 -282.982416) (xy 286.922464 -283.006038) (xy 286.92475 -283.018484) (xy 286.927234 -283.032449)
			(xy 286.929901 -283.060689) (xy 286.930084 -283.074872) (xy 286.929652 -283.099695) (xy 286.921625 -283.148688)
			(xy 286.905777 -283.195737) (xy 286.882526 -283.239603) (xy 286.852485 -283.279128) (xy 286.816445 -283.313273)
			(xy 286.775356 -283.341138) (xy 286.7303 -283.361988) (xy 286.682464 -283.375274) (xy 286.633109 -283.380646)
			(xy 286.583535 -283.377963) (xy 286.535049 -283.367294) (xy 286.488927 -283.348922) (xy 286.446385 -283.323331)
			(xy 286.408543 -283.291193) (xy 286.3764 -283.253358) (xy 286.350801 -283.21082) (xy 286.332421 -283.164701)
			(xy 286.321744 -283.116216) (xy 286.319052 -283.066643) (xy 285.979958 -283.066643) (xy 285.980124 -283.074872)
			(xy 285.979629 -283.099479) (xy 285.971734 -283.148056) (xy 285.95615 -283.194737) (xy 285.933279 -283.238314)
			(xy 285.903714 -283.277658) (xy 285.868221 -283.31175) (xy 285.827718 -283.339706) (xy 285.783256 -283.360804)
			(xy 285.735985 -283.374496) (xy 285.68713 -283.380428) (xy 285.637955 -283.378447) (xy 285.589736 -283.368603)
			(xy 285.54372 -283.351151) (xy 285.501099 -283.326544) (xy 285.462978 -283.295419) (xy 285.430343 -283.258582)
			(xy 285.40404 -283.216986) (xy 285.384749 -283.17171) (xy 285.372972 -283.123926) (xy 285.369012 -283.074872)
			(xy 285.030164 -283.074872) (xy 285.029669 -283.099479) (xy 285.021774 -283.148056) (xy 285.00619 -283.194737)
			(xy 284.983319 -283.238314) (xy 284.953754 -283.277658) (xy 284.918261 -283.31175) (xy 284.877758 -283.339706)
			(xy 284.833296 -283.360804) (xy 284.786025 -283.374496) (xy 284.73717 -283.380428) (xy 284.687995 -283.378447)
			(xy 284.639776 -283.368603) (xy 284.59376 -283.351151) (xy 284.551139 -283.326544) (xy 284.513018 -283.295419)
			(xy 284.480383 -283.258582) (xy 284.45408 -283.216986) (xy 284.434789 -283.17171) (xy 284.423012 -283.123926)
			(xy 284.419052 -283.074872) (xy 284.080204 -283.074872) (xy 284.079709 -283.099479) (xy 284.071814 -283.148056)
			(xy 284.05623 -283.194737) (xy 284.033359 -283.238314) (xy 284.003794 -283.277658) (xy 283.968301 -283.31175)
			(xy 283.927798 -283.339706) (xy 283.883336 -283.360804) (xy 283.836065 -283.374496) (xy 283.78721 -283.380428)
			(xy 283.738035 -283.378447) (xy 283.689816 -283.368603) (xy 283.6438 -283.351151) (xy 283.601179 -283.326544)
			(xy 283.563058 -283.295419) (xy 283.530423 -283.258582) (xy 283.50412 -283.216986) (xy 283.484829 -283.17171)
			(xy 283.473052 -283.123926) (xy 283.469092 -283.074872) (xy 283.130244 -283.074872) (xy 283.129749 -283.099479)
			(xy 283.121854 -283.148056) (xy 283.10627 -283.194737) (xy 283.083399 -283.238314) (xy 283.053834 -283.277658)
			(xy 283.018341 -283.31175) (xy 282.977838 -283.339706) (xy 282.933376 -283.360804) (xy 282.886105 -283.374496)
			(xy 282.83725 -283.380428) (xy 282.788075 -283.378447) (xy 282.739856 -283.368603) (xy 282.69384 -283.351151)
			(xy 282.651219 -283.326544) (xy 282.613098 -283.295419) (xy 282.580463 -283.258582) (xy 282.55416 -283.216986)
			(xy 282.534869 -283.17171) (xy 282.523092 -283.123926) (xy 282.519132 -283.074872) (xy 282.18003 -283.074872)
			(xy 282.179535 -283.099479) (xy 282.17164 -283.148056) (xy 282.156056 -283.194737) (xy 282.133185 -283.238314)
			(xy 282.10362 -283.277658) (xy 282.068127 -283.31175) (xy 282.027624 -283.339706) (xy 281.983162 -283.360804)
			(xy 281.935891 -283.374496) (xy 281.887036 -283.380428) (xy 281.837861 -283.378447) (xy 281.789642 -283.368603)
			(xy 281.743626 -283.351151) (xy 281.701005 -283.326544) (xy 281.662884 -283.295419) (xy 281.630249 -283.258582)
			(xy 281.603946 -283.216986) (xy 281.584655 -283.17171) (xy 281.572878 -283.123926) (xy 281.568918 -283.074872)
			(xy 281.23007 -283.074872) (xy 281.229575 -283.099479) (xy 281.22168 -283.148056) (xy 281.206096 -283.194737)
			(xy 281.183225 -283.238314) (xy 281.15366 -283.277658) (xy 281.118167 -283.31175) (xy 281.077664 -283.339706)
			(xy 281.033202 -283.360804) (xy 280.985931 -283.374496) (xy 280.937076 -283.380428) (xy 280.887901 -283.378447)
			(xy 280.839682 -283.368603) (xy 280.793666 -283.351151) (xy 280.751045 -283.326544) (xy 280.712924 -283.295419)
			(xy 280.680289 -283.258582) (xy 280.653986 -283.216986) (xy 280.634695 -283.17171) (xy 280.622918 -283.123926)
			(xy 280.618958 -283.074872) (xy 280.28011 -283.074872) (xy 280.279615 -283.099479) (xy 280.27172 -283.148056)
			(xy 280.256136 -283.194737) (xy 280.233265 -283.238314) (xy 280.2037 -283.277658) (xy 280.168207 -283.31175)
			(xy 280.127704 -283.339706) (xy 280.083242 -283.360804) (xy 280.035971 -283.374496) (xy 279.987116 -283.380428)
			(xy 279.937941 -283.378447) (xy 279.889722 -283.368603) (xy 279.843706 -283.351151) (xy 279.801085 -283.326544)
			(xy 279.762964 -283.295419) (xy 279.730329 -283.258582) (xy 279.704026 -283.216986) (xy 279.684735 -283.17171)
			(xy 279.672958 -283.123926) (xy 279.668998 -283.074872) (xy 279.33015 -283.074872) (xy 279.329655 -283.099479)
			(xy 279.32176 -283.148056) (xy 279.306176 -283.194737) (xy 279.283305 -283.238314) (xy 279.25374 -283.277658)
			(xy 279.218247 -283.31175) (xy 279.177744 -283.339706) (xy 279.133282 -283.360804) (xy 279.086011 -283.374496)
			(xy 279.037156 -283.380428) (xy 278.987981 -283.378447) (xy 278.939762 -283.368603) (xy 278.893746 -283.351151)
			(xy 278.851125 -283.326544) (xy 278.813004 -283.295419) (xy 278.780369 -283.258582) (xy 278.754066 -283.216986)
			(xy 278.734775 -283.17171) (xy 278.722998 -283.123926) (xy 278.719038 -283.074872) (xy 278.38019 -283.074872)
			(xy 278.379695 -283.099479) (xy 278.3718 -283.148056) (xy 278.356216 -283.194737) (xy 278.333345 -283.238314)
			(xy 278.30378 -283.277658) (xy 278.268287 -283.31175) (xy 278.227784 -283.339706) (xy 278.183322 -283.360804)
			(xy 278.136051 -283.374496) (xy 278.087196 -283.380428) (xy 278.038021 -283.378447) (xy 277.989802 -283.368603)
			(xy 277.943786 -283.351151) (xy 277.901165 -283.326544) (xy 277.863044 -283.295419) (xy 277.830409 -283.258582)
			(xy 277.804106 -283.216986) (xy 277.784815 -283.17171) (xy 277.773038 -283.123926) (xy 277.769078 -283.074872)
			(xy 277.43023 -283.074872) (xy 277.429735 -283.099479) (xy 277.42184 -283.148056) (xy 277.406256 -283.194737)
			(xy 277.383385 -283.238314) (xy 277.35382 -283.277658) (xy 277.318327 -283.31175) (xy 277.277824 -283.339706)
			(xy 277.233362 -283.360804) (xy 277.186091 -283.374496) (xy 277.137236 -283.380428) (xy 277.088061 -283.378447)
			(xy 277.039842 -283.368603) (xy 276.993826 -283.351151) (xy 276.951205 -283.326544) (xy 276.913084 -283.295419)
			(xy 276.880449 -283.258582) (xy 276.854146 -283.216986) (xy 276.834855 -283.17171) (xy 276.823078 -283.123926)
			(xy 276.819118 -283.074872) (xy 276.480016 -283.074872) (xy 276.479521 -283.099479) (xy 276.471626 -283.148056)
			(xy 276.456042 -283.194737) (xy 276.433171 -283.238314) (xy 276.403606 -283.277658) (xy 276.368113 -283.31175)
			(xy 276.32761 -283.339706) (xy 276.283148 -283.360804) (xy 276.235877 -283.374496) (xy 276.187022 -283.380428)
			(xy 276.137847 -283.378447) (xy 276.089628 -283.368603) (xy 276.043612 -283.351151) (xy 276.000991 -283.326544)
			(xy 275.96287 -283.295419) (xy 275.930235 -283.258582) (xy 275.903932 -283.216986) (xy 275.884641 -283.17171)
			(xy 275.872864 -283.123926) (xy 275.868904 -283.074872) (xy 275.530056 -283.074872) (xy 275.529561 -283.099479)
			(xy 275.521666 -283.148056) (xy 275.506082 -283.194737) (xy 275.483211 -283.238314) (xy 275.453646 -283.277658)
			(xy 275.418153 -283.31175) (xy 275.37765 -283.339706) (xy 275.333188 -283.360804) (xy 275.285917 -283.374496)
			(xy 275.237062 -283.380428) (xy 275.187887 -283.378447) (xy 275.139668 -283.368603) (xy 275.093652 -283.351151)
			(xy 275.051031 -283.326544) (xy 275.01291 -283.295419) (xy 274.980275 -283.258582) (xy 274.953972 -283.216986)
			(xy 274.934681 -283.17171) (xy 274.922904 -283.123926) (xy 274.918944 -283.074872) (xy 274.580096 -283.074872)
			(xy 274.579601 -283.099479) (xy 274.571706 -283.148056) (xy 274.556122 -283.194737) (xy 274.533251 -283.238314)
			(xy 274.503686 -283.277658) (xy 274.468193 -283.31175) (xy 274.42769 -283.339706) (xy 274.383228 -283.360804)
			(xy 274.335957 -283.374496) (xy 274.287102 -283.380428) (xy 274.237927 -283.378447) (xy 274.189708 -283.368603)
			(xy 274.143692 -283.351151) (xy 274.101071 -283.326544) (xy 274.06295 -283.295419) (xy 274.030315 -283.258582)
			(xy 274.004012 -283.216986) (xy 273.984721 -283.17171) (xy 273.972944 -283.123926) (xy 273.968984 -283.074872)
			(xy 273.630136 -283.074872) (xy 273.629641 -283.099479) (xy 273.621746 -283.148056) (xy 273.606162 -283.194737)
			(xy 273.583291 -283.238314) (xy 273.553726 -283.277658) (xy 273.518233 -283.31175) (xy 273.47773 -283.339706)
			(xy 273.433268 -283.360804) (xy 273.385997 -283.374496) (xy 273.337142 -283.380428) (xy 273.287967 -283.378447)
			(xy 273.239748 -283.368603) (xy 273.193732 -283.351151) (xy 273.151111 -283.326544) (xy 273.11299 -283.295419)
			(xy 273.080355 -283.258582) (xy 273.054052 -283.216986) (xy 273.034761 -283.17171) (xy 273.022984 -283.123926)
			(xy 273.019024 -283.074872) (xy 272.680176 -283.074872) (xy 272.679681 -283.099479) (xy 272.671786 -283.148056)
			(xy 272.656202 -283.194737) (xy 272.633331 -283.238314) (xy 272.603766 -283.277658) (xy 272.568273 -283.31175)
			(xy 272.52777 -283.339706) (xy 272.483308 -283.360804) (xy 272.436037 -283.374496) (xy 272.387182 -283.380428)
			(xy 272.338007 -283.378447) (xy 272.289788 -283.368603) (xy 272.243772 -283.351151) (xy 272.201151 -283.326544)
			(xy 272.16303 -283.295419) (xy 272.130395 -283.258582) (xy 272.104092 -283.216986) (xy 272.084801 -283.17171)
			(xy 272.073024 -283.123926) (xy 272.069064 -283.074872) (xy 271.730216 -283.074872) (xy 271.729721 -283.099479)
			(xy 271.721826 -283.148056) (xy 271.706242 -283.194737) (xy 271.683371 -283.238314) (xy 271.653806 -283.277658)
			(xy 271.618313 -283.31175) (xy 271.57781 -283.339706) (xy 271.533348 -283.360804) (xy 271.486077 -283.374496)
			(xy 271.437222 -283.380428) (xy 271.388047 -283.378447) (xy 271.339828 -283.368603) (xy 271.293812 -283.351151)
			(xy 271.251191 -283.326544) (xy 271.21307 -283.295419) (xy 271.180435 -283.258582) (xy 271.154132 -283.216986)
			(xy 271.134841 -283.17171) (xy 271.123064 -283.123926) (xy 271.119104 -283.074872) (xy 270.780256 -283.074872)
			(xy 270.779761 -283.099479) (xy 270.771866 -283.148056) (xy 270.756282 -283.194737) (xy 270.733411 -283.238314)
			(xy 270.703846 -283.277658) (xy 270.668353 -283.31175) (xy 270.62785 -283.339706) (xy 270.583388 -283.360804)
			(xy 270.536117 -283.374496) (xy 270.487262 -283.380428) (xy 270.438087 -283.378447) (xy 270.389868 -283.368603)
			(xy 270.343852 -283.351151) (xy 270.301231 -283.326544) (xy 270.26311 -283.295419) (xy 270.230475 -283.258582)
			(xy 270.204172 -283.216986) (xy 270.184881 -283.17171) (xy 270.173104 -283.123926) (xy 270.169144 -283.074872)
			(xy 269.830042 -283.074872) (xy 269.829547 -283.099479) (xy 269.821652 -283.148056) (xy 269.806068 -283.194737)
			(xy 269.783197 -283.238314) (xy 269.753632 -283.277658) (xy 269.718139 -283.31175) (xy 269.677636 -283.339706)
			(xy 269.633174 -283.360804) (xy 269.585903 -283.374496) (xy 269.537048 -283.380428) (xy 269.487873 -283.378447)
			(xy 269.439654 -283.368603) (xy 269.393638 -283.351151) (xy 269.351017 -283.326544) (xy 269.312896 -283.295419)
			(xy 269.280261 -283.258582) (xy 269.253958 -283.216986) (xy 269.234667 -283.17171) (xy 269.22289 -283.123926)
			(xy 269.21893 -283.074872) (xy 268.880082 -283.074872) (xy 268.879587 -283.099479) (xy 268.871692 -283.148056)
			(xy 268.856108 -283.194737) (xy 268.833237 -283.238314) (xy 268.803672 -283.277658) (xy 268.768179 -283.31175)
			(xy 268.727676 -283.339706) (xy 268.683214 -283.360804) (xy 268.635943 -283.374496) (xy 268.587088 -283.380428)
			(xy 268.537913 -283.378447) (xy 268.489694 -283.368603) (xy 268.443678 -283.351151) (xy 268.401057 -283.326544)
			(xy 268.362936 -283.295419) (xy 268.330301 -283.258582) (xy 268.303998 -283.216986) (xy 268.284707 -283.17171)
			(xy 268.27293 -283.123926) (xy 268.26897 -283.074872) (xy 264.307689 -283.074872) (xy 264.311914 -283.104263)
			(xy 264.3124 -283.131514) (xy 264.311872 -283.160897) (xy 264.302839 -283.218964) (xy 264.285005 -283.274959)
			(xy 264.258791 -283.327554) (xy 264.224818 -283.375505) (xy 264.183891 -283.417676) (xy 264.160762 -283.435806)
			(xy 264.151364 -283.443172) (xy 264.14095 -283.463746) (xy 264.139426 -283.567632) (xy 264.149332 -283.588714)
			(xy 264.158476 -283.59608) (xy 264.180292 -283.614323) (xy 264.218835 -283.656133) (xy 264.250747 -283.703201)
			(xy 264.275319 -283.754484) (xy 264.292009 -283.808845) (xy 264.300447 -283.865081) (xy 264.30097 -283.893514)
			(xy 264.934444 -283.893514) (xy 264.938515 -283.837892) (xy 264.950641 -283.783455) (xy 264.970564 -283.731364)
			(xy 264.99786 -283.682729) (xy 265.031946 -283.638586) (xy 265.072095 -283.599877) (xy 265.117453 -283.567426)
			(xy 265.167053 -283.541925) (xy 265.219837 -283.523918) (xy 265.27468 -283.513788) (xy 265.330414 -283.511751)
			(xy 265.385851 -283.517851) (xy 265.439808 -283.531957) (xy 265.491137 -283.553769) (xy 265.538743 -283.582823)
			(xy 265.581611 -283.618498) (xy 265.618828 -283.660035) (xy 265.649601 -283.706548) (xy 265.673273 -283.757045)
			(xy 265.689341 -283.810452) (xy 265.697461 -283.865628) (xy 265.69797 -283.893514) (xy 265.820904 -283.893514)
			(xy 265.824975 -283.837892) (xy 265.837101 -283.783455) (xy 265.857024 -283.731364) (xy 265.88432 -283.682729)
			(xy 265.918406 -283.638586) (xy 265.958555 -283.599877) (xy 266.003913 -283.567426) (xy 266.053513 -283.541925)
			(xy 266.106297 -283.523918) (xy 266.16114 -283.513788) (xy 266.216874 -283.511751) (xy 266.272311 -283.517851)
			(xy 266.326268 -283.531957) (xy 266.368379 -283.549852) (xy 305.793914 -283.549852) (xy 305.797874 -283.500798)
			(xy 305.809651 -283.453014) (xy 305.828942 -283.407738) (xy 305.855245 -283.366142) (xy 305.88788 -283.329305)
			(xy 305.926001 -283.29818) (xy 305.968622 -283.273573) (xy 306.014638 -283.256121) (xy 306.062857 -283.246277)
			(xy 306.112032 -283.244296) (xy 306.160887 -283.250228) (xy 306.208158 -283.26392) (xy 306.25262 -283.285018)
			(xy 306.293123 -283.312974) (xy 306.328616 -283.347066) (xy 306.358181 -283.38641) (xy 306.381052 -283.429987)
			(xy 306.396636 -283.476668) (xy 306.404531 -283.525245) (xy 306.405026 -283.549852) (xy 306.404531 -283.574459)
			(xy 306.404352 -283.57556) (xy 306.72303 -283.57556) (xy 306.72303 -283.524144) (xy 306.731073 -283.473362)
			(xy 306.746961 -283.424463) (xy 306.770304 -283.378651) (xy 306.800525 -283.337055) (xy 306.836881 -283.300699)
			(xy 306.878477 -283.270478) (xy 306.924289 -283.247135) (xy 306.973188 -283.231247) (xy 307.02397 -283.223204)
			(xy 307.075386 -283.223204) (xy 307.126168 -283.231247) (xy 307.175067 -283.247135) (xy 307.220879 -283.270478)
			(xy 307.262475 -283.300699) (xy 307.298831 -283.337055) (xy 307.329052 -283.378651) (xy 307.352395 -283.424463)
			(xy 307.368283 -283.473362) (xy 307.376326 -283.524144) (xy 307.37683 -283.549852) (xy 307.376326 -283.57556)
			(xy 307.673244 -283.57556) (xy 307.673244 -283.524144) (xy 307.681287 -283.473362) (xy 307.697175 -283.424463)
			(xy 307.720518 -283.378651) (xy 307.750739 -283.337055) (xy 307.787095 -283.300699) (xy 307.828691 -283.270478)
			(xy 307.874503 -283.247135) (xy 307.923402 -283.231247) (xy 307.974184 -283.223204) (xy 308.0256 -283.223204)
			(xy 308.076382 -283.231247) (xy 308.125281 -283.247135) (xy 308.171093 -283.270478) (xy 308.212689 -283.300699)
			(xy 308.249045 -283.337055) (xy 308.279266 -283.378651) (xy 308.302609 -283.424463) (xy 308.318497 -283.473362)
			(xy 308.32654 -283.524144) (xy 308.327044 -283.549852) (xy 308.644048 -283.549852) (xy 308.648008 -283.500798)
			(xy 308.659785 -283.453014) (xy 308.679076 -283.407738) (xy 308.705379 -283.366142) (xy 308.738014 -283.329305)
			(xy 308.776135 -283.29818) (xy 308.818756 -283.273573) (xy 308.864772 -283.256121) (xy 308.912991 -283.246277)
			(xy 308.962166 -283.244296) (xy 309.011021 -283.250228) (xy 309.058292 -283.26392) (xy 309.102754 -283.285018)
			(xy 309.143257 -283.312974) (xy 309.17875 -283.347066) (xy 309.208315 -283.38641) (xy 309.231186 -283.429987)
			(xy 309.24677 -283.476668) (xy 309.254665 -283.525245) (xy 309.25516 -283.549852) (xy 309.594008 -283.549852)
			(xy 309.597968 -283.500798) (xy 309.609745 -283.453014) (xy 309.629036 -283.407738) (xy 309.655339 -283.366142)
			(xy 309.687974 -283.329305) (xy 309.726095 -283.29818) (xy 309.768716 -283.273573) (xy 309.814732 -283.256121)
			(xy 309.862951 -283.246277) (xy 309.912126 -283.244296) (xy 309.960981 -283.250228) (xy 310.008252 -283.26392)
			(xy 310.052714 -283.285018) (xy 310.093217 -283.312974) (xy 310.12871 -283.347066) (xy 310.158275 -283.38641)
			(xy 310.181146 -283.429987) (xy 310.19673 -283.476668) (xy 310.204625 -283.525245) (xy 310.20512 -283.549852)
			(xy 310.543968 -283.549852) (xy 310.547928 -283.500798) (xy 310.559705 -283.453014) (xy 310.578996 -283.407738)
			(xy 310.605299 -283.366142) (xy 310.637934 -283.329305) (xy 310.676055 -283.29818) (xy 310.718676 -283.273573)
			(xy 310.764692 -283.256121) (xy 310.812911 -283.246277) (xy 310.862086 -283.244296) (xy 310.910941 -283.250228)
			(xy 310.958212 -283.26392) (xy 311.002674 -283.285018) (xy 311.043177 -283.312974) (xy 311.07867 -283.347066)
			(xy 311.108235 -283.38641) (xy 311.131106 -283.429987) (xy 311.14669 -283.476668) (xy 311.154585 -283.525245)
			(xy 311.15508 -283.549852) (xy 311.493928 -283.549852) (xy 311.497888 -283.500798) (xy 311.509665 -283.453014)
			(xy 311.528956 -283.407738) (xy 311.555259 -283.366142) (xy 311.587894 -283.329305) (xy 311.626015 -283.29818)
			(xy 311.668636 -283.273573) (xy 311.714652 -283.256121) (xy 311.762871 -283.246277) (xy 311.812046 -283.244296)
			(xy 311.860901 -283.250228) (xy 311.908172 -283.26392) (xy 311.952634 -283.285018) (xy 311.993137 -283.312974)
			(xy 312.02863 -283.347066) (xy 312.058195 -283.38641) (xy 312.081066 -283.429987) (xy 312.09665 -283.476668)
			(xy 312.104545 -283.525245) (xy 312.10504 -283.549852) (xy 312.443888 -283.549852) (xy 312.447848 -283.500798)
			(xy 312.459625 -283.453014) (xy 312.478916 -283.407738) (xy 312.505219 -283.366142) (xy 312.537854 -283.329305)
			(xy 312.575975 -283.29818) (xy 312.618596 -283.273573) (xy 312.664612 -283.256121) (xy 312.712831 -283.246277)
			(xy 312.762006 -283.244296) (xy 312.810861 -283.250228) (xy 312.858132 -283.26392) (xy 312.902594 -283.285018)
			(xy 312.943097 -283.312974) (xy 312.97859 -283.347066) (xy 313.008155 -283.38641) (xy 313.031026 -283.429987)
			(xy 313.04661 -283.476668) (xy 313.054505 -283.525245) (xy 313.055 -283.549852) (xy 313.054505 -283.574459)
			(xy 313.054326 -283.57556) (xy 313.373258 -283.57556) (xy 313.373258 -283.524144) (xy 313.381301 -283.473362)
			(xy 313.397189 -283.424463) (xy 313.420532 -283.378651) (xy 313.450753 -283.337055) (xy 313.487109 -283.300699)
			(xy 313.528705 -283.270478) (xy 313.574517 -283.247135) (xy 313.623416 -283.231247) (xy 313.674198 -283.223204)
			(xy 313.725614 -283.223204) (xy 313.776396 -283.231247) (xy 313.825295 -283.247135) (xy 313.871107 -283.270478)
			(xy 313.912703 -283.300699) (xy 313.949059 -283.337055) (xy 313.97928 -283.378651) (xy 314.002623 -283.424463)
			(xy 314.018511 -283.473362) (xy 314.026554 -283.524144) (xy 314.027058 -283.549852) (xy 314.026554 -283.57556)
			(xy 314.323218 -283.57556) (xy 314.323218 -283.524144) (xy 314.331261 -283.473362) (xy 314.347149 -283.424463)
			(xy 314.370492 -283.378651) (xy 314.400713 -283.337055) (xy 314.437069 -283.300699) (xy 314.478665 -283.270478)
			(xy 314.524477 -283.247135) (xy 314.573376 -283.231247) (xy 314.624158 -283.223204) (xy 314.675574 -283.223204)
			(xy 314.726356 -283.231247) (xy 314.775255 -283.247135) (xy 314.821067 -283.270478) (xy 314.862663 -283.300699)
			(xy 314.899019 -283.337055) (xy 314.92924 -283.378651) (xy 314.952583 -283.424463) (xy 314.968471 -283.473362)
			(xy 314.976514 -283.524144) (xy 314.977018 -283.549852) (xy 314.977013 -283.550106) (xy 315.294276 -283.550106)
			(xy 315.298236 -283.501052) (xy 315.310013 -283.453268) (xy 315.329304 -283.407992) (xy 315.355607 -283.366396)
			(xy 315.388242 -283.329559) (xy 315.426363 -283.298434) (xy 315.468984 -283.273827) (xy 315.515 -283.256375)
			(xy 315.563219 -283.246531) (xy 315.612394 -283.24455) (xy 315.661249 -283.250482) (xy 315.70852 -283.264174)
			(xy 315.752982 -283.285272) (xy 315.793485 -283.313228) (xy 315.828978 -283.34732) (xy 315.858543 -283.386664)
			(xy 315.881414 -283.430241) (xy 315.896998 -283.476922) (xy 315.904893 -283.525499) (xy 315.905388 -283.550106)
			(xy 315.904893 -283.574713) (xy 315.896998 -283.62329) (xy 315.881414 -283.669971) (xy 315.858543 -283.713548)
			(xy 315.828978 -283.752892) (xy 315.793485 -283.786984) (xy 315.752982 -283.81494) (xy 315.70852 -283.836038)
			(xy 315.661249 -283.84973) (xy 315.612394 -283.855662) (xy 315.563219 -283.853681) (xy 315.515 -283.843837)
			(xy 315.468984 -283.826385) (xy 315.426363 -283.801778) (xy 315.388242 -283.770653) (xy 315.355607 -283.733816)
			(xy 315.329304 -283.69222) (xy 315.310013 -283.646944) (xy 315.298236 -283.59916) (xy 315.294276 -283.550106)
			(xy 314.977013 -283.550106) (xy 314.976514 -283.57556) (xy 314.968471 -283.626342) (xy 314.952583 -283.675241)
			(xy 314.92924 -283.721053) (xy 314.899019 -283.762649) (xy 314.862663 -283.799005) (xy 314.821067 -283.829226)
			(xy 314.775255 -283.852569) (xy 314.726356 -283.868457) (xy 314.675574 -283.8765) (xy 314.624158 -283.8765)
			(xy 314.573376 -283.868457) (xy 314.524477 -283.852569) (xy 314.478665 -283.829226) (xy 314.437069 -283.799005)
			(xy 314.400713 -283.762649) (xy 314.370492 -283.721053) (xy 314.347149 -283.675241) (xy 314.331261 -283.626342)
			(xy 314.323218 -283.57556) (xy 314.026554 -283.57556) (xy 314.018511 -283.626342) (xy 314.002623 -283.675241)
			(xy 313.97928 -283.721053) (xy 313.949059 -283.762649) (xy 313.912703 -283.799005) (xy 313.871107 -283.829226)
			(xy 313.825295 -283.852569) (xy 313.776396 -283.868457) (xy 313.725614 -283.8765) (xy 313.674198 -283.8765)
			(xy 313.623416 -283.868457) (xy 313.574517 -283.852569) (xy 313.528705 -283.829226) (xy 313.487109 -283.799005)
			(xy 313.450753 -283.762649) (xy 313.420532 -283.721053) (xy 313.397189 -283.675241) (xy 313.381301 -283.626342)
			(xy 313.373258 -283.57556) (xy 313.054326 -283.57556) (xy 313.04661 -283.623036) (xy 313.031026 -283.669717)
			(xy 313.008155 -283.713294) (xy 312.97859 -283.752638) (xy 312.943097 -283.78673) (xy 312.902594 -283.814686)
			(xy 312.858132 -283.835784) (xy 312.810861 -283.849476) (xy 312.762006 -283.855408) (xy 312.712831 -283.853427)
			(xy 312.664612 -283.843583) (xy 312.618596 -283.826131) (xy 312.575975 -283.801524) (xy 312.537854 -283.770399)
			(xy 312.505219 -283.733562) (xy 312.478916 -283.691966) (xy 312.459625 -283.64669) (xy 312.447848 -283.598906)
			(xy 312.443888 -283.549852) (xy 312.10504 -283.549852) (xy 312.104545 -283.574459) (xy 312.09665 -283.623036)
			(xy 312.081066 -283.669717) (xy 312.058195 -283.713294) (xy 312.02863 -283.752638) (xy 311.993137 -283.78673)
			(xy 311.952634 -283.814686) (xy 311.908172 -283.835784) (xy 311.860901 -283.849476) (xy 311.812046 -283.855408)
			(xy 311.762871 -283.853427) (xy 311.714652 -283.843583) (xy 311.668636 -283.826131) (xy 311.626015 -283.801524)
			(xy 311.587894 -283.770399) (xy 311.555259 -283.733562) (xy 311.528956 -283.691966) (xy 311.509665 -283.64669)
			(xy 311.497888 -283.598906) (xy 311.493928 -283.549852) (xy 311.15508 -283.549852) (xy 311.154585 -283.574459)
			(xy 311.14669 -283.623036) (xy 311.131106 -283.669717) (xy 311.108235 -283.713294) (xy 311.07867 -283.752638)
			(xy 311.043177 -283.78673) (xy 311.002674 -283.814686) (xy 310.958212 -283.835784) (xy 310.910941 -283.849476)
			(xy 310.862086 -283.855408) (xy 310.812911 -283.853427) (xy 310.764692 -283.843583) (xy 310.718676 -283.826131)
			(xy 310.676055 -283.801524) (xy 310.637934 -283.770399) (xy 310.605299 -283.733562) (xy 310.578996 -283.691966)
			(xy 310.559705 -283.64669) (xy 310.547928 -283.598906) (xy 310.543968 -283.549852) (xy 310.20512 -283.549852)
			(xy 310.204625 -283.574459) (xy 310.19673 -283.623036) (xy 310.181146 -283.669717) (xy 310.158275 -283.713294)
			(xy 310.12871 -283.752638) (xy 310.093217 -283.78673) (xy 310.052714 -283.814686) (xy 310.008252 -283.835784)
			(xy 309.960981 -283.849476) (xy 309.912126 -283.855408) (xy 309.862951 -283.853427) (xy 309.814732 -283.843583)
			(xy 309.768716 -283.826131) (xy 309.726095 -283.801524) (xy 309.687974 -283.770399) (xy 309.655339 -283.733562)
			(xy 309.629036 -283.691966) (xy 309.609745 -283.64669) (xy 309.597968 -283.598906) (xy 309.594008 -283.549852)
			(xy 309.25516 -283.549852) (xy 309.254665 -283.574459) (xy 309.24677 -283.623036) (xy 309.231186 -283.669717)
			(xy 309.208315 -283.713294) (xy 309.17875 -283.752638) (xy 309.143257 -283.78673) (xy 309.102754 -283.814686)
			(xy 309.058292 -283.835784) (xy 309.011021 -283.849476) (xy 308.962166 -283.855408) (xy 308.912991 -283.853427)
			(xy 308.864772 -283.843583) (xy 308.818756 -283.826131) (xy 308.776135 -283.801524) (xy 308.738014 -283.770399)
			(xy 308.705379 -283.733562) (xy 308.679076 -283.691966) (xy 308.659785 -283.64669) (xy 308.648008 -283.598906)
			(xy 308.644048 -283.549852) (xy 308.327044 -283.549852) (xy 308.32654 -283.57556) (xy 308.318497 -283.626342)
			(xy 308.302609 -283.675241) (xy 308.279266 -283.721053) (xy 308.249045 -283.762649) (xy 308.212689 -283.799005)
			(xy 308.171093 -283.829226) (xy 308.125281 -283.852569) (xy 308.076382 -283.868457) (xy 308.0256 -283.8765)
			(xy 307.974184 -283.8765) (xy 307.923402 -283.868457) (xy 307.874503 -283.852569) (xy 307.828691 -283.829226)
			(xy 307.787095 -283.799005) (xy 307.750739 -283.762649) (xy 307.720518 -283.721053) (xy 307.697175 -283.675241)
			(xy 307.681287 -283.626342) (xy 307.673244 -283.57556) (xy 307.376326 -283.57556) (xy 307.368283 -283.626342)
			(xy 307.352395 -283.675241) (xy 307.329052 -283.721053) (xy 307.298831 -283.762649) (xy 307.262475 -283.799005)
			(xy 307.220879 -283.829226) (xy 307.175067 -283.852569) (xy 307.126168 -283.868457) (xy 307.075386 -283.8765)
			(xy 307.02397 -283.8765) (xy 306.973188 -283.868457) (xy 306.924289 -283.852569) (xy 306.878477 -283.829226)
			(xy 306.836881 -283.799005) (xy 306.800525 -283.762649) (xy 306.770304 -283.721053) (xy 306.746961 -283.675241)
			(xy 306.731073 -283.626342) (xy 306.72303 -283.57556) (xy 306.404352 -283.57556) (xy 306.396636 -283.623036)
			(xy 306.381052 -283.669717) (xy 306.358181 -283.713294) (xy 306.328616 -283.752638) (xy 306.293123 -283.78673)
			(xy 306.25262 -283.814686) (xy 306.208158 -283.835784) (xy 306.160887 -283.849476) (xy 306.112032 -283.855408)
			(xy 306.062857 -283.853427) (xy 306.014638 -283.843583) (xy 305.968622 -283.826131) (xy 305.926001 -283.801524)
			(xy 305.88788 -283.770399) (xy 305.855245 -283.733562) (xy 305.828942 -283.691966) (xy 305.809651 -283.64669)
			(xy 305.797874 -283.598906) (xy 305.793914 -283.549852) (xy 266.368379 -283.549852) (xy 266.377597 -283.553769)
			(xy 266.425203 -283.582823) (xy 266.468071 -283.618498) (xy 266.505288 -283.660035) (xy 266.536061 -283.706548)
			(xy 266.559733 -283.757045) (xy 266.575801 -283.810452) (xy 266.583921 -283.865628) (xy 266.58443 -283.893514)
			(xy 266.583921 -283.9214) (xy 266.575801 -283.976576) (xy 266.561283 -284.024832) (xy 268.26897 -284.024832)
			(xy 268.27293 -283.975778) (xy 268.284707 -283.927994) (xy 268.303998 -283.882718) (xy 268.330301 -283.841122)
			(xy 268.362936 -283.804285) (xy 268.401057 -283.77316) (xy 268.443678 -283.748553) (xy 268.489694 -283.731101)
			(xy 268.537913 -283.721257) (xy 268.587088 -283.719276) (xy 268.635943 -283.725208) (xy 268.683214 -283.7389)
			(xy 268.727676 -283.759998) (xy 268.768179 -283.787954) (xy 268.803672 -283.822046) (xy 268.833237 -283.86139)
			(xy 268.856108 -283.904967) (xy 268.871692 -283.951648) (xy 268.879587 -284.000225) (xy 268.880082 -284.024832)
			(xy 269.21893 -284.024832) (xy 269.22289 -283.975778) (xy 269.234667 -283.927994) (xy 269.253958 -283.882718)
			(xy 269.280261 -283.841122) (xy 269.312896 -283.804285) (xy 269.351017 -283.77316) (xy 269.393638 -283.748553)
			(xy 269.439654 -283.731101) (xy 269.487873 -283.721257) (xy 269.537048 -283.719276) (xy 269.585903 -283.725208)
			(xy 269.633174 -283.7389) (xy 269.677636 -283.759998) (xy 269.718139 -283.787954) (xy 269.753632 -283.822046)
			(xy 269.783197 -283.86139) (xy 269.806068 -283.904967) (xy 269.821652 -283.951648) (xy 269.829547 -284.000225)
			(xy 269.830042 -284.024832) (xy 270.169144 -284.024832) (xy 270.173104 -283.975778) (xy 270.184881 -283.927994)
			(xy 270.204172 -283.882718) (xy 270.230475 -283.841122) (xy 270.26311 -283.804285) (xy 270.301231 -283.77316)
			(xy 270.343852 -283.748553) (xy 270.389868 -283.731101) (xy 270.438087 -283.721257) (xy 270.487262 -283.719276)
			(xy 270.536117 -283.725208) (xy 270.583388 -283.7389) (xy 270.62785 -283.759998) (xy 270.668353 -283.787954)
			(xy 270.703846 -283.822046) (xy 270.733411 -283.86139) (xy 270.756282 -283.904967) (xy 270.771866 -283.951648)
			(xy 270.779761 -284.000225) (xy 270.780256 -284.024832) (xy 271.119104 -284.024832) (xy 271.123064 -283.975778)
			(xy 271.134841 -283.927994) (xy 271.154132 -283.882718) (xy 271.180435 -283.841122) (xy 271.21307 -283.804285)
			(xy 271.251191 -283.77316) (xy 271.293812 -283.748553) (xy 271.339828 -283.731101) (xy 271.388047 -283.721257)
			(xy 271.437222 -283.719276) (xy 271.486077 -283.725208) (xy 271.533348 -283.7389) (xy 271.57781 -283.759998)
			(xy 271.618313 -283.787954) (xy 271.653806 -283.822046) (xy 271.683371 -283.86139) (xy 271.706242 -283.904967)
			(xy 271.721826 -283.951648) (xy 271.729721 -284.000225) (xy 271.730216 -284.024832) (xy 272.069064 -284.024832)
			(xy 272.073024 -283.975778) (xy 272.084801 -283.927994) (xy 272.104092 -283.882718) (xy 272.130395 -283.841122)
			(xy 272.16303 -283.804285) (xy 272.201151 -283.77316) (xy 272.243772 -283.748553) (xy 272.289788 -283.731101)
			(xy 272.338007 -283.721257) (xy 272.387182 -283.719276) (xy 272.436037 -283.725208) (xy 272.483308 -283.7389)
			(xy 272.52777 -283.759998) (xy 272.568273 -283.787954) (xy 272.603766 -283.822046) (xy 272.633331 -283.86139)
			(xy 272.656202 -283.904967) (xy 272.671786 -283.951648) (xy 272.679681 -284.000225) (xy 272.680176 -284.024832)
			(xy 274.918944 -284.024832) (xy 274.922904 -283.975778) (xy 274.934681 -283.927994) (xy 274.953972 -283.882718)
			(xy 274.980275 -283.841122) (xy 275.01291 -283.804285) (xy 275.051031 -283.77316) (xy 275.093652 -283.748553)
			(xy 275.139668 -283.731101) (xy 275.187887 -283.721257) (xy 275.237062 -283.719276) (xy 275.285917 -283.725208)
			(xy 275.333188 -283.7389) (xy 275.37765 -283.759998) (xy 275.418153 -283.787954) (xy 275.453646 -283.822046)
			(xy 275.483211 -283.86139) (xy 275.506082 -283.904967) (xy 275.521666 -283.951648) (xy 275.529561 -284.000225)
			(xy 275.530056 -284.024832) (xy 275.868904 -284.024832) (xy 275.872864 -283.975778) (xy 275.884641 -283.927994)
			(xy 275.903932 -283.882718) (xy 275.930235 -283.841122) (xy 275.96287 -283.804285) (xy 276.000991 -283.77316)
			(xy 276.043612 -283.748553) (xy 276.089628 -283.731101) (xy 276.137847 -283.721257) (xy 276.187022 -283.719276)
			(xy 276.235877 -283.725208) (xy 276.283148 -283.7389) (xy 276.32761 -283.759998) (xy 276.368113 -283.787954)
			(xy 276.403606 -283.822046) (xy 276.433171 -283.86139) (xy 276.456042 -283.904967) (xy 276.471626 -283.951648)
			(xy 276.479521 -284.000225) (xy 276.480016 -284.024832) (xy 276.819118 -284.024832) (xy 276.823078 -283.975778)
			(xy 276.834855 -283.927994) (xy 276.854146 -283.882718) (xy 276.880449 -283.841122) (xy 276.913084 -283.804285)
			(xy 276.951205 -283.77316) (xy 276.993826 -283.748553) (xy 277.039842 -283.731101) (xy 277.088061 -283.721257)
			(xy 277.137236 -283.719276) (xy 277.186091 -283.725208) (xy 277.233362 -283.7389) (xy 277.277824 -283.759998)
			(xy 277.318327 -283.787954) (xy 277.35382 -283.822046) (xy 277.383385 -283.86139) (xy 277.406256 -283.904967)
			(xy 277.42184 -283.951648) (xy 277.429735 -284.000225) (xy 277.43023 -284.024832) (xy 277.769078 -284.024832)
			(xy 277.773038 -283.975778) (xy 277.784815 -283.927994) (xy 277.804106 -283.882718) (xy 277.830409 -283.841122)
			(xy 277.863044 -283.804285) (xy 277.901165 -283.77316) (xy 277.943786 -283.748553) (xy 277.989802 -283.731101)
			(xy 278.038021 -283.721257) (xy 278.087196 -283.719276) (xy 278.136051 -283.725208) (xy 278.183322 -283.7389)
			(xy 278.227784 -283.759998) (xy 278.268287 -283.787954) (xy 278.30378 -283.822046) (xy 278.333345 -283.86139)
			(xy 278.356216 -283.904967) (xy 278.3718 -283.951648) (xy 278.379695 -284.000225) (xy 278.38019 -284.024832)
			(xy 278.719038 -284.024832) (xy 278.722998 -283.975778) (xy 278.734775 -283.927994) (xy 278.754066 -283.882718)
			(xy 278.780369 -283.841122) (xy 278.813004 -283.804285) (xy 278.851125 -283.77316) (xy 278.893746 -283.748553)
			(xy 278.939762 -283.731101) (xy 278.987981 -283.721257) (xy 279.037156 -283.719276) (xy 279.086011 -283.725208)
			(xy 279.133282 -283.7389) (xy 279.177744 -283.759998) (xy 279.218247 -283.787954) (xy 279.25374 -283.822046)
			(xy 279.283305 -283.86139) (xy 279.306176 -283.904967) (xy 279.32176 -283.951648) (xy 279.329655 -284.000225)
			(xy 279.33015 -284.024832) (xy 279.668998 -284.024832) (xy 279.672958 -283.975778) (xy 279.684735 -283.927994)
			(xy 279.704026 -283.882718) (xy 279.730329 -283.841122) (xy 279.762964 -283.804285) (xy 279.801085 -283.77316)
			(xy 279.843706 -283.748553) (xy 279.889722 -283.731101) (xy 279.937941 -283.721257) (xy 279.987116 -283.719276)
			(xy 280.035971 -283.725208) (xy 280.083242 -283.7389) (xy 280.127704 -283.759998) (xy 280.168207 -283.787954)
			(xy 280.2037 -283.822046) (xy 280.233265 -283.86139) (xy 280.256136 -283.904967) (xy 280.27172 -283.951648)
			(xy 280.279615 -284.000225) (xy 280.28011 -284.024832) (xy 280.618958 -284.024832) (xy 280.622918 -283.975778)
			(xy 280.634695 -283.927994) (xy 280.653986 -283.882718) (xy 280.680289 -283.841122) (xy 280.712924 -283.804285)
			(xy 280.751045 -283.77316) (xy 280.793666 -283.748553) (xy 280.839682 -283.731101) (xy 280.887901 -283.721257)
			(xy 280.937076 -283.719276) (xy 280.985931 -283.725208) (xy 281.033202 -283.7389) (xy 281.077664 -283.759998)
			(xy 281.118167 -283.787954) (xy 281.15366 -283.822046) (xy 281.183225 -283.86139) (xy 281.206096 -283.904967)
			(xy 281.22168 -283.951648) (xy 281.229575 -284.000225) (xy 281.23007 -284.024832) (xy 281.568918 -284.024832)
			(xy 281.572878 -283.975778) (xy 281.584655 -283.927994) (xy 281.603946 -283.882718) (xy 281.630249 -283.841122)
			(xy 281.662884 -283.804285) (xy 281.701005 -283.77316) (xy 281.743626 -283.748553) (xy 281.789642 -283.731101)
			(xy 281.837861 -283.721257) (xy 281.887036 -283.719276) (xy 281.935891 -283.725208) (xy 281.983162 -283.7389)
			(xy 282.027624 -283.759998) (xy 282.068127 -283.787954) (xy 282.10362 -283.822046) (xy 282.133185 -283.86139)
			(xy 282.156056 -283.904967) (xy 282.17164 -283.951648) (xy 282.179535 -284.000225) (xy 282.18003 -284.024832)
			(xy 282.519132 -284.024832) (xy 282.523092 -283.975778) (xy 282.534869 -283.927994) (xy 282.55416 -283.882718)
			(xy 282.580463 -283.841122) (xy 282.613098 -283.804285) (xy 282.651219 -283.77316) (xy 282.69384 -283.748553)
			(xy 282.739856 -283.731101) (xy 282.788075 -283.721257) (xy 282.83725 -283.719276) (xy 282.886105 -283.725208)
			(xy 282.933376 -283.7389) (xy 282.977838 -283.759998) (xy 283.018341 -283.787954) (xy 283.053834 -283.822046)
			(xy 283.083399 -283.86139) (xy 283.10627 -283.904967) (xy 283.121854 -283.951648) (xy 283.129749 -284.000225)
			(xy 283.130244 -284.024832) (xy 283.469092 -284.024832) (xy 283.473052 -283.975778) (xy 283.484829 -283.927994)
			(xy 283.50412 -283.882718) (xy 283.530423 -283.841122) (xy 283.563058 -283.804285) (xy 283.601179 -283.77316)
			(xy 283.6438 -283.748553) (xy 283.689816 -283.731101) (xy 283.738035 -283.721257) (xy 283.78721 -283.719276)
			(xy 283.836065 -283.725208) (xy 283.883336 -283.7389) (xy 283.927798 -283.759998) (xy 283.968301 -283.787954)
			(xy 284.003794 -283.822046) (xy 284.033359 -283.86139) (xy 284.05623 -283.904967) (xy 284.071814 -283.951648)
			(xy 284.079709 -284.000225) (xy 284.080204 -284.024832) (xy 284.419052 -284.024832) (xy 284.423012 -283.975778)
			(xy 284.434789 -283.927994) (xy 284.45408 -283.882718) (xy 284.480383 -283.841122) (xy 284.513018 -283.804285)
			(xy 284.551139 -283.77316) (xy 284.59376 -283.748553) (xy 284.639776 -283.731101) (xy 284.687995 -283.721257)
			(xy 284.73717 -283.719276) (xy 284.786025 -283.725208) (xy 284.833296 -283.7389) (xy 284.877758 -283.759998)
			(xy 284.918261 -283.787954) (xy 284.953754 -283.822046) (xy 284.983319 -283.86139) (xy 285.00619 -283.904967)
			(xy 285.021774 -283.951648) (xy 285.029669 -284.000225) (xy 285.030164 -284.024832) (xy 285.369012 -284.024832)
			(xy 285.372972 -283.975778) (xy 285.384749 -283.927994) (xy 285.40404 -283.882718) (xy 285.430343 -283.841122)
			(xy 285.462978 -283.804285) (xy 285.501099 -283.77316) (xy 285.54372 -283.748553) (xy 285.589736 -283.731101)
			(xy 285.637955 -283.721257) (xy 285.68713 -283.719276) (xy 285.735985 -283.725208) (xy 285.783256 -283.7389)
			(xy 285.827718 -283.759998) (xy 285.868221 -283.787954) (xy 285.903714 -283.822046) (xy 285.933279 -283.86139)
			(xy 285.95615 -283.904967) (xy 285.971734 -283.951648) (xy 285.979629 -284.000225) (xy 285.980124 -284.024832)
			(xy 286.318972 -284.024832) (xy 286.322932 -283.975778) (xy 286.334709 -283.927994) (xy 286.354 -283.882718)
			(xy 286.380303 -283.841122) (xy 286.412938 -283.804285) (xy 286.451059 -283.77316) (xy 286.49368 -283.748553)
			(xy 286.539696 -283.731101) (xy 286.587915 -283.721257) (xy 286.63709 -283.719276) (xy 286.685945 -283.725208)
			(xy 286.733216 -283.7389) (xy 286.777678 -283.759998) (xy 286.818181 -283.787954) (xy 286.853674 -283.822046)
			(xy 286.883239 -283.86139) (xy 286.90611 -283.904967) (xy 286.921694 -283.951648) (xy 286.929589 -284.000225)
			(xy 286.930084 -284.024832) (xy 287.268932 -284.024832) (xy 287.272892 -283.975778) (xy 287.284669 -283.927994)
			(xy 287.30396 -283.882718) (xy 287.330263 -283.841122) (xy 287.362898 -283.804285) (xy 287.401019 -283.77316)
			(xy 287.44364 -283.748553) (xy 287.489656 -283.731101) (xy 287.537875 -283.721257) (xy 287.58705 -283.719276)
			(xy 287.635905 -283.725208) (xy 287.683176 -283.7389) (xy 287.727638 -283.759998) (xy 287.768141 -283.787954)
			(xy 287.803634 -283.822046) (xy 287.833199 -283.86139) (xy 287.85607 -283.904967) (xy 287.871654 -283.951648)
			(xy 287.879549 -284.000225) (xy 287.880044 -284.024832) (xy 288.218892 -284.024832) (xy 288.222852 -283.975778)
			(xy 288.234629 -283.927994) (xy 288.25392 -283.882718) (xy 288.280223 -283.841122) (xy 288.312858 -283.804285)
			(xy 288.350979 -283.77316) (xy 288.3936 -283.748553) (xy 288.439616 -283.731101) (xy 288.487835 -283.721257)
			(xy 288.53701 -283.719276) (xy 288.585865 -283.725208) (xy 288.633136 -283.7389) (xy 288.677598 -283.759998)
			(xy 288.718101 -283.787954) (xy 288.753594 -283.822046) (xy 288.783159 -283.86139) (xy 288.80603 -283.904967)
			(xy 288.821614 -283.951648) (xy 288.829509 -284.000225) (xy 288.830004 -284.024832) (xy 289.169106 -284.024832)
			(xy 289.173066 -283.975778) (xy 289.184843 -283.927994) (xy 289.204134 -283.882718) (xy 289.230437 -283.841122)
			(xy 289.263072 -283.804285) (xy 289.301193 -283.77316) (xy 289.343814 -283.748553) (xy 289.38983 -283.731101)
			(xy 289.438049 -283.721257) (xy 289.487224 -283.719276) (xy 289.536079 -283.725208) (xy 289.58335 -283.7389)
			(xy 289.627812 -283.759998) (xy 289.668315 -283.787954) (xy 289.703808 -283.822046) (xy 289.733373 -283.86139)
			(xy 289.756244 -283.904967) (xy 289.771828 -283.951648) (xy 289.779723 -284.000225) (xy 289.780218 -284.024832)
			(xy 290.119066 -284.024832) (xy 290.123026 -283.975778) (xy 290.134803 -283.927994) (xy 290.154094 -283.882718)
			(xy 290.180397 -283.841122) (xy 290.213032 -283.804285) (xy 290.251153 -283.77316) (xy 290.293774 -283.748553)
			(xy 290.33979 -283.731101) (xy 290.388009 -283.721257) (xy 290.437184 -283.719276) (xy 290.486039 -283.725208)
			(xy 290.53331 -283.7389) (xy 290.577772 -283.759998) (xy 290.618275 -283.787954) (xy 290.653768 -283.822046)
			(xy 290.683333 -283.86139) (xy 290.706204 -283.904967) (xy 290.721788 -283.951648) (xy 290.729683 -284.000225)
			(xy 290.730178 -284.024832) (xy 292.018986 -284.024832) (xy 292.022946 -283.975778) (xy 292.034723 -283.927994)
			(xy 292.054014 -283.882718) (xy 292.080317 -283.841122) (xy 292.112952 -283.804285) (xy 292.151073 -283.77316)
			(xy 292.193694 -283.748553) (xy 292.23971 -283.731101) (xy 292.287929 -283.721257) (xy 292.337104 -283.719276)
			(xy 292.385959 -283.725208) (xy 292.43323 -283.7389) (xy 292.477692 -283.759998) (xy 292.518195 -283.787954)
			(xy 292.553688 -283.822046) (xy 292.583253 -283.86139) (xy 292.606124 -283.904967) (xy 292.621708 -283.951648)
			(xy 292.629603 -284.000225) (xy 292.630098 -284.024832) (xy 292.968946 -284.024832) (xy 292.972906 -283.975778)
			(xy 292.984683 -283.927994) (xy 293.003974 -283.882718) (xy 293.030277 -283.841122) (xy 293.062912 -283.804285)
			(xy 293.101033 -283.77316) (xy 293.143654 -283.748553) (xy 293.18967 -283.731101) (xy 293.237889 -283.721257)
			(xy 293.287064 -283.719276) (xy 293.335919 -283.725208) (xy 293.38319 -283.7389) (xy 293.427652 -283.759998)
			(xy 293.468155 -283.787954) (xy 293.503648 -283.822046) (xy 293.533213 -283.86139) (xy 293.556084 -283.904967)
			(xy 293.571668 -283.951648) (xy 293.579563 -284.000225) (xy 293.580058 -284.024832) (xy 293.918906 -284.024832)
			(xy 293.922866 -283.975778) (xy 293.934643 -283.927994) (xy 293.953934 -283.882718) (xy 293.980237 -283.841122)
			(xy 294.012872 -283.804285) (xy 294.050993 -283.77316) (xy 294.093614 -283.748553) (xy 294.13963 -283.731101)
			(xy 294.187849 -283.721257) (xy 294.237024 -283.719276) (xy 294.285879 -283.725208) (xy 294.33315 -283.7389)
			(xy 294.377612 -283.759998) (xy 294.418115 -283.787954) (xy 294.453608 -283.822046) (xy 294.483173 -283.86139)
			(xy 294.506044 -283.904967) (xy 294.521628 -283.951648) (xy 294.529523 -284.000225) (xy 294.530018 -284.024832)
			(xy 294.86912 -284.024832) (xy 294.87308 -283.975778) (xy 294.884857 -283.927994) (xy 294.904148 -283.882718)
			(xy 294.930451 -283.841122) (xy 294.963086 -283.804285) (xy 295.001207 -283.77316) (xy 295.043828 -283.748553)
			(xy 295.089844 -283.731101) (xy 295.138063 -283.721257) (xy 295.187238 -283.719276) (xy 295.236093 -283.725208)
			(xy 295.283364 -283.7389) (xy 295.327826 -283.759998) (xy 295.368329 -283.787954) (xy 295.403822 -283.822046)
			(xy 295.433387 -283.86139) (xy 295.456258 -283.904967) (xy 295.471842 -283.951648) (xy 295.479737 -284.000225)
			(xy 295.480232 -284.024832) (xy 295.81908 -284.024832) (xy 295.82304 -283.975778) (xy 295.834817 -283.927994)
			(xy 295.854108 -283.882718) (xy 295.880411 -283.841122) (xy 295.913046 -283.804285) (xy 295.951167 -283.77316)
			(xy 295.993788 -283.748553) (xy 296.039804 -283.731101) (xy 296.088023 -283.721257) (xy 296.137198 -283.719276)
			(xy 296.186053 -283.725208) (xy 296.233324 -283.7389) (xy 296.277786 -283.759998) (xy 296.318289 -283.787954)
			(xy 296.353782 -283.822046) (xy 296.383347 -283.86139) (xy 296.406218 -283.904967) (xy 296.421802 -283.951648)
			(xy 296.429697 -284.000225) (xy 296.430192 -284.024832) (xy 296.76904 -284.024832) (xy 296.773 -283.975778)
			(xy 296.784777 -283.927994) (xy 296.804068 -283.882718) (xy 296.830371 -283.841122) (xy 296.863006 -283.804285)
			(xy 296.901127 -283.77316) (xy 296.943748 -283.748553) (xy 296.989764 -283.731101) (xy 297.037983 -283.721257)
			(xy 297.087158 -283.719276) (xy 297.136013 -283.725208) (xy 297.183284 -283.7389) (xy 297.227746 -283.759998)
			(xy 297.268249 -283.787954) (xy 297.303742 -283.822046) (xy 297.333307 -283.86139) (xy 297.356178 -283.904967)
			(xy 297.371762 -283.951648) (xy 297.379657 -284.000225) (xy 297.380152 -284.024832) (xy 297.719 -284.024832)
			(xy 297.72296 -283.975778) (xy 297.734737 -283.927994) (xy 297.754028 -283.882718) (xy 297.780331 -283.841122)
			(xy 297.812966 -283.804285) (xy 297.851087 -283.77316) (xy 297.893708 -283.748553) (xy 297.939724 -283.731101)
			(xy 297.987943 -283.721257) (xy 298.037118 -283.719276) (xy 298.085973 -283.725208) (xy 298.133244 -283.7389)
			(xy 298.177706 -283.759998) (xy 298.218209 -283.787954) (xy 298.253702 -283.822046) (xy 298.283267 -283.86139)
			(xy 298.306138 -283.904967) (xy 298.321722 -283.951648) (xy 298.329617 -284.000225) (xy 298.330112 -284.024832)
			(xy 298.66896 -284.024832) (xy 298.67292 -283.975778) (xy 298.684697 -283.927994) (xy 298.703988 -283.882718)
			(xy 298.730291 -283.841122) (xy 298.762926 -283.804285) (xy 298.801047 -283.77316) (xy 298.843668 -283.748553)
			(xy 298.889684 -283.731101) (xy 298.937903 -283.721257) (xy 298.987078 -283.719276) (xy 299.035933 -283.725208)
			(xy 299.083204 -283.7389) (xy 299.127666 -283.759998) (xy 299.168169 -283.787954) (xy 299.203662 -283.822046)
			(xy 299.233227 -283.86139) (xy 299.256098 -283.904967) (xy 299.271682 -283.951648) (xy 299.279577 -284.000225)
			(xy 299.280072 -284.024832) (xy 300.56888 -284.024832) (xy 300.57284 -283.975778) (xy 300.584617 -283.927994)
			(xy 300.603908 -283.882718) (xy 300.630211 -283.841122) (xy 300.662846 -283.804285) (xy 300.700967 -283.77316)
			(xy 300.743588 -283.748553) (xy 300.789604 -283.731101) (xy 300.837823 -283.721257) (xy 300.886998 -283.719276)
			(xy 300.935853 -283.725208) (xy 300.983124 -283.7389) (xy 301.027586 -283.759998) (xy 301.068089 -283.787954)
			(xy 301.103582 -283.822046) (xy 301.133147 -283.86139) (xy 301.156018 -283.904967) (xy 301.171602 -283.951648)
			(xy 301.179497 -284.000225) (xy 301.179992 -284.024832) (xy 301.519094 -284.024832) (xy 301.523054 -283.975778)
			(xy 301.534831 -283.927994) (xy 301.554122 -283.882718) (xy 301.580425 -283.841122) (xy 301.61306 -283.804285)
			(xy 301.651181 -283.77316) (xy 301.693802 -283.748553) (xy 301.739818 -283.731101) (xy 301.788037 -283.721257)
			(xy 301.837212 -283.719276) (xy 301.886067 -283.725208) (xy 301.933338 -283.7389) (xy 301.9778 -283.759998)
			(xy 302.018303 -283.787954) (xy 302.053796 -283.822046) (xy 302.083361 -283.86139) (xy 302.106232 -283.904967)
			(xy 302.121816 -283.951648) (xy 302.129711 -284.000225) (xy 302.130206 -284.024832) (xy 302.469054 -284.024832)
			(xy 302.473014 -283.975778) (xy 302.484791 -283.927994) (xy 302.504082 -283.882718) (xy 302.530385 -283.841122)
			(xy 302.56302 -283.804285) (xy 302.601141 -283.77316) (xy 302.643762 -283.748553) (xy 302.689778 -283.731101)
			(xy 302.737997 -283.721257) (xy 302.787172 -283.719276) (xy 302.836027 -283.725208) (xy 302.883298 -283.7389)
			(xy 302.92776 -283.759998) (xy 302.968263 -283.787954) (xy 303.003756 -283.822046) (xy 303.033321 -283.86139)
			(xy 303.056192 -283.904967) (xy 303.071776 -283.951648) (xy 303.079671 -284.000225) (xy 303.080166 -284.024832)
			(xy 303.079671 -284.049439) (xy 303.071776 -284.098016) (xy 303.056192 -284.144697) (xy 303.033321 -284.188274)
			(xy 303.003756 -284.227618) (xy 302.968263 -284.26171) (xy 302.92776 -284.289666) (xy 302.883298 -284.310764)
			(xy 302.836027 -284.324456) (xy 302.787172 -284.330388) (xy 302.737997 -284.328407) (xy 302.689778 -284.318563)
			(xy 302.643762 -284.301111) (xy 302.601141 -284.276504) (xy 302.56302 -284.245379) (xy 302.530385 -284.208542)
			(xy 302.504082 -284.166946) (xy 302.484791 -284.12167) (xy 302.473014 -284.073886) (xy 302.469054 -284.024832)
			(xy 302.130206 -284.024832) (xy 302.129711 -284.049439) (xy 302.121816 -284.098016) (xy 302.106232 -284.144697)
			(xy 302.083361 -284.188274) (xy 302.053796 -284.227618) (xy 302.018303 -284.26171) (xy 301.9778 -284.289666)
			(xy 301.933338 -284.310764) (xy 301.886067 -284.324456) (xy 301.837212 -284.330388) (xy 301.788037 -284.328407)
			(xy 301.739818 -284.318563) (xy 301.693802 -284.301111) (xy 301.651181 -284.276504) (xy 301.61306 -284.245379)
			(xy 301.580425 -284.208542) (xy 301.554122 -284.166946) (xy 301.534831 -284.12167) (xy 301.523054 -284.073886)
			(xy 301.519094 -284.024832) (xy 301.179992 -284.024832) (xy 301.179497 -284.049439) (xy 301.171602 -284.098016)
			(xy 301.156018 -284.144697) (xy 301.133147 -284.188274) (xy 301.103582 -284.227618) (xy 301.068089 -284.26171)
			(xy 301.027586 -284.289666) (xy 300.983124 -284.310764) (xy 300.935853 -284.324456) (xy 300.886998 -284.330388)
			(xy 300.837823 -284.328407) (xy 300.789604 -284.318563) (xy 300.743588 -284.301111) (xy 300.700967 -284.276504)
			(xy 300.662846 -284.245379) (xy 300.630211 -284.208542) (xy 300.603908 -284.166946) (xy 300.584617 -284.12167)
			(xy 300.57284 -284.073886) (xy 300.56888 -284.024832) (xy 299.280072 -284.024832) (xy 299.279577 -284.049439)
			(xy 299.271682 -284.098016) (xy 299.256098 -284.144697) (xy 299.233227 -284.188274) (xy 299.203662 -284.227618)
			(xy 299.168169 -284.26171) (xy 299.127666 -284.289666) (xy 299.083204 -284.310764) (xy 299.035933 -284.324456)
			(xy 298.987078 -284.330388) (xy 298.937903 -284.328407) (xy 298.889684 -284.318563) (xy 298.843668 -284.301111)
			(xy 298.801047 -284.276504) (xy 298.762926 -284.245379) (xy 298.730291 -284.208542) (xy 298.703988 -284.166946)
			(xy 298.684697 -284.12167) (xy 298.67292 -284.073886) (xy 298.66896 -284.024832) (xy 298.330112 -284.024832)
			(xy 298.329617 -284.049439) (xy 298.321722 -284.098016) (xy 298.306138 -284.144697) (xy 298.283267 -284.188274)
			(xy 298.253702 -284.227618) (xy 298.218209 -284.26171) (xy 298.177706 -284.289666) (xy 298.133244 -284.310764)
			(xy 298.085973 -284.324456) (xy 298.037118 -284.330388) (xy 297.987943 -284.328407) (xy 297.939724 -284.318563)
			(xy 297.893708 -284.301111) (xy 297.851087 -284.276504) (xy 297.812966 -284.245379) (xy 297.780331 -284.208542)
			(xy 297.754028 -284.166946) (xy 297.734737 -284.12167) (xy 297.72296 -284.073886) (xy 297.719 -284.024832)
			(xy 297.380152 -284.024832) (xy 297.379657 -284.049439) (xy 297.371762 -284.098016) (xy 297.356178 -284.144697)
			(xy 297.333307 -284.188274) (xy 297.303742 -284.227618) (xy 297.268249 -284.26171) (xy 297.227746 -284.289666)
			(xy 297.183284 -284.310764) (xy 297.136013 -284.324456) (xy 297.087158 -284.330388) (xy 297.037983 -284.328407)
			(xy 296.989764 -284.318563) (xy 296.943748 -284.301111) (xy 296.901127 -284.276504) (xy 296.863006 -284.245379)
			(xy 296.830371 -284.208542) (xy 296.804068 -284.166946) (xy 296.784777 -284.12167) (xy 296.773 -284.073886)
			(xy 296.76904 -284.024832) (xy 296.430192 -284.024832) (xy 296.429697 -284.049439) (xy 296.421802 -284.098016)
			(xy 296.406218 -284.144697) (xy 296.383347 -284.188274) (xy 296.353782 -284.227618) (xy 296.318289 -284.26171)
			(xy 296.277786 -284.289666) (xy 296.233324 -284.310764) (xy 296.186053 -284.324456) (xy 296.137198 -284.330388)
			(xy 296.088023 -284.328407) (xy 296.039804 -284.318563) (xy 295.993788 -284.301111) (xy 295.951167 -284.276504)
			(xy 295.913046 -284.245379) (xy 295.880411 -284.208542) (xy 295.854108 -284.166946) (xy 295.834817 -284.12167)
			(xy 295.82304 -284.073886) (xy 295.81908 -284.024832) (xy 295.480232 -284.024832) (xy 295.479737 -284.049439)
			(xy 295.471842 -284.098016) (xy 295.456258 -284.144697) (xy 295.433387 -284.188274) (xy 295.403822 -284.227618)
			(xy 295.368329 -284.26171) (xy 295.327826 -284.289666) (xy 295.283364 -284.310764) (xy 295.236093 -284.324456)
			(xy 295.187238 -284.330388) (xy 295.138063 -284.328407) (xy 295.089844 -284.318563) (xy 295.043828 -284.301111)
			(xy 295.001207 -284.276504) (xy 294.963086 -284.245379) (xy 294.930451 -284.208542) (xy 294.904148 -284.166946)
			(xy 294.884857 -284.12167) (xy 294.87308 -284.073886) (xy 294.86912 -284.024832) (xy 294.530018 -284.024832)
			(xy 294.529523 -284.049439) (xy 294.521628 -284.098016) (xy 294.506044 -284.144697) (xy 294.483173 -284.188274)
			(xy 294.453608 -284.227618) (xy 294.418115 -284.26171) (xy 294.377612 -284.289666) (xy 294.33315 -284.310764)
			(xy 294.285879 -284.324456) (xy 294.237024 -284.330388) (xy 294.187849 -284.328407) (xy 294.13963 -284.318563)
			(xy 294.093614 -284.301111) (xy 294.050993 -284.276504) (xy 294.012872 -284.245379) (xy 293.980237 -284.208542)
			(xy 293.953934 -284.166946) (xy 293.934643 -284.12167) (xy 293.922866 -284.073886) (xy 293.918906 -284.024832)
			(xy 293.580058 -284.024832) (xy 293.579563 -284.049439) (xy 293.571668 -284.098016) (xy 293.556084 -284.144697)
			(xy 293.533213 -284.188274) (xy 293.503648 -284.227618) (xy 293.468155 -284.26171) (xy 293.427652 -284.289666)
			(xy 293.38319 -284.310764) (xy 293.335919 -284.324456) (xy 293.287064 -284.330388) (xy 293.237889 -284.328407)
			(xy 293.18967 -284.318563) (xy 293.143654 -284.301111) (xy 293.101033 -284.276504) (xy 293.062912 -284.245379)
			(xy 293.030277 -284.208542) (xy 293.003974 -284.166946) (xy 292.984683 -284.12167) (xy 292.972906 -284.073886)
			(xy 292.968946 -284.024832) (xy 292.630098 -284.024832) (xy 292.629603 -284.049439) (xy 292.621708 -284.098016)
			(xy 292.606124 -284.144697) (xy 292.583253 -284.188274) (xy 292.553688 -284.227618) (xy 292.518195 -284.26171)
			(xy 292.477692 -284.289666) (xy 292.43323 -284.310764) (xy 292.385959 -284.324456) (xy 292.337104 -284.330388)
			(xy 292.287929 -284.328407) (xy 292.23971 -284.318563) (xy 292.193694 -284.301111) (xy 292.151073 -284.276504)
			(xy 292.112952 -284.245379) (xy 292.080317 -284.208542) (xy 292.054014 -284.166946) (xy 292.034723 -284.12167)
			(xy 292.022946 -284.073886) (xy 292.018986 -284.024832) (xy 290.730178 -284.024832) (xy 290.729683 -284.049439)
			(xy 290.721788 -284.098016) (xy 290.706204 -284.144697) (xy 290.683333 -284.188274) (xy 290.653768 -284.227618)
			(xy 290.618275 -284.26171) (xy 290.577772 -284.289666) (xy 290.53331 -284.310764) (xy 290.486039 -284.324456)
			(xy 290.437184 -284.330388) (xy 290.388009 -284.328407) (xy 290.33979 -284.318563) (xy 290.293774 -284.301111)
			(xy 290.251153 -284.276504) (xy 290.213032 -284.245379) (xy 290.180397 -284.208542) (xy 290.154094 -284.166946)
			(xy 290.134803 -284.12167) (xy 290.123026 -284.073886) (xy 290.119066 -284.024832) (xy 289.780218 -284.024832)
			(xy 289.779723 -284.049439) (xy 289.771828 -284.098016) (xy 289.756244 -284.144697) (xy 289.733373 -284.188274)
			(xy 289.703808 -284.227618) (xy 289.668315 -284.26171) (xy 289.627812 -284.289666) (xy 289.58335 -284.310764)
			(xy 289.536079 -284.324456) (xy 289.487224 -284.330388) (xy 289.438049 -284.328407) (xy 289.38983 -284.318563)
			(xy 289.343814 -284.301111) (xy 289.301193 -284.276504) (xy 289.263072 -284.245379) (xy 289.230437 -284.208542)
			(xy 289.204134 -284.166946) (xy 289.184843 -284.12167) (xy 289.173066 -284.073886) (xy 289.169106 -284.024832)
			(xy 288.830004 -284.024832) (xy 288.829509 -284.049439) (xy 288.821614 -284.098016) (xy 288.80603 -284.144697)
			(xy 288.783159 -284.188274) (xy 288.753594 -284.227618) (xy 288.718101 -284.26171) (xy 288.677598 -284.289666)
			(xy 288.633136 -284.310764) (xy 288.585865 -284.324456) (xy 288.53701 -284.330388) (xy 288.487835 -284.328407)
			(xy 288.439616 -284.318563) (xy 288.3936 -284.301111) (xy 288.350979 -284.276504) (xy 288.312858 -284.245379)
			(xy 288.280223 -284.208542) (xy 288.25392 -284.166946) (xy 288.234629 -284.12167) (xy 288.222852 -284.073886)
			(xy 288.218892 -284.024832) (xy 287.880044 -284.024832) (xy 287.879549 -284.049439) (xy 287.871654 -284.098016)
			(xy 287.85607 -284.144697) (xy 287.833199 -284.188274) (xy 287.803634 -284.227618) (xy 287.768141 -284.26171)
			(xy 287.727638 -284.289666) (xy 287.683176 -284.310764) (xy 287.635905 -284.324456) (xy 287.58705 -284.330388)
			(xy 287.537875 -284.328407) (xy 287.489656 -284.318563) (xy 287.44364 -284.301111) (xy 287.401019 -284.276504)
			(xy 287.362898 -284.245379) (xy 287.330263 -284.208542) (xy 287.30396 -284.166946) (xy 287.284669 -284.12167)
			(xy 287.272892 -284.073886) (xy 287.268932 -284.024832) (xy 286.930084 -284.024832) (xy 286.929589 -284.049439)
			(xy 286.921694 -284.098016) (xy 286.90611 -284.144697) (xy 286.883239 -284.188274) (xy 286.853674 -284.227618)
			(xy 286.818181 -284.26171) (xy 286.777678 -284.289666) (xy 286.733216 -284.310764) (xy 286.685945 -284.324456)
			(xy 286.63709 -284.330388) (xy 286.587915 -284.328407) (xy 286.539696 -284.318563) (xy 286.49368 -284.301111)
			(xy 286.451059 -284.276504) (xy 286.412938 -284.245379) (xy 286.380303 -284.208542) (xy 286.354 -284.166946)
			(xy 286.334709 -284.12167) (xy 286.322932 -284.073886) (xy 286.318972 -284.024832) (xy 285.980124 -284.024832)
			(xy 285.979629 -284.049439) (xy 285.971734 -284.098016) (xy 285.95615 -284.144697) (xy 285.933279 -284.188274)
			(xy 285.903714 -284.227618) (xy 285.868221 -284.26171) (xy 285.827718 -284.289666) (xy 285.783256 -284.310764)
			(xy 285.735985 -284.324456) (xy 285.68713 -284.330388) (xy 285.637955 -284.328407) (xy 285.589736 -284.318563)
			(xy 285.54372 -284.301111) (xy 285.501099 -284.276504) (xy 285.462978 -284.245379) (xy 285.430343 -284.208542)
			(xy 285.40404 -284.166946) (xy 285.384749 -284.12167) (xy 285.372972 -284.073886) (xy 285.369012 -284.024832)
			(xy 285.030164 -284.024832) (xy 285.029669 -284.049439) (xy 285.021774 -284.098016) (xy 285.00619 -284.144697)
			(xy 284.983319 -284.188274) (xy 284.953754 -284.227618) (xy 284.918261 -284.26171) (xy 284.877758 -284.289666)
			(xy 284.833296 -284.310764) (xy 284.786025 -284.324456) (xy 284.73717 -284.330388) (xy 284.687995 -284.328407)
			(xy 284.639776 -284.318563) (xy 284.59376 -284.301111) (xy 284.551139 -284.276504) (xy 284.513018 -284.245379)
			(xy 284.480383 -284.208542) (xy 284.45408 -284.166946) (xy 284.434789 -284.12167) (xy 284.423012 -284.073886)
			(xy 284.419052 -284.024832) (xy 284.080204 -284.024832) (xy 284.079709 -284.049439) (xy 284.071814 -284.098016)
			(xy 284.05623 -284.144697) (xy 284.033359 -284.188274) (xy 284.003794 -284.227618) (xy 283.968301 -284.26171)
			(xy 283.927798 -284.289666) (xy 283.883336 -284.310764) (xy 283.836065 -284.324456) (xy 283.78721 -284.330388)
			(xy 283.738035 -284.328407) (xy 283.689816 -284.318563) (xy 283.6438 -284.301111) (xy 283.601179 -284.276504)
			(xy 283.563058 -284.245379) (xy 283.530423 -284.208542) (xy 283.50412 -284.166946) (xy 283.484829 -284.12167)
			(xy 283.473052 -284.073886) (xy 283.469092 -284.024832) (xy 283.130244 -284.024832) (xy 283.129749 -284.049439)
			(xy 283.121854 -284.098016) (xy 283.10627 -284.144697) (xy 283.083399 -284.188274) (xy 283.053834 -284.227618)
			(xy 283.018341 -284.26171) (xy 282.977838 -284.289666) (xy 282.933376 -284.310764) (xy 282.886105 -284.324456)
			(xy 282.83725 -284.330388) (xy 282.788075 -284.328407) (xy 282.739856 -284.318563) (xy 282.69384 -284.301111)
			(xy 282.651219 -284.276504) (xy 282.613098 -284.245379) (xy 282.580463 -284.208542) (xy 282.55416 -284.166946)
			(xy 282.534869 -284.12167) (xy 282.523092 -284.073886) (xy 282.519132 -284.024832) (xy 282.18003 -284.024832)
			(xy 282.179535 -284.049439) (xy 282.17164 -284.098016) (xy 282.156056 -284.144697) (xy 282.133185 -284.188274)
			(xy 282.10362 -284.227618) (xy 282.068127 -284.26171) (xy 282.027624 -284.289666) (xy 281.983162 -284.310764)
			(xy 281.935891 -284.324456) (xy 281.887036 -284.330388) (xy 281.837861 -284.328407) (xy 281.789642 -284.318563)
			(xy 281.743626 -284.301111) (xy 281.701005 -284.276504) (xy 281.662884 -284.245379) (xy 281.630249 -284.208542)
			(xy 281.603946 -284.166946) (xy 281.584655 -284.12167) (xy 281.572878 -284.073886) (xy 281.568918 -284.024832)
			(xy 281.23007 -284.024832) (xy 281.229575 -284.049439) (xy 281.22168 -284.098016) (xy 281.206096 -284.144697)
			(xy 281.183225 -284.188274) (xy 281.15366 -284.227618) (xy 281.118167 -284.26171) (xy 281.077664 -284.289666)
			(xy 281.033202 -284.310764) (xy 280.985931 -284.324456) (xy 280.937076 -284.330388) (xy 280.887901 -284.328407)
			(xy 280.839682 -284.318563) (xy 280.793666 -284.301111) (xy 280.751045 -284.276504) (xy 280.712924 -284.245379)
			(xy 280.680289 -284.208542) (xy 280.653986 -284.166946) (xy 280.634695 -284.12167) (xy 280.622918 -284.073886)
			(xy 280.618958 -284.024832) (xy 280.28011 -284.024832) (xy 280.279615 -284.049439) (xy 280.27172 -284.098016)
			(xy 280.256136 -284.144697) (xy 280.233265 -284.188274) (xy 280.2037 -284.227618) (xy 280.168207 -284.26171)
			(xy 280.127704 -284.289666) (xy 280.083242 -284.310764) (xy 280.035971 -284.324456) (xy 279.987116 -284.330388)
			(xy 279.937941 -284.328407) (xy 279.889722 -284.318563) (xy 279.843706 -284.301111) (xy 279.801085 -284.276504)
			(xy 279.762964 -284.245379) (xy 279.730329 -284.208542) (xy 279.704026 -284.166946) (xy 279.684735 -284.12167)
			(xy 279.672958 -284.073886) (xy 279.668998 -284.024832) (xy 279.33015 -284.024832) (xy 279.329655 -284.049439)
			(xy 279.32176 -284.098016) (xy 279.306176 -284.144697) (xy 279.283305 -284.188274) (xy 279.25374 -284.227618)
			(xy 279.218247 -284.26171) (xy 279.177744 -284.289666) (xy 279.133282 -284.310764) (xy 279.086011 -284.324456)
			(xy 279.037156 -284.330388) (xy 278.987981 -284.328407) (xy 278.939762 -284.318563) (xy 278.893746 -284.301111)
			(xy 278.851125 -284.276504) (xy 278.813004 -284.245379) (xy 278.780369 -284.208542) (xy 278.754066 -284.166946)
			(xy 278.734775 -284.12167) (xy 278.722998 -284.073886) (xy 278.719038 -284.024832) (xy 278.38019 -284.024832)
			(xy 278.379695 -284.049439) (xy 278.3718 -284.098016) (xy 278.356216 -284.144697) (xy 278.333345 -284.188274)
			(xy 278.30378 -284.227618) (xy 278.268287 -284.26171) (xy 278.227784 -284.289666) (xy 278.183322 -284.310764)
			(xy 278.136051 -284.324456) (xy 278.087196 -284.330388) (xy 278.038021 -284.328407) (xy 277.989802 -284.318563)
			(xy 277.943786 -284.301111) (xy 277.901165 -284.276504) (xy 277.863044 -284.245379) (xy 277.830409 -284.208542)
			(xy 277.804106 -284.166946) (xy 277.784815 -284.12167) (xy 277.773038 -284.073886) (xy 277.769078 -284.024832)
			(xy 277.43023 -284.024832) (xy 277.429735 -284.049439) (xy 277.42184 -284.098016) (xy 277.406256 -284.144697)
			(xy 277.383385 -284.188274) (xy 277.35382 -284.227618) (xy 277.318327 -284.26171) (xy 277.277824 -284.289666)
			(xy 277.233362 -284.310764) (xy 277.186091 -284.324456) (xy 277.137236 -284.330388) (xy 277.088061 -284.328407)
			(xy 277.039842 -284.318563) (xy 276.993826 -284.301111) (xy 276.951205 -284.276504) (xy 276.913084 -284.245379)
			(xy 276.880449 -284.208542) (xy 276.854146 -284.166946) (xy 276.834855 -284.12167) (xy 276.823078 -284.073886)
			(xy 276.819118 -284.024832) (xy 276.480016 -284.024832) (xy 276.479521 -284.049439) (xy 276.471626 -284.098016)
			(xy 276.456042 -284.144697) (xy 276.433171 -284.188274) (xy 276.403606 -284.227618) (xy 276.368113 -284.26171)
			(xy 276.32761 -284.289666) (xy 276.283148 -284.310764) (xy 276.235877 -284.324456) (xy 276.187022 -284.330388)
			(xy 276.137847 -284.328407) (xy 276.089628 -284.318563) (xy 276.043612 -284.301111) (xy 276.000991 -284.276504)
			(xy 275.96287 -284.245379) (xy 275.930235 -284.208542) (xy 275.903932 -284.166946) (xy 275.884641 -284.12167)
			(xy 275.872864 -284.073886) (xy 275.868904 -284.024832) (xy 275.530056 -284.024832) (xy 275.529561 -284.049439)
			(xy 275.521666 -284.098016) (xy 275.506082 -284.144697) (xy 275.483211 -284.188274) (xy 275.453646 -284.227618)
			(xy 275.418153 -284.26171) (xy 275.37765 -284.289666) (xy 275.333188 -284.310764) (xy 275.285917 -284.324456)
			(xy 275.237062 -284.330388) (xy 275.187887 -284.328407) (xy 275.139668 -284.318563) (xy 275.093652 -284.301111)
			(xy 275.051031 -284.276504) (xy 275.01291 -284.245379) (xy 274.980275 -284.208542) (xy 274.953972 -284.166946)
			(xy 274.934681 -284.12167) (xy 274.922904 -284.073886) (xy 274.918944 -284.024832) (xy 272.680176 -284.024832)
			(xy 272.679681 -284.049439) (xy 272.671786 -284.098016) (xy 272.656202 -284.144697) (xy 272.633331 -284.188274)
			(xy 272.603766 -284.227618) (xy 272.568273 -284.26171) (xy 272.52777 -284.289666) (xy 272.483308 -284.310764)
			(xy 272.436037 -284.324456) (xy 272.387182 -284.330388) (xy 272.338007 -284.328407) (xy 272.289788 -284.318563)
			(xy 272.243772 -284.301111) (xy 272.201151 -284.276504) (xy 272.16303 -284.245379) (xy 272.130395 -284.208542)
			(xy 272.104092 -284.166946) (xy 272.084801 -284.12167) (xy 272.073024 -284.073886) (xy 272.069064 -284.024832)
			(xy 271.730216 -284.024832) (xy 271.729721 -284.049439) (xy 271.721826 -284.098016) (xy 271.706242 -284.144697)
			(xy 271.683371 -284.188274) (xy 271.653806 -284.227618) (xy 271.618313 -284.26171) (xy 271.57781 -284.289666)
			(xy 271.533348 -284.310764) (xy 271.486077 -284.324456) (xy 271.437222 -284.330388) (xy 271.388047 -284.328407)
			(xy 271.339828 -284.318563) (xy 271.293812 -284.301111) (xy 271.251191 -284.276504) (xy 271.21307 -284.245379)
			(xy 271.180435 -284.208542) (xy 271.154132 -284.166946) (xy 271.134841 -284.12167) (xy 271.123064 -284.073886)
			(xy 271.119104 -284.024832) (xy 270.780256 -284.024832) (xy 270.779761 -284.049439) (xy 270.771866 -284.098016)
			(xy 270.756282 -284.144697) (xy 270.733411 -284.188274) (xy 270.703846 -284.227618) (xy 270.668353 -284.26171)
			(xy 270.62785 -284.289666) (xy 270.583388 -284.310764) (xy 270.536117 -284.324456) (xy 270.487262 -284.330388)
			(xy 270.438087 -284.328407) (xy 270.389868 -284.318563) (xy 270.343852 -284.301111) (xy 270.301231 -284.276504)
			(xy 270.26311 -284.245379) (xy 270.230475 -284.208542) (xy 270.204172 -284.166946) (xy 270.184881 -284.12167)
			(xy 270.173104 -284.073886) (xy 270.169144 -284.024832) (xy 269.830042 -284.024832) (xy 269.829547 -284.049439)
			(xy 269.821652 -284.098016) (xy 269.806068 -284.144697) (xy 269.783197 -284.188274) (xy 269.753632 -284.227618)
			(xy 269.718139 -284.26171) (xy 269.677636 -284.289666) (xy 269.633174 -284.310764) (xy 269.585903 -284.324456)
			(xy 269.537048 -284.330388) (xy 269.487873 -284.328407) (xy 269.439654 -284.318563) (xy 269.393638 -284.301111)
			(xy 269.351017 -284.276504) (xy 269.312896 -284.245379) (xy 269.280261 -284.208542) (xy 269.253958 -284.166946)
			(xy 269.234667 -284.12167) (xy 269.22289 -284.073886) (xy 269.21893 -284.024832) (xy 268.880082 -284.024832)
			(xy 268.879587 -284.049439) (xy 268.871692 -284.098016) (xy 268.856108 -284.144697) (xy 268.833237 -284.188274)
			(xy 268.803672 -284.227618) (xy 268.768179 -284.26171) (xy 268.727676 -284.289666) (xy 268.683214 -284.310764)
			(xy 268.635943 -284.324456) (xy 268.587088 -284.330388) (xy 268.537913 -284.328407) (xy 268.489694 -284.318563)
			(xy 268.443678 -284.301111) (xy 268.401057 -284.276504) (xy 268.362936 -284.245379) (xy 268.330301 -284.208542)
			(xy 268.303998 -284.166946) (xy 268.284707 -284.12167) (xy 268.27293 -284.073886) (xy 268.26897 -284.024832)
			(xy 266.561283 -284.024832) (xy 266.559733 -284.029983) (xy 266.536061 -284.08048) (xy 266.505288 -284.126993)
			(xy 266.468071 -284.16853) (xy 266.425203 -284.204205) (xy 266.377597 -284.233259) (xy 266.326268 -284.255071)
			(xy 266.272311 -284.269177) (xy 266.216874 -284.275277) (xy 266.16114 -284.27324) (xy 266.106297 -284.26311)
			(xy 266.053513 -284.245103) (xy 266.003913 -284.219602) (xy 265.958555 -284.187151) (xy 265.918406 -284.148442)
			(xy 265.88432 -284.104299) (xy 265.857024 -284.055664) (xy 265.837101 -284.003573) (xy 265.824975 -283.949136)
			(xy 265.820904 -283.893514) (xy 265.69797 -283.893514) (xy 265.697461 -283.9214) (xy 265.689341 -283.976576)
			(xy 265.673273 -284.029983) (xy 265.649601 -284.08048) (xy 265.618828 -284.126993) (xy 265.581611 -284.16853)
			(xy 265.538743 -284.204205) (xy 265.491137 -284.233259) (xy 265.439808 -284.255071) (xy 265.385851 -284.269177)
			(xy 265.330414 -284.275277) (xy 265.27468 -284.27324) (xy 265.219837 -284.26311) (xy 265.167053 -284.245103)
			(xy 265.117453 -284.219602) (xy 265.072095 -284.187151) (xy 265.031946 -284.148442) (xy 264.99786 -284.104299)
			(xy 264.970564 -284.055664) (xy 264.950641 -284.003573) (xy 264.938515 -283.949136) (xy 264.934444 -283.893514)
			(xy 264.30097 -283.893514) (xy 264.300484 -283.920765) (xy 264.292728 -283.974713) (xy 264.277373 -284.027008)
			(xy 264.254731 -284.076585) (xy 264.225265 -284.122435) (xy 264.189574 -284.163626) (xy 264.148383 -284.199317)
			(xy 264.102533 -284.228783) (xy 264.052956 -284.251425) (xy 264.000661 -284.26678) (xy 263.946713 -284.274536)
			(xy 263.892211 -284.274536) (xy 263.838263 -284.26678) (xy 263.785968 -284.251425) (xy 263.736391 -284.228783)
			(xy 263.690541 -284.199317) (xy 263.64935 -284.163626) (xy 263.613659 -284.122435) (xy 263.584193 -284.076585)
			(xy 263.561551 -284.027008) (xy 263.546196 -283.974713) (xy 263.53844 -283.920765) (xy 263.537954 -283.893514)
			(xy 215.255348 -283.893514) (xy 214.480115 -284.668747) (xy 216.926722 -284.668747) (xy 216.926722 -284.614253)
			(xy 216.934477 -284.560315) (xy 216.949829 -284.508029) (xy 216.972465 -284.458459) (xy 217.001925 -284.412616)
			(xy 217.037609 -284.371431) (xy 217.07879 -284.335744) (xy 217.124631 -284.30628) (xy 217.174199 -284.28364)
			(xy 217.226483 -284.268284) (xy 217.280421 -284.260524) (xy 217.307668 -284.260036) (xy 217.336408 -284.260535)
			(xy 217.393235 -284.269167) (xy 217.448126 -284.286223) (xy 217.499837 -284.31132) (xy 217.547199 -284.343888)
			(xy 217.568526 -284.36316) (xy 217.575638 -284.369764) (xy 217.593164 -284.376876) (xy 217.682572 -284.376876)
			(xy 217.700098 -284.369764) (xy 217.70721 -284.36316) (xy 217.728553 -284.343908) (xy 217.775911 -284.311338)
			(xy 217.827618 -284.286242) (xy 217.882505 -284.269187) (xy 217.93933 -284.260559) (xy 217.968068 -284.260036)
			(xy 217.99819 -284.260631) (xy 218.057685 -284.270107) (xy 218.114953 -284.288812) (xy 218.16857 -284.316282)
			(xy 218.217206 -284.351836) (xy 218.238832 -284.372812) (xy 218.245944 -284.380178) (xy 218.26474 -284.387798)
			(xy 218.357196 -284.387798) (xy 218.375992 -284.380178) (xy 218.383104 -284.372812) (xy 218.404706 -284.351807)
			(xy 218.453341 -284.316241) (xy 218.506963 -284.288766) (xy 218.564238 -284.270063) (xy 218.623742 -284.2606)
			(xy 218.653868 -284.260036) (xy 218.681238 -284.260512) (xy 218.735417 -284.268326) (xy 218.78792 -284.283812)
			(xy 218.837667 -284.306652) (xy 218.883634 -284.336375) (xy 218.904566 -284.354016) (xy 218.911678 -284.360112)
			(xy 218.928696 -284.366462) (xy 219.01404 -284.366462) (xy 219.031058 -284.360112) (xy 219.03817 -284.354016)
			(xy 219.059105 -284.33638) (xy 219.105076 -284.306667) (xy 219.154823 -284.28383) (xy 219.207324 -284.268339)
			(xy 219.261499 -284.26051) (xy 219.288868 -284.260036) (xy 219.316126 -284.260409) (xy 219.370086 -284.268163)
			(xy 219.422394 -284.283518) (xy 219.471984 -284.306161) (xy 219.517846 -284.335632) (xy 219.559048 -284.37133)
			(xy 219.594749 -284.412528) (xy 219.624223 -284.458388) (xy 219.646871 -284.507976) (xy 219.66223 -284.560283)
			(xy 219.669989 -284.614243) (xy 219.669989 -284.668746) (xy 220.945522 -284.668746) (xy 220.945522 -284.614254)
			(xy 220.953276 -284.560316) (xy 220.968628 -284.508031) (xy 220.991263 -284.458463) (xy 221.020722 -284.41262)
			(xy 221.056404 -284.371435) (xy 221.097584 -284.335748) (xy 221.143424 -284.306284) (xy 221.19299 -284.283643)
			(xy 221.245273 -284.268286) (xy 221.29921 -284.260525) (xy 221.326456 -284.260036) (xy 221.355195 -284.260543)
			(xy 221.412023 -284.269172) (xy 221.466913 -284.286227) (xy 221.518624 -284.311322) (xy 221.565987 -284.343889)
			(xy 221.587314 -284.36316) (xy 221.594426 -284.369764) (xy 221.611952 -284.376876) (xy 221.70136 -284.376876)
			(xy 221.718886 -284.369764) (xy 221.725998 -284.36316) (xy 221.747325 -284.34389) (xy 221.794688 -284.311325)
			(xy 221.846399 -284.286234) (xy 221.90129 -284.269184) (xy 221.958117 -284.260562) (xy 222.015595 -284.260562)
			(xy 222.072422 -284.269184) (xy 222.127313 -284.286234) (xy 222.179024 -284.311325) (xy 222.226387 -284.34389)
			(xy 222.247714 -284.36316) (xy 222.254826 -284.369764) (xy 222.272352 -284.376876) (xy 222.36176 -284.376876)
			(xy 222.379286 -284.369764) (xy 222.386398 -284.36316) (xy 222.407705 -284.343866) (xy 222.455072 -284.311302)
			(xy 222.506789 -284.286214) (xy 222.561684 -284.269169) (xy 222.618516 -284.260553) (xy 222.647256 -284.260036)
			(xy 222.677378 -284.260638) (xy 222.736873 -284.270112) (xy 222.79414 -284.288816) (xy 222.847758 -284.316285)
			(xy 222.896394 -284.351836) (xy 222.91802 -284.372812) (xy 222.925132 -284.380178) (xy 222.943928 -284.387798)
			(xy 223.036384 -284.387798) (xy 223.05518 -284.380178) (xy 223.062292 -284.372812) (xy 223.083899 -284.351813)
			(xy 223.132533 -284.316246) (xy 223.186153 -284.28877) (xy 223.243428 -284.270066) (xy 223.30293 -284.260601)
			(xy 223.333056 -284.260036) (xy 223.360314 -284.260408) (xy 223.414276 -284.268161) (xy 223.466585 -284.283515)
			(xy 223.516177 -284.306157) (xy 223.562041 -284.335628) (xy 223.603243 -284.371325) (xy 223.638946 -284.412524)
			(xy 223.668422 -284.458385) (xy 223.69107 -284.507973) (xy 223.70643 -284.560281) (xy 223.714189 -284.614242)
			(xy 223.714189 -284.668748) (xy 234.543122 -284.668748) (xy 234.543122 -284.614252) (xy 234.550878 -284.560312)
			(xy 234.56623 -284.508024) (xy 234.588868 -284.458453) (xy 234.618331 -284.412608) (xy 234.654017 -284.371423)
			(xy 234.695202 -284.335735) (xy 234.741046 -284.306272) (xy 234.790616 -284.283633) (xy 234.842904 -284.268279)
			(xy 234.896844 -284.260523) (xy 234.924092 -284.260036) (xy 234.954215 -284.260616) (xy 235.013711 -284.270095)
			(xy 235.070978 -284.288804) (xy 235.124596 -284.316278) (xy 235.173231 -284.351834) (xy 235.194856 -284.372812)
			(xy 235.201968 -284.380178) (xy 235.220764 -284.387798) (xy 235.31322 -284.387798) (xy 235.332016 -284.380178)
			(xy 235.339128 -284.372812) (xy 235.360763 -284.351843) (xy 235.409389 -284.316273) (xy 235.463003 -284.288791)
			(xy 235.520271 -284.27008) (xy 235.579768 -284.260606) (xy 235.609892 -284.260036) (xy 235.637148 -284.26041)
			(xy 235.691106 -284.268167) (xy 235.743411 -284.283524) (xy 235.792998 -284.306169) (xy 235.838858 -284.33564)
			(xy 235.880056 -284.371338) (xy 235.915755 -284.412536) (xy 235.945227 -284.458395) (xy 235.967873 -284.507981)
			(xy 235.983231 -284.560286) (xy 235.990989 -284.614244) (xy 235.990989 -284.66875) (xy 237.195599 -284.66875)
			(xy 237.195599 -284.61425) (xy 237.203356 -284.560304) (xy 237.218711 -284.508011) (xy 237.241352 -284.458435)
			(xy 237.270817 -284.412587) (xy 237.306509 -284.371399) (xy 237.347698 -284.335709) (xy 237.393548 -284.306245)
			(xy 237.443124 -284.283606) (xy 237.495417 -284.268253) (xy 237.549364 -284.260498) (xy 237.576614 -284.260036)
			(xy 237.605352 -284.260568) (xy 237.662179 -284.269191) (xy 237.717069 -284.28624) (xy 237.76878 -284.31133)
			(xy 237.816144 -284.343891) (xy 237.837472 -284.36316) (xy 237.844584 -284.369764) (xy 237.86211 -284.376876)
			(xy 237.951518 -284.376876) (xy 237.969044 -284.369764) (xy 237.976156 -284.36316) (xy 237.997483 -284.34389)
			(xy 238.044846 -284.311325) (xy 238.096557 -284.286234) (xy 238.151448 -284.269184) (xy 238.208275 -284.260562)
			(xy 238.265753 -284.260562) (xy 238.32258 -284.269184) (xy 238.377471 -284.286234) (xy 238.429182 -284.311325)
			(xy 238.476545 -284.34389) (xy 238.497872 -284.36316) (xy 238.504984 -284.369764) (xy 238.52251 -284.376876)
			(xy 238.611918 -284.376876) (xy 238.629444 -284.369764) (xy 238.636556 -284.36316) (xy 238.657881 -284.343886)
			(xy 238.705243 -284.31132) (xy 238.756955 -284.286227) (xy 238.811847 -284.269177) (xy 238.868675 -284.260556)
			(xy 238.897414 -284.260036) (xy 238.927538 -284.260602) (xy 238.987034 -284.270085) (xy 239.044302 -284.288797)
			(xy 239.097919 -284.316274) (xy 239.146553 -284.351833) (xy 239.168178 -284.372812) (xy 239.17529 -284.380178)
			(xy 239.194086 -284.387798) (xy 239.286542 -284.387798) (xy 239.305338 -284.380178) (xy 239.31245 -284.372812)
			(xy 239.334076 -284.351833) (xy 239.382704 -284.316264) (xy 239.43632 -284.288783) (xy 239.49359 -284.270075)
			(xy 239.55309 -284.260604) (xy 239.583214 -284.260036) (xy 239.610468 -284.260435) (xy 239.66442 -284.268194)
			(xy 239.716719 -284.283552) (xy 239.7663 -284.306197) (xy 239.812154 -284.335667) (xy 239.853348 -284.371362)
			(xy 239.889042 -284.412557) (xy 239.91851 -284.458412) (xy 239.937416 -284.499812) (xy 305.793914 -284.499812)
			(xy 305.797874 -284.450758) (xy 305.809651 -284.402974) (xy 305.828942 -284.357698) (xy 305.855245 -284.316102)
			(xy 305.88788 -284.279265) (xy 305.926001 -284.24814) (xy 305.968622 -284.223533) (xy 306.014638 -284.206081)
			(xy 306.062857 -284.196237) (xy 306.112032 -284.194256) (xy 306.160887 -284.200188) (xy 306.208158 -284.21388)
			(xy 306.25262 -284.234978) (xy 306.293123 -284.262934) (xy 306.328616 -284.297026) (xy 306.358181 -284.33637)
			(xy 306.381052 -284.379947) (xy 306.396636 -284.426628) (xy 306.404531 -284.475205) (xy 306.405026 -284.499812)
			(xy 306.743874 -284.499812) (xy 306.747834 -284.450758) (xy 306.759611 -284.402974) (xy 306.778902 -284.357698)
			(xy 306.805205 -284.316102) (xy 306.83784 -284.279265) (xy 306.875961 -284.24814) (xy 306.918582 -284.223533)
			(xy 306.964598 -284.206081) (xy 307.012817 -284.196237) (xy 307.061992 -284.194256) (xy 307.110847 -284.200188)
			(xy 307.158118 -284.21388) (xy 307.20258 -284.234978) (xy 307.243083 -284.262934) (xy 307.278576 -284.297026)
			(xy 307.308141 -284.33637) (xy 307.331012 -284.379947) (xy 307.346596 -284.426628) (xy 307.354491 -284.475205)
			(xy 307.354986 -284.499812) (xy 307.694088 -284.499812) (xy 307.698048 -284.450758) (xy 307.709825 -284.402974)
			(xy 307.729116 -284.357698) (xy 307.755419 -284.316102) (xy 307.788054 -284.279265) (xy 307.826175 -284.24814)
			(xy 307.868796 -284.223533) (xy 307.914812 -284.206081) (xy 307.963031 -284.196237) (xy 308.012206 -284.194256)
			(xy 308.061061 -284.200188) (xy 308.108332 -284.21388) (xy 308.152794 -284.234978) (xy 308.193297 -284.262934)
			(xy 308.22879 -284.297026) (xy 308.258355 -284.33637) (xy 308.281226 -284.379947) (xy 308.29681 -284.426628)
			(xy 308.304705 -284.475205) (xy 308.3052 -284.499812) (xy 308.304705 -284.524419) (xy 308.304526 -284.52552)
			(xy 308.623204 -284.52552) (xy 308.623204 -284.474104) (xy 308.631247 -284.423322) (xy 308.647135 -284.374423)
			(xy 308.670478 -284.328611) (xy 308.700699 -284.287015) (xy 308.737055 -284.250659) (xy 308.778651 -284.220438)
			(xy 308.824463 -284.197095) (xy 308.873362 -284.181207) (xy 308.924144 -284.173164) (xy 308.97556 -284.173164)
			(xy 309.026342 -284.181207) (xy 309.075241 -284.197095) (xy 309.121053 -284.220438) (xy 309.162649 -284.250659)
			(xy 309.199005 -284.287015) (xy 309.229226 -284.328611) (xy 309.252569 -284.374423) (xy 309.268457 -284.423322)
			(xy 309.2765 -284.474104) (xy 309.277004 -284.499812) (xy 309.2765 -284.52552) (xy 309.573164 -284.52552)
			(xy 309.573164 -284.474104) (xy 309.581207 -284.423322) (xy 309.597095 -284.374423) (xy 309.620438 -284.328611)
			(xy 309.650659 -284.287015) (xy 309.687015 -284.250659) (xy 309.728611 -284.220438) (xy 309.774423 -284.197095)
			(xy 309.823322 -284.181207) (xy 309.874104 -284.173164) (xy 309.92552 -284.173164) (xy 309.976302 -284.181207)
			(xy 310.025201 -284.197095) (xy 310.071013 -284.220438) (xy 310.112609 -284.250659) (xy 310.148965 -284.287015)
			(xy 310.179186 -284.328611) (xy 310.202529 -284.374423) (xy 310.218417 -284.423322) (xy 310.22646 -284.474104)
			(xy 310.226964 -284.499812) (xy 310.543968 -284.499812) (xy 310.547928 -284.450758) (xy 310.559705 -284.402974)
			(xy 310.578996 -284.357698) (xy 310.605299 -284.316102) (xy 310.637934 -284.279265) (xy 310.676055 -284.24814)
			(xy 310.718676 -284.223533) (xy 310.764692 -284.206081) (xy 310.812911 -284.196237) (xy 310.862086 -284.194256)
			(xy 310.910941 -284.200188) (xy 310.958212 -284.21388) (xy 311.002674 -284.234978) (xy 311.043177 -284.262934)
			(xy 311.07867 -284.297026) (xy 311.108235 -284.33637) (xy 311.131106 -284.379947) (xy 311.14669 -284.426628)
			(xy 311.154585 -284.475205) (xy 311.15508 -284.499812) (xy 311.154585 -284.524419) (xy 311.154406 -284.52552)
			(xy 311.473084 -284.52552) (xy 311.473084 -284.474104) (xy 311.481127 -284.423322) (xy 311.497015 -284.374423)
			(xy 311.520358 -284.328611) (xy 311.550579 -284.287015) (xy 311.586935 -284.250659) (xy 311.628531 -284.220438)
			(xy 311.674343 -284.197095) (xy 311.723242 -284.181207) (xy 311.774024 -284.173164) (xy 311.82544 -284.173164)
			(xy 311.876222 -284.181207) (xy 311.925121 -284.197095) (xy 311.970933 -284.220438) (xy 312.012529 -284.250659)
			(xy 312.048885 -284.287015) (xy 312.079106 -284.328611) (xy 312.102449 -284.374423) (xy 312.118337 -284.423322)
			(xy 312.12638 -284.474104) (xy 312.126884 -284.499812) (xy 312.12638 -284.52552) (xy 312.423044 -284.52552)
			(xy 312.423044 -284.474104) (xy 312.431087 -284.423322) (xy 312.446975 -284.374423) (xy 312.470318 -284.328611)
			(xy 312.500539 -284.287015) (xy 312.536895 -284.250659) (xy 312.578491 -284.220438) (xy 312.624303 -284.197095)
			(xy 312.673202 -284.181207) (xy 312.723984 -284.173164) (xy 312.7754 -284.173164) (xy 312.826182 -284.181207)
			(xy 312.875081 -284.197095) (xy 312.920893 -284.220438) (xy 312.962489 -284.250659) (xy 312.998845 -284.287015)
			(xy 313.029066 -284.328611) (xy 313.052409 -284.374423) (xy 313.068297 -284.423322) (xy 313.07634 -284.474104)
			(xy 313.076844 -284.499812) (xy 313.394102 -284.499812) (xy 313.398062 -284.450758) (xy 313.409839 -284.402974)
			(xy 313.42913 -284.357698) (xy 313.455433 -284.316102) (xy 313.488068 -284.279265) (xy 313.526189 -284.24814)
			(xy 313.56881 -284.223533) (xy 313.614826 -284.206081) (xy 313.663045 -284.196237) (xy 313.71222 -284.194256)
			(xy 313.761075 -284.200188) (xy 313.808346 -284.21388) (xy 313.852808 -284.234978) (xy 313.893311 -284.262934)
			(xy 313.928804 -284.297026) (xy 313.958369 -284.33637) (xy 313.98124 -284.379947) (xy 313.996824 -284.426628)
			(xy 314.004719 -284.475205) (xy 314.005214 -284.499812) (xy 314.344062 -284.499812) (xy 314.348022 -284.450758)
			(xy 314.359799 -284.402974) (xy 314.37909 -284.357698) (xy 314.405393 -284.316102) (xy 314.438028 -284.279265)
			(xy 314.476149 -284.24814) (xy 314.51877 -284.223533) (xy 314.564786 -284.206081) (xy 314.613005 -284.196237)
			(xy 314.66218 -284.194256) (xy 314.711035 -284.200188) (xy 314.758306 -284.21388) (xy 314.802768 -284.234978)
			(xy 314.843271 -284.262934) (xy 314.878764 -284.297026) (xy 314.908329 -284.33637) (xy 314.9312 -284.379947)
			(xy 314.946784 -284.426628) (xy 314.954679 -284.475205) (xy 314.955174 -284.499812) (xy 314.954679 -284.524419)
			(xy 314.946784 -284.572996) (xy 314.9312 -284.619677) (xy 314.908329 -284.663254) (xy 314.878764 -284.702598)
			(xy 314.843271 -284.73669) (xy 314.802768 -284.764646) (xy 314.758306 -284.785744) (xy 314.711035 -284.799436)
			(xy 314.66218 -284.805368) (xy 314.613005 -284.803387) (xy 314.564786 -284.793543) (xy 314.51877 -284.776091)
			(xy 314.476149 -284.751484) (xy 314.438028 -284.720359) (xy 314.405393 -284.683522) (xy 314.37909 -284.641926)
			(xy 314.359799 -284.59665) (xy 314.348022 -284.548866) (xy 314.344062 -284.499812) (xy 314.005214 -284.499812)
			(xy 314.004719 -284.524419) (xy 313.996824 -284.572996) (xy 313.98124 -284.619677) (xy 313.958369 -284.663254)
			(xy 313.928804 -284.702598) (xy 313.893311 -284.73669) (xy 313.852808 -284.764646) (xy 313.808346 -284.785744)
			(xy 313.761075 -284.799436) (xy 313.71222 -284.805368) (xy 313.663045 -284.803387) (xy 313.614826 -284.793543)
			(xy 313.56881 -284.776091) (xy 313.526189 -284.751484) (xy 313.488068 -284.720359) (xy 313.455433 -284.683522)
			(xy 313.42913 -284.641926) (xy 313.409839 -284.59665) (xy 313.398062 -284.548866) (xy 313.394102 -284.499812)
			(xy 313.076844 -284.499812) (xy 313.07634 -284.52552) (xy 313.068297 -284.576302) (xy 313.052409 -284.625201)
			(xy 313.029066 -284.671013) (xy 312.998845 -284.712609) (xy 312.962489 -284.748965) (xy 312.920893 -284.779186)
			(xy 312.875081 -284.802529) (xy 312.826182 -284.818417) (xy 312.7754 -284.82646) (xy 312.723984 -284.82646)
			(xy 312.673202 -284.818417) (xy 312.624303 -284.802529) (xy 312.578491 -284.779186) (xy 312.536895 -284.748965)
			(xy 312.500539 -284.712609) (xy 312.470318 -284.671013) (xy 312.446975 -284.625201) (xy 312.431087 -284.576302)
			(xy 312.423044 -284.52552) (xy 312.12638 -284.52552) (xy 312.118337 -284.576302) (xy 312.102449 -284.625201)
			(xy 312.079106 -284.671013) (xy 312.048885 -284.712609) (xy 312.012529 -284.748965) (xy 311.970933 -284.779186)
			(xy 311.925121 -284.802529) (xy 311.876222 -284.818417) (xy 311.82544 -284.82646) (xy 311.774024 -284.82646)
			(xy 311.723242 -284.818417) (xy 311.674343 -284.802529) (xy 311.628531 -284.779186) (xy 311.586935 -284.748965)
			(xy 311.550579 -284.712609) (xy 311.520358 -284.671013) (xy 311.497015 -284.625201) (xy 311.481127 -284.576302)
			(xy 311.473084 -284.52552) (xy 311.154406 -284.52552) (xy 311.14669 -284.572996) (xy 311.131106 -284.619677)
			(xy 311.108235 -284.663254) (xy 311.07867 -284.702598) (xy 311.043177 -284.73669) (xy 311.002674 -284.764646)
			(xy 310.958212 -284.785744) (xy 310.910941 -284.799436) (xy 310.862086 -284.805368) (xy 310.812911 -284.803387)
			(xy 310.764692 -284.793543) (xy 310.718676 -284.776091) (xy 310.676055 -284.751484) (xy 310.637934 -284.720359)
			(xy 310.605299 -284.683522) (xy 310.578996 -284.641926) (xy 310.559705 -284.59665) (xy 310.547928 -284.548866)
			(xy 310.543968 -284.499812) (xy 310.226964 -284.499812) (xy 310.22646 -284.52552) (xy 310.218417 -284.576302)
			(xy 310.202529 -284.625201) (xy 310.179186 -284.671013) (xy 310.148965 -284.712609) (xy 310.112609 -284.748965)
			(xy 310.071013 -284.779186) (xy 310.025201 -284.802529) (xy 309.976302 -284.818417) (xy 309.92552 -284.82646)
			(xy 309.874104 -284.82646) (xy 309.823322 -284.818417) (xy 309.774423 -284.802529) (xy 309.728611 -284.779186)
			(xy 309.687015 -284.748965) (xy 309.650659 -284.712609) (xy 309.620438 -284.671013) (xy 309.597095 -284.625201)
			(xy 309.581207 -284.576302) (xy 309.573164 -284.52552) (xy 309.2765 -284.52552) (xy 309.268457 -284.576302)
			(xy 309.252569 -284.625201) (xy 309.229226 -284.671013) (xy 309.199005 -284.712609) (xy 309.162649 -284.748965)
			(xy 309.121053 -284.779186) (xy 309.075241 -284.802529) (xy 309.026342 -284.818417) (xy 308.97556 -284.82646)
			(xy 308.924144 -284.82646) (xy 308.873362 -284.818417) (xy 308.824463 -284.802529) (xy 308.778651 -284.779186)
			(xy 308.737055 -284.748965) (xy 308.700699 -284.712609) (xy 308.670478 -284.671013) (xy 308.647135 -284.625201)
			(xy 308.631247 -284.576302) (xy 308.623204 -284.52552) (xy 308.304526 -284.52552) (xy 308.29681 -284.572996)
			(xy 308.281226 -284.619677) (xy 308.258355 -284.663254) (xy 308.22879 -284.702598) (xy 308.193297 -284.73669)
			(xy 308.152794 -284.764646) (xy 308.108332 -284.785744) (xy 308.061061 -284.799436) (xy 308.012206 -284.805368)
			(xy 307.963031 -284.803387) (xy 307.914812 -284.793543) (xy 307.868796 -284.776091) (xy 307.826175 -284.751484)
			(xy 307.788054 -284.720359) (xy 307.755419 -284.683522) (xy 307.729116 -284.641926) (xy 307.709825 -284.59665)
			(xy 307.698048 -284.548866) (xy 307.694088 -284.499812) (xy 307.354986 -284.499812) (xy 307.354491 -284.524419)
			(xy 307.346596 -284.572996) (xy 307.331012 -284.619677) (xy 307.308141 -284.663254) (xy 307.278576 -284.702598)
			(xy 307.243083 -284.73669) (xy 307.20258 -284.764646) (xy 307.158118 -284.785744) (xy 307.110847 -284.799436)
			(xy 307.061992 -284.805368) (xy 307.012817 -284.803387) (xy 306.964598 -284.793543) (xy 306.918582 -284.776091)
			(xy 306.875961 -284.751484) (xy 306.83784 -284.720359) (xy 306.805205 -284.683522) (xy 306.778902 -284.641926)
			(xy 306.759611 -284.59665) (xy 306.747834 -284.548866) (xy 306.743874 -284.499812) (xy 306.405026 -284.499812)
			(xy 306.404531 -284.524419) (xy 306.396636 -284.572996) (xy 306.381052 -284.619677) (xy 306.358181 -284.663254)
			(xy 306.328616 -284.702598) (xy 306.293123 -284.73669) (xy 306.25262 -284.764646) (xy 306.208158 -284.785744)
			(xy 306.160887 -284.799436) (xy 306.112032 -284.805368) (xy 306.062857 -284.803387) (xy 306.014638 -284.793543)
			(xy 305.968622 -284.776091) (xy 305.926001 -284.751484) (xy 305.88788 -284.720359) (xy 305.855245 -284.683522)
			(xy 305.828942 -284.641926) (xy 305.809651 -284.59665) (xy 305.797874 -284.548866) (xy 305.793914 -284.499812)
			(xy 239.937416 -284.499812) (xy 239.941153 -284.507994) (xy 239.956509 -284.560294) (xy 239.964266 -284.614246)
			(xy 239.964266 -284.668754) (xy 239.956509 -284.722706) (xy 239.941153 -284.775006) (xy 239.91851 -284.824588)
			(xy 239.889042 -284.870443) (xy 239.853348 -284.911638) (xy 239.812154 -284.947333) (xy 239.7663 -284.976803)
			(xy 239.716719 -284.999448) (xy 239.66442 -285.014806) (xy 239.610468 -285.022565) (xy 239.583214 -285.023052)
			(xy 239.553091 -285.022472) (xy 239.493595 -285.012993) (xy 239.436327 -284.994284) (xy 239.38271 -284.966811)
			(xy 239.334075 -284.931254) (xy 239.31245 -284.910276) (xy 239.305338 -284.90291) (xy 239.286542 -284.89529)
			(xy 239.194086 -284.89529) (xy 239.17529 -284.90291) (xy 239.168178 -284.910276) (xy 239.146538 -284.93124)
			(xy 239.097914 -284.966811) (xy 239.044301 -284.994295) (xy 238.987034 -285.013007) (xy 238.927537 -285.022482)
			(xy 238.897414 -285.023052) (xy 238.868676 -285.022506) (xy 238.81185 -285.013887) (xy 238.75696 -284.996841)
			(xy 238.705248 -284.971755) (xy 238.657884 -284.939196) (xy 238.636556 -284.919928) (xy 238.629444 -284.913324)
			(xy 238.611918 -284.906212) (xy 238.52251 -284.906212) (xy 238.504984 -284.913324) (xy 238.497872 -284.919928)
			(xy 238.476545 -284.939198) (xy 238.429182 -284.971763) (xy 238.377471 -284.996854) (xy 238.32258 -285.013904)
			(xy 238.265753 -285.022526) (xy 238.208275 -285.022526) (xy 238.151448 -285.013904) (xy 238.096557 -284.996854)
			(xy 238.044846 -284.971763) (xy 237.997483 -284.939198) (xy 237.976156 -284.919928) (xy 237.969044 -284.913324)
			(xy 237.951518 -284.906212) (xy 237.86211 -284.906212) (xy 237.844584 -284.913324) (xy 237.837472 -284.919928)
			(xy 237.816134 -284.939186) (xy 237.768776 -284.971756) (xy 237.717067 -284.996851) (xy 237.662178 -285.013905)
			(xy 237.605352 -285.02253) (xy 237.576614 -285.023052) (xy 237.549364 -285.022502) (xy 237.495417 -285.014747)
			(xy 237.443124 -284.999394) (xy 237.393548 -284.976755) (xy 237.347698 -284.947291) (xy 237.306509 -284.911601)
			(xy 237.270817 -284.870413) (xy 237.241352 -284.824565) (xy 237.218711 -284.774989) (xy 237.203356 -284.722696)
			(xy 237.195599 -284.66875) (xy 235.990989 -284.66875) (xy 235.990989 -284.668756) (xy 235.983231 -284.722714)
			(xy 235.967873 -284.775019) (xy 235.945227 -284.824605) (xy 235.915755 -284.870464) (xy 235.880056 -284.911662)
			(xy 235.838858 -284.94736) (xy 235.792998 -284.976831) (xy 235.743411 -284.999476) (xy 235.691106 -285.014833)
			(xy 235.637148 -285.02259) (xy 235.609892 -285.023052) (xy 235.579768 -285.022486) (xy 235.520272 -285.013004)
			(xy 235.463004 -284.994292) (xy 235.409387 -284.966815) (xy 235.360753 -284.931255) (xy 235.339128 -284.910276)
			(xy 235.332016 -284.90291) (xy 235.31322 -284.89529) (xy 235.220764 -284.89529) (xy 235.201968 -284.90291)
			(xy 235.194856 -284.910276) (xy 235.173226 -284.93125) (xy 235.124599 -284.96682) (xy 235.070984 -284.994302)
			(xy 235.013715 -285.013011) (xy 234.954216 -285.022483) (xy 234.924092 -285.023052) (xy 234.896844 -285.022477)
			(xy 234.842904 -285.014721) (xy 234.790616 -284.999367) (xy 234.741046 -284.976728) (xy 234.695202 -284.947265)
			(xy 234.654017 -284.911577) (xy 234.618331 -284.870392) (xy 234.588868 -284.824547) (xy 234.56623 -284.774976)
			(xy 234.550878 -284.722688) (xy 234.543122 -284.668748) (xy 223.714189 -284.668748) (xy 223.714189 -284.668758)
			(xy 223.70643 -284.722719) (xy 223.69107 -284.775027) (xy 223.668422 -284.824615) (xy 223.638946 -284.870476)
			(xy 223.603243 -284.911675) (xy 223.562041 -284.947372) (xy 223.516177 -284.976843) (xy 223.466585 -284.999485)
			(xy 223.414276 -285.014839) (xy 223.360314 -285.022592) (xy 223.333056 -285.023052) (xy 223.302934 -285.022445)
			(xy 223.243439 -285.012973) (xy 223.186172 -284.99427) (xy 223.132554 -284.966802) (xy 223.083918 -284.931251)
			(xy 223.062292 -284.910276) (xy 223.05518 -284.90291) (xy 223.036384 -284.89529) (xy 222.943928 -284.89529)
			(xy 222.925132 -284.90291) (xy 222.91802 -284.910276) (xy 222.896406 -284.931268) (xy 222.847774 -284.966835)
			(xy 222.794155 -284.994314) (xy 222.736883 -285.013019) (xy 222.677381 -285.022486) (xy 222.647256 -285.023052)
			(xy 222.618517 -285.022541) (xy 222.561689 -285.013913) (xy 222.506799 -284.996859) (xy 222.455088 -284.971765)
			(xy 222.407725 -284.939199) (xy 222.386398 -284.919928) (xy 222.379286 -284.913324) (xy 222.36176 -284.906212)
			(xy 222.272352 -284.906212) (xy 222.254826 -284.913324) (xy 222.247714 -284.919928) (xy 222.226387 -284.939198)
			(xy 222.179024 -284.971763) (xy 222.127313 -284.996854) (xy 222.072422 -285.013904) (xy 222.015595 -285.022526)
			(xy 221.958117 -285.022526) (xy 221.90129 -285.013904) (xy 221.846399 -284.996854) (xy 221.794688 -284.971763)
			(xy 221.747325 -284.939198) (xy 221.725998 -284.919928) (xy 221.718886 -284.913324) (xy 221.70136 -284.906212)
			(xy 221.611952 -284.906212) (xy 221.594426 -284.913324) (xy 221.587314 -284.919928) (xy 221.566 -284.939214)
			(xy 221.518635 -284.971779) (xy 221.46692 -284.99687) (xy 221.412026 -285.013916) (xy 221.355196 -285.022534)
			(xy 221.326456 -285.023052) (xy 221.29921 -285.022475) (xy 221.245273 -285.014714) (xy 221.19299 -284.999357)
			(xy 221.143424 -284.976716) (xy 221.097584 -284.947252) (xy 221.056404 -284.911565) (xy 221.020722 -284.87038)
			(xy 220.991263 -284.824537) (xy 220.968628 -284.774969) (xy 220.953276 -284.722684) (xy 220.945522 -284.668746)
			(xy 219.669989 -284.668746) (xy 219.669989 -284.668757) (xy 219.66223 -284.722717) (xy 219.646871 -284.775024)
			(xy 219.624223 -284.824612) (xy 219.594749 -284.870472) (xy 219.559048 -284.91167) (xy 219.517846 -284.947368)
			(xy 219.471984 -284.976839) (xy 219.422394 -284.999482) (xy 219.370086 -285.014837) (xy 219.316126 -285.022591)
			(xy 219.288868 -285.023052) (xy 219.261497 -285.022616) (xy 219.207316 -285.014793) (xy 219.154812 -284.999297)
			(xy 219.105065 -284.976449) (xy 219.0591 -284.946717) (xy 219.03817 -284.929072) (xy 219.031058 -284.922976)
			(xy 219.01404 -284.916626) (xy 218.928696 -284.916626) (xy 218.911678 -284.922976) (xy 218.904566 -284.929072)
			(xy 218.883616 -284.946689) (xy 218.837649 -284.976405) (xy 218.787906 -284.999246) (xy 218.735409 -285.014742)
			(xy 218.681236 -285.022575) (xy 218.653868 -285.023052) (xy 218.623744 -285.022501) (xy 218.564247 -285.013015)
			(xy 218.506978 -284.994299) (xy 218.453362 -284.966819) (xy 218.404728 -284.931257) (xy 218.383104 -284.910276)
			(xy 218.375992 -284.90291) (xy 218.357196 -284.89529) (xy 218.26474 -284.89529) (xy 218.245944 -284.90291)
			(xy 218.238832 -284.910276) (xy 218.217212 -284.931262) (xy 218.168583 -284.96683) (xy 218.114965 -284.99431)
			(xy 218.057693 -285.013017) (xy 217.998193 -285.022485) (xy 217.968068 -285.023052) (xy 217.939329 -285.022534)
			(xy 217.882502 -285.013908) (xy 217.827612 -284.996856) (xy 217.7759 -284.971763) (xy 217.728537 -284.939198)
			(xy 217.70721 -284.919928) (xy 217.700098 -284.913324) (xy 217.682572 -284.906212) (xy 217.593164 -284.906212)
			(xy 217.575638 -284.913324) (xy 217.568526 -284.919928) (xy 217.547207 -284.939208) (xy 217.499843 -284.971774)
			(xy 217.44813 -284.996866) (xy 217.393237 -285.013914) (xy 217.336408 -285.022533) (xy 217.307668 -285.023052)
			(xy 217.280421 -285.022476) (xy 217.226483 -285.014716) (xy 217.174199 -284.99936) (xy 217.124631 -284.97672)
			(xy 217.07879 -284.947256) (xy 217.037609 -284.911569) (xy 217.001925 -284.870384) (xy 216.972465 -284.824541)
			(xy 216.949829 -284.774971) (xy 216.934477 -284.722685) (xy 216.926722 -284.668747) (xy 214.480115 -284.668747)
			(xy 214.119206 -285.029656) (xy 258.01142 -285.029656) (xy 258.015491 -284.974034) (xy 258.027617 -284.919597)
			(xy 258.04754 -284.867506) (xy 258.074836 -284.818871) (xy 258.108922 -284.774728) (xy 258.149071 -284.736019)
			(xy 258.194429 -284.703568) (xy 258.244029 -284.678067) (xy 258.296813 -284.66006) (xy 258.351656 -284.64993)
			(xy 258.40739 -284.647893) (xy 258.462827 -284.653993) (xy 258.516784 -284.668099) (xy 258.568113 -284.689911)
			(xy 258.615719 -284.718965) (xy 258.658587 -284.75464) (xy 258.695804 -284.796177) (xy 258.726577 -284.84269)
			(xy 258.750249 -284.893187) (xy 258.766317 -284.946594) (xy 258.774437 -285.00177) (xy 258.774946 -285.029656)
			(xy 259.496558 -285.029656) (xy 259.500629 -284.974034) (xy 259.512755 -284.919597) (xy 259.532678 -284.867506)
			(xy 259.559974 -284.818871) (xy 259.59406 -284.774728) (xy 259.634209 -284.736019) (xy 259.679567 -284.703568)
			(xy 259.729167 -284.678067) (xy 259.781951 -284.66006) (xy 259.836794 -284.64993) (xy 259.892528 -284.647893)
			(xy 259.947965 -284.653993) (xy 260.001922 -284.668099) (xy 260.053251 -284.689911) (xy 260.100857 -284.718965)
			(xy 260.143725 -284.75464) (xy 260.180942 -284.796177) (xy 260.211715 -284.84269) (xy 260.235387 -284.893187)
			(xy 260.251455 -284.946594) (xy 260.255605 -284.974792) (xy 268.26897 -284.974792) (xy 268.27293 -284.925738)
			(xy 268.284707 -284.877954) (xy 268.303998 -284.832678) (xy 268.330301 -284.791082) (xy 268.362936 -284.754245)
			(xy 268.401057 -284.72312) (xy 268.443678 -284.698513) (xy 268.489694 -284.681061) (xy 268.537913 -284.671217)
			(xy 268.587088 -284.669236) (xy 268.635943 -284.675168) (xy 268.683214 -284.68886) (xy 268.727676 -284.709958)
			(xy 268.768179 -284.737914) (xy 268.803672 -284.772006) (xy 268.833237 -284.81135) (xy 268.856108 -284.854927)
			(xy 268.871692 -284.901608) (xy 268.879587 -284.950185) (xy 268.880082 -284.974792) (xy 269.21893 -284.974792)
			(xy 269.22289 -284.925738) (xy 269.234667 -284.877954) (xy 269.253958 -284.832678) (xy 269.280261 -284.791082)
			(xy 269.312896 -284.754245) (xy 269.351017 -284.72312) (xy 269.393638 -284.698513) (xy 269.439654 -284.681061)
			(xy 269.487873 -284.671217) (xy 269.537048 -284.669236) (xy 269.585903 -284.675168) (xy 269.633174 -284.68886)
			(xy 269.677636 -284.709958) (xy 269.718139 -284.737914) (xy 269.753632 -284.772006) (xy 269.783197 -284.81135)
			(xy 269.806068 -284.854927) (xy 269.821652 -284.901608) (xy 269.829547 -284.950185) (xy 269.830042 -284.974792)
			(xy 270.169144 -284.974792) (xy 270.173104 -284.925738) (xy 270.184881 -284.877954) (xy 270.204172 -284.832678)
			(xy 270.230475 -284.791082) (xy 270.26311 -284.754245) (xy 270.301231 -284.72312) (xy 270.343852 -284.698513)
			(xy 270.389868 -284.681061) (xy 270.438087 -284.671217) (xy 270.487262 -284.669236) (xy 270.536117 -284.675168)
			(xy 270.583388 -284.68886) (xy 270.62785 -284.709958) (xy 270.668353 -284.737914) (xy 270.703846 -284.772006)
			(xy 270.733411 -284.81135) (xy 270.756282 -284.854927) (xy 270.771866 -284.901608) (xy 270.779761 -284.950185)
			(xy 270.780256 -284.974792) (xy 271.119104 -284.974792) (xy 271.123064 -284.925738) (xy 271.134841 -284.877954)
			(xy 271.154132 -284.832678) (xy 271.180435 -284.791082) (xy 271.21307 -284.754245) (xy 271.251191 -284.72312)
			(xy 271.293812 -284.698513) (xy 271.339828 -284.681061) (xy 271.388047 -284.671217) (xy 271.437222 -284.669236)
			(xy 271.486077 -284.675168) (xy 271.533348 -284.68886) (xy 271.57781 -284.709958) (xy 271.618313 -284.737914)
			(xy 271.653806 -284.772006) (xy 271.683371 -284.81135) (xy 271.706242 -284.854927) (xy 271.721826 -284.901608)
			(xy 271.729721 -284.950185) (xy 271.730216 -284.974792) (xy 272.069064 -284.974792) (xy 272.073024 -284.925738)
			(xy 272.084801 -284.877954) (xy 272.104092 -284.832678) (xy 272.130395 -284.791082) (xy 272.16303 -284.754245)
			(xy 272.201151 -284.72312) (xy 272.243772 -284.698513) (xy 272.289788 -284.681061) (xy 272.338007 -284.671217)
			(xy 272.387182 -284.669236) (xy 272.436037 -284.675168) (xy 272.483308 -284.68886) (xy 272.52777 -284.709958)
			(xy 272.568273 -284.737914) (xy 272.603766 -284.772006) (xy 272.633331 -284.81135) (xy 272.656202 -284.854927)
			(xy 272.671786 -284.901608) (xy 272.679681 -284.950185) (xy 272.680176 -284.974792) (xy 274.918944 -284.974792)
			(xy 274.922904 -284.925738) (xy 274.934681 -284.877954) (xy 274.953972 -284.832678) (xy 274.980275 -284.791082)
			(xy 275.01291 -284.754245) (xy 275.051031 -284.72312) (xy 275.093652 -284.698513) (xy 275.139668 -284.681061)
			(xy 275.187887 -284.671217) (xy 275.237062 -284.669236) (xy 275.285917 -284.675168) (xy 275.333188 -284.68886)
			(xy 275.37765 -284.709958) (xy 275.418153 -284.737914) (xy 275.453646 -284.772006) (xy 275.483211 -284.81135)
			(xy 275.506082 -284.854927) (xy 275.521666 -284.901608) (xy 275.529561 -284.950185) (xy 275.530056 -284.974792)
			(xy 276.819118 -284.974792) (xy 276.823078 -284.925738) (xy 276.834855 -284.877954) (xy 276.854146 -284.832678)
			(xy 276.880449 -284.791082) (xy 276.913084 -284.754245) (xy 276.951205 -284.72312) (xy 276.993826 -284.698513)
			(xy 277.039842 -284.681061) (xy 277.088061 -284.671217) (xy 277.137236 -284.669236) (xy 277.186091 -284.675168)
			(xy 277.233362 -284.68886) (xy 277.277824 -284.709958) (xy 277.318327 -284.737914) (xy 277.35382 -284.772006)
			(xy 277.383385 -284.81135) (xy 277.406256 -284.854927) (xy 277.42184 -284.901608) (xy 277.429735 -284.950185)
			(xy 277.43023 -284.974792) (xy 277.769078 -284.974792) (xy 277.773038 -284.925738) (xy 277.784815 -284.877954)
			(xy 277.804106 -284.832678) (xy 277.830409 -284.791082) (xy 277.863044 -284.754245) (xy 277.901165 -284.72312)
			(xy 277.943786 -284.698513) (xy 277.989802 -284.681061) (xy 278.038021 -284.671217) (xy 278.087196 -284.669236)
			(xy 278.136051 -284.675168) (xy 278.183322 -284.68886) (xy 278.227784 -284.709958) (xy 278.268287 -284.737914)
			(xy 278.30378 -284.772006) (xy 278.333345 -284.81135) (xy 278.356216 -284.854927) (xy 278.3718 -284.901608)
			(xy 278.379695 -284.950185) (xy 278.38019 -284.974792) (xy 278.719038 -284.974792) (xy 278.722998 -284.925738)
			(xy 278.734775 -284.877954) (xy 278.754066 -284.832678) (xy 278.780369 -284.791082) (xy 278.813004 -284.754245)
			(xy 278.851125 -284.72312) (xy 278.893746 -284.698513) (xy 278.939762 -284.681061) (xy 278.987981 -284.671217)
			(xy 279.037156 -284.669236) (xy 279.086011 -284.675168) (xy 279.133282 -284.68886) (xy 279.177744 -284.709958)
			(xy 279.218247 -284.737914) (xy 279.25374 -284.772006) (xy 279.283305 -284.81135) (xy 279.306176 -284.854927)
			(xy 279.32176 -284.901608) (xy 279.329655 -284.950185) (xy 279.33015 -284.974792) (xy 279.668998 -284.974792)
			(xy 279.672958 -284.925738) (xy 279.684735 -284.877954) (xy 279.704026 -284.832678) (xy 279.730329 -284.791082)
			(xy 279.762964 -284.754245) (xy 279.801085 -284.72312) (xy 279.843706 -284.698513) (xy 279.889722 -284.681061)
			(xy 279.937941 -284.671217) (xy 279.987116 -284.669236) (xy 280.035971 -284.675168) (xy 280.083242 -284.68886)
			(xy 280.127704 -284.709958) (xy 280.168207 -284.737914) (xy 280.2037 -284.772006) (xy 280.233265 -284.81135)
			(xy 280.256136 -284.854927) (xy 280.27172 -284.901608) (xy 280.279615 -284.950185) (xy 280.28011 -284.974792)
			(xy 280.618958 -284.974792) (xy 280.622918 -284.925738) (xy 280.634695 -284.877954) (xy 280.653986 -284.832678)
			(xy 280.680289 -284.791082) (xy 280.712924 -284.754245) (xy 280.751045 -284.72312) (xy 280.793666 -284.698513)
			(xy 280.839682 -284.681061) (xy 280.887901 -284.671217) (xy 280.937076 -284.669236) (xy 280.985931 -284.675168)
			(xy 281.033202 -284.68886) (xy 281.077664 -284.709958) (xy 281.118167 -284.737914) (xy 281.15366 -284.772006)
			(xy 281.183225 -284.81135) (xy 281.206096 -284.854927) (xy 281.22168 -284.901608) (xy 281.229575 -284.950185)
			(xy 281.23007 -284.974792) (xy 281.568918 -284.974792) (xy 281.572878 -284.925738) (xy 281.584655 -284.877954)
			(xy 281.603946 -284.832678) (xy 281.630249 -284.791082) (xy 281.662884 -284.754245) (xy 281.701005 -284.72312)
			(xy 281.743626 -284.698513) (xy 281.789642 -284.681061) (xy 281.837861 -284.671217) (xy 281.887036 -284.669236)
			(xy 281.935891 -284.675168) (xy 281.983162 -284.68886) (xy 282.027624 -284.709958) (xy 282.068127 -284.737914)
			(xy 282.10362 -284.772006) (xy 282.133185 -284.81135) (xy 282.156056 -284.854927) (xy 282.17164 -284.901608)
			(xy 282.179535 -284.950185) (xy 282.18003 -284.974792) (xy 282.519132 -284.974792) (xy 282.523092 -284.925738)
			(xy 282.534869 -284.877954) (xy 282.55416 -284.832678) (xy 282.580463 -284.791082) (xy 282.613098 -284.754245)
			(xy 282.651219 -284.72312) (xy 282.69384 -284.698513) (xy 282.739856 -284.681061) (xy 282.788075 -284.671217)
			(xy 282.83725 -284.669236) (xy 282.886105 -284.675168) (xy 282.933376 -284.68886) (xy 282.977838 -284.709958)
			(xy 283.018341 -284.737914) (xy 283.053834 -284.772006) (xy 283.083399 -284.81135) (xy 283.10627 -284.854927)
			(xy 283.121854 -284.901608) (xy 283.129749 -284.950185) (xy 283.130244 -284.974792) (xy 283.469092 -284.974792)
			(xy 283.473052 -284.925738) (xy 283.484829 -284.877954) (xy 283.50412 -284.832678) (xy 283.530423 -284.791082)
			(xy 283.563058 -284.754245) (xy 283.601179 -284.72312) (xy 283.6438 -284.698513) (xy 283.689816 -284.681061)
			(xy 283.738035 -284.671217) (xy 283.78721 -284.669236) (xy 283.836065 -284.675168) (xy 283.883336 -284.68886)
			(xy 283.927798 -284.709958) (xy 283.968301 -284.737914) (xy 284.003794 -284.772006) (xy 284.033359 -284.81135)
			(xy 284.05623 -284.854927) (xy 284.071814 -284.901608) (xy 284.079709 -284.950185) (xy 284.080204 -284.974792)
			(xy 284.419052 -284.974792) (xy 284.423012 -284.925738) (xy 284.434789 -284.877954) (xy 284.45408 -284.832678)
			(xy 284.480383 -284.791082) (xy 284.513018 -284.754245) (xy 284.551139 -284.72312) (xy 284.59376 -284.698513)
			(xy 284.639776 -284.681061) (xy 284.687995 -284.671217) (xy 284.73717 -284.669236) (xy 284.786025 -284.675168)
			(xy 284.833296 -284.68886) (xy 284.877758 -284.709958) (xy 284.918261 -284.737914) (xy 284.953754 -284.772006)
			(xy 284.983319 -284.81135) (xy 285.00619 -284.854927) (xy 285.021774 -284.901608) (xy 285.029669 -284.950185)
			(xy 285.030164 -284.974792) (xy 285.369012 -284.974792) (xy 285.372972 -284.925738) (xy 285.384749 -284.877954)
			(xy 285.40404 -284.832678) (xy 285.430343 -284.791082) (xy 285.462978 -284.754245) (xy 285.501099 -284.72312)
			(xy 285.54372 -284.698513) (xy 285.589736 -284.681061) (xy 285.637955 -284.671217) (xy 285.68713 -284.669236)
			(xy 285.735985 -284.675168) (xy 285.783256 -284.68886) (xy 285.827718 -284.709958) (xy 285.868221 -284.737914)
			(xy 285.903714 -284.772006) (xy 285.933279 -284.81135) (xy 285.95615 -284.854927) (xy 285.971734 -284.901608)
			(xy 285.979629 -284.950185) (xy 285.980124 -284.974792) (xy 286.318972 -284.974792) (xy 286.322932 -284.925738)
			(xy 286.334709 -284.877954) (xy 286.354 -284.832678) (xy 286.380303 -284.791082) (xy 286.412938 -284.754245)
			(xy 286.451059 -284.72312) (xy 286.49368 -284.698513) (xy 286.539696 -284.681061) (xy 286.587915 -284.671217)
			(xy 286.63709 -284.669236) (xy 286.685945 -284.675168) (xy 286.733216 -284.68886) (xy 286.777678 -284.709958)
			(xy 286.818181 -284.737914) (xy 286.853674 -284.772006) (xy 286.883239 -284.81135) (xy 286.90611 -284.854927)
			(xy 286.921694 -284.901608) (xy 286.929589 -284.950185) (xy 286.930084 -284.974792) (xy 287.268932 -284.974792)
			(xy 287.272892 -284.925738) (xy 287.284669 -284.877954) (xy 287.30396 -284.832678) (xy 287.330263 -284.791082)
			(xy 287.362898 -284.754245) (xy 287.401019 -284.72312) (xy 287.44364 -284.698513) (xy 287.489656 -284.681061)
			(xy 287.537875 -284.671217) (xy 287.58705 -284.669236) (xy 287.635905 -284.675168) (xy 287.683176 -284.68886)
			(xy 287.727638 -284.709958) (xy 287.768141 -284.737914) (xy 287.803634 -284.772006) (xy 287.833199 -284.81135)
			(xy 287.85607 -284.854927) (xy 287.871654 -284.901608) (xy 287.879549 -284.950185) (xy 287.880044 -284.974792)
			(xy 288.218892 -284.974792) (xy 288.222852 -284.925738) (xy 288.234629 -284.877954) (xy 288.25392 -284.832678)
			(xy 288.280223 -284.791082) (xy 288.312858 -284.754245) (xy 288.350979 -284.72312) (xy 288.3936 -284.698513)
			(xy 288.439616 -284.681061) (xy 288.487835 -284.671217) (xy 288.53701 -284.669236) (xy 288.585865 -284.675168)
			(xy 288.633136 -284.68886) (xy 288.677598 -284.709958) (xy 288.718101 -284.737914) (xy 288.753594 -284.772006)
			(xy 288.783159 -284.81135) (xy 288.80603 -284.854927) (xy 288.821614 -284.901608) (xy 288.829509 -284.950185)
			(xy 288.830004 -284.974792) (xy 289.169106 -284.974792) (xy 289.173066 -284.925738) (xy 289.184843 -284.877954)
			(xy 289.204134 -284.832678) (xy 289.230437 -284.791082) (xy 289.263072 -284.754245) (xy 289.301193 -284.72312)
			(xy 289.343814 -284.698513) (xy 289.38983 -284.681061) (xy 289.438049 -284.671217) (xy 289.487224 -284.669236)
			(xy 289.536079 -284.675168) (xy 289.58335 -284.68886) (xy 289.627812 -284.709958) (xy 289.668315 -284.737914)
			(xy 289.703808 -284.772006) (xy 289.733373 -284.81135) (xy 289.756244 -284.854927) (xy 289.771828 -284.901608)
			(xy 289.779723 -284.950185) (xy 289.780218 -284.974792) (xy 290.119066 -284.974792) (xy 290.123026 -284.925738)
			(xy 290.134803 -284.877954) (xy 290.154094 -284.832678) (xy 290.180397 -284.791082) (xy 290.213032 -284.754245)
			(xy 290.251153 -284.72312) (xy 290.293774 -284.698513) (xy 290.33979 -284.681061) (xy 290.388009 -284.671217)
			(xy 290.437184 -284.669236) (xy 290.486039 -284.675168) (xy 290.53331 -284.68886) (xy 290.577772 -284.709958)
			(xy 290.618275 -284.737914) (xy 290.653768 -284.772006) (xy 290.683333 -284.81135) (xy 290.706204 -284.854927)
			(xy 290.721788 -284.901608) (xy 290.729683 -284.950185) (xy 290.730178 -284.974792) (xy 292.018986 -284.974792)
			(xy 292.022946 -284.925738) (xy 292.034723 -284.877954) (xy 292.054014 -284.832678) (xy 292.080317 -284.791082)
			(xy 292.112952 -284.754245) (xy 292.151073 -284.72312) (xy 292.193694 -284.698513) (xy 292.23971 -284.681061)
			(xy 292.287929 -284.671217) (xy 292.337104 -284.669236) (xy 292.385959 -284.675168) (xy 292.43323 -284.68886)
			(xy 292.477692 -284.709958) (xy 292.518195 -284.737914) (xy 292.553688 -284.772006) (xy 292.583253 -284.81135)
			(xy 292.606124 -284.854927) (xy 292.621708 -284.901608) (xy 292.629603 -284.950185) (xy 292.630098 -284.974792)
			(xy 292.968946 -284.974792) (xy 292.972906 -284.925738) (xy 292.984683 -284.877954) (xy 293.003974 -284.832678)
			(xy 293.030277 -284.791082) (xy 293.062912 -284.754245) (xy 293.101033 -284.72312) (xy 293.143654 -284.698513)
			(xy 293.18967 -284.681061) (xy 293.237889 -284.671217) (xy 293.287064 -284.669236) (xy 293.335919 -284.675168)
			(xy 293.38319 -284.68886) (xy 293.427652 -284.709958) (xy 293.468155 -284.737914) (xy 293.503648 -284.772006)
			(xy 293.533213 -284.81135) (xy 293.556084 -284.854927) (xy 293.571668 -284.901608) (xy 293.579563 -284.950185)
			(xy 293.580058 -284.974792) (xy 293.918906 -284.974792) (xy 293.922866 -284.925738) (xy 293.934643 -284.877954)
			(xy 293.953934 -284.832678) (xy 293.980237 -284.791082) (xy 294.012872 -284.754245) (xy 294.050993 -284.72312)
			(xy 294.093614 -284.698513) (xy 294.13963 -284.681061) (xy 294.187849 -284.671217) (xy 294.237024 -284.669236)
			(xy 294.285879 -284.675168) (xy 294.33315 -284.68886) (xy 294.377612 -284.709958) (xy 294.418115 -284.737914)
			(xy 294.453608 -284.772006) (xy 294.483173 -284.81135) (xy 294.506044 -284.854927) (xy 294.521628 -284.901608)
			(xy 294.529523 -284.950185) (xy 294.530018 -284.974792) (xy 294.86912 -284.974792) (xy 294.87308 -284.925738)
			(xy 294.884857 -284.877954) (xy 294.904148 -284.832678) (xy 294.930451 -284.791082) (xy 294.963086 -284.754245)
			(xy 295.001207 -284.72312) (xy 295.043828 -284.698513) (xy 295.089844 -284.681061) (xy 295.138063 -284.671217)
			(xy 295.187238 -284.669236) (xy 295.236093 -284.675168) (xy 295.283364 -284.68886) (xy 295.327826 -284.709958)
			(xy 295.368329 -284.737914) (xy 295.403822 -284.772006) (xy 295.433387 -284.81135) (xy 295.456258 -284.854927)
			(xy 295.471842 -284.901608) (xy 295.479737 -284.950185) (xy 295.480232 -284.974792) (xy 295.81908 -284.974792)
			(xy 295.82304 -284.925738) (xy 295.834817 -284.877954) (xy 295.854108 -284.832678) (xy 295.880411 -284.791082)
			(xy 295.913046 -284.754245) (xy 295.951167 -284.72312) (xy 295.993788 -284.698513) (xy 296.039804 -284.681061)
			(xy 296.088023 -284.671217) (xy 296.137198 -284.669236) (xy 296.186053 -284.675168) (xy 296.233324 -284.68886)
			(xy 296.277786 -284.709958) (xy 296.318289 -284.737914) (xy 296.353782 -284.772006) (xy 296.383347 -284.81135)
			(xy 296.406218 -284.854927) (xy 296.421802 -284.901608) (xy 296.429697 -284.950185) (xy 296.430192 -284.974792)
			(xy 296.76904 -284.974792) (xy 296.773 -284.925738) (xy 296.784777 -284.877954) (xy 296.804068 -284.832678)
			(xy 296.830371 -284.791082) (xy 296.863006 -284.754245) (xy 296.901127 -284.72312) (xy 296.943748 -284.698513)
			(xy 296.989764 -284.681061) (xy 297.037983 -284.671217) (xy 297.087158 -284.669236) (xy 297.136013 -284.675168)
			(xy 297.183284 -284.68886) (xy 297.227746 -284.709958) (xy 297.268249 -284.737914) (xy 297.303742 -284.772006)
			(xy 297.333307 -284.81135) (xy 297.356178 -284.854927) (xy 297.371762 -284.901608) (xy 297.379657 -284.950185)
			(xy 297.380152 -284.974792) (xy 297.719 -284.974792) (xy 297.72296 -284.925738) (xy 297.734737 -284.877954)
			(xy 297.754028 -284.832678) (xy 297.780331 -284.791082) (xy 297.812966 -284.754245) (xy 297.851087 -284.72312)
			(xy 297.893708 -284.698513) (xy 297.939724 -284.681061) (xy 297.987943 -284.671217) (xy 298.037118 -284.669236)
			(xy 298.085973 -284.675168) (xy 298.133244 -284.68886) (xy 298.177706 -284.709958) (xy 298.218209 -284.737914)
			(xy 298.253702 -284.772006) (xy 298.283267 -284.81135) (xy 298.306138 -284.854927) (xy 298.321722 -284.901608)
			(xy 298.329617 -284.950185) (xy 298.330112 -284.974792) (xy 298.66896 -284.974792) (xy 298.67292 -284.925738)
			(xy 298.684697 -284.877954) (xy 298.703988 -284.832678) (xy 298.730291 -284.791082) (xy 298.762926 -284.754245)
			(xy 298.801047 -284.72312) (xy 298.843668 -284.698513) (xy 298.889684 -284.681061) (xy 298.937903 -284.671217)
			(xy 298.987078 -284.669236) (xy 299.035933 -284.675168) (xy 299.083204 -284.68886) (xy 299.127666 -284.709958)
			(xy 299.168169 -284.737914) (xy 299.203662 -284.772006) (xy 299.233227 -284.81135) (xy 299.256098 -284.854927)
			(xy 299.271682 -284.901608) (xy 299.279577 -284.950185) (xy 299.280072 -284.974792) (xy 299.61892 -284.974792)
			(xy 299.62288 -284.925738) (xy 299.634657 -284.877954) (xy 299.653948 -284.832678) (xy 299.680251 -284.791082)
			(xy 299.712886 -284.754245) (xy 299.751007 -284.72312) (xy 299.793628 -284.698513) (xy 299.839644 -284.681061)
			(xy 299.887863 -284.671217) (xy 299.937038 -284.669236) (xy 299.985893 -284.675168) (xy 300.033164 -284.68886)
			(xy 300.077626 -284.709958) (xy 300.118129 -284.737914) (xy 300.153622 -284.772006) (xy 300.183187 -284.81135)
			(xy 300.206058 -284.854927) (xy 300.221642 -284.901608) (xy 300.229537 -284.950185) (xy 300.230032 -284.974792)
			(xy 300.56888 -284.974792) (xy 300.57284 -284.925738) (xy 300.584617 -284.877954) (xy 300.603908 -284.832678)
			(xy 300.630211 -284.791082) (xy 300.662846 -284.754245) (xy 300.700967 -284.72312) (xy 300.743588 -284.698513)
			(xy 300.789604 -284.681061) (xy 300.837823 -284.671217) (xy 300.886998 -284.669236) (xy 300.935853 -284.675168)
			(xy 300.983124 -284.68886) (xy 301.027586 -284.709958) (xy 301.068089 -284.737914) (xy 301.103582 -284.772006)
			(xy 301.133147 -284.81135) (xy 301.156018 -284.854927) (xy 301.171602 -284.901608) (xy 301.179497 -284.950185)
			(xy 301.179992 -284.974792) (xy 301.519094 -284.974792) (xy 301.523054 -284.925738) (xy 301.534831 -284.877954)
			(xy 301.554122 -284.832678) (xy 301.580425 -284.791082) (xy 301.61306 -284.754245) (xy 301.651181 -284.72312)
			(xy 301.693802 -284.698513) (xy 301.739818 -284.681061) (xy 301.788037 -284.671217) (xy 301.837212 -284.669236)
			(xy 301.886067 -284.675168) (xy 301.933338 -284.68886) (xy 301.9778 -284.709958) (xy 302.018303 -284.737914)
			(xy 302.053796 -284.772006) (xy 302.083361 -284.81135) (xy 302.106232 -284.854927) (xy 302.121816 -284.901608)
			(xy 302.129711 -284.950185) (xy 302.130206 -284.974792) (xy 302.469054 -284.974792) (xy 302.473014 -284.925738)
			(xy 302.484791 -284.877954) (xy 302.504082 -284.832678) (xy 302.530385 -284.791082) (xy 302.56302 -284.754245)
			(xy 302.601141 -284.72312) (xy 302.643762 -284.698513) (xy 302.689778 -284.681061) (xy 302.737997 -284.671217)
			(xy 302.787172 -284.669236) (xy 302.836027 -284.675168) (xy 302.883298 -284.68886) (xy 302.92776 -284.709958)
			(xy 302.968263 -284.737914) (xy 303.003756 -284.772006) (xy 303.033321 -284.81135) (xy 303.056192 -284.854927)
			(xy 303.071776 -284.901608) (xy 303.079671 -284.950185) (xy 303.080166 -284.974792) (xy 303.079671 -284.999399)
			(xy 303.071776 -285.047976) (xy 303.056192 -285.094657) (xy 303.033321 -285.138234) (xy 303.003756 -285.177578)
			(xy 302.968263 -285.21167) (xy 302.92776 -285.239626) (xy 302.883298 -285.260724) (xy 302.836027 -285.274416)
			(xy 302.787172 -285.280348) (xy 302.737997 -285.278367) (xy 302.689778 -285.268523) (xy 302.643762 -285.251071)
			(xy 302.601141 -285.226464) (xy 302.56302 -285.195339) (xy 302.530385 -285.158502) (xy 302.504082 -285.116906)
			(xy 302.484791 -285.07163) (xy 302.473014 -285.023846) (xy 302.469054 -284.974792) (xy 302.130206 -284.974792)
			(xy 302.129711 -284.999399) (xy 302.121816 -285.047976) (xy 302.106232 -285.094657) (xy 302.083361 -285.138234)
			(xy 302.053796 -285.177578) (xy 302.018303 -285.21167) (xy 301.9778 -285.239626) (xy 301.933338 -285.260724)
			(xy 301.886067 -285.274416) (xy 301.837212 -285.280348) (xy 301.788037 -285.278367) (xy 301.739818 -285.268523)
			(xy 301.693802 -285.251071) (xy 301.651181 -285.226464) (xy 301.61306 -285.195339) (xy 301.580425 -285.158502)
			(xy 301.554122 -285.116906) (xy 301.534831 -285.07163) (xy 301.523054 -285.023846) (xy 301.519094 -284.974792)
			(xy 301.179992 -284.974792) (xy 301.179497 -284.999399) (xy 301.171602 -285.047976) (xy 301.156018 -285.094657)
			(xy 301.133147 -285.138234) (xy 301.103582 -285.177578) (xy 301.068089 -285.21167) (xy 301.027586 -285.239626)
			(xy 300.983124 -285.260724) (xy 300.935853 -285.274416) (xy 300.886998 -285.280348) (xy 300.837823 -285.278367)
			(xy 300.789604 -285.268523) (xy 300.743588 -285.251071) (xy 300.700967 -285.226464) (xy 300.662846 -285.195339)
			(xy 300.630211 -285.158502) (xy 300.603908 -285.116906) (xy 300.584617 -285.07163) (xy 300.57284 -285.023846)
			(xy 300.56888 -284.974792) (xy 300.230032 -284.974792) (xy 300.229537 -284.999399) (xy 300.221642 -285.047976)
			(xy 300.206058 -285.094657) (xy 300.183187 -285.138234) (xy 300.153622 -285.177578) (xy 300.118129 -285.21167)
			(xy 300.077626 -285.239626) (xy 300.033164 -285.260724) (xy 299.985893 -285.274416) (xy 299.937038 -285.280348)
			(xy 299.887863 -285.278367) (xy 299.839644 -285.268523) (xy 299.793628 -285.251071) (xy 299.751007 -285.226464)
			(xy 299.712886 -285.195339) (xy 299.680251 -285.158502) (xy 299.653948 -285.116906) (xy 299.634657 -285.07163)
			(xy 299.62288 -285.023846) (xy 299.61892 -284.974792) (xy 299.280072 -284.974792) (xy 299.279577 -284.999399)
			(xy 299.271682 -285.047976) (xy 299.256098 -285.094657) (xy 299.233227 -285.138234) (xy 299.203662 -285.177578)
			(xy 299.168169 -285.21167) (xy 299.127666 -285.239626) (xy 299.083204 -285.260724) (xy 299.035933 -285.274416)
			(xy 298.987078 -285.280348) (xy 298.937903 -285.278367) (xy 298.889684 -285.268523) (xy 298.843668 -285.251071)
			(xy 298.801047 -285.226464) (xy 298.762926 -285.195339) (xy 298.730291 -285.158502) (xy 298.703988 -285.116906)
			(xy 298.684697 -285.07163) (xy 298.67292 -285.023846) (xy 298.66896 -284.974792) (xy 298.330112 -284.974792)
			(xy 298.329617 -284.999399) (xy 298.321722 -285.047976) (xy 298.306138 -285.094657) (xy 298.283267 -285.138234)
			(xy 298.253702 -285.177578) (xy 298.218209 -285.21167) (xy 298.177706 -285.239626) (xy 298.133244 -285.260724)
			(xy 298.085973 -285.274416) (xy 298.037118 -285.280348) (xy 297.987943 -285.278367) (xy 297.939724 -285.268523)
			(xy 297.893708 -285.251071) (xy 297.851087 -285.226464) (xy 297.812966 -285.195339) (xy 297.780331 -285.158502)
			(xy 297.754028 -285.116906) (xy 297.734737 -285.07163) (xy 297.72296 -285.023846) (xy 297.719 -284.974792)
			(xy 297.380152 -284.974792) (xy 297.379657 -284.999399) (xy 297.371762 -285.047976) (xy 297.356178 -285.094657)
			(xy 297.333307 -285.138234) (xy 297.303742 -285.177578) (xy 297.268249 -285.21167) (xy 297.227746 -285.239626)
			(xy 297.183284 -285.260724) (xy 297.136013 -285.274416) (xy 297.087158 -285.280348) (xy 297.037983 -285.278367)
			(xy 296.989764 -285.268523) (xy 296.943748 -285.251071) (xy 296.901127 -285.226464) (xy 296.863006 -285.195339)
			(xy 296.830371 -285.158502) (xy 296.804068 -285.116906) (xy 296.784777 -285.07163) (xy 296.773 -285.023846)
			(xy 296.76904 -284.974792) (xy 296.430192 -284.974792) (xy 296.429697 -284.999399) (xy 296.421802 -285.047976)
			(xy 296.406218 -285.094657) (xy 296.383347 -285.138234) (xy 296.353782 -285.177578) (xy 296.318289 -285.21167)
			(xy 296.277786 -285.239626) (xy 296.233324 -285.260724) (xy 296.186053 -285.274416) (xy 296.137198 -285.280348)
			(xy 296.088023 -285.278367) (xy 296.039804 -285.268523) (xy 295.993788 -285.251071) (xy 295.951167 -285.226464)
			(xy 295.913046 -285.195339) (xy 295.880411 -285.158502) (xy 295.854108 -285.116906) (xy 295.834817 -285.07163)
			(xy 295.82304 -285.023846) (xy 295.81908 -284.974792) (xy 295.480232 -284.974792) (xy 295.479737 -284.999399)
			(xy 295.471842 -285.047976) (xy 295.456258 -285.094657) (xy 295.433387 -285.138234) (xy 295.403822 -285.177578)
			(xy 295.368329 -285.21167) (xy 295.327826 -285.239626) (xy 295.283364 -285.260724) (xy 295.236093 -285.274416)
			(xy 295.187238 -285.280348) (xy 295.138063 -285.278367) (xy 295.089844 -285.268523) (xy 295.043828 -285.251071)
			(xy 295.001207 -285.226464) (xy 294.963086 -285.195339) (xy 294.930451 -285.158502) (xy 294.904148 -285.116906)
			(xy 294.884857 -285.07163) (xy 294.87308 -285.023846) (xy 294.86912 -284.974792) (xy 294.530018 -284.974792)
			(xy 294.529523 -284.999399) (xy 294.521628 -285.047976) (xy 294.506044 -285.094657) (xy 294.483173 -285.138234)
			(xy 294.453608 -285.177578) (xy 294.418115 -285.21167) (xy 294.377612 -285.239626) (xy 294.33315 -285.260724)
			(xy 294.285879 -285.274416) (xy 294.237024 -285.280348) (xy 294.187849 -285.278367) (xy 294.13963 -285.268523)
			(xy 294.093614 -285.251071) (xy 294.050993 -285.226464) (xy 294.012872 -285.195339) (xy 293.980237 -285.158502)
			(xy 293.953934 -285.116906) (xy 293.934643 -285.07163) (xy 293.922866 -285.023846) (xy 293.918906 -284.974792)
			(xy 293.580058 -284.974792) (xy 293.579563 -284.999399) (xy 293.571668 -285.047976) (xy 293.556084 -285.094657)
			(xy 293.533213 -285.138234) (xy 293.503648 -285.177578) (xy 293.468155 -285.21167) (xy 293.427652 -285.239626)
			(xy 293.38319 -285.260724) (xy 293.335919 -285.274416) (xy 293.287064 -285.280348) (xy 293.237889 -285.278367)
			(xy 293.18967 -285.268523) (xy 293.143654 -285.251071) (xy 293.101033 -285.226464) (xy 293.062912 -285.195339)
			(xy 293.030277 -285.158502) (xy 293.003974 -285.116906) (xy 292.984683 -285.07163) (xy 292.972906 -285.023846)
			(xy 292.968946 -284.974792) (xy 292.630098 -284.974792) (xy 292.629603 -284.999399) (xy 292.621708 -285.047976)
			(xy 292.606124 -285.094657) (xy 292.583253 -285.138234) (xy 292.553688 -285.177578) (xy 292.518195 -285.21167)
			(xy 292.477692 -285.239626) (xy 292.43323 -285.260724) (xy 292.385959 -285.274416) (xy 292.337104 -285.280348)
			(xy 292.287929 -285.278367) (xy 292.23971 -285.268523) (xy 292.193694 -285.251071) (xy 292.151073 -285.226464)
			(xy 292.112952 -285.195339) (xy 292.080317 -285.158502) (xy 292.054014 -285.116906) (xy 292.034723 -285.07163)
			(xy 292.022946 -285.023846) (xy 292.018986 -284.974792) (xy 290.730178 -284.974792) (xy 290.729683 -284.999399)
			(xy 290.721788 -285.047976) (xy 290.706204 -285.094657) (xy 290.683333 -285.138234) (xy 290.653768 -285.177578)
			(xy 290.618275 -285.21167) (xy 290.577772 -285.239626) (xy 290.53331 -285.260724) (xy 290.486039 -285.274416)
			(xy 290.437184 -285.280348) (xy 290.388009 -285.278367) (xy 290.33979 -285.268523) (xy 290.293774 -285.251071)
			(xy 290.251153 -285.226464) (xy 290.213032 -285.195339) (xy 290.180397 -285.158502) (xy 290.154094 -285.116906)
			(xy 290.134803 -285.07163) (xy 290.123026 -285.023846) (xy 290.119066 -284.974792) (xy 289.780218 -284.974792)
			(xy 289.779723 -284.999399) (xy 289.771828 -285.047976) (xy 289.756244 -285.094657) (xy 289.733373 -285.138234)
			(xy 289.703808 -285.177578) (xy 289.668315 -285.21167) (xy 289.627812 -285.239626) (xy 289.58335 -285.260724)
			(xy 289.536079 -285.274416) (xy 289.487224 -285.280348) (xy 289.438049 -285.278367) (xy 289.38983 -285.268523)
			(xy 289.343814 -285.251071) (xy 289.301193 -285.226464) (xy 289.263072 -285.195339) (xy 289.230437 -285.158502)
			(xy 289.204134 -285.116906) (xy 289.184843 -285.07163) (xy 289.173066 -285.023846) (xy 289.169106 -284.974792)
			(xy 288.830004 -284.974792) (xy 288.829509 -284.999399) (xy 288.821614 -285.047976) (xy 288.80603 -285.094657)
			(xy 288.783159 -285.138234) (xy 288.753594 -285.177578) (xy 288.718101 -285.21167) (xy 288.677598 -285.239626)
			(xy 288.633136 -285.260724) (xy 288.585865 -285.274416) (xy 288.53701 -285.280348) (xy 288.487835 -285.278367)
			(xy 288.439616 -285.268523) (xy 288.3936 -285.251071) (xy 288.350979 -285.226464) (xy 288.312858 -285.195339)
			(xy 288.280223 -285.158502) (xy 288.25392 -285.116906) (xy 288.234629 -285.07163) (xy 288.222852 -285.023846)
			(xy 288.218892 -284.974792) (xy 287.880044 -284.974792) (xy 287.879549 -284.999399) (xy 287.871654 -285.047976)
			(xy 287.85607 -285.094657) (xy 287.833199 -285.138234) (xy 287.803634 -285.177578) (xy 287.768141 -285.21167)
			(xy 287.727638 -285.239626) (xy 287.683176 -285.260724) (xy 287.635905 -285.274416) (xy 287.58705 -285.280348)
			(xy 287.537875 -285.278367) (xy 287.489656 -285.268523) (xy 287.44364 -285.251071) (xy 287.401019 -285.226464)
			(xy 287.362898 -285.195339) (xy 287.330263 -285.158502) (xy 287.30396 -285.116906) (xy 287.284669 -285.07163)
			(xy 287.272892 -285.023846) (xy 287.268932 -284.974792) (xy 286.930084 -284.974792) (xy 286.929589 -284.999399)
			(xy 286.921694 -285.047976) (xy 286.90611 -285.094657) (xy 286.883239 -285.138234) (xy 286.853674 -285.177578)
			(xy 286.818181 -285.21167) (xy 286.777678 -285.239626) (xy 286.733216 -285.260724) (xy 286.685945 -285.274416)
			(xy 286.63709 -285.280348) (xy 286.587915 -285.278367) (xy 286.539696 -285.268523) (xy 286.49368 -285.251071)
			(xy 286.451059 -285.226464) (xy 286.412938 -285.195339) (xy 286.380303 -285.158502) (xy 286.354 -285.116906)
			(xy 286.334709 -285.07163) (xy 286.322932 -285.023846) (xy 286.318972 -284.974792) (xy 285.980124 -284.974792)
			(xy 285.979629 -284.999399) (xy 285.971734 -285.047976) (xy 285.95615 -285.094657) (xy 285.933279 -285.138234)
			(xy 285.903714 -285.177578) (xy 285.868221 -285.21167) (xy 285.827718 -285.239626) (xy 285.783256 -285.260724)
			(xy 285.735985 -285.274416) (xy 285.68713 -285.280348) (xy 285.637955 -285.278367) (xy 285.589736 -285.268523)
			(xy 285.54372 -285.251071) (xy 285.501099 -285.226464) (xy 285.462978 -285.195339) (xy 285.430343 -285.158502)
			(xy 285.40404 -285.116906) (xy 285.384749 -285.07163) (xy 285.372972 -285.023846) (xy 285.369012 -284.974792)
			(xy 285.030164 -284.974792) (xy 285.029669 -284.999399) (xy 285.021774 -285.047976) (xy 285.00619 -285.094657)
			(xy 284.983319 -285.138234) (xy 284.953754 -285.177578) (xy 284.918261 -285.21167) (xy 284.877758 -285.239626)
			(xy 284.833296 -285.260724) (xy 284.786025 -285.274416) (xy 284.73717 -285.280348) (xy 284.687995 -285.278367)
			(xy 284.639776 -285.268523) (xy 284.59376 -285.251071) (xy 284.551139 -285.226464) (xy 284.513018 -285.195339)
			(xy 284.480383 -285.158502) (xy 284.45408 -285.116906) (xy 284.434789 -285.07163) (xy 284.423012 -285.023846)
			(xy 284.419052 -284.974792) (xy 284.080204 -284.974792) (xy 284.079709 -284.999399) (xy 284.071814 -285.047976)
			(xy 284.05623 -285.094657) (xy 284.033359 -285.138234) (xy 284.003794 -285.177578) (xy 283.968301 -285.21167)
			(xy 283.927798 -285.239626) (xy 283.883336 -285.260724) (xy 283.836065 -285.274416) (xy 283.78721 -285.280348)
			(xy 283.738035 -285.278367) (xy 283.689816 -285.268523) (xy 283.6438 -285.251071) (xy 283.601179 -285.226464)
			(xy 283.563058 -285.195339) (xy 283.530423 -285.158502) (xy 283.50412 -285.116906) (xy 283.484829 -285.07163)
			(xy 283.473052 -285.023846) (xy 283.469092 -284.974792) (xy 283.130244 -284.974792) (xy 283.129749 -284.999399)
			(xy 283.121854 -285.047976) (xy 283.10627 -285.094657) (xy 283.083399 -285.138234) (xy 283.053834 -285.177578)
			(xy 283.018341 -285.21167) (xy 282.977838 -285.239626) (xy 282.933376 -285.260724) (xy 282.886105 -285.274416)
			(xy 282.83725 -285.280348) (xy 282.788075 -285.278367) (xy 282.739856 -285.268523) (xy 282.69384 -285.251071)
			(xy 282.651219 -285.226464) (xy 282.613098 -285.195339) (xy 282.580463 -285.158502) (xy 282.55416 -285.116906)
			(xy 282.534869 -285.07163) (xy 282.523092 -285.023846) (xy 282.519132 -284.974792) (xy 282.18003 -284.974792)
			(xy 282.179535 -284.999399) (xy 282.17164 -285.047976) (xy 282.156056 -285.094657) (xy 282.133185 -285.138234)
			(xy 282.10362 -285.177578) (xy 282.068127 -285.21167) (xy 282.027624 -285.239626) (xy 281.983162 -285.260724)
			(xy 281.935891 -285.274416) (xy 281.887036 -285.280348) (xy 281.837861 -285.278367) (xy 281.789642 -285.268523)
			(xy 281.743626 -285.251071) (xy 281.701005 -285.226464) (xy 281.662884 -285.195339) (xy 281.630249 -285.158502)
			(xy 281.603946 -285.116906) (xy 281.584655 -285.07163) (xy 281.572878 -285.023846) (xy 281.568918 -284.974792)
			(xy 281.23007 -284.974792) (xy 281.229575 -284.999399) (xy 281.22168 -285.047976) (xy 281.206096 -285.094657)
			(xy 281.183225 -285.138234) (xy 281.15366 -285.177578) (xy 281.118167 -285.21167) (xy 281.077664 -285.239626)
			(xy 281.033202 -285.260724) (xy 280.985931 -285.274416) (xy 280.937076 -285.280348) (xy 280.887901 -285.278367)
			(xy 280.839682 -285.268523) (xy 280.793666 -285.251071) (xy 280.751045 -285.226464) (xy 280.712924 -285.195339)
			(xy 280.680289 -285.158502) (xy 280.653986 -285.116906) (xy 280.634695 -285.07163) (xy 280.622918 -285.023846)
			(xy 280.618958 -284.974792) (xy 280.28011 -284.974792) (xy 280.279615 -284.999399) (xy 280.27172 -285.047976)
			(xy 280.256136 -285.094657) (xy 280.233265 -285.138234) (xy 280.2037 -285.177578) (xy 280.168207 -285.21167)
			(xy 280.127704 -285.239626) (xy 280.083242 -285.260724) (xy 280.035971 -285.274416) (xy 279.987116 -285.280348)
			(xy 279.937941 -285.278367) (xy 279.889722 -285.268523) (xy 279.843706 -285.251071) (xy 279.801085 -285.226464)
			(xy 279.762964 -285.195339) (xy 279.730329 -285.158502) (xy 279.704026 -285.116906) (xy 279.684735 -285.07163)
			(xy 279.672958 -285.023846) (xy 279.668998 -284.974792) (xy 279.33015 -284.974792) (xy 279.329655 -284.999399)
			(xy 279.32176 -285.047976) (xy 279.306176 -285.094657) (xy 279.283305 -285.138234) (xy 279.25374 -285.177578)
			(xy 279.218247 -285.21167) (xy 279.177744 -285.239626) (xy 279.133282 -285.260724) (xy 279.086011 -285.274416)
			(xy 279.037156 -285.280348) (xy 278.987981 -285.278367) (xy 278.939762 -285.268523) (xy 278.893746 -285.251071)
			(xy 278.851125 -285.226464) (xy 278.813004 -285.195339) (xy 278.780369 -285.158502) (xy 278.754066 -285.116906)
			(xy 278.734775 -285.07163) (xy 278.722998 -285.023846) (xy 278.719038 -284.974792) (xy 278.38019 -284.974792)
			(xy 278.379695 -284.999399) (xy 278.3718 -285.047976) (xy 278.356216 -285.094657) (xy 278.333345 -285.138234)
			(xy 278.30378 -285.177578) (xy 278.268287 -285.21167) (xy 278.227784 -285.239626) (xy 278.183322 -285.260724)
			(xy 278.136051 -285.274416) (xy 278.087196 -285.280348) (xy 278.038021 -285.278367) (xy 277.989802 -285.268523)
			(xy 277.943786 -285.251071) (xy 277.901165 -285.226464) (xy 277.863044 -285.195339) (xy 277.830409 -285.158502)
			(xy 277.804106 -285.116906) (xy 277.784815 -285.07163) (xy 277.773038 -285.023846) (xy 277.769078 -284.974792)
			(xy 277.43023 -284.974792) (xy 277.429735 -284.999399) (xy 277.42184 -285.047976) (xy 277.406256 -285.094657)
			(xy 277.383385 -285.138234) (xy 277.35382 -285.177578) (xy 277.318327 -285.21167) (xy 277.277824 -285.239626)
			(xy 277.233362 -285.260724) (xy 277.186091 -285.274416) (xy 277.137236 -285.280348) (xy 277.088061 -285.278367)
			(xy 277.039842 -285.268523) (xy 276.993826 -285.251071) (xy 276.951205 -285.226464) (xy 276.913084 -285.195339)
			(xy 276.880449 -285.158502) (xy 276.854146 -285.116906) (xy 276.834855 -285.07163) (xy 276.823078 -285.023846)
			(xy 276.819118 -284.974792) (xy 275.530056 -284.974792) (xy 275.529561 -284.999399) (xy 275.521666 -285.047976)
			(xy 275.506082 -285.094657) (xy 275.483211 -285.138234) (xy 275.453646 -285.177578) (xy 275.418153 -285.21167)
			(xy 275.37765 -285.239626) (xy 275.333188 -285.260724) (xy 275.285917 -285.274416) (xy 275.237062 -285.280348)
			(xy 275.187887 -285.278367) (xy 275.139668 -285.268523) (xy 275.093652 -285.251071) (xy 275.051031 -285.226464)
			(xy 275.01291 -285.195339) (xy 274.980275 -285.158502) (xy 274.953972 -285.116906) (xy 274.934681 -285.07163)
			(xy 274.922904 -285.023846) (xy 274.918944 -284.974792) (xy 272.680176 -284.974792) (xy 272.679681 -284.999399)
			(xy 272.671786 -285.047976) (xy 272.656202 -285.094657) (xy 272.633331 -285.138234) (xy 272.603766 -285.177578)
			(xy 272.568273 -285.21167) (xy 272.52777 -285.239626) (xy 272.483308 -285.260724) (xy 272.436037 -285.274416)
			(xy 272.387182 -285.280348) (xy 272.338007 -285.278367) (xy 272.289788 -285.268523) (xy 272.243772 -285.251071)
			(xy 272.201151 -285.226464) (xy 272.16303 -285.195339) (xy 272.130395 -285.158502) (xy 272.104092 -285.116906)
			(xy 272.084801 -285.07163) (xy 272.073024 -285.023846) (xy 272.069064 -284.974792) (xy 271.730216 -284.974792)
			(xy 271.729721 -284.999399) (xy 271.721826 -285.047976) (xy 271.706242 -285.094657) (xy 271.683371 -285.138234)
			(xy 271.653806 -285.177578) (xy 271.618313 -285.21167) (xy 271.57781 -285.239626) (xy 271.533348 -285.260724)
			(xy 271.486077 -285.274416) (xy 271.437222 -285.280348) (xy 271.388047 -285.278367) (xy 271.339828 -285.268523)
			(xy 271.293812 -285.251071) (xy 271.251191 -285.226464) (xy 271.21307 -285.195339) (xy 271.180435 -285.158502)
			(xy 271.154132 -285.116906) (xy 271.134841 -285.07163) (xy 271.123064 -285.023846) (xy 271.119104 -284.974792)
			(xy 270.780256 -284.974792) (xy 270.779761 -284.999399) (xy 270.771866 -285.047976) (xy 270.756282 -285.094657)
			(xy 270.733411 -285.138234) (xy 270.703846 -285.177578) (xy 270.668353 -285.21167) (xy 270.62785 -285.239626)
			(xy 270.583388 -285.260724) (xy 270.536117 -285.274416) (xy 270.487262 -285.280348) (xy 270.438087 -285.278367)
			(xy 270.389868 -285.268523) (xy 270.343852 -285.251071) (xy 270.301231 -285.226464) (xy 270.26311 -285.195339)
			(xy 270.230475 -285.158502) (xy 270.204172 -285.116906) (xy 270.184881 -285.07163) (xy 270.173104 -285.023846)
			(xy 270.169144 -284.974792) (xy 269.830042 -284.974792) (xy 269.829547 -284.999399) (xy 269.821652 -285.047976)
			(xy 269.806068 -285.094657) (xy 269.783197 -285.138234) (xy 269.753632 -285.177578) (xy 269.718139 -285.21167)
			(xy 269.677636 -285.239626) (xy 269.633174 -285.260724) (xy 269.585903 -285.274416) (xy 269.537048 -285.280348)
			(xy 269.487873 -285.278367) (xy 269.439654 -285.268523) (xy 269.393638 -285.251071) (xy 269.351017 -285.226464)
			(xy 269.312896 -285.195339) (xy 269.280261 -285.158502) (xy 269.253958 -285.116906) (xy 269.234667 -285.07163)
			(xy 269.22289 -285.023846) (xy 269.21893 -284.974792) (xy 268.880082 -284.974792) (xy 268.879587 -284.999399)
			(xy 268.871692 -285.047976) (xy 268.856108 -285.094657) (xy 268.833237 -285.138234) (xy 268.803672 -285.177578)
			(xy 268.768179 -285.21167) (xy 268.727676 -285.239626) (xy 268.683214 -285.260724) (xy 268.635943 -285.274416)
			(xy 268.587088 -285.280348) (xy 268.537913 -285.278367) (xy 268.489694 -285.268523) (xy 268.443678 -285.251071)
			(xy 268.401057 -285.226464) (xy 268.362936 -285.195339) (xy 268.330301 -285.158502) (xy 268.303998 -285.116906)
			(xy 268.284707 -285.07163) (xy 268.27293 -285.023846) (xy 268.26897 -284.974792) (xy 260.255605 -284.974792)
			(xy 260.259575 -285.00177) (xy 260.260084 -285.029656) (xy 260.259575 -285.057542) (xy 260.251455 -285.112718)
			(xy 260.235387 -285.166125) (xy 260.211715 -285.216622) (xy 260.180942 -285.263135) (xy 260.143725 -285.304672)
			(xy 260.100857 -285.340347) (xy 260.053251 -285.369401) (xy 260.001922 -285.391213) (xy 259.947965 -285.405319)
			(xy 259.892528 -285.411419) (xy 259.836794 -285.409382) (xy 259.781951 -285.399252) (xy 259.729167 -285.381245)
			(xy 259.679567 -285.355744) (xy 259.634209 -285.323293) (xy 259.59406 -285.284584) (xy 259.559974 -285.240441)
			(xy 259.532678 -285.191806) (xy 259.512755 -285.139715) (xy 259.500629 -285.085278) (xy 259.496558 -285.029656)
			(xy 258.774946 -285.029656) (xy 258.774437 -285.057542) (xy 258.766317 -285.112718) (xy 258.750249 -285.166125)
			(xy 258.726577 -285.216622) (xy 258.695804 -285.263135) (xy 258.658587 -285.304672) (xy 258.615719 -285.340347)
			(xy 258.568113 -285.369401) (xy 258.516784 -285.391213) (xy 258.462827 -285.405319) (xy 258.40739 -285.411419)
			(xy 258.351656 -285.409382) (xy 258.296813 -285.399252) (xy 258.244029 -285.381245) (xy 258.194429 -285.355744)
			(xy 258.149071 -285.323293) (xy 258.108922 -285.284584) (xy 258.074836 -285.240441) (xy 258.04754 -285.191806)
			(xy 258.027617 -285.139715) (xy 258.015491 -285.085278) (xy 258.01142 -285.029656) (xy 214.119206 -285.029656)
			(xy 214.017352 -285.13151) (xy 214.010658 -285.138953) (xy 214.003061 -285.157451) (xy 214.00308 -285.177448)
			(xy 214.00643 -285.186882) (xy 214.012526 -285.201106) (xy 214.037672 -285.218124) (xy 224.802192 -285.218124)
			(xy 224.813303 -285.21757) (xy 224.833465 -285.208223) (xy 224.841054 -285.20009) (xy 224.859262 -285.179237)
			(xy 224.900671 -285.142495) (xy 224.946958 -285.112128) (xy 224.997149 -285.088773) (xy 225.05019 -285.072923)
			(xy 225.104967 -285.064909) (xy 225.132646 -285.064454) (xy 225.161386 -285.064971) (xy 225.218217 -285.073588)
			(xy 225.273112 -285.090634) (xy 225.324828 -285.115723) (xy 225.372193 -285.148288) (xy 225.393504 -285.167578)
			(xy 225.400616 -285.174182) (xy 225.418142 -285.181294) (xy 225.50755 -285.181294) (xy 225.525076 -285.174182)
			(xy 225.532188 -285.167578) (xy 225.553515 -285.148308) (xy 225.600878 -285.115743) (xy 225.652589 -285.090652)
			(xy 225.70748 -285.073602) (xy 225.764307 -285.06498) (xy 225.821785 -285.06498) (xy 225.878612 -285.073602)
			(xy 225.933503 -285.090652) (xy 225.985214 -285.115743) (xy 226.032577 -285.148308) (xy 226.053904 -285.167578)
			(xy 226.061016 -285.174182) (xy 226.078542 -285.181294) (xy 226.16795 -285.181294) (xy 226.185476 -285.174182)
			(xy 226.192588 -285.167578) (xy 226.213915 -285.148306) (xy 226.261277 -285.115738) (xy 226.312988 -285.090642)
			(xy 226.367879 -285.073587) (xy 226.424706 -285.064957) (xy 226.453446 -285.064454) (xy 226.481123 -285.064952)
			(xy 226.535893 -285.072963) (xy 226.588929 -285.088811) (xy 226.639116 -285.112162) (xy 226.685398 -285.142526)
			(xy 226.726803 -285.179263) (xy 226.745038 -285.20009) (xy 226.752404 -285.208726) (xy 226.77247 -285.218124)
			(xy 226.820222 -285.218124) (xy 226.840288 -285.208726) (xy 226.847654 -285.20009) (xy 226.865864 -285.17924)
			(xy 226.907274 -285.142505) (xy 226.953562 -285.112145) (xy 227.003753 -285.088798) (xy 227.056794 -285.072955)
			(xy 227.111568 -285.06495) (xy 227.166924 -285.06495) (xy 227.221698 -285.072955) (xy 227.274739 -285.088798)
			(xy 227.32493 -285.112145) (xy 227.371218 -285.142505) (xy 227.412628 -285.17924) (xy 227.430838 -285.20009)
			(xy 227.438425 -285.208232) (xy 227.458585 -285.217596) (xy 227.4697 -285.218124) (xy 229.07498 -285.218124)
			(xy 229.086083 -285.217552) (xy 229.106217 -285.208184) (xy 229.113842 -285.20009) (xy 229.132052 -285.179241)
			(xy 229.173463 -285.142509) (xy 229.219751 -285.112152) (xy 229.269943 -285.088809) (xy 229.322983 -285.072971)
			(xy 229.377757 -285.06497) (xy 229.405434 -285.064454) (xy 229.434172 -285.064978) (xy 229.490996 -285.073606)
			(xy 229.545883 -285.090662) (xy 229.597589 -285.115759) (xy 229.644945 -285.14833) (xy 229.666292 -285.167578)
			(xy 229.673404 -285.174182) (xy 229.69093 -285.181294) (xy 229.780338 -285.181294) (xy 229.797864 -285.174182)
			(xy 229.804976 -285.167578) (xy 229.826303 -285.148308) (xy 229.873666 -285.115743) (xy 229.925377 -285.090652)
			(xy 229.980268 -285.073602) (xy 230.037095 -285.06498) (xy 230.094573 -285.06498) (xy 230.1514 -285.073602)
			(xy 230.206291 -285.090652) (xy 230.258002 -285.115743) (xy 230.305365 -285.148308) (xy 230.326692 -285.167578)
			(xy 230.333804 -285.174182) (xy 230.35133 -285.181294) (xy 230.440738 -285.181294) (xy 230.458264 -285.174182)
			(xy 230.465376 -285.167578) (xy 230.486703 -285.148305) (xy 230.534064 -285.115736) (xy 230.585776 -285.090638)
			(xy 230.640666 -285.073581) (xy 230.697494 -285.06495) (xy 230.726234 -285.064454) (xy 230.753911 -285.064951)
			(xy 230.808682 -285.072961) (xy 230.86172 -285.088808) (xy 230.911907 -285.112158) (xy 230.958191 -285.142521)
			(xy 230.999597 -285.179257) (xy 231.017826 -285.20009) (xy 231.025192 -285.208726) (xy 231.045258 -285.218124)
			(xy 231.09301 -285.218124) (xy 231.113076 -285.208726) (xy 231.120442 -285.20009) (xy 231.138652 -285.179241)
			(xy 231.180063 -285.142509) (xy 231.226351 -285.112152) (xy 231.276543 -285.088809) (xy 231.329583 -285.072971)
			(xy 231.384357 -285.06497) (xy 231.412034 -285.064454) (xy 231.439285 -285.064942) (xy 231.493231 -285.072702)
			(xy 231.545524 -285.08806) (xy 231.595099 -285.110703) (xy 231.640948 -285.140169) (xy 231.682137 -285.17586)
			(xy 231.717828 -285.217049) (xy 231.747296 -285.262898) (xy 231.769939 -285.312473) (xy 231.785297 -285.364765)
			(xy 231.793058 -285.418711) (xy 231.793542 -285.445962) (xy 231.793334 -285.462496) (xy 231.79238 -285.473256)
			(xy 241.001717 -285.473256) (xy 241.001717 -285.418744) (xy 241.009475 -285.364788) (xy 241.024833 -285.312484)
			(xy 241.047478 -285.262899) (xy 241.076949 -285.217041) (xy 241.112647 -285.175844) (xy 241.153844 -285.140147)
			(xy 241.199702 -285.110676) (xy 241.249288 -285.088031) (xy 241.301591 -285.072674) (xy 241.355548 -285.064917)
			(xy 241.382804 -285.064454) (xy 241.411542 -285.064988) (xy 241.468369 -285.07361) (xy 241.523259 -285.090658)
			(xy 241.574971 -285.115747) (xy 241.622334 -285.148309) (xy 241.643662 -285.167578) (xy 241.650774 -285.174182)
			(xy 241.6683 -285.181294) (xy 241.757708 -285.181294) (xy 241.775234 -285.174182) (xy 241.782346 -285.167578)
			(xy 241.803673 -285.148308) (xy 241.851036 -285.115743) (xy 241.902747 -285.090652) (xy 241.957638 -285.073602)
			(xy 242.014465 -285.06498) (xy 242.071943 -285.06498) (xy 242.12877 -285.073602) (xy 242.183661 -285.090652)
			(xy 242.235372 -285.115743) (xy 242.282735 -285.148308) (xy 242.304062 -285.167578) (xy 242.311174 -285.174182)
			(xy 242.3287 -285.181294) (xy 242.418108 -285.181294) (xy 242.435634 -285.174182) (xy 242.442746 -285.167578)
			(xy 242.464077 -285.148312) (xy 242.511437 -285.115744) (xy 242.563148 -285.090649) (xy 242.618038 -285.073598)
			(xy 242.674865 -285.064975) (xy 242.703604 -285.064454) (xy 242.733728 -285.065021) (xy 242.793224 -285.074503)
			(xy 242.850492 -285.093214) (xy 242.904109 -285.120691) (xy 242.952743 -285.156251) (xy 242.974368 -285.17723)
			(xy 242.98148 -285.184596) (xy 243.000276 -285.192216) (xy 243.092732 -285.192216) (xy 243.111528 -285.184596)
			(xy 243.11864 -285.17723) (xy 243.140273 -285.156259) (xy 243.188899 -285.120688) (xy 243.242513 -285.093206)
			(xy 243.299782 -285.074496) (xy 243.35928 -285.065023) (xy 243.389404 -285.064454) (xy 243.416652 -285.065016)
			(xy 243.470594 -285.072773) (xy 243.522883 -285.088127) (xy 243.572455 -285.110766) (xy 243.6183 -285.140229)
			(xy 243.659486 -285.175917) (xy 243.695173 -285.217103) (xy 243.724636 -285.262949) (xy 243.747275 -285.312521)
			(xy 243.762628 -285.36481) (xy 243.770384 -285.418752) (xy 243.770384 -285.473248) (xy 243.770383 -285.473254)
			(xy 245.27454 -285.473254) (xy 245.27454 -285.418746) (xy 245.282297 -285.364794) (xy 245.297653 -285.312495)
			(xy 245.320296 -285.262913) (xy 245.349764 -285.217058) (xy 245.385459 -285.175864) (xy 245.426652 -285.140169)
			(xy 245.472506 -285.1107) (xy 245.522087 -285.088056) (xy 245.574386 -285.072699) (xy 245.628338 -285.06494)
			(xy 245.655592 -285.064454) (xy 245.68433 -285.064995) (xy 245.741156 -285.073615) (xy 245.796046 -285.090662)
			(xy 245.847758 -285.115749) (xy 245.895122 -285.14831) (xy 245.91645 -285.167578) (xy 245.923562 -285.174182)
			(xy 245.941088 -285.181294) (xy 246.030496 -285.181294) (xy 246.048022 -285.174182) (xy 246.055134 -285.167578)
			(xy 246.076461 -285.148308) (xy 246.123824 -285.115743) (xy 246.175535 -285.090652) (xy 246.230426 -285.073602)
			(xy 246.287253 -285.06498) (xy 246.344731 -285.06498) (xy 246.401558 -285.073602) (xy 246.456449 -285.090652)
			(xy 246.50816 -285.115743) (xy 246.555523 -285.148308) (xy 246.57685 -285.167578) (xy 246.583962 -285.174182)
			(xy 246.601488 -285.181294) (xy 246.690896 -285.181294) (xy 246.708422 -285.174182) (xy 246.715534 -285.167578)
			(xy 246.73687 -285.148318) (xy 246.784229 -285.115748) (xy 246.835938 -285.090653) (xy 246.890827 -285.0736)
			(xy 246.947653 -285.064976) (xy 246.976392 -285.064454) (xy 247.006515 -285.065029) (xy 247.066012 -285.074508)
			(xy 247.123279 -285.093218) (xy 247.176897 -285.120693) (xy 247.225531 -285.156251) (xy 247.247156 -285.17723)
			(xy 247.254268 -285.184596) (xy 247.273064 -285.192216) (xy 247.36552 -285.192216) (xy 247.384316 -285.184596)
			(xy 247.391428 -285.17723) (xy 247.413066 -285.156264) (xy 247.461691 -285.120693) (xy 247.515304 -285.09321)
			(xy 247.572571 -285.074498) (xy 247.632069 -285.065024) (xy 247.662192 -285.064454) (xy 247.689443 -285.064993)
			(xy 247.743389 -285.072748) (xy 247.795683 -285.088102) (xy 247.845259 -285.110742) (xy 247.891108 -285.140206)
			(xy 247.932298 -285.175897) (xy 247.967989 -285.217085) (xy 247.997455 -285.262934) (xy 248.020095 -285.31251)
			(xy 248.03545 -285.364803) (xy 248.043207 -285.418749) (xy 248.043207 -285.473251) (xy 248.03545 -285.527197)
			(xy 248.020095 -285.57949) (xy 247.997455 -285.629066) (xy 247.967989 -285.674915) (xy 247.932298 -285.716103)
			(xy 247.891108 -285.751794) (xy 247.845259 -285.781258) (xy 247.795683 -285.803898) (xy 247.743389 -285.819252)
			(xy 247.689443 -285.827007) (xy 247.662192 -285.82747) (xy 247.632069 -285.826899) (xy 247.572573 -285.817417)
			(xy 247.515305 -285.798706) (xy 247.461688 -285.77123) (xy 247.413053 -285.735672) (xy 247.391428 -285.714694)
			(xy 247.384316 -285.707328) (xy 247.36552 -285.699708) (xy 247.273064 -285.699708) (xy 247.254268 -285.707328)
			(xy 247.247156 -285.714694) (xy 247.225529 -285.735671) (xy 247.176901 -285.77124) (xy 247.123285 -285.798721)
			(xy 247.066015 -285.81743) (xy 247.006516 -285.826901) (xy 246.976392 -285.82747) (xy 246.947654 -285.826932)
			(xy 246.890828 -285.81831) (xy 246.835938 -285.801262) (xy 246.784226 -285.776175) (xy 246.736862 -285.743614)
			(xy 246.715534 -285.724346) (xy 246.708422 -285.717742) (xy 246.690896 -285.71063) (xy 246.601488 -285.71063)
			(xy 246.583962 -285.717742) (xy 246.57685 -285.724346) (xy 246.555523 -285.743616) (xy 246.50816 -285.776181)
			(xy 246.456449 -285.801272) (xy 246.401558 -285.818322) (xy 246.344731 -285.826944) (xy 246.287253 -285.826944)
			(xy 246.230426 -285.818322) (xy 246.175535 -285.801272) (xy 246.123824 -285.776181) (xy 246.076461 -285.743616)
			(xy 246.055134 -285.724346) (xy 246.048022 -285.717742) (xy 246.030496 -285.71063) (xy 245.941088 -285.71063)
			(xy 245.923562 -285.717742) (xy 245.91645 -285.724346) (xy 245.895124 -285.743618) (xy 245.847762 -285.776185)
			(xy 245.79605 -285.801277) (xy 245.741159 -285.818327) (xy 245.684331 -285.82695) (xy 245.655592 -285.82747)
			(xy 245.628338 -285.82706) (xy 245.574386 -285.819301) (xy 245.522087 -285.803944) (xy 245.472506 -285.7813)
			(xy 245.426652 -285.751831) (xy 245.385459 -285.716136) (xy 245.349764 -285.674942) (xy 245.320296 -285.629087)
			(xy 245.297653 -285.579505) (xy 245.282297 -285.527206) (xy 245.27454 -285.473254) (xy 243.770383 -285.473254)
			(xy 243.762628 -285.52719) (xy 243.747275 -285.579479) (xy 243.724636 -285.629051) (xy 243.695173 -285.674897)
			(xy 243.659486 -285.716083) (xy 243.6183 -285.751771) (xy 243.572455 -285.781234) (xy 243.522883 -285.803873)
			(xy 243.470594 -285.819227) (xy 243.416652 -285.826984) (xy 243.389404 -285.82747) (xy 243.359281 -285.826891)
			(xy 243.299785 -285.817411) (xy 243.242518 -285.798702) (xy 243.1889 -285.771228) (xy 243.140265 -285.735672)
			(xy 243.11864 -285.714694) (xy 243.111528 -285.707328) (xy 243.092732 -285.699708) (xy 243.000276 -285.699708)
			(xy 242.98148 -285.707328) (xy 242.974368 -285.714694) (xy 242.952735 -285.735666) (xy 242.904109 -285.771235)
			(xy 242.850494 -285.798717) (xy 242.793226 -285.817427) (xy 242.733728 -285.826901) (xy 242.703604 -285.82747)
			(xy 242.674866 -285.826925) (xy 242.618041 -285.818305) (xy 242.563151 -285.801259) (xy 242.511439 -285.776172)
			(xy 242.464074 -285.743613) (xy 242.442746 -285.724346) (xy 242.435634 -285.717742) (xy 242.418108 -285.71063)
			(xy 242.3287 -285.71063) (xy 242.311174 -285.717742) (xy 242.304062 -285.724346) (xy 242.282735 -285.743616)
			(xy 242.235372 -285.776181) (xy 242.183661 -285.801272) (xy 242.12877 -285.818322) (xy 242.071943 -285.826944)
			(xy 242.014465 -285.826944) (xy 241.957638 -285.818322) (xy 241.902747 -285.801272) (xy 241.851036 -285.776181)
			(xy 241.803673 -285.743616) (xy 241.782346 -285.724346) (xy 241.775234 -285.717742) (xy 241.757708 -285.71063)
			(xy 241.6683 -285.71063) (xy 241.650774 -285.717742) (xy 241.643662 -285.724346) (xy 241.622331 -285.743612)
			(xy 241.57497 -285.77618) (xy 241.52326 -285.801273) (xy 241.46837 -285.818325) (xy 241.411543 -285.826949)
			(xy 241.382804 -285.82747) (xy 241.355548 -285.827083) (xy 241.301591 -285.819326) (xy 241.249288 -285.803969)
			(xy 241.199702 -285.781324) (xy 241.153844 -285.751853) (xy 241.112647 -285.716156) (xy 241.076949 -285.674959)
			(xy 241.047478 -285.629101) (xy 241.024833 -285.579516) (xy 241.009475 -285.527212) (xy 241.001717 -285.473256)
			(xy 231.79238 -285.473256) (xy 231.790412 -285.495436) (xy 231.7877 -285.511748) (xy 231.785668 -285.52394)
			(xy 231.793034 -285.547562) (xy 231.995726 -285.750254) (xy 232.028238 -285.755334) (xy 232.043224 -285.747714)
			(xy 232.070303 -285.7345) (xy 232.127585 -285.71582) (xy 232.187089 -285.706356) (xy 232.217214 -285.705804)
			(xy 232.24419 -285.706271) (xy 232.297604 -285.713872) (xy 232.349415 -285.728921) (xy 232.39859 -285.751118)
			(xy 232.444148 -285.78002) (xy 232.485181 -285.815051) (xy 232.52087 -285.855512) (xy 232.550505 -285.900596)
			(xy 232.561882 -285.924752) (xy 268.26897 -285.924752) (xy 268.27293 -285.875698) (xy 268.284707 -285.827914)
			(xy 268.303998 -285.782638) (xy 268.330301 -285.741042) (xy 268.362936 -285.704205) (xy 268.401057 -285.67308)
			(xy 268.443678 -285.648473) (xy 268.489694 -285.631021) (xy 268.537913 -285.621177) (xy 268.587088 -285.619196)
			(xy 268.635943 -285.625128) (xy 268.683214 -285.63882) (xy 268.727676 -285.659918) (xy 268.768179 -285.687874)
			(xy 268.803672 -285.721966) (xy 268.833237 -285.76131) (xy 268.856108 -285.804887) (xy 268.871692 -285.851568)
			(xy 268.879587 -285.900145) (xy 268.880082 -285.924752) (xy 269.21893 -285.924752) (xy 269.22289 -285.875698)
			(xy 269.234667 -285.827914) (xy 269.253958 -285.782638) (xy 269.280261 -285.741042) (xy 269.312896 -285.704205)
			(xy 269.351017 -285.67308) (xy 269.393638 -285.648473) (xy 269.439654 -285.631021) (xy 269.487873 -285.621177)
			(xy 269.537048 -285.619196) (xy 269.585903 -285.625128) (xy 269.633174 -285.63882) (xy 269.677636 -285.659918)
			(xy 269.718139 -285.687874) (xy 269.753632 -285.721966) (xy 269.783197 -285.76131) (xy 269.806068 -285.804887)
			(xy 269.821652 -285.851568) (xy 269.829547 -285.900145) (xy 269.830042 -285.924752) (xy 270.169144 -285.924752)
			(xy 270.173104 -285.875698) (xy 270.184881 -285.827914) (xy 270.204172 -285.782638) (xy 270.230475 -285.741042)
			(xy 270.26311 -285.704205) (xy 270.301231 -285.67308) (xy 270.343852 -285.648473) (xy 270.389868 -285.631021)
			(xy 270.438087 -285.621177) (xy 270.487262 -285.619196) (xy 270.536117 -285.625128) (xy 270.583388 -285.63882)
			(xy 270.62785 -285.659918) (xy 270.668353 -285.687874) (xy 270.703846 -285.721966) (xy 270.733411 -285.76131)
			(xy 270.756282 -285.804887) (xy 270.771866 -285.851568) (xy 270.779761 -285.900145) (xy 270.780256 -285.924752)
			(xy 271.119104 -285.924752) (xy 271.123064 -285.875698) (xy 271.134841 -285.827914) (xy 271.154132 -285.782638)
			(xy 271.180435 -285.741042) (xy 271.21307 -285.704205) (xy 271.251191 -285.67308) (xy 271.293812 -285.648473)
			(xy 271.339828 -285.631021) (xy 271.388047 -285.621177) (xy 271.437222 -285.619196) (xy 271.486077 -285.625128)
			(xy 271.533348 -285.63882) (xy 271.57781 -285.659918) (xy 271.618313 -285.687874) (xy 271.653806 -285.721966)
			(xy 271.683371 -285.76131) (xy 271.706242 -285.804887) (xy 271.721826 -285.851568) (xy 271.729721 -285.900145)
			(xy 271.730216 -285.924752) (xy 272.069064 -285.924752) (xy 272.073024 -285.875698) (xy 272.084801 -285.827914)
			(xy 272.104092 -285.782638) (xy 272.130395 -285.741042) (xy 272.16303 -285.704205) (xy 272.201151 -285.67308)
			(xy 272.243772 -285.648473) (xy 272.289788 -285.631021) (xy 272.338007 -285.621177) (xy 272.387182 -285.619196)
			(xy 272.436037 -285.625128) (xy 272.483308 -285.63882) (xy 272.52777 -285.659918) (xy 272.568273 -285.687874)
			(xy 272.603766 -285.721966) (xy 272.633331 -285.76131) (xy 272.656202 -285.804887) (xy 272.671786 -285.851568)
			(xy 272.679681 -285.900145) (xy 272.680176 -285.924752) (xy 273.019024 -285.924752) (xy 273.022984 -285.875698)
			(xy 273.034761 -285.827914) (xy 273.054052 -285.782638) (xy 273.080355 -285.741042) (xy 273.11299 -285.704205)
			(xy 273.151111 -285.67308) (xy 273.193732 -285.648473) (xy 273.239748 -285.631021) (xy 273.287967 -285.621177)
			(xy 273.337142 -285.619196) (xy 273.385997 -285.625128) (xy 273.433268 -285.63882) (xy 273.47773 -285.659918)
			(xy 273.518233 -285.687874) (xy 273.553726 -285.721966) (xy 273.583291 -285.76131) (xy 273.606162 -285.804887)
			(xy 273.621746 -285.851568) (xy 273.629641 -285.900145) (xy 273.630136 -285.924752) (xy 276.819118 -285.924752)
			(xy 276.823078 -285.875698) (xy 276.834855 -285.827914) (xy 276.854146 -285.782638) (xy 276.880449 -285.741042)
			(xy 276.913084 -285.704205) (xy 276.951205 -285.67308) (xy 276.993826 -285.648473) (xy 277.039842 -285.631021)
			(xy 277.088061 -285.621177) (xy 277.137236 -285.619196) (xy 277.186091 -285.625128) (xy 277.233362 -285.63882)
			(xy 277.277824 -285.659918) (xy 277.318327 -285.687874) (xy 277.35382 -285.721966) (xy 277.383385 -285.76131)
			(xy 277.406256 -285.804887) (xy 277.42184 -285.851568) (xy 277.429735 -285.900145) (xy 277.43023 -285.924752)
			(xy 277.769078 -285.924752) (xy 277.773038 -285.875698) (xy 277.784815 -285.827914) (xy 277.804106 -285.782638)
			(xy 277.830409 -285.741042) (xy 277.863044 -285.704205) (xy 277.901165 -285.67308) (xy 277.943786 -285.648473)
			(xy 277.989802 -285.631021) (xy 278.038021 -285.621177) (xy 278.087196 -285.619196) (xy 278.136051 -285.625128)
			(xy 278.183322 -285.63882) (xy 278.227784 -285.659918) (xy 278.268287 -285.687874) (xy 278.30378 -285.721966)
			(xy 278.333345 -285.76131) (xy 278.356216 -285.804887) (xy 278.3718 -285.851568) (xy 278.379695 -285.900145)
			(xy 278.38019 -285.924752) (xy 278.379695 -285.949359) (xy 278.3718 -285.997936) (xy 278.356216 -286.044617)
			(xy 278.333345 -286.088194) (xy 278.30378 -286.127538) (xy 278.268287 -286.16163) (xy 278.227784 -286.189586)
			(xy 278.183322 -286.210684) (xy 278.136051 -286.224376) (xy 278.087196 -286.230308) (xy 278.038021 -286.228327)
			(xy 277.989802 -286.218483) (xy 277.943786 -286.201031) (xy 277.901165 -286.176424) (xy 277.863044 -286.145299)
			(xy 277.830409 -286.108462) (xy 277.804106 -286.066866) (xy 277.784815 -286.02159) (xy 277.773038 -285.973806)
			(xy 277.769078 -285.924752) (xy 277.43023 -285.924752) (xy 277.429735 -285.949359) (xy 277.42184 -285.997936)
			(xy 277.406256 -286.044617) (xy 277.383385 -286.088194) (xy 277.35382 -286.127538) (xy 277.318327 -286.16163)
			(xy 277.277824 -286.189586) (xy 277.233362 -286.210684) (xy 277.186091 -286.224376) (xy 277.137236 -286.230308)
			(xy 277.088061 -286.228327) (xy 277.039842 -286.218483) (xy 276.993826 -286.201031) (xy 276.951205 -286.176424)
			(xy 276.913084 -286.145299) (xy 276.880449 -286.108462) (xy 276.854146 -286.066866) (xy 276.834855 -286.02159)
			(xy 276.823078 -285.973806) (xy 276.819118 -285.924752) (xy 273.630136 -285.924752) (xy 273.629641 -285.949359)
			(xy 273.621746 -285.997936) (xy 273.606162 -286.044617) (xy 273.583291 -286.088194) (xy 273.553726 -286.127538)
			(xy 273.518233 -286.16163) (xy 273.47773 -286.189586) (xy 273.433268 -286.210684) (xy 273.385997 -286.224376)
			(xy 273.337142 -286.230308) (xy 273.287967 -286.228327) (xy 273.239748 -286.218483) (xy 273.193732 -286.201031)
			(xy 273.151111 -286.176424) (xy 273.11299 -286.145299) (xy 273.080355 -286.108462) (xy 273.054052 -286.066866)
			(xy 273.034761 -286.02159) (xy 273.022984 -285.973806) (xy 273.019024 -285.924752) (xy 272.680176 -285.924752)
			(xy 272.679681 -285.949359) (xy 272.671786 -285.997936) (xy 272.656202 -286.044617) (xy 272.633331 -286.088194)
			(xy 272.603766 -286.127538) (xy 272.568273 -286.16163) (xy 272.52777 -286.189586) (xy 272.483308 -286.210684)
			(xy 272.436037 -286.224376) (xy 272.387182 -286.230308) (xy 272.338007 -286.228327) (xy 272.289788 -286.218483)
			(xy 272.243772 -286.201031) (xy 272.201151 -286.176424) (xy 272.16303 -286.145299) (xy 272.130395 -286.108462)
			(xy 272.104092 -286.066866) (xy 272.084801 -286.02159) (xy 272.073024 -285.973806) (xy 272.069064 -285.924752)
			(xy 271.730216 -285.924752) (xy 271.729721 -285.949359) (xy 271.721826 -285.997936) (xy 271.706242 -286.044617)
			(xy 271.683371 -286.088194) (xy 271.653806 -286.127538) (xy 271.618313 -286.16163) (xy 271.57781 -286.189586)
			(xy 271.533348 -286.210684) (xy 271.486077 -286.224376) (xy 271.437222 -286.230308) (xy 271.388047 -286.228327)
			(xy 271.339828 -286.218483) (xy 271.293812 -286.201031) (xy 271.251191 -286.176424) (xy 271.21307 -286.145299)
			(xy 271.180435 -286.108462) (xy 271.154132 -286.066866) (xy 271.134841 -286.02159) (xy 271.123064 -285.973806)
			(xy 271.119104 -285.924752) (xy 270.780256 -285.924752) (xy 270.779761 -285.949359) (xy 270.771866 -285.997936)
			(xy 270.756282 -286.044617) (xy 270.733411 -286.088194) (xy 270.703846 -286.127538) (xy 270.668353 -286.16163)
			(xy 270.62785 -286.189586) (xy 270.583388 -286.210684) (xy 270.536117 -286.224376) (xy 270.487262 -286.230308)
			(xy 270.438087 -286.228327) (xy 270.389868 -286.218483) (xy 270.343852 -286.201031) (xy 270.301231 -286.176424)
			(xy 270.26311 -286.145299) (xy 270.230475 -286.108462) (xy 270.204172 -286.066866) (xy 270.184881 -286.02159)
			(xy 270.173104 -285.973806) (xy 270.169144 -285.924752) (xy 269.830042 -285.924752) (xy 269.829547 -285.949359)
			(xy 269.821652 -285.997936) (xy 269.806068 -286.044617) (xy 269.783197 -286.088194) (xy 269.753632 -286.127538)
			(xy 269.718139 -286.16163) (xy 269.677636 -286.189586) (xy 269.633174 -286.210684) (xy 269.585903 -286.224376)
			(xy 269.537048 -286.230308) (xy 269.487873 -286.228327) (xy 269.439654 -286.218483) (xy 269.393638 -286.201031)
			(xy 269.351017 -286.176424) (xy 269.312896 -286.145299) (xy 269.280261 -286.108462) (xy 269.253958 -286.066866)
			(xy 269.234667 -286.02159) (xy 269.22289 -285.973806) (xy 269.21893 -285.924752) (xy 268.880082 -285.924752)
			(xy 268.879587 -285.949359) (xy 268.871692 -285.997936) (xy 268.856108 -286.044617) (xy 268.833237 -286.088194)
			(xy 268.803672 -286.127538) (xy 268.768179 -286.16163) (xy 268.727676 -286.189586) (xy 268.683214 -286.210684)
			(xy 268.635943 -286.224376) (xy 268.587088 -286.230308) (xy 268.537913 -286.228327) (xy 268.489694 -286.218483)
			(xy 268.443678 -286.201031) (xy 268.401057 -286.176424) (xy 268.362936 -286.145299) (xy 268.330301 -286.108462)
			(xy 268.303998 -286.066866) (xy 268.284707 -286.02159) (xy 268.27293 -285.973806) (xy 268.26897 -285.924752)
			(xy 232.561882 -285.924752) (xy 232.573494 -285.949406) (xy 232.589379 -286.000966) (xy 232.597843 -286.054251)
			(xy 232.598722 -286.081216) (xy 232.598722 -286.091376) (xy 232.606596 -286.109664) (xy 232.664508 -286.166814)
			(xy 232.671939 -286.173443) (xy 232.690373 -286.180917) (xy 232.700322 -286.181292) (xy 249.339608 -286.181292)
			(xy 249.349677 -286.180867) (xy 249.368279 -286.17315) (xy 249.375676 -286.166306) (xy 249.512328 -286.029654)
			(xy 249.519726 -286.022806) (xy 249.538324 -286.015074) (xy 249.548396 -286.014668) (xy 258.166616 -286.014668)
			(xy 258.173655 -286.014444) (xy 258.18719 -286.010575) (xy 258.193286 -286.007048) (xy 258.215948 -285.993599)
			(xy 258.264187 -285.972392) (xy 258.314891 -285.958041) (xy 258.36709 -285.95082) (xy 258.393438 -285.950406)
			(xy 258.419782 -285.950856) (xy 258.471969 -285.958109) (xy 258.522667 -285.972457) (xy 258.570914 -285.993631)
			(xy 258.59359 -286.007048) (xy 258.599696 -286.010549) (xy 258.613226 -286.014411) (xy 258.62026 -286.014668)
			(xy 259.642102 -286.014668) (xy 259.649142 -286.014446) (xy 259.662679 -286.01058) (xy 259.668772 -286.007048)
			(xy 259.691433 -285.993599) (xy 259.739673 -285.97239) (xy 259.790377 -285.958037) (xy 259.842576 -285.950813)
			(xy 259.868924 -285.950406) (xy 259.895268 -285.950855) (xy 259.947456 -285.958106) (xy 259.998155 -285.972453)
			(xy 260.046403 -285.993625) (xy 260.069076 -286.007048) (xy 260.075182 -286.01055) (xy 260.088712 -286.014416)
			(xy 260.095746 -286.014668) (xy 260.531102 -286.014668) (xy 260.538142 -286.014446) (xy 260.551679 -286.01058)
			(xy 260.557772 -286.007048) (xy 260.580433 -285.993599) (xy 260.628673 -285.97239) (xy 260.679377 -285.958037)
			(xy 260.731576 -285.950813) (xy 260.757924 -285.950406) (xy 260.784268 -285.950855) (xy 260.836456 -285.958106)
			(xy 260.887155 -285.972453) (xy 260.935403 -285.993625) (xy 260.958076 -286.007048) (xy 260.964182 -286.01055)
			(xy 260.977712 -286.014416) (xy 260.984746 -286.014668) (xy 263.70407 -286.014668) (xy 263.711111 -286.01445)
			(xy 263.724653 -286.010592) (xy 263.73074 -286.007048) (xy 263.753402 -285.993603) (xy 263.801643 -285.972402)
			(xy 263.852347 -285.958058) (xy 263.904545 -285.950844) (xy 263.930892 -285.950406) (xy 263.957237 -285.950853)
			(xy 264.009427 -285.9581) (xy 264.060127 -285.972443) (xy 264.108378 -285.993612) (xy 264.131044 -286.007048)
			(xy 264.137149 -286.010554) (xy 264.150679 -286.014428) (xy 264.157714 -286.014668) (xy 266.436348 -286.014668)
			(xy 266.446415 -286.015099) (xy 266.46501 -286.022822) (xy 266.472416 -286.029654) (xy 267.317728 -286.874966)
			(xy 268.26897 -286.874966) (xy 268.27293 -286.825912) (xy 268.284707 -286.778128) (xy 268.303998 -286.732852)
			(xy 268.330301 -286.691256) (xy 268.362936 -286.654419) (xy 268.401057 -286.623294) (xy 268.443678 -286.598687)
			(xy 268.489694 -286.581235) (xy 268.537913 -286.571391) (xy 268.587088 -286.56941) (xy 268.635943 -286.575342)
			(xy 268.683214 -286.589034) (xy 268.727676 -286.610132) (xy 268.768179 -286.638088) (xy 268.803672 -286.67218)
			(xy 268.833237 -286.711524) (xy 268.856108 -286.755101) (xy 268.871692 -286.801782) (xy 268.879587 -286.850359)
			(xy 268.880082 -286.874966) (xy 269.21893 -286.874966) (xy 269.22289 -286.825912) (xy 269.234667 -286.778128)
			(xy 269.253958 -286.732852) (xy 269.280261 -286.691256) (xy 269.312896 -286.654419) (xy 269.351017 -286.623294)
			(xy 269.393638 -286.598687) (xy 269.439654 -286.581235) (xy 269.487873 -286.571391) (xy 269.537048 -286.56941)
			(xy 269.585903 -286.575342) (xy 269.633174 -286.589034) (xy 269.677636 -286.610132) (xy 269.718139 -286.638088)
			(xy 269.753632 -286.67218) (xy 269.783197 -286.711524) (xy 269.806068 -286.755101) (xy 269.821652 -286.801782)
			(xy 269.829547 -286.850359) (xy 269.830042 -286.874966) (xy 270.169144 -286.874966) (xy 270.173104 -286.825912)
			(xy 270.184881 -286.778128) (xy 270.204172 -286.732852) (xy 270.230475 -286.691256) (xy 270.26311 -286.654419)
			(xy 270.301231 -286.623294) (xy 270.343852 -286.598687) (xy 270.389868 -286.581235) (xy 270.438087 -286.571391)
			(xy 270.487262 -286.56941) (xy 270.536117 -286.575342) (xy 270.583388 -286.589034) (xy 270.62785 -286.610132)
			(xy 270.668353 -286.638088) (xy 270.703846 -286.67218) (xy 270.733411 -286.711524) (xy 270.756282 -286.755101)
			(xy 270.771866 -286.801782) (xy 270.779761 -286.850359) (xy 270.780256 -286.874966) (xy 271.119104 -286.874966)
			(xy 271.123064 -286.825912) (xy 271.134841 -286.778128) (xy 271.154132 -286.732852) (xy 271.180435 -286.691256)
			(xy 271.21307 -286.654419) (xy 271.251191 -286.623294) (xy 271.293812 -286.598687) (xy 271.339828 -286.581235)
			(xy 271.388047 -286.571391) (xy 271.437222 -286.56941) (xy 271.486077 -286.575342) (xy 271.533348 -286.589034)
			(xy 271.57781 -286.610132) (xy 271.618313 -286.638088) (xy 271.653806 -286.67218) (xy 271.683371 -286.711524)
			(xy 271.706242 -286.755101) (xy 271.721826 -286.801782) (xy 271.729721 -286.850359) (xy 271.730216 -286.874966)
			(xy 272.069064 -286.874966) (xy 272.073024 -286.825912) (xy 272.084801 -286.778128) (xy 272.104092 -286.732852)
			(xy 272.130395 -286.691256) (xy 272.16303 -286.654419) (xy 272.201151 -286.623294) (xy 272.243772 -286.598687)
			(xy 272.289788 -286.581235) (xy 272.338007 -286.571391) (xy 272.387182 -286.56941) (xy 272.436037 -286.575342)
			(xy 272.483308 -286.589034) (xy 272.52777 -286.610132) (xy 272.568273 -286.638088) (xy 272.603766 -286.67218)
			(xy 272.633331 -286.711524) (xy 272.656202 -286.755101) (xy 272.671786 -286.801782) (xy 272.679681 -286.850359)
			(xy 272.680176 -286.874966) (xy 273.019024 -286.874966) (xy 273.022984 -286.825912) (xy 273.034761 -286.778128)
			(xy 273.054052 -286.732852) (xy 273.080355 -286.691256) (xy 273.11299 -286.654419) (xy 273.151111 -286.623294)
			(xy 273.193732 -286.598687) (xy 273.239748 -286.581235) (xy 273.287967 -286.571391) (xy 273.337142 -286.56941)
			(xy 273.385997 -286.575342) (xy 273.433268 -286.589034) (xy 273.47773 -286.610132) (xy 273.518233 -286.638088)
			(xy 273.553726 -286.67218) (xy 273.583291 -286.711524) (xy 273.606162 -286.755101) (xy 273.621746 -286.801782)
			(xy 273.629641 -286.850359) (xy 273.630136 -286.874966) (xy 273.968984 -286.874966) (xy 273.972944 -286.825912)
			(xy 273.984721 -286.778128) (xy 274.004012 -286.732852) (xy 274.030315 -286.691256) (xy 274.06295 -286.654419)
			(xy 274.101071 -286.623294) (xy 274.143692 -286.598687) (xy 274.189708 -286.581235) (xy 274.237927 -286.571391)
			(xy 274.287102 -286.56941) (xy 274.335957 -286.575342) (xy 274.383228 -286.589034) (xy 274.42769 -286.610132)
			(xy 274.468193 -286.638088) (xy 274.503686 -286.67218) (xy 274.533251 -286.711524) (xy 274.556122 -286.755101)
			(xy 274.571706 -286.801782) (xy 274.579601 -286.850359) (xy 274.580091 -286.874712) (xy 274.918944 -286.874712)
			(xy 274.922904 -286.825658) (xy 274.934681 -286.777874) (xy 274.953972 -286.732598) (xy 274.980275 -286.691002)
			(xy 275.01291 -286.654165) (xy 275.051031 -286.62304) (xy 275.093652 -286.598433) (xy 275.139668 -286.580981)
			(xy 275.187887 -286.571137) (xy 275.237062 -286.569156) (xy 275.285917 -286.575088) (xy 275.333188 -286.58878)
			(xy 275.37765 -286.609878) (xy 275.418153 -286.637834) (xy 275.453646 -286.671926) (xy 275.483211 -286.71127)
			(xy 275.506082 -286.754847) (xy 275.521666 -286.801528) (xy 275.529561 -286.850105) (xy 275.530056 -286.874712)
			(xy 275.868904 -286.874712) (xy 275.872864 -286.825658) (xy 275.884641 -286.777874) (xy 275.903932 -286.732598)
			(xy 275.930235 -286.691002) (xy 275.96287 -286.654165) (xy 276.000991 -286.62304) (xy 276.043612 -286.598433)
			(xy 276.089628 -286.580981) (xy 276.137847 -286.571137) (xy 276.187022 -286.569156) (xy 276.235877 -286.575088)
			(xy 276.283148 -286.58878) (xy 276.32761 -286.609878) (xy 276.368113 -286.637834) (xy 276.403606 -286.671926)
			(xy 276.433171 -286.71127) (xy 276.456042 -286.754847) (xy 276.471626 -286.801528) (xy 276.479521 -286.850105)
			(xy 276.480016 -286.874712) (xy 276.480011 -286.874966) (xy 276.819118 -286.874966) (xy 276.823078 -286.825912)
			(xy 276.834855 -286.778128) (xy 276.854146 -286.732852) (xy 276.880449 -286.691256) (xy 276.913084 -286.654419)
			(xy 276.951205 -286.623294) (xy 276.993826 -286.598687) (xy 277.039842 -286.581235) (xy 277.088061 -286.571391)
			(xy 277.137236 -286.56941) (xy 277.186091 -286.575342) (xy 277.233362 -286.589034) (xy 277.277824 -286.610132)
			(xy 277.318327 -286.638088) (xy 277.35382 -286.67218) (xy 277.383385 -286.711524) (xy 277.406256 -286.755101)
			(xy 277.42184 -286.801782) (xy 277.429735 -286.850359) (xy 277.43023 -286.874966) (xy 277.769078 -286.874966)
			(xy 277.773038 -286.825912) (xy 277.784815 -286.778128) (xy 277.804106 -286.732852) (xy 277.830409 -286.691256)
			(xy 277.863044 -286.654419) (xy 277.901165 -286.623294) (xy 277.943786 -286.598687) (xy 277.989802 -286.581235)
			(xy 278.038021 -286.571391) (xy 278.087196 -286.56941) (xy 278.136051 -286.575342) (xy 278.183322 -286.589034)
			(xy 278.227784 -286.610132) (xy 278.268287 -286.638088) (xy 278.30378 -286.67218) (xy 278.333345 -286.711524)
			(xy 278.356216 -286.755101) (xy 278.3718 -286.801782) (xy 278.379695 -286.850359) (xy 278.38019 -286.874966)
			(xy 278.379695 -286.899573) (xy 278.3718 -286.94815) (xy 278.356216 -286.994831) (xy 278.333345 -287.038408)
			(xy 278.30378 -287.077752) (xy 278.268287 -287.111844) (xy 278.227784 -287.1398) (xy 278.183322 -287.160898)
			(xy 278.136051 -287.17459) (xy 278.087196 -287.180522) (xy 278.038021 -287.178541) (xy 277.989802 -287.168697)
			(xy 277.943786 -287.151245) (xy 277.901165 -287.126638) (xy 277.863044 -287.095513) (xy 277.830409 -287.058676)
			(xy 277.804106 -287.01708) (xy 277.784815 -286.971804) (xy 277.773038 -286.92402) (xy 277.769078 -286.874966)
			(xy 277.43023 -286.874966) (xy 277.429735 -286.899573) (xy 277.42184 -286.94815) (xy 277.406256 -286.994831)
			(xy 277.383385 -287.038408) (xy 277.35382 -287.077752) (xy 277.318327 -287.111844) (xy 277.277824 -287.1398)
			(xy 277.233362 -287.160898) (xy 277.186091 -287.17459) (xy 277.137236 -287.180522) (xy 277.088061 -287.178541)
			(xy 277.039842 -287.168697) (xy 276.993826 -287.151245) (xy 276.951205 -287.126638) (xy 276.913084 -287.095513)
			(xy 276.880449 -287.058676) (xy 276.854146 -287.01708) (xy 276.834855 -286.971804) (xy 276.823078 -286.92402)
			(xy 276.819118 -286.874966) (xy 276.480011 -286.874966) (xy 276.479521 -286.899319) (xy 276.471626 -286.947896)
			(xy 276.456042 -286.994577) (xy 276.433171 -287.038154) (xy 276.403606 -287.077498) (xy 276.368113 -287.11159)
			(xy 276.32761 -287.139546) (xy 276.283148 -287.160644) (xy 276.235877 -287.174336) (xy 276.187022 -287.180268)
			(xy 276.137847 -287.178287) (xy 276.089628 -287.168443) (xy 276.043612 -287.150991) (xy 276.000991 -287.126384)
			(xy 275.96287 -287.095259) (xy 275.930235 -287.058422) (xy 275.903932 -287.016826) (xy 275.884641 -286.97155)
			(xy 275.872864 -286.923766) (xy 275.868904 -286.874712) (xy 275.530056 -286.874712) (xy 275.529561 -286.899319)
			(xy 275.521666 -286.947896) (xy 275.506082 -286.994577) (xy 275.483211 -287.038154) (xy 275.453646 -287.077498)
			(xy 275.418153 -287.11159) (xy 275.37765 -287.139546) (xy 275.333188 -287.160644) (xy 275.285917 -287.174336)
			(xy 275.237062 -287.180268) (xy 275.187887 -287.178287) (xy 275.139668 -287.168443) (xy 275.093652 -287.150991)
			(xy 275.051031 -287.126384) (xy 275.01291 -287.095259) (xy 274.980275 -287.058422) (xy 274.953972 -287.016826)
			(xy 274.934681 -286.97155) (xy 274.922904 -286.923766) (xy 274.918944 -286.874712) (xy 274.580091 -286.874712)
			(xy 274.580096 -286.874966) (xy 274.579601 -286.899573) (xy 274.571706 -286.94815) (xy 274.556122 -286.994831)
			(xy 274.533251 -287.038408) (xy 274.503686 -287.077752) (xy 274.468193 -287.111844) (xy 274.42769 -287.1398)
			(xy 274.383228 -287.160898) (xy 274.335957 -287.17459) (xy 274.287102 -287.180522) (xy 274.237927 -287.178541)
			(xy 274.189708 -287.168697) (xy 274.143692 -287.151245) (xy 274.101071 -287.126638) (xy 274.06295 -287.095513)
			(xy 274.030315 -287.058676) (xy 274.004012 -287.01708) (xy 273.984721 -286.971804) (xy 273.972944 -286.92402)
			(xy 273.968984 -286.874966) (xy 273.630136 -286.874966) (xy 273.629641 -286.899573) (xy 273.621746 -286.94815)
			(xy 273.606162 -286.994831) (xy 273.583291 -287.038408) (xy 273.553726 -287.077752) (xy 273.518233 -287.111844)
			(xy 273.47773 -287.1398) (xy 273.433268 -287.160898) (xy 273.385997 -287.17459) (xy 273.337142 -287.180522)
			(xy 273.287967 -287.178541) (xy 273.239748 -287.168697) (xy 273.193732 -287.151245) (xy 273.151111 -287.126638)
			(xy 273.11299 -287.095513) (xy 273.080355 -287.058676) (xy 273.054052 -287.01708) (xy 273.034761 -286.971804)
			(xy 273.022984 -286.92402) (xy 273.019024 -286.874966) (xy 272.680176 -286.874966) (xy 272.679681 -286.899573)
			(xy 272.671786 -286.94815) (xy 272.656202 -286.994831) (xy 272.633331 -287.038408) (xy 272.603766 -287.077752)
			(xy 272.568273 -287.111844) (xy 272.52777 -287.1398) (xy 272.483308 -287.160898) (xy 272.436037 -287.17459)
			(xy 272.387182 -287.180522) (xy 272.338007 -287.178541) (xy 272.289788 -287.168697) (xy 272.243772 -287.151245)
			(xy 272.201151 -287.126638) (xy 272.16303 -287.095513) (xy 272.130395 -287.058676) (xy 272.104092 -287.01708)
			(xy 272.084801 -286.971804) (xy 272.073024 -286.92402) (xy 272.069064 -286.874966) (xy 271.730216 -286.874966)
			(xy 271.729721 -286.899573) (xy 271.721826 -286.94815) (xy 271.706242 -286.994831) (xy 271.683371 -287.038408)
			(xy 271.653806 -287.077752) (xy 271.618313 -287.111844) (xy 271.57781 -287.1398) (xy 271.533348 -287.160898)
			(xy 271.486077 -287.17459) (xy 271.437222 -287.180522) (xy 271.388047 -287.178541) (xy 271.339828 -287.168697)
			(xy 271.293812 -287.151245) (xy 271.251191 -287.126638) (xy 271.21307 -287.095513) (xy 271.180435 -287.058676)
			(xy 271.154132 -287.01708) (xy 271.134841 -286.971804) (xy 271.123064 -286.92402) (xy 271.119104 -286.874966)
			(xy 270.780256 -286.874966) (xy 270.779761 -286.899573) (xy 270.771866 -286.94815) (xy 270.756282 -286.994831)
			(xy 270.733411 -287.038408) (xy 270.703846 -287.077752) (xy 270.668353 -287.111844) (xy 270.62785 -287.1398)
			(xy 270.583388 -287.160898) (xy 270.536117 -287.17459) (xy 270.487262 -287.180522) (xy 270.438087 -287.178541)
			(xy 270.389868 -287.168697) (xy 270.343852 -287.151245) (xy 270.301231 -287.126638) (xy 270.26311 -287.095513)
			(xy 270.230475 -287.058676) (xy 270.204172 -287.01708) (xy 270.184881 -286.971804) (xy 270.173104 -286.92402)
			(xy 270.169144 -286.874966) (xy 269.830042 -286.874966) (xy 269.829547 -286.899573) (xy 269.821652 -286.94815)
			(xy 269.806068 -286.994831) (xy 269.783197 -287.038408) (xy 269.753632 -287.077752) (xy 269.718139 -287.111844)
			(xy 269.677636 -287.1398) (xy 269.633174 -287.160898) (xy 269.585903 -287.17459) (xy 269.537048 -287.180522)
			(xy 269.487873 -287.178541) (xy 269.439654 -287.168697) (xy 269.393638 -287.151245) (xy 269.351017 -287.126638)
			(xy 269.312896 -287.095513) (xy 269.280261 -287.058676) (xy 269.253958 -287.01708) (xy 269.234667 -286.971804)
			(xy 269.22289 -286.92402) (xy 269.21893 -286.874966) (xy 268.880082 -286.874966) (xy 268.879587 -286.899573)
			(xy 268.871692 -286.94815) (xy 268.856108 -286.994831) (xy 268.833237 -287.038408) (xy 268.803672 -287.077752)
			(xy 268.768179 -287.111844) (xy 268.727676 -287.1398) (xy 268.683214 -287.160898) (xy 268.635943 -287.17459)
			(xy 268.587088 -287.180522) (xy 268.537913 -287.178541) (xy 268.489694 -287.168697) (xy 268.443678 -287.151245)
			(xy 268.401057 -287.126638) (xy 268.362936 -287.095513) (xy 268.330301 -287.058676) (xy 268.303998 -287.01708)
			(xy 268.284707 -286.971804) (xy 268.27293 -286.92402) (xy 268.26897 -286.874966) (xy 267.317728 -286.874966)
			(xy 267.46708 -287.024318) (xy 267.473926 -287.031717) (xy 267.481657 -287.050315) (xy 267.482066 -287.060386)
			(xy 267.482066 -287.824926) (xy 268.26897 -287.824926) (xy 268.27293 -287.775872) (xy 268.284707 -287.728088)
			(xy 268.303998 -287.682812) (xy 268.330301 -287.641216) (xy 268.362936 -287.604379) (xy 268.401057 -287.573254)
			(xy 268.443678 -287.548647) (xy 268.489694 -287.531195) (xy 268.537913 -287.521351) (xy 268.587088 -287.51937)
			(xy 268.635943 -287.525302) (xy 268.683214 -287.538994) (xy 268.727676 -287.560092) (xy 268.768179 -287.588048)
			(xy 268.803672 -287.62214) (xy 268.833237 -287.661484) (xy 268.856108 -287.705061) (xy 268.871692 -287.751742)
			(xy 268.879587 -287.800319) (xy 268.880082 -287.824926) (xy 269.21893 -287.824926) (xy 269.22289 -287.775872)
			(xy 269.234667 -287.728088) (xy 269.253958 -287.682812) (xy 269.280261 -287.641216) (xy 269.312896 -287.604379)
			(xy 269.351017 -287.573254) (xy 269.393638 -287.548647) (xy 269.439654 -287.531195) (xy 269.487873 -287.521351)
			(xy 269.537048 -287.51937) (xy 269.585903 -287.525302) (xy 269.633174 -287.538994) (xy 269.677636 -287.560092)
			(xy 269.718139 -287.588048) (xy 269.753632 -287.62214) (xy 269.783197 -287.661484) (xy 269.806068 -287.705061)
			(xy 269.821652 -287.751742) (xy 269.829547 -287.800319) (xy 269.830042 -287.824926) (xy 270.169144 -287.824926)
			(xy 270.173104 -287.775872) (xy 270.184881 -287.728088) (xy 270.204172 -287.682812) (xy 270.230475 -287.641216)
			(xy 270.26311 -287.604379) (xy 270.301231 -287.573254) (xy 270.343852 -287.548647) (xy 270.389868 -287.531195)
			(xy 270.438087 -287.521351) (xy 270.487262 -287.51937) (xy 270.536117 -287.525302) (xy 270.583388 -287.538994)
			(xy 270.62785 -287.560092) (xy 270.668353 -287.588048) (xy 270.703846 -287.62214) (xy 270.733411 -287.661484)
			(xy 270.756282 -287.705061) (xy 270.771866 -287.751742) (xy 270.779761 -287.800319) (xy 270.780256 -287.824926)
			(xy 273.019024 -287.824926) (xy 273.022984 -287.775872) (xy 273.034761 -287.728088) (xy 273.054052 -287.682812)
			(xy 273.080355 -287.641216) (xy 273.11299 -287.604379) (xy 273.151111 -287.573254) (xy 273.193732 -287.548647)
			(xy 273.239748 -287.531195) (xy 273.287967 -287.521351) (xy 273.337142 -287.51937) (xy 273.385997 -287.525302)
			(xy 273.433268 -287.538994) (xy 273.47773 -287.560092) (xy 273.518233 -287.588048) (xy 273.553726 -287.62214)
			(xy 273.583291 -287.661484) (xy 273.606162 -287.705061) (xy 273.621746 -287.751742) (xy 273.629641 -287.800319)
			(xy 273.630136 -287.824926) (xy 276.819118 -287.824926) (xy 276.823078 -287.775872) (xy 276.834855 -287.728088)
			(xy 276.854146 -287.682812) (xy 276.880449 -287.641216) (xy 276.913084 -287.604379) (xy 276.951205 -287.573254)
			(xy 276.993826 -287.548647) (xy 277.039842 -287.531195) (xy 277.088061 -287.521351) (xy 277.137236 -287.51937)
			(xy 277.186091 -287.525302) (xy 277.233362 -287.538994) (xy 277.277824 -287.560092) (xy 277.318327 -287.588048)
			(xy 277.35382 -287.62214) (xy 277.383385 -287.661484) (xy 277.406256 -287.705061) (xy 277.42184 -287.751742)
			(xy 277.429735 -287.800319) (xy 277.43023 -287.824926) (xy 277.769078 -287.824926) (xy 277.773038 -287.775872)
			(xy 277.784815 -287.728088) (xy 277.804106 -287.682812) (xy 277.830409 -287.641216) (xy 277.863044 -287.604379)
			(xy 277.901165 -287.573254) (xy 277.943786 -287.548647) (xy 277.989802 -287.531195) (xy 278.038021 -287.521351)
			(xy 278.087196 -287.51937) (xy 278.136051 -287.525302) (xy 278.183322 -287.538994) (xy 278.227784 -287.560092)
			(xy 278.268287 -287.588048) (xy 278.30378 -287.62214) (xy 278.333345 -287.661484) (xy 278.356216 -287.705061)
			(xy 278.3718 -287.751742) (xy 278.379695 -287.800319) (xy 278.38019 -287.824926) (xy 278.379695 -287.849533)
			(xy 278.3718 -287.89811) (xy 278.356216 -287.944791) (xy 278.333345 -287.988368) (xy 278.30378 -288.027712)
			(xy 278.268287 -288.061804) (xy 278.227784 -288.08976) (xy 278.183322 -288.110858) (xy 278.136051 -288.12455)
			(xy 278.087196 -288.130482) (xy 278.038021 -288.128501) (xy 277.989802 -288.118657) (xy 277.943786 -288.101205)
			(xy 277.901165 -288.076598) (xy 277.863044 -288.045473) (xy 277.830409 -288.008636) (xy 277.804106 -287.96704)
			(xy 277.784815 -287.921764) (xy 277.773038 -287.87398) (xy 277.769078 -287.824926) (xy 277.43023 -287.824926)
			(xy 277.429735 -287.849533) (xy 277.42184 -287.89811) (xy 277.406256 -287.944791) (xy 277.383385 -287.988368)
			(xy 277.35382 -288.027712) (xy 277.318327 -288.061804) (xy 277.277824 -288.08976) (xy 277.233362 -288.110858)
			(xy 277.186091 -288.12455) (xy 277.137236 -288.130482) (xy 277.088061 -288.128501) (xy 277.039842 -288.118657)
			(xy 276.993826 -288.101205) (xy 276.951205 -288.076598) (xy 276.913084 -288.045473) (xy 276.880449 -288.008636)
			(xy 276.854146 -287.96704) (xy 276.834855 -287.921764) (xy 276.823078 -287.87398) (xy 276.819118 -287.824926)
			(xy 273.630136 -287.824926) (xy 273.629641 -287.849533) (xy 273.621746 -287.89811) (xy 273.606162 -287.944791)
			(xy 273.583291 -287.988368) (xy 273.553726 -288.027712) (xy 273.518233 -288.061804) (xy 273.47773 -288.08976)
			(xy 273.433268 -288.110858) (xy 273.385997 -288.12455) (xy 273.337142 -288.130482) (xy 273.287967 -288.128501)
			(xy 273.239748 -288.118657) (xy 273.193732 -288.101205) (xy 273.151111 -288.076598) (xy 273.11299 -288.045473)
			(xy 273.080355 -288.008636) (xy 273.054052 -287.96704) (xy 273.034761 -287.921764) (xy 273.022984 -287.87398)
			(xy 273.019024 -287.824926) (xy 270.780256 -287.824926) (xy 270.779761 -287.849533) (xy 270.771866 -287.89811)
			(xy 270.756282 -287.944791) (xy 270.733411 -287.988368) (xy 270.703846 -288.027712) (xy 270.668353 -288.061804)
			(xy 270.62785 -288.08976) (xy 270.583388 -288.110858) (xy 270.536117 -288.12455) (xy 270.487262 -288.130482)
			(xy 270.438087 -288.128501) (xy 270.389868 -288.118657) (xy 270.343852 -288.101205) (xy 270.301231 -288.076598)
			(xy 270.26311 -288.045473) (xy 270.230475 -288.008636) (xy 270.204172 -287.96704) (xy 270.184881 -287.921764)
			(xy 270.173104 -287.87398) (xy 270.169144 -287.824926) (xy 269.830042 -287.824926) (xy 269.829547 -287.849533)
			(xy 269.821652 -287.89811) (xy 269.806068 -287.944791) (xy 269.783197 -287.988368) (xy 269.753632 -288.027712)
			(xy 269.718139 -288.061804) (xy 269.677636 -288.08976) (xy 269.633174 -288.110858) (xy 269.585903 -288.12455)
			(xy 269.537048 -288.130482) (xy 269.487873 -288.128501) (xy 269.439654 -288.118657) (xy 269.393638 -288.101205)
			(xy 269.351017 -288.076598) (xy 269.312896 -288.045473) (xy 269.280261 -288.008636) (xy 269.253958 -287.96704)
			(xy 269.234667 -287.921764) (xy 269.22289 -287.87398) (xy 269.21893 -287.824926) (xy 268.880082 -287.824926)
			(xy 268.879587 -287.849533) (xy 268.871692 -287.89811) (xy 268.856108 -287.944791) (xy 268.833237 -287.988368)
			(xy 268.803672 -288.027712) (xy 268.768179 -288.061804) (xy 268.727676 -288.08976) (xy 268.683214 -288.110858)
			(xy 268.635943 -288.12455) (xy 268.587088 -288.130482) (xy 268.537913 -288.128501) (xy 268.489694 -288.118657)
			(xy 268.443678 -288.101205) (xy 268.401057 -288.076598) (xy 268.362936 -288.045473) (xy 268.330301 -288.008636)
			(xy 268.303998 -287.96704) (xy 268.284707 -287.921764) (xy 268.27293 -287.87398) (xy 268.26897 -287.824926)
			(xy 267.482066 -287.824926) (xy 267.482066 -288.774886) (xy 268.26897 -288.774886) (xy 268.27293 -288.725832)
			(xy 268.284707 -288.678048) (xy 268.303998 -288.632772) (xy 268.330301 -288.591176) (xy 268.362936 -288.554339)
			(xy 268.401057 -288.523214) (xy 268.443678 -288.498607) (xy 268.489694 -288.481155) (xy 268.537913 -288.471311)
			(xy 268.587088 -288.46933) (xy 268.635943 -288.475262) (xy 268.683214 -288.488954) (xy 268.727676 -288.510052)
			(xy 268.768179 -288.538008) (xy 268.803672 -288.5721) (xy 268.833237 -288.611444) (xy 268.856108 -288.655021)
			(xy 268.871692 -288.701702) (xy 268.879587 -288.750279) (xy 268.880082 -288.774886) (xy 269.21893 -288.774886)
			(xy 269.22289 -288.725832) (xy 269.234667 -288.678048) (xy 269.253958 -288.632772) (xy 269.280261 -288.591176)
			(xy 269.312896 -288.554339) (xy 269.351017 -288.523214) (xy 269.393638 -288.498607) (xy 269.439654 -288.481155)
			(xy 269.487873 -288.471311) (xy 269.537048 -288.46933) (xy 269.585903 -288.475262) (xy 269.633174 -288.488954)
			(xy 269.677636 -288.510052) (xy 269.718139 -288.538008) (xy 269.753632 -288.5721) (xy 269.783197 -288.611444)
			(xy 269.806068 -288.655021) (xy 269.821652 -288.701702) (xy 269.829547 -288.750279) (xy 269.830042 -288.774886)
			(xy 270.169144 -288.774886) (xy 270.173104 -288.725832) (xy 270.184881 -288.678048) (xy 270.204172 -288.632772)
			(xy 270.230475 -288.591176) (xy 270.26311 -288.554339) (xy 270.301231 -288.523214) (xy 270.343852 -288.498607)
			(xy 270.389868 -288.481155) (xy 270.438087 -288.471311) (xy 270.487262 -288.46933) (xy 270.536117 -288.475262)
			(xy 270.583388 -288.488954) (xy 270.62785 -288.510052) (xy 270.668353 -288.538008) (xy 270.703846 -288.5721)
			(xy 270.733411 -288.611444) (xy 270.756282 -288.655021) (xy 270.771866 -288.701702) (xy 270.779761 -288.750279)
			(xy 270.780256 -288.774886) (xy 274.918944 -288.774886) (xy 274.922904 -288.725832) (xy 274.934681 -288.678048)
			(xy 274.953972 -288.632772) (xy 274.980275 -288.591176) (xy 275.01291 -288.554339) (xy 275.051031 -288.523214)
			(xy 275.093652 -288.498607) (xy 275.139668 -288.481155) (xy 275.187887 -288.471311) (xy 275.237062 -288.46933)
			(xy 275.285917 -288.475262) (xy 275.333188 -288.488954) (xy 275.37765 -288.510052) (xy 275.418153 -288.538008)
			(xy 275.453646 -288.5721) (xy 275.483211 -288.611444) (xy 275.506082 -288.655021) (xy 275.521666 -288.701702)
			(xy 275.529561 -288.750279) (xy 275.530056 -288.774886) (xy 275.868904 -288.774886) (xy 275.872864 -288.725832)
			(xy 275.884641 -288.678048) (xy 275.903932 -288.632772) (xy 275.930235 -288.591176) (xy 275.96287 -288.554339)
			(xy 276.000991 -288.523214) (xy 276.043612 -288.498607) (xy 276.089628 -288.481155) (xy 276.137847 -288.471311)
			(xy 276.187022 -288.46933) (xy 276.235877 -288.475262) (xy 276.283148 -288.488954) (xy 276.32761 -288.510052)
			(xy 276.368113 -288.538008) (xy 276.403606 -288.5721) (xy 276.433171 -288.611444) (xy 276.456042 -288.655021)
			(xy 276.471626 -288.701702) (xy 276.479521 -288.750279) (xy 276.480016 -288.774886) (xy 276.819118 -288.774886)
			(xy 276.823078 -288.725832) (xy 276.834855 -288.678048) (xy 276.854146 -288.632772) (xy 276.880449 -288.591176)
			(xy 276.913084 -288.554339) (xy 276.951205 -288.523214) (xy 276.993826 -288.498607) (xy 277.039842 -288.481155)
			(xy 277.088061 -288.471311) (xy 277.137236 -288.46933) (xy 277.186091 -288.475262) (xy 277.233362 -288.488954)
			(xy 277.277824 -288.510052) (xy 277.318327 -288.538008) (xy 277.35382 -288.5721) (xy 277.383385 -288.611444)
			(xy 277.406256 -288.655021) (xy 277.42184 -288.701702) (xy 277.429735 -288.750279) (xy 277.43023 -288.774886)
			(xy 277.769078 -288.774886) (xy 277.773038 -288.725832) (xy 277.784815 -288.678048) (xy 277.804106 -288.632772)
			(xy 277.830409 -288.591176) (xy 277.863044 -288.554339) (xy 277.901165 -288.523214) (xy 277.943786 -288.498607)
			(xy 277.989802 -288.481155) (xy 278.038021 -288.471311) (xy 278.087196 -288.46933) (xy 278.136051 -288.475262)
			(xy 278.183322 -288.488954) (xy 278.227784 -288.510052) (xy 278.268287 -288.538008) (xy 278.30378 -288.5721)
			(xy 278.333345 -288.611444) (xy 278.356216 -288.655021) (xy 278.3718 -288.701702) (xy 278.379695 -288.750279)
			(xy 278.38019 -288.774886) (xy 278.379695 -288.799493) (xy 278.3718 -288.84807) (xy 278.356216 -288.894751)
			(xy 278.333345 -288.938328) (xy 278.30378 -288.977672) (xy 278.268287 -289.011764) (xy 278.227784 -289.03972)
			(xy 278.183322 -289.060818) (xy 278.136051 -289.07451) (xy 278.087196 -289.080442) (xy 278.038021 -289.078461)
			(xy 277.989802 -289.068617) (xy 277.943786 -289.051165) (xy 277.901165 -289.026558) (xy 277.863044 -288.995433)
			(xy 277.830409 -288.958596) (xy 277.804106 -288.917) (xy 277.784815 -288.871724) (xy 277.773038 -288.82394)
			(xy 277.769078 -288.774886) (xy 277.43023 -288.774886) (xy 277.429735 -288.799493) (xy 277.42184 -288.84807)
			(xy 277.406256 -288.894751) (xy 277.383385 -288.938328) (xy 277.35382 -288.977672) (xy 277.318327 -289.011764)
			(xy 277.277824 -289.03972) (xy 277.233362 -289.060818) (xy 277.186091 -289.07451) (xy 277.137236 -289.080442)
			(xy 277.088061 -289.078461) (xy 277.039842 -289.068617) (xy 276.993826 -289.051165) (xy 276.951205 -289.026558)
			(xy 276.913084 -288.995433) (xy 276.880449 -288.958596) (xy 276.854146 -288.917) (xy 276.834855 -288.871724)
			(xy 276.823078 -288.82394) (xy 276.819118 -288.774886) (xy 276.480016 -288.774886) (xy 276.479521 -288.799493)
			(xy 276.471626 -288.84807) (xy 276.456042 -288.894751) (xy 276.433171 -288.938328) (xy 276.403606 -288.977672)
			(xy 276.368113 -289.011764) (xy 276.32761 -289.03972) (xy 276.283148 -289.060818) (xy 276.235877 -289.07451)
			(xy 276.187022 -289.080442) (xy 276.137847 -289.078461) (xy 276.089628 -289.068617) (xy 276.043612 -289.051165)
			(xy 276.000991 -289.026558) (xy 275.96287 -288.995433) (xy 275.930235 -288.958596) (xy 275.903932 -288.917)
			(xy 275.884641 -288.871724) (xy 275.872864 -288.82394) (xy 275.868904 -288.774886) (xy 275.530056 -288.774886)
			(xy 275.529561 -288.799493) (xy 275.521666 -288.84807) (xy 275.506082 -288.894751) (xy 275.483211 -288.938328)
			(xy 275.453646 -288.977672) (xy 275.418153 -289.011764) (xy 275.37765 -289.03972) (xy 275.333188 -289.060818)
			(xy 275.285917 -289.07451) (xy 275.237062 -289.080442) (xy 275.187887 -289.078461) (xy 275.139668 -289.068617)
			(xy 275.093652 -289.051165) (xy 275.051031 -289.026558) (xy 275.01291 -288.995433) (xy 274.980275 -288.958596)
			(xy 274.953972 -288.917) (xy 274.934681 -288.871724) (xy 274.922904 -288.82394) (xy 274.918944 -288.774886)
			(xy 270.780256 -288.774886) (xy 270.779761 -288.799493) (xy 270.771866 -288.84807) (xy 270.756282 -288.894751)
			(xy 270.733411 -288.938328) (xy 270.703846 -288.977672) (xy 270.668353 -289.011764) (xy 270.62785 -289.03972)
			(xy 270.583388 -289.060818) (xy 270.536117 -289.07451) (xy 270.487262 -289.080442) (xy 270.438087 -289.078461)
			(xy 270.389868 -289.068617) (xy 270.343852 -289.051165) (xy 270.301231 -289.026558) (xy 270.26311 -288.995433)
			(xy 270.230475 -288.958596) (xy 270.204172 -288.917) (xy 270.184881 -288.871724) (xy 270.173104 -288.82394)
			(xy 270.169144 -288.774886) (xy 269.830042 -288.774886) (xy 269.829547 -288.799493) (xy 269.821652 -288.84807)
			(xy 269.806068 -288.894751) (xy 269.783197 -288.938328) (xy 269.753632 -288.977672) (xy 269.718139 -289.011764)
			(xy 269.677636 -289.03972) (xy 269.633174 -289.060818) (xy 269.585903 -289.07451) (xy 269.537048 -289.080442)
			(xy 269.487873 -289.078461) (xy 269.439654 -289.068617) (xy 269.393638 -289.051165) (xy 269.351017 -289.026558)
			(xy 269.312896 -288.995433) (xy 269.280261 -288.958596) (xy 269.253958 -288.917) (xy 269.234667 -288.871724)
			(xy 269.22289 -288.82394) (xy 269.21893 -288.774886) (xy 268.880082 -288.774886) (xy 268.879587 -288.799493)
			(xy 268.871692 -288.84807) (xy 268.856108 -288.894751) (xy 268.833237 -288.938328) (xy 268.803672 -288.977672)
			(xy 268.768179 -289.011764) (xy 268.727676 -289.03972) (xy 268.683214 -289.060818) (xy 268.635943 -289.07451)
			(xy 268.587088 -289.080442) (xy 268.537913 -289.078461) (xy 268.489694 -289.068617) (xy 268.443678 -289.051165)
			(xy 268.401057 -289.026558) (xy 268.362936 -288.995433) (xy 268.330301 -288.958596) (xy 268.303998 -288.917)
			(xy 268.284707 -288.871724) (xy 268.27293 -288.82394) (xy 268.26897 -288.774886) (xy 267.482066 -288.774886)
			(xy 267.482066 -289.724846) (xy 268.26897 -289.724846) (xy 268.27293 -289.675792) (xy 268.284707 -289.628008)
			(xy 268.303998 -289.582732) (xy 268.330301 -289.541136) (xy 268.362936 -289.504299) (xy 268.401057 -289.473174)
			(xy 268.443678 -289.448567) (xy 268.489694 -289.431115) (xy 268.537913 -289.421271) (xy 268.587088 -289.41929)
			(xy 268.635943 -289.425222) (xy 268.683214 -289.438914) (xy 268.727676 -289.460012) (xy 268.768179 -289.487968)
			(xy 268.803672 -289.52206) (xy 268.833237 -289.561404) (xy 268.856108 -289.604981) (xy 268.871692 -289.651662)
			(xy 268.879587 -289.700239) (xy 268.880082 -289.724846) (xy 269.21893 -289.724846) (xy 269.22289 -289.675792)
			(xy 269.234667 -289.628008) (xy 269.253958 -289.582732) (xy 269.280261 -289.541136) (xy 269.312896 -289.504299)
			(xy 269.351017 -289.473174) (xy 269.393638 -289.448567) (xy 269.439654 -289.431115) (xy 269.487873 -289.421271)
			(xy 269.537048 -289.41929) (xy 269.585903 -289.425222) (xy 269.633174 -289.438914) (xy 269.677636 -289.460012)
			(xy 269.718139 -289.487968) (xy 269.753632 -289.52206) (xy 269.783197 -289.561404) (xy 269.806068 -289.604981)
			(xy 269.821652 -289.651662) (xy 269.829547 -289.700239) (xy 269.830042 -289.724846) (xy 270.169144 -289.724846)
			(xy 270.173104 -289.675792) (xy 270.184881 -289.628008) (xy 270.204172 -289.582732) (xy 270.230475 -289.541136)
			(xy 270.26311 -289.504299) (xy 270.301231 -289.473174) (xy 270.343852 -289.448567) (xy 270.389868 -289.431115)
			(xy 270.438087 -289.421271) (xy 270.487262 -289.41929) (xy 270.536117 -289.425222) (xy 270.583388 -289.438914)
			(xy 270.62785 -289.460012) (xy 270.668353 -289.487968) (xy 270.703846 -289.52206) (xy 270.733411 -289.561404)
			(xy 270.756282 -289.604981) (xy 270.771866 -289.651662) (xy 270.779761 -289.700239) (xy 270.780256 -289.724846)
			(xy 271.119104 -289.724846) (xy 271.123064 -289.675792) (xy 271.134841 -289.628008) (xy 271.154132 -289.582732)
			(xy 271.180435 -289.541136) (xy 271.21307 -289.504299) (xy 271.251191 -289.473174) (xy 271.293812 -289.448567)
			(xy 271.339828 -289.431115) (xy 271.388047 -289.421271) (xy 271.437222 -289.41929) (xy 271.486077 -289.425222)
			(xy 271.533348 -289.438914) (xy 271.57781 -289.460012) (xy 271.618313 -289.487968) (xy 271.653806 -289.52206)
			(xy 271.683371 -289.561404) (xy 271.706242 -289.604981) (xy 271.721826 -289.651662) (xy 271.729721 -289.700239)
			(xy 271.730216 -289.724846) (xy 272.069064 -289.724846) (xy 272.073024 -289.675792) (xy 272.084801 -289.628008)
			(xy 272.104092 -289.582732) (xy 272.130395 -289.541136) (xy 272.16303 -289.504299) (xy 272.201151 -289.473174)
			(xy 272.243772 -289.448567) (xy 272.289788 -289.431115) (xy 272.338007 -289.421271) (xy 272.387182 -289.41929)
			(xy 272.436037 -289.425222) (xy 272.483308 -289.438914) (xy 272.52777 -289.460012) (xy 272.568273 -289.487968)
			(xy 272.603766 -289.52206) (xy 272.633331 -289.561404) (xy 272.656202 -289.604981) (xy 272.671786 -289.651662)
			(xy 272.679681 -289.700239) (xy 272.680176 -289.724846) (xy 273.019024 -289.724846) (xy 273.022984 -289.675792)
			(xy 273.034761 -289.628008) (xy 273.054052 -289.582732) (xy 273.080355 -289.541136) (xy 273.11299 -289.504299)
			(xy 273.151111 -289.473174) (xy 273.193732 -289.448567) (xy 273.239748 -289.431115) (xy 273.287967 -289.421271)
			(xy 273.337142 -289.41929) (xy 273.385997 -289.425222) (xy 273.433268 -289.438914) (xy 273.47773 -289.460012)
			(xy 273.518233 -289.487968) (xy 273.553726 -289.52206) (xy 273.583291 -289.561404) (xy 273.606162 -289.604981)
			(xy 273.621746 -289.651662) (xy 273.629641 -289.700239) (xy 273.630136 -289.724846) (xy 273.968984 -289.724846)
			(xy 273.972944 -289.675792) (xy 273.984721 -289.628008) (xy 274.004012 -289.582732) (xy 274.030315 -289.541136)
			(xy 274.06295 -289.504299) (xy 274.101071 -289.473174) (xy 274.143692 -289.448567) (xy 274.189708 -289.431115)
			(xy 274.237927 -289.421271) (xy 274.287102 -289.41929) (xy 274.335957 -289.425222) (xy 274.383228 -289.438914)
			(xy 274.42769 -289.460012) (xy 274.468193 -289.487968) (xy 274.503686 -289.52206) (xy 274.533251 -289.561404)
			(xy 274.556122 -289.604981) (xy 274.571706 -289.651662) (xy 274.579601 -289.700239) (xy 274.580096 -289.724846)
			(xy 274.918944 -289.724846) (xy 274.922904 -289.675792) (xy 274.934681 -289.628008) (xy 274.953972 -289.582732)
			(xy 274.980275 -289.541136) (xy 275.01291 -289.504299) (xy 275.051031 -289.473174) (xy 275.093652 -289.448567)
			(xy 275.139668 -289.431115) (xy 275.187887 -289.421271) (xy 275.237062 -289.41929) (xy 275.285917 -289.425222)
			(xy 275.333188 -289.438914) (xy 275.37765 -289.460012) (xy 275.418153 -289.487968) (xy 275.453646 -289.52206)
			(xy 275.483211 -289.561404) (xy 275.506082 -289.604981) (xy 275.521666 -289.651662) (xy 275.529561 -289.700239)
			(xy 275.530056 -289.724846) (xy 275.868904 -289.724846) (xy 275.872864 -289.675792) (xy 275.884641 -289.628008)
			(xy 275.903932 -289.582732) (xy 275.930235 -289.541136) (xy 275.96287 -289.504299) (xy 276.000991 -289.473174)
			(xy 276.043612 -289.448567) (xy 276.089628 -289.431115) (xy 276.137847 -289.421271) (xy 276.187022 -289.41929)
			(xy 276.235877 -289.425222) (xy 276.283148 -289.438914) (xy 276.32761 -289.460012) (xy 276.368113 -289.487968)
			(xy 276.403606 -289.52206) (xy 276.433171 -289.561404) (xy 276.456042 -289.604981) (xy 276.471626 -289.651662)
			(xy 276.479521 -289.700239) (xy 276.480016 -289.724846) (xy 276.819118 -289.724846) (xy 276.823078 -289.675792)
			(xy 276.834855 -289.628008) (xy 276.854146 -289.582732) (xy 276.880449 -289.541136) (xy 276.913084 -289.504299)
			(xy 276.951205 -289.473174) (xy 276.993826 -289.448567) (xy 277.039842 -289.431115) (xy 277.088061 -289.421271)
			(xy 277.137236 -289.41929) (xy 277.186091 -289.425222) (xy 277.233362 -289.438914) (xy 277.277824 -289.460012)
			(xy 277.318327 -289.487968) (xy 277.35382 -289.52206) (xy 277.383385 -289.561404) (xy 277.406256 -289.604981)
			(xy 277.42184 -289.651662) (xy 277.429735 -289.700239) (xy 277.43023 -289.724846) (xy 277.769078 -289.724846)
			(xy 277.773038 -289.675792) (xy 277.784815 -289.628008) (xy 277.804106 -289.582732) (xy 277.830409 -289.541136)
			(xy 277.863044 -289.504299) (xy 277.901165 -289.473174) (xy 277.943786 -289.448567) (xy 277.989802 -289.431115)
			(xy 278.038021 -289.421271) (xy 278.087196 -289.41929) (xy 278.136051 -289.425222) (xy 278.183322 -289.438914)
			(xy 278.227784 -289.460012) (xy 278.268287 -289.487968) (xy 278.30378 -289.52206) (xy 278.333345 -289.561404)
			(xy 278.356216 -289.604981) (xy 278.3718 -289.651662) (xy 278.379695 -289.700239) (xy 278.38019 -289.724846)
			(xy 278.379695 -289.749453) (xy 278.3718 -289.79803) (xy 278.356216 -289.844711) (xy 278.333345 -289.888288)
			(xy 278.30378 -289.927632) (xy 278.268287 -289.961724) (xy 278.227784 -289.98968) (xy 278.183322 -290.010778)
			(xy 278.136051 -290.02447) (xy 278.087196 -290.030402) (xy 278.038021 -290.028421) (xy 277.989802 -290.018577)
			(xy 277.943786 -290.001125) (xy 277.901165 -289.976518) (xy 277.863044 -289.945393) (xy 277.830409 -289.908556)
			(xy 277.804106 -289.86696) (xy 277.784815 -289.821684) (xy 277.773038 -289.7739) (xy 277.769078 -289.724846)
			(xy 277.43023 -289.724846) (xy 277.429735 -289.749453) (xy 277.42184 -289.79803) (xy 277.406256 -289.844711)
			(xy 277.383385 -289.888288) (xy 277.35382 -289.927632) (xy 277.318327 -289.961724) (xy 277.277824 -289.98968)
			(xy 277.233362 -290.010778) (xy 277.186091 -290.02447) (xy 277.137236 -290.030402) (xy 277.088061 -290.028421)
			(xy 277.039842 -290.018577) (xy 276.993826 -290.001125) (xy 276.951205 -289.976518) (xy 276.913084 -289.945393)
			(xy 276.880449 -289.908556) (xy 276.854146 -289.86696) (xy 276.834855 -289.821684) (xy 276.823078 -289.7739)
			(xy 276.819118 -289.724846) (xy 276.480016 -289.724846) (xy 276.479521 -289.749453) (xy 276.471626 -289.79803)
			(xy 276.456042 -289.844711) (xy 276.433171 -289.888288) (xy 276.403606 -289.927632) (xy 276.368113 -289.961724)
			(xy 276.32761 -289.98968) (xy 276.283148 -290.010778) (xy 276.235877 -290.02447) (xy 276.187022 -290.030402)
			(xy 276.137847 -290.028421) (xy 276.089628 -290.018577) (xy 276.043612 -290.001125) (xy 276.000991 -289.976518)
			(xy 275.96287 -289.945393) (xy 275.930235 -289.908556) (xy 275.903932 -289.86696) (xy 275.884641 -289.821684)
			(xy 275.872864 -289.7739) (xy 275.868904 -289.724846) (xy 275.530056 -289.724846) (xy 275.529561 -289.749453)
			(xy 275.521666 -289.79803) (xy 275.506082 -289.844711) (xy 275.483211 -289.888288) (xy 275.453646 -289.927632)
			(xy 275.418153 -289.961724) (xy 275.37765 -289.98968) (xy 275.333188 -290.010778) (xy 275.285917 -290.02447)
			(xy 275.237062 -290.030402) (xy 275.187887 -290.028421) (xy 275.139668 -290.018577) (xy 275.093652 -290.001125)
			(xy 275.051031 -289.976518) (xy 275.01291 -289.945393) (xy 274.980275 -289.908556) (xy 274.953972 -289.86696)
			(xy 274.934681 -289.821684) (xy 274.922904 -289.7739) (xy 274.918944 -289.724846) (xy 274.580096 -289.724846)
			(xy 274.579601 -289.749453) (xy 274.571706 -289.79803) (xy 274.556122 -289.844711) (xy 274.533251 -289.888288)
			(xy 274.503686 -289.927632) (xy 274.468193 -289.961724) (xy 274.42769 -289.98968) (xy 274.383228 -290.010778)
			(xy 274.335957 -290.02447) (xy 274.287102 -290.030402) (xy 274.237927 -290.028421) (xy 274.189708 -290.018577)
			(xy 274.143692 -290.001125) (xy 274.101071 -289.976518) (xy 274.06295 -289.945393) (xy 274.030315 -289.908556)
			(xy 274.004012 -289.86696) (xy 273.984721 -289.821684) (xy 273.972944 -289.7739) (xy 273.968984 -289.724846)
			(xy 273.630136 -289.724846) (xy 273.629641 -289.749453) (xy 273.621746 -289.79803) (xy 273.606162 -289.844711)
			(xy 273.583291 -289.888288) (xy 273.553726 -289.927632) (xy 273.518233 -289.961724) (xy 273.47773 -289.98968)
			(xy 273.433268 -290.010778) (xy 273.385997 -290.02447) (xy 273.337142 -290.030402) (xy 273.287967 -290.028421)
			(xy 273.239748 -290.018577) (xy 273.193732 -290.001125) (xy 273.151111 -289.976518) (xy 273.11299 -289.945393)
			(xy 273.080355 -289.908556) (xy 273.054052 -289.86696) (xy 273.034761 -289.821684) (xy 273.022984 -289.7739)
			(xy 273.019024 -289.724846) (xy 272.680176 -289.724846) (xy 272.679681 -289.749453) (xy 272.671786 -289.79803)
			(xy 272.656202 -289.844711) (xy 272.633331 -289.888288) (xy 272.603766 -289.927632) (xy 272.568273 -289.961724)
			(xy 272.52777 -289.98968) (xy 272.483308 -290.010778) (xy 272.436037 -290.02447) (xy 272.387182 -290.030402)
			(xy 272.338007 -290.028421) (xy 272.289788 -290.018577) (xy 272.243772 -290.001125) (xy 272.201151 -289.976518)
			(xy 272.16303 -289.945393) (xy 272.130395 -289.908556) (xy 272.104092 -289.86696) (xy 272.084801 -289.821684)
			(xy 272.073024 -289.7739) (xy 272.069064 -289.724846) (xy 271.730216 -289.724846) (xy 271.729721 -289.749453)
			(xy 271.721826 -289.79803) (xy 271.706242 -289.844711) (xy 271.683371 -289.888288) (xy 271.653806 -289.927632)
			(xy 271.618313 -289.961724) (xy 271.57781 -289.98968) (xy 271.533348 -290.010778) (xy 271.486077 -290.02447)
			(xy 271.437222 -290.030402) (xy 271.388047 -290.028421) (xy 271.339828 -290.018577) (xy 271.293812 -290.001125)
			(xy 271.251191 -289.976518) (xy 271.21307 -289.945393) (xy 271.180435 -289.908556) (xy 271.154132 -289.86696)
			(xy 271.134841 -289.821684) (xy 271.123064 -289.7739) (xy 271.119104 -289.724846) (xy 270.780256 -289.724846)
			(xy 270.779761 -289.749453) (xy 270.771866 -289.79803) (xy 270.756282 -289.844711) (xy 270.733411 -289.888288)
			(xy 270.703846 -289.927632) (xy 270.668353 -289.961724) (xy 270.62785 -289.98968) (xy 270.583388 -290.010778)
			(xy 270.536117 -290.02447) (xy 270.487262 -290.030402) (xy 270.438087 -290.028421) (xy 270.389868 -290.018577)
			(xy 270.343852 -290.001125) (xy 270.301231 -289.976518) (xy 270.26311 -289.945393) (xy 270.230475 -289.908556)
			(xy 270.204172 -289.86696) (xy 270.184881 -289.821684) (xy 270.173104 -289.7739) (xy 270.169144 -289.724846)
			(xy 269.830042 -289.724846) (xy 269.829547 -289.749453) (xy 269.821652 -289.79803) (xy 269.806068 -289.844711)
			(xy 269.783197 -289.888288) (xy 269.753632 -289.927632) (xy 269.718139 -289.961724) (xy 269.677636 -289.98968)
			(xy 269.633174 -290.010778) (xy 269.585903 -290.02447) (xy 269.537048 -290.030402) (xy 269.487873 -290.028421)
			(xy 269.439654 -290.018577) (xy 269.393638 -290.001125) (xy 269.351017 -289.976518) (xy 269.312896 -289.945393)
			(xy 269.280261 -289.908556) (xy 269.253958 -289.86696) (xy 269.234667 -289.821684) (xy 269.22289 -289.7739)
			(xy 269.21893 -289.724846) (xy 268.880082 -289.724846) (xy 268.879587 -289.749453) (xy 268.871692 -289.79803)
			(xy 268.856108 -289.844711) (xy 268.833237 -289.888288) (xy 268.803672 -289.927632) (xy 268.768179 -289.961724)
			(xy 268.727676 -289.98968) (xy 268.683214 -290.010778) (xy 268.635943 -290.02447) (xy 268.587088 -290.030402)
			(xy 268.537913 -290.028421) (xy 268.489694 -290.018577) (xy 268.443678 -290.001125) (xy 268.401057 -289.976518)
			(xy 268.362936 -289.945393) (xy 268.330301 -289.908556) (xy 268.303998 -289.86696) (xy 268.284707 -289.821684)
			(xy 268.27293 -289.7739) (xy 268.26897 -289.724846) (xy 267.482066 -289.724846) (xy 267.482066 -290.674806)
			(xy 268.26897 -290.674806) (xy 268.27293 -290.625752) (xy 268.284707 -290.577968) (xy 268.303998 -290.532692)
			(xy 268.330301 -290.491096) (xy 268.362936 -290.454259) (xy 268.401057 -290.423134) (xy 268.443678 -290.398527)
			(xy 268.489694 -290.381075) (xy 268.537913 -290.371231) (xy 268.587088 -290.36925) (xy 268.635943 -290.375182)
			(xy 268.683214 -290.388874) (xy 268.727676 -290.409972) (xy 268.768179 -290.437928) (xy 268.803672 -290.47202)
			(xy 268.833237 -290.511364) (xy 268.856108 -290.554941) (xy 268.871692 -290.601622) (xy 268.879587 -290.650199)
			(xy 268.880082 -290.674806) (xy 269.21893 -290.674806) (xy 269.22289 -290.625752) (xy 269.234667 -290.577968)
			(xy 269.253958 -290.532692) (xy 269.280261 -290.491096) (xy 269.312896 -290.454259) (xy 269.351017 -290.423134)
			(xy 269.393638 -290.398527) (xy 269.439654 -290.381075) (xy 269.487873 -290.371231) (xy 269.537048 -290.36925)
			(xy 269.585903 -290.375182) (xy 269.633174 -290.388874) (xy 269.677636 -290.409972) (xy 269.718139 -290.437928)
			(xy 269.753632 -290.47202) (xy 269.783197 -290.511364) (xy 269.806068 -290.554941) (xy 269.821652 -290.601622)
			(xy 269.829547 -290.650199) (xy 269.830042 -290.674806) (xy 270.169144 -290.674806) (xy 270.173104 -290.625752)
			(xy 270.184881 -290.577968) (xy 270.204172 -290.532692) (xy 270.230475 -290.491096) (xy 270.26311 -290.454259)
			(xy 270.301231 -290.423134) (xy 270.343852 -290.398527) (xy 270.389868 -290.381075) (xy 270.438087 -290.371231)
			(xy 270.487262 -290.36925) (xy 270.536117 -290.375182) (xy 270.583388 -290.388874) (xy 270.62785 -290.409972)
			(xy 270.668353 -290.437928) (xy 270.703846 -290.47202) (xy 270.733411 -290.511364) (xy 270.756282 -290.554941)
			(xy 270.771866 -290.601622) (xy 270.779761 -290.650199) (xy 270.780256 -290.674806) (xy 273.019024 -290.674806)
			(xy 273.022984 -290.625752) (xy 273.034761 -290.577968) (xy 273.054052 -290.532692) (xy 273.080355 -290.491096)
			(xy 273.11299 -290.454259) (xy 273.151111 -290.423134) (xy 273.193732 -290.398527) (xy 273.239748 -290.381075)
			(xy 273.287967 -290.371231) (xy 273.337142 -290.36925) (xy 273.385997 -290.375182) (xy 273.433268 -290.388874)
			(xy 273.47773 -290.409972) (xy 273.518233 -290.437928) (xy 273.553726 -290.47202) (xy 273.583291 -290.511364)
			(xy 273.606162 -290.554941) (xy 273.621746 -290.601622) (xy 273.629641 -290.650199) (xy 273.630136 -290.674806)
			(xy 273.968984 -290.674806) (xy 273.972944 -290.625752) (xy 273.984721 -290.577968) (xy 274.004012 -290.532692)
			(xy 274.030315 -290.491096) (xy 274.06295 -290.454259) (xy 274.101071 -290.423134) (xy 274.143692 -290.398527)
			(xy 274.189708 -290.381075) (xy 274.237927 -290.371231) (xy 274.287102 -290.36925) (xy 274.335957 -290.375182)
			(xy 274.383228 -290.388874) (xy 274.42769 -290.409972) (xy 274.468193 -290.437928) (xy 274.503686 -290.47202)
			(xy 274.533251 -290.511364) (xy 274.556122 -290.554941) (xy 274.571706 -290.601622) (xy 274.579601 -290.650199)
			(xy 274.580096 -290.674806) (xy 274.918944 -290.674806) (xy 274.922904 -290.625752) (xy 274.934681 -290.577968)
			(xy 274.953972 -290.532692) (xy 274.980275 -290.491096) (xy 275.01291 -290.454259) (xy 275.051031 -290.423134)
			(xy 275.093652 -290.398527) (xy 275.139668 -290.381075) (xy 275.187887 -290.371231) (xy 275.237062 -290.36925)
			(xy 275.285917 -290.375182) (xy 275.333188 -290.388874) (xy 275.37765 -290.409972) (xy 275.418153 -290.437928)
			(xy 275.453646 -290.47202) (xy 275.483211 -290.511364) (xy 275.506082 -290.554941) (xy 275.521666 -290.601622)
			(xy 275.529561 -290.650199) (xy 275.530056 -290.674806) (xy 275.868904 -290.674806) (xy 275.872864 -290.625752)
			(xy 275.884641 -290.577968) (xy 275.903932 -290.532692) (xy 275.930235 -290.491096) (xy 275.96287 -290.454259)
			(xy 276.000991 -290.423134) (xy 276.043612 -290.398527) (xy 276.089628 -290.381075) (xy 276.137847 -290.371231)
			(xy 276.187022 -290.36925) (xy 276.235877 -290.375182) (xy 276.283148 -290.388874) (xy 276.32761 -290.409972)
			(xy 276.368113 -290.437928) (xy 276.403606 -290.47202) (xy 276.433171 -290.511364) (xy 276.456042 -290.554941)
			(xy 276.471626 -290.601622) (xy 276.479521 -290.650199) (xy 276.480016 -290.674806) (xy 277.769078 -290.674806)
			(xy 277.773038 -290.625752) (xy 277.784815 -290.577968) (xy 277.804106 -290.532692) (xy 277.830409 -290.491096)
			(xy 277.863044 -290.454259) (xy 277.901165 -290.423134) (xy 277.943786 -290.398527) (xy 277.989802 -290.381075)
			(xy 278.038021 -290.371231) (xy 278.087196 -290.36925) (xy 278.136051 -290.375182) (xy 278.183322 -290.388874)
			(xy 278.227784 -290.409972) (xy 278.268287 -290.437928) (xy 278.30378 -290.47202) (xy 278.333345 -290.511364)
			(xy 278.356216 -290.554941) (xy 278.3718 -290.601622) (xy 278.379695 -290.650199) (xy 278.38019 -290.674806)
			(xy 278.379695 -290.699413) (xy 278.3718 -290.74799) (xy 278.356216 -290.794671) (xy 278.333345 -290.838248)
			(xy 278.30378 -290.877592) (xy 278.268287 -290.911684) (xy 278.227784 -290.93964) (xy 278.183322 -290.960738)
			(xy 278.136051 -290.97443) (xy 278.087196 -290.980362) (xy 278.038021 -290.978381) (xy 277.989802 -290.968537)
			(xy 277.943786 -290.951085) (xy 277.901165 -290.926478) (xy 277.863044 -290.895353) (xy 277.830409 -290.858516)
			(xy 277.804106 -290.81692) (xy 277.784815 -290.771644) (xy 277.773038 -290.72386) (xy 277.769078 -290.674806)
			(xy 276.480016 -290.674806) (xy 276.479521 -290.699413) (xy 276.471626 -290.74799) (xy 276.456042 -290.794671)
			(xy 276.433171 -290.838248) (xy 276.403606 -290.877592) (xy 276.368113 -290.911684) (xy 276.32761 -290.93964)
			(xy 276.283148 -290.960738) (xy 276.235877 -290.97443) (xy 276.187022 -290.980362) (xy 276.137847 -290.978381)
			(xy 276.089628 -290.968537) (xy 276.043612 -290.951085) (xy 276.000991 -290.926478) (xy 275.96287 -290.895353)
			(xy 275.930235 -290.858516) (xy 275.903932 -290.81692) (xy 275.884641 -290.771644) (xy 275.872864 -290.72386)
			(xy 275.868904 -290.674806) (xy 275.530056 -290.674806) (xy 275.529561 -290.699413) (xy 275.521666 -290.74799)
			(xy 275.506082 -290.794671) (xy 275.483211 -290.838248) (xy 275.453646 -290.877592) (xy 275.418153 -290.911684)
			(xy 275.37765 -290.93964) (xy 275.333188 -290.960738) (xy 275.285917 -290.97443) (xy 275.237062 -290.980362)
			(xy 275.187887 -290.978381) (xy 275.139668 -290.968537) (xy 275.093652 -290.951085) (xy 275.051031 -290.926478)
			(xy 275.01291 -290.895353) (xy 274.980275 -290.858516) (xy 274.953972 -290.81692) (xy 274.934681 -290.771644)
			(xy 274.922904 -290.72386) (xy 274.918944 -290.674806) (xy 274.580096 -290.674806) (xy 274.579601 -290.699413)
			(xy 274.571706 -290.74799) (xy 274.556122 -290.794671) (xy 274.533251 -290.838248) (xy 274.503686 -290.877592)
			(xy 274.468193 -290.911684) (xy 274.42769 -290.93964) (xy 274.383228 -290.960738) (xy 274.335957 -290.97443)
			(xy 274.287102 -290.980362) (xy 274.237927 -290.978381) (xy 274.189708 -290.968537) (xy 274.143692 -290.951085)
			(xy 274.101071 -290.926478) (xy 274.06295 -290.895353) (xy 274.030315 -290.858516) (xy 274.004012 -290.81692)
			(xy 273.984721 -290.771644) (xy 273.972944 -290.72386) (xy 273.968984 -290.674806) (xy 273.630136 -290.674806)
			(xy 273.629641 -290.699413) (xy 273.621746 -290.74799) (xy 273.606162 -290.794671) (xy 273.583291 -290.838248)
			(xy 273.553726 -290.877592) (xy 273.518233 -290.911684) (xy 273.47773 -290.93964) (xy 273.433268 -290.960738)
			(xy 273.385997 -290.97443) (xy 273.337142 -290.980362) (xy 273.287967 -290.978381) (xy 273.239748 -290.968537)
			(xy 273.193732 -290.951085) (xy 273.151111 -290.926478) (xy 273.11299 -290.895353) (xy 273.080355 -290.858516)
			(xy 273.054052 -290.81692) (xy 273.034761 -290.771644) (xy 273.022984 -290.72386) (xy 273.019024 -290.674806)
			(xy 270.780256 -290.674806) (xy 270.779761 -290.699413) (xy 270.771866 -290.74799) (xy 270.756282 -290.794671)
			(xy 270.733411 -290.838248) (xy 270.703846 -290.877592) (xy 270.668353 -290.911684) (xy 270.62785 -290.93964)
			(xy 270.583388 -290.960738) (xy 270.536117 -290.97443) (xy 270.487262 -290.980362) (xy 270.438087 -290.978381)
			(xy 270.389868 -290.968537) (xy 270.343852 -290.951085) (xy 270.301231 -290.926478) (xy 270.26311 -290.895353)
			(xy 270.230475 -290.858516) (xy 270.204172 -290.81692) (xy 270.184881 -290.771644) (xy 270.173104 -290.72386)
			(xy 270.169144 -290.674806) (xy 269.830042 -290.674806) (xy 269.829547 -290.699413) (xy 269.821652 -290.74799)
			(xy 269.806068 -290.794671) (xy 269.783197 -290.838248) (xy 269.753632 -290.877592) (xy 269.718139 -290.911684)
			(xy 269.677636 -290.93964) (xy 269.633174 -290.960738) (xy 269.585903 -290.97443) (xy 269.537048 -290.980362)
			(xy 269.487873 -290.978381) (xy 269.439654 -290.968537) (xy 269.393638 -290.951085) (xy 269.351017 -290.926478)
			(xy 269.312896 -290.895353) (xy 269.280261 -290.858516) (xy 269.253958 -290.81692) (xy 269.234667 -290.771644)
			(xy 269.22289 -290.72386) (xy 269.21893 -290.674806) (xy 268.880082 -290.674806) (xy 268.879587 -290.699413)
			(xy 268.871692 -290.74799) (xy 268.856108 -290.794671) (xy 268.833237 -290.838248) (xy 268.803672 -290.877592)
			(xy 268.768179 -290.911684) (xy 268.727676 -290.93964) (xy 268.683214 -290.960738) (xy 268.635943 -290.97443)
			(xy 268.587088 -290.980362) (xy 268.537913 -290.978381) (xy 268.489694 -290.968537) (xy 268.443678 -290.951085)
			(xy 268.401057 -290.926478) (xy 268.362936 -290.895353) (xy 268.330301 -290.858516) (xy 268.303998 -290.81692)
			(xy 268.284707 -290.771644) (xy 268.27293 -290.72386) (xy 268.26897 -290.674806) (xy 267.482066 -290.674806)
			(xy 267.482066 -291.624766) (xy 268.26897 -291.624766) (xy 268.27293 -291.575712) (xy 268.284707 -291.527928)
			(xy 268.303998 -291.482652) (xy 268.330301 -291.441056) (xy 268.362936 -291.404219) (xy 268.401057 -291.373094)
			(xy 268.443678 -291.348487) (xy 268.489694 -291.331035) (xy 268.537913 -291.321191) (xy 268.587088 -291.31921)
			(xy 268.635943 -291.325142) (xy 268.683214 -291.338834) (xy 268.727676 -291.359932) (xy 268.768179 -291.387888)
			(xy 268.803672 -291.42198) (xy 268.833237 -291.461324) (xy 268.856108 -291.504901) (xy 268.871692 -291.551582)
			(xy 268.879587 -291.600159) (xy 268.880082 -291.624766) (xy 269.21893 -291.624766) (xy 269.22289 -291.575712)
			(xy 269.234667 -291.527928) (xy 269.253958 -291.482652) (xy 269.280261 -291.441056) (xy 269.312896 -291.404219)
			(xy 269.351017 -291.373094) (xy 269.393638 -291.348487) (xy 269.439654 -291.331035) (xy 269.487873 -291.321191)
			(xy 269.537048 -291.31921) (xy 269.585903 -291.325142) (xy 269.633174 -291.338834) (xy 269.677636 -291.359932)
			(xy 269.718139 -291.387888) (xy 269.753632 -291.42198) (xy 269.783197 -291.461324) (xy 269.806068 -291.504901)
			(xy 269.821652 -291.551582) (xy 269.829547 -291.600159) (xy 269.830042 -291.624766) (xy 270.169144 -291.624766)
			(xy 270.173104 -291.575712) (xy 270.184881 -291.527928) (xy 270.204172 -291.482652) (xy 270.230475 -291.441056)
			(xy 270.26311 -291.404219) (xy 270.301231 -291.373094) (xy 270.343852 -291.348487) (xy 270.389868 -291.331035)
			(xy 270.438087 -291.321191) (xy 270.487262 -291.31921) (xy 270.536117 -291.325142) (xy 270.583388 -291.338834)
			(xy 270.62785 -291.359932) (xy 270.668353 -291.387888) (xy 270.703846 -291.42198) (xy 270.733411 -291.461324)
			(xy 270.756282 -291.504901) (xy 270.771866 -291.551582) (xy 270.779761 -291.600159) (xy 270.780256 -291.624766)
			(xy 273.019024 -291.624766) (xy 273.022984 -291.575712) (xy 273.034761 -291.527928) (xy 273.054052 -291.482652)
			(xy 273.080355 -291.441056) (xy 273.11299 -291.404219) (xy 273.151111 -291.373094) (xy 273.193732 -291.348487)
			(xy 273.239748 -291.331035) (xy 273.287967 -291.321191) (xy 273.337142 -291.31921) (xy 273.385997 -291.325142)
			(xy 273.433268 -291.338834) (xy 273.47773 -291.359932) (xy 273.518233 -291.387888) (xy 273.553726 -291.42198)
			(xy 273.583291 -291.461324) (xy 273.606162 -291.504901) (xy 273.621746 -291.551582) (xy 273.629641 -291.600159)
			(xy 273.630136 -291.624766) (xy 273.968984 -291.624766) (xy 273.972944 -291.575712) (xy 273.984721 -291.527928)
			(xy 274.004012 -291.482652) (xy 274.030315 -291.441056) (xy 274.06295 -291.404219) (xy 274.101071 -291.373094)
			(xy 274.143692 -291.348487) (xy 274.189708 -291.331035) (xy 274.237927 -291.321191) (xy 274.287102 -291.31921)
			(xy 274.335957 -291.325142) (xy 274.383228 -291.338834) (xy 274.42769 -291.359932) (xy 274.468193 -291.387888)
			(xy 274.503686 -291.42198) (xy 274.533251 -291.461324) (xy 274.556122 -291.504901) (xy 274.571706 -291.551582)
			(xy 274.579601 -291.600159) (xy 274.580096 -291.624766) (xy 274.918944 -291.624766) (xy 274.922904 -291.575712)
			(xy 274.934681 -291.527928) (xy 274.953972 -291.482652) (xy 274.980275 -291.441056) (xy 275.01291 -291.404219)
			(xy 275.051031 -291.373094) (xy 275.093652 -291.348487) (xy 275.139668 -291.331035) (xy 275.187887 -291.321191)
			(xy 275.237062 -291.31921) (xy 275.285917 -291.325142) (xy 275.333188 -291.338834) (xy 275.37765 -291.359932)
			(xy 275.418153 -291.387888) (xy 275.453646 -291.42198) (xy 275.483211 -291.461324) (xy 275.506082 -291.504901)
			(xy 275.521666 -291.551582) (xy 275.529561 -291.600159) (xy 275.530056 -291.624766) (xy 275.868904 -291.624766)
			(xy 275.872864 -291.575712) (xy 275.884641 -291.527928) (xy 275.903932 -291.482652) (xy 275.930235 -291.441056)
			(xy 275.96287 -291.404219) (xy 276.000991 -291.373094) (xy 276.043612 -291.348487) (xy 276.089628 -291.331035)
			(xy 276.137847 -291.321191) (xy 276.187022 -291.31921) (xy 276.235877 -291.325142) (xy 276.283148 -291.338834)
			(xy 276.32761 -291.359932) (xy 276.368113 -291.387888) (xy 276.403606 -291.42198) (xy 276.433171 -291.461324)
			(xy 276.456042 -291.504901) (xy 276.471626 -291.551582) (xy 276.479521 -291.600159) (xy 276.480016 -291.624766)
			(xy 277.769078 -291.624766) (xy 277.773038 -291.575712) (xy 277.784815 -291.527928) (xy 277.804106 -291.482652)
			(xy 277.830409 -291.441056) (xy 277.863044 -291.404219) (xy 277.901165 -291.373094) (xy 277.943786 -291.348487)
			(xy 277.989802 -291.331035) (xy 278.038021 -291.321191) (xy 278.087196 -291.31921) (xy 278.136051 -291.325142)
			(xy 278.183322 -291.338834) (xy 278.227784 -291.359932) (xy 278.268287 -291.387888) (xy 278.30378 -291.42198)
			(xy 278.333345 -291.461324) (xy 278.356216 -291.504901) (xy 278.3718 -291.551582) (xy 278.379695 -291.600159)
			(xy 278.38019 -291.624766) (xy 278.379695 -291.649373) (xy 278.3718 -291.69795) (xy 278.356216 -291.744631)
			(xy 278.333345 -291.788208) (xy 278.30378 -291.827552) (xy 278.268287 -291.861644) (xy 278.227784 -291.8896)
			(xy 278.183322 -291.910698) (xy 278.136051 -291.92439) (xy 278.087196 -291.930322) (xy 278.038021 -291.928341)
			(xy 277.989802 -291.918497) (xy 277.943786 -291.901045) (xy 277.901165 -291.876438) (xy 277.863044 -291.845313)
			(xy 277.830409 -291.808476) (xy 277.804106 -291.76688) (xy 277.784815 -291.721604) (xy 277.773038 -291.67382)
			(xy 277.769078 -291.624766) (xy 276.480016 -291.624766) (xy 276.479521 -291.649373) (xy 276.471626 -291.69795)
			(xy 276.456042 -291.744631) (xy 276.433171 -291.788208) (xy 276.403606 -291.827552) (xy 276.368113 -291.861644)
			(xy 276.32761 -291.8896) (xy 276.283148 -291.910698) (xy 276.235877 -291.92439) (xy 276.187022 -291.930322)
			(xy 276.137847 -291.928341) (xy 276.089628 -291.918497) (xy 276.043612 -291.901045) (xy 276.000991 -291.876438)
			(xy 275.96287 -291.845313) (xy 275.930235 -291.808476) (xy 275.903932 -291.76688) (xy 275.884641 -291.721604)
			(xy 275.872864 -291.67382) (xy 275.868904 -291.624766) (xy 275.530056 -291.624766) (xy 275.529561 -291.649373)
			(xy 275.521666 -291.69795) (xy 275.506082 -291.744631) (xy 275.483211 -291.788208) (xy 275.453646 -291.827552)
			(xy 275.418153 -291.861644) (xy 275.37765 -291.8896) (xy 275.333188 -291.910698) (xy 275.285917 -291.92439)
			(xy 275.237062 -291.930322) (xy 275.187887 -291.928341) (xy 275.139668 -291.918497) (xy 275.093652 -291.901045)
			(xy 275.051031 -291.876438) (xy 275.01291 -291.845313) (xy 274.980275 -291.808476) (xy 274.953972 -291.76688)
			(xy 274.934681 -291.721604) (xy 274.922904 -291.67382) (xy 274.918944 -291.624766) (xy 274.580096 -291.624766)
			(xy 274.579601 -291.649373) (xy 274.571706 -291.69795) (xy 274.556122 -291.744631) (xy 274.533251 -291.788208)
			(xy 274.503686 -291.827552) (xy 274.468193 -291.861644) (xy 274.42769 -291.8896) (xy 274.383228 -291.910698)
			(xy 274.335957 -291.92439) (xy 274.287102 -291.930322) (xy 274.237927 -291.928341) (xy 274.189708 -291.918497)
			(xy 274.143692 -291.901045) (xy 274.101071 -291.876438) (xy 274.06295 -291.845313) (xy 274.030315 -291.808476)
			(xy 274.004012 -291.76688) (xy 273.984721 -291.721604) (xy 273.972944 -291.67382) (xy 273.968984 -291.624766)
			(xy 273.630136 -291.624766) (xy 273.629641 -291.649373) (xy 273.621746 -291.69795) (xy 273.606162 -291.744631)
			(xy 273.583291 -291.788208) (xy 273.553726 -291.827552) (xy 273.518233 -291.861644) (xy 273.47773 -291.8896)
			(xy 273.433268 -291.910698) (xy 273.385997 -291.92439) (xy 273.337142 -291.930322) (xy 273.287967 -291.928341)
			(xy 273.239748 -291.918497) (xy 273.193732 -291.901045) (xy 273.151111 -291.876438) (xy 273.11299 -291.845313)
			(xy 273.080355 -291.808476) (xy 273.054052 -291.76688) (xy 273.034761 -291.721604) (xy 273.022984 -291.67382)
			(xy 273.019024 -291.624766) (xy 270.780256 -291.624766) (xy 270.779761 -291.649373) (xy 270.771866 -291.69795)
			(xy 270.756282 -291.744631) (xy 270.733411 -291.788208) (xy 270.703846 -291.827552) (xy 270.668353 -291.861644)
			(xy 270.62785 -291.8896) (xy 270.583388 -291.910698) (xy 270.536117 -291.92439) (xy 270.487262 -291.930322)
			(xy 270.438087 -291.928341) (xy 270.389868 -291.918497) (xy 270.343852 -291.901045) (xy 270.301231 -291.876438)
			(xy 270.26311 -291.845313) (xy 270.230475 -291.808476) (xy 270.204172 -291.76688) (xy 270.184881 -291.721604)
			(xy 270.173104 -291.67382) (xy 270.169144 -291.624766) (xy 269.830042 -291.624766) (xy 269.829547 -291.649373)
			(xy 269.821652 -291.69795) (xy 269.806068 -291.744631) (xy 269.783197 -291.788208) (xy 269.753632 -291.827552)
			(xy 269.718139 -291.861644) (xy 269.677636 -291.8896) (xy 269.633174 -291.910698) (xy 269.585903 -291.92439)
			(xy 269.537048 -291.930322) (xy 269.487873 -291.928341) (xy 269.439654 -291.918497) (xy 269.393638 -291.901045)
			(xy 269.351017 -291.876438) (xy 269.312896 -291.845313) (xy 269.280261 -291.808476) (xy 269.253958 -291.76688)
			(xy 269.234667 -291.721604) (xy 269.22289 -291.67382) (xy 269.21893 -291.624766) (xy 268.880082 -291.624766)
			(xy 268.879587 -291.649373) (xy 268.871692 -291.69795) (xy 268.856108 -291.744631) (xy 268.833237 -291.788208)
			(xy 268.803672 -291.827552) (xy 268.768179 -291.861644) (xy 268.727676 -291.8896) (xy 268.683214 -291.910698)
			(xy 268.635943 -291.92439) (xy 268.587088 -291.930322) (xy 268.537913 -291.928341) (xy 268.489694 -291.918497)
			(xy 268.443678 -291.901045) (xy 268.401057 -291.876438) (xy 268.362936 -291.845313) (xy 268.330301 -291.808476)
			(xy 268.303998 -291.76688) (xy 268.284707 -291.721604) (xy 268.27293 -291.67382) (xy 268.26897 -291.624766)
			(xy 267.482066 -291.624766) (xy 267.482066 -292.57498) (xy 268.26897 -292.57498) (xy 268.27293 -292.525926)
			(xy 268.284707 -292.478142) (xy 268.303998 -292.432866) (xy 268.330301 -292.39127) (xy 268.362936 -292.354433)
			(xy 268.401057 -292.323308) (xy 268.443678 -292.298701) (xy 268.489694 -292.281249) (xy 268.537913 -292.271405)
			(xy 268.587088 -292.269424) (xy 268.635943 -292.275356) (xy 268.683214 -292.289048) (xy 268.727676 -292.310146)
			(xy 268.768179 -292.338102) (xy 268.803672 -292.372194) (xy 268.833237 -292.411538) (xy 268.856108 -292.455115)
			(xy 268.871692 -292.501796) (xy 268.879587 -292.550373) (xy 268.880082 -292.57498) (xy 269.21893 -292.57498)
			(xy 269.22289 -292.525926) (xy 269.234667 -292.478142) (xy 269.253958 -292.432866) (xy 269.280261 -292.39127)
			(xy 269.312896 -292.354433) (xy 269.351017 -292.323308) (xy 269.393638 -292.298701) (xy 269.439654 -292.281249)
			(xy 269.487873 -292.271405) (xy 269.537048 -292.269424) (xy 269.585903 -292.275356) (xy 269.633174 -292.289048)
			(xy 269.677636 -292.310146) (xy 269.718139 -292.338102) (xy 269.753632 -292.372194) (xy 269.783197 -292.411538)
			(xy 269.806068 -292.455115) (xy 269.821652 -292.501796) (xy 269.829547 -292.550373) (xy 269.830042 -292.57498)
			(xy 270.169144 -292.57498) (xy 270.173104 -292.525926) (xy 270.184881 -292.478142) (xy 270.204172 -292.432866)
			(xy 270.230475 -292.39127) (xy 270.26311 -292.354433) (xy 270.301231 -292.323308) (xy 270.343852 -292.298701)
			(xy 270.389868 -292.281249) (xy 270.438087 -292.271405) (xy 270.487262 -292.269424) (xy 270.536117 -292.275356)
			(xy 270.583388 -292.289048) (xy 270.62785 -292.310146) (xy 270.668353 -292.338102) (xy 270.703846 -292.372194)
			(xy 270.733411 -292.411538) (xy 270.756282 -292.455115) (xy 270.771866 -292.501796) (xy 270.779761 -292.550373)
			(xy 270.780251 -292.574726) (xy 271.119104 -292.574726) (xy 271.123064 -292.525672) (xy 271.134841 -292.477888)
			(xy 271.154132 -292.432612) (xy 271.180435 -292.391016) (xy 271.21307 -292.354179) (xy 271.251191 -292.323054)
			(xy 271.293812 -292.298447) (xy 271.339828 -292.280995) (xy 271.388047 -292.271151) (xy 271.437222 -292.26917)
			(xy 271.486077 -292.275102) (xy 271.533348 -292.288794) (xy 271.57781 -292.309892) (xy 271.618313 -292.337848)
			(xy 271.653806 -292.37194) (xy 271.683371 -292.411284) (xy 271.706242 -292.454861) (xy 271.721826 -292.501542)
			(xy 271.729721 -292.550119) (xy 271.730216 -292.574726) (xy 272.069064 -292.574726) (xy 272.073024 -292.525672)
			(xy 272.084801 -292.477888) (xy 272.104092 -292.432612) (xy 272.130395 -292.391016) (xy 272.16303 -292.354179)
			(xy 272.201151 -292.323054) (xy 272.243772 -292.298447) (xy 272.289788 -292.280995) (xy 272.338007 -292.271151)
			(xy 272.387182 -292.26917) (xy 272.436037 -292.275102) (xy 272.483308 -292.288794) (xy 272.52777 -292.309892)
			(xy 272.568273 -292.337848) (xy 272.603766 -292.37194) (xy 272.633331 -292.411284) (xy 272.656202 -292.454861)
			(xy 272.671786 -292.501542) (xy 272.679681 -292.550119) (xy 272.680176 -292.574726) (xy 272.680171 -292.57498)
			(xy 273.019024 -292.57498) (xy 273.022984 -292.525926) (xy 273.034761 -292.478142) (xy 273.054052 -292.432866)
			(xy 273.080355 -292.39127) (xy 273.11299 -292.354433) (xy 273.151111 -292.323308) (xy 273.193732 -292.298701)
			(xy 273.239748 -292.281249) (xy 273.287967 -292.271405) (xy 273.337142 -292.269424) (xy 273.385997 -292.275356)
			(xy 273.433268 -292.289048) (xy 273.47773 -292.310146) (xy 273.518233 -292.338102) (xy 273.553726 -292.372194)
			(xy 273.583291 -292.411538) (xy 273.606162 -292.455115) (xy 273.621746 -292.501796) (xy 273.629641 -292.550373)
			(xy 273.630136 -292.57498) (xy 273.629641 -292.599587) (xy 273.629309 -292.601629) (xy 273.919178 -292.601629)
			(xy 273.919178 -292.548331) (xy 273.927121 -292.495627) (xy 273.942831 -292.444697) (xy 273.965957 -292.396676)
			(xy 273.995981 -292.352639) (xy 274.032233 -292.313568) (xy 274.073904 -292.280337) (xy 274.120062 -292.253688)
			(xy 274.169676 -292.234216) (xy 274.221638 -292.222356) (xy 274.274788 -292.218373) (xy 274.327938 -292.222356)
			(xy 274.3799 -292.234216) (xy 274.429514 -292.253688) (xy 274.475672 -292.280337) (xy 274.517343 -292.313568)
			(xy 274.553595 -292.352639) (xy 274.583619 -292.396676) (xy 274.606745 -292.444697) (xy 274.622455 -292.495627)
			(xy 274.630398 -292.548331) (xy 274.630896 -292.57498) (xy 274.918944 -292.57498) (xy 274.922904 -292.525926)
			(xy 274.934681 -292.478142) (xy 274.953972 -292.432866) (xy 274.980275 -292.39127) (xy 275.01291 -292.354433)
			(xy 275.051031 -292.323308) (xy 275.093652 -292.298701) (xy 275.139668 -292.281249) (xy 275.187887 -292.271405)
			(xy 275.237062 -292.269424) (xy 275.285917 -292.275356) (xy 275.333188 -292.289048) (xy 275.37765 -292.310146)
			(xy 275.418153 -292.338102) (xy 275.453646 -292.372194) (xy 275.483211 -292.411538) (xy 275.506082 -292.455115)
			(xy 275.521666 -292.501796) (xy 275.529561 -292.550373) (xy 275.530056 -292.57498) (xy 275.868904 -292.57498)
			(xy 275.872864 -292.525926) (xy 275.884641 -292.478142) (xy 275.903932 -292.432866) (xy 275.930235 -292.39127)
			(xy 275.96287 -292.354433) (xy 276.000991 -292.323308) (xy 276.043612 -292.298701) (xy 276.089628 -292.281249)
			(xy 276.137847 -292.271405) (xy 276.187022 -292.269424) (xy 276.235877 -292.275356) (xy 276.283148 -292.289048)
			(xy 276.32761 -292.310146) (xy 276.368113 -292.338102) (xy 276.403606 -292.372194) (xy 276.433171 -292.411538)
			(xy 276.456042 -292.455115) (xy 276.471626 -292.501796) (xy 276.479521 -292.550373) (xy 276.480016 -292.57498)
			(xy 277.769078 -292.57498) (xy 277.773038 -292.525926) (xy 277.784815 -292.478142) (xy 277.804106 -292.432866)
			(xy 277.830409 -292.39127) (xy 277.863044 -292.354433) (xy 277.901165 -292.323308) (xy 277.943786 -292.298701)
			(xy 277.989802 -292.281249) (xy 278.038021 -292.271405) (xy 278.087196 -292.269424) (xy 278.136051 -292.275356)
			(xy 278.183322 -292.289048) (xy 278.227784 -292.310146) (xy 278.268287 -292.338102) (xy 278.30378 -292.372194)
			(xy 278.333345 -292.411538) (xy 278.356216 -292.455115) (xy 278.3718 -292.501796) (xy 278.379695 -292.550373)
			(xy 278.38019 -292.57498) (xy 278.379695 -292.599587) (xy 278.3718 -292.648164) (xy 278.356216 -292.694845)
			(xy 278.333345 -292.738422) (xy 278.30378 -292.777766) (xy 278.268287 -292.811858) (xy 278.227784 -292.839814)
			(xy 278.183322 -292.860912) (xy 278.136051 -292.874604) (xy 278.087196 -292.880536) (xy 278.038021 -292.878555)
			(xy 277.989802 -292.868711) (xy 277.943786 -292.851259) (xy 277.901165 -292.826652) (xy 277.863044 -292.795527)
			(xy 277.830409 -292.75869) (xy 277.804106 -292.717094) (xy 277.784815 -292.671818) (xy 277.773038 -292.624034)
			(xy 277.769078 -292.57498) (xy 276.480016 -292.57498) (xy 276.479521 -292.599587) (xy 276.471626 -292.648164)
			(xy 276.456042 -292.694845) (xy 276.433171 -292.738422) (xy 276.403606 -292.777766) (xy 276.368113 -292.811858)
			(xy 276.32761 -292.839814) (xy 276.283148 -292.860912) (xy 276.235877 -292.874604) (xy 276.187022 -292.880536)
			(xy 276.137847 -292.878555) (xy 276.089628 -292.868711) (xy 276.043612 -292.851259) (xy 276.000991 -292.826652)
			(xy 275.96287 -292.795527) (xy 275.930235 -292.75869) (xy 275.903932 -292.717094) (xy 275.884641 -292.671818)
			(xy 275.872864 -292.624034) (xy 275.868904 -292.57498) (xy 275.530056 -292.57498) (xy 275.529561 -292.599587)
			(xy 275.521666 -292.648164) (xy 275.506082 -292.694845) (xy 275.483211 -292.738422) (xy 275.453646 -292.777766)
			(xy 275.418153 -292.811858) (xy 275.37765 -292.839814) (xy 275.333188 -292.860912) (xy 275.285917 -292.874604)
			(xy 275.237062 -292.880536) (xy 275.187887 -292.878555) (xy 275.139668 -292.868711) (xy 275.093652 -292.851259)
			(xy 275.051031 -292.826652) (xy 275.01291 -292.795527) (xy 274.980275 -292.75869) (xy 274.953972 -292.717094)
			(xy 274.934681 -292.671818) (xy 274.922904 -292.624034) (xy 274.918944 -292.57498) (xy 274.630896 -292.57498)
			(xy 274.630398 -292.601629) (xy 274.622455 -292.654333) (xy 274.606745 -292.705263) (xy 274.583619 -292.753284)
			(xy 274.553595 -292.797321) (xy 274.517343 -292.836392) (xy 274.475672 -292.869623) (xy 274.429514 -292.896272)
			(xy 274.3799 -292.915744) (xy 274.327938 -292.927604) (xy 274.274788 -292.931588) (xy 274.221638 -292.927604)
			(xy 274.169676 -292.915744) (xy 274.120062 -292.896272) (xy 274.073904 -292.869623) (xy 274.032233 -292.836392)
			(xy 273.995981 -292.797321) (xy 273.965957 -292.753284) (xy 273.942831 -292.705263) (xy 273.927121 -292.654333)
			(xy 273.919178 -292.601629) (xy 273.629309 -292.601629) (xy 273.621746 -292.648164) (xy 273.606162 -292.694845)
			(xy 273.583291 -292.738422) (xy 273.553726 -292.777766) (xy 273.518233 -292.811858) (xy 273.47773 -292.839814)
			(xy 273.433268 -292.860912) (xy 273.385997 -292.874604) (xy 273.337142 -292.880536) (xy 273.287967 -292.878555)
			(xy 273.239748 -292.868711) (xy 273.193732 -292.851259) (xy 273.151111 -292.826652) (xy 273.11299 -292.795527)
			(xy 273.080355 -292.75869) (xy 273.054052 -292.717094) (xy 273.034761 -292.671818) (xy 273.022984 -292.624034)
			(xy 273.019024 -292.57498) (xy 272.680171 -292.57498) (xy 272.679681 -292.599333) (xy 272.671786 -292.64791)
			(xy 272.656202 -292.694591) (xy 272.633331 -292.738168) (xy 272.603766 -292.777512) (xy 272.568273 -292.811604)
			(xy 272.52777 -292.83956) (xy 272.483308 -292.860658) (xy 272.436037 -292.87435) (xy 272.387182 -292.880282)
			(xy 272.338007 -292.878301) (xy 272.289788 -292.868457) (xy 272.243772 -292.851005) (xy 272.201151 -292.826398)
			(xy 272.16303 -292.795273) (xy 272.130395 -292.758436) (xy 272.104092 -292.71684) (xy 272.084801 -292.671564)
			(xy 272.073024 -292.62378) (xy 272.069064 -292.574726) (xy 271.730216 -292.574726) (xy 271.729721 -292.599333)
			(xy 271.721826 -292.64791) (xy 271.706242 -292.694591) (xy 271.683371 -292.738168) (xy 271.653806 -292.777512)
			(xy 271.618313 -292.811604) (xy 271.57781 -292.83956) (xy 271.533348 -292.860658) (xy 271.486077 -292.87435)
			(xy 271.437222 -292.880282) (xy 271.388047 -292.878301) (xy 271.339828 -292.868457) (xy 271.293812 -292.851005)
			(xy 271.251191 -292.826398) (xy 271.21307 -292.795273) (xy 271.180435 -292.758436) (xy 271.154132 -292.71684)
			(xy 271.134841 -292.671564) (xy 271.123064 -292.62378) (xy 271.119104 -292.574726) (xy 270.780251 -292.574726)
			(xy 270.780256 -292.57498) (xy 270.779761 -292.599587) (xy 270.771866 -292.648164) (xy 270.756282 -292.694845)
			(xy 270.733411 -292.738422) (xy 270.703846 -292.777766) (xy 270.668353 -292.811858) (xy 270.62785 -292.839814)
			(xy 270.583388 -292.860912) (xy 270.536117 -292.874604) (xy 270.487262 -292.880536) (xy 270.438087 -292.878555)
			(xy 270.389868 -292.868711) (xy 270.343852 -292.851259) (xy 270.301231 -292.826652) (xy 270.26311 -292.795527)
			(xy 270.230475 -292.75869) (xy 270.204172 -292.717094) (xy 270.184881 -292.671818) (xy 270.173104 -292.624034)
			(xy 270.169144 -292.57498) (xy 269.830042 -292.57498) (xy 269.829547 -292.599587) (xy 269.821652 -292.648164)
			(xy 269.806068 -292.694845) (xy 269.783197 -292.738422) (xy 269.753632 -292.777766) (xy 269.718139 -292.811858)
			(xy 269.677636 -292.839814) (xy 269.633174 -292.860912) (xy 269.585903 -292.874604) (xy 269.537048 -292.880536)
			(xy 269.487873 -292.878555) (xy 269.439654 -292.868711) (xy 269.393638 -292.851259) (xy 269.351017 -292.826652)
			(xy 269.312896 -292.795527) (xy 269.280261 -292.75869) (xy 269.253958 -292.717094) (xy 269.234667 -292.671818)
			(xy 269.22289 -292.624034) (xy 269.21893 -292.57498) (xy 268.880082 -292.57498) (xy 268.879587 -292.599587)
			(xy 268.871692 -292.648164) (xy 268.856108 -292.694845) (xy 268.833237 -292.738422) (xy 268.803672 -292.777766)
			(xy 268.768179 -292.811858) (xy 268.727676 -292.839814) (xy 268.683214 -292.860912) (xy 268.635943 -292.874604)
			(xy 268.587088 -292.880536) (xy 268.537913 -292.878555) (xy 268.489694 -292.868711) (xy 268.443678 -292.851259)
			(xy 268.401057 -292.826652) (xy 268.362936 -292.795527) (xy 268.330301 -292.75869) (xy 268.303998 -292.717094)
			(xy 268.284707 -292.671818) (xy 268.27293 -292.624034) (xy 268.26897 -292.57498) (xy 267.482066 -292.57498)
			(xy 267.482066 -293.52494) (xy 270.169144 -293.52494) (xy 270.173104 -293.475886) (xy 270.184881 -293.428102)
			(xy 270.204172 -293.382826) (xy 270.230475 -293.34123) (xy 270.26311 -293.304393) (xy 270.301231 -293.273268)
			(xy 270.343852 -293.248661) (xy 270.389868 -293.231209) (xy 270.438087 -293.221365) (xy 270.487262 -293.219384)
			(xy 270.536117 -293.225316) (xy 270.583388 -293.239008) (xy 270.62785 -293.260106) (xy 270.668353 -293.288062)
			(xy 270.703846 -293.322154) (xy 270.733411 -293.361498) (xy 270.756282 -293.405075) (xy 270.771866 -293.451756)
			(xy 270.779761 -293.500333) (xy 270.780256 -293.52494) (xy 271.119104 -293.52494) (xy 271.123064 -293.475886)
			(xy 271.134841 -293.428102) (xy 271.154132 -293.382826) (xy 271.180435 -293.34123) (xy 271.21307 -293.304393)
			(xy 271.251191 -293.273268) (xy 271.293812 -293.248661) (xy 271.339828 -293.231209) (xy 271.388047 -293.221365)
			(xy 271.437222 -293.219384) (xy 271.486077 -293.225316) (xy 271.533348 -293.239008) (xy 271.57781 -293.260106)
			(xy 271.618313 -293.288062) (xy 271.653806 -293.322154) (xy 271.683371 -293.361498) (xy 271.706242 -293.405075)
			(xy 271.721826 -293.451756) (xy 271.729721 -293.500333) (xy 271.730216 -293.52494) (xy 272.069064 -293.52494)
			(xy 272.073024 -293.475886) (xy 272.084801 -293.428102) (xy 272.104092 -293.382826) (xy 272.130395 -293.34123)
			(xy 272.16303 -293.304393) (xy 272.201151 -293.273268) (xy 272.243772 -293.248661) (xy 272.289788 -293.231209)
			(xy 272.338007 -293.221365) (xy 272.387182 -293.219384) (xy 272.436037 -293.225316) (xy 272.483308 -293.239008)
			(xy 272.52777 -293.260106) (xy 272.568273 -293.288062) (xy 272.603766 -293.322154) (xy 272.633331 -293.361498)
			(xy 272.656202 -293.405075) (xy 272.671786 -293.451756) (xy 272.679681 -293.500333) (xy 272.680176 -293.52494)
			(xy 273.019024 -293.52494) (xy 273.022984 -293.475886) (xy 273.034761 -293.428102) (xy 273.054052 -293.382826)
			(xy 273.080355 -293.34123) (xy 273.11299 -293.304393) (xy 273.151111 -293.273268) (xy 273.193732 -293.248661)
			(xy 273.239748 -293.231209) (xy 273.287967 -293.221365) (xy 273.337142 -293.219384) (xy 273.385997 -293.225316)
			(xy 273.433268 -293.239008) (xy 273.47773 -293.260106) (xy 273.518233 -293.288062) (xy 273.553726 -293.322154)
			(xy 273.583291 -293.361498) (xy 273.606162 -293.405075) (xy 273.621746 -293.451756) (xy 273.629641 -293.500333)
			(xy 273.630136 -293.52494) (xy 273.968984 -293.52494) (xy 273.972944 -293.475886) (xy 273.984721 -293.428102)
			(xy 274.004012 -293.382826) (xy 274.030315 -293.34123) (xy 274.06295 -293.304393) (xy 274.101071 -293.273268)
			(xy 274.143692 -293.248661) (xy 274.189708 -293.231209) (xy 274.237927 -293.221365) (xy 274.287102 -293.219384)
			(xy 274.335957 -293.225316) (xy 274.383228 -293.239008) (xy 274.42769 -293.260106) (xy 274.468193 -293.288062)
			(xy 274.503686 -293.322154) (xy 274.533251 -293.361498) (xy 274.556122 -293.405075) (xy 274.571706 -293.451756)
			(xy 274.579601 -293.500333) (xy 274.580096 -293.52494) (xy 274.579601 -293.549547) (xy 274.579269 -293.551589)
			(xy 274.869138 -293.551589) (xy 274.869138 -293.498291) (xy 274.877081 -293.445587) (xy 274.892791 -293.394657)
			(xy 274.915917 -293.346636) (xy 274.945941 -293.302599) (xy 274.982193 -293.263528) (xy 275.023864 -293.230297)
			(xy 275.070022 -293.203648) (xy 275.119636 -293.184176) (xy 275.171598 -293.172316) (xy 275.224748 -293.168333)
			(xy 275.277898 -293.172316) (xy 275.32986 -293.184176) (xy 275.379474 -293.203648) (xy 275.425632 -293.230297)
			(xy 275.467303 -293.263528) (xy 275.503555 -293.302599) (xy 275.533579 -293.346636) (xy 275.556705 -293.394657)
			(xy 275.572415 -293.445587) (xy 275.580358 -293.498291) (xy 275.580856 -293.52494) (xy 275.868904 -293.52494)
			(xy 275.872864 -293.475886) (xy 275.884641 -293.428102) (xy 275.903932 -293.382826) (xy 275.930235 -293.34123)
			(xy 275.96287 -293.304393) (xy 276.000991 -293.273268) (xy 276.043612 -293.248661) (xy 276.089628 -293.231209)
			(xy 276.137847 -293.221365) (xy 276.187022 -293.219384) (xy 276.235877 -293.225316) (xy 276.283148 -293.239008)
			(xy 276.32761 -293.260106) (xy 276.368113 -293.288062) (xy 276.403606 -293.322154) (xy 276.433171 -293.361498)
			(xy 276.456042 -293.405075) (xy 276.471626 -293.451756) (xy 276.479521 -293.500333) (xy 276.480016 -293.52494)
			(xy 277.769078 -293.52494) (xy 277.773038 -293.475886) (xy 277.784815 -293.428102) (xy 277.804106 -293.382826)
			(xy 277.830409 -293.34123) (xy 277.863044 -293.304393) (xy 277.901165 -293.273268) (xy 277.943786 -293.248661)
			(xy 277.989802 -293.231209) (xy 278.038021 -293.221365) (xy 278.087196 -293.219384) (xy 278.136051 -293.225316)
			(xy 278.183322 -293.239008) (xy 278.227784 -293.260106) (xy 278.268287 -293.288062) (xy 278.30378 -293.322154)
			(xy 278.333345 -293.361498) (xy 278.356216 -293.405075) (xy 278.3718 -293.451756) (xy 278.379695 -293.500333)
			(xy 278.38019 -293.52494) (xy 278.379695 -293.549547) (xy 278.3718 -293.598124) (xy 278.356216 -293.644805)
			(xy 278.333345 -293.688382) (xy 278.30378 -293.727726) (xy 278.268287 -293.761818) (xy 278.227784 -293.789774)
			(xy 278.183322 -293.810872) (xy 278.136051 -293.824564) (xy 278.087196 -293.830496) (xy 278.038021 -293.828515)
			(xy 277.989802 -293.818671) (xy 277.943786 -293.801219) (xy 277.901165 -293.776612) (xy 277.863044 -293.745487)
			(xy 277.830409 -293.70865) (xy 277.804106 -293.667054) (xy 277.784815 -293.621778) (xy 277.773038 -293.573994)
			(xy 277.769078 -293.52494) (xy 276.480016 -293.52494) (xy 276.479521 -293.549547) (xy 276.471626 -293.598124)
			(xy 276.456042 -293.644805) (xy 276.433171 -293.688382) (xy 276.403606 -293.727726) (xy 276.368113 -293.761818)
			(xy 276.32761 -293.789774) (xy 276.283148 -293.810872) (xy 276.235877 -293.824564) (xy 276.187022 -293.830496)
			(xy 276.137847 -293.828515) (xy 276.089628 -293.818671) (xy 276.043612 -293.801219) (xy 276.000991 -293.776612)
			(xy 275.96287 -293.745487) (xy 275.930235 -293.70865) (xy 275.903932 -293.667054) (xy 275.884641 -293.621778)
			(xy 275.872864 -293.573994) (xy 275.868904 -293.52494) (xy 275.580856 -293.52494) (xy 275.580358 -293.551589)
			(xy 275.572415 -293.604293) (xy 275.556705 -293.655223) (xy 275.533579 -293.703244) (xy 275.503555 -293.747281)
			(xy 275.467303 -293.786352) (xy 275.425632 -293.819583) (xy 275.379474 -293.846232) (xy 275.32986 -293.865704)
			(xy 275.277898 -293.877564) (xy 275.224748 -293.881548) (xy 275.171598 -293.877564) (xy 275.119636 -293.865704)
			(xy 275.070022 -293.846232) (xy 275.023864 -293.819583) (xy 274.982193 -293.786352) (xy 274.945941 -293.747281)
			(xy 274.915917 -293.703244) (xy 274.892791 -293.655223) (xy 274.877081 -293.604293) (xy 274.869138 -293.551589)
			(xy 274.579269 -293.551589) (xy 274.571706 -293.598124) (xy 274.556122 -293.644805) (xy 274.533251 -293.688382)
			(xy 274.503686 -293.727726) (xy 274.468193 -293.761818) (xy 274.42769 -293.789774) (xy 274.383228 -293.810872)
			(xy 274.335957 -293.824564) (xy 274.287102 -293.830496) (xy 274.237927 -293.828515) (xy 274.189708 -293.818671)
			(xy 274.143692 -293.801219) (xy 274.101071 -293.776612) (xy 274.06295 -293.745487) (xy 274.030315 -293.70865)
			(xy 274.004012 -293.667054) (xy 273.984721 -293.621778) (xy 273.972944 -293.573994) (xy 273.968984 -293.52494)
			(xy 273.630136 -293.52494) (xy 273.629641 -293.549547) (xy 273.621746 -293.598124) (xy 273.606162 -293.644805)
			(xy 273.583291 -293.688382) (xy 273.553726 -293.727726) (xy 273.518233 -293.761818) (xy 273.47773 -293.789774)
			(xy 273.433268 -293.810872) (xy 273.385997 -293.824564) (xy 273.337142 -293.830496) (xy 273.287967 -293.828515)
			(xy 273.239748 -293.818671) (xy 273.193732 -293.801219) (xy 273.151111 -293.776612) (xy 273.11299 -293.745487)
			(xy 273.080355 -293.70865) (xy 273.054052 -293.667054) (xy 273.034761 -293.621778) (xy 273.022984 -293.573994)
			(xy 273.019024 -293.52494) (xy 272.680176 -293.52494) (xy 272.679681 -293.549547) (xy 272.671786 -293.598124)
			(xy 272.656202 -293.644805) (xy 272.633331 -293.688382) (xy 272.603766 -293.727726) (xy 272.568273 -293.761818)
			(xy 272.52777 -293.789774) (xy 272.483308 -293.810872) (xy 272.436037 -293.824564) (xy 272.387182 -293.830496)
			(xy 272.338007 -293.828515) (xy 272.289788 -293.818671) (xy 272.243772 -293.801219) (xy 272.201151 -293.776612)
			(xy 272.16303 -293.745487) (xy 272.130395 -293.70865) (xy 272.104092 -293.667054) (xy 272.084801 -293.621778)
			(xy 272.073024 -293.573994) (xy 272.069064 -293.52494) (xy 271.730216 -293.52494) (xy 271.729721 -293.549547)
			(xy 271.721826 -293.598124) (xy 271.706242 -293.644805) (xy 271.683371 -293.688382) (xy 271.653806 -293.727726)
			(xy 271.618313 -293.761818) (xy 271.57781 -293.789774) (xy 271.533348 -293.810872) (xy 271.486077 -293.824564)
			(xy 271.437222 -293.830496) (xy 271.388047 -293.828515) (xy 271.339828 -293.818671) (xy 271.293812 -293.801219)
			(xy 271.251191 -293.776612) (xy 271.21307 -293.745487) (xy 271.180435 -293.70865) (xy 271.154132 -293.667054)
			(xy 271.134841 -293.621778) (xy 271.123064 -293.573994) (xy 271.119104 -293.52494) (xy 270.780256 -293.52494)
			(xy 270.779761 -293.549547) (xy 270.771866 -293.598124) (xy 270.756282 -293.644805) (xy 270.733411 -293.688382)
			(xy 270.703846 -293.727726) (xy 270.668353 -293.761818) (xy 270.62785 -293.789774) (xy 270.583388 -293.810872)
			(xy 270.536117 -293.824564) (xy 270.487262 -293.830496) (xy 270.438087 -293.828515) (xy 270.389868 -293.818671)
			(xy 270.343852 -293.801219) (xy 270.301231 -293.776612) (xy 270.26311 -293.745487) (xy 270.230475 -293.70865)
			(xy 270.204172 -293.667054) (xy 270.184881 -293.621778) (xy 270.173104 -293.573994) (xy 270.169144 -293.52494)
			(xy 267.482066 -293.52494) (xy 267.482066 -294.4749) (xy 268.26897 -294.4749) (xy 268.27293 -294.425846)
			(xy 268.284707 -294.378062) (xy 268.303998 -294.332786) (xy 268.330301 -294.29119) (xy 268.362936 -294.254353)
			(xy 268.401057 -294.223228) (xy 268.443678 -294.198621) (xy 268.489694 -294.181169) (xy 268.537913 -294.171325)
			(xy 268.587088 -294.169344) (xy 268.635943 -294.175276) (xy 268.683214 -294.188968) (xy 268.727676 -294.210066)
			(xy 268.768179 -294.238022) (xy 268.803672 -294.272114) (xy 268.833237 -294.311458) (xy 268.856108 -294.355035)
			(xy 268.871692 -294.401716) (xy 268.879587 -294.450293) (xy 268.880082 -294.4749) (xy 269.21893 -294.4749)
			(xy 269.22289 -294.425846) (xy 269.234667 -294.378062) (xy 269.253958 -294.332786) (xy 269.280261 -294.29119)
			(xy 269.312896 -294.254353) (xy 269.351017 -294.223228) (xy 269.393638 -294.198621) (xy 269.439654 -294.181169)
			(xy 269.487873 -294.171325) (xy 269.537048 -294.169344) (xy 269.585903 -294.175276) (xy 269.633174 -294.188968)
			(xy 269.677636 -294.210066) (xy 269.718139 -294.238022) (xy 269.753632 -294.272114) (xy 269.783197 -294.311458)
			(xy 269.806068 -294.355035) (xy 269.821652 -294.401716) (xy 269.829547 -294.450293) (xy 269.830042 -294.4749)
			(xy 270.169144 -294.4749) (xy 270.173104 -294.425846) (xy 270.184881 -294.378062) (xy 270.204172 -294.332786)
			(xy 270.230475 -294.29119) (xy 270.26311 -294.254353) (xy 270.301231 -294.223228) (xy 270.343852 -294.198621)
			(xy 270.389868 -294.181169) (xy 270.438087 -294.171325) (xy 270.487262 -294.169344) (xy 270.536117 -294.175276)
			(xy 270.583388 -294.188968) (xy 270.62785 -294.210066) (xy 270.668353 -294.238022) (xy 270.703846 -294.272114)
			(xy 270.733411 -294.311458) (xy 270.756282 -294.355035) (xy 270.771866 -294.401716) (xy 270.779761 -294.450293)
			(xy 270.780256 -294.4749) (xy 273.019024 -294.4749) (xy 273.022984 -294.425846) (xy 273.034761 -294.378062)
			(xy 273.054052 -294.332786) (xy 273.080355 -294.29119) (xy 273.11299 -294.254353) (xy 273.151111 -294.223228)
			(xy 273.193732 -294.198621) (xy 273.239748 -294.181169) (xy 273.287967 -294.171325) (xy 273.337142 -294.169344)
			(xy 273.385997 -294.175276) (xy 273.433268 -294.188968) (xy 273.47773 -294.210066) (xy 273.518233 -294.238022)
			(xy 273.553726 -294.272114) (xy 273.583291 -294.311458) (xy 273.606162 -294.355035) (xy 273.621746 -294.401716)
			(xy 273.629641 -294.450293) (xy 273.630136 -294.4749) (xy 273.629641 -294.499507) (xy 273.629309 -294.501549)
			(xy 273.919178 -294.501549) (xy 273.919178 -294.448251) (xy 273.927121 -294.395547) (xy 273.942831 -294.344617)
			(xy 273.965957 -294.296596) (xy 273.995981 -294.252559) (xy 274.032233 -294.213488) (xy 274.073904 -294.180257)
			(xy 274.120062 -294.153608) (xy 274.169676 -294.134136) (xy 274.221638 -294.122276) (xy 274.274788 -294.118293)
			(xy 274.327938 -294.122276) (xy 274.3799 -294.134136) (xy 274.429514 -294.153608) (xy 274.475672 -294.180257)
			(xy 274.517343 -294.213488) (xy 274.553595 -294.252559) (xy 274.583619 -294.296596) (xy 274.606745 -294.344617)
			(xy 274.622455 -294.395547) (xy 274.630398 -294.448251) (xy 274.630896 -294.4749) (xy 274.918944 -294.4749)
			(xy 274.922904 -294.425846) (xy 274.934681 -294.378062) (xy 274.953972 -294.332786) (xy 274.980275 -294.29119)
			(xy 275.01291 -294.254353) (xy 275.051031 -294.223228) (xy 275.093652 -294.198621) (xy 275.139668 -294.181169)
			(xy 275.187887 -294.171325) (xy 275.237062 -294.169344) (xy 275.285917 -294.175276) (xy 275.333188 -294.188968)
			(xy 275.37765 -294.210066) (xy 275.418153 -294.238022) (xy 275.453646 -294.272114) (xy 275.483211 -294.311458)
			(xy 275.506082 -294.355035) (xy 275.521666 -294.401716) (xy 275.529561 -294.450293) (xy 275.530056 -294.4749)
			(xy 275.868904 -294.4749) (xy 275.872864 -294.425846) (xy 275.884641 -294.378062) (xy 275.903932 -294.332786)
			(xy 275.930235 -294.29119) (xy 275.96287 -294.254353) (xy 276.000991 -294.223228) (xy 276.043612 -294.198621)
			(xy 276.089628 -294.181169) (xy 276.137847 -294.171325) (xy 276.187022 -294.169344) (xy 276.235877 -294.175276)
			(xy 276.283148 -294.188968) (xy 276.32761 -294.210066) (xy 276.368113 -294.238022) (xy 276.403606 -294.272114)
			(xy 276.433171 -294.311458) (xy 276.456042 -294.355035) (xy 276.471626 -294.401716) (xy 276.479521 -294.450293)
			(xy 276.480016 -294.4749) (xy 277.769078 -294.4749) (xy 277.773038 -294.425846) (xy 277.784815 -294.378062)
			(xy 277.804106 -294.332786) (xy 277.830409 -294.29119) (xy 277.863044 -294.254353) (xy 277.901165 -294.223228)
			(xy 277.943786 -294.198621) (xy 277.989802 -294.181169) (xy 278.038021 -294.171325) (xy 278.087196 -294.169344)
			(xy 278.136051 -294.175276) (xy 278.183322 -294.188968) (xy 278.227784 -294.210066) (xy 278.268287 -294.238022)
			(xy 278.30378 -294.272114) (xy 278.333345 -294.311458) (xy 278.356216 -294.355035) (xy 278.3718 -294.401716)
			(xy 278.379695 -294.450293) (xy 278.38019 -294.4749) (xy 278.379695 -294.499507) (xy 278.3718 -294.548084)
			(xy 278.356216 -294.594765) (xy 278.333345 -294.638342) (xy 278.30378 -294.677686) (xy 278.268287 -294.711778)
			(xy 278.227784 -294.739734) (xy 278.183322 -294.760832) (xy 278.136051 -294.774524) (xy 278.087196 -294.780456)
			(xy 278.038021 -294.778475) (xy 277.989802 -294.768631) (xy 277.943786 -294.751179) (xy 277.901165 -294.726572)
			(xy 277.863044 -294.695447) (xy 277.830409 -294.65861) (xy 277.804106 -294.617014) (xy 277.784815 -294.571738)
			(xy 277.773038 -294.523954) (xy 277.769078 -294.4749) (xy 276.480016 -294.4749) (xy 276.479521 -294.499507)
			(xy 276.471626 -294.548084) (xy 276.456042 -294.594765) (xy 276.433171 -294.638342) (xy 276.403606 -294.677686)
			(xy 276.368113 -294.711778) (xy 276.32761 -294.739734) (xy 276.283148 -294.760832) (xy 276.235877 -294.774524)
			(xy 276.187022 -294.780456) (xy 276.137847 -294.778475) (xy 276.089628 -294.768631) (xy 276.043612 -294.751179)
			(xy 276.000991 -294.726572) (xy 275.96287 -294.695447) (xy 275.930235 -294.65861) (xy 275.903932 -294.617014)
			(xy 275.884641 -294.571738) (xy 275.872864 -294.523954) (xy 275.868904 -294.4749) (xy 275.530056 -294.4749)
			(xy 275.529561 -294.499507) (xy 275.521666 -294.548084) (xy 275.506082 -294.594765) (xy 275.483211 -294.638342)
			(xy 275.453646 -294.677686) (xy 275.418153 -294.711778) (xy 275.37765 -294.739734) (xy 275.333188 -294.760832)
			(xy 275.285917 -294.774524) (xy 275.237062 -294.780456) (xy 275.187887 -294.778475) (xy 275.139668 -294.768631)
			(xy 275.093652 -294.751179) (xy 275.051031 -294.726572) (xy 275.01291 -294.695447) (xy 274.980275 -294.65861)
			(xy 274.953972 -294.617014) (xy 274.934681 -294.571738) (xy 274.922904 -294.523954) (xy 274.918944 -294.4749)
			(xy 274.630896 -294.4749) (xy 274.630398 -294.501549) (xy 274.622455 -294.554253) (xy 274.606745 -294.605183)
			(xy 274.583619 -294.653204) (xy 274.553595 -294.697241) (xy 274.517343 -294.736312) (xy 274.475672 -294.769543)
			(xy 274.429514 -294.796192) (xy 274.3799 -294.815664) (xy 274.327938 -294.827524) (xy 274.274788 -294.831508)
			(xy 274.221638 -294.827524) (xy 274.169676 -294.815664) (xy 274.120062 -294.796192) (xy 274.073904 -294.769543)
			(xy 274.032233 -294.736312) (xy 273.995981 -294.697241) (xy 273.965957 -294.653204) (xy 273.942831 -294.605183)
			(xy 273.927121 -294.554253) (xy 273.919178 -294.501549) (xy 273.629309 -294.501549) (xy 273.621746 -294.548084)
			(xy 273.606162 -294.594765) (xy 273.583291 -294.638342) (xy 273.553726 -294.677686) (xy 273.518233 -294.711778)
			(xy 273.47773 -294.739734) (xy 273.433268 -294.760832) (xy 273.385997 -294.774524) (xy 273.337142 -294.780456)
			(xy 273.287967 -294.778475) (xy 273.239748 -294.768631) (xy 273.193732 -294.751179) (xy 273.151111 -294.726572)
			(xy 273.11299 -294.695447) (xy 273.080355 -294.65861) (xy 273.054052 -294.617014) (xy 273.034761 -294.571738)
			(xy 273.022984 -294.523954) (xy 273.019024 -294.4749) (xy 270.780256 -294.4749) (xy 270.779761 -294.499507)
			(xy 270.771866 -294.548084) (xy 270.756282 -294.594765) (xy 270.733411 -294.638342) (xy 270.703846 -294.677686)
			(xy 270.668353 -294.711778) (xy 270.62785 -294.739734) (xy 270.583388 -294.760832) (xy 270.536117 -294.774524)
			(xy 270.487262 -294.780456) (xy 270.438087 -294.778475) (xy 270.389868 -294.768631) (xy 270.343852 -294.751179)
			(xy 270.301231 -294.726572) (xy 270.26311 -294.695447) (xy 270.230475 -294.65861) (xy 270.204172 -294.617014)
			(xy 270.184881 -294.571738) (xy 270.173104 -294.523954) (xy 270.169144 -294.4749) (xy 269.830042 -294.4749)
			(xy 269.829547 -294.499507) (xy 269.821652 -294.548084) (xy 269.806068 -294.594765) (xy 269.783197 -294.638342)
			(xy 269.753632 -294.677686) (xy 269.718139 -294.711778) (xy 269.677636 -294.739734) (xy 269.633174 -294.760832)
			(xy 269.585903 -294.774524) (xy 269.537048 -294.780456) (xy 269.487873 -294.778475) (xy 269.439654 -294.768631)
			(xy 269.393638 -294.751179) (xy 269.351017 -294.726572) (xy 269.312896 -294.695447) (xy 269.280261 -294.65861)
			(xy 269.253958 -294.617014) (xy 269.234667 -294.571738) (xy 269.22289 -294.523954) (xy 269.21893 -294.4749)
			(xy 268.880082 -294.4749) (xy 268.879587 -294.499507) (xy 268.871692 -294.548084) (xy 268.856108 -294.594765)
			(xy 268.833237 -294.638342) (xy 268.803672 -294.677686) (xy 268.768179 -294.711778) (xy 268.727676 -294.739734)
			(xy 268.683214 -294.760832) (xy 268.635943 -294.774524) (xy 268.587088 -294.780456) (xy 268.537913 -294.778475)
			(xy 268.489694 -294.768631) (xy 268.443678 -294.751179) (xy 268.401057 -294.726572) (xy 268.362936 -294.695447)
			(xy 268.330301 -294.65861) (xy 268.303998 -294.617014) (xy 268.284707 -294.571738) (xy 268.27293 -294.523954)
			(xy 268.26897 -294.4749) (xy 267.482066 -294.4749) (xy 267.482066 -296.37482) (xy 269.219184 -296.37482)
			(xy 269.223144 -296.325766) (xy 269.234921 -296.277982) (xy 269.254212 -296.232706) (xy 269.280515 -296.19111)
			(xy 269.31315 -296.154273) (xy 269.351271 -296.123148) (xy 269.393892 -296.098541) (xy 269.439908 -296.081089)
			(xy 269.488127 -296.071245) (xy 269.537302 -296.069264) (xy 269.586157 -296.075196) (xy 269.633428 -296.088888)
			(xy 269.67789 -296.109986) (xy 269.718393 -296.137942) (xy 269.753886 -296.172034) (xy 269.783451 -296.211378)
			(xy 269.806322 -296.254955) (xy 269.821906 -296.301636) (xy 269.829801 -296.350213) (xy 269.830296 -296.37482)
			(xy 270.16889 -296.37482) (xy 270.17285 -296.325766) (xy 270.184627 -296.277982) (xy 270.203918 -296.232706)
			(xy 270.230221 -296.19111) (xy 270.262856 -296.154273) (xy 270.300977 -296.123148) (xy 270.343598 -296.098541)
			(xy 270.389614 -296.081089) (xy 270.437833 -296.071245) (xy 270.487008 -296.069264) (xy 270.535863 -296.075196)
			(xy 270.583134 -296.088888) (xy 270.627596 -296.109986) (xy 270.668099 -296.137942) (xy 270.703592 -296.172034)
			(xy 270.733157 -296.211378) (xy 270.756028 -296.254955) (xy 270.771612 -296.301636) (xy 270.779507 -296.350213)
			(xy 270.780002 -296.37482) (xy 271.119104 -296.37482) (xy 271.123064 -296.325766) (xy 271.134841 -296.277982)
			(xy 271.154132 -296.232706) (xy 271.180435 -296.19111) (xy 271.21307 -296.154273) (xy 271.251191 -296.123148)
			(xy 271.293812 -296.098541) (xy 271.339828 -296.081089) (xy 271.388047 -296.071245) (xy 271.437222 -296.069264)
			(xy 271.486077 -296.075196) (xy 271.533348 -296.088888) (xy 271.57781 -296.109986) (xy 271.618313 -296.137942)
			(xy 271.653806 -296.172034) (xy 271.683371 -296.211378) (xy 271.706242 -296.254955) (xy 271.721826 -296.301636)
			(xy 271.729721 -296.350213) (xy 271.730216 -296.37482) (xy 272.069064 -296.37482) (xy 272.073024 -296.325766)
			(xy 272.084801 -296.277982) (xy 272.104092 -296.232706) (xy 272.130395 -296.19111) (xy 272.16303 -296.154273)
			(xy 272.201151 -296.123148) (xy 272.243772 -296.098541) (xy 272.289788 -296.081089) (xy 272.338007 -296.071245)
			(xy 272.387182 -296.069264) (xy 272.436037 -296.075196) (xy 272.483308 -296.088888) (xy 272.52777 -296.109986)
			(xy 272.568273 -296.137942) (xy 272.603766 -296.172034) (xy 272.633331 -296.211378) (xy 272.656202 -296.254955)
			(xy 272.671786 -296.301636) (xy 272.679681 -296.350213) (xy 272.680176 -296.37482) (xy 273.968984 -296.37482)
			(xy 273.972944 -296.325766) (xy 273.984721 -296.277982) (xy 274.004012 -296.232706) (xy 274.030315 -296.19111)
			(xy 274.06295 -296.154273) (xy 274.101071 -296.123148) (xy 274.143692 -296.098541) (xy 274.189708 -296.081089)
			(xy 274.237927 -296.071245) (xy 274.287102 -296.069264) (xy 274.335957 -296.075196) (xy 274.383228 -296.088888)
			(xy 274.42769 -296.109986) (xy 274.468193 -296.137942) (xy 274.503686 -296.172034) (xy 274.533251 -296.211378)
			(xy 274.556122 -296.254955) (xy 274.571706 -296.301636) (xy 274.579601 -296.350213) (xy 274.580096 -296.37482)
			(xy 275.868904 -296.37482) (xy 275.872864 -296.325766) (xy 275.884641 -296.277982) (xy 275.903932 -296.232706)
			(xy 275.930235 -296.19111) (xy 275.96287 -296.154273) (xy 276.000991 -296.123148) (xy 276.043612 -296.098541)
			(xy 276.089628 -296.081089) (xy 276.137847 -296.071245) (xy 276.187022 -296.069264) (xy 276.235877 -296.075196)
			(xy 276.283148 -296.088888) (xy 276.32761 -296.109986) (xy 276.368113 -296.137942) (xy 276.403606 -296.172034)
			(xy 276.433171 -296.211378) (xy 276.456042 -296.254955) (xy 276.471626 -296.301636) (xy 276.479521 -296.350213)
			(xy 276.480016 -296.37482) (xy 277.769078 -296.37482) (xy 277.773038 -296.325766) (xy 277.784815 -296.277982)
			(xy 277.804106 -296.232706) (xy 277.830409 -296.19111) (xy 277.863044 -296.154273) (xy 277.901165 -296.123148)
			(xy 277.943786 -296.098541) (xy 277.989802 -296.081089) (xy 278.038021 -296.071245) (xy 278.087196 -296.069264)
			(xy 278.136051 -296.075196) (xy 278.183322 -296.088888) (xy 278.227784 -296.109986) (xy 278.268287 -296.137942)
			(xy 278.30378 -296.172034) (xy 278.333345 -296.211378) (xy 278.356216 -296.254955) (xy 278.3718 -296.301636)
			(xy 278.379695 -296.350213) (xy 278.38019 -296.37482) (xy 278.379695 -296.399427) (xy 278.3718 -296.448004)
			(xy 278.356216 -296.494685) (xy 278.333345 -296.538262) (xy 278.30378 -296.577606) (xy 278.268287 -296.611698)
			(xy 278.227784 -296.639654) (xy 278.183322 -296.660752) (xy 278.136051 -296.674444) (xy 278.087196 -296.680376)
			(xy 278.038021 -296.678395) (xy 277.989802 -296.668551) (xy 277.943786 -296.651099) (xy 277.901165 -296.626492)
			(xy 277.863044 -296.595367) (xy 277.830409 -296.55853) (xy 277.804106 -296.516934) (xy 277.784815 -296.471658)
			(xy 277.773038 -296.423874) (xy 277.769078 -296.37482) (xy 276.480016 -296.37482) (xy 276.479521 -296.399427)
			(xy 276.471626 -296.448004) (xy 276.456042 -296.494685) (xy 276.433171 -296.538262) (xy 276.403606 -296.577606)
			(xy 276.368113 -296.611698) (xy 276.32761 -296.639654) (xy 276.283148 -296.660752) (xy 276.235877 -296.674444)
			(xy 276.187022 -296.680376) (xy 276.137847 -296.678395) (xy 276.089628 -296.668551) (xy 276.043612 -296.651099)
			(xy 276.000991 -296.626492) (xy 275.96287 -296.595367) (xy 275.930235 -296.55853) (xy 275.903932 -296.516934)
			(xy 275.884641 -296.471658) (xy 275.872864 -296.423874) (xy 275.868904 -296.37482) (xy 274.580096 -296.37482)
			(xy 274.579601 -296.399427) (xy 274.571706 -296.448004) (xy 274.556122 -296.494685) (xy 274.533251 -296.538262)
			(xy 274.503686 -296.577606) (xy 274.468193 -296.611698) (xy 274.42769 -296.639654) (xy 274.383228 -296.660752)
			(xy 274.335957 -296.674444) (xy 274.287102 -296.680376) (xy 274.237927 -296.678395) (xy 274.189708 -296.668551)
			(xy 274.143692 -296.651099) (xy 274.101071 -296.626492) (xy 274.06295 -296.595367) (xy 274.030315 -296.55853)
			(xy 274.004012 -296.516934) (xy 273.984721 -296.471658) (xy 273.972944 -296.423874) (xy 273.968984 -296.37482)
			(xy 272.680176 -296.37482) (xy 272.679681 -296.399427) (xy 272.671786 -296.448004) (xy 272.656202 -296.494685)
			(xy 272.633331 -296.538262) (xy 272.603766 -296.577606) (xy 272.568273 -296.611698) (xy 272.52777 -296.639654)
			(xy 272.483308 -296.660752) (xy 272.436037 -296.674444) (xy 272.387182 -296.680376) (xy 272.338007 -296.678395)
			(xy 272.289788 -296.668551) (xy 272.243772 -296.651099) (xy 272.201151 -296.626492) (xy 272.16303 -296.595367)
			(xy 272.130395 -296.55853) (xy 272.104092 -296.516934) (xy 272.084801 -296.471658) (xy 272.073024 -296.423874)
			(xy 272.069064 -296.37482) (xy 271.730216 -296.37482) (xy 271.729721 -296.399427) (xy 271.721826 -296.448004)
			(xy 271.706242 -296.494685) (xy 271.683371 -296.538262) (xy 271.653806 -296.577606) (xy 271.618313 -296.611698)
			(xy 271.57781 -296.639654) (xy 271.533348 -296.660752) (xy 271.486077 -296.674444) (xy 271.437222 -296.680376)
			(xy 271.388047 -296.678395) (xy 271.339828 -296.668551) (xy 271.293812 -296.651099) (xy 271.251191 -296.626492)
			(xy 271.21307 -296.595367) (xy 271.180435 -296.55853) (xy 271.154132 -296.516934) (xy 271.134841 -296.471658)
			(xy 271.123064 -296.423874) (xy 271.119104 -296.37482) (xy 270.780002 -296.37482) (xy 270.779507 -296.399427)
			(xy 270.771612 -296.448004) (xy 270.756028 -296.494685) (xy 270.733157 -296.538262) (xy 270.703592 -296.577606)
			(xy 270.668099 -296.611698) (xy 270.627596 -296.639654) (xy 270.583134 -296.660752) (xy 270.535863 -296.674444)
			(xy 270.487008 -296.680376) (xy 270.437833 -296.678395) (xy 270.389614 -296.668551) (xy 270.343598 -296.651099)
			(xy 270.300977 -296.626492) (xy 270.262856 -296.595367) (xy 270.230221 -296.55853) (xy 270.203918 -296.516934)
			(xy 270.184627 -296.471658) (xy 270.17285 -296.423874) (xy 270.16889 -296.37482) (xy 269.830296 -296.37482)
			(xy 269.829801 -296.399427) (xy 269.821906 -296.448004) (xy 269.806322 -296.494685) (xy 269.783451 -296.538262)
			(xy 269.753886 -296.577606) (xy 269.718393 -296.611698) (xy 269.67789 -296.639654) (xy 269.633428 -296.660752)
			(xy 269.586157 -296.674444) (xy 269.537302 -296.680376) (xy 269.488127 -296.678395) (xy 269.439908 -296.668551)
			(xy 269.393892 -296.651099) (xy 269.351271 -296.626492) (xy 269.31315 -296.595367) (xy 269.280515 -296.55853)
			(xy 269.254212 -296.516934) (xy 269.234921 -296.471658) (xy 269.223144 -296.423874) (xy 269.219184 -296.37482)
			(xy 267.482066 -296.37482) (xy 267.482066 -297.3248) (xy 267.633949 -297.3248) (xy 267.63812 -297.274461)
			(xy 267.650519 -297.225496) (xy 267.670808 -297.179238) (xy 267.698434 -297.136951) (xy 267.732643 -297.099787)
			(xy 267.772502 -297.068761) (xy 267.816923 -297.044718) (xy 267.864697 -297.028313) (xy 267.914518 -297.019996)
			(xy 267.939774 -297.019472) (xy 267.965169 -297.019983) (xy 268.015259 -297.028397) (xy 268.063266 -297.044981)
			(xy 268.107868 -297.069279) (xy 268.147837 -297.100619) (xy 268.165326 -297.11904) (xy 268.172946 -297.127168)
			(xy 268.192758 -297.135804) (xy 268.292072 -297.13301) (xy 268.31163 -297.123612) (xy 268.318742 -297.114976)
			(xy 268.334531 -297.096404) (xy 268.370664 -297.063685) (xy 268.411205 -297.036618) (xy 268.455277 -297.01579)
			(xy 268.501928 -297.00165) (xy 268.550147 -296.994504) (xy 268.57452 -296.994072) (xy 269.52448 -296.994072)
			(xy 269.550469 -296.994594) (xy 269.601807 -297.002722) (xy 269.651241 -297.018781) (xy 269.697554 -297.042377)
			(xy 269.739606 -297.072927) (xy 269.77636 -297.109679) (xy 269.806913 -297.151729) (xy 269.830511 -297.198041)
			(xy 269.846573 -297.247474) (xy 269.854705 -297.298811) (xy 269.854705 -297.32478) (xy 270.16889 -297.32478)
			(xy 270.17285 -297.275726) (xy 270.184627 -297.227942) (xy 270.203918 -297.182666) (xy 270.230221 -297.14107)
			(xy 270.262856 -297.104233) (xy 270.300977 -297.073108) (xy 270.343598 -297.048501) (xy 270.389614 -297.031049)
			(xy 270.437833 -297.021205) (xy 270.487008 -297.019224) (xy 270.535863 -297.025156) (xy 270.583134 -297.038848)
			(xy 270.627596 -297.059946) (xy 270.668099 -297.087902) (xy 270.703592 -297.121994) (xy 270.733157 -297.161338)
			(xy 270.756028 -297.204915) (xy 270.771612 -297.251596) (xy 270.779507 -297.300173) (xy 270.780002 -297.32478)
			(xy 271.119104 -297.32478) (xy 271.123064 -297.275726) (xy 271.134841 -297.227942) (xy 271.154132 -297.182666)
			(xy 271.180435 -297.14107) (xy 271.21307 -297.104233) (xy 271.251191 -297.073108) (xy 271.293812 -297.048501)
			(xy 271.339828 -297.031049) (xy 271.388047 -297.021205) (xy 271.437222 -297.019224) (xy 271.486077 -297.025156)
			(xy 271.533348 -297.038848) (xy 271.57781 -297.059946) (xy 271.618313 -297.087902) (xy 271.653806 -297.121994)
			(xy 271.683371 -297.161338) (xy 271.706242 -297.204915) (xy 271.721826 -297.251596) (xy 271.729721 -297.300173)
			(xy 271.730216 -297.32478) (xy 273.968984 -297.32478) (xy 273.972944 -297.275726) (xy 273.984721 -297.227942)
			(xy 274.004012 -297.182666) (xy 274.030315 -297.14107) (xy 274.06295 -297.104233) (xy 274.101071 -297.073108)
			(xy 274.143692 -297.048501) (xy 274.189708 -297.031049) (xy 274.237927 -297.021205) (xy 274.287102 -297.019224)
			(xy 274.335957 -297.025156) (xy 274.383228 -297.038848) (xy 274.42769 -297.059946) (xy 274.468193 -297.087902)
			(xy 274.503686 -297.121994) (xy 274.533251 -297.161338) (xy 274.556122 -297.204915) (xy 274.571706 -297.251596)
			(xy 274.579601 -297.300173) (xy 274.580096 -297.32478) (xy 275.868904 -297.32478) (xy 275.872864 -297.275726)
			(xy 275.884641 -297.227942) (xy 275.903932 -297.182666) (xy 275.930235 -297.14107) (xy 275.96287 -297.104233)
			(xy 276.000991 -297.073108) (xy 276.043612 -297.048501) (xy 276.089628 -297.031049) (xy 276.137847 -297.021205)
			(xy 276.187022 -297.019224) (xy 276.235877 -297.025156) (xy 276.283148 -297.038848) (xy 276.32761 -297.059946)
			(xy 276.368113 -297.087902) (xy 276.403606 -297.121994) (xy 276.433171 -297.161338) (xy 276.456042 -297.204915)
			(xy 276.471626 -297.251596) (xy 276.479521 -297.300173) (xy 276.480016 -297.32478) (xy 276.819118 -297.32478)
			(xy 276.823078 -297.275726) (xy 276.834855 -297.227942) (xy 276.854146 -297.182666) (xy 276.880449 -297.14107)
			(xy 276.913084 -297.104233) (xy 276.951205 -297.073108) (xy 276.993826 -297.048501) (xy 277.039842 -297.031049)
			(xy 277.088061 -297.021205) (xy 277.137236 -297.019224) (xy 277.186091 -297.025156) (xy 277.233362 -297.038848)
			(xy 277.277824 -297.059946) (xy 277.318327 -297.087902) (xy 277.35382 -297.121994) (xy 277.383385 -297.161338)
			(xy 277.406256 -297.204915) (xy 277.42184 -297.251596) (xy 277.429735 -297.300173) (xy 277.43023 -297.32478)
			(xy 277.769078 -297.32478) (xy 277.773038 -297.275726) (xy 277.784815 -297.227942) (xy 277.804106 -297.182666)
			(xy 277.830409 -297.14107) (xy 277.863044 -297.104233) (xy 277.901165 -297.073108) (xy 277.943786 -297.048501)
			(xy 277.989802 -297.031049) (xy 278.038021 -297.021205) (xy 278.087196 -297.019224) (xy 278.136051 -297.025156)
			(xy 278.183322 -297.038848) (xy 278.227784 -297.059946) (xy 278.268287 -297.087902) (xy 278.30378 -297.121994)
			(xy 278.333345 -297.161338) (xy 278.356216 -297.204915) (xy 278.3718 -297.251596) (xy 278.379695 -297.300173)
			(xy 278.38019 -297.32478) (xy 278.379695 -297.349387) (xy 278.3718 -297.397964) (xy 278.356216 -297.444645)
			(xy 278.333345 -297.488222) (xy 278.30378 -297.527566) (xy 278.268287 -297.561658) (xy 278.227784 -297.589614)
			(xy 278.183322 -297.610712) (xy 278.136051 -297.624404) (xy 278.087196 -297.630336) (xy 278.038021 -297.628355)
			(xy 277.989802 -297.618511) (xy 277.943786 -297.601059) (xy 277.901165 -297.576452) (xy 277.863044 -297.545327)
			(xy 277.830409 -297.50849) (xy 277.804106 -297.466894) (xy 277.784815 -297.421618) (xy 277.773038 -297.373834)
			(xy 277.769078 -297.32478) (xy 277.43023 -297.32478) (xy 277.429735 -297.349387) (xy 277.42184 -297.397964)
			(xy 277.406256 -297.444645) (xy 277.383385 -297.488222) (xy 277.35382 -297.527566) (xy 277.318327 -297.561658)
			(xy 277.277824 -297.589614) (xy 277.233362 -297.610712) (xy 277.186091 -297.624404) (xy 277.137236 -297.630336)
			(xy 277.088061 -297.628355) (xy 277.039842 -297.618511) (xy 276.993826 -297.601059) (xy 276.951205 -297.576452)
			(xy 276.913084 -297.545327) (xy 276.880449 -297.50849) (xy 276.854146 -297.466894) (xy 276.834855 -297.421618)
			(xy 276.823078 -297.373834) (xy 276.819118 -297.32478) (xy 276.480016 -297.32478) (xy 276.479521 -297.349387)
			(xy 276.471626 -297.397964) (xy 276.456042 -297.444645) (xy 276.433171 -297.488222) (xy 276.403606 -297.527566)
			(xy 276.368113 -297.561658) (xy 276.32761 -297.589614) (xy 276.283148 -297.610712) (xy 276.235877 -297.624404)
			(xy 276.187022 -297.630336) (xy 276.137847 -297.628355) (xy 276.089628 -297.618511) (xy 276.043612 -297.601059)
			(xy 276.000991 -297.576452) (xy 275.96287 -297.545327) (xy 275.930235 -297.50849) (xy 275.903932 -297.466894)
			(xy 275.884641 -297.421618) (xy 275.872864 -297.373834) (xy 275.868904 -297.32478) (xy 274.580096 -297.32478)
			(xy 274.579601 -297.349387) (xy 274.571706 -297.397964) (xy 274.556122 -297.444645) (xy 274.533251 -297.488222)
			(xy 274.503686 -297.527566) (xy 274.468193 -297.561658) (xy 274.42769 -297.589614) (xy 274.383228 -297.610712)
			(xy 274.335957 -297.624404) (xy 274.287102 -297.630336) (xy 274.237927 -297.628355) (xy 274.189708 -297.618511)
			(xy 274.143692 -297.601059) (xy 274.101071 -297.576452) (xy 274.06295 -297.545327) (xy 274.030315 -297.50849)
			(xy 274.004012 -297.466894) (xy 273.984721 -297.421618) (xy 273.972944 -297.373834) (xy 273.968984 -297.32478)
			(xy 271.730216 -297.32478) (xy 271.729721 -297.349387) (xy 271.721826 -297.397964) (xy 271.706242 -297.444645)
			(xy 271.683371 -297.488222) (xy 271.653806 -297.527566) (xy 271.618313 -297.561658) (xy 271.57781 -297.589614)
			(xy 271.533348 -297.610712) (xy 271.486077 -297.624404) (xy 271.437222 -297.630336) (xy 271.388047 -297.628355)
			(xy 271.339828 -297.618511) (xy 271.293812 -297.601059) (xy 271.251191 -297.576452) (xy 271.21307 -297.545327)
			(xy 271.180435 -297.50849) (xy 271.154132 -297.466894) (xy 271.134841 -297.421618) (xy 271.123064 -297.373834)
			(xy 271.119104 -297.32478) (xy 270.780002 -297.32478) (xy 270.779507 -297.349387) (xy 270.771612 -297.397964)
			(xy 270.756028 -297.444645) (xy 270.733157 -297.488222) (xy 270.703592 -297.527566) (xy 270.668099 -297.561658)
			(xy 270.627596 -297.589614) (xy 270.583134 -297.610712) (xy 270.535863 -297.624404) (xy 270.487008 -297.630336)
			(xy 270.437833 -297.628355) (xy 270.389614 -297.618511) (xy 270.343598 -297.601059) (xy 270.300977 -297.576452)
			(xy 270.262856 -297.545327) (xy 270.230221 -297.50849) (xy 270.203918 -297.466894) (xy 270.184627 -297.421618)
			(xy 270.17285 -297.373834) (xy 270.16889 -297.32478) (xy 269.854705 -297.32478) (xy 269.854705 -297.350789)
			(xy 269.846573 -297.402126) (xy 269.830511 -297.451559) (xy 269.806913 -297.497871) (xy 269.77636 -297.539921)
			(xy 269.739606 -297.576673) (xy 269.697554 -297.607223) (xy 269.651241 -297.630819) (xy 269.601807 -297.646878)
			(xy 269.550469 -297.655006) (xy 269.52448 -297.655488) (xy 268.57452 -297.655488) (xy 268.550146 -297.655084)
			(xy 268.501926 -297.647935) (xy 268.455276 -297.63379) (xy 268.411206 -297.612953) (xy 268.370669 -297.585877)
			(xy 268.334544 -297.553147) (xy 268.318742 -297.534584) (xy 268.31163 -297.525948) (xy 268.292072 -297.51655)
			(xy 268.192758 -297.513756) (xy 268.172946 -297.522392) (xy 268.165326 -297.53052) (xy 268.14784 -297.548945)
			(xy 268.107876 -297.580296) (xy 268.063274 -297.604598) (xy 268.015264 -297.62118) (xy 267.965171 -297.629585)
			(xy 267.939774 -297.630088) (xy 267.914518 -297.629604) (xy 267.864697 -297.621287) (xy 267.816923 -297.604882)
			(xy 267.772502 -297.580839) (xy 267.732643 -297.549813) (xy 267.698434 -297.512649) (xy 267.670808 -297.470362)
			(xy 267.650519 -297.424104) (xy 267.63812 -297.375139) (xy 267.633949 -297.3248) (xy 267.482066 -297.3248)
			(xy 267.482066 -298.27474) (xy 269.218676 -298.27474) (xy 269.222636 -298.225686) (xy 269.234413 -298.177902)
			(xy 269.253704 -298.132626) (xy 269.280007 -298.09103) (xy 269.312642 -298.054193) (xy 269.350763 -298.023068)
			(xy 269.393384 -297.998461) (xy 269.4394 -297.981009) (xy 269.487619 -297.971165) (xy 269.536794 -297.969184)
			(xy 269.585649 -297.975116) (xy 269.63292 -297.988808) (xy 269.677382 -298.009906) (xy 269.717885 -298.037862)
			(xy 269.753378 -298.071954) (xy 269.782943 -298.111298) (xy 269.805814 -298.154875) (xy 269.821398 -298.201556)
			(xy 269.829293 -298.250133) (xy 269.829788 -298.27474) (xy 270.16889 -298.27474) (xy 270.17285 -298.225686)
			(xy 270.184627 -298.177902) (xy 270.203918 -298.132626) (xy 270.230221 -298.09103) (xy 270.262856 -298.054193)
			(xy 270.300977 -298.023068) (xy 270.343598 -297.998461) (xy 270.389614 -297.981009) (xy 270.437833 -297.971165)
			(xy 270.487008 -297.969184) (xy 270.535863 -297.975116) (xy 270.583134 -297.988808) (xy 270.627596 -298.009906)
			(xy 270.668099 -298.037862) (xy 270.703592 -298.071954) (xy 270.733157 -298.111298) (xy 270.756028 -298.154875)
			(xy 270.771612 -298.201556) (xy 270.779507 -298.250133) (xy 270.780002 -298.27474) (xy 271.119104 -298.27474)
			(xy 271.123064 -298.225686) (xy 271.134841 -298.177902) (xy 271.154132 -298.132626) (xy 271.180435 -298.09103)
			(xy 271.21307 -298.054193) (xy 271.251191 -298.023068) (xy 271.293812 -297.998461) (xy 271.339828 -297.981009)
			(xy 271.388047 -297.971165) (xy 271.437222 -297.969184) (xy 271.486077 -297.975116) (xy 271.533348 -297.988808)
			(xy 271.57781 -298.009906) (xy 271.618313 -298.037862) (xy 271.653806 -298.071954) (xy 271.683371 -298.111298)
			(xy 271.706242 -298.154875) (xy 271.721826 -298.201556) (xy 271.729721 -298.250133) (xy 271.730216 -298.27474)
			(xy 272.069064 -298.27474) (xy 272.073024 -298.225686) (xy 272.084801 -298.177902) (xy 272.104092 -298.132626)
			(xy 272.130395 -298.09103) (xy 272.16303 -298.054193) (xy 272.201151 -298.023068) (xy 272.243772 -297.998461)
			(xy 272.289788 -297.981009) (xy 272.338007 -297.971165) (xy 272.387182 -297.969184) (xy 272.436037 -297.975116)
			(xy 272.483308 -297.988808) (xy 272.52777 -298.009906) (xy 272.568273 -298.037862) (xy 272.603766 -298.071954)
			(xy 272.633331 -298.111298) (xy 272.656202 -298.154875) (xy 272.671786 -298.201556) (xy 272.679681 -298.250133)
			(xy 272.680176 -298.27474) (xy 273.019024 -298.27474) (xy 273.022984 -298.225686) (xy 273.034761 -298.177902)
			(xy 273.054052 -298.132626) (xy 273.080355 -298.09103) (xy 273.11299 -298.054193) (xy 273.151111 -298.023068)
			(xy 273.193732 -297.998461) (xy 273.239748 -297.981009) (xy 273.287967 -297.971165) (xy 273.337142 -297.969184)
			(xy 273.385997 -297.975116) (xy 273.433268 -297.988808) (xy 273.47773 -298.009906) (xy 273.518233 -298.037862)
			(xy 273.553726 -298.071954) (xy 273.583291 -298.111298) (xy 273.606162 -298.154875) (xy 273.621746 -298.201556)
			(xy 273.629641 -298.250133) (xy 273.630136 -298.27474) (xy 273.968984 -298.27474) (xy 273.972944 -298.225686)
			(xy 273.984721 -298.177902) (xy 274.004012 -298.132626) (xy 274.030315 -298.09103) (xy 274.06295 -298.054193)
			(xy 274.101071 -298.023068) (xy 274.143692 -297.998461) (xy 274.189708 -297.981009) (xy 274.237927 -297.971165)
			(xy 274.287102 -297.969184) (xy 274.335957 -297.975116) (xy 274.383228 -297.988808) (xy 274.42769 -298.009906)
			(xy 274.468193 -298.037862) (xy 274.503686 -298.071954) (xy 274.533251 -298.111298) (xy 274.556122 -298.154875)
			(xy 274.571706 -298.201556) (xy 274.579601 -298.250133) (xy 274.580096 -298.27474) (xy 275.868904 -298.27474)
			(xy 275.872864 -298.225686) (xy 275.884641 -298.177902) (xy 275.903932 -298.132626) (xy 275.930235 -298.09103)
			(xy 275.96287 -298.054193) (xy 276.000991 -298.023068) (xy 276.043612 -297.998461) (xy 276.089628 -297.981009)
			(xy 276.137847 -297.971165) (xy 276.187022 -297.969184) (xy 276.235877 -297.975116) (xy 276.283148 -297.988808)
			(xy 276.32761 -298.009906) (xy 276.368113 -298.037862) (xy 276.403606 -298.071954) (xy 276.433171 -298.111298)
			(xy 276.456042 -298.154875) (xy 276.471626 -298.201556) (xy 276.479521 -298.250133) (xy 276.480016 -298.27474)
			(xy 276.819118 -298.27474) (xy 276.823078 -298.225686) (xy 276.834855 -298.177902) (xy 276.854146 -298.132626)
			(xy 276.880449 -298.09103) (xy 276.913084 -298.054193) (xy 276.951205 -298.023068) (xy 276.993826 -297.998461)
			(xy 277.039842 -297.981009) (xy 277.088061 -297.971165) (xy 277.137236 -297.969184) (xy 277.186091 -297.975116)
			(xy 277.233362 -297.988808) (xy 277.277824 -298.009906) (xy 277.318327 -298.037862) (xy 277.35382 -298.071954)
			(xy 277.383385 -298.111298) (xy 277.406256 -298.154875) (xy 277.42184 -298.201556) (xy 277.429735 -298.250133)
			(xy 277.43023 -298.27474) (xy 277.769078 -298.27474) (xy 277.773038 -298.225686) (xy 277.784815 -298.177902)
			(xy 277.804106 -298.132626) (xy 277.830409 -298.09103) (xy 277.863044 -298.054193) (xy 277.901165 -298.023068)
			(xy 277.943786 -297.998461) (xy 277.989802 -297.981009) (xy 278.038021 -297.971165) (xy 278.087196 -297.969184)
			(xy 278.136051 -297.975116) (xy 278.183322 -297.988808) (xy 278.227784 -298.009906) (xy 278.268287 -298.037862)
			(xy 278.30378 -298.071954) (xy 278.333345 -298.111298) (xy 278.356216 -298.154875) (xy 278.3718 -298.201556)
			(xy 278.379695 -298.250133) (xy 278.38019 -298.27474) (xy 278.379695 -298.299347) (xy 278.3718 -298.347924)
			(xy 278.356216 -298.394605) (xy 278.333345 -298.438182) (xy 278.30378 -298.477526) (xy 278.268287 -298.511618)
			(xy 278.227784 -298.539574) (xy 278.183322 -298.560672) (xy 278.136051 -298.574364) (xy 278.087196 -298.580296)
			(xy 278.038021 -298.578315) (xy 277.989802 -298.568471) (xy 277.943786 -298.551019) (xy 277.901165 -298.526412)
			(xy 277.863044 -298.495287) (xy 277.830409 -298.45845) (xy 277.804106 -298.416854) (xy 277.784815 -298.371578)
			(xy 277.773038 -298.323794) (xy 277.769078 -298.27474) (xy 277.43023 -298.27474) (xy 277.429735 -298.299347)
			(xy 277.42184 -298.347924) (xy 277.406256 -298.394605) (xy 277.383385 -298.438182) (xy 277.35382 -298.477526)
			(xy 277.318327 -298.511618) (xy 277.277824 -298.539574) (xy 277.233362 -298.560672) (xy 277.186091 -298.574364)
			(xy 277.137236 -298.580296) (xy 277.088061 -298.578315) (xy 277.039842 -298.568471) (xy 276.993826 -298.551019)
			(xy 276.951205 -298.526412) (xy 276.913084 -298.495287) (xy 276.880449 -298.45845) (xy 276.854146 -298.416854)
			(xy 276.834855 -298.371578) (xy 276.823078 -298.323794) (xy 276.819118 -298.27474) (xy 276.480016 -298.27474)
			(xy 276.479521 -298.299347) (xy 276.471626 -298.347924) (xy 276.456042 -298.394605) (xy 276.433171 -298.438182)
			(xy 276.403606 -298.477526) (xy 276.368113 -298.511618) (xy 276.32761 -298.539574) (xy 276.283148 -298.560672)
			(xy 276.235877 -298.574364) (xy 276.187022 -298.580296) (xy 276.137847 -298.578315) (xy 276.089628 -298.568471)
			(xy 276.043612 -298.551019) (xy 276.000991 -298.526412) (xy 275.96287 -298.495287) (xy 275.930235 -298.45845)
			(xy 275.903932 -298.416854) (xy 275.884641 -298.371578) (xy 275.872864 -298.323794) (xy 275.868904 -298.27474)
			(xy 274.580096 -298.27474) (xy 274.579601 -298.299347) (xy 274.571706 -298.347924) (xy 274.556122 -298.394605)
			(xy 274.533251 -298.438182) (xy 274.503686 -298.477526) (xy 274.468193 -298.511618) (xy 274.42769 -298.539574)
			(xy 274.383228 -298.560672) (xy 274.335957 -298.574364) (xy 274.287102 -298.580296) (xy 274.237927 -298.578315)
			(xy 274.189708 -298.568471) (xy 274.143692 -298.551019) (xy 274.101071 -298.526412) (xy 274.06295 -298.495287)
			(xy 274.030315 -298.45845) (xy 274.004012 -298.416854) (xy 273.984721 -298.371578) (xy 273.972944 -298.323794)
			(xy 273.968984 -298.27474) (xy 273.630136 -298.27474) (xy 273.629641 -298.299347) (xy 273.621746 -298.347924)
			(xy 273.606162 -298.394605) (xy 273.583291 -298.438182) (xy 273.553726 -298.477526) (xy 273.518233 -298.511618)
			(xy 273.47773 -298.539574) (xy 273.433268 -298.560672) (xy 273.385997 -298.574364) (xy 273.337142 -298.580296)
			(xy 273.287967 -298.578315) (xy 273.239748 -298.568471) (xy 273.193732 -298.551019) (xy 273.151111 -298.526412)
			(xy 273.11299 -298.495287) (xy 273.080355 -298.45845) (xy 273.054052 -298.416854) (xy 273.034761 -298.371578)
			(xy 273.022984 -298.323794) (xy 273.019024 -298.27474) (xy 272.680176 -298.27474) (xy 272.679681 -298.299347)
			(xy 272.671786 -298.347924) (xy 272.656202 -298.394605) (xy 272.633331 -298.438182) (xy 272.603766 -298.477526)
			(xy 272.568273 -298.511618) (xy 272.52777 -298.539574) (xy 272.483308 -298.560672) (xy 272.436037 -298.574364)
			(xy 272.387182 -298.580296) (xy 272.338007 -298.578315) (xy 272.289788 -298.568471) (xy 272.243772 -298.551019)
			(xy 272.201151 -298.526412) (xy 272.16303 -298.495287) (xy 272.130395 -298.45845) (xy 272.104092 -298.416854)
			(xy 272.084801 -298.371578) (xy 272.073024 -298.323794) (xy 272.069064 -298.27474) (xy 271.730216 -298.27474)
			(xy 271.729721 -298.299347) (xy 271.721826 -298.347924) (xy 271.706242 -298.394605) (xy 271.683371 -298.438182)
			(xy 271.653806 -298.477526) (xy 271.618313 -298.511618) (xy 271.57781 -298.539574) (xy 271.533348 -298.560672)
			(xy 271.486077 -298.574364) (xy 271.437222 -298.580296) (xy 271.388047 -298.578315) (xy 271.339828 -298.568471)
			(xy 271.293812 -298.551019) (xy 271.251191 -298.526412) (xy 271.21307 -298.495287) (xy 271.180435 -298.45845)
			(xy 271.154132 -298.416854) (xy 271.134841 -298.371578) (xy 271.123064 -298.323794) (xy 271.119104 -298.27474)
			(xy 270.780002 -298.27474) (xy 270.779507 -298.299347) (xy 270.771612 -298.347924) (xy 270.756028 -298.394605)
			(xy 270.733157 -298.438182) (xy 270.703592 -298.477526) (xy 270.668099 -298.511618) (xy 270.627596 -298.539574)
			(xy 270.583134 -298.560672) (xy 270.535863 -298.574364) (xy 270.487008 -298.580296) (xy 270.437833 -298.578315)
			(xy 270.389614 -298.568471) (xy 270.343598 -298.551019) (xy 270.300977 -298.526412) (xy 270.262856 -298.495287)
			(xy 270.230221 -298.45845) (xy 270.203918 -298.416854) (xy 270.184627 -298.371578) (xy 270.17285 -298.323794)
			(xy 270.16889 -298.27474) (xy 269.829788 -298.27474) (xy 269.829293 -298.299347) (xy 269.821398 -298.347924)
			(xy 269.805814 -298.394605) (xy 269.782943 -298.438182) (xy 269.753378 -298.477526) (xy 269.717885 -298.511618)
			(xy 269.677382 -298.539574) (xy 269.63292 -298.560672) (xy 269.585649 -298.574364) (xy 269.536794 -298.580296)
			(xy 269.487619 -298.578315) (xy 269.4394 -298.568471) (xy 269.393384 -298.551019) (xy 269.350763 -298.526412)
			(xy 269.312642 -298.495287) (xy 269.280007 -298.45845) (xy 269.253704 -298.416854) (xy 269.234413 -298.371578)
			(xy 269.222636 -298.323794) (xy 269.218676 -298.27474) (xy 267.482066 -298.27474) (xy 267.482066 -299.2247)
			(xy 267.633969 -299.2247) (xy 267.63814 -299.174365) (xy 267.650538 -299.125402) (xy 267.670826 -299.079148)
			(xy 267.69845 -299.036863) (xy 267.732656 -298.999702) (xy 267.772513 -298.968678) (xy 267.816932 -298.944636)
			(xy 267.864702 -298.928233) (xy 267.91452 -298.919916) (xy 267.939774 -298.919392) (xy 267.96517 -298.919897)
			(xy 268.01526 -298.928312) (xy 268.063267 -298.944897) (xy 268.10787 -298.969196) (xy 268.147838 -299.000538)
			(xy 268.165326 -299.01896) (xy 268.172946 -299.027342) (xy 268.193012 -299.035724) (xy 268.292326 -299.033184)
			(xy 268.31163 -299.023786) (xy 268.318996 -299.014896) (xy 268.3348 -298.996366) (xy 268.370891 -298.963667)
			(xy 268.411384 -298.93661) (xy 268.455404 -298.915778) (xy 268.502001 -298.901621) (xy 268.55017 -298.894444)
			(xy 268.57452 -298.893992) (xy 269.52448 -298.893992) (xy 269.550487 -298.894566) (xy 269.60186 -298.9027)
			(xy 269.651328 -298.91877) (xy 269.697673 -298.942382) (xy 269.739754 -298.972953) (xy 269.776534 -299.009731)
			(xy 269.807108 -299.05181) (xy 269.830722 -299.098153) (xy 269.846796 -299.147621) (xy 269.854933 -299.198993)
			(xy 269.854933 -299.224954) (xy 270.16889 -299.224954) (xy 270.17285 -299.1759) (xy 270.184627 -299.128116)
			(xy 270.203918 -299.08284) (xy 270.230221 -299.041244) (xy 270.262856 -299.004407) (xy 270.300977 -298.973282)
			(xy 270.343598 -298.948675) (xy 270.389614 -298.931223) (xy 270.437833 -298.921379) (xy 270.487008 -298.919398)
			(xy 270.535863 -298.92533) (xy 270.583134 -298.939022) (xy 270.627596 -298.96012) (xy 270.668099 -298.988076)
			(xy 270.703592 -299.022168) (xy 270.733157 -299.061512) (xy 270.756028 -299.105089) (xy 270.771612 -299.15177)
			(xy 270.779507 -299.200347) (xy 270.780002 -299.224954) (xy 270.779507 -299.249561) (xy 270.779271 -299.251013)
			(xy 271.094376 -299.251013) (xy 271.094376 -299.198987) (xy 271.102514 -299.147601) (xy 271.118592 -299.098121)
			(xy 271.142212 -299.051765) (xy 271.172792 -299.009675) (xy 271.209581 -298.972887) (xy 271.251672 -298.942307)
			(xy 271.298028 -298.918689) (xy 271.347509 -298.902613) (xy 271.398895 -298.894475) (xy 271.424908 -298.893992)
			(xy 272.374868 -298.893992) (xy 272.400875 -298.894565) (xy 272.45225 -298.902697) (xy 272.50172 -298.918767)
			(xy 272.548067 -298.942378) (xy 272.590149 -298.972949) (xy 272.626931 -299.009727) (xy 272.657506 -299.051806)
			(xy 272.681121 -299.09815) (xy 272.697195 -299.147619) (xy 272.705333 -299.198993) (xy 272.705333 -299.224954)
			(xy 273.019024 -299.224954) (xy 273.022984 -299.1759) (xy 273.034761 -299.128116) (xy 273.054052 -299.08284)
			(xy 273.080355 -299.041244) (xy 273.11299 -299.004407) (xy 273.151111 -298.973282) (xy 273.193732 -298.948675)
			(xy 273.239748 -298.931223) (xy 273.287967 -298.921379) (xy 273.337142 -298.919398) (xy 273.385997 -298.92533)
			(xy 273.433268 -298.939022) (xy 273.47773 -298.96012) (xy 273.518233 -298.988076) (xy 273.553726 -299.022168)
			(xy 273.583291 -299.061512) (xy 273.606162 -299.105089) (xy 273.621746 -299.15177) (xy 273.629641 -299.200347)
			(xy 273.630136 -299.224954) (xy 273.629975 -299.232973) (xy 273.969093 -299.232973) (xy 273.971782 -299.183407)
			(xy 273.982454 -299.134928) (xy 274.000828 -299.088815) (xy 274.026421 -299.046282) (xy 274.058558 -299.008449)
			(xy 274.096391 -298.976314) (xy 274.138926 -298.950723) (xy 274.18504 -298.93235) (xy 274.233519 -298.92168)
			(xy 274.283085 -298.918993) (xy 274.332434 -298.924361) (xy 274.380263 -298.937641) (xy 274.425315 -298.958485)
			(xy 274.4664 -298.986342) (xy 274.502438 -299.020479) (xy 274.532478 -299.059997) (xy 274.55573 -299.103854)
			(xy 274.571579 -299.150895) (xy 274.57961 -299.19988) (xy 274.580096 -299.2247) (xy 274.580093 -299.224954)
			(xy 275.868904 -299.224954) (xy 275.872864 -299.1759) (xy 275.884641 -299.128116) (xy 275.903932 -299.08284)
			(xy 275.930235 -299.041244) (xy 275.96287 -299.004407) (xy 276.000991 -298.973282) (xy 276.043612 -298.948675)
			(xy 276.089628 -298.931223) (xy 276.137847 -298.921379) (xy 276.187022 -298.919398) (xy 276.235877 -298.92533)
			(xy 276.283148 -298.939022) (xy 276.32761 -298.96012) (xy 276.368113 -298.988076) (xy 276.403606 -299.022168)
			(xy 276.433171 -299.061512) (xy 276.456042 -299.105089) (xy 276.471626 -299.15177) (xy 276.479521 -299.200347)
			(xy 276.480016 -299.224954) (xy 276.819118 -299.224954) (xy 276.823078 -299.1759) (xy 276.834855 -299.128116)
			(xy 276.854146 -299.08284) (xy 276.880449 -299.041244) (xy 276.913084 -299.004407) (xy 276.951205 -298.973282)
			(xy 276.993826 -298.948675) (xy 277.039842 -298.931223) (xy 277.088061 -298.921379) (xy 277.137236 -298.919398)
			(xy 277.186091 -298.92533) (xy 277.233362 -298.939022) (xy 277.277824 -298.96012) (xy 277.318327 -298.988076)
			(xy 277.35382 -299.022168) (xy 277.383385 -299.061512) (xy 277.406256 -299.105089) (xy 277.42184 -299.15177)
			(xy 277.429735 -299.200347) (xy 277.43023 -299.224954) (xy 277.769078 -299.224954) (xy 277.773038 -299.1759)
			(xy 277.784815 -299.128116) (xy 277.804106 -299.08284) (xy 277.830409 -299.041244) (xy 277.863044 -299.004407)
			(xy 277.901165 -298.973282) (xy 277.943786 -298.948675) (xy 277.989802 -298.931223) (xy 278.038021 -298.921379)
			(xy 278.087196 -298.919398) (xy 278.136051 -298.92533) (xy 278.183322 -298.939022) (xy 278.227784 -298.96012)
			(xy 278.268287 -298.988076) (xy 278.30378 -299.022168) (xy 278.333345 -299.061512) (xy 278.356216 -299.105089)
			(xy 278.3718 -299.15177) (xy 278.379695 -299.200347) (xy 278.38019 -299.224954) (xy 278.379695 -299.249561)
			(xy 278.3718 -299.298138) (xy 278.356216 -299.344819) (xy 278.333345 -299.388396) (xy 278.30378 -299.42774)
			(xy 278.268287 -299.461832) (xy 278.227784 -299.489788) (xy 278.183322 -299.510886) (xy 278.136051 -299.524578)
			(xy 278.087196 -299.53051) (xy 278.038021 -299.528529) (xy 277.989802 -299.518685) (xy 277.943786 -299.501233)
			(xy 277.901165 -299.476626) (xy 277.863044 -299.445501) (xy 277.830409 -299.408664) (xy 277.804106 -299.367068)
			(xy 277.784815 -299.321792) (xy 277.773038 -299.274008) (xy 277.769078 -299.224954) (xy 277.43023 -299.224954)
			(xy 277.429735 -299.249561) (xy 277.42184 -299.298138) (xy 277.406256 -299.344819) (xy 277.383385 -299.388396)
			(xy 277.35382 -299.42774) (xy 277.318327 -299.461832) (xy 277.277824 -299.489788) (xy 277.233362 -299.510886)
			(xy 277.186091 -299.524578) (xy 277.137236 -299.53051) (xy 277.088061 -299.528529) (xy 277.039842 -299.518685)
			(xy 276.993826 -299.501233) (xy 276.951205 -299.476626) (xy 276.913084 -299.445501) (xy 276.880449 -299.408664)
			(xy 276.854146 -299.367068) (xy 276.834855 -299.321792) (xy 276.823078 -299.274008) (xy 276.819118 -299.224954)
			(xy 276.480016 -299.224954) (xy 276.479521 -299.249561) (xy 276.471626 -299.298138) (xy 276.456042 -299.344819)
			(xy 276.433171 -299.388396) (xy 276.403606 -299.42774) (xy 276.368113 -299.461832) (xy 276.32761 -299.489788)
			(xy 276.283148 -299.510886) (xy 276.235877 -299.524578) (xy 276.187022 -299.53051) (xy 276.137847 -299.528529)
			(xy 276.089628 -299.518685) (xy 276.043612 -299.501233) (xy 276.000991 -299.476626) (xy 275.96287 -299.445501)
			(xy 275.930235 -299.408664) (xy 275.903932 -299.367068) (xy 275.884641 -299.321792) (xy 275.872864 -299.274008)
			(xy 275.868904 -299.224954) (xy 274.580093 -299.224954) (xy 274.579922 -299.238946) (xy 274.577254 -299.267314)
			(xy 274.574762 -299.281342) (xy 274.572476 -299.293534) (xy 274.579842 -299.317664) (xy 274.657058 -299.39488)
			(xy 274.680934 -299.402246) (xy 274.69338 -299.39996) (xy 274.707345 -299.397477) (xy 274.735585 -299.394809)
			(xy 274.749768 -299.394626) (xy 274.773762 -299.395068) (xy 274.82116 -299.402571) (xy 274.8668 -299.417397)
			(xy 274.909558 -299.439181) (xy 274.948382 -299.467387) (xy 274.982314 -299.50132) (xy 275.01052 -299.540144)
			(xy 275.032304 -299.582902) (xy 275.04713 -299.628542) (xy 275.054632 -299.67594) (xy 275.055076 -299.699934)
			(xy 275.054905 -299.714117) (xy 275.052229 -299.742357) (xy 275.049742 -299.756322) (xy 275.047456 -299.768768)
			(xy 275.054822 -299.79239) (xy 275.132292 -299.86986) (xy 275.155914 -299.877226) (xy 275.16836 -299.87494)
			(xy 275.182325 -299.87246) (xy 275.210565 -299.86979) (xy 275.224748 -299.869606) (xy 275.248741 -299.870018)
			(xy 275.296136 -299.877532) (xy 275.341772 -299.892367) (xy 275.384526 -299.914158) (xy 275.423344 -299.942368)
			(xy 275.457272 -299.976303) (xy 275.485475 -300.015127) (xy 275.507257 -300.057886) (xy 275.522082 -300.103524)
			(xy 275.529586 -300.150921) (xy 275.530056 -300.174914) (xy 275.529882 -300.189097) (xy 275.527208 -300.217337)
			(xy 275.524722 -300.231302) (xy 275.522436 -300.243748) (xy 275.529802 -300.26737) (xy 275.607272 -300.34484)
			(xy 275.630894 -300.352206) (xy 275.64334 -300.34992) (xy 275.657306 -300.347442) (xy 275.685545 -300.344771)
			(xy 275.699728 -300.344586) (xy 275.713911 -300.344759) (xy 275.742151 -300.347433) (xy 275.756116 -300.34992)
			(xy 275.768562 -300.352206) (xy 275.792184 -300.34484) (xy 275.869654 -300.26737) (xy 275.87702 -300.243748)
			(xy 275.874734 -300.231302) (xy 275.872262 -300.217335) (xy 275.869587 -300.189096) (xy 275.8694 -300.174914)
			(xy 275.869863 -300.150092) (xy 275.877892 -300.101101) (xy 275.893741 -300.054055) (xy 275.916993 -300.010193)
			(xy 275.947035 -299.97067) (xy 275.983075 -299.936528) (xy 276.024164 -299.908667) (xy 276.069219 -299.88782)
			(xy 276.117053 -299.874537) (xy 276.166406 -299.869167) (xy 276.215977 -299.871853) (xy 276.264461 -299.882523)
			(xy 276.31058 -299.900897) (xy 276.353119 -299.92649) (xy 276.390957 -299.958627) (xy 276.423098 -299.996463)
			(xy 276.448693 -300.039) (xy 276.46707 -300.085118) (xy 276.477744 -300.133601) (xy 276.479985 -300.174914)
			(xy 276.819118 -300.174914) (xy 276.823078 -300.12586) (xy 276.834855 -300.078076) (xy 276.854146 -300.0328)
			(xy 276.880449 -299.991204) (xy 276.913084 -299.954367) (xy 276.951205 -299.923242) (xy 276.993826 -299.898635)
			(xy 277.039842 -299.881183) (xy 277.088061 -299.871339) (xy 277.137236 -299.869358) (xy 277.186091 -299.87529)
			(xy 277.233362 -299.888982) (xy 277.277824 -299.91008) (xy 277.318327 -299.938036) (xy 277.35382 -299.972128)
			(xy 277.383385 -300.011472) (xy 277.406256 -300.055049) (xy 277.42184 -300.10173) (xy 277.429735 -300.150307)
			(xy 277.43023 -300.174914) (xy 277.769078 -300.174914) (xy 277.773038 -300.12586) (xy 277.784815 -300.078076)
			(xy 277.804106 -300.0328) (xy 277.830409 -299.991204) (xy 277.863044 -299.954367) (xy 277.901165 -299.923242)
			(xy 277.943786 -299.898635) (xy 277.989802 -299.881183) (xy 278.038021 -299.871339) (xy 278.087196 -299.869358)
			(xy 278.136051 -299.87529) (xy 278.183322 -299.888982) (xy 278.227784 -299.91008) (xy 278.268287 -299.938036)
			(xy 278.30378 -299.972128) (xy 278.333345 -300.011472) (xy 278.356216 -300.055049) (xy 278.3718 -300.10173)
			(xy 278.379695 -300.150307) (xy 278.38019 -300.174914) (xy 278.379695 -300.199521) (xy 278.3718 -300.248098)
			(xy 278.356216 -300.294779) (xy 278.333345 -300.338356) (xy 278.30378 -300.3777) (xy 278.268287 -300.411792)
			(xy 278.227784 -300.439748) (xy 278.183322 -300.460846) (xy 278.136051 -300.474538) (xy 278.087196 -300.48047)
			(xy 278.038021 -300.478489) (xy 277.989802 -300.468645) (xy 277.943786 -300.451193) (xy 277.901165 -300.426586)
			(xy 277.863044 -300.395461) (xy 277.830409 -300.358624) (xy 277.804106 -300.317028) (xy 277.784815 -300.271752)
			(xy 277.773038 -300.223968) (xy 277.769078 -300.174914) (xy 277.43023 -300.174914) (xy 277.429735 -300.199521)
			(xy 277.42184 -300.248098) (xy 277.406256 -300.294779) (xy 277.383385 -300.338356) (xy 277.35382 -300.3777)
			(xy 277.318327 -300.411792) (xy 277.277824 -300.439748) (xy 277.233362 -300.460846) (xy 277.186091 -300.474538)
			(xy 277.137236 -300.48047) (xy 277.088061 -300.478489) (xy 277.039842 -300.468645) (xy 276.993826 -300.451193)
			(xy 276.951205 -300.426586) (xy 276.913084 -300.395461) (xy 276.880449 -300.358624) (xy 276.854146 -300.317028)
			(xy 276.834855 -300.271752) (xy 276.823078 -300.223968) (xy 276.819118 -300.174914) (xy 276.479985 -300.174914)
			(xy 276.480433 -300.183172) (xy 276.475067 -300.232525) (xy 276.461788 -300.280361) (xy 276.440944 -300.325417)
			(xy 276.413085 -300.366508) (xy 276.378946 -300.40255) (xy 276.339426 -300.432595) (xy 276.295565 -300.45585)
			(xy 276.24852 -300.471703) (xy 276.19953 -300.479735) (xy 276.174708 -300.480222) (xy 276.160525 -300.480044)
			(xy 276.132285 -300.477373) (xy 276.11832 -300.474888) (xy 276.105874 -300.472602) (xy 276.082252 -300.479968)
			(xy 276.004782 -300.557438) (xy 275.997416 -300.58106) (xy 275.999702 -300.593506) (xy 276.002175 -300.607472)
			(xy 276.004849 -300.635712) (xy 276.005036 -300.649894) (xy 276.004514 -300.675149) (xy 275.996201 -300.724971)
			(xy 275.9798 -300.772745) (xy 275.955759 -300.817168) (xy 275.924735 -300.857028) (xy 275.887573 -300.891238)
			(xy 275.845287 -300.918864) (xy 275.799031 -300.939154) (xy 275.750066 -300.951554) (xy 275.699728 -300.955725)
			(xy 275.64939 -300.951554) (xy 275.600425 -300.939154) (xy 275.554169 -300.918864) (xy 275.511883 -300.891238)
			(xy 275.474721 -300.857028) (xy 275.443697 -300.817168) (xy 275.419656 -300.772745) (xy 275.403255 -300.724971)
			(xy 275.394942 -300.675149) (xy 275.39442 -300.649894) (xy 275.394595 -300.635711) (xy 275.397268 -300.607471)
			(xy 275.399754 -300.593506) (xy 275.40204 -300.58106) (xy 275.394674 -300.557438) (xy 275.317204 -300.479968)
			(xy 275.293582 -300.472602) (xy 275.281136 -300.474888) (xy 275.267171 -300.477369) (xy 275.238931 -300.480038)
			(xy 275.224748 -300.480222) (xy 275.210565 -300.480038) (xy 275.182325 -300.477371) (xy 275.16836 -300.474888)
			(xy 275.155914 -300.472602) (xy 275.132292 -300.479968) (xy 275.054822 -300.557438) (xy 275.047456 -300.58106)
			(xy 275.049742 -300.593506) (xy 275.052215 -300.607472) (xy 275.054889 -300.635712) (xy 275.055076 -300.649894)
			(xy 275.054629 -300.674715) (xy 275.046599 -300.723703) (xy 275.030749 -300.770747) (xy 275.007498 -300.814606)
			(xy 274.977457 -300.854127) (xy 274.941418 -300.888267) (xy 274.900332 -300.916126) (xy 274.855279 -300.936972)
			(xy 274.807447 -300.950255) (xy 274.758096 -300.955624) (xy 274.708527 -300.952939) (xy 274.660046 -300.94227)
			(xy 274.613928 -300.923899) (xy 274.571391 -300.898308) (xy 274.533554 -300.866173) (xy 274.501414 -300.82834)
			(xy 274.475818 -300.785806) (xy 274.457441 -300.739691) (xy 274.446766 -300.69121) (xy 274.444075 -300.641642)
			(xy 274.449438 -300.59229) (xy 274.462715 -300.544457) (xy 274.483555 -300.499402) (xy 274.51141 -300.458311)
			(xy 274.545545 -300.422268) (xy 274.585062 -300.392223) (xy 274.628919 -300.368966) (xy 274.67596 -300.353111)
			(xy 274.724947 -300.345074) (xy 274.749768 -300.344586) (xy 274.763951 -300.344767) (xy 274.792191 -300.347436)
			(xy 274.806156 -300.34992) (xy 274.818602 -300.352206) (xy 274.842224 -300.34484) (xy 274.919694 -300.26737)
			(xy 274.92706 -300.243748) (xy 274.924774 -300.231302) (xy 274.922301 -300.217335) (xy 274.919627 -300.189096)
			(xy 274.91944 -300.174914) (xy 274.919618 -300.160731) (xy 274.922289 -300.132491) (xy 274.924774 -300.118526)
			(xy 274.92706 -300.10608) (xy 274.919694 -300.082458) (xy 274.842224 -300.004988) (xy 274.818602 -299.997622)
			(xy 274.806156 -299.999908) (xy 274.79219 -300.002387) (xy 274.763951 -300.005057) (xy 274.749768 -300.005242)
			(xy 274.725778 -300.004767) (xy 274.678388 -299.997257) (xy 274.632756 -299.982428) (xy 274.590006 -299.960643)
			(xy 274.551189 -299.93244) (xy 274.517262 -299.898512) (xy 274.489058 -299.859696) (xy 274.467273 -299.816945)
			(xy 274.452443 -299.771314) (xy 274.444933 -299.723924) (xy 274.44446 -299.699934) (xy 274.444619 -299.685687)
			(xy 274.447293 -299.657319) (xy 274.449794 -299.643292) (xy 274.45208 -299.6311) (xy 274.444714 -299.60697)
			(xy 274.367498 -299.529754) (xy 274.343622 -299.522388) (xy 274.331176 -299.524674) (xy 274.31721 -299.52715)
			(xy 274.28897 -299.529822) (xy 274.274788 -299.530008) (xy 274.249968 -299.529509) (xy 274.200983 -299.521477)
			(xy 274.153943 -299.505625) (xy 274.110087 -299.482372) (xy 274.07057 -299.45233) (xy 274.036434 -299.416291)
			(xy 274.008579 -299.375204) (xy 273.987737 -299.330152) (xy 273.974459 -299.282322) (xy 273.969093 -299.232973)
			(xy 273.629975 -299.232973) (xy 273.629641 -299.249561) (xy 273.621746 -299.298138) (xy 273.606162 -299.344819)
			(xy 273.583291 -299.388396) (xy 273.553726 -299.42774) (xy 273.518233 -299.461832) (xy 273.47773 -299.489788)
			(xy 273.433268 -299.510886) (xy 273.385997 -299.524578) (xy 273.337142 -299.53051) (xy 273.287967 -299.528529)
			(xy 273.239748 -299.518685) (xy 273.193732 -299.501233) (xy 273.151111 -299.476626) (xy 273.11299 -299.445501)
			(xy 273.080355 -299.408664) (xy 273.054052 -299.367068) (xy 273.034761 -299.321792) (xy 273.022984 -299.274008)
			(xy 273.019024 -299.224954) (xy 272.705333 -299.224954) (xy 272.705333 -299.251007) (xy 272.697195 -299.302381)
			(xy 272.681121 -299.35185) (xy 272.657506 -299.398194) (xy 272.626931 -299.440273) (xy 272.590149 -299.477051)
			(xy 272.548067 -299.507622) (xy 272.50172 -299.531233) (xy 272.45225 -299.547303) (xy 272.400875 -299.555435)
			(xy 272.374868 -299.555916) (xy 271.424908 -299.555916) (xy 271.398895 -299.555525) (xy 271.347509 -299.547387)
			(xy 271.298028 -299.531311) (xy 271.251672 -299.507693) (xy 271.209581 -299.477113) (xy 271.172792 -299.440325)
			(xy 271.142212 -299.398235) (xy 271.118592 -299.351879) (xy 271.102514 -299.302399) (xy 271.094376 -299.251013)
			(xy 270.779271 -299.251013) (xy 270.771612 -299.298138) (xy 270.756028 -299.344819) (xy 270.733157 -299.388396)
			(xy 270.703592 -299.42774) (xy 270.668099 -299.461832) (xy 270.627596 -299.489788) (xy 270.583134 -299.510886)
			(xy 270.535863 -299.524578) (xy 270.487008 -299.53051) (xy 270.437833 -299.528529) (xy 270.389614 -299.518685)
			(xy 270.343598 -299.501233) (xy 270.300977 -299.476626) (xy 270.262856 -299.445501) (xy 270.230221 -299.408664)
			(xy 270.203918 -299.367068) (xy 270.184627 -299.321792) (xy 270.17285 -299.274008) (xy 270.16889 -299.224954)
			(xy 269.854933 -299.224954) (xy 269.854933 -299.251007) (xy 269.846796 -299.302379) (xy 269.830722 -299.351847)
			(xy 269.807108 -299.39819) (xy 269.776534 -299.440269) (xy 269.739754 -299.477047) (xy 269.697673 -299.507618)
			(xy 269.651328 -299.53123) (xy 269.60186 -299.5473) (xy 269.550487 -299.555434) (xy 269.52448 -299.555916)
			(xy 268.57452 -299.555916) (xy 268.550136 -299.555482) (xy 268.501899 -299.548309) (xy 268.455238 -299.534129)
			(xy 268.411165 -299.513251) (xy 268.370636 -299.486128) (xy 268.334529 -299.453346) (xy 268.318742 -299.434758)
			(xy 268.31163 -299.426122) (xy 268.292072 -299.41647) (xy 268.192758 -299.41393) (xy 268.172692 -299.422312)
			(xy 268.165072 -299.430694) (xy 268.147587 -299.44907) (xy 268.107657 -299.480344) (xy 268.063104 -299.504585)
			(xy 268.015157 -299.521125) (xy 267.965134 -299.529508) (xy 267.939774 -299.530008) (xy 267.91452 -299.529484)
			(xy 267.864702 -299.521167) (xy 267.816932 -299.504764) (xy 267.772513 -299.480722) (xy 267.732656 -299.449698)
			(xy 267.69845 -299.412537) (xy 267.670826 -299.370252) (xy 267.650538 -299.323998) (xy 267.63814 -299.275035)
			(xy 267.633969 -299.2247) (xy 267.482066 -299.2247) (xy 267.482066 -300.641651) (xy 268.744074 -300.641651)
			(xy 268.749436 -300.5923) (xy 268.762711 -300.544467) (xy 268.783549 -300.499411) (xy 268.811402 -300.45832)
			(xy 268.845536 -300.422276) (xy 268.885051 -300.392229) (xy 268.928907 -300.368971) (xy 268.975947 -300.353114)
			(xy 269.024933 -300.345076) (xy 269.049754 -300.344586) (xy 269.063868 -300.34472) (xy 269.091979 -300.347267)
			(xy 269.105888 -300.349666) (xy 269.118588 -300.352206) (xy 269.14221 -300.34484) (xy 269.219426 -300.26737)
			(xy 269.226792 -300.243748) (xy 269.224506 -300.231302) (xy 269.222034 -300.217335) (xy 269.219359 -300.189096)
			(xy 269.219172 -300.174914) (xy 269.219694 -300.149659) (xy 269.228007 -300.099837) (xy 269.244408 -300.052063)
			(xy 269.268449 -300.00764) (xy 269.299473 -299.96778) (xy 269.336635 -299.93357) (xy 269.378921 -299.905944)
			(xy 269.425177 -299.885654) (xy 269.474142 -299.873254) (xy 269.52448 -299.869083) (xy 269.574818 -299.873254)
			(xy 269.623783 -299.885654) (xy 269.670039 -299.905944) (xy 269.712325 -299.93357) (xy 269.749487 -299.96778)
			(xy 269.780511 -300.00764) (xy 269.804552 -300.052063) (xy 269.820953 -300.099837) (xy 269.829266 -300.149659)
			(xy 269.829788 -300.174914) (xy 269.829614 -300.189097) (xy 269.82694 -300.217337) (xy 269.824454 -300.231302)
			(xy 269.822168 -300.243748) (xy 269.829534 -300.267624) (xy 269.90675 -300.34484) (xy 269.93088 -300.352206)
			(xy 269.943072 -300.34992) (xy 269.957102 -300.347441) (xy 269.985468 -300.344765) (xy 269.999714 -300.344586)
			(xy 270.013897 -300.344761) (xy 270.042137 -300.347434) (xy 270.056102 -300.34992) (xy 270.068548 -300.352206)
			(xy 270.09217 -300.34484) (xy 270.16964 -300.26737) (xy 270.177006 -300.243748) (xy 270.17472 -300.231302)
			(xy 270.172248 -300.217335) (xy 270.169573 -300.189096) (xy 270.169386 -300.174914) (xy 270.169908 -300.149659)
			(xy 270.178221 -300.099837) (xy 270.194622 -300.052063) (xy 270.218663 -300.00764) (xy 270.249687 -299.96778)
			(xy 270.286849 -299.93357) (xy 270.329135 -299.905944) (xy 270.375391 -299.885654) (xy 270.424356 -299.873254)
			(xy 270.474694 -299.869083) (xy 270.525032 -299.873254) (xy 270.573997 -299.885654) (xy 270.620253 -299.905944)
			(xy 270.662539 -299.93357) (xy 270.699701 -299.96778) (xy 270.730725 -300.00764) (xy 270.754766 -300.052063)
			(xy 270.771167 -300.099837) (xy 270.77948 -300.149659) (xy 270.780002 -300.174914) (xy 270.779827 -300.189097)
			(xy 270.777154 -300.217337) (xy 270.774668 -300.231302) (xy 270.772382 -300.243748) (xy 270.779748 -300.267624)
			(xy 270.856964 -300.34484) (xy 270.881094 -300.352206) (xy 270.893286 -300.34992) (xy 270.907315 -300.347439)
			(xy 270.935682 -300.344765) (xy 270.949928 -300.344586) (xy 270.964111 -300.344759) (xy 270.992351 -300.347433)
			(xy 271.006316 -300.34992) (xy 271.018762 -300.352206) (xy 271.042384 -300.34484) (xy 271.119854 -300.26737)
			(xy 271.12722 -300.243748) (xy 271.124934 -300.231302) (xy 271.122462 -300.217335) (xy 271.119787 -300.189096)
			(xy 271.1196 -300.174914) (xy 271.120122 -300.149659) (xy 271.128435 -300.099837) (xy 271.144836 -300.052063)
			(xy 271.168877 -300.00764) (xy 271.199901 -299.96778) (xy 271.237063 -299.93357) (xy 271.279349 -299.905944)
			(xy 271.325605 -299.885654) (xy 271.37457 -299.873254) (xy 271.424908 -299.869083) (xy 271.475246 -299.873254)
			(xy 271.524211 -299.885654) (xy 271.570467 -299.905944) (xy 271.612753 -299.93357) (xy 271.649915 -299.96778)
			(xy 271.680939 -300.00764) (xy 271.70498 -300.052063) (xy 271.721381 -300.099837) (xy 271.729694 -300.149659)
			(xy 271.730216 -300.174914) (xy 271.730041 -300.189097) (xy 271.727368 -300.217337) (xy 271.724882 -300.231302)
			(xy 271.722596 -300.243748) (xy 271.729962 -300.26737) (xy 271.807432 -300.34484) (xy 271.831054 -300.352206)
			(xy 271.8435 -300.34992) (xy 271.857467 -300.347448) (xy 271.885706 -300.344773) (xy 271.899888 -300.344586)
			(xy 271.914071 -300.344764) (xy 271.942311 -300.347435) (xy 271.956276 -300.34992) (xy 271.968722 -300.352206)
			(xy 271.992344 -300.34484) (xy 272.069814 -300.26737) (xy 272.07718 -300.243748) (xy 272.074894 -300.231302)
			(xy 272.072422 -300.217335) (xy 272.069747 -300.189096) (xy 272.06956 -300.174914) (xy 272.070082 -300.149659)
			(xy 272.078395 -300.099837) (xy 272.094796 -300.052063) (xy 272.118837 -300.00764) (xy 272.149861 -299.96778)
			(xy 272.187023 -299.93357) (xy 272.229309 -299.905944) (xy 272.275565 -299.885654) (xy 272.32453 -299.873254)
			(xy 272.374868 -299.869083) (xy 272.425206 -299.873254) (xy 272.474171 -299.885654) (xy 272.520427 -299.905944)
			(xy 272.562713 -299.93357) (xy 272.599875 -299.96778) (xy 272.630899 -300.00764) (xy 272.65494 -300.052063)
			(xy 272.671341 -300.099837) (xy 272.679654 -300.149659) (xy 272.680176 -300.174914) (xy 272.680002 -300.189097)
			(xy 272.677328 -300.217337) (xy 272.674842 -300.231302) (xy 272.672556 -300.243748) (xy 272.679922 -300.26737)
			(xy 272.757392 -300.34484) (xy 272.781014 -300.352206) (xy 272.79346 -300.34992) (xy 272.807425 -300.347439)
			(xy 272.835665 -300.34477) (xy 272.849848 -300.344586) (xy 272.864031 -300.34477) (xy 272.892271 -300.347437)
			(xy 272.906236 -300.34992) (xy 272.918682 -300.352206) (xy 272.942304 -300.34484) (xy 273.019774 -300.26737)
			(xy 273.02714 -300.243748) (xy 273.024854 -300.231302) (xy 273.022382 -300.217335) (xy 273.019707 -300.189096)
			(xy 273.01952 -300.174914) (xy 273.020042 -300.149659) (xy 273.028355 -300.099837) (xy 273.044756 -300.052063)
			(xy 273.068797 -300.00764) (xy 273.099821 -299.96778) (xy 273.136983 -299.93357) (xy 273.179269 -299.905944)
			(xy 273.225525 -299.885654) (xy 273.27449 -299.873254) (xy 273.324828 -299.869083) (xy 273.375166 -299.873254)
			(xy 273.424131 -299.885654) (xy 273.470387 -299.905944) (xy 273.512673 -299.93357) (xy 273.549835 -299.96778)
			(xy 273.580859 -300.00764) (xy 273.6049 -300.052063) (xy 273.621301 -300.099837) (xy 273.629614 -300.149659)
			(xy 273.630136 -300.174914) (xy 273.629961 -300.189097) (xy 273.627288 -300.217337) (xy 273.624802 -300.231302)
			(xy 273.622516 -300.243748) (xy 273.629882 -300.26737) (xy 273.707352 -300.34484) (xy 273.730974 -300.352206)
			(xy 273.74342 -300.34992) (xy 273.757386 -300.347445) (xy 273.785626 -300.344772) (xy 273.799808 -300.344586)
			(xy 273.824628 -300.345086) (xy 273.873614 -300.353119) (xy 273.920656 -300.36897) (xy 273.964513 -300.392223)
			(xy 274.004031 -300.422265) (xy 274.038167 -300.458305) (xy 274.066024 -300.499392) (xy 274.086866 -300.544445)
			(xy 274.100145 -300.592276) (xy 274.105511 -300.641626) (xy 274.102822 -300.691193) (xy 274.09215 -300.739673)
			(xy 274.073775 -300.785787) (xy 274.048182 -300.828321) (xy 274.016045 -300.866154) (xy 273.97821 -300.89829)
			(xy 273.935675 -300.923881) (xy 273.889559 -300.942254) (xy 273.841079 -300.952924) (xy 273.791512 -300.955611)
			(xy 273.742163 -300.950243) (xy 273.694332 -300.936961) (xy 273.64928 -300.916117) (xy 273.608194 -300.888259)
			(xy 273.572156 -300.85412) (xy 273.542116 -300.814601) (xy 273.518865 -300.770743) (xy 273.503015 -300.723701)
			(xy 273.494985 -300.674714) (xy 273.4945 -300.649894) (xy 273.494676 -300.635711) (xy 273.497348 -300.607471)
			(xy 273.499834 -300.593506) (xy 273.50212 -300.58106) (xy 273.494754 -300.557438) (xy 273.417284 -300.479968)
			(xy 273.393662 -300.472602) (xy 273.381216 -300.474888) (xy 273.367251 -300.477372) (xy 273.339011 -300.480039)
			(xy 273.324828 -300.480222) (xy 273.310645 -300.480041) (xy 273.282405 -300.477372) (xy 273.26844 -300.474888)
			(xy 273.255994 -300.472602) (xy 273.232372 -300.479968) (xy 273.154902 -300.557438) (xy 273.147536 -300.58106)
			(xy 273.149822 -300.593506) (xy 273.152296 -300.607472) (xy 273.154969 -300.635712) (xy 273.155156 -300.649894)
			(xy 273.154634 -300.675149) (xy 273.146321 -300.724971) (xy 273.12992 -300.772745) (xy 273.105879 -300.817168)
			(xy 273.074855 -300.857028) (xy 273.037693 -300.891238) (xy 272.995407 -300.918864) (xy 272.949151 -300.939154)
			(xy 272.900186 -300.951554) (xy 272.849848 -300.955725) (xy 272.79951 -300.951554) (xy 272.750545 -300.939154)
			(xy 272.704289 -300.918864) (xy 272.662003 -300.891238) (xy 272.624841 -300.857028) (xy 272.593817 -300.817168)
			(xy 272.569776 -300.772745) (xy 272.553375 -300.724971) (xy 272.545062 -300.675149) (xy 272.54454 -300.649894)
			(xy 272.544715 -300.635711) (xy 272.547388 -300.607471) (xy 272.549874 -300.593506) (xy 272.55216 -300.58106)
			(xy 272.544794 -300.557438) (xy 272.467324 -300.479968) (xy 272.443702 -300.472602) (xy 272.431256 -300.474888)
			(xy 272.41729 -300.477366) (xy 272.389051 -300.480037) (xy 272.374868 -300.480222) (xy 272.360685 -300.48005)
			(xy 272.332445 -300.477375) (xy 272.31848 -300.474888) (xy 272.306034 -300.472602) (xy 272.282412 -300.479968)
			(xy 272.204942 -300.557438) (xy 272.197576 -300.58106) (xy 272.199862 -300.593506) (xy 272.202335 -300.607472)
			(xy 272.205009 -300.635712) (xy 272.205196 -300.649894) (xy 272.204674 -300.675149) (xy 272.196361 -300.724971)
			(xy 272.17996 -300.772745) (xy 272.155919 -300.817168) (xy 272.124895 -300.857028) (xy 272.087733 -300.891238)
			(xy 272.045447 -300.918864) (xy 271.999191 -300.939154) (xy 271.950226 -300.951554) (xy 271.899888 -300.955725)
			(xy 271.84955 -300.951554) (xy 271.800585 -300.939154) (xy 271.754329 -300.918864) (xy 271.712043 -300.891238)
			(xy 271.674881 -300.857028) (xy 271.643857 -300.817168) (xy 271.619816 -300.772745) (xy 271.603415 -300.724971)
			(xy 271.595102 -300.675149) (xy 271.59458 -300.649894) (xy 271.594756 -300.635711) (xy 271.597429 -300.607471)
			(xy 271.599914 -300.593506) (xy 271.6022 -300.58106) (xy 271.594834 -300.557438) (xy 271.517364 -300.479968)
			(xy 271.493742 -300.472602) (xy 271.481296 -300.474888) (xy 271.46733 -300.477361) (xy 271.43909 -300.480035)
			(xy 271.424908 -300.480222) (xy 271.410725 -300.480044) (xy 271.382485 -300.477373) (xy 271.36852 -300.474888)
			(xy 271.356074 -300.472602) (xy 271.332452 -300.479968) (xy 271.254982 -300.557438) (xy 271.247616 -300.58106)
			(xy 271.249902 -300.593506) (xy 271.252375 -300.607472) (xy 271.255049 -300.635712) (xy 271.255236 -300.649894)
			(xy 271.254714 -300.675149) (xy 271.246401 -300.724971) (xy 271.23 -300.772745) (xy 271.205959 -300.817168)
			(xy 271.174935 -300.857028) (xy 271.137773 -300.891238) (xy 271.095487 -300.918864) (xy 271.049231 -300.939154)
			(xy 271.000266 -300.951554) (xy 270.949928 -300.955725) (xy 270.89959 -300.951554) (xy 270.850625 -300.939154)
			(xy 270.804369 -300.918864) (xy 270.762083 -300.891238) (xy 270.724921 -300.857028) (xy 270.693897 -300.817168)
			(xy 270.669856 -300.772745) (xy 270.653455 -300.724971) (xy 270.645142 -300.675149) (xy 270.64462 -300.649894)
			(xy 270.644795 -300.635711) (xy 270.647468 -300.607471) (xy 270.649954 -300.593506) (xy 270.65224 -300.58106)
			(xy 270.644874 -300.557184) (xy 270.567658 -300.479968) (xy 270.543528 -300.472602) (xy 270.531336 -300.474888)
			(xy 270.517308 -300.47738) (xy 270.48894 -300.480047) (xy 270.474694 -300.480222) (xy 270.460511 -300.480046)
			(xy 270.432271 -300.477373) (xy 270.418306 -300.474888) (xy 270.40586 -300.472602) (xy 270.382238 -300.479968)
			(xy 270.304768 -300.557438) (xy 270.297402 -300.58106) (xy 270.299688 -300.593506) (xy 270.302161 -300.607472)
			(xy 270.304835 -300.635712) (xy 270.305022 -300.649894) (xy 270.3045 -300.675149) (xy 270.296187 -300.724971)
			(xy 270.279786 -300.772745) (xy 270.255745 -300.817168) (xy 270.224721 -300.857028) (xy 270.187559 -300.891238)
			(xy 270.145273 -300.918864) (xy 270.099017 -300.939154) (xy 270.050052 -300.951554) (xy 269.999714 -300.955725)
			(xy 269.949376 -300.951554) (xy 269.900411 -300.939154) (xy 269.854155 -300.918864) (xy 269.811869 -300.891238)
			(xy 269.774707 -300.857028) (xy 269.743683 -300.817168) (xy 269.719642 -300.772745) (xy 269.703241 -300.724971)
			(xy 269.694928 -300.675149) (xy 269.694406 -300.649894) (xy 269.694582 -300.635711) (xy 269.697254 -300.607471)
			(xy 269.69974 -300.593506) (xy 269.702026 -300.58106) (xy 269.69466 -300.557184) (xy 269.617444 -300.479968)
			(xy 269.593314 -300.472602) (xy 269.581122 -300.474888) (xy 269.567092 -300.477368) (xy 269.538726 -300.480043)
			(xy 269.52448 -300.480222) (xy 269.510367 -300.480083) (xy 269.482255 -300.47754) (xy 269.468346 -300.475142)
			(xy 269.455646 -300.472602) (xy 269.432024 -300.479968) (xy 269.354808 -300.557438) (xy 269.347442 -300.58106)
			(xy 269.349728 -300.593506) (xy 269.352202 -300.607472) (xy 269.354875 -300.635712) (xy 269.355062 -300.649894)
			(xy 269.354629 -300.674715) (xy 269.346599 -300.723702) (xy 269.33075 -300.770745) (xy 269.307499 -300.814605)
			(xy 269.277458 -300.854125) (xy 269.241421 -300.888265) (xy 269.200334 -300.916125) (xy 269.155282 -300.936971)
			(xy 269.107451 -300.950254) (xy 269.058101 -300.955624) (xy 269.008532 -300.95294) (xy 268.960051 -300.942272)
			(xy 268.913934 -300.923901) (xy 268.871396 -300.898312) (xy 268.833559 -300.866178) (xy 268.801419 -300.828346)
			(xy 268.775822 -300.785813) (xy 268.757443 -300.739699) (xy 268.746767 -300.691219) (xy 268.744074 -300.641651)
			(xy 267.482066 -300.641651) (xy 267.482066 -301.083472) (xy 267.482504 -301.093535) (xy 267.490244 -301.112114)
			(xy 267.497052 -301.11954) (xy 267.941552 -301.56404) (xy 267.94895 -301.570885) (xy 267.967549 -301.57861)
			(xy 267.97762 -301.579026) (xy 268.7193 -301.579026)
		)
		(stroke
			(width 0)
			(type solid)
		)
		(fill yes)
		(layer "In15.Cu")
		(net "P1V8_PEX")
	)
	(gr_line
		(start 30.109922 -379.772164)
		(end 30.236922 -379.899164)
		(stroke
			(width 0.08255)
			(type default)
		)
		(layer "In15.Cu")
	)
	(gr_line
		(start 30.109922 -379.390148)
		(end 30.109922 -379.772164)
		(stroke
			(width 0.08255)
			(type default)
		)
		(layer "In15.Cu")
	)
	(gr_line
		(start 31.646876 -367.555272)
		(end 31.874714 -367.129314)
		(stroke
			(width 0.08255)
			(type default)
		)
		(layer "In15.Cu")
	)
	(gr_line
		(start 31.688024 -367.691162)
		(end 31.646876 -367.555272)
		(stroke
			(width 0.08255)
			(type default)
		)
		(layer "In15.Cu")
	)
	(gr_line
		(start 31.874714 -367.129314)
		(end 32.010604 -367.088166)
		(stroke
			(width 0.08255)
			(type default)
		)
		(layer "In15.Cu")
	)
	(gr_line
		(start 32.197802 -366.524794)
		(end 32.42564 -366.098836)
		(stroke
			(width 0.08255)
			(type default)
		)
		(layer "In15.Cu")
	)
	(gr_line
		(start 32.23895 -366.660684)
		(end 32.197802 -366.524794)
		(stroke
			(width 0.08255)
			(type default)
		)
		(layer "In15.Cu")
	)
	(gr_line
		(start 32.31007 -378.67209)
		(end 32.43707 -378.79909)
		(stroke
			(width 0.08255)
			(type default)
		)
		(layer "In15.Cu")
	)
	(gr_line
		(start 32.31007 -378.290074)
		(end 32.31007 -378.67209)
		(stroke
			(width 0.08255)
			(type default)
		)
		(layer "In15.Cu")
	)
	(gr_line
		(start 32.42564 -366.098836)
		(end 32.561276 -366.057688)
		(stroke
			(width 0.08255)
			(type default)
		)
		(layer "In15.Cu")
	)
	(gr_line
		(start 32.563054 -366.05718)
		(end 32.692086 -365.815626)
		(stroke
			(width 0.08255)
			(type default)
		)
		(layer "In15.Cu")
	)
	(gr_line
		(start 32.748728 -365.494316)
		(end 32.976566 -365.068358)
		(stroke
			(width 0.08255)
			(type default)
		)
		(layer "In15.Cu")
	)
	(gr_line
		(start 32.789876 -365.629952)
		(end 32.748728 -365.494316)
		(stroke
			(width 0.08255)
			(type default)
		)
		(layer "In15.Cu")
	)
	(gr_line
		(start 32.976566 -365.068358)
		(end 33.112202 -365.02721)
		(stroke
			(width 0.08255)
			(type default)
		)
		(layer "In15.Cu")
	)
	(gr_line
		(start 33.11398 -365.026702)
		(end 33.113726 -365.026702)
		(stroke
			(width 0.08255)
			(type default)
		)
		(layer "In15.Cu")
	)
	(gr_line
		(start 33.299654 -364.463838)
		(end 33.527492 -364.03788)
		(stroke
			(width 0.08255)
			(type default)
		)
		(layer "In15.Cu")
	)
	(gr_line
		(start 33.340802 -364.599474)
		(end 33.299654 -364.463838)
		(stroke
			(width 0.08255)
			(type default)
		)
		(layer "In15.Cu")
	)
	(gr_line
		(start 33.341056 -364.601252)
		(end 33.34131 -364.601252)
		(stroke
			(width 0.08255)
			(type default)
		)
		(layer "In15.Cu")
	)
	(gr_line
		(start 33.491424 -367.939066)
		(end 33.759648 -367.537492)
		(stroke
			(width 0.08255)
			(type default)
		)
		(layer "In15.Cu")
	)
	(gr_line
		(start 33.51911 -368.078512)
		(end 33.491424 -367.939066)
		(stroke
			(width 0.08255)
			(type default)
		)
		(layer "In15.Cu")
	)
	(gr_line
		(start 33.527492 -364.03788)
		(end 33.662874 -363.996732)
		(stroke
			(width 0.08255)
			(type default)
		)
		(layer "In15.Cu")
	)
	(gr_line
		(start 33.664906 -363.996224)
		(end 33.664652 -363.99597)
		(stroke
			(width 0.08255)
			(type default)
		)
		(layer "In15.Cu")
	)
	(gr_line
		(start 33.759648 -367.537492)
		(end 33.899094 -367.509806)
		(stroke
			(width 0.08255)
			(type default)
		)
		(layer "In15.Cu")
	)
	(gr_line
		(start 33.850326 -363.433106)
		(end 34.078164 -363.007148)
		(stroke
			(width 0.08255)
			(type default)
		)
		(layer "In15.Cu")
	)
	(gr_line
		(start 33.891474 -363.568996)
		(end 33.850326 -363.433106)
		(stroke
			(width 0.08255)
			(type default)
		)
		(layer "In15.Cu")
	)
	(gr_line
		(start 34.078164 -363.007148)
		(end 34.214054 -362.966)
		(stroke
			(width 0.08255)
			(type default)
		)
		(layer "In15.Cu")
	)
	(gr_line
		(start 34.140648 -366.967516)
		(end 34.408872 -366.565942)
		(stroke
			(width 0.08255)
			(type default)
		)
		(layer "In15.Cu")
	)
	(gr_line
		(start 34.168334 -367.106962)
		(end 34.140648 -366.967516)
		(stroke
			(width 0.08255)
			(type default)
		)
		(layer "In15.Cu")
	)
	(gr_line
		(start 34.408872 -366.565942)
		(end 34.548064 -366.538256)
		(stroke
			(width 0.08255)
			(type default)
		)
		(layer "In15.Cu")
	)
	(gr_line
		(start 34.789618 -365.995966)
		(end 35.058096 -365.594392)
		(stroke
			(width 0.08255)
			(type default)
		)
		(layer "In15.Cu")
	)
	(gr_line
		(start 34.817558 -366.135158)
		(end 34.789618 -365.995966)
		(stroke
			(width 0.08255)
			(type default)
		)
		(layer "In15.Cu")
	)
	(gr_line
		(start 35.058096 -365.594392)
		(end 35.197542 -365.566452)
		(stroke
			(width 0.08255)
			(type default)
		)
		(layer "In15.Cu")
	)
	(gr_line
		(start 35.438842 -365.024162)
		(end 35.70732 -364.622588)
		(stroke
			(width 0.08255)
			(type default)
		)
		(layer "In15.Cu")
	)
	(gr_line
		(start 35.466782 -365.163608)
		(end 35.438842 -365.024162)
		(stroke
			(width 0.08255)
			(type default)
		)
		(layer "In15.Cu")
	)
	(gr_line
		(start 35.70732 -364.622588)
		(end 35.846766 -364.594648)
		(stroke
			(width 0.08255)
			(type default)
		)
		(layer "In15.Cu")
	)
	(gr_line
		(start 36.95319 -362.6612)
		(end 37.201602 -362.246926)
		(stroke
			(width 0.08255)
			(type default)
		)
		(layer "In15.Cu")
	)
	(gr_line
		(start 36.987988 -362.799122)
		(end 36.95319 -362.6612)
		(stroke
			(width 0.08255)
			(type default)
		)
		(layer "In15.Cu")
	)
	(gr_line
		(start 37.201602 -362.246926)
		(end 37.339524 -362.212382)
		(stroke
			(width 0.08255)
			(type default)
		)
		(layer "In15.Cu")
	)
	(gr_line
		(start 37.554154 -361.658916)
		(end 37.802566 -361.244896)
		(stroke
			(width 0.08255)
			(type default)
		)
		(layer "In15.Cu")
	)
	(gr_line
		(start 37.588698 -361.797092)
		(end 37.554154 -361.658916)
		(stroke
			(width 0.08255)
			(type default)
		)
		(layer "In15.Cu")
	)
	(gr_line
		(start 37.802566 -361.244896)
		(end 37.940488 -361.210352)
		(stroke
			(width 0.08255)
			(type default)
		)
		(layer "In15.Cu")
	)
	(gr_line
		(start 38.155118 -360.656632)
		(end 38.40353 -360.242358)
		(stroke
			(width 0.08255)
			(type default)
		)
		(layer "In15.Cu")
	)
	(gr_line
		(start 38.189662 -360.794554)
		(end 38.155118 -360.656632)
		(stroke
			(width 0.08255)
			(type default)
		)
		(layer "In15.Cu")
	)
	(gr_line
		(start 38.40353 -360.242358)
		(end 38.541198 -360.208068)
		(stroke
			(width 0.08255)
			(type default)
		)
		(layer "In15.Cu")
	)
	(gr_line
		(start 38.542976 -360.20756)
		(end 38.542722 -360.207306)
		(stroke
			(width 0.08255)
			(type default)
		)
		(layer "In15.Cu")
	)
	(gr_line
		(start 38.755828 -359.654094)
		(end 39.00424 -359.240074)
		(stroke
			(width 0.08255)
			(type default)
		)
		(layer "In15.Cu")
	)
	(gr_line
		(start 38.790626 -359.79227)
		(end 38.755828 -359.654094)
		(stroke
			(width 0.08255)
			(type default)
		)
		(layer "In15.Cu")
	)
	(gr_line
		(start 39.00424 -359.240074)
		(end 39.142162 -359.205276)
		(stroke
			(width 0.08255)
			(type default)
		)
		(layer "In15.Cu")
	)
	(gr_line
		(start 47.71009 -397.972026)
		(end 47.582836 -398.09928)
		(stroke
			(width 0.08255)
			(type default)
		)
		(layer "In15.Cu")
	)
	(gr_line
		(start 47.71009 -397.59001)
		(end 47.71009 -397.972026)
		(stroke
			(width 0.08255)
			(type default)
		)
		(layer "In15.Cu")
	)
	(gr_line
		(start 47.71009 -372.457218)
		(end 47.71009 -372.890034)
		(stroke
			(width 0.08255)
			(type default)
		)
		(layer "In15.Cu")
	)
	(gr_line
		(start 47.71009 -372.022878)
		(end 47.71009 -371.590062)
		(stroke
			(width 0.08255)
			(type default)
		)
		(layer "In15.Cu")
	)
	(gr_line
		(start 47.78629 -372.381018)
		(end 47.71009 -372.457218)
		(stroke
			(width 0.08255)
			(type default)
		)
		(layer "In15.Cu")
	)
	(gr_line
		(start 47.78629 -372.099078)
		(end 47.71009 -372.022878)
		(stroke
			(width 0.08255)
			(type default)
		)
		(layer "In15.Cu")
	)
	(gr_line
		(start 48.316642 -394.572236)
		(end 48.448214 -394.626592)
		(stroke
			(width 0.08255)
			(type default)
		)
		(layer "In15.Cu")
	)
	(gr_line
		(start 48.448214 -394.626592)
		(end 48.894238 -394.441934)
		(stroke
			(width 0.08255)
			(type default)
		)
		(layer "In15.Cu")
	)
	(gr_line
		(start 48.894238 -394.441934)
		(end 48.94834 -394.310616)
		(stroke
			(width 0.08255)
			(type default)
		)
		(layer "In15.Cu")
	)
	(gr_line
		(start 48.949102 -394.308838)
		(end 48.949102 -394.309092)
		(stroke
			(width 0.08255)
			(type default)
		)
		(layer "In15.Cu")
	)
	(gr_line
		(start 49.396142 -394.125196)
		(end 49.527714 -394.179552)
		(stroke
			(width 0.08255)
			(type default)
		)
		(layer "In15.Cu")
	)
	(gr_line
		(start 49.527714 -394.179552)
		(end 49.973738 -393.994894)
		(stroke
			(width 0.08255)
			(type default)
		)
		(layer "In15.Cu")
	)
	(gr_line
		(start 49.973738 -393.994894)
		(end 50.02784 -393.863576)
		(stroke
			(width 0.08255)
			(type default)
		)
		(layer "In15.Cu")
	)
	(gr_line
		(start 50.028602 -393.861798)
		(end 50.028602 -393.862052)
		(stroke
			(width 0.08255)
			(type default)
		)
		(layer "In15.Cu")
	)
	(gr_line
		(start 50.475642 -393.678156)
		(end 50.607214 -393.732512)
		(stroke
			(width 0.08255)
			(type default)
		)
		(layer "In15.Cu")
	)
	(gr_line
		(start 50.607214 -393.732512)
		(end 51.053238 -393.547854)
		(stroke
			(width 0.08255)
			(type default)
		)
		(layer "In15.Cu")
	)
	(gr_line
		(start 51.053238 -393.547854)
		(end 51.10734 -393.416536)
		(stroke
			(width 0.08255)
			(type default)
		)
		(layer "In15.Cu")
	)
	(gr_line
		(start 51.108102 -393.414758)
		(end 51.108102 -393.415012)
		(stroke
			(width 0.08255)
			(type default)
		)
		(layer "In15.Cu")
	)
	(gr_line
		(start 52.834032 -393.151614)
		(end 52.944268 -393.267692)
		(stroke
			(width 0.08255)
			(type default)
		)
		(layer "In15.Cu")
	)
	(gr_line
		(start 52.944268 -393.267692)
		(end 53.426868 -393.279376)
		(stroke
			(width 0.08255)
			(type default)
		)
		(layer "In15.Cu")
	)
	(gr_line
		(start 53.426868 -393.279376)
		(end 53.542946 -393.168632)
		(stroke
			(width 0.08255)
			(type default)
		)
		(layer "In15.Cu")
	)
	(gr_line
		(start 54.278784 -393.186412)
		(end 54.389274 -393.302744)
		(stroke
			(width 0.08255)
			(type default)
		)
		(layer "In15.Cu")
	)
	(gr_line
		(start 54.348126 -371.310662)
		(end 54.057296 -371.019832)
		(stroke
			(width 0.08255)
			(type default)
		)
		(layer "In15.Cu")
	)
	(gr_line
		(start 54.348126 -370.447062)
		(end 54.057296 -370.737892)
		(stroke
			(width 0.08255)
			(type default)
		)
		(layer "In15.Cu")
	)
	(gr_line
		(start 54.389274 -393.302744)
		(end 54.872128 -393.314428)
		(stroke
			(width 0.08255)
			(type default)
		)
		(layer "In15.Cu")
	)
	(gr_line
		(start 54.872128 -393.314428)
		(end 54.98846 -393.203684)
		(stroke
			(width 0.08255)
			(type default)
		)
		(layer "In15.Cu")
	)
	(gr_line
		(start 55.472584 -393.215368)
		(end 55.583074 -393.3317)
		(stroke
			(width 0.08255)
			(type default)
		)
		(layer "In15.Cu")
	)
	(gr_line
		(start 55.583074 -393.3317)
		(end 56.065674 -393.343384)
		(stroke
			(width 0.08255)
			(type default)
		)
		(layer "In15.Cu")
	)
	(gr_line
		(start 56.065674 -393.343384)
		(end 56.18226 -393.232386)
		(stroke
			(width 0.08255)
			(type default)
		)
		(layer "In15.Cu")
	)
	(gr_line
		(start 56.665876 -393.24407)
		(end 56.77662 -393.360656)
		(stroke
			(width 0.08255)
			(type default)
		)
		(layer "In15.Cu")
	)
	(gr_line
		(start 56.77662 -393.360656)
		(end 57.25922 -393.37234)
		(stroke
			(width 0.08255)
			(type default)
		)
		(layer "In15.Cu")
	)
	(gr_line
		(start 57.25922 -393.37234)
		(end 57.375806 -393.261342)
		(stroke
			(width 0.08255)
			(type default)
		)
		(layer "In15.Cu")
	)
	(gr_line
		(start 57.886092 -393.273534)
		(end 57.99709 -393.390374)
		(stroke
			(width 0.08255)
			(type default)
		)
		(layer "In15.Cu")
	)
	(gr_line
		(start 57.99709 -393.390374)
		(end 58.479944 -393.401804)
		(stroke
			(width 0.08255)
			(type default)
		)
		(layer "In15.Cu")
	)
	(gr_line
		(start 58.479944 -393.401804)
		(end 58.596276 -393.290806)
		(stroke
			(width 0.08255)
			(type default)
		)
		(layer "In15.Cu")
	)
	(gr_line
		(start 59.079892 -393.30249)
		(end 59.190636 -393.419076)
		(stroke
			(width 0.08255)
			(type default)
		)
		(layer "In15.Cu")
	)
	(gr_line
		(start 59.190636 -393.419076)
		(end 59.673236 -393.43076)
		(stroke
			(width 0.08255)
			(type default)
		)
		(layer "In15.Cu")
	)
	(gr_line
		(start 59.673236 -393.43076)
		(end 59.790076 -393.319508)
		(stroke
			(width 0.08255)
			(type default)
		)
		(layer "In15.Cu")
	)
	(gr_line
		(start 60.273184 -393.331192)
		(end 60.384182 -393.448032)
		(stroke
			(width 0.08255)
			(type default)
		)
		(layer "In15.Cu")
	)
	(gr_line
		(start 60.384182 -393.448032)
		(end 60.866782 -393.459716)
		(stroke
			(width 0.08255)
			(type default)
		)
		(layer "In15.Cu")
	)
	(gr_line
		(start 60.866782 -393.459716)
		(end 60.983876 -393.34821)
		(stroke
			(width 0.08255)
			(type default)
		)
		(layer "In15.Cu")
	)
	(gr_line
		(start 75.770232 -393.705588)
		(end 75.880468 -393.821666)
		(stroke
			(width 0.08255)
			(type default)
		)
		(layer "In15.Cu")
	)
	(gr_line
		(start 75.880468 -393.821666)
		(end 76.363322 -393.83335)
		(stroke
			(width 0.08255)
			(type default)
		)
		(layer "In15.Cu")
	)
	(gr_line
		(start 76.363322 -393.83335)
		(end 76.479654 -393.722606)
		(stroke
			(width 0.08255)
			(type default)
		)
		(layer "In15.Cu")
	)
	(gr_line
		(start 78.286356 -393.765278)
		(end 78.286356 -393.765024)
		(stroke
			(width 0.08255)
			(type default)
		)
		(layer "In15.Cu")
	)
	(gr_line
		(start 78.287626 -393.766294)
		(end 78.397862 -393.882372)
		(stroke
			(width 0.08255)
			(type default)
		)
		(layer "In15.Cu")
	)
	(gr_line
		(start 78.397862 -393.882372)
		(end 78.880462 -393.894056)
		(stroke
			(width 0.08255)
			(type default)
		)
		(layer "In15.Cu")
	)
	(gr_line
		(start 78.880462 -393.894056)
		(end 78.99654 -393.783566)
		(stroke
			(width 0.08255)
			(type default)
		)
		(layer "In15.Cu")
	)
	(gr_line
		(start 79.479902 -393.79398)
		(end 79.479902 -393.793726)
		(stroke
			(width 0.08255)
			(type default)
		)
		(layer "In15.Cu")
	)
	(gr_line
		(start 79.481172 -393.79525)
		(end 79.591408 -393.911074)
		(stroke
			(width 0.08255)
			(type default)
		)
		(layer "In15.Cu")
	)
	(gr_line
		(start 79.591408 -393.911074)
		(end 80.074008 -393.922758)
		(stroke
			(width 0.08255)
			(type default)
		)
		(layer "In15.Cu")
	)
	(gr_line
		(start 79.89062 -309.199788)
		(end 79.59979 -309.199788)
		(stroke
			(width 0.05715)
			(type default)
		)
		(layer "In15.Cu")
	)
	(gr_line
		(start 79.97952 -309.288688)
		(end 79.89062 -309.199788)
		(stroke
			(width 0.05715)
			(type default)
		)
		(layer "In15.Cu")
	)
	(gr_line
		(start 80.074008 -393.922758)
		(end 80.190086 -393.812268)
		(stroke
			(width 0.08255)
			(type default)
		)
		(layer "In15.Cu")
	)
	(gr_line
		(start 80.674718 -393.823952)
		(end 80.784954 -393.94003)
		(stroke
			(width 0.08255)
			(type default)
		)
		(layer "In15.Cu")
	)
	(gr_line
		(start 80.784954 -393.94003)
		(end 81.267554 -393.95146)
		(stroke
			(width 0.08255)
			(type default)
		)
		(layer "In15.Cu")
	)
	(gr_line
		(start 81.267554 -393.95146)
		(end 81.383378 -393.84097)
		(stroke
			(width 0.08255)
			(type default)
		)
		(layer "In15.Cu")
	)
	(gr_line
		(start 81.790794 -310.149748)
		(end 81.499964 -310.149748)
		(stroke
			(width 0.05715)
			(type default)
		)
		(layer "In15.Cu")
	)
	(gr_line
		(start 81.879694 -310.238648)
		(end 81.790794 -310.149748)
		(stroke
			(width 0.05715)
			(type default)
		)
		(layer "In15.Cu")
	)
	(gr_line
		(start 82.069432 -393.856464)
		(end 82.069432 -393.85621)
		(stroke
			(width 0.08255)
			(type default)
		)
		(layer "In15.Cu")
	)
	(gr_line
		(start 82.070956 -393.857734)
		(end 82.180938 -393.973558)
		(stroke
			(width 0.08255)
			(type default)
		)
		(layer "In15.Cu")
	)
	(gr_line
		(start 82.180938 -393.973558)
		(end 82.663792 -393.985242)
		(stroke
			(width 0.08255)
			(type default)
		)
		(layer "In15.Cu")
	)
	(gr_line
		(start 82.663792 -393.985242)
		(end 82.77987 -393.874752)
		(stroke
			(width 0.08255)
			(type default)
		)
		(layer "In15.Cu")
	)
	(gr_line
		(start 83.314286 -311.11571)
		(end 83.314286 -311.051448)
		(stroke
			(width 0.05715)
			(type default)
		)
		(layer "In15.Cu")
	)
	(gr_line
		(start 83.334352 -311.135776)
		(end 83.314286 -311.11571)
		(stroke
			(width 0.05715)
			(type default)
		)
		(layer "In15.Cu")
	)
	(gr_line
		(start 83.6168 -309.815738)
		(end 83.57108 -309.770018)
		(stroke
			(width 0.05715)
			(type default)
		)
		(layer "In15.Cu")
	)
	(gr_line
		(start 83.645248 -309.815738)
		(end 83.6168 -309.815738)
		(stroke
			(width 0.05715)
			(type default)
		)
		(layer "In15.Cu")
	)
	(gr_line
		(start 84.150454 -393.906756)
		(end 84.150454 -393.906502)
		(stroke
			(width 0.08255)
			(type default)
		)
		(layer "In15.Cu")
	)
	(gr_line
		(start 84.151724 -393.908026)
		(end 84.26196 -394.02385)
		(stroke
			(width 0.08255)
			(type default)
		)
		(layer "In15.Cu")
	)
	(gr_line
		(start 84.26196 -394.02385)
		(end 84.744814 -394.03528)
		(stroke
			(width 0.08255)
			(type default)
		)
		(layer "In15.Cu")
	)
	(gr_line
		(start 84.744814 -394.03528)
		(end 84.860384 -393.925044)
		(stroke
			(width 0.08255)
			(type default)
		)
		(layer "In15.Cu")
	)
	(gr_line
		(start 84.861654 -393.923774)
		(end 84.861654 -393.924028)
		(stroke
			(width 0.08255)
			(type default)
		)
		(layer "In15.Cu")
	)
	(gr_line
		(start 85.800946 -393.946888)
		(end 85.8012 -393.94638)
		(stroke
			(width 0.08255)
			(type default)
		)
		(layer "In15.Cu")
	)
	(gr_line
		(start 85.80247 -393.947904)
		(end 85.912706 -394.063728)
		(stroke
			(width 0.08255)
			(type default)
		)
		(layer "In15.Cu")
	)
	(gr_line
		(start 85.912706 -394.063728)
		(end 86.395306 -394.075412)
		(stroke
			(width 0.08255)
			(type default)
		)
		(layer "In15.Cu")
	)
	(gr_line
		(start 86.395306 -394.075412)
		(end 86.511384 -393.964922)
		(stroke
			(width 0.08255)
			(type default)
		)
		(layer "In15.Cu")
	)
	(gr_line
		(start 89.53627 -394.00861)
		(end 89.6493 -394.12164)
		(stroke
			(width 0.08255)
			(type default)
		)
		(layer "In15.Cu")
	)
	(gr_line
		(start 89.6493 -394.12164)
		(end 90.1319 -394.12164)
		(stroke
			(width 0.08255)
			(type default)
		)
		(layer "In15.Cu")
	)
	(gr_line
		(start 90.1319 -394.12164)
		(end 90.24493 -394.00861)
		(stroke
			(width 0.08255)
			(type default)
		)
		(layer "In15.Cu")
	)
	(gr_line
		(start 91.710002 -397.97609)
		(end 91.710002 -397.59001)
		(stroke
			(width 0.08255)
			(type default)
		)
		(layer "In15.Cu")
	)
	(gr_line
		(start 91.831668 -398.097756)
		(end 91.710002 -397.97609)
		(stroke
			(width 0.08255)
			(type default)
		)
		(layer "In15.Cu")
	)
	(gr_line
		(start 92.124784 -394.944346)
		(end 92.466414 -395.285976)
		(stroke
			(width 0.08255)
			(type default)
		)
		(layer "In15.Cu")
	)
	(gr_line
		(start 92.124784 -394.784326)
		(end 92.124784 -394.944346)
		(stroke
			(width 0.08255)
			(type default)
		)
		(layer "In15.Cu")
	)
	(gr_line
		(start 92.466414 -395.285976)
		(end 92.62618 -395.285976)
		(stroke
			(width 0.08255)
			(type default)
		)
		(layer "In15.Cu")
	)
	(gr_line
		(start 115.202462 -339.874352)
		(end 115.202208 -339.874606)
		(stroke
			(width 0.08255)
			(type default)
		)
		(layer "In15.Cu")
	)
	(gr_line
		(start 115.202462 -339.874352)
		(end 115.969542 -339.730334)
		(stroke
			(width 0.08255)
			(type default)
		)
		(layer "In15.Cu")
	)
	(gr_line
		(start 115.340638 -392.889486)
		(end 115.299998 -392.791442)
		(stroke
			(width 0.08255)
			(type default)
		)
		(layer "In15.Cu")
	)
	(gr_line
		(start 115.7986 -393.079224)
		(end 115.340638 -392.889486)
		(stroke
			(width 0.08255)
			(type default)
		)
		(layer "In15.Cu")
	)
	(gr_line
		(start 115.896644 -393.038584)
		(end 115.7986 -393.079224)
		(stroke
			(width 0.08255)
			(type default)
		)
		(layer "In15.Cu")
	)
	(gr_line
		(start 116.006118 -392.777472)
		(end 115.40744 -392.529314)
		(stroke
			(width 0.08255)
			(type default)
		)
		(layer "In15.Cu")
	)
	(gr_line
		(start 116.39677 -393.326874)
		(end 116.35613 -393.229084)
		(stroke
			(width 0.08255)
			(type default)
		)
		(layer "In15.Cu")
	)
	(gr_line
		(start 116.854732 -393.516866)
		(end 116.39677 -393.326874)
		(stroke
			(width 0.08255)
			(type default)
		)
		(layer "In15.Cu")
	)
	(gr_line
		(start 116.952522 -393.476226)
		(end 116.854732 -393.516866)
		(stroke
			(width 0.08255)
			(type default)
		)
		(layer "In15.Cu")
	)
	(gr_line
		(start 117.044216 -393.512802)
		(end 116.9543 -393.475464)
		(stroke
			(width 0.08255)
			(type default)
		)
		(layer "In15.Cu")
	)
	(gr_line
		(start 117.06225 -393.215114)
		(end 116.463572 -392.966956)
		(stroke
			(width 0.08255)
			(type default)
		)
		(layer "In15.Cu")
	)
	(gr_line
		(start 117.152166 -393.252198)
		(end 117.06225 -393.215114)
		(stroke
			(width 0.08255)
			(type default)
		)
		(layer "In15.Cu")
	)
	(gr_line
		(start 117.822218 -394.123672)
		(end 117.822218 -394.041884)
		(stroke
			(width 0.08255)
			(type default)
		)
		(layer "In15.Cu")
	)
	(gr_line
		(start 118.11 -402.790152)
		(end 118.11 -402.465032)
		(stroke
			(width 0.08255)
			(type default)
		)
		(layer "In15.Cu")
	)
	(gr_line
		(start 118.11 -402.465032)
		(end 118.292626 -402.282406)
		(stroke
			(width 0.08255)
			(type default)
		)
		(layer "In15.Cu")
	)
	(gr_line
		(start 118.11 -401.872196)
		(end 118.237 -401.999196)
		(stroke
			(width 0.08255)
			(type default)
		)
		(layer "In15.Cu")
	)
	(gr_line
		(start 118.11 -401.49018)
		(end 118.11 -401.872196)
		(stroke
			(width 0.08255)
			(type default)
		)
		(layer "In15.Cu")
	)
	(gr_line
		(start 118.11 -371.972078)
		(end 118.237 -372.099078)
		(stroke
			(width 0.08255)
			(type default)
		)
		(layer "In15.Cu")
	)
	(gr_line
		(start 118.11 -371.590062)
		(end 118.11 -371.972078)
		(stroke
			(width 0.08255)
			(type default)
		)
		(layer "In15.Cu")
	)
	(gr_line
		(start 118.237 -401.999196)
		(end 118.293896 -401.999196)
		(stroke
			(width 0.08255)
			(type default)
		)
		(layer "In15.Cu")
	)
	(gr_line
		(start 118.25097 -394.552424)
		(end 117.822218 -394.123672)
		(stroke
			(width 0.08255)
			(type default)
		)
		(layer "In15.Cu")
	)
	(gr_line
		(start 118.332758 -394.552424)
		(end 118.25097 -394.552424)
		(stroke
			(width 0.08255)
			(type default)
		)
		(layer "In15.Cu")
	)
	(gr_line
		(start 118.533926 -394.353034)
		(end 118.021608 -393.840716)
		(stroke
			(width 0.08255)
			(type default)
		)
		(layer "In15.Cu")
	)
	(gr_line
		(start 118.984776 -398.67332)
		(end 118.984776 -398.672558)
		(stroke
			(width 0.08255)
			(type default)
		)
		(layer "In15.Cu")
	)
	(gr_line
		(start 119.267478 -398.79016)
		(end 119.267478 -398.789398)
		(stroke
			(width 0.08255)
			(type default)
		)
		(layer "In15.Cu")
	)
	(gr_line
		(start 120.310148 -370.872258)
		(end 120.437148 -370.999258)
		(stroke
			(width 0.08255)
			(type default)
		)
		(layer "In15.Cu")
	)
	(gr_line
		(start 120.310148 -370.489988)
		(end 120.310148 -370.872258)
		(stroke
			(width 0.08255)
			(type default)
		)
		(layer "In15.Cu")
	)
	(gr_line
		(start 122.510042 -371.972078)
		(end 122.637042 -372.099078)
		(stroke
			(width 0.08255)
			(type default)
		)
		(layer "In15.Cu")
	)
	(gr_line
		(start 122.510042 -371.590062)
		(end 122.510042 -371.972078)
		(stroke
			(width 0.08255)
			(type default)
		)
		(layer "In15.Cu")
	)
	(gr_line
		(start 126.910084 -371.972078)
		(end 127.037084 -372.099078)
		(stroke
			(width 0.08255)
			(type default)
		)
		(layer "In15.Cu")
	)
	(gr_line
		(start 126.910084 -371.590062)
		(end 126.910084 -371.972078)
		(stroke
			(width 0.08255)
			(type default)
		)
		(layer "In15.Cu")
	)
	(gr_line
		(start 129.109978 -370.872258)
		(end 129.236978 -370.999258)
		(stroke
			(width 0.08255)
			(type default)
		)
		(layer "In15.Cu")
	)
	(gr_line
		(start 129.109978 -370.489988)
		(end 129.109978 -370.872258)
		(stroke
			(width 0.08255)
			(type default)
		)
		(layer "In15.Cu")
	)
	(gr_line
		(start 130.019298 -361.40517)
		(end 130.052826 -361.295442)
		(stroke
			(width 0.08255)
			(type default)
		)
		(layer "In15.Cu")
	)
	(gr_line
		(start 130.052826 -361.295442)
		(end 130.546856 -361.032044)
		(stroke
			(width 0.08255)
			(type default)
		)
		(layer "In15.Cu")
	)
	(gr_line
		(start 130.546856 -361.032044)
		(end 130.656584 -361.065572)
		(stroke
			(width 0.08255)
			(type default)
		)
		(layer "In15.Cu")
	)
	(gr_line
		(start 131.095496 -360.831638)
		(end 131.136898 -360.695494)
		(stroke
			(width 0.08255)
			(type default)
		)
		(layer "In15.Cu")
	)
	(gr_line
		(start 131.136898 -360.695494)
		(end 131.574286 -360.462322)
		(stroke
			(width 0.08255)
			(type default)
		)
		(layer "In15.Cu")
	)
	(gr_line
		(start 131.167378 -362.503466)
		(end 131.210304 -362.36783)
		(stroke
			(width 0.08255)
			(type default)
		)
		(layer "In15.Cu")
	)
	(gr_line
		(start 131.210304 -362.36783)
		(end 131.650232 -362.139484)
		(stroke
			(width 0.08255)
			(type default)
		)
		(layer "In15.Cu")
	)
	(gr_line
		(start 131.310126 -371.972078)
		(end 131.437126 -372.099078)
		(stroke
			(width 0.08255)
			(type default)
		)
		(layer "In15.Cu")
	)
	(gr_line
		(start 131.310126 -371.590062)
		(end 131.310126 -371.972078)
		(stroke
			(width 0.08255)
			(type default)
		)
		(layer "In15.Cu")
	)
	(gr_line
		(start 131.574286 -360.462322)
		(end 131.71043 -360.503978)
		(stroke
			(width 0.08255)
			(type default)
		)
		(layer "In15.Cu")
	)
	(gr_line
		(start 131.650232 -362.139484)
		(end 131.785868 -362.182156)
		(stroke
			(width 0.08255)
			(type default)
		)
		(layer "In15.Cu")
	)
	(gr_line
		(start 132.148834 -360.270298)
		(end 132.19049 -360.1339)
		(stroke
			(width 0.08255)
			(type default)
		)
		(layer "In15.Cu")
	)
	(gr_line
		(start 132.19049 -360.1339)
		(end 132.627878 -359.900728)
		(stroke
			(width 0.08255)
			(type default)
		)
		(layer "In15.Cu")
	)
	(gr_line
		(start 132.226812 -361.953302)
		(end 132.269992 -361.817666)
		(stroke
			(width 0.08255)
			(type default)
		)
		(layer "In15.Cu")
	)
	(gr_line
		(start 132.269992 -361.817666)
		(end 132.70992 -361.58932)
		(stroke
			(width 0.08255)
			(type default)
		)
		(layer "In15.Cu")
	)
	(gr_line
		(start 132.3848 -363.313726)
		(end 132.430266 -363.179106)
		(stroke
			(width 0.08255)
			(type default)
		)
		(layer "In15.Cu")
	)
	(gr_line
		(start 132.430266 -363.179106)
		(end 132.874766 -362.959396)
		(stroke
			(width 0.08255)
			(type default)
		)
		(layer "In15.Cu")
	)
	(gr_line
		(start 132.627878 -359.900728)
		(end 132.764276 -359.942384)
		(stroke
			(width 0.08255)
			(type default)
		)
		(layer "In15.Cu")
	)
	(gr_line
		(start 132.70992 -361.58932)
		(end 132.84581 -361.632246)
		(stroke
			(width 0.08255)
			(type default)
		)
		(layer "In15.Cu")
	)
	(gr_line
		(start 132.874766 -362.959396)
		(end 133.009386 -363.005116)
		(stroke
			(width 0.08255)
			(type default)
		)
		(layer "In15.Cu")
	)
	(gr_line
		(start 133.2865 -361.403392)
		(end 133.32968 -361.267502)
		(stroke
			(width 0.08255)
			(type default)
		)
		(layer "In15.Cu")
	)
	(gr_line
		(start 133.32968 -361.267502)
		(end 133.769608 -361.039156)
		(stroke
			(width 0.08255)
			(type default)
		)
		(layer "In15.Cu")
	)
	(gr_line
		(start 133.455156 -362.784644)
		(end 133.500622 -362.650278)
		(stroke
			(width 0.08255)
			(type default)
		)
		(layer "In15.Cu")
	)
	(gr_line
		(start 133.500622 -362.650278)
		(end 133.944868 -362.430568)
		(stroke
			(width 0.08255)
			(type default)
		)
		(layer "In15.Cu")
	)
	(gr_line
		(start 133.769608 -361.039156)
		(end 133.905498 -361.082082)
		(stroke
			(width 0.08255)
			(type default)
		)
		(layer "In15.Cu")
	)
	(gr_line
		(start 133.874256 -365.17072)
		(end 133.914896 -365.053626)
		(stroke
			(width 0.08255)
			(type default)
		)
		(layer "In15.Cu")
	)
	(gr_line
		(start 133.914896 -365.053626)
		(end 134.360666 -364.83671)
		(stroke
			(width 0.08255)
			(type default)
		)
		(layer "In15.Cu")
	)
	(gr_line
		(start 133.944868 -362.430568)
		(end 134.079742 -362.476034)
		(stroke
			(width 0.08255)
			(type default)
		)
		(layer "In15.Cu")
	)
	(gr_line
		(start 134.360666 -364.83671)
		(end 134.478014 -364.877096)
		(stroke
			(width 0.08255)
			(type default)
		)
		(layer "In15.Cu")
	)
	(gr_line
		(start 134.525512 -362.255816)
		(end 134.559548 -362.155232)
		(stroke
			(width 0.08255)
			(type default)
		)
		(layer "In15.Cu")
	)
	(gr_line
		(start 134.559548 -362.155232)
		(end 135.003794 -361.935522)
		(stroke
			(width 0.08255)
			(type default)
		)
		(layer "In15.Cu")
	)
	(gr_line
		(start 134.885938 -365.93526)
		(end 134.886192 -365.93526)
		(stroke
			(width 0.08255)
			(type default)
		)
		(layer "In15.Cu")
	)
	(gr_line
		(start 134.8867 -365.933482)
		(end 134.939024 -365.782606)
		(stroke
			(width 0.08255)
			(type default)
		)
		(layer "In15.Cu")
	)
	(gr_line
		(start 134.920228 -364.663482)
		(end 134.9248 -364.661196)
		(stroke
			(width 0.08255)
			(type default)
		)
		(layer "In15.Cu")
	)
	(gr_line
		(start 134.925308 -364.659418)
		(end 134.965948 -364.542324)
		(stroke
			(width 0.08255)
			(type default)
		)
		(layer "In15.Cu")
	)
	(gr_line
		(start 134.939024 -365.782606)
		(end 135.38454 -365.56569)
		(stroke
			(width 0.08255)
			(type default)
		)
		(layer "In15.Cu")
	)
	(gr_line
		(start 134.965948 -364.542324)
		(end 135.411464 -364.325408)
		(stroke
			(width 0.08255)
			(type default)
		)
		(layer "In15.Cu")
	)
	(gr_line
		(start 135.003794 -361.935522)
		(end 135.104632 -361.969558)
		(stroke
			(width 0.08255)
			(type default)
		)
		(layer "In15.Cu")
	)
	(gr_line
		(start 135.38454 -365.56569)
		(end 135.53567 -365.618014)
		(stroke
			(width 0.08255)
			(type default)
		)
		(layer "In15.Cu")
	)
	(gr_line
		(start 135.411464 -364.325408)
		(end 135.528812 -364.366048)
		(stroke
			(width 0.08255)
			(type default)
		)
		(layer "In15.Cu")
	)
	(gr_line
		(start 135.642096 -366.780318)
		(end 135.642096 -366.780572)
		(stroke
			(width 0.08255)
			(type default)
		)
		(layer "In15.Cu")
	)
	(gr_line
		(start 135.642858 -366.778794)
		(end 135.68299 -366.6617)
		(stroke
			(width 0.08255)
			(type default)
		)
		(layer "In15.Cu")
	)
	(gr_line
		(start 135.68299 -366.6617)
		(end 136.12876 -366.444784)
		(stroke
			(width 0.08255)
			(type default)
		)
		(layer "In15.Cu")
	)
	(gr_line
		(start 135.976106 -364.14837)
		(end 136.016746 -364.031276)
		(stroke
			(width 0.08255)
			(type default)
		)
		(layer "In15.Cu")
	)
	(gr_line
		(start 135.982456 -365.40186)
		(end 135.98271 -365.402114)
		(stroke
			(width 0.08255)
			(type default)
		)
		(layer "In15.Cu")
	)
	(gr_line
		(start 135.983472 -365.400336)
		(end 136.035542 -365.249206)
		(stroke
			(width 0.08255)
			(type default)
		)
		(layer "In15.Cu")
	)
	(gr_line
		(start 136.016746 -364.031276)
		(end 136.462262 -363.81436)
		(stroke
			(width 0.08255)
			(type default)
		)
		(layer "In15.Cu")
	)
	(gr_line
		(start 136.035542 -365.249206)
		(end 136.481312 -365.03229)
		(stroke
			(width 0.08255)
			(type default)
		)
		(layer "In15.Cu")
	)
	(gr_line
		(start 136.03859 -187.094622)
		(end 136.33196 -187.387992)
		(stroke
			(width 0.08255)
			(type default)
		)
		(layer "In15.Cu")
	)
	(gr_line
		(start 136.12876 -366.444784)
		(end 136.246108 -366.485424)
		(stroke
			(width 0.08255)
			(type default)
		)
		(layer "In15.Cu")
	)
	(gr_line
		(start 136.462262 -363.81436)
		(end 136.57961 -363.855)
		(stroke
			(width 0.08255)
			(type default)
		)
		(layer "In15.Cu")
	)
	(gr_line
		(start 136.481312 -365.03229)
		(end 136.632442 -365.084614)
		(stroke
			(width 0.08255)
			(type default)
		)
		(layer "In15.Cu")
	)
	(gr_line
		(start 136.61517 -187.381642)
		(end 136.61517 -187.389262)
		(stroke
			(width 0.08255)
			(type default)
		)
		(layer "In15.Cu")
	)
	(gr_line
		(start 136.69264 -366.269524)
		(end 136.692894 -366.269524)
		(stroke
			(width 0.08255)
			(type default)
		)
		(layer "In15.Cu")
	)
	(gr_line
		(start 136.693402 -366.267746)
		(end 136.734042 -366.150652)
		(stroke
			(width 0.08255)
			(type default)
		)
		(layer "In15.Cu")
	)
	(gr_line
		(start 136.734042 -366.150652)
		(end 137.179558 -365.933736)
		(stroke
			(width 0.08255)
			(type default)
		)
		(layer "In15.Cu")
	)
	(gr_line
		(start 136.90219 -187.094622)
		(end 136.61517 -187.381642)
		(stroke
			(width 0.08255)
			(type default)
		)
		(layer "In15.Cu")
	)
	(gr_line
		(start 136.976104 -364.919006)
		(end 137.079228 -364.868714)
		(stroke
			(width 0.08255)
			(type default)
		)
		(layer "In15.Cu")
	)
	(gr_line
		(start 137.079736 -364.866936)
		(end 137.13206 -364.715806)
		(stroke
			(width 0.08255)
			(type default)
		)
		(layer "In15.Cu")
	)
	(gr_line
		(start 137.13206 -364.715806)
		(end 137.57783 -364.49889)
		(stroke
			(width 0.08255)
			(type default)
		)
		(layer "In15.Cu")
	)
	(gr_line
		(start 137.179558 -365.933736)
		(end 137.296906 -365.974376)
		(stroke
			(width 0.08255)
			(type default)
		)
		(layer "In15.Cu")
	)
	(gr_line
		(start 137.57783 -364.49889)
		(end 137.72896 -364.551214)
		(stroke
			(width 0.08255)
			(type default)
		)
		(layer "In15.Cu")
	)
	(gr_line
		(start 137.681208 -365.788956)
		(end 137.743692 -365.758476)
		(stroke
			(width 0.08255)
			(type default)
		)
		(layer "In15.Cu")
	)
	(gr_line
		(start 137.7442 -365.756698)
		(end 137.78484 -365.639604)
		(stroke
			(width 0.08255)
			(type default)
		)
		(layer "In15.Cu")
	)
	(gr_line
		(start 137.78484 -365.639604)
		(end 138.23061 -365.422688)
		(stroke
			(width 0.08255)
			(type default)
		)
		(layer "In15.Cu")
	)
	(gr_line
		(start 138.23061 -365.422688)
		(end 138.347704 -365.463328)
		(stroke
			(width 0.08255)
			(type default)
		)
		(layer "In15.Cu")
	)
	(gr_line
		(start 142.63878 -180.037486)
		(end 142.913354 -180.31206)
		(stroke
			(width 0.08255)
			(type default)
		)
		(layer "In15.Cu")
	)
	(gr_line
		(start 142.913354 -180.31206)
		(end 142.945866 -180.31206)
		(stroke
			(width 0.08255)
			(type default)
		)
		(layer "In15.Cu")
	)
	(gr_line
		(start 159.933894 -319.865248)
		(end 159.933894 -319.8368)
		(stroke
			(width 0.05715)
			(type default)
		)
		(layer "In15.Cu")
	)
	(gr_line
		(start 159.933894 -319.8368)
		(end 159.979614 -319.79108)
		(stroke
			(width 0.05715)
			(type default)
		)
		(layer "In15.Cu")
	)
	(gr_line
		(start 160.215834 -319.865248)
		(end 160.215834 -319.8368)
		(stroke
			(width 0.05715)
			(type default)
		)
		(layer "In15.Cu")
	)
	(gr_line
		(start 160.215834 -319.8368)
		(end 160.170114 -319.79108)
		(stroke
			(width 0.05715)
			(type default)
		)
		(layer "In15.Cu")
	)
	(gr_line
		(start 160.460944 -318.320166)
		(end 160.549844 -318.409066)
		(stroke
			(width 0.05715)
			(type default)
		)
		(layer "In15.Cu")
	)
	(gr_line
		(start 160.460944 -318.129666)
		(end 160.549844 -318.040766)
		(stroke
			(width 0.05715)
			(type default)
		)
		(layer "In15.Cu")
	)
	(gr_line
		(start 160.549844 -318.409066)
		(end 160.549844 -318.699896)
		(stroke
			(width 0.05715)
			(type default)
		)
		(layer "In15.Cu")
	)
	(gr_line
		(start 160.549844 -318.040766)
		(end 160.549844 -317.749936)
		(stroke
			(width 0.05715)
			(type default)
		)
		(layer "In15.Cu")
	)
	(gr_line
		(start 162.546792 -184.198768)
		(end 163.270692 -184.198768)
		(stroke
			(width 0.08255)
			(type default)
		)
		(layer "In15.Cu")
	)
	(gr_line
		(start 162.548062 -183.915558)
		(end 162.661092 -183.802528)
		(stroke
			(width 0.08255)
			(type default)
		)
		(layer "In15.Cu")
	)
	(gr_line
		(start 162.621214 -341.669878)
		(end 162.6235 -341.667592)
		(stroke
			(width 0.08255)
			(type default)
		)
		(layer "In15.Cu")
	)
	(gr_line
		(start 162.6235 -341.667592)
		(end 162.65017 -341.641938)
		(stroke
			(width 0.08255)
			(type default)
		)
		(layer "In15.Cu")
	)
	(gr_line
		(start 162.661092 -183.802528)
		(end 163.156392 -183.802528)
		(stroke
			(width 0.08255)
			(type default)
		)
		(layer "In15.Cu")
	)
	(gr_line
		(start 163.156392 -183.802528)
		(end 163.269422 -183.915558)
		(stroke
			(width 0.08255)
			(type default)
		)
		(layer "In15.Cu")
	)
	(gr_line
		(start 163.359084 -342.303354)
		(end 163.371784 -342.289638)
		(stroke
			(width 0.08255)
			(type default)
		)
		(layer "In15.Cu")
	)
	(gr_line
		(start 163.371784 -342.289638)
		(end 163.386516 -342.277446)
		(stroke
			(width 0.08255)
			(type default)
		)
		(layer "In15.Cu")
	)
	(gr_line
		(start 163.765992 -184.198768)
		(end 164.489892 -184.198768)
		(stroke
			(width 0.08255)
			(type default)
		)
		(layer "In15.Cu")
	)
	(gr_line
		(start 163.767262 -183.915558)
		(end 163.880292 -183.802528)
		(stroke
			(width 0.08255)
			(type default)
		)
		(layer "In15.Cu")
	)
	(gr_line
		(start 163.880292 -183.802528)
		(end 164.375592 -183.802528)
		(stroke
			(width 0.08255)
			(type default)
		)
		(layer "In15.Cu")
	)
	(gr_line
		(start 164.375592 -183.802528)
		(end 164.488622 -183.915558)
		(stroke
			(width 0.08255)
			(type default)
		)
		(layer "In15.Cu")
	)
	(gr_line
		(start 164.985192 -184.198768)
		(end 165.709092 -184.198768)
		(stroke
			(width 0.08255)
			(type default)
		)
		(layer "In15.Cu")
	)
	(gr_line
		(start 164.986462 -183.915558)
		(end 165.099492 -183.802528)
		(stroke
			(width 0.08255)
			(type default)
		)
		(layer "In15.Cu")
	)
	(gr_line
		(start 165.099492 -183.802528)
		(end 165.594792 -183.802528)
		(stroke
			(width 0.08255)
			(type default)
		)
		(layer "In15.Cu")
	)
	(gr_line
		(start 165.594792 -183.802528)
		(end 165.707822 -183.915558)
		(stroke
			(width 0.08255)
			(type default)
		)
		(layer "In15.Cu")
	)
	(gr_line
		(start 182.73395 -320.068448)
		(end 182.73395 -320.04)
		(stroke
			(width 0.05715)
			(type default)
		)
		(layer "In15.Cu")
	)
	(gr_line
		(start 182.73395 -320.04)
		(end 182.77967 -319.99428)
		(stroke
			(width 0.05715)
			(type default)
		)
		(layer "In15.Cu")
	)
	(gr_line
		(start 183.261 -318.129666)
		(end 183.3499 -318.040766)
		(stroke
			(width 0.05715)
			(type default)
		)
		(layer "In15.Cu")
	)
	(gr_line
		(start 183.3499 -318.040766)
		(end 183.3499 -317.749936)
		(stroke
			(width 0.05715)
			(type default)
		)
		(layer "In15.Cu")
	)
	(gr_line
		(start 183.68391 -319.916048)
		(end 183.68391 -319.8876)
		(stroke
			(width 0.05715)
			(type default)
		)
		(layer "In15.Cu")
	)
	(gr_line
		(start 183.68391 -319.8876)
		(end 183.72963 -319.84188)
		(stroke
			(width 0.05715)
			(type default)
		)
		(layer "In15.Cu")
	)
	(gr_line
		(start 184.21096 -316.229492)
		(end 184.29986 -316.140592)
		(stroke
			(width 0.05715)
			(type default)
		)
		(layer "In15.Cu")
	)
	(gr_line
		(start 184.29986 -316.140592)
		(end 184.29986 -315.849762)
		(stroke
			(width 0.05715)
			(type default)
		)
		(layer "In15.Cu")
	)
	(gr_line
		(start 184.634124 -319.916048)
		(end 184.634124 -319.8876)
		(stroke
			(width 0.05715)
			(type default)
		)
		(layer "In15.Cu")
	)
	(gr_line
		(start 184.634124 -319.8876)
		(end 184.679844 -319.84188)
		(stroke
			(width 0.05715)
			(type default)
		)
		(layer "In15.Cu")
	)
	(gr_line
		(start 185.161174 -318.129666)
		(end 185.250074 -318.040766)
		(stroke
			(width 0.05715)
			(type default)
		)
		(layer "In15.Cu")
	)
	(gr_line
		(start 185.250074 -318.040766)
		(end 185.250074 -317.749936)
		(stroke
			(width 0.05715)
			(type default)
		)
		(layer "In15.Cu")
	)
	(gr_line
		(start 186.534044 -319.916048)
		(end 186.534044 -319.8876)
		(stroke
			(width 0.05715)
			(type default)
		)
		(layer "In15.Cu")
	)
	(gr_line
		(start 186.534044 -319.8876)
		(end 186.579764 -319.84188)
		(stroke
			(width 0.05715)
			(type default)
		)
		(layer "In15.Cu")
	)
	(gr_line
		(start 187.061094 -318.129666)
		(end 187.149994 -318.040766)
		(stroke
			(width 0.05715)
			(type default)
		)
		(layer "In15.Cu")
	)
	(gr_line
		(start 187.149994 -318.040766)
		(end 187.149994 -317.749936)
		(stroke
			(width 0.05715)
			(type default)
		)
		(layer "In15.Cu")
	)
	(gr_line
		(start 187.484004 -319.916048)
		(end 187.484004 -319.8876)
		(stroke
			(width 0.05715)
			(type default)
		)
		(layer "In15.Cu")
	)
	(gr_line
		(start 187.484004 -319.8876)
		(end 187.529724 -319.84188)
		(stroke
			(width 0.05715)
			(type default)
		)
		(layer "In15.Cu")
	)
	(gr_line
		(start 188.011054 -316.229492)
		(end 188.099954 -316.140592)
		(stroke
			(width 0.05715)
			(type default)
		)
		(layer "In15.Cu")
	)
	(gr_line
		(start 188.099954 -316.140592)
		(end 188.099954 -315.849762)
		(stroke
			(width 0.05715)
			(type default)
		)
		(layer "In15.Cu")
	)
	(gr_line
		(start 188.433964 -319.916048)
		(end 188.433964 -319.8876)
		(stroke
			(width 0.05715)
			(type default)
		)
		(layer "In15.Cu")
	)
	(gr_line
		(start 188.433964 -319.8876)
		(end 188.479684 -319.84188)
		(stroke
			(width 0.05715)
			(type default)
		)
		(layer "In15.Cu")
	)
	(gr_line
		(start 188.961014 -318.129666)
		(end 189.049914 -318.040766)
		(stroke
			(width 0.05715)
			(type default)
		)
		(layer "In15.Cu")
	)
	(gr_line
		(start 189.049914 -318.040766)
		(end 189.049914 -317.749936)
		(stroke
			(width 0.05715)
			(type default)
		)
		(layer "In15.Cu")
	)
	(gr_line
		(start 229.48646 -85.1154)
		(end 229.48646 -85.8393)
		(stroke
			(width 0.08255)
			(type default)
		)
		(layer "In15.Cu")
	)
	(gr_line
		(start 229.48646 -83.8962)
		(end 229.48646 -84.6201)
		(stroke
			(width 0.08255)
			(type default)
		)
		(layer "In15.Cu")
	)
	(gr_line
		(start 229.48646 -82.677)
		(end 229.48646 -83.4009)
		(stroke
			(width 0.08255)
			(type default)
		)
		(layer "In15.Cu")
	)
	(gr_line
		(start 229.48646 -81.4578)
		(end 229.48646 -82.1817)
		(stroke
			(width 0.08255)
			(type default)
		)
		(layer "In15.Cu")
	)
	(gr_line
		(start 229.76967 -85.11667)
		(end 229.8827 -85.2297)
		(stroke
			(width 0.08255)
			(type default)
		)
		(layer "In15.Cu")
	)
	(gr_line
		(start 229.76967 -83.89747)
		(end 229.8827 -84.0105)
		(stroke
			(width 0.08255)
			(type default)
		)
		(layer "In15.Cu")
	)
	(gr_line
		(start 229.76967 -82.67827)
		(end 229.8827 -82.7913)
		(stroke
			(width 0.08255)
			(type default)
		)
		(layer "In15.Cu")
	)
	(gr_line
		(start 229.76967 -81.45907)
		(end 229.8827 -81.5721)
		(stroke
			(width 0.08255)
			(type default)
		)
		(layer "In15.Cu")
	)
	(gr_line
		(start 229.8827 -85.725)
		(end 229.76967 -85.83803)
		(stroke
			(width 0.08255)
			(type default)
		)
		(layer "In15.Cu")
	)
	(gr_line
		(start 229.8827 -85.2297)
		(end 229.8827 -85.725)
		(stroke
			(width 0.08255)
			(type default)
		)
		(layer "In15.Cu")
	)
	(gr_line
		(start 229.8827 -84.5058)
		(end 229.76967 -84.61883)
		(stroke
			(width 0.08255)
			(type default)
		)
		(layer "In15.Cu")
	)
	(gr_line
		(start 229.8827 -84.0105)
		(end 229.8827 -84.5058)
		(stroke
			(width 0.08255)
			(type default)
		)
		(layer "In15.Cu")
	)
	(gr_line
		(start 229.8827 -83.2866)
		(end 229.76967 -83.39963)
		(stroke
			(width 0.08255)
			(type default)
		)
		(layer "In15.Cu")
	)
	(gr_line
		(start 229.8827 -82.7913)
		(end 229.8827 -83.2866)
		(stroke
			(width 0.08255)
			(type default)
		)
		(layer "In15.Cu")
	)
	(gr_line
		(start 229.8827 -82.0674)
		(end 229.76967 -82.18043)
		(stroke
			(width 0.08255)
			(type default)
		)
		(layer "In15.Cu")
	)
	(gr_line
		(start 229.8827 -81.5721)
		(end 229.8827 -82.0674)
		(stroke
			(width 0.08255)
			(type default)
		)
		(layer "In15.Cu")
	)
	(gr_line
		(start 230.3907 -86.8426)
		(end 231.1146 -86.8426)
		(stroke
			(width 0.08255)
			(type default)
		)
		(layer "In15.Cu")
	)
	(gr_line
		(start 230.39197 -86.55939)
		(end 230.505 -86.44636)
		(stroke
			(width 0.08255)
			(type default)
		)
		(layer "In15.Cu")
	)
	(gr_line
		(start 230.505 -86.44636)
		(end 231.0003 -86.44636)
		(stroke
			(width 0.08255)
			(type default)
		)
		(layer "In15.Cu")
	)
	(gr_line
		(start 230.549958 -80.9498)
		(end 230.436928 -80.83677)
		(stroke
			(width 0.08255)
			(type default)
		)
		(layer "In15.Cu")
	)
	(gr_line
		(start 231.0003 -86.44636)
		(end 231.11333 -86.55939)
		(stroke
			(width 0.08255)
			(type default)
		)
		(layer "In15.Cu")
	)
	(gr_line
		(start 231.045258 -80.9498)
		(end 230.549958 -80.9498)
		(stroke
			(width 0.08255)
			(type default)
		)
		(layer "In15.Cu")
	)
	(gr_line
		(start 231.158288 -80.83677)
		(end 231.045258 -80.9498)
		(stroke
			(width 0.08255)
			(type default)
		)
		(layer "In15.Cu")
	)
	(gr_line
		(start 231.159558 -80.55356)
		(end 230.435658 -80.55356)
		(stroke
			(width 0.08255)
			(type default)
		)
		(layer "In15.Cu")
	)
	(gr_line
		(start 231.6099 -86.8426)
		(end 232.3338 -86.8426)
		(stroke
			(width 0.08255)
			(type default)
		)
		(layer "In15.Cu")
	)
	(gr_line
		(start 231.61117 -86.55939)
		(end 231.7242 -86.44636)
		(stroke
			(width 0.08255)
			(type default)
		)
		(layer "In15.Cu")
	)
	(gr_line
		(start 231.7242 -86.44636)
		(end 232.2195 -86.44636)
		(stroke
			(width 0.08255)
			(type default)
		)
		(layer "In15.Cu")
	)
	(gr_line
		(start 231.769158 -80.9498)
		(end 231.656128 -80.83677)
		(stroke
			(width 0.08255)
			(type default)
		)
		(layer "In15.Cu")
	)
	(gr_line
		(start 232.2195 -86.44636)
		(end 232.33253 -86.55939)
		(stroke
			(width 0.08255)
			(type default)
		)
		(layer "In15.Cu")
	)
	(gr_line
		(start 232.264458 -80.9498)
		(end 231.769158 -80.9498)
		(stroke
			(width 0.08255)
			(type default)
		)
		(layer "In15.Cu")
	)
	(gr_line
		(start 232.377488 -80.83677)
		(end 232.264458 -80.9498)
		(stroke
			(width 0.08255)
			(type default)
		)
		(layer "In15.Cu")
	)
	(gr_line
		(start 232.378758 -80.55356)
		(end 231.654858 -80.55356)
		(stroke
			(width 0.08255)
			(type default)
		)
		(layer "In15.Cu")
	)
	(gr_line
		(start 232.939336 -87.12708)
		(end 232.652316 -87.4141)
		(stroke
			(width 0.08255)
			(type default)
		)
		(layer "In15.Cu")
	)
	(gr_line
		(start 232.939336 -87.11946)
		(end 232.939336 -87.12708)
		(stroke
			(width 0.08255)
			(type default)
		)
		(layer "In15.Cu")
	)
	(gr_line
		(start 232.988358 -80.9498)
		(end 232.875328 -80.83677)
		(stroke
			(width 0.08255)
			(type default)
		)
		(layer "In15.Cu")
	)
	(gr_line
		(start 233.142028 -83.366864)
		(end 233.453432 -83.05546)
		(stroke
			(width 0.08255)
			(type default)
		)
		(layer "In15.Cu")
	)
	(gr_line
		(start 233.142028 -82.503264)
		(end 233.411014 -82.77225)
		(stroke
			(width 0.08255)
			(type default)
		)
		(layer "In15.Cu")
	)
	(gr_line
		(start 233.222546 -87.12073)
		(end 233.515916 -87.4141)
		(stroke
			(width 0.08255)
			(type default)
		)
		(layer "In15.Cu")
	)
	(gr_line
		(start 233.411014 -82.77225)
		(end 233.454702 -82.77225)
		(stroke
			(width 0.08255)
			(type default)
		)
		(layer "In15.Cu")
	)
	(gr_line
		(start 233.483658 -80.9498)
		(end 232.988358 -80.9498)
		(stroke
			(width 0.08255)
			(type default)
		)
		(layer "In15.Cu")
	)
	(gr_line
		(start 233.596688 -80.83677)
		(end 233.483658 -80.9498)
		(stroke
			(width 0.08255)
			(type default)
		)
		(layer "In15.Cu")
	)
	(gr_line
		(start 233.597958 -80.55356)
		(end 232.874058 -80.55356)
		(stroke
			(width 0.08255)
			(type default)
		)
		(layer "In15.Cu")
	)
	(gr_line
		(start 233.906314 -83.05419)
		(end 234.630214 -83.05419)
		(stroke
			(width 0.08255)
			(type default)
		)
		(layer "In15.Cu")
	)
	(gr_line
		(start 233.907584 -82.77098)
		(end 234.020614 -82.65795)
		(stroke
			(width 0.08255)
			(type default)
		)
		(layer "In15.Cu")
	)
	(gr_line
		(start 234.020614 -82.65795)
		(end 234.515914 -82.65795)
		(stroke
			(width 0.08255)
			(type default)
		)
		(layer "In15.Cu")
	)
	(gr_line
		(start 234.207558 -80.9498)
		(end 234.094528 -80.83677)
		(stroke
			(width 0.08255)
			(type default)
		)
		(layer "In15.Cu")
	)
	(gr_line
		(start 234.515914 -82.65795)
		(end 234.628944 -82.77098)
		(stroke
			(width 0.08255)
			(type default)
		)
		(layer "In15.Cu")
	)
	(gr_line
		(start 234.702858 -80.9498)
		(end 234.207558 -80.9498)
		(stroke
			(width 0.08255)
			(type default)
		)
		(layer "In15.Cu")
	)
	(gr_line
		(start 234.815888 -80.83677)
		(end 234.702858 -80.9498)
		(stroke
			(width 0.08255)
			(type default)
		)
		(layer "In15.Cu")
	)
	(gr_line
		(start 234.817158 -80.55356)
		(end 234.093258 -80.55356)
		(stroke
			(width 0.08255)
			(type default)
		)
		(layer "In15.Cu")
	)
	(gr_line
		(start 234.839256 -87.386414)
		(end 235.132118 -87.093552)
		(stroke
			(width 0.08255)
			(type default)
		)
		(layer "In15.Cu")
	)
	(gr_line
		(start 235.125514 -83.05419)
		(end 235.849414 -83.05419)
		(stroke
			(width 0.08255)
			(type default)
		)
		(layer "In15.Cu")
	)
	(gr_line
		(start 235.126784 -82.77098)
		(end 235.239814 -82.65795)
		(stroke
			(width 0.08255)
			(type default)
		)
		(layer "In15.Cu")
	)
	(gr_line
		(start 235.239814 -82.65795)
		(end 235.735114 -82.65795)
		(stroke
			(width 0.08255)
			(type default)
		)
		(layer "In15.Cu")
	)
	(gr_line
		(start 235.415328 -87.098886)
		(end 235.415328 -87.092282)
		(stroke
			(width 0.08255)
			(type default)
		)
		(layer "In15.Cu")
	)
	(gr_line
		(start 235.426758 -80.9498)
		(end 235.313728 -80.83677)
		(stroke
			(width 0.08255)
			(type default)
		)
		(layer "In15.Cu")
	)
	(gr_line
		(start 235.702856 -87.386414)
		(end 235.415328 -87.098886)
		(stroke
			(width 0.08255)
			(type default)
		)
		(layer "In15.Cu")
	)
	(gr_line
		(start 235.735114 -82.65795)
		(end 235.848144 -82.77098)
		(stroke
			(width 0.08255)
			(type default)
		)
		(layer "In15.Cu")
	)
	(gr_line
		(start 235.922058 -80.9498)
		(end 235.426758 -80.9498)
		(stroke
			(width 0.08255)
			(type default)
		)
		(layer "In15.Cu")
	)
	(gr_line
		(start 235.925868 -86.364826)
		(end 236.649768 -86.364826)
		(stroke
			(width 0.08255)
			(type default)
		)
		(layer "In15.Cu")
	)
	(gr_line
		(start 235.927138 -86.081616)
		(end 236.040168 -85.968586)
		(stroke
			(width 0.08255)
			(type default)
		)
		(layer "In15.Cu")
	)
	(gr_line
		(start 236.035088 -80.83677)
		(end 235.922058 -80.9498)
		(stroke
			(width 0.08255)
			(type default)
		)
		(layer "In15.Cu")
	)
	(gr_line
		(start 236.036358 -80.55356)
		(end 235.312458 -80.55356)
		(stroke
			(width 0.08255)
			(type default)
		)
		(layer "In15.Cu")
	)
	(gr_line
		(start 236.040168 -85.968586)
		(end 236.535468 -85.968586)
		(stroke
			(width 0.08255)
			(type default)
		)
		(layer "In15.Cu")
	)
	(gr_line
		(start 236.535468 -85.968586)
		(end 236.648498 -86.081616)
		(stroke
			(width 0.08255)
			(type default)
		)
		(layer "In15.Cu")
	)
	(gr_line
		(start 236.77626 -82.105754)
		(end 236.77626 -81.610454)
		(stroke
			(width 0.08255)
			(type default)
		)
		(layer "In15.Cu")
	)
	(gr_line
		(start 236.77626 -81.610454)
		(end 236.88929 -81.497424)
		(stroke
			(width 0.08255)
			(type default)
		)
		(layer "In15.Cu")
	)
	(gr_line
		(start 236.88929 -82.218784)
		(end 236.77626 -82.105754)
		(stroke
			(width 0.08255)
			(type default)
		)
		(layer "In15.Cu")
	)
	(gr_line
		(start 237.1725 -82.220054)
		(end 237.1725 -81.496154)
		(stroke
			(width 0.08255)
			(type default)
		)
		(layer "In15.Cu")
	)
	(gr_line
		(start 238.071914 -86.995)
		(end 238.795814 -86.995)
		(stroke
			(width 0.08255)
			(type default)
		)
		(layer "In15.Cu")
	)
	(gr_line
		(start 238.073184 -86.71179)
		(end 238.186214 -86.59876)
		(stroke
			(width 0.08255)
			(type default)
		)
		(layer "In15.Cu")
	)
	(gr_line
		(start 238.186214 -86.59876)
		(end 238.681514 -86.59876)
		(stroke
			(width 0.08255)
			(type default)
		)
		(layer "In15.Cu")
	)
	(gr_line
		(start 238.681514 -86.59876)
		(end 238.794544 -86.71179)
		(stroke
			(width 0.08255)
			(type default)
		)
		(layer "In15.Cu")
	)
	(gr_line
		(start 239.291114 -86.995)
		(end 240.015014 -86.995)
		(stroke
			(width 0.08255)
			(type default)
		)
		(layer "In15.Cu")
	)
	(gr_line
		(start 239.292384 -86.71179)
		(end 239.405414 -86.59876)
		(stroke
			(width 0.08255)
			(type default)
		)
		(layer "In15.Cu")
	)
	(gr_line
		(start 239.298226 -84.590636)
		(end 239.013238 -84.305648)
		(stroke
			(width 0.08255)
			(type default)
		)
		(layer "In15.Cu")
	)
	(gr_line
		(start 239.30864 -84.873846)
		(end 239.013238 -85.169248)
		(stroke
			(width 0.08255)
			(type default)
		)
		(layer "In15.Cu")
	)
	(gr_line
		(start 239.30991 -84.590636)
		(end 239.298226 -84.590636)
		(stroke
			(width 0.08255)
			(type default)
		)
		(layer "In15.Cu")
	)
	(gr_line
		(start 239.405414 -86.59876)
		(end 239.900714 -86.59876)
		(stroke
			(width 0.08255)
			(type default)
		)
		(layer "In15.Cu")
	)
	(gr_line
		(start 239.900714 -86.59876)
		(end 240.013744 -86.71179)
		(stroke
			(width 0.08255)
			(type default)
		)
		(layer "In15.Cu")
	)
	(gr_line
		(start 240.294414 -86.014052)
		(end 240.294414 -85.56244)
		(stroke
			(width 0.08255)
			(type default)
		)
		(layer "In15.Cu")
	)
	(gr_line
		(start 240.294414 -85.56244)
		(end 240.407444 -85.44941)
		(stroke
			(width 0.08255)
			(type default)
		)
		(layer "In15.Cu")
	)
	(gr_line
		(start 240.407444 -86.127082)
		(end 240.294414 -86.014052)
		(stroke
			(width 0.08255)
			(type default)
		)
		(layer "In15.Cu")
	)
	(gr_line
		(start 240.690654 -86.128352)
		(end 240.690654 -85.44814)
		(stroke
			(width 0.08255)
			(type default)
		)
		(layer "In15.Cu")
	)
	(gr_line
		(start 282.461462 -341.667084)
		(end 282.831286 -341.224616)
		(stroke
			(width 0.08255)
			(type default)
		)
		(layer "In15.Cu")
	)
	(gr_line
		(start 282.825952 -391.495788)
		(end 282.809188 -391.372852)
		(stroke
			(width 0.08255)
			(type default)
		)
		(layer "In15.Cu")
	)
	(gr_line
		(start 282.83154 -341.224108)
		(end 282.847796 -341.204804)
		(stroke
			(width 0.08255)
			(type default)
		)
		(layer "In15.Cu")
	)
	(gr_line
		(start 283.220414 -391.795762)
		(end 282.825952 -391.495788)
		(stroke
			(width 0.08255)
			(type default)
		)
		(layer "In15.Cu")
	)
	(gr_line
		(start 283.343604 -391.778998)
		(end 283.220414 -391.795762)
		(stroke
			(width 0.08255)
			(type default)
		)
		(layer "In15.Cu")
	)
	(gr_line
		(start 283.7561 -392.20267)
		(end 283.73959 -392.079734)
		(stroke
			(width 0.08255)
			(type default)
		)
		(layer "In15.Cu")
	)
	(gr_line
		(start 284.150816 -392.502644)
		(end 283.7561 -392.20267)
		(stroke
			(width 0.08255)
			(type default)
		)
		(layer "In15.Cu")
	)
	(gr_line
		(start 284.274006 -392.48588)
		(end 284.150816 -392.502644)
		(stroke
			(width 0.08255)
			(type default)
		)
		(layer "In15.Cu")
	)
	(gr_line
		(start 285.890208 -393.4587)
		(end 285.846266 -393.342368)
		(stroke
			(width 0.08255)
			(type default)
		)
		(layer "In15.Cu")
	)
	(gr_line
		(start 286.342074 -393.662662)
		(end 285.890208 -393.4587)
		(stroke
			(width 0.08255)
			(type default)
		)
		(layer "In15.Cu")
	)
	(gr_line
		(start 286.458406 -393.61872)
		(end 286.342074 -393.662662)
		(stroke
			(width 0.08255)
			(type default)
		)
		(layer "In15.Cu")
	)
	(gr_line
		(start 287.4899 -404.672038)
		(end 287.6169 -404.799038)
		(stroke
			(width 0.08255)
			(type default)
		)
		(layer "In15.Cu")
	)
	(gr_line
		(start 287.4899 -404.290022)
		(end 287.4899 -404.672038)
		(stroke
			(width 0.08255)
			(type default)
		)
		(layer "In15.Cu")
	)
	(gr_line
		(start 288.88817 -392.274044)
		(end 288.858452 -392.256264)
		(stroke
			(width 0.08255)
			(type default)
		)
		(layer "In15.Cu")
	)
	(gr_line
		(start 289.46602 -392.619992)
		(end 288.88817 -392.274044)
		(stroke
			(width 0.08255)
			(type default)
		)
		(layer "In15.Cu")
	)
	(gr_line
		(start 289.689794 -380.69012)
		(end 289.689794 -380.308104)
		(stroke
			(width 0.08255)
			(type default)
		)
		(layer "In15.Cu")
	)
	(gr_line
		(start 289.689794 -380.308104)
		(end 289.816794 -380.181104)
		(stroke
			(width 0.08255)
			(type default)
		)
		(layer "In15.Cu")
	)
	(gr_line
		(start 289.689794 -379.772164)
		(end 289.816794 -379.899164)
		(stroke
			(width 0.08255)
			(type default)
		)
		(layer "In15.Cu")
	)
	(gr_line
		(start 289.689794 -379.390148)
		(end 289.689794 -379.772164)
		(stroke
			(width 0.08255)
			(type default)
		)
		(layer "In15.Cu")
	)
	(gr_line
		(start 290.468812 -393.220194)
		(end 289.890962 -392.874246)
		(stroke
			(width 0.08255)
			(type default)
		)
		(layer "In15.Cu")
	)
	(gr_line
		(start 291.471604 -393.820142)
		(end 290.893754 -393.474448)
		(stroke
			(width 0.08255)
			(type default)
		)
		(layer "In15.Cu")
	)
	(gr_line
		(start 291.889942 -405.589994)
		(end 291.889942 -405.207978)
		(stroke
			(width 0.08255)
			(type default)
		)
		(layer "In15.Cu")
	)
	(gr_line
		(start 291.889942 -405.207978)
		(end 292.016942 -405.080978)
		(stroke
			(width 0.08255)
			(type default)
		)
		(layer "In15.Cu")
	)
	(gr_line
		(start 291.889942 -379.590046)
		(end 291.889942 -379.20803)
		(stroke
			(width 0.08255)
			(type default)
		)
		(layer "In15.Cu")
	)
	(gr_line
		(start 291.889942 -379.20803)
		(end 292.016942 -379.08103)
		(stroke
			(width 0.08255)
			(type default)
		)
		(layer "In15.Cu")
	)
	(gr_line
		(start 291.889942 -378.67209)
		(end 292.016942 -378.79909)
		(stroke
			(width 0.08255)
			(type default)
		)
		(layer "In15.Cu")
	)
	(gr_line
		(start 291.889942 -378.290074)
		(end 291.889942 -378.67209)
		(stroke
			(width 0.08255)
			(type default)
		)
		(layer "In15.Cu")
	)
	(gr_line
		(start 292.913562 -366.92205)
		(end 292.920928 -366.780064)
		(stroke
			(width 0.08255)
			(type default)
		)
		(layer "In15.Cu")
	)
	(gr_line
		(start 292.920928 -366.780064)
		(end 293.289228 -366.44834)
		(stroke
			(width 0.08255)
			(type default)
		)
		(layer "In15.Cu")
	)
	(gr_line
		(start 293.102538 -367.133124)
		(end 293.621714 -366.665256)
		(stroke
			(width 0.08255)
			(type default)
		)
		(layer "In15.Cu")
	)
	(gr_line
		(start 293.289228 -366.44834)
		(end 293.431214 -366.455706)
		(stroke
			(width 0.08255)
			(type default)
		)
		(layer "In15.Cu")
	)
	(gr_line
		(start 293.80053 -366.122712)
		(end 293.807896 -365.980726)
		(stroke
			(width 0.08255)
			(type default)
		)
		(layer "In15.Cu")
	)
	(gr_line
		(start 293.807896 -365.980726)
		(end 294.176196 -365.649002)
		(stroke
			(width 0.08255)
			(type default)
		)
		(layer "In15.Cu")
	)
	(gr_line
		(start 293.989506 -366.333786)
		(end 294.508682 -365.865918)
		(stroke
			(width 0.08255)
			(type default)
		)
		(layer "In15.Cu")
	)
	(gr_line
		(start 294.089836 -379.772164)
		(end 294.216836 -379.899164)
		(stroke
			(width 0.08255)
			(type default)
		)
		(layer "In15.Cu")
	)
	(gr_line
		(start 294.089836 -379.390148)
		(end 294.089836 -379.772164)
		(stroke
			(width 0.08255)
			(type default)
		)
		(layer "In15.Cu")
	)
	(gr_line
		(start 294.176196 -365.649002)
		(end 294.318182 -365.656368)
		(stroke
			(width 0.08255)
			(type default)
		)
		(layer "In15.Cu")
	)
	(gr_line
		(start 294.687498 -365.323374)
		(end 294.694864 -365.181388)
		(stroke
			(width 0.08255)
			(type default)
		)
		(layer "In15.Cu")
	)
	(gr_line
		(start 294.694864 -365.181388)
		(end 295.063164 -364.849664)
		(stroke
			(width 0.08255)
			(type default)
		)
		(layer "In15.Cu")
	)
	(gr_line
		(start 294.876474 -365.534448)
		(end 295.39565 -365.06658)
		(stroke
			(width 0.08255)
			(type default)
		)
		(layer "In15.Cu")
	)
	(gr_line
		(start 295.063164 -364.849664)
		(end 295.20515 -364.85703)
		(stroke
			(width 0.08255)
			(type default)
		)
		(layer "In15.Cu")
	)
	(gr_line
		(start 295.082722 -366.797844)
		(end 295.084754 -366.655604)
		(stroke
			(width 0.08255)
			(type default)
		)
		(layer "In15.Cu")
	)
	(gr_line
		(start 295.084754 -366.655604)
		(end 295.439846 -366.310164)
		(stroke
			(width 0.08255)
			(type default)
		)
		(layer "In15.Cu")
	)
	(gr_line
		(start 295.16832 -157.764226)
		(end 295.28135 -157.651196)
		(stroke
			(width 0.08255)
			(type default)
		)
		(layer "In15.Cu")
	)
	(gr_line
		(start 295.279318 -367.001552)
		(end 295.78046 -366.514126)
		(stroke
			(width 0.08255)
			(type default)
		)
		(layer "In15.Cu")
	)
	(gr_line
		(start 295.28135 -157.651196)
		(end 295.77665 -157.651196)
		(stroke
			(width 0.08255)
			(type default)
		)
		(layer "In15.Cu")
	)
	(gr_line
		(start 295.439846 -366.310164)
		(end 295.582086 -366.311942)
		(stroke
			(width 0.08255)
			(type default)
		)
		(layer "In15.Cu")
	)
	(gr_line
		(start 295.77665 -157.651196)
		(end 295.88968 -157.764226)
		(stroke
			(width 0.08255)
			(type default)
		)
		(layer "In15.Cu")
	)
	(gr_line
		(start 295.938448 -365.965232)
		(end 295.94048 -365.822992)
		(stroke
			(width 0.08255)
			(type default)
		)
		(layer "In15.Cu")
	)
	(gr_line
		(start 295.94048 -365.822992)
		(end 296.295826 -365.477552)
		(stroke
			(width 0.08255)
			(type default)
		)
		(layer "In15.Cu")
	)
	(gr_line
		(start 296.135298 -366.16894)
		(end 296.63644 -365.681514)
		(stroke
			(width 0.08255)
			(type default)
		)
		(layer "In15.Cu")
	)
	(gr_line
		(start 296.289984 -379.590046)
		(end 296.289984 -379.20803)
		(stroke
			(width 0.08255)
			(type default)
		)
		(layer "In15.Cu")
	)
	(gr_line
		(start 296.289984 -379.20803)
		(end 296.416984 -379.08103)
		(stroke
			(width 0.08255)
			(type default)
		)
		(layer "In15.Cu")
	)
	(gr_line
		(start 296.289984 -378.67209)
		(end 296.416984 -378.79909)
		(stroke
			(width 0.08255)
			(type default)
		)
		(layer "In15.Cu")
	)
	(gr_line
		(start 296.289984 -378.290074)
		(end 296.289984 -378.67209)
		(stroke
			(width 0.08255)
			(type default)
		)
		(layer "In15.Cu")
	)
	(gr_line
		(start 296.295826 -365.477552)
		(end 296.438066 -365.47933)
		(stroke
			(width 0.08255)
			(type default)
		)
		(layer "In15.Cu")
	)
	(gr_line
		(start 296.38752 -157.764226)
		(end 296.50055 -157.651196)
		(stroke
			(width 0.08255)
			(type default)
		)
		(layer "In15.Cu")
	)
	(gr_line
		(start 296.40784 -367.400332)
		(end 296.745914 -367.03762)
		(stroke
			(width 0.08255)
			(type default)
		)
		(layer "In15.Cu")
	)
	(gr_line
		(start 296.413174 -367.542318)
		(end 296.40784 -367.400332)
		(stroke
			(width 0.08255)
			(type default)
		)
		(layer "In15.Cu")
	)
	(gr_line
		(start 296.50055 -157.651196)
		(end 296.99585 -157.651196)
		(stroke
			(width 0.08255)
			(type default)
		)
		(layer "In15.Cu")
	)
	(gr_line
		(start 296.745914 -367.03762)
		(end 296.888154 -367.03254)
		(stroke
			(width 0.08255)
			(type default)
		)
		(layer "In15.Cu")
	)
	(gr_line
		(start 296.794428 -365.13262)
		(end 296.79646 -364.99038)
		(stroke
			(width 0.08255)
			(type default)
		)
		(layer "In15.Cu")
	)
	(gr_line
		(start 296.79646 -364.99038)
		(end 297.151806 -364.64494)
		(stroke
			(width 0.08255)
			(type default)
		)
		(layer "In15.Cu")
	)
	(gr_line
		(start 296.991278 -365.336328)
		(end 297.49242 -364.848902)
		(stroke
			(width 0.08255)
			(type default)
		)
		(layer "In15.Cu")
	)
	(gr_line
		(start 296.99585 -157.651196)
		(end 297.10888 -157.764226)
		(stroke
			(width 0.08255)
			(type default)
		)
		(layer "In15.Cu")
	)
	(gr_line
		(start 297.151806 -364.64494)
		(end 297.294046 -364.646718)
		(stroke
			(width 0.08255)
			(type default)
		)
		(layer "In15.Cu")
	)
	(gr_line
		(start 297.22191 -366.526572)
		(end 297.55973 -366.164114)
		(stroke
			(width 0.08255)
			(type default)
		)
		(layer "In15.Cu")
	)
	(gr_line
		(start 297.22699 -366.668812)
		(end 297.22191 -366.526572)
		(stroke
			(width 0.08255)
			(type default)
		)
		(layer "In15.Cu")
	)
	(gr_line
		(start 297.49242 -364.848902)
		(end 297.492166 -364.848902)
		(stroke
			(width 0.08255)
			(type default)
		)
		(layer "In15.Cu")
	)
	(gr_line
		(start 297.55973 -366.164114)
		(end 297.701716 -366.159034)
		(stroke
			(width 0.08255)
			(type default)
		)
		(layer "In15.Cu")
	)
	(gr_line
		(start 297.60672 -157.764226)
		(end 297.71975 -157.651196)
		(stroke
			(width 0.08255)
			(type default)
		)
		(layer "In15.Cu")
	)
	(gr_line
		(start 297.71975 -157.651196)
		(end 298.21505 -157.651196)
		(stroke
			(width 0.08255)
			(type default)
		)
		(layer "In15.Cu")
	)
	(gr_line
		(start 298.035726 -365.653066)
		(end 298.373546 -365.290608)
		(stroke
			(width 0.08255)
			(type default)
		)
		(layer "In15.Cu")
	)
	(gr_line
		(start 298.040806 -365.795306)
		(end 298.035726 -365.653066)
		(stroke
			(width 0.08255)
			(type default)
		)
		(layer "In15.Cu")
	)
	(gr_line
		(start 298.063158 -367.608612)
		(end 298.388024 -367.234216)
		(stroke
			(width 0.08255)
			(type default)
		)
		(layer "In15.Cu")
	)
	(gr_line
		(start 298.073318 -367.750598)
		(end 298.063158 -367.608612)
		(stroke
			(width 0.08255)
			(type default)
		)
		(layer "In15.Cu")
	)
	(gr_line
		(start 298.21505 -157.651196)
		(end 298.32808 -157.764226)
		(stroke
			(width 0.08255)
			(type default)
		)
		(layer "In15.Cu")
	)
	(gr_line
		(start 298.286424 -367.93678)
		(end 298.744386 -367.409222)
		(stroke
			(width 0.08255)
			(type default)
		)
		(layer "In15.Cu")
	)
	(gr_line
		(start 298.373546 -365.290608)
		(end 298.515532 -365.285528)
		(stroke
			(width 0.08255)
			(type default)
		)
		(layer "In15.Cu")
	)
	(gr_line
		(start 298.388024 -367.234216)
		(end 298.53001 -367.224056)
		(stroke
			(width 0.08255)
			(type default)
		)
		(layer "In15.Cu")
	)
	(gr_line
		(start 298.82592 -157.764226)
		(end 298.93895 -157.651196)
		(stroke
			(width 0.08255)
			(type default)
		)
		(layer "In15.Cu")
	)
	(gr_line
		(start 298.845732 -366.706912)
		(end 299.170598 -366.332516)
		(stroke
			(width 0.08255)
			(type default)
		)
		(layer "In15.Cu")
	)
	(gr_line
		(start 298.855892 -366.848898)
		(end 298.845732 -366.706912)
		(stroke
			(width 0.08255)
			(type default)
		)
		(layer "In15.Cu")
	)
	(gr_line
		(start 298.93895 -157.651196)
		(end 299.43425 -157.651196)
		(stroke
			(width 0.08255)
			(type default)
		)
		(layer "In15.Cu")
	)
	(gr_line
		(start 299.068998 -367.03508)
		(end 299.52696 -366.507522)
		(stroke
			(width 0.08255)
			(type default)
		)
		(layer "In15.Cu")
	)
	(gr_line
		(start 299.170598 -366.332516)
		(end 299.312584 -366.322356)
		(stroke
			(width 0.08255)
			(type default)
		)
		(layer "In15.Cu")
	)
	(gr_line
		(start 299.43425 -157.651196)
		(end 299.54728 -157.764226)
		(stroke
			(width 0.08255)
			(type default)
		)
		(layer "In15.Cu")
	)
	(gr_line
		(start 299.628306 -365.805212)
		(end 299.953172 -365.430816)
		(stroke
			(width 0.08255)
			(type default)
		)
		(layer "In15.Cu")
	)
	(gr_line
		(start 299.638466 -365.947198)
		(end 299.628306 -365.805212)
		(stroke
			(width 0.08255)
			(type default)
		)
		(layer "In15.Cu")
	)
	(gr_line
		(start 299.851572 -366.133634)
		(end 300.309534 -365.605822)
		(stroke
			(width 0.08255)
			(type default)
		)
		(layer "In15.Cu")
	)
	(gr_line
		(start 299.953172 -365.430816)
		(end 300.095158 -365.420656)
		(stroke
			(width 0.08255)
			(type default)
		)
		(layer "In15.Cu")
	)
	(gr_line
		(start 300.04512 -157.764226)
		(end 300.15815 -157.651196)
		(stroke
			(width 0.08255)
			(type default)
		)
		(layer "In15.Cu")
	)
	(gr_line
		(start 300.15815 -157.651196)
		(end 300.65345 -157.651196)
		(stroke
			(width 0.08255)
			(type default)
		)
		(layer "In15.Cu")
	)
	(gr_line
		(start 300.65345 -157.651196)
		(end 300.76648 -157.764226)
		(stroke
			(width 0.08255)
			(type default)
		)
		(layer "In15.Cu")
	)
	(gr_line
		(start 300.689772 -378.67209)
		(end 300.816772 -378.79909)
		(stroke
			(width 0.08255)
			(type default)
		)
		(layer "In15.Cu")
	)
	(gr_line
		(start 300.689772 -378.290074)
		(end 300.689772 -378.67209)
		(stroke
			(width 0.08255)
			(type default)
		)
		(layer "In15.Cu")
	)
	(gr_line
		(start 301.26432 -157.764226)
		(end 301.37735 -157.651196)
		(stroke
			(width 0.08255)
			(type default)
		)
		(layer "In15.Cu")
	)
	(gr_line
		(start 301.37735 -157.651196)
		(end 301.87265 -157.651196)
		(stroke
			(width 0.08255)
			(type default)
		)
		(layer "In15.Cu")
	)
	(gr_line
		(start 301.87265 -157.651196)
		(end 301.98568 -157.764226)
		(stroke
			(width 0.08255)
			(type default)
		)
		(layer "In15.Cu")
	)
	(gr_line
		(start 302.48352 -157.764226)
		(end 302.59655 -157.651196)
		(stroke
			(width 0.08255)
			(type default)
		)
		(layer "In15.Cu")
	)
	(gr_line
		(start 302.59655 -157.651196)
		(end 303.09185 -157.651196)
		(stroke
			(width 0.08255)
			(type default)
		)
		(layer "In15.Cu")
	)
	(gr_line
		(start 302.88992 -380.69012)
		(end 302.88992 -380.308104)
		(stroke
			(width 0.08255)
			(type default)
		)
		(layer "In15.Cu")
	)
	(gr_line
		(start 302.88992 -380.308104)
		(end 303.01692 -380.181104)
		(stroke
			(width 0.08255)
			(type default)
		)
		(layer "In15.Cu")
	)
	(gr_line
		(start 302.88992 -379.772164)
		(end 303.01692 -379.899164)
		(stroke
			(width 0.08255)
			(type default)
		)
		(layer "In15.Cu")
	)
	(gr_line
		(start 302.88992 -379.390148)
		(end 302.88992 -379.772164)
		(stroke
			(width 0.08255)
			(type default)
		)
		(layer "In15.Cu")
	)
	(gr_line
		(start 303.09185 -157.651196)
		(end 303.20488 -157.764226)
		(stroke
			(width 0.08255)
			(type default)
		)
		(layer "In15.Cu")
	)
	(gr_line
		(start 303.4919 -366.102646)
		(end 303.821846 -365.732822)
		(stroke
			(width 0.08255)
			(type default)
		)
		(layer "In15.Cu")
	)
	(gr_line
		(start 303.501044 -366.262412)
		(end 303.4919 -366.102646)
		(stroke
			(width 0.08255)
			(type default)
		)
		(layer "In15.Cu")
	)
	(gr_line
		(start 303.70272 -157.764226)
		(end 303.81575 -157.651196)
		(stroke
			(width 0.08255)
			(type default)
		)
		(layer "In15.Cu")
	)
	(gr_line
		(start 303.81575 -157.651196)
		(end 304.31105 -157.651196)
		(stroke
			(width 0.08255)
			(type default)
		)
		(layer "In15.Cu")
	)
	(gr_line
		(start 303.821846 -365.732822)
		(end 303.981866 -365.723678)
		(stroke
			(width 0.08255)
			(type default)
		)
		(layer "In15.Cu")
	)
	(gr_line
		(start 304.303938 -365.193072)
		(end 304.634138 -364.823248)
		(stroke
			(width 0.08255)
			(type default)
		)
		(layer "In15.Cu")
	)
	(gr_line
		(start 304.31105 -157.651196)
		(end 304.42408 -157.764226)
		(stroke
			(width 0.08255)
			(type default)
		)
		(layer "In15.Cu")
	)
	(gr_line
		(start 304.313082 -365.352838)
		(end 304.303938 -365.193072)
		(stroke
			(width 0.08255)
			(type default)
		)
		(layer "In15.Cu")
	)
	(gr_line
		(start 304.634138 -364.823248)
		(end 304.793904 -364.814104)
		(stroke
			(width 0.08255)
			(type default)
		)
		(layer "In15.Cu")
	)
	(gr_line
		(start 304.92192 -157.764226)
		(end 305.03495 -157.651196)
		(stroke
			(width 0.08255)
			(type default)
		)
		(layer "In15.Cu")
	)
	(gr_line
		(start 305.03495 -157.651196)
		(end 305.53025 -157.651196)
		(stroke
			(width 0.08255)
			(type default)
		)
		(layer "In15.Cu")
	)
	(gr_line
		(start 305.115976 -364.283498)
		(end 305.446176 -363.913674)
		(stroke
			(width 0.08255)
			(type default)
		)
		(layer "In15.Cu")
	)
	(gr_line
		(start 305.12512 -364.443518)
		(end 305.115976 -364.283498)
		(stroke
			(width 0.08255)
			(type default)
		)
		(layer "In15.Cu")
	)
	(gr_line
		(start 305.291236 -358.198928)
		(end 305.461416 -357.7336)
		(stroke
			(width 0.08255)
			(type default)
		)
		(layer "In15.Cu")
	)
	(gr_line
		(start 305.314604 -351.47631)
		(end 305.48453 -351.010982)
		(stroke
			(width 0.08255)
			(type default)
		)
		(layer "In15.Cu")
	)
	(gr_line
		(start 305.35118 -358.32796)
		(end 305.291236 -358.198928)
		(stroke
			(width 0.08255)
			(type default)
		)
		(layer "In15.Cu")
	)
	(gr_line
		(start 305.365404 -354.876862)
		(end 305.53787 -354.412296)
		(stroke
			(width 0.08255)
			(type default)
		)
		(layer "In15.Cu")
	)
	(gr_line
		(start 305.374294 -351.605342)
		(end 305.314604 -351.47631)
		(stroke
			(width 0.08255)
			(type default)
		)
		(layer "In15.Cu")
	)
	(gr_line
		(start 305.42484 -355.006402)
		(end 305.365404 -354.876862)
		(stroke
			(width 0.08255)
			(type default)
		)
		(layer "In15.Cu")
	)
	(gr_line
		(start 305.446176 -363.913674)
		(end 305.606196 -363.90453)
		(stroke
			(width 0.08255)
			(type default)
		)
		(layer "In15.Cu")
	)
	(gr_line
		(start 305.461416 -357.7336)
		(end 305.590702 -357.673402)
		(stroke
			(width 0.08255)
			(type default)
		)
		(layer "In15.Cu")
	)
	(gr_line
		(start 305.470814 -366.37468)
		(end 305.812444 -366.015524)
		(stroke
			(width 0.08255)
			(type default)
		)
		(layer "In15.Cu")
	)
	(gr_line
		(start 305.473862 -366.498886)
		(end 305.470814 -366.37468)
		(stroke
			(width 0.08255)
			(type default)
		)
		(layer "In15.Cu")
	)
	(gr_line
		(start 305.483768 -319.941448)
		(end 305.483768 -319.913)
		(stroke
			(width 0.05715)
			(type default)
		)
		(layer "In15.Cu")
	)
	(gr_line
		(start 305.483768 -319.913)
		(end 305.529488 -319.86728)
		(stroke
			(width 0.05715)
			(type default)
		)
		(layer "In15.Cu")
	)
	(gr_line
		(start 305.484276 -347.88983)
		(end 305.653948 -347.423994)
		(stroke
			(width 0.08255)
			(type default)
		)
		(layer "In15.Cu")
	)
	(gr_line
		(start 305.48453 -351.010982)
		(end 305.613308 -350.951038)
		(stroke
			(width 0.08255)
			(type default)
		)
		(layer "In15.Cu")
	)
	(gr_line
		(start 305.53025 -157.651196)
		(end 305.64328 -157.764226)
		(stroke
			(width 0.08255)
			(type default)
		)
		(layer "In15.Cu")
	)
	(gr_line
		(start 305.5366 -348.002352)
		(end 305.484276 -347.88983)
		(stroke
			(width 0.08255)
			(type default)
		)
		(layer "In15.Cu")
	)
	(gr_line
		(start 305.53787 -354.412296)
		(end 305.66741 -354.353368)
		(stroke
			(width 0.08255)
			(type default)
		)
		(layer "In15.Cu")
	)
	(gr_line
		(start 305.615086 -350.950276)
		(end 305.614832 -350.950276)
		(stroke
			(width 0.08255)
			(type default)
		)
		(layer "In15.Cu")
	)
	(gr_line
		(start 305.616864 -358.426258)
		(end 305.857148 -357.769922)
		(stroke
			(width 0.08255)
			(type default)
		)
		(layer "In15.Cu")
	)
	(gr_line
		(start 305.639978 -351.703386)
		(end 305.879754 -351.04705)
		(stroke
			(width 0.08255)
			(type default)
		)
		(layer "In15.Cu")
	)
	(gr_line
		(start 305.653948 -347.423994)
		(end 305.76647 -347.37167)
		(stroke
			(width 0.08255)
			(type default)
		)
		(layer "In15.Cu")
	)
	(gr_line
		(start 305.668426 -354.35286)
		(end 305.668934 -354.352606)
		(stroke
			(width 0.08255)
			(type default)
		)
		(layer "In15.Cu")
	)
	(gr_line
		(start 305.668934 -354.352606)
		(end 305.669442 -354.351082)
		(stroke
			(width 0.08255)
			(type default)
		)
		(layer "In15.Cu")
	)
	(gr_line
		(start 305.669442 -354.351082)
		(end 305.669188 -354.351082)
		(stroke
			(width 0.08255)
			(type default)
		)
		(layer "In15.Cu")
	)
	(gr_line
		(start 305.678586 -366.69472)
		(end 306.142644 -366.206786)
		(stroke
			(width 0.08255)
			(type default)
		)
		(layer "In15.Cu")
	)
	(gr_line
		(start 305.7017 -357.077518)
		(end 305.87188 -356.61219)
		(stroke
			(width 0.08255)
			(type default)
		)
		(layer "In15.Cu")
	)
	(gr_line
		(start 305.724306 -350.3549)
		(end 305.894232 -349.889318)
		(stroke
			(width 0.08255)
			(type default)
		)
		(layer "In15.Cu")
	)
	(gr_line
		(start 305.761644 -357.20655)
		(end 305.7017 -357.077518)
		(stroke
			(width 0.08255)
			(type default)
		)
		(layer "In15.Cu")
	)
	(gr_line
		(start 305.781456 -353.757738)
		(end 305.953922 -353.293172)
		(stroke
			(width 0.08255)
			(type default)
		)
		(layer "In15.Cu")
	)
	(gr_line
		(start 305.78425 -350.483424)
		(end 305.724306 -350.3549)
		(stroke
			(width 0.08255)
			(type default)
		)
		(layer "In15.Cu")
	)
	(gr_line
		(start 305.784758 -350.484948)
		(end 305.785012 -350.485202)
		(stroke
			(width 0.08255)
			(type default)
		)
		(layer "In15.Cu")
	)
	(gr_line
		(start 305.802538 -348.100142)
		(end 306.03317 -347.467428)
		(stroke
			(width 0.08255)
			(type default)
		)
		(layer "In15.Cu")
	)
	(gr_line
		(start 305.812444 -366.015524)
		(end 305.93665 -366.012222)
		(stroke
			(width 0.08255)
			(type default)
		)
		(layer "In15.Cu")
	)
	(gr_line
		(start 305.840638 -353.88677)
		(end 305.781456 -353.757738)
		(stroke
			(width 0.08255)
			(type default)
		)
		(layer "In15.Cu")
	)
	(gr_line
		(start 305.840892 -353.888294)
		(end 305.8414 -353.888548)
		(stroke
			(width 0.08255)
			(type default)
		)
		(layer "In15.Cu")
	)
	(gr_line
		(start 305.87188 -356.61219)
		(end 306.001166 -356.552246)
		(stroke
			(width 0.08255)
			(type default)
		)
		(layer "In15.Cu")
	)
	(gr_line
		(start 305.884326 -346.791788)
		(end 306.054252 -346.326206)
		(stroke
			(width 0.08255)
			(type default)
		)
		(layer "In15.Cu")
	)
	(gr_line
		(start 305.894232 -349.889318)
		(end 306.02301 -349.829628)
		(stroke
			(width 0.08255)
			(type default)
		)
		(layer "In15.Cu")
	)
	(gr_line
		(start 305.936904 -346.90431)
		(end 305.884326 -346.791788)
		(stroke
			(width 0.08255)
			(type default)
		)
		(layer "In15.Cu")
	)
	(gr_line
		(start 305.953922 -353.293172)
		(end 306.082954 -353.234244)
		(stroke
			(width 0.08255)
			(type default)
		)
		(layer "In15.Cu")
	)
	(gr_line
		(start 305.985418 -316.229492)
		(end 306.099718 -316.115192)
		(stroke
			(width 0.05715)
			(type default)
		)
		(layer "In15.Cu")
	)
	(gr_line
		(start 306.024788 -349.828866)
		(end 306.024534 -349.828866)
		(stroke
			(width 0.08255)
			(type default)
		)
		(layer "In15.Cu")
	)
	(gr_line
		(start 306.027328 -357.304848)
		(end 306.267358 -356.648766)
		(stroke
			(width 0.08255)
			(type default)
		)
		(layer "In15.Cu")
	)
	(gr_line
		(start 306.04968 -350.581722)
		(end 306.289456 -349.92564)
		(stroke
			(width 0.08255)
			(type default)
		)
		(layer "In15.Cu")
	)
	(gr_line
		(start 306.054252 -346.326206)
		(end 306.16652 -346.273882)
		(stroke
			(width 0.08255)
			(type default)
		)
		(layer "In15.Cu")
	)
	(gr_line
		(start 306.084732 -353.233482)
		(end 306.084224 -353.233482)
		(stroke
			(width 0.08255)
			(type default)
		)
		(layer "In15.Cu")
	)
	(gr_line
		(start 306.099718 -316.115192)
		(end 306.099718 -315.849762)
		(stroke
			(width 0.05715)
			(type default)
		)
		(layer "In15.Cu")
	)
	(gr_line
		(start 306.112164 -355.956362)
		(end 306.282344 -355.491034)
		(stroke
			(width 0.08255)
			(type default)
		)
		(layer "In15.Cu")
	)
	(gr_line
		(start 306.134008 -349.23349)
		(end 306.303934 -348.767908)
		(stroke
			(width 0.08255)
			(type default)
		)
		(layer "In15.Cu")
	)
	(gr_line
		(start 306.168044 -346.27312)
		(end 306.168298 -346.27312)
		(stroke
			(width 0.08255)
			(type default)
		)
		(layer "In15.Cu")
	)
	(gr_line
		(start 306.172108 -356.085394)
		(end 306.112164 -355.956362)
		(stroke
			(width 0.08255)
			(type default)
		)
		(layer "In15.Cu")
	)
	(gr_line
		(start 306.193952 -349.362014)
		(end 306.134008 -349.23349)
		(stroke
			(width 0.08255)
			(type default)
		)
		(layer "In15.Cu")
	)
	(gr_line
		(start 306.194206 -349.363792)
		(end 306.194714 -349.363792)
		(stroke
			(width 0.08255)
			(type default)
		)
		(layer "In15.Cu")
	)
	(gr_line
		(start 306.197254 -352.638614)
		(end 306.36972 -352.174048)
		(stroke
			(width 0.08255)
			(type default)
		)
		(layer "In15.Cu")
	)
	(gr_line
		(start 306.202588 -347.0021)
		(end 306.43322 -346.36964)
		(stroke
			(width 0.08255)
			(type default)
		)
		(layer "In15.Cu")
	)
	(gr_line
		(start 306.256436 -352.767646)
		(end 306.197254 -352.638614)
		(stroke
			(width 0.08255)
			(type default)
		)
		(layer "In15.Cu")
	)
	(gr_line
		(start 306.25669 -352.76917)
		(end 306.257198 -352.769424)
		(stroke
			(width 0.08255)
			(type default)
		)
		(layer "In15.Cu")
	)
	(gr_line
		(start 306.275994 -365.527844)
		(end 306.617624 -365.168434)
		(stroke
			(width 0.08255)
			(type default)
		)
		(layer "In15.Cu")
	)
	(gr_line
		(start 306.279042 -365.652304)
		(end 306.275994 -365.527844)
		(stroke
			(width 0.08255)
			(type default)
		)
		(layer "In15.Cu")
	)
	(gr_line
		(start 306.282344 -355.491034)
		(end 306.41163 -355.43109)
		(stroke
			(width 0.08255)
			(type default)
		)
		(layer "In15.Cu")
	)
	(gr_line
		(start 306.29733 -345.721432)
		(end 306.484528 -345.208352)
		(stroke
			(width 0.08255)
			(type default)
		)
		(layer "In15.Cu")
	)
	(gr_line
		(start 306.303934 -348.767908)
		(end 306.432712 -348.708218)
		(stroke
			(width 0.08255)
			(type default)
		)
		(layer "In15.Cu")
	)
	(gr_line
		(start 306.336954 -345.806776)
		(end 306.29733 -345.721432)
		(stroke
			(width 0.08255)
			(type default)
		)
		(layer "In15.Cu")
	)
	(gr_line
		(start 306.36972 -352.174048)
		(end 306.498752 -352.11512)
		(stroke
			(width 0.08255)
			(type default)
		)
		(layer "In15.Cu")
	)
	(gr_line
		(start 306.43449 -348.707456)
		(end 306.434236 -348.707202)
		(stroke
			(width 0.08255)
			(type default)
		)
		(layer "In15.Cu")
	)
	(gr_line
		(start 306.437792 -356.183692)
		(end 306.677822 -355.52761)
		(stroke
			(width 0.08255)
			(type default)
		)
		(layer "In15.Cu")
	)
	(gr_line
		(start 306.459382 -349.460566)
		(end 306.699158 -348.803976)
		(stroke
			(width 0.08255)
			(type default)
		)
		(layer "In15.Cu")
	)
	(gr_line
		(start 306.483766 -365.847884)
		(end 306.947824 -365.35995)
		(stroke
			(width 0.08255)
			(type default)
		)
		(layer "In15.Cu")
	)
	(gr_line
		(start 306.484528 -345.208352)
		(end 306.567078 -345.175586)
		(stroke
			(width 0.08255)
			(type default)
		)
		(layer "In15.Cu")
	)
	(gr_line
		(start 306.50053 -352.114358)
		(end 306.500022 -352.114104)
		(stroke
			(width 0.08255)
			(type default)
		)
		(layer "In15.Cu")
	)
	(gr_line
		(start 306.602384 -345.905074)
		(end 306.605178 -345.897962)
		(stroke
			(width 0.08255)
			(type default)
		)
		(layer "In15.Cu")
	)
	(gr_line
		(start 306.605432 -345.8972)
		(end 306.83327 -345.271852)
		(stroke
			(width 0.08255)
			(type default)
		)
		(layer "In15.Cu")
	)
	(gr_line
		(start 306.617624 -365.168434)
		(end 306.74183 -365.165386)
		(stroke
			(width 0.08255)
			(type default)
		)
		(layer "In15.Cu")
	)
	(gr_line
		(start 306.803044 -157.413706)
		(end 306.803044 -157.253686)
		(stroke
			(width 0.08255)
			(type default)
		)
		(layer "In15.Cu")
	)
	(gr_line
		(start 306.803044 -157.253686)
		(end 307.153564 -156.903166)
		(stroke
			(width 0.08255)
			(type default)
		)
		(layer "In15.Cu")
	)
	(gr_line
		(start 307.081174 -364.681008)
		(end 307.422804 -364.321852)
		(stroke
			(width 0.08255)
			(type default)
		)
		(layer "In15.Cu")
	)
	(gr_line
		(start 307.084222 -364.805468)
		(end 307.081174 -364.681008)
		(stroke
			(width 0.08255)
			(type default)
		)
		(layer "In15.Cu")
	)
	(gr_line
		(start 307.153564 -156.903166)
		(end 307.313584 -156.903166)
		(stroke
			(width 0.08255)
			(type default)
		)
		(layer "In15.Cu")
	)
	(gr_line
		(start 307.288946 -365.001048)
		(end 307.753004 -364.513114)
		(stroke
			(width 0.08255)
			(type default)
		)
		(layer "In15.Cu")
	)
	(gr_line
		(start 307.419756 -117.471952)
		(end 307.132736 -117.758972)
		(stroke
			(width 0.08255)
			(type default)
		)
		(layer "In15.Cu")
	)
	(gr_line
		(start 307.422804 -364.321852)
		(end 307.547264 -364.31855)
		(stroke
			(width 0.08255)
			(type default)
		)
		(layer "In15.Cu")
	)
	(gr_line
		(start 307.427376 -117.471952)
		(end 307.419756 -117.471952)
		(stroke
			(width 0.08255)
			(type default)
		)
		(layer "In15.Cu")
	)
	(gr_line
		(start 307.665882 -319.941448)
		(end 307.665882 -319.913)
		(stroke
			(width 0.05715)
			(type default)
		)
		(layer "In15.Cu")
	)
	(gr_line
		(start 307.665882 -319.913)
		(end 307.620162 -319.86728)
		(stroke
			(width 0.05715)
			(type default)
		)
		(layer "In15.Cu")
	)
	(gr_line
		(start 307.885592 -316.419992)
		(end 307.999892 -316.534292)
		(stroke
			(width 0.05715)
			(type default)
		)
		(layer "In15.Cu")
	)
	(gr_line
		(start 307.885846 -363.816138)
		(end 308.227476 -363.456982)
		(stroke
			(width 0.08255)
			(type default)
		)
		(layer "In15.Cu")
	)
	(gr_line
		(start 307.889402 -363.958632)
		(end 307.885846 -363.816138)
		(stroke
			(width 0.08255)
			(type default)
		)
		(layer "In15.Cu")
	)
	(gr_line
		(start 307.999892 -316.534292)
		(end 307.999892 -316.799722)
		(stroke
			(width 0.05715)
			(type default)
		)
		(layer "In15.Cu")
	)
	(gr_line
		(start 308.094126 -364.154212)
		(end 308.57571 -363.64799)
		(stroke
			(width 0.08255)
			(type default)
		)
		(layer "In15.Cu")
	)
	(gr_line
		(start 308.227476 -363.456982)
		(end 308.369716 -363.453426)
		(stroke
			(width 0.08255)
			(type default)
		)
		(layer "In15.Cu")
	)
	(gr_line
		(start 310.761634 -340.641686)
		(end 310.780176 -340.591902)
		(stroke
			(width 0.08255)
			(type default)
		)
		(layer "In15.Cu")
	)
	(gr_line
		(start 310.780176 -340.591902)
		(end 310.78043 -340.591902)
		(stroke
			(width 0.08255)
			(type default)
		)
		(layer "In15.Cu")
	)
	(gr_line
		(start 310.78043 -340.591902)
		(end 310.81599 -340.552024)
		(stroke
			(width 0.08255)
			(type default)
		)
		(layer "In15.Cu")
	)
	(gr_line
		(start 312.065162 -309.199788)
		(end 311.799732 -309.199788)
		(stroke
			(width 0.05715)
			(type default)
		)
		(layer "In15.Cu")
	)
	(gr_line
		(start 312.065162 -307.299868)
		(end 311.799732 -307.299868)
		(stroke
			(width 0.05715)
			(type default)
		)
		(layer "In15.Cu")
	)
	(gr_line
		(start 312.065162 -305.399948)
		(end 311.799732 -305.399948)
		(stroke
			(width 0.05715)
			(type default)
		)
		(layer "In15.Cu")
	)
	(gr_line
		(start 312.179462 -309.314088)
		(end 312.065162 -309.199788)
		(stroke
			(width 0.05715)
			(type default)
		)
		(layer "In15.Cu")
	)
	(gr_line
		(start 312.179462 -307.414168)
		(end 312.065162 -307.299868)
		(stroke
			(width 0.05715)
			(type default)
		)
		(layer "In15.Cu")
	)
	(gr_line
		(start 312.179462 -305.514248)
		(end 312.065162 -305.399948)
		(stroke
			(width 0.05715)
			(type default)
		)
		(layer "In15.Cu")
	)
	(gr_line
		(start 312.369962 -309.314088)
		(end 312.484262 -309.199788)
		(stroke
			(width 0.05715)
			(type default)
		)
		(layer "In15.Cu")
	)
	(gr_line
		(start 312.369962 -307.414168)
		(end 312.484262 -307.299868)
		(stroke
			(width 0.05715)
			(type default)
		)
		(layer "In15.Cu")
	)
	(gr_line
		(start 312.484262 -309.199788)
		(end 312.749692 -309.199788)
		(stroke
			(width 0.05715)
			(type default)
		)
		(layer "In15.Cu")
	)
	(gr_line
		(start 312.484262 -307.299868)
		(end 312.749692 -307.299868)
		(stroke
			(width 0.05715)
			(type default)
		)
		(layer "In15.Cu")
	)
	(gr_line
		(start 313.45886 -329.181206)
		(end 313.628786 -328.715624)
		(stroke
			(width 0.08255)
			(type default)
		)
		(layer "In15.Cu")
	)
	(gr_line
		(start 313.518804 -329.309984)
		(end 313.45886 -329.181206)
		(stroke
			(width 0.08255)
			(type default)
		)
		(layer "In15.Cu")
	)
	(gr_line
		(start 313.519312 -329.311508)
		(end 313.519566 -329.311508)
		(stroke
			(width 0.08255)
			(type default)
		)
		(layer "In15.Cu")
	)
	(gr_line
		(start 313.628786 -328.715624)
		(end 313.757818 -328.655934)
		(stroke
			(width 0.08255)
			(type default)
		)
		(layer "In15.Cu")
	)
	(gr_line
		(start 313.784488 -329.408282)
		(end 314.024264 -328.751946)
		(stroke
			(width 0.08255)
			(type default)
		)
		(layer "In15.Cu")
	)
	(gr_line
		(start 313.868562 -328.059796)
		(end 314.038488 -327.594214)
		(stroke
			(width 0.08255)
			(type default)
		)
		(layer "In15.Cu")
	)
	(gr_line
		(start 313.928506 -328.188574)
		(end 313.868562 -328.059796)
		(stroke
			(width 0.08255)
			(type default)
		)
		(layer "In15.Cu")
	)
	(gr_line
		(start 313.965336 -310.149748)
		(end 313.699906 -310.149748)
		(stroke
			(width 0.05715)
			(type default)
		)
		(layer "In15.Cu")
	)
	(gr_line
		(start 313.965336 -308.249828)
		(end 313.699906 -308.249828)
		(stroke
			(width 0.05715)
			(type default)
		)
		(layer "In15.Cu")
	)
	(gr_line
		(start 313.965336 -304.449734)
		(end 313.699906 -304.449734)
		(stroke
			(width 0.05715)
			(type default)
		)
		(layer "In15.Cu")
	)
	(gr_line
		(start 314.038488 -327.594214)
		(end 314.16752 -327.534524)
		(stroke
			(width 0.08255)
			(type default)
		)
		(layer "In15.Cu")
	)
	(gr_line
		(start 314.079636 -310.264048)
		(end 313.965336 -310.149748)
		(stroke
			(width 0.05715)
			(type default)
		)
		(layer "In15.Cu")
	)
	(gr_line
		(start 314.079636 -308.364128)
		(end 313.965336 -308.249828)
		(stroke
			(width 0.05715)
			(type default)
		)
		(layer "In15.Cu")
	)
	(gr_line
		(start 314.079636 -304.564034)
		(end 313.965336 -304.449734)
		(stroke
			(width 0.05715)
			(type default)
		)
		(layer "In15.Cu")
	)
	(gr_line
		(start 314.169044 -327.533762)
		(end 314.16879 -327.533762)
		(stroke
			(width 0.08255)
			(type default)
		)
		(layer "In15.Cu")
	)
	(gr_line
		(start 314.19419 -328.286872)
		(end 314.433712 -327.630536)
		(stroke
			(width 0.08255)
			(type default)
		)
		(layer "In15.Cu")
	)
	(gr_line
		(start 314.270136 -310.264048)
		(end 314.384436 -310.149748)
		(stroke
			(width 0.05715)
			(type default)
		)
		(layer "In15.Cu")
	)
	(gr_line
		(start 314.270136 -304.564034)
		(end 314.384436 -304.449734)
		(stroke
			(width 0.05715)
			(type default)
		)
		(layer "In15.Cu")
	)
	(gr_line
		(start 314.384436 -310.149748)
		(end 314.649866 -310.149748)
		(stroke
			(width 0.05715)
			(type default)
		)
		(layer "In15.Cu")
	)
	(gr_line
		(start 314.384436 -304.449734)
		(end 314.649866 -304.449734)
		(stroke
			(width 0.05715)
			(type default)
		)
		(layer "In15.Cu")
	)
	(gr_line
		(start 315.324744 -310.999124)
		(end 315.324744 -310.934862)
		(stroke
			(width 0.05715)
			(type default)
		)
		(layer "In15.Cu")
	)
	(gr_line
		(start 315.324744 -310.934862)
		(end 315.324236 -310.934608)
		(stroke
			(width 0.05715)
			(type default)
		)
		(layer "In15.Cu")
	)
	(gr_line
		(start 315.34481 -311.01919)
		(end 315.324744 -310.999124)
		(stroke
			(width 0.05715)
			(type default)
		)
		(layer "In15.Cu")
	)
	(gr_line
		(start 315.524134 -310.799734)
		(end 315.459872 -310.799734)
		(stroke
			(width 0.05715)
			(type default)
		)
		(layer "In15.Cu")
	)
	(gr_line
		(start 315.5442 -310.8198)
		(end 315.524134 -310.799734)
		(stroke
			(width 0.05715)
			(type default)
		)
		(layer "In15.Cu")
	)
	(gr_line
		(start 315.8236 -309.815738)
		(end 315.77788 -309.770018)
		(stroke
			(width 0.05715)
			(type default)
		)
		(layer "In15.Cu")
	)
	(gr_line
		(start 315.8236 -309.533798)
		(end 315.77788 -309.579518)
		(stroke
			(width 0.05715)
			(type default)
		)
		(layer "In15.Cu")
	)
	(gr_line
		(start 315.8236 -308.865778)
		(end 315.77788 -308.820058)
		(stroke
			(width 0.05715)
			(type default)
		)
		(layer "In15.Cu")
	)
	(gr_line
		(start 315.8236 -307.915818)
		(end 315.77788 -307.870098)
		(stroke
			(width 0.05715)
			(type default)
		)
		(layer "In15.Cu")
	)
	(gr_line
		(start 315.8236 -307.633878)
		(end 315.77788 -307.679598)
		(stroke
			(width 0.05715)
			(type default)
		)
		(layer "In15.Cu")
	)
	(gr_line
		(start 315.8236 -306.015898)
		(end 315.77788 -305.970178)
		(stroke
			(width 0.05715)
			(type default)
		)
		(layer "In15.Cu")
	)
	(gr_line
		(start 315.8236 -305.065684)
		(end 315.77788 -305.019964)
		(stroke
			(width 0.05715)
			(type default)
		)
		(layer "In15.Cu")
	)
	(gr_line
		(start 315.8236 -304.783744)
		(end 315.77788 -304.829464)
		(stroke
			(width 0.05715)
			(type default)
		)
		(layer "In15.Cu")
	)
	(gr_line
		(start 315.852048 -309.815738)
		(end 315.8236 -309.815738)
		(stroke
			(width 0.05715)
			(type default)
		)
		(layer "In15.Cu")
	)
	(gr_line
		(start 315.852048 -309.533798)
		(end 315.8236 -309.533798)
		(stroke
			(width 0.05715)
			(type default)
		)
		(layer "In15.Cu")
	)
	(gr_line
		(start 315.852048 -308.865778)
		(end 315.8236 -308.865778)
		(stroke
			(width 0.05715)
			(type default)
		)
		(layer "In15.Cu")
	)
	(gr_line
		(start 315.852048 -307.915818)
		(end 315.8236 -307.915818)
		(stroke
			(width 0.05715)
			(type default)
		)
		(layer "In15.Cu")
	)
	(gr_line
		(start 315.852048 -307.633878)
		(end 315.8236 -307.633878)
		(stroke
			(width 0.05715)
			(type default)
		)
		(layer "In15.Cu")
	)
	(gr_line
		(start 315.852048 -306.015898)
		(end 315.8236 -306.015898)
		(stroke
			(width 0.05715)
			(type default)
		)
		(layer "In15.Cu")
	)
	(gr_line
		(start 315.852048 -305.065684)
		(end 315.8236 -305.065684)
		(stroke
			(width 0.05715)
			(type default)
		)
		(layer "In15.Cu")
	)
	(gr_line
		(start 315.852048 -304.783744)
		(end 315.8236 -304.783744)
		(stroke
			(width 0.05715)
			(type default)
		)
		(layer "In15.Cu")
	)
	(gr_line
		(start 318.969136 -339.130894)
		(end 319.250314 -338.722462)
		(stroke
			(width 0.08255)
			(type default)
		)
		(layer "In15.Cu")
	)
	(gr_line
		(start 318.998346 -339.28812)
		(end 318.969136 -339.130894)
		(stroke
			(width 0.08255)
			(type default)
		)
		(layer "In15.Cu")
	)
	(gr_line
		(start 319.250314 -338.722462)
		(end 319.407794 -338.693506)
		(stroke
			(width 0.08255)
			(type default)
		)
		(layer "In15.Cu")
	)
	(gr_line
		(start 319.660778 -338.126578)
		(end 319.941956 -337.718146)
		(stroke
			(width 0.08255)
			(type default)
		)
		(layer "In15.Cu")
	)
	(gr_line
		(start 319.689734 -338.284058)
		(end 319.660778 -338.126578)
		(stroke
			(width 0.08255)
			(type default)
		)
		(layer "In15.Cu")
	)
	(gr_line
		(start 319.941956 -337.718146)
		(end 320.099182 -337.68919)
		(stroke
			(width 0.08255)
			(type default)
		)
		(layer "In15.Cu")
	)
	(gr_line
		(start 320.35242 -337.122262)
		(end 320.633598 -336.71383)
		(stroke
			(width 0.08255)
			(type default)
		)
		(layer "In15.Cu")
	)
	(gr_line
		(start 320.381376 -337.279488)
		(end 320.35242 -337.122262)
		(stroke
			(width 0.08255)
			(type default)
		)
		(layer "In15.Cu")
	)
	(gr_line
		(start 320.633598 -336.71383)
		(end 320.79057 -336.684874)
		(stroke
			(width 0.08255)
			(type default)
		)
		(layer "In15.Cu")
	)
	(gr_line
		(start 321.317112 -339.974936)
		(end 321.56146 -339.543644)
		(stroke
			(width 0.08255)
			(type default)
		)
		(layer "In15.Cu")
	)
	(gr_line
		(start 321.359784 -340.129622)
		(end 321.317112 -339.974936)
		(stroke
			(width 0.08255)
			(type default)
		)
		(layer "In15.Cu")
	)
	(gr_line
		(start 321.56146 -339.543644)
		(end 321.715638 -339.500972)
		(stroke
			(width 0.08255)
			(type default)
		)
		(layer "In15.Cu")
	)
	(gr_line
		(start 321.60591 -340.26983)
		(end 321.96278 -339.639402)
		(stroke
			(width 0.08255)
			(type default)
		)
		(layer "In15.Cu")
	)
	(gr_line
		(start 321.917822 -338.913724)
		(end 322.16217 -338.482432)
		(stroke
			(width 0.08255)
			(type default)
		)
		(layer "In15.Cu")
	)
	(gr_line
		(start 321.960748 -339.068156)
		(end 321.917822 -338.913724)
		(stroke
			(width 0.08255)
			(type default)
		)
		(layer "In15.Cu")
	)
	(gr_line
		(start 322.16217 -338.482432)
		(end 322.316348 -338.43976)
		(stroke
			(width 0.08255)
			(type default)
		)
		(layer "In15.Cu")
	)
	(gr_line
		(start 322.20662 -339.208364)
		(end 322.56349 -338.57819)
		(stroke
			(width 0.08255)
			(type default)
		)
		(layer "In15.Cu")
	)
	(gr_line
		(start 323.504814 -327.833482)
		(end 323.836792 -327.465436)
		(stroke
			(width 0.08255)
			(type default)
		)
		(layer "In15.Cu")
	)
	(gr_line
		(start 323.51218 -327.975722)
		(end 323.504814 -327.833482)
		(stroke
			(width 0.08255)
			(type default)
		)
		(layer "In15.Cu")
	)
	(gr_line
		(start 323.72173 -328.165968)
		(end 324.189852 -327.6473)
		(stroke
			(width 0.08255)
			(type default)
		)
		(layer "In15.Cu")
	)
	(gr_line
		(start 323.836792 -327.465436)
		(end 323.979032 -327.45807)
		(stroke
			(width 0.08255)
			(type default)
		)
		(layer "In15.Cu")
	)
	(gr_line
		(start 324.30466 -326.947022)
		(end 324.636892 -326.57923)
		(stroke
			(width 0.08255)
			(type default)
		)
		(layer "In15.Cu")
	)
	(gr_line
		(start 324.312026 -327.089262)
		(end 324.30466 -326.947022)
		(stroke
			(width 0.08255)
			(type default)
		)
		(layer "In15.Cu")
	)
	(gr_line
		(start 324.521576 -327.279762)
		(end 324.989698 -326.76084)
		(stroke
			(width 0.08255)
			(type default)
		)
		(layer "In15.Cu")
	)
	(gr_line
		(start 324.636892 -326.57923)
		(end 324.778624 -326.571864)
		(stroke
			(width 0.08255)
			(type default)
		)
		(layer "In15.Cu")
	)
	(gr_line
		(start 325.22668 -330.042266)
		(end 325.507858 -329.634088)
		(stroke
			(width 0.08255)
			(type default)
		)
		(layer "In15.Cu")
	)
	(gr_line
		(start 325.25589 -330.199492)
		(end 325.22668 -330.042266)
		(stroke
			(width 0.08255)
			(type default)
		)
		(layer "In15.Cu")
	)
	(gr_line
		(start 325.507858 -329.634088)
		(end 325.665338 -329.604878)
		(stroke
			(width 0.08255)
			(type default)
		)
		(layer "In15.Cu")
	)
	(gr_line
		(start 377.689872 -371.972078)
		(end 377.816872 -372.099078)
		(stroke
			(width 0.08255)
			(type default)
		)
		(layer "In15.Cu")
	)
	(gr_line
		(start 377.689872 -371.590062)
		(end 377.689872 -371.972078)
		(stroke
			(width 0.08255)
			(type default)
		)
		(layer "In15.Cu")
	)
	(gr_line
		(start 386.489956 -371.972078)
		(end 386.616956 -372.099078)
		(stroke
			(width 0.08255)
			(type default)
		)
		(layer "In15.Cu")
	)
	(gr_line
		(start 386.489956 -371.590062)
		(end 386.489956 -371.972078)
		(stroke
			(width 0.08255)
			(type default)
		)
		(layer "In15.Cu")
	)
	(gr_line
		(start 390.87552 -339.659214)
		(end 390.892284 -339.536278)
		(stroke
			(width 0.08255)
			(type default)
		)
		(layer "In15.Cu")
	)
	(gr_line
		(start 390.892284 -339.536278)
		(end 391.286746 -339.236304)
		(stroke
			(width 0.08255)
			(type default)
		)
		(layer "In15.Cu")
	)
	(gr_line
		(start 391.286746 -339.236304)
		(end 391.409682 -339.252814)
		(stroke
			(width 0.08255)
			(type default)
		)
		(layer "In15.Cu")
	)
	(gr_line
		(start 391.805668 -338.951824)
		(end 391.822178 -338.828888)
		(stroke
			(width 0.08255)
			(type default)
		)
		(layer "In15.Cu")
	)
	(gr_line
		(start 391.822178 -338.828888)
		(end 392.21664 -338.52866)
		(stroke
			(width 0.08255)
			(type default)
		)
		(layer "In15.Cu")
	)
	(gr_line
		(start 392.21664 -338.52866)
		(end 392.33983 -338.545424)
		(stroke
			(width 0.08255)
			(type default)
		)
		(layer "In15.Cu")
	)
	(gr_line
		(start 392.735816 -338.24418)
		(end 392.752326 -338.121498)
		(stroke
			(width 0.08255)
			(type default)
		)
		(layer "In15.Cu")
	)
	(gr_line
		(start 392.752326 -338.121498)
		(end 393.146788 -337.82127)
		(stroke
			(width 0.08255)
			(type default)
		)
		(layer "In15.Cu")
	)
	(gr_line
		(start 393.146788 -337.82127)
		(end 393.269978 -337.838034)
		(stroke
			(width 0.08255)
			(type default)
		)
		(layer "In15.Cu")
	)
	(gr_line
		(start 402.849334 -339.420454)
		(end 403.196806 -339.066886)
		(stroke
			(width 0.08255)
			(type default)
		)
		(layer "In15.Cu")
	)
	(gr_line
		(start 402.850604 -339.54466)
		(end 402.849334 -339.420454)
		(stroke
			(width 0.08255)
			(type default)
		)
		(layer "In15.Cu")
	)
	(gr_line
		(start 403.196806 -339.066886)
		(end 403.321012 -339.065616)
		(stroke
			(width 0.08255)
			(type default)
		)
		(layer "In15.Cu")
	)
	(gr_line
		(start 403.668484 -338.586572)
		(end 404.015702 -338.233004)
		(stroke
			(width 0.08255)
			(type default)
		)
		(layer "In15.Cu")
	)
	(gr_line
		(start 403.6695 -338.710778)
		(end 403.668484 -338.586572)
		(stroke
			(width 0.08255)
			(type default)
		)
		(layer "In15.Cu")
	)
	(gr_line
		(start 404.015702 -338.233004)
		(end 404.139908 -338.231988)
		(stroke
			(width 0.08255)
			(type default)
		)
		(layer "In15.Cu")
	)
	(gr_line
		(start 404.48738 -337.752944)
		(end 404.834598 -337.399376)
		(stroke
			(width 0.08255)
			(type default)
		)
		(layer "In15.Cu")
	)
	(gr_line
		(start 404.488396 -337.87715)
		(end 404.48738 -337.752944)
		(stroke
			(width 0.08255)
			(type default)
		)
		(layer "In15.Cu")
	)
	(gr_line
		(start 404.834598 -337.399376)
		(end 404.958804 -337.39836)
		(stroke
			(width 0.08255)
			(type default)
		)
		(layer "In15.Cu")
	)
	(gr_line
		(start 414.933892 -319.995296)
		(end 414.933892 -319.966848)
		(stroke
			(width 0.05715)
			(type default)
		)
		(layer "In15.Cu")
	)
	(gr_line
		(start 414.933892 -319.966848)
		(end 414.979612 -319.921128)
		(stroke
			(width 0.05715)
			(type default)
		)
		(layer "In15.Cu")
	)
	(gr_line
		(start 415.435542 -318.129666)
		(end 415.549842 -318.015366)
		(stroke
			(width 0.05715)
			(type default)
		)
		(layer "In15.Cu")
	)
	(gr_line
		(start 415.549842 -318.015366)
		(end 415.549842 -317.749936)
		(stroke
			(width 0.05715)
			(type default)
		)
		(layer "In15.Cu")
	)
	(gr_line
		(start 418.733986 -319.969896)
		(end 418.733986 -319.941448)
		(stroke
			(width 0.05715)
			(type default)
		)
		(layer "In15.Cu")
	)
	(gr_line
		(start 418.733986 -319.941448)
		(end 418.779706 -319.895728)
		(stroke
			(width 0.05715)
			(type default)
		)
		(layer "In15.Cu")
	)
	(gr_line
		(start 419.235636 -318.129666)
		(end 419.349936 -318.015366)
		(stroke
			(width 0.05715)
			(type default)
		)
		(layer "In15.Cu")
	)
	(gr_line
		(start 419.349936 -318.015366)
		(end 419.349936 -317.749936)
		(stroke
			(width 0.05715)
			(type default)
		)
		(layer "In15.Cu")
	)
	(gr_line
		(start 420.569644 -164.33673)
		(end 420.569644 -164.176964)
		(stroke
			(width 0.08255)
			(type default)
		)
		(layer "In15.Cu")
	)
	(gr_line
		(start 420.569644 -164.176964)
		(end 420.920164 -163.826444)
		(stroke
			(width 0.08255)
			(type default)
		)
		(layer "In15.Cu")
	)
	(gr_line
		(start 420.769034 -164.537898)
		(end 421.281098 -164.025834)
		(stroke
			(width 0.08255)
			(type default)
		)
		(layer "In15.Cu")
	)
	(gr_line
		(start 420.920164 -163.826444)
		(end 421.07993 -163.826444)
		(stroke
			(width 0.08255)
			(type default)
		)
		(layer "In15.Cu")
	)
	(gr_line
		(start 421.43172 -163.474654)
		(end 421.43172 -163.314634)
		(stroke
			(width 0.08255)
			(type default)
		)
		(layer "In15.Cu")
	)
	(gr_line
		(start 421.43172 -163.314634)
		(end 421.78224 -162.964114)
		(stroke
			(width 0.08255)
			(type default)
		)
		(layer "In15.Cu")
	)
	(gr_line
		(start 421.63111 -163.675822)
		(end 422.143428 -163.163504)
		(stroke
			(width 0.08255)
			(type default)
		)
		(layer "In15.Cu")
	)
	(gr_line
		(start 421.78224 -162.964114)
		(end 421.94226 -162.964114)
		(stroke
			(width 0.08255)
			(type default)
		)
		(layer "In15.Cu")
	)
	(gr_line
		(start 422.29405 -162.612324)
		(end 422.29405 -162.452304)
		(stroke
			(width 0.08255)
			(type default)
		)
		(layer "In15.Cu")
	)
	(gr_line
		(start 422.29405 -162.452304)
		(end 422.64457 -162.101784)
		(stroke
			(width 0.08255)
			(type default)
		)
		(layer "In15.Cu")
	)
	(gr_line
		(start 422.49344 -162.813492)
		(end 423.005758 -162.301174)
		(stroke
			(width 0.08255)
			(type default)
		)
		(layer "In15.Cu")
	)
	(gr_line
		(start 422.64457 -162.101784)
		(end 422.80459 -162.101784)
		(stroke
			(width 0.08255)
			(type default)
		)
		(layer "In15.Cu")
	)
	(gr_line
		(start 423.15638 -161.749994)
		(end 423.15638 -161.589974)
		(stroke
			(width 0.08255)
			(type default)
		)
		(layer "In15.Cu")
	)
	(gr_line
		(start 423.15638 -161.589974)
		(end 423.5069 -161.239454)
		(stroke
			(width 0.08255)
			(type default)
		)
		(layer "In15.Cu")
	)
	(gr_line
		(start 423.35577 -161.951162)
		(end 423.868088 -161.438844)
		(stroke
			(width 0.08255)
			(type default)
		)
		(layer "In15.Cu")
	)
	(gr_line
		(start 423.5069 -161.239454)
		(end 423.66692 -161.239454)
		(stroke
			(width 0.08255)
			(type default)
		)
		(layer "In15.Cu")
	)
	(gr_line
		(start 423.519854 -117.471952)
		(end 423.232834 -117.758972)
		(stroke
			(width 0.08255)
			(type default)
		)
		(layer "In15.Cu")
	)
	(gr_line
		(start 423.526204 -117.188742)
		(end 423.232834 -116.895372)
		(stroke
			(width 0.08255)
			(type default)
		)
		(layer "In15.Cu")
	)
	(gr_line
		(start 423.527474 -117.471952)
		(end 423.519854 -117.471952)
		(stroke
			(width 0.08255)
			(type default)
		)
		(layer "In15.Cu")
	)
	(gr_line
		(start 424.01871 -160.887664)
		(end 424.01871 -160.727644)
		(stroke
			(width 0.08255)
			(type default)
		)
		(layer "In15.Cu")
	)
	(gr_line
		(start 424.01871 -160.727644)
		(end 424.36923 -160.377124)
		(stroke
			(width 0.08255)
			(type default)
		)
		(layer "In15.Cu")
	)
	(gr_line
		(start 424.2181 -161.088832)
		(end 424.730418 -160.576514)
		(stroke
			(width 0.08255)
			(type default)
		)
		(layer "In15.Cu")
	)
	(gr_line
		(start 424.36923 -160.377124)
		(end 424.52925 -160.377124)
		(stroke
			(width 0.08255)
			(type default)
		)
		(layer "In15.Cu")
	)
	(gr_line
		(start 424.790108 -125.72238)
		(end 424.790108 -125.22708)
		(stroke
			(width 0.08255)
			(type default)
		)
		(layer "In15.Cu")
	)
	(gr_line
		(start 424.790108 -125.22708)
		(end 424.903138 -125.11405)
		(stroke
			(width 0.08255)
			(type default)
		)
		(layer "In15.Cu")
	)
	(gr_line
		(start 424.790108 -124.50318)
		(end 424.790108 -124.00788)
		(stroke
			(width 0.08255)
			(type default)
		)
		(layer "In15.Cu")
	)
	(gr_line
		(start 424.790108 -124.00788)
		(end 424.903138 -123.89485)
		(stroke
			(width 0.08255)
			(type default)
		)
		(layer "In15.Cu")
	)
	(gr_line
		(start 424.790108 -123.28398)
		(end 424.790108 -122.78868)
		(stroke
			(width 0.08255)
			(type default)
		)
		(layer "In15.Cu")
	)
	(gr_line
		(start 424.790108 -122.78868)
		(end 424.903138 -122.67565)
		(stroke
			(width 0.08255)
			(type default)
		)
		(layer "In15.Cu")
	)
	(gr_line
		(start 424.790108 -122.06478)
		(end 424.790108 -121.56948)
		(stroke
			(width 0.08255)
			(type default)
		)
		(layer "In15.Cu")
	)
	(gr_line
		(start 424.790108 -121.56948)
		(end 424.903138 -121.45645)
		(stroke
			(width 0.08255)
			(type default)
		)
		(layer "In15.Cu")
	)
	(gr_line
		(start 424.790108 -120.84558)
		(end 424.790108 -120.35028)
		(stroke
			(width 0.08255)
			(type default)
		)
		(layer "In15.Cu")
	)
	(gr_line
		(start 424.790108 -120.35028)
		(end 424.903138 -120.23725)
		(stroke
			(width 0.08255)
			(type default)
		)
		(layer "In15.Cu")
	)
	(gr_line
		(start 424.790108 -119.62638)
		(end 424.790108 -119.13108)
		(stroke
			(width 0.08255)
			(type default)
		)
		(layer "In15.Cu")
	)
	(gr_line
		(start 424.790108 -119.13108)
		(end 424.903138 -119.01805)
		(stroke
			(width 0.08255)
			(type default)
		)
		(layer "In15.Cu")
	)
	(gr_line
		(start 424.903138 -125.83541)
		(end 424.790108 -125.72238)
		(stroke
			(width 0.08255)
			(type default)
		)
		(layer "In15.Cu")
	)
	(gr_line
		(start 424.903138 -124.61621)
		(end 424.790108 -124.50318)
		(stroke
			(width 0.08255)
			(type default)
		)
		(layer "In15.Cu")
	)
	(gr_line
		(start 424.903138 -123.39701)
		(end 424.790108 -123.28398)
		(stroke
			(width 0.08255)
			(type default)
		)
		(layer "In15.Cu")
	)
	(gr_line
		(start 424.903138 -122.17781)
		(end 424.790108 -122.06478)
		(stroke
			(width 0.08255)
			(type default)
		)
		(layer "In15.Cu")
	)
	(gr_line
		(start 424.903138 -120.95861)
		(end 424.790108 -120.84558)
		(stroke
			(width 0.08255)
			(type default)
		)
		(layer "In15.Cu")
	)
	(gr_line
		(start 424.903138 -119.73941)
		(end 424.790108 -119.62638)
		(stroke
			(width 0.08255)
			(type default)
		)
		(layer "In15.Cu")
	)
	(gr_line
		(start 425.186348 -125.83668)
		(end 425.186348 -125.11278)
		(stroke
			(width 0.08255)
			(type default)
		)
		(layer "In15.Cu")
	)
	(gr_line
		(start 425.186348 -124.61748)
		(end 425.186348 -123.89358)
		(stroke
			(width 0.08255)
			(type default)
		)
		(layer "In15.Cu")
	)
	(gr_line
		(start 425.186348 -123.39828)
		(end 425.186348 -122.67438)
		(stroke
			(width 0.08255)
			(type default)
		)
		(layer "In15.Cu")
	)
	(gr_line
		(start 425.186348 -122.17908)
		(end 425.186348 -121.45518)
		(stroke
			(width 0.08255)
			(type default)
		)
		(layer "In15.Cu")
	)
	(gr_line
		(start 425.186348 -120.95988)
		(end 425.186348 -120.23598)
		(stroke
			(width 0.08255)
			(type default)
		)
		(layer "In15.Cu")
	)
	(gr_line
		(start 425.186348 -119.74068)
		(end 425.186348 -119.01678)
		(stroke
			(width 0.08255)
			(type default)
		)
		(layer "In15.Cu")
	)
	(gr_poly
		(pts
			(arc
				(start 265.615928 -377.679966)
				(mid 265.635451 -377.676065)
				(end 265.651996 -377.66498)
			)
			(arc
				(start 265.851386 -377.46559)
				(mid 265.862497 -377.449056)
				(end 265.866372 -377.429522)
			)
			(arc
				(start 265.866372 -368.884962)
				(mid 265.862471 -368.865439)
				(end 265.851386 -368.848894)
			)
			(arc
				(start 265.514582 -368.51209)
				(mid 265.498048 -368.500979)
				(end 265.478514 -368.497104)
			)
			(arc
				(start 242.901216 -368.497104)
				(mid 242.881693 -368.501005)
				(end 242.865148 -368.51209)
			)
			(arc
				(start 242.760754 -368.616484)
				(mid 242.749643 -368.633018)
				(end 242.745768 -368.652552)
			)
			(arc
				(start 242.745768 -377.268994)
				(mid 242.749669 -377.288517)
				(end 242.760754 -377.305062)
			)
			(arc
				(start 243.120672 -377.66498)
				(mid 243.137206 -377.676091)
				(end 243.15674 -377.679966)
			)
		)
		(stroke
			(width 0)
			(type solid)
		)
		(fill yes)
		(layer "In16.Cu")
		(net "P12V_STBY_R2")
	)
	(gr_poly
		(pts
			(arc
				(start 241.741198 -376.399806)
				(mid 241.763367 -376.39459)
				(end 241.781076 -376.380248)
			)
			(arc
				(start 241.781076 -376.380248)
				(mid 241.793461 -376.365378)
				(end 241.80673 -376.351292)
			)
			(xy 242.08994 -376.068082)
			(arc
				(start 242.09502 -376.063002)
				(mid 242.106647 -376.046325)
				(end 242.110768 -376.026426)
			)
			(arc
				(start 242.110768 -368.666268)
				(mid 242.106867 -368.646745)
				(end 242.095782 -368.6302)
			)
			(arc
				(start 241.977672 -368.51209)
				(mid 241.961138 -368.500979)
				(end 241.941604 -368.497104)
			)
			(arc
				(start 236.370368 -368.497104)
				(mid 236.350845 -368.501005)
				(end 236.3343 -368.51209)
			)
			(arc
				(start 236.123734 -368.722656)
				(mid 236.112623 -368.73919)
				(end 236.108748 -368.758724)
			)
			(arc
				(start 236.108748 -376.146314)
				(mid 236.112649 -376.165837)
				(end 236.123734 -376.182382)
			)
			(arc
				(start 236.326172 -376.38482)
				(mid 236.342706 -376.395931)
				(end 236.36224 -376.399806)
			)
		)
		(stroke
			(width 0)
			(type solid)
		)
		(fill yes)
		(layer "In16.Cu")
		(net "P12V_STBY_R1")
	)
	(gr_poly
		(pts
			(arc
				(start 235.60151 -413.087058)
				(mid 235.621033 -413.083157)
				(end 235.637578 -413.072072)
			)
			(arc
				(start 236.756956 -411.952694)
				(mid 236.768067 -411.93616)
				(end 236.771942 -411.916626)
			)
			(arc
				(start 236.771942 -402.84527)
				(mid 236.796095 -402.723754)
				(end 236.864906 -402.620734)
			)
			(arc
				(start 238.766604 -400.719036)
				(mid 238.869636 -400.650255)
				(end 238.99114 -400.626072)
			)
			(arc
				(start 242.910868 -400.626072)
				(mid 242.930391 -400.622171)
				(end 242.946936 -400.611086)
			)
			(arc
				(start 243.79682 -399.761202)
				(mid 243.807931 -399.744668)
				(end 243.811806 -399.725134)
			)
			(arc
				(start 243.811806 -392.09472)
				(mid 243.835959 -391.973204)
				(end 243.90477 -391.870184)
			)
			(arc
				(start 244.93093 -390.844024)
				(mid 245.033962 -390.775243)
				(end 245.155466 -390.75106)
			)
			(arc
				(start 259.056124 -390.75106)
				(mid 259.075647 -390.747159)
				(end 259.092192 -390.736074)
			)
			(arc
				(start 262.00481 -387.823456)
				(mid 262.015921 -387.806922)
				(end 262.019796 -387.787388)
			)
			(arc
				(start 262.019796 -379.197616)
				(mid 262.015895 -379.178093)
				(end 262.00481 -379.161548)
			)
			(arc
				(start 261.967472 -379.12421)
				(mid 261.950938 -379.113099)
				(end 261.931404 -379.109224)
			)
			(arc
				(start 240.584482 -379.109224)
				(mid 240.564959 -379.113125)
				(end 240.548414 -379.12421)
			)
			(arc
				(start 239.998504 -379.67412)
				(mid 239.895472 -379.742901)
				(end 239.773968 -379.767084)
			)
			(arc
				(start 237.129066 -379.767084)
				(mid 237.00755 -379.742931)
				(end 236.90453 -379.67412)
			)
			(arc
				(start 232.953814 -375.723404)
				(mid 232.885033 -375.620372)
				(end 232.86085 -375.498868)
			)
			(arc
				(start 232.86085 -372.11508)
				(mid 232.856949 -372.095557)
				(end 232.845864 -372.079012)
			)
			(arc
				(start 232.203752 -371.4369)
				(mid 232.134971 -371.333868)
				(end 232.110788 -371.212364)
			)
			(arc
				(start 232.110788 -371.075712)
				(mid 232.106887 -371.056189)
				(end 232.095802 -371.039644)
			)
			(arc
				(start 232.035858 -370.9797)
				(mid 231.967077 -370.876668)
				(end 231.942894 -370.755164)
			)
			(arc
				(start 231.942894 -367.397792)
				(mid 231.938993 -367.378269)
				(end 231.927908 -367.361724)
			)
			(arc
				(start 231.89057 -367.324386)
				(mid 231.874036 -367.313275)
				(end 231.854502 -367.3094)
			)
			(arc
				(start 228.741986 -367.3094)
				(mid 228.722463 -367.313301)
				(end 228.705918 -367.324386)
			)
			(arc
				(start 228.66858 -367.361724)
				(mid 228.657469 -367.378258)
				(end 228.653594 -367.397792)
			)
			(arc
				(start 228.653594 -370.74856)
				(mid 228.629441 -370.870076)
				(end 228.56063 -370.973096)
			)
			(arc
				(start 228.481128 -371.052598)
				(mid 228.470017 -371.069132)
				(end 228.466142 -371.088666)
			)
			(arc
				(start 228.466142 -371.354096)
				(mid 228.441989 -371.475612)
				(end 228.373178 -371.578632)
			)
			(arc
				(start 227.178362 -372.773448)
				(mid 227.167251 -372.789982)
				(end 227.163376 -372.809516)
			)
			(arc
				(start 227.163376 -374.166384)
				(mid 227.139223 -374.2879)
				(end 227.070412 -374.39092)
			)
			(arc
				(start 225.794062 -375.66727)
				(mid 225.69103 -375.736051)
				(end 225.569526 -375.760234)
			)
			(arc
				(start 223.648016 -375.760234)
				(mid 223.5265 -375.736081)
				(end 223.42348 -375.66727)
			)
			(arc
				(start 221.55531 -373.7991)
				(mid 221.486529 -373.696068)
				(end 221.462346 -373.574564)
			)
			(arc
				(start 221.462346 -371.091714)
				(mid 221.458445 -371.072191)
				(end 221.44736 -371.055646)
			)
			(arc
				(start 221.361508 -370.969794)
				(mid 221.292727 -370.866762)
				(end 221.268544 -370.745258)
			)
			(arc
				(start 221.268544 -367.391442)
				(mid 221.264643 -367.371919)
				(end 221.253558 -367.355374)
			)
			(arc
				(start 221.225872 -367.327688)
				(mid 221.209338 -367.316577)
				(end 221.189804 -367.312702)
			)
			(arc
				(start 218.110308 -367.312702)
				(mid 218.090785 -367.316603)
				(end 218.07424 -367.327688)
			)
			(arc
				(start 217.967306 -367.434622)
				(mid 217.956195 -367.451156)
				(end 217.95232 -367.47069)
			)
			(arc
				(start 217.95232 -370.719096)
				(mid 217.928167 -370.840612)
				(end 217.859356 -370.943632)
			)
			(arc
				(start 216.82964 -371.973348)
				(mid 216.726608 -372.042129)
				(end 216.605104 -372.066312)
			)
			(arc
				(start 210.424014 -372.066312)
				(mid 210.302498 -372.042159)
				(end 210.199478 -371.973348)
			)
			(arc
				(start 210.067906 -371.841776)
				(mid 209.999125 -371.738744)
				(end 209.974942 -371.61724)
			)
			(arc
				(start 209.974942 -371.309138)
				(mid 209.971041 -371.289615)
				(end 209.959956 -371.27307)
			)
			(arc
				(start 209.949034 -371.262148)
				(mid 209.9325 -371.251037)
				(end 209.912966 -371.247162)
			)
			(arc
				(start 209.559144 -371.247162)
				(mid 209.437628 -371.223009)
				(end 209.334608 -371.154198)
			)
			(arc
				(start 208.669382 -370.488972)
				(mid 208.652848 -370.477861)
				(end 208.633314 -370.473986)
			)
			(arc
				(start 208.394554 -370.473986)
				(mid 208.273038 -370.449833)
				(end 208.170018 -370.381022)
			)
			(arc
				(start 208.11744 -370.328444)
				(mid 208.048659 -370.225412)
				(end 208.024476 -370.103908)
			)
			(arc
				(start 208.024476 -367.401348)
				(mid 208.020575 -367.381825)
				(end 208.00949 -367.36528)
			)
			(arc
				(start 207.981804 -367.337594)
				(mid 207.96527 -367.326483)
				(end 207.945736 -367.322608)
			)
			(arc
				(start 204.823822 -367.322608)
				(mid 204.804299 -367.326509)
				(end 204.787754 -367.337594)
			)
			(arc
				(start 204.740002 -367.385346)
				(mid 204.728891 -367.40188)
				(end 204.725016 -367.421414)
			)
			(arc
				(start 204.725016 -370.796312)
				(mid 204.728917 -370.815835)
				(end 204.740002 -370.83238)
			)
			(arc
				(start 204.77353 -370.865908)
				(mid 204.842311 -370.96894)
				(end 204.866494 -371.090444)
			)
			(arc
				(start 204.866494 -374.47474)
				(mid 204.870058 -374.493432)
				(end 204.88021 -374.509538)
			)
			(arc
				(start 204.88021 -374.509538)
				(mid 204.94326 -374.609679)
				(end 204.9653 -374.725946)
			)
			(arc
				(start 204.9653 -387.02361)
				(mid 204.969201 -387.043133)
				(end 204.980286 -387.059678)
			)
			(arc
				(start 207.47482 -389.554212)
				(mid 207.543601 -389.657244)
				(end 207.567784 -389.778748)
			)
			(arc
				(start 207.567784 -411.696662)
				(mid 207.571685 -411.716185)
				(end 207.58277 -411.73273)
			)
			(arc
				(start 208.922112 -413.072072)
				(mid 208.938646 -413.083183)
				(end 208.95818 -413.087058)
			)
		)
		(stroke
			(width 0)
			(type solid)
		)
		(fill yes)
		(layer "In16.Cu")
		(net "P12V_STBY")
	)
	(gr_poly
		(pts
			(xy 465.600034 -461.99552) (xy 465.655841 -461.994997) (xy 465.767141 -461.986654) (xy 465.877508 -461.970017)
			(xy 465.986322 -461.945179) (xy 466.092976 -461.912278) (xy 466.196873 -461.8715) (xy 466.297432 -461.823072)
			(xy 466.394091 -461.767264) (xy 466.48631 -461.70439) (xy 466.573572 -461.6348) (xy 466.65539 -461.558883)
			(xy 466.731306 -461.477065) (xy 466.800896 -461.389802) (xy 466.86377 -461.297583) (xy 466.919577 -461.200923)
			(xy 466.968004 -461.100364) (xy 467.008782 -460.996466) (xy 467.041681 -460.889812) (xy 467.066519 -460.780998)
			(xy 467.083155 -460.670631) (xy 467.091497 -460.559331) (xy 467.09203 -460.503524) (xy 467.09203 -422.58996)
			(xy 467.091507 -422.534153) (xy 467.083163 -422.422853) (xy 467.066526 -422.312487) (xy 467.041687 -422.203672)
			(xy 467.008787 -422.097019) (xy 466.968009 -421.993121) (xy 466.91958 -421.892562) (xy 466.863773 -421.795903)
			(xy 466.800898 -421.703684) (xy 466.731308 -421.616422) (xy 466.655392 -421.534604) (xy 466.573573 -421.458688)
			(xy 466.486311 -421.389098) (xy 466.394092 -421.326224) (xy 466.297433 -421.270417) (xy 466.196873 -421.221989)
			(xy 466.092976 -421.181211) (xy 465.986322 -421.148311) (xy 465.877508 -421.123473) (xy 465.767141 -421.106836)
			(xy 465.655841 -421.098493) (xy 465.600034 -421.097964) (xy 447.939922 -421.097964) (xy 447.884114 -421.098485)
			(xy 447.77281 -421.106824) (xy 447.66244 -421.123458) (xy 447.553622 -421.148293) (xy 447.446964 -421.181191)
			(xy 447.343062 -421.221967) (xy 447.242499 -421.270394) (xy 447.145835 -421.3262) (xy 447.053613 -421.389074)
			(xy 446.966346 -421.458664) (xy 446.884524 -421.53458) (xy 446.808604 -421.616399) (xy 446.739011 -421.703663)
			(xy 446.676133 -421.795883) (xy 446.620323 -421.892544) (xy 446.571892 -421.993106) (xy 446.531111 -422.097005)
			(xy 446.498209 -422.203662) (xy 446.47337 -422.312479) (xy 446.456731 -422.422848) (xy 446.448387 -422.534152)
			(xy 446.447926 -422.58996) (xy 446.447926 -429.090074) (xy 446.447433 -429.160429) (xy 446.439545 -429.300916)
			(xy 446.423792 -429.440741) (xy 446.400224 -429.579462) (xy 446.368915 -429.716643) (xy 446.329963 -429.851854)
			(xy 446.283491 -429.984667) (xy 446.229646 -430.114666) (xy 446.168596 -430.241441) (xy 446.100533 -430.364593)
			(xy 446.025673 -430.483736) (xy 445.94425 -430.598494) (xy 445.856521 -430.708505) (xy 445.762761 -430.813425)
			(xy 445.663266 -430.912922) (xy 445.558348 -431.006684) (xy 445.448338 -431.094416) (xy 445.333582 -431.175842)
			(xy 445.214442 -431.250705) (xy 445.091291 -431.31877) (xy 444.964517 -431.379823) (xy 444.834519 -431.433671)
			(xy 444.701707 -431.480146) (xy 444.566498 -431.519101) (xy 444.429317 -431.550413) (xy 444.290596 -431.573985)
			(xy 444.150772 -431.589741) (xy 444.010285 -431.597632) (xy 443.93993 -431.59807) (xy 371.24005 -431.59807)
			(xy 371.169695 -431.597587) (xy 371.029207 -431.5897) (xy 370.889383 -431.573948) (xy 370.750661 -431.550381)
			(xy 370.613479 -431.519072) (xy 370.478269 -431.480121) (xy 370.345455 -431.433649) (xy 370.215456 -431.379804)
			(xy 370.088681 -431.318754) (xy 369.965528 -431.250691) (xy 369.846385 -431.175831) (xy 369.731628 -431.094407)
			(xy 369.621616 -431.006677) (xy 369.516697 -430.912917) (xy 369.4172 -430.813421) (xy 369.323438 -430.708502)
			(xy 369.235707 -430.598492) (xy 369.154283 -430.483735) (xy 369.079421 -430.364593) (xy 369.011357 -430.241441)
			(xy 368.950306 -430.114666) (xy 368.896459 -429.984667) (xy 368.849986 -429.851854) (xy 368.811034 -429.716644)
			(xy 368.779724 -429.579463) (xy 368.756155 -429.440741) (xy 368.740402 -429.300917) (xy 368.732514 -429.160429)
			(xy 368.732054 -429.090074) (xy 368.732054 -422.58996) (xy 368.731543 -422.534154) (xy 368.7232 -422.422854)
			(xy 368.706562 -422.31249) (xy 368.681723 -422.203677) (xy 368.648822 -422.097024) (xy 368.608042 -421.993129)
			(xy 368.559613 -421.892571) (xy 368.503804 -421.795914) (xy 368.440929 -421.703697) (xy 368.371337 -421.616438)
			(xy 368.29542 -421.534622) (xy 368.2136 -421.458709) (xy 368.126337 -421.389123) (xy 368.034117 -421.326252)
			(xy 367.937456 -421.270449) (xy 367.836896 -421.222025) (xy 367.732998 -421.181251) (xy 367.626344 -421.148356)
			(xy 367.51753 -421.123523) (xy 367.407164 -421.106891) (xy 367.295864 -421.098554) (xy 367.240058 -421.097964)
			(xy 359.940098 -421.097964) (xy 359.88429 -421.098486) (xy 359.772988 -421.106827) (xy 359.662619 -421.123462)
			(xy 359.553802 -421.148298) (xy 359.447146 -421.181197) (xy 359.343246 -421.221974) (xy 359.242684 -421.270401)
			(xy 359.146022 -421.326208) (xy 359.053801 -421.389082) (xy 358.966536 -421.458672) (xy 358.884716 -421.534589)
			(xy 358.808797 -421.616407) (xy 358.739205 -421.70367) (xy 358.676328 -421.79589) (xy 358.620519 -421.892551)
			(xy 358.572089 -421.993111) (xy 358.53131 -422.09701) (xy 358.498408 -422.203666) (xy 358.473569 -422.312482)
			(xy 358.456931 -422.42285) (xy 358.448587 -422.534152) (xy 358.448102 -422.58996) (xy 358.448102 -429.090074)
			(xy 358.447618 -429.160429) (xy 358.43973 -429.300916) (xy 358.423977 -429.440741) (xy 358.400409 -429.579462)
			(xy 358.369099 -429.716643) (xy 358.330147 -429.851853) (xy 358.283675 -429.984667) (xy 358.229829 -430.114665)
			(xy 358.168779 -430.24144) (xy 358.100716 -430.364593) (xy 358.025856 -430.483735) (xy 357.944432 -430.598492)
			(xy 357.856702 -430.708504) (xy 357.762942 -430.813423) (xy 357.663446 -430.91292) (xy 357.558528 -431.006682)
			(xy 357.448518 -431.094413) (xy 357.333762 -431.175838) (xy 357.21462 -431.2507) (xy 357.091469 -431.318764)
			(xy 356.964695 -431.379816) (xy 356.834697 -431.433664) (xy 356.701884 -431.480138) (xy 356.566674 -431.519091)
			(xy 356.429493 -431.550403) (xy 356.290772 -431.573973) (xy 356.150948 -431.589728) (xy 356.010461 -431.597618)
			(xy 355.940106 -431.59807) (xy 283.239972 -431.59807) (xy 283.169619 -431.597576) (xy 283.029135 -431.589685)
			(xy 282.889313 -431.573929) (xy 282.750596 -431.550359) (xy 282.613418 -431.519047) (xy 282.478212 -431.480093)
			(xy 282.345402 -431.43362) (xy 282.215407 -431.379772) (xy 282.088636 -431.318721) (xy 281.965488 -431.250657)
			(xy 281.84635 -431.175796) (xy 281.731596 -431.094372) (xy 281.621589 -431.006642) (xy 281.516674 -430.912882)
			(xy 281.417181 -430.813387) (xy 281.323423 -430.70847) (xy 281.235695 -430.598461) (xy 281.154274 -430.483705)
			(xy 281.079415 -430.364565) (xy 281.011354 -430.241416) (xy 280.950306 -430.114643) (xy 280.896461 -429.984647)
			(xy 280.84999 -429.851837) (xy 280.811039 -429.71663) (xy 280.779731 -429.579451) (xy 280.756163 -429.440733)
			(xy 280.740411 -429.300912) (xy 280.732523 -429.160427) (xy 280.731976 -429.090074) (xy 280.731976 -422.58996)
			(xy 280.731453 -422.534154) (xy 280.723109 -422.422855) (xy 280.706471 -422.31249) (xy 280.681633 -422.203678)
			(xy 280.648732 -422.097025) (xy 280.607953 -421.99313) (xy 280.559525 -421.892573) (xy 280.503717 -421.795915)
			(xy 280.440842 -421.703699) (xy 280.371251 -421.616439) (xy 280.295334 -421.534623) (xy 280.213516 -421.45871)
			(xy 280.126253 -421.389123) (xy 280.034034 -421.326251) (xy 279.937374 -421.270447) (xy 279.836815 -421.222023)
			(xy 279.732918 -421.181248) (xy 279.626264 -421.148352) (xy 279.517451 -421.123517) (xy 279.407085 -421.106884)
			(xy 279.295786 -421.098545) (xy 279.23998 -421.097964) (xy 276.880066 -421.097964) (xy 276.824259 -421.098487)
			(xy 276.712958 -421.10683) (xy 276.602591 -421.123467) (xy 276.493777 -421.148305) (xy 276.387122 -421.181205)
			(xy 276.283225 -421.221984) (xy 276.182665 -421.270412) (xy 276.086005 -421.326219) (xy 275.993786 -421.389094)
			(xy 275.906523 -421.458684) (xy 275.824704 -421.5346) (xy 275.748787 -421.616418) (xy 275.679197 -421.703681)
			(xy 275.616322 -421.7959) (xy 275.560514 -421.892559) (xy 275.512086 -421.993119) (xy 275.471307 -422.097017)
			(xy 275.438407 -422.203671) (xy 275.413568 -422.312485) (xy 275.396931 -422.422852) (xy 275.388587 -422.534153)
			(xy 275.38807 -422.58996) (xy 275.38807 -430.55794) (xy 275.387576 -430.628293) (xy 275.379684 -430.768777)
			(xy 275.363928 -430.908597) (xy 275.340357 -431.047314) (xy 275.309045 -431.184492) (xy 275.27009 -431.319698)
			(xy 275.223616 -431.452506) (xy 275.169769 -431.582501) (xy 275.108717 -431.709271) (xy 275.040653 -431.832419)
			(xy 274.965792 -431.951557) (xy 274.884368 -432.066309) (xy 274.796638 -432.176316) (xy 274.702878 -432.281231)
			(xy 274.603383 -432.380723) (xy 274.498466 -432.474481) (xy 274.388457 -432.562208) (xy 274.273702 -432.643629)
			(xy 274.154562 -432.718487) (xy 274.031412 -432.786547) (xy 273.90464 -432.847596) (xy 273.774645 -432.90144)
			(xy 273.641835 -432.94791) (xy 273.506628 -432.986861) (xy 273.36945 -433.018169) (xy 273.230732 -433.041737)
			(xy 273.090911 -433.05749) (xy 272.950427 -433.065377) (xy 272.880074 -433.065936) (xy 202.360022 -433.065936)
			(xy 202.289667 -433.065443) (xy 202.14918 -433.057555) (xy 202.009355 -433.041802) (xy 201.870634 -433.018234)
			(xy 201.733452 -432.986924) (xy 201.598242 -432.947972) (xy 201.465429 -432.9015) (xy 201.33543 -432.847655)
			(xy 201.208655 -432.786605) (xy 201.085502 -432.718542) (xy 200.96636 -432.643682) (xy 200.851602 -432.562259)
			(xy 200.74159 -432.47453) (xy 200.63667 -432.38077) (xy 200.537173 -432.281275) (xy 200.44341 -432.176357)
			(xy 200.355678 -432.066348) (xy 200.274252 -431.951592) (xy 200.199389 -431.832451) (xy 200.131324 -431.7093)
			(xy 200.070271 -431.582527) (xy 200.016422 -431.452529) (xy 199.969947 -431.319717) (xy 199.930991 -431.184508)
			(xy 199.899679 -431.047327) (xy 199.876107 -430.908606) (xy 199.86035 -430.768782) (xy 199.852458 -430.628295)
			(xy 199.852026 -430.55794) (xy 199.852026 -422.58996) (xy 199.851503 -422.534154) (xy 199.843159 -422.422853)
			(xy 199.826522 -422.312487) (xy 199.801683 -422.203673) (xy 199.768783 -422.097019) (xy 199.728004 -421.993122)
			(xy 199.679576 -421.892563) (xy 199.623769 -421.795904) (xy 199.560894 -421.703685) (xy 199.491304 -421.616423)
			(xy 199.415387 -421.534606) (xy 199.333569 -421.45869) (xy 199.246306 -421.3891) (xy 199.154088 -421.326226)
			(xy 199.057428 -421.270419) (xy 198.956869 -421.221992) (xy 198.852972 -421.181214) (xy 198.746318 -421.148314)
			(xy 198.637503 -421.123476) (xy 198.527137 -421.10684) (xy 198.415836 -421.098497) (xy 198.36003 -421.097964)
			(xy 188.36005 -421.097964) (xy 188.304244 -421.098488) (xy 188.192943 -421.106832) (xy 188.082578 -421.12347)
			(xy 187.973764 -421.148309) (xy 187.86711 -421.18121) (xy 187.763214 -421.221988) (xy 187.662655 -421.270417)
			(xy 187.565996 -421.326225) (xy 187.473778 -421.389099) (xy 187.386516 -421.458689) (xy 187.304699 -421.534606)
			(xy 187.228783 -421.616424) (xy 187.159193 -421.703686) (xy 187.096319 -421.795905) (xy 187.040512 -421.892564)
			(xy 186.992084 -421.993123) (xy 186.951306 -422.09702) (xy 186.918406 -422.203673) (xy 186.893568 -422.312487)
			(xy 186.876931 -422.422853) (xy 186.868587 -422.534154) (xy 186.868054 -422.58996) (xy 186.868054 -429.090074)
			(xy 186.86757 -429.160428) (xy 186.859682 -429.300915) (xy 186.843929 -429.440738) (xy 186.820361 -429.579458)
			(xy 186.789051 -429.716639) (xy 186.750099 -429.851848) (xy 186.703626 -429.98466) (xy 186.64978 -430.114658)
			(xy 186.58873 -430.241431) (xy 186.520667 -430.364582) (xy 186.445806 -430.483723) (xy 186.364382 -430.598479)
			(xy 186.276652 -430.708489) (xy 186.182891 -430.813407) (xy 186.083395 -430.912902) (xy 185.978477 -431.006662)
			(xy 185.868467 -431.094392) (xy 185.75371 -431.175815) (xy 185.634569 -431.250675) (xy 185.511417 -431.318737)
			(xy 185.384643 -431.379787) (xy 185.254645 -431.433632) (xy 185.121833 -431.480104) (xy 184.986623 -431.519055)
			(xy 184.849443 -431.550364) (xy 184.710722 -431.573931) (xy 184.570899 -431.589684) (xy 184.430412 -431.597571)
			(xy 184.360058 -431.59807) (xy 111.660178 -431.59807) (xy 111.589825 -431.597585) (xy 111.449339 -431.589694)
			(xy 111.309518 -431.573939) (xy 111.170799 -431.550369) (xy 111.033621 -431.519057) (xy 110.898414 -431.480103)
			(xy 110.765603 -431.43363) (xy 110.635608 -431.379782) (xy 110.508836 -431.318731) (xy 110.385687 -431.250667)
			(xy 110.266548 -431.175806) (xy 110.151794 -431.094382) (xy 110.041786 -431.006651) (xy 109.93687 -430.912891)
			(xy 109.837376 -430.813395) (xy 109.743618 -430.708478) (xy 109.65589 -430.598468) (xy 109.574468 -430.483712)
			(xy 109.499608 -430.364572) (xy 109.431547 -430.241421) (xy 109.370498 -430.114648) (xy 109.316653 -429.984652)
			(xy 109.270182 -429.851841) (xy 109.231231 -429.716633) (xy 109.199922 -429.579454) (xy 109.176354 -429.440735)
			(xy 109.160602 -429.300913) (xy 109.152714 -429.160427) (xy 109.152182 -429.090074) (xy 109.152182 -422.58996)
			(xy 109.151659 -422.534154) (xy 109.143315 -422.422855) (xy 109.126678 -422.31249) (xy 109.101839 -422.203677)
			(xy 109.068938 -422.097025) (xy 109.02816 -421.993129) (xy 108.979731 -421.892571) (xy 108.923923 -421.795914)
			(xy 108.861048 -421.703697) (xy 108.791457 -421.616437) (xy 108.715541 -421.534621) (xy 108.633722 -421.458707)
			(xy 108.546459 -421.38912) (xy 108.45424 -421.326248) (xy 108.357581 -421.270444) (xy 108.257021 -421.222019)
			(xy 108.153124 -421.181244) (xy 108.046471 -421.148347) (xy 107.937657 -421.123512) (xy 107.827292 -421.106879)
			(xy 107.715992 -421.098539) (xy 107.660186 -421.097964) (xy 100.359972 -421.097964) (xy 100.304165 -421.098487)
			(xy 100.192864 -421.106829) (xy 100.082497 -421.123466) (xy 99.973681 -421.148304) (xy 99.867027 -421.181204)
			(xy 99.763129 -421.221982) (xy 99.662568 -421.27041) (xy 99.565908 -421.326217) (xy 99.473689 -421.389091)
			(xy 99.386425 -421.458681) (xy 99.304606 -421.534598) (xy 99.228689 -421.616416) (xy 99.159099 -421.703679)
			(xy 99.096223 -421.795898) (xy 99.040415 -421.892558) (xy 98.991987 -421.993118) (xy 98.951208 -422.097015)
			(xy 98.918307 -422.20367) (xy 98.893468 -422.312485) (xy 98.876831 -422.422852) (xy 98.868487 -422.534153)
			(xy 98.867976 -422.58996) (xy 98.867976 -429.090074) (xy 98.867492 -429.160428) (xy 98.859604 -429.300915)
			(xy 98.843851 -429.440739) (xy 98.820283 -429.57946) (xy 98.788973 -429.716641) (xy 98.750021 -429.85185)
			(xy 98.703549 -429.984663) (xy 98.649703 -430.114661) (xy 98.588652 -430.241435) (xy 98.520589 -430.364587)
			(xy 98.445729 -430.483729) (xy 98.364305 -430.598485) (xy 98.276575 -430.708496) (xy 98.182814 -430.813414)
			(xy 98.083319 -430.91291) (xy 97.9784 -431.006671) (xy 97.86839 -431.094401) (xy 97.753634 -431.175825)
			(xy 97.634492 -431.250686) (xy 97.511341 -431.31875) (xy 97.384567 -431.3798) (xy 97.254569 -431.433647)
			(xy 97.121756 -431.480119) (xy 96.986547 -431.519072) (xy 96.849366 -431.550382) (xy 96.710645 -431.57395)
			(xy 96.570821 -431.589704) (xy 96.430334 -431.597592) (xy 96.35998 -431.59807) (xy 23.6601 -431.59807)
			(xy 23.589746 -431.597586) (xy 23.44926 -431.589696) (xy 23.309437 -431.573942) (xy 23.170718 -431.550372)
			(xy 23.033539 -431.519062) (xy 22.89833 -431.480109) (xy 22.765519 -431.433636) (xy 22.635522 -431.379789)
			(xy 22.50875 -431.318738) (xy 22.385599 -431.250675) (xy 22.266459 -431.175813) (xy 22.151704 -431.094389)
			(xy 22.041695 -431.006659) (xy 21.936778 -430.912899) (xy 21.837283 -430.813403) (xy 21.743524 -430.708485)
			(xy 21.655795 -430.598475) (xy 21.574372 -430.483719) (xy 21.499512 -430.364578) (xy 21.43145 -430.241427)
			(xy 21.370401 -430.114654) (xy 21.316555 -429.984657) (xy 21.270083 -429.851845) (xy 21.231132 -429.716636)
			(xy 21.199823 -429.579456) (xy 21.176255 -429.440737) (xy 21.160502 -429.300914) (xy 21.152614 -429.160428)
			(xy 21.152104 -429.090074) (xy 21.152104 -422.58996) (xy 21.151595 -422.534153) (xy 21.143254 -422.42285)
			(xy 21.126618 -422.312481) (xy 21.101782 -422.203665) (xy 21.068883 -422.097009) (xy 21.028105 -421.993109)
			(xy 20.979677 -421.892548) (xy 20.92387 -421.795886) (xy 20.860995 -421.703666) (xy 20.791404 -421.616402)
			(xy 20.715486 -421.534582) (xy 20.633667 -421.458665) (xy 20.546403 -421.389074) (xy 20.454182 -421.326199)
			(xy 20.357521 -421.270392) (xy 20.256959 -421.221964) (xy 20.153059 -421.181187) (xy 20.046403 -421.148288)
			(xy 19.937587 -421.123451) (xy 19.827218 -421.106816) (xy 19.715915 -421.098475) (xy 19.660108 -421.097964)
			(xy 1.999996 -421.097964) (xy 1.944189 -421.098486) (xy 1.832887 -421.106827) (xy 1.72252 -421.123463)
			(xy 1.613705 -421.148299) (xy 1.50705 -421.181198) (xy 1.403151 -421.221976) (xy 1.302591 -421.270403)
			(xy 1.20593 -421.32621) (xy 1.113711 -421.389085) (xy 1.026448 -421.458675) (xy 0.944629 -421.534592)
			(xy 0.868712 -421.616411) (xy 0.799122 -421.703674) (xy 0.736248 -421.795894) (xy 0.680441 -421.892554)
			(xy 0.632014 -421.993115) (xy 0.591237 -422.097013) (xy 0.558338 -422.203669) (xy 0.533502 -422.312484)
			(xy 0.516867 -422.422851) (xy 0.508526 -422.534153) (xy 0.508 -422.58996) (xy 0.508 -457.5681) (xy 2.904225 -457.5681)
			(xy 2.904225 -457.43896) (xy 2.912175 -457.310065) (xy 2.928045 -457.181905) (xy 2.951774 -457.054964)
			(xy 2.983273 -456.929725) (xy 3.022422 -456.806662) (xy 3.069073 -456.686243) (xy 3.123048 -456.568924)
			(xy 3.184143 -456.45515) (xy 3.252126 -456.345353) (xy 3.32674 -456.23995) (xy 3.407701 -456.13934)
			(xy 3.494701 -456.043905) (xy 3.587412 -455.954006) (xy 3.685482 -455.869985) (xy 3.788537 -455.792161)
			(xy 3.896188 -455.720829) (xy 4.008027 -455.656259) (xy 4.123628 -455.598697) (xy 4.242553 -455.54836)
			(xy 4.364352 -455.50544) (xy 4.488562 -455.470099) (xy 4.614711 -455.442472) (xy 4.742323 -455.422663)
			(xy 4.870912 -455.410747) (xy 4.99999 -455.406771) (xy 5.129068 -455.410747) (xy 5.257657 -455.422663)
			(xy 5.385269 -455.442472) (xy 5.511418 -455.470099) (xy 5.635628 -455.50544) (xy 5.757427 -455.54836)
			(xy 5.876352 -455.598697) (xy 5.991953 -455.656259) (xy 6.103792 -455.720829) (xy 6.211443 -455.792161)
			(xy 6.314498 -455.869985) (xy 6.412568 -455.954006) (xy 6.505279 -456.043905) (xy 6.592279 -456.13934)
			(xy 6.67324 -456.23995) (xy 6.747854 -456.345353) (xy 6.815837 -456.45515) (xy 6.876932 -456.568924)
			(xy 6.930907 -456.686243) (xy 6.977558 -456.806662) (xy 7.016707 -456.929725) (xy 7.048206 -457.054964)
			(xy 7.071935 -457.181905) (xy 7.087805 -457.310065) (xy 7.095755 -457.43896) (xy 7.096252 -457.50353)
			(xy 7.095755 -457.5681) (xy 460.504275 -457.5681) (xy 460.504275 -457.43896) (xy 460.512225 -457.310065)
			(xy 460.528095 -457.181905) (xy 460.551824 -457.054964) (xy 460.583323 -456.929725) (xy 460.622472 -456.806662)
			(xy 460.669123 -456.686243) (xy 460.723098 -456.568924) (xy 460.784193 -456.45515) (xy 460.852176 -456.345353)
			(xy 460.92679 -456.23995) (xy 461.007751 -456.13934) (xy 461.094751 -456.043905) (xy 461.187462 -455.954006)
			(xy 461.285532 -455.869985) (xy 461.388587 -455.792161) (xy 461.496238 -455.720829) (xy 461.608077 -455.656259)
			(xy 461.723678 -455.598697) (xy 461.842603 -455.54836) (xy 461.964402 -455.50544) (xy 462.088612 -455.470099)
			(xy 462.214761 -455.442472) (xy 462.342373 -455.422663) (xy 462.470962 -455.410747) (xy 462.60004 -455.406771)
			(xy 462.729118 -455.410747) (xy 462.857707 -455.422663) (xy 462.985319 -455.442472) (xy 463.111468 -455.470099)
			(xy 463.235678 -455.50544) (xy 463.357477 -455.54836) (xy 463.476402 -455.598697) (xy 463.592003 -455.656259)
			(xy 463.703842 -455.720829) (xy 463.811493 -455.792161) (xy 463.914548 -455.869985) (xy 464.012618 -455.954006)
			(xy 464.105329 -456.043905) (xy 464.192329 -456.13934) (xy 464.27329 -456.23995) (xy 464.347904 -456.345353)
			(xy 464.415887 -456.45515) (xy 464.476982 -456.568924) (xy 464.530957 -456.686243) (xy 464.577608 -456.806662)
			(xy 464.616757 -456.929725) (xy 464.648256 -457.054964) (xy 464.671985 -457.181905) (xy 464.687855 -457.310065)
			(xy 464.695805 -457.43896) (xy 464.696302 -457.50353) (xy 464.695805 -457.5681) (xy 464.687855 -457.696995)
			(xy 464.671985 -457.825155) (xy 464.648256 -457.952096) (xy 464.616757 -458.077335) (xy 464.577608 -458.200398)
			(xy 464.530957 -458.320817) (xy 464.476982 -458.438136) (xy 464.415887 -458.55191) (xy 464.347904 -458.661707)
			(xy 464.27329 -458.76711) (xy 464.192329 -458.86772) (xy 464.105329 -458.963155) (xy 464.012618 -459.053054)
			(xy 463.914548 -459.137075) (xy 463.811493 -459.214899) (xy 463.703842 -459.286231) (xy 463.592003 -459.350801)
			(xy 463.476402 -459.408363) (xy 463.357477 -459.4587) (xy 463.235678 -459.50162) (xy 463.111468 -459.536961)
			(xy 462.985319 -459.564588) (xy 462.857707 -459.584397) (xy 462.729118 -459.596313) (xy 462.60004 -459.60029)
			(xy 462.470962 -459.596313) (xy 462.342373 -459.584397) (xy 462.214761 -459.564588) (xy 462.088612 -459.536961)
			(xy 461.964402 -459.50162) (xy 461.842603 -459.4587) (xy 461.723678 -459.408363) (xy 461.608077 -459.350801)
			(xy 461.496238 -459.286231) (xy 461.388587 -459.214899) (xy 461.285532 -459.137075) (xy 461.187462 -459.053054)
			(xy 461.094751 -458.963155) (xy 461.007751 -458.86772) (xy 460.92679 -458.76711) (xy 460.852176 -458.661707)
			(xy 460.784193 -458.55191) (xy 460.723098 -458.438136) (xy 460.669123 -458.320817) (xy 460.622472 -458.200398)
			(xy 460.583323 -458.077335) (xy 460.551824 -457.952096) (xy 460.528095 -457.825155) (xy 460.512225 -457.696995)
			(xy 460.504275 -457.5681) (xy 7.095755 -457.5681) (xy 7.087805 -457.696995) (xy 7.071935 -457.825155)
			(xy 7.048206 -457.952096) (xy 7.016707 -458.077335) (xy 6.977558 -458.200398) (xy 6.930907 -458.320817)
			(xy 6.876932 -458.438136) (xy 6.815837 -458.55191) (xy 6.747854 -458.661707) (xy 6.67324 -458.76711)
			(xy 6.592279 -458.86772) (xy 6.505279 -458.963155) (xy 6.412568 -459.053054) (xy 6.314498 -459.137075)
			(xy 6.211443 -459.214899) (xy 6.103792 -459.286231) (xy 5.991953 -459.350801) (xy 5.876352 -459.408363)
			(xy 5.757427 -459.4587) (xy 5.635628 -459.50162) (xy 5.511418 -459.536961) (xy 5.385269 -459.564588)
			(xy 5.257657 -459.584397) (xy 5.129068 -459.596313) (xy 4.99999 -459.60029) (xy 4.870912 -459.596313)
			(xy 4.742323 -459.584397) (xy 4.614711 -459.564588) (xy 4.488562 -459.536961) (xy 4.364352 -459.50162)
			(xy 4.242553 -459.4587) (xy 4.123628 -459.408363) (xy 4.008027 -459.350801) (xy 3.896188 -459.286231)
			(xy 3.788537 -459.214899) (xy 3.685482 -459.137075) (xy 3.587412 -459.053054) (xy 3.494701 -458.963155)
			(xy 3.407701 -458.86772) (xy 3.32674 -458.76711) (xy 3.252126 -458.661707) (xy 3.184143 -458.55191)
			(xy 3.123048 -458.438136) (xy 3.069073 -458.320817) (xy 3.022422 -458.200398) (xy 2.983273 -458.077335)
			(xy 2.951774 -457.952096) (xy 2.928045 -457.825155) (xy 2.912175 -457.696995) (xy 2.904225 -457.5681)
			(xy 0.508 -457.5681) (xy 0.508 -460.503524) (xy 0.508522 -460.559331) (xy 0.516863 -460.670633) (xy 0.533498 -460.781)
			(xy 0.558335 -460.889816) (xy 0.591234 -460.996471) (xy 0.632011 -461.10037) (xy 0.680438 -461.20093)
			(xy 0.736246 -461.297591) (xy 0.79912 -461.389811) (xy 0.86871 -461.477074) (xy 0.944627 -461.558893)
			(xy 1.026446 -461.63481) (xy 1.113709 -461.7044) (xy 1.205929 -461.767274) (xy 1.30259 -461.823082)
			(xy 1.40315 -461.871509) (xy 1.507049 -461.912286) (xy 1.613704 -461.945185) (xy 1.72252 -461.970022)
			(xy 1.832887 -461.986657) (xy 1.944189 -461.994998) (xy 1.999996 -461.99552)
		)
		(stroke
			(width 0)
			(type solid)
		)
		(fill yes)
		(layer "In16.Cu")
		(net "COUPON_GND1")
	)
	(gr_poly
		(pts
			(xy 13.96492 -10.342118) (xy 14.020727 -10.341596) (xy 14.132028 -10.333253) (xy 14.242395 -10.316617)
			(xy 14.35121 -10.29178) (xy 14.457865 -10.25888) (xy 14.561763 -10.218102) (xy 14.662323 -10.169674)
			(xy 14.758983 -10.113867) (xy 14.851203 -10.050993) (xy 14.938466 -9.981402) (xy 15.020284 -9.905486)
			(xy 15.096201 -9.823667) (xy 15.165791 -9.736404) (xy 15.228666 -9.644185) (xy 15.284473 -9.547525)
			(xy 15.332901 -9.446965) (xy 15.373679 -9.343067) (xy 15.406579 -9.236412) (xy 15.431417 -9.127597)
			(xy 15.448053 -9.01723) (xy 15.456395 -8.905929) (xy 15.456916 -8.850122) (xy 15.456916 0) (xy 15.4574 0.070354)
			(xy 15.46529 0.21084) (xy 15.481044 0.350663) (xy 15.504614 0.489383) (xy 15.535924 0.626563) (xy 15.574877 0.761771)
			(xy 15.62135 0.894583) (xy 15.675197 1.02458) (xy 15.736248 1.151353) (xy 15.804311 1.274504) (xy 15.879172 1.393644)
			(xy 15.960596 1.5084) (xy 16.048326 1.618409) (xy 16.142086 1.723327) (xy 16.241582 1.822822) (xy 16.3465 1.916582)
			(xy 16.45651 2.004311) (xy 16.571266 2.085734) (xy 16.690407 2.160595) (xy 16.813558 2.228658) (xy 16.940331 2.289708)
			(xy 17.070328 2.343554) (xy 17.20314 2.390026) (xy 17.338349 2.428979) (xy 17.475529 2.460289) (xy 17.614249 2.483858)
			(xy 17.754072 2.499611) (xy 17.894558 2.5075) (xy 17.964912 2.507996) (xy 33.96488 2.507996) (xy 34.035234 2.507512)
			(xy 34.175722 2.499624) (xy 34.315546 2.48387) (xy 34.454267 2.460302) (xy 34.591448 2.428992) (xy 34.726657 2.39004)
			(xy 34.85947 2.343568) (xy 34.989468 2.289721) (xy 35.116243 2.228671) (xy 35.239395 2.160608) (xy 35.358537 2.085747)
			(xy 35.473294 2.004324) (xy 35.583304 1.916594) (xy 35.688223 1.822833) (xy 35.78772 1.723338) (xy 35.881481 1.61842)
			(xy 35.969212 1.50841) (xy 36.050636 1.393653) (xy 36.125498 1.274512) (xy 36.193562 1.151361) (xy 36.254613 1.024587)
			(xy 36.30846 0.894589) (xy 36.354934 0.761776) (xy 36.393887 0.626567) (xy 36.425198 0.489386) (xy 36.448768 0.350666)
			(xy 36.464522 0.210842) (xy 36.472412 0.070354) (xy 36.472876 0) (xy 36.472876 -8.850122) (xy 36.473399 -8.905929)
			(xy 36.481741 -9.01723) (xy 36.498377 -9.127597) (xy 36.523215 -9.236413) (xy 36.556114 -9.343067)
			(xy 36.596892 -9.446965) (xy 36.64532 -9.547526) (xy 36.701127 -9.644186) (xy 36.764002 -9.736405)
			(xy 36.833592 -9.823668) (xy 36.909508 -9.905487) (xy 36.991327 -9.981404) (xy 37.07859 -10.050995)
			(xy 37.170809 -10.113869) (xy 37.267469 -10.169677) (xy 37.368029 -10.218105) (xy 37.471927 -10.258884)
			(xy 37.578582 -10.291784) (xy 37.687397 -10.316622) (xy 37.797764 -10.333258) (xy 37.909065 -10.341601)
			(xy 37.964872 -10.342118) (xy 39.965122 -10.342118) (xy 40.020929 -10.341595) (xy 40.13223 -10.333253)
			(xy 40.242597 -10.316617) (xy 40.351412 -10.291779) (xy 40.458067 -10.258879) (xy 40.561964 -10.218102)
			(xy 40.662525 -10.169674) (xy 40.759184 -10.113866) (xy 40.851404 -10.050992) (xy 40.938667 -9.981402)
			(xy 41.020485 -9.905485) (xy 41.096402 -9.823667) (xy 41.165992 -9.736404) (xy 41.228866 -9.644184)
			(xy 41.284674 -9.547525) (xy 41.333102 -9.446964) (xy 41.373879 -9.343067) (xy 41.406779 -9.236412)
			(xy 41.431617 -9.127597) (xy 41.448253 -9.01723) (xy 41.456595 -8.905929) (xy 41.457118 -8.850122)
			(xy 41.457118 0) (xy 41.457602 0.070354) (xy 41.465492 0.21084) (xy 41.481246 0.350663) (xy 41.504816 0.489383)
			(xy 41.536126 0.626563) (xy 41.575079 0.761771) (xy 41.621552 0.894583) (xy 41.675399 1.02458) (xy 41.73645 1.151353)
			(xy 41.804513 1.274503) (xy 41.879374 1.393644) (xy 41.960798 1.508399) (xy 42.048528 1.618409) (xy 42.142288 1.723326)
			(xy 42.241784 1.822821) (xy 42.346702 1.916581) (xy 42.456712 2.00431) (xy 42.571468 2.085733) (xy 42.690609 2.160594)
			(xy 42.81376 2.228657) (xy 42.940533 2.289707) (xy 43.07053 2.343553) (xy 43.203342 2.390025) (xy 43.338551 2.428977)
			(xy 43.475731 2.460287) (xy 43.614451 2.483856) (xy 43.754274 2.499609) (xy 43.89476 2.507498) (xy 43.965114 2.507996)
			(xy 59.965082 2.507996) (xy 60.035436 2.507512) (xy 60.175924 2.499624) (xy 60.315748 2.48387) (xy 60.454468 2.460301)
			(xy 60.591649 2.428992) (xy 60.726859 2.390039) (xy 60.859672 2.343567) (xy 60.98967 2.289721) (xy 61.116444 2.22867)
			(xy 61.239596 2.160607) (xy 61.358738 2.085747) (xy 61.473495 2.004323) (xy 61.583505 1.916593) (xy 61.688424 1.822833)
			(xy 61.78792 1.723337) (xy 61.881681 1.618419) (xy 61.969412 1.508409) (xy 62.050837 1.393653) (xy 62.125698 1.274512)
			(xy 62.193762 1.15136) (xy 62.254813 1.024586) (xy 62.308661 0.894588) (xy 62.355134 0.761776) (xy 62.394087 0.626567)
			(xy 62.425398 0.489386) (xy 62.448968 0.350665) (xy 62.464722 0.210842) (xy 62.472612 0.070354) (xy 62.473078 0)
			(xy 62.473078 -8.850122) (xy 62.473601 -8.905929) (xy 62.481943 -9.01723) (xy 62.498579 -9.127597)
			(xy 62.523417 -9.236412) (xy 62.556316 -9.343067) (xy 62.597094 -9.446965) (xy 62.645522 -9.547525)
			(xy 62.701329 -9.644185) (xy 62.764204 -9.736405) (xy 62.833794 -9.823668) (xy 62.909711 -9.905487)
			(xy 62.991529 -9.981403) (xy 63.078792 -10.050994) (xy 63.171011 -10.113868) (xy 63.267671 -10.169676)
			(xy 63.368231 -10.218104) (xy 63.472129 -10.258882) (xy 63.578784 -10.291782) (xy 63.687599 -10.31662)
			(xy 63.797966 -10.333257) (xy 63.909267 -10.341599) (xy 63.965074 -10.342118) (xy 65.96507 -10.342118)
			(xy 66.020879 -10.34161) (xy 66.132184 -10.333271) (xy 66.242554 -10.316637) (xy 66.351373 -10.291802)
			(xy 66.458032 -10.258905) (xy 66.561934 -10.218128) (xy 66.662499 -10.169702) (xy 66.759163 -10.113895)
			(xy 66.851386 -10.05102) (xy 66.938653 -9.98143) (xy 67.020476 -9.905512) (xy 67.096396 -9.823693)
			(xy 67.165989 -9.736428) (xy 67.228867 -9.644207) (xy 67.284677 -9.547545) (xy 67.333108 -9.446982)
			(xy 67.373888 -9.343081) (xy 67.406789 -9.236424) (xy 67.431628 -9.127605) (xy 67.448265 -9.017235)
			(xy 67.456608 -8.905931) (xy 67.457066 -8.850122) (xy 67.457066 0) (xy 67.457559 0.070354) (xy 67.465449 0.210841)
			(xy 67.481203 0.350665) (xy 67.504772 0.489385) (xy 67.536082 0.626565) (xy 67.575035 0.761774) (xy 67.621508 0.894587)
			(xy 67.675354 1.024584) (xy 67.736404 1.151358) (xy 67.804467 1.27451) (xy 67.879328 1.393651) (xy 67.960751 1.508408)
			(xy 68.04848 1.618419) (xy 68.14224 1.723337) (xy 68.241735 1.822834) (xy 68.346652 1.916595) (xy 68.456662 2.004326)
			(xy 68.571417 2.085751) (xy 68.690557 2.160614) (xy 68.813708 2.228678) (xy 68.940481 2.289731) (xy 69.070478 2.343579)
			(xy 69.203289 2.390053) (xy 69.338498 2.429008) (xy 69.475678 2.46032) (xy 69.614398 2.483892) (xy 69.754221 2.499648)
			(xy 69.894708 2.50754) (xy 69.965062 2.507996) (xy 85.96503 2.507996) (xy 86.035383 2.507502) (xy 86.175868 2.499611)
			(xy 86.31569 2.483855) (xy 86.454408 2.460284) (xy 86.591586 2.428973) (xy 86.726793 2.390019) (xy 86.859603 2.343545)
			(xy 86.989598 2.289698) (xy 87.11637 2.228647) (xy 87.239519 2.160584) (xy 87.358658 2.085722) (xy 87.473412 2.004299)
			(xy 87.58342 1.916569) (xy 87.688336 1.822809) (xy 87.78783 1.723314) (xy 87.881588 1.618397) (xy 87.969317 1.508388)
			(xy 88.050739 1.393633) (xy 88.125599 1.274493) (xy 88.193661 1.151343) (xy 88.254711 1.024571) (xy 88.308556 0.894575)
			(xy 88.355028 0.761764) (xy 88.39398 0.626557) (xy 88.42529 0.489378) (xy 88.448859 0.35066) (xy 88.464613 0.210838)
			(xy 88.472503 0.070353) (xy 88.473026 0) (xy 88.473026 -8.850122) (xy 88.473549 -8.905928) (xy 88.481891 -9.017228)
			(xy 88.498528 -9.127594) (xy 88.523365 -9.236408) (xy 88.556265 -9.343061) (xy 88.597043 -9.446957)
			(xy 88.645472 -9.547516) (xy 88.701279 -9.644174) (xy 88.764154 -9.736392) (xy 88.833745 -9.823653)
			(xy 88.909662 -9.90547) (xy 88.99148 -9.981384) (xy 89.078743 -10.050972) (xy 89.170963 -10.113844)
			(xy 89.267623 -10.169649) (xy 89.368183 -10.218074) (xy 89.472081 -10.258849) (xy 89.578735 -10.291746)
			(xy 89.687549 -10.316581) (xy 89.797915 -10.333214) (xy 89.909216 -10.341553) (xy 89.965022 -10.342118)
			(xy 91.965018 -10.342118) (xy 92.020825 -10.341596) (xy 92.132127 -10.333254) (xy 92.242494 -10.316617)
			(xy 92.351309 -10.29178) (xy 92.457964 -10.258881) (xy 92.561862 -10.218103) (xy 92.662422 -10.169675)
			(xy 92.759082 -10.113868) (xy 92.851302 -10.050993) (xy 92.938565 -9.981403) (xy 93.020384 -9.905487)
			(xy 93.096301 -9.823668) (xy 93.165891 -9.736405) (xy 93.228766 -9.644186) (xy 93.284573 -9.547526)
			(xy 93.333001 -9.446965) (xy 93.373779 -9.343067) (xy 93.406679 -9.236413) (xy 93.431517 -9.127597)
			(xy 93.448153 -9.01723) (xy 93.456495 -8.905929) (xy 93.457014 -8.850122) (xy 93.457014 0) (xy 93.457498 0.070354)
			(xy 93.465388 0.21084) (xy 93.481142 0.350663) (xy 93.504712 0.489383) (xy 93.536022 0.626563) (xy 93.574975 0.761771)
			(xy 93.621448 0.894583) (xy 93.675295 1.02458) (xy 93.736346 1.151353) (xy 93.804409 1.274504) (xy 93.87927 1.393645)
			(xy 93.960694 1.5084) (xy 94.048424 1.61841) (xy 94.142184 1.723327) (xy 94.24168 1.822823) (xy 94.346598 1.916583)
			(xy 94.456608 2.004312) (xy 94.571364 2.085735) (xy 94.690505 2.160596) (xy 94.813655 2.228659) (xy 94.940429 2.289709)
			(xy 95.070426 2.343555) (xy 95.203238 2.390028) (xy 95.338447 2.42898) (xy 95.475627 2.46029) (xy 95.614347 2.483859)
			(xy 95.75417 2.499613) (xy 95.894656 2.507502) (xy 95.96501 2.507996) (xy 124.06503 2.507996) (xy 124.135383 2.507502)
			(xy 124.275868 2.499611) (xy 124.41569 2.483855) (xy 124.554408 2.460284) (xy 124.691586 2.428973)
			(xy 124.826793 2.390019) (xy 124.959603 2.343545) (xy 125.089598 2.289698) (xy 125.21637 2.228647)
			(xy 125.339519 2.160584) (xy 125.458658 2.085722) (xy 125.573412 2.004299) (xy 125.68342 1.916569)
			(xy 125.788336 1.822809) (xy 125.88783 1.723314) (xy 125.981588 1.618397) (xy 126.069317 1.508388)
			(xy 126.150739 1.393633) (xy 126.225599 1.274493) (xy 126.293661 1.151343) (xy 126.354711 1.024571)
			(xy 126.408556 0.894575) (xy 126.455028 0.761764) (xy 126.49398 0.626557) (xy 126.52529 0.489378)
			(xy 126.548859 0.35066) (xy 126.564613 0.210838) (xy 126.572503 0.070353) (xy 126.573026 0) (xy 126.573026 -8.850122)
			(xy 126.573549 -8.905928) (xy 126.581891 -9.017228) (xy 126.598528 -9.127594) (xy 126.623365 -9.236408)
			(xy 126.656265 -9.343061) (xy 126.697043 -9.446957) (xy 126.745472 -9.547516) (xy 126.801279 -9.644174)
			(xy 126.864154 -9.736392) (xy 126.933745 -9.823653) (xy 127.009662 -9.90547) (xy 127.09148 -9.981384)
			(xy 127.178743 -10.050972) (xy 127.270963 -10.113844) (xy 127.367623 -10.169649) (xy 127.468183 -10.218074)
			(xy 127.572081 -10.258849) (xy 127.678735 -10.291746) (xy 127.787549 -10.316581) (xy 127.897915 -10.333214)
			(xy 128.009216 -10.341553) (xy 128.065022 -10.342118) (xy 130.065018 -10.342118) (xy 130.120825 -10.341596)
			(xy 130.232127 -10.333254) (xy 130.342494 -10.316617) (xy 130.451309 -10.29178) (xy 130.557964 -10.258881)
			(xy 130.661862 -10.218103) (xy 130.762422 -10.169675) (xy 130.859082 -10.113868) (xy 130.951302 -10.050993)
			(xy 131.038565 -9.981403) (xy 131.120384 -9.905487) (xy 131.196301 -9.823668) (xy 131.265891 -9.736405)
			(xy 131.328766 -9.644186) (xy 131.384573 -9.547526) (xy 131.433001 -9.446965) (xy 131.473779 -9.343067)
			(xy 131.506679 -9.236413) (xy 131.531517 -9.127597) (xy 131.548153 -9.01723) (xy 131.556495 -8.905929)
			(xy 131.557014 -8.850122) (xy 131.557014 0) (xy 131.557498 0.070354) (xy 131.565388 0.21084) (xy 131.581142 0.350663)
			(xy 131.604712 0.489383) (xy 131.636022 0.626563) (xy 131.674975 0.761771) (xy 131.721448 0.894583)
			(xy 131.775295 1.02458) (xy 131.836346 1.151353) (xy 131.904409 1.274504) (xy 131.97927 1.393645)
			(xy 132.060694 1.5084) (xy 132.148424 1.61841) (xy 132.242184 1.723327) (xy 132.34168 1.822823) (xy 132.446598 1.916583)
			(xy 132.556608 2.004312) (xy 132.671364 2.085735) (xy 132.790505 2.160596) (xy 132.913655 2.228659)
			(xy 133.040429 2.289709) (xy 133.170426 2.343555) (xy 133.303238 2.390028) (xy 133.438447 2.42898)
			(xy 133.575627 2.46029) (xy 133.714347 2.483859) (xy 133.85417 2.499613) (xy 133.994656 2.507502)
			(xy 134.06501 2.507996) (xy 150.064978 2.507996) (xy 150.135332 2.507512) (xy 150.27582 2.499624)
			(xy 150.415644 2.483871) (xy 150.554365 2.460302) (xy 150.691546 2.428993) (xy 150.826756 2.39004)
			(xy 150.959569 2.343568) (xy 151.089567 2.289722) (xy 151.216342 2.228672) (xy 151.339494 2.160609)
			(xy 151.458636 2.085748) (xy 151.573393 2.004324) (xy 151.683404 1.916594) (xy 151.788322 1.822834)
			(xy 151.887819 1.723338) (xy 151.98158 1.61842) (xy 152.069311 1.50841) (xy 152.150736 1.393654)
			(xy 152.225598 1.274513) (xy 152.293661 1.151361) (xy 152.354713 1.024587) (xy 152.40856 0.894589)
			(xy 152.455034 0.761777) (xy 152.493987 0.626567) (xy 152.525298 0.489386) (xy 152.548868 0.350666)
			(xy 152.564622 0.210842) (xy 152.572512 0.070354) (xy 152.572974 0) (xy 152.572974 -8.850122) (xy 152.573497 -8.905929)
			(xy 152.581839 -9.017231) (xy 152.598475 -9.127598) (xy 152.623313 -9.236413) (xy 152.656212 -9.343068)
			(xy 152.69699 -9.446966) (xy 152.745418 -9.547526) (xy 152.801225 -9.644186) (xy 152.8641 -9.736406)
			(xy 152.93369 -9.823669) (xy 153.009606 -9.905488) (xy 153.091425 -9.981405) (xy 153.178688 -10.050995)
			(xy 153.270907 -10.11387) (xy 153.367567 -10.169678) (xy 153.468127 -10.218107) (xy 153.572025 -10.258885)
			(xy 153.67868 -10.291785) (xy 153.787495 -10.316623) (xy 153.897862 -10.33326) (xy 154.009163 -10.341603)
			(xy 154.06497 -10.342118) (xy 156.064966 -10.342118) (xy 156.120775 -10.34161) (xy 156.23208 -10.333271)
			(xy 156.342451 -10.316638) (xy 156.45127 -10.291803) (xy 156.557929 -10.258906) (xy 156.661832 -10.21813)
			(xy 156.762396 -10.169703) (xy 156.859061 -10.113896) (xy 156.951284 -10.051022) (xy 157.038552 -9.981431)
			(xy 157.120374 -9.905514) (xy 157.196295 -9.823694) (xy 157.265888 -9.736429) (xy 157.328766 -9.644208)
			(xy 157.384577 -9.547546) (xy 157.433007 -9.446983) (xy 157.473787 -9.343082) (xy 157.506689 -9.236424)
			(xy 157.531528 -9.127606) (xy 157.548165 -9.017236) (xy 157.556508 -8.905931) (xy 157.556962 -8.850122)
			(xy 157.556962 0) (xy 157.557455 0.070354) (xy 157.565345 0.210841) (xy 157.581099 0.350665) (xy 157.604668 0.489385)
			(xy 157.635978 0.626566) (xy 157.674931 0.761775) (xy 157.721404 0.894587) (xy 157.77525 1.024585)
			(xy 157.8363 1.151359) (xy 157.904363 1.274511) (xy 157.979224 1.393652) (xy 158.060647 1.508409)
			(xy 158.148376 1.61842) (xy 158.242136 1.723339) (xy 158.341631 1.822835) (xy 158.446548 1.916597)
			(xy 158.556557 2.004328) (xy 158.671313 2.085753) (xy 158.790453 2.160616) (xy 158.913604 2.22868)
			(xy 159.040377 2.289733) (xy 159.170374 2.343581) (xy 159.303185 2.390056) (xy 159.438394 2.429011)
			(xy 159.575574 2.460324) (xy 159.714294 2.483895) (xy 159.854117 2.499652) (xy 159.994604 2.507544)
			(xy 160.064958 2.507996) (xy 176.064926 2.507996) (xy 176.135279 2.507502) (xy 176.275764 2.499611)
			(xy 176.415586 2.483856) (xy 176.554304 2.460285) (xy 176.691483 2.428974) (xy 176.82669 2.39002)
			(xy 176.9595 2.343547) (xy 177.089496 2.289699) (xy 177.216267 2.228648) (xy 177.339416 2.160585)
			(xy 177.458556 2.085724) (xy 177.57331 2.0043) (xy 177.683318 1.91657) (xy 177.788234 1.822811) (xy 177.887728 1.723315)
			(xy 177.981487 1.618398) (xy 178.069216 1.508389) (xy 178.150638 1.393634) (xy 178.225498 1.274494)
			(xy 178.29356 1.151344) (xy 178.35461 1.024572) (xy 178.408456 0.894576) (xy 178.454928 0.761765)
			(xy 178.49388 0.626558) (xy 178.52519 0.489379) (xy 178.548759 0.35066) (xy 178.564513 0.210838)
			(xy 178.572403 0.070353) (xy 178.572922 0) (xy 178.572922 -8.850122) (xy 178.573445 -8.905928) (xy 178.581787 -9.017229)
			(xy 178.598424 -9.127594) (xy 178.623261 -9.236408) (xy 178.656161 -9.343061) (xy 178.696939 -9.446958)
			(xy 178.745367 -9.547517) (xy 178.801175 -9.644175) (xy 178.86405 -9.736393) (xy 178.93364 -9.823654)
			(xy 179.009557 -9.905471) (xy 179.091376 -9.981386) (xy 179.178639 -10.050974) (xy 179.270859 -10.113846)
			(xy 179.367519 -10.169651) (xy 179.468079 -10.218077) (xy 179.571976 -10.258852) (xy 179.678631 -10.291749)
			(xy 179.787445 -10.316584) (xy 179.897811 -10.333218) (xy 180.009112 -10.341557) (xy 180.064918 -10.342118)
			(xy 182.064914 -10.342118) (xy 182.120721 -10.341596) (xy 182.232023 -10.333254) (xy 182.34239 -10.316618)
			(xy 182.451206 -10.291781) (xy 182.557861 -10.258882) (xy 182.661759 -10.218104) (xy 182.76232 -10.169676)
			(xy 182.85898 -10.113869) (xy 182.9512 -10.050995) (xy 183.038463 -9.981405) (xy 183.120282 -9.905488)
			(xy 183.196199 -9.823669) (xy 183.26579 -9.736406) (xy 183.328665 -9.644187) (xy 183.384473 -9.547527)
			(xy 183.432901 -9.446966) (xy 183.473679 -9.343068) (xy 183.506579 -9.236413) (xy 183.531416 -9.127598)
			(xy 183.548053 -9.017231) (xy 183.556395 -8.905929) (xy 183.55691 -8.850122) (xy 183.55691 0) (xy 183.557394 0.070354)
			(xy 183.565284 0.21084) (xy 183.581038 0.350664) (xy 183.604608 0.489383) (xy 183.635918 0.626563)
			(xy 183.674871 0.761772) (xy 183.721344 0.894584) (xy 183.775191 1.024581) (xy 183.836242 1.151354)
			(xy 183.904305 1.274505) (xy 183.979166 1.393646) (xy 184.06059 1.508401) (xy 184.14832 1.618411)
			(xy 184.24208 1.723329) (xy 184.341576 1.822824) (xy 184.446493 1.916584) (xy 184.556503 2.004314)
			(xy 184.671259 2.085737) (xy 184.7904 2.160598) (xy 184.913551 2.228661) (xy 185.040325 2.289712)
			(xy 185.170322 2.343558) (xy 185.303134 2.390031) (xy 185.438342 2.428983) (xy 185.575523 2.460294)
			(xy 185.714242 2.483863) (xy 185.854066 2.499617) (xy 185.994552 2.507506) (xy 186.064906 2.507996)
			(xy 202.064874 2.507996) (xy 202.135228 2.507512) (xy 202.275716 2.499624) (xy 202.41554 2.483871)
			(xy 202.554261 2.460303) (xy 202.691443 2.428993) (xy 202.826653 2.390041) (xy 202.959466 2.343569)
			(xy 203.089464 2.289723) (xy 203.216239 2.228673) (xy 203.339391 2.16061) (xy 203.458534 2.085749)
			(xy 203.573291 2.004326) (xy 203.683302 1.916596) (xy 203.788221 1.822836) (xy 203.887718 1.72334)
			(xy 203.981479 1.618422) (xy 204.06921 1.508412) (xy 204.150635 1.393655) (xy 204.225497 1.274514)
			(xy 204.293561 1.151362) (xy 204.354613 1.024588) (xy 204.40846 0.89459) (xy 204.454933 0.761778)
			(xy 204.493887 0.626568) (xy 204.525198 0.489387) (xy 204.548768 0.350666) (xy 204.564522 0.210842)
			(xy 204.572412 0.070354) (xy 204.57287 0) (xy 204.57287 -8.850122) (xy 204.573393 -8.905929) (xy 204.581735 -9.017231)
			(xy 204.598371 -9.127598) (xy 204.623209 -9.236413) (xy 204.656108 -9.343068) (xy 204.696886 -9.446966)
			(xy 204.745314 -9.547527) (xy 204.801121 -9.644187) (xy 204.863996 -9.736407) (xy 204.933586 -9.82367)
			(xy 205.009502 -9.905489) (xy 205.091321 -9.981407) (xy 205.178583 -10.050997) (xy 205.270803 -10.113872)
			(xy 205.367463 -10.16968) (xy 205.468023 -10.218109) (xy 205.571921 -10.258888) (xy 205.678575 -10.291788)
			(xy 205.78739 -10.316626) (xy 205.897757 -10.333264) (xy 206.009059 -10.341607) (xy 206.064866 -10.342118)
			(xy 208.065116 -10.342118) (xy 208.120923 -10.341596) (xy 208.232225 -10.333254) (xy 208.342592 -10.316618)
			(xy 208.451407 -10.29178) (xy 208.558062 -10.258881) (xy 208.66196 -10.218103) (xy 208.762521 -10.169676)
			(xy 208.859181 -10.113868) (xy 208.951401 -10.050994) (xy 209.038664 -9.981404) (xy 209.120483 -9.905487)
			(xy 209.1964 -9.823669) (xy 209.26599 -9.736406) (xy 209.328865 -9.644186) (xy 209.384673 -9.547526)
			(xy 209.433101 -9.446966) (xy 209.473879 -9.343068) (xy 209.506779 -9.236413) (xy 209.531617 -9.127598)
			(xy 209.548253 -9.017231) (xy 209.556595 -8.905929) (xy 209.557112 -8.850122) (xy 209.557112 0) (xy 209.557596 0.070354)
			(xy 209.565486 0.21084) (xy 209.58124 0.350663) (xy 209.60481 0.489383) (xy 209.63612 0.626563) (xy 209.675073 0.761772)
			(xy 209.721546 0.894583) (xy 209.775393 1.02458) (xy 209.836444 1.151354) (xy 209.904507 1.274505)
			(xy 209.979368 1.393645) (xy 210.060792 1.508401) (xy 210.148522 1.618411) (xy 210.242282 1.723328)
			(xy 210.341778 1.822823) (xy 210.446696 1.916583) (xy 210.556706 2.004313) (xy 210.671462 2.085736)
			(xy 210.790602 2.160597) (xy 210.913753 2.22866) (xy 211.040527 2.289711) (xy 211.170524 2.343557)
			(xy 211.303336 2.390029) (xy 211.438545 2.428982) (xy 211.575725 2.460292) (xy 211.714444 2.483861)
			(xy 211.854268 2.499615) (xy 211.994754 2.507504) (xy 212.065108 2.507996) (xy 240.164874 2.507996)
			(xy 240.235228 2.507512) (xy 240.375716 2.499624) (xy 240.51554 2.483871) (xy 240.654261 2.460303)
			(xy 240.791443 2.428993) (xy 240.926653 2.390041) (xy 241.059466 2.343569) (xy 241.189464 2.289723)
			(xy 241.316239 2.228673) (xy 241.439391 2.16061) (xy 241.558534 2.085749) (xy 241.673291 2.004326)
			(xy 241.783302 1.916596) (xy 241.888221 1.822836) (xy 241.987718 1.72334) (xy 242.081479 1.618422)
			(xy 242.16921 1.508412) (xy 242.250635 1.393655) (xy 242.325497 1.274514) (xy 242.393561 1.151362)
			(xy 242.454613 1.024588) (xy 242.50846 0.89459) (xy 242.554933 0.761778) (xy 242.593887 0.626568)
			(xy 242.625198 0.489387) (xy 242.648768 0.350666) (xy 242.664522 0.210842) (xy 242.672412 0.070354)
			(xy 242.67287 0) (xy 242.67287 -8.850122) (xy 242.673393 -8.905929) (xy 242.681735 -9.017231) (xy 242.698371 -9.127598)
			(xy 242.723209 -9.236413) (xy 242.756108 -9.343068) (xy 242.796886 -9.446966) (xy 242.845314 -9.547527)
			(xy 242.901121 -9.644187) (xy 242.963996 -9.736407) (xy 243.033586 -9.82367) (xy 243.109502 -9.905489)
			(xy 243.191321 -9.981407) (xy 243.278583 -10.050997) (xy 243.370803 -10.113872) (xy 243.467463 -10.16968)
			(xy 243.568023 -10.218109) (xy 243.671921 -10.258888) (xy 243.778575 -10.291788) (xy 243.88739 -10.316626)
			(xy 243.997757 -10.333264) (xy 244.109059 -10.341607) (xy 244.164866 -10.342118) (xy 246.165116 -10.342118)
			(xy 246.220923 -10.341596) (xy 246.332225 -10.333254) (xy 246.442592 -10.316618) (xy 246.551407 -10.29178)
			(xy 246.658062 -10.258881) (xy 246.76196 -10.218103) (xy 246.862521 -10.169676) (xy 246.959181 -10.113868)
			(xy 247.051401 -10.050994) (xy 247.138664 -9.981404) (xy 247.220483 -9.905487) (xy 247.2964 -9.823669)
			(xy 247.36599 -9.736406) (xy 247.428865 -9.644186) (xy 247.484673 -9.547526) (xy 247.533101 -9.446966)
			(xy 247.573879 -9.343068) (xy 247.606779 -9.236413) (xy 247.631617 -9.127598) (xy 247.648253 -9.017231)
			(xy 247.656595 -8.905929) (xy 247.657112 -8.850122) (xy 247.657112 0) (xy 247.657596 0.070354) (xy 247.665486 0.21084)
			(xy 247.68124 0.350663) (xy 247.70481 0.489383) (xy 247.73612 0.626563) (xy 247.775073 0.761772)
			(xy 247.821546 0.894583) (xy 247.875393 1.02458) (xy 247.936444 1.151354) (xy 248.004507 1.274505)
			(xy 248.079368 1.393645) (xy 248.160792 1.508401) (xy 248.248522 1.618411) (xy 248.342282 1.723328)
			(xy 248.441778 1.822823) (xy 248.546696 1.916583) (xy 248.656706 2.004313) (xy 248.771462 2.085736)
			(xy 248.890602 2.160597) (xy 249.013753 2.22866) (xy 249.140527 2.289711) (xy 249.270524 2.343557)
			(xy 249.403336 2.390029) (xy 249.538545 2.428982) (xy 249.675725 2.460292) (xy 249.814444 2.483861)
			(xy 249.954268 2.499615) (xy 250.094754 2.507504) (xy 250.165108 2.507996) (xy 266.165076 2.507996)
			(xy 266.23543 2.507512) (xy 266.375918 2.499624) (xy 266.515742 2.483871) (xy 266.654463 2.460303)
			(xy 266.791644 2.428993) (xy 266.926854 2.390041) (xy 267.059667 2.343569) (xy 267.189666 2.289723)
			(xy 267.31644 2.228672) (xy 267.439593 2.160609) (xy 267.558735 2.085749) (xy 267.673492 2.004325)
			(xy 267.783503 1.916595) (xy 267.888422 1.822835) (xy 267.987918 1.723339) (xy 268.08168 1.618421)
			(xy 268.169411 1.508411) (xy 268.250835 1.393655) (xy 268.325697 1.274513) (xy 268.393761 1.151362)
			(xy 268.454813 1.024588) (xy 268.50866 0.89459) (xy 268.555134 0.761777) (xy 268.594087 0.626568)
			(xy 268.625398 0.489387) (xy 268.648968 0.350666) (xy 268.664722 0.210842) (xy 268.672612 0.070354)
			(xy 268.673072 0) (xy 268.673072 -8.850122) (xy 268.673595 -8.905929) (xy 268.681937 -9.017231) (xy 268.698573 -9.127598)
			(xy 268.723411 -9.236413) (xy 268.75631 -9.343068) (xy 268.797088 -9.446966) (xy 268.845516 -9.547526)
			(xy 268.901323 -9.644187) (xy 268.964198 -9.736406) (xy 269.033788 -9.82367) (xy 269.109704 -9.905489)
			(xy 269.191523 -9.981406) (xy 269.278786 -10.050996) (xy 269.371005 -10.113871) (xy 269.467665 -10.169679)
			(xy 269.568225 -10.218108) (xy 269.672123 -10.258886) (xy 269.778777 -10.291787) (xy 269.887592 -10.316625)
			(xy 269.997959 -10.333262) (xy 270.109261 -10.341605) (xy 270.165068 -10.342118) (xy 272.165064 -10.342118)
			(xy 272.220873 -10.34161) (xy 272.332178 -10.333272) (xy 272.442549 -10.316638) (xy 272.551368 -10.291804)
			(xy 272.658028 -10.258906) (xy 272.76193 -10.21813) (xy 272.862495 -10.169703) (xy 272.95916 -10.113897)
			(xy 273.051383 -10.051022) (xy 273.138651 -9.981432) (xy 273.220473 -9.905515) (xy 273.296394 -9.823695)
			(xy 273.365988 -9.73643) (xy 273.428866 -9.644209) (xy 273.484676 -9.547546) (xy 273.533107 -9.446983)
			(xy 273.573887 -9.343082) (xy 273.606789 -9.236425) (xy 273.631628 -9.127606) (xy 273.648265 -9.017236)
			(xy 273.656608 -8.905931) (xy 273.65706 -8.850122) (xy 273.65706 0) (xy 273.657553 0.070354) (xy 273.665443 0.210841)
			(xy 273.681197 0.350665) (xy 273.704766 0.489385) (xy 273.736076 0.626566) (xy 273.775029 0.761775)
			(xy 273.821502 0.894588) (xy 273.875348 1.024585) (xy 273.936398 1.15136) (xy 274.004461 1.274511)
			(xy 274.079321 1.393653) (xy 274.160745 1.50841) (xy 274.248474 1.618421) (xy 274.342234 1.723339)
			(xy 274.441729 1.822836) (xy 274.546646 1.916598) (xy 274.656655 2.004329) (xy 274.771411 2.085754)
			(xy 274.890551 2.160617) (xy 275.013701 2.228682) (xy 275.140474 2.289734) (xy 275.270471 2.343583)
			(xy 275.403283 2.390058) (xy 275.538492 2.429013) (xy 275.675672 2.460325) (xy 275.814392 2.483897)
			(xy 275.954215 2.499654) (xy 276.094702 2.507545) (xy 276.165056 2.507996) (xy 292.165024 2.507996)
			(xy 292.235377 2.507502) (xy 292.375862 2.499611) (xy 292.515684 2.483856) (xy 292.654403 2.460285)
			(xy 292.791581 2.428974) (xy 292.926788 2.390021) (xy 293.059599 2.343547) (xy 293.189594 2.2897)
			(xy 293.316366 2.228649) (xy 293.439515 2.160586) (xy 293.558655 2.085724) (xy 293.673409 2.004301)
			(xy 293.783417 1.916571) (xy 293.888334 1.822811) (xy 293.987828 1.723316) (xy 294.081587 1.618399)
			(xy 294.169315 1.50839) (xy 294.250738 1.393635) (xy 294.325598 1.274495) (xy 294.39366 1.151345)
			(xy 294.45471 1.024572) (xy 294.508556 0.894576) (xy 294.555028 0.761765) (xy 294.59398 0.626558)
			(xy 294.62529 0.489379) (xy 294.648859 0.35066) (xy 294.664613 0.210839) (xy 294.672503 0.070353)
			(xy 294.67302 0) (xy 294.67302 -8.850122) (xy 294.673543 -8.905928) (xy 294.681885 -9.017229) (xy 294.698522 -9.127594)
			(xy 294.723359 -9.236408) (xy 294.756259 -9.343062) (xy 294.797037 -9.446958) (xy 294.845465 -9.547517)
			(xy 294.901273 -9.644176) (xy 294.964148 -9.736394) (xy 295.033738 -9.823655) (xy 295.109655 -9.905472)
			(xy 295.191474 -9.981387) (xy 295.278737 -10.050975) (xy 295.370956 -10.113847) (xy 295.467616 -10.169652)
			(xy 295.568176 -10.218078) (xy 295.672074 -10.258853) (xy 295.778728 -10.291751) (xy 295.887543 -10.316586)
			(xy 295.997909 -10.333219) (xy 296.10921 -10.341559) (xy 296.165016 -10.342118) (xy 298.165012 -10.342118)
			(xy 298.220819 -10.341596) (xy 298.332121 -10.333254) (xy 298.442488 -10.316618) (xy 298.551304 -10.291781)
			(xy 298.657959 -10.258882) (xy 298.761858 -10.218105) (xy 298.862418 -10.169677) (xy 298.959079 -10.11387)
			(xy 299.051299 -10.050995) (xy 299.138562 -9.981405) (xy 299.220382 -9.905489) (xy 299.296299 -9.82367)
			(xy 299.365889 -9.736407) (xy 299.428764 -9.644188) (xy 299.484572 -9.547527) (xy 299.533001 -9.446967)
			(xy 299.573779 -9.343069) (xy 299.606679 -9.236414) (xy 299.631516 -9.127598) (xy 299.648153 -9.017231)
			(xy 299.656495 -8.905929) (xy 299.657008 -8.850122) (xy 299.657008 0) (xy 299.657492 0.070354) (xy 299.665382 0.21084)
			(xy 299.681136 0.350664) (xy 299.704706 0.489383) (xy 299.736016 0.626564) (xy 299.774969 0.761772)
			(xy 299.821442 0.894584) (xy 299.875289 1.024581) (xy 299.93634 1.151355) (xy 300.004403 1.274505)
			(xy 300.079264 1.393646) (xy 300.160688 1.508402) (xy 300.248418 1.618412) (xy 300.342178 1.723329)
			(xy 300.441673 1.822825) (xy 300.546591 1.916585) (xy 300.656601 2.004315) (xy 300.771357 2.085738)
			(xy 300.890498 2.160599) (xy 301.013649 2.228662) (xy 301.140423 2.289713) (xy 301.27042 2.343559)
			(xy 301.403232 2.390032) (xy 301.53844 2.428985) (xy 301.67562 2.460295) (xy 301.81434 2.483864)
			(xy 301.954163 2.499618) (xy 302.09465 2.507508) (xy 302.165004 2.507996) (xy 318.164972 2.507996)
			(xy 318.235326 2.507512) (xy 318.375814 2.499624) (xy 318.515639 2.483871) (xy 318.65436 2.460303)
			(xy 318.791541 2.428994) (xy 318.926751 2.390042) (xy 319.059564 2.34357) (xy 319.189563 2.289724)
			(xy 319.316338 2.228673) (xy 319.43949 2.160611) (xy 319.558633 2.08575) (xy 319.67339 2.004327)
			(xy 319.783401 1.916597) (xy 319.88832 1.822836) (xy 319.987817 1.723341) (xy 320.081579 1.618423)
			(xy 320.16931 1.508412) (xy 320.250734 1.393656) (xy 320.325597 1.274514) (xy 320.393661 1.151363)
			(xy 320.454712 1.024589) (xy 320.50856 0.894591) (xy 320.555033 0.761778) (xy 320.593987 0.626568)
			(xy 320.625298 0.489387) (xy 320.648868 0.350666) (xy 320.664622 0.210842) (xy 320.672512 0.070354)
			(xy 320.672968 0) (xy 320.672968 -8.850122) (xy 320.673491 -8.905929) (xy 320.681833 -9.017231) (xy 320.698469 -9.127598)
			(xy 320.723307 -9.236413) (xy 320.756206 -9.343068) (xy 320.796984 -9.446967) (xy 320.845412 -9.547527)
			(xy 320.901219 -9.644188) (xy 320.964093 -9.736408) (xy 321.033684 -9.823671) (xy 321.1096 -9.90549)
			(xy 321.191418 -9.981407) (xy 321.278681 -10.050998) (xy 321.3709 -10.113873) (xy 321.46756 -10.169682)
			(xy 321.56812 -10.21811) (xy 321.672018 -10.258889) (xy 321.778673 -10.29179) (xy 321.887488 -10.316628)
			(xy 321.997855 -10.333266) (xy 322.109157 -10.341609) (xy 322.164964 -10.342118) (xy 324.16496 -10.342118)
			(xy 324.220769 -10.34161) (xy 324.332074 -10.333272) (xy 324.442446 -10.316639) (xy 324.551265 -10.291805)
			(xy 324.657925 -10.258907) (xy 324.761827 -10.218131) (xy 324.862393 -10.169705) (xy 324.959057 -10.113898)
			(xy 325.051281 -10.051024) (xy 325.138549 -9.981433) (xy 325.220372 -9.905516) (xy 325.296293 -9.823696)
			(xy 325.365887 -9.736431) (xy 325.428765 -9.64421) (xy 325.484576 -9.547547) (xy 325.533007 -9.446984)
			(xy 325.573787 -9.343083) (xy 325.606689 -9.236425) (xy 325.631528 -9.127607) (xy 325.648165 -9.017236)
			(xy 325.656508 -8.905931) (xy 325.656956 -8.850122) (xy 325.656956 0) (xy 325.657449 0.070354) (xy 325.665339 0.210841)
			(xy 325.681093 0.350665) (xy 325.704662 0.489386) (xy 325.735972 0.626566) (xy 325.774925 0.761776)
			(xy 325.821398 0.894588) (xy 325.875244 1.024586) (xy 325.936294 1.15136) (xy 326.004357 1.274512)
			(xy 326.079217 1.393654) (xy 326.16064 1.508411) (xy 326.24837 1.618422) (xy 326.342129 1.723341)
			(xy 326.441624 1.822838) (xy 326.546542 1.916599) (xy 326.656551 2.004331) (xy 326.771306 2.085756)
			(xy 326.890447 2.160619) (xy 327.013597 2.228684) (xy 327.14037 2.289737) (xy 327.270367 2.343585)
			(xy 327.403179 2.39006) (xy 327.538387 2.429016) (xy 327.675567 2.460328) (xy 327.814287 2.4839)
			(xy 327.954111 2.499657) (xy 328.094598 2.507549) (xy 328.164952 2.507996) (xy 356.264972 2.507996)
			(xy 356.335326 2.507512) (xy 356.475814 2.499624) (xy 356.615639 2.483871) (xy 356.75436 2.460303)
			(xy 356.891541 2.428994) (xy 357.026751 2.390042) (xy 357.159564 2.34357) (xy 357.289563 2.289724)
			(xy 357.416338 2.228673) (xy 357.53949 2.160611) (xy 357.658633 2.08575) (xy 357.77339 2.004327)
			(xy 357.883401 1.916597) (xy 357.98832 1.822836) (xy 358.087817 1.723341) (xy 358.181579 1.618423)
			(xy 358.26931 1.508412) (xy 358.350734 1.393656) (xy 358.425597 1.274514) (xy 358.493661 1.151363)
			(xy 358.554712 1.024589) (xy 358.60856 0.894591) (xy 358.655033 0.761778) (xy 358.693987 0.626568)
			(xy 358.725298 0.489387) (xy 358.748868 0.350666) (xy 358.764622 0.210842) (xy 358.772512 0.070354)
			(xy 358.772968 0) (xy 358.772968 -8.850122) (xy 358.773491 -8.905929) (xy 358.781833 -9.017231) (xy 358.798469 -9.127598)
			(xy 358.823307 -9.236413) (xy 358.856206 -9.343068) (xy 358.896984 -9.446967) (xy 358.945412 -9.547527)
			(xy 359.001219 -9.644188) (xy 359.064093 -9.736408) (xy 359.133684 -9.823671) (xy 359.2096 -9.90549)
			(xy 359.291418 -9.981407) (xy 359.378681 -10.050998) (xy 359.4709 -10.113873) (xy 359.56756 -10.169682)
			(xy 359.66812 -10.21811) (xy 359.772018 -10.258889) (xy 359.878673 -10.29179) (xy 359.987488 -10.316628)
			(xy 360.097855 -10.333266) (xy 360.209157 -10.341609) (xy 360.264964 -10.342118) (xy 362.26496 -10.342118)
			(xy 362.320769 -10.34161) (xy 362.432074 -10.333272) (xy 362.542446 -10.316639) (xy 362.651265 -10.291805)
			(xy 362.757925 -10.258907) (xy 362.861827 -10.218131) (xy 362.962393 -10.169705) (xy 363.059057 -10.113898)
			(xy 363.151281 -10.051024) (xy 363.238549 -9.981433) (xy 363.320372 -9.905516) (xy 363.396293 -9.823696)
			(xy 363.465887 -9.736431) (xy 363.528765 -9.64421) (xy 363.584576 -9.547547) (xy 363.633007 -9.446984)
			(xy 363.673787 -9.343083) (xy 363.706689 -9.236425) (xy 363.731528 -9.127607) (xy 363.748165 -9.017236)
			(xy 363.756508 -8.905931) (xy 363.756956 -8.850122) (xy 363.756956 0) (xy 363.757449 0.070354) (xy 363.765339 0.210841)
			(xy 363.781093 0.350665) (xy 363.804662 0.489386) (xy 363.835972 0.626566) (xy 363.874925 0.761776)
			(xy 363.921398 0.894588) (xy 363.975244 1.024586) (xy 364.036294 1.15136) (xy 364.104357 1.274512)
			(xy 364.179217 1.393654) (xy 364.26064 1.508411) (xy 364.34837 1.618422) (xy 364.442129 1.723341)
			(xy 364.541624 1.822838) (xy 364.646542 1.916599) (xy 364.756551 2.004331) (xy 364.871306 2.085756)
			(xy 364.990447 2.160619) (xy 365.113597 2.228684) (xy 365.24037 2.289737) (xy 365.370367 2.343585)
			(xy 365.503179 2.39006) (xy 365.638387 2.429016) (xy 365.775567 2.460328) (xy 365.914287 2.4839)
			(xy 366.054111 2.499657) (xy 366.194598 2.507549) (xy 366.264952 2.507996) (xy 382.26492 2.507996)
			(xy 382.335273 2.507502) (xy 382.475759 2.499612) (xy 382.615581 2.483856) (xy 382.754299 2.460286)
			(xy 382.891478 2.428975) (xy 383.026685 2.390022) (xy 383.159496 2.343548) (xy 383.289491 2.289701)
			(xy 383.416264 2.22865) (xy 383.539413 2.160587) (xy 383.658552 2.085726) (xy 383.773307 2.004302)
			(xy 383.883316 1.916573) (xy 383.988232 1.822813) (xy 384.087726 1.723318) (xy 384.181485 1.6184)
			(xy 384.269214 1.508391) (xy 384.350637 1.393636) (xy 384.425497 1.274496) (xy 384.493559 1.151346)
			(xy 384.554609 1.024573) (xy 384.608455 0.894577) (xy 384.654928 0.761766) (xy 384.69388 0.626559)
			(xy 384.72519 0.48938) (xy 384.748759 0.350661) (xy 384.764513 0.210839) (xy 384.772403 0.070353)
			(xy 384.772916 0) (xy 384.772916 -8.850122) (xy 384.773439 -8.905928) (xy 384.781781 -9.017229) (xy 384.798418 -9.127595)
			(xy 384.823255 -9.236409) (xy 384.856155 -9.343062) (xy 384.896933 -9.446959) (xy 384.945361 -9.547518)
			(xy 385.001169 -9.644177) (xy 385.064044 -9.736395) (xy 385.133634 -9.823656) (xy 385.209551 -9.905473)
			(xy 385.29137 -9.981388) (xy 385.378633 -10.050977) (xy 385.470852 -10.113849) (xy 385.567512 -10.169655)
			(xy 385.668072 -10.218081) (xy 385.77197 -10.258856) (xy 385.878624 -10.291754) (xy 385.987439 -10.316589)
			(xy 386.097805 -10.333223) (xy 386.209106 -10.341563) (xy 386.264912 -10.342118) (xy 388.264908 -10.342118)
			(xy 388.320715 -10.341596) (xy 388.432017 -10.333255) (xy 388.542385 -10.316619) (xy 388.651201 -10.291782)
			(xy 388.757856 -10.258883) (xy 388.861755 -10.218106) (xy 388.962316 -10.169678) (xy 389.058977 -10.113871)
			(xy 389.151197 -10.050997) (xy 389.238461 -9.981407) (xy 389.32028 -9.90549) (xy 389.396198 -9.823671)
			(xy 389.465789 -9.736408) (xy 389.528664 -9.644189) (xy 389.584472 -9.547528) (xy 389.6329 -9.446968)
			(xy 389.673678 -9.343069) (xy 389.706579 -9.236414) (xy 389.731416 -9.127599) (xy 389.748053 -9.017231)
			(xy 389.756395 -8.905929) (xy 389.756904 -8.850122) (xy 389.756904 0) (xy 389.757397 0.070354) (xy 389.765287 0.21084)
			(xy 389.781041 0.350663) (xy 389.80461 0.489382) (xy 389.835921 0.626562) (xy 389.874874 0.76177)
			(xy 389.921346 0.894581) (xy 389.975193 1.024578) (xy 390.036243 1.151351) (xy 390.104306 1.274502)
			(xy 390.179167 1.393642) (xy 390.260591 1.508398) (xy 390.34832 1.618407) (xy 390.44208 1.723325)
			(xy 390.541575 1.82282) (xy 390.646493 1.91658) (xy 390.756502 2.004309) (xy 390.871258 2.085733)
			(xy 390.990398 2.160594) (xy 391.113549 2.228657) (xy 391.240322 2.289707) (xy 391.370319 2.343554)
			(xy 391.50313 2.390026) (xy 391.638338 2.428979) (xy 391.775518 2.46029) (xy 391.914237 2.483859)
			(xy 392.05406 2.499613) (xy 392.194546 2.507503) (xy 392.2649 2.507996) (xy 408.265122 2.507996)
			(xy 408.335475 2.507502) (xy 408.475961 2.499611) (xy 408.615782 2.483856) (xy 408.754501 2.460286)
			(xy 408.89168 2.428975) (xy 409.026887 2.390021) (xy 409.159697 2.343548) (xy 409.289693 2.289701)
			(xy 409.416465 2.22865) (xy 409.539614 2.160586) (xy 409.658754 2.085725) (xy 409.773508 2.004302)
			(xy 409.883516 1.916572) (xy 409.988433 1.822812) (xy 410.087927 1.723317) (xy 410.181686 1.6184)
			(xy 410.269415 1.50839) (xy 410.350837 1.393635) (xy 410.425697 1.274495) (xy 410.49376 1.151345)
			(xy 410.55481 1.024573) (xy 410.608655 0.894577) (xy 410.655128 0.761766) (xy 410.69408 0.626558)
			(xy 410.72539 0.489379) (xy 410.748959 0.350661) (xy 410.764713 0.210839) (xy 410.772603 0.070353)
			(xy 410.773118 0) (xy 410.773118 -8.850122) (xy 410.773641 -8.905928) (xy 410.781983 -9.017229) (xy 410.79862 -9.127595)
			(xy 410.823457 -9.236408) (xy 410.856357 -9.343062) (xy 410.897135 -9.446959) (xy 410.945563 -9.547518)
			(xy 411.001371 -9.644176) (xy 411.064246 -9.736394) (xy 411.133836 -9.823656) (xy 411.209753 -9.905472)
			(xy 411.291572 -9.981387) (xy 411.378835 -10.050976) (xy 411.471054 -10.113848) (xy 411.567714 -10.169653)
			(xy 411.668274 -10.218079) (xy 411.772172 -10.258855) (xy 411.878826 -10.291752) (xy 411.987641 -10.316587)
			(xy 412.098007 -10.333221) (xy 412.209308 -10.341561) (xy 412.265114 -10.342118) (xy 414.26511 -10.342118)
			(xy 414.320917 -10.341596) (xy 414.432219 -10.333254) (xy 414.542587 -10.316619) (xy 414.651402 -10.291782)
			(xy 414.758058 -10.258883) (xy 414.861956 -10.218105) (xy 414.962517 -10.169678) (xy 415.059178 -10.11387)
			(xy 415.151398 -10.050996) (xy 415.238662 -9.981406) (xy 415.320481 -9.905489) (xy 415.396398 -9.823671)
			(xy 415.465989 -9.736408) (xy 415.528864 -9.644188) (xy 415.584672 -9.547528) (xy 415.6331 -9.446967)
			(xy 415.673879 -9.343069) (xy 415.706779 -9.236414) (xy 415.731616 -9.127598) (xy 415.748253 -9.017231)
			(xy 415.756595 -8.905929) (xy 415.757106 -8.850122) (xy 415.757106 0) (xy 415.75759 0.070354) (xy 415.76548 0.210841)
			(xy 415.781234 0.350664) (xy 415.804804 0.489384) (xy 415.836114 0.626564) (xy 415.875067 0.761772)
			(xy 415.92154 0.894584) (xy 415.975387 1.024581) (xy 416.036438 1.151355) (xy 416.104501 1.274506)
			(xy 416.179362 1.393647) (xy 416.260785 1.508402) (xy 416.348515 1.618412) (xy 416.442276 1.72333)
			(xy 416.541771 1.822826) (xy 416.646689 1.916586) (xy 416.756699 2.004316) (xy 416.871455 2.085739)
			(xy 416.990596 2.1606) (xy 417.113747 2.228663) (xy 417.24052 2.289714) (xy 417.370518 2.343561)
			(xy 417.503329 2.390034) (xy 417.638538 2.428986) (xy 417.775718 2.460297) (xy 417.914438 2.483866)
			(xy 418.054261 2.49962) (xy 418.194748 2.50751) (xy 418.265102 2.507996) (xy 434.26507 2.507996)
			(xy 434.335425 2.507513) (xy 434.475912 2.499625) (xy 434.615737 2.483872) (xy 434.754458 2.460304)
			(xy 434.89164 2.428994) (xy 435.02685 2.390042) (xy 435.159663 2.34357) (xy 435.289662 2.289724)
			(xy 435.416437 2.228674) (xy 435.539589 2.160612) (xy 435.658732 2.085751) (xy 435.773489 2.004327)
			(xy 435.8835 1.916597) (xy 435.988419 1.822837) (xy 436.087916 1.723341) (xy 436.181678 1.618423)
			(xy 436.269409 1.508413) (xy 436.350834 1.393656) (xy 436.425696 1.274515) (xy 436.49376 1.151363)
			(xy 436.554812 1.024589) (xy 436.60866 0.894591) (xy 436.655133 0.761778) (xy 436.694087 0.626569)
			(xy 436.725398 0.489387) (xy 436.748967 0.350667) (xy 436.764722 0.210842) (xy 436.772612 0.070355)
			(xy 436.773066 0) (xy 436.773066 -8.850122) (xy 436.773589 -8.905929) (xy 436.781931 -9.017231) (xy 436.798567 -9.127598)
			(xy 436.823405 -9.236414) (xy 436.856304 -9.343069) (xy 436.897082 -9.446967) (xy 436.94551 -9.547528)
			(xy 437.001317 -9.644188) (xy 437.064191 -9.736408) (xy 437.133781 -9.823672) (xy 437.209698 -9.905491)
			(xy 437.291516 -9.981408) (xy 437.378779 -10.050999) (xy 437.470998 -10.113874) (xy 437.567658 -10.169683)
			(xy 437.668218 -10.218112) (xy 437.772116 -10.25889) (xy 437.878771 -10.291791) (xy 437.987586 -10.31663)
			(xy 438.097953 -10.333267) (xy 438.209255 -10.341611) (xy 438.265062 -10.342118) (xy 440.265058 -10.342118)
			(xy 440.320867 -10.34161) (xy 440.432173 -10.333272) (xy 440.542544 -10.316639) (xy 440.651364 -10.291805)
			(xy 440.758023 -10.258908) (xy 440.861926 -10.218132) (xy 440.962491 -10.169705) (xy 441.059156 -10.113899)
			(xy 441.151381 -10.051025) (xy 441.238648 -9.981434) (xy 441.320471 -9.905517) (xy 441.396392 -9.823697)
			(xy 441.465987 -9.736432) (xy 441.528865 -9.64421) (xy 441.584675 -9.547548) (xy 441.633106 -9.446985)
			(xy 441.673887 -9.343084) (xy 441.706788 -9.236425) (xy 441.731628 -9.127607) (xy 441.748265 -9.017236)
			(xy 441.756608 -8.905931) (xy 441.757054 -8.850122) (xy 441.757054 0) (xy 441.757538 0.070353) (xy 441.765428 0.210839)
			(xy 441.781182 0.350661) (xy 441.804752 0.48938) (xy 441.836062 0.626559) (xy 441.875016 0.761767)
			(xy 441.921489 0.894578) (xy 441.975336 1.024574) (xy 442.036387 1.151346) (xy 442.10445 1.274495)
			(xy 442.179312 1.393635) (xy 442.260736 1.508389) (xy 442.348466 1.618398) (xy 442.442227 1.723314)
			(xy 442.541722 1.822808) (xy 442.64664 1.916566) (xy 442.756651 2.004294) (xy 442.871407 2.085716)
			(xy 442.990548 2.160575) (xy 443.113699 2.228636) (xy 443.240472 2.289685) (xy 443.370469 2.343529)
			(xy 443.503281 2.39) (xy 443.638489 2.42895) (xy 443.775669 2.460258) (xy 443.914388 2.483825) (xy 444.054211 2.499576)
			(xy 444.194697 2.507463) (xy 444.26505 2.507996) (xy 465.600034 2.507996) (xy 465.65584 2.508519)
			(xy 465.767141 2.516862) (xy 465.877506 2.533499) (xy 465.98632 2.558338) (xy 466.092974 2.591238)
			(xy 466.19687 2.632016) (xy 466.297429 2.680445) (xy 466.394088 2.736252) (xy 466.486306 2.799127)
			(xy 466.573567 2.868717) (xy 466.655384 2.944634) (xy 466.7313 3.026452) (xy 466.800888 3.113715)
			(xy 466.863762 3.205934) (xy 466.919568 3.302594) (xy 466.967994 3.403154) (xy 467.008771 3.507051)
			(xy 467.041669 3.613705) (xy 467.066505 3.722519) (xy 467.083141 3.832885) (xy 467.091482 3.944186)
			(xy 467.09203 3.999992) (xy 467.09203 24.157686) (xy 467.091509 24.213494) (xy 467.083169 24.324797)
			(xy 467.066535 24.435167) (xy 467.041699 24.543984) (xy 467.008801 24.650641) (xy 466.968025 24.754542)
			(xy 466.919598 24.855105) (xy 466.863791 24.951768) (xy 466.800917 25.04399) (xy 466.731327 25.131255)
			(xy 466.655411 25.213077) (xy 466.573592 25.288996) (xy 466.486328 25.358589) (xy 466.394108 25.421466)
			(xy 466.297447 25.477275) (xy 466.196886 25.525705) (xy 466.092987 25.566485) (xy 465.986331 25.599387)
			(xy 465.877514 25.624226) (xy 465.767145 25.640863) (xy 465.655842 25.649207) (xy 465.600034 25.649682)
			(xy 160.11398 25.649682) (xy 160.058174 25.64916) (xy 159.946873 25.640817) (xy 159.836507 25.624181)
			(xy 159.727693 25.599343) (xy 159.62104 25.566443) (xy 159.517143 25.525665) (xy 159.416584 25.477237)
			(xy 159.319925 25.42143) (xy 159.227707 25.358555) (xy 159.140445 25.288965) (xy 159.058628 25.213048)
			(xy 158.982713 25.131229) (xy 158.913125 25.043966) (xy 158.850252 24.951746) (xy 158.794447 24.855086)
			(xy 158.746021 24.754526) (xy 158.705245 24.650628) (xy 158.672348 24.543974) (xy 158.647513 24.435159)
			(xy 158.630879 24.324793) (xy 158.622539 24.213492) (xy 158.621984 24.157686) (xy 158.621984 21.802649)
			(xy 269.304757 21.802649) (xy 269.304757 21.888399) (xy 269.312669 21.973782) (xy 269.328425 22.058072)
			(xy 269.351892 22.140548) (xy 269.382868 22.220507) (xy 269.42109 22.297267) (xy 269.466231 22.370173)
			(xy 269.517907 22.438602) (xy 269.575676 22.501972) (xy 269.639046 22.559741) (xy 269.707475 22.611417)
			(xy 269.780381 22.656558) (xy 269.857141 22.69478) (xy 269.9371 22.725756) (xy 270.019576 22.749223)
			(xy 270.103866 22.764979) (xy 270.189249 22.772891) (xy 270.274999 22.772891) (xy 270.360382 22.764979)
			(xy 270.444672 22.749223) (xy 270.527148 22.725756) (xy 270.607107 22.69478) (xy 270.683867 22.656558)
			(xy 270.756773 22.611417) (xy 270.825202 22.559741) (xy 270.888572 22.501972) (xy 270.946341 22.438602)
			(xy 270.998017 22.370173) (xy 271.043158 22.297267) (xy 271.08138 22.220507) (xy 271.112356 22.140548)
			(xy 271.135823 22.058072) (xy 271.151579 21.973782) (xy 271.159491 21.888399) (xy 271.159986 21.845524)
			(xy 271.159491 21.802649) (xy 275.654757 21.802649) (xy 275.654757 21.888399) (xy 275.662669 21.973782)
			(xy 275.678425 22.058072) (xy 275.701892 22.140548) (xy 275.732868 22.220507) (xy 275.77109 22.297267)
			(xy 275.816231 22.370173) (xy 275.867907 22.438602) (xy 275.925676 22.501972) (xy 275.989046 22.559741)
			(xy 276.057475 22.611417) (xy 276.130381 22.656558) (xy 276.207141 22.69478) (xy 276.2871 22.725756)
			(xy 276.369576 22.749223) (xy 276.453866 22.764979) (xy 276.539249 22.772891) (xy 276.624999 22.772891)
			(xy 276.710382 22.764979) (xy 276.794672 22.749223) (xy 276.877148 22.725756) (xy 276.957107 22.69478)
			(xy 277.033867 22.656558) (xy 277.106773 22.611417) (xy 277.175202 22.559741) (xy 277.238572 22.501972)
			(xy 277.296341 22.438602) (xy 277.348017 22.370173) (xy 277.393158 22.297267) (xy 277.43138 22.220507)
			(xy 277.462356 22.140548) (xy 277.485823 22.058072) (xy 277.501579 21.973782) (xy 277.509491 21.888399)
			(xy 277.509986 21.845524) (xy 277.509491 21.802649) (xy 277.508832 21.795537) (xy 308.364877 21.795537)
			(xy 308.364877 21.881287) (xy 308.372789 21.96667) (xy 308.388545 22.05096) (xy 308.412012 22.133436)
			(xy 308.442988 22.213395) (xy 308.48121 22.290155) (xy 308.526351 22.363061) (xy 308.578027 22.43149)
			(xy 308.635796 22.49486) (xy 308.699166 22.552629) (xy 308.767595 22.604305) (xy 308.840501 22.649446)
			(xy 308.917261 22.687668) (xy 308.99722 22.718644) (xy 309.079696 22.742111) (xy 309.163986 22.757867)
			(xy 309.249369 22.765779) (xy 309.335119 22.765779) (xy 309.420502 22.757867) (xy 309.504792 22.742111)
			(xy 309.587268 22.718644) (xy 309.667227 22.687668) (xy 309.743987 22.649446) (xy 309.816893 22.604305)
			(xy 309.885322 22.552629) (xy 309.948692 22.49486) (xy 310.006461 22.43149) (xy 310.058137 22.363061)
			(xy 310.103278 22.290155) (xy 310.1415 22.213395) (xy 310.172476 22.133436) (xy 310.195943 22.05096)
			(xy 310.211699 21.96667) (xy 310.219611 21.881287) (xy 310.220106 21.838412) (xy 310.219611 21.795537)
			(xy 314.714877 21.795537) (xy 314.714877 21.881287) (xy 314.722789 21.96667) (xy 314.738545 22.05096)
			(xy 314.762012 22.133436) (xy 314.792988 22.213395) (xy 314.83121 22.290155) (xy 314.876351 22.363061)
			(xy 314.928027 22.43149) (xy 314.985796 22.49486) (xy 315.049166 22.552629) (xy 315.117595 22.604305)
			(xy 315.190501 22.649446) (xy 315.267261 22.687668) (xy 315.34722 22.718644) (xy 315.429696 22.742111)
			(xy 315.513986 22.757867) (xy 315.599369 22.765779) (xy 315.685119 22.765779) (xy 315.770502 22.757867)
			(xy 315.854792 22.742111) (xy 315.937268 22.718644) (xy 316.017227 22.687668) (xy 316.093987 22.649446)
			(xy 316.166893 22.604305) (xy 316.235322 22.552629) (xy 316.298692 22.49486) (xy 316.356461 22.43149)
			(xy 316.408137 22.363061) (xy 316.453278 22.290155) (xy 316.4915 22.213395) (xy 316.522476 22.133436)
			(xy 316.545943 22.05096) (xy 316.561699 21.96667) (xy 316.569611 21.881287) (xy 316.570106 21.838412)
			(xy 316.569693 21.802649) (xy 334.455757 21.802649) (xy 334.455757 21.888399) (xy 334.463669 21.973782)
			(xy 334.479425 22.058072) (xy 334.502892 22.140548) (xy 334.533868 22.220507) (xy 334.57209 22.297267)
			(xy 334.617231 22.370173) (xy 334.668907 22.438602) (xy 334.726676 22.501972) (xy 334.790046 22.559741)
			(xy 334.858475 22.611417) (xy 334.931381 22.656558) (xy 335.008141 22.69478) (xy 335.0881 22.725756)
			(xy 335.170576 22.749223) (xy 335.254866 22.764979) (xy 335.340249 22.772891) (xy 335.425999 22.772891)
			(xy 335.511382 22.764979) (xy 335.595672 22.749223) (xy 335.678148 22.725756) (xy 335.758107 22.69478)
			(xy 335.834867 22.656558) (xy 335.907773 22.611417) (xy 335.976202 22.559741) (xy 336.039572 22.501972)
			(xy 336.097341 22.438602) (xy 336.149017 22.370173) (xy 336.194158 22.297267) (xy 336.23238 22.220507)
			(xy 336.263356 22.140548) (xy 336.286823 22.058072) (xy 336.302579 21.973782) (xy 336.310491 21.888399)
			(xy 336.310986 21.845524) (xy 336.310491 21.802649) (xy 340.805757 21.802649) (xy 340.805757 21.888399)
			(xy 340.813669 21.973782) (xy 340.829425 22.058072) (xy 340.852892 22.140548) (xy 340.883868 22.220507)
			(xy 340.92209 22.297267) (xy 340.967231 22.370173) (xy 341.018907 22.438602) (xy 341.076676 22.501972)
			(xy 341.140046 22.559741) (xy 341.208475 22.611417) (xy 341.281381 22.656558) (xy 341.358141 22.69478)
			(xy 341.4381 22.725756) (xy 341.520576 22.749223) (xy 341.604866 22.764979) (xy 341.690249 22.772891)
			(xy 341.775999 22.772891) (xy 341.861382 22.764979) (xy 341.945672 22.749223) (xy 342.028148 22.725756)
			(xy 342.108107 22.69478) (xy 342.184867 22.656558) (xy 342.257773 22.611417) (xy 342.326202 22.559741)
			(xy 342.389572 22.501972) (xy 342.447341 22.438602) (xy 342.499017 22.370173) (xy 342.544158 22.297267)
			(xy 342.58238 22.220507) (xy 342.613356 22.140548) (xy 342.636823 22.058072) (xy 342.652579 21.973782)
			(xy 342.660491 21.888399) (xy 342.660986 21.845524) (xy 342.660491 21.802649) (xy 342.659832 21.795537)
			(xy 373.515877 21.795537) (xy 373.515877 21.881287) (xy 373.523789 21.96667) (xy 373.539545 22.05096)
			(xy 373.563012 22.133436) (xy 373.593988 22.213395) (xy 373.63221 22.290155) (xy 373.677351 22.363061)
			(xy 373.729027 22.43149) (xy 373.786796 22.49486) (xy 373.850166 22.552629) (xy 373.918595 22.604305)
			(xy 373.991501 22.649446) (xy 374.068261 22.687668) (xy 374.14822 22.718644) (xy 374.230696 22.742111)
			(xy 374.314986 22.757867) (xy 374.400369 22.765779) (xy 374.486119 22.765779) (xy 374.571502 22.757867)
			(xy 374.655792 22.742111) (xy 374.738268 22.718644) (xy 374.818227 22.687668) (xy 374.894987 22.649446)
			(xy 374.967893 22.604305) (xy 375.036322 22.552629) (xy 375.099692 22.49486) (xy 375.157461 22.43149)
			(xy 375.209137 22.363061) (xy 375.254278 22.290155) (xy 375.2925 22.213395) (xy 375.323476 22.133436)
			(xy 375.346943 22.05096) (xy 375.362699 21.96667) (xy 375.370611 21.881287) (xy 375.371106 21.838412)
			(xy 375.370611 21.795537) (xy 379.865877 21.795537) (xy 379.865877 21.881287) (xy 379.873789 21.96667)
			(xy 379.889545 22.05096) (xy 379.913012 22.133436) (xy 379.943988 22.213395) (xy 379.98221 22.290155)
			(xy 380.027351 22.363061) (xy 380.079027 22.43149) (xy 380.136796 22.49486) (xy 380.200166 22.552629)
			(xy 380.268595 22.604305) (xy 380.341501 22.649446) (xy 380.418261 22.687668) (xy 380.49822 22.718644)
			(xy 380.580696 22.742111) (xy 380.664986 22.757867) (xy 380.750369 22.765779) (xy 380.836119 22.765779)
			(xy 380.921502 22.757867) (xy 381.005792 22.742111) (xy 381.088268 22.718644) (xy 381.168227 22.687668)
			(xy 381.244987 22.649446) (xy 381.317893 22.604305) (xy 381.386322 22.552629) (xy 381.449692 22.49486)
			(xy 381.507461 22.43149) (xy 381.559137 22.363061) (xy 381.604278 22.290155) (xy 381.6425 22.213395)
			(xy 381.673476 22.133436) (xy 381.696943 22.05096) (xy 381.712699 21.96667) (xy 381.720611 21.881287)
			(xy 381.721106 21.838412) (xy 381.720693 21.802649) (xy 399.098757 21.802649) (xy 399.098757 21.888399)
			(xy 399.106669 21.973782) (xy 399.122425 22.058072) (xy 399.145892 22.140548) (xy 399.176868 22.220507)
			(xy 399.21509 22.297267) (xy 399.260231 22.370173) (xy 399.311907 22.438602) (xy 399.369676 22.501972)
			(xy 399.433046 22.559741) (xy 399.501475 22.611417) (xy 399.574381 22.656558) (xy 399.651141 22.69478)
			(xy 399.7311 22.725756) (xy 399.813576 22.749223) (xy 399.897866 22.764979) (xy 399.983249 22.772891)
			(xy 400.068999 22.772891) (xy 400.154382 22.764979) (xy 400.238672 22.749223) (xy 400.321148 22.725756)
			(xy 400.401107 22.69478) (xy 400.477867 22.656558) (xy 400.550773 22.611417) (xy 400.619202 22.559741)
			(xy 400.682572 22.501972) (xy 400.740341 22.438602) (xy 400.792017 22.370173) (xy 400.837158 22.297267)
			(xy 400.87538 22.220507) (xy 400.906356 22.140548) (xy 400.929823 22.058072) (xy 400.945579 21.973782)
			(xy 400.953491 21.888399) (xy 400.953986 21.845524) (xy 400.953491 21.802649) (xy 405.448757 21.802649)
			(xy 405.448757 21.888399) (xy 405.456669 21.973782) (xy 405.472425 22.058072) (xy 405.495892 22.140548)
			(xy 405.526868 22.220507) (xy 405.56509 22.297267) (xy 405.610231 22.370173) (xy 405.661907 22.438602)
			(xy 405.719676 22.501972) (xy 405.783046 22.559741) (xy 405.851475 22.611417) (xy 405.924381 22.656558)
			(xy 406.001141 22.69478) (xy 406.0811 22.725756) (xy 406.163576 22.749223) (xy 406.247866 22.764979)
			(xy 406.333249 22.772891) (xy 406.418999 22.772891) (xy 406.504382 22.764979) (xy 406.588672 22.749223)
			(xy 406.671148 22.725756) (xy 406.751107 22.69478) (xy 406.827867 22.656558) (xy 406.900773 22.611417)
			(xy 406.969202 22.559741) (xy 407.032572 22.501972) (xy 407.090341 22.438602) (xy 407.142017 22.370173)
			(xy 407.187158 22.297267) (xy 407.22538 22.220507) (xy 407.256356 22.140548) (xy 407.279823 22.058072)
			(xy 407.295579 21.973782) (xy 407.303491 21.888399) (xy 407.303986 21.845524) (xy 407.303491 21.802649)
			(xy 407.302832 21.795537) (xy 438.158877 21.795537) (xy 438.158877 21.881287) (xy 438.166789 21.96667)
			(xy 438.182545 22.05096) (xy 438.206012 22.133436) (xy 438.236988 22.213395) (xy 438.27521 22.290155)
			(xy 438.320351 22.363061) (xy 438.372027 22.43149) (xy 438.429796 22.49486) (xy 438.493166 22.552629)
			(xy 438.561595 22.604305) (xy 438.634501 22.649446) (xy 438.711261 22.687668) (xy 438.79122 22.718644)
			(xy 438.873696 22.742111) (xy 438.957986 22.757867) (xy 439.043369 22.765779) (xy 439.129119 22.765779)
			(xy 439.214502 22.757867) (xy 439.298792 22.742111) (xy 439.381268 22.718644) (xy 439.461227 22.687668)
			(xy 439.537987 22.649446) (xy 439.610893 22.604305) (xy 439.679322 22.552629) (xy 439.742692 22.49486)
			(xy 439.800461 22.43149) (xy 439.852137 22.363061) (xy 439.897278 22.290155) (xy 439.9355 22.213395)
			(xy 439.966476 22.133436) (xy 439.989943 22.05096) (xy 440.005699 21.96667) (xy 440.013611 21.881287)
			(xy 440.014106 21.838412) (xy 440.013611 21.795537) (xy 444.508877 21.795537) (xy 444.508877 21.881287)
			(xy 444.516789 21.96667) (xy 444.532545 22.05096) (xy 444.556012 22.133436) (xy 444.586988 22.213395)
			(xy 444.62521 22.290155) (xy 444.670351 22.363061) (xy 444.722027 22.43149) (xy 444.779796 22.49486)
			(xy 444.843166 22.552629) (xy 444.911595 22.604305) (xy 444.984501 22.649446) (xy 445.061261 22.687668)
			(xy 445.14122 22.718644) (xy 445.223696 22.742111) (xy 445.307986 22.757867) (xy 445.393369 22.765779)
			(xy 445.479119 22.765779) (xy 445.564502 22.757867) (xy 445.648792 22.742111) (xy 445.731268 22.718644)
			(xy 445.811227 22.687668) (xy 445.887987 22.649446) (xy 445.960893 22.604305) (xy 446.029322 22.552629)
			(xy 446.092692 22.49486) (xy 446.150461 22.43149) (xy 446.202137 22.363061) (xy 446.247278 22.290155)
			(xy 446.2855 22.213395) (xy 446.316476 22.133436) (xy 446.339943 22.05096) (xy 446.355699 21.96667)
			(xy 446.363611 21.881287) (xy 446.364106 21.838412) (xy 446.363611 21.795537) (xy 446.355699 21.710154)
			(xy 446.339943 21.625864) (xy 446.316476 21.543388) (xy 446.2855 21.463429) (xy 446.247278 21.386669)
			(xy 446.202137 21.313763) (xy 446.150461 21.245334) (xy 446.092692 21.181964) (xy 446.029322 21.124195)
			(xy 445.988175 21.093122) (xy 460.504275 21.093122) (xy 460.504275 21.222262) (xy 460.512225 21.351157)
			(xy 460.528095 21.479317) (xy 460.551824 21.606258) (xy 460.583323 21.731497) (xy 460.622472 21.85456)
			(xy 460.669123 21.974979) (xy 460.723098 22.092298) (xy 460.784193 22.206072) (xy 460.852176 22.315869)
			(xy 460.92679 22.421272) (xy 461.007751 22.521882) (xy 461.094751 22.617317) (xy 461.187462 22.707216)
			(xy 461.285532 22.791237) (xy 461.388587 22.869061) (xy 461.496238 22.940393) (xy 461.608077 23.004963)
			(xy 461.723678 23.062525) (xy 461.842603 23.112862) (xy 461.964402 23.155782) (xy 462.088612 23.191123)
			(xy 462.214761 23.21875) (xy 462.342373 23.238559) (xy 462.470962 23.250475) (xy 462.60004 23.254452)
			(xy 462.729118 23.250475) (xy 462.857707 23.238559) (xy 462.985319 23.21875) (xy 463.111468 23.191123)
			(xy 463.235678 23.155782) (xy 463.357477 23.112862) (xy 463.476402 23.062525) (xy 463.592003 23.004963)
			(xy 463.703842 22.940393) (xy 463.811493 22.869061) (xy 463.914548 22.791237) (xy 464.012618 22.707216)
			(xy 464.105329 22.617317) (xy 464.192329 22.521882) (xy 464.27329 22.421272) (xy 464.347904 22.315869)
			(xy 464.415887 22.206072) (xy 464.476982 22.092298) (xy 464.530957 21.974979) (xy 464.577608 21.85456)
			(xy 464.616757 21.731497) (xy 464.648256 21.606258) (xy 464.671985 21.479317) (xy 464.687855 21.351157)
			(xy 464.695805 21.222262) (xy 464.696302 21.157692) (xy 464.695805 21.093122) (xy 464.687855 20.964227)
			(xy 464.671985 20.836067) (xy 464.648256 20.709126) (xy 464.616757 20.583887) (xy 464.577608 20.460824)
			(xy 464.530957 20.340405) (xy 464.476982 20.223086) (xy 464.415887 20.109312) (xy 464.347904 19.999515)
			(xy 464.27329 19.894112) (xy 464.192329 19.793502) (xy 464.105329 19.698067) (xy 464.012618 19.608168)
			(xy 463.914548 19.524147) (xy 463.811493 19.446323) (xy 463.703842 19.374991) (xy 463.592003 19.310421)
			(xy 463.476402 19.252859) (xy 463.357477 19.202522) (xy 463.235678 19.159602) (xy 463.111468 19.124261)
			(xy 462.985319 19.096634) (xy 462.857707 19.076825) (xy 462.729118 19.064909) (xy 462.60004 19.060933)
			(xy 462.470962 19.064909) (xy 462.342373 19.076825) (xy 462.214761 19.096634) (xy 462.088612 19.124261)
			(xy 461.964402 19.159602) (xy 461.842603 19.202522) (xy 461.723678 19.252859) (xy 461.608077 19.310421)
			(xy 461.496238 19.374991) (xy 461.388587 19.446323) (xy 461.285532 19.524147) (xy 461.187462 19.608168)
			(xy 461.094751 19.698067) (xy 461.007751 19.793502) (xy 460.92679 19.894112) (xy 460.852176 19.999515)
			(xy 460.784193 20.109312) (xy 460.723098 20.223086) (xy 460.669123 20.340405) (xy 460.622472 20.460824)
			(xy 460.583323 20.583887) (xy 460.551824 20.709126) (xy 460.528095 20.836067) (xy 460.512225 20.964227)
			(xy 460.504275 21.093122) (xy 445.988175 21.093122) (xy 445.960893 21.072519) (xy 445.887987 21.027378)
			(xy 445.811227 20.989156) (xy 445.731268 20.95818) (xy 445.648792 20.934713) (xy 445.564502 20.918957)
			(xy 445.479119 20.911045) (xy 445.393369 20.911045) (xy 445.307986 20.918957) (xy 445.223696 20.934713)
			(xy 445.14122 20.95818) (xy 445.061261 20.989156) (xy 444.984501 21.027378) (xy 444.911595 21.072519)
			(xy 444.843166 21.124195) (xy 444.779796 21.181964) (xy 444.722027 21.245334) (xy 444.670351 21.313763)
			(xy 444.62521 21.386669) (xy 444.586988 21.463429) (xy 444.556012 21.543388) (xy 444.532545 21.625864)
			(xy 444.516789 21.710154) (xy 444.508877 21.795537) (xy 440.013611 21.795537) (xy 440.005699 21.710154)
			(xy 439.989943 21.625864) (xy 439.966476 21.543388) (xy 439.9355 21.463429) (xy 439.897278 21.386669)
			(xy 439.852137 21.313763) (xy 439.800461 21.245334) (xy 439.742692 21.181964) (xy 439.679322 21.124195)
			(xy 439.610893 21.072519) (xy 439.537987 21.027378) (xy 439.461227 20.989156) (xy 439.381268 20.95818)
			(xy 439.298792 20.934713) (xy 439.214502 20.918957) (xy 439.129119 20.911045) (xy 439.043369 20.911045)
			(xy 438.957986 20.918957) (xy 438.873696 20.934713) (xy 438.79122 20.95818) (xy 438.711261 20.989156)
			(xy 438.634501 21.027378) (xy 438.561595 21.072519) (xy 438.493166 21.124195) (xy 438.429796 21.181964)
			(xy 438.372027 21.245334) (xy 438.320351 21.313763) (xy 438.27521 21.386669) (xy 438.236988 21.463429)
			(xy 438.206012 21.543388) (xy 438.182545 21.625864) (xy 438.166789 21.710154) (xy 438.158877 21.795537)
			(xy 407.302832 21.795537) (xy 407.295579 21.717266) (xy 407.279823 21.632976) (xy 407.256356 21.5505)
			(xy 407.22538 21.470541) (xy 407.187158 21.393781) (xy 407.142017 21.320875) (xy 407.090341 21.252446)
			(xy 407.032572 21.189076) (xy 406.969202 21.131307) (xy 406.900773 21.079631) (xy 406.827867 21.03449)
			(xy 406.751107 20.996268) (xy 406.671148 20.965292) (xy 406.588672 20.941825) (xy 406.504382 20.926069)
			(xy 406.418999 20.918157) (xy 406.333249 20.918157) (xy 406.247866 20.926069) (xy 406.163576 20.941825)
			(xy 406.0811 20.965292) (xy 406.001141 20.996268) (xy 405.924381 21.03449) (xy 405.851475 21.079631)
			(xy 405.783046 21.131307) (xy 405.719676 21.189076) (xy 405.661907 21.252446) (xy 405.610231 21.320875)
			(xy 405.56509 21.393781) (xy 405.526868 21.470541) (xy 405.495892 21.5505) (xy 405.472425 21.632976)
			(xy 405.456669 21.717266) (xy 405.448757 21.802649) (xy 400.953491 21.802649) (xy 400.945579 21.717266)
			(xy 400.929823 21.632976) (xy 400.906356 21.5505) (xy 400.87538 21.470541) (xy 400.837158 21.393781)
			(xy 400.792017 21.320875) (xy 400.740341 21.252446) (xy 400.682572 21.189076) (xy 400.619202 21.131307)
			(xy 400.550773 21.079631) (xy 400.477867 21.03449) (xy 400.401107 20.996268) (xy 400.321148 20.965292)
			(xy 400.238672 20.941825) (xy 400.154382 20.926069) (xy 400.068999 20.918157) (xy 399.983249 20.918157)
			(xy 399.897866 20.926069) (xy 399.813576 20.941825) (xy 399.7311 20.965292) (xy 399.651141 20.996268)
			(xy 399.574381 21.03449) (xy 399.501475 21.079631) (xy 399.433046 21.131307) (xy 399.369676 21.189076)
			(xy 399.311907 21.252446) (xy 399.260231 21.320875) (xy 399.21509 21.393781) (xy 399.176868 21.470541)
			(xy 399.145892 21.5505) (xy 399.122425 21.632976) (xy 399.106669 21.717266) (xy 399.098757 21.802649)
			(xy 381.720693 21.802649) (xy 381.720611 21.795537) (xy 381.712699 21.710154) (xy 381.696943 21.625864)
			(xy 381.673476 21.543388) (xy 381.6425 21.463429) (xy 381.604278 21.386669) (xy 381.559137 21.313763)
			(xy 381.507461 21.245334) (xy 381.449692 21.181964) (xy 381.386322 21.124195) (xy 381.317893 21.072519)
			(xy 381.244987 21.027378) (xy 381.168227 20.989156) (xy 381.088268 20.95818) (xy 381.005792 20.934713)
			(xy 380.921502 20.918957) (xy 380.836119 20.911045) (xy 380.750369 20.911045) (xy 380.664986 20.918957)
			(xy 380.580696 20.934713) (xy 380.49822 20.95818) (xy 380.418261 20.989156) (xy 380.341501 21.027378)
			(xy 380.268595 21.072519) (xy 380.200166 21.124195) (xy 380.136796 21.181964) (xy 380.079027 21.245334)
			(xy 380.027351 21.313763) (xy 379.98221 21.386669) (xy 379.943988 21.463429) (xy 379.913012 21.543388)
			(xy 379.889545 21.625864) (xy 379.873789 21.710154) (xy 379.865877 21.795537) (xy 375.370611 21.795537)
			(xy 375.362699 21.710154) (xy 375.346943 21.625864) (xy 375.323476 21.543388) (xy 375.2925 21.463429)
			(xy 375.254278 21.386669) (xy 375.209137 21.313763) (xy 375.157461 21.245334) (xy 375.099692 21.181964)
			(xy 375.036322 21.124195) (xy 374.967893 21.072519) (xy 374.894987 21.027378) (xy 374.818227 20.989156)
			(xy 374.738268 20.95818) (xy 374.655792 20.934713) (xy 374.571502 20.918957) (xy 374.486119 20.911045)
			(xy 374.400369 20.911045) (xy 374.314986 20.918957) (xy 374.230696 20.934713) (xy 374.14822 20.95818)
			(xy 374.068261 20.989156) (xy 373.991501 21.027378) (xy 373.918595 21.072519) (xy 373.850166 21.124195)
			(xy 373.786796 21.181964) (xy 373.729027 21.245334) (xy 373.677351 21.313763) (xy 373.63221 21.386669)
			(xy 373.593988 21.463429) (xy 373.563012 21.543388) (xy 373.539545 21.625864) (xy 373.523789 21.710154)
			(xy 373.515877 21.795537) (xy 342.659832 21.795537) (xy 342.652579 21.717266) (xy 342.636823 21.632976)
			(xy 342.613356 21.5505) (xy 342.58238 21.470541) (xy 342.544158 21.393781) (xy 342.499017 21.320875)
			(xy 342.447341 21.252446) (xy 342.389572 21.189076) (xy 342.326202 21.131307) (xy 342.257773 21.079631)
			(xy 342.184867 21.03449) (xy 342.108107 20.996268) (xy 342.028148 20.965292) (xy 341.945672 20.941825)
			(xy 341.861382 20.926069) (xy 341.775999 20.918157) (xy 341.690249 20.918157) (xy 341.604866 20.926069)
			(xy 341.520576 20.941825) (xy 341.4381 20.965292) (xy 341.358141 20.996268) (xy 341.281381 21.03449)
			(xy 341.208475 21.079631) (xy 341.140046 21.131307) (xy 341.076676 21.189076) (xy 341.018907 21.252446)
			(xy 340.967231 21.320875) (xy 340.92209 21.393781) (xy 340.883868 21.470541) (xy 340.852892 21.5505)
			(xy 340.829425 21.632976) (xy 340.813669 21.717266) (xy 340.805757 21.802649) (xy 336.310491 21.802649)
			(xy 336.302579 21.717266) (xy 336.286823 21.632976) (xy 336.263356 21.5505) (xy 336.23238 21.470541)
			(xy 336.194158 21.393781) (xy 336.149017 21.320875) (xy 336.097341 21.252446) (xy 336.039572 21.189076)
			(xy 335.976202 21.131307) (xy 335.907773 21.079631) (xy 335.834867 21.03449) (xy 335.758107 20.996268)
			(xy 335.678148 20.965292) (xy 335.595672 20.941825) (xy 335.511382 20.926069) (xy 335.425999 20.918157)
			(xy 335.340249 20.918157) (xy 335.254866 20.926069) (xy 335.170576 20.941825) (xy 335.0881 20.965292)
			(xy 335.008141 20.996268) (xy 334.931381 21.03449) (xy 334.858475 21.079631) (xy 334.790046 21.131307)
			(xy 334.726676 21.189076) (xy 334.668907 21.252446) (xy 334.617231 21.320875) (xy 334.57209 21.393781)
			(xy 334.533868 21.470541) (xy 334.502892 21.5505) (xy 334.479425 21.632976) (xy 334.463669 21.717266)
			(xy 334.455757 21.802649) (xy 316.569693 21.802649) (xy 316.569611 21.795537) (xy 316.561699 21.710154)
			(xy 316.545943 21.625864) (xy 316.522476 21.543388) (xy 316.4915 21.463429) (xy 316.453278 21.386669)
			(xy 316.408137 21.313763) (xy 316.356461 21.245334) (xy 316.298692 21.181964) (xy 316.235322 21.124195)
			(xy 316.166893 21.072519) (xy 316.093987 21.027378) (xy 316.017227 20.989156) (xy 315.937268 20.95818)
			(xy 315.854792 20.934713) (xy 315.770502 20.918957) (xy 315.685119 20.911045) (xy 315.599369 20.911045)
			(xy 315.513986 20.918957) (xy 315.429696 20.934713) (xy 315.34722 20.95818) (xy 315.267261 20.989156)
			(xy 315.190501 21.027378) (xy 315.117595 21.072519) (xy 315.049166 21.124195) (xy 314.985796 21.181964)
			(xy 314.928027 21.245334) (xy 314.876351 21.313763) (xy 314.83121 21.386669) (xy 314.792988 21.463429)
			(xy 314.762012 21.543388) (xy 314.738545 21.625864) (xy 314.722789 21.710154) (xy 314.714877 21.795537)
			(xy 310.219611 21.795537) (xy 310.211699 21.710154) (xy 310.195943 21.625864) (xy 310.172476 21.543388)
			(xy 310.1415 21.463429) (xy 310.103278 21.386669) (xy 310.058137 21.313763) (xy 310.006461 21.245334)
			(xy 309.948692 21.181964) (xy 309.885322 21.124195) (xy 309.816893 21.072519) (xy 309.743987 21.027378)
			(xy 309.667227 20.989156) (xy 309.587268 20.95818) (xy 309.504792 20.934713) (xy 309.420502 20.918957)
			(xy 309.335119 20.911045) (xy 309.249369 20.911045) (xy 309.163986 20.918957) (xy 309.079696 20.934713)
			(xy 308.99722 20.95818) (xy 308.917261 20.989156) (xy 308.840501 21.027378) (xy 308.767595 21.072519)
			(xy 308.699166 21.124195) (xy 308.635796 21.181964) (xy 308.578027 21.245334) (xy 308.526351 21.313763)
			(xy 308.48121 21.386669) (xy 308.442988 21.463429) (xy 308.412012 21.543388) (xy 308.388545 21.625864)
			(xy 308.372789 21.710154) (xy 308.364877 21.795537) (xy 277.508832 21.795537) (xy 277.501579 21.717266)
			(xy 277.485823 21.632976) (xy 277.462356 21.5505) (xy 277.43138 21.470541) (xy 277.393158 21.393781)
			(xy 277.348017 21.320875) (xy 277.296341 21.252446) (xy 277.238572 21.189076) (xy 277.175202 21.131307)
			(xy 277.106773 21.079631) (xy 277.033867 21.03449) (xy 276.957107 20.996268) (xy 276.877148 20.965292)
			(xy 276.794672 20.941825) (xy 276.710382 20.926069) (xy 276.624999 20.918157) (xy 276.539249 20.918157)
			(xy 276.453866 20.926069) (xy 276.369576 20.941825) (xy 276.2871 20.965292) (xy 276.207141 20.996268)
			(xy 276.130381 21.03449) (xy 276.057475 21.079631) (xy 275.989046 21.131307) (xy 275.925676 21.189076)
			(xy 275.867907 21.252446) (xy 275.816231 21.320875) (xy 275.77109 21.393781) (xy 275.732868 21.470541)
			(xy 275.701892 21.5505) (xy 275.678425 21.632976) (xy 275.662669 21.717266) (xy 275.654757 21.802649)
			(xy 271.159491 21.802649) (xy 271.151579 21.717266) (xy 271.135823 21.632976) (xy 271.112356 21.5505)
			(xy 271.08138 21.470541) (xy 271.043158 21.393781) (xy 270.998017 21.320875) (xy 270.946341 21.252446)
			(xy 270.888572 21.189076) (xy 270.825202 21.131307) (xy 270.756773 21.079631) (xy 270.683867 21.03449)
			(xy 270.607107 20.996268) (xy 270.527148 20.965292) (xy 270.444672 20.941825) (xy 270.360382 20.926069)
			(xy 270.274999 20.918157) (xy 270.189249 20.918157) (xy 270.103866 20.926069) (xy 270.019576 20.941825)
			(xy 269.9371 20.965292) (xy 269.857141 20.996268) (xy 269.780381 21.03449) (xy 269.707475 21.079631)
			(xy 269.639046 21.131307) (xy 269.575676 21.189076) (xy 269.517907 21.252446) (xy 269.466231 21.320875)
			(xy 269.42109 21.393781) (xy 269.382868 21.470541) (xy 269.351892 21.5505) (xy 269.328425 21.632976)
			(xy 269.312669 21.717266) (xy 269.304757 21.802649) (xy 158.621984 21.802649) (xy 158.621984 19.262649)
			(xy 209.995757 19.262649) (xy 209.995757 19.348399) (xy 210.003669 19.433782) (xy 210.019425 19.518072)
			(xy 210.042892 19.600548) (xy 210.073868 19.680507) (xy 210.11209 19.757267) (xy 210.157231 19.830173)
			(xy 210.208907 19.898602) (xy 210.266676 19.961972) (xy 210.330046 20.019741) (xy 210.398475 20.071417)
			(xy 210.471381 20.116558) (xy 210.548141 20.15478) (xy 210.6281 20.185756) (xy 210.710576 20.209223)
			(xy 210.794866 20.224979) (xy 210.880249 20.232891) (xy 210.965999 20.232891) (xy 211.051382 20.224979)
			(xy 211.135672 20.209223) (xy 211.218148 20.185756) (xy 211.298107 20.15478) (xy 211.374867 20.116558)
			(xy 211.447773 20.071417) (xy 211.516202 20.019741) (xy 211.579572 19.961972) (xy 211.637341 19.898602)
			(xy 211.689017 19.830173) (xy 211.734158 19.757267) (xy 211.77238 19.680507) (xy 211.803356 19.600548)
			(xy 211.826823 19.518072) (xy 211.842579 19.433782) (xy 211.850491 19.348399) (xy 211.850986 19.305524)
			(xy 211.850491 19.262649) (xy 216.345757 19.262649) (xy 216.345757 19.348399) (xy 216.353669 19.433782)
			(xy 216.369425 19.518072) (xy 216.392892 19.600548) (xy 216.423868 19.680507) (xy 216.46209 19.757267)
			(xy 216.507231 19.830173) (xy 216.558907 19.898602) (xy 216.616676 19.961972) (xy 216.680046 20.019741)
			(xy 216.748475 20.071417) (xy 216.821381 20.116558) (xy 216.898141 20.15478) (xy 216.9781 20.185756)
			(xy 217.060576 20.209223) (xy 217.144866 20.224979) (xy 217.230249 20.232891) (xy 217.315999 20.232891)
			(xy 217.401382 20.224979) (xy 217.485672 20.209223) (xy 217.568148 20.185756) (xy 217.648107 20.15478)
			(xy 217.724867 20.116558) (xy 217.797773 20.071417) (xy 217.866202 20.019741) (xy 217.929572 19.961972)
			(xy 217.987341 19.898602) (xy 218.039017 19.830173) (xy 218.084158 19.757267) (xy 218.12238 19.680507)
			(xy 218.153356 19.600548) (xy 218.176823 19.518072) (xy 218.192579 19.433782) (xy 218.200491 19.348399)
			(xy 218.200986 19.305524) (xy 218.200491 19.262649) (xy 218.199832 19.255537) (xy 244.026677 19.255537)
			(xy 244.026677 19.341287) (xy 244.034589 19.42667) (xy 244.050345 19.51096) (xy 244.073812 19.593436)
			(xy 244.104788 19.673395) (xy 244.14301 19.750155) (xy 244.188151 19.823061) (xy 244.239827 19.89149)
			(xy 244.297596 19.95486) (xy 244.360966 20.012629) (xy 244.429395 20.064305) (xy 244.502301 20.109446)
			(xy 244.579061 20.147668) (xy 244.65902 20.178644) (xy 244.741496 20.202111) (xy 244.825786 20.217867)
			(xy 244.911169 20.225779) (xy 244.996919 20.225779) (xy 245.082302 20.217867) (xy 245.166592 20.202111)
			(xy 245.249068 20.178644) (xy 245.329027 20.147668) (xy 245.405787 20.109446) (xy 245.478693 20.064305)
			(xy 245.547122 20.012629) (xy 245.610492 19.95486) (xy 245.668261 19.89149) (xy 245.719937 19.823061)
			(xy 245.765078 19.750155) (xy 245.8033 19.673395) (xy 245.834276 19.593436) (xy 245.857743 19.51096)
			(xy 245.873499 19.42667) (xy 245.881411 19.341287) (xy 245.881906 19.298412) (xy 245.881411 19.255537)
			(xy 250.376677 19.255537) (xy 250.376677 19.341287) (xy 250.384589 19.42667) (xy 250.400345 19.51096)
			(xy 250.423812 19.593436) (xy 250.454788 19.673395) (xy 250.49301 19.750155) (xy 250.538151 19.823061)
			(xy 250.589827 19.89149) (xy 250.647596 19.95486) (xy 250.710966 20.012629) (xy 250.779395 20.064305)
			(xy 250.852301 20.109446) (xy 250.929061 20.147668) (xy 251.00902 20.178644) (xy 251.091496 20.202111)
			(xy 251.175786 20.217867) (xy 251.261169 20.225779) (xy 251.346919 20.225779) (xy 251.432302 20.217867)
			(xy 251.516592 20.202111) (xy 251.599068 20.178644) (xy 251.679027 20.147668) (xy 251.755787 20.109446)
			(xy 251.828693 20.064305) (xy 251.897122 20.012629) (xy 251.960492 19.95486) (xy 252.018261 19.89149)
			(xy 252.069937 19.823061) (xy 252.115078 19.750155) (xy 252.1533 19.673395) (xy 252.184276 19.593436)
			(xy 252.207743 19.51096) (xy 252.223499 19.42667) (xy 252.231411 19.341287) (xy 252.231906 19.298412)
			(xy 252.231493 19.262649) (xy 269.304757 19.262649) (xy 269.304757 19.348399) (xy 269.312669 19.433782)
			(xy 269.328425 19.518072) (xy 269.351892 19.600548) (xy 269.382868 19.680507) (xy 269.42109 19.757267)
			(xy 269.466231 19.830173) (xy 269.517907 19.898602) (xy 269.575676 19.961972) (xy 269.639046 20.019741)
			(xy 269.707475 20.071417) (xy 269.780381 20.116558) (xy 269.857141 20.15478) (xy 269.9371 20.185756)
			(xy 270.019576 20.209223) (xy 270.103866 20.224979) (xy 270.189249 20.232891) (xy 270.274999 20.232891)
			(xy 270.360382 20.224979) (xy 270.444672 20.209223) (xy 270.527148 20.185756) (xy 270.607107 20.15478)
			(xy 270.683867 20.116558) (xy 270.756773 20.071417) (xy 270.815743 20.026884) (xy 273.463512 20.026884)
			(xy 273.463512 21.124164) (xy 273.463944 21.136247) (xy 273.471404 21.159232) (xy 273.485604 21.178784)
			(xy 273.505154 21.192989) (xy 273.528137 21.200454) (xy 273.54022 21.200872) (xy 274.15236 21.200872)
			(xy 274.160617 21.200709) (xy 274.17676 21.197239) (xy 274.184364 21.194014) (xy 274.192492 21.190204)
			(xy 274.210272 21.18868) (xy 274.290282 21.21027) (xy 274.30476 21.22043) (xy 274.30984 21.227542)
			(xy 274.325255 21.248552) (xy 274.360854 21.286606) (xy 274.401298 21.319463) (xy 274.445835 21.346514)
			(xy 274.493639 21.367255) (xy 274.543819 21.3813) (xy 274.595444 21.388389) (xy 274.621498 21.388832)
			(xy 274.648757 21.388375) (xy 274.702721 21.380619) (xy 274.755033 21.365265) (xy 274.804628 21.342626)
			(xy 274.850498 21.313161) (xy 274.89171 21.27747) (xy 274.927425 21.236279) (xy 274.956917 21.190427)
			(xy 274.979586 21.140845) (xy 274.994971 21.088542) (xy 275.002758 21.034583) (xy 275.00326 21.007324)
			(xy 275.00326 20.143724) (xy 275.002821 20.116458) (xy 274.99506 20.062481) (xy 274.979692 20.01016)
			(xy 274.95703 19.96056) (xy 274.927536 19.914692) (xy 274.891812 19.873491) (xy 274.850585 19.837797)
			(xy 274.804696 19.808337) (xy 274.755079 19.785711) (xy 274.702747 19.770381) (xy 274.648764 19.762659)
			(xy 274.621498 19.762216) (xy 274.595444 19.762672) (xy 274.54382 19.769759) (xy 274.49364 19.783803)
			(xy 274.445836 19.804541) (xy 274.401297 19.831588) (xy 274.360851 19.864443) (xy 274.325249 19.902493)
			(xy 274.30984 19.923506) (xy 274.30476 19.930618) (xy 274.290282 19.940778) (xy 274.210272 19.962368)
			(xy 274.192492 19.960844) (xy 274.184364 19.957034) (xy 274.176759 19.953818) (xy 274.160615 19.950365)
			(xy 274.15236 19.950176) (xy 273.54022 19.950176) (xy 273.52814 19.95063) (xy 273.505161 19.95809)
			(xy 273.485611 19.972286) (xy 273.471406 19.991828) (xy 273.463935 20.014804) (xy 273.463512 20.026884)
			(xy 270.815743 20.026884) (xy 270.825202 20.019741) (xy 270.888572 19.961972) (xy 270.946341 19.898602)
			(xy 270.998017 19.830173) (xy 271.043158 19.757267) (xy 271.08138 19.680507) (xy 271.112356 19.600548)
			(xy 271.135823 19.518072) (xy 271.151579 19.433782) (xy 271.159491 19.348399) (xy 271.159986 19.305524)
			(xy 271.159491 19.262649) (xy 275.654757 19.262649) (xy 275.654757 19.348399) (xy 275.662669 19.433782)
			(xy 275.678425 19.518072) (xy 275.701892 19.600548) (xy 275.732868 19.680507) (xy 275.77109 19.757267)
			(xy 275.816231 19.830173) (xy 275.867907 19.898602) (xy 275.925676 19.961972) (xy 275.989046 20.019741)
			(xy 276.057475 20.071417) (xy 276.130381 20.116558) (xy 276.207141 20.15478) (xy 276.2871 20.185756)
			(xy 276.369576 20.209223) (xy 276.453866 20.224979) (xy 276.539249 20.232891) (xy 276.624999 20.232891)
			(xy 276.710382 20.224979) (xy 276.794672 20.209223) (xy 276.877148 20.185756) (xy 276.957107 20.15478)
			(xy 277.033867 20.116558) (xy 277.106773 20.071417) (xy 277.175202 20.019741) (xy 277.238572 19.961972)
			(xy 277.296341 19.898602) (xy 277.348017 19.830173) (xy 277.393158 19.757267) (xy 277.43138 19.680507)
			(xy 277.462356 19.600548) (xy 277.485823 19.518072) (xy 277.501579 19.433782) (xy 277.509491 19.348399)
			(xy 277.509986 19.305524) (xy 277.509491 19.262649) (xy 277.508832 19.255537) (xy 308.364877 19.255537)
			(xy 308.364877 19.341287) (xy 308.372789 19.42667) (xy 308.388545 19.51096) (xy 308.412012 19.593436)
			(xy 308.442988 19.673395) (xy 308.48121 19.750155) (xy 308.526351 19.823061) (xy 308.578027 19.89149)
			(xy 308.635796 19.95486) (xy 308.699166 20.012629) (xy 308.767595 20.064305) (xy 308.840501 20.109446)
			(xy 308.917261 20.147668) (xy 308.99722 20.178644) (xy 309.079696 20.202111) (xy 309.163986 20.217867)
			(xy 309.249369 20.225779) (xy 309.335119 20.225779) (xy 309.420502 20.217867) (xy 309.504792 20.202111)
			(xy 309.587268 20.178644) (xy 309.667227 20.147668) (xy 309.68943 20.136612) (xy 310.871108 20.136612)
			(xy 310.871108 21.000212) (xy 310.871544 21.027477) (xy 310.87931 21.081453) (xy 310.894681 21.133772)
			(xy 310.917345 21.18337) (xy 310.946839 21.229237) (xy 310.982563 21.270436) (xy 311.023789 21.30613)
			(xy 311.069677 21.33559) (xy 311.119292 21.358217) (xy 311.171623 21.37355) (xy 311.225604 21.381276)
			(xy 311.25287 21.38172) (xy 311.278923 21.381225) (xy 311.330544 21.374143) (xy 311.380723 21.360105)
			(xy 311.428526 21.339373) (xy 311.473065 21.312331) (xy 311.513513 21.279484) (xy 311.549117 21.24144)
			(xy 311.564528 21.22043) (xy 311.569608 21.213318) (xy 311.584086 21.203158) (xy 311.664096 21.181568)
			(xy 311.681876 21.183092) (xy 311.690004 21.186902) (xy 311.697614 21.190105) (xy 311.713754 21.193567)
			(xy 311.722008 21.19376) (xy 312.334148 21.19376) (xy 312.34623 21.193376) (xy 312.369207 21.185894)
			(xy 312.388747 21.171679) (xy 312.402938 21.152121) (xy 312.410391 21.129134) (xy 312.410856 21.117052)
			(xy 312.410856 20.019772) (xy 312.410361 20.007701) (xy 312.402896 19.984741) (xy 312.388706 19.965208)
			(xy 312.369177 19.951013) (xy 312.346219 19.943542) (xy 312.334148 19.943064) (xy 311.722008 19.943064)
			(xy 311.713753 19.943253) (xy 311.697609 19.946706) (xy 311.690004 19.949922) (xy 311.681876 19.953732)
			(xy 311.664096 19.955256) (xy 311.584086 19.933666) (xy 311.569608 19.923506) (xy 311.564528 19.916394)
			(xy 311.549122 19.895377) (xy 311.513523 19.857322) (xy 311.473078 19.824463) (xy 311.428539 19.797413)
			(xy 311.380734 19.776674) (xy 311.330551 19.762631) (xy 311.278925 19.755545) (xy 311.25287 19.755104)
			(xy 311.225613 19.755596) (xy 311.171654 19.763354) (xy 311.119347 19.778708) (xy 311.069755 19.801347)
			(xy 311.023889 19.830809) (xy 310.982679 19.866496) (xy 310.946964 19.907682) (xy 310.917471 19.953529)
			(xy 310.894799 20.003105) (xy 310.879409 20.055401) (xy 310.871614 20.109355) (xy 310.871108 20.136612)
			(xy 309.68943 20.136612) (xy 309.743987 20.109446) (xy 309.816893 20.064305) (xy 309.885322 20.012629)
			(xy 309.948692 19.95486) (xy 310.006461 19.89149) (xy 310.058137 19.823061) (xy 310.103278 19.750155)
			(xy 310.1415 19.673395) (xy 310.172476 19.593436) (xy 310.195943 19.51096) (xy 310.211699 19.42667)
			(xy 310.219611 19.341287) (xy 310.220106 19.298412) (xy 310.219611 19.255537) (xy 314.714877 19.255537)
			(xy 314.714877 19.341287) (xy 314.722789 19.42667) (xy 314.738545 19.51096) (xy 314.762012 19.593436)
			(xy 314.792988 19.673395) (xy 314.83121 19.750155) (xy 314.876351 19.823061) (xy 314.928027 19.89149)
			(xy 314.985796 19.95486) (xy 315.049166 20.012629) (xy 315.117595 20.064305) (xy 315.190501 20.109446)
			(xy 315.267261 20.147668) (xy 315.34722 20.178644) (xy 315.429696 20.202111) (xy 315.513986 20.217867)
			(xy 315.599369 20.225779) (xy 315.685119 20.225779) (xy 315.770502 20.217867) (xy 315.854792 20.202111)
			(xy 315.937268 20.178644) (xy 316.017227 20.147668) (xy 316.093987 20.109446) (xy 316.166893 20.064305)
			(xy 316.235322 20.012629) (xy 316.298692 19.95486) (xy 316.356461 19.89149) (xy 316.408137 19.823061)
			(xy 316.453278 19.750155) (xy 316.4915 19.673395) (xy 316.522476 19.593436) (xy 316.545943 19.51096)
			(xy 316.561699 19.42667) (xy 316.569611 19.341287) (xy 316.570106 19.298412) (xy 316.569693 19.262649)
			(xy 334.455757 19.262649) (xy 334.455757 19.348399) (xy 334.463669 19.433782) (xy 334.479425 19.518072)
			(xy 334.502892 19.600548) (xy 334.533868 19.680507) (xy 334.57209 19.757267) (xy 334.617231 19.830173)
			(xy 334.668907 19.898602) (xy 334.726676 19.961972) (xy 334.790046 20.019741) (xy 334.858475 20.071417)
			(xy 334.931381 20.116558) (xy 335.008141 20.15478) (xy 335.0881 20.185756) (xy 335.170576 20.209223)
			(xy 335.254866 20.224979) (xy 335.340249 20.232891) (xy 335.425999 20.232891) (xy 335.511382 20.224979)
			(xy 335.595672 20.209223) (xy 335.678148 20.185756) (xy 335.758107 20.15478) (xy 335.834867 20.116558)
			(xy 335.907773 20.071417) (xy 335.966743 20.026884) (xy 338.614512 20.026884) (xy 338.614512 21.124164)
			(xy 338.614944 21.136247) (xy 338.622404 21.159232) (xy 338.636604 21.178784) (xy 338.656154 21.192989)
			(xy 338.679137 21.200454) (xy 338.69122 21.200872) (xy 339.30336 21.200872) (xy 339.311617 21.200709)
			(xy 339.32776 21.197239) (xy 339.335364 21.194014) (xy 339.343492 21.190204) (xy 339.361272 21.18868)
			(xy 339.441282 21.21027) (xy 339.45576 21.22043) (xy 339.46084 21.227542) (xy 339.476255 21.248552)
			(xy 339.511854 21.286606) (xy 339.552298 21.319463) (xy 339.596835 21.346514) (xy 339.644639 21.367255)
			(xy 339.694819 21.3813) (xy 339.746444 21.388389) (xy 339.772498 21.388832) (xy 339.799757 21.388375)
			(xy 339.853721 21.380619) (xy 339.906033 21.365265) (xy 339.955628 21.342626) (xy 340.001498 21.313161)
			(xy 340.04271 21.27747) (xy 340.078425 21.236279) (xy 340.107917 21.190427) (xy 340.130586 21.140845)
			(xy 340.145971 21.088542) (xy 340.153758 21.034583) (xy 340.15426 21.007324) (xy 340.15426 20.143724)
			(xy 340.153821 20.116458) (xy 340.14606 20.062481) (xy 340.130692 20.01016) (xy 340.10803 19.96056)
			(xy 340.078536 19.914692) (xy 340.042812 19.873491) (xy 340.001585 19.837797) (xy 339.955696 19.808337)
			(xy 339.906079 19.785711) (xy 339.853747 19.770381) (xy 339.799764 19.762659) (xy 339.772498 19.762216)
			(xy 339.746444 19.762672) (xy 339.69482 19.769759) (xy 339.64464 19.783803) (xy 339.596836 19.804541)
			(xy 339.552297 19.831588) (xy 339.511851 19.864443) (xy 339.476249 19.902493) (xy 339.46084 19.923506)
			(xy 339.45576 19.930618) (xy 339.441282 19.940778) (xy 339.361272 19.962368) (xy 339.343492 19.960844)
			(xy 339.335364 19.957034) (xy 339.327759 19.953818) (xy 339.311615 19.950365) (xy 339.30336 19.950176)
			(xy 338.69122 19.950176) (xy 338.67914 19.95063) (xy 338.656161 19.95809) (xy 338.636611 19.972286)
			(xy 338.622406 19.991828) (xy 338.614935 20.014804) (xy 338.614512 20.026884) (xy 335.966743 20.026884)
			(xy 335.976202 20.019741) (xy 336.039572 19.961972) (xy 336.097341 19.898602) (xy 336.149017 19.830173)
			(xy 336.194158 19.757267) (xy 336.23238 19.680507) (xy 336.263356 19.600548) (xy 336.286823 19.518072)
			(xy 336.302579 19.433782) (xy 336.310491 19.348399) (xy 336.310986 19.305524) (xy 336.310491 19.262649)
			(xy 340.805757 19.262649) (xy 340.805757 19.348399) (xy 340.813669 19.433782) (xy 340.829425 19.518072)
			(xy 340.852892 19.600548) (xy 340.883868 19.680507) (xy 340.92209 19.757267) (xy 340.967231 19.830173)
			(xy 341.018907 19.898602) (xy 341.076676 19.961972) (xy 341.140046 20.019741) (xy 341.208475 20.071417)
			(xy 341.281381 20.116558) (xy 341.358141 20.15478) (xy 341.4381 20.185756) (xy 341.520576 20.209223)
			(xy 341.604866 20.224979) (xy 341.690249 20.232891) (xy 341.775999 20.232891) (xy 341.861382 20.224979)
			(xy 341.945672 20.209223) (xy 342.028148 20.185756) (xy 342.108107 20.15478) (xy 342.184867 20.116558)
			(xy 342.257773 20.071417) (xy 342.326202 20.019741) (xy 342.389572 19.961972) (xy 342.447341 19.898602)
			(xy 342.499017 19.830173) (xy 342.544158 19.757267) (xy 342.58238 19.680507) (xy 342.613356 19.600548)
			(xy 342.636823 19.518072) (xy 342.652579 19.433782) (xy 342.660491 19.348399) (xy 342.660986 19.305524)
			(xy 342.660491 19.262649) (xy 342.659832 19.255537) (xy 373.515877 19.255537) (xy 373.515877 19.341287)
			(xy 373.523789 19.42667) (xy 373.539545 19.51096) (xy 373.563012 19.593436) (xy 373.593988 19.673395)
			(xy 373.63221 19.750155) (xy 373.677351 19.823061) (xy 373.729027 19.89149) (xy 373.786796 19.95486)
			(xy 373.850166 20.012629) (xy 373.918595 20.064305) (xy 373.991501 20.109446) (xy 374.068261 20.147668)
			(xy 374.14822 20.178644) (xy 374.230696 20.202111) (xy 374.314986 20.217867) (xy 374.400369 20.225779)
			(xy 374.486119 20.225779) (xy 374.571502 20.217867) (xy 374.655792 20.202111) (xy 374.738268 20.178644)
			(xy 374.818227 20.147668) (xy 374.84043 20.136612) (xy 376.022108 20.136612) (xy 376.022108 21.000212)
			(xy 376.022544 21.027477) (xy 376.03031 21.081453) (xy 376.045681 21.133772) (xy 376.068345 21.18337)
			(xy 376.097839 21.229237) (xy 376.133563 21.270436) (xy 376.174789 21.30613) (xy 376.220677 21.33559)
			(xy 376.270292 21.358217) (xy 376.322623 21.37355) (xy 376.376604 21.381276) (xy 376.40387 21.38172)
			(xy 376.429923 21.381225) (xy 376.481544 21.374143) (xy 376.531723 21.360105) (xy 376.579526 21.339373)
			(xy 376.624065 21.312331) (xy 376.664513 21.279484) (xy 376.700117 21.24144) (xy 376.715528 21.22043)
			(xy 376.720608 21.213318) (xy 376.735086 21.203158) (xy 376.815096 21.181568) (xy 376.832876 21.183092)
			(xy 376.841004 21.186902) (xy 376.848614 21.190105) (xy 376.864754 21.193567) (xy 376.873008 21.19376)
			(xy 377.485148 21.19376) (xy 377.49723 21.193376) (xy 377.520207 21.185894) (xy 377.539747 21.171679)
			(xy 377.553938 21.152121) (xy 377.561391 21.129134) (xy 377.561856 21.117052) (xy 377.561856 20.019772)
			(xy 377.561361 20.007701) (xy 377.553896 19.984741) (xy 377.539706 19.965208) (xy 377.520177 19.951013)
			(xy 377.497219 19.943542) (xy 377.485148 19.943064) (xy 376.873008 19.943064) (xy 376.864753 19.943253)
			(xy 376.848609 19.946706) (xy 376.841004 19.949922) (xy 376.832876 19.953732) (xy 376.815096 19.955256)
			(xy 376.735086 19.933666) (xy 376.720608 19.923506) (xy 376.715528 19.916394) (xy 376.700122 19.895377)
			(xy 376.664523 19.857322) (xy 376.624078 19.824463) (xy 376.579539 19.797413) (xy 376.531734 19.776674)
			(xy 376.481551 19.762631) (xy 376.429925 19.755545) (xy 376.40387 19.755104) (xy 376.376613 19.755596)
			(xy 376.322654 19.763354) (xy 376.270347 19.778708) (xy 376.220755 19.801347) (xy 376.174889 19.830809)
			(xy 376.133679 19.866496) (xy 376.097964 19.907682) (xy 376.068471 19.953529) (xy 376.045799 20.003105)
			(xy 376.030409 20.055401) (xy 376.022614 20.109355) (xy 376.022108 20.136612) (xy 374.84043 20.136612)
			(xy 374.894987 20.109446) (xy 374.967893 20.064305) (xy 375.036322 20.012629) (xy 375.099692 19.95486)
			(xy 375.157461 19.89149) (xy 375.209137 19.823061) (xy 375.254278 19.750155) (xy 375.2925 19.673395)
			(xy 375.323476 19.593436) (xy 375.346943 19.51096) (xy 375.362699 19.42667) (xy 375.370611 19.341287)
			(xy 375.371106 19.298412) (xy 375.370611 19.255537) (xy 379.865877 19.255537) (xy 379.865877 19.341287)
			(xy 379.873789 19.42667) (xy 379.889545 19.51096) (xy 379.913012 19.593436) (xy 379.943988 19.673395)
			(xy 379.98221 19.750155) (xy 380.027351 19.823061) (xy 380.079027 19.89149) (xy 380.136796 19.95486)
			(xy 380.200166 20.012629) (xy 380.268595 20.064305) (xy 380.341501 20.109446) (xy 380.418261 20.147668)
			(xy 380.49822 20.178644) (xy 380.580696 20.202111) (xy 380.664986 20.217867) (xy 380.750369 20.225779)
			(xy 380.836119 20.225779) (xy 380.921502 20.217867) (xy 381.005792 20.202111) (xy 381.088268 20.178644)
			(xy 381.168227 20.147668) (xy 381.244987 20.109446) (xy 381.317893 20.064305) (xy 381.386322 20.012629)
			(xy 381.449692 19.95486) (xy 381.507461 19.89149) (xy 381.559137 19.823061) (xy 381.604278 19.750155)
			(xy 381.6425 19.673395) (xy 381.673476 19.593436) (xy 381.696943 19.51096) (xy 381.712699 19.42667)
			(xy 381.720611 19.341287) (xy 381.721106 19.298412) (xy 381.720693 19.262649) (xy 399.098757 19.262649)
			(xy 399.098757 19.348399) (xy 399.106669 19.433782) (xy 399.122425 19.518072) (xy 399.145892 19.600548)
			(xy 399.176868 19.680507) (xy 399.21509 19.757267) (xy 399.260231 19.830173) (xy 399.311907 19.898602)
			(xy 399.369676 19.961972) (xy 399.433046 20.019741) (xy 399.501475 20.071417) (xy 399.574381 20.116558)
			(xy 399.651141 20.15478) (xy 399.7311 20.185756) (xy 399.813576 20.209223) (xy 399.897866 20.224979)
			(xy 399.983249 20.232891) (xy 400.068999 20.232891) (xy 400.154382 20.224979) (xy 400.238672 20.209223)
			(xy 400.321148 20.185756) (xy 400.401107 20.15478) (xy 400.477867 20.116558) (xy 400.550773 20.071417)
			(xy 400.609743 20.026884) (xy 403.257512 20.026884) (xy 403.257512 21.124164) (xy 403.257944 21.136247)
			(xy 403.265404 21.159232) (xy 403.279604 21.178784) (xy 403.299154 21.192989) (xy 403.322137 21.200454)
			(xy 403.33422 21.200872) (xy 403.94636 21.200872) (xy 403.954617 21.200709) (xy 403.97076 21.197239)
			(xy 403.978364 21.194014) (xy 403.986492 21.190204) (xy 404.004272 21.18868) (xy 404.084282 21.21027)
			(xy 404.09876 21.22043) (xy 404.10384 21.227542) (xy 404.119255 21.248552) (xy 404.154854 21.286606)
			(xy 404.195298 21.319463) (xy 404.239835 21.346514) (xy 404.287639 21.367255) (xy 404.337819 21.3813)
			(xy 404.389444 21.388389) (xy 404.415498 21.388832) (xy 404.442757 21.388375) (xy 404.496721 21.380619)
			(xy 404.549033 21.365265) (xy 404.598628 21.342626) (xy 404.644498 21.313161) (xy 404.68571 21.27747)
			(xy 404.721425 21.236279) (xy 404.750917 21.190427) (xy 404.773586 21.140845) (xy 404.788971 21.088542)
			(xy 404.796758 21.034583) (xy 404.79726 21.007324) (xy 404.79726 20.143724) (xy 404.796821 20.116458)
			(xy 404.78906 20.062481) (xy 404.773692 20.01016) (xy 404.75103 19.96056) (xy 404.721536 19.914692)
			(xy 404.685812 19.873491) (xy 404.644585 19.837797) (xy 404.598696 19.808337) (xy 404.549079 19.785711)
			(xy 404.496747 19.770381) (xy 404.442764 19.762659) (xy 404.415498 19.762216) (xy 404.389444 19.762672)
			(xy 404.33782 19.769759) (xy 404.28764 19.783803) (xy 404.239836 19.804541) (xy 404.195297 19.831588)
			(xy 404.154851 19.864443) (xy 404.119249 19.902493) (xy 404.10384 19.923506) (xy 404.09876 19.930618)
			(xy 404.084282 19.940778) (xy 404.004272 19.962368) (xy 403.986492 19.960844) (xy 403.978364 19.957034)
			(xy 403.970759 19.953818) (xy 403.954615 19.950365) (xy 403.94636 19.950176) (xy 403.33422 19.950176)
			(xy 403.32214 19.95063) (xy 403.299161 19.95809) (xy 403.279611 19.972286) (xy 403.265406 19.991828)
			(xy 403.257935 20.014804) (xy 403.257512 20.026884) (xy 400.609743 20.026884) (xy 400.619202 20.019741)
			(xy 400.682572 19.961972) (xy 400.740341 19.898602) (xy 400.792017 19.830173) (xy 400.837158 19.757267)
			(xy 400.87538 19.680507) (xy 400.906356 19.600548) (xy 400.929823 19.518072) (xy 400.945579 19.433782)
			(xy 400.953491 19.348399) (xy 400.953986 19.305524) (xy 400.953491 19.262649) (xy 405.448757 19.262649)
			(xy 405.448757 19.348399) (xy 405.456669 19.433782) (xy 405.472425 19.518072) (xy 405.495892 19.600548)
			(xy 405.526868 19.680507) (xy 405.56509 19.757267) (xy 405.610231 19.830173) (xy 405.661907 19.898602)
			(xy 405.719676 19.961972) (xy 405.783046 20.019741) (xy 405.851475 20.071417) (xy 405.924381 20.116558)
			(xy 406.001141 20.15478) (xy 406.0811 20.185756) (xy 406.163576 20.209223) (xy 406.247866 20.224979)
			(xy 406.333249 20.232891) (xy 406.418999 20.232891) (xy 406.504382 20.224979) (xy 406.588672 20.209223)
			(xy 406.671148 20.185756) (xy 406.751107 20.15478) (xy 406.827867 20.116558) (xy 406.900773 20.071417)
			(xy 406.969202 20.019741) (xy 407.032572 19.961972) (xy 407.090341 19.898602) (xy 407.142017 19.830173)
			(xy 407.187158 19.757267) (xy 407.22538 19.680507) (xy 407.256356 19.600548) (xy 407.279823 19.518072)
			(xy 407.295579 19.433782) (xy 407.303491 19.348399) (xy 407.303986 19.305524) (xy 407.303491 19.262649)
			(xy 407.302832 19.255537) (xy 438.158877 19.255537) (xy 438.158877 19.341287) (xy 438.166789 19.42667)
			(xy 438.182545 19.51096) (xy 438.206012 19.593436) (xy 438.236988 19.673395) (xy 438.27521 19.750155)
			(xy 438.320351 19.823061) (xy 438.372027 19.89149) (xy 438.429796 19.95486) (xy 438.493166 20.012629)
			(xy 438.561595 20.064305) (xy 438.634501 20.109446) (xy 438.711261 20.147668) (xy 438.79122 20.178644)
			(xy 438.873696 20.202111) (xy 438.957986 20.217867) (xy 439.043369 20.225779) (xy 439.129119 20.225779)
			(xy 439.214502 20.217867) (xy 439.298792 20.202111) (xy 439.381268 20.178644) (xy 439.461227 20.147668)
			(xy 439.48343 20.136612) (xy 440.665108 20.136612) (xy 440.665108 21.000212) (xy 440.665544 21.027477)
			(xy 440.67331 21.081453) (xy 440.688681 21.133772) (xy 440.711345 21.18337) (xy 440.740839 21.229237)
			(xy 440.776563 21.270436) (xy 440.817789 21.30613) (xy 440.863677 21.33559) (xy 440.913292 21.358217)
			(xy 440.965623 21.37355) (xy 441.019604 21.381276) (xy 441.04687 21.38172) (xy 441.072923 21.381225)
			(xy 441.124544 21.374143) (xy 441.174723 21.360105) (xy 441.222526 21.339373) (xy 441.267065 21.312331)
			(xy 441.307513 21.279484) (xy 441.343117 21.24144) (xy 441.358528 21.22043) (xy 441.363608 21.213318)
			(xy 441.378086 21.203158) (xy 441.458096 21.181568) (xy 441.475876 21.183092) (xy 441.484004 21.186902)
			(xy 441.491614 21.190105) (xy 441.507754 21.193567) (xy 441.516008 21.19376) (xy 442.128148 21.19376)
			(xy 442.14023 21.193376) (xy 442.163207 21.185894) (xy 442.182747 21.171679) (xy 442.196938 21.152121)
			(xy 442.204391 21.129134) (xy 442.204856 21.117052) (xy 442.204856 20.019772) (xy 442.204361 20.007701)
			(xy 442.196896 19.984741) (xy 442.182706 19.965208) (xy 442.163177 19.951013) (xy 442.140219 19.943542)
			(xy 442.128148 19.943064) (xy 441.516008 19.943064) (xy 441.507753 19.943253) (xy 441.491609 19.946706)
			(xy 441.484004 19.949922) (xy 441.475876 19.953732) (xy 441.458096 19.955256) (xy 441.378086 19.933666)
			(xy 441.363608 19.923506) (xy 441.358528 19.916394) (xy 441.343122 19.895377) (xy 441.307523 19.857322)
			(xy 441.267078 19.824463) (xy 441.222539 19.797413) (xy 441.174734 19.776674) (xy 441.124551 19.762631)
			(xy 441.072925 19.755545) (xy 441.04687 19.755104) (xy 441.019613 19.755596) (xy 440.965654 19.763354)
			(xy 440.913347 19.778708) (xy 440.863755 19.801347) (xy 440.817889 19.830809) (xy 440.776679 19.866496)
			(xy 440.740964 19.907682) (xy 440.711471 19.953529) (xy 440.688799 20.003105) (xy 440.673409 20.055401)
			(xy 440.665614 20.109355) (xy 440.665108 20.136612) (xy 439.48343 20.136612) (xy 439.537987 20.109446)
			(xy 439.610893 20.064305) (xy 439.679322 20.012629) (xy 439.742692 19.95486) (xy 439.800461 19.89149)
			(xy 439.852137 19.823061) (xy 439.897278 19.750155) (xy 439.9355 19.673395) (xy 439.966476 19.593436)
			(xy 439.989943 19.51096) (xy 440.005699 19.42667) (xy 440.013611 19.341287) (xy 440.014106 19.298412)
			(xy 440.013611 19.255537) (xy 444.508877 19.255537) (xy 444.508877 19.341287) (xy 444.516789 19.42667)
			(xy 444.532545 19.51096) (xy 444.556012 19.593436) (xy 444.586988 19.673395) (xy 444.62521 19.750155)
			(xy 444.670351 19.823061) (xy 444.722027 19.89149) (xy 444.779796 19.95486) (xy 444.843166 20.012629)
			(xy 444.911595 20.064305) (xy 444.984501 20.109446) (xy 445.061261 20.147668) (xy 445.14122 20.178644)
			(xy 445.223696 20.202111) (xy 445.307986 20.217867) (xy 445.393369 20.225779) (xy 445.479119 20.225779)
			(xy 445.564502 20.217867) (xy 445.648792 20.202111) (xy 445.731268 20.178644) (xy 445.811227 20.147668)
			(xy 445.887987 20.109446) (xy 445.960893 20.064305) (xy 446.029322 20.012629) (xy 446.092692 19.95486)
			(xy 446.150461 19.89149) (xy 446.202137 19.823061) (xy 446.247278 19.750155) (xy 446.2855 19.673395)
			(xy 446.316476 19.593436) (xy 446.339943 19.51096) (xy 446.355699 19.42667) (xy 446.363611 19.341287)
			(xy 446.364106 19.298412) (xy 446.363611 19.255537) (xy 446.355699 19.170154) (xy 446.339943 19.085864)
			(xy 446.316476 19.003388) (xy 446.2855 18.923429) (xy 446.247278 18.846669) (xy 446.202137 18.773763)
			(xy 446.150461 18.705334) (xy 446.092692 18.641964) (xy 446.029322 18.584195) (xy 445.960893 18.532519)
			(xy 445.887987 18.487378) (xy 445.811227 18.449156) (xy 445.731268 18.41818) (xy 445.648792 18.394713)
			(xy 445.564502 18.378957) (xy 445.479119 18.371045) (xy 445.393369 18.371045) (xy 445.307986 18.378957)
			(xy 445.223696 18.394713) (xy 445.14122 18.41818) (xy 445.061261 18.449156) (xy 444.984501 18.487378)
			(xy 444.911595 18.532519) (xy 444.843166 18.584195) (xy 444.779796 18.641964) (xy 444.722027 18.705334)
			(xy 444.670351 18.773763) (xy 444.62521 18.846669) (xy 444.586988 18.923429) (xy 444.556012 19.003388)
			(xy 444.532545 19.085864) (xy 444.516789 19.170154) (xy 444.508877 19.255537) (xy 440.013611 19.255537)
			(xy 440.005699 19.170154) (xy 439.989943 19.085864) (xy 439.966476 19.003388) (xy 439.9355 18.923429)
			(xy 439.897278 18.846669) (xy 439.852137 18.773763) (xy 439.800461 18.705334) (xy 439.742692 18.641964)
			(xy 439.679322 18.584195) (xy 439.610893 18.532519) (xy 439.537987 18.487378) (xy 439.461227 18.449156)
			(xy 439.381268 18.41818) (xy 439.298792 18.394713) (xy 439.214502 18.378957) (xy 439.129119 18.371045)
			(xy 439.043369 18.371045) (xy 438.957986 18.378957) (xy 438.873696 18.394713) (xy 438.79122 18.41818)
			(xy 438.711261 18.449156) (xy 438.634501 18.487378) (xy 438.561595 18.532519) (xy 438.493166 18.584195)
			(xy 438.429796 18.641964) (xy 438.372027 18.705334) (xy 438.320351 18.773763) (xy 438.27521 18.846669)
			(xy 438.236988 18.923429) (xy 438.206012 19.003388) (xy 438.182545 19.085864) (xy 438.166789 19.170154)
			(xy 438.158877 19.255537) (xy 407.302832 19.255537) (xy 407.295579 19.177266) (xy 407.279823 19.092976)
			(xy 407.256356 19.0105) (xy 407.22538 18.930541) (xy 407.187158 18.853781) (xy 407.142017 18.780875)
			(xy 407.090341 18.712446) (xy 407.032572 18.649076) (xy 406.969202 18.591307) (xy 406.900773 18.539631)
			(xy 406.827867 18.49449) (xy 406.751107 18.456268) (xy 406.671148 18.425292) (xy 406.588672 18.401825)
			(xy 406.504382 18.386069) (xy 406.418999 18.378157) (xy 406.333249 18.378157) (xy 406.247866 18.386069)
			(xy 406.163576 18.401825) (xy 406.0811 18.425292) (xy 406.001141 18.456268) (xy 405.924381 18.49449)
			(xy 405.851475 18.539631) (xy 405.783046 18.591307) (xy 405.719676 18.649076) (xy 405.661907 18.712446)
			(xy 405.610231 18.780875) (xy 405.56509 18.853781) (xy 405.526868 18.930541) (xy 405.495892 19.0105)
			(xy 405.472425 19.092976) (xy 405.456669 19.177266) (xy 405.448757 19.262649) (xy 400.953491 19.262649)
			(xy 400.945579 19.177266) (xy 400.929823 19.092976) (xy 400.906356 19.0105) (xy 400.87538 18.930541)
			(xy 400.837158 18.853781) (xy 400.792017 18.780875) (xy 400.740341 18.712446) (xy 400.682572 18.649076)
			(xy 400.619202 18.591307) (xy 400.550773 18.539631) (xy 400.477867 18.49449) (xy 400.401107 18.456268)
			(xy 400.321148 18.425292) (xy 400.238672 18.401825) (xy 400.154382 18.386069) (xy 400.068999 18.378157)
			(xy 399.983249 18.378157) (xy 399.897866 18.386069) (xy 399.813576 18.401825) (xy 399.7311 18.425292)
			(xy 399.651141 18.456268) (xy 399.574381 18.49449) (xy 399.501475 18.539631) (xy 399.433046 18.591307)
			(xy 399.369676 18.649076) (xy 399.311907 18.712446) (xy 399.260231 18.780875) (xy 399.21509 18.853781)
			(xy 399.176868 18.930541) (xy 399.145892 19.0105) (xy 399.122425 19.092976) (xy 399.106669 19.177266)
			(xy 399.098757 19.262649) (xy 381.720693 19.262649) (xy 381.720611 19.255537) (xy 381.712699 19.170154)
			(xy 381.696943 19.085864) (xy 381.673476 19.003388) (xy 381.6425 18.923429) (xy 381.604278 18.846669)
			(xy 381.559137 18.773763) (xy 381.507461 18.705334) (xy 381.449692 18.641964) (xy 381.386322 18.584195)
			(xy 381.317893 18.532519) (xy 381.244987 18.487378) (xy 381.168227 18.449156) (xy 381.088268 18.41818)
			(xy 381.005792 18.394713) (xy 380.921502 18.378957) (xy 380.836119 18.371045) (xy 380.750369 18.371045)
			(xy 380.664986 18.378957) (xy 380.580696 18.394713) (xy 380.49822 18.41818) (xy 380.418261 18.449156)
			(xy 380.341501 18.487378) (xy 380.268595 18.532519) (xy 380.200166 18.584195) (xy 380.136796 18.641964)
			(xy 380.079027 18.705334) (xy 380.027351 18.773763) (xy 379.98221 18.846669) (xy 379.943988 18.923429)
			(xy 379.913012 19.003388) (xy 379.889545 19.085864) (xy 379.873789 19.170154) (xy 379.865877 19.255537)
			(xy 375.370611 19.255537) (xy 375.362699 19.170154) (xy 375.346943 19.085864) (xy 375.323476 19.003388)
			(xy 375.2925 18.923429) (xy 375.254278 18.846669) (xy 375.209137 18.773763) (xy 375.157461 18.705334)
			(xy 375.099692 18.641964) (xy 375.036322 18.584195) (xy 374.967893 18.532519) (xy 374.894987 18.487378)
			(xy 374.818227 18.449156) (xy 374.738268 18.41818) (xy 374.655792 18.394713) (xy 374.571502 18.378957)
			(xy 374.486119 18.371045) (xy 374.400369 18.371045) (xy 374.314986 18.378957) (xy 374.230696 18.394713)
			(xy 374.14822 18.41818) (xy 374.068261 18.449156) (xy 373.991501 18.487378) (xy 373.918595 18.532519)
			(xy 373.850166 18.584195) (xy 373.786796 18.641964) (xy 373.729027 18.705334) (xy 373.677351 18.773763)
			(xy 373.63221 18.846669) (xy 373.593988 18.923429) (xy 373.563012 19.003388) (xy 373.539545 19.085864)
			(xy 373.523789 19.170154) (xy 373.515877 19.255537) (xy 342.659832 19.255537) (xy 342.652579 19.177266)
			(xy 342.636823 19.092976) (xy 342.613356 19.0105) (xy 342.58238 18.930541) (xy 342.544158 18.853781)
			(xy 342.499017 18.780875) (xy 342.447341 18.712446) (xy 342.389572 18.649076) (xy 342.326202 18.591307)
			(xy 342.257773 18.539631) (xy 342.184867 18.49449) (xy 342.108107 18.456268) (xy 342.028148 18.425292)
			(xy 341.945672 18.401825) (xy 341.861382 18.386069) (xy 341.775999 18.378157) (xy 341.690249 18.378157)
			(xy 341.604866 18.386069) (xy 341.520576 18.401825) (xy 341.4381 18.425292) (xy 341.358141 18.456268)
			(xy 341.281381 18.49449) (xy 341.208475 18.539631) (xy 341.140046 18.591307) (xy 341.076676 18.649076)
			(xy 341.018907 18.712446) (xy 340.967231 18.780875) (xy 340.92209 18.853781) (xy 340.883868 18.930541)
			(xy 340.852892 19.0105) (xy 340.829425 19.092976) (xy 340.813669 19.177266) (xy 340.805757 19.262649)
			(xy 336.310491 19.262649) (xy 336.302579 19.177266) (xy 336.286823 19.092976) (xy 336.263356 19.0105)
			(xy 336.23238 18.930541) (xy 336.194158 18.853781) (xy 336.149017 18.780875) (xy 336.097341 18.712446)
			(xy 336.039572 18.649076) (xy 335.976202 18.591307) (xy 335.907773 18.539631) (xy 335.834867 18.49449)
			(xy 335.758107 18.456268) (xy 335.678148 18.425292) (xy 335.595672 18.401825) (xy 335.511382 18.386069)
			(xy 335.425999 18.378157) (xy 335.340249 18.378157) (xy 335.254866 18.386069) (xy 335.170576 18.401825)
			(xy 335.0881 18.425292) (xy 335.008141 18.456268) (xy 334.931381 18.49449) (xy 334.858475 18.539631)
			(xy 334.790046 18.591307) (xy 334.726676 18.649076) (xy 334.668907 18.712446) (xy 334.617231 18.780875)
			(xy 334.57209 18.853781) (xy 334.533868 18.930541) (xy 334.502892 19.0105) (xy 334.479425 19.092976)
			(xy 334.463669 19.177266) (xy 334.455757 19.262649) (xy 316.569693 19.262649) (xy 316.569611 19.255537)
			(xy 316.561699 19.170154) (xy 316.545943 19.085864) (xy 316.522476 19.003388) (xy 316.4915 18.923429)
			(xy 316.453278 18.846669) (xy 316.408137 18.773763) (xy 316.356461 18.705334) (xy 316.298692 18.641964)
			(xy 316.235322 18.584195) (xy 316.166893 18.532519) (xy 316.093987 18.487378) (xy 316.017227 18.449156)
			(xy 315.937268 18.41818) (xy 315.854792 18.394713) (xy 315.770502 18.378957) (xy 315.685119 18.371045)
			(xy 315.599369 18.371045) (xy 315.513986 18.378957) (xy 315.429696 18.394713) (xy 315.34722 18.41818)
			(xy 315.267261 18.449156) (xy 315.190501 18.487378) (xy 315.117595 18.532519) (xy 315.049166 18.584195)
			(xy 314.985796 18.641964) (xy 314.928027 18.705334) (xy 314.876351 18.773763) (xy 314.83121 18.846669)
			(xy 314.792988 18.923429) (xy 314.762012 19.003388) (xy 314.738545 19.085864) (xy 314.722789 19.170154)
			(xy 314.714877 19.255537) (xy 310.219611 19.255537) (xy 310.211699 19.170154) (xy 310.195943 19.085864)
			(xy 310.172476 19.003388) (xy 310.1415 18.923429) (xy 310.103278 18.846669) (xy 310.058137 18.773763)
			(xy 310.006461 18.705334) (xy 309.948692 18.641964) (xy 309.885322 18.584195) (xy 309.816893 18.532519)
			(xy 309.743987 18.487378) (xy 309.667227 18.449156) (xy 309.587268 18.41818) (xy 309.504792 18.394713)
			(xy 309.420502 18.378957) (xy 309.335119 18.371045) (xy 309.249369 18.371045) (xy 309.163986 18.378957)
			(xy 309.079696 18.394713) (xy 308.99722 18.41818) (xy 308.917261 18.449156) (xy 308.840501 18.487378)
			(xy 308.767595 18.532519) (xy 308.699166 18.584195) (xy 308.635796 18.641964) (xy 308.578027 18.705334)
			(xy 308.526351 18.773763) (xy 308.48121 18.846669) (xy 308.442988 18.923429) (xy 308.412012 19.003388)
			(xy 308.388545 19.085864) (xy 308.372789 19.170154) (xy 308.364877 19.255537) (xy 277.508832 19.255537)
			(xy 277.501579 19.177266) (xy 277.485823 19.092976) (xy 277.462356 19.0105) (xy 277.43138 18.930541)
			(xy 277.393158 18.853781) (xy 277.348017 18.780875) (xy 277.296341 18.712446) (xy 277.238572 18.649076)
			(xy 277.175202 18.591307) (xy 277.106773 18.539631) (xy 277.033867 18.49449) (xy 276.957107 18.456268)
			(xy 276.877148 18.425292) (xy 276.794672 18.401825) (xy 276.710382 18.386069) (xy 276.624999 18.378157)
			(xy 276.539249 18.378157) (xy 276.453866 18.386069) (xy 276.369576 18.401825) (xy 276.2871 18.425292)
			(xy 276.207141 18.456268) (xy 276.130381 18.49449) (xy 276.057475 18.539631) (xy 275.989046 18.591307)
			(xy 275.925676 18.649076) (xy 275.867907 18.712446) (xy 275.816231 18.780875) (xy 275.77109 18.853781)
			(xy 275.732868 18.930541) (xy 275.701892 19.0105) (xy 275.678425 19.092976) (xy 275.662669 19.177266)
			(xy 275.654757 19.262649) (xy 271.159491 19.262649) (xy 271.151579 19.177266) (xy 271.135823 19.092976)
			(xy 271.112356 19.0105) (xy 271.08138 18.930541) (xy 271.043158 18.853781) (xy 270.998017 18.780875)
			(xy 270.946341 18.712446) (xy 270.888572 18.649076) (xy 270.825202 18.591307) (xy 270.756773 18.539631)
			(xy 270.683867 18.49449) (xy 270.607107 18.456268) (xy 270.527148 18.425292) (xy 270.444672 18.401825)
			(xy 270.360382 18.386069) (xy 270.274999 18.378157) (xy 270.189249 18.378157) (xy 270.103866 18.386069)
			(xy 270.019576 18.401825) (xy 269.9371 18.425292) (xy 269.857141 18.456268) (xy 269.780381 18.49449)
			(xy 269.707475 18.539631) (xy 269.639046 18.591307) (xy 269.575676 18.649076) (xy 269.517907 18.712446)
			(xy 269.466231 18.780875) (xy 269.42109 18.853781) (xy 269.382868 18.930541) (xy 269.351892 19.0105)
			(xy 269.328425 19.092976) (xy 269.312669 19.177266) (xy 269.304757 19.262649) (xy 252.231493 19.262649)
			(xy 252.231411 19.255537) (xy 252.223499 19.170154) (xy 252.207743 19.085864) (xy 252.184276 19.003388)
			(xy 252.1533 18.923429) (xy 252.115078 18.846669) (xy 252.069937 18.773763) (xy 252.018261 18.705334)
			(xy 251.960492 18.641964) (xy 251.897122 18.584195) (xy 251.828693 18.532519) (xy 251.755787 18.487378)
			(xy 251.679027 18.449156) (xy 251.599068 18.41818) (xy 251.516592 18.394713) (xy 251.432302 18.378957)
			(xy 251.346919 18.371045) (xy 251.261169 18.371045) (xy 251.175786 18.378957) (xy 251.091496 18.394713)
			(xy 251.00902 18.41818) (xy 250.929061 18.449156) (xy 250.852301 18.487378) (xy 250.779395 18.532519)
			(xy 250.710966 18.584195) (xy 250.647596 18.641964) (xy 250.589827 18.705334) (xy 250.538151 18.773763)
			(xy 250.49301 18.846669) (xy 250.454788 18.923429) (xy 250.423812 19.003388) (xy 250.400345 19.085864)
			(xy 250.384589 19.170154) (xy 250.376677 19.255537) (xy 245.881411 19.255537) (xy 245.873499 19.170154)
			(xy 245.857743 19.085864) (xy 245.834276 19.003388) (xy 245.8033 18.923429) (xy 245.765078 18.846669)
			(xy 245.719937 18.773763) (xy 245.668261 18.705334) (xy 245.610492 18.641964) (xy 245.547122 18.584195)
			(xy 245.478693 18.532519) (xy 245.405787 18.487378) (xy 245.329027 18.449156) (xy 245.249068 18.41818)
			(xy 245.166592 18.394713) (xy 245.082302 18.378957) (xy 244.996919 18.371045) (xy 244.911169 18.371045)
			(xy 244.825786 18.378957) (xy 244.741496 18.394713) (xy 244.65902 18.41818) (xy 244.579061 18.449156)
			(xy 244.502301 18.487378) (xy 244.429395 18.532519) (xy 244.360966 18.584195) (xy 244.297596 18.641964)
			(xy 244.239827 18.705334) (xy 244.188151 18.773763) (xy 244.14301 18.846669) (xy 244.104788 18.923429)
			(xy 244.073812 19.003388) (xy 244.050345 19.085864) (xy 244.034589 19.170154) (xy 244.026677 19.255537)
			(xy 218.199832 19.255537) (xy 218.192579 19.177266) (xy 218.176823 19.092976) (xy 218.153356 19.0105)
			(xy 218.12238 18.930541) (xy 218.084158 18.853781) (xy 218.039017 18.780875) (xy 217.987341 18.712446)
			(xy 217.929572 18.649076) (xy 217.866202 18.591307) (xy 217.797773 18.539631) (xy 217.724867 18.49449)
			(xy 217.648107 18.456268) (xy 217.568148 18.425292) (xy 217.485672 18.401825) (xy 217.401382 18.386069)
			(xy 217.315999 18.378157) (xy 217.230249 18.378157) (xy 217.144866 18.386069) (xy 217.060576 18.401825)
			(xy 216.9781 18.425292) (xy 216.898141 18.456268) (xy 216.821381 18.49449) (xy 216.748475 18.539631)
			(xy 216.680046 18.591307) (xy 216.616676 18.649076) (xy 216.558907 18.712446) (xy 216.507231 18.780875)
			(xy 216.46209 18.853781) (xy 216.423868 18.930541) (xy 216.392892 19.0105) (xy 216.369425 19.092976)
			(xy 216.353669 19.177266) (xy 216.345757 19.262649) (xy 211.850491 19.262649) (xy 211.842579 19.177266)
			(xy 211.826823 19.092976) (xy 211.803356 19.0105) (xy 211.77238 18.930541) (xy 211.734158 18.853781)
			(xy 211.689017 18.780875) (xy 211.637341 18.712446) (xy 211.579572 18.649076) (xy 211.516202 18.591307)
			(xy 211.447773 18.539631) (xy 211.374867 18.49449) (xy 211.298107 18.456268) (xy 211.218148 18.425292)
			(xy 211.135672 18.401825) (xy 211.051382 18.386069) (xy 210.965999 18.378157) (xy 210.880249 18.378157)
			(xy 210.794866 18.386069) (xy 210.710576 18.401825) (xy 210.6281 18.425292) (xy 210.548141 18.456268)
			(xy 210.471381 18.49449) (xy 210.398475 18.539631) (xy 210.330046 18.591307) (xy 210.266676 18.649076)
			(xy 210.208907 18.712446) (xy 210.157231 18.780875) (xy 210.11209 18.853781) (xy 210.073868 18.930541)
			(xy 210.042892 19.0105) (xy 210.019425 19.092976) (xy 210.003669 19.177266) (xy 209.995757 19.262649)
			(xy 158.621984 19.262649) (xy 158.621984 16.722649) (xy 209.995757 16.722649) (xy 209.995757 16.808399)
			(xy 210.003669 16.893782) (xy 210.019425 16.978072) (xy 210.042892 17.060548) (xy 210.073868 17.140507)
			(xy 210.11209 17.217267) (xy 210.157231 17.290173) (xy 210.208907 17.358602) (xy 210.266676 17.421972)
			(xy 210.330046 17.479741) (xy 210.398475 17.531417) (xy 210.471381 17.576558) (xy 210.548141 17.61478)
			(xy 210.6281 17.645756) (xy 210.710576 17.669223) (xy 210.794866 17.684979) (xy 210.880249 17.692891)
			(xy 210.965999 17.692891) (xy 211.051382 17.684979) (xy 211.135672 17.669223) (xy 211.218148 17.645756)
			(xy 211.298107 17.61478) (xy 211.374867 17.576558) (xy 211.447773 17.531417) (xy 211.506743 17.486884)
			(xy 214.154512 17.486884) (xy 214.154512 18.584164) (xy 214.154944 18.596247) (xy 214.162404 18.619232)
			(xy 214.176604 18.638784) (xy 214.196154 18.652989) (xy 214.219137 18.660454) (xy 214.23122 18.660872)
			(xy 214.84336 18.660872) (xy 214.855444 18.660453) (xy 214.878432 18.652992) (xy 214.897986 18.638789)
			(xy 214.91219 18.619235) (xy 214.919652 18.596248) (xy 214.920068 18.584164) (xy 214.920068 17.486884)
			(xy 214.9197 17.474796) (xy 214.912224 17.451806) (xy 214.898007 17.432253) (xy 214.878443 17.418051)
			(xy 214.855448 17.410591) (xy 214.84336 17.410176) (xy 214.23122 17.410176) (xy 214.21914 17.41063)
			(xy 214.196161 17.41809) (xy 214.176611 17.432286) (xy 214.162406 17.451828) (xy 214.154935 17.474804)
			(xy 214.154512 17.486884) (xy 211.506743 17.486884) (xy 211.516202 17.479741) (xy 211.579572 17.421972)
			(xy 211.637341 17.358602) (xy 211.689017 17.290173) (xy 211.734158 17.217267) (xy 211.77238 17.140507)
			(xy 211.803356 17.060548) (xy 211.826823 16.978072) (xy 211.842579 16.893782) (xy 211.850491 16.808399)
			(xy 211.850986 16.765524) (xy 211.850491 16.722649) (xy 216.345757 16.722649) (xy 216.345757 16.808399)
			(xy 216.353669 16.893782) (xy 216.369425 16.978072) (xy 216.392892 17.060548) (xy 216.423868 17.140507)
			(xy 216.46209 17.217267) (xy 216.507231 17.290173) (xy 216.558907 17.358602) (xy 216.616676 17.421972)
			(xy 216.680046 17.479741) (xy 216.748475 17.531417) (xy 216.821381 17.576558) (xy 216.898141 17.61478)
			(xy 216.9781 17.645756) (xy 217.060576 17.669223) (xy 217.144866 17.684979) (xy 217.230249 17.692891)
			(xy 217.315999 17.692891) (xy 217.401382 17.684979) (xy 217.485672 17.669223) (xy 217.568148 17.645756)
			(xy 217.648107 17.61478) (xy 217.724867 17.576558) (xy 217.797773 17.531417) (xy 217.866202 17.479741)
			(xy 217.929572 17.421972) (xy 217.987341 17.358602) (xy 218.039017 17.290173) (xy 218.084158 17.217267)
			(xy 218.12238 17.140507) (xy 218.153356 17.060548) (xy 218.176823 16.978072) (xy 218.192579 16.893782)
			(xy 218.200491 16.808399) (xy 218.200986 16.765524) (xy 218.200491 16.722649) (xy 218.199832 16.715537)
			(xy 244.026677 16.715537) (xy 244.026677 16.801287) (xy 244.034589 16.88667) (xy 244.050345 16.97096)
			(xy 244.073812 17.053436) (xy 244.104788 17.133395) (xy 244.14301 17.210155) (xy 244.188151 17.283061)
			(xy 244.239827 17.35149) (xy 244.297596 17.41486) (xy 244.360966 17.472629) (xy 244.429395 17.524305)
			(xy 244.502301 17.569446) (xy 244.579061 17.607668) (xy 244.65902 17.638644) (xy 244.741496 17.662111)
			(xy 244.825786 17.677867) (xy 244.911169 17.685779) (xy 244.996919 17.685779) (xy 245.082302 17.677867)
			(xy 245.166592 17.662111) (xy 245.249068 17.638644) (xy 245.329027 17.607668) (xy 245.405787 17.569446)
			(xy 245.478693 17.524305) (xy 245.537663 17.479772) (xy 247.3071 17.479772) (xy 247.3071 18.577052)
			(xy 247.307554 18.589133) (xy 247.315009 18.612116) (xy 247.329204 18.631667) (xy 247.348749 18.645873)
			(xy 247.371727 18.65334) (xy 247.383808 18.65376) (xy 247.995948 18.65376) (xy 248.00803 18.653376)
			(xy 248.031007 18.645894) (xy 248.050547 18.631679) (xy 248.064738 18.612121) (xy 248.072191 18.589134)
			(xy 248.072656 18.577052) (xy 248.072656 17.479772) (xy 248.072161 17.467701) (xy 248.064696 17.444741)
			(xy 248.050506 17.425208) (xy 248.030977 17.411013) (xy 248.008019 17.403542) (xy 247.995948 17.403064)
			(xy 247.383808 17.403064) (xy 247.371737 17.403571) (xy 247.348774 17.411028) (xy 247.32924 17.425214)
			(xy 247.315044 17.444742) (xy 247.307576 17.467701) (xy 247.3071 17.479772) (xy 245.537663 17.479772)
			(xy 245.547122 17.472629) (xy 245.610492 17.41486) (xy 245.668261 17.35149) (xy 245.719937 17.283061)
			(xy 245.765078 17.210155) (xy 245.8033 17.133395) (xy 245.834276 17.053436) (xy 245.857743 16.97096)
			(xy 245.873499 16.88667) (xy 245.881411 16.801287) (xy 245.881906 16.758412) (xy 245.881411 16.715537)
			(xy 250.376677 16.715537) (xy 250.376677 16.801287) (xy 250.384589 16.88667) (xy 250.400345 16.97096)
			(xy 250.423812 17.053436) (xy 250.454788 17.133395) (xy 250.49301 17.210155) (xy 250.538151 17.283061)
			(xy 250.589827 17.35149) (xy 250.647596 17.41486) (xy 250.710966 17.472629) (xy 250.779395 17.524305)
			(xy 250.852301 17.569446) (xy 250.929061 17.607668) (xy 251.00902 17.638644) (xy 251.091496 17.662111)
			(xy 251.175786 17.677867) (xy 251.261169 17.685779) (xy 251.346919 17.685779) (xy 251.432302 17.677867)
			(xy 251.516592 17.662111) (xy 251.599068 17.638644) (xy 251.679027 17.607668) (xy 251.755787 17.569446)
			(xy 251.828693 17.524305) (xy 251.897122 17.472629) (xy 251.960492 17.41486) (xy 252.018261 17.35149)
			(xy 252.069937 17.283061) (xy 252.115078 17.210155) (xy 252.1533 17.133395) (xy 252.184276 17.053436)
			(xy 252.207743 16.97096) (xy 252.223499 16.88667) (xy 252.231411 16.801287) (xy 252.231906 16.758412)
			(xy 252.231493 16.722649) (xy 269.304757 16.722649) (xy 269.304757 16.808399) (xy 269.312669 16.893782)
			(xy 269.328425 16.978072) (xy 269.351892 17.060548) (xy 269.382868 17.140507) (xy 269.42109 17.217267)
			(xy 269.466231 17.290173) (xy 269.517907 17.358602) (xy 269.575676 17.421972) (xy 269.639046 17.479741)
			(xy 269.707475 17.531417) (xy 269.780381 17.576558) (xy 269.857141 17.61478) (xy 269.9371 17.645756)
			(xy 270.019576 17.669223) (xy 270.103866 17.684979) (xy 270.189249 17.692891) (xy 270.274999 17.692891)
			(xy 270.360382 17.684979) (xy 270.444672 17.669223) (xy 270.527148 17.645756) (xy 270.607107 17.61478)
			(xy 270.62931 17.603724) (xy 274.239736 17.603724) (xy 274.239736 18.467324) (xy 274.240222 18.494593)
			(xy 274.247984 18.548577) (xy 274.263349 18.600907) (xy 274.286006 18.650517) (xy 274.315492 18.696398)
			(xy 274.351207 18.737615) (xy 274.392424 18.77333) (xy 274.438305 18.802816) (xy 274.487915 18.825473)
			(xy 274.540245 18.840838) (xy 274.594229 18.8486) (xy 274.648767 18.8486) (xy 274.702751 18.840838)
			(xy 274.755081 18.825473) (xy 274.804691 18.802816) (xy 274.850572 18.77333) (xy 274.891789 18.737615)
			(xy 274.927504 18.696398) (xy 274.95699 18.650517) (xy 274.979647 18.600907) (xy 274.995012 18.548577)
			(xy 275.002774 18.494593) (xy 275.00326 18.467324) (xy 275.00326 17.603724) (xy 275.002774 17.576455)
			(xy 274.995012 17.522471) (xy 274.979647 17.470141) (xy 274.95699 17.420531) (xy 274.927504 17.37465)
			(xy 274.891789 17.333433) (xy 274.850572 17.297718) (xy 274.804691 17.268232) (xy 274.755081 17.245575)
			(xy 274.702751 17.23021) (xy 274.648767 17.222448) (xy 274.594229 17.222448) (xy 274.540245 17.23021)
			(xy 274.487915 17.245575) (xy 274.438305 17.268232) (xy 274.392424 17.297718) (xy 274.351207 17.333433)
			(xy 274.315492 17.37465) (xy 274.286006 17.420531) (xy 274.263349 17.470141) (xy 274.247984 17.522471)
			(xy 274.240222 17.576455) (xy 274.239736 17.603724) (xy 270.62931 17.603724) (xy 270.683867 17.576558)
			(xy 270.756773 17.531417) (xy 270.825202 17.479741) (xy 270.888572 17.421972) (xy 270.946341 17.358602)
			(xy 270.998017 17.290173) (xy 271.043158 17.217267) (xy 271.08138 17.140507) (xy 271.112356 17.060548)
			(xy 271.135823 16.978072) (xy 271.151579 16.893782) (xy 271.159491 16.808399) (xy 271.159986 16.765524)
			(xy 271.159491 16.722649) (xy 275.654757 16.722649) (xy 275.654757 16.808399) (xy 275.662669 16.893782)
			(xy 275.678425 16.978072) (xy 275.701892 17.060548) (xy 275.732868 17.140507) (xy 275.77109 17.217267)
			(xy 275.816231 17.290173) (xy 275.867907 17.358602) (xy 275.925676 17.421972) (xy 275.989046 17.479741)
			(xy 276.057475 17.531417) (xy 276.130381 17.576558) (xy 276.207141 17.61478) (xy 276.2871 17.645756)
			(xy 276.369576 17.669223) (xy 276.453866 17.684979) (xy 276.539249 17.692891) (xy 276.624999 17.692891)
			(xy 276.710382 17.684979) (xy 276.794672 17.669223) (xy 276.877148 17.645756) (xy 276.957107 17.61478)
			(xy 277.033867 17.576558) (xy 277.106773 17.531417) (xy 277.175202 17.479741) (xy 277.238572 17.421972)
			(xy 277.296341 17.358602) (xy 277.348017 17.290173) (xy 277.393158 17.217267) (xy 277.43138 17.140507)
			(xy 277.462356 17.060548) (xy 277.485823 16.978072) (xy 277.501579 16.893782) (xy 277.509491 16.808399)
			(xy 277.509986 16.765524) (xy 277.509491 16.722649) (xy 277.508832 16.715537) (xy 308.364877 16.715537)
			(xy 308.364877 16.801287) (xy 308.372789 16.88667) (xy 308.388545 16.97096) (xy 308.412012 17.053436)
			(xy 308.442988 17.133395) (xy 308.48121 17.210155) (xy 308.526351 17.283061) (xy 308.578027 17.35149)
			(xy 308.635796 17.41486) (xy 308.699166 17.472629) (xy 308.767595 17.524305) (xy 308.840501 17.569446)
			(xy 308.917261 17.607668) (xy 308.99722 17.638644) (xy 309.079696 17.662111) (xy 309.163986 17.677867)
			(xy 309.249369 17.685779) (xy 309.335119 17.685779) (xy 309.420502 17.677867) (xy 309.504792 17.662111)
			(xy 309.587268 17.638644) (xy 309.667227 17.607668) (xy 309.68943 17.596612) (xy 310.871108 17.596612)
			(xy 310.871108 18.460212) (xy 310.871594 18.487481) (xy 310.879356 18.541465) (xy 310.894721 18.593795)
			(xy 310.917378 18.643405) (xy 310.946864 18.689286) (xy 310.982579 18.730503) (xy 311.023796 18.766218)
			(xy 311.069677 18.795704) (xy 311.119287 18.818361) (xy 311.171617 18.833726) (xy 311.225601 18.841488)
			(xy 311.280139 18.841488) (xy 311.334123 18.833726) (xy 311.386453 18.818361) (xy 311.436063 18.795704)
			(xy 311.481944 18.766218) (xy 311.523161 18.730503) (xy 311.558876 18.689286) (xy 311.588362 18.643405)
			(xy 311.611019 18.593795) (xy 311.626384 18.541465) (xy 311.634146 18.487481) (xy 311.634632 18.460212)
			(xy 311.634632 17.596612) (xy 311.634146 17.569343) (xy 311.626384 17.515359) (xy 311.611019 17.463029)
			(xy 311.588362 17.413419) (xy 311.558876 17.367538) (xy 311.523161 17.326321) (xy 311.481944 17.290606)
			(xy 311.436063 17.26112) (xy 311.386453 17.238463) (xy 311.334123 17.223098) (xy 311.280139 17.215336)
			(xy 311.225601 17.215336) (xy 311.171617 17.223098) (xy 311.119287 17.238463) (xy 311.069677 17.26112)
			(xy 311.023796 17.290606) (xy 310.982579 17.326321) (xy 310.946864 17.367538) (xy 310.917378 17.413419)
			(xy 310.894721 17.463029) (xy 310.879356 17.515359) (xy 310.871594 17.569343) (xy 310.871108 17.596612)
			(xy 309.68943 17.596612) (xy 309.743987 17.569446) (xy 309.816893 17.524305) (xy 309.885322 17.472629)
			(xy 309.948692 17.41486) (xy 310.006461 17.35149) (xy 310.058137 17.283061) (xy 310.103278 17.210155)
			(xy 310.1415 17.133395) (xy 310.172476 17.053436) (xy 310.195943 16.97096) (xy 310.211699 16.88667)
			(xy 310.219611 16.801287) (xy 310.220106 16.758412) (xy 310.219611 16.715537) (xy 314.714877 16.715537)
			(xy 314.714877 16.801287) (xy 314.722789 16.88667) (xy 314.738545 16.97096) (xy 314.762012 17.053436)
			(xy 314.792988 17.133395) (xy 314.83121 17.210155) (xy 314.876351 17.283061) (xy 314.928027 17.35149)
			(xy 314.985796 17.41486) (xy 315.049166 17.472629) (xy 315.117595 17.524305) (xy 315.190501 17.569446)
			(xy 315.267261 17.607668) (xy 315.34722 17.638644) (xy 315.429696 17.662111) (xy 315.513986 17.677867)
			(xy 315.599369 17.685779) (xy 315.685119 17.685779) (xy 315.770502 17.677867) (xy 315.854792 17.662111)
			(xy 315.937268 17.638644) (xy 316.017227 17.607668) (xy 316.093987 17.569446) (xy 316.166893 17.524305)
			(xy 316.235322 17.472629) (xy 316.298692 17.41486) (xy 316.356461 17.35149) (xy 316.408137 17.283061)
			(xy 316.453278 17.210155) (xy 316.4915 17.133395) (xy 316.522476 17.053436) (xy 316.545943 16.97096)
			(xy 316.561699 16.88667) (xy 316.569611 16.801287) (xy 316.570106 16.758412) (xy 316.569693 16.722649)
			(xy 334.455757 16.722649) (xy 334.455757 16.808399) (xy 334.463669 16.893782) (xy 334.479425 16.978072)
			(xy 334.502892 17.060548) (xy 334.533868 17.140507) (xy 334.57209 17.217267) (xy 334.617231 17.290173)
			(xy 334.668907 17.358602) (xy 334.726676 17.421972) (xy 334.790046 17.479741) (xy 334.858475 17.531417)
			(xy 334.931381 17.576558) (xy 335.008141 17.61478) (xy 335.0881 17.645756) (xy 335.170576 17.669223)
			(xy 335.254866 17.684979) (xy 335.340249 17.692891) (xy 335.425999 17.692891) (xy 335.511382 17.684979)
			(xy 335.595672 17.669223) (xy 335.678148 17.645756) (xy 335.758107 17.61478) (xy 335.78031 17.603724)
			(xy 339.390736 17.603724) (xy 339.390736 18.467324) (xy 339.391222 18.494593) (xy 339.398984 18.548577)
			(xy 339.414349 18.600907) (xy 339.437006 18.650517) (xy 339.466492 18.696398) (xy 339.502207 18.737615)
			(xy 339.543424 18.77333) (xy 339.589305 18.802816) (xy 339.638915 18.825473) (xy 339.691245 18.840838)
			(xy 339.745229 18.8486) (xy 339.799767 18.8486) (xy 339.853751 18.840838) (xy 339.906081 18.825473)
			(xy 339.955691 18.802816) (xy 340.001572 18.77333) (xy 340.042789 18.737615) (xy 340.078504 18.696398)
			(xy 340.10799 18.650517) (xy 340.130647 18.600907) (xy 340.146012 18.548577) (xy 340.153774 18.494593)
			(xy 340.15426 18.467324) (xy 340.15426 17.603724) (xy 340.153774 17.576455) (xy 340.146012 17.522471)
			(xy 340.130647 17.470141) (xy 340.10799 17.420531) (xy 340.078504 17.37465) (xy 340.042789 17.333433)
			(xy 340.001572 17.297718) (xy 339.955691 17.268232) (xy 339.906081 17.245575) (xy 339.853751 17.23021)
			(xy 339.799767 17.222448) (xy 339.745229 17.222448) (xy 339.691245 17.23021) (xy 339.638915 17.245575)
			(xy 339.589305 17.268232) (xy 339.543424 17.297718) (xy 339.502207 17.333433) (xy 339.466492 17.37465)
			(xy 339.437006 17.420531) (xy 339.414349 17.470141) (xy 339.398984 17.522471) (xy 339.391222 17.576455)
			(xy 339.390736 17.603724) (xy 335.78031 17.603724) (xy 335.834867 17.576558) (xy 335.907773 17.531417)
			(xy 335.976202 17.479741) (xy 336.039572 17.421972) (xy 336.097341 17.358602) (xy 336.149017 17.290173)
			(xy 336.194158 17.217267) (xy 336.23238 17.140507) (xy 336.263356 17.060548) (xy 336.286823 16.978072)
			(xy 336.302579 16.893782) (xy 336.310491 16.808399) (xy 336.310986 16.765524) (xy 336.310491 16.722649)
			(xy 340.805757 16.722649) (xy 340.805757 16.808399) (xy 340.813669 16.893782) (xy 340.829425 16.978072)
			(xy 340.852892 17.060548) (xy 340.883868 17.140507) (xy 340.92209 17.217267) (xy 340.967231 17.290173)
			(xy 341.018907 17.358602) (xy 341.076676 17.421972) (xy 341.140046 17.479741) (xy 341.208475 17.531417)
			(xy 341.281381 17.576558) (xy 341.358141 17.61478) (xy 341.4381 17.645756) (xy 341.520576 17.669223)
			(xy 341.604866 17.684979) (xy 341.690249 17.692891) (xy 341.775999 17.692891) (xy 341.861382 17.684979)
			(xy 341.945672 17.669223) (xy 342.028148 17.645756) (xy 342.108107 17.61478) (xy 342.184867 17.576558)
			(xy 342.257773 17.531417) (xy 342.326202 17.479741) (xy 342.389572 17.421972) (xy 342.447341 17.358602)
			(xy 342.499017 17.290173) (xy 342.544158 17.217267) (xy 342.58238 17.140507) (xy 342.613356 17.060548)
			(xy 342.636823 16.978072) (xy 342.652579 16.893782) (xy 342.660491 16.808399) (xy 342.660986 16.765524)
			(xy 342.660491 16.722649) (xy 342.659832 16.715537) (xy 373.515877 16.715537) (xy 373.515877 16.801287)
			(xy 373.523789 16.88667) (xy 373.539545 16.97096) (xy 373.563012 17.053436) (xy 373.593988 17.133395)
			(xy 373.63221 17.210155) (xy 373.677351 17.283061) (xy 373.729027 17.35149) (xy 373.786796 17.41486)
			(xy 373.850166 17.472629) (xy 373.918595 17.524305) (xy 373.991501 17.569446) (xy 374.068261 17.607668)
			(xy 374.14822 17.638644) (xy 374.230696 17.662111) (xy 374.314986 17.677867) (xy 374.400369 17.685779)
			(xy 374.486119 17.685779) (xy 374.571502 17.677867) (xy 374.655792 17.662111) (xy 374.738268 17.638644)
			(xy 374.818227 17.607668) (xy 374.84043 17.596612) (xy 376.022108 17.596612) (xy 376.022108 18.460212)
			(xy 376.022594 18.487481) (xy 376.030356 18.541465) (xy 376.045721 18.593795) (xy 376.068378 18.643405)
			(xy 376.097864 18.689286) (xy 376.133579 18.730503) (xy 376.174796 18.766218) (xy 376.220677 18.795704)
			(xy 376.270287 18.818361) (xy 376.322617 18.833726) (xy 376.376601 18.841488) (xy 376.431139 18.841488)
			(xy 376.485123 18.833726) (xy 376.537453 18.818361) (xy 376.587063 18.795704) (xy 376.632944 18.766218)
			(xy 376.674161 18.730503) (xy 376.709876 18.689286) (xy 376.739362 18.643405) (xy 376.762019 18.593795)
			(xy 376.777384 18.541465) (xy 376.785146 18.487481) (xy 376.785632 18.460212) (xy 376.785632 17.596612)
			(xy 376.785146 17.569343) (xy 376.777384 17.515359) (xy 376.762019 17.463029) (xy 376.739362 17.413419)
			(xy 376.709876 17.367538) (xy 376.674161 17.326321) (xy 376.632944 17.290606) (xy 376.587063 17.26112)
			(xy 376.537453 17.238463) (xy 376.485123 17.223098) (xy 376.431139 17.215336) (xy 376.376601 17.215336)
			(xy 376.322617 17.223098) (xy 376.270287 17.238463) (xy 376.220677 17.26112) (xy 376.174796 17.290606)
			(xy 376.133579 17.326321) (xy 376.097864 17.367538) (xy 376.068378 17.413419) (xy 376.045721 17.463029)
			(xy 376.030356 17.515359) (xy 376.022594 17.569343) (xy 376.022108 17.596612) (xy 374.84043 17.596612)
			(xy 374.894987 17.569446) (xy 374.967893 17.524305) (xy 375.036322 17.472629) (xy 375.099692 17.41486)
			(xy 375.157461 17.35149) (xy 375.209137 17.283061) (xy 375.254278 17.210155) (xy 375.2925 17.133395)
			(xy 375.323476 17.053436) (xy 375.346943 16.97096) (xy 375.362699 16.88667) (xy 375.370611 16.801287)
			(xy 375.371106 16.758412) (xy 375.370611 16.715537) (xy 379.865877 16.715537) (xy 379.865877 16.801287)
			(xy 379.873789 16.88667) (xy 379.889545 16.97096) (xy 379.913012 17.053436) (xy 379.943988 17.133395)
			(xy 379.98221 17.210155) (xy 380.027351 17.283061) (xy 380.079027 17.35149) (xy 380.136796 17.41486)
			(xy 380.200166 17.472629) (xy 380.268595 17.524305) (xy 380.341501 17.569446) (xy 380.418261 17.607668)
			(xy 380.49822 17.638644) (xy 380.580696 17.662111) (xy 380.664986 17.677867) (xy 380.750369 17.685779)
			(xy 380.836119 17.685779) (xy 380.921502 17.677867) (xy 381.005792 17.662111) (xy 381.088268 17.638644)
			(xy 381.168227 17.607668) (xy 381.244987 17.569446) (xy 381.317893 17.524305) (xy 381.386322 17.472629)
			(xy 381.449692 17.41486) (xy 381.507461 17.35149) (xy 381.559137 17.283061) (xy 381.604278 17.210155)
			(xy 381.6425 17.133395) (xy 381.673476 17.053436) (xy 381.696943 16.97096) (xy 381.712699 16.88667)
			(xy 381.720611 16.801287) (xy 381.721106 16.758412) (xy 381.720693 16.722649) (xy 399.098757 16.722649)
			(xy 399.098757 16.808399) (xy 399.106669 16.893782) (xy 399.122425 16.978072) (xy 399.145892 17.060548)
			(xy 399.176868 17.140507) (xy 399.21509 17.217267) (xy 399.260231 17.290173) (xy 399.311907 17.358602)
			(xy 399.369676 17.421972) (xy 399.433046 17.479741) (xy 399.501475 17.531417) (xy 399.574381 17.576558)
			(xy 399.651141 17.61478) (xy 399.7311 17.645756) (xy 399.813576 17.669223) (xy 399.897866 17.684979)
			(xy 399.983249 17.692891) (xy 400.068999 17.692891) (xy 400.154382 17.684979) (xy 400.238672 17.669223)
			(xy 400.321148 17.645756) (xy 400.401107 17.61478) (xy 400.42331 17.603724) (xy 404.033736 17.603724)
			(xy 404.033736 18.467324) (xy 404.034222 18.494593) (xy 404.041984 18.548577) (xy 404.057349 18.600907)
			(xy 404.080006 18.650517) (xy 404.109492 18.696398) (xy 404.145207 18.737615) (xy 404.186424 18.77333)
			(xy 404.232305 18.802816) (xy 404.281915 18.825473) (xy 404.334245 18.840838) (xy 404.388229 18.8486)
			(xy 404.442767 18.8486) (xy 404.496751 18.840838) (xy 404.549081 18.825473) (xy 404.598691 18.802816)
			(xy 404.644572 18.77333) (xy 404.685789 18.737615) (xy 404.721504 18.696398) (xy 404.75099 18.650517)
			(xy 404.773647 18.600907) (xy 404.789012 18.548577) (xy 404.796774 18.494593) (xy 404.79726 18.467324)
			(xy 404.79726 17.603724) (xy 404.796774 17.576455) (xy 404.789012 17.522471) (xy 404.773647 17.470141)
			(xy 404.75099 17.420531) (xy 404.721504 17.37465) (xy 404.685789 17.333433) (xy 404.644572 17.297718)
			(xy 404.598691 17.268232) (xy 404.549081 17.245575) (xy 404.496751 17.23021) (xy 404.442767 17.222448)
			(xy 404.388229 17.222448) (xy 404.334245 17.23021) (xy 404.281915 17.245575) (xy 404.232305 17.268232)
			(xy 404.186424 17.297718) (xy 404.145207 17.333433) (xy 404.109492 17.37465) (xy 404.080006 17.420531)
			(xy 404.057349 17.470141) (xy 404.041984 17.522471) (xy 404.034222 17.576455) (xy 404.033736 17.603724)
			(xy 400.42331 17.603724) (xy 400.477867 17.576558) (xy 400.550773 17.531417) (xy 400.619202 17.479741)
			(xy 400.682572 17.421972) (xy 400.740341 17.358602) (xy 400.792017 17.290173) (xy 400.837158 17.217267)
			(xy 400.87538 17.140507) (xy 400.906356 17.060548) (xy 400.929823 16.978072) (xy 400.945579 16.893782)
			(xy 400.953491 16.808399) (xy 400.953986 16.765524) (xy 400.953491 16.722649) (xy 405.448757 16.722649)
			(xy 405.448757 16.808399) (xy 405.456669 16.893782) (xy 405.472425 16.978072) (xy 405.495892 17.060548)
			(xy 405.526868 17.140507) (xy 405.56509 17.217267) (xy 405.610231 17.290173) (xy 405.661907 17.358602)
			(xy 405.719676 17.421972) (xy 405.783046 17.479741) (xy 405.851475 17.531417) (xy 405.924381 17.576558)
			(xy 406.001141 17.61478) (xy 406.0811 17.645756) (xy 406.163576 17.669223) (xy 406.247866 17.684979)
			(xy 406.333249 17.692891) (xy 406.418999 17.692891) (xy 406.504382 17.684979) (xy 406.588672 17.669223)
			(xy 406.671148 17.645756) (xy 406.751107 17.61478) (xy 406.827867 17.576558) (xy 406.900773 17.531417)
			(xy 406.969202 17.479741) (xy 407.032572 17.421972) (xy 407.090341 17.358602) (xy 407.142017 17.290173)
			(xy 407.187158 17.217267) (xy 407.22538 17.140507) (xy 407.256356 17.060548) (xy 407.279823 16.978072)
			(xy 407.295579 16.893782) (xy 407.303491 16.808399) (xy 407.303986 16.765524) (xy 407.303491 16.722649)
			(xy 407.302832 16.715537) (xy 438.158877 16.715537) (xy 438.158877 16.801287) (xy 438.166789 16.88667)
			(xy 438.182545 16.97096) (xy 438.206012 17.053436) (xy 438.236988 17.133395) (xy 438.27521 17.210155)
			(xy 438.320351 17.283061) (xy 438.372027 17.35149) (xy 438.429796 17.41486) (xy 438.493166 17.472629)
			(xy 438.561595 17.524305) (xy 438.634501 17.569446) (xy 438.711261 17.607668) (xy 438.79122 17.638644)
			(xy 438.873696 17.662111) (xy 438.957986 17.677867) (xy 439.043369 17.685779) (xy 439.129119 17.685779)
			(xy 439.214502 17.677867) (xy 439.298792 17.662111) (xy 439.381268 17.638644) (xy 439.461227 17.607668)
			(xy 439.48343 17.596612) (xy 440.665108 17.596612) (xy 440.665108 18.460212) (xy 440.665594 18.487481)
			(xy 440.673356 18.541465) (xy 440.688721 18.593795) (xy 440.711378 18.643405) (xy 440.740864 18.689286)
			(xy 440.776579 18.730503) (xy 440.817796 18.766218) (xy 440.863677 18.795704) (xy 440.913287 18.818361)
			(xy 440.965617 18.833726) (xy 441.019601 18.841488) (xy 441.074139 18.841488) (xy 441.128123 18.833726)
			(xy 441.180453 18.818361) (xy 441.230063 18.795704) (xy 441.275944 18.766218) (xy 441.317161 18.730503)
			(xy 441.352876 18.689286) (xy 441.382362 18.643405) (xy 441.405019 18.593795) (xy 441.420384 18.541465)
			(xy 441.428146 18.487481) (xy 441.428632 18.460212) (xy 441.428632 17.596612) (xy 441.428146 17.569343)
			(xy 441.420384 17.515359) (xy 441.405019 17.463029) (xy 441.382362 17.413419) (xy 441.352876 17.367538)
			(xy 441.317161 17.326321) (xy 441.275944 17.290606) (xy 441.230063 17.26112) (xy 441.180453 17.238463)
			(xy 441.128123 17.223098) (xy 441.074139 17.215336) (xy 441.019601 17.215336) (xy 440.965617 17.223098)
			(xy 440.913287 17.238463) (xy 440.863677 17.26112) (xy 440.817796 17.290606) (xy 440.776579 17.326321)
			(xy 440.740864 17.367538) (xy 440.711378 17.413419) (xy 440.688721 17.463029) (xy 440.673356 17.515359)
			(xy 440.665594 17.569343) (xy 440.665108 17.596612) (xy 439.48343 17.596612) (xy 439.537987 17.569446)
			(xy 439.610893 17.524305) (xy 439.679322 17.472629) (xy 439.742692 17.41486) (xy 439.800461 17.35149)
			(xy 439.852137 17.283061) (xy 439.897278 17.210155) (xy 439.9355 17.133395) (xy 439.966476 17.053436)
			(xy 439.989943 16.97096) (xy 440.005699 16.88667) (xy 440.013611 16.801287) (xy 440.014106 16.758412)
			(xy 440.013611 16.715537) (xy 444.508877 16.715537) (xy 444.508877 16.801287) (xy 444.516789 16.88667)
			(xy 444.532545 16.97096) (xy 444.556012 17.053436) (xy 444.586988 17.133395) (xy 444.62521 17.210155)
			(xy 444.670351 17.283061) (xy 444.722027 17.35149) (xy 444.779796 17.41486) (xy 444.843166 17.472629)
			(xy 444.911595 17.524305) (xy 444.984501 17.569446) (xy 445.061261 17.607668) (xy 445.14122 17.638644)
			(xy 445.223696 17.662111) (xy 445.307986 17.677867) (xy 445.393369 17.685779) (xy 445.479119 17.685779)
			(xy 445.564502 17.677867) (xy 445.648792 17.662111) (xy 445.731268 17.638644) (xy 445.811227 17.607668)
			(xy 445.887987 17.569446) (xy 445.960893 17.524305) (xy 446.029322 17.472629) (xy 446.092692 17.41486)
			(xy 446.150461 17.35149) (xy 446.202137 17.283061) (xy 446.247278 17.210155) (xy 446.2855 17.133395)
			(xy 446.316476 17.053436) (xy 446.339943 16.97096) (xy 446.355699 16.88667) (xy 446.363611 16.801287)
			(xy 446.364106 16.758412) (xy 446.363611 16.715537) (xy 446.355699 16.630154) (xy 446.339943 16.545864)
			(xy 446.316476 16.463388) (xy 446.2855 16.383429) (xy 446.247278 16.306669) (xy 446.202137 16.233763)
			(xy 446.150461 16.165334) (xy 446.092692 16.101964) (xy 446.029322 16.044195) (xy 445.960893 15.992519)
			(xy 445.887987 15.947378) (xy 445.811227 15.909156) (xy 445.731268 15.87818) (xy 445.648792 15.854713)
			(xy 445.564502 15.838957) (xy 445.479119 15.831045) (xy 445.393369 15.831045) (xy 445.307986 15.838957)
			(xy 445.223696 15.854713) (xy 445.14122 15.87818) (xy 445.061261 15.909156) (xy 444.984501 15.947378)
			(xy 444.911595 15.992519) (xy 444.843166 16.044195) (xy 444.779796 16.101964) (xy 444.722027 16.165334)
			(xy 444.670351 16.233763) (xy 444.62521 16.306669) (xy 444.586988 16.383429) (xy 444.556012 16.463388)
			(xy 444.532545 16.545864) (xy 444.516789 16.630154) (xy 444.508877 16.715537) (xy 440.013611 16.715537)
			(xy 440.005699 16.630154) (xy 439.989943 16.545864) (xy 439.966476 16.463388) (xy 439.9355 16.383429)
			(xy 439.897278 16.306669) (xy 439.852137 16.233763) (xy 439.800461 16.165334) (xy 439.742692 16.101964)
			(xy 439.679322 16.044195) (xy 439.610893 15.992519) (xy 439.537987 15.947378) (xy 439.461227 15.909156)
			(xy 439.381268 15.87818) (xy 439.298792 15.854713) (xy 439.214502 15.838957) (xy 439.129119 15.831045)
			(xy 439.043369 15.831045) (xy 438.957986 15.838957) (xy 438.873696 15.854713) (xy 438.79122 15.87818)
			(xy 438.711261 15.909156) (xy 438.634501 15.947378) (xy 438.561595 15.992519) (xy 438.493166 16.044195)
			(xy 438.429796 16.101964) (xy 438.372027 16.165334) (xy 438.320351 16.233763) (xy 438.27521 16.306669)
			(xy 438.236988 16.383429) (xy 438.206012 16.463388) (xy 438.182545 16.545864) (xy 438.166789 16.630154)
			(xy 438.158877 16.715537) (xy 407.302832 16.715537) (xy 407.295579 16.637266) (xy 407.279823 16.552976)
			(xy 407.256356 16.4705) (xy 407.22538 16.390541) (xy 407.187158 16.313781) (xy 407.142017 16.240875)
			(xy 407.090341 16.172446) (xy 407.032572 16.109076) (xy 406.969202 16.051307) (xy 406.900773 15.999631)
			(xy 406.827867 15.95449) (xy 406.751107 15.916268) (xy 406.671148 15.885292) (xy 406.588672 15.861825)
			(xy 406.504382 15.846069) (xy 406.418999 15.838157) (xy 406.333249 15.838157) (xy 406.247866 15.846069)
			(xy 406.163576 15.861825) (xy 406.0811 15.885292) (xy 406.001141 15.916268) (xy 405.924381 15.95449)
			(xy 405.851475 15.999631) (xy 405.783046 16.051307) (xy 405.719676 16.109076) (xy 405.661907 16.172446)
			(xy 405.610231 16.240875) (xy 405.56509 16.313781) (xy 405.526868 16.390541) (xy 405.495892 16.4705)
			(xy 405.472425 16.552976) (xy 405.456669 16.637266) (xy 405.448757 16.722649) (xy 400.953491 16.722649)
			(xy 400.945579 16.637266) (xy 400.929823 16.552976) (xy 400.906356 16.4705) (xy 400.87538 16.390541)
			(xy 400.837158 16.313781) (xy 400.792017 16.240875) (xy 400.740341 16.172446) (xy 400.682572 16.109076)
			(xy 400.619202 16.051307) (xy 400.550773 15.999631) (xy 400.477867 15.95449) (xy 400.401107 15.916268)
			(xy 400.321148 15.885292) (xy 400.238672 15.861825) (xy 400.154382 15.846069) (xy 400.068999 15.838157)
			(xy 399.983249 15.838157) (xy 399.897866 15.846069) (xy 399.813576 15.861825) (xy 399.7311 15.885292)
			(xy 399.651141 15.916268) (xy 399.574381 15.95449) (xy 399.501475 15.999631) (xy 399.433046 16.051307)
			(xy 399.369676 16.109076) (xy 399.311907 16.172446) (xy 399.260231 16.240875) (xy 399.21509 16.313781)
			(xy 399.176868 16.390541) (xy 399.145892 16.4705) (xy 399.122425 16.552976) (xy 399.106669 16.637266)
			(xy 399.098757 16.722649) (xy 381.720693 16.722649) (xy 381.720611 16.715537) (xy 381.712699 16.630154)
			(xy 381.696943 16.545864) (xy 381.673476 16.463388) (xy 381.6425 16.383429) (xy 381.604278 16.306669)
			(xy 381.559137 16.233763) (xy 381.507461 16.165334) (xy 381.449692 16.101964) (xy 381.386322 16.044195)
			(xy 381.317893 15.992519) (xy 381.244987 15.947378) (xy 381.168227 15.909156) (xy 381.088268 15.87818)
			(xy 381.005792 15.854713) (xy 380.921502 15.838957) (xy 380.836119 15.831045) (xy 380.750369 15.831045)
			(xy 380.664986 15.838957) (xy 380.580696 15.854713) (xy 380.49822 15.87818) (xy 380.418261 15.909156)
			(xy 380.341501 15.947378) (xy 380.268595 15.992519) (xy 380.200166 16.044195) (xy 380.136796 16.101964)
			(xy 380.079027 16.165334) (xy 380.027351 16.233763) (xy 379.98221 16.306669) (xy 379.943988 16.383429)
			(xy 379.913012 16.463388) (xy 379.889545 16.545864) (xy 379.873789 16.630154) (xy 379.865877 16.715537)
			(xy 375.370611 16.715537) (xy 375.362699 16.630154) (xy 375.346943 16.545864) (xy 375.323476 16.463388)
			(xy 375.2925 16.383429) (xy 375.254278 16.306669) (xy 375.209137 16.233763) (xy 375.157461 16.165334)
			(xy 375.099692 16.101964) (xy 375.036322 16.044195) (xy 374.967893 15.992519) (xy 374.894987 15.947378)
			(xy 374.818227 15.909156) (xy 374.738268 15.87818) (xy 374.655792 15.854713) (xy 374.571502 15.838957)
			(xy 374.486119 15.831045) (xy 374.400369 15.831045) (xy 374.314986 15.838957) (xy 374.230696 15.854713)
			(xy 374.14822 15.87818) (xy 374.068261 15.909156) (xy 373.991501 15.947378) (xy 373.918595 15.992519)
			(xy 373.850166 16.044195) (xy 373.786796 16.101964) (xy 373.729027 16.165334) (xy 373.677351 16.233763)
			(xy 373.63221 16.306669) (xy 373.593988 16.383429) (xy 373.563012 16.463388) (xy 373.539545 16.545864)
			(xy 373.523789 16.630154) (xy 373.515877 16.715537) (xy 342.659832 16.715537) (xy 342.652579 16.637266)
			(xy 342.636823 16.552976) (xy 342.613356 16.4705) (xy 342.58238 16.390541) (xy 342.544158 16.313781)
			(xy 342.499017 16.240875) (xy 342.447341 16.172446) (xy 342.389572 16.109076) (xy 342.326202 16.051307)
			(xy 342.257773 15.999631) (xy 342.184867 15.95449) (xy 342.108107 15.916268) (xy 342.028148 15.885292)
			(xy 341.945672 15.861825) (xy 341.861382 15.846069) (xy 341.775999 15.838157) (xy 341.690249 15.838157)
			(xy 341.604866 15.846069) (xy 341.520576 15.861825) (xy 341.4381 15.885292) (xy 341.358141 15.916268)
			(xy 341.281381 15.95449) (xy 341.208475 15.999631) (xy 341.140046 16.051307) (xy 341.076676 16.109076)
			(xy 341.018907 16.172446) (xy 340.967231 16.240875) (xy 340.92209 16.313781) (xy 340.883868 16.390541)
			(xy 340.852892 16.4705) (xy 340.829425 16.552976) (xy 340.813669 16.637266) (xy 340.805757 16.722649)
			(xy 336.310491 16.722649) (xy 336.302579 16.637266) (xy 336.286823 16.552976) (xy 336.263356 16.4705)
			(xy 336.23238 16.390541) (xy 336.194158 16.313781) (xy 336.149017 16.240875) (xy 336.097341 16.172446)
			(xy 336.039572 16.109076) (xy 335.976202 16.051307) (xy 335.907773 15.999631) (xy 335.834867 15.95449)
			(xy 335.758107 15.916268) (xy 335.678148 15.885292) (xy 335.595672 15.861825) (xy 335.511382 15.846069)
			(xy 335.425999 15.838157) (xy 335.340249 15.838157) (xy 335.254866 15.846069) (xy 335.170576 15.861825)
			(xy 335.0881 15.885292) (xy 335.008141 15.916268) (xy 334.931381 15.95449) (xy 334.858475 15.999631)
			(xy 334.790046 16.051307) (xy 334.726676 16.109076) (xy 334.668907 16.172446) (xy 334.617231 16.240875)
			(xy 334.57209 16.313781) (xy 334.533868 16.390541) (xy 334.502892 16.4705) (xy 334.479425 16.552976)
			(xy 334.463669 16.637266) (xy 334.455757 16.722649) (xy 316.569693 16.722649) (xy 316.569611 16.715537)
			(xy 316.561699 16.630154) (xy 316.545943 16.545864) (xy 316.522476 16.463388) (xy 316.4915 16.383429)
			(xy 316.453278 16.306669) (xy 316.408137 16.233763) (xy 316.356461 16.165334) (xy 316.298692 16.101964)
			(xy 316.235322 16.044195) (xy 316.166893 15.992519) (xy 316.093987 15.947378) (xy 316.017227 15.909156)
			(xy 315.937268 15.87818) (xy 315.854792 15.854713) (xy 315.770502 15.838957) (xy 315.685119 15.831045)
			(xy 315.599369 15.831045) (xy 315.513986 15.838957) (xy 315.429696 15.854713) (xy 315.34722 15.87818)
			(xy 315.267261 15.909156) (xy 315.190501 15.947378) (xy 315.117595 15.992519) (xy 315.049166 16.044195)
			(xy 314.985796 16.101964) (xy 314.928027 16.165334) (xy 314.876351 16.233763) (xy 314.83121 16.306669)
			(xy 314.792988 16.383429) (xy 314.762012 16.463388) (xy 314.738545 16.545864) (xy 314.722789 16.630154)
			(xy 314.714877 16.715537) (xy 310.219611 16.715537) (xy 310.211699 16.630154) (xy 310.195943 16.545864)
			(xy 310.172476 16.463388) (xy 310.1415 16.383429) (xy 310.103278 16.306669) (xy 310.058137 16.233763)
			(xy 310.006461 16.165334) (xy 309.948692 16.101964) (xy 309.885322 16.044195) (xy 309.816893 15.992519)
			(xy 309.743987 15.947378) (xy 309.667227 15.909156) (xy 309.587268 15.87818) (xy 309.504792 15.854713)
			(xy 309.420502 15.838957) (xy 309.335119 15.831045) (xy 309.249369 15.831045) (xy 309.163986 15.838957)
			(xy 309.079696 15.854713) (xy 308.99722 15.87818) (xy 308.917261 15.909156) (xy 308.840501 15.947378)
			(xy 308.767595 15.992519) (xy 308.699166 16.044195) (xy 308.635796 16.101964) (xy 308.578027 16.165334)
			(xy 308.526351 16.233763) (xy 308.48121 16.306669) (xy 308.442988 16.383429) (xy 308.412012 16.463388)
			(xy 308.388545 16.545864) (xy 308.372789 16.630154) (xy 308.364877 16.715537) (xy 277.508832 16.715537)
			(xy 277.501579 16.637266) (xy 277.485823 16.552976) (xy 277.462356 16.4705) (xy 277.43138 16.390541)
			(xy 277.393158 16.313781) (xy 277.348017 16.240875) (xy 277.296341 16.172446) (xy 277.238572 16.109076)
			(xy 277.175202 16.051307) (xy 277.106773 15.999631) (xy 277.033867 15.95449) (xy 276.957107 15.916268)
			(xy 276.877148 15.885292) (xy 276.794672 15.861825) (xy 276.710382 15.846069) (xy 276.624999 15.838157)
			(xy 276.539249 15.838157) (xy 276.453866 15.846069) (xy 276.369576 15.861825) (xy 276.2871 15.885292)
			(xy 276.207141 15.916268) (xy 276.130381 15.95449) (xy 276.057475 15.999631) (xy 275.989046 16.051307)
			(xy 275.925676 16.109076) (xy 275.867907 16.172446) (xy 275.816231 16.240875) (xy 275.77109 16.313781)
			(xy 275.732868 16.390541) (xy 275.701892 16.4705) (xy 275.678425 16.552976) (xy 275.662669 16.637266)
			(xy 275.654757 16.722649) (xy 271.159491 16.722649) (xy 271.151579 16.637266) (xy 271.135823 16.552976)
			(xy 271.112356 16.4705) (xy 271.08138 16.390541) (xy 271.043158 16.313781) (xy 270.998017 16.240875)
			(xy 270.946341 16.172446) (xy 270.888572 16.109076) (xy 270.825202 16.051307) (xy 270.756773 15.999631)
			(xy 270.683867 15.95449) (xy 270.607107 15.916268) (xy 270.527148 15.885292) (xy 270.444672 15.861825)
			(xy 270.360382 15.846069) (xy 270.274999 15.838157) (xy 270.189249 15.838157) (xy 270.103866 15.846069)
			(xy 270.019576 15.861825) (xy 269.9371 15.885292) (xy 269.857141 15.916268) (xy 269.780381 15.95449)
			(xy 269.707475 15.999631) (xy 269.639046 16.051307) (xy 269.575676 16.109076) (xy 269.517907 16.172446)
			(xy 269.466231 16.240875) (xy 269.42109 16.313781) (xy 269.382868 16.390541) (xy 269.351892 16.4705)
			(xy 269.328425 16.552976) (xy 269.312669 16.637266) (xy 269.304757 16.722649) (xy 252.231493 16.722649)
			(xy 252.231411 16.715537) (xy 252.223499 16.630154) (xy 252.207743 16.545864) (xy 252.184276 16.463388)
			(xy 252.1533 16.383429) (xy 252.115078 16.306669) (xy 252.069937 16.233763) (xy 252.018261 16.165334)
			(xy 251.960492 16.101964) (xy 251.897122 16.044195) (xy 251.828693 15.992519) (xy 251.755787 15.947378)
			(xy 251.679027 15.909156) (xy 251.599068 15.87818) (xy 251.516592 15.854713) (xy 251.432302 15.838957)
			(xy 251.346919 15.831045) (xy 251.261169 15.831045) (xy 251.175786 15.838957) (xy 251.091496 15.854713)
			(xy 251.00902 15.87818) (xy 250.929061 15.909156) (xy 250.852301 15.947378) (xy 250.779395 15.992519)
			(xy 250.710966 16.044195) (xy 250.647596 16.101964) (xy 250.589827 16.165334) (xy 250.538151 16.233763)
			(xy 250.49301 16.306669) (xy 250.454788 16.383429) (xy 250.423812 16.463388) (xy 250.400345 16.545864)
			(xy 250.384589 16.630154) (xy 250.376677 16.715537) (xy 245.881411 16.715537) (xy 245.873499 16.630154)
			(xy 245.857743 16.545864) (xy 245.834276 16.463388) (xy 245.8033 16.383429) (xy 245.765078 16.306669)
			(xy 245.719937 16.233763) (xy 245.668261 16.165334) (xy 245.610492 16.101964) (xy 245.547122 16.044195)
			(xy 245.478693 15.992519) (xy 245.405787 15.947378) (xy 245.329027 15.909156) (xy 245.249068 15.87818)
			(xy 245.166592 15.854713) (xy 245.082302 15.838957) (xy 244.996919 15.831045) (xy 244.911169 15.831045)
			(xy 244.825786 15.838957) (xy 244.741496 15.854713) (xy 244.65902 15.87818) (xy 244.579061 15.909156)
			(xy 244.502301 15.947378) (xy 244.429395 15.992519) (xy 244.360966 16.044195) (xy 244.297596 16.101964)
			(xy 244.239827 16.165334) (xy 244.188151 16.233763) (xy 244.14301 16.306669) (xy 244.104788 16.383429)
			(xy 244.073812 16.463388) (xy 244.050345 16.545864) (xy 244.034589 16.630154) (xy 244.026677 16.715537)
			(xy 218.199832 16.715537) (xy 218.192579 16.637266) (xy 218.176823 16.552976) (xy 218.153356 16.4705)
			(xy 218.12238 16.390541) (xy 218.084158 16.313781) (xy 218.039017 16.240875) (xy 217.987341 16.172446)
			(xy 217.929572 16.109076) (xy 217.866202 16.051307) (xy 217.797773 15.999631) (xy 217.724867 15.95449)
			(xy 217.648107 15.916268) (xy 217.568148 15.885292) (xy 217.485672 15.861825) (xy 217.401382 15.846069)
			(xy 217.315999 15.838157) (xy 217.230249 15.838157) (xy 217.144866 15.846069) (xy 217.060576 15.861825)
			(xy 216.9781 15.885292) (xy 216.898141 15.916268) (xy 216.821381 15.95449) (xy 216.748475 15.999631)
			(xy 216.680046 16.051307) (xy 216.616676 16.109076) (xy 216.558907 16.172446) (xy 216.507231 16.240875)
			(xy 216.46209 16.313781) (xy 216.423868 16.390541) (xy 216.392892 16.4705) (xy 216.369425 16.552976)
			(xy 216.353669 16.637266) (xy 216.345757 16.722649) (xy 211.850491 16.722649) (xy 211.842579 16.637266)
			(xy 211.826823 16.552976) (xy 211.803356 16.4705) (xy 211.77238 16.390541) (xy 211.734158 16.313781)
			(xy 211.689017 16.240875) (xy 211.637341 16.172446) (xy 211.579572 16.109076) (xy 211.516202 16.051307)
			(xy 211.447773 15.999631) (xy 211.374867 15.95449) (xy 211.298107 15.916268) (xy 211.218148 15.885292)
			(xy 211.135672 15.861825) (xy 211.051382 15.846069) (xy 210.965999 15.838157) (xy 210.880249 15.838157)
			(xy 210.794866 15.846069) (xy 210.710576 15.861825) (xy 210.6281 15.885292) (xy 210.548141 15.916268)
			(xy 210.471381 15.95449) (xy 210.398475 15.999631) (xy 210.330046 16.051307) (xy 210.266676 16.109076)
			(xy 210.208907 16.172446) (xy 210.157231 16.240875) (xy 210.11209 16.313781) (xy 210.073868 16.390541)
			(xy 210.042892 16.4705) (xy 210.019425 16.552976) (xy 210.003669 16.637266) (xy 209.995757 16.722649)
			(xy 158.621984 16.722649) (xy 158.621984 11.850929) (xy 251.524757 11.850929) (xy 251.524757 11.936679)
			(xy 251.532669 12.022062) (xy 251.548425 12.106352) (xy 251.571892 12.188828) (xy 251.602868 12.268787)
			(xy 251.64109 12.345547) (xy 251.686231 12.418453) (xy 251.737907 12.486882) (xy 251.795676 12.550252)
			(xy 251.859046 12.608021) (xy 251.927475 12.659697) (xy 252.000381 12.704838) (xy 252.077141 12.74306)
			(xy 252.1571 12.774036) (xy 252.239576 12.797503) (xy 252.323866 12.813259) (xy 252.409249 12.821171)
			(xy 252.494999 12.821171) (xy 252.580382 12.813259) (xy 252.664672 12.797503) (xy 252.747148 12.774036)
			(xy 252.827107 12.74306) (xy 252.903867 12.704838) (xy 252.976773 12.659697) (xy 253.045202 12.608021)
			(xy 253.108572 12.550252) (xy 253.166341 12.486882) (xy 253.218017 12.418453) (xy 253.263158 12.345547)
			(xy 253.30138 12.268787) (xy 253.332356 12.188828) (xy 253.355823 12.106352) (xy 253.371579 12.022062)
			(xy 253.379491 11.936679) (xy 253.379986 11.893804) (xy 253.379491 11.850929) (xy 257.874757 11.850929)
			(xy 257.874757 11.936679) (xy 257.882669 12.022062) (xy 257.898425 12.106352) (xy 257.921892 12.188828)
			(xy 257.952868 12.268787) (xy 257.99109 12.345547) (xy 258.036231 12.418453) (xy 258.087907 12.486882)
			(xy 258.145676 12.550252) (xy 258.209046 12.608021) (xy 258.277475 12.659697) (xy 258.350381 12.704838)
			(xy 258.427141 12.74306) (xy 258.5071 12.774036) (xy 258.589576 12.797503) (xy 258.673866 12.813259)
			(xy 258.759249 12.821171) (xy 258.844999 12.821171) (xy 258.930382 12.813259) (xy 259.014672 12.797503)
			(xy 259.097148 12.774036) (xy 259.177107 12.74306) (xy 259.253867 12.704838) (xy 259.326773 12.659697)
			(xy 259.395202 12.608021) (xy 259.458572 12.550252) (xy 259.516341 12.486882) (xy 259.568017 12.418453)
			(xy 259.613158 12.345547) (xy 259.65138 12.268787) (xy 259.682356 12.188828) (xy 259.705823 12.106352)
			(xy 259.721579 12.022062) (xy 259.729491 11.936679) (xy 259.729986 11.893804) (xy 259.72979 11.876837)
			(xy 309.725301 11.876837) (xy 309.725301 11.962587) (xy 309.733213 12.04797) (xy 309.748969 12.13226)
			(xy 309.772436 12.214736) (xy 309.803412 12.294695) (xy 309.841634 12.371455) (xy 309.886775 12.444361)
			(xy 309.938451 12.51279) (xy 309.99622 12.57616) (xy 310.05959 12.633929) (xy 310.128019 12.685605)
			(xy 310.200925 12.730746) (xy 310.277685 12.768968) (xy 310.357644 12.799944) (xy 310.44012 12.823411)
			(xy 310.52441 12.839167) (xy 310.609793 12.847079) (xy 310.695543 12.847079) (xy 310.780926 12.839167)
			(xy 310.865216 12.823411) (xy 310.947692 12.799944) (xy 311.027651 12.768968) (xy 311.104411 12.730746)
			(xy 311.177317 12.685605) (xy 311.245746 12.633929) (xy 311.309116 12.57616) (xy 311.366885 12.51279)
			(xy 311.418561 12.444361) (xy 311.463702 12.371455) (xy 311.501924 12.294695) (xy 311.5329 12.214736)
			(xy 311.556367 12.13226) (xy 311.572123 12.04797) (xy 311.580035 11.962587) (xy 311.58053 11.919712)
			(xy 311.580035 11.876837) (xy 316.075301 11.876837) (xy 316.075301 11.962587) (xy 316.083213 12.04797)
			(xy 316.098969 12.13226) (xy 316.122436 12.214736) (xy 316.153412 12.294695) (xy 316.191634 12.371455)
			(xy 316.236775 12.444361) (xy 316.288451 12.51279) (xy 316.34622 12.57616) (xy 316.40959 12.633929)
			(xy 316.478019 12.685605) (xy 316.550925 12.730746) (xy 316.627685 12.768968) (xy 316.707644 12.799944)
			(xy 316.79012 12.823411) (xy 316.87441 12.839167) (xy 316.959793 12.847079) (xy 317.045543 12.847079)
			(xy 317.130926 12.839167) (xy 317.215216 12.823411) (xy 317.297692 12.799944) (xy 317.377651 12.768968)
			(xy 317.454411 12.730746) (xy 317.527317 12.685605) (xy 317.595746 12.633929) (xy 317.659116 12.57616)
			(xy 317.716885 12.51279) (xy 317.768561 12.444361) (xy 317.813702 12.371455) (xy 317.851924 12.294695)
			(xy 317.8829 12.214736) (xy 317.906367 12.13226) (xy 317.922123 12.04797) (xy 317.930035 11.962587)
			(xy 317.93053 11.919712) (xy 317.930117 11.883949) (xy 324.295757 11.883949) (xy 324.295757 11.969699)
			(xy 324.303669 12.055082) (xy 324.319425 12.139372) (xy 324.342892 12.221848) (xy 324.373868 12.301807)
			(xy 324.41209 12.378567) (xy 324.457231 12.451473) (xy 324.508907 12.519902) (xy 324.566676 12.583272)
			(xy 324.630046 12.641041) (xy 324.698475 12.692717) (xy 324.771381 12.737858) (xy 324.848141 12.77608)
			(xy 324.9281 12.807056) (xy 325.010576 12.830523) (xy 325.094866 12.846279) (xy 325.180249 12.854191)
			(xy 325.265999 12.854191) (xy 325.351382 12.846279) (xy 325.435672 12.830523) (xy 325.518148 12.807056)
			(xy 325.598107 12.77608) (xy 325.674867 12.737858) (xy 325.747773 12.692717) (xy 325.816202 12.641041)
			(xy 325.879572 12.583272) (xy 325.937341 12.519902) (xy 325.989017 12.451473) (xy 326.034158 12.378567)
			(xy 326.07238 12.301807) (xy 326.103356 12.221848) (xy 326.126823 12.139372) (xy 326.142579 12.055082)
			(xy 326.150491 11.969699) (xy 326.150986 11.926824) (xy 326.150491 11.883949) (xy 330.645757 11.883949)
			(xy 330.645757 11.969699) (xy 330.653669 12.055082) (xy 330.669425 12.139372) (xy 330.692892 12.221848)
			(xy 330.723868 12.301807) (xy 330.76209 12.378567) (xy 330.807231 12.451473) (xy 330.858907 12.519902)
			(xy 330.916676 12.583272) (xy 330.980046 12.641041) (xy 331.048475 12.692717) (xy 331.121381 12.737858)
			(xy 331.198141 12.77608) (xy 331.2781 12.807056) (xy 331.360576 12.830523) (xy 331.444866 12.846279)
			(xy 331.530249 12.854191) (xy 331.615999 12.854191) (xy 331.701382 12.846279) (xy 331.785672 12.830523)
			(xy 331.868148 12.807056) (xy 331.948107 12.77608) (xy 332.024867 12.737858) (xy 332.097773 12.692717)
			(xy 332.166202 12.641041) (xy 332.229572 12.583272) (xy 332.287341 12.519902) (xy 332.339017 12.451473)
			(xy 332.384158 12.378567) (xy 332.42238 12.301807) (xy 332.453356 12.221848) (xy 332.476823 12.139372)
			(xy 332.492579 12.055082) (xy 332.500491 11.969699) (xy 332.500986 11.926824) (xy 332.50079 11.909857)
			(xy 382.496301 11.909857) (xy 382.496301 11.995607) (xy 382.504213 12.08099) (xy 382.519969 12.16528)
			(xy 382.543436 12.247756) (xy 382.574412 12.327715) (xy 382.612634 12.404475) (xy 382.657775 12.477381)
			(xy 382.709451 12.54581) (xy 382.76722 12.60918) (xy 382.83059 12.666949) (xy 382.899019 12.718625)
			(xy 382.971925 12.763766) (xy 383.048685 12.801988) (xy 383.128644 12.832964) (xy 383.21112 12.856431)
			(xy 383.29541 12.872187) (xy 383.380793 12.880099) (xy 383.466543 12.880099) (xy 383.551926 12.872187)
			(xy 383.636216 12.856431) (xy 383.718692 12.832964) (xy 383.798651 12.801988) (xy 383.875411 12.763766)
			(xy 383.948317 12.718625) (xy 384.016746 12.666949) (xy 384.080116 12.60918) (xy 384.137885 12.54581)
			(xy 384.189561 12.477381) (xy 384.234702 12.404475) (xy 384.272924 12.327715) (xy 384.3039 12.247756)
			(xy 384.327367 12.16528) (xy 384.343123 12.08099) (xy 384.351035 11.995607) (xy 384.35153 11.952732)
			(xy 384.351035 11.909857) (xy 388.846301 11.909857) (xy 388.846301 11.995607) (xy 388.854213 12.08099)
			(xy 388.869969 12.16528) (xy 388.893436 12.247756) (xy 388.924412 12.327715) (xy 388.962634 12.404475)
			(xy 389.007775 12.477381) (xy 389.059451 12.54581) (xy 389.11722 12.60918) (xy 389.18059 12.666949)
			(xy 389.249019 12.718625) (xy 389.321925 12.763766) (xy 389.398685 12.801988) (xy 389.478644 12.832964)
			(xy 389.56112 12.856431) (xy 389.64541 12.872187) (xy 389.730793 12.880099) (xy 389.816543 12.880099)
			(xy 389.901926 12.872187) (xy 389.986216 12.856431) (xy 390.068692 12.832964) (xy 390.148651 12.801988)
			(xy 390.225411 12.763766) (xy 390.298317 12.718625) (xy 390.366746 12.666949) (xy 390.430116 12.60918)
			(xy 390.487885 12.54581) (xy 390.539561 12.477381) (xy 390.584702 12.404475) (xy 390.622924 12.327715)
			(xy 390.6539 12.247756) (xy 390.677367 12.16528) (xy 390.693123 12.08099) (xy 390.701035 11.995607)
			(xy 390.70153 11.952732) (xy 390.701117 11.916969) (xy 396.558757 11.916969) (xy 396.558757 12.002719)
			(xy 396.566669 12.088102) (xy 396.582425 12.172392) (xy 396.605892 12.254868) (xy 396.636868 12.334827)
			(xy 396.67509 12.411587) (xy 396.720231 12.484493) (xy 396.771907 12.552922) (xy 396.829676 12.616292)
			(xy 396.893046 12.674061) (xy 396.961475 12.725737) (xy 397.034381 12.770878) (xy 397.111141 12.8091)
			(xy 397.1911 12.840076) (xy 397.273576 12.863543) (xy 397.357866 12.879299) (xy 397.443249 12.887211)
			(xy 397.528999 12.887211) (xy 397.614382 12.879299) (xy 397.698672 12.863543) (xy 397.781148 12.840076)
			(xy 397.861107 12.8091) (xy 397.937867 12.770878) (xy 398.010773 12.725737) (xy 398.079202 12.674061)
			(xy 398.142572 12.616292) (xy 398.200341 12.552922) (xy 398.252017 12.484493) (xy 398.297158 12.411587)
			(xy 398.33538 12.334827) (xy 398.366356 12.254868) (xy 398.389823 12.172392) (xy 398.405579 12.088102)
			(xy 398.413491 12.002719) (xy 398.413986 11.959844) (xy 398.413491 11.916969) (xy 402.908757 11.916969)
			(xy 402.908757 12.002719) (xy 402.916669 12.088102) (xy 402.932425 12.172392) (xy 402.955892 12.254868)
			(xy 402.986868 12.334827) (xy 403.02509 12.411587) (xy 403.070231 12.484493) (xy 403.121907 12.552922)
			(xy 403.179676 12.616292) (xy 403.243046 12.674061) (xy 403.311475 12.725737) (xy 403.384381 12.770878)
			(xy 403.461141 12.8091) (xy 403.5411 12.840076) (xy 403.623576 12.863543) (xy 403.707866 12.879299)
			(xy 403.793249 12.887211) (xy 403.878999 12.887211) (xy 403.964382 12.879299) (xy 404.048672 12.863543)
			(xy 404.131148 12.840076) (xy 404.211107 12.8091) (xy 404.287867 12.770878) (xy 404.360773 12.725737)
			(xy 404.429202 12.674061) (xy 404.492572 12.616292) (xy 404.550341 12.552922) (xy 404.602017 12.484493)
			(xy 404.647158 12.411587) (xy 404.68538 12.334827) (xy 404.716356 12.254868) (xy 404.739823 12.172392)
			(xy 404.755579 12.088102) (xy 404.763491 12.002719) (xy 404.763986 11.959844) (xy 404.76379 11.942877)
			(xy 454.759301 11.942877) (xy 454.759301 12.028627) (xy 454.767213 12.11401) (xy 454.782969 12.1983)
			(xy 454.806436 12.280776) (xy 454.837412 12.360735) (xy 454.875634 12.437495) (xy 454.920775 12.510401)
			(xy 454.972451 12.57883) (xy 455.03022 12.6422) (xy 455.09359 12.699969) (xy 455.162019 12.751645)
			(xy 455.234925 12.796786) (xy 455.311685 12.835008) (xy 455.391644 12.865984) (xy 455.47412 12.889451)
			(xy 455.55841 12.905207) (xy 455.643793 12.913119) (xy 455.729543 12.913119) (xy 455.814926 12.905207)
			(xy 455.899216 12.889451) (xy 455.981692 12.865984) (xy 456.061651 12.835008) (xy 456.138411 12.796786)
			(xy 456.211317 12.751645) (xy 456.279746 12.699969) (xy 456.343116 12.6422) (xy 456.400885 12.57883)
			(xy 456.452561 12.510401) (xy 456.497702 12.437495) (xy 456.535924 12.360735) (xy 456.5669 12.280776)
			(xy 456.590367 12.1983) (xy 456.606123 12.11401) (xy 456.614035 12.028627) (xy 456.61453 11.985752)
			(xy 456.614035 11.942877) (xy 461.109301 11.942877) (xy 461.109301 12.028627) (xy 461.117213 12.11401)
			(xy 461.132969 12.1983) (xy 461.156436 12.280776) (xy 461.187412 12.360735) (xy 461.225634 12.437495)
			(xy 461.270775 12.510401) (xy 461.322451 12.57883) (xy 461.38022 12.6422) (xy 461.44359 12.699969)
			(xy 461.512019 12.751645) (xy 461.584925 12.796786) (xy 461.661685 12.835008) (xy 461.741644 12.865984)
			(xy 461.82412 12.889451) (xy 461.90841 12.905207) (xy 461.993793 12.913119) (xy 462.079543 12.913119)
			(xy 462.164926 12.905207) (xy 462.249216 12.889451) (xy 462.331692 12.865984) (xy 462.411651 12.835008)
			(xy 462.488411 12.796786) (xy 462.561317 12.751645) (xy 462.629746 12.699969) (xy 462.693116 12.6422)
			(xy 462.750885 12.57883) (xy 462.802561 12.510401) (xy 462.847702 12.437495) (xy 462.885924 12.360735)
			(xy 462.9169 12.280776) (xy 462.940367 12.1983) (xy 462.956123 12.11401) (xy 462.964035 12.028627)
			(xy 462.96453 11.985752) (xy 462.964035 11.942877) (xy 462.956123 11.857494) (xy 462.940367 11.773204)
			(xy 462.9169 11.690728) (xy 462.885924 11.610769) (xy 462.847702 11.534009) (xy 462.802561 11.461103)
			(xy 462.750885 11.392674) (xy 462.693116 11.329304) (xy 462.629746 11.271535) (xy 462.561317 11.219859)
			(xy 462.488411 11.174718) (xy 462.411651 11.136496) (xy 462.331692 11.10552) (xy 462.249216 11.082053)
			(xy 462.164926 11.066297) (xy 462.079543 11.058385) (xy 461.993793 11.058385) (xy 461.90841 11.066297)
			(xy 461.82412 11.082053) (xy 461.741644 11.10552) (xy 461.661685 11.136496) (xy 461.584925 11.174718)
			(xy 461.512019 11.219859) (xy 461.44359 11.271535) (xy 461.38022 11.329304) (xy 461.322451 11.392674)
			(xy 461.270775 11.461103) (xy 461.225634 11.534009) (xy 461.187412 11.610769) (xy 461.156436 11.690728)
			(xy 461.132969 11.773204) (xy 461.117213 11.857494) (xy 461.109301 11.942877) (xy 456.614035 11.942877)
			(xy 456.606123 11.857494) (xy 456.590367 11.773204) (xy 456.5669 11.690728) (xy 456.535924 11.610769)
			(xy 456.497702 11.534009) (xy 456.452561 11.461103) (xy 456.400885 11.392674) (xy 456.343116 11.329304)
			(xy 456.279746 11.271535) (xy 456.211317 11.219859) (xy 456.138411 11.174718) (xy 456.061651 11.136496)
			(xy 455.981692 11.10552) (xy 455.899216 11.082053) (xy 455.814926 11.066297) (xy 455.729543 11.058385)
			(xy 455.643793 11.058385) (xy 455.55841 11.066297) (xy 455.47412 11.082053) (xy 455.391644 11.10552)
			(xy 455.311685 11.136496) (xy 455.234925 11.174718) (xy 455.162019 11.219859) (xy 455.09359 11.271535)
			(xy 455.03022 11.329304) (xy 454.972451 11.392674) (xy 454.920775 11.461103) (xy 454.875634 11.534009)
			(xy 454.837412 11.610769) (xy 454.806436 11.690728) (xy 454.782969 11.773204) (xy 454.767213 11.857494)
			(xy 454.759301 11.942877) (xy 404.76379 11.942877) (xy 404.763491 11.916969) (xy 404.755579 11.831586)
			(xy 404.739823 11.747296) (xy 404.716356 11.66482) (xy 404.68538 11.584861) (xy 404.647158 11.508101)
			(xy 404.602017 11.435195) (xy 404.550341 11.366766) (xy 404.492572 11.303396) (xy 404.429202 11.245627)
			(xy 404.360773 11.193951) (xy 404.287867 11.14881) (xy 404.211107 11.110588) (xy 404.131148 11.079612)
			(xy 404.048672 11.056145) (xy 403.964382 11.040389) (xy 403.878999 11.032477) (xy 403.793249 11.032477)
			(xy 403.707866 11.040389) (xy 403.623576 11.056145) (xy 403.5411 11.079612) (xy 403.461141 11.110588)
			(xy 403.384381 11.14881) (xy 403.311475 11.193951) (xy 403.243046 11.245627) (xy 403.179676 11.303396)
			(xy 403.121907 11.366766) (xy 403.070231 11.435195) (xy 403.02509 11.508101) (xy 402.986868 11.584861)
			(xy 402.955892 11.66482) (xy 402.932425 11.747296) (xy 402.916669 11.831586) (xy 402.908757 11.916969)
			(xy 398.413491 11.916969) (xy 398.405579 11.831586) (xy 398.389823 11.747296) (xy 398.366356 11.66482)
			(xy 398.33538 11.584861) (xy 398.297158 11.508101) (xy 398.252017 11.435195) (xy 398.200341 11.366766)
			(xy 398.142572 11.303396) (xy 398.079202 11.245627) (xy 398.010773 11.193951) (xy 397.937867 11.14881)
			(xy 397.861107 11.110588) (xy 397.781148 11.079612) (xy 397.698672 11.056145) (xy 397.614382 11.040389)
			(xy 397.528999 11.032477) (xy 397.443249 11.032477) (xy 397.357866 11.040389) (xy 397.273576 11.056145)
			(xy 397.1911 11.079612) (xy 397.111141 11.110588) (xy 397.034381 11.14881) (xy 396.961475 11.193951)
			(xy 396.893046 11.245627) (xy 396.829676 11.303396) (xy 396.771907 11.366766) (xy 396.720231 11.435195)
			(xy 396.67509 11.508101) (xy 396.636868 11.584861) (xy 396.605892 11.66482) (xy 396.582425 11.747296)
			(xy 396.566669 11.831586) (xy 396.558757 11.916969) (xy 390.701117 11.916969) (xy 390.701035 11.909857)
			(xy 390.693123 11.824474) (xy 390.677367 11.740184) (xy 390.6539 11.657708) (xy 390.622924 11.577749)
			(xy 390.584702 11.500989) (xy 390.539561 11.428083) (xy 390.487885 11.359654) (xy 390.430116 11.296284)
			(xy 390.366746 11.238515) (xy 390.298317 11.186839) (xy 390.225411 11.141698) (xy 390.148651 11.103476)
			(xy 390.068692 11.0725) (xy 389.986216 11.049033) (xy 389.901926 11.033277) (xy 389.816543 11.025365)
			(xy 389.730793 11.025365) (xy 389.64541 11.033277) (xy 389.56112 11.049033) (xy 389.478644 11.0725)
			(xy 389.398685 11.103476) (xy 389.321925 11.141698) (xy 389.249019 11.186839) (xy 389.18059 11.238515)
			(xy 389.11722 11.296284) (xy 389.059451 11.359654) (xy 389.007775 11.428083) (xy 388.962634 11.500989)
			(xy 388.924412 11.577749) (xy 388.893436 11.657708) (xy 388.869969 11.740184) (xy 388.854213 11.824474)
			(xy 388.846301 11.909857) (xy 384.351035 11.909857) (xy 384.343123 11.824474) (xy 384.327367 11.740184)
			(xy 384.3039 11.657708) (xy 384.272924 11.577749) (xy 384.234702 11.500989) (xy 384.189561 11.428083)
			(xy 384.137885 11.359654) (xy 384.080116 11.296284) (xy 384.016746 11.238515) (xy 383.948317 11.186839)
			(xy 383.875411 11.141698) (xy 383.798651 11.103476) (xy 383.718692 11.0725) (xy 383.636216 11.049033)
			(xy 383.551926 11.033277) (xy 383.466543 11.025365) (xy 383.380793 11.025365) (xy 383.29541 11.033277)
			(xy 383.21112 11.049033) (xy 383.128644 11.0725) (xy 383.048685 11.103476) (xy 382.971925 11.141698)
			(xy 382.899019 11.186839) (xy 382.83059 11.238515) (xy 382.76722 11.296284) (xy 382.709451 11.359654)
			(xy 382.657775 11.428083) (xy 382.612634 11.500989) (xy 382.574412 11.577749) (xy 382.543436 11.657708)
			(xy 382.519969 11.740184) (xy 382.504213 11.824474) (xy 382.496301 11.909857) (xy 332.50079 11.909857)
			(xy 332.500491 11.883949) (xy 332.492579 11.798566) (xy 332.476823 11.714276) (xy 332.453356 11.6318)
			(xy 332.42238 11.551841) (xy 332.384158 11.475081) (xy 332.339017 11.402175) (xy 332.287341 11.333746)
			(xy 332.229572 11.270376) (xy 332.166202 11.212607) (xy 332.097773 11.160931) (xy 332.024867 11.11579)
			(xy 331.948107 11.077568) (xy 331.868148 11.046592) (xy 331.785672 11.023125) (xy 331.701382 11.007369)
			(xy 331.615999 10.999457) (xy 331.530249 10.999457) (xy 331.444866 11.007369) (xy 331.360576 11.023125)
			(xy 331.2781 11.046592) (xy 331.198141 11.077568) (xy 331.121381 11.11579) (xy 331.048475 11.160931)
			(xy 330.980046 11.212607) (xy 330.916676 11.270376) (xy 330.858907 11.333746) (xy 330.807231 11.402175)
			(xy 330.76209 11.475081) (xy 330.723868 11.551841) (xy 330.692892 11.6318) (xy 330.669425 11.714276)
			(xy 330.653669 11.798566) (xy 330.645757 11.883949) (xy 326.150491 11.883949) (xy 326.142579 11.798566)
			(xy 326.126823 11.714276) (xy 326.103356 11.6318) (xy 326.07238 11.551841) (xy 326.034158 11.475081)
			(xy 325.989017 11.402175) (xy 325.937341 11.333746) (xy 325.879572 11.270376) (xy 325.816202 11.212607)
			(xy 325.747773 11.160931) (xy 325.674867 11.11579) (xy 325.598107 11.077568) (xy 325.518148 11.046592)
			(xy 325.435672 11.023125) (xy 325.351382 11.007369) (xy 325.265999 10.999457) (xy 325.180249 10.999457)
			(xy 325.094866 11.007369) (xy 325.010576 11.023125) (xy 324.9281 11.046592) (xy 324.848141 11.077568)
			(xy 324.771381 11.11579) (xy 324.698475 11.160931) (xy 324.630046 11.212607) (xy 324.566676 11.270376)
			(xy 324.508907 11.333746) (xy 324.457231 11.402175) (xy 324.41209 11.475081) (xy 324.373868 11.551841)
			(xy 324.342892 11.6318) (xy 324.319425 11.714276) (xy 324.303669 11.798566) (xy 324.295757 11.883949)
			(xy 317.930117 11.883949) (xy 317.930035 11.876837) (xy 317.922123 11.791454) (xy 317.906367 11.707164)
			(xy 317.8829 11.624688) (xy 317.851924 11.544729) (xy 317.813702 11.467969) (xy 317.768561 11.395063)
			(xy 317.716885 11.326634) (xy 317.659116 11.263264) (xy 317.595746 11.205495) (xy 317.527317 11.153819)
			(xy 317.454411 11.108678) (xy 317.377651 11.070456) (xy 317.297692 11.03948) (xy 317.215216 11.016013)
			(xy 317.130926 11.000257) (xy 317.045543 10.992345) (xy 316.959793 10.992345) (xy 316.87441 11.000257)
			(xy 316.79012 11.016013) (xy 316.707644 11.03948) (xy 316.627685 11.070456) (xy 316.550925 11.108678)
			(xy 316.478019 11.153819) (xy 316.40959 11.205495) (xy 316.34622 11.263264) (xy 316.288451 11.326634)
			(xy 316.236775 11.395063) (xy 316.191634 11.467969) (xy 316.153412 11.544729) (xy 316.122436 11.624688)
			(xy 316.098969 11.707164) (xy 316.083213 11.791454) (xy 316.075301 11.876837) (xy 311.580035 11.876837)
			(xy 311.572123 11.791454) (xy 311.556367 11.707164) (xy 311.5329 11.624688) (xy 311.501924 11.544729)
			(xy 311.463702 11.467969) (xy 311.418561 11.395063) (xy 311.366885 11.326634) (xy 311.309116 11.263264)
			(xy 311.245746 11.205495) (xy 311.177317 11.153819) (xy 311.104411 11.108678) (xy 311.027651 11.070456)
			(xy 310.947692 11.03948) (xy 310.865216 11.016013) (xy 310.780926 11.000257) (xy 310.695543 10.992345)
			(xy 310.609793 10.992345) (xy 310.52441 11.000257) (xy 310.44012 11.016013) (xy 310.357644 11.03948)
			(xy 310.277685 11.070456) (xy 310.200925 11.108678) (xy 310.128019 11.153819) (xy 310.05959 11.205495)
			(xy 309.99622 11.263264) (xy 309.938451 11.326634) (xy 309.886775 11.395063) (xy 309.841634 11.467969)
			(xy 309.803412 11.544729) (xy 309.772436 11.624688) (xy 309.748969 11.707164) (xy 309.733213 11.791454)
			(xy 309.725301 11.876837) (xy 259.72979 11.876837) (xy 259.729491 11.850929) (xy 259.721579 11.765546)
			(xy 259.705823 11.681256) (xy 259.682356 11.59878) (xy 259.65138 11.518821) (xy 259.613158 11.442061)
			(xy 259.568017 11.369155) (xy 259.516341 11.300726) (xy 259.458572 11.237356) (xy 259.395202 11.179587)
			(xy 259.326773 11.127911) (xy 259.253867 11.08277) (xy 259.177107 11.044548) (xy 259.097148 11.013572)
			(xy 259.014672 10.990105) (xy 258.930382 10.974349) (xy 258.844999 10.966437) (xy 258.759249 10.966437)
			(xy 258.673866 10.974349) (xy 258.589576 10.990105) (xy 258.5071 11.013572) (xy 258.427141 11.044548)
			(xy 258.350381 11.08277) (xy 258.277475 11.127911) (xy 258.209046 11.179587) (xy 258.145676 11.237356)
			(xy 258.087907 11.300726) (xy 258.036231 11.369155) (xy 257.99109 11.442061) (xy 257.952868 11.518821)
			(xy 257.921892 11.59878) (xy 257.898425 11.681256) (xy 257.882669 11.765546) (xy 257.874757 11.850929)
			(xy 253.379491 11.850929) (xy 253.371579 11.765546) (xy 253.355823 11.681256) (xy 253.332356 11.59878)
			(xy 253.30138 11.518821) (xy 253.263158 11.442061) (xy 253.218017 11.369155) (xy 253.166341 11.300726)
			(xy 253.108572 11.237356) (xy 253.045202 11.179587) (xy 252.976773 11.127911) (xy 252.903867 11.08277)
			(xy 252.827107 11.044548) (xy 252.747148 11.013572) (xy 252.664672 10.990105) (xy 252.580382 10.974349)
			(xy 252.494999 10.966437) (xy 252.409249 10.966437) (xy 252.323866 10.974349) (xy 252.239576 10.990105)
			(xy 252.1571 11.013572) (xy 252.077141 11.044548) (xy 252.000381 11.08277) (xy 251.927475 11.127911)
			(xy 251.859046 11.179587) (xy 251.795676 11.237356) (xy 251.737907 11.300726) (xy 251.686231 11.369155)
			(xy 251.64109 11.442061) (xy 251.602868 11.518821) (xy 251.571892 11.59878) (xy 251.548425 11.681256)
			(xy 251.532669 11.765546) (xy 251.524757 11.850929) (xy 158.621984 11.850929) (xy 158.621984 9.310929)
			(xy 179.515757 9.310929) (xy 179.515757 9.396679) (xy 179.523669 9.482062) (xy 179.539425 9.566352)
			(xy 179.562892 9.648828) (xy 179.593868 9.728787) (xy 179.63209 9.805547) (xy 179.677231 9.878453)
			(xy 179.728907 9.946882) (xy 179.786676 10.010252) (xy 179.850046 10.068021) (xy 179.918475 10.119697)
			(xy 179.991381 10.164838) (xy 180.068141 10.20306) (xy 180.1481 10.234036) (xy 180.230576 10.257503)
			(xy 180.314866 10.273259) (xy 180.400249 10.281171) (xy 180.485999 10.281171) (xy 180.571382 10.273259)
			(xy 180.655672 10.257503) (xy 180.738148 10.234036) (xy 180.818107 10.20306) (xy 180.894867 10.164838)
			(xy 180.967773 10.119697) (xy 181.036202 10.068021) (xy 181.099572 10.010252) (xy 181.157341 9.946882)
			(xy 181.209017 9.878453) (xy 181.254158 9.805547) (xy 181.29238 9.728787) (xy 181.323356 9.648828)
			(xy 181.346823 9.566352) (xy 181.362579 9.482062) (xy 181.370491 9.396679) (xy 181.370986 9.353804)
			(xy 181.370491 9.310929) (xy 185.865757 9.310929) (xy 185.865757 9.396679) (xy 185.873669 9.482062)
			(xy 185.889425 9.566352) (xy 185.912892 9.648828) (xy 185.943868 9.728787) (xy 185.98209 9.805547)
			(xy 186.027231 9.878453) (xy 186.078907 9.946882) (xy 186.136676 10.010252) (xy 186.200046 10.068021)
			(xy 186.268475 10.119697) (xy 186.341381 10.164838) (xy 186.418141 10.20306) (xy 186.4981 10.234036)
			(xy 186.580576 10.257503) (xy 186.664866 10.273259) (xy 186.750249 10.281171) (xy 186.835999 10.281171)
			(xy 186.921382 10.273259) (xy 187.005672 10.257503) (xy 187.088148 10.234036) (xy 187.168107 10.20306)
			(xy 187.244867 10.164838) (xy 187.317773 10.119697) (xy 187.386202 10.068021) (xy 187.449572 10.010252)
			(xy 187.507341 9.946882) (xy 187.559017 9.878453) (xy 187.604158 9.805547) (xy 187.64238 9.728787)
			(xy 187.673356 9.648828) (xy 187.696823 9.566352) (xy 187.712579 9.482062) (xy 187.720491 9.396679)
			(xy 187.720986 9.353804) (xy 187.720491 9.310929) (xy 187.719832 9.303817) (xy 237.716301 9.303817)
			(xy 237.716301 9.389567) (xy 237.724213 9.47495) (xy 237.739969 9.55924) (xy 237.763436 9.641716)
			(xy 237.794412 9.721675) (xy 237.832634 9.798435) (xy 237.877775 9.871341) (xy 237.929451 9.93977)
			(xy 237.98722 10.00314) (xy 238.05059 10.060909) (xy 238.119019 10.112585) (xy 238.191925 10.157726)
			(xy 238.268685 10.195948) (xy 238.348644 10.226924) (xy 238.43112 10.250391) (xy 238.51541 10.266147)
			(xy 238.600793 10.274059) (xy 238.686543 10.274059) (xy 238.771926 10.266147) (xy 238.856216 10.250391)
			(xy 238.938692 10.226924) (xy 239.018651 10.195948) (xy 239.095411 10.157726) (xy 239.168317 10.112585)
			(xy 239.236746 10.060909) (xy 239.300116 10.00314) (xy 239.357885 9.93977) (xy 239.409561 9.871341)
			(xy 239.454702 9.798435) (xy 239.492924 9.721675) (xy 239.5239 9.641716) (xy 239.547367 9.55924)
			(xy 239.563123 9.47495) (xy 239.571035 9.389567) (xy 239.57153 9.346692) (xy 239.571035 9.303817)
			(xy 244.066301 9.303817) (xy 244.066301 9.389567) (xy 244.074213 9.47495) (xy 244.089969 9.55924)
			(xy 244.113436 9.641716) (xy 244.144412 9.721675) (xy 244.182634 9.798435) (xy 244.227775 9.871341)
			(xy 244.279451 9.93977) (xy 244.33722 10.00314) (xy 244.40059 10.060909) (xy 244.469019 10.112585)
			(xy 244.541925 10.157726) (xy 244.618685 10.195948) (xy 244.698644 10.226924) (xy 244.78112 10.250391)
			(xy 244.86541 10.266147) (xy 244.950793 10.274059) (xy 245.036543 10.274059) (xy 245.121926 10.266147)
			(xy 245.206216 10.250391) (xy 245.288692 10.226924) (xy 245.368651 10.195948) (xy 245.445411 10.157726)
			(xy 245.518317 10.112585) (xy 245.586746 10.060909) (xy 245.650116 10.00314) (xy 245.707885 9.93977)
			(xy 245.759561 9.871341) (xy 245.804702 9.798435) (xy 245.842924 9.721675) (xy 245.8739 9.641716)
			(xy 245.897367 9.55924) (xy 245.913123 9.47495) (xy 245.921035 9.389567) (xy 245.92153 9.346692)
			(xy 245.921117 9.310929) (xy 251.524757 9.310929) (xy 251.524757 9.396679) (xy 251.532669 9.482062)
			(xy 251.548425 9.566352) (xy 251.571892 9.648828) (xy 251.602868 9.728787) (xy 251.64109 9.805547)
			(xy 251.686231 9.878453) (xy 251.737907 9.946882) (xy 251.795676 10.010252) (xy 251.859046 10.068021)
			(xy 251.927475 10.119697) (xy 252.000381 10.164838) (xy 252.077141 10.20306) (xy 252.1571 10.234036)
			(xy 252.239576 10.257503) (xy 252.323866 10.273259) (xy 252.409249 10.281171) (xy 252.494999 10.281171)
			(xy 252.580382 10.273259) (xy 252.664672 10.257503) (xy 252.747148 10.234036) (xy 252.827107 10.20306)
			(xy 252.903867 10.164838) (xy 252.976773 10.119697) (xy 253.035743 10.075164) (xy 255.683512 10.075164)
			(xy 255.683512 11.172444) (xy 255.683927 11.184523) (xy 255.691404 11.207495) (xy 255.705613 11.227033)
			(xy 255.725162 11.241225) (xy 255.748141 11.248683) (xy 255.76022 11.249152) (xy 256.37236 11.249152)
			(xy 256.380616 11.248982) (xy 256.39676 11.245516) (xy 256.404364 11.242294) (xy 256.412492 11.238484)
			(xy 256.430272 11.23696) (xy 256.510282 11.25855) (xy 256.52476 11.26871) (xy 256.52984 11.275822)
			(xy 256.545261 11.296827) (xy 256.580858 11.334882) (xy 256.6213 11.367741) (xy 256.665837 11.394793)
			(xy 256.71364 11.415534) (xy 256.76382 11.42958) (xy 256.815444 11.436669) (xy 256.841498 11.437112)
			(xy 256.868754 11.436575) (xy 256.92271 11.428821) (xy 256.975016 11.413472) (xy 257.024606 11.390838)
			(xy 257.070472 11.36138) (xy 257.111682 11.325698) (xy 257.147397 11.284517) (xy 257.176891 11.238674)
			(xy 257.199564 11.189103) (xy 257.214956 11.13681) (xy 257.222753 11.082859) (xy 257.22326 11.055604)
			(xy 257.22326 10.192004) (xy 257.22284 10.164738) (xy 257.215076 10.11076) (xy 257.199705 10.058438)
			(xy 257.177041 10.008838) (xy 257.147545 9.96297) (xy 257.111819 9.92177) (xy 257.070591 9.886076)
			(xy 257.0247 9.856616) (xy 256.975082 9.833991) (xy 256.922748 9.818661) (xy 256.868765 9.810939)
			(xy 256.841498 9.810496) (xy 256.815444 9.81096) (xy 256.763821 9.818047) (xy 256.713641 9.83209)
			(xy 256.665838 9.852827) (xy 256.621299 9.879873) (xy 256.580852 9.912725) (xy 256.54525 9.950773)
			(xy 256.52984 9.971786) (xy 256.52476 9.978898) (xy 256.510282 9.989058) (xy 256.430272 10.010648)
			(xy 256.412492 10.009124) (xy 256.404364 10.005314) (xy 256.39676 10.002097) (xy 256.380615 9.998644)
			(xy 256.37236 9.998456) (xy 255.76022 9.998456) (xy 255.74815 9.998981) (xy 255.72519 10.006433)
			(xy 255.705655 10.020615) (xy 255.691459 10.040139) (xy 255.683989 10.063094) (xy 255.683512 10.075164)
			(xy 253.035743 10.075164) (xy 253.045202 10.068021) (xy 253.108572 10.010252) (xy 253.166341 9.946882)
			(xy 253.218017 9.878453) (xy 253.263158 9.805547) (xy 253.30138 9.728787) (xy 253.332356 9.648828)
			(xy 253.355823 9.566352) (xy 253.371579 9.482062) (xy 253.379491 9.396679) (xy 253.379986 9.353804)
			(xy 253.379491 9.310929) (xy 257.874757 9.310929) (xy 257.874757 9.396679) (xy 257.882669 9.482062)
			(xy 257.898425 9.566352) (xy 257.921892 9.648828) (xy 257.952868 9.728787) (xy 257.99109 9.805547)
			(xy 258.036231 9.878453) (xy 258.087907 9.946882) (xy 258.145676 10.010252) (xy 258.209046 10.068021)
			(xy 258.277475 10.119697) (xy 258.350381 10.164838) (xy 258.427141 10.20306) (xy 258.5071 10.234036)
			(xy 258.589576 10.257503) (xy 258.673866 10.273259) (xy 258.759249 10.281171) (xy 258.844999 10.281171)
			(xy 258.930382 10.273259) (xy 259.014672 10.257503) (xy 259.097148 10.234036) (xy 259.177107 10.20306)
			(xy 259.253867 10.164838) (xy 259.326773 10.119697) (xy 259.395202 10.068021) (xy 259.458572 10.010252)
			(xy 259.516341 9.946882) (xy 259.568017 9.878453) (xy 259.613158 9.805547) (xy 259.65138 9.728787)
			(xy 259.682356 9.648828) (xy 259.705823 9.566352) (xy 259.721579 9.482062) (xy 259.729491 9.396679)
			(xy 259.729986 9.353804) (xy 259.72979 9.336837) (xy 309.725301 9.336837) (xy 309.725301 9.422587)
			(xy 309.733213 9.50797) (xy 309.748969 9.59226) (xy 309.772436 9.674736) (xy 309.803412 9.754695)
			(xy 309.841634 9.831455) (xy 309.886775 9.904361) (xy 309.938451 9.97279) (xy 309.99622 10.03616)
			(xy 310.05959 10.093929) (xy 310.128019 10.145605) (xy 310.200925 10.190746) (xy 310.277685 10.228968)
			(xy 310.357644 10.259944) (xy 310.44012 10.283411) (xy 310.52441 10.299167) (xy 310.609793 10.307079)
			(xy 310.695543 10.307079) (xy 310.780926 10.299167) (xy 310.865216 10.283411) (xy 310.947692 10.259944)
			(xy 311.027651 10.228968) (xy 311.049854 10.217912) (xy 312.231532 10.217912) (xy 312.231532 11.081512)
			(xy 312.231945 11.108779) (xy 312.239711 11.162756) (xy 312.255083 11.215077) (xy 312.277749 11.264677)
			(xy 312.307245 11.310544) (xy 312.342972 11.351745) (xy 312.384201 11.387438) (xy 312.430092 11.416898)
			(xy 312.47971 11.439524) (xy 312.532044 11.454854) (xy 312.586027 11.462577) (xy 312.613294 11.46302)
			(xy 312.639347 11.462543) (xy 312.69097 11.455457) (xy 312.741149 11.441416) (xy 312.788952 11.420681)
			(xy 312.833491 11.393637) (xy 312.873938 11.360787) (xy 312.909541 11.322741) (xy 312.924952 11.30173)
			(xy 312.930032 11.294618) (xy 312.94451 11.284458) (xy 313.02452 11.262868) (xy 313.0423 11.264392)
			(xy 313.050428 11.268202) (xy 313.058035 11.271412) (xy 313.074177 11.27487) (xy 313.082432 11.27506)
			(xy 313.694572 11.27506) (xy 313.706658 11.274663) (xy 313.729648 11.267197) (xy 313.749203 11.252989)
			(xy 313.763406 11.23343) (xy 313.770866 11.210438) (xy 313.77128 11.198352) (xy 313.77128 10.101072)
			(xy 313.770859 10.088993) (xy 313.763386 10.06602) (xy 313.749179 10.046481) (xy 313.72963 10.032289)
			(xy 313.706651 10.024832) (xy 313.694572 10.024364) (xy 313.082432 10.024364) (xy 313.074177 10.024561)
			(xy 313.058034 10.028009) (xy 313.050428 10.031222) (xy 313.0423 10.035032) (xy 313.02452 10.036556)
			(xy 312.94451 10.014966) (xy 312.930032 10.004806) (xy 312.924952 9.997694) (xy 312.909531 9.976688)
			(xy 312.873935 9.938633) (xy 312.833492 9.905774) (xy 312.788956 9.878722) (xy 312.741153 9.85798)
			(xy 312.690973 9.843935) (xy 312.639348 9.836847) (xy 312.613294 9.836404) (xy 312.586038 9.836918)
			(xy 312.532079 9.844673) (xy 312.479772 9.860024) (xy 312.430181 9.88266) (xy 312.384314 9.91212)
			(xy 312.343104 9.947805) (xy 312.307389 9.988988) (xy 312.277896 10.034834) (xy 312.255223 10.084408)
			(xy 312.239833 10.136703) (xy 312.232038 10.190656) (xy 312.231532 10.217912) (xy 311.049854 10.217912)
			(xy 311.104411 10.190746) (xy 311.177317 10.145605) (xy 311.245746 10.093929) (xy 311.309116 10.03616)
			(xy 311.366885 9.97279) (xy 311.418561 9.904361) (xy 311.463702 9.831455) (xy 311.501924 9.754695)
			(xy 311.5329 9.674736) (xy 311.556367 9.59226) (xy 311.572123 9.50797) (xy 311.580035 9.422587) (xy 311.58053 9.379712)
			(xy 311.580035 9.336837) (xy 316.075301 9.336837) (xy 316.075301 9.422587) (xy 316.083213 9.50797)
			(xy 316.098969 9.59226) (xy 316.122436 9.674736) (xy 316.153412 9.754695) (xy 316.191634 9.831455)
			(xy 316.236775 9.904361) (xy 316.288451 9.97279) (xy 316.34622 10.03616) (xy 316.40959 10.093929)
			(xy 316.478019 10.145605) (xy 316.550925 10.190746) (xy 316.627685 10.228968) (xy 316.707644 10.259944)
			(xy 316.79012 10.283411) (xy 316.87441 10.299167) (xy 316.959793 10.307079) (xy 317.045543 10.307079)
			(xy 317.130926 10.299167) (xy 317.215216 10.283411) (xy 317.297692 10.259944) (xy 317.377651 10.228968)
			(xy 317.454411 10.190746) (xy 317.527317 10.145605) (xy 317.595746 10.093929) (xy 317.659116 10.03616)
			(xy 317.716885 9.97279) (xy 317.768561 9.904361) (xy 317.813702 9.831455) (xy 317.851924 9.754695)
			(xy 317.8829 9.674736) (xy 317.906367 9.59226) (xy 317.922123 9.50797) (xy 317.930035 9.422587) (xy 317.93053 9.379712)
			(xy 317.930117 9.343949) (xy 324.295757 9.343949) (xy 324.295757 9.429699) (xy 324.303669 9.515082)
			(xy 324.319425 9.599372) (xy 324.342892 9.681848) (xy 324.373868 9.761807) (xy 324.41209 9.838567)
			(xy 324.457231 9.911473) (xy 324.508907 9.979902) (xy 324.566676 10.043272) (xy 324.630046 10.101041)
			(xy 324.698475 10.152717) (xy 324.771381 10.197858) (xy 324.848141 10.23608) (xy 324.9281 10.267056)
			(xy 325.010576 10.290523) (xy 325.094866 10.306279) (xy 325.180249 10.314191) (xy 325.265999 10.314191)
			(xy 325.351382 10.306279) (xy 325.435672 10.290523) (xy 325.518148 10.267056) (xy 325.598107 10.23608)
			(xy 325.674867 10.197858) (xy 325.747773 10.152717) (xy 325.806743 10.108184) (xy 328.454512 10.108184)
			(xy 328.454512 11.205464) (xy 328.454944 11.217547) (xy 328.462404 11.240532) (xy 328.476604 11.260084)
			(xy 328.496154 11.274289) (xy 328.519137 11.281754) (xy 328.53122 11.282172) (xy 329.14336 11.282172)
			(xy 329.151617 11.282009) (xy 329.16776 11.278539) (xy 329.175364 11.275314) (xy 329.183492 11.271504)
			(xy 329.201272 11.26998) (xy 329.281282 11.29157) (xy 329.29576 11.30173) (xy 329.30084 11.308842)
			(xy 329.316255 11.329852) (xy 329.351854 11.367906) (xy 329.392298 11.400763) (xy 329.436835 11.427814)
			(xy 329.484639 11.448555) (xy 329.534819 11.4626) (xy 329.586444 11.469689) (xy 329.612498 11.470132)
			(xy 329.639757 11.469675) (xy 329.693721 11.461919) (xy 329.746033 11.446565) (xy 329.795628 11.423926)
			(xy 329.841498 11.394461) (xy 329.88271 11.35877) (xy 329.918425 11.317579) (xy 329.947917 11.271727)
			(xy 329.970586 11.222145) (xy 329.985971 11.169842) (xy 329.993758 11.115883) (xy 329.99426 11.088624)
			(xy 329.99426 10.225024) (xy 329.993821 10.197758) (xy 329.98606 10.143781) (xy 329.970692 10.09146)
			(xy 329.94803 10.04186) (xy 329.918536 9.995992) (xy 329.882812 9.954791) (xy 329.841585 9.919097)
			(xy 329.795696 9.889637) (xy 329.746079 9.867011) (xy 329.693747 9.851681) (xy 329.639764 9.843959)
			(xy 329.612498 9.843516) (xy 329.586444 9.843972) (xy 329.53482 9.851059) (xy 329.48464 9.865103)
			(xy 329.436836 9.885841) (xy 329.392297 9.912888) (xy 329.351851 9.945743) (xy 329.316249 9.983793)
			(xy 329.30084 10.004806) (xy 329.29576 10.011918) (xy 329.281282 10.022078) (xy 329.201272 10.043668)
			(xy 329.183492 10.042144) (xy 329.175364 10.038334) (xy 329.167759 10.035118) (xy 329.151615 10.031665)
			(xy 329.14336 10.031476) (xy 328.53122 10.031476) (xy 328.51914 10.03193) (xy 328.496161 10.03939)
			(xy 328.476611 10.053586) (xy 328.462406 10.073128) (xy 328.454935 10.096104) (xy 328.454512 10.108184)
			(xy 325.806743 10.108184) (xy 325.816202 10.101041) (xy 325.879572 10.043272) (xy 325.937341 9.979902)
			(xy 325.989017 9.911473) (xy 326.034158 9.838567) (xy 326.07238 9.761807) (xy 326.103356 9.681848)
			(xy 326.126823 9.599372) (xy 326.142579 9.515082) (xy 326.150491 9.429699) (xy 326.150986 9.386824)
			(xy 326.150491 9.343949) (xy 330.645757 9.343949) (xy 330.645757 9.429699) (xy 330.653669 9.515082)
			(xy 330.669425 9.599372) (xy 330.692892 9.681848) (xy 330.723868 9.761807) (xy 330.76209 9.838567)
			(xy 330.807231 9.911473) (xy 330.858907 9.979902) (xy 330.916676 10.043272) (xy 330.980046 10.101041)
			(xy 331.048475 10.152717) (xy 331.121381 10.197858) (xy 331.198141 10.23608) (xy 331.2781 10.267056)
			(xy 331.360576 10.290523) (xy 331.444866 10.306279) (xy 331.530249 10.314191) (xy 331.615999 10.314191)
			(xy 331.701382 10.306279) (xy 331.785672 10.290523) (xy 331.868148 10.267056) (xy 331.948107 10.23608)
			(xy 332.024867 10.197858) (xy 332.097773 10.152717) (xy 332.166202 10.101041) (xy 332.229572 10.043272)
			(xy 332.287341 9.979902) (xy 332.339017 9.911473) (xy 332.384158 9.838567) (xy 332.42238 9.761807)
			(xy 332.453356 9.681848) (xy 332.476823 9.599372) (xy 332.492579 9.515082) (xy 332.500491 9.429699)
			(xy 332.500986 9.386824) (xy 332.50079 9.369857) (xy 382.496301 9.369857) (xy 382.496301 9.455607)
			(xy 382.504213 9.54099) (xy 382.519969 9.62528) (xy 382.543436 9.707756) (xy 382.574412 9.787715)
			(xy 382.612634 9.864475) (xy 382.657775 9.937381) (xy 382.709451 10.00581) (xy 382.76722 10.06918)
			(xy 382.83059 10.126949) (xy 382.899019 10.178625) (xy 382.971925 10.223766) (xy 383.048685 10.261988)
			(xy 383.128644 10.292964) (xy 383.21112 10.316431) (xy 383.29541 10.332187) (xy 383.380793 10.340099)
			(xy 383.466543 10.340099) (xy 383.551926 10.332187) (xy 383.636216 10.316431) (xy 383.718692 10.292964)
			(xy 383.798651 10.261988) (xy 383.820854 10.250932) (xy 385.002532 10.250932) (xy 385.002532 11.114532)
			(xy 385.002926 11.141799) (xy 385.010695 11.195777) (xy 385.02607 11.248099) (xy 385.048738 11.297699)
			(xy 385.078236 11.343566) (xy 385.113965 11.384766) (xy 385.155195 11.420459) (xy 385.201088 11.449919)
			(xy 385.250707 11.472544) (xy 385.303042 11.487874) (xy 385.357027 11.495597) (xy 385.384294 11.49604)
			(xy 385.410349 11.495597) (xy 385.461974 11.488509) (xy 385.512155 11.474465) (xy 385.55996 11.453725)
			(xy 385.604499 11.426675) (xy 385.644944 11.393818) (xy 385.680544 11.355765) (xy 385.695952 11.33475)
			(xy 385.701032 11.327638) (xy 385.71551 11.317478) (xy 385.79552 11.295888) (xy 385.8133 11.297412)
			(xy 385.821428 11.301222) (xy 385.829035 11.304434) (xy 385.845177 11.30789) (xy 385.853432 11.30808)
			(xy 386.465572 11.30808) (xy 386.477656 11.307663) (xy 386.500643 11.3002) (xy 386.520196 11.285996)
			(xy 386.5344 11.266443) (xy 386.541863 11.243456) (xy 386.54228 11.231372) (xy 386.54228 10.134092)
			(xy 386.541894 10.122006) (xy 386.534421 10.099018) (xy 386.520209 10.079466) (xy 386.500649 10.065263)
			(xy 386.477658 10.0578) (xy 386.465572 10.057384) (xy 385.853432 10.057384) (xy 385.845177 10.057579)
			(xy 385.829034 10.061028) (xy 385.821428 10.064242) (xy 385.8133 10.068052) (xy 385.79552 10.069576)
			(xy 385.71551 10.047986) (xy 385.701032 10.037826) (xy 385.695952 10.030714) (xy 385.680555 10.009691)
			(xy 385.644952 9.971639) (xy 385.604504 9.938784) (xy 385.559963 9.911736) (xy 385.512158 9.890997)
			(xy 385.461975 9.876954) (xy 385.410349 9.869867) (xy 385.384294 9.869424) (xy 385.357037 9.869918)
			(xy 385.303076 9.877673) (xy 385.250768 9.893026) (xy 385.201176 9.915663) (xy 385.155308 9.945125)
			(xy 385.114097 9.980812) (xy 385.078382 10.021998) (xy 385.048889 10.067846) (xy 385.026218 10.117422)
			(xy 385.010829 10.16972) (xy 385.003037 10.223675) (xy 385.002532 10.250932) (xy 383.820854 10.250932)
			(xy 383.875411 10.223766) (xy 383.948317 10.178625) (xy 384.016746 10.126949) (xy 384.080116 10.06918)
			(xy 384.137885 10.00581) (xy 384.189561 9.937381) (xy 384.234702 9.864475) (xy 384.272924 9.787715)
			(xy 384.3039 9.707756) (xy 384.327367 9.62528) (xy 384.343123 9.54099) (xy 384.351035 9.455607) (xy 384.35153 9.412732)
			(xy 384.351035 9.369857) (xy 388.846301 9.369857) (xy 388.846301 9.455607) (xy 388.854213 9.54099)
			(xy 388.869969 9.62528) (xy 388.893436 9.707756) (xy 388.924412 9.787715) (xy 388.962634 9.864475)
			(xy 389.007775 9.937381) (xy 389.059451 10.00581) (xy 389.11722 10.06918) (xy 389.18059 10.126949)
			(xy 389.249019 10.178625) (xy 389.321925 10.223766) (xy 389.398685 10.261988) (xy 389.478644 10.292964)
			(xy 389.56112 10.316431) (xy 389.64541 10.332187) (xy 389.730793 10.340099) (xy 389.816543 10.340099)
			(xy 389.901926 10.332187) (xy 389.986216 10.316431) (xy 390.068692 10.292964) (xy 390.148651 10.261988)
			(xy 390.225411 10.223766) (xy 390.298317 10.178625) (xy 390.366746 10.126949) (xy 390.430116 10.06918)
			(xy 390.487885 10.00581) (xy 390.539561 9.937381) (xy 390.584702 9.864475) (xy 390.622924 9.787715)
			(xy 390.6539 9.707756) (xy 390.677367 9.62528) (xy 390.693123 9.54099) (xy 390.701035 9.455607) (xy 390.70153 9.412732)
			(xy 390.701117 9.376969) (xy 396.558757 9.376969) (xy 396.558757 9.462719) (xy 396.566669 9.548102)
			(xy 396.582425 9.632392) (xy 396.605892 9.714868) (xy 396.636868 9.794827) (xy 396.67509 9.871587)
			(xy 396.720231 9.944493) (xy 396.771907 10.012922) (xy 396.829676 10.076292) (xy 396.893046 10.134061)
			(xy 396.961475 10.185737) (xy 397.034381 10.230878) (xy 397.111141 10.2691) (xy 397.1911 10.300076)
			(xy 397.273576 10.323543) (xy 397.357866 10.339299) (xy 397.443249 10.347211) (xy 397.528999 10.347211)
			(xy 397.614382 10.339299) (xy 397.698672 10.323543) (xy 397.781148 10.300076) (xy 397.861107 10.2691)
			(xy 397.937867 10.230878) (xy 398.010773 10.185737) (xy 398.069743 10.141204) (xy 400.717512 10.141204)
			(xy 400.717512 11.238484) (xy 400.717927 11.250568) (xy 400.725392 11.273553) (xy 400.739597 11.293106)
			(xy 400.75915 11.30731) (xy 400.782136 11.314774) (xy 400.79422 11.315192) (xy 401.40636 11.315192)
			(xy 401.414617 11.315028) (xy 401.43076 11.311558) (xy 401.438364 11.308334) (xy 401.446492 11.304524)
			(xy 401.464272 11.303) (xy 401.544282 11.32459) (xy 401.55876 11.33475) (xy 401.56384 11.341862)
			(xy 401.579249 11.362876) (xy 401.614849 11.400929) (xy 401.655295 11.433786) (xy 401.699833 11.460836)
			(xy 401.747637 11.481576) (xy 401.797818 11.49562) (xy 401.849443 11.502709) (xy 401.875498 11.503152)
			(xy 401.902756 11.502675) (xy 401.956718 11.494919) (xy 402.009028 11.479567) (xy 402.058622 11.456929)
			(xy 402.104491 11.427466) (xy 402.145703 11.391777) (xy 402.181418 11.350589) (xy 402.21091 11.304739)
			(xy 402.233581 11.255159) (xy 402.248967 11.202859) (xy 402.256757 11.148902) (xy 402.25726 11.121644)
			(xy 402.25726 10.258044) (xy 402.256803 10.230779) (xy 402.249044 10.176802) (xy 402.233678 10.124481)
			(xy 402.211019 10.074881) (xy 402.181527 10.029013) (xy 402.145805 9.987812) (xy 402.10458 9.952118)
			(xy 402.058692 9.922657) (xy 402.009077 9.900031) (xy 401.956745 9.884701) (xy 401.902764 9.876979)
			(xy 401.875498 9.876536) (xy 401.849443 9.876983) (xy 401.797819 9.884071) (xy 401.747638 9.898116)
			(xy 401.699834 9.918855) (xy 401.655295 9.945904) (xy 401.614849 9.97876) (xy 401.579249 10.016812)
			(xy 401.56384 10.037826) (xy 401.55876 10.044938) (xy 401.544282 10.055098) (xy 401.464272 10.076688)
			(xy 401.446492 10.075164) (xy 401.438364 10.071354) (xy 401.430759 10.068139) (xy 401.414615 10.064685)
			(xy 401.40636 10.064496) (xy 400.79422 10.064496) (xy 400.782138 10.06493) (xy 400.759155 10.072392)
			(xy 400.739604 10.086593) (xy 400.7254 10.106141) (xy 400.717932 10.129122) (xy 400.717512 10.141204)
			(xy 398.069743 10.141204) (xy 398.079202 10.134061) (xy 398.142572 10.076292) (xy 398.200341 10.012922)
			(xy 398.252017 9.944493) (xy 398.297158 9.871587) (xy 398.33538 9.794827) (xy 398.366356 9.714868)
			(xy 398.389823 9.632392) (xy 398.405579 9.548102) (xy 398.413491 9.462719) (xy 398.413986 9.419844)
			(xy 398.413491 9.376969) (xy 402.908757 9.376969) (xy 402.908757 9.462719) (xy 402.916669 9.548102)
			(xy 402.932425 9.632392) (xy 402.955892 9.714868) (xy 402.986868 9.794827) (xy 403.02509 9.871587)
			(xy 403.070231 9.944493) (xy 403.121907 10.012922) (xy 403.179676 10.076292) (xy 403.243046 10.134061)
			(xy 403.311475 10.185737) (xy 403.384381 10.230878) (xy 403.461141 10.2691) (xy 403.5411 10.300076)
			(xy 403.623576 10.323543) (xy 403.707866 10.339299) (xy 403.793249 10.347211) (xy 403.878999 10.347211)
			(xy 403.964382 10.339299) (xy 404.048672 10.323543) (xy 404.131148 10.300076) (xy 404.211107 10.2691)
			(xy 404.287867 10.230878) (xy 404.360773 10.185737) (xy 404.429202 10.134061) (xy 404.492572 10.076292)
			(xy 404.550341 10.012922) (xy 404.602017 9.944493) (xy 404.647158 9.871587) (xy 404.68538 9.794827)
			(xy 404.716356 9.714868) (xy 404.739823 9.632392) (xy 404.755579 9.548102) (xy 404.763491 9.462719)
			(xy 404.763986 9.419844) (xy 404.76379 9.402877) (xy 454.759301 9.402877) (xy 454.759301 9.488627)
			(xy 454.767213 9.57401) (xy 454.782969 9.6583) (xy 454.806436 9.740776) (xy 454.837412 9.820735)
			(xy 454.875634 9.897495) (xy 454.920775 9.970401) (xy 454.972451 10.03883) (xy 455.03022 10.1022)
			(xy 455.09359 10.159969) (xy 455.162019 10.211645) (xy 455.234925 10.256786) (xy 455.311685 10.295008)
			(xy 455.391644 10.325984) (xy 455.47412 10.349451) (xy 455.55841 10.365207) (xy 455.643793 10.373119)
			(xy 455.729543 10.373119) (xy 455.814926 10.365207) (xy 455.899216 10.349451) (xy 455.981692 10.325984)
			(xy 456.061651 10.295008) (xy 456.083854 10.283952) (xy 457.265532 10.283952) (xy 457.265532 11.147552)
			(xy 457.266001 11.174817) (xy 457.273759 11.228792) (xy 457.289124 11.281113) (xy 457.311782 11.330712)
			(xy 457.341272 11.37658) (xy 457.376993 11.417781) (xy 457.418217 11.453475) (xy 457.464104 11.482936)
			(xy 457.513718 11.505562) (xy 457.566048 11.520893) (xy 457.620029 11.528617) (xy 457.647294 11.52906)
			(xy 457.673348 11.528609) (xy 457.724973 11.521521) (xy 457.775154 11.507478) (xy 457.822958 11.486739)
			(xy 457.867497 11.459691) (xy 457.907943 11.426836) (xy 457.943543 11.388784) (xy 457.958952 11.36777)
			(xy 457.964032 11.360658) (xy 457.97851 11.350498) (xy 458.05852 11.328908) (xy 458.0763 11.330432)
			(xy 458.084428 11.334242) (xy 458.092034 11.337455) (xy 458.108177 11.340911) (xy 458.116432 11.3411)
			(xy 458.728572 11.3411) (xy 458.740654 11.340663) (xy 458.763637 11.333202) (xy 458.783189 11.319003)
			(xy 458.797393 11.299455) (xy 458.80486 11.276474) (xy 458.80528 11.264392) (xy 458.80528 10.167112)
			(xy 458.804876 10.155027) (xy 458.797409 10.13204) (xy 458.783201 10.112487) (xy 458.763646 10.098284)
			(xy 458.740657 10.090821) (xy 458.728572 10.090404) (xy 458.116432 10.090404) (xy 458.108177 10.090597)
			(xy 458.092033 10.094047) (xy 458.084428 10.097262) (xy 458.0763 10.101072) (xy 458.05852 10.102596)
			(xy 457.97851 10.081006) (xy 457.964032 10.070846) (xy 457.958952 10.063734) (xy 457.943549 10.042715)
			(xy 457.907948 10.004663) (xy 457.867501 9.971806) (xy 457.822962 9.944757) (xy 457.775156 9.924018)
			(xy 457.724975 9.909974) (xy 457.673349 9.902887) (xy 457.647294 9.902444) (xy 457.620036 9.902918)
			(xy 457.566074 9.910674) (xy 457.513764 9.926028) (xy 457.46417 9.948666) (xy 457.418301 9.97813)
			(xy 457.37709 10.013819) (xy 457.341375 10.055007) (xy 457.311883 10.100857) (xy 457.289212 10.150437)
			(xy 457.273826 10.202737) (xy 457.266035 10.256694) (xy 457.265532 10.283952) (xy 456.083854 10.283952)
			(xy 456.138411 10.256786) (xy 456.211317 10.211645) (xy 456.279746 10.159969) (xy 456.343116 10.1022)
			(xy 456.400885 10.03883) (xy 456.452561 9.970401) (xy 456.497702 9.897495) (xy 456.535924 9.820735)
			(xy 456.5669 9.740776) (xy 456.590367 9.6583) (xy 456.606123 9.57401) (xy 456.614035 9.488627) (xy 456.61453 9.445752)
			(xy 456.614035 9.402877) (xy 461.109301 9.402877) (xy 461.109301 9.488627) (xy 461.117213 9.57401)
			(xy 461.132969 9.6583) (xy 461.156436 9.740776) (xy 461.187412 9.820735) (xy 461.225634 9.897495)
			(xy 461.270775 9.970401) (xy 461.322451 10.03883) (xy 461.38022 10.1022) (xy 461.44359 10.159969)
			(xy 461.512019 10.211645) (xy 461.584925 10.256786) (xy 461.661685 10.295008) (xy 461.741644 10.325984)
			(xy 461.82412 10.349451) (xy 461.90841 10.365207) (xy 461.993793 10.373119) (xy 462.079543 10.373119)
			(xy 462.164926 10.365207) (xy 462.249216 10.349451) (xy 462.331692 10.325984) (xy 462.411651 10.295008)
			(xy 462.488411 10.256786) (xy 462.561317 10.211645) (xy 462.629746 10.159969) (xy 462.693116 10.1022)
			(xy 462.750885 10.03883) (xy 462.802561 9.970401) (xy 462.847702 9.897495) (xy 462.885924 9.820735)
			(xy 462.9169 9.740776) (xy 462.940367 9.6583) (xy 462.956123 9.57401) (xy 462.964035 9.488627) (xy 462.96453 9.445752)
			(xy 462.964035 9.402877) (xy 462.956123 9.317494) (xy 462.940367 9.233204) (xy 462.9169 9.150728)
			(xy 462.885924 9.070769) (xy 462.847702 8.994009) (xy 462.802561 8.921103) (xy 462.750885 8.852674)
			(xy 462.693116 8.789304) (xy 462.629746 8.731535) (xy 462.561317 8.679859) (xy 462.488411 8.634718)
			(xy 462.411651 8.596496) (xy 462.331692 8.56552) (xy 462.249216 8.542053) (xy 462.164926 8.526297)
			(xy 462.079543 8.518385) (xy 461.993793 8.518385) (xy 461.90841 8.526297) (xy 461.82412 8.542053)
			(xy 461.741644 8.56552) (xy 461.661685 8.596496) (xy 461.584925 8.634718) (xy 461.512019 8.679859)
			(xy 461.44359 8.731535) (xy 461.38022 8.789304) (xy 461.322451 8.852674) (xy 461.270775 8.921103)
			(xy 461.225634 8.994009) (xy 461.187412 9.070769) (xy 461.156436 9.150728) (xy 461.132969 9.233204)
			(xy 461.117213 9.317494) (xy 461.109301 9.402877) (xy 456.614035 9.402877) (xy 456.606123 9.317494)
			(xy 456.590367 9.233204) (xy 456.5669 9.150728) (xy 456.535924 9.070769) (xy 456.497702 8.994009)
			(xy 456.452561 8.921103) (xy 456.400885 8.852674) (xy 456.343116 8.789304) (xy 456.279746 8.731535)
			(xy 456.211317 8.679859) (xy 456.138411 8.634718) (xy 456.061651 8.596496) (xy 455.981692 8.56552)
			(xy 455.899216 8.542053) (xy 455.814926 8.526297) (xy 455.729543 8.518385) (xy 455.643793 8.518385)
			(xy 455.55841 8.526297) (xy 455.47412 8.542053) (xy 455.391644 8.56552) (xy 455.311685 8.596496)
			(xy 455.234925 8.634718) (xy 455.162019 8.679859) (xy 455.09359 8.731535) (xy 455.03022 8.789304)
			(xy 454.972451 8.852674) (xy 454.920775 8.921103) (xy 454.875634 8.994009) (xy 454.837412 9.070769)
			(xy 454.806436 9.150728) (xy 454.782969 9.233204) (xy 454.767213 9.317494) (xy 454.759301 9.402877)
			(xy 404.76379 9.402877) (xy 404.763491 9.376969) (xy 404.755579 9.291586) (xy 404.739823 9.207296)
			(xy 404.716356 9.12482) (xy 404.68538 9.044861) (xy 404.647158 8.968101) (xy 404.602017 8.895195)
			(xy 404.550341 8.826766) (xy 404.492572 8.763396) (xy 404.429202 8.705627) (xy 404.360773 8.653951)
			(xy 404.287867 8.60881) (xy 404.211107 8.570588) (xy 404.131148 8.539612) (xy 404.048672 8.516145)
			(xy 403.964382 8.500389) (xy 403.878999 8.492477) (xy 403.793249 8.492477) (xy 403.707866 8.500389)
			(xy 403.623576 8.516145) (xy 403.5411 8.539612) (xy 403.461141 8.570588) (xy 403.384381 8.60881)
			(xy 403.311475 8.653951) (xy 403.243046 8.705627) (xy 403.179676 8.763396) (xy 403.121907 8.826766)
			(xy 403.070231 8.895195) (xy 403.02509 8.968101) (xy 402.986868 9.044861) (xy 402.955892 9.12482)
			(xy 402.932425 9.207296) (xy 402.916669 9.291586) (xy 402.908757 9.376969) (xy 398.413491 9.376969)
			(xy 398.405579 9.291586) (xy 398.389823 9.207296) (xy 398.366356 9.12482) (xy 398.33538 9.044861)
			(xy 398.297158 8.968101) (xy 398.252017 8.895195) (xy 398.200341 8.826766) (xy 398.142572 8.763396)
			(xy 398.079202 8.705627) (xy 398.010773 8.653951) (xy 397.937867 8.60881) (xy 397.861107 8.570588)
			(xy 397.781148 8.539612) (xy 397.698672 8.516145) (xy 397.614382 8.500389) (xy 397.528999 8.492477)
			(xy 397.443249 8.492477) (xy 397.357866 8.500389) (xy 397.273576 8.516145) (xy 397.1911 8.539612)
			(xy 397.111141 8.570588) (xy 397.034381 8.60881) (xy 396.961475 8.653951) (xy 396.893046 8.705627)
			(xy 396.829676 8.763396) (xy 396.771907 8.826766) (xy 396.720231 8.895195) (xy 396.67509 8.968101)
			(xy 396.636868 9.044861) (xy 396.605892 9.12482) (xy 396.582425 9.207296) (xy 396.566669 9.291586)
			(xy 396.558757 9.376969) (xy 390.701117 9.376969) (xy 390.701035 9.369857) (xy 390.693123 9.284474)
			(xy 390.677367 9.200184) (xy 390.6539 9.117708) (xy 390.622924 9.037749) (xy 390.584702 8.960989)
			(xy 390.539561 8.888083) (xy 390.487885 8.819654) (xy 390.430116 8.756284) (xy 390.366746 8.698515)
			(xy 390.298317 8.646839) (xy 390.225411 8.601698) (xy 390.148651 8.563476) (xy 390.068692 8.5325)
			(xy 389.986216 8.509033) (xy 389.901926 8.493277) (xy 389.816543 8.485365) (xy 389.730793 8.485365)
			(xy 389.64541 8.493277) (xy 389.56112 8.509033) (xy 389.478644 8.5325) (xy 389.398685 8.563476) (xy 389.321925 8.601698)
			(xy 389.249019 8.646839) (xy 389.18059 8.698515) (xy 389.11722 8.756284) (xy 389.059451 8.819654)
			(xy 389.007775 8.888083) (xy 388.962634 8.960989) (xy 388.924412 9.037749) (xy 388.893436 9.117708)
			(xy 388.869969 9.200184) (xy 388.854213 9.284474) (xy 388.846301 9.369857) (xy 384.351035 9.369857)
			(xy 384.343123 9.284474) (xy 384.327367 9.200184) (xy 384.3039 9.117708) (xy 384.272924 9.037749)
			(xy 384.234702 8.960989) (xy 384.189561 8.888083) (xy 384.137885 8.819654) (xy 384.080116 8.756284)
			(xy 384.016746 8.698515) (xy 383.948317 8.646839) (xy 383.875411 8.601698) (xy 383.798651 8.563476)
			(xy 383.718692 8.5325) (xy 383.636216 8.509033) (xy 383.551926 8.493277) (xy 383.466543 8.485365)
			(xy 383.380793 8.485365) (xy 383.29541 8.493277) (xy 383.21112 8.509033) (xy 383.128644 8.5325) (xy 383.048685 8.563476)
			(xy 382.971925 8.601698) (xy 382.899019 8.646839) (xy 382.83059 8.698515) (xy 382.76722 8.756284)
			(xy 382.709451 8.819654) (xy 382.657775 8.888083) (xy 382.612634 8.960989) (xy 382.574412 9.037749)
			(xy 382.543436 9.117708) (xy 382.519969 9.200184) (xy 382.504213 9.284474) (xy 382.496301 9.369857)
			(xy 332.50079 9.369857) (xy 332.500491 9.343949) (xy 332.492579 9.258566) (xy 332.476823 9.174276)
			(xy 332.453356 9.0918) (xy 332.42238 9.011841) (xy 332.384158 8.935081) (xy 332.339017 8.862175)
			(xy 332.287341 8.793746) (xy 332.229572 8.730376) (xy 332.166202 8.672607) (xy 332.097773 8.620931)
			(xy 332.024867 8.57579) (xy 331.948107 8.537568) (xy 331.868148 8.506592) (xy 331.785672 8.483125)
			(xy 331.701382 8.467369) (xy 331.615999 8.459457) (xy 331.530249 8.459457) (xy 331.444866 8.467369)
			(xy 331.360576 8.483125) (xy 331.2781 8.506592) (xy 331.198141 8.537568) (xy 331.121381 8.57579)
			(xy 331.048475 8.620931) (xy 330.980046 8.672607) (xy 330.916676 8.730376) (xy 330.858907 8.793746)
			(xy 330.807231 8.862175) (xy 330.76209 8.935081) (xy 330.723868 9.011841) (xy 330.692892 9.0918)
			(xy 330.669425 9.174276) (xy 330.653669 9.258566) (xy 330.645757 9.343949) (xy 326.150491 9.343949)
			(xy 326.142579 9.258566) (xy 326.126823 9.174276) (xy 326.103356 9.0918) (xy 326.07238 9.011841)
			(xy 326.034158 8.935081) (xy 325.989017 8.862175) (xy 325.937341 8.793746) (xy 325.879572 8.730376)
			(xy 325.816202 8.672607) (xy 325.747773 8.620931) (xy 325.674867 8.57579) (xy 325.598107 8.537568)
			(xy 325.518148 8.506592) (xy 325.435672 8.483125) (xy 325.351382 8.467369) (xy 325.265999 8.459457)
			(xy 325.180249 8.459457) (xy 325.094866 8.467369) (xy 325.010576 8.483125) (xy 324.9281 8.506592)
			(xy 324.848141 8.537568) (xy 324.771381 8.57579) (xy 324.698475 8.620931) (xy 324.630046 8.672607)
			(xy 324.566676 8.730376) (xy 324.508907 8.793746) (xy 324.457231 8.862175) (xy 324.41209 8.935081)
			(xy 324.373868 9.011841) (xy 324.342892 9.0918) (xy 324.319425 9.174276) (xy 324.303669 9.258566)
			(xy 324.295757 9.343949) (xy 317.930117 9.343949) (xy 317.930035 9.336837) (xy 317.922123 9.251454)
			(xy 317.906367 9.167164) (xy 317.8829 9.084688) (xy 317.851924 9.004729) (xy 317.813702 8.927969)
			(xy 317.768561 8.855063) (xy 317.716885 8.786634) (xy 317.659116 8.723264) (xy 317.595746 8.665495)
			(xy 317.527317 8.613819) (xy 317.454411 8.568678) (xy 317.377651 8.530456) (xy 317.297692 8.49948)
			(xy 317.215216 8.476013) (xy 317.130926 8.460257) (xy 317.045543 8.452345) (xy 316.959793 8.452345)
			(xy 316.87441 8.460257) (xy 316.79012 8.476013) (xy 316.707644 8.49948) (xy 316.627685 8.530456)
			(xy 316.550925 8.568678) (xy 316.478019 8.613819) (xy 316.40959 8.665495) (xy 316.34622 8.723264)
			(xy 316.288451 8.786634) (xy 316.236775 8.855063) (xy 316.191634 8.927969) (xy 316.153412 9.004729)
			(xy 316.122436 9.084688) (xy 316.098969 9.167164) (xy 316.083213 9.251454) (xy 316.075301 9.336837)
			(xy 311.580035 9.336837) (xy 311.572123 9.251454) (xy 311.556367 9.167164) (xy 311.5329 9.084688)
			(xy 311.501924 9.004729) (xy 311.463702 8.927969) (xy 311.418561 8.855063) (xy 311.366885 8.786634)
			(xy 311.309116 8.723264) (xy 311.245746 8.665495) (xy 311.177317 8.613819) (xy 311.104411 8.568678)
			(xy 311.027651 8.530456) (xy 310.947692 8.49948) (xy 310.865216 8.476013) (xy 310.780926 8.460257)
			(xy 310.695543 8.452345) (xy 310.609793 8.452345) (xy 310.52441 8.460257) (xy 310.44012 8.476013)
			(xy 310.357644 8.49948) (xy 310.277685 8.530456) (xy 310.200925 8.568678) (xy 310.128019 8.613819)
			(xy 310.05959 8.665495) (xy 309.99622 8.723264) (xy 309.938451 8.786634) (xy 309.886775 8.855063)
			(xy 309.841634 8.927969) (xy 309.803412 9.004729) (xy 309.772436 9.084688) (xy 309.748969 9.167164)
			(xy 309.733213 9.251454) (xy 309.725301 9.336837) (xy 259.72979 9.336837) (xy 259.729491 9.310929)
			(xy 259.721579 9.225546) (xy 259.705823 9.141256) (xy 259.682356 9.05878) (xy 259.65138 8.978821)
			(xy 259.613158 8.902061) (xy 259.568017 8.829155) (xy 259.516341 8.760726) (xy 259.458572 8.697356)
			(xy 259.395202 8.639587) (xy 259.326773 8.587911) (xy 259.253867 8.54277) (xy 259.177107 8.504548)
			(xy 259.097148 8.473572) (xy 259.014672 8.450105) (xy 258.930382 8.434349) (xy 258.844999 8.426437)
			(xy 258.759249 8.426437) (xy 258.673866 8.434349) (xy 258.589576 8.450105) (xy 258.5071 8.473572)
			(xy 258.427141 8.504548) (xy 258.350381 8.54277) (xy 258.277475 8.587911) (xy 258.209046 8.639587)
			(xy 258.145676 8.697356) (xy 258.087907 8.760726) (xy 258.036231 8.829155) (xy 257.99109 8.902061)
			(xy 257.952868 8.978821) (xy 257.921892 9.05878) (xy 257.898425 9.141256) (xy 257.882669 9.225546)
			(xy 257.874757 9.310929) (xy 253.379491 9.310929) (xy 253.371579 9.225546) (xy 253.355823 9.141256)
			(xy 253.332356 9.05878) (xy 253.30138 8.978821) (xy 253.263158 8.902061) (xy 253.218017 8.829155)
			(xy 253.166341 8.760726) (xy 253.108572 8.697356) (xy 253.045202 8.639587) (xy 252.976773 8.587911)
			(xy 252.903867 8.54277) (xy 252.827107 8.504548) (xy 252.747148 8.473572) (xy 252.664672 8.450105)
			(xy 252.580382 8.434349) (xy 252.494999 8.426437) (xy 252.409249 8.426437) (xy 252.323866 8.434349)
			(xy 252.239576 8.450105) (xy 252.1571 8.473572) (xy 252.077141 8.504548) (xy 252.000381 8.54277)
			(xy 251.927475 8.587911) (xy 251.859046 8.639587) (xy 251.795676 8.697356) (xy 251.737907 8.760726)
			(xy 251.686231 8.829155) (xy 251.64109 8.902061) (xy 251.602868 8.978821) (xy 251.571892 9.05878)
			(xy 251.548425 9.141256) (xy 251.532669 9.225546) (xy 251.524757 9.310929) (xy 245.921117 9.310929)
			(xy 245.921035 9.303817) (xy 245.913123 9.218434) (xy 245.897367 9.134144) (xy 245.8739 9.051668)
			(xy 245.842924 8.971709) (xy 245.804702 8.894949) (xy 245.759561 8.822043) (xy 245.707885 8.753614)
			(xy 245.650116 8.690244) (xy 245.586746 8.632475) (xy 245.518317 8.580799) (xy 245.445411 8.535658)
			(xy 245.368651 8.497436) (xy 245.288692 8.46646) (xy 245.206216 8.442993) (xy 245.121926 8.427237)
			(xy 245.036543 8.419325) (xy 244.950793 8.419325) (xy 244.86541 8.427237) (xy 244.78112 8.442993)
			(xy 244.698644 8.46646) (xy 244.618685 8.497436) (xy 244.541925 8.535658) (xy 244.469019 8.580799)
			(xy 244.40059 8.632475) (xy 244.33722 8.690244) (xy 244.279451 8.753614) (xy 244.227775 8.822043)
			(xy 244.182634 8.894949) (xy 244.144412 8.971709) (xy 244.113436 9.051668) (xy 244.089969 9.134144)
			(xy 244.074213 9.218434) (xy 244.066301 9.303817) (xy 239.571035 9.303817) (xy 239.563123 9.218434)
			(xy 239.547367 9.134144) (xy 239.5239 9.051668) (xy 239.492924 8.971709) (xy 239.454702 8.894949)
			(xy 239.409561 8.822043) (xy 239.357885 8.753614) (xy 239.300116 8.690244) (xy 239.236746 8.632475)
			(xy 239.168317 8.580799) (xy 239.095411 8.535658) (xy 239.018651 8.497436) (xy 238.938692 8.46646)
			(xy 238.856216 8.442993) (xy 238.771926 8.427237) (xy 238.686543 8.419325) (xy 238.600793 8.419325)
			(xy 238.51541 8.427237) (xy 238.43112 8.442993) (xy 238.348644 8.46646) (xy 238.268685 8.497436)
			(xy 238.191925 8.535658) (xy 238.119019 8.580799) (xy 238.05059 8.632475) (xy 237.98722 8.690244)
			(xy 237.929451 8.753614) (xy 237.877775 8.822043) (xy 237.832634 8.894949) (xy 237.794412 8.971709)
			(xy 237.763436 9.051668) (xy 237.739969 9.134144) (xy 237.724213 9.218434) (xy 237.716301 9.303817)
			(xy 187.719832 9.303817) (xy 187.712579 9.225546) (xy 187.696823 9.141256) (xy 187.673356 9.05878)
			(xy 187.64238 8.978821) (xy 187.604158 8.902061) (xy 187.559017 8.829155) (xy 187.507341 8.760726)
			(xy 187.449572 8.697356) (xy 187.386202 8.639587) (xy 187.317773 8.587911) (xy 187.244867 8.54277)
			(xy 187.168107 8.504548) (xy 187.088148 8.473572) (xy 187.005672 8.450105) (xy 186.921382 8.434349)
			(xy 186.835999 8.426437) (xy 186.750249 8.426437) (xy 186.664866 8.434349) (xy 186.580576 8.450105)
			(xy 186.4981 8.473572) (xy 186.418141 8.504548) (xy 186.341381 8.54277) (xy 186.268475 8.587911)
			(xy 186.200046 8.639587) (xy 186.136676 8.697356) (xy 186.078907 8.760726) (xy 186.027231 8.829155)
			(xy 185.98209 8.902061) (xy 185.943868 8.978821) (xy 185.912892 9.05878) (xy 185.889425 9.141256)
			(xy 185.873669 9.225546) (xy 185.865757 9.310929) (xy 181.370491 9.310929) (xy 181.362579 9.225546)
			(xy 181.346823 9.141256) (xy 181.323356 9.05878) (xy 181.29238 8.978821) (xy 181.254158 8.902061)
			(xy 181.209017 8.829155) (xy 181.157341 8.760726) (xy 181.099572 8.697356) (xy 181.036202 8.639587)
			(xy 180.967773 8.587911) (xy 180.894867 8.54277) (xy 180.818107 8.504548) (xy 180.738148 8.473572)
			(xy 180.655672 8.450105) (xy 180.571382 8.434349) (xy 180.485999 8.426437) (xy 180.400249 8.426437)
			(xy 180.314866 8.434349) (xy 180.230576 8.450105) (xy 180.1481 8.473572) (xy 180.068141 8.504548)
			(xy 179.991381 8.54277) (xy 179.918475 8.587911) (xy 179.850046 8.639587) (xy 179.786676 8.697356)
			(xy 179.728907 8.760726) (xy 179.677231 8.829155) (xy 179.63209 8.902061) (xy 179.593868 8.978821)
			(xy 179.562892 9.05878) (xy 179.539425 9.141256) (xy 179.523669 9.225546) (xy 179.515757 9.310929)
			(xy 158.621984 9.310929) (xy 158.621984 8.377682) (xy 158.62149 8.307329) (xy 158.6136 8.166844)
			(xy 158.597845 8.027022) (xy 158.574274 7.888303) (xy 158.542963 7.751125) (xy 158.50401 7.615918)
			(xy 158.457537 7.483107) (xy 158.40369 7.353112) (xy 158.342638 7.22634) (xy 158.274575 7.103191)
			(xy 158.199714 6.984051) (xy 158.11829 6.869297) (xy 158.039844 6.770929) (xy 179.515757 6.770929)
			(xy 179.515757 6.856679) (xy 179.523669 6.942062) (xy 179.539425 7.026352) (xy 179.562892 7.108828)
			(xy 179.593868 7.188787) (xy 179.63209 7.265547) (xy 179.677231 7.338453) (xy 179.728907 7.406882)
			(xy 179.786676 7.470252) (xy 179.850046 7.528021) (xy 179.918475 7.579697) (xy 179.991381 7.624838)
			(xy 180.068141 7.66306) (xy 180.1481 7.694036) (xy 180.230576 7.717503) (xy 180.314866 7.733259)
			(xy 180.400249 7.741171) (xy 180.485999 7.741171) (xy 180.571382 7.733259) (xy 180.655672 7.717503)
			(xy 180.738148 7.694036) (xy 180.818107 7.66306) (xy 180.894867 7.624838) (xy 180.967773 7.579697)
			(xy 181.026743 7.535164) (xy 183.674512 7.535164) (xy 183.674512 8.632444) (xy 183.674927 8.644523)
			(xy 183.682404 8.667495) (xy 183.696613 8.687033) (xy 183.716162 8.701225) (xy 183.739141 8.708683)
			(xy 183.75122 8.709152) (xy 184.36336 8.709152) (xy 184.375428 8.708603) (xy 184.398387 8.701156)
			(xy 184.417921 8.68698) (xy 184.432118 8.667462) (xy 184.439589 8.644512) (xy 184.440068 8.632444)
			(xy 184.440068 7.535164) (xy 184.439717 7.523075) (xy 184.432235 7.500085) (xy 184.418014 7.480532)
			(xy 184.398447 7.46633) (xy 184.375449 7.458871) (xy 184.36336 7.458456) (xy 183.75122 7.458456)
			(xy 183.73915 7.458981) (xy 183.71619 7.466433) (xy 183.696655 7.480615) (xy 183.682459 7.500139)
			(xy 183.674989 7.523094) (xy 183.674512 7.535164) (xy 181.026743 7.535164) (xy 181.036202 7.528021)
			(xy 181.099572 7.470252) (xy 181.157341 7.406882) (xy 181.209017 7.338453) (xy 181.254158 7.265547)
			(xy 181.29238 7.188787) (xy 181.323356 7.108828) (xy 181.346823 7.026352) (xy 181.362579 6.942062)
			(xy 181.370491 6.856679) (xy 181.370986 6.813804) (xy 181.370491 6.770929) (xy 185.865757 6.770929)
			(xy 185.865757 6.856679) (xy 185.873669 6.942062) (xy 185.889425 7.026352) (xy 185.912892 7.108828)
			(xy 185.943868 7.188787) (xy 185.98209 7.265547) (xy 186.027231 7.338453) (xy 186.078907 7.406882)
			(xy 186.136676 7.470252) (xy 186.200046 7.528021) (xy 186.268475 7.579697) (xy 186.341381 7.624838)
			(xy 186.418141 7.66306) (xy 186.4981 7.694036) (xy 186.580576 7.717503) (xy 186.664866 7.733259)
			(xy 186.750249 7.741171) (xy 186.835999 7.741171) (xy 186.921382 7.733259) (xy 187.005672 7.717503)
			(xy 187.088148 7.694036) (xy 187.168107 7.66306) (xy 187.244867 7.624838) (xy 187.317773 7.579697)
			(xy 187.386202 7.528021) (xy 187.449572 7.470252) (xy 187.507341 7.406882) (xy 187.559017 7.338453)
			(xy 187.604158 7.265547) (xy 187.64238 7.188787) (xy 187.673356 7.108828) (xy 187.696823 7.026352)
			(xy 187.712579 6.942062) (xy 187.720491 6.856679) (xy 187.720986 6.813804) (xy 187.720491 6.770929)
			(xy 187.719832 6.763817) (xy 237.716301 6.763817) (xy 237.716301 6.849567) (xy 237.724213 6.93495)
			(xy 237.739969 7.01924) (xy 237.763436 7.101716) (xy 237.794412 7.181675) (xy 237.832634 7.258435)
			(xy 237.877775 7.331341) (xy 237.929451 7.39977) (xy 237.98722 7.46314) (xy 238.05059 7.520909) (xy 238.119019 7.572585)
			(xy 238.191925 7.617726) (xy 238.268685 7.655948) (xy 238.348644 7.686924) (xy 238.43112 7.710391)
			(xy 238.51541 7.726147) (xy 238.600793 7.734059) (xy 238.686543 7.734059) (xy 238.771926 7.726147)
			(xy 238.856216 7.710391) (xy 238.938692 7.686924) (xy 239.018651 7.655948) (xy 239.095411 7.617726)
			(xy 239.168317 7.572585) (xy 239.227287 7.528052) (xy 240.996724 7.528052) (xy 240.996724 8.625332)
			(xy 240.997137 8.637411) (xy 241.004612 8.660385) (xy 241.018821 8.679925) (xy 241.038372 8.694117)
			(xy 241.061352 8.701573) (xy 241.073432 8.70204) (xy 241.685572 8.70204) (xy 241.697642 8.701513)
			(xy 241.720603 8.694062) (xy 241.740138 8.67988) (xy 241.754334 8.660357) (xy 241.761803 8.637402)
			(xy 241.76228 8.625332) (xy 241.76228 7.528052) (xy 241.761876 7.515972) (xy 241.754397 7.492999)
			(xy 241.740186 7.47346) (xy 241.720633 7.459268) (xy 241.697652 7.451812) (xy 241.685572 7.451344)
			(xy 241.073432 7.451344) (xy 241.061364 7.451891) (xy 241.038406 7.459338) (xy 241.018872 7.473515)
			(xy 241.004675 7.493034) (xy 240.997203 7.515984) (xy 240.996724 7.528052) (xy 239.227287 7.528052)
			(xy 239.236746 7.520909) (xy 239.300116 7.46314) (xy 239.357885 7.39977) (xy 239.409561 7.331341)
			(xy 239.454702 7.258435) (xy 239.492924 7.181675) (xy 239.5239 7.101716) (xy 239.547367 7.01924)
			(xy 239.563123 6.93495) (xy 239.571035 6.849567) (xy 239.57153 6.806692) (xy 239.571035 6.763817)
			(xy 244.066301 6.763817) (xy 244.066301 6.849567) (xy 244.074213 6.93495) (xy 244.089969 7.01924)
			(xy 244.113436 7.101716) (xy 244.144412 7.181675) (xy 244.182634 7.258435) (xy 244.227775 7.331341)
			(xy 244.279451 7.39977) (xy 244.33722 7.46314) (xy 244.40059 7.520909) (xy 244.469019 7.572585) (xy 244.541925 7.617726)
			(xy 244.618685 7.655948) (xy 244.698644 7.686924) (xy 244.78112 7.710391) (xy 244.86541 7.726147)
			(xy 244.950793 7.734059) (xy 245.036543 7.734059) (xy 245.121926 7.726147) (xy 245.206216 7.710391)
			(xy 245.288692 7.686924) (xy 245.368651 7.655948) (xy 245.445411 7.617726) (xy 245.518317 7.572585)
			(xy 245.586746 7.520909) (xy 245.650116 7.46314) (xy 245.707885 7.39977) (xy 245.759561 7.331341)
			(xy 245.804702 7.258435) (xy 245.842924 7.181675) (xy 245.8739 7.101716) (xy 245.897367 7.01924)
			(xy 245.913123 6.93495) (xy 245.921035 6.849567) (xy 245.92153 6.806692) (xy 245.921117 6.770929)
			(xy 251.524757 6.770929) (xy 251.524757 6.856679) (xy 251.532669 6.942062) (xy 251.548425 7.026352)
			(xy 251.571892 7.108828) (xy 251.602868 7.188787) (xy 251.64109 7.265547) (xy 251.686231 7.338453)
			(xy 251.737907 7.406882) (xy 251.795676 7.470252) (xy 251.859046 7.528021) (xy 251.927475 7.579697)
			(xy 252.000381 7.624838) (xy 252.077141 7.66306) (xy 252.1571 7.694036) (xy 252.239576 7.717503)
			(xy 252.323866 7.733259) (xy 252.409249 7.741171) (xy 252.494999 7.741171) (xy 252.580382 7.733259)
			(xy 252.664672 7.717503) (xy 252.747148 7.694036) (xy 252.827107 7.66306) (xy 252.84931 7.652004)
			(xy 256.459736 7.652004) (xy 256.459736 8.515604) (xy 256.460222 8.542873) (xy 256.467984 8.596857)
			(xy 256.483349 8.649187) (xy 256.506006 8.698797) (xy 256.535492 8.744678) (xy 256.571207 8.785895)
			(xy 256.612424 8.82161) (xy 256.658305 8.851096) (xy 256.707915 8.873753) (xy 256.760245 8.889118)
			(xy 256.814229 8.89688) (xy 256.868767 8.89688) (xy 256.922751 8.889118) (xy 256.975081 8.873753)
			(xy 257.024691 8.851096) (xy 257.070572 8.82161) (xy 257.111789 8.785895) (xy 257.147504 8.744678)
			(xy 257.17699 8.698797) (xy 257.199647 8.649187) (xy 257.215012 8.596857) (xy 257.222774 8.542873)
			(xy 257.22326 8.515604) (xy 257.22326 7.652004) (xy 257.222774 7.624735) (xy 257.215012 7.570751)
			(xy 257.199647 7.518421) (xy 257.17699 7.468811) (xy 257.147504 7.42293) (xy 257.111789 7.381713)
			(xy 257.070572 7.345998) (xy 257.024691 7.316512) (xy 256.975081 7.293855) (xy 256.922751 7.27849)
			(xy 256.868767 7.270728) (xy 256.814229 7.270728) (xy 256.760245 7.27849) (xy 256.707915 7.293855)
			(xy 256.658305 7.316512) (xy 256.612424 7.345998) (xy 256.571207 7.381713) (xy 256.535492 7.42293)
			(xy 256.506006 7.468811) (xy 256.483349 7.518421) (xy 256.467984 7.570751) (xy 256.460222 7.624735)
			(xy 256.459736 7.652004) (xy 252.84931 7.652004) (xy 252.903867 7.624838) (xy 252.976773 7.579697)
			(xy 253.045202 7.528021) (xy 253.108572 7.470252) (xy 253.166341 7.406882) (xy 253.218017 7.338453)
			(xy 253.263158 7.265547) (xy 253.30138 7.188787) (xy 253.332356 7.108828) (xy 253.355823 7.026352)
			(xy 253.371579 6.942062) (xy 253.379491 6.856679) (xy 253.379986 6.813804) (xy 253.379491 6.770929)
			(xy 257.874757 6.770929) (xy 257.874757 6.856679) (xy 257.882669 6.942062) (xy 257.898425 7.026352)
			(xy 257.921892 7.108828) (xy 257.952868 7.188787) (xy 257.99109 7.265547) (xy 258.036231 7.338453)
			(xy 258.087907 7.406882) (xy 258.145676 7.470252) (xy 258.209046 7.528021) (xy 258.277475 7.579697)
			(xy 258.350381 7.624838) (xy 258.427141 7.66306) (xy 258.5071 7.694036) (xy 258.589576 7.717503)
			(xy 258.673866 7.733259) (xy 258.759249 7.741171) (xy 258.844999 7.741171) (xy 258.930382 7.733259)
			(xy 259.014672 7.717503) (xy 259.097148 7.694036) (xy 259.177107 7.66306) (xy 259.253867 7.624838)
			(xy 259.326773 7.579697) (xy 259.395202 7.528021) (xy 259.458572 7.470252) (xy 259.516341 7.406882)
			(xy 259.568017 7.338453) (xy 259.613158 7.265547) (xy 259.65138 7.188787) (xy 259.682356 7.108828)
			(xy 259.705823 7.026352) (xy 259.721579 6.942062) (xy 259.729491 6.856679) (xy 259.729986 6.813804)
			(xy 259.72979 6.796837) (xy 309.725301 6.796837) (xy 309.725301 6.882587) (xy 309.733213 6.96797)
			(xy 309.748969 7.05226) (xy 309.772436 7.134736) (xy 309.803412 7.214695) (xy 309.841634 7.291455)
			(xy 309.886775 7.364361) (xy 309.938451 7.43279) (xy 309.99622 7.49616) (xy 310.05959 7.553929) (xy 310.128019 7.605605)
			(xy 310.200925 7.650746) (xy 310.277685 7.688968) (xy 310.357644 7.719944) (xy 310.44012 7.743411)
			(xy 310.52441 7.759167) (xy 310.609793 7.767079) (xy 310.695543 7.767079) (xy 310.780926 7.759167)
			(xy 310.865216 7.743411) (xy 310.947692 7.719944) (xy 311.027651 7.688968) (xy 311.049854 7.677912)
			(xy 312.231532 7.677912) (xy 312.231532 8.541512) (xy 312.232018 8.568781) (xy 312.23978 8.622765)
			(xy 312.255145 8.675095) (xy 312.277802 8.724705) (xy 312.307288 8.770586) (xy 312.343003 8.811803)
			(xy 312.38422 8.847518) (xy 312.430101 8.877004) (xy 312.479711 8.899661) (xy 312.532041 8.915026)
			(xy 312.586025 8.922788) (xy 312.640563 8.922788) (xy 312.694547 8.915026) (xy 312.746877 8.899661)
			(xy 312.796487 8.877004) (xy 312.842368 8.847518) (xy 312.883585 8.811803) (xy 312.9193 8.770586)
			(xy 312.948786 8.724705) (xy 312.971443 8.675095) (xy 312.986808 8.622765) (xy 312.99457 8.568781)
			(xy 312.995056 8.541512) (xy 312.995056 7.677912) (xy 312.99457 7.650643) (xy 312.986808 7.596659)
			(xy 312.971443 7.544329) (xy 312.948786 7.494719) (xy 312.9193 7.448838) (xy 312.883585 7.407621)
			(xy 312.842368 7.371906) (xy 312.796487 7.34242) (xy 312.746877 7.319763) (xy 312.694547 7.304398)
			(xy 312.640563 7.296636) (xy 312.586025 7.296636) (xy 312.532041 7.304398) (xy 312.479711 7.319763)
			(xy 312.430101 7.34242) (xy 312.38422 7.371906) (xy 312.343003 7.407621) (xy 312.307288 7.448838)
			(xy 312.277802 7.494719) (xy 312.255145 7.544329) (xy 312.23978 7.596659) (xy 312.232018 7.650643)
			(xy 312.231532 7.677912) (xy 311.049854 7.677912) (xy 311.104411 7.650746) (xy 311.177317 7.605605)
			(xy 311.245746 7.553929) (xy 311.309116 7.49616) (xy 311.366885 7.43279) (xy 311.418561 7.364361)
			(xy 311.463702 7.291455) (xy 311.501924 7.214695) (xy 311.5329 7.134736) (xy 311.556367 7.05226)
			(xy 311.572123 6.96797) (xy 311.580035 6.882587) (xy 311.58053 6.839712) (xy 311.580035 6.796837)
			(xy 316.075301 6.796837) (xy 316.075301 6.882587) (xy 316.083213 6.96797) (xy 316.098969 7.05226)
			(xy 316.122436 7.134736) (xy 316.153412 7.214695) (xy 316.191634 7.291455) (xy 316.236775 7.364361)
			(xy 316.288451 7.43279) (xy 316.34622 7.49616) (xy 316.40959 7.553929) (xy 316.478019 7.605605) (xy 316.550925 7.650746)
			(xy 316.627685 7.688968) (xy 316.707644 7.719944) (xy 316.79012 7.743411) (xy 316.87441 7.759167)
			(xy 316.959793 7.767079) (xy 317.045543 7.767079) (xy 317.130926 7.759167) (xy 317.215216 7.743411)
			(xy 317.297692 7.719944) (xy 317.377651 7.688968) (xy 317.454411 7.650746) (xy 317.527317 7.605605)
			(xy 317.595746 7.553929) (xy 317.659116 7.49616) (xy 317.716885 7.43279) (xy 317.768561 7.364361)
			(xy 317.813702 7.291455) (xy 317.851924 7.214695) (xy 317.8829 7.134736) (xy 317.906367 7.05226)
			(xy 317.922123 6.96797) (xy 317.930035 6.882587) (xy 317.93053 6.839712) (xy 317.930117 6.803949)
			(xy 324.295757 6.803949) (xy 324.295757 6.889699) (xy 324.303669 6.975082) (xy 324.319425 7.059372)
			(xy 324.342892 7.141848) (xy 324.373868 7.221807) (xy 324.41209 7.298567) (xy 324.457231 7.371473)
			(xy 324.508907 7.439902) (xy 324.566676 7.503272) (xy 324.630046 7.561041) (xy 324.698475 7.612717)
			(xy 324.771381 7.657858) (xy 324.848141 7.69608) (xy 324.9281 7.727056) (xy 325.010576 7.750523)
			(xy 325.094866 7.766279) (xy 325.180249 7.774191) (xy 325.265999 7.774191) (xy 325.351382 7.766279)
			(xy 325.435672 7.750523) (xy 325.518148 7.727056) (xy 325.598107 7.69608) (xy 325.62031 7.685024)
			(xy 329.230736 7.685024) (xy 329.230736 8.548624) (xy 329.231222 8.575893) (xy 329.238984 8.629877)
			(xy 329.254349 8.682207) (xy 329.277006 8.731817) (xy 329.306492 8.777698) (xy 329.342207 8.818915)
			(xy 329.383424 8.85463) (xy 329.429305 8.884116) (xy 329.478915 8.906773) (xy 329.531245 8.922138)
			(xy 329.585229 8.9299) (xy 329.639767 8.9299) (xy 329.693751 8.922138) (xy 329.746081 8.906773) (xy 329.795691 8.884116)
			(xy 329.841572 8.85463) (xy 329.882789 8.818915) (xy 329.918504 8.777698) (xy 329.94799 8.731817)
			(xy 329.970647 8.682207) (xy 329.986012 8.629877) (xy 329.993774 8.575893) (xy 329.99426 8.548624)
			(xy 329.99426 7.685024) (xy 329.993774 7.657755) (xy 329.986012 7.603771) (xy 329.970647 7.551441)
			(xy 329.94799 7.501831) (xy 329.918504 7.45595) (xy 329.882789 7.414733) (xy 329.841572 7.379018)
			(xy 329.795691 7.349532) (xy 329.746081 7.326875) (xy 329.693751 7.31151) (xy 329.639767 7.303748)
			(xy 329.585229 7.303748) (xy 329.531245 7.31151) (xy 329.478915 7.326875) (xy 329.429305 7.349532)
			(xy 329.383424 7.379018) (xy 329.342207 7.414733) (xy 329.306492 7.45595) (xy 329.277006 7.501831)
			(xy 329.254349 7.551441) (xy 329.238984 7.603771) (xy 329.231222 7.657755) (xy 329.230736 7.685024)
			(xy 325.62031 7.685024) (xy 325.674867 7.657858) (xy 325.747773 7.612717) (xy 325.816202 7.561041)
			(xy 325.879572 7.503272) (xy 325.937341 7.439902) (xy 325.989017 7.371473) (xy 326.034158 7.298567)
			(xy 326.07238 7.221807) (xy 326.103356 7.141848) (xy 326.126823 7.059372) (xy 326.142579 6.975082)
			(xy 326.150491 6.889699) (xy 326.150986 6.846824) (xy 326.150491 6.803949) (xy 330.645757 6.803949)
			(xy 330.645757 6.889699) (xy 330.653669 6.975082) (xy 330.669425 7.059372) (xy 330.692892 7.141848)
			(xy 330.723868 7.221807) (xy 330.76209 7.298567) (xy 330.807231 7.371473) (xy 330.858907 7.439902)
			(xy 330.916676 7.503272) (xy 330.980046 7.561041) (xy 331.048475 7.612717) (xy 331.121381 7.657858)
			(xy 331.198141 7.69608) (xy 331.2781 7.727056) (xy 331.360576 7.750523) (xy 331.444866 7.766279)
			(xy 331.530249 7.774191) (xy 331.615999 7.774191) (xy 331.701382 7.766279) (xy 331.785672 7.750523)
			(xy 331.868148 7.727056) (xy 331.948107 7.69608) (xy 332.024867 7.657858) (xy 332.097773 7.612717)
			(xy 332.166202 7.561041) (xy 332.229572 7.503272) (xy 332.287341 7.439902) (xy 332.339017 7.371473)
			(xy 332.384158 7.298567) (xy 332.42238 7.221807) (xy 332.453356 7.141848) (xy 332.476823 7.059372)
			(xy 332.492579 6.975082) (xy 332.500491 6.889699) (xy 332.500986 6.846824) (xy 332.50079 6.829857)
			(xy 382.496301 6.829857) (xy 382.496301 6.915607) (xy 382.504213 7.00099) (xy 382.519969 7.08528)
			(xy 382.543436 7.167756) (xy 382.574412 7.247715) (xy 382.612634 7.324475) (xy 382.657775 7.397381)
			(xy 382.709451 7.46581) (xy 382.76722 7.52918) (xy 382.83059 7.586949) (xy 382.899019 7.638625) (xy 382.971925 7.683766)
			(xy 383.048685 7.721988) (xy 383.128644 7.752964) (xy 383.21112 7.776431) (xy 383.29541 7.792187)
			(xy 383.380793 7.800099) (xy 383.466543 7.800099) (xy 383.551926 7.792187) (xy 383.636216 7.776431)
			(xy 383.718692 7.752964) (xy 383.798651 7.721988) (xy 383.820854 7.710932) (xy 385.002532 7.710932)
			(xy 385.002532 8.574532) (xy 385.003018 8.601801) (xy 385.01078 8.655785) (xy 385.026145 8.708115)
			(xy 385.048802 8.757725) (xy 385.078288 8.803606) (xy 385.114003 8.844823) (xy 385.15522 8.880538)
			(xy 385.201101 8.910024) (xy 385.250711 8.932681) (xy 385.303041 8.948046) (xy 385.357025 8.955808)
			(xy 385.411563 8.955808) (xy 385.465547 8.948046) (xy 385.517877 8.932681) (xy 385.567487 8.910024)
			(xy 385.613368 8.880538) (xy 385.654585 8.844823) (xy 385.6903 8.803606) (xy 385.719786 8.757725)
			(xy 385.742443 8.708115) (xy 385.757808 8.655785) (xy 385.76557 8.601801) (xy 385.766056 8.574532)
			(xy 385.766056 7.710932) (xy 385.76557 7.683663) (xy 385.757808 7.629679) (xy 385.742443 7.577349)
			(xy 385.719786 7.527739) (xy 385.6903 7.481858) (xy 385.654585 7.440641) (xy 385.613368 7.404926)
			(xy 385.567487 7.37544) (xy 385.517877 7.352783) (xy 385.465547 7.337418) (xy 385.411563 7.329656)
			(xy 385.357025 7.329656) (xy 385.303041 7.337418) (xy 385.250711 7.352783) (xy 385.201101 7.37544)
			(xy 385.15522 7.404926) (xy 385.114003 7.440641) (xy 385.078288 7.481858) (xy 385.048802 7.527739)
			(xy 385.026145 7.577349) (xy 385.01078 7.629679) (xy 385.003018 7.683663) (xy 385.002532 7.710932)
			(xy 383.820854 7.710932) (xy 383.875411 7.683766) (xy 383.948317 7.638625) (xy 384.016746 7.586949)
			(xy 384.080116 7.52918) (xy 384.137885 7.46581) (xy 384.189561 7.397381) (xy 384.234702 7.324475)
			(xy 384.272924 7.247715) (xy 384.3039 7.167756) (xy 384.327367 7.08528) (xy 384.343123 7.00099) (xy 384.351035 6.915607)
			(xy 384.35153 6.872732) (xy 384.351035 6.829857) (xy 388.846301 6.829857) (xy 388.846301 6.915607)
			(xy 388.854213 7.00099) (xy 388.869969 7.08528) (xy 388.893436 7.167756) (xy 388.924412 7.247715)
			(xy 388.962634 7.324475) (xy 389.007775 7.397381) (xy 389.059451 7.46581) (xy 389.11722 7.52918)
			(xy 389.18059 7.586949) (xy 389.249019 7.638625) (xy 389.321925 7.683766) (xy 389.398685 7.721988)
			(xy 389.478644 7.752964) (xy 389.56112 7.776431) (xy 389.64541 7.792187) (xy 389.730793 7.800099)
			(xy 389.816543 7.800099) (xy 389.901926 7.792187) (xy 389.986216 7.776431) (xy 390.068692 7.752964)
			(xy 390.148651 7.721988) (xy 390.225411 7.683766) (xy 390.298317 7.638625) (xy 390.366746 7.586949)
			(xy 390.430116 7.52918) (xy 390.487885 7.46581) (xy 390.539561 7.397381) (xy 390.584702 7.324475)
			(xy 390.622924 7.247715) (xy 390.6539 7.167756) (xy 390.677367 7.08528) (xy 390.693123 7.00099) (xy 390.701035 6.915607)
			(xy 390.70153 6.872732) (xy 390.701117 6.836969) (xy 396.558757 6.836969) (xy 396.558757 6.922719)
			(xy 396.566669 7.008102) (xy 396.582425 7.092392) (xy 396.605892 7.174868) (xy 396.636868 7.254827)
			(xy 396.67509 7.331587) (xy 396.720231 7.404493) (xy 396.771907 7.472922) (xy 396.829676 7.536292)
			(xy 396.893046 7.594061) (xy 396.961475 7.645737) (xy 397.034381 7.690878) (xy 397.111141 7.7291)
			(xy 397.1911 7.760076) (xy 397.273576 7.783543) (xy 397.357866 7.799299) (xy 397.443249 7.807211)
			(xy 397.528999 7.807211) (xy 397.614382 7.799299) (xy 397.698672 7.783543) (xy 397.781148 7.760076)
			(xy 397.861107 7.7291) (xy 397.88331 7.718044) (xy 401.493736 7.718044) (xy 401.493736 8.581644)
			(xy 401.494222 8.608913) (xy 401.501984 8.662897) (xy 401.517349 8.715227) (xy 401.540006 8.764837)
			(xy 401.569492 8.810718) (xy 401.605207 8.851935) (xy 401.646424 8.88765) (xy 401.692305 8.917136)
			(xy 401.741915 8.939793) (xy 401.794245 8.955158) (xy 401.848229 8.96292) (xy 401.902767 8.96292)
			(xy 401.956751 8.955158) (xy 402.009081 8.939793) (xy 402.058691 8.917136) (xy 402.104572 8.88765)
			(xy 402.145789 8.851935) (xy 402.181504 8.810718) (xy 402.21099 8.764837) (xy 402.233647 8.715227)
			(xy 402.249012 8.662897) (xy 402.256774 8.608913) (xy 402.25726 8.581644) (xy 402.25726 7.718044)
			(xy 402.256774 7.690775) (xy 402.249012 7.636791) (xy 402.233647 7.584461) (xy 402.21099 7.534851)
			(xy 402.181504 7.48897) (xy 402.145789 7.447753) (xy 402.104572 7.412038) (xy 402.058691 7.382552)
			(xy 402.009081 7.359895) (xy 401.956751 7.34453) (xy 401.902767 7.336768) (xy 401.848229 7.336768)
			(xy 401.794245 7.34453) (xy 401.741915 7.359895) (xy 401.692305 7.382552) (xy 401.646424 7.412038)
			(xy 401.605207 7.447753) (xy 401.569492 7.48897) (xy 401.540006 7.534851) (xy 401.517349 7.584461)
			(xy 401.501984 7.636791) (xy 401.494222 7.690775) (xy 401.493736 7.718044) (xy 397.88331 7.718044)
			(xy 397.937867 7.690878) (xy 398.010773 7.645737) (xy 398.079202 7.594061) (xy 398.142572 7.536292)
			(xy 398.200341 7.472922) (xy 398.252017 7.404493) (xy 398.297158 7.331587) (xy 398.33538 7.254827)
			(xy 398.366356 7.174868) (xy 398.389823 7.092392) (xy 398.405579 7.008102) (xy 398.413491 6.922719)
			(xy 398.413986 6.879844) (xy 398.413491 6.836969) (xy 402.908757 6.836969) (xy 402.908757 6.922719)
			(xy 402.916669 7.008102) (xy 402.932425 7.092392) (xy 402.955892 7.174868) (xy 402.986868 7.254827)
			(xy 403.02509 7.331587) (xy 403.070231 7.404493) (xy 403.121907 7.472922) (xy 403.179676 7.536292)
			(xy 403.243046 7.594061) (xy 403.311475 7.645737) (xy 403.384381 7.690878) (xy 403.461141 7.7291)
			(xy 403.5411 7.760076) (xy 403.623576 7.783543) (xy 403.707866 7.799299) (xy 403.793249 7.807211)
			(xy 403.878999 7.807211) (xy 403.964382 7.799299) (xy 404.048672 7.783543) (xy 404.131148 7.760076)
			(xy 404.211107 7.7291) (xy 404.287867 7.690878) (xy 404.360773 7.645737) (xy 404.429202 7.594061)
			(xy 404.492572 7.536292) (xy 404.550341 7.472922) (xy 404.602017 7.404493) (xy 404.647158 7.331587)
			(xy 404.68538 7.254827) (xy 404.716356 7.174868) (xy 404.739823 7.092392) (xy 404.755579 7.008102)
			(xy 404.763491 6.922719) (xy 404.763986 6.879844) (xy 404.76379 6.862877) (xy 454.759301 6.862877)
			(xy 454.759301 6.948627) (xy 454.767213 7.03401) (xy 454.782969 7.1183) (xy 454.806436 7.200776)
			(xy 454.837412 7.280735) (xy 454.875634 7.357495) (xy 454.920775 7.430401) (xy 454.972451 7.49883)
			(xy 455.03022 7.5622) (xy 455.09359 7.619969) (xy 455.162019 7.671645) (xy 455.234925 7.716786) (xy 455.311685 7.755008)
			(xy 455.391644 7.785984) (xy 455.47412 7.809451) (xy 455.55841 7.825207) (xy 455.643793 7.833119)
			(xy 455.729543 7.833119) (xy 455.814926 7.825207) (xy 455.899216 7.809451) (xy 455.981692 7.785984)
			(xy 456.061651 7.755008) (xy 456.083854 7.743952) (xy 457.265532 7.743952) (xy 457.265532 8.607552)
			(xy 457.266018 8.634821) (xy 457.27378 8.688805) (xy 457.289145 8.741135) (xy 457.311802 8.790745)
			(xy 457.341288 8.836626) (xy 457.377003 8.877843) (xy 457.41822 8.913558) (xy 457.464101 8.943044)
			(xy 457.513711 8.965701) (xy 457.566041 8.981066) (xy 457.620025 8.988828) (xy 457.674563 8.988828)
			(xy 457.728547 8.981066) (xy 457.780877 8.965701) (xy 457.830487 8.943044) (xy 457.876368 8.913558)
			(xy 457.917585 8.877843) (xy 457.9533 8.836626) (xy 457.982786 8.790745) (xy 458.005443 8.741135)
			(xy 458.020808 8.688805) (xy 458.02857 8.634821) (xy 458.029056 8.607552) (xy 458.029056 7.743952)
			(xy 458.02857 7.716683) (xy 458.020808 7.662699) (xy 458.005443 7.610369) (xy 457.982786 7.560759)
			(xy 457.9533 7.514878) (xy 457.917585 7.473661) (xy 457.876368 7.437946) (xy 457.830487 7.40846)
			(xy 457.780877 7.385803) (xy 457.728547 7.370438) (xy 457.674563 7.362676) (xy 457.620025 7.362676)
			(xy 457.566041 7.370438) (xy 457.513711 7.385803) (xy 457.464101 7.40846) (xy 457.41822 7.437946)
			(xy 457.377003 7.473661) (xy 457.341288 7.514878) (xy 457.311802 7.560759) (xy 457.289145 7.610369)
			(xy 457.27378 7.662699) (xy 457.266018 7.716683) (xy 457.265532 7.743952) (xy 456.083854 7.743952)
			(xy 456.138411 7.716786) (xy 456.211317 7.671645) (xy 456.279746 7.619969) (xy 456.343116 7.5622)
			(xy 456.400885 7.49883) (xy 456.452561 7.430401) (xy 456.497702 7.357495) (xy 456.535924 7.280735)
			(xy 456.5669 7.200776) (xy 456.590367 7.1183) (xy 456.606123 7.03401) (xy 456.614035 6.948627) (xy 456.61453 6.905752)
			(xy 456.614035 6.862877) (xy 461.109301 6.862877) (xy 461.109301 6.948627) (xy 461.117213 7.03401)
			(xy 461.132969 7.1183) (xy 461.156436 7.200776) (xy 461.187412 7.280735) (xy 461.225634 7.357495)
			(xy 461.270775 7.430401) (xy 461.322451 7.49883) (xy 461.38022 7.5622) (xy 461.44359 7.619969) (xy 461.512019 7.671645)
			(xy 461.584925 7.716786) (xy 461.661685 7.755008) (xy 461.741644 7.785984) (xy 461.82412 7.809451)
			(xy 461.90841 7.825207) (xy 461.993793 7.833119) (xy 462.079543 7.833119) (xy 462.164926 7.825207)
			(xy 462.249216 7.809451) (xy 462.331692 7.785984) (xy 462.411651 7.755008) (xy 462.488411 7.716786)
			(xy 462.561317 7.671645) (xy 462.629746 7.619969) (xy 462.693116 7.5622) (xy 462.750885 7.49883)
			(xy 462.802561 7.430401) (xy 462.847702 7.357495) (xy 462.885924 7.280735) (xy 462.9169 7.200776)
			(xy 462.940367 7.1183) (xy 462.956123 7.03401) (xy 462.964035 6.948627) (xy 462.96453 6.905752) (xy 462.964035 6.862877)
			(xy 462.956123 6.777494) (xy 462.940367 6.693204) (xy 462.9169 6.610728) (xy 462.885924 6.530769)
			(xy 462.847702 6.454009) (xy 462.802561 6.381103) (xy 462.750885 6.312674) (xy 462.693116 6.249304)
			(xy 462.629746 6.191535) (xy 462.561317 6.139859) (xy 462.488411 6.094718) (xy 462.411651 6.056496)
			(xy 462.331692 6.02552) (xy 462.249216 6.002053) (xy 462.164926 5.986297) (xy 462.079543 5.978385)
			(xy 461.993793 5.978385) (xy 461.90841 5.986297) (xy 461.82412 6.002053) (xy 461.741644 6.02552)
			(xy 461.661685 6.056496) (xy 461.584925 6.094718) (xy 461.512019 6.139859) (xy 461.44359 6.191535)
			(xy 461.38022 6.249304) (xy 461.322451 6.312674) (xy 461.270775 6.381103) (xy 461.225634 6.454009)
			(xy 461.187412 6.530769) (xy 461.156436 6.610728) (xy 461.132969 6.693204) (xy 461.117213 6.777494)
			(xy 461.109301 6.862877) (xy 456.614035 6.862877) (xy 456.606123 6.777494) (xy 456.590367 6.693204)
			(xy 456.5669 6.610728) (xy 456.535924 6.530769) (xy 456.497702 6.454009) (xy 456.452561 6.381103)
			(xy 456.400885 6.312674) (xy 456.343116 6.249304) (xy 456.279746 6.191535) (xy 456.211317 6.139859)
			(xy 456.138411 6.094718) (xy 456.061651 6.056496) (xy 455.981692 6.02552) (xy 455.899216 6.002053)
			(xy 455.814926 5.986297) (xy 455.729543 5.978385) (xy 455.643793 5.978385) (xy 455.55841 5.986297)
			(xy 455.47412 6.002053) (xy 455.391644 6.02552) (xy 455.311685 6.056496) (xy 455.234925 6.094718)
			(xy 455.162019 6.139859) (xy 455.09359 6.191535) (xy 455.03022 6.249304) (xy 454.972451 6.312674)
			(xy 454.920775 6.381103) (xy 454.875634 6.454009) (xy 454.837412 6.530769) (xy 454.806436 6.610728)
			(xy 454.782969 6.693204) (xy 454.767213 6.777494) (xy 454.759301 6.862877) (xy 404.76379 6.862877)
			(xy 404.763491 6.836969) (xy 404.755579 6.751586) (xy 404.739823 6.667296) (xy 404.716356 6.58482)
			(xy 404.68538 6.504861) (xy 404.647158 6.428101) (xy 404.602017 6.355195) (xy 404.550341 6.286766)
			(xy 404.492572 6.223396) (xy 404.429202 6.165627) (xy 404.360773 6.113951) (xy 404.287867 6.06881)
			(xy 404.211107 6.030588) (xy 404.131148 5.999612) (xy 404.048672 5.976145) (xy 403.964382 5.960389)
			(xy 403.878999 5.952477) (xy 403.793249 5.952477) (xy 403.707866 5.960389) (xy 403.623576 5.976145)
			(xy 403.5411 5.999612) (xy 403.461141 6.030588) (xy 403.384381 6.06881) (xy 403.311475 6.113951)
			(xy 403.243046 6.165627) (xy 403.179676 6.223396) (xy 403.121907 6.286766) (xy 403.070231 6.355195)
			(xy 403.02509 6.428101) (xy 402.986868 6.504861) (xy 402.955892 6.58482) (xy 402.932425 6.667296)
			(xy 402.916669 6.751586) (xy 402.908757 6.836969) (xy 398.413491 6.836969) (xy 398.405579 6.751586)
			(xy 398.389823 6.667296) (xy 398.366356 6.58482) (xy 398.33538 6.504861) (xy 398.297158 6.428101)
			(xy 398.252017 6.355195) (xy 398.200341 6.286766) (xy 398.142572 6.223396) (xy 398.079202 6.165627)
			(xy 398.010773 6.113951) (xy 397.937867 6.06881) (xy 397.861107 6.030588) (xy 397.781148 5.999612)
			(xy 397.698672 5.976145) (xy 397.614382 5.960389) (xy 397.528999 5.952477) (xy 397.443249 5.952477)
			(xy 397.357866 5.960389) (xy 397.273576 5.976145) (xy 397.1911 5.999612) (xy 397.111141 6.030588)
			(xy 397.034381 6.06881) (xy 396.961475 6.113951) (xy 396.893046 6.165627) (xy 396.829676 6.223396)
			(xy 396.771907 6.286766) (xy 396.720231 6.355195) (xy 396.67509 6.428101) (xy 396.636868 6.504861)
			(xy 396.605892 6.58482) (xy 396.582425 6.667296) (xy 396.566669 6.751586) (xy 396.558757 6.836969)
			(xy 390.701117 6.836969) (xy 390.701035 6.829857) (xy 390.693123 6.744474) (xy 390.677367 6.660184)
			(xy 390.6539 6.577708) (xy 390.622924 6.497749) (xy 390.584702 6.420989) (xy 390.539561 6.348083)
			(xy 390.487885 6.279654) (xy 390.430116 6.216284) (xy 390.366746 6.158515) (xy 390.298317 6.106839)
			(xy 390.225411 6.061698) (xy 390.148651 6.023476) (xy 390.068692 5.9925) (xy 389.986216 5.969033)
			(xy 389.901926 5.953277) (xy 389.816543 5.945365) (xy 389.730793 5.945365) (xy 389.64541 5.953277)
			(xy 389.56112 5.969033) (xy 389.478644 5.9925) (xy 389.398685 6.023476) (xy 389.321925 6.061698)
			(xy 389.249019 6.106839) (xy 389.18059 6.158515) (xy 389.11722 6.216284) (xy 389.059451 6.279654)
			(xy 389.007775 6.348083) (xy 388.962634 6.420989) (xy 388.924412 6.497749) (xy 388.893436 6.577708)
			(xy 388.869969 6.660184) (xy 388.854213 6.744474) (xy 388.846301 6.829857) (xy 384.351035 6.829857)
			(xy 384.343123 6.744474) (xy 384.327367 6.660184) (xy 384.3039 6.577708) (xy 384.272924 6.497749)
			(xy 384.234702 6.420989) (xy 384.189561 6.348083) (xy 384.137885 6.279654) (xy 384.080116 6.216284)
			(xy 384.016746 6.158515) (xy 383.948317 6.106839) (xy 383.875411 6.061698) (xy 383.798651 6.023476)
			(xy 383.718692 5.9925) (xy 383.636216 5.969033) (xy 383.551926 5.953277) (xy 383.466543 5.945365)
			(xy 383.380793 5.945365) (xy 383.29541 5.953277) (xy 383.21112 5.969033) (xy 383.128644 5.9925) (xy 383.048685 6.023476)
			(xy 382.971925 6.061698) (xy 382.899019 6.106839) (xy 382.83059 6.158515) (xy 382.76722 6.216284)
			(xy 382.709451 6.279654) (xy 382.657775 6.348083) (xy 382.612634 6.420989) (xy 382.574412 6.497749)
			(xy 382.543436 6.577708) (xy 382.519969 6.660184) (xy 382.504213 6.744474) (xy 382.496301 6.829857)
			(xy 332.50079 6.829857) (xy 332.500491 6.803949) (xy 332.492579 6.718566) (xy 332.476823 6.634276)
			(xy 332.453356 6.5518) (xy 332.42238 6.471841) (xy 332.384158 6.395081) (xy 332.339017 6.322175)
			(xy 332.287341 6.253746) (xy 332.229572 6.190376) (xy 332.166202 6.132607) (xy 332.097773 6.080931)
			(xy 332.024867 6.03579) (xy 331.948107 5.997568) (xy 331.868148 5.966592) (xy 331.785672 5.943125)
			(xy 331.701382 5.927369) (xy 331.615999 5.919457) (xy 331.530249 5.919457) (xy 331.444866 5.927369)
			(xy 331.360576 5.943125) (xy 331.2781 5.966592) (xy 331.198141 5.997568) (xy 331.121381 6.03579)
			(xy 331.048475 6.080931) (xy 330.980046 6.132607) (xy 330.916676 6.190376) (xy 330.858907 6.253746)
			(xy 330.807231 6.322175) (xy 330.76209 6.395081) (xy 330.723868 6.471841) (xy 330.692892 6.5518)
			(xy 330.669425 6.634276) (xy 330.653669 6.718566) (xy 330.645757 6.803949) (xy 326.150491 6.803949)
			(xy 326.142579 6.718566) (xy 326.126823 6.634276) (xy 326.103356 6.5518) (xy 326.07238 6.471841)
			(xy 326.034158 6.395081) (xy 325.989017 6.322175) (xy 325.937341 6.253746) (xy 325.879572 6.190376)
			(xy 325.816202 6.132607) (xy 325.747773 6.080931) (xy 325.674867 6.03579) (xy 325.598107 5.997568)
			(xy 325.518148 5.966592) (xy 325.435672 5.943125) (xy 325.351382 5.927369) (xy 325.265999 5.919457)
			(xy 325.180249 5.919457) (xy 325.094866 5.927369) (xy 325.010576 5.943125) (xy 324.9281 5.966592)
			(xy 324.848141 5.997568) (xy 324.771381 6.03579) (xy 324.698475 6.080931) (xy 324.630046 6.132607)
			(xy 324.566676 6.190376) (xy 324.508907 6.253746) (xy 324.457231 6.322175) (xy 324.41209 6.395081)
			(xy 324.373868 6.471841) (xy 324.342892 6.5518) (xy 324.319425 6.634276) (xy 324.303669 6.718566)
			(xy 324.295757 6.803949) (xy 317.930117 6.803949) (xy 317.930035 6.796837) (xy 317.922123 6.711454)
			(xy 317.906367 6.627164) (xy 317.8829 6.544688) (xy 317.851924 6.464729) (xy 317.813702 6.387969)
			(xy 317.768561 6.315063) (xy 317.716885 6.246634) (xy 317.659116 6.183264) (xy 317.595746 6.125495)
			(xy 317.527317 6.073819) (xy 317.454411 6.028678) (xy 317.377651 5.990456) (xy 317.297692 5.95948)
			(xy 317.215216 5.936013) (xy 317.130926 5.920257) (xy 317.045543 5.912345) (xy 316.959793 5.912345)
			(xy 316.87441 5.920257) (xy 316.79012 5.936013) (xy 316.707644 5.95948) (xy 316.627685 5.990456)
			(xy 316.550925 6.028678) (xy 316.478019 6.073819) (xy 316.40959 6.125495) (xy 316.34622 6.183264)
			(xy 316.288451 6.246634) (xy 316.236775 6.315063) (xy 316.191634 6.387969) (xy 316.153412 6.464729)
			(xy 316.122436 6.544688) (xy 316.098969 6.627164) (xy 316.083213 6.711454) (xy 316.075301 6.796837)
			(xy 311.580035 6.796837) (xy 311.572123 6.711454) (xy 311.556367 6.627164) (xy 311.5329 6.544688)
			(xy 311.501924 6.464729) (xy 311.463702 6.387969) (xy 311.418561 6.315063) (xy 311.366885 6.246634)
			(xy 311.309116 6.183264) (xy 311.245746 6.125495) (xy 311.177317 6.073819) (xy 311.104411 6.028678)
			(xy 311.027651 5.990456) (xy 310.947692 5.95948) (xy 310.865216 5.936013) (xy 310.780926 5.920257)
			(xy 310.695543 5.912345) (xy 310.609793 5.912345) (xy 310.52441 5.920257) (xy 310.44012 5.936013)
			(xy 310.357644 5.95948) (xy 310.277685 5.990456) (xy 310.200925 6.028678) (xy 310.128019 6.073819)
			(xy 310.05959 6.125495) (xy 309.99622 6.183264) (xy 309.938451 6.246634) (xy 309.886775 6.315063)
			(xy 309.841634 6.387969) (xy 309.803412 6.464729) (xy 309.772436 6.544688) (xy 309.748969 6.627164)
			(xy 309.733213 6.711454) (xy 309.725301 6.796837) (xy 259.72979 6.796837) (xy 259.729491 6.770929)
			(xy 259.721579 6.685546) (xy 259.705823 6.601256) (xy 259.682356 6.51878) (xy 259.65138 6.438821)
			(xy 259.613158 6.362061) (xy 259.568017 6.289155) (xy 259.516341 6.220726) (xy 259.458572 6.157356)
			(xy 259.395202 6.099587) (xy 259.326773 6.047911) (xy 259.253867 6.00277) (xy 259.177107 5.964548)
			(xy 259.097148 5.933572) (xy 259.014672 5.910105) (xy 258.930382 5.894349) (xy 258.844999 5.886437)
			(xy 258.759249 5.886437) (xy 258.673866 5.894349) (xy 258.589576 5.910105) (xy 258.5071 5.933572)
			(xy 258.427141 5.964548) (xy 258.350381 6.00277) (xy 258.277475 6.047911) (xy 258.209046 6.099587)
			(xy 258.145676 6.157356) (xy 258.087907 6.220726) (xy 258.036231 6.289155) (xy 257.99109 6.362061)
			(xy 257.952868 6.438821) (xy 257.921892 6.51878) (xy 257.898425 6.601256) (xy 257.882669 6.685546)
			(xy 257.874757 6.770929) (xy 253.379491 6.770929) (xy 253.371579 6.685546) (xy 253.355823 6.601256)
			(xy 253.332356 6.51878) (xy 253.30138 6.438821) (xy 253.263158 6.362061) (xy 253.218017 6.289155)
			(xy 253.166341 6.220726) (xy 253.108572 6.157356) (xy 253.045202 6.099587) (xy 252.976773 6.047911)
			(xy 252.903867 6.00277) (xy 252.827107 5.964548) (xy 252.747148 5.933572) (xy 252.664672 5.910105)
			(xy 252.580382 5.894349) (xy 252.494999 5.886437) (xy 252.409249 5.886437) (xy 252.323866 5.894349)
			(xy 252.239576 5.910105) (xy 252.1571 5.933572) (xy 252.077141 5.964548) (xy 252.000381 6.00277)
			(xy 251.927475 6.047911) (xy 251.859046 6.099587) (xy 251.795676 6.157356) (xy 251.737907 6.220726)
			(xy 251.686231 6.289155) (xy 251.64109 6.362061) (xy 251.602868 6.438821) (xy 251.571892 6.51878)
			(xy 251.548425 6.601256) (xy 251.532669 6.685546) (xy 251.524757 6.770929) (xy 245.921117 6.770929)
			(xy 245.921035 6.763817) (xy 245.913123 6.678434) (xy 245.897367 6.594144) (xy 245.8739 6.511668)
			(xy 245.842924 6.431709) (xy 245.804702 6.354949) (xy 245.759561 6.282043) (xy 245.707885 6.213614)
			(xy 245.650116 6.150244) (xy 245.586746 6.092475) (xy 245.518317 6.040799) (xy 245.445411 5.995658)
			(xy 245.368651 5.957436) (xy 245.288692 5.92646) (xy 245.206216 5.902993) (xy 245.121926 5.887237)
			(xy 245.036543 5.879325) (xy 244.950793 5.879325) (xy 244.86541 5.887237) (xy 244.78112 5.902993)
			(xy 244.698644 5.92646) (xy 244.618685 5.957436) (xy 244.541925 5.995658) (xy 244.469019 6.040799)
			(xy 244.40059 6.092475) (xy 244.33722 6.150244) (xy 244.279451 6.213614) (xy 244.227775 6.282043)
			(xy 244.182634 6.354949) (xy 244.144412 6.431709) (xy 244.113436 6.511668) (xy 244.089969 6.594144)
			(xy 244.074213 6.678434) (xy 244.066301 6.763817) (xy 239.571035 6.763817) (xy 239.563123 6.678434)
			(xy 239.547367 6.594144) (xy 239.5239 6.511668) (xy 239.492924 6.431709) (xy 239.454702 6.354949)
			(xy 239.409561 6.282043) (xy 239.357885 6.213614) (xy 239.300116 6.150244) (xy 239.236746 6.092475)
			(xy 239.168317 6.040799) (xy 239.095411 5.995658) (xy 239.018651 5.957436) (xy 238.938692 5.92646)
			(xy 238.856216 5.902993) (xy 238.771926 5.887237) (xy 238.686543 5.879325) (xy 238.600793 5.879325)
			(xy 238.51541 5.887237) (xy 238.43112 5.902993) (xy 238.348644 5.92646) (xy 238.268685 5.957436)
			(xy 238.191925 5.995658) (xy 238.119019 6.040799) (xy 238.05059 6.092475) (xy 237.98722 6.150244)
			(xy 237.929451 6.213614) (xy 237.877775 6.282043) (xy 237.832634 6.354949) (xy 237.794412 6.431709)
			(xy 237.763436 6.511668) (xy 237.739969 6.594144) (xy 237.724213 6.678434) (xy 237.716301 6.763817)
			(xy 187.719832 6.763817) (xy 187.712579 6.685546) (xy 187.696823 6.601256) (xy 187.673356 6.51878)
			(xy 187.64238 6.438821) (xy 187.604158 6.362061) (xy 187.559017 6.289155) (xy 187.507341 6.220726)
			(xy 187.449572 6.157356) (xy 187.386202 6.099587) (xy 187.317773 6.047911) (xy 187.244867 6.00277)
			(xy 187.168107 5.964548) (xy 187.088148 5.933572) (xy 187.005672 5.910105) (xy 186.921382 5.894349)
			(xy 186.835999 5.886437) (xy 186.750249 5.886437) (xy 186.664866 5.894349) (xy 186.580576 5.910105)
			(xy 186.4981 5.933572) (xy 186.418141 5.964548) (xy 186.341381 6.00277) (xy 186.268475 6.047911)
			(xy 186.200046 6.099587) (xy 186.136676 6.157356) (xy 186.078907 6.220726) (xy 186.027231 6.289155)
			(xy 185.98209 6.362061) (xy 185.943868 6.438821) (xy 185.912892 6.51878) (xy 185.889425 6.601256)
			(xy 185.873669 6.685546) (xy 185.865757 6.770929) (xy 181.370491 6.770929) (xy 181.362579 6.685546)
			(xy 181.346823 6.601256) (xy 181.323356 6.51878) (xy 181.29238 6.438821) (xy 181.254158 6.362061)
			(xy 181.209017 6.289155) (xy 181.157341 6.220726) (xy 181.099572 6.157356) (xy 181.036202 6.099587)
			(xy 180.967773 6.047911) (xy 180.894867 6.00277) (xy 180.818107 5.964548) (xy 180.738148 5.933572)
			(xy 180.655672 5.910105) (xy 180.571382 5.894349) (xy 180.485999 5.886437) (xy 180.400249 5.886437)
			(xy 180.314866 5.894349) (xy 180.230576 5.910105) (xy 180.1481 5.933572) (xy 180.068141 5.964548)
			(xy 179.991381 6.00277) (xy 179.918475 6.047911) (xy 179.850046 6.099587) (xy 179.786676 6.157356)
			(xy 179.728907 6.220726) (xy 179.677231 6.289155) (xy 179.63209 6.362061) (xy 179.593868 6.438821)
			(xy 179.562892 6.51878) (xy 179.539425 6.601256) (xy 179.523669 6.685546) (xy 179.515757 6.770929)
			(xy 158.039844 6.770929) (xy 158.030561 6.759289) (xy 157.936801 6.654373) (xy 157.837306 6.554879)
			(xy 157.732388 6.46112) (xy 157.622379 6.373391) (xy 157.507624 6.291969) (xy 157.388483 6.21711)
			(xy 157.265333 6.149048) (xy 157.138561 6.087998) (xy 157.008565 6.034153) (xy 156.875754 5.987681)
			(xy 156.740546 5.948729) (xy 156.603367 5.91742) (xy 156.464649 5.893851) (xy 156.324827 5.878098)
			(xy 156.184341 5.870209) (xy 156.113988 5.869686) (xy 17.493996 5.869686) (xy 17.423642 5.870179)
			(xy 17.283156 5.878069) (xy 17.143333 5.893824) (xy 17.004613 5.917393) (xy 16.867433 5.948703) (xy 16.732225 5.987656)
			(xy 16.599413 6.034129) (xy 16.469416 6.087976) (xy 16.342643 6.149026) (xy 16.219492 6.217089) (xy 16.100351 6.29195)
			(xy 15.985596 6.373373) (xy 15.875586 6.461103) (xy 15.770668 6.554863) (xy 15.671172 6.654358) (xy 15.577412 6.759275)
			(xy 15.489682 6.869284) (xy 15.408258 6.98404) (xy 15.333396 7.10318) (xy 15.265333 7.22633) (xy 15.204281 7.353103)
			(xy 15.150434 7.4831) (xy 15.103961 7.615912) (xy 15.065007 7.75112) (xy 15.033696 7.8883) (xy 15.010125 8.027019)
			(xy 14.99437 8.166842) (xy 14.98648 8.307328) (xy 14.986 8.377682) (xy 14.986 24.157686) (xy 14.985478 24.213493)
			(xy 14.977137 24.324795) (xy 14.960501 24.435162) (xy 14.935664 24.543977) (xy 14.902765 24.650632)
			(xy 14.861988 24.754531) (xy 14.81356 24.855091) (xy 14.757753 24.951752) (xy 14.694879 25.043971)
			(xy 14.625289 25.131234) (xy 14.549372 25.213053) (xy 14.467553 25.28897) (xy 14.38029 25.35856)
			(xy 14.28807 25.421434) (xy 14.19141 25.477241) (xy 14.090849 25.525669) (xy 13.986951 25.566446)
			(xy 13.880295 25.599345) (xy 13.77148 25.624182) (xy 13.661113 25.640817) (xy 13.549811 25.649158)
			(xy 13.494004 25.649682) (xy 1.999996 25.649682) (xy 1.944189 25.64916) (xy 1.832887 25.640819) (xy 1.72252 25.624184)
			(xy 1.613704 25.599347) (xy 1.507049 25.566448) (xy 1.40315 25.525671) (xy 1.30259 25.477243) (xy 1.205929 25.421436)
			(xy 1.113709 25.358562) (xy 1.026446 25.288971) (xy 0.944627 25.213055) (xy 0.86871 25.131236) (xy 0.79912 25.043972)
			(xy 0.736245 24.951753) (xy 0.680438 24.855092) (xy 0.63201 24.754532) (xy 0.591233 24.650633) (xy 0.558334 24.543978)
			(xy 0.533497 24.435162) (xy 0.516861 24.324795) (xy 0.50852 24.213493) (xy 0.508 24.157686) (xy 0.508 21.093122)
			(xy 2.904225 21.093122) (xy 2.904225 21.222262) (xy 2.912175 21.351157) (xy 2.928045 21.479317) (xy 2.951774 21.606258)
			(xy 2.983273 21.731497) (xy 3.022422 21.85456) (xy 3.069073 21.974979) (xy 3.123048 22.092298) (xy 3.184143 22.206072)
			(xy 3.252126 22.315869) (xy 3.32674 22.421272) (xy 3.407701 22.521882) (xy 3.494701 22.617317) (xy 3.587412 22.707216)
			(xy 3.685482 22.791237) (xy 3.788537 22.869061) (xy 3.896188 22.940393) (xy 4.008027 23.004963) (xy 4.123628 23.062525)
			(xy 4.242553 23.112862) (xy 4.364352 23.155782) (xy 4.488562 23.191123) (xy 4.614711 23.21875) (xy 4.742323 23.238559)
			(xy 4.870912 23.250475) (xy 4.99999 23.254452) (xy 5.129068 23.250475) (xy 5.257657 23.238559) (xy 5.385269 23.21875)
			(xy 5.511418 23.191123) (xy 5.635628 23.155782) (xy 5.757427 23.112862) (xy 5.876352 23.062525) (xy 5.991953 23.004963)
			(xy 6.103792 22.940393) (xy 6.211443 22.869061) (xy 6.314498 22.791237) (xy 6.412568 22.707216) (xy 6.505279 22.617317)
			(xy 6.592279 22.521882) (xy 6.67324 22.421272) (xy 6.747854 22.315869) (xy 6.815837 22.206072) (xy 6.876932 22.092298)
			(xy 6.930907 21.974979) (xy 6.977558 21.85456) (xy 7.016707 21.731497) (xy 7.048206 21.606258) (xy 7.071935 21.479317)
			(xy 7.087805 21.351157) (xy 7.095755 21.222262) (xy 7.096252 21.157692) (xy 7.095755 21.093122) (xy 7.087805 20.964227)
			(xy 7.071935 20.836067) (xy 7.048206 20.709126) (xy 7.016707 20.583887) (xy 6.977558 20.460824) (xy 6.930907 20.340405)
			(xy 6.876932 20.223086) (xy 6.815837 20.109312) (xy 6.747854 19.999515) (xy 6.67324 19.894112) (xy 6.592279 19.793502)
			(xy 6.505279 19.698067) (xy 6.412568 19.608168) (xy 6.314498 19.524147) (xy 6.211443 19.446323) (xy 6.103792 19.374991)
			(xy 5.991953 19.310421) (xy 5.876352 19.252859) (xy 5.757427 19.202522) (xy 5.635628 19.159602) (xy 5.511418 19.124261)
			(xy 5.385269 19.096634) (xy 5.257657 19.076825) (xy 5.129068 19.064909) (xy 4.99999 19.060933) (xy 4.870912 19.064909)
			(xy 4.742323 19.076825) (xy 4.614711 19.096634) (xy 4.488562 19.124261) (xy 4.364352 19.159602) (xy 4.242553 19.202522)
			(xy 4.123628 19.252859) (xy 4.008027 19.310421) (xy 3.896188 19.374991) (xy 3.788537 19.446323) (xy 3.685482 19.524147)
			(xy 3.587412 19.608168) (xy 3.494701 19.698067) (xy 3.407701 19.793502) (xy 3.32674 19.894112) (xy 3.252126 19.999515)
			(xy 3.184143 20.109312) (xy 3.123048 20.223086) (xy 3.069073 20.340405) (xy 3.022422 20.460824) (xy 2.983273 20.583887)
			(xy 2.951774 20.709126) (xy 2.928045 20.836067) (xy 2.912175 20.964227) (xy 2.904225 21.093122) (xy 0.508 21.093122)
			(xy 0.508 3.999992) (xy 0.508522 3.944185) (xy 0.516863 3.832883) (xy 0.533498 3.722516) (xy 0.558335 3.6137)
			(xy 0.591234 3.507045) (xy 0.632011 3.403146) (xy 0.680438 3.302586) (xy 0.736246 3.205925) (xy 0.79912 3.113705)
			(xy 0.86871 3.026442) (xy 0.944627 2.944623) (xy 1.026446 2.868706) (xy 1.113709 2.799116) (xy 1.205929 2.736242)
			(xy 1.30259 2.680434) (xy 1.40315 2.632007) (xy 1.507049 2.59123) (xy 1.613704 2.558331) (xy 1.72252 2.533494)
			(xy 1.832887 2.516859) (xy 1.944189 2.508518) (xy 1.999996 2.507996) (xy 7.964932 2.507996) (xy 8.035286 2.507503)
			(xy 8.175772 2.499613) (xy 8.315594 2.483859) (xy 8.454314 2.460289) (xy 8.591493 2.428979) (xy 8.726701 2.390026)
			(xy 8.859513 2.343553) (xy 8.989509 2.289707) (xy 9.116282 2.228656) (xy 9.239433 2.160593) (xy 9.358573 2.085732)
			(xy 9.473329 2.004309) (xy 9.583338 1.916579) (xy 9.688255 1.822819) (xy 9.78775 1.723324) (xy 9.88151 1.618406)
			(xy 9.96924 1.508397) (xy 10.050663 1.393641) (xy 10.125524 1.274501) (xy 10.193587 1.151351) (xy 10.254637 1.024578)
			(xy 10.308484 0.894581) (xy 10.354957 0.76177) (xy 10.393909 0.626561) (xy 10.42522 0.489382) (xy 10.448789 0.350662)
			(xy 10.464543 0.21084) (xy 10.472433 0.070354) (xy 10.472928 0) (xy 10.472928 -8.850122) (xy 10.47345 -8.905929)
			(xy 10.481791 -9.017231) (xy 10.498426 -9.127599) (xy 10.523263 -9.236414) (xy 10.556162 -9.34307)
			(xy 10.596939 -9.446968) (xy 10.645366 -9.547529) (xy 10.701173 -9.64419) (xy 10.764048 -9.73641)
			(xy 10.833638 -9.823673) (xy 10.909555 -9.905492) (xy 10.991374 -9.981409) (xy 11.078637 -10.051)
			(xy 11.170857 -10.113875) (xy 11.267517 -10.169682) (xy 11.368078 -10.21811) (xy 11.471977 -10.258887)
			(xy 11.578632 -10.291786) (xy 11.687448 -10.316623) (xy 11.797815 -10.333259) (xy 11.909117 -10.3416)
			(xy 11.964924 -10.342118)
		)
		(stroke
			(width 0)
			(type solid)
		)
		(fill yes)
		(layer "In16.Cu")
		(net "COUPON_GND2")
	)
	(gr_poly
		(pts
			(xy 7.987284 -418.080952) (xy 200.481184 -418.080952) (xy 200.53776 -418.08043) (xy 200.650587 -418.071859)
			(xy 200.762439 -418.054758) (xy 200.872672 -418.029225) (xy 200.980652 -417.995406) (xy 201.085757 -417.953498)
			(xy 201.187381 -417.90374) (xy 201.28494 -417.84642) (xy 201.377872 -417.781868) (xy 201.465642 -417.710455)
			(xy 201.547744 -417.632592) (xy 201.586084 -417.590986) (xy 201.633303 -417.539598) (xy 201.732638 -417.441554)
			(xy 201.837271 -417.349184) (xy 201.946878 -417.262774) (xy 202.06112 -417.182592) (xy 202.179643 -417.108886)
			(xy 202.302081 -417.041884) (xy 202.428054 -416.981794) (xy 202.557174 -416.9288) (xy 202.689041 -416.883067)
			(xy 202.823246 -416.844737) (xy 202.959375 -416.813928) (xy 203.097007 -416.790736) (xy 203.235715 -416.775231)
			(xy 203.37507 -416.767463) (xy 203.444856 -416.76701) (xy 271.794986 -416.76701) (xy 271.864771 -416.767495)
			(xy 272.004124 -416.77527) (xy 272.142829 -416.790779) (xy 272.280457 -416.813975) (xy 272.416584 -416.844786)
			(xy 272.550787 -416.883117) (xy 272.682651 -416.92885) (xy 272.811769 -416.981841) (xy 272.937742 -417.041929)
			(xy 273.06018 -417.108927) (xy 273.178704 -417.182628) (xy 273.292947 -417.262803) (xy 273.402557 -417.349206)
			(xy 273.436768 -417.379404) (xy 313.073796 -417.379404) (xy 313.073796 -394.27912) (xy 326.479662 -394.27912)
			(xy 326.525636 -394.325094) (xy 326.525636 -397.823826) (xy 330.929171 -397.823826) (xy 330.929175 -397.756517)
			(xy 330.937223 -397.689692) (xy 330.953201 -397.624307) (xy 330.976879 -397.561301) (xy 331.007918 -397.501576)
			(xy 331.045873 -397.44599) (xy 331.067664 -397.420338) (xy 331.073477 -397.413205) (xy 331.07998 -397.396005)
			(xy 331.080364 -397.38681) (xy 331.080364 -396.893542) (xy 331.079919 -396.884359) (xy 331.073428 -396.867175)
			(xy 331.067664 -396.860014) (xy 331.045866 -396.83437) (xy 331.007916 -396.778783) (xy 330.976881 -396.719059)
			(xy 330.953208 -396.656053) (xy 330.937235 -396.59067) (xy 330.929191 -396.523846) (xy 330.929192 -396.456539)
			(xy 330.937238 -396.389716) (xy 330.953213 -396.324333) (xy 330.976888 -396.261328) (xy 331.007923 -396.201604)
			(xy 331.045875 -396.146018) (xy 331.067664 -396.120366) (xy 331.073465 -396.113225) (xy 331.079975 -396.096031)
			(xy 331.080364 -396.086838) (xy 331.080364 -395.92885) (xy 331.080805 -395.918678) (xy 331.088579 -395.89988)
			(xy 331.10296 -395.885492) (xy 331.121755 -395.87771) (xy 331.131926 -395.877288) (xy 331.848206 -395.877288)
			(xy 331.858384 -395.87766) (xy 331.877189 -395.885456) (xy 331.891575 -395.899859) (xy 331.899351 -395.918671)
			(xy 331.899768 -395.92885) (xy 331.899768 -396.086838) (xy 331.900167 -396.096026) (xy 331.906689 -396.11321)
			(xy 331.912468 -396.120366) (xy 331.934246 -396.146026) (xy 331.972195 -396.201612) (xy 332.003228 -396.261334)
			(xy 332.026901 -396.324338) (xy 332.042874 -396.389719) (xy 332.050919 -396.45654) (xy 332.05092 -396.523845)
			(xy 332.042877 -396.590666) (xy 332.026905 -396.656048) (xy 332.003234 -396.719052) (xy 331.972202 -396.778775)
			(xy 331.934255 -396.834362) (xy 331.912468 -396.860014) (xy 331.906679 -396.867164) (xy 331.90016 -396.884351)
			(xy 331.899768 -396.893542) (xy 331.899768 -397.38681) (xy 331.90018 -397.395997) (xy 331.906693 -397.413181)
			(xy 331.912468 -397.420338) (xy 331.934218 -397.446021) (xy 331.972167 -397.501603) (xy 332.00059 -397.556296)
			(xy 333.128836 -397.556296) (xy 333.136911 -397.489358) (xy 333.152946 -397.423869) (xy 333.17671 -397.360773)
			(xy 333.20786 -397.300977) (xy 333.245948 -397.245343) (xy 333.267812 -397.219678) (xy 333.273602 -397.212528)
			(xy 333.28012 -397.195341) (xy 333.280512 -397.18615) (xy 333.280512 -397.028924) (xy 333.280936 -397.018802)
			(xy 333.288678 -397.000096) (xy 333.302993 -396.985781) (xy 333.321698 -396.978037) (xy 333.33182 -396.977616)
			(xy 334.0481 -396.977616) (xy 334.058224 -396.978016) (xy 334.076931 -396.985768) (xy 334.091246 -397.000089)
			(xy 334.098988 -397.018799) (xy 334.099408 -397.028924) (xy 334.099408 -397.18615) (xy 334.09984 -397.195335)
			(xy 334.106338 -397.21252) (xy 334.112108 -397.219678) (xy 334.133982 -397.245335) (xy 334.172069 -397.300971)
			(xy 334.203219 -397.360769) (xy 334.226982 -397.423866) (xy 334.243017 -397.489356) (xy 334.251092 -397.556295)
			(xy 334.251091 -397.62372) (xy 334.243014 -397.690658) (xy 334.226978 -397.756148) (xy 334.203213 -397.819245)
			(xy 334.200796 -397.823884) (xy 335.328964 -397.823884) (xy 335.328968 -397.756459) (xy 335.337047 -397.689518)
			(xy 335.353085 -397.624028) (xy 335.376852 -397.560929) (xy 335.408005 -397.501132) (xy 335.446095 -397.445496)
			(xy 335.46796 -397.41983) (xy 335.473776 -397.412699) (xy 335.480277 -397.395497) (xy 335.48066 -397.386302)
			(xy 335.48066 -396.89405) (xy 335.480213 -396.884867) (xy 335.473723 -396.867683) (xy 335.46796 -396.860522)
			(xy 335.446088 -396.834864) (xy 335.408002 -396.779228) (xy 335.376854 -396.71943) (xy 335.353092 -396.656332)
			(xy 335.337058 -396.590843) (xy 335.328984 -396.523904) (xy 335.328985 -396.456481) (xy 335.337061 -396.389542)
			(xy 335.353096 -396.324053) (xy 335.37686 -396.260956) (xy 335.40801 -396.201159) (xy 335.446097 -396.145524)
			(xy 335.46796 -396.119858) (xy 335.473764 -396.112719) (xy 335.480273 -396.095523) (xy 335.48066 -396.08633)
			(xy 335.48066 -395.92885) (xy 335.481168 -395.918724) (xy 335.488883 -395.9) (xy 335.503164 -395.885642)
			(xy 335.521845 -395.877824) (xy 335.531968 -395.877288) (xy 336.248248 -395.877288) (xy 336.258404 -395.877682)
			(xy 336.277155 -395.885491) (xy 336.291476 -395.899896) (xy 336.299176 -395.918692) (xy 336.299556 -395.92885)
			(xy 336.299556 -396.08633) (xy 336.299962 -396.095517) (xy 336.30648 -396.112701) (xy 336.312256 -396.119858)
			(xy 336.334112 -396.145531) (xy 336.372204 -396.201163) (xy 336.403357 -396.260958) (xy 336.427124 -396.324054)
			(xy 336.443161 -396.389542) (xy 336.451239 -396.456481) (xy 336.45124 -396.523904) (xy 336.443164 -396.590843)
			(xy 336.427128 -396.656332) (xy 336.403363 -396.719428) (xy 336.372211 -396.779224) (xy 336.334121 -396.834858)
			(xy 336.312256 -396.860522) (xy 336.306462 -396.867669) (xy 336.299947 -396.884858) (xy 336.299556 -396.89405)
			(xy 336.299556 -397.386302) (xy 336.299975 -397.395488) (xy 336.306484 -397.412672) (xy 336.312256 -397.41983)
			(xy 336.334084 -397.445525) (xy 336.372177 -397.501154) (xy 336.40094 -397.556356) (xy 337.529156 -397.556356)
			(xy 337.537198 -397.489535) (xy 337.553169 -397.424153) (xy 337.576839 -397.361149) (xy 337.607869 -397.301426)
			(xy 337.645814 -397.245839) (xy 337.6676 -397.220186) (xy 337.673385 -397.213033) (xy 337.679907 -397.195848)
			(xy 337.6803 -397.186658) (xy 337.6803 -397.028924) (xy 337.680741 -397.018771) (xy 337.688529 -397.000019)
			(xy 337.70292 -396.985695) (xy 337.721708 -396.977995) (xy 337.731862 -396.977616) (xy 338.448142 -396.977616)
			(xy 338.458268 -396.978091) (xy 338.476986 -396.985829) (xy 338.49134 -397.000118) (xy 338.499162 -397.0188)
			(xy 338.499704 -397.028924) (xy 338.499704 -397.186658) (xy 338.500133 -397.195843) (xy 338.506634 -397.213028)
			(xy 338.512404 -397.220186) (xy 338.5342 -397.245831) (xy 338.572146 -397.301419) (xy 338.603176 -397.361144)
			(xy 338.626847 -397.42415) (xy 338.642818 -397.489532) (xy 338.65086 -397.556355) (xy 338.650859 -397.62366)
			(xy 338.642815 -397.690483) (xy 338.626842 -397.755865) (xy 338.60317 -397.81887) (xy 338.600595 -397.823826)
			(xy 339.729259 -397.823826) (xy 339.729263 -397.756517) (xy 339.737311 -397.689692) (xy 339.753288 -397.624308)
			(xy 339.776965 -397.561301) (xy 339.808004 -397.501577) (xy 339.845958 -397.44599) (xy 339.867748 -397.420338)
			(xy 339.873559 -397.413204) (xy 339.880064 -397.396005) (xy 339.880448 -397.38681) (xy 339.880448 -396.893542)
			(xy 339.880007 -396.884358) (xy 339.873513 -396.867174) (xy 339.867748 -396.860014) (xy 339.84595 -396.83437)
			(xy 339.808001 -396.778783) (xy 339.776968 -396.719058) (xy 339.753295 -396.656052) (xy 339.737322 -396.590669)
			(xy 339.729279 -396.523845) (xy 339.72928 -396.456539) (xy 339.737325 -396.389716) (xy 339.753299 -396.324333)
			(xy 339.776974 -396.261328) (xy 339.808009 -396.201604) (xy 339.845959 -396.146018) (xy 339.867748 -396.120366)
			(xy 339.873547 -396.113223) (xy 339.880059 -396.096031) (xy 339.880448 -396.086838) (xy 339.880448 -395.92885)
			(xy 339.880905 -395.91868) (xy 339.888675 -395.899885) (xy 339.903051 -395.885498) (xy 339.921841 -395.877713)
			(xy 339.93201 -395.877288) (xy 340.64829 -395.877288) (xy 340.658467 -395.877673) (xy 340.677271 -395.885464)
			(xy 340.691658 -395.899862) (xy 340.699435 -395.918672) (xy 340.699852 -395.92885) (xy 340.699852 -396.086838)
			(xy 340.700255 -396.096026) (xy 340.706775 -396.113209) (xy 340.712552 -396.120366) (xy 340.73433 -396.146026)
			(xy 340.77228 -396.201611) (xy 340.803314 -396.261334) (xy 340.826988 -396.324337) (xy 340.842962 -396.389718)
			(xy 340.851007 -396.45654) (xy 340.851007 -396.523845) (xy 340.842964 -396.590667) (xy 340.826992 -396.656048)
			(xy 340.80332 -396.719053) (xy 340.772287 -396.778776) (xy 340.734339 -396.834362) (xy 340.712552 -396.860014)
			(xy 340.706761 -396.867163) (xy 340.700244 -396.884351) (xy 340.699852 -396.893542) (xy 340.699852 -397.38681)
			(xy 340.700268 -397.395996) (xy 340.706779 -397.41318) (xy 340.712552 -397.420338) (xy 340.734302 -397.446021)
			(xy 340.772253 -397.501603) (xy 340.800676 -397.556296) (xy 341.928924 -397.556296) (xy 341.936999 -397.489359)
			(xy 341.953033 -397.42387) (xy 341.976796 -397.360774) (xy 342.007946 -397.300978) (xy 342.046033 -397.245343)
			(xy 342.067896 -397.219678) (xy 342.073684 -397.212527) (xy 342.080204 -397.195341) (xy 342.080596 -397.18615)
			(xy 342.080596 -397.028924) (xy 342.081035 -397.018804) (xy 342.088775 -397.000101) (xy 342.103084 -396.985786)
			(xy 342.121784 -396.978039) (xy 342.131904 -396.977616) (xy 342.848184 -396.977616) (xy 342.858307 -396.978029)
			(xy 342.877014 -396.985775) (xy 342.891329 -397.000093) (xy 342.899072 -397.0188) (xy 342.899492 -397.028924)
			(xy 342.899492 -397.18615) (xy 342.899928 -397.195334) (xy 342.906424 -397.212519) (xy 342.912192 -397.219678)
			(xy 342.934066 -397.245335) (xy 342.972155 -397.300971) (xy 343.003306 -397.360768) (xy 343.02707 -397.423866)
			(xy 343.043105 -397.489356) (xy 343.05118 -397.556295) (xy 343.051179 -397.62372) (xy 343.043102 -397.690659)
			(xy 343.027065 -397.756149) (xy 343.0033 -397.819246) (xy 343.000914 -397.823825) (xy 344.12905 -397.823825)
			(xy 344.129054 -397.756517) (xy 344.137101 -397.689692) (xy 344.153078 -397.624308) (xy 344.176755 -397.561302)
			(xy 344.207793 -397.501577) (xy 344.245746 -397.44599) (xy 344.267536 -397.420338) (xy 344.273346 -397.413202)
			(xy 344.279852 -397.396004) (xy 344.280236 -397.38681) (xy 344.280236 -396.893542) (xy 344.279797 -396.884358)
			(xy 344.273303 -396.867174) (xy 344.267536 -396.860014) (xy 344.245738 -396.83437) (xy 344.20779 -396.778782)
			(xy 344.176757 -396.719058) (xy 344.153085 -396.656052) (xy 344.137113 -396.590669) (xy 344.12907 -396.523845)
			(xy 344.129071 -396.45654) (xy 344.137116 -396.389716) (xy 344.15309 -396.324334) (xy 344.176764 -396.261329)
			(xy 344.207798 -396.201605) (xy 344.245748 -396.146018) (xy 344.267536 -396.120366) (xy 344.273334 -396.113222)
			(xy 344.279847 -396.09603) (xy 344.280236 -396.086838) (xy 344.280236 -395.92885) (xy 344.280705 -395.918682)
			(xy 344.288473 -395.899889) (xy 344.302845 -395.885502) (xy 344.32163 -395.877715) (xy 344.331798 -395.877288)
			(xy 345.048078 -395.877288) (xy 345.058254 -395.877683) (xy 345.077058 -395.88547) (xy 345.091445 -395.899866)
			(xy 345.099222 -395.918673) (xy 345.09964 -395.92885) (xy 345.09964 -396.086838) (xy 345.100045 -396.096025)
			(xy 345.106564 -396.113209) (xy 345.11234 -396.120366) (xy 345.134118 -396.146026) (xy 345.172069 -396.201611)
			(xy 345.203104 -396.261333) (xy 345.226778 -396.324337) (xy 345.242752 -396.389718) (xy 345.250798 -396.45654)
			(xy 345.250798 -396.523845) (xy 345.242755 -396.590667) (xy 345.226782 -396.656049) (xy 345.20311 -396.719053)
			(xy 345.172077 -396.778776) (xy 345.134128 -396.834362) (xy 345.11234 -396.860014) (xy 345.106548 -396.867162)
			(xy 345.100032 -396.884351) (xy 345.09964 -396.893542) (xy 345.09964 -397.38681) (xy 345.100059 -397.395996)
			(xy 345.106568 -397.41318) (xy 345.11234 -397.420338) (xy 345.134091 -397.446021) (xy 345.172042 -397.501602)
			(xy 345.200497 -397.556355) (xy 346.32922 -397.556355) (xy 346.337264 -397.489532) (xy 346.353237 -397.42415)
			(xy 346.37691 -397.361146) (xy 346.407945 -397.301423) (xy 346.445896 -397.245838) (xy 346.467684 -397.220186)
			(xy 346.473467 -397.213031) (xy 346.47999 -397.195848) (xy 346.480384 -397.186658) (xy 346.480384 -397.028924)
			(xy 346.480841 -397.018773) (xy 346.488625 -397.000025) (xy 346.503011 -396.985701) (xy 346.521794 -396.977997)
			(xy 346.531946 -396.977616) (xy 347.248226 -396.977616) (xy 347.258351 -396.978104) (xy 347.277069 -396.985836)
			(xy 347.291423 -397.000121) (xy 347.299246 -397.018801) (xy 347.299788 -397.028924) (xy 347.299788 -397.186658)
			(xy 347.300221 -397.195843) (xy 347.306719 -397.213027) (xy 347.312488 -397.220186) (xy 347.334285 -397.24583)
			(xy 347.372232 -397.301419) (xy 347.403263 -397.361143) (xy 347.426934 -397.424149) (xy 347.442905 -397.489532)
			(xy 347.450948 -397.556355) (xy 347.450947 -397.62366) (xy 347.442903 -397.690483) (xy 347.426929 -397.755865)
			(xy 347.403257 -397.81887) (xy 347.400682 -397.823826) (xy 374.92908 -397.823826) (xy 374.929084 -397.756517)
			(xy 374.937132 -397.689691) (xy 374.95311 -397.624306) (xy 374.976789 -397.5613) (xy 375.007829 -397.501576)
			(xy 375.045785 -397.445989) (xy 375.067576 -397.420338) (xy 375.073379 -397.413197) (xy 375.07989 -397.396003)
			(xy 375.080276 -397.38681) (xy 375.080276 -396.893542) (xy 375.079851 -396.884356) (xy 375.073348 -396.867171)
			(xy 375.067576 -396.860014) (xy 375.045777 -396.83437) (xy 375.007826 -396.778784) (xy 374.976792 -396.719059)
			(xy 374.953118 -396.656053) (xy 374.937144 -396.59067) (xy 374.9291 -396.523846) (xy 374.929101 -396.456539)
			(xy 374.937147 -396.389715) (xy 374.953122 -396.324332) (xy 374.976798 -396.261327) (xy 375.007834 -396.201604)
			(xy 375.045787 -396.146018) (xy 375.067576 -396.120366) (xy 375.073367 -396.113216) (xy 375.079886 -396.096029)
			(xy 375.080276 -396.086838) (xy 375.080276 -395.92885) (xy 375.080706 -395.918677) (xy 375.088481 -395.899876)
			(xy 375.102866 -395.885488) (xy 375.121665 -395.877708) (xy 375.131838 -395.877288) (xy 375.848118 -395.877288)
			(xy 375.858297 -395.87765) (xy 375.877102 -395.885451) (xy 375.891487 -395.899856) (xy 375.899263 -395.91867)
			(xy 375.89968 -395.92885) (xy 375.89968 -396.086838) (xy 375.900076 -396.096027) (xy 375.9066 -396.113211)
			(xy 375.91238 -396.120366) (xy 375.934157 -396.146026) (xy 375.972105 -396.201612) (xy 376.003138 -396.261335)
			(xy 376.02681 -396.324338) (xy 376.042784 -396.389719) (xy 376.050828 -396.456541) (xy 376.050829 -396.523844)
			(xy 376.042786 -396.590666) (xy 376.026815 -396.656047) (xy 376.003144 -396.719051) (xy 375.972113 -396.778775)
			(xy 375.934167 -396.834362) (xy 375.91238 -396.860014) (xy 375.906593 -396.867166) (xy 375.900073 -396.884351)
			(xy 375.89968 -396.893542) (xy 375.89968 -397.38681) (xy 375.90009 -397.395997) (xy 375.906604 -397.413181)
			(xy 375.91238 -397.420338) (xy 375.93413 -397.446021) (xy 375.972078 -397.501604) (xy 376.0005 -397.556296)
			(xy 377.128745 -397.556296) (xy 377.136821 -397.489358) (xy 377.152856 -397.423869) (xy 377.17662 -397.360772)
			(xy 377.207771 -397.300977) (xy 377.24586 -397.245343) (xy 377.267724 -397.219678) (xy 377.273515 -397.212529)
			(xy 377.280032 -397.195341) (xy 377.280424 -397.18615) (xy 377.280424 -397.028924) (xy 377.280836 -397.0188)
			(xy 377.288581 -397.000092) (xy 377.302899 -396.985776) (xy 377.321608 -396.978034) (xy 377.331732 -396.977616)
			(xy 378.048012 -396.977616) (xy 378.058137 -396.978006) (xy 378.076844 -396.985761) (xy 378.091159 -397.000086)
			(xy 378.098901 -397.018798) (xy 378.09932 -397.028924) (xy 378.09932 -397.18615) (xy 378.09975 -397.195335)
			(xy 378.10625 -397.21252) (xy 378.11202 -397.219678) (xy 378.133893 -397.245335) (xy 378.17198 -397.300972)
			(xy 378.203129 -397.360769) (xy 378.226892 -397.423867) (xy 378.242926 -397.489357) (xy 378.251001 -397.556295)
			(xy 378.251 -397.62372) (xy 378.242924 -397.690658) (xy 378.226888 -397.756147) (xy 378.203123 -397.819245)
			(xy 378.200706 -397.823885) (xy 379.328873 -397.823885) (xy 379.328877 -397.756458) (xy 379.336956 -397.689518)
			(xy 379.352995 -397.624027) (xy 379.376762 -397.560929) (xy 379.407915 -397.501131) (xy 379.446007 -397.445496)
			(xy 379.467872 -397.41983) (xy 379.47369 -397.4127) (xy 379.48019 -397.395498) (xy 379.480572 -397.386302)
			(xy 379.480572 -396.89405) (xy 379.480144 -396.884865) (xy 379.473643 -396.86768) (xy 379.467872 -396.860522)
			(xy 379.445999 -396.834864) (xy 379.407913 -396.779228) (xy 379.376764 -396.719431) (xy 379.353002 -396.656333)
			(xy 379.336968 -396.590843) (xy 379.328893 -396.523904) (xy 379.328894 -396.456481) (xy 379.33697 -396.389542)
			(xy 379.353006 -396.324053) (xy 379.37677 -396.260956) (xy 379.40792 -396.201159) (xy 379.446008 -396.145524)
			(xy 379.467872 -396.119858) (xy 379.473678 -396.11272) (xy 379.480185 -396.095524) (xy 379.480572 -396.08633)
			(xy 379.480572 -395.92885) (xy 379.481069 -395.918723) (xy 379.488786 -395.899996) (xy 379.50307 -395.885637)
			(xy 379.521755 -395.877822) (xy 379.53188 -395.877288) (xy 380.24816 -395.877288) (xy 380.258278 -395.877749)
			(xy 380.276979 -395.885481) (xy 380.291294 -395.899784) (xy 380.299043 -395.918478) (xy 380.299468 -395.928596)
			(xy 380.299468 -396.08633) (xy 380.299871 -396.095518) (xy 380.30639 -396.112702) (xy 380.312168 -396.119858)
			(xy 380.334023 -396.145531) (xy 380.372114 -396.201163) (xy 380.403267 -396.260958) (xy 380.427033 -396.324054)
			(xy 380.443071 -396.389543) (xy 380.451148 -396.456481) (xy 380.451149 -396.523904) (xy 380.443073 -396.590842)
			(xy 380.427038 -396.656331) (xy 380.403273 -396.719428) (xy 380.372122 -396.779224) (xy 380.334032 -396.834857)
			(xy 380.312168 -396.860522) (xy 380.306375 -396.86767) (xy 380.299859 -396.884858) (xy 380.299468 -396.89405)
			(xy 380.299468 -397.386302) (xy 380.299884 -397.395488) (xy 380.306394 -397.412672) (xy 380.312168 -397.41983)
			(xy 380.333996 -397.445525) (xy 380.372088 -397.501155) (xy 380.40085 -397.556356) (xy 381.529065 -397.556356)
			(xy 381.537108 -397.489534) (xy 381.553079 -397.424153) (xy 381.576749 -397.361149) (xy 381.60778 -397.301425)
			(xy 381.645726 -397.245838) (xy 381.667512 -397.220186) (xy 381.673298 -397.213034) (xy 381.679819 -397.195849)
			(xy 381.680212 -397.186658) (xy 381.680212 -397.028924) (xy 381.680636 -397.018802) (xy 381.688378 -397.000096)
			(xy 381.702693 -396.985781) (xy 381.721398 -396.978037) (xy 381.73152 -396.977616) (xy 382.448054 -396.977616)
			(xy 382.458175 -396.978164) (xy 382.47689 -396.985872) (xy 382.491247 -397.000139) (xy 382.499072 -397.018806)
			(xy 382.499616 -397.028924) (xy 382.499616 -397.186658) (xy 382.500043 -397.195844) (xy 382.506544 -397.213028)
			(xy 382.512316 -397.220186) (xy 382.534115 -397.245829) (xy 382.572066 -397.301416) (xy 382.603102 -397.36114)
			(xy 382.626776 -397.424146) (xy 382.642749 -397.48953) (xy 382.650793 -397.556354) (xy 382.650793 -397.623661)
			(xy 382.642747 -397.690485) (xy 382.626771 -397.755868) (xy 382.603096 -397.818873) (xy 382.600522 -397.823826)
			(xy 383.729168 -397.823826) (xy 383.729172 -397.756517) (xy 383.73722 -397.689692) (xy 383.753198 -397.624307)
			(xy 383.776876 -397.561301) (xy 383.807914 -397.501576) (xy 383.845869 -397.44599) (xy 383.86766 -397.420338)
			(xy 383.873473 -397.413205) (xy 383.879976 -397.396005) (xy 383.88036 -397.38681) (xy 383.88036 -396.893542)
			(xy 383.879916 -396.884359) (xy 383.873425 -396.867175) (xy 383.86766 -396.860014) (xy 383.845862 -396.83437)
			(xy 383.807912 -396.778783) (xy 383.776878 -396.719058) (xy 383.753205 -396.656053) (xy 383.737232 -396.590669)
			(xy 383.729188 -396.523846) (xy 383.729189 -396.456539) (xy 383.737235 -396.389716) (xy 383.753209 -396.324333)
			(xy 383.776884 -396.261328) (xy 383.80792 -396.201604) (xy 383.845871 -396.146018) (xy 383.86766 -396.120366)
			(xy 383.873461 -396.113224) (xy 383.879971 -396.096031) (xy 383.88036 -396.086838) (xy 383.88036 -395.92885)
			(xy 383.880805 -395.918679) (xy 383.888578 -395.899881) (xy 383.902958 -395.885494) (xy 383.921751 -395.877711)
			(xy 383.931922 -395.877288) (xy 384.648202 -395.877288) (xy 384.65838 -395.877663) (xy 384.677184 -395.885458)
			(xy 384.691571 -395.899859) (xy 384.699347 -395.918672) (xy 384.699764 -395.92885) (xy 384.699764 -396.086838)
			(xy 384.700164 -396.096026) (xy 384.706686 -396.11321) (xy 384.712464 -396.120366) (xy 384.734242 -396.146026)
			(xy 384.772191 -396.201612) (xy 384.803224 -396.261334) (xy 384.826898 -396.324337) (xy 384.842871 -396.389719)
			(xy 384.850916 -396.45654) (xy 384.850917 -396.523845) (xy 384.842874 -396.590666) (xy 384.826902 -396.656048)
			(xy 384.803231 -396.719052) (xy 384.772199 -396.778776) (xy 384.734251 -396.834362) (xy 384.712464 -396.860014)
			(xy 384.706674 -396.867164) (xy 384.700156 -396.884351) (xy 384.699764 -396.893542) (xy 384.699764 -397.38681)
			(xy 384.700177 -397.395997) (xy 384.70669 -397.413181) (xy 384.712464 -397.420338) (xy 384.734214 -397.446021)
			(xy 384.772164 -397.501603) (xy 384.800587 -397.556296) (xy 385.928833 -397.556296) (xy 385.936908 -397.489358)
			(xy 385.952943 -397.42387) (xy 385.976706 -397.360773) (xy 386.007856 -397.300977) (xy 386.045944 -397.245343)
			(xy 386.067808 -397.219678) (xy 386.073597 -397.212528) (xy 386.080116 -397.195341) (xy 386.080508 -397.18615)
			(xy 386.080508 -397.028924) (xy 386.080936 -397.018802) (xy 386.088677 -397.000097) (xy 386.102991 -396.985782)
			(xy 386.121694 -396.978037) (xy 386.131816 -396.977616) (xy 386.848096 -396.977616) (xy 386.85822 -396.97802)
			(xy 386.876927 -396.985769) (xy 386.891242 -397.00009) (xy 386.898984 -397.0188) (xy 386.899404 -397.028924)
			(xy 386.899404 -397.18615) (xy 386.899837 -397.195335) (xy 386.906335 -397.212519) (xy 386.912104 -397.219678)
			(xy 386.933978 -397.245335) (xy 386.972066 -397.300971) (xy 387.003216 -397.360768) (xy 387.026979 -397.423866)
			(xy 387.043014 -397.489356) (xy 387.051089 -397.556295) (xy 387.051088 -397.62372) (xy 387.043011 -397.690659)
			(xy 387.026975 -397.756148) (xy 387.00321 -397.819245) (xy 387.000823 -397.823826) (xy 388.128959 -397.823826)
			(xy 388.128963 -397.756517) (xy 388.137011 -397.689692) (xy 388.152988 -397.624308) (xy 388.176665 -397.561301)
			(xy 388.207704 -397.501577) (xy 388.245658 -397.44599) (xy 388.267448 -397.420338) (xy 388.273259 -397.413204)
			(xy 388.279764 -397.396005) (xy 388.280148 -397.38681) (xy 388.280148 -396.893542) (xy 388.279707 -396.884358)
			(xy 388.273213 -396.867174) (xy 388.267448 -396.860014) (xy 388.24565 -396.83437) (xy 388.207701 -396.778783)
			(xy 388.176668 -396.719058) (xy 388.152995 -396.656052) (xy 388.137022 -396.590669) (xy 388.128979 -396.523845)
			(xy 388.12898 -396.456539) (xy 388.137025 -396.389716) (xy 388.152999 -396.324333) (xy 388.176674 -396.261328)
			(xy 388.207709 -396.201604) (xy 388.245659 -396.146018) (xy 388.267448 -396.120366) (xy 388.273247 -396.113223)
			(xy 388.279759 -396.096031) (xy 388.280148 -396.086838) (xy 388.280148 -395.92885) (xy 388.280605 -395.91868)
			(xy 388.288375 -395.899885) (xy 388.302751 -395.885498) (xy 388.321541 -395.877713) (xy 388.33171 -395.877288)
			(xy 389.04799 -395.877288) (xy 389.058167 -395.877673) (xy 389.076971 -395.885464) (xy 389.091358 -395.899862)
			(xy 389.099135 -395.918672) (xy 389.099552 -395.92885) (xy 389.099552 -396.086838) (xy 389.099955 -396.096026)
			(xy 389.106475 -396.113209) (xy 389.112252 -396.120366) (xy 389.13403 -396.146026) (xy 389.17198 -396.201611)
			(xy 389.203014 -396.261334) (xy 389.226688 -396.324337) (xy 389.242662 -396.389718) (xy 389.250707 -396.45654)
			(xy 389.250707 -396.523845) (xy 389.242664 -396.590667) (xy 389.226692 -396.656048) (xy 389.20302 -396.719053)
			(xy 389.171987 -396.778776) (xy 389.134039 -396.834362) (xy 389.112252 -396.860014) (xy 389.106461 -396.867163)
			(xy 389.099944 -396.884351) (xy 389.099552 -396.893542) (xy 389.099552 -397.38681) (xy 389.099968 -397.395996)
			(xy 389.106479 -397.41318) (xy 389.112252 -397.420338) (xy 389.134002 -397.446021) (xy 389.171953 -397.501603)
			(xy 389.200407 -397.556356) (xy 390.329153 -397.556356) (xy 390.337195 -397.489535) (xy 390.353166 -397.424153)
			(xy 390.376836 -397.36115) (xy 390.407865 -397.301426) (xy 390.44581 -397.245839) (xy 390.467596 -397.220186)
			(xy 390.473381 -397.213032) (xy 390.479903 -397.195848) (xy 390.480296 -397.186658) (xy 390.480296 -397.028924)
			(xy 390.480735 -397.018804) (xy 390.488475 -397.000101) (xy 390.502784 -396.985786) (xy 390.521484 -396.978039)
			(xy 390.531604 -396.977616) (xy 391.248138 -396.977616) (xy 391.258264 -396.978095) (xy 391.276982 -396.985831)
			(xy 391.291336 -397.000119) (xy 391.299158 -397.0188) (xy 391.2997 -397.028924) (xy 391.2997 -397.186658)
			(xy 391.30013 -397.195843) (xy 391.30663 -397.213028) (xy 391.3124 -397.220186) (xy 391.334196 -397.245831)
			(xy 391.372142 -397.301419) (xy 391.403173 -397.361144) (xy 391.426844 -397.424149) (xy 391.442815 -397.489532)
			(xy 391.450857 -397.556355) (xy 391.450856 -397.62366) (xy 391.442812 -397.690483) (xy 391.426839 -397.755865)
			(xy 391.403167 -397.81887) (xy 391.372135 -397.878594) (xy 391.334187 -397.934181) (xy 391.3124 -397.959834)
			(xy 391.306606 -397.966981) (xy 391.30009 -397.98417) (xy 391.2997 -397.993362) (xy 391.2997 -398.486884)
			(xy 391.300118 -398.49607) (xy 391.306626 -398.513255) (xy 391.3124 -398.520412) (xy 391.334222 -398.546036)
			(xy 391.372167 -398.601627) (xy 391.403197 -398.661355) (xy 391.426866 -398.724363) (xy 391.442835 -398.789748)
			(xy 391.450876 -398.856574) (xy 391.450872 -398.923881) (xy 391.442825 -398.990705) (xy 391.42685 -399.056089)
			(xy 391.403175 -399.119095) (xy 391.372139 -399.178819) (xy 391.334189 -399.234407) (xy 391.3124 -399.26006)
			(xy 391.306595 -399.2672) (xy 391.300086 -399.284394) (xy 391.2997 -399.293588) (xy 391.2997 -399.451576)
			(xy 391.299265 -399.461697) (xy 391.291524 -399.4804) (xy 391.277214 -399.494715) (xy 391.258513 -399.502461)
			(xy 391.248392 -399.502884) (xy 390.531858 -399.502884) (xy 390.521732 -399.502409) (xy 390.503014 -399.494671)
			(xy 390.48866 -399.480382) (xy 390.480838 -399.4617) (xy 390.480296 -399.451576) (xy 390.480296 -399.293588)
			(xy 390.479892 -399.2844) (xy 390.473374 -399.267216) (xy 390.467596 -399.26006) (xy 390.445845 -399.234378)
			(xy 390.407898 -399.178795) (xy 390.376865 -399.119075) (xy 390.353192 -399.056075) (xy 390.337218 -398.990696)
			(xy 390.329172 -398.923878) (xy 390.329169 -398.856576) (xy 390.337209 -398.789757) (xy 390.353176 -398.724377)
			(xy 390.376843 -398.661374) (xy 390.40787 -398.601652) (xy 390.445812 -398.546065) (xy 390.467596 -398.520412)
			(xy 390.473412 -398.51328) (xy 390.479915 -398.49608) (xy 390.480296 -398.486884) (xy 390.480296 -397.993362)
			(xy 390.479905 -397.984173) (xy 390.473378 -397.966988) (xy 390.467596 -397.959834) (xy 390.445819 -397.934173)
			(xy 390.407873 -397.878587) (xy 390.376842 -397.818864) (xy 390.35317 -397.755861) (xy 390.337198 -397.69048)
			(xy 390.329154 -397.623659) (xy 390.329153 -397.556356) (xy 389.200407 -397.556356) (xy 389.202988 -397.561322)
			(xy 389.226664 -397.624322) (xy 389.24264 -397.689701) (xy 389.250687 -397.75652) (xy 389.25069 -397.823823)
			(xy 389.24265 -397.890643) (xy 389.226681 -397.956023) (xy 389.203012 -398.019026) (xy 389.171982 -398.078748)
			(xy 389.134038 -398.134334) (xy 389.112252 -398.159986) (xy 389.10643 -398.167113) (xy 389.099932 -398.184318)
			(xy 389.099552 -398.193514) (xy 389.099552 -398.351502) (xy 389.099138 -398.361675) (xy 389.09135 -398.380472)
			(xy 389.076962 -398.394857) (xy 389.058163 -398.40264) (xy 389.04799 -398.403064) (xy 388.33171 -398.403064)
			(xy 388.321539 -398.402628) (xy 388.302745 -398.394847) (xy 388.28836 -398.380465) (xy 388.280574 -398.361673)
			(xy 388.280148 -398.351502) (xy 388.280148 -398.193514) (xy 388.27972 -398.184329) (xy 388.273218 -398.167145)
			(xy 388.267448 -398.159986) (xy 388.245622 -398.134365) (xy 388.207674 -398.078774) (xy 388.176642 -398.019046)
			(xy 388.152971 -397.956038) (xy 388.137 -397.890652) (xy 388.128959 -397.823826) (xy 387.000823 -397.823826)
			(xy 386.972058 -397.879042) (xy 386.933968 -397.934677) (xy 386.912104 -397.960342) (xy 386.906308 -397.967487)
			(xy 386.899793 -397.984678) (xy 386.899404 -397.99387) (xy 386.899404 -398.486376) (xy 386.899825 -398.495562)
			(xy 386.906331 -398.512747) (xy 386.912104 -398.519904) (xy 386.934003 -398.54554) (xy 386.972091 -398.601179)
			(xy 387.003239 -398.660979) (xy 387.027001 -398.72408) (xy 387.043034 -398.789572) (xy 387.051107 -398.856514)
			(xy 387.051104 -398.92394) (xy 387.043025 -398.990881) (xy 387.026985 -399.056372) (xy 387.003217 -399.11947)
			(xy 386.972063 -399.179268) (xy 386.93397 -399.234903) (xy 386.912104 -399.260568) (xy 386.906297 -399.267706)
			(xy 386.899788 -399.284902) (xy 386.899404 -399.294096) (xy 386.899404 -399.451576) (xy 386.898965 -399.461696)
			(xy 386.891225 -399.480399) (xy 386.876916 -399.494714) (xy 386.858216 -399.502461) (xy 386.848096 -399.502884)
			(xy 386.131816 -399.502884) (xy 386.121693 -399.502471) (xy 386.102986 -399.494725) (xy 386.088671 -399.480407)
			(xy 386.080928 -399.4617) (xy 386.080508 -399.451576) (xy 386.080508 -399.294096) (xy 386.080098 -399.284909)
			(xy 386.073584 -399.267725) (xy 386.067808 -399.260568) (xy 386.045979 -399.234874) (xy 386.007889 -399.179244)
			(xy 385.976736 -399.119451) (xy 385.95297 -399.056358) (xy 385.936931 -398.990873) (xy 385.928852 -398.923938)
			(xy 385.928849 -398.856517) (xy 385.936922 -398.789581) (xy 385.952954 -398.724093) (xy 385.976714 -398.660998)
			(xy 386.007861 -398.601203) (xy 386.045946 -398.545569) (xy 386.067808 -398.519904) (xy 386.073586 -398.512746)
			(xy 386.080112 -398.495565) (xy 386.080508 -398.486376) (xy 386.080508 -397.99387) (xy 386.080111 -397.984681)
			(xy 386.073588 -397.967497) (xy 386.067808 -397.960342) (xy 386.045954 -397.934669) (xy 386.007864 -397.879036)
			(xy 385.976712 -397.819241) (xy 385.952947 -397.756145) (xy 385.936911 -397.690657) (xy 385.928834 -397.623719)
			(xy 385.928833 -397.556296) (xy 384.800587 -397.556296) (xy 384.803199 -397.561322) (xy 384.826873 -397.624323)
			(xy 384.842849 -397.689701) (xy 384.850896 -397.75652) (xy 384.850899 -397.823822) (xy 384.842859 -397.890642)
			(xy 384.82689 -397.956022) (xy 384.803222 -398.019025) (xy 384.772193 -398.078748) (xy 384.734249 -398.134334)
			(xy 384.712464 -398.159986) (xy 384.706644 -398.167114) (xy 384.700144 -398.184318) (xy 384.699764 -398.193514)
			(xy 384.699764 -398.351502) (xy 384.699268 -398.36166) (xy 384.691494 -398.380428) (xy 384.677128 -398.394794)
			(xy 384.65836 -398.402568) (xy 384.648202 -398.403064) (xy 383.931922 -398.403064) (xy 383.921752 -398.402618)
			(xy 383.902958 -398.394841) (xy 383.888573 -398.380462) (xy 383.880787 -398.361672) (xy 383.88036 -398.351502)
			(xy 383.88036 -398.193514) (xy 383.87993 -398.184329) (xy 383.873429 -398.167145) (xy 383.86766 -398.159986)
			(xy 383.845834 -398.134365) (xy 383.807885 -398.078775) (xy 383.776852 -398.019047) (xy 383.753181 -397.956038)
			(xy 383.73721 -397.890652) (xy 383.729168 -397.823826) (xy 382.600522 -397.823826) (xy 382.572059 -397.878597)
			(xy 382.534106 -397.934182) (xy 382.512316 -397.959834) (xy 382.506524 -397.966983) (xy 382.500006 -397.98417)
			(xy 382.499616 -397.993362) (xy 382.499616 -398.486884) (xy 382.50003 -398.496071) (xy 382.506541 -398.513255)
			(xy 382.512316 -398.520412) (xy 382.53414 -398.546034) (xy 382.572091 -398.601624) (xy 382.603125 -398.661351)
			(xy 382.626798 -398.72436) (xy 382.64277 -398.789746) (xy 382.650812 -398.856573) (xy 382.650808 -398.923881)
			(xy 382.64276 -398.990707) (xy 382.626782 -399.056092) (xy 382.603103 -399.119098) (xy 382.572063 -399.178822)
			(xy 382.534107 -399.234408) (xy 382.512316 -399.26006) (xy 382.506513 -399.267201) (xy 382.500002 -399.284395)
			(xy 382.499616 -399.293588) (xy 382.499616 -399.451576) (xy 382.499165 -399.461695) (xy 382.491428 -399.480395)
			(xy 382.477122 -399.49471) (xy 382.458427 -399.502459) (xy 382.448308 -399.502884) (xy 381.731774 -399.502884)
			(xy 381.721649 -399.502396) (xy 381.702931 -399.494664) (xy 381.688577 -399.480379) (xy 381.680754 -399.461699)
			(xy 381.680212 -399.451576) (xy 381.680212 -399.293588) (xy 381.679805 -399.284401) (xy 381.673289 -399.267216)
			(xy 381.667512 -399.26006) (xy 381.64576 -399.234378) (xy 381.607812 -399.178796) (xy 381.576779 -399.119076)
			(xy 381.553105 -399.056075) (xy 381.537131 -398.990697) (xy 381.529084 -398.923878) (xy 381.529081 -398.856576)
			(xy 381.537121 -398.789757) (xy 381.553089 -398.724377) (xy 381.576757 -398.661374) (xy 381.607784 -398.601651)
			(xy 381.645727 -398.546064) (xy 381.667512 -398.520412) (xy 381.67333 -398.513282) (xy 381.679831 -398.49608)
			(xy 381.680212 -398.486884) (xy 381.680212 -397.993362) (xy 381.679818 -397.984173) (xy 381.673293 -397.966989)
			(xy 381.667512 -397.959834) (xy 381.645735 -397.934173) (xy 381.607788 -397.878588) (xy 381.576755 -397.818865)
			(xy 381.553083 -397.755862) (xy 381.53711 -397.690481) (xy 381.529066 -397.623659) (xy 381.529065 -397.556356)
			(xy 380.40085 -397.556356) (xy 380.403242 -397.560947) (xy 380.42701 -397.62404) (xy 380.443049 -397.689525)
			(xy 380.451128 -397.756461) (xy 380.451131 -397.823882) (xy 380.443059 -397.890818) (xy 380.427026 -397.956306)
			(xy 380.403265 -398.019401) (xy 380.372117 -398.079196) (xy 380.334031 -398.134829) (xy 380.312168 -398.160494)
			(xy 380.306387 -398.16765) (xy 380.299864 -398.184832) (xy 380.299468 -398.194022) (xy 380.299468 -398.351502)
			(xy 380.298975 -398.361628) (xy 380.291248 -398.380347) (xy 380.276964 -398.394703) (xy 380.258283 -398.402524)
			(xy 380.24816 -398.403064) (xy 379.53188 -398.403064) (xy 379.521752 -398.4027) (xy 379.503041 -398.394938)
			(xy 379.488726 -398.380605) (xy 379.480988 -398.361885) (xy 379.480572 -398.351756) (xy 379.480572 -398.194022)
			(xy 379.480158 -398.184835) (xy 379.473648 -398.16765) (xy 379.467872 -398.160494) (xy 379.445972 -398.134859)
			(xy 379.407886 -398.07922) (xy 379.376738 -398.019419) (xy 379.352978 -397.956318) (xy 379.336946 -397.890826)
			(xy 379.328873 -397.823885) (xy 378.200706 -397.823885) (xy 378.171972 -397.879041) (xy 378.133884 -397.934676)
			(xy 378.11202 -397.960342) (xy 378.106225 -397.967489) (xy 378.099709 -397.984678) (xy 378.09932 -397.99387)
			(xy 378.09932 -398.486376) (xy 378.099737 -398.495563) (xy 378.106245 -398.512747) (xy 378.11202 -398.519904)
			(xy 378.133919 -398.54554) (xy 378.172005 -398.60118) (xy 378.203153 -398.66098) (xy 378.226914 -398.724081)
			(xy 378.242947 -398.789573) (xy 378.251019 -398.856514) (xy 378.251016 -398.92394) (xy 378.242937 -398.99088)
			(xy 378.226898 -399.056371) (xy 378.203131 -399.11947) (xy 378.171977 -399.179267) (xy 378.133885 -399.234902)
			(xy 378.11202 -399.260568) (xy 378.106214 -399.267707) (xy 378.099704 -399.284902) (xy 378.09932 -399.294096)
			(xy 378.09932 -399.451576) (xy 378.098865 -399.461694) (xy 378.091128 -399.480394) (xy 378.076824 -399.494708)
			(xy 378.05813 -399.502458) (xy 378.048012 -399.502884) (xy 377.331732 -399.502884) (xy 377.32161 -399.502458)
			(xy 377.302903 -399.494717) (xy 377.288587 -399.480403) (xy 377.280844 -399.461698) (xy 377.280424 -399.451576)
			(xy 377.280424 -399.294096) (xy 377.280011 -399.284909) (xy 377.273499 -399.267725) (xy 377.267724 -399.260568)
			(xy 377.245895 -399.234874) (xy 377.207803 -399.179244) (xy 377.17665 -399.119452) (xy 377.152882 -399.056359)
			(xy 377.136844 -398.990873) (xy 377.128765 -398.923938) (xy 377.128761 -398.856516) (xy 377.136834 -398.78958)
			(xy 377.152866 -398.724093) (xy 377.176627 -398.660997) (xy 377.207775 -398.601202) (xy 377.245861 -398.545569)
			(xy 377.267724 -398.519904) (xy 377.273504 -398.512747) (xy 377.280028 -398.495565) (xy 377.280424 -398.486376)
			(xy 377.280424 -397.99387) (xy 377.280023 -397.984682) (xy 377.273502 -397.967498) (xy 377.267724 -397.960342)
			(xy 377.245869 -397.934669) (xy 377.207778 -397.879036) (xy 377.176626 -397.819241) (xy 377.15286 -397.756145)
			(xy 377.136823 -397.690657) (xy 377.128746 -397.623719) (xy 377.128745 -397.556296) (xy 376.0005 -397.556296)
			(xy 376.003112 -397.561323) (xy 376.026786 -397.624324) (xy 376.042761 -397.689702) (xy 376.050808 -397.756521)
			(xy 376.050811 -397.823822) (xy 376.042771 -397.890642) (xy 376.026803 -397.956022) (xy 376.003135 -398.019025)
			(xy 375.972108 -398.078747) (xy 375.934165 -398.134333) (xy 375.91238 -398.159986) (xy 375.906562 -398.167116)
			(xy 375.900061 -398.184318) (xy 375.89968 -398.193514) (xy 375.89968 -398.351502) (xy 375.899169 -398.361658)
			(xy 375.891397 -398.380423) (xy 375.877037 -398.394788) (xy 375.858274 -398.402565) (xy 375.848118 -398.403064)
			(xy 375.131838 -398.403064) (xy 375.121669 -398.402605) (xy 375.102876 -398.394833) (xy 375.08849 -398.380458)
			(xy 375.080703 -398.361671) (xy 375.080276 -398.351502) (xy 375.080276 -398.193514) (xy 375.079865 -398.184327)
			(xy 375.073352 -398.167142) (xy 375.067576 -398.159986) (xy 375.04575 -398.134365) (xy 375.007799 -398.078775)
			(xy 374.976766 -398.019048) (xy 374.953093 -397.956039) (xy 374.937122 -397.890652) (xy 374.92908 -397.823826)
			(xy 347.400682 -397.823826) (xy 347.372224 -397.878594) (xy 347.334276 -397.934182) (xy 347.312488 -397.959834)
			(xy 347.306693 -397.96698) (xy 347.300178 -397.98417) (xy 347.299788 -397.993362) (xy 347.299788 -398.486884)
			(xy 347.300209 -398.49607) (xy 347.306715 -398.513254) (xy 347.312488 -398.520412) (xy 347.33431 -398.546035)
			(xy 347.372256 -398.601627) (xy 347.403286 -398.661354) (xy 347.426956 -398.724363) (xy 347.442926 -398.789748)
			(xy 347.450967 -398.856573) (xy 347.450963 -398.923881) (xy 347.442916 -398.990705) (xy 347.42694 -399.056089)
			(xy 347.403264 -399.119095) (xy 347.372228 -399.17882) (xy 347.334277 -399.234407) (xy 347.312488 -399.26006)
			(xy 347.306682 -399.267199) (xy 347.300173 -399.284394) (xy 347.299788 -399.293588) (xy 347.299788 -399.451576)
			(xy 347.299359 -399.46173) (xy 347.291569 -399.480484) (xy 347.277174 -399.494809) (xy 347.258382 -399.502507)
			(xy 347.248226 -399.502884) (xy 346.531946 -399.502884) (xy 346.521825 -399.502336) (xy 346.50311 -399.494628)
			(xy 346.488753 -399.480361) (xy 346.480928 -399.461694) (xy 346.480384 -399.451576) (xy 346.480384 -399.293588)
			(xy 346.479983 -399.2844) (xy 346.473463 -399.267215) (xy 346.467684 -399.26006) (xy 346.44593 -399.234379)
			(xy 346.407977 -399.178798) (xy 346.37694 -399.119079) (xy 346.353263 -399.056078) (xy 346.337287 -398.990699)
			(xy 346.329239 -398.923879) (xy 346.329236 -398.856576) (xy 346.337277 -398.789755) (xy 346.353247 -398.724374)
			(xy 346.376918 -398.661371) (xy 346.40795 -398.601648) (xy 346.445897 -398.546064) (xy 346.467684 -398.520412)
			(xy 346.473499 -398.513279) (xy 346.480003 -398.496079) (xy 346.480384 -398.486884) (xy 346.480384 -397.993362)
			(xy 346.479996 -397.984172) (xy 346.473467 -397.966988) (xy 346.467684 -397.959834) (xy 346.445905 -397.934174)
			(xy 346.407953 -397.87859) (xy 346.376917 -397.818868) (xy 346.353241 -397.755864) (xy 346.337266 -397.690483)
			(xy 346.329221 -397.62366) (xy 346.32922 -397.556355) (xy 345.200497 -397.556355) (xy 345.203078 -397.561321)
			(xy 345.226754 -397.624322) (xy 345.24273 -397.689701) (xy 345.250778 -397.75652) (xy 345.250781 -397.823823)
			(xy 345.242741 -397.890643) (xy 345.226771 -397.956023) (xy 345.203102 -398.019026) (xy 345.172072 -398.078749)
			(xy 345.134126 -398.134334) (xy 345.11234 -398.159986) (xy 345.106517 -398.167112) (xy 345.10002 -398.184318)
			(xy 345.09964 -398.193514) (xy 345.09964 -398.351502) (xy 345.099237 -398.361676) (xy 345.091447 -398.380475)
			(xy 345.077055 -398.394861) (xy 345.058253 -398.402642) (xy 345.048078 -398.403064) (xy 344.331798 -398.403064)
			(xy 344.32164 -398.402568) (xy 344.302872 -398.394794) (xy 344.288506 -398.380428) (xy 344.280732 -398.36166)
			(xy 344.280236 -398.351502) (xy 344.280236 -398.193514) (xy 344.279811 -398.184329) (xy 344.273307 -398.167144)
			(xy 344.267536 -398.159986) (xy 344.245711 -398.134365) (xy 344.207763 -398.078774) (xy 344.176732 -398.019046)
			(xy 344.153061 -397.956037) (xy 344.137091 -397.890651) (xy 344.12905 -397.823825) (xy 343.000914 -397.823825)
			(xy 342.972147 -397.879042) (xy 342.934057 -397.934677) (xy 342.912192 -397.960342) (xy 342.906394 -397.967486)
			(xy 342.899881 -397.984678) (xy 342.899492 -397.99387) (xy 342.899492 -398.486376) (xy 342.899916 -398.495562)
			(xy 342.90642 -398.512746) (xy 342.912192 -398.519904) (xy 342.934092 -398.54554) (xy 342.97218 -398.601178)
			(xy 343.003329 -398.660979) (xy 343.027092 -398.724079) (xy 343.043125 -398.789572) (xy 343.051198 -398.856514)
			(xy 343.051195 -398.92394) (xy 343.043115 -398.990881) (xy 343.027076 -399.056372) (xy 343.003307 -399.119471)
			(xy 342.972152 -399.179268) (xy 342.934058 -399.234903) (xy 342.912192 -399.260568) (xy 342.906383 -399.267704)
			(xy 342.899876 -399.284902) (xy 342.899492 -399.294096) (xy 342.899492 -399.451576) (xy 342.899064 -399.461698)
			(xy 342.891323 -399.480403) (xy 342.877009 -399.494718) (xy 342.858306 -399.502463) (xy 342.848184 -399.502884)
			(xy 342.131904 -399.502884) (xy 342.12178 -399.50248) (xy 342.103073 -399.494731) (xy 342.088758 -399.48041)
			(xy 342.081016 -399.4617) (xy 342.080596 -399.451576) (xy 342.080596 -399.294096) (xy 342.080189 -399.284909)
			(xy 342.073673 -399.267724) (xy 342.067896 -399.260568) (xy 342.046068 -399.234874) (xy 342.007978 -399.179243)
			(xy 341.976826 -399.119451) (xy 341.95306 -399.056358) (xy 341.937022 -398.990872) (xy 341.928943 -398.923937)
			(xy 341.92894 -398.856517) (xy 341.937012 -398.789581) (xy 341.953044 -398.724094) (xy 341.976804 -398.660999)
			(xy 342.00795 -398.601203) (xy 342.046034 -398.545569) (xy 342.067896 -398.519904) (xy 342.073673 -398.512745)
			(xy 342.080199 -398.495565) (xy 342.080596 -398.486376) (xy 342.080596 -397.99387) (xy 342.080201 -397.984681)
			(xy 342.073677 -397.967497) (xy 342.067896 -397.960342) (xy 342.046042 -397.934669) (xy 342.007953 -397.879035)
			(xy 341.976802 -397.81924) (xy 341.953038 -397.756144) (xy 341.937002 -397.690656) (xy 341.928925 -397.623719)
			(xy 341.928924 -397.556296) (xy 340.800676 -397.556296) (xy 340.803288 -397.561322) (xy 340.826964 -397.624322)
			(xy 340.84294 -397.689701) (xy 340.850987 -397.75652) (xy 340.85099 -397.823823) (xy 340.84295 -397.890643)
			(xy 340.826981 -397.956023) (xy 340.803312 -398.019026) (xy 340.772282 -398.078748) (xy 340.734338 -398.134334)
			(xy 340.712552 -398.159986) (xy 340.70673 -398.167113) (xy 340.700232 -398.184318) (xy 340.699852 -398.193514)
			(xy 340.699852 -398.351502) (xy 340.699438 -398.361675) (xy 340.69165 -398.380472) (xy 340.677262 -398.394857)
			(xy 340.658463 -398.40264) (xy 340.64829 -398.403064) (xy 339.93201 -398.403064) (xy 339.921839 -398.402628)
			(xy 339.903045 -398.394847) (xy 339.88866 -398.380465) (xy 339.880874 -398.361673) (xy 339.880448 -398.351502)
			(xy 339.880448 -398.193514) (xy 339.88002 -398.184329) (xy 339.873518 -398.167145) (xy 339.867748 -398.159986)
			(xy 339.845922 -398.134365) (xy 339.807974 -398.078774) (xy 339.776942 -398.019046) (xy 339.753271 -397.956038)
			(xy 339.7373 -397.890652) (xy 339.729259 -397.823826) (xy 338.600595 -397.823826) (xy 338.572138 -397.878594)
			(xy 338.534191 -397.934181) (xy 338.512404 -397.959834) (xy 338.506611 -397.966982) (xy 338.500094 -397.98417)
			(xy 338.499704 -397.993362) (xy 338.499704 -398.486884) (xy 338.500121 -398.49607) (xy 338.50663 -398.513255)
			(xy 338.512404 -398.520412) (xy 338.534226 -398.546036) (xy 338.572171 -398.601627) (xy 338.6032 -398.661355)
			(xy 338.626869 -398.724363) (xy 338.642838 -398.789748) (xy 338.650879 -398.856574) (xy 338.650875 -398.923881)
			(xy 338.642828 -398.990705) (xy 338.626853 -399.056089) (xy 338.603178 -399.119094) (xy 338.572143 -399.178819)
			(xy 338.534193 -399.234407) (xy 338.512404 -399.26006) (xy 338.5066 -399.2672) (xy 338.50009 -399.284394)
			(xy 338.499704 -399.293588) (xy 338.499704 -399.451576) (xy 338.499259 -399.461728) (xy 338.491472 -399.480479)
			(xy 338.477082 -399.494803) (xy 338.458296 -399.502505) (xy 338.448142 -399.502884) (xy 337.731862 -399.502884)
			(xy 337.721736 -399.502405) (xy 337.703018 -399.494669) (xy 337.688664 -399.480381) (xy 337.680842 -399.4617)
			(xy 337.6803 -399.451576) (xy 337.6803 -399.293588) (xy 337.679895 -399.2844) (xy 337.673378 -399.267216)
			(xy 337.6676 -399.26006) (xy 337.645849 -399.234378) (xy 337.607901 -399.178795) (xy 337.576869 -399.119075)
			(xy 337.553196 -399.056075) (xy 337.537221 -398.990697) (xy 337.529175 -398.923878) (xy 337.529172 -398.856576)
			(xy 337.537212 -398.789757) (xy 337.55318 -398.724377) (xy 337.576847 -398.661374) (xy 337.607874 -398.601651)
			(xy 337.645816 -398.546065) (xy 337.6676 -398.520412) (xy 337.673416 -398.513281) (xy 337.679919 -398.49608)
			(xy 337.6803 -398.486884) (xy 337.6803 -397.993362) (xy 337.679908 -397.984173) (xy 337.673382 -397.966989)
			(xy 337.6676 -397.959834) (xy 337.645823 -397.934173) (xy 337.607877 -397.878587) (xy 337.576845 -397.818864)
			(xy 337.553174 -397.755861) (xy 337.537201 -397.69048) (xy 337.529157 -397.623659) (xy 337.529156 -397.556356)
			(xy 336.40094 -397.556356) (xy 336.403332 -397.560946) (xy 336.4271 -397.624039) (xy 336.443139 -397.689525)
			(xy 336.451219 -397.756461) (xy 336.451222 -397.823882) (xy 336.44315 -397.890819) (xy 336.427117 -397.956306)
			(xy 336.403355 -398.019402) (xy 336.372206 -398.079196) (xy 336.334119 -398.13483) (xy 336.312256 -398.160494)
			(xy 336.306474 -398.167649) (xy 336.299952 -398.184832) (xy 336.299556 -398.194022) (xy 336.299556 -398.351502)
			(xy 336.299075 -398.361629) (xy 336.291346 -398.380351) (xy 336.277058 -398.394708) (xy 336.258373 -398.402526)
			(xy 336.248248 -398.403064) (xy 335.531968 -398.403064) (xy 335.521807 -398.402704) (xy 335.503047 -398.394891)
			(xy 335.488724 -398.380475) (xy 335.481032 -398.361665) (xy 335.48066 -398.351502) (xy 335.48066 -398.194022)
			(xy 335.480226 -398.184838) (xy 335.473727 -398.167654) (xy 335.46796 -398.160494) (xy 335.44606 -398.134859)
			(xy 335.407975 -398.079219) (xy 335.376828 -398.019418) (xy 335.353068 -397.956318) (xy 335.337036 -397.890825)
			(xy 335.328964 -397.823884) (xy 334.200796 -397.823884) (xy 334.172062 -397.879042) (xy 334.133972 -397.934677)
			(xy 334.112108 -397.960342) (xy 334.106312 -397.967488) (xy 334.099797 -397.984678) (xy 334.099408 -397.99387)
			(xy 334.099408 -398.486376) (xy 334.099828 -398.495562) (xy 334.106335 -398.512747) (xy 334.112108 -398.519904)
			(xy 334.134007 -398.54554) (xy 334.172094 -398.601179) (xy 334.203243 -398.660979) (xy 334.227005 -398.72408)
			(xy 334.243037 -398.789573) (xy 334.25111 -398.856514) (xy 334.251107 -398.92394) (xy 334.243028 -398.990881)
			(xy 334.226989 -399.056372) (xy 334.203221 -399.11947) (xy 334.172066 -399.179267) (xy 334.133974 -399.234903)
			(xy 334.112108 -399.260568) (xy 334.106301 -399.267706) (xy 334.099792 -399.284902) (xy 334.099408 -399.294096)
			(xy 334.099408 -399.451576) (xy 334.098965 -399.461696) (xy 334.091226 -399.480398) (xy 334.076918 -399.494712)
			(xy 334.05822 -399.50246) (xy 334.0481 -399.502884) (xy 333.33182 -399.502884) (xy 333.321697 -399.502467)
			(xy 333.302991 -399.494723) (xy 333.288675 -399.480406) (xy 333.280932 -399.461699) (xy 333.280512 -399.451576)
			(xy 333.280512 -399.294096) (xy 333.280101 -399.284909) (xy 333.273587 -399.267725) (xy 333.267812 -399.260568)
			(xy 333.245983 -399.234874) (xy 333.207892 -399.179244) (xy 333.176739 -399.119452) (xy 333.152973 -399.056358)
			(xy 333.136934 -398.990873) (xy 333.128855 -398.923938) (xy 333.128852 -398.856516) (xy 333.136925 -398.78958)
			(xy 333.152957 -398.724093) (xy 333.176717 -398.660998) (xy 333.207865 -398.601203) (xy 333.24595 -398.545569)
			(xy 333.267812 -398.519904) (xy 333.273591 -398.512746) (xy 333.280116 -398.495565) (xy 333.280512 -398.486376)
			(xy 333.280512 -397.99387) (xy 333.280114 -397.984682) (xy 333.273592 -397.967497) (xy 333.267812 -397.960342)
			(xy 333.245957 -397.934669) (xy 333.207868 -397.879036) (xy 333.176716 -397.819241) (xy 333.152951 -397.756145)
			(xy 333.136914 -397.690657) (xy 333.128837 -397.623719) (xy 333.128836 -397.556296) (xy 332.00059 -397.556296)
			(xy 332.003202 -397.561323) (xy 332.026877 -397.624323) (xy 332.042852 -397.689701) (xy 332.050899 -397.75652)
			(xy 332.050902 -397.823822) (xy 332.042862 -397.890642) (xy 332.026893 -397.956022) (xy 332.003225 -398.019025)
			(xy 331.972197 -398.078748) (xy 331.934253 -398.134334) (xy 331.912468 -398.159986) (xy 331.906648 -398.167115)
			(xy 331.900148 -398.184318) (xy 331.899768 -398.193514) (xy 331.899768 -398.351502) (xy 331.899268 -398.361659)
			(xy 331.891494 -398.380427) (xy 331.877131 -398.394792) (xy 331.858363 -398.402568) (xy 331.848206 -398.403064)
			(xy 331.131926 -398.403064) (xy 331.121756 -398.402615) (xy 331.102963 -398.394839) (xy 331.088577 -398.380461)
			(xy 331.080791 -398.361671) (xy 331.080364 -398.351502) (xy 331.080364 -398.193514) (xy 331.079933 -398.184329)
			(xy 331.073432 -398.167146) (xy 331.067664 -398.159986) (xy 331.045838 -398.134365) (xy 331.007889 -398.078775)
			(xy 330.976856 -398.019047) (xy 330.953184 -397.956038) (xy 330.937213 -397.890652) (xy 330.929171 -397.823826)
			(xy 326.525636 -397.823826) (xy 326.525636 -401.723737) (xy 330.929183 -401.723737) (xy 330.929184 -401.65643)
			(xy 330.937231 -401.589605) (xy 330.953207 -401.524221) (xy 330.976884 -401.461216) (xy 331.007921 -401.401492)
			(xy 331.045874 -401.345906) (xy 331.067664 -401.320254) (xy 331.07347 -401.313116) (xy 331.079977 -401.29592)
			(xy 331.080364 -401.286726) (xy 331.080364 -400.793458) (xy 331.07996 -400.78427) (xy 331.073441 -400.767087)
			(xy 331.067664 -400.75993) (xy 331.045882 -400.734273) (xy 331.007931 -400.678688) (xy 330.976896 -400.618965)
			(xy 330.953222 -400.555961) (xy 330.937248 -400.490579) (xy 330.929203 -400.423757) (xy 330.929202 -400.356452)
			(xy 330.937246 -400.289629) (xy 330.953219 -400.224247) (xy 330.976892 -400.161243) (xy 331.007926 -400.10152)
			(xy 331.045876 -400.045934) (xy 331.067664 -400.020282) (xy 331.073459 -400.013136) (xy 331.079973 -399.995946)
			(xy 331.080364 -399.986754) (xy 331.080364 -399.828766) (xy 331.080806 -399.818603) (xy 331.088597 -399.799828)
			(xy 331.102978 -399.785463) (xy 331.121762 -399.777694) (xy 331.131926 -399.777204) (xy 331.848206 -399.777204)
			(xy 331.85836 -399.777728) (xy 331.877123 -399.785498) (xy 331.891486 -399.799854) (xy 331.899267 -399.818612)
			(xy 331.899768 -399.828766) (xy 331.899768 -399.986754) (xy 331.900208 -399.995938) (xy 331.906702 -400.013122)
			(xy 331.912468 -400.020282) (xy 331.934262 -400.045929) (xy 331.97221 -400.101517) (xy 332.003242 -400.161241)
			(xy 332.026915 -400.224246) (xy 332.042887 -400.289629) (xy 332.05093 -400.356452) (xy 332.05093 -400.423757)
			(xy 332.042885 -400.49058) (xy 332.026912 -400.555963) (xy 332.003239 -400.618967) (xy 331.972205 -400.678691)
			(xy 331.934256 -400.734278) (xy 331.912468 -400.75993) (xy 331.906672 -400.767076) (xy 331.900158 -400.784266)
			(xy 331.899768 -400.793458) (xy 331.899768 -401.286726) (xy 331.900173 -401.295914) (xy 331.906691 -401.313098)
			(xy 331.912468 -401.320254) (xy 331.934234 -401.345924) (xy 331.972183 -401.401508) (xy 332.003216 -401.461229)
			(xy 332.02689 -401.524231) (xy 332.042864 -401.589611) (xy 332.05091 -401.656432) (xy 332.050912 -401.723735)
			(xy 332.04287 -401.790556) (xy 332.0269 -401.855937) (xy 332.00323 -401.91894) (xy 331.9722 -401.978663)
			(xy 331.934254 -402.03425) (xy 331.912468 -402.059902) (xy 331.906684 -402.067056) (xy 331.900163 -402.08424)
			(xy 331.899768 -402.09343) (xy 331.899768 -402.251418) (xy 331.899282 -402.261576) (xy 331.891502 -402.280345)
			(xy 331.877135 -402.294709) (xy 331.858364 -402.302484) (xy 331.848206 -402.30298) (xy 331.131926 -402.30298)
			(xy 331.121758 -402.302515) (xy 331.102968 -402.294742) (xy 331.088583 -402.280369) (xy 331.080794 -402.261585)
			(xy 331.080364 -402.251418) (xy 331.080364 -402.09343) (xy 331.079925 -402.084246) (xy 331.07343 -402.067062)
			(xy 331.067664 -402.059902) (xy 331.045854 -402.034268) (xy 331.007904 -401.97868) (xy 330.97687 -401.918954)
			(xy 330.953197 -401.855947) (xy 330.937225 -401.790562) (xy 330.929183 -401.723737) (xy 326.525636 -401.723737)
			(xy 326.525636 -402.823878) (xy 333.128796 -402.823878) (xy 333.128801 -402.75645) (xy 333.136882 -402.689508)
			(xy 333.152922 -402.624016) (xy 333.176693 -402.560918) (xy 333.20785 -402.50112) (xy 333.245945 -402.445485)
			(xy 333.267812 -402.41982) (xy 333.273626 -402.412687) (xy 333.28013 -402.395487) (xy 333.280512 -402.386292)
			(xy 333.280512 -401.89404) (xy 333.28008 -401.884855) (xy 333.273581 -401.867671) (xy 333.267812 -401.860512)
			(xy 333.245928 -401.834863) (xy 333.207839 -401.779227) (xy 333.176689 -401.719428) (xy 333.152925 -401.656329)
			(xy 333.136891 -401.590838) (xy 333.128816 -401.523898) (xy 333.128818 -401.456472) (xy 333.136896 -401.389532)
			(xy 333.152934 -401.324042) (xy 333.176701 -401.260944) (xy 333.207855 -401.201148) (xy 333.245946 -401.145513)
			(xy 333.267812 -401.119848) (xy 333.273615 -401.112707) (xy 333.280125 -401.095513) (xy 333.280512 -401.08632)
			(xy 333.280512 -400.92884) (xy 333.280949 -400.918719) (xy 333.288686 -400.900014) (xy 333.302997 -400.885698)
			(xy 333.321699 -400.877953) (xy 333.33182 -400.877532) (xy 334.0481 -400.877532) (xy 334.058226 -400.877917)
			(xy 334.076936 -400.885671) (xy 334.091252 -400.899997) (xy 334.098991 -400.918713) (xy 334.099408 -400.92884)
			(xy 334.099408 -401.08632) (xy 334.099807 -401.095508) (xy 334.106328 -401.112693) (xy 334.112108 -401.119848)
			(xy 334.133952 -401.14553) (xy 334.172041 -401.201162) (xy 334.203192 -401.260956) (xy 334.226957 -401.324051)
			(xy 334.242994 -401.389538) (xy 334.251071 -401.456474) (xy 334.251073 -401.523896) (xy 334.242999 -401.590833)
			(xy 334.226966 -401.656321) (xy 334.203204 -401.719417) (xy 334.200923 -401.723796) (xy 335.328975 -401.723796)
			(xy 335.328977 -401.656371) (xy 335.337055 -401.589432) (xy 335.353091 -401.523942) (xy 335.376856 -401.460845)
			(xy 335.408007 -401.401048) (xy 335.446096 -401.345412) (xy 335.46796 -401.319746) (xy 335.473769 -401.31261)
			(xy 335.480275 -401.295412) (xy 335.48066 -401.286218) (xy 335.48066 -400.793966) (xy 335.480253 -400.784779)
			(xy 335.473735 -400.767595) (xy 335.46796 -400.760438) (xy 335.446103 -400.734767) (xy 335.408017 -400.679133)
			(xy 335.376868 -400.619337) (xy 335.353106 -400.556241) (xy 335.337071 -400.490753) (xy 335.328995 -400.423816)
			(xy 335.328995 -400.356393) (xy 335.337069 -400.289456) (xy 335.353103 -400.223968) (xy 335.376865 -400.160872)
			(xy 335.408012 -400.101075) (xy 335.446098 -400.04544) (xy 335.46796 -400.019774) (xy 335.473757 -400.01263)
			(xy 335.48027 -399.995438) (xy 335.48066 -399.986246) (xy 335.48066 -399.828766) (xy 335.481099 -399.818635)
			(xy 335.488842 -399.799909) (xy 335.503143 -399.785553) (xy 335.521839 -399.777739) (xy 335.531968 -399.777204)
			(xy 336.248248 -399.777204) (xy 336.258406 -399.777583) (xy 336.27716 -399.785395) (xy 336.291482 -399.799804)
			(xy 336.299179 -399.818606) (xy 336.299556 -399.828766) (xy 336.299556 -399.986246) (xy 336.300002 -399.995429)
			(xy 336.306492 -400.012613) (xy 336.312256 -400.019774) (xy 336.334127 -400.045434) (xy 336.372219 -400.101068)
			(xy 336.403372 -400.160864) (xy 336.427138 -400.223962) (xy 336.443174 -400.289452) (xy 336.45125 -400.356392)
			(xy 336.451249 -400.423817) (xy 336.443172 -400.490756) (xy 336.427135 -400.556246) (xy 336.403368 -400.619344)
			(xy 336.372214 -400.67914) (xy 336.334122 -400.734774) (xy 336.312256 -400.760438) (xy 336.306455 -400.76758)
			(xy 336.299944 -400.784773) (xy 336.299556 -400.793966) (xy 336.299556 -401.286218) (xy 336.299967 -401.295405)
			(xy 336.306481 -401.312589) (xy 336.312256 -401.319746) (xy 336.3341 -401.345428) (xy 336.372192 -401.401059)
			(xy 336.403346 -401.460853) (xy 336.427114 -401.523948) (xy 336.443152 -401.589435) (xy 336.45123 -401.656372)
			(xy 336.451232 -401.723795) (xy 336.443158 -401.790732) (xy 336.427123 -401.856221) (xy 336.40336 -401.919317)
			(xy 336.372209 -401.979112) (xy 336.33412 -402.034746) (xy 336.312256 -402.06041) (xy 336.306467 -402.06756)
			(xy 336.299949 -402.084747) (xy 336.299556 -402.093938) (xy 336.299556 -402.251418) (xy 336.299088 -402.261546)
			(xy 336.291354 -402.280269) (xy 336.277062 -402.294625) (xy 336.258374 -402.302443) (xy 336.248248 -402.30298)
			(xy 335.531968 -402.30298) (xy 335.521809 -402.302604) (xy 335.503052 -402.294794) (xy 335.488729 -402.280384)
			(xy 335.481034 -402.261579) (xy 335.48066 -402.251418) (xy 335.48066 -402.093938) (xy 335.480218 -402.084754)
			(xy 335.473725 -402.06757) (xy 335.46796 -402.06041) (xy 335.446076 -402.034762) (xy 335.40799 -401.979124)
			(xy 335.376843 -401.919325) (xy 335.353082 -401.856226) (xy 335.337049 -401.790735) (xy 335.328975 -401.723796)
			(xy 334.200923 -401.723796) (xy 334.172056 -401.779212) (xy 334.13397 -401.834847) (xy 334.112108 -401.860512)
			(xy 334.106325 -401.867667) (xy 334.099802 -401.88485) (xy 334.099408 -401.89404) (xy 334.099408 -402.386292)
			(xy 334.09982 -402.395479) (xy 334.106332 -402.412663) (xy 334.112108 -402.41982) (xy 334.133925 -402.445524)
			(xy 334.172014 -402.501153) (xy 334.203166 -402.560944) (xy 334.226933 -402.624036) (xy 334.242972 -402.68952)
			(xy 334.251051 -402.756454) (xy 334.251055 -402.823818) (xy 337.529116 -402.823818) (xy 337.52912 -402.75651)
			(xy 337.537169 -402.689685) (xy 337.553145 -402.6243) (xy 337.576822 -402.561294) (xy 337.607859 -402.501569)
			(xy 337.645811 -402.445981) (xy 337.6676 -402.420328) (xy 337.67341 -402.413192) (xy 337.679917 -402.395994)
			(xy 337.6803 -402.3868) (xy 337.6803 -401.893532) (xy 337.679874 -401.884346) (xy 337.673371 -401.867162)
			(xy 337.6676 -401.860004) (xy 337.645794 -401.834367) (xy 337.607848 -401.778778) (xy 337.576818 -401.719052)
			(xy 337.553148 -401.656045) (xy 337.537178 -401.590662) (xy 337.529136 -401.523838) (xy 337.529137 -401.456532)
			(xy 337.537183 -401.389709) (xy 337.553157 -401.324326) (xy 337.57683 -401.261321) (xy 337.607864 -401.201596)
			(xy 337.645812 -401.146009) (xy 337.6676 -401.120356) (xy 337.673398 -401.113212) (xy 337.679912 -401.09602)
			(xy 337.6803 -401.086828) (xy 337.6803 -400.92884) (xy 337.680755 -400.918688) (xy 337.688537 -400.899937)
			(xy 337.702924 -400.885612) (xy 337.721709 -400.877911) (xy 337.731862 -400.877532) (xy 338.448142 -400.877532)
			(xy 338.45827 -400.877992) (xy 338.476991 -400.885732) (xy 338.491346 -400.900026) (xy 338.499165 -400.918714)
			(xy 338.499704 -400.92884) (xy 338.499704 -401.086828) (xy 338.5001 -401.096017) (xy 338.506623 -401.113201)
			(xy 338.512404 -401.120356) (xy 338.534171 -401.146025) (xy 338.572117 -401.20161) (xy 338.603149 -401.261332)
			(xy 338.626821 -401.324334) (xy 338.642794 -401.389714) (xy 338.650839 -401.456534) (xy 338.650841 -401.523836)
			(xy 338.6428 -401.590657) (xy 338.62683 -401.656037) (xy 338.603161 -401.719041) (xy 338.600721 -401.723737)
			(xy 339.72927 -401.723737) (xy 339.729272 -401.65643) (xy 339.737319 -401.589606) (xy 339.753294 -401.524222)
			(xy 339.77697 -401.461217) (xy 339.808006 -401.401492) (xy 339.845959 -401.345906) (xy 339.867748 -401.320254)
			(xy 339.873553 -401.313115) (xy 339.880061 -401.295919) (xy 339.880448 -401.286726) (xy 339.880448 -400.793458)
			(xy 339.880047 -400.78427) (xy 339.873526 -400.767086) (xy 339.867748 -400.75993) (xy 339.845966 -400.734273)
			(xy 339.808017 -400.678687) (xy 339.776983 -400.618965) (xy 339.753309 -400.555961) (xy 339.737335 -400.490579)
			(xy 339.729291 -400.423757) (xy 339.72929 -400.356452) (xy 339.737334 -400.28963) (xy 339.753306 -400.224248)
			(xy 339.776979 -400.161244) (xy 339.808012 -400.10152) (xy 339.845961 -400.045934) (xy 339.867748 -400.020282)
			(xy 339.873541 -400.013134) (xy 339.880056 -399.995946) (xy 339.880448 -399.986754) (xy 339.880448 -399.828766)
			(xy 339.880906 -399.818605) (xy 339.888693 -399.799833) (xy 339.90307 -399.785469) (xy 339.921848 -399.777697)
			(xy 339.93201 -399.777204) (xy 340.64829 -399.777204) (xy 340.658443 -399.777741) (xy 340.677205 -399.785506)
			(xy 340.69157 -399.799858) (xy 340.699351 -399.818613) (xy 340.699852 -399.828766) (xy 340.699852 -399.986754)
			(xy 340.700295 -399.995937) (xy 340.706787 -400.013121) (xy 340.712552 -400.020282) (xy 340.734346 -400.045929)
			(xy 340.772295 -400.101516) (xy 340.803329 -400.16124) (xy 340.827002 -400.224245) (xy 340.842975 -400.289628)
			(xy 340.851018 -400.356452) (xy 340.851018 -400.423757) (xy 340.842973 -400.490581) (xy 340.826999 -400.555963)
			(xy 340.803325 -400.618968) (xy 340.772291 -400.678692) (xy 340.734341 -400.734278) (xy 340.712552 -400.75993)
			(xy 340.706754 -400.767074) (xy 340.700242 -400.784266) (xy 340.699852 -400.793458) (xy 340.699852 -401.286726)
			(xy 340.70026 -401.295913) (xy 340.706777 -401.313097) (xy 340.712552 -401.320254) (xy 340.734318 -401.345924)
			(xy 340.772268 -401.401508) (xy 340.803303 -401.461229) (xy 340.826977 -401.524231) (xy 340.842952 -401.589611)
			(xy 340.850998 -401.656432) (xy 340.851 -401.723735) (xy 340.842958 -401.790556) (xy 340.826987 -401.855937)
			(xy 340.803316 -401.918941) (xy 340.772285 -401.978664) (xy 340.734338 -402.03425) (xy 340.712552 -402.059902)
			(xy 340.706766 -402.067055) (xy 340.700246 -402.08424) (xy 340.699852 -402.09343) (xy 340.699852 -402.251418)
			(xy 340.699381 -402.261578) (xy 340.691599 -402.28035) (xy 340.677226 -402.294715) (xy 340.65845 -402.302487)
			(xy 340.64829 -402.30298) (xy 339.93201 -402.30298) (xy 339.921855 -402.302459) (xy 339.90309 -402.294691)
			(xy 339.888725 -402.280334) (xy 339.880947 -402.261573) (xy 339.880448 -402.251418) (xy 339.880448 -402.09343)
			(xy 339.880013 -402.084246) (xy 339.873515 -402.067062) (xy 339.867748 -402.059902) (xy 339.845938 -402.034268)
			(xy 339.807989 -401.978679) (xy 339.776957 -401.918953) (xy 339.753285 -401.855946) (xy 339.737313 -401.790562)
			(xy 339.72927 -401.723737) (xy 338.600721 -401.723737) (xy 338.572133 -401.778764) (xy 338.534189 -401.834351)
			(xy 338.512404 -401.860004) (xy 338.506624 -401.867161) (xy 338.500099 -401.884342) (xy 338.499704 -401.893532)
			(xy 338.499704 -402.3868) (xy 338.500113 -402.395987) (xy 338.506628 -402.413172) (xy 338.512404 -402.420328)
			(xy 338.534143 -402.44602) (xy 338.572091 -402.501601) (xy 338.603124 -402.56132) (xy 338.626797 -402.624319)
			(xy 338.642772 -402.689696) (xy 338.65082 -402.756514) (xy 338.650824 -402.823814) (xy 338.650816 -402.823878)
			(xy 341.928884 -402.823878) (xy 341.928889 -402.75645) (xy 341.936969 -402.689509) (xy 341.95301 -402.624017)
			(xy 341.976779 -402.560918) (xy 342.007935 -402.501121) (xy 342.046029 -402.445485) (xy 342.067896 -402.41982)
			(xy 342.073709 -402.412686) (xy 342.080214 -402.395487) (xy 342.080596 -402.386292) (xy 342.080596 -401.89404)
			(xy 342.080168 -401.884855) (xy 342.073667 -401.86767) (xy 342.067896 -401.860512) (xy 342.046013 -401.834863)
			(xy 342.007925 -401.779226) (xy 341.976775 -401.719428) (xy 341.953012 -401.656329) (xy 341.936978 -401.590838)
			(xy 341.928904 -401.523898) (xy 341.928906 -401.456472) (xy 341.936984 -401.389533) (xy 341.953021 -401.324043)
			(xy 341.976787 -401.260945) (xy 342.00794 -401.201148) (xy 342.046031 -401.145513) (xy 342.067896 -401.119848)
			(xy 342.073697 -401.112706) (xy 342.080209 -401.095513) (xy 342.080596 -401.08632) (xy 342.080596 -400.92884)
			(xy 342.081049 -400.918721) (xy 342.088783 -400.900019) (xy 342.103088 -400.885703) (xy 342.121785 -400.877956)
			(xy 342.131904 -400.877532) (xy 342.848184 -400.877532) (xy 342.858309 -400.87793) (xy 342.877019 -400.885679)
			(xy 342.891335 -400.900001) (xy 342.899075 -400.918714) (xy 342.899492 -400.92884) (xy 342.899492 -401.08632)
			(xy 342.899894 -401.095508) (xy 342.906413 -401.112692) (xy 342.912192 -401.119848) (xy 342.934037 -401.145529)
			(xy 342.972126 -401.201161) (xy 343.003278 -401.260955) (xy 343.027044 -401.32405) (xy 343.043081 -401.389537)
			(xy 343.051159 -401.456474) (xy 343.051161 -401.523896) (xy 343.043087 -401.590833) (xy 343.027053 -401.656321)
			(xy 343.003291 -401.719417) (xy 343.001041 -401.723737) (xy 344.129061 -401.723737) (xy 344.129063 -401.65643)
			(xy 344.13711 -401.589606) (xy 344.153085 -401.524223) (xy 344.17676 -401.461217) (xy 344.207796 -401.401493)
			(xy 344.245747 -401.345906) (xy 344.267536 -401.320254) (xy 344.273339 -401.313114) (xy 344.279849 -401.295919)
			(xy 344.280236 -401.286726) (xy 344.280236 -400.793458) (xy 344.279838 -400.78427) (xy 344.273315 -400.767086)
			(xy 344.267536 -400.75993) (xy 344.245754 -400.734273) (xy 344.207805 -400.678687) (xy 344.176772 -400.618964)
			(xy 344.153099 -400.55596) (xy 344.137126 -400.490579) (xy 344.129081 -400.423757) (xy 344.129081 -400.356452)
			(xy 344.137124 -400.28963) (xy 344.153096 -400.224248) (xy 344.176768 -400.161244) (xy 344.207801 -400.101521)
			(xy 344.245749 -400.045934) (xy 344.267536 -400.020282) (xy 344.273327 -400.013133) (xy 344.279844 -399.995945)
			(xy 344.280236 -399.986754) (xy 344.280236 -399.828766) (xy 344.280705 -399.818606) (xy 344.288491 -399.799837)
			(xy 344.302864 -399.785473) (xy 344.321638 -399.777699) (xy 344.331798 -399.777204) (xy 345.048078 -399.777204)
			(xy 345.05823 -399.77775) (xy 345.076992 -399.785511) (xy 345.091357 -399.799861) (xy 345.099139 -399.818614)
			(xy 345.09964 -399.828766) (xy 345.09964 -399.986754) (xy 345.100086 -399.995937) (xy 345.106576 -400.013121)
			(xy 345.11234 -400.020282) (xy 345.134134 -400.045929) (xy 345.172084 -400.101516) (xy 345.203118 -400.16124)
			(xy 345.226792 -400.224245) (xy 345.242765 -400.289628) (xy 345.250809 -400.356452) (xy 345.250808 -400.423757)
			(xy 345.242763 -400.490581) (xy 345.226789 -400.555964) (xy 345.203115 -400.618968) (xy 345.172079 -400.678692)
			(xy 345.134129 -400.734278) (xy 345.11234 -400.75993) (xy 345.106541 -400.767073) (xy 345.100029 -400.784265)
			(xy 345.09964 -400.793458) (xy 345.09964 -401.286726) (xy 345.100051 -401.295913) (xy 345.106566 -401.313096)
			(xy 345.11234 -401.320254) (xy 345.134107 -401.345924) (xy 345.172057 -401.401507) (xy 345.203093 -401.461228)
			(xy 345.226768 -401.52423) (xy 345.242743 -401.589611) (xy 345.250789 -401.656432) (xy 345.250791 -401.723735)
			(xy 345.242749 -401.790557) (xy 345.226778 -401.855938) (xy 345.203106 -401.918942) (xy 345.172074 -401.978664)
			(xy 345.134127 -402.03425) (xy 345.11234 -402.059902) (xy 345.106553 -402.067053) (xy 345.100034 -402.084239)
			(xy 345.09964 -402.09343) (xy 345.09964 -402.251418) (xy 345.09925 -402.261593) (xy 345.091455 -402.280393)
			(xy 345.077059 -402.294778) (xy 345.058254 -402.302558) (xy 345.048078 -402.30298) (xy 344.331798 -402.30298)
			(xy 344.321642 -402.302469) (xy 344.302877 -402.294697) (xy 344.288512 -402.280337) (xy 344.280735 -402.261574)
			(xy 344.280236 -402.251418) (xy 344.280236 -402.09343) (xy 344.279803 -402.084245) (xy 344.273304 -402.067061)
			(xy 344.267536 -402.059902) (xy 344.245727 -402.034268) (xy 344.207779 -401.978679) (xy 344.176746 -401.918953)
			(xy 344.153075 -401.855946) (xy 344.137104 -401.790561) (xy 344.129061 -401.723737) (xy 343.001041 -401.723737)
			(xy 342.972142 -401.779213) (xy 342.934055 -401.834847) (xy 342.912192 -401.860512) (xy 342.906407 -401.867665)
			(xy 342.899886 -401.88485) (xy 342.899492 -401.89404) (xy 342.899492 -402.386292) (xy 342.899908 -402.395479)
			(xy 342.906418 -402.412663) (xy 342.912192 -402.41982) (xy 342.934009 -402.445524) (xy 342.9721 -402.501153)
			(xy 343.003253 -402.560944) (xy 343.02702 -402.624035) (xy 343.043059 -402.68952) (xy 343.051139 -402.756454)
			(xy 343.051143 -402.823819) (xy 346.329179 -402.823819) (xy 346.329184 -402.756509) (xy 346.337233 -402.689682)
			(xy 346.353213 -402.624297) (xy 346.376893 -402.56129) (xy 346.407934 -402.501566) (xy 346.445892 -402.445979)
			(xy 346.467684 -402.420328) (xy 346.473492 -402.413191) (xy 346.48 -402.395994) (xy 346.480384 -402.3868)
			(xy 346.480384 -401.893532) (xy 346.479962 -401.884346) (xy 346.473457 -401.867161) (xy 346.467684 -401.860004)
			(xy 346.445875 -401.834369) (xy 346.407924 -401.778781) (xy 346.376889 -401.719055) (xy 346.353216 -401.656049)
			(xy 346.337243 -401.590664) (xy 346.3292 -401.523839) (xy 346.329201 -401.456531) (xy 346.337248 -401.389707)
			(xy 346.353225 -401.324323) (xy 346.376902 -401.261317) (xy 346.40794 -401.201593) (xy 346.445894 -401.146008)
			(xy 346.467684 -401.120356) (xy 346.47348 -401.11321) (xy 346.479995 -401.09602) (xy 346.480384 -401.086828)
			(xy 346.480384 -400.92884) (xy 346.480854 -400.91869) (xy 346.488634 -400.899942) (xy 346.503015 -400.885618)
			(xy 346.521795 -400.877914) (xy 346.531946 -400.877532) (xy 347.248226 -400.877532) (xy 347.258353 -400.878005)
			(xy 347.277074 -400.88574) (xy 347.291429 -400.90003) (xy 347.299249 -400.918715) (xy 347.299788 -400.92884)
			(xy 347.299788 -401.086828) (xy 347.300187 -401.096016) (xy 347.306709 -401.1132) (xy 347.312488 -401.120356)
			(xy 347.334255 -401.146025) (xy 347.372203 -401.201609) (xy 347.403236 -401.261331) (xy 347.426908 -401.324333)
			(xy 347.442882 -401.389713) (xy 347.450927 -401.456533) (xy 347.450929 -401.523836) (xy 347.442887 -401.590657)
			(xy 347.426917 -401.656038) (xy 347.403248 -401.719042) (xy 347.400809 -401.723737) (xy 374.929092 -401.723737)
			(xy 374.929094 -401.65643) (xy 374.937141 -401.589605) (xy 374.953117 -401.524221) (xy 374.976794 -401.461216)
			(xy 375.007832 -401.401492) (xy 375.045786 -401.345906) (xy 375.067576 -401.320254) (xy 375.073372 -401.313108)
			(xy 375.079888 -401.295918) (xy 375.080276 -401.286726) (xy 375.080276 -400.793458) (xy 375.079891 -400.784268)
			(xy 375.07336 -400.767084) (xy 375.067576 -400.75993) (xy 375.045793 -400.734273) (xy 375.007842 -400.678688)
			(xy 374.976806 -400.618966) (xy 374.953131 -400.555962) (xy 374.937157 -400.49058) (xy 374.929112 -400.423757)
			(xy 374.929111 -400.356452) (xy 374.937155 -400.289629) (xy 374.953129 -400.224247) (xy 374.976802 -400.161242)
			(xy 375.007837 -400.101519) (xy 375.045788 -400.045934) (xy 375.067576 -400.020282) (xy 375.07336 -400.013128)
			(xy 375.079883 -399.995944) (xy 375.080276 -399.986754) (xy 375.080276 -399.828766) (xy 375.080637 -399.818587)
			(xy 375.08844 -399.799785) (xy 375.102845 -399.7854) (xy 375.121659 -399.777623) (xy 375.131838 -399.777204)
			(xy 375.848118 -399.777204) (xy 375.858273 -399.777718) (xy 375.877036 -399.785492) (xy 375.891399 -399.799851)
			(xy 375.899179 -399.818611) (xy 375.89968 -399.828766) (xy 375.89968 -399.986754) (xy 375.900117 -399.995938)
			(xy 375.906612 -400.013123) (xy 375.91238 -400.020282) (xy 375.934173 -400.045929) (xy 375.972121 -400.101517)
			(xy 376.003152 -400.161241) (xy 376.026824 -400.224247) (xy 376.042796 -400.289629) (xy 376.050839 -400.356452)
			(xy 376.050839 -400.423757) (xy 376.042794 -400.49058) (xy 376.026821 -400.555962) (xy 376.003149 -400.618967)
			(xy 375.972116 -400.678691) (xy 375.934168 -400.734278) (xy 375.91238 -400.75993) (xy 375.906586 -400.767077)
			(xy 375.90007 -400.784266) (xy 375.89968 -400.793458) (xy 375.89968 -401.286726) (xy 375.900082 -401.295914)
			(xy 375.906602 -401.313098) (xy 375.91238 -401.320254) (xy 375.934146 -401.345924) (xy 375.972094 -401.401508)
			(xy 376.003127 -401.46123) (xy 376.0268 -401.524232) (xy 376.042774 -401.589612) (xy 376.05082 -401.656432)
			(xy 376.050822 -401.723735) (xy 376.04278 -401.790556) (xy 376.02681 -401.855937) (xy 376.003141 -401.91894)
			(xy 375.972111 -401.978663) (xy 375.934166 -402.03425) (xy 375.91238 -402.059902) (xy 375.906598 -402.067057)
			(xy 375.900075 -402.08424) (xy 375.89968 -402.09343) (xy 375.89968 -402.251418) (xy 375.899182 -402.261575)
			(xy 375.891405 -402.280341) (xy 375.877041 -402.294705) (xy 375.858275 -402.302482) (xy 375.848118 -402.30298)
			(xy 375.131838 -402.30298) (xy 375.121671 -402.302505) (xy 375.102881 -402.294736) (xy 375.088495 -402.280366)
			(xy 375.080706 -402.261584) (xy 375.080276 -402.251418) (xy 375.080276 -402.09343) (xy 375.079857 -402.084244)
			(xy 375.07335 -402.067059) (xy 375.067576 -402.059902) (xy 375.045766 -402.034268) (xy 375.007815 -401.97868)
			(xy 374.976781 -401.918954) (xy 374.953108 -401.855947) (xy 374.937135 -401.790562) (xy 374.929092 -401.723737)
			(xy 347.400809 -401.723737) (xy 347.372218 -401.778765) (xy 347.334274 -401.834352) (xy 347.312488 -401.860004)
			(xy 347.306706 -401.867159) (xy 347.300183 -401.884342) (xy 347.299788 -401.893532) (xy 347.299788 -402.3868)
			(xy 347.300201 -402.395987) (xy 347.306713 -402.413171) (xy 347.312488 -402.420328) (xy 347.334227 -402.44602)
			(xy 347.372176 -402.501601) (xy 347.40321 -402.561319) (xy 347.426884 -402.624319) (xy 347.442859 -402.689696)
			(xy 347.450907 -402.756514) (xy 347.450911 -402.823814) (xy 347.450903 -402.823878) (xy 377.128705 -402.823878)
			(xy 377.12871 -402.75645) (xy 377.136791 -402.689508) (xy 377.152832 -402.624016) (xy 377.176603 -402.560917)
			(xy 377.20776 -402.50112) (xy 377.245856 -402.445485) (xy 377.267724 -402.41982) (xy 377.27354 -402.412689)
			(xy 377.280042 -402.395487) (xy 377.280424 -402.386292) (xy 377.280424 -401.89404) (xy 377.279989 -401.884856)
			(xy 377.273492 -401.867671) (xy 377.267724 -401.860512) (xy 377.24584 -401.834863) (xy 377.20775 -401.779227)
			(xy 377.176599 -401.719429) (xy 377.152835 -401.65633) (xy 377.1368 -401.590838) (xy 377.128725 -401.523898)
			(xy 377.128727 -401.456472) (xy 377.136805 -401.389532) (xy 377.152843 -401.324042) (xy 377.176611 -401.260944)
			(xy 377.207765 -401.201147) (xy 377.245858 -401.145513) (xy 377.267724 -401.119848) (xy 377.273528 -401.112708)
			(xy 377.280037 -401.095513) (xy 377.280424 -401.08632) (xy 377.280424 -400.92884) (xy 377.280849 -400.918717)
			(xy 377.288589 -400.90001) (xy 377.302903 -400.885693) (xy 377.321609 -400.877951) (xy 377.331732 -400.877532)
			(xy 378.048012 -400.877532) (xy 378.058139 -400.877907) (xy 378.076849 -400.885665) (xy 378.091164 -400.899994)
			(xy 378.098904 -400.918712) (xy 378.09932 -400.92884) (xy 378.09932 -401.08632) (xy 378.099716 -401.095509)
			(xy 378.106239 -401.112693) (xy 378.11202 -401.119848) (xy 378.133864 -401.14553) (xy 378.171952 -401.201162)
			(xy 378.203102 -401.260957) (xy 378.226866 -401.324051) (xy 378.242903 -401.389538) (xy 378.25098 -401.456474)
			(xy 378.250982 -401.523896) (xy 378.242908 -401.590832) (xy 378.226875 -401.65632) (xy 378.203114 -401.719416)
			(xy 378.200833 -401.723796) (xy 379.328885 -401.723796) (xy 379.328887 -401.656371) (xy 379.336964 -401.589432)
			(xy 379.353001 -401.523942) (xy 379.376766 -401.460844) (xy 379.407918 -401.401047) (xy 379.446008 -401.345412)
			(xy 379.467872 -401.319746) (xy 379.473683 -401.312611) (xy 379.480187 -401.295412) (xy 379.480572 -401.286218)
			(xy 379.480572 -400.793966) (xy 379.480184 -400.784776) (xy 379.473656 -400.767592) (xy 379.467872 -400.760438)
			(xy 379.446015 -400.734767) (xy 379.407928 -400.679133) (xy 379.376778 -400.619337) (xy 379.353015 -400.556241)
			(xy 379.33698 -400.490753) (xy 379.328904 -400.423816) (xy 379.328904 -400.356393) (xy 379.336979 -400.289456)
			(xy 379.353013 -400.223967) (xy 379.376775 -400.160871) (xy 379.407923 -400.101075) (xy 379.446009 -400.04544)
			(xy 379.467872 -400.019774) (xy 379.473671 -400.012631) (xy 379.480182 -399.995438) (xy 379.480572 -399.986246)
			(xy 379.480572 -399.828766) (xy 379.481 -399.818633) (xy 379.488744 -399.799905) (xy 379.503049 -399.785549)
			(xy 379.521749 -399.777737) (xy 379.53188 -399.777204) (xy 380.24816 -399.777204) (xy 380.25828 -399.777649)
			(xy 380.276984 -399.785385) (xy 380.2913 -399.799693) (xy 380.299045 -399.818392) (xy 380.299468 -399.828512)
			(xy 380.299468 -399.986246) (xy 380.299911 -399.99543) (xy 380.306403 -400.012614) (xy 380.312168 -400.019774)
			(xy 380.334039 -400.045434) (xy 380.37213 -400.101068) (xy 380.403282 -400.160865) (xy 380.427047 -400.223963)
			(xy 380.443083 -400.289453) (xy 380.451159 -400.356392) (xy 380.451158 -400.423817) (xy 380.443082 -400.490756)
			(xy 380.427044 -400.556246) (xy 380.403278 -400.619343) (xy 380.372125 -400.679139) (xy 380.334033 -400.734773)
			(xy 380.312168 -400.760438) (xy 380.306369 -400.767581) (xy 380.299856 -400.784773) (xy 380.299468 -400.793966)
			(xy 380.299468 -401.286218) (xy 380.299877 -401.295405) (xy 380.306392 -401.312589) (xy 380.312168 -401.319746)
			(xy 380.334011 -401.345429) (xy 380.372103 -401.40106) (xy 380.403256 -401.460853) (xy 380.427023 -401.523948)
			(xy 380.443061 -401.589435) (xy 380.451139 -401.656372) (xy 380.451141 -401.723795) (xy 380.443067 -401.790732)
			(xy 380.427033 -401.85622) (xy 380.40327 -401.919316) (xy 380.37212 -401.979112) (xy 380.334032 -402.034745)
			(xy 380.312168 -402.06041) (xy 380.306381 -402.067562) (xy 380.299861 -402.084747) (xy 380.299468 -402.093938)
			(xy 380.299468 -402.251418) (xy 380.298989 -402.261545) (xy 380.291256 -402.280265) (xy 380.276968 -402.29462)
			(xy 380.258284 -402.30244) (xy 380.24816 -402.30298) (xy 379.53188 -402.30298) (xy 379.521754 -402.3026)
			(xy 379.503046 -402.294842) (xy 379.488731 -402.280514) (xy 379.48099 -402.261799) (xy 379.480572 -402.251672)
			(xy 379.480572 -402.093938) (xy 379.48015 -402.084752) (xy 379.473645 -402.067567) (xy 379.467872 -402.06041)
			(xy 379.445987 -402.034762) (xy 379.407901 -401.979124) (xy 379.376753 -401.919326) (xy 379.352991 -401.856227)
			(xy 379.336958 -401.790736) (xy 379.328885 -401.723796) (xy 378.200833 -401.723796) (xy 378.171967 -401.779212)
			(xy 378.133882 -401.834846) (xy 378.11202 -401.860512) (xy 378.106238 -401.867668) (xy 378.099714 -401.88485)
			(xy 378.09932 -401.89404) (xy 378.09932 -402.386292) (xy 378.099729 -402.395479) (xy 378.106243 -402.412664)
			(xy 378.11202 -402.41982) (xy 378.133836 -402.445524) (xy 378.171925 -402.501154) (xy 378.203077 -402.560945)
			(xy 378.226843 -402.624037) (xy 378.242881 -402.689521) (xy 378.25096 -402.756454) (xy 378.250965 -402.823818)
			(xy 381.529025 -402.823818) (xy 381.529029 -402.75651) (xy 381.537078 -402.689684) (xy 381.553055 -402.6243)
			(xy 381.576732 -402.561293) (xy 381.607769 -402.501568) (xy 381.645722 -402.445981) (xy 381.667512 -402.420328)
			(xy 381.673323 -402.413193) (xy 381.679829 -402.395995) (xy 381.680212 -402.3868) (xy 381.680212 -401.893532)
			(xy 381.679784 -401.884347) (xy 381.673282 -401.867162) (xy 381.667512 -401.860004) (xy 381.645705 -401.834368)
			(xy 381.607759 -401.778778) (xy 381.576728 -401.719052) (xy 381.553058 -401.656046) (xy 381.537087 -401.590662)
			(xy 381.529045 -401.523838) (xy 381.529046 -401.456532) (xy 381.537092 -401.389708) (xy 381.553066 -401.324325)
			(xy 381.57674 -401.26132) (xy 381.607774 -401.201596) (xy 381.645724 -401.146009) (xy 381.667512 -401.120356)
			(xy 381.673311 -401.113213) (xy 381.679824 -401.096021) (xy 381.680212 -401.086828) (xy 381.680212 -400.92884)
			(xy 381.680649 -400.918719) (xy 381.688386 -400.900014) (xy 381.702697 -400.885698) (xy 381.721399 -400.877953)
			(xy 381.73152 -400.877532) (xy 382.448054 -400.877532) (xy 382.458177 -400.878064) (xy 382.476895 -400.885775)
			(xy 382.491253 -400.900048) (xy 382.499075 -400.91872) (xy 382.499616 -400.92884) (xy 382.499616 -401.086828)
			(xy 382.500009 -401.096017) (xy 382.506534 -401.113201) (xy 382.512316 -401.120356) (xy 382.534085 -401.146024)
			(xy 382.572038 -401.201607) (xy 382.603074 -401.261328) (xy 382.62675 -401.32433) (xy 382.642726 -401.389711)
			(xy 382.650772 -401.456533) (xy 382.650774 -401.523837) (xy 382.642731 -401.590659) (xy 382.626759 -401.656041)
			(xy 382.603087 -401.719045) (xy 382.600649 -401.723737) (xy 383.729179 -401.723737) (xy 383.729181 -401.65643)
			(xy 383.737228 -401.589605) (xy 383.753204 -401.524222) (xy 383.77688 -401.461216) (xy 383.807917 -401.401492)
			(xy 383.84587 -401.345906) (xy 383.86766 -401.320254) (xy 383.873466 -401.313116) (xy 383.879973 -401.29592)
			(xy 383.88036 -401.286726) (xy 383.88036 -400.793458) (xy 383.879957 -400.78427) (xy 383.873437 -400.767087)
			(xy 383.86766 -400.75993) (xy 383.845878 -400.734273) (xy 383.807927 -400.678688) (xy 383.776893 -400.618965)
			(xy 383.753219 -400.555961) (xy 383.737245 -400.490579) (xy 383.7292 -400.423757) (xy 383.729199 -400.356452)
			(xy 383.737243 -400.28963) (xy 383.753216 -400.224247) (xy 383.776889 -400.161243) (xy 383.807923 -400.10152)
			(xy 383.845872 -400.045934) (xy 383.86766 -400.020282) (xy 383.873454 -400.013135) (xy 383.879969 -399.995946)
			(xy 383.88036 -399.986754) (xy 383.88036 -399.828766) (xy 383.880806 -399.818603) (xy 383.888596 -399.799829)
			(xy 383.902976 -399.785464) (xy 383.921759 -399.777695) (xy 383.931922 -399.777204) (xy 384.648202 -399.777204)
			(xy 384.658356 -399.777731) (xy 384.677118 -399.7855) (xy 384.691482 -399.799855) (xy 384.699263 -399.818613)
			(xy 384.699764 -399.828766) (xy 384.699764 -399.986754) (xy 384.700205 -399.995938) (xy 384.706698 -400.013122)
			(xy 384.712464 -400.020282) (xy 384.734258 -400.045929) (xy 384.772206 -400.101516) (xy 384.803239 -400.161241)
			(xy 384.826911 -400.224246) (xy 384.842884 -400.289629) (xy 384.850927 -400.356452) (xy 384.850927 -400.423757)
			(xy 384.842882 -400.49058) (xy 384.826909 -400.555963) (xy 384.803235 -400.618968) (xy 384.772201 -400.678691)
			(xy 384.734252 -400.734278) (xy 384.712464 -400.75993) (xy 384.706668 -400.767075) (xy 384.700154 -400.784266)
			(xy 384.699764 -400.793458) (xy 384.699764 -401.286726) (xy 384.70017 -401.295913) (xy 384.706687 -401.313097)
			(xy 384.712464 -401.320254) (xy 384.73423 -401.345924) (xy 384.772179 -401.401508) (xy 384.803213 -401.461229)
			(xy 384.826887 -401.524231) (xy 384.842861 -401.589611) (xy 384.850907 -401.656432) (xy 384.850909 -401.723735)
			(xy 384.842867 -401.790556) (xy 384.826897 -401.855937) (xy 384.803227 -401.918941) (xy 384.772196 -401.978663)
			(xy 384.73425 -402.03425) (xy 384.712464 -402.059902) (xy 384.706679 -402.067056) (xy 384.700158 -402.08424)
			(xy 384.699764 -402.09343) (xy 384.699764 -402.251418) (xy 384.699282 -402.261577) (xy 384.691502 -402.280346)
			(xy 384.677133 -402.294711) (xy 384.658361 -402.302485) (xy 384.648202 -402.30298) (xy 383.931922 -402.30298)
			(xy 383.921754 -402.302518) (xy 383.902963 -402.294744) (xy 383.888578 -402.28037) (xy 383.88079 -402.261586)
			(xy 383.88036 -402.251418) (xy 383.88036 -402.09343) (xy 383.879922 -402.084246) (xy 383.873426 -402.067062)
			(xy 383.86766 -402.059902) (xy 383.84585 -402.034268) (xy 383.8079 -401.97868) (xy 383.776867 -401.918954)
			(xy 383.753194 -401.855947) (xy 383.737222 -401.790562) (xy 383.729179 -401.723737) (xy 382.600649 -401.723737)
			(xy 382.572053 -401.778767) (xy 382.534104 -401.834352) (xy 382.512316 -401.860004) (xy 382.506537 -401.867162)
			(xy 382.500011 -401.884343) (xy 382.499616 -401.893532) (xy 382.499616 -402.3868) (xy 382.500023 -402.395988)
			(xy 382.506538 -402.413172) (xy 382.512316 -402.420328) (xy 382.534058 -402.446018) (xy 382.572011 -402.501598)
			(xy 382.603049 -402.561316) (xy 382.626726 -402.624316) (xy 382.642704 -402.689694) (xy 382.650753 -402.756513)
			(xy 382.650757 -402.823815) (xy 382.650749 -402.823878) (xy 385.928793 -402.823878) (xy 385.928798 -402.75645)
			(xy 385.936878 -402.689508) (xy 385.952919 -402.624017) (xy 385.976689 -402.560918) (xy 386.007846 -402.50112)
			(xy 386.045941 -402.445485) (xy 386.067808 -402.41982) (xy 386.073622 -402.412687) (xy 386.080126 -402.395487)
			(xy 386.080508 -402.386292) (xy 386.080508 -401.89404) (xy 386.080077 -401.884855) (xy 386.073578 -401.867671)
			(xy 386.067808 -401.860512) (xy 386.045924 -401.834863) (xy 386.007835 -401.779226) (xy 385.976685 -401.719428)
			(xy 385.952922 -401.656329) (xy 385.936887 -401.590838) (xy 385.928813 -401.523898) (xy 385.928815 -401.456472)
			(xy 385.936893 -401.389533) (xy 385.952931 -401.324042) (xy 385.976697 -401.260944) (xy 386.007851 -401.201148)
			(xy 386.045943 -401.145513) (xy 386.067808 -401.119848) (xy 386.07361 -401.112707) (xy 386.080121 -401.095513)
			(xy 386.080508 -401.08632) (xy 386.080508 -400.92884) (xy 386.080949 -400.918719) (xy 386.088686 -400.900015)
			(xy 386.102995 -400.885699) (xy 386.121695 -400.877954) (xy 386.131816 -400.877532) (xy 386.848096 -400.877532)
			(xy 386.858222 -400.87792) (xy 386.876932 -400.885673) (xy 386.891247 -400.899998) (xy 386.898987 -400.918714)
			(xy 386.899404 -400.92884) (xy 386.899404 -401.08632) (xy 386.899804 -401.095508) (xy 386.906325 -401.112692)
			(xy 386.912104 -401.119848) (xy 386.933948 -401.14553) (xy 386.972037 -401.201162) (xy 387.003189 -401.260956)
			(xy 387.026954 -401.324051) (xy 387.04299 -401.389538) (xy 387.051068 -401.456474) (xy 387.05107 -401.523896)
			(xy 387.042996 -401.590833) (xy 387.026963 -401.656321) (xy 387.003201 -401.719417) (xy 387.000951 -401.723737)
			(xy 388.12897 -401.723737) (xy 388.128972 -401.65643) (xy 388.137019 -401.589606) (xy 388.152994 -401.524222)
			(xy 388.17667 -401.461217) (xy 388.207706 -401.401492) (xy 388.245659 -401.345906) (xy 388.267448 -401.320254)
			(xy 388.273253 -401.313115) (xy 388.279761 -401.295919) (xy 388.280148 -401.286726) (xy 388.280148 -400.793458)
			(xy 388.279747 -400.78427) (xy 388.273226 -400.767086) (xy 388.267448 -400.75993) (xy 388.245666 -400.734273)
			(xy 388.207717 -400.678687) (xy 388.176683 -400.618965) (xy 388.153009 -400.555961) (xy 388.137035 -400.490579)
			(xy 388.128991 -400.423757) (xy 388.12899 -400.356452) (xy 388.137034 -400.28963) (xy 388.153006 -400.224248)
			(xy 388.176679 -400.161244) (xy 388.207712 -400.10152) (xy 388.245661 -400.045934) (xy 388.267448 -400.020282)
			(xy 388.273241 -400.013134) (xy 388.279756 -399.995946) (xy 388.280148 -399.986754) (xy 388.280148 -399.828766)
			(xy 388.280606 -399.818605) (xy 388.288393 -399.799833) (xy 388.30277 -399.785469) (xy 388.321548 -399.777697)
			(xy 388.33171 -399.777204) (xy 389.04799 -399.777204) (xy 389.058143 -399.777741) (xy 389.076905 -399.785506)
			(xy 389.09127 -399.799858) (xy 389.099051 -399.818613) (xy 389.099552 -399.828766) (xy 389.099552 -399.986754)
			(xy 389.099995 -399.995937) (xy 389.106487 -400.013121) (xy 389.112252 -400.020282) (xy 389.134046 -400.045929)
			(xy 389.171995 -400.101516) (xy 389.203029 -400.16124) (xy 389.226702 -400.224245) (xy 389.242675 -400.289628)
			(xy 389.250718 -400.356452) (xy 389.250718 -400.423757) (xy 389.242673 -400.490581) (xy 389.226699 -400.555963)
			(xy 389.203025 -400.618968) (xy 389.171991 -400.678692) (xy 389.134041 -400.734278) (xy 389.112252 -400.75993)
			(xy 389.106454 -400.767074) (xy 389.099942 -400.784266) (xy 389.099552 -400.793458) (xy 389.099552 -401.286726)
			(xy 389.09996 -401.295913) (xy 389.106477 -401.313097) (xy 389.112252 -401.320254) (xy 389.134018 -401.345924)
			(xy 389.171968 -401.401508) (xy 389.203003 -401.461229) (xy 389.226677 -401.524231) (xy 389.242652 -401.589611)
			(xy 389.250698 -401.656432) (xy 389.2507 -401.723735) (xy 389.242658 -401.790556) (xy 389.226687 -401.855937)
			(xy 389.203016 -401.918941) (xy 389.171985 -401.978664) (xy 389.134038 -402.03425) (xy 389.112252 -402.059902)
			(xy 389.106466 -402.067055) (xy 389.099946 -402.08424) (xy 389.099552 -402.09343) (xy 389.099552 -402.251418)
			(xy 389.099081 -402.261578) (xy 389.091299 -402.28035) (xy 389.076926 -402.294715) (xy 389.05815 -402.302487)
			(xy 389.04799 -402.30298) (xy 388.33171 -402.30298) (xy 388.321555 -402.302459) (xy 388.30279 -402.294691)
			(xy 388.288425 -402.280334) (xy 388.280647 -402.261573) (xy 388.280148 -402.251418) (xy 388.280148 -402.09343)
			(xy 388.279713 -402.084246) (xy 388.273215 -402.067062) (xy 388.267448 -402.059902) (xy 388.245638 -402.034268)
			(xy 388.207689 -401.978679) (xy 388.176657 -401.918953) (xy 388.152985 -401.855946) (xy 388.137013 -401.790562)
			(xy 388.12897 -401.723737) (xy 387.000951 -401.723737) (xy 386.972053 -401.779212) (xy 386.933967 -401.834847)
			(xy 386.912104 -401.860512) (xy 386.90632 -401.867666) (xy 386.899798 -401.88485) (xy 386.899404 -401.89404)
			(xy 386.899404 -402.386292) (xy 386.899817 -402.395479) (xy 386.906329 -402.412663) (xy 386.912104 -402.41982)
			(xy 386.933921 -402.445524) (xy 386.972011 -402.501153) (xy 387.003163 -402.560944) (xy 387.02693 -402.624036)
			(xy 387.042968 -402.68952) (xy 387.051048 -402.756454) (xy 387.051052 -402.823818) (xy 390.329113 -402.823818)
			(xy 390.329117 -402.75651) (xy 390.337166 -402.689685) (xy 390.353142 -402.6243) (xy 390.376819 -402.561294)
			(xy 390.407855 -402.501569) (xy 390.445807 -402.445981) (xy 390.467596 -402.420328) (xy 390.473405 -402.413192)
			(xy 390.479912 -402.395994) (xy 390.480296 -402.3868) (xy 390.480296 -401.893532) (xy 390.479871 -401.884346)
			(xy 390.473368 -401.867162) (xy 390.467596 -401.860004) (xy 390.44579 -401.834367) (xy 390.407845 -401.778778)
			(xy 390.376815 -401.719052) (xy 390.353145 -401.656045) (xy 390.337174 -401.590661) (xy 390.329133 -401.523838)
			(xy 390.329134 -401.456532) (xy 390.33718 -401.389709) (xy 390.353154 -401.324326) (xy 390.376827 -401.261321)
			(xy 390.40786 -401.201596) (xy 390.445808 -401.146009) (xy 390.467596 -401.120356) (xy 390.473393 -401.113211)
			(xy 390.479908 -401.09602) (xy 390.480296 -401.086828) (xy 390.480296 -400.92884) (xy 390.480749 -400.918721)
			(xy 390.488483 -400.900019) (xy 390.502788 -400.885703) (xy 390.521485 -400.877956) (xy 390.531604 -400.877532)
			(xy 391.248138 -400.877532) (xy 391.258266 -400.877995) (xy 391.276987 -400.885734) (xy 391.291341 -400.900027)
			(xy 391.299161 -400.918714) (xy 391.2997 -400.92884) (xy 391.2997 -401.086828) (xy 391.300096 -401.096017)
			(xy 391.30662 -401.113201) (xy 391.3124 -401.120356) (xy 391.334167 -401.146025) (xy 391.372114 -401.20161)
			(xy 391.403146 -401.261331) (xy 391.426818 -401.324334) (xy 391.442791 -401.389713) (xy 391.450836 -401.456534)
			(xy 391.450838 -401.523836) (xy 391.442797 -401.590657) (xy 391.426827 -401.656038) (xy 391.403158 -401.719041)
			(xy 391.372129 -401.778764) (xy 391.334185 -401.834351) (xy 391.3124 -401.860004) (xy 391.306619 -401.86716)
			(xy 391.300095 -401.884342) (xy 391.2997 -401.893532) (xy 391.2997 -402.3868) (xy 391.30011 -402.395987)
			(xy 391.306624 -402.413171) (xy 391.3124 -402.420328) (xy 391.334139 -402.446019) (xy 391.372087 -402.501601)
			(xy 391.40312 -402.56132) (xy 391.426794 -402.624319) (xy 391.442769 -402.689696) (xy 391.450817 -402.756514)
			(xy 391.450821 -402.823814) (xy 391.442782 -402.890633) (xy 391.426815 -402.956012) (xy 391.40315 -403.019014)
			(xy 391.372124 -403.078737) (xy 391.334184 -403.134323) (xy 391.3124 -403.159976) (xy 391.306589 -403.167111)
			(xy 391.300083 -403.184309) (xy 391.2997 -403.193504) (xy 391.2997 -403.351492) (xy 391.299277 -403.361614)
			(xy 391.291532 -403.380317) (xy 391.277217 -403.394632) (xy 391.258514 -403.402377) (xy 391.248392 -403.4028)
			(xy 390.531858 -403.4028) (xy 390.521734 -403.402309) (xy 390.503019 -403.394575) (xy 390.488666 -403.380291)
			(xy 390.480841 -403.361614) (xy 390.480296 -403.351492) (xy 390.480296 -403.193504) (xy 390.479885 -403.184317)
			(xy 390.473372 -403.167133) (xy 390.467596 -403.159976) (xy 390.445763 -403.134362) (xy 390.407818 -403.078769)
			(xy 390.376789 -403.01904) (xy 390.353121 -402.95603) (xy 390.337153 -402.890644) (xy 390.329113 -402.823818)
			(xy 387.051052 -402.823818) (xy 387.051052 -402.823874) (xy 387.042981 -402.890809) (xy 387.026951 -402.956295)
			(xy 387.003193 -403.01939) (xy 386.972048 -403.079185) (xy 386.933965 -403.134819) (xy 386.912104 -403.160484)
			(xy 386.90629 -403.167617) (xy 386.899785 -403.184817) (xy 386.899404 -403.194012) (xy 386.899404 -403.351492)
			(xy 386.898978 -403.361613) (xy 386.891233 -403.380316) (xy 386.87692 -403.394631) (xy 386.858217 -403.402377)
			(xy 386.848096 -403.4028) (xy 386.131816 -403.4028) (xy 386.121695 -403.402371) (xy 386.102991 -403.394628)
			(xy 386.088676 -403.380315) (xy 386.080931 -403.361613) (xy 386.080508 -403.351492) (xy 386.080508 -403.194012)
			(xy 386.08009 -403.184826) (xy 386.073582 -403.167641) (xy 386.067808 -403.160484) (xy 386.045897 -403.134858)
			(xy 386.007809 -403.079218) (xy 385.97666 -403.019416) (xy 385.952898 -402.956314) (xy 385.936865 -402.89082)
			(xy 385.928793 -402.823878) (xy 382.650749 -402.823878) (xy 382.642717 -402.890635) (xy 382.626748 -402.956015)
			(xy 382.603078 -403.019018) (xy 382.572048 -403.07874) (xy 382.534102 -403.134324) (xy 382.512316 -403.159976)
			(xy 382.506507 -403.167112) (xy 382.499999 -403.18431) (xy 382.499616 -403.193504) (xy 382.499616 -403.351492)
			(xy 382.499109 -403.361598) (xy 382.491377 -403.380273) (xy 382.477087 -403.394568) (xy 382.458414 -403.402306)
			(xy 382.448308 -403.4028) (xy 381.731774 -403.4028) (xy 381.721651 -403.402296) (xy 381.702936 -403.394567)
			(xy 381.688582 -403.380287) (xy 381.680757 -403.361613) (xy 381.680212 -403.351492) (xy 381.680212 -403.193504)
			(xy 381.679797 -403.184317) (xy 381.673286 -403.167133) (xy 381.667512 -403.159976) (xy 381.645678 -403.134362)
			(xy 381.607732 -403.07877) (xy 381.576703 -403.019041) (xy 381.553034 -402.956031) (xy 381.537065 -402.890644)
			(xy 381.529025 -402.823818) (xy 378.250965 -402.823818) (xy 378.250965 -402.823874) (xy 378.242894 -402.890808)
			(xy 378.226864 -402.956294) (xy 378.203106 -403.019389) (xy 378.171962 -403.079184) (xy 378.13388 -403.134818)
			(xy 378.11202 -403.160484) (xy 378.106208 -403.167618) (xy 378.099702 -403.184817) (xy 378.09932 -403.194012)
			(xy 378.09932 -403.351492) (xy 378.098809 -403.361598) (xy 378.091078 -403.380272) (xy 378.076789 -403.394566)
			(xy 378.058118 -403.402305) (xy 378.048012 -403.4028) (xy 377.331732 -403.4028) (xy 377.321612 -403.402358)
			(xy 377.302909 -403.39462) (xy 377.288593 -403.380312) (xy 377.280847 -403.361612) (xy 377.280424 -403.351492)
			(xy 377.280424 -403.194012) (xy 377.280002 -403.184826) (xy 377.273496 -403.167642) (xy 377.267724 -403.160484)
			(xy 377.245812 -403.134858) (xy 377.207723 -403.079218) (xy 377.176573 -403.019417) (xy 377.152811 -402.956315)
			(xy 377.136778 -402.890821) (xy 377.128705 -402.823878) (xy 347.450903 -402.823878) (xy 347.442872 -402.890633)
			(xy 347.426905 -402.956012) (xy 347.403239 -403.019015) (xy 347.372213 -403.078737) (xy 347.334272 -403.134323)
			(xy 347.312488 -403.159976) (xy 347.306675 -403.16711) (xy 347.300171 -403.184309) (xy 347.299788 -403.193504)
			(xy 347.299788 -403.351492) (xy 347.299372 -403.361647) (xy 347.291576 -403.380402) (xy 347.277178 -403.394726)
			(xy 347.258383 -403.402424) (xy 347.248226 -403.4028) (xy 346.531946 -403.4028) (xy 346.521827 -403.402237)
			(xy 346.503115 -403.394532) (xy 346.488758 -403.380269) (xy 346.48093 -403.361607) (xy 346.480384 -403.351492)
			(xy 346.480384 -403.193504) (xy 346.479975 -403.184317) (xy 346.473461 -403.167132) (xy 346.467684 -403.159976)
			(xy 346.445847 -403.134364) (xy 346.407897 -403.078772) (xy 346.376863 -403.019044) (xy 346.353191 -402.956034)
			(xy 346.33722 -402.890646) (xy 346.329179 -402.823819) (xy 343.051143 -402.823819) (xy 343.051143 -402.823874)
			(xy 343.043072 -402.890809) (xy 343.027042 -402.956296) (xy 343.003282 -403.019391) (xy 342.972137 -403.079185)
			(xy 342.934053 -403.134819) (xy 342.912192 -403.160484) (xy 342.906376 -403.167616) (xy 342.899873 -403.184817)
			(xy 342.899492 -403.194012) (xy 342.899492 -403.351492) (xy 342.899077 -403.361615) (xy 342.89133 -403.38032)
			(xy 342.877013 -403.394635) (xy 342.858307 -403.402379) (xy 342.848184 -403.4028) (xy 342.131904 -403.4028)
			(xy 342.121782 -403.402381) (xy 342.103078 -403.394634) (xy 342.088764 -403.380318) (xy 342.081019 -403.361614)
			(xy 342.080596 -403.351492) (xy 342.080596 -403.194012) (xy 342.080181 -403.184825) (xy 342.073671 -403.167641)
			(xy 342.067896 -403.160484) (xy 342.045985 -403.134858) (xy 342.007898 -403.079217) (xy 341.97675 -403.019416)
			(xy 341.952988 -402.956314) (xy 341.936956 -402.89082) (xy 341.928884 -402.823878) (xy 338.650816 -402.823878)
			(xy 338.642785 -402.890633) (xy 338.626819 -402.956012) (xy 338.603153 -403.019014) (xy 338.572128 -403.078737)
			(xy 338.534188 -403.134323) (xy 338.512404 -403.159976) (xy 338.506593 -403.167111) (xy 338.500087 -403.184309)
			(xy 338.499704 -403.193504) (xy 338.499704 -403.351492) (xy 338.499272 -403.361645) (xy 338.49148 -403.380397)
			(xy 338.477086 -403.39472) (xy 338.458297 -403.402421) (xy 338.448142 -403.4028) (xy 337.731862 -403.4028)
			(xy 337.721738 -403.402306) (xy 337.703023 -403.394573) (xy 337.68867 -403.38029) (xy 337.680845 -403.361614)
			(xy 337.6803 -403.351492) (xy 337.6803 -403.193504) (xy 337.679888 -403.184317) (xy 337.673375 -403.167133)
			(xy 337.6676 -403.159976) (xy 337.645766 -403.134362) (xy 337.607822 -403.078769) (xy 337.576793 -403.01904)
			(xy 337.553124 -402.956031) (xy 337.537156 -402.890644) (xy 337.529116 -402.823818) (xy 334.251055 -402.823818)
			(xy 334.251055 -402.823874) (xy 334.242984 -402.890809) (xy 334.226954 -402.956295) (xy 334.203196 -403.01939)
			(xy 334.172051 -403.079185) (xy 334.133969 -403.134819) (xy 334.112108 -403.160484) (xy 334.106294 -403.167617)
			(xy 334.09979 -403.184817) (xy 334.099408 -403.194012) (xy 334.099408 -403.351492) (xy 334.098978 -403.361613)
			(xy 334.091234 -403.380315) (xy 334.076922 -403.394629) (xy 334.058221 -403.402376) (xy 334.0481 -403.4028)
			(xy 333.33182 -403.4028) (xy 333.321699 -403.402368) (xy 333.302996 -403.394626) (xy 333.288681 -403.380315)
			(xy 333.280935 -403.361613) (xy 333.280512 -403.351492) (xy 333.280512 -403.194012) (xy 333.280093 -403.184826)
			(xy 333.273585 -403.167642) (xy 333.267812 -403.160484) (xy 333.2459 -403.134858) (xy 333.207812 -403.079218)
			(xy 333.176663 -403.019417) (xy 333.152901 -402.956315) (xy 333.136869 -402.890821) (xy 333.128796 -402.823878)
			(xy 326.525636 -402.823878) (xy 326.525636 -405.623648) (xy 330.929194 -405.623648) (xy 330.929195 -405.556343)
			(xy 330.93724 -405.489519) (xy 330.953214 -405.424136) (xy 330.976889 -405.361131) (xy 331.007924 -405.301408)
			(xy 331.045875 -405.245822) (xy 331.067664 -405.22017) (xy 331.073464 -405.213027) (xy 331.079975 -405.195835)
			(xy 331.080364 -405.186642) (xy 331.080364 -404.693374) (xy 331.079952 -404.684187) (xy 331.073438 -404.667004)
			(xy 331.067664 -404.659846) (xy 331.045897 -404.634176) (xy 331.007946 -404.578593) (xy 330.976911 -404.518872)
			(xy 330.953235 -404.45587) (xy 330.93726 -404.390489) (xy 330.929214 -404.323668) (xy 330.929212 -404.256365)
			(xy 330.937254 -404.189543) (xy 330.953226 -404.124162) (xy 330.976897 -404.061158) (xy 331.007929 -404.001435)
			(xy 331.045877 -403.94585) (xy 331.067664 -403.920198) (xy 331.073452 -403.913047) (xy 331.07997 -403.895861)
			(xy 331.080364 -403.88667) (xy 331.080364 -403.728682) (xy 331.08075 -403.718506) (xy 331.088546 -403.699706)
			(xy 331.102943 -403.685321) (xy 331.12175 -403.677541) (xy 331.131926 -403.67712) (xy 331.848206 -403.67712)
			(xy 331.858362 -403.677628) (xy 331.877128 -403.685401) (xy 331.891492 -403.699762) (xy 331.899269 -403.718526)
			(xy 331.899768 -403.728682) (xy 331.899768 -403.88667) (xy 331.9002 -403.895855) (xy 331.906699 -403.913039)
			(xy 331.912468 -403.920198) (xy 331.934277 -403.945832) (xy 331.972225 -404.001422) (xy 332.003257 -404.061148)
			(xy 332.026928 -404.124154) (xy 332.042899 -404.189539) (xy 332.050942 -404.256363) (xy 332.05094 -404.32367)
			(xy 332.042893 -404.390494) (xy 332.026918 -404.455877) (xy 332.003243 -404.518883) (xy 331.972208 -404.578607)
			(xy 331.934257 -404.634194) (xy 331.912468 -404.659846) (xy 331.906665 -404.666987) (xy 331.900155 -404.684181)
			(xy 331.899768 -404.693374) (xy 331.899768 -405.186642) (xy 331.900165 -405.19583) (xy 331.906689 -405.213014)
			(xy 331.912468 -405.22017) (xy 331.93425 -405.245827) (xy 331.972198 -405.301413) (xy 332.003231 -405.361136)
			(xy 332.026904 -405.42414) (xy 332.042877 -405.489521) (xy 332.050922 -405.556343) (xy 332.050923 -405.623648)
			(xy 332.042879 -405.69047) (xy 332.026907 -405.755852) (xy 332.003235 -405.818856) (xy 331.972203 -405.878579)
			(xy 331.934255 -405.934166) (xy 331.912468 -405.959818) (xy 331.906677 -405.966967) (xy 331.90016 -405.984155)
			(xy 331.899768 -405.993346) (xy 331.899768 -406.151334) (xy 331.899295 -406.161493) (xy 331.89151 -406.180262)
			(xy 331.877138 -406.194626) (xy 331.858365 -406.2024) (xy 331.848206 -406.202896) (xy 331.131926 -406.202896)
			(xy 331.121774 -406.202346) (xy 331.103012 -406.194587) (xy 331.088647 -406.180238) (xy 331.080865 -406.161485)
			(xy 331.080364 -406.151334) (xy 331.080364 -405.993346) (xy 331.079918 -405.984163) (xy 331.073428 -405.966979)
			(xy 331.067664 -405.959818) (xy 331.04587 -405.934171) (xy 331.007919 -405.878584) (xy 330.976885 -405.81886)
			(xy 330.953212 -405.755855) (xy 330.937238 -405.690472) (xy 330.929194 -405.623648) (xy 326.525636 -405.623648)
			(xy 326.525636 -406.723789) (xy 333.128808 -406.723789) (xy 333.128811 -406.656363) (xy 333.13689 -406.589422)
			(xy 333.152929 -406.523931) (xy 333.176697 -406.460833) (xy 333.207852 -406.401036) (xy 333.245946 -406.345401)
			(xy 333.267812 -406.319736) (xy 333.27362 -406.312599) (xy 333.280127 -406.295402) (xy 333.280512 -406.286208)
			(xy 333.280512 -405.793956) (xy 333.28012 -405.784767) (xy 333.273594 -405.767583) (xy 333.267812 -405.760428)
			(xy 333.245944 -405.734766) (xy 333.207854 -405.679131) (xy 333.176703 -405.619335) (xy 333.152939 -405.556238)
			(xy 333.136903 -405.490748) (xy 333.128827 -405.423809) (xy 333.128828 -405.356385) (xy 333.136904 -405.289446)
			(xy 333.15294 -405.223957) (xy 333.176706 -405.16086) (xy 333.207857 -405.101063) (xy 333.245947 -405.045429)
			(xy 333.267812 -405.019764) (xy 333.273608 -405.012618) (xy 333.280123 -404.995428) (xy 333.280512 -404.986236)
			(xy 333.280512 -404.828756) (xy 333.280949 -404.818643) (xy 333.288704 -404.799961) (xy 333.303015 -404.785668)
			(xy 333.321706 -404.777937) (xy 333.33182 -404.777448) (xy 334.0481 -404.777448) (xy 334.058202 -404.777984)
			(xy 334.076871 -404.785712) (xy 334.091163 -404.799993) (xy 334.098907 -404.818654) (xy 334.099408 -404.828756)
			(xy 334.099408 -404.986236) (xy 334.099799 -404.995425) (xy 334.106326 -405.01261) (xy 334.112108 -405.019764)
			(xy 334.133968 -405.045433) (xy 334.172056 -405.101067) (xy 334.203206 -405.160863) (xy 334.226971 -405.223959)
			(xy 334.243006 -405.289448) (xy 334.251082 -405.356385) (xy 334.251082 -405.423809) (xy 334.243007 -405.490746)
			(xy 334.226972 -405.556235) (xy 334.203209 -405.619332) (xy 334.20093 -405.623707) (xy 335.328987 -405.623707)
			(xy 335.328987 -405.556284) (xy 335.337063 -405.489346) (xy 335.353098 -405.423857) (xy 335.376861 -405.36076)
			(xy 335.40801 -405.300963) (xy 335.446097 -405.245328) (xy 335.46796 -405.219662) (xy 335.473763 -405.212521)
			(xy 335.480272 -405.195327) (xy 335.48066 -405.186134) (xy 335.48066 -404.693882) (xy 335.480245 -404.684696)
			(xy 335.473733 -404.667512) (xy 335.46796 -404.660354) (xy 335.446119 -404.63467) (xy 335.408032 -404.579037)
			(xy 335.376883 -404.519243) (xy 335.353119 -404.456149) (xy 335.337083 -404.390663) (xy 335.329006 -404.323727)
			(xy 335.329004 -404.256306) (xy 335.337078 -404.18937) (xy 335.353109 -404.123883) (xy 335.376869 -404.060787)
			(xy 335.408015 -404.000991) (xy 335.446099 -403.945356) (xy 335.46796 -403.91969) (xy 335.473751 -403.912541)
			(xy 335.480267 -403.895353) (xy 335.48066 -403.886162) (xy 335.48066 -403.728682) (xy 335.481112 -403.718552)
			(xy 335.48885 -403.699826) (xy 335.503147 -403.68547) (xy 335.52184 -403.677655) (xy 335.531968 -403.67712)
			(xy 336.248248 -403.67712) (xy 336.258408 -403.677483) (xy 336.277165 -403.685298) (xy 336.291487 -403.699713)
			(xy 336.299182 -403.71852) (xy 336.299556 -403.728682) (xy 336.299556 -403.886162) (xy 336.299995 -403.895346)
			(xy 336.30649 -403.91253) (xy 336.312256 -403.91969) (xy 336.334143 -403.945337) (xy 336.372234 -404.000973)
			(xy 336.403386 -404.060771) (xy 336.427151 -404.123871) (xy 336.443186 -404.189362) (xy 336.451261 -404.256303)
			(xy 336.451259 -404.32373) (xy 336.443181 -404.39067) (xy 336.427141 -404.456161) (xy 336.403373 -404.519259)
			(xy 336.372217 -404.579056) (xy 336.334123 -404.634689) (xy 336.312256 -404.660354) (xy 336.306449 -404.667491)
			(xy 336.299941 -404.684688) (xy 336.299556 -404.693882) (xy 336.299556 -405.186134) (xy 336.29996 -405.195322)
			(xy 336.306479 -405.212505) (xy 336.312256 -405.219662) (xy 336.334116 -405.245331) (xy 336.372207 -405.300964)
			(xy 336.403361 -405.360759) (xy 336.427127 -405.423856) (xy 336.443164 -405.489345) (xy 336.451242 -405.556283)
			(xy 336.451242 -405.623708) (xy 336.443166 -405.690646) (xy 336.42713 -405.756135) (xy 336.403365 -405.819232)
			(xy 336.372212 -405.879028) (xy 336.334121 -405.934662) (xy 336.312256 -405.960326) (xy 336.30646 -405.967472)
			(xy 336.299946 -405.984662) (xy 336.299556 -405.993854) (xy 336.299556 -406.151334) (xy 336.299101 -406.161463)
			(xy 336.291362 -406.180186) (xy 336.277066 -406.194541) (xy 336.258375 -406.202359) (xy 336.248248 -406.202896)
			(xy 335.531968 -406.202896) (xy 335.521811 -406.202505) (xy 335.503057 -406.194698) (xy 335.488735 -406.180292)
			(xy 335.481037 -406.161493) (xy 335.48066 -406.151334) (xy 335.48066 -405.993854) (xy 335.48021 -405.984671)
			(xy 335.473722 -405.967487) (xy 335.46796 -405.960326) (xy 335.446092 -405.934665) (xy 335.408006 -405.879029)
			(xy 335.376857 -405.819232) (xy 335.353095 -405.756134) (xy 335.337062 -405.690645) (xy 335.328987 -405.623707)
			(xy 334.20093 -405.623707) (xy 334.172059 -405.679128) (xy 334.133971 -405.734763) (xy 334.112108 -405.760428)
			(xy 334.106318 -405.767578) (xy 334.099799 -405.784765) (xy 334.099408 -405.793956) (xy 334.099408 -406.286208)
			(xy 334.099813 -406.295396) (xy 334.10633 -406.31258) (xy 334.112108 -406.319736) (xy 334.13394 -406.345427)
			(xy 334.172029 -406.401058) (xy 334.203181 -406.460851) (xy 334.226947 -406.523944) (xy 334.242984 -406.58943)
			(xy 334.251062 -406.656365) (xy 334.251065 -406.723729) (xy 337.529127 -406.723729) (xy 337.52913 -406.656423)
			(xy 337.537177 -406.589598) (xy 337.553152 -406.524215) (xy 337.576827 -406.461209) (xy 337.607861 -406.401484)
			(xy 337.645812 -406.345897) (xy 337.6676 -406.320244) (xy 337.673403 -406.313103) (xy 337.679914 -406.295909)
			(xy 337.6803 -406.286716) (xy 337.6803 -405.793448) (xy 337.679867 -405.784263) (xy 337.673369 -405.767079)
			(xy 337.6676 -405.75992) (xy 337.64581 -405.734271) (xy 337.607863 -405.678683) (xy 337.576832 -405.618958)
			(xy 337.553162 -405.555954) (xy 337.53719 -405.490572) (xy 337.529147 -405.423749) (xy 337.529147 -405.356445)
			(xy 337.537191 -405.289622) (xy 337.553163 -405.224241) (xy 337.576835 -405.161236) (xy 337.607866 -405.101512)
			(xy 337.645813 -405.045925) (xy 337.6676 -405.020272) (xy 337.673391 -405.013123) (xy 337.679909 -404.995935)
			(xy 337.6803 -404.986744) (xy 337.6803 -404.828756) (xy 337.680686 -404.818599) (xy 337.688496 -404.799846)
			(xy 337.702903 -404.785524) (xy 337.721703 -404.777826) (xy 337.731862 -404.777448) (xy 338.448142 -404.777448)
			(xy 338.458272 -404.777892) (xy 338.476996 -404.785635) (xy 338.491351 -404.799934) (xy 338.499167 -404.818628)
			(xy 338.499704 -404.828756) (xy 338.499704 -404.986744) (xy 338.500092 -404.995934) (xy 338.506621 -405.013118)
			(xy 338.512404 -405.020272) (xy 338.534186 -405.045928) (xy 338.572133 -405.101515) (xy 338.603164 -405.161238)
			(xy 338.626835 -405.224242) (xy 338.642807 -405.289624) (xy 338.650851 -405.356445) (xy 338.650851 -405.423749)
			(xy 338.642808 -405.490571) (xy 338.626837 -405.555952) (xy 338.603166 -405.618956) (xy 338.600728 -405.623648)
			(xy 339.729282 -405.623648) (xy 339.729282 -405.556343) (xy 339.737327 -405.489519) (xy 339.753301 -405.424137)
			(xy 339.776975 -405.361132) (xy 339.808009 -405.301408) (xy 339.845959 -405.245822) (xy 339.867748 -405.22017)
			(xy 339.873546 -405.213026) (xy 339.880058 -405.195834) (xy 339.880448 -405.186642) (xy 339.880448 -404.693374)
			(xy 339.88004 -404.684187) (xy 339.873523 -404.667003) (xy 339.867748 -404.659846) (xy 339.845982 -404.634176)
			(xy 339.808032 -404.578592) (xy 339.776997 -404.518871) (xy 339.753323 -404.455869) (xy 339.737348 -404.390489)
			(xy 339.729302 -404.323668) (xy 339.7293 -404.256365) (xy 339.737342 -404.189544) (xy 339.753313 -404.124163)
			(xy 339.776984 -404.061159) (xy 339.808015 -404.001436) (xy 339.845962 -403.94585) (xy 339.867748 -403.920198)
			(xy 339.873534 -403.913045) (xy 339.880054 -403.89586) (xy 339.880448 -403.88667) (xy 339.880448 -403.728682)
			(xy 339.880919 -403.718522) (xy 339.888701 -403.69975) (xy 339.903074 -403.685385) (xy 339.92185 -403.677613)
			(xy 339.93201 -403.67712) (xy 340.64829 -403.67712) (xy 340.658445 -403.677641) (xy 340.67721 -403.685409)
			(xy 340.691575 -403.699766) (xy 340.699353 -403.718527) (xy 340.699852 -403.728682) (xy 340.699852 -403.88667)
			(xy 340.700287 -403.895854) (xy 340.706785 -403.913038) (xy 340.712552 -403.920198) (xy 340.734362 -403.945832)
			(xy 340.772311 -404.001421) (xy 340.803343 -404.061147) (xy 340.827015 -404.124154) (xy 340.842987 -404.189538)
			(xy 340.85103 -404.256363) (xy 340.851028 -404.32367) (xy 340.842981 -404.390494) (xy 340.827006 -404.455878)
			(xy 340.80333 -404.518883) (xy 340.772294 -404.578608) (xy 340.734341 -404.634194) (xy 340.712552 -404.659846)
			(xy 340.706747 -404.666985) (xy 340.700239 -404.684181) (xy 340.699852 -404.693374) (xy 340.699852 -405.186642)
			(xy 340.700253 -405.19583) (xy 340.706774 -405.213014) (xy 340.712552 -405.22017) (xy 340.734334 -405.245827)
			(xy 340.772283 -405.301413) (xy 340.803317 -405.361135) (xy 340.826991 -405.424139) (xy 340.842965 -405.489521)
			(xy 340.851009 -405.556343) (xy 340.85101 -405.623648) (xy 340.842966 -405.69047) (xy 340.826994 -405.755852)
			(xy 340.803321 -405.818856) (xy 340.772288 -405.87858) (xy 340.734339 -405.934166) (xy 340.712552 -405.959818)
			(xy 340.706759 -405.966966) (xy 340.700244 -405.984154) (xy 340.699852 -405.993346) (xy 340.699852 -406.151334)
			(xy 340.699394 -406.161495) (xy 340.691607 -406.180267) (xy 340.67723 -406.194631) (xy 340.658452 -406.202403)
			(xy 340.64829 -406.202896) (xy 339.93201 -406.202896) (xy 339.921857 -406.202359) (xy 339.903095 -406.194594)
			(xy 339.88873 -406.180242) (xy 339.880949 -406.161487) (xy 339.880448 -406.151334) (xy 339.880448 -405.993346)
			(xy 339.880005 -405.984163) (xy 339.873513 -405.966979) (xy 339.867748 -405.959818) (xy 339.845954 -405.934171)
			(xy 339.808005 -405.878584) (xy 339.776971 -405.81886) (xy 339.753298 -405.755855) (xy 339.737325 -405.690472)
			(xy 339.729282 -405.623648) (xy 338.600728 -405.623648) (xy 338.572136 -405.67868) (xy 338.53419 -405.734267)
			(xy 338.512404 -405.75992) (xy 338.506617 -405.767072) (xy 338.500096 -405.784257) (xy 338.499704 -405.793448)
			(xy 338.499704 -406.286716) (xy 338.500106 -406.295904) (xy 338.506625 -406.313088) (xy 338.512404 -406.320244)
			(xy 338.534159 -406.345923) (xy 338.572106 -406.401506) (xy 338.603138 -406.461227) (xy 338.626811 -406.524228)
			(xy 338.642785 -406.589606) (xy 338.650831 -406.656425) (xy 338.650834 -406.723727) (xy 338.650827 -406.723789)
			(xy 341.928896 -406.723789) (xy 341.928898 -406.656363) (xy 341.936977 -406.589423) (xy 341.953016 -406.523932)
			(xy 341.976784 -406.460834) (xy 342.007938 -406.401036) (xy 342.04603 -406.345401) (xy 342.067896 -406.319736)
			(xy 342.073702 -406.312597) (xy 342.080211 -406.295402) (xy 342.080596 -406.286208) (xy 342.080596 -405.793956)
			(xy 342.080208 -405.784766) (xy 342.073679 -405.767582) (xy 342.067896 -405.760428) (xy 342.046028 -405.734766)
			(xy 342.00794 -405.679131) (xy 341.97679 -405.619334) (xy 341.953026 -405.556237) (xy 341.936991 -405.490748)
			(xy 341.928915 -405.423809) (xy 341.928916 -405.356385) (xy 341.936992 -405.289447) (xy 341.953028 -405.223957)
			(xy 341.976792 -405.16086) (xy 342.007943 -405.101064) (xy 342.046032 -405.045429) (xy 342.067896 -405.019764)
			(xy 342.07369 -405.012617) (xy 342.080206 -404.995428) (xy 342.080596 -404.986236) (xy 342.080596 -404.828756)
			(xy 342.081049 -404.818645) (xy 342.0888 -404.799967) (xy 342.103107 -404.785673) (xy 342.121793 -404.77794)
			(xy 342.131904 -404.777448) (xy 342.848184 -404.777448) (xy 342.858285 -404.777997) (xy 342.876953 -404.78572)
			(xy 342.891247 -404.799996) (xy 342.898991 -404.818655) (xy 342.899492 -404.828756) (xy 342.899492 -404.986236)
			(xy 342.899886 -404.995425) (xy 342.906411 -405.012609) (xy 342.912192 -405.019764) (xy 342.934052 -405.045432)
			(xy 342.972142 -405.101066) (xy 343.003293 -405.160862) (xy 343.027058 -405.223958) (xy 343.043094 -405.289447)
			(xy 343.05117 -405.356385) (xy 343.05117 -405.423809) (xy 343.043095 -405.490747) (xy 343.02706 -405.556236)
			(xy 343.003295 -405.619333) (xy 343.001047 -405.623648) (xy 344.129073 -405.623648) (xy 344.129073 -405.556343)
			(xy 344.137118 -405.48952) (xy 344.153091 -405.424137) (xy 344.176765 -405.361132) (xy 344.207799 -405.301409)
			(xy 344.245748 -405.245822) (xy 344.267536 -405.22017) (xy 344.273332 -405.213025) (xy 344.279846 -405.195834)
			(xy 344.280236 -405.186642) (xy 344.280236 -404.693374) (xy 344.27983 -404.684187) (xy 344.273313 -404.667003)
			(xy 344.267536 -404.659846) (xy 344.24577 -404.634176) (xy 344.207821 -404.578592) (xy 344.176787 -404.518871)
			(xy 344.153113 -404.455869) (xy 344.137139 -404.390489) (xy 344.129093 -404.323668) (xy 344.129091 -404.256365)
			(xy 344.137133 -404.189544) (xy 344.153103 -404.124163) (xy 344.176773 -404.061159) (xy 344.207804 -404.001437)
			(xy 344.24575 -403.94585) (xy 344.267536 -403.920198) (xy 344.273321 -403.913044) (xy 344.279842 -403.89586)
			(xy 344.280236 -403.88667) (xy 344.280236 -403.728682) (xy 344.280718 -403.718523) (xy 344.288498 -403.699754)
			(xy 344.302867 -403.685389) (xy 344.321639 -403.677615) (xy 344.331798 -403.67712) (xy 345.048078 -403.67712)
			(xy 345.058246 -403.677582) (xy 345.077037 -403.685356) (xy 345.091422 -403.69973) (xy 345.09921 -403.718514)
			(xy 345.09964 -403.728682) (xy 345.09964 -403.88667) (xy 345.100078 -403.895854) (xy 345.106574 -403.913038)
			(xy 345.11234 -403.920198) (xy 345.13415 -403.945832) (xy 345.1721 -404.00142) (xy 345.203133 -404.061146)
			(xy 345.226806 -404.124153) (xy 345.242778 -404.189538) (xy 345.250821 -404.256363) (xy 345.250819 -404.32367)
			(xy 345.242772 -404.390495) (xy 345.226796 -404.455878) (xy 345.20312 -404.518884) (xy 345.172083 -404.578608)
			(xy 345.13413 -404.634194) (xy 345.11234 -404.659846) (xy 345.106534 -404.666984) (xy 345.100027 -404.68418)
			(xy 345.09964 -404.693374) (xy 345.09964 -405.186642) (xy 345.100043 -405.19583) (xy 345.106563 -405.213013)
			(xy 345.11234 -405.22017) (xy 345.134122 -405.245827) (xy 345.172073 -405.301412) (xy 345.203107 -405.361135)
			(xy 345.226781 -405.424139) (xy 345.242755 -405.489521) (xy 345.2508 -405.556343) (xy 345.250801 -405.623648)
			(xy 345.242757 -405.69047) (xy 345.226784 -405.755853) (xy 345.203111 -405.818857) (xy 345.172077 -405.87858)
			(xy 345.134128 -405.934166) (xy 345.11234 -405.959818) (xy 345.106546 -405.966965) (xy 345.100031 -405.984154)
			(xy 345.09964 -405.993346) (xy 345.09964 -406.151334) (xy 345.099194 -406.161497) (xy 345.091404 -406.180271)
			(xy 345.077024 -406.194636) (xy 345.058241 -406.202405) (xy 345.048078 -406.202896) (xy 344.331798 -406.202896)
			(xy 344.321644 -406.202369) (xy 344.302882 -406.1946) (xy 344.288518 -406.180245) (xy 344.280737 -406.161487)
			(xy 344.280236 -406.151334) (xy 344.280236 -405.993346) (xy 344.279795 -405.984162) (xy 344.273302 -405.966978)
			(xy 344.267536 -405.959818) (xy 344.245742 -405.934171) (xy 344.207794 -405.878584) (xy 344.176761 -405.818859)
			(xy 344.153089 -405.755854) (xy 344.137116 -405.690471) (xy 344.129073 -405.623648) (xy 343.001047 -405.623648)
			(xy 342.972145 -405.679129) (xy 342.934056 -405.734763) (xy 342.912192 -405.760428) (xy 342.9064 -405.767576)
			(xy 342.899883 -405.784765) (xy 342.899492 -405.793956) (xy 342.899492 -406.286208) (xy 342.8999 -406.295395)
			(xy 342.906416 -406.312579) (xy 342.912192 -406.319736) (xy 342.934025 -406.345427) (xy 342.972115 -406.401058)
			(xy 343.003268 -406.46085) (xy 343.027034 -406.523944) (xy 343.043072 -406.58943) (xy 343.05115 -406.656365)
			(xy 343.051153 -406.72373) (xy 346.329191 -406.72373) (xy 346.329194 -406.656422) (xy 346.337242 -406.589596)
			(xy 346.35322 -406.524212) (xy 346.376898 -406.461206) (xy 346.407937 -406.401482) (xy 346.445893 -406.345896)
			(xy 346.467684 -406.320244) (xy 346.473485 -406.313102) (xy 346.479998 -406.295909) (xy 346.480384 -406.286716)
			(xy 346.480384 -405.793448) (xy 346.479955 -405.784263) (xy 346.473455 -405.767078) (xy 346.467684 -405.75992)
			(xy 346.445891 -405.734272) (xy 346.407939 -405.678686) (xy 346.376904 -405.618962) (xy 346.353229 -405.555957)
			(xy 346.337255 -405.490574) (xy 346.329211 -405.42375) (xy 346.329211 -405.356444) (xy 346.337256 -405.28962)
			(xy 346.353231 -405.224237) (xy 346.376906 -405.161232) (xy 346.407942 -405.101509) (xy 346.445895 -405.045924)
			(xy 346.467684 -405.020272) (xy 346.473473 -405.013121) (xy 346.479993 -404.995935) (xy 346.480384 -404.986744)
			(xy 346.480384 -404.828756) (xy 346.480785 -404.818601) (xy 346.488592 -404.799851) (xy 346.502995 -404.78553)
			(xy 346.521789 -404.777829) (xy 346.531946 -404.777448) (xy 347.248226 -404.777448) (xy 347.258355 -404.777905)
			(xy 347.277079 -404.785643) (xy 347.291434 -404.799938) (xy 347.299251 -404.818629) (xy 347.299788 -404.828756)
			(xy 347.299788 -404.986744) (xy 347.30018 -404.995933) (xy 347.306706 -405.013117) (xy 347.312488 -405.020272)
			(xy 347.334271 -405.045928) (xy 347.372218 -405.101514) (xy 347.40325 -405.161238) (xy 347.426922 -405.224242)
			(xy 347.442894 -405.289623) (xy 347.450938 -405.356445) (xy 347.450939 -405.423749) (xy 347.442895 -405.490571)
			(xy 347.426924 -405.555953) (xy 347.403253 -405.618957) (xy 347.400815 -405.623649) (xy 374.929103 -405.623649)
			(xy 374.929104 -405.556342) (xy 374.937149 -405.489519) (xy 374.953124 -405.424136) (xy 374.976799 -405.361131)
			(xy 375.007835 -405.301407) (xy 375.045787 -405.245822) (xy 375.067576 -405.22017) (xy 375.073365 -405.213019)
			(xy 375.079885 -405.195833) (xy 375.080276 -405.186642) (xy 375.080276 -404.693374) (xy 375.079884 -404.684185)
			(xy 375.073358 -404.667) (xy 375.067576 -404.659846) (xy 375.045809 -404.634177) (xy 375.007857 -404.578593)
			(xy 374.976821 -404.518873) (xy 374.953145 -404.45587) (xy 374.937169 -404.39049) (xy 374.929123 -404.323669)
			(xy 374.929121 -404.256365) (xy 374.937164 -404.189543) (xy 374.953135 -404.124161) (xy 374.976807 -404.061158)
			(xy 375.00784 -404.001435) (xy 375.045789 -403.94585) (xy 375.067576 -403.920198) (xy 375.073353 -403.913039)
			(xy 375.07988 -403.895859) (xy 375.080276 -403.88667) (xy 375.080276 -403.728682) (xy 375.08065 -403.718505)
			(xy 375.088448 -403.699702) (xy 375.102849 -403.685317) (xy 375.12166 -403.677539) (xy 375.131838 -403.67712)
			(xy 375.848118 -403.67712) (xy 375.858275 -403.677618) (xy 375.877041 -403.685395) (xy 375.891405 -403.699759)
			(xy 375.899182 -403.718525) (xy 375.89968 -403.728682) (xy 375.89968 -403.88667) (xy 375.900109 -403.895855)
			(xy 375.90661 -403.913039) (xy 375.91238 -403.920198) (xy 375.934189 -403.945833) (xy 375.972136 -404.001422)
			(xy 376.003167 -404.061148) (xy 376.026838 -404.124155) (xy 376.042809 -404.189539) (xy 376.050851 -404.256363)
			(xy 376.050849 -404.32367) (xy 376.042803 -404.390494) (xy 376.026828 -404.455877) (xy 376.003154 -404.518882)
			(xy 375.972119 -404.578606) (xy 375.934169 -404.634194) (xy 375.91238 -404.659846) (xy 375.906579 -404.666988)
			(xy 375.900068 -404.684181) (xy 375.89968 -404.693374) (xy 375.89968 -405.186642) (xy 375.900074 -405.195831)
			(xy 375.9066 -405.213015) (xy 375.91238 -405.22017) (xy 375.934161 -405.245827) (xy 375.972109 -405.301413)
			(xy 376.003142 -405.361136) (xy 376.026814 -405.42414) (xy 376.042787 -405.489522) (xy 376.050831 -405.556343)
			(xy 376.050832 -405.623648) (xy 376.042788 -405.690469) (xy 376.026817 -405.755851) (xy 376.003145 -405.818855)
			(xy 375.972114 -405.878579) (xy 375.934167 -405.934166) (xy 375.91238 -405.959818) (xy 375.906591 -405.966968)
			(xy 375.900072 -405.984155) (xy 375.89968 -405.993346) (xy 375.89968 -406.151334) (xy 375.899195 -406.161492)
			(xy 375.891413 -406.180258) (xy 375.877045 -406.194622) (xy 375.858276 -406.202398) (xy 375.848118 -406.202896)
			(xy 375.131838 -406.202896) (xy 375.121673 -406.202406) (xy 375.102886 -406.19464) (xy 375.088501 -406.180275)
			(xy 375.080708 -406.161498) (xy 375.080276 -406.151334) (xy 375.080276 -405.993346) (xy 375.079849 -405.984161)
			(xy 375.073347 -405.966976) (xy 375.067576 -405.959818) (xy 375.045781 -405.934171) (xy 375.00783 -405.878585)
			(xy 374.976795 -405.818861) (xy 374.953121 -405.755856) (xy 374.937148 -405.690472) (xy 374.929103 -405.623649)
			(xy 347.400815 -405.623649) (xy 347.372221 -405.678681) (xy 347.334275 -405.734268) (xy 347.312488 -405.75992)
			(xy 347.306699 -405.767071) (xy 347.30018 -405.784257) (xy 347.299788 -405.793448) (xy 347.299788 -406.286716)
			(xy 347.300193 -406.295904) (xy 347.30671 -406.313088) (xy 347.312488 -406.320244) (xy 347.334244 -406.345922)
			(xy 347.372192 -406.401506) (xy 347.403225 -406.461226) (xy 347.426898 -406.524227) (xy 347.442873 -406.589606)
			(xy 347.450919 -406.656425) (xy 347.450922 -406.723727) (xy 347.450915 -406.723789) (xy 377.128717 -406.723789)
			(xy 377.12872 -406.656363) (xy 377.136799 -406.589422) (xy 377.152839 -406.523931) (xy 377.176607 -406.460832)
			(xy 377.207763 -406.401035) (xy 377.245857 -406.345401) (xy 377.267724 -406.319736) (xy 377.273533 -406.3126)
			(xy 377.280039 -406.295402) (xy 377.280424 -406.286208) (xy 377.280424 -405.793956) (xy 377.28003 -405.784767)
			(xy 377.273504 -405.767583) (xy 377.267724 -405.760428) (xy 377.245855 -405.734766) (xy 377.207765 -405.679132)
			(xy 377.176613 -405.619335) (xy 377.152848 -405.556238) (xy 377.136812 -405.490748) (xy 377.128736 -405.423809)
			(xy 377.128737 -405.356385) (xy 377.136813 -405.289446) (xy 377.15285 -405.223956) (xy 377.176616 -405.160859)
			(xy 377.207768 -405.101063) (xy 377.245859 -405.045429) (xy 377.267724 -405.019764) (xy 377.273521 -405.012619)
			(xy 377.280035 -404.995428) (xy 377.280424 -404.986236) (xy 377.280424 -404.828756) (xy 377.28085 -404.818641)
			(xy 377.288606 -404.799958) (xy 377.302922 -404.785664) (xy 377.321617 -404.777935) (xy 377.331732 -404.777448)
			(xy 378.048012 -404.777448) (xy 378.058115 -404.777974) (xy 378.076783 -404.785706) (xy 378.091076 -404.79999)
			(xy 378.098819 -404.818653) (xy 378.09932 -404.828756) (xy 378.09932 -404.986236) (xy 378.099709 -404.995426)
			(xy 378.106237 -405.01261) (xy 378.11202 -405.019764) (xy 378.133879 -405.045433) (xy 378.171967 -405.101067)
			(xy 378.203117 -405.160863) (xy 378.22688 -405.22396) (xy 378.242915 -405.289448) (xy 378.250991 -405.356386)
			(xy 378.250992 -405.423808) (xy 378.242916 -405.490746) (xy 378.226882 -405.556235) (xy 378.203119 -405.619331)
			(xy 378.200839 -405.623707) (xy 379.328896 -405.623707) (xy 379.328896 -405.556284) (xy 379.336972 -405.489346)
			(xy 379.353008 -405.423856) (xy 379.376771 -405.360759) (xy 379.407921 -405.300963) (xy 379.446009 -405.245328)
			(xy 379.467872 -405.219662) (xy 379.473676 -405.212522) (xy 379.480184 -405.195327) (xy 379.480572 -405.186134)
			(xy 379.480572 -404.693882) (xy 379.480177 -404.684693) (xy 379.473653 -404.667509) (xy 379.467872 -404.660354)
			(xy 379.446031 -404.63467) (xy 379.407943 -404.579038) (xy 379.376793 -404.519244) (xy 379.353029 -404.45615)
			(xy 379.336993 -404.390663) (xy 379.328915 -404.323727) (xy 379.328913 -404.256306) (xy 379.336987 -404.18937)
			(xy 379.353019 -404.123882) (xy 379.376779 -404.060786) (xy 379.407926 -404.00099) (xy 379.44601 -403.945356)
			(xy 379.467872 -403.91969) (xy 379.473664 -403.912542) (xy 379.480179 -403.895353) (xy 379.480572 -403.886162)
			(xy 379.480572 -403.728682) (xy 379.481013 -403.71855) (xy 379.488752 -403.699822) (xy 379.503053 -403.685466)
			(xy 379.52175 -403.677653) (xy 379.53188 -403.67712) (xy 380.24816 -403.67712) (xy 380.258282 -403.677549)
			(xy 380.276989 -403.685288) (xy 380.291305 -403.699601) (xy 380.299048 -403.718306) (xy 380.299468 -403.728428)
			(xy 380.299468 -403.886162) (xy 380.299904 -403.895346) (xy 380.306401 -403.91253) (xy 380.312168 -403.91969)
			(xy 380.334055 -403.945337) (xy 380.372145 -404.000973) (xy 380.403296 -404.060772) (xy 380.427061 -404.123871)
			(xy 380.443096 -404.189363) (xy 380.45117 -404.256303) (xy 380.451168 -404.32373) (xy 380.44309 -404.39067)
			(xy 380.427051 -404.456161) (xy 380.403283 -404.519259) (xy 380.372128 -404.579055) (xy 380.334034 -404.634689)
			(xy 380.312168 -404.660354) (xy 380.306362 -404.667492) (xy 380.299854 -404.684688) (xy 380.299468 -404.693882)
			(xy 380.299468 -405.186134) (xy 380.299869 -405.195322) (xy 380.30639 -405.212506) (xy 380.312168 -405.219662)
			(xy 380.334027 -405.245332) (xy 380.372118 -405.300965) (xy 380.403271 -405.36076) (xy 380.427037 -405.423856)
			(xy 380.443074 -405.489345) (xy 380.451151 -405.556284) (xy 380.451151 -405.623707) (xy 380.443075 -405.690646)
			(xy 380.42704 -405.756135) (xy 380.403275 -405.819232) (xy 380.372123 -405.879028) (xy 380.334033 -405.934661)
			(xy 380.312168 -405.960326) (xy 380.306374 -405.967473) (xy 380.299858 -405.984662) (xy 380.299468 -405.993854)
			(xy 380.299468 -406.151334) (xy 380.299002 -406.161462) (xy 380.291264 -406.180182) (xy 380.276972 -406.194537)
			(xy 380.258286 -406.202357) (xy 380.24816 -406.202896) (xy 379.53188 -406.202896) (xy 379.521769 -406.202431)
			(xy 379.50309 -406.194686) (xy 379.488796 -406.180383) (xy 379.481062 -406.161699) (xy 379.480572 -406.151588)
			(xy 379.480572 -405.993854) (xy 379.480142 -405.984669) (xy 379.473643 -405.967484) (xy 379.467872 -405.960326)
			(xy 379.446003 -405.934665) (xy 379.407916 -405.879029) (xy 379.376768 -405.819232) (xy 379.353005 -405.756135)
			(xy 379.336971 -405.690646) (xy 379.328896 -405.623707) (xy 378.200839 -405.623707) (xy 378.17197 -405.679128)
			(xy 378.133883 -405.734762) (xy 378.11202 -405.760428) (xy 378.106231 -405.767579) (xy 378.099711 -405.784765)
			(xy 378.09932 -405.793956) (xy 378.09932 -406.286208) (xy 378.099722 -406.295396) (xy 378.106241 -406.312581)
			(xy 378.11202 -406.319736) (xy 378.133852 -406.345428) (xy 378.17194 -406.401059) (xy 378.203091 -406.460852)
			(xy 378.226856 -406.523945) (xy 378.242893 -406.589431) (xy 378.250971 -406.656366) (xy 378.250974 -406.723729)
			(xy 381.529036 -406.723729) (xy 381.529039 -406.656422) (xy 381.537086 -406.589598) (xy 381.553062 -406.524214)
			(xy 381.576737 -406.461209) (xy 381.607772 -406.401484) (xy 381.645723 -406.345897) (xy 381.667512 -406.320244)
			(xy 381.673316 -406.313104) (xy 381.679826 -406.29591) (xy 381.680212 -406.286716) (xy 381.680212 -405.793448)
			(xy 381.679776 -405.784264) (xy 381.67328 -405.767079) (xy 381.667512 -405.75992) (xy 381.645721 -405.734271)
			(xy 381.607774 -405.678683) (xy 381.576743 -405.618959) (xy 381.553071 -405.555954) (xy 381.537099 -405.490572)
			(xy 381.529056 -405.423749) (xy 381.529056 -405.356445) (xy 381.5371 -405.289622) (xy 381.553073 -405.22424)
			(xy 381.576745 -405.161235) (xy 381.607777 -405.101512) (xy 381.645725 -405.045924) (xy 381.667512 -405.020272)
			(xy 381.673304 -405.013124) (xy 381.679821 -404.995936) (xy 381.680212 -404.986744) (xy 381.680212 -404.828756)
			(xy 381.680649 -404.818643) (xy 381.688404 -404.799961) (xy 381.702715 -404.785668) (xy 381.721406 -404.777937)
			(xy 381.73152 -404.777448) (xy 382.448054 -404.777448) (xy 382.458179 -404.777965) (xy 382.4769 -404.785679)
			(xy 382.491258 -404.799956) (xy 382.499078 -404.818634) (xy 382.499616 -404.828756) (xy 382.499616 -404.986744)
			(xy 382.500001 -404.995934) (xy 382.506532 -405.013118) (xy 382.512316 -405.020272) (xy 382.534101 -405.045927)
			(xy 382.572053 -405.101512) (xy 382.603089 -405.161235) (xy 382.626764 -405.224239) (xy 382.642738 -405.289621)
			(xy 382.650784 -405.356444) (xy 382.650784 -405.42375) (xy 382.64274 -405.490573) (xy 382.626766 -405.555955)
			(xy 382.603091 -405.61896) (xy 382.600655 -405.623648) (xy 383.729191 -405.623648) (xy 383.729192 -405.556343)
			(xy 383.737237 -405.489519) (xy 383.753211 -405.424136) (xy 383.776885 -405.361132) (xy 383.807921 -405.301408)
			(xy 383.845871 -405.245822) (xy 383.86766 -405.22017) (xy 383.873459 -405.213027) (xy 383.879971 -405.195835)
			(xy 383.88036 -405.186642) (xy 383.88036 -404.693374) (xy 383.879949 -404.684187) (xy 383.873434 -404.667004)
			(xy 383.86766 -404.659846) (xy 383.845893 -404.634176) (xy 383.807943 -404.578593) (xy 383.776907 -404.518872)
			(xy 383.753232 -404.45587) (xy 383.737257 -404.390489) (xy 383.729211 -404.323668) (xy 383.729209 -404.256365)
			(xy 383.737251 -404.189543) (xy 383.753222 -404.124162) (xy 383.776894 -404.061158) (xy 383.807926 -404.001436)
			(xy 383.845873 -403.94585) (xy 383.86766 -403.920198) (xy 383.873447 -403.913047) (xy 383.879966 -403.895861)
			(xy 383.88036 -403.88667) (xy 383.88036 -403.728682) (xy 383.88075 -403.718507) (xy 383.888545 -403.699707)
			(xy 383.902941 -403.685322) (xy 383.921746 -403.677542) (xy 383.931922 -403.67712) (xy 384.648202 -403.67712)
			(xy 384.658358 -403.677631) (xy 384.677123 -403.685403) (xy 384.691488 -403.699763) (xy 384.699265 -403.718526)
			(xy 384.699764 -403.728682) (xy 384.699764 -403.88667) (xy 384.700197 -403.895855) (xy 384.706696 -403.913039)
			(xy 384.712464 -403.920198) (xy 384.734273 -403.945832) (xy 384.772221 -404.001421) (xy 384.803254 -404.061147)
			(xy 384.826925 -404.124154) (xy 384.842896 -404.189539) (xy 384.850939 -404.256363) (xy 384.850937 -404.32367)
			(xy 384.84289 -404.390494) (xy 384.826915 -404.455877) (xy 384.80324 -404.518883) (xy 384.772204 -404.578607)
			(xy 384.734253 -404.634194) (xy 384.712464 -404.659846) (xy 384.706661 -404.666986) (xy 384.700151 -404.684181)
			(xy 384.699764 -404.693374) (xy 384.699764 -405.186642) (xy 384.700162 -405.19583) (xy 384.706685 -405.213014)
			(xy 384.712464 -405.22017) (xy 384.734246 -405.245827) (xy 384.772195 -405.301413) (xy 384.803228 -405.361136)
			(xy 384.826901 -405.42414) (xy 384.842874 -405.489521) (xy 384.850919 -405.556343) (xy 384.850919 -405.623648)
			(xy 384.842876 -405.69047) (xy 384.826904 -405.755852) (xy 384.803232 -405.818856) (xy 384.772199 -405.878579)
			(xy 384.734251 -405.934166) (xy 384.712464 -405.959818) (xy 384.706673 -405.966967) (xy 384.700156 -405.984155)
			(xy 384.699764 -405.993346) (xy 384.699764 -406.151334) (xy 384.699295 -406.161494) (xy 384.691509 -406.180263)
			(xy 384.677136 -406.194627) (xy 384.658362 -406.202401) (xy 384.648202 -406.202896) (xy 383.931922 -406.202896)
			(xy 383.92177 -406.20235) (xy 383.903008 -406.194589) (xy 383.888643 -406.180239) (xy 383.880861 -406.161486)
			(xy 383.88036 -406.151334) (xy 383.88036 -405.993346) (xy 383.879914 -405.984163) (xy 383.873424 -405.966979)
			(xy 383.86766 -405.959818) (xy 383.845866 -405.934171) (xy 383.807916 -405.878584) (xy 383.776882 -405.81886)
			(xy 383.753208 -405.755855) (xy 383.737235 -405.690472) (xy 383.729191 -405.623648) (xy 382.600655 -405.623648)
			(xy 382.572056 -405.678683) (xy 382.534105 -405.734268) (xy 382.512316 -405.75992) (xy 382.50653 -405.767073)
			(xy 382.500009 -405.784257) (xy 382.499616 -405.793448) (xy 382.499616 -406.286716) (xy 382.500015 -406.295904)
			(xy 382.506536 -406.313089) (xy 382.512316 -406.320244) (xy 382.534074 -406.345921) (xy 382.572026 -406.401503)
			(xy 382.603063 -406.461223) (xy 382.62674 -406.524224) (xy 382.642717 -406.589604) (xy 382.650764 -406.656424)
			(xy 382.650767 -406.723728) (xy 382.65076 -406.723789) (xy 385.928805 -406.723789) (xy 385.928807 -406.656363)
			(xy 385.936887 -406.589422) (xy 385.952926 -406.523931) (xy 385.976694 -406.460833) (xy 386.007849 -406.401036)
			(xy 386.045942 -406.345401) (xy 386.067808 -406.319736) (xy 386.073615 -406.312598) (xy 386.080123 -406.295402)
			(xy 386.080508 -406.286208) (xy 386.080508 -405.793956) (xy 386.080117 -405.784767) (xy 386.07359 -405.767583)
			(xy 386.067808 -405.760428) (xy 386.04594 -405.734766) (xy 386.007851 -405.679131) (xy 385.9767 -405.619335)
			(xy 385.952935 -405.556237) (xy 385.9369 -405.490748) (xy 385.928824 -405.423809) (xy 385.928825 -405.356385)
			(xy 385.936901 -405.289446) (xy 385.952937 -405.223957) (xy 385.976702 -405.16086) (xy 386.007854 -405.101064)
			(xy 386.045944 -405.045429) (xy 386.067808 -405.019764) (xy 386.073603 -405.012618) (xy 386.080118 -404.995428)
			(xy 386.080508 -404.986236) (xy 386.080508 -404.828756) (xy 386.080949 -404.818643) (xy 386.088703 -404.799963)
			(xy 386.103013 -404.785669) (xy 386.121703 -404.777938) (xy 386.131816 -404.777448) (xy 386.848096 -404.777448)
			(xy 386.858198 -404.777987) (xy 386.876866 -404.785714) (xy 386.891159 -404.799993) (xy 386.898903 -404.818654)
			(xy 386.899404 -404.828756) (xy 386.899404 -404.986236) (xy 386.899796 -404.995425) (xy 386.906322 -405.012609)
			(xy 386.912104 -405.019764) (xy 386.933964 -405.045433) (xy 386.972052 -405.101067) (xy 387.003203 -405.160862)
			(xy 387.026967 -405.223959) (xy 387.043003 -405.289448) (xy 387.051079 -405.356385) (xy 387.051079 -405.423809)
			(xy 387.043004 -405.490747) (xy 387.026969 -405.556235) (xy 387.003206 -405.619332) (xy 387.000958 -405.623648)
			(xy 388.128982 -405.623648) (xy 388.128982 -405.556343) (xy 388.137027 -405.489519) (xy 388.153001 -405.424137)
			(xy 388.176675 -405.361132) (xy 388.207709 -405.301408) (xy 388.245659 -405.245822) (xy 388.267448 -405.22017)
			(xy 388.273246 -405.213026) (xy 388.279758 -405.195834) (xy 388.280148 -405.186642) (xy 388.280148 -404.693374)
			(xy 388.27974 -404.684187) (xy 388.273223 -404.667003) (xy 388.267448 -404.659846) (xy 388.245682 -404.634176)
			(xy 388.207732 -404.578592) (xy 388.176697 -404.518871) (xy 388.153023 -404.455869) (xy 388.137048 -404.390489)
			(xy 388.129002 -404.323668) (xy 388.129 -404.256365) (xy 388.137042 -404.189544) (xy 388.153013 -404.124163)
			(xy 388.176684 -404.061159) (xy 388.207715 -404.001436) (xy 388.245662 -403.94585) (xy 388.267448 -403.920198)
			(xy 388.273234 -403.913045) (xy 388.279754 -403.89586) (xy 388.280148 -403.88667) (xy 388.280148 -403.728682)
			(xy 388.280619 -403.718522) (xy 388.288401 -403.69975) (xy 388.302774 -403.685385) (xy 388.32155 -403.677613)
			(xy 388.33171 -403.67712) (xy 389.04799 -403.67712) (xy 389.058145 -403.677641) (xy 389.07691 -403.685409)
			(xy 389.091275 -403.699766) (xy 389.099053 -403.718527) (xy 389.099552 -403.728682) (xy 389.099552 -403.88667)
			(xy 389.099987 -403.895854) (xy 389.106485 -403.913038) (xy 389.112252 -403.920198) (xy 389.134062 -403.945832)
			(xy 389.172011 -404.001421) (xy 389.203043 -404.061147) (xy 389.226715 -404.124154) (xy 389.242687 -404.189538)
			(xy 389.25073 -404.256363) (xy 389.250728 -404.32367) (xy 389.242681 -404.390494) (xy 389.226706 -404.455878)
			(xy 389.20303 -404.518883) (xy 389.171994 -404.578608) (xy 389.134041 -404.634194) (xy 389.112252 -404.659846)
			(xy 389.106447 -404.666985) (xy 389.099939 -404.684181) (xy 389.099552 -404.693374) (xy 389.099552 -405.186642)
			(xy 389.099953 -405.19583) (xy 389.106474 -405.213014) (xy 389.112252 -405.22017) (xy 389.134034 -405.245827)
			(xy 389.171983 -405.301413) (xy 389.203017 -405.361135) (xy 389.226691 -405.424139) (xy 389.242665 -405.489521)
			(xy 389.250709 -405.556343) (xy 389.25071 -405.623648) (xy 389.242666 -405.69047) (xy 389.226694 -405.755852)
			(xy 389.203021 -405.818856) (xy 389.171988 -405.87858) (xy 389.134039 -405.934166) (xy 389.112252 -405.959818)
			(xy 389.106459 -405.966966) (xy 389.099944 -405.984154) (xy 389.099552 -405.993346) (xy 389.099552 -406.151334)
			(xy 389.099094 -406.161495) (xy 389.091307 -406.180267) (xy 389.07693 -406.194631) (xy 389.058152 -406.202403)
			(xy 389.04799 -406.202896) (xy 388.33171 -406.202896) (xy 388.321557 -406.202359) (xy 388.302795 -406.194594)
			(xy 388.28843 -406.180242) (xy 388.280649 -406.161487) (xy 388.280148 -406.151334) (xy 388.280148 -405.993346)
			(xy 388.279705 -405.984163) (xy 388.273213 -405.966979) (xy 388.267448 -405.959818) (xy 388.245654 -405.934171)
			(xy 388.207705 -405.878584) (xy 388.176671 -405.81886) (xy 388.152998 -405.755855) (xy 388.137025 -405.690472)
			(xy 388.128982 -405.623648) (xy 387.000958 -405.623648) (xy 386.972056 -405.679128) (xy 386.933968 -405.734763)
			(xy 386.912104 -405.760428) (xy 386.906314 -405.767578) (xy 386.899795 -405.784765) (xy 386.899404 -405.793956)
			(xy 386.899404 -406.286208) (xy 386.89981 -406.295396) (xy 386.906326 -406.31258) (xy 386.912104 -406.319736)
			(xy 386.933936 -406.345427) (xy 386.972026 -406.401058) (xy 387.003178 -406.460851) (xy 387.026943 -406.523944)
			(xy 387.042981 -406.58943) (xy 387.051059 -406.656365) (xy 387.051062 -406.723729) (xy 390.329124 -406.723729)
			(xy 390.329127 -406.656423) (xy 390.337174 -406.589599) (xy 390.353149 -406.524215) (xy 390.376823 -406.461209)
			(xy 390.407858 -406.401485) (xy 390.445808 -406.345897) (xy 390.467596 -406.320244) (xy 390.473398 -406.313103)
			(xy 390.47991 -406.295909) (xy 390.480296 -406.286716) (xy 390.480296 -405.793448) (xy 390.479864 -405.784263)
			(xy 390.473366 -405.767078) (xy 390.467596 -405.75992) (xy 390.445806 -405.73427) (xy 390.40786 -405.678683)
			(xy 390.376829 -405.618958) (xy 390.353158 -405.555954) (xy 390.337187 -405.490571) (xy 390.329144 -405.423749)
			(xy 390.329144 -405.356445) (xy 390.337188 -405.289623) (xy 390.35316 -405.224241) (xy 390.376832 -405.161236)
			(xy 390.407863 -405.101512) (xy 390.445809 -405.045925) (xy 390.467596 -405.020272) (xy 390.473386 -405.013122)
			(xy 390.479905 -404.995935) (xy 390.480296 -404.986744) (xy 390.480296 -404.828756) (xy 390.480749 -404.818645)
			(xy 390.4885 -404.799967) (xy 390.502807 -404.785673) (xy 390.521493 -404.77794) (xy 390.531604 -404.777448)
			(xy 391.248138 -404.777448) (xy 391.258268 -404.777896) (xy 391.276992 -404.785637) (xy 391.291347 -404.799935)
			(xy 391.299163 -404.818628) (xy 391.2997 -404.828756) (xy 391.2997 -404.986744) (xy 391.300089 -404.995933)
			(xy 391.306617 -405.013118) (xy 391.3124 -405.020272) (xy 391.334183 -405.045928) (xy 391.372129 -405.101515)
			(xy 391.40316 -405.161238) (xy 391.426832 -405.224242) (xy 391.442804 -405.289623) (xy 391.450848 -405.356445)
			(xy 391.450848 -405.423749) (xy 391.442805 -405.490571) (xy 391.426833 -405.555952) (xy 391.403163 -405.618956)
			(xy 391.372132 -405.67868) (xy 391.334186 -405.734267) (xy 391.3124 -405.75992) (xy 391.306612 -405.767072)
			(xy 391.300092 -405.784257) (xy 391.2997 -405.793448) (xy 391.2997 -406.286716) (xy 391.300103 -406.295904)
			(xy 391.306622 -406.313088) (xy 391.3124 -406.320244) (xy 391.334155 -406.345923) (xy 391.372102 -406.401506)
			(xy 391.403135 -406.461226) (xy 391.426808 -406.524227) (xy 391.442782 -406.589606) (xy 391.450828 -406.656425)
			(xy 391.450831 -406.723727) (xy 391.44279 -406.790547) (xy 391.426822 -406.855927) (xy 391.403154 -406.91893)
			(xy 391.372127 -406.978653) (xy 391.334185 -407.034239) (xy 391.3124 -407.059892) (xy 391.306624 -407.067052)
			(xy 391.300097 -407.084231) (xy 391.2997 -407.09342) (xy 391.2997 -407.251408) (xy 391.299221 -407.261517)
			(xy 391.291481 -407.280196) (xy 391.277182 -407.29449) (xy 391.258501 -407.302224) (xy 391.248392 -407.302716)
			(xy 390.531858 -407.302716) (xy 390.521723 -407.302307) (xy 390.502993 -407.294557) (xy 390.488636 -407.280247)
			(xy 390.480826 -407.261541) (xy 390.480296 -407.251408) (xy 390.480296 -407.09342) (xy 390.479877 -407.084234)
			(xy 390.47337 -407.067049) (xy 390.467596 -407.059892) (xy 390.445778 -407.034265) (xy 390.407833 -406.978674)
			(xy 390.376804 -406.918947) (xy 390.353135 -406.855939) (xy 390.337165 -406.790554) (xy 390.329124 -406.723729)
			(xy 387.051062 -406.723729) (xy 387.051062 -406.723787) (xy 387.04299 -406.790723) (xy 387.026958 -406.85621)
			(xy 387.003197 -406.919305) (xy 386.972051 -406.979101) (xy 386.933966 -407.034735) (xy 386.912104 -407.0604)
			(xy 386.906325 -407.067558) (xy 386.8998 -407.084739) (xy 386.899404 -407.093928) (xy 386.899404 -407.251408)
			(xy 386.898921 -407.261517) (xy 386.891182 -407.280194) (xy 386.876884 -407.294489) (xy 386.858205 -407.302224)
			(xy 386.848096 -407.302716) (xy 386.131816 -407.302716) (xy 386.121697 -407.302271) (xy 386.102996 -407.294531)
			(xy 386.088682 -407.280224) (xy 386.080933 -407.261527) (xy 386.080508 -407.251408) (xy 386.080508 -407.093928)
			(xy 386.080083 -407.084742) (xy 386.073579 -407.067558) (xy 386.067808 -407.0604) (xy 386.045912 -407.034761)
			(xy 386.007824 -406.979123) (xy 385.976674 -406.919323) (xy 385.952912 -406.856223) (xy 385.936878 -406.79073)
			(xy 385.928805 -406.723789) (xy 382.65076 -406.723789) (xy 382.642725 -406.790549) (xy 382.626754 -406.85593)
			(xy 382.603083 -406.918933) (xy 382.572051 -406.978655) (xy 382.534103 -407.03424) (xy 382.512316 -407.059892)
			(xy 382.506542 -407.067053) (xy 382.500013 -407.084231) (xy 382.499616 -407.09342) (xy 382.499616 -407.251408)
			(xy 382.499122 -407.261515) (xy 382.491384 -407.28019) (xy 382.47709 -407.294484) (xy 382.458415 -407.302222)
			(xy 382.448308 -407.302716) (xy 381.731774 -407.302716) (xy 381.72164 -407.302294) (xy 381.70291 -407.294549)
			(xy 381.688553 -407.280243) (xy 381.680743 -407.26154) (xy 381.680212 -407.251408) (xy 381.680212 -407.09342)
			(xy 381.679789 -407.084234) (xy 381.673284 -407.06705) (xy 381.667512 -407.059892) (xy 381.645694 -407.034265)
			(xy 381.607748 -406.978675) (xy 381.576717 -406.918947) (xy 381.553047 -406.855939) (xy 381.537077 -406.790554)
			(xy 381.529036 -406.723729) (xy 378.250974 -406.723729) (xy 378.250974 -406.723786) (xy 378.242902 -406.790722)
			(xy 378.226871 -406.856209) (xy 378.203111 -406.919305) (xy 378.171965 -406.9791) (xy 378.133881 -407.034734)
			(xy 378.11202 -407.0604) (xy 378.106243 -407.067559) (xy 378.099716 -407.084739) (xy 378.09932 -407.093928)
			(xy 378.09932 -407.251408) (xy 378.098822 -407.261515) (xy 378.091085 -407.280189) (xy 378.076793 -407.294483)
			(xy 378.058119 -407.302221) (xy 378.048012 -407.302716) (xy 377.331732 -407.302716) (xy 377.321614 -407.302258)
			(xy 377.302914 -407.294524) (xy 377.288599 -407.28022) (xy 377.280849 -407.261526) (xy 377.280424 -407.251408)
			(xy 377.280424 -407.093928) (xy 377.279995 -407.084743) (xy 377.273494 -407.067559) (xy 377.267724 -407.0604)
			(xy 377.245828 -407.034761) (xy 377.207738 -406.979123) (xy 377.176588 -406.919324) (xy 377.152824 -406.856223)
			(xy 377.13679 -406.790731) (xy 377.128717 -406.723789) (xy 347.450915 -406.723789) (xy 347.442881 -406.790547)
			(xy 347.426912 -406.855927) (xy 347.403244 -406.91893) (xy 347.372216 -406.978653) (xy 347.334273 -407.03424)
			(xy 347.312488 -407.059892) (xy 347.306711 -407.067051) (xy 347.300185 -407.084231) (xy 347.299788 -407.09342)
			(xy 347.299788 -407.251408) (xy 347.299385 -407.261564) (xy 347.291584 -407.280319) (xy 347.277182 -407.294642)
			(xy 347.258384 -407.30234) (xy 347.248226 -407.302716) (xy 346.531946 -407.302716) (xy 346.521817 -407.302234)
			(xy 346.503088 -407.294514) (xy 346.488729 -407.280225) (xy 346.480916 -407.261535) (xy 346.480384 -407.251408)
			(xy 346.480384 -407.09342) (xy 346.479968 -407.084233) (xy 346.473459 -407.067049) (xy 346.467684 -407.059892)
			(xy 346.445864 -407.034266) (xy 346.407913 -406.978677) (xy 346.376878 -406.91895) (xy 346.353205 -406.855942)
			(xy 346.337233 -406.790556) (xy 346.329191 -406.72373) (xy 343.051153 -406.72373) (xy 343.051153 -406.723787)
			(xy 343.04308 -406.790723) (xy 343.027048 -406.85621) (xy 343.003287 -406.919306) (xy 342.97214 -406.979101)
			(xy 342.934054 -407.034735) (xy 342.912192 -407.0604) (xy 342.906412 -407.067557) (xy 342.899888 -407.084738)
			(xy 342.899492 -407.093928) (xy 342.899492 -407.251408) (xy 342.89909 -407.261532) (xy 342.891338 -407.280237)
			(xy 342.877017 -407.294551) (xy 342.858308 -407.302295) (xy 342.848184 -407.302716) (xy 342.131904 -407.302716)
			(xy 342.121798 -407.302212) (xy 342.103122 -407.294479) (xy 342.088828 -407.280188) (xy 342.08109 -407.261514)
			(xy 342.080596 -407.251408) (xy 342.080596 -407.093928) (xy 342.080173 -407.084742) (xy 342.073668 -407.067558)
			(xy 342.067896 -407.0604) (xy 342.046001 -407.034761) (xy 342.007913 -406.979122) (xy 341.976764 -406.919322)
			(xy 341.953002 -406.856222) (xy 341.936969 -406.79073) (xy 341.928896 -406.723789) (xy 338.650827 -406.723789)
			(xy 338.642793 -406.790546) (xy 338.626825 -406.855926) (xy 338.603158 -406.918929) (xy 338.572131 -406.978652)
			(xy 338.534188 -407.034239) (xy 338.512404 -407.059892) (xy 338.506629 -407.067052) (xy 338.500101 -407.084231)
			(xy 338.499704 -407.09342) (xy 338.499704 -407.251408) (xy 338.499285 -407.261562) (xy 338.491487 -407.280314)
			(xy 338.47709 -407.294637) (xy 338.458298 -407.302337) (xy 338.448142 -407.302716) (xy 337.731862 -407.302716)
			(xy 337.721727 -407.302303) (xy 337.702997 -407.294555) (xy 337.688641 -407.280246) (xy 337.68083 -407.261541)
			(xy 337.6803 -407.251408) (xy 337.6803 -407.09342) (xy 337.67988 -407.084234) (xy 337.673373 -407.067049)
			(xy 337.6676 -407.059892) (xy 337.645782 -407.034265) (xy 337.607837 -406.978674) (xy 337.576807 -406.918947)
			(xy 337.553138 -406.855939) (xy 337.537168 -406.790554) (xy 337.529127 -406.723729) (xy 334.251065 -406.723729)
			(xy 334.251065 -406.723786) (xy 334.242993 -406.790722) (xy 334.226961 -406.85621) (xy 334.203201 -406.919305)
			(xy 334.172054 -406.9791) (xy 334.13397 -407.034735) (xy 334.112108 -407.0604) (xy 334.10633 -407.067558)
			(xy 334.099804 -407.084739) (xy 334.099408 -407.093928) (xy 334.099408 -407.251408) (xy 334.098921 -407.261516)
			(xy 334.091183 -407.280193) (xy 334.076886 -407.294487) (xy 334.058208 -407.302223) (xy 334.0481 -407.302716)
			(xy 333.33182 -407.302716) (xy 333.321701 -407.302268) (xy 333.303001 -407.29453) (xy 333.288686 -407.280223)
			(xy 333.280937 -407.261527) (xy 333.280512 -407.251408) (xy 333.280512 -407.093928) (xy 333.280086 -407.084743)
			(xy 333.273583 -407.067558) (xy 333.267812 -407.0604) (xy 333.245916 -407.034761) (xy 333.207828 -406.979123)
			(xy 333.176678 -406.919323) (xy 333.152915 -406.856223) (xy 333.136881 -406.790731) (xy 333.128808 -406.723789)
			(xy 326.525636 -406.723789) (xy 326.525636 -409.523827) (xy 330.929173 -409.523827) (xy 330.929176 -409.456519)
			(xy 330.937224 -409.389693) (xy 330.953202 -409.324309) (xy 330.976879 -409.261303) (xy 331.007918 -409.201578)
			(xy 331.045873 -409.145992) (xy 331.067664 -409.12034) (xy 331.073476 -409.113206) (xy 331.07998 -409.096007)
			(xy 331.080364 -409.086812) (xy 331.080364 -408.593544) (xy 331.079919 -408.584361) (xy 331.073428 -408.567177)
			(xy 331.067664 -408.560016) (xy 331.045868 -408.534371) (xy 331.007918 -408.478784) (xy 330.976883 -408.419059)
			(xy 330.95321 -408.356054) (xy 330.937237 -408.290671) (xy 330.929193 -408.223847) (xy 330.929194 -408.156541)
			(xy 330.937239 -408.089717) (xy 330.953213 -408.024334) (xy 330.976888 -407.96133) (xy 331.007924 -407.901606)
			(xy 331.045875 -407.84602) (xy 331.067664 -407.820368) (xy 331.073464 -407.813226) (xy 331.079975 -407.796033)
			(xy 331.080364 -407.78684) (xy 331.080364 -407.628852) (xy 331.080782 -407.618699) (xy 331.088586 -407.599953)
			(xy 331.102983 -407.585633) (xy 331.121771 -407.577928) (xy 331.131926 -407.577544) (xy 331.848206 -407.577544)
			(xy 331.858334 -407.578022) (xy 331.877056 -407.585752) (xy 331.891412 -407.600041) (xy 331.89923 -407.618727)
			(xy 331.899768 -407.628852) (xy 331.899768 -407.78684) (xy 331.900166 -407.796028) (xy 331.906689 -407.813212)
			(xy 331.912468 -407.820368) (xy 331.934248 -407.846027) (xy 331.972196 -407.901612) (xy 332.00323 -407.961335)
			(xy 332.026903 -408.024339) (xy 332.042876 -408.08972) (xy 332.050921 -408.156542) (xy 332.050921 -408.223846)
			(xy 332.042878 -408.290668) (xy 332.026906 -408.35605) (xy 332.003235 -408.419054) (xy 331.972203 -408.478777)
			(xy 331.934255 -408.534364) (xy 331.912468 -408.560016) (xy 331.906678 -408.567166) (xy 331.90016 -408.584353)
			(xy 331.899768 -408.593544) (xy 331.899768 -409.086812) (xy 331.900179 -409.095999) (xy 331.906693 -409.113183)
			(xy 331.912468 -409.12034) (xy 331.93422 -409.146022) (xy 331.972169 -409.201604) (xy 332.003204 -409.261323)
			(xy 332.026878 -409.324324) (xy 332.042853 -409.389703) (xy 332.0509 -409.456522) (xy 332.050904 -409.523824)
			(xy 332.042863 -409.590644) (xy 332.026894 -409.656024) (xy 332.003226 -409.719027) (xy 331.972197 -409.77875)
			(xy 331.934253 -409.834336) (xy 331.912468 -409.859988) (xy 331.906647 -409.867116) (xy 331.900148 -409.88432)
			(xy 331.899768 -409.893516) (xy 331.899768 -410.051504) (xy 331.899381 -410.061662) (xy 331.891578 -410.080421)
			(xy 331.87717 -410.094745) (xy 331.858367 -410.102439) (xy 331.848206 -410.102812) (xy 331.131926 -410.102812)
			(xy 331.121807 -410.102254) (xy 331.103097 -410.094544) (xy 331.088741 -410.08028) (xy 331.080912 -410.061619)
			(xy 331.080364 -410.051504) (xy 331.080364 -409.893516) (xy 331.079932 -409.884331) (xy 331.073432 -409.867148)
			(xy 331.067664 -409.859988) (xy 331.04584 -409.834365) (xy 331.007891 -409.778775) (xy 330.976857 -409.719048)
			(xy 330.953186 -409.656039) (xy 330.937214 -409.590653) (xy 330.929173 -409.523827) (xy 326.525636 -409.523827)
			(xy 326.525636 -410.623701) (xy 333.128819 -410.623701) (xy 333.12882 -410.556275) (xy 333.136898 -410.489336)
			(xy 333.152936 -410.423846) (xy 333.176702 -410.360748) (xy 333.207855 -410.300952) (xy 333.245947 -410.245317)
			(xy 333.267812 -410.219652) (xy 333.273613 -410.21251) (xy 333.280125 -410.195317) (xy 333.280512 -410.186124)
			(xy 333.280512 -409.693872) (xy 333.280113 -409.684684) (xy 333.273591 -409.6675) (xy 333.267812 -409.660344)
			(xy 333.245959 -409.634669) (xy 333.20787 -409.579036) (xy 333.176718 -409.519242) (xy 333.152952 -409.456146)
			(xy 333.136916 -409.390658) (xy 333.128839 -409.32372) (xy 333.128837 -409.256298) (xy 333.136912 -409.18936)
			(xy 333.152947 -409.123871) (xy 333.17671 -409.060775) (xy 333.20786 -409.000979) (xy 333.245948 -408.945345)
			(xy 333.267812 -408.91968) (xy 333.273601 -408.912529) (xy 333.28012 -408.895343) (xy 333.280512 -408.886152)
			(xy 333.280512 -408.728672) (xy 333.280962 -408.71856) (xy 333.288711 -408.699879) (xy 333.303019 -408.685585)
			(xy 333.321708 -408.677853) (xy 333.33182 -408.677364) (xy 334.0481 -408.677364) (xy 334.058204 -408.677884)
			(xy 334.076876 -408.685615) (xy 334.091169 -408.699901) (xy 334.09891 -408.718568) (xy 334.099408 -408.728672)
			(xy 334.099408 -408.886152) (xy 334.099839 -408.895337) (xy 334.106338 -408.912522) (xy 334.112108 -408.91968)
			(xy 334.133983 -408.945336) (xy 334.172071 -409.000972) (xy 334.203221 -409.060769) (xy 334.226984 -409.123867)
			(xy 334.243019 -409.189358) (xy 334.251093 -409.256297) (xy 334.251092 -409.323721) (xy 334.243015 -409.39066)
			(xy 334.226979 -409.45615) (xy 334.203214 -409.519247) (xy 334.200797 -409.523886) (xy 335.328966 -409.523886)
			(xy 335.328969 -409.45646) (xy 335.337048 -409.38952) (xy 335.353086 -409.32403) (xy 335.376852 -409.260931)
			(xy 335.408005 -409.201134) (xy 335.446095 -409.145498) (xy 335.46796 -409.119832) (xy 335.473775 -409.1127)
			(xy 335.480277 -409.095499) (xy 335.48066 -409.086304) (xy 335.48066 -408.594052) (xy 335.480211 -408.584869)
			(xy 335.473723 -408.567685) (xy 335.46796 -408.560524) (xy 335.44609 -408.534865) (xy 335.408004 -408.479228)
			(xy 335.376856 -408.419431) (xy 335.353094 -408.356333) (xy 335.33706 -408.290844) (xy 335.328985 -408.223906)
			(xy 335.328986 -408.156482) (xy 335.337062 -408.089544) (xy 335.353097 -408.024055) (xy 335.376861 -407.960958)
			(xy 335.40801 -407.901161) (xy 335.446097 -407.845526) (xy 335.46796 -407.81986) (xy 335.473763 -407.81272)
			(xy 335.480272 -407.795525) (xy 335.48066 -407.786332) (xy 335.48066 -407.628852) (xy 335.481145 -407.618745)
			(xy 335.488891 -407.600074) (xy 335.503187 -407.585782) (xy 335.521861 -407.578042) (xy 335.531968 -407.577544)
			(xy 336.248248 -407.577544) (xy 336.258353 -407.578045) (xy 336.277021 -407.585788) (xy 336.291312 -407.600079)
			(xy 336.299055 -407.618747) (xy 336.299556 -407.628852) (xy 336.299556 -407.786332) (xy 336.299961 -407.79552)
			(xy 336.306479 -407.812703) (xy 336.312256 -407.81986) (xy 336.334114 -407.845531) (xy 336.372205 -407.901164)
			(xy 336.403359 -407.960959) (xy 336.427126 -408.024055) (xy 336.443163 -408.089544) (xy 336.45124 -408.156482)
			(xy 336.451241 -408.223906) (xy 336.443165 -408.290844) (xy 336.427129 -408.356334) (xy 336.403364 -408.41943)
			(xy 336.372212 -408.479226) (xy 336.334121 -408.53486) (xy 336.312256 -408.560524) (xy 336.306461 -408.56767)
			(xy 336.299947 -408.58486) (xy 336.299556 -408.594052) (xy 336.299556 -409.086304) (xy 336.299974 -409.09549)
			(xy 336.306483 -409.112674) (xy 336.312256 -409.119832) (xy 336.334086 -409.145526) (xy 336.372179 -409.201155)
			(xy 336.403334 -409.260947) (xy 336.427102 -409.32404) (xy 336.443141 -409.389526) (xy 336.45122 -409.456462)
			(xy 336.451224 -409.523884) (xy 336.443151 -409.59082) (xy 336.427118 -409.656308) (xy 336.403356 -409.719404)
			(xy 336.372207 -409.779198) (xy 336.334119 -409.834832) (xy 336.312256 -409.860496) (xy 336.306473 -409.867651)
			(xy 336.299951 -409.884834) (xy 336.299556 -409.894024) (xy 336.299556 -410.051504) (xy 336.299019 -410.061606)
			(xy 336.291291 -410.080274) (xy 336.277011 -410.094566) (xy 336.25835 -410.102311) (xy 336.248248 -410.102812)
			(xy 335.531968 -410.102812) (xy 335.521859 -410.102341) (xy 335.503182 -410.094595) (xy 335.488889 -410.080294)
			(xy 335.481153 -410.061614) (xy 335.48066 -410.051504) (xy 335.48066 -409.894024) (xy 335.480225 -409.88484)
			(xy 335.473727 -409.867656) (xy 335.46796 -409.860496) (xy 335.446062 -409.834859) (xy 335.407977 -409.77922)
			(xy 335.37683 -409.719419) (xy 335.35307 -409.656319) (xy 335.337038 -409.590827) (xy 335.328966 -409.523886)
			(xy 334.200797 -409.523886) (xy 334.172062 -409.579044) (xy 334.133972 -409.634679) (xy 334.112108 -409.660344)
			(xy 334.106311 -409.667489) (xy 334.099796 -409.68468) (xy 334.099408 -409.693872) (xy 334.099408 -410.186124)
			(xy 334.099805 -410.195313) (xy 334.106328 -410.212497) (xy 334.112108 -410.219652) (xy 334.133956 -410.24533)
			(xy 334.172045 -410.300963) (xy 334.203196 -410.360758) (xy 334.22696 -410.423853) (xy 334.242997 -410.48934)
			(xy 334.251074 -410.556277) (xy 334.251075 -410.623641) (xy 337.529138 -410.623641) (xy 337.52914 -410.556335)
			(xy 337.537185 -410.489512) (xy 337.553158 -410.42413) (xy 337.576831 -410.361125) (xy 337.607864 -410.3014)
			(xy 337.645813 -410.245813) (xy 337.6676 -410.22016) (xy 337.673396 -410.213014) (xy 337.679911 -410.195824)
			(xy 337.6803 -410.186632) (xy 337.6803 -409.693364) (xy 337.679907 -409.684175) (xy 337.673382 -409.666991)
			(xy 337.6676 -409.659836) (xy 337.645825 -409.634174) (xy 337.607879 -409.578588) (xy 337.576847 -409.518865)
			(xy 337.553175 -409.455862) (xy 337.537203 -409.390482) (xy 337.529158 -409.323661) (xy 337.529157 -409.256357)
			(xy 337.537199 -409.189536) (xy 337.55317 -409.124155) (xy 337.57684 -409.061151) (xy 337.607869 -409.001428)
			(xy 337.645814 -408.945841) (xy 337.6676 -408.920188) (xy 337.673384 -408.913034) (xy 337.679906 -408.89585)
			(xy 337.6803 -408.88666) (xy 337.6803 -408.728672) (xy 337.680699 -408.718516) (xy 337.688503 -408.699763)
			(xy 337.702907 -408.685441) (xy 337.721704 -408.677742) (xy 337.731862 -408.677364) (xy 338.448142 -408.677364)
			(xy 338.458274 -408.677793) (xy 338.477001 -408.685539) (xy 338.491357 -408.699843) (xy 338.49917 -408.718542)
			(xy 338.499704 -408.728672) (xy 338.499704 -408.88666) (xy 338.500132 -408.895845) (xy 338.506633 -408.91303)
			(xy 338.512404 -408.920188) (xy 338.534202 -408.945831) (xy 338.572148 -409.00142) (xy 338.603178 -409.061145)
			(xy 338.626848 -409.124151) (xy 338.642819 -409.189534) (xy 338.650862 -409.256356) (xy 338.650861 -409.323662)
			(xy 338.642816 -409.390484) (xy 338.626843 -409.455867) (xy 338.603171 -409.518871) (xy 338.600596 -409.523827)
			(xy 339.729261 -409.523827) (xy 339.729264 -409.456519) (xy 339.737312 -409.389694) (xy 339.753289 -409.324309)
			(xy 339.776966 -409.261303) (xy 339.808004 -409.201579) (xy 339.845958 -409.145992) (xy 339.867748 -409.12034)
			(xy 339.873559 -409.113205) (xy 339.880064 -409.096006) (xy 339.880448 -409.086812) (xy 339.880448 -408.593544)
			(xy 339.880006 -408.58436) (xy 339.873513 -408.567176) (xy 339.867748 -408.560016) (xy 339.845952 -408.534371)
			(xy 339.808003 -408.478783) (xy 339.776969 -408.419059) (xy 339.753297 -408.356054) (xy 339.737324 -408.29067)
			(xy 339.72928 -408.223847) (xy 339.729281 -408.156541) (xy 339.737326 -408.089718) (xy 339.7533 -408.024335)
			(xy 339.776974 -407.96133) (xy 339.808009 -407.901606) (xy 339.845959 -407.84602) (xy 339.867748 -407.820368)
			(xy 339.873547 -407.813224) (xy 339.880059 -407.796032) (xy 339.880448 -407.78684) (xy 339.880448 -407.628852)
			(xy 339.880881 -407.618701) (xy 339.888683 -407.599958) (xy 339.903075 -407.585638) (xy 339.921857 -407.577931)
			(xy 339.93201 -407.577544) (xy 340.64829 -407.577544) (xy 340.658417 -407.578035) (xy 340.677138 -407.58576)
			(xy 340.691495 -407.600045) (xy 340.699314 -407.618728) (xy 340.699852 -407.628852) (xy 340.699852 -407.78684)
			(xy 340.700254 -407.796028) (xy 340.706775 -407.813211) (xy 340.712552 -407.820368) (xy 340.734332 -407.846027)
			(xy 340.772282 -407.901612) (xy 340.803316 -407.961335) (xy 340.826989 -408.024338) (xy 340.842963 -408.08972)
			(xy 340.851008 -408.156542) (xy 340.851009 -408.223846) (xy 340.842965 -408.290668) (xy 340.826993 -408.35605)
			(xy 340.803321 -408.419054) (xy 340.772288 -408.478778) (xy 340.734339 -408.534364) (xy 340.712552 -408.560016)
			(xy 340.70676 -408.567164) (xy 340.700244 -408.584353) (xy 340.699852 -408.593544) (xy 340.699852 -409.086812)
			(xy 340.700267 -409.095998) (xy 340.706779 -409.113182) (xy 340.712552 -409.12034) (xy 340.734304 -409.146021)
			(xy 340.772255 -409.201603) (xy 340.80329 -409.261323) (xy 340.826965 -409.324323) (xy 340.842941 -409.389702)
			(xy 340.850988 -409.456522) (xy 340.850992 -409.523824) (xy 340.842951 -409.590644) (xy 340.826981 -409.656025)
			(xy 340.803312 -409.719028) (xy 340.772283 -409.77875) (xy 340.734338 -409.834336) (xy 340.712552 -409.859988)
			(xy 340.70673 -409.867115) (xy 340.700232 -409.88432) (xy 340.699852 -409.893516) (xy 340.699852 -410.051504)
			(xy 340.699383 -410.061652) (xy 340.691595 -410.080394) (xy 340.677214 -410.094716) (xy 340.65844 -410.102424)
			(xy 340.64829 -410.102812) (xy 339.93201 -410.102812) (xy 339.92189 -410.102267) (xy 339.903179 -410.094552)
			(xy 339.888824 -410.080284) (xy 339.880996 -410.061621) (xy 339.880448 -410.051504) (xy 339.880448 -409.893516)
			(xy 339.88002 -409.884331) (xy 339.873517 -409.867147) (xy 339.867748 -409.859988) (xy 339.845924 -409.834365)
			(xy 339.807976 -409.778775) (xy 339.776944 -409.719047) (xy 339.753273 -409.656039) (xy 339.737302 -409.590653)
			(xy 339.729261 -409.523827) (xy 338.600596 -409.523827) (xy 338.572139 -409.578596) (xy 338.534191 -409.634183)
			(xy 338.512404 -409.659836) (xy 338.50661 -409.666983) (xy 338.500094 -409.684172) (xy 338.499704 -409.693364)
			(xy 338.499704 -410.186632) (xy 338.500098 -410.195821) (xy 338.506623 -410.213005) (xy 338.512404 -410.22016)
			(xy 338.534175 -410.245826) (xy 338.572121 -410.301411) (xy 338.603153 -410.361133) (xy 338.626825 -410.424136)
			(xy 338.642797 -410.489516) (xy 338.650842 -410.556336) (xy 338.650844 -410.623639) (xy 338.650837 -410.6237)
			(xy 341.928907 -410.6237) (xy 341.928908 -410.556276) (xy 341.936986 -410.489336) (xy 341.953023 -410.423846)
			(xy 341.976789 -410.360749) (xy 342.007941 -410.300952) (xy 342.046031 -410.245317) (xy 342.067896 -410.219652)
			(xy 342.073695 -410.212508) (xy 342.080208 -410.195317) (xy 342.080596 -410.186124) (xy 342.080596 -409.693872)
			(xy 342.0802 -409.684683) (xy 342.073677 -409.667499) (xy 342.067896 -409.660344) (xy 342.046044 -409.634669)
			(xy 342.007955 -409.579036) (xy 341.976804 -409.519241) (xy 341.953039 -409.456145) (xy 341.937003 -409.390657)
			(xy 341.928927 -409.32372) (xy 341.928925 -409.256298) (xy 341.937 -409.18936) (xy 341.953034 -409.123872)
			(xy 341.976797 -409.060776) (xy 342.007946 -409.00098) (xy 342.046033 -408.945345) (xy 342.067896 -408.91968)
			(xy 342.073683 -408.912528) (xy 342.080204 -408.895343) (xy 342.080596 -408.886152) (xy 342.080596 -408.728672)
			(xy 342.081062 -408.718562) (xy 342.088808 -408.699884) (xy 342.103111 -408.68559) (xy 342.121794 -408.677856)
			(xy 342.131904 -408.677364) (xy 342.848184 -408.677364) (xy 342.858287 -408.677897) (xy 342.876958 -408.685623)
			(xy 342.891252 -408.699905) (xy 342.898994 -408.718569) (xy 342.899492 -408.728672) (xy 342.899492 -408.886152)
			(xy 342.899927 -408.895337) (xy 342.906424 -408.912521) (xy 342.912192 -408.91968) (xy 342.934068 -408.945335)
			(xy 342.972157 -409.000971) (xy 343.003308 -409.060769) (xy 343.027071 -409.123867) (xy 343.043106 -409.189357)
			(xy 343.051181 -409.256297) (xy 343.05118 -409.323721) (xy 343.043103 -409.390661) (xy 343.027066 -409.45615)
			(xy 343.0033 -409.519248) (xy 343.000914 -409.523827) (xy 344.129052 -409.523827) (xy 344.129055 -409.456519)
			(xy 344.137102 -409.389694) (xy 344.153079 -409.32431) (xy 344.176756 -409.261304) (xy 344.207793 -409.201579)
			(xy 344.245746 -409.145992) (xy 344.267536 -409.12034) (xy 344.273345 -409.113204) (xy 344.279851 -409.096006)
			(xy 344.280236 -409.086812) (xy 344.280236 -408.593544) (xy 344.279796 -408.58436) (xy 344.273302 -408.567176)
			(xy 344.267536 -408.560016) (xy 344.24574 -408.53437) (xy 344.207792 -408.478783) (xy 344.176759 -408.419058)
			(xy 344.153087 -408.356053) (xy 344.137115 -408.29067) (xy 344.129071 -408.223847) (xy 344.129072 -408.156541)
			(xy 344.137117 -408.089718) (xy 344.153091 -408.024335) (xy 344.176764 -407.961331) (xy 344.207798 -407.901607)
			(xy 344.245748 -407.84602) (xy 344.267536 -407.820368) (xy 344.273333 -407.813223) (xy 344.279847 -407.796032)
			(xy 344.280236 -407.78684) (xy 344.280236 -407.628852) (xy 344.280583 -407.61869) (xy 344.288401 -407.59993)
			(xy 344.302821 -407.585607) (xy 344.321634 -407.577916) (xy 344.331798 -407.577544) (xy 345.048078 -407.577544)
			(xy 345.058204 -407.578045) (xy 345.076925 -407.585766) (xy 345.091283 -407.600048) (xy 345.099102 -407.618729)
			(xy 345.09964 -407.628852) (xy 345.09964 -407.78684) (xy 345.100044 -407.796028) (xy 345.106563 -407.813211)
			(xy 345.11234 -407.820368) (xy 345.13412 -407.846026) (xy 345.172071 -407.901611) (xy 345.203106 -407.961334)
			(xy 345.22678 -408.024338) (xy 345.242754 -408.089719) (xy 345.250799 -408.156542) (xy 345.2508 -408.223846)
			(xy 345.242756 -408.290669) (xy 345.226783 -408.356051) (xy 345.20311 -408.419055) (xy 345.172077 -408.478778)
			(xy 345.134128 -408.534364) (xy 345.11234 -408.560016) (xy 345.106547 -408.567163) (xy 345.100032 -408.584352)
			(xy 345.09964 -408.593544) (xy 345.09964 -409.086812) (xy 345.100058 -409.095998) (xy 345.106568 -409.113182)
			(xy 345.11234 -409.12034) (xy 345.134093 -409.146021) (xy 345.172044 -409.201603) (xy 345.20308 -409.261322)
			(xy 345.226756 -409.324323) (xy 345.242732 -409.389702) (xy 345.250779 -409.456522) (xy 345.250783 -409.523824)
			(xy 345.242742 -409.590645) (xy 345.226772 -409.656025) (xy 345.203102 -409.719028) (xy 345.172072 -409.778751)
			(xy 345.134126 -409.834336) (xy 345.11234 -409.859988) (xy 345.106516 -409.867114) (xy 345.100019 -409.884319)
			(xy 345.09964 -409.893516) (xy 345.09964 -410.051504) (xy 345.099182 -410.061653) (xy 345.091393 -410.080398)
			(xy 345.077008 -410.09472) (xy 345.058229 -410.102427) (xy 345.048078 -410.102812) (xy 344.331798 -410.102812)
			(xy 344.321678 -410.102277) (xy 344.302966 -410.094558) (xy 344.288612 -410.080287) (xy 344.280784 -410.061621)
			(xy 344.280236 -410.051504) (xy 344.280236 -409.893516) (xy 344.27981 -409.884331) (xy 344.273307 -409.867146)
			(xy 344.267536 -409.859988) (xy 344.245713 -409.834365) (xy 344.207765 -409.778774) (xy 344.176734 -409.719047)
			(xy 344.153063 -409.656038) (xy 344.137093 -409.590653) (xy 344.129052 -409.523827) (xy 343.000914 -409.523827)
			(xy 342.972148 -409.579044) (xy 342.934057 -409.634679) (xy 342.912192 -409.660344) (xy 342.906393 -409.667488)
			(xy 342.89988 -409.684679) (xy 342.899492 -409.693872) (xy 342.899492 -410.186124) (xy 342.899892 -410.195312)
			(xy 342.906413 -410.212496) (xy 342.912192 -410.219652) (xy 342.934041 -410.24533) (xy 342.97213 -410.300963)
			(xy 343.003282 -410.360757) (xy 343.027048 -410.423852) (xy 343.043084 -410.48934) (xy 343.051162 -410.556277)
			(xy 343.051163 -410.623642) (xy 346.329202 -410.623642) (xy 346.329204 -410.556334) (xy 346.33725 -410.48951)
			(xy 346.353226 -410.424126) (xy 346.376903 -410.361121) (xy 346.40794 -410.301397) (xy 346.445894 -410.245812)
			(xy 346.467684 -410.22016) (xy 346.473478 -410.213013) (xy 346.479995 -410.195824) (xy 346.480384 -410.186632)
			(xy 346.480384 -409.693364) (xy 346.479995 -409.684175) (xy 346.473467 -409.66699) (xy 346.467684 -409.659836)
			(xy 346.445907 -409.634175) (xy 346.407955 -409.578591) (xy 346.376918 -409.518869) (xy 346.353243 -409.455865)
			(xy 346.337268 -409.390484) (xy 346.329222 -409.323661) (xy 346.329221 -409.256357) (xy 346.337265 -409.189534)
			(xy 346.353238 -409.124152) (xy 346.376911 -409.061148) (xy 346.407945 -409.001425) (xy 346.445896 -408.94584)
			(xy 346.467684 -408.920188) (xy 346.473466 -408.913033) (xy 346.47999 -408.89585) (xy 346.480384 -408.88666)
			(xy 346.480384 -408.728672) (xy 346.480798 -408.718518) (xy 346.4886 -408.699768) (xy 346.502999 -408.685446)
			(xy 346.52179 -408.677745) (xy 346.531946 -408.677364) (xy 347.248226 -408.677364) (xy 347.258357 -408.677806)
			(xy 347.277084 -408.685547) (xy 347.29144 -408.699847) (xy 347.299254 -408.718543) (xy 347.299788 -408.728672)
			(xy 347.299788 -408.88666) (xy 347.30022 -408.895845) (xy 347.306719 -408.913029) (xy 347.312488 -408.920188)
			(xy 347.334287 -408.945831) (xy 347.372233 -409.001419) (xy 347.403265 -409.061144) (xy 347.426936 -409.12415)
			(xy 347.442907 -409.189533) (xy 347.45095 -409.256356) (xy 347.450949 -409.323662) (xy 347.442904 -409.390485)
			(xy 347.42693 -409.455867) (xy 347.403257 -409.518872) (xy 347.400682 -409.523827) (xy 374.929082 -409.523827)
			(xy 374.929085 -409.456519) (xy 374.937133 -409.389693) (xy 374.953111 -409.324308) (xy 374.97679 -409.261302)
			(xy 375.007829 -409.201578) (xy 375.045785 -409.145991) (xy 375.067576 -409.12034) (xy 375.073378 -409.113198)
			(xy 375.07989 -409.096005) (xy 375.080276 -409.086812) (xy 375.080276 -408.593544) (xy 375.07985 -408.584358)
			(xy 375.073348 -408.567174) (xy 375.067576 -408.560016) (xy 375.045779 -408.534371) (xy 375.007828 -408.478784)
			(xy 374.976793 -408.41906) (xy 374.953119 -408.356055) (xy 374.937146 -408.290671) (xy 374.929102 -408.223847)
			(xy 374.929103 -408.156541) (xy 374.937148 -408.089717) (xy 374.953123 -408.024334) (xy 374.976798 -407.961329)
			(xy 375.007835 -407.901605) (xy 375.045787 -407.84602) (xy 375.067576 -407.820368) (xy 375.073366 -407.813218)
			(xy 375.079885 -407.796031) (xy 375.080276 -407.78684) (xy 375.080276 -407.628852) (xy 375.080682 -407.618698)
			(xy 375.088489 -407.599949) (xy 375.10289 -407.585628) (xy 375.121682 -407.577926) (xy 375.131838 -407.577544)
			(xy 375.848118 -407.577544) (xy 375.858246 -407.578012) (xy 375.876969 -407.585746) (xy 375.891325 -407.600038)
			(xy 375.899143 -407.618726) (xy 375.89968 -407.628852) (xy 375.89968 -407.78684) (xy 375.900075 -407.796029)
			(xy 375.9066 -407.813213) (xy 375.91238 -407.820368) (xy 375.934159 -407.846027) (xy 375.972107 -407.901613)
			(xy 376.00314 -407.961336) (xy 376.026812 -408.024339) (xy 376.042785 -408.08972) (xy 376.05083 -408.156542)
			(xy 376.05083 -408.223846) (xy 376.042787 -408.290668) (xy 376.026816 -408.356049) (xy 376.003145 -408.419053)
			(xy 375.972113 -408.478777) (xy 375.934167 -408.534364) (xy 375.91238 -408.560016) (xy 375.906592 -408.567167)
			(xy 375.900073 -408.584353) (xy 375.89968 -408.593544) (xy 375.89968 -409.086812) (xy 375.900089 -409.095999)
			(xy 375.906604 -409.113183) (xy 375.91238 -409.12034) (xy 375.934131 -409.146022) (xy 375.97208 -409.201604)
			(xy 376.003114 -409.261324) (xy 376.026788 -409.324325) (xy 376.042763 -409.389703) (xy 376.050809 -409.456522)
			(xy 376.050813 -409.523824) (xy 376.042772 -409.590644) (xy 376.026804 -409.656024) (xy 376.003136 -409.719026)
			(xy 375.972108 -409.778749) (xy 375.934165 -409.834335) (xy 375.91238 -409.859988) (xy 375.906561 -409.867117)
			(xy 375.90006 -409.88432) (xy 375.89968 -409.893516) (xy 375.89968 -410.051504) (xy 375.899281 -410.061661)
			(xy 375.891481 -410.080417) (xy 375.877077 -410.094741) (xy 375.858277 -410.102437) (xy 375.848118 -410.102812)
			(xy 375.131838 -410.102812) (xy 375.12172 -410.102244) (xy 375.10301 -410.094538) (xy 375.088654 -410.080277)
			(xy 375.080824 -410.061618) (xy 375.080276 -410.051504) (xy 375.080276 -409.893516) (xy 375.079864 -409.884329)
			(xy 375.073352 -409.867144) (xy 375.067576 -409.859988) (xy 375.045751 -409.834366) (xy 375.007801 -409.778776)
			(xy 374.976768 -409.719048) (xy 374.953095 -409.65604) (xy 374.937124 -409.590654) (xy 374.929082 -409.523827)
			(xy 347.400682 -409.523827) (xy 347.372224 -409.578596) (xy 347.334276 -409.634184) (xy 347.312488 -409.659836)
			(xy 347.306692 -409.666982) (xy 347.300177 -409.684172) (xy 347.299788 -409.693364) (xy 347.299788 -410.186632)
			(xy 347.300185 -410.195821) (xy 347.306708 -410.213005) (xy 347.312488 -410.22016) (xy 347.334259 -410.245825)
			(xy 347.372207 -410.301411) (xy 347.403239 -410.361133) (xy 347.426912 -410.424135) (xy 347.442885 -410.489516)
			(xy 347.45093 -410.556336) (xy 347.450931 -410.62364) (xy 347.450924 -410.623701) (xy 377.128728 -410.623701)
			(xy 377.128729 -410.556275) (xy 377.136807 -410.489335) (xy 377.152845 -410.423845) (xy 377.176612 -410.360748)
			(xy 377.207766 -410.300951) (xy 377.245858 -410.245317) (xy 377.267724 -410.219652) (xy 377.273526 -410.212511)
			(xy 377.280037 -410.195317) (xy 377.280424 -410.186124) (xy 377.280424 -409.693872) (xy 377.280022 -409.684684)
			(xy 377.273502 -409.6675) (xy 377.267724 -409.660344) (xy 377.245871 -409.634669) (xy 377.20778 -409.579037)
			(xy 377.176628 -409.519242) (xy 377.152862 -409.456146) (xy 377.136825 -409.390658) (xy 377.128748 -409.323721)
			(xy 377.128747 -409.256297) (xy 377.136822 -409.18936) (xy 377.152857 -409.123871) (xy 377.17662 -409.060774)
			(xy 377.207771 -409.000979) (xy 377.24586 -408.945345) (xy 377.267724 -408.91968) (xy 377.273514 -408.912531)
			(xy 377.280032 -408.895343) (xy 377.280424 -408.886152) (xy 377.280424 -408.728672) (xy 377.280794 -408.718545)
			(xy 377.288555 -408.699836) (xy 377.302886 -408.685522) (xy 377.321604 -408.677782) (xy 377.331732 -408.677364)
			(xy 378.048012 -408.677364) (xy 378.058117 -408.677875) (xy 378.076789 -408.685609) (xy 378.091082 -408.699898)
			(xy 378.098822 -408.718567) (xy 378.09932 -408.728672) (xy 378.09932 -408.886152) (xy 378.099749 -408.895337)
			(xy 378.106249 -408.912522) (xy 378.11202 -408.91968) (xy 378.133895 -408.945336) (xy 378.171982 -409.000972)
			(xy 378.203131 -409.06077) (xy 378.226894 -409.123868) (xy 378.242928 -409.189358) (xy 378.251002 -409.256297)
			(xy 378.251001 -409.323721) (xy 378.242925 -409.39066) (xy 378.226888 -409.456149) (xy 378.203124 -409.519247)
			(xy 378.200707 -409.523886) (xy 379.328875 -409.523886) (xy 379.328878 -409.45646) (xy 379.336957 -409.38952)
			(xy 379.352995 -409.324029) (xy 379.376762 -409.260931) (xy 379.407916 -409.201133) (xy 379.446007 -409.145498)
			(xy 379.467872 -409.119832) (xy 379.473689 -409.112701) (xy 379.480189 -409.095499) (xy 379.480572 -409.086304)
			(xy 379.480572 -408.594052) (xy 379.480143 -408.584867) (xy 379.473643 -408.567682) (xy 379.467872 -408.560524)
			(xy 379.446001 -408.534865) (xy 379.407915 -408.479229) (xy 379.376766 -408.419431) (xy 379.353003 -408.356334)
			(xy 379.336969 -408.290844) (xy 379.328894 -408.223906) (xy 379.328895 -408.156482) (xy 379.336971 -408.089544)
			(xy 379.353007 -408.024055) (xy 379.376771 -407.960958) (xy 379.407921 -407.901161) (xy 379.446009 -407.845526)
			(xy 379.467872 -407.81986) (xy 379.473677 -407.812721) (xy 379.480185 -407.795525) (xy 379.480572 -407.786332)
			(xy 379.480572 -407.628852) (xy 379.481045 -407.618744) (xy 379.488793 -407.60007) (xy 379.503093 -407.585778)
			(xy 379.521771 -407.57804) (xy 379.53188 -407.577544) (xy 380.24816 -407.577544) (xy 380.258259 -407.578117)
			(xy 380.276926 -407.585831) (xy 380.29122 -407.6001) (xy 380.298966 -407.618754) (xy 380.299468 -407.628852)
			(xy 380.299468 -407.786332) (xy 380.29987 -407.79552) (xy 380.30639 -407.812704) (xy 380.312168 -407.81986)
			(xy 380.334025 -407.845531) (xy 380.372116 -407.901164) (xy 380.403269 -407.960959) (xy 380.427035 -408.024055)
			(xy 380.443072 -408.089544) (xy 380.451149 -408.156482) (xy 380.45115 -408.223906) (xy 380.443074 -408.290844)
			(xy 380.427039 -408.356333) (xy 380.403274 -408.41943) (xy 380.372122 -408.479226) (xy 380.334033 -408.534859)
			(xy 380.312168 -408.560524) (xy 380.306375 -408.567671) (xy 380.299859 -408.58486) (xy 380.299468 -408.594052)
			(xy 380.299468 -409.086304) (xy 380.299883 -409.09549) (xy 380.306394 -409.112675) (xy 380.312168 -409.119832)
			(xy 380.333998 -409.145526) (xy 380.37209 -409.201156) (xy 380.403244 -409.260947) (xy 380.427011 -409.324041)
			(xy 380.44305 -409.389527) (xy 380.451129 -409.456462) (xy 380.451133 -409.523884) (xy 380.44306 -409.59082)
			(xy 380.427027 -409.656308) (xy 380.403266 -409.719403) (xy 380.372117 -409.779198) (xy 380.334031 -409.834831)
			(xy 380.312168 -409.860496) (xy 380.306386 -409.867652) (xy 380.299864 -409.884834) (xy 380.299468 -409.894024)
			(xy 380.299468 -410.051504) (xy 380.299086 -410.061631) (xy 380.291331 -410.08034) (xy 380.277003 -410.094656)
			(xy 380.258287 -410.102395) (xy 380.24816 -410.102812) (xy 379.53188 -410.102812) (xy 379.521771 -410.102332)
			(xy 379.503095 -410.09459) (xy 379.488801 -410.080292) (xy 379.481065 -410.061613) (xy 379.480572 -410.051504)
			(xy 379.480572 -409.894024) (xy 379.480157 -409.884837) (xy 379.473647 -409.867652) (xy 379.467872 -409.860496)
			(xy 379.445974 -409.834859) (xy 379.407888 -409.77922) (xy 379.37674 -409.71942) (xy 379.352979 -409.656319)
			(xy 379.336947 -409.590827) (xy 379.328875 -409.523886) (xy 378.200707 -409.523886) (xy 378.171973 -409.579043)
			(xy 378.133884 -409.634678) (xy 378.11202 -409.660344) (xy 378.106225 -409.66749) (xy 378.099709 -409.68468)
			(xy 378.09932 -409.693872) (xy 378.09932 -410.186124) (xy 378.099714 -410.195313) (xy 378.106239 -410.212497)
			(xy 378.11202 -410.219652) (xy 378.133868 -410.245331) (xy 378.171955 -410.300964) (xy 378.203106 -410.360758)
			(xy 378.22687 -410.423853) (xy 378.242906 -410.48934) (xy 378.250983 -410.556277) (xy 378.250984 -410.623641)
			(xy 381.529047 -410.623641) (xy 381.529049 -410.556335) (xy 381.537094 -410.489512) (xy 381.553068 -410.424129)
			(xy 381.576742 -410.361124) (xy 381.607775 -410.3014) (xy 381.645724 -410.245812) (xy 381.667512 -410.22016)
			(xy 381.673309 -410.213015) (xy 381.679823 -410.195824) (xy 381.680212 -410.186632) (xy 381.680212 -409.693364)
			(xy 381.679817 -409.684175) (xy 381.673292 -409.666991) (xy 381.667512 -409.659836) (xy 381.645737 -409.634174)
			(xy 381.607789 -409.578588) (xy 381.576757 -409.518866) (xy 381.553085 -409.455863) (xy 381.537112 -409.390482)
			(xy 381.529067 -409.323661) (xy 381.529066 -409.256357) (xy 381.537109 -409.189536) (xy 381.553079 -409.124155)
			(xy 381.57675 -409.061151) (xy 381.60778 -409.001427) (xy 381.645726 -408.94584) (xy 381.667512 -408.920188)
			(xy 381.673298 -408.913035) (xy 381.679818 -408.89585) (xy 381.680212 -408.88666) (xy 381.680212 -408.728672)
			(xy 381.680662 -408.71856) (xy 381.688411 -408.699879) (xy 381.702719 -408.685585) (xy 381.721408 -408.677853)
			(xy 381.73152 -408.677364) (xy 382.448054 -408.677364) (xy 382.458181 -408.677865) (xy 382.476905 -408.685582)
			(xy 382.491264 -408.699865) (xy 382.499081 -408.718548) (xy 382.499616 -408.728672) (xy 382.499616 -408.88666)
			(xy 382.500042 -408.895846) (xy 382.506544 -408.91303) (xy 382.512316 -408.920188) (xy 382.534117 -408.94583)
			(xy 382.572068 -409.001417) (xy 382.603103 -409.061141) (xy 382.626778 -409.124147) (xy 382.642751 -409.189531)
			(xy 382.650795 -409.256356) (xy 382.650794 -409.323662) (xy 382.642748 -409.390487) (xy 382.626772 -409.45587)
			(xy 382.603096 -409.518875) (xy 382.600523 -409.523827) (xy 383.72917 -409.523827) (xy 383.729173 -409.456519)
			(xy 383.737221 -409.389693) (xy 383.753198 -409.324309) (xy 383.776876 -409.261303) (xy 383.807915 -409.201578)
			(xy 383.845869 -409.145992) (xy 383.86766 -409.12034) (xy 383.873472 -409.113206) (xy 383.879976 -409.096007)
			(xy 383.88036 -409.086812) (xy 383.88036 -408.593544) (xy 383.879915 -408.584361) (xy 383.873424 -408.567177)
			(xy 383.86766 -408.560016) (xy 383.845864 -408.53437) (xy 383.807914 -408.478784) (xy 383.77688 -408.419059)
			(xy 383.753207 -408.356054) (xy 383.737234 -408.290671) (xy 383.72919 -408.223847) (xy 383.729191 -408.156541)
			(xy 383.737236 -408.089717) (xy 383.75321 -408.024335) (xy 383.776885 -407.96133) (xy 383.80792 -407.901606)
			(xy 383.845871 -407.84602) (xy 383.86766 -407.820368) (xy 383.87346 -407.813226) (xy 383.879971 -407.796033)
			(xy 383.88036 -407.78684) (xy 383.88036 -407.628852) (xy 383.880845 -407.618745) (xy 383.888591 -407.600074)
			(xy 383.902887 -407.585782) (xy 383.921561 -407.578042) (xy 383.931668 -407.577544) (xy 384.648202 -407.577544)
			(xy 384.658329 -407.578025) (xy 384.677051 -407.585754) (xy 384.691408 -407.600042) (xy 384.699226 -407.618727)
			(xy 384.699764 -407.628852) (xy 384.699764 -407.78684) (xy 384.700163 -407.796028) (xy 384.706685 -407.813212)
			(xy 384.712464 -407.820368) (xy 384.734244 -407.846027) (xy 384.772193 -407.901612) (xy 384.803226 -407.961335)
			(xy 384.826899 -408.024339) (xy 384.842873 -408.08972) (xy 384.850918 -408.156542) (xy 384.850918 -408.223846)
			(xy 384.842875 -408.290668) (xy 384.826903 -408.35605) (xy 384.803231 -408.419054) (xy 384.772199 -408.478778)
			(xy 384.734251 -408.534364) (xy 384.712464 -408.560016) (xy 384.706674 -408.567165) (xy 384.700156 -408.584353)
			(xy 384.699764 -408.593544) (xy 384.699764 -409.086812) (xy 384.700176 -409.095999) (xy 384.706689 -409.113183)
			(xy 384.712464 -409.12034) (xy 384.734216 -409.146021) (xy 384.772166 -409.201604) (xy 384.8032 -409.261323)
			(xy 384.826875 -409.324324) (xy 384.84285 -409.389703) (xy 384.850897 -409.456522) (xy 384.850901 -409.523824)
			(xy 384.84286 -409.590644) (xy 384.826891 -409.656024) (xy 384.803222 -409.719027) (xy 384.772194 -409.77875)
			(xy 384.734249 -409.834336) (xy 384.712464 -409.859988) (xy 384.706643 -409.867116) (xy 384.700144 -409.88432)
			(xy 384.699764 -409.893516) (xy 384.699764 -410.051504) (xy 384.699386 -410.061631) (xy 384.69163 -410.080342)
			(xy 384.677301 -410.094657) (xy 384.658584 -410.102396) (xy 384.648456 -410.102812) (xy 383.931922 -410.102812)
			(xy 383.921803 -410.102257) (xy 383.903092 -410.094546) (xy 383.888737 -410.080281) (xy 383.880908 -410.06162)
			(xy 383.88036 -410.051504) (xy 383.88036 -409.893516) (xy 383.879929 -409.884331) (xy 383.873428 -409.867147)
			(xy 383.86766 -409.859988) (xy 383.845836 -409.834365) (xy 383.807887 -409.778775) (xy 383.776854 -409.719048)
			(xy 383.753182 -409.656039) (xy 383.737211 -409.590653) (xy 383.72917 -409.523827) (xy 382.600523 -409.523827)
			(xy 382.572059 -409.578599) (xy 382.534106 -409.634184) (xy 382.512316 -409.659836) (xy 382.506523 -409.666984)
			(xy 382.500006 -409.684172) (xy 382.499616 -409.693364) (xy 382.499616 -410.186632) (xy 382.500007 -410.195821)
			(xy 382.506534 -410.213006) (xy 382.512316 -410.22016) (xy 382.534089 -410.245824) (xy 382.572042 -410.301408)
			(xy 382.603078 -410.36113) (xy 382.626754 -410.424133) (xy 382.642729 -410.489514) (xy 382.650775 -410.556336)
			(xy 382.650777 -410.62364) (xy 382.65077 -410.623701) (xy 385.928816 -410.623701) (xy 385.928817 -410.556275)
			(xy 385.936895 -410.489336) (xy 385.952932 -410.423846) (xy 385.976699 -410.360748) (xy 386.007852 -410.300952)
			(xy 386.045943 -410.245317) (xy 386.067808 -410.219652) (xy 386.073608 -410.21251) (xy 386.080121 -410.195317)
			(xy 386.080508 -410.186124) (xy 386.080508 -409.693872) (xy 386.08011 -409.684684) (xy 386.073588 -409.667499)
			(xy 386.067808 -409.660344) (xy 386.045956 -409.634669) (xy 386.007866 -409.579036) (xy 385.976714 -409.519241)
			(xy 385.952949 -409.456146) (xy 385.936913 -409.390658) (xy 385.928836 -409.32372) (xy 385.928834 -409.256298)
			(xy 385.936909 -409.18936) (xy 385.952944 -409.123871) (xy 385.976707 -409.060775) (xy 386.007857 -409.000979)
			(xy 386.045944 -408.945345) (xy 386.067808 -408.91968) (xy 386.073596 -408.912529) (xy 386.080116 -408.895343)
			(xy 386.080508 -408.886152) (xy 386.080508 -408.728672) (xy 386.080962 -408.71856) (xy 386.088711 -408.69988)
			(xy 386.103017 -408.685586) (xy 386.121704 -408.677854) (xy 386.131816 -408.677364) (xy 386.848096 -408.677364)
			(xy 386.8582 -408.677888) (xy 386.876871 -408.685617) (xy 386.891165 -408.699902) (xy 386.898906 -408.718568)
			(xy 386.899404 -408.728672) (xy 386.899404 -408.886152) (xy 386.899836 -408.895337) (xy 386.906334 -408.912522)
			(xy 386.912104 -408.91968) (xy 386.93398 -408.945336) (xy 386.972068 -409.000972) (xy 387.003218 -409.060769)
			(xy 387.026981 -409.123867) (xy 387.043016 -409.189357) (xy 387.05109 -409.256297) (xy 387.051089 -409.323721)
			(xy 387.043012 -409.39066) (xy 387.026976 -409.45615) (xy 387.00321 -409.519247) (xy 387.000824 -409.523827)
			(xy 388.128961 -409.523827) (xy 388.128964 -409.456519) (xy 388.137012 -409.389694) (xy 388.152989 -409.324309)
			(xy 388.176666 -409.261303) (xy 388.207704 -409.201579) (xy 388.245658 -409.145992) (xy 388.267448 -409.12034)
			(xy 388.273259 -409.113205) (xy 388.279764 -409.096006) (xy 388.280148 -409.086812) (xy 388.280148 -408.593544)
			(xy 388.279706 -408.58436) (xy 388.273213 -408.567176) (xy 388.267448 -408.560016) (xy 388.245652 -408.534371)
			(xy 388.207703 -408.478783) (xy 388.176669 -408.419059) (xy 388.152997 -408.356054) (xy 388.137024 -408.29067)
			(xy 388.12898 -408.223847) (xy 388.128981 -408.156541) (xy 388.137026 -408.089718) (xy 388.153 -408.024335)
			(xy 388.176674 -407.96133) (xy 388.207709 -407.901606) (xy 388.245659 -407.84602) (xy 388.267448 -407.820368)
			(xy 388.273247 -407.813224) (xy 388.279759 -407.796032) (xy 388.280148 -407.78684) (xy 388.280148 -407.628852)
			(xy 388.280645 -407.618747) (xy 388.288388 -407.600077) (xy 388.302681 -407.585786) (xy 388.321351 -407.578044)
			(xy 388.331456 -407.577544) (xy 389.04799 -407.577544) (xy 389.058117 -407.578035) (xy 389.076838 -407.58576)
			(xy 389.091195 -407.600045) (xy 389.099014 -407.618728) (xy 389.099552 -407.628852) (xy 389.099552 -407.78684)
			(xy 389.099954 -407.796028) (xy 389.106475 -407.813211) (xy 389.112252 -407.820368) (xy 389.134032 -407.846027)
			(xy 389.171982 -407.901612) (xy 389.203016 -407.961335) (xy 389.226689 -408.024338) (xy 389.242663 -408.08972)
			(xy 389.250708 -408.156542) (xy 389.250709 -408.223846) (xy 389.242665 -408.290668) (xy 389.226693 -408.35605)
			(xy 389.203021 -408.419054) (xy 389.171988 -408.478778) (xy 389.134039 -408.534364) (xy 389.112252 -408.560016)
			(xy 389.10646 -408.567164) (xy 389.099944 -408.584353) (xy 389.099552 -408.593544) (xy 389.099552 -409.086812)
			(xy 389.099967 -409.095998) (xy 389.106479 -409.113182) (xy 389.112252 -409.12034) (xy 389.134004 -409.146021)
			(xy 389.171955 -409.201603) (xy 389.20299 -409.261323) (xy 389.226665 -409.324323) (xy 389.242641 -409.389702)
			(xy 389.250688 -409.456522) (xy 389.250692 -409.523824) (xy 389.242651 -409.590644) (xy 389.226681 -409.656025)
			(xy 389.203012 -409.719028) (xy 389.171983 -409.77875) (xy 389.134038 -409.834336) (xy 389.112252 -409.859988)
			(xy 389.10643 -409.867115) (xy 389.099932 -409.88432) (xy 389.099552 -409.893516) (xy 389.099552 -410.051504)
			(xy 389.099019 -410.061607) (xy 389.09129 -410.080275) (xy 389.077008 -410.094568) (xy 389.058346 -410.102311)
			(xy 389.048244 -410.102812) (xy 388.33171 -410.102812) (xy 388.32159 -410.102267) (xy 388.302879 -410.094552)
			(xy 388.288524 -410.080284) (xy 388.280696 -410.061621) (xy 388.280148 -410.051504) (xy 388.280148 -409.893516)
			(xy 388.27972 -409.884331) (xy 388.273217 -409.867147) (xy 388.267448 -409.859988) (xy 388.245624 -409.834365)
			(xy 388.207676 -409.778775) (xy 388.176644 -409.719047) (xy 388.152973 -409.656039) (xy 388.137002 -409.590653)
			(xy 388.128961 -409.523827) (xy 387.000824 -409.523827) (xy 386.972058 -409.579044) (xy 386.933969 -409.634679)
			(xy 386.912104 -409.660344) (xy 386.906307 -409.667489) (xy 386.899792 -409.68468) (xy 386.899404 -409.693872)
			(xy 386.899404 -410.186124) (xy 386.899801 -410.195313) (xy 386.906324 -410.212497) (xy 386.912104 -410.219652)
			(xy 386.933952 -410.24533) (xy 386.972041 -410.300963) (xy 387.003192 -410.360757) (xy 387.026957 -410.423853)
			(xy 387.042994 -410.48934) (xy 387.051071 -410.556277) (xy 387.051072 -410.623641) (xy 390.329135 -410.623641)
			(xy 390.329137 -410.556335) (xy 390.337182 -410.489512) (xy 390.353155 -410.42413) (xy 390.376828 -410.361125)
			(xy 390.407861 -410.3014) (xy 390.445809 -410.245813) (xy 390.467596 -410.22016) (xy 390.473392 -410.213014)
			(xy 390.479907 -410.195824) (xy 390.480296 -410.186632) (xy 390.480296 -409.693364) (xy 390.479904 -409.684175)
			(xy 390.473378 -409.666991) (xy 390.467596 -409.659836) (xy 390.445821 -409.634174) (xy 390.407875 -409.578588)
			(xy 390.376844 -409.518865) (xy 390.353172 -409.455862) (xy 390.3372 -409.390481) (xy 390.329155 -409.323661)
			(xy 390.329154 -409.256357) (xy 390.337196 -409.189536) (xy 390.353167 -409.124155) (xy 390.376836 -409.061151)
			(xy 390.407866 -409.001428) (xy 390.44581 -408.945841) (xy 390.467596 -408.920188) (xy 390.47338 -408.913034)
			(xy 390.479902 -408.89585) (xy 390.480296 -408.88666) (xy 390.480296 -408.728672) (xy 390.480762 -408.718562)
			(xy 390.488508 -408.699884) (xy 390.502811 -408.68559) (xy 390.521494 -408.677856) (xy 390.531604 -408.677364)
			(xy 391.248138 -408.677364) (xy 391.25827 -408.677796) (xy 391.276997 -408.685541) (xy 391.291352 -408.699844)
			(xy 391.299166 -408.718542) (xy 391.2997 -408.728672) (xy 391.2997 -408.88666) (xy 391.300129 -408.895845)
			(xy 391.30663 -408.91303) (xy 391.3124 -408.920188) (xy 391.334198 -408.945831) (xy 391.372144 -409.00142)
			(xy 391.403175 -409.061145) (xy 391.426845 -409.12415) (xy 391.442816 -409.189533) (xy 391.450859 -409.256356)
			(xy 391.450858 -409.323662) (xy 391.442813 -409.390484) (xy 391.42684 -409.455867) (xy 391.403167 -409.518872)
			(xy 391.372135 -409.578596) (xy 391.334187 -409.634183) (xy 391.3124 -409.659836) (xy 391.306606 -409.666983)
			(xy 391.30009 -409.684172) (xy 391.2997 -409.693364) (xy 391.2997 -410.186632) (xy 391.300095 -410.195821)
			(xy 391.306619 -410.213005) (xy 391.3124 -410.22016) (xy 391.334171 -410.245826) (xy 391.372118 -410.301411)
			(xy 391.403149 -410.361133) (xy 391.426821 -410.424136) (xy 391.442794 -410.489516) (xy 391.450839 -410.556336)
			(xy 391.450841 -410.623639) (xy 391.442799 -410.69046) (xy 391.426828 -410.755841) (xy 391.403159 -410.818845)
			(xy 391.37213 -410.878568) (xy 391.334186 -410.934155) (xy 391.3124 -410.959808) (xy 391.306618 -410.966963)
			(xy 391.300094 -410.984146) (xy 391.2997 -410.993336) (xy 391.2997 -411.151324) (xy 391.299235 -411.161434)
			(xy 391.291489 -411.180113) (xy 391.277186 -411.194407) (xy 391.258503 -411.202141) (xy 391.248392 -411.202632)
			(xy 390.531858 -411.202632) (xy 390.521725 -411.202207) (xy 390.502998 -411.19446) (xy 390.488642 -411.180155)
			(xy 390.480829 -411.161455) (xy 390.480296 -411.151324) (xy 390.480296 -410.993336) (xy 390.479869 -410.984151)
			(xy 390.473367 -410.966966) (xy 390.467596 -410.959808) (xy 390.445794 -410.934168) (xy 390.407848 -410.878579)
			(xy 390.376818 -410.818853) (xy 390.353148 -410.755847) (xy 390.337178 -410.690464) (xy 390.329135 -410.623641)
			(xy 387.051072 -410.623641) (xy 387.051072 -410.623699) (xy 387.042998 -410.690636) (xy 387.026964 -410.756124)
			(xy 387.003202 -410.819221) (xy 386.972053 -410.879016) (xy 386.933967 -410.934651) (xy 386.912104 -410.960316)
			(xy 386.906319 -410.967469) (xy 386.899797 -410.984654) (xy 386.899404 -410.993844) (xy 386.899404 -411.151324)
			(xy 386.898935 -411.161434) (xy 386.89119 -411.180112) (xy 386.876888 -411.194406) (xy 386.858206 -411.20214)
			(xy 386.848096 -411.202632) (xy 386.131816 -411.202632) (xy 386.121712 -411.202103) (xy 386.10304 -411.194376)
			(xy 386.088746 -411.180093) (xy 386.081005 -411.161427) (xy 386.080508 -411.151324) (xy 386.080508 -410.993844)
			(xy 386.080075 -410.984659) (xy 386.073577 -410.967475) (xy 386.067808 -410.960316) (xy 386.045928 -410.934664)
			(xy 386.007839 -410.879028) (xy 385.976689 -410.81923) (xy 385.952925 -410.756131) (xy 385.936891 -410.69064)
			(xy 385.928816 -410.623701) (xy 382.65077 -410.623701) (xy 382.642733 -410.690463) (xy 382.626761 -410.755844)
			(xy 382.603088 -410.818848) (xy 382.572054 -410.878571) (xy 382.534104 -410.934156) (xy 382.512316 -410.959808)
			(xy 382.506535 -410.966965) (xy 382.500011 -410.984146) (xy 382.499616 -410.993336) (xy 382.499616 -411.151324)
			(xy 382.499135 -411.161432) (xy 382.491392 -411.180108) (xy 382.477095 -411.194401) (xy 382.458416 -411.202138)
			(xy 382.448308 -411.202632) (xy 381.731774 -411.202632) (xy 381.721642 -411.202194) (xy 381.702915 -411.194453)
			(xy 381.688559 -411.180151) (xy 381.680745 -411.161454) (xy 381.680212 -411.151324) (xy 381.680212 -410.993336)
			(xy 381.679782 -410.984151) (xy 381.673282 -410.966967) (xy 381.667512 -410.959808) (xy 381.645709 -410.934168)
			(xy 381.607763 -410.87858) (xy 381.576732 -410.818854) (xy 381.553061 -410.755848) (xy 381.53709 -410.690464)
			(xy 381.529047 -410.623641) (xy 378.250984 -410.623641) (xy 378.250984 -410.623699) (xy 378.24291 -410.690636)
			(xy 378.226877 -410.756124) (xy 378.203116 -410.81922) (xy 378.171968 -410.879016) (xy 378.133882 -410.93465)
			(xy 378.11202 -410.960316) (xy 378.106236 -410.967471) (xy 378.099713 -410.984654) (xy 378.09932 -410.993844)
			(xy 378.09932 -411.151324) (xy 378.098835 -411.161432) (xy 378.091093 -411.180107) (xy 378.076797 -411.1944)
			(xy 378.05812 -411.202138) (xy 378.048012 -411.202632) (xy 377.331732 -411.202632) (xy 377.321615 -411.202159)
			(xy 377.302919 -411.194427) (xy 377.288604 -411.180128) (xy 377.280852 -411.16144) (xy 377.280424 -411.151324)
			(xy 377.280424 -410.993844) (xy 377.279987 -410.98466) (xy 377.273491 -410.967475) (xy 377.267724 -410.960316)
			(xy 377.245843 -410.934664) (xy 377.207754 -410.879028) (xy 377.176602 -410.81923) (xy 377.152838 -410.756132)
			(xy 377.136803 -410.690641) (xy 377.128728 -410.623701) (xy 347.450924 -410.623701) (xy 347.442889 -410.690461)
			(xy 347.426919 -410.755842) (xy 347.403249 -410.818845) (xy 347.372219 -410.878569) (xy 347.334274 -410.934156)
			(xy 347.312488 -410.959808) (xy 347.306704 -410.966962) (xy 347.300182 -410.984146) (xy 347.299788 -410.993336)
			(xy 347.299788 -411.151324) (xy 347.299398 -411.161481) (xy 347.291592 -411.180236) (xy 347.277186 -411.194559)
			(xy 347.258386 -411.202256) (xy 347.248226 -411.202632) (xy 346.531946 -411.202632) (xy 346.521819 -411.202135)
			(xy 346.503093 -411.194417) (xy 346.488735 -411.180133) (xy 346.480919 -411.161449) (xy 346.480384 -411.151324)
			(xy 346.480384 -410.993336) (xy 346.47996 -410.98415) (xy 346.473456 -410.966965) (xy 346.467684 -410.959808)
			(xy 346.445879 -410.934169) (xy 346.407928 -410.878582) (xy 346.376893 -410.818857) (xy 346.353219 -410.755851)
			(xy 346.337246 -410.690466) (xy 346.329202 -410.623642) (xy 343.051163 -410.623642) (xy 343.051163 -410.623699)
			(xy 343.043089 -410.690637) (xy 343.027055 -410.756125) (xy 343.003292 -410.819221) (xy 342.972143 -410.879017)
			(xy 342.934055 -410.934651) (xy 342.912192 -410.960316) (xy 342.906405 -410.967468) (xy 342.899885 -410.984653)
			(xy 342.899492 -410.993844) (xy 342.899492 -411.151324) (xy 342.899034 -411.161435) (xy 342.891287 -411.180116)
			(xy 342.876982 -411.19441) (xy 342.858296 -411.202142) (xy 342.848184 -411.202632) (xy 342.131904 -411.202632)
			(xy 342.121799 -411.202112) (xy 342.103128 -411.194382) (xy 342.088834 -411.180096) (xy 342.081093 -411.161428)
			(xy 342.080596 -411.151324) (xy 342.080596 -410.993844) (xy 342.080166 -410.984659) (xy 342.073666 -410.967474)
			(xy 342.067896 -410.960316) (xy 342.046016 -410.934664) (xy 342.007928 -410.879027) (xy 341.976779 -410.819229)
			(xy 341.953016 -410.756131) (xy 341.936981 -410.69064) (xy 341.928907 -410.6237) (xy 338.650837 -410.6237)
			(xy 338.642802 -410.69046) (xy 338.626832 -410.755841) (xy 338.603163 -410.818845) (xy 338.572134 -410.878568)
			(xy 338.534189 -410.934155) (xy 338.512404 -410.959808) (xy 338.506622 -410.966964) (xy 338.500098 -410.984146)
			(xy 338.499704 -410.993336) (xy 338.499704 -411.151324) (xy 338.499298 -411.161479) (xy 338.491495 -411.180231)
			(xy 338.477094 -411.194554) (xy 338.458299 -411.202253) (xy 338.448142 -411.202632) (xy 337.731862 -411.202632)
			(xy 337.721729 -411.202204) (xy 337.703002 -411.194458) (xy 337.688646 -411.180154) (xy 337.680833 -411.161455)
			(xy 337.6803 -411.151324) (xy 337.6803 -410.993336) (xy 337.679873 -410.984151) (xy 337.673371 -410.966966)
			(xy 337.6676 -410.959808) (xy 337.645798 -410.934168) (xy 337.607852 -410.878579) (xy 337.576822 -410.818853)
			(xy 337.553151 -410.755847) (xy 337.537181 -410.690464) (xy 337.529138 -410.623641) (xy 334.251075 -410.623641)
			(xy 334.251075 -410.623699) (xy 334.243001 -410.690636) (xy 334.226967 -410.756124) (xy 334.203205 -410.81922)
			(xy 334.172057 -410.879016) (xy 334.133971 -410.934651) (xy 334.112108 -410.960316) (xy 334.106323 -410.96747)
			(xy 334.099801 -410.984654) (xy 334.099408 -410.993844) (xy 334.099408 -411.151324) (xy 334.098935 -411.161433)
			(xy 334.091191 -411.180111) (xy 334.07689 -411.194404) (xy 334.05821 -411.20214) (xy 334.0481 -411.202632)
			(xy 333.33182 -411.202632) (xy 333.321716 -411.202099) (xy 333.303045 -411.194374) (xy 333.28875 -411.180092)
			(xy 333.281009 -411.161427) (xy 333.280512 -411.151324) (xy 333.280512 -410.993844) (xy 333.280078 -410.984659)
			(xy 333.273581 -410.967475) (xy 333.267812 -410.960316) (xy 333.245932 -410.934664) (xy 333.207843 -410.879028)
			(xy 333.176692 -410.81923) (xy 333.152928 -410.756131) (xy 333.136894 -410.69064) (xy 333.128819 -410.623701)
			(xy 326.525636 -410.623701) (xy 326.525636 -417.379404) (xy 326.525636 -417.533836) (xy 401.074128 -417.533836)
			(xy 401.074128 -417.366196) (xy 401.074128 -394.27912) (xy 414.451292 -394.27912) (xy 414.525968 -394.353542)
			(xy 414.525968 -397.823826) (xy 418.92899 -397.823826) (xy 418.928993 -397.756517) (xy 418.937042 -397.689691)
			(xy 418.95302 -397.624306) (xy 418.9767 -397.5613) (xy 419.00774 -397.501575) (xy 419.045697 -397.44599)
			(xy 419.067488 -397.420338) (xy 419.073292 -397.413198) (xy 419.079803 -397.396004) (xy 419.080188 -397.38681)
			(xy 419.080188 -396.893542) (xy 419.07976 -396.884357) (xy 419.073259 -396.867172) (xy 419.067488 -396.860014)
			(xy 419.045689 -396.834371) (xy 419.007737 -396.778784) (xy 418.976702 -396.71906) (xy 418.953027 -396.656054)
			(xy 418.937054 -396.59067) (xy 418.92901 -396.523846) (xy 418.92901 -396.456539) (xy 418.937056 -396.389715)
			(xy 418.953032 -396.324332) (xy 418.976708 -396.261327) (xy 419.007745 -396.201603) (xy 419.045698 -396.146018)
			(xy 419.067488 -396.120366) (xy 419.07328 -396.113218) (xy 419.079798 -396.09603) (xy 419.080188 -396.086838)
			(xy 419.080188 -395.92885) (xy 419.080606 -395.918675) (xy 419.088384 -395.899872) (xy 419.102772 -395.885484)
			(xy 419.121575 -395.877706) (xy 419.13175 -395.877288) (xy 419.84803 -395.877288) (xy 419.85821 -395.87764)
			(xy 419.877015 -395.885445) (xy 419.8914 -395.899852) (xy 419.899175 -395.91867) (xy 419.899592 -395.92885)
			(xy 419.899592 -396.086838) (xy 419.899986 -396.096027) (xy 419.906511 -396.113211) (xy 419.912292 -396.120366)
			(xy 419.934069 -396.146027) (xy 419.972016 -396.201613) (xy 420.003048 -396.261335) (xy 420.02672 -396.324339)
			(xy 420.042693 -396.389719) (xy 420.050737 -396.456541) (xy 420.050738 -396.523844) (xy 420.042695 -396.590666)
			(xy 420.026725 -396.656047) (xy 420.003054 -396.719051) (xy 419.972024 -396.778774) (xy 419.934078 -396.834361)
			(xy 419.912292 -396.860014) (xy 419.906506 -396.867167) (xy 419.899985 -396.884351) (xy 419.899592 -396.893542)
			(xy 419.899592 -397.38681) (xy 419.899999 -397.395998) (xy 419.906515 -397.413182) (xy 419.912292 -397.420338)
			(xy 419.934041 -397.446021) (xy 419.971989 -397.501604) (xy 420.00041 -397.556296) (xy 421.128654 -397.556296)
			(xy 421.13673 -397.489357) (xy 421.152765 -397.423869) (xy 421.17653 -397.360772) (xy 421.207681 -397.300976)
			(xy 421.245771 -397.245343) (xy 421.267636 -397.219678) (xy 421.273429 -397.21253) (xy 421.279945 -397.195342)
			(xy 421.280336 -397.18615) (xy 421.280336 -397.028924) (xy 421.280736 -397.018799) (xy 421.288483 -397.000089)
			(xy 421.302805 -396.985772) (xy 421.321518 -396.978032) (xy 421.331644 -396.977616) (xy 422.047924 -396.977616)
			(xy 422.058036 -396.978066) (xy 422.076718 -396.985814) (xy 422.091013 -397.000122) (xy 422.098744 -397.018811)
			(xy 422.099232 -397.028924) (xy 422.099232 -397.18615) (xy 422.099681 -397.195333) (xy 422.106169 -397.212517)
			(xy 422.111932 -397.219678) (xy 422.133805 -397.245336) (xy 422.171891 -397.300972) (xy 422.203039 -397.36077)
			(xy 422.226802 -397.423867) (xy 422.242835 -397.489357) (xy 422.25091 -397.556296) (xy 422.250909 -397.623719)
			(xy 422.242833 -397.690658) (xy 422.226797 -397.756147) (xy 422.203033 -397.819244) (xy 422.200615 -397.823885)
			(xy 423.328782 -397.823885) (xy 423.328786 -397.756458) (xy 423.336865 -397.689518) (xy 423.352904 -397.624027)
			(xy 423.376672 -397.560928) (xy 423.407826 -397.501131) (xy 423.445918 -397.445496) (xy 423.467784 -397.41983)
			(xy 423.473591 -397.412692) (xy 423.4801 -397.395496) (xy 423.480484 -397.386302) (xy 423.480484 -396.89405)
			(xy 423.480054 -396.884865) (xy 423.473554 -396.86768) (xy 423.467784 -396.860522) (xy 423.445911 -396.834865)
			(xy 423.407823 -396.779229) (xy 423.376674 -396.719431) (xy 423.352911 -396.656333) (xy 423.336877 -396.590843)
			(xy 423.328802 -396.523905) (xy 423.328803 -396.45648) (xy 423.33688 -396.389542) (xy 423.352916 -396.324052)
			(xy 423.37668 -396.260955) (xy 423.407831 -396.201159) (xy 423.44592 -396.145524) (xy 423.467784 -396.119858)
			(xy 423.473579 -396.112712) (xy 423.480095 -396.095522) (xy 423.480484 -396.08633) (xy 423.480484 -395.92885)
			(xy 423.480969 -395.918721) (xy 423.488688 -395.899993) (xy 423.502976 -395.885633) (xy 423.521666 -395.87782)
			(xy 423.531792 -395.877288) (xy 424.248072 -395.877288) (xy 424.258223 -395.877744) (xy 424.276972 -395.885528)
			(xy 424.291296 -395.899914) (xy 424.298999 -395.918697) (xy 424.29938 -395.92885) (xy 424.29938 -396.08633)
			(xy 424.29978 -396.095518) (xy 424.306301 -396.112702) (xy 424.31208 -396.119858) (xy 424.333935 -396.145531)
			(xy 424.372025 -396.201164) (xy 424.403177 -396.260959) (xy 424.426943 -396.324055) (xy 424.44298 -396.389543)
			(xy 424.451057 -396.456481) (xy 424.451058 -396.523904) (xy 424.442983 -396.590842) (xy 424.426948 -396.656331)
			(xy 424.403184 -396.719427) (xy 424.372033 -396.779223) (xy 424.333944 -396.834857) (xy 424.31208 -396.860522)
			(xy 424.306289 -396.867671) (xy 424.299772 -396.884859) (xy 424.29938 -396.89405) (xy 424.29938 -397.386302)
			(xy 424.299793 -397.395489) (xy 424.306305 -397.412673) (xy 424.31208 -397.41983) (xy 424.333907 -397.445526)
			(xy 424.371998 -397.501155) (xy 424.40076 -397.556356) (xy 425.528974 -397.556356) (xy 425.537017 -397.489534)
			(xy 425.552988 -397.424152) (xy 425.576659 -397.361148) (xy 425.607691 -397.301425) (xy 425.645637 -397.245838)
			(xy 425.667424 -397.220186) (xy 425.673212 -397.213035) (xy 425.679731 -397.195849) (xy 425.680124 -397.186658)
			(xy 425.680124 -397.028924) (xy 425.680542 -397.018768) (xy 425.688334 -397.000012) (xy 425.702732 -396.985687)
			(xy 425.721528 -396.97799) (xy 425.731686 -396.977616) (xy 426.447966 -396.977616) (xy 426.458088 -396.978154)
			(xy 426.476803 -396.985866) (xy 426.49116 -397.000137) (xy 426.498984 -397.018806) (xy 426.499528 -397.028924)
			(xy 426.499528 -397.186658) (xy 426.499952 -397.195844) (xy 426.506456 -397.213029) (xy 426.512228 -397.220186)
			(xy 426.534026 -397.24583) (xy 426.571977 -397.301417) (xy 426.603012 -397.361141) (xy 426.626685 -397.424147)
			(xy 426.642659 -397.48953) (xy 426.650703 -397.556354) (xy 426.650702 -397.623661) (xy 426.642656 -397.690485)
			(xy 426.626681 -397.755868) (xy 426.603006 -397.818873) (xy 426.600432 -397.823826) (xy 427.729077 -397.823826)
			(xy 427.729081 -397.756517) (xy 427.737129 -397.689691) (xy 427.753107 -397.624307) (xy 427.776786 -397.5613)
			(xy 427.807825 -397.501576) (xy 427.845781 -397.44599) (xy 427.867572 -397.420338) (xy 427.873386 -397.413206)
			(xy 427.879888 -397.396005) (xy 427.880272 -397.38681) (xy 427.880272 -396.893542) (xy 427.879848 -396.884356)
			(xy 427.873344 -396.867171) (xy 427.867572 -396.860014) (xy 427.845774 -396.83437) (xy 427.807823 -396.778783)
			(xy 427.776788 -396.719059) (xy 427.753115 -396.656053) (xy 427.737141 -396.59067) (xy 427.729097 -396.523846)
			(xy 427.729098 -396.456539) (xy 427.737144 -396.389715) (xy 427.753119 -396.324332) (xy 427.776794 -396.261327)
			(xy 427.807831 -396.201604) (xy 427.845783 -396.146018) (xy 427.867572 -396.120366) (xy 427.873374 -396.113225)
			(xy 427.879883 -396.096031) (xy 427.880272 -396.086838) (xy 427.880272 -395.92885) (xy 427.880706 -395.918677)
			(xy 427.88848 -395.899877) (xy 427.902864 -395.885489) (xy 427.921662 -395.877709) (xy 427.931834 -395.877288)
			(xy 428.648114 -395.877288) (xy 428.658293 -395.877654) (xy 428.677097 -395.885453) (xy 428.691483 -395.899857)
			(xy 428.699259 -395.918671) (xy 428.699676 -395.92885) (xy 428.699676 -396.086838) (xy 428.700073 -396.096026)
			(xy 428.706596 -396.11321) (xy 428.712376 -396.120366) (xy 428.734154 -396.146026) (xy 428.772102 -396.201612)
			(xy 428.803135 -396.261335) (xy 428.826807 -396.324338) (xy 428.84278 -396.389719) (xy 428.850825 -396.45654)
			(xy 428.850826 -396.523844) (xy 428.842783 -396.590666) (xy 428.826812 -396.656048) (xy 428.803141 -396.719052)
			(xy 428.772109 -396.778775) (xy 428.734163 -396.834362) (xy 428.712376 -396.860014) (xy 428.706588 -396.867165)
			(xy 428.700069 -396.884351) (xy 428.699676 -396.893542) (xy 428.699676 -397.38681) (xy 428.700087 -397.395997)
			(xy 428.7066 -397.413181) (xy 428.712376 -397.420338) (xy 428.734126 -397.446021) (xy 428.772075 -397.501604)
			(xy 428.800497 -397.556296) (xy 429.928742 -397.556296) (xy 429.936817 -397.489358) (xy 429.952852 -397.423869)
			(xy 429.976616 -397.360773) (xy 430.007767 -397.300977) (xy 430.045856 -397.245343) (xy 430.06772 -397.219678)
			(xy 430.073511 -397.212529) (xy 430.080028 -397.195341) (xy 430.08042 -397.18615) (xy 430.08042 -397.028924)
			(xy 430.080836 -397.018801) (xy 430.08858 -397.000094) (xy 430.102897 -396.985778) (xy 430.121605 -396.978035)
			(xy 430.131728 -396.977616) (xy 430.848008 -396.977616) (xy 430.858133 -396.97801) (xy 430.87684 -396.985764)
			(xy 430.891154 -397.000087) (xy 430.898896 -397.018799) (xy 430.899316 -397.028924) (xy 430.899316 -397.18615)
			(xy 430.899746 -397.195335) (xy 430.906246 -397.21252) (xy 430.912016 -397.219678) (xy 430.933889 -397.245335)
			(xy 430.971977 -397.300971) (xy 431.003126 -397.360769) (xy 431.026889 -397.423867) (xy 431.042923 -397.489357)
			(xy 431.050998 -397.556295) (xy 431.050997 -397.62372) (xy 431.04292 -397.690658) (xy 431.026884 -397.756148)
			(xy 431.00312 -397.819245) (xy 431.000734 -397.823826) (xy 432.128868 -397.823826) (xy 432.128872 -397.756517)
			(xy 432.13692 -397.689692) (xy 432.152898 -397.624307) (xy 432.176576 -397.561301) (xy 432.207614 -397.501576)
			(xy 432.245569 -397.44599) (xy 432.26736 -397.420338) (xy 432.273173 -397.413205) (xy 432.279676 -397.396005)
			(xy 432.28006 -397.38681) (xy 432.28006 -396.893542) (xy 432.279616 -396.884359) (xy 432.273125 -396.867175)
			(xy 432.26736 -396.860014) (xy 432.245562 -396.83437) (xy 432.207612 -396.778783) (xy 432.176578 -396.719058)
			(xy 432.152905 -396.656053) (xy 432.136932 -396.590669) (xy 432.128888 -396.523846) (xy 432.128889 -396.456539)
			(xy 432.136935 -396.389716) (xy 432.152909 -396.324333) (xy 432.176584 -396.261328) (xy 432.20762 -396.201604)
			(xy 432.245571 -396.146018) (xy 432.26736 -396.120366) (xy 432.273161 -396.113224) (xy 432.279671 -396.096031)
			(xy 432.28006 -396.086838) (xy 432.28006 -395.92885) (xy 432.280505 -395.918679) (xy 432.288278 -395.899881)
			(xy 432.302658 -395.885494) (xy 432.321451 -395.877711) (xy 432.331622 -395.877288) (xy 433.047902 -395.877288)
			(xy 433.05808 -395.877663) (xy 433.076884 -395.885458) (xy 433.091271 -395.899859) (xy 433.099047 -395.918672)
			(xy 433.099464 -395.92885) (xy 433.099464 -396.086838) (xy 433.099864 -396.096026) (xy 433.106386 -396.11321)
			(xy 433.112164 -396.120366) (xy 433.133942 -396.146026) (xy 433.171891 -396.201612) (xy 433.202924 -396.261334)
			(xy 433.226598 -396.324337) (xy 433.242571 -396.389719) (xy 433.250616 -396.45654) (xy 433.250617 -396.523845)
			(xy 433.242574 -396.590666) (xy 433.226602 -396.656048) (xy 433.202931 -396.719052) (xy 433.171899 -396.778776)
			(xy 433.133951 -396.834362) (xy 433.112164 -396.860014) (xy 433.106374 -396.867164) (xy 433.099856 -396.884351)
			(xy 433.099464 -396.893542) (xy 433.099464 -397.38681) (xy 433.099877 -397.395997) (xy 433.10639 -397.413181)
			(xy 433.112164 -397.420338) (xy 433.133914 -397.446021) (xy 433.171864 -397.501603) (xy 433.200318 -397.556356)
			(xy 434.329062 -397.556356) (xy 434.337105 -397.489534) (xy 434.353075 -397.424153) (xy 434.376746 -397.361149)
			(xy 434.407776 -397.301426) (xy 434.445722 -397.245839) (xy 434.467508 -397.220186) (xy 434.473294 -397.213033)
			(xy 434.479815 -397.195849) (xy 434.480208 -397.186658) (xy 434.480208 -397.028924) (xy 434.480641 -397.01877)
			(xy 434.48843 -397.000017) (xy 434.502824 -396.985692) (xy 434.521614 -396.977993) (xy 434.53177 -396.977616)
			(xy 435.24805 -396.977616) (xy 435.258171 -396.978167) (xy 435.276886 -396.985874) (xy 435.291243 -397.00014)
			(xy 435.299068 -397.018807) (xy 435.299612 -397.028924) (xy 435.299612 -397.186658) (xy 435.30004 -397.195843)
			(xy 435.306541 -397.213028) (xy 435.312312 -397.220186) (xy 435.334111 -397.245829) (xy 435.372063 -397.301416)
			(xy 435.403098 -397.36114) (xy 435.426773 -397.424146) (xy 435.442746 -397.48953) (xy 435.45079 -397.556354)
			(xy 435.45079 -397.623661) (xy 435.442744 -397.690485) (xy 435.426768 -397.755868) (xy 435.403092 -397.818873)
			(xy 435.372055 -397.878597) (xy 435.334102 -397.934182) (xy 435.312312 -397.959834) (xy 435.30652 -397.966982)
			(xy 435.300002 -397.98417) (xy 435.299612 -397.993362) (xy 435.299612 -398.100042) (xy 459.541382 -398.100042)
			(xy 459.545364 -397.972056) (xy 459.557296 -397.844565) (xy 459.57713 -397.718062) (xy 459.604791 -397.593037)
			(xy 459.640171 -397.469974) (xy 459.683133 -397.349348) (xy 459.733511 -397.231627) (xy 459.791111 -397.117265)
			(xy 459.855709 -397.006706) (xy 459.927056 -396.900376) (xy 460.004875 -396.798688) (xy 460.088865 -396.702034)
			(xy 460.178702 -396.610789) (xy 460.274038 -396.525306) (xy 460.374503 -396.445915) (xy 460.479711 -396.372923)
			(xy 460.589252 -396.306614) (xy 460.702704 -396.247243) (xy 460.819628 -396.195039) (xy 460.939571 -396.150206)
			(xy 461.062069 -396.112917) (xy 461.186649 -396.083315) (xy 461.312827 -396.061516) (xy 461.440117 -396.047603)
			(xy 461.568026 -396.041631) (xy 461.696059 -396.043622) (xy 461.82372 -396.05357) (xy 461.950516 -396.071434)
			(xy 462.075955 -396.097147) (xy 462.199554 -396.130609) (xy 462.320833 -396.17169) (xy 462.439324 -396.220232)
			(xy 462.554568 -396.276046) (xy 462.666118 -396.338917) (xy 462.773545 -396.408601) (xy 462.876431 -396.484829)
			(xy 462.974379 -396.567306) (xy 463.06701 -396.655713) (xy 463.153966 -396.749708) (xy 463.23491 -396.848927)
			(xy 463.309529 -396.952986) (xy 463.377534 -397.061483) (xy 463.438662 -397.173998) (xy 463.492677 -397.290096)
			(xy 463.53937 -397.409327) (xy 463.57856 -397.531231) (xy 463.610096 -397.655335) (xy 463.633855 -397.781159)
			(xy 463.649745 -397.908218) (xy 463.657706 -398.036018) (xy 463.658204 -398.100042) (xy 463.657706 -398.164066)
			(xy 463.649745 -398.291866) (xy 463.633855 -398.418925) (xy 463.610096 -398.544749) (xy 463.57856 -398.668853)
			(xy 463.53937 -398.790757) (xy 463.492677 -398.909988) (xy 463.438662 -399.026086) (xy 463.377534 -399.138601)
			(xy 463.309529 -399.247098) (xy 463.23491 -399.351157) (xy 463.153966 -399.450376) (xy 463.06701 -399.544371)
			(xy 462.974379 -399.632778) (xy 462.876431 -399.715255) (xy 462.773545 -399.791483) (xy 462.666118 -399.861167)
			(xy 462.554568 -399.924038) (xy 462.439324 -399.979852) (xy 462.320833 -400.028394) (xy 462.199554 -400.069475)
			(xy 462.075955 -400.102937) (xy 461.950516 -400.12865) (xy 461.82372 -400.146514) (xy 461.696059 -400.156462)
			(xy 461.568026 -400.158453) (xy 461.440117 -400.152481) (xy 461.312827 -400.138568) (xy 461.186649 -400.116769)
			(xy 461.062069 -400.087167) (xy 460.939571 -400.049878) (xy 460.819628 -400.005045) (xy 460.702704 -399.952841)
			(xy 460.589252 -399.89347) (xy 460.479711 -399.827161) (xy 460.374503 -399.754169) (xy 460.274038 -399.674778)
			(xy 460.178702 -399.589295) (xy 460.088865 -399.49805) (xy 460.004875 -399.401396) (xy 459.927056 -399.299708)
			(xy 459.855709 -399.193378) (xy 459.791111 -399.082819) (xy 459.733511 -398.968457) (xy 459.683133 -398.850736)
			(xy 459.640171 -398.73011) (xy 459.604791 -398.607047) (xy 459.57713 -398.482022) (xy 459.557296 -398.355519)
			(xy 459.545364 -398.228028) (xy 459.541382 -398.100042) (xy 435.299612 -398.100042) (xy 435.299612 -398.486884)
			(xy 435.300027 -398.496071) (xy 435.306537 -398.513255) (xy 435.312312 -398.520412) (xy 435.334137 -398.546034)
			(xy 435.372087 -398.601624) (xy 435.403122 -398.661351) (xy 435.426795 -398.72436) (xy 435.442767 -398.789746)
			(xy 435.450809 -398.856573) (xy 435.450805 -398.923881) (xy 435.442757 -398.990707) (xy 435.426779 -399.056092)
			(xy 435.4031 -399.119098) (xy 435.37206 -399.178823) (xy 435.334103 -399.234408) (xy 435.312312 -399.26006)
			(xy 435.306509 -399.267201) (xy 435.299998 -399.284395) (xy 435.299612 -399.293588) (xy 435.299612 -399.451576)
			(xy 435.299159 -399.461727) (xy 435.291374 -399.480477) (xy 435.276987 -399.494801) (xy 435.258203 -399.502503)
			(xy 435.24805 -399.502884) (xy 434.53177 -399.502884) (xy 434.521644 -399.502399) (xy 434.502927 -399.494666)
			(xy 434.488573 -399.480379) (xy 434.48075 -399.461699) (xy 434.480208 -399.451576) (xy 434.480208 -399.293588)
			(xy 434.479802 -399.2844) (xy 434.473285 -399.267216) (xy 434.467508 -399.26006) (xy 434.445757 -399.234378)
			(xy 434.407809 -399.178795) (xy 434.376776 -399.119076) (xy 434.353102 -399.056075) (xy 434.337128 -398.990697)
			(xy 434.329081 -398.923878) (xy 434.329078 -398.856576) (xy 434.337118 -398.789757) (xy 434.353086 -398.724377)
			(xy 434.376753 -398.661374) (xy 434.407781 -398.601651) (xy 434.445723 -398.546064) (xy 434.467508 -398.520412)
			(xy 434.473325 -398.513282) (xy 434.479827 -398.49608) (xy 434.480208 -398.486884) (xy 434.480208 -397.993362)
			(xy 434.479814 -397.984173) (xy 434.473289 -397.966989) (xy 434.467508 -397.959834) (xy 434.445731 -397.934173)
			(xy 434.407784 -397.878587) (xy 434.376752 -397.818865) (xy 434.35308 -397.755861) (xy 434.337107 -397.690481)
			(xy 434.329063 -397.623659) (xy 434.329062 -397.556356) (xy 433.200318 -397.556356) (xy 433.202899 -397.561322)
			(xy 433.226573 -397.624323) (xy 433.242549 -397.689701) (xy 433.250596 -397.75652) (xy 433.250599 -397.823822)
			(xy 433.242559 -397.890642) (xy 433.22659 -397.956022) (xy 433.202922 -398.019025) (xy 433.171893 -398.078748)
			(xy 433.133949 -398.134334) (xy 433.112164 -398.159986) (xy 433.106344 -398.167114) (xy 433.099844 -398.184318)
			(xy 433.099464 -398.193514) (xy 433.099464 -398.351502) (xy 433.098968 -398.36166) (xy 433.091194 -398.380428)
			(xy 433.076828 -398.394794) (xy 433.05806 -398.402568) (xy 433.047902 -398.403064) (xy 432.331622 -398.403064)
			(xy 432.321452 -398.402618) (xy 432.302658 -398.394841) (xy 432.288273 -398.380462) (xy 432.280487 -398.361672)
			(xy 432.28006 -398.351502) (xy 432.28006 -398.193514) (xy 432.27963 -398.184329) (xy 432.273129 -398.167145)
			(xy 432.26736 -398.159986) (xy 432.245534 -398.134365) (xy 432.207585 -398.078775) (xy 432.176552 -398.019047)
			(xy 432.152881 -397.956038) (xy 432.13691 -397.890652) (xy 432.128868 -397.823826) (xy 431.000734 -397.823826)
			(xy 430.971969 -397.879041) (xy 430.93388 -397.934676) (xy 430.912016 -397.960342) (xy 430.906221 -397.967488)
			(xy 430.899705 -397.984678) (xy 430.899316 -397.99387) (xy 430.899316 -398.486376) (xy 430.899734 -398.495562)
			(xy 430.906242 -398.512747) (xy 430.912016 -398.519904) (xy 430.933915 -398.54554) (xy 430.972001 -398.601179)
			(xy 431.00315 -398.66098) (xy 431.026911 -398.72408) (xy 431.042944 -398.789573) (xy 431.051016 -398.856514)
			(xy 431.051013 -398.92394) (xy 431.042934 -398.990881) (xy 431.026895 -399.056371) (xy 431.003128 -399.11947)
			(xy 430.971974 -399.179267) (xy 430.933882 -399.234902) (xy 430.912016 -399.260568) (xy 430.90621 -399.267707)
			(xy 430.8997 -399.284902) (xy 430.899316 -399.294096) (xy 430.899316 -399.451576) (xy 430.898865 -399.461695)
			(xy 430.891128 -399.480395) (xy 430.876822 -399.49471) (xy 430.858127 -399.502459) (xy 430.848008 -399.502884)
			(xy 430.131728 -399.502884) (xy 430.121605 -399.502461) (xy 430.102899 -399.494719) (xy 430.088583 -399.480404)
			(xy 430.08084 -399.461699) (xy 430.08042 -399.451576) (xy 430.08042 -399.294096) (xy 430.080008 -399.284909)
			(xy 430.073495 -399.267725) (xy 430.06772 -399.260568) (xy 430.045891 -399.234874) (xy 430.0078 -399.179244)
			(xy 429.976646 -399.119452) (xy 429.952879 -399.056359) (xy 429.936841 -398.990873) (xy 429.928761 -398.923938)
			(xy 429.928758 -398.856516) (xy 429.936831 -398.78958) (xy 429.952863 -398.724093) (xy 429.976624 -398.660997)
			(xy 430.007772 -398.601202) (xy 430.045857 -398.545569) (xy 430.06772 -398.519904) (xy 430.0735 -398.512747)
			(xy 430.080024 -398.495565) (xy 430.08042 -398.486376) (xy 430.08042 -397.99387) (xy 430.08002 -397.984682)
			(xy 430.073499 -397.967498) (xy 430.06772 -397.960342) (xy 430.045865 -397.934669) (xy 430.007775 -397.879036)
			(xy 429.976623 -397.819241) (xy 429.952857 -397.756145) (xy 429.93682 -397.690657) (xy 429.928743 -397.623719)
			(xy 429.928742 -397.556296) (xy 428.800497 -397.556296) (xy 428.803109 -397.561323) (xy 428.826783 -397.624323)
			(xy 428.842758 -397.689702) (xy 428.850805 -397.756521) (xy 428.850808 -397.823822) (xy 428.842768 -397.890642)
			(xy 428.8268 -397.956022) (xy 428.803132 -398.019025) (xy 428.772104 -398.078747) (xy 428.734161 -398.134333)
			(xy 428.712376 -398.159986) (xy 428.706558 -398.167116) (xy 428.700057 -398.184318) (xy 428.699676 -398.193514)
			(xy 428.699676 -398.351502) (xy 428.699169 -398.361658) (xy 428.691396 -398.380425) (xy 428.677035 -398.394789)
			(xy 428.65827 -398.402566) (xy 428.648114 -398.403064) (xy 427.931834 -398.403064) (xy 427.921665 -398.402608)
			(xy 427.902871 -398.394835) (xy 427.888485 -398.380459) (xy 427.880699 -398.361671) (xy 427.880272 -398.351502)
			(xy 427.880272 -398.193514) (xy 427.879861 -398.184327) (xy 427.873349 -398.167142) (xy 427.867572 -398.159986)
			(xy 427.845746 -398.134365) (xy 427.807796 -398.078775) (xy 427.776762 -398.019047) (xy 427.75309 -397.956039)
			(xy 427.737119 -397.890652) (xy 427.729077 -397.823826) (xy 426.600432 -397.823826) (xy 426.571969 -397.878596)
			(xy 426.534017 -397.934182) (xy 426.512228 -397.959834) (xy 426.506426 -397.966975) (xy 426.499917 -397.984169)
			(xy 426.499528 -397.993362) (xy 426.499528 -398.486884) (xy 426.499939 -398.496071) (xy 426.506451 -398.513256)
			(xy 426.512228 -398.520412) (xy 426.534052 -398.546034) (xy 426.572002 -398.601624) (xy 426.603036 -398.661352)
			(xy 426.626708 -398.72436) (xy 426.64268 -398.789746) (xy 426.650721 -398.856573) (xy 426.650718 -398.923881)
			(xy 426.64267 -398.990707) (xy 426.626692 -399.056092) (xy 426.603014 -399.119098) (xy 426.571974 -399.178822)
			(xy 426.534019 -399.234408) (xy 426.512228 -399.26006) (xy 426.506415 -399.267193) (xy 426.499912 -399.284393)
			(xy 426.499528 -399.293588) (xy 426.499528 -399.451576) (xy 426.499059 -399.461725) (xy 426.491277 -399.480472)
			(xy 426.476895 -399.494795) (xy 426.458117 -399.502501) (xy 426.447966 -399.502884) (xy 425.731686 -399.502884)
			(xy 425.721561 -399.502385) (xy 425.702845 -399.494657) (xy 425.68849 -399.480375) (xy 425.680667 -399.461698)
			(xy 425.680124 -399.451576) (xy 425.680124 -399.293588) (xy 425.679714 -399.284401) (xy 425.6732 -399.267217)
			(xy 425.667424 -399.26006) (xy 425.645672 -399.234378) (xy 425.607723 -399.178796) (xy 425.576689 -399.119076)
			(xy 425.553015 -399.056076) (xy 425.53704 -398.990697) (xy 425.528994 -398.923878) (xy 425.52899 -398.856576)
			(xy 425.537031 -398.789756) (xy 425.552999 -398.724376) (xy 425.576667 -398.661373) (xy 425.607696 -398.601651)
			(xy 425.645639 -398.546065) (xy 425.667424 -398.520412) (xy 425.673243 -398.513283) (xy 425.679744 -398.49608)
			(xy 425.680124 -398.486884) (xy 425.680124 -397.993362) (xy 425.679727 -397.984174) (xy 425.673204 -397.96699)
			(xy 425.667424 -397.959834) (xy 425.645646 -397.934174) (xy 425.607698 -397.878588) (xy 425.576665 -397.818865)
			(xy 425.552993 -397.755862) (xy 425.53702 -397.690481) (xy 425.528975 -397.62366) (xy 425.528974 -397.556356)
			(xy 424.40076 -397.556356) (xy 424.403152 -397.560947) (xy 424.426919 -397.62404) (xy 424.442958 -397.689526)
			(xy 424.451037 -397.756461) (xy 424.451041 -397.823882) (xy 424.442968 -397.890818) (xy 424.426936 -397.956305)
			(xy 424.403175 -398.019401) (xy 424.372028 -398.079196) (xy 424.333942 -398.134829) (xy 424.31208 -398.160494)
			(xy 424.306301 -398.167652) (xy 424.299777 -398.184833) (xy 424.29938 -398.194022) (xy 424.29938 -398.351502)
			(xy 424.298876 -398.361626) (xy 424.291151 -398.380344) (xy 424.27687 -398.394699) (xy 424.258194 -398.402522)
			(xy 424.248072 -398.403064) (xy 423.531792 -398.403064) (xy 423.521633 -398.402684) (xy 423.502873 -398.394879)
			(xy 423.488549 -398.380469) (xy 423.480856 -398.361663) (xy 423.480484 -398.351502) (xy 423.480484 -398.194022)
			(xy 423.480067 -398.184835) (xy 423.473558 -398.167651) (xy 423.467784 -398.160494) (xy 423.445883 -398.134859)
			(xy 423.407797 -398.07922) (xy 423.376649 -398.019419) (xy 423.352887 -397.956319) (xy 423.336855 -397.890826)
			(xy 423.328782 -397.823885) (xy 422.200615 -397.823885) (xy 422.171883 -397.879041) (xy 422.133795 -397.934676)
			(xy 422.111932 -397.960342) (xy 422.106127 -397.967481) (xy 422.099619 -397.984676) (xy 422.099232 -397.99387)
			(xy 422.099232 -398.486376) (xy 422.099669 -398.49556) (xy 422.106166 -398.512744) (xy 422.111932 -398.519904)
			(xy 422.13383 -398.545541) (xy 422.171916 -398.60118) (xy 422.203063 -398.66098) (xy 422.226824 -398.724081)
			(xy 422.242856 -398.789573) (xy 422.250928 -398.856514) (xy 422.250925 -398.92394) (xy 422.242846 -398.99088)
			(xy 422.226808 -399.056371) (xy 422.203041 -399.119469) (xy 422.171888 -399.179266) (xy 422.133797 -399.234902)
			(xy 422.111932 -399.260568) (xy 422.106116 -399.267699) (xy 422.099615 -399.284901) (xy 422.099232 -399.294096)
			(xy 422.099232 -399.451576) (xy 422.098696 -399.461679) (xy 422.090972 -399.480351) (xy 422.076691 -399.494645)
			(xy 422.058027 -399.502387) (xy 422.047924 -399.502884) (xy 421.331644 -399.502884) (xy 421.321522 -399.502447)
			(xy 421.302817 -399.494711) (xy 421.2885 -399.4804) (xy 421.280756 -399.461697) (xy 421.280336 -399.451576)
			(xy 421.280336 -399.294096) (xy 421.27992 -399.28491) (xy 421.27341 -399.267726) (xy 421.267636 -399.260568)
			(xy 421.245806 -399.234874) (xy 421.207714 -399.179245) (xy 421.17656 -399.119453) (xy 421.152792 -399.056359)
			(xy 421.136753 -398.990873) (xy 421.128674 -398.923938) (xy 421.12867 -398.856516) (xy 421.136743 -398.78958)
			(xy 421.152776 -398.724092) (xy 421.176538 -398.660997) (xy 421.207686 -398.601202) (xy 421.245773 -398.545569)
			(xy 421.267636 -398.519904) (xy 421.273418 -398.512749) (xy 421.27994 -398.495566) (xy 421.280336 -398.486376)
			(xy 421.280336 -397.99387) (xy 421.279932 -397.984682) (xy 421.273413 -397.967498) (xy 421.267636 -397.960342)
			(xy 421.245781 -397.934669) (xy 421.207689 -397.879037) (xy 421.176536 -397.819242) (xy 421.15277 -397.756146)
			(xy 421.136732 -397.690657) (xy 421.128655 -397.623719) (xy 421.128654 -397.556296) (xy 420.00041 -397.556296)
			(xy 420.003023 -397.561324) (xy 420.026696 -397.624324) (xy 420.042671 -397.689702) (xy 420.050718 -397.756521)
			(xy 420.050721 -397.823822) (xy 420.042681 -397.890642) (xy 420.026713 -397.956021) (xy 420.003046 -398.019024)
			(xy 419.972019 -398.078747) (xy 419.934077 -398.134334) (xy 419.912292 -398.159986) (xy 419.906475 -398.167117)
			(xy 419.899973 -398.184318) (xy 419.899592 -398.193514) (xy 419.899592 -398.351502) (xy 419.899069 -398.361656)
			(xy 419.891299 -398.38042) (xy 419.876943 -398.394784) (xy 419.858184 -398.402563) (xy 419.84803 -398.403064)
			(xy 419.13175 -398.403064) (xy 419.121582 -398.402595) (xy 419.102789 -398.394827) (xy 419.088402 -398.380455)
			(xy 419.080615 -398.36167) (xy 419.080188 -398.351502) (xy 419.080188 -398.193514) (xy 419.079774 -398.184327)
			(xy 419.073263 -398.167143) (xy 419.067488 -398.159986) (xy 419.045661 -398.134365) (xy 419.007711 -398.078775)
			(xy 418.976676 -398.019048) (xy 418.953004 -397.956039) (xy 418.937032 -397.890653) (xy 418.92899 -397.823826)
			(xy 414.525968 -397.823826) (xy 414.525968 -401.723737) (xy 418.929001 -401.723737) (xy 418.929003 -401.65643)
			(xy 418.93705 -401.589605) (xy 418.953027 -401.524221) (xy 418.976704 -401.461215) (xy 419.007743 -401.401491)
			(xy 419.045697 -401.345906) (xy 419.067488 -401.320254) (xy 419.073285 -401.313109) (xy 419.0798 -401.295918)
			(xy 419.080188 -401.286726) (xy 419.080188 -400.793458) (xy 419.079801 -400.784268) (xy 419.073272 -400.767084)
			(xy 419.067488 -400.75993) (xy 419.045705 -400.734274) (xy 419.007752 -400.678689) (xy 418.976716 -400.618966)
			(xy 418.953041 -400.555962) (xy 418.937066 -400.49058) (xy 418.929021 -400.423757) (xy 418.92902 -400.356452)
			(xy 418.937065 -400.289629) (xy 418.953038 -400.224246) (xy 418.976713 -400.161242) (xy 419.007748 -400.101519)
			(xy 419.045699 -400.045933) (xy 419.067488 -400.020282) (xy 419.073273 -400.013129) (xy 419.079795 -399.995944)
			(xy 419.080188 -399.986754) (xy 419.080188 -399.828766) (xy 419.080537 -399.818586) (xy 419.088343 -399.799781)
			(xy 419.102752 -399.785395) (xy 419.121569 -399.777621) (xy 419.13175 -399.777204) (xy 419.84803 -399.777204)
			(xy 419.858186 -399.777708) (xy 419.876949 -399.785486) (xy 419.891312 -399.799848) (xy 419.899091 -399.818611)
			(xy 419.899592 -399.828766) (xy 419.899592 -399.986754) (xy 419.900026 -399.995939) (xy 419.906523 -400.013123)
			(xy 419.912292 -400.020282) (xy 419.934085 -400.04593) (xy 419.972031 -400.101518) (xy 420.003063 -400.161242)
			(xy 420.026734 -400.224247) (xy 420.042705 -400.289629) (xy 420.050749 -400.356452) (xy 420.050748 -400.423757)
			(xy 420.042704 -400.490579) (xy 420.026731 -400.555962) (xy 420.003059 -400.618966) (xy 419.972027 -400.67869)
			(xy 419.934079 -400.734277) (xy 419.912292 -400.75993) (xy 419.906499 -400.767078) (xy 419.899983 -400.784266)
			(xy 419.899592 -400.793458) (xy 419.899592 -401.286726) (xy 419.899991 -401.295914) (xy 419.906513 -401.313099)
			(xy 419.912292 -401.320254) (xy 419.934057 -401.345924) (xy 419.972005 -401.401509) (xy 420.003037 -401.46123)
			(xy 420.02671 -401.524232) (xy 420.042683 -401.589612) (xy 420.050729 -401.656432) (xy 420.050731 -401.723735)
			(xy 420.042689 -401.790555) (xy 420.02672 -401.855936) (xy 420.003051 -401.918939) (xy 419.972022 -401.978663)
			(xy 419.934077 -402.034249) (xy 419.912292 -402.059902) (xy 419.906511 -402.067058) (xy 419.899987 -402.08424)
			(xy 419.899592 -402.09343) (xy 419.899592 -402.251418) (xy 419.899082 -402.261573) (xy 419.891308 -402.280337)
			(xy 419.876947 -402.294701) (xy 419.858185 -402.30248) (xy 419.84803 -402.30298) (xy 419.13175 -402.30298)
			(xy 419.121584 -402.302496) (xy 419.102794 -402.29473) (xy 419.088408 -402.280363) (xy 419.080618 -402.261584)
			(xy 419.080188 -402.251418) (xy 419.080188 -402.09343) (xy 419.079766 -402.084244) (xy 419.073261 -402.067059)
			(xy 419.067488 -402.059902) (xy 419.045677 -402.034268) (xy 419.007726 -401.97868) (xy 418.976691 -401.918955)
			(xy 418.953017 -401.855948) (xy 418.937044 -401.790563) (xy 418.929001 -401.723737) (xy 414.525968 -401.723737)
			(xy 414.525968 -402.823878) (xy 421.128614 -402.823878) (xy 421.128619 -402.75645) (xy 421.1367 -402.689508)
			(xy 421.152742 -402.624016) (xy 421.176513 -402.560916) (xy 421.207671 -402.501119) (xy 421.245768 -402.445485)
			(xy 421.267636 -402.41982) (xy 421.273454 -402.41269) (xy 421.279955 -402.395488) (xy 421.280336 -402.386292)
			(xy 421.280336 -401.89404) (xy 421.279898 -401.884856) (xy 421.273403 -401.867672) (xy 421.267636 -401.860512)
			(xy 421.245751 -401.834864) (xy 421.207661 -401.779227) (xy 421.176509 -401.719429) (xy 421.152744 -401.65633)
			(xy 421.136709 -401.590839) (xy 421.128634 -401.523898) (xy 421.128636 -401.456472) (xy 421.136714 -401.389532)
			(xy 421.152753 -401.324041) (xy 421.176521 -401.260943) (xy 421.207676 -401.201147) (xy 421.24577 -401.145513)
			(xy 421.267636 -401.119848) (xy 421.273442 -401.112709) (xy 421.27995 -401.095514) (xy 421.280336 -401.08632)
			(xy 421.280336 -400.92884) (xy 421.28075 -400.918716) (xy 421.288491 -400.900006) (xy 421.302809 -400.885689)
			(xy 421.32152 -400.877949) (xy 421.331644 -400.877532) (xy 422.047924 -400.877532) (xy 422.058052 -400.877897)
			(xy 422.076762 -400.885659) (xy 422.091077 -400.899991) (xy 422.098816 -400.918711) (xy 422.099232 -400.92884)
			(xy 422.099232 -401.08632) (xy 422.099648 -401.095506) (xy 422.106159 -401.11269) (xy 422.111932 -401.119848)
			(xy 422.133775 -401.14553) (xy 422.171862 -401.201163) (xy 422.203012 -401.260957) (xy 422.226776 -401.324052)
			(xy 422.242812 -401.389538) (xy 422.250889 -401.456474) (xy 422.250891 -401.523896) (xy 422.242817 -401.590832)
			(xy 422.226785 -401.65632) (xy 422.203024 -401.719415) (xy 422.200742 -401.723796) (xy 423.328794 -401.723796)
			(xy 423.328796 -401.656371) (xy 423.336873 -401.589431) (xy 423.352911 -401.523941) (xy 423.376677 -401.460844)
			(xy 423.407829 -401.401047) (xy 423.445919 -401.345412) (xy 423.467784 -401.319746) (xy 423.473584 -401.312603)
			(xy 423.480097 -401.295411) (xy 423.480484 -401.286218) (xy 423.480484 -400.793966) (xy 423.480094 -400.784777)
			(xy 423.473566 -400.767592) (xy 423.467784 -400.760438) (xy 423.445926 -400.734768) (xy 423.407839 -400.679133)
			(xy 423.376689 -400.619338) (xy 423.352925 -400.556242) (xy 423.336889 -400.490753) (xy 423.328813 -400.423816)
			(xy 423.328813 -400.356393) (xy 423.336888 -400.289455) (xy 423.352922 -400.223967) (xy 423.376685 -400.16087)
			(xy 423.407834 -400.101074) (xy 423.445921 -400.045439) (xy 423.467784 -400.019774) (xy 423.473572 -400.012623)
			(xy 423.480092 -399.995437) (xy 423.480484 -399.986246) (xy 423.480484 -399.828766) (xy 423.4809 -399.818632)
			(xy 423.488647 -399.799901) (xy 423.502955 -399.785545) (xy 423.521659 -399.777735) (xy 423.531792 -399.777204)
			(xy 424.248072 -399.777204) (xy 424.258225 -399.777644) (xy 424.276977 -399.785431) (xy 424.291302 -399.799823)
			(xy 424.299002 -399.818611) (xy 424.29938 -399.828766) (xy 424.29938 -399.986246) (xy 424.299821 -399.99543)
			(xy 424.306314 -400.012614) (xy 424.31208 -400.019774) (xy 424.333951 -400.045434) (xy 424.37204 -400.101069)
			(xy 424.403192 -400.160866) (xy 424.426957 -400.223963) (xy 424.442992 -400.289453) (xy 424.451068 -400.356392)
			(xy 424.451068 -400.423817) (xy 424.442991 -400.490756) (xy 424.426954 -400.556245) (xy 424.403188 -400.619343)
			(xy 424.372036 -400.679139) (xy 424.333945 -400.734773) (xy 424.31208 -400.760438) (xy 424.306282 -400.767582)
			(xy 424.299769 -400.784774) (xy 424.29938 -400.793966) (xy 424.29938 -401.286218) (xy 424.299786 -401.295406)
			(xy 424.306303 -401.31259) (xy 424.31208 -401.319746) (xy 424.333923 -401.345429) (xy 424.372014 -401.40106)
			(xy 424.403167 -401.460854) (xy 424.426933 -401.523949) (xy 424.44297 -401.589436) (xy 424.451048 -401.656372)
			(xy 424.45105 -401.723795) (xy 424.442976 -401.790732) (xy 424.426943 -401.85622) (xy 424.40318 -401.919316)
			(xy 424.372031 -401.979111) (xy 424.333943 -402.034745) (xy 424.31208 -402.06041) (xy 424.306294 -402.067563)
			(xy 424.299774 -402.084748) (xy 424.29938 -402.093938) (xy 424.29938 -402.251418) (xy 424.298889 -402.261543)
			(xy 424.291159 -402.280261) (xy 424.276874 -402.294616) (xy 424.258195 -402.302438) (xy 424.248072 -402.30298)
			(xy 423.531792 -402.30298) (xy 423.521635 -402.302584) (xy 423.502879 -402.294782) (xy 423.488555 -402.280378)
			(xy 423.480859 -402.261577) (xy 423.480484 -402.251418) (xy 423.480484 -402.093938) (xy 423.480059 -402.084752)
			(xy 423.473556 -402.067568) (xy 423.467784 -402.06041) (xy 423.445899 -402.034762) (xy 423.407812 -401.979125)
			(xy 423.376663 -401.919326) (xy 423.352901 -401.856227) (xy 423.336867 -401.790736) (xy 423.328794 -401.723796)
			(xy 422.200742 -401.723796) (xy 422.171878 -401.779211) (xy 422.133794 -401.834846) (xy 422.111932 -401.860512)
			(xy 422.10614 -401.86766) (xy 422.099624 -401.884849) (xy 422.099232 -401.89404) (xy 422.099232 -402.386292)
			(xy 422.099661 -402.395477) (xy 422.106163 -402.412661) (xy 422.111932 -402.41982) (xy 422.133748 -402.445525)
			(xy 422.171836 -402.501154) (xy 422.202987 -402.560945) (xy 422.226752 -402.624037) (xy 422.24279 -402.689521)
			(xy 422.250869 -402.756454) (xy 422.250874 -402.823818) (xy 425.528934 -402.823818) (xy 425.528938 -402.75651)
			(xy 425.536987 -402.689684) (xy 425.552965 -402.624299) (xy 425.576642 -402.561293) (xy 425.60768 -402.501568)
			(xy 425.645634 -402.44598) (xy 425.667424 -402.420328) (xy 425.673236 -402.413194) (xy 425.679741 -402.395995)
			(xy 425.680124 -402.3868) (xy 425.680124 -401.893532) (xy 425.679693 -401.884347) (xy 425.673193 -401.867163)
			(xy 425.667424 -401.860004) (xy 425.645617 -401.834368) (xy 425.60767 -401.778779) (xy 425.576638 -401.719053)
			(xy 425.552967 -401.656046) (xy 425.536996 -401.590662) (xy 425.528954 -401.523838) (xy 425.528956 -401.456532)
			(xy 425.537001 -401.389708) (xy 425.552976 -401.324325) (xy 425.57665 -401.26132) (xy 425.607685 -401.201595)
			(xy 425.645635 -401.146008) (xy 425.667424 -401.120356) (xy 425.673225 -401.113214) (xy 425.679736 -401.096021)
			(xy 425.680124 -401.086828) (xy 425.680124 -400.92884) (xy 425.680555 -400.918686) (xy 425.688342 -400.899929)
			(xy 425.702736 -400.885604) (xy 425.72153 -400.877907) (xy 425.731686 -400.877532) (xy 426.447966 -400.877532)
			(xy 426.45809 -400.878054) (xy 426.476808 -400.88577) (xy 426.491165 -400.900045) (xy 426.498987 -400.918719)
			(xy 426.499528 -400.92884) (xy 426.499528 -401.086828) (xy 426.499918 -401.096017) (xy 426.506445 -401.113202)
			(xy 426.512228 -401.120356) (xy 426.533997 -401.146024) (xy 426.571949 -401.201607) (xy 426.602985 -401.261328)
			(xy 426.62666 -401.324331) (xy 426.642635 -401.389712) (xy 426.650681 -401.456533) (xy 426.650683 -401.523837)
			(xy 426.642641 -401.590659) (xy 426.626669 -401.65604) (xy 426.602997 -401.719044) (xy 426.600558 -401.723737)
			(xy 427.729089 -401.723737) (xy 427.729091 -401.65643) (xy 427.737138 -401.589605) (xy 427.753114 -401.524221)
			(xy 427.776791 -401.461216) (xy 427.807828 -401.401492) (xy 427.845782 -401.345906) (xy 427.867572 -401.320254)
			(xy 427.873379 -401.313117) (xy 427.879886 -401.29592) (xy 427.880272 -401.286726) (xy 427.880272 -400.793458)
			(xy 427.879888 -400.784268) (xy 427.873357 -400.767084) (xy 427.867572 -400.75993) (xy 427.845789 -400.734273)
			(xy 427.807838 -400.678688) (xy 427.776803 -400.618966) (xy 427.753128 -400.555962) (xy 427.737154 -400.49058)
			(xy 427.729109 -400.423757) (xy 427.729108 -400.356452) (xy 427.737152 -400.289629) (xy 427.753126 -400.224247)
			(xy 427.776799 -400.161243) (xy 427.807833 -400.101519) (xy 427.845784 -400.045934) (xy 427.867572 -400.020282)
			(xy 427.873367 -400.013136) (xy 427.879881 -399.995946) (xy 427.880272 -399.986754) (xy 427.880272 -399.828766)
			(xy 427.880706 -399.818602) (xy 427.888498 -399.799825) (xy 427.902883 -399.78546) (xy 427.921669 -399.777693)
			(xy 427.931834 -399.777204) (xy 428.648114 -399.777204) (xy 428.658268 -399.777721) (xy 428.677031 -399.785494)
			(xy 428.691395 -399.799852) (xy 428.699175 -399.818612) (xy 428.699676 -399.828766) (xy 428.699676 -399.986754)
			(xy 428.700114 -399.995938) (xy 428.706609 -400.013122) (xy 428.712376 -400.020282) (xy 428.734169 -400.045929)
			(xy 428.772117 -400.101517) (xy 428.803149 -400.161241) (xy 428.826821 -400.224246) (xy 428.842793 -400.289629)
			(xy 428.850836 -400.356452) (xy 428.850836 -400.423757) (xy 428.842791 -400.49058) (xy 428.826818 -400.555962)
			(xy 428.803145 -400.618967) (xy 428.772112 -400.678691) (xy 428.734164 -400.734278) (xy 428.712376 -400.75993)
			(xy 428.706581 -400.767076) (xy 428.700066 -400.784266) (xy 428.699676 -400.793458) (xy 428.699676 -401.286726)
			(xy 428.700079 -401.295914) (xy 428.706598 -401.313098) (xy 428.712376 -401.320254) (xy 428.734142 -401.345924)
			(xy 428.77209 -401.401508) (xy 428.803124 -401.46123) (xy 428.826797 -401.524232) (xy 428.842771 -401.589612)
			(xy 428.850817 -401.656432) (xy 428.850819 -401.723735) (xy 428.842777 -401.790556) (xy 428.826807 -401.855937)
			(xy 428.803137 -401.91894) (xy 428.772107 -401.978663) (xy 428.734162 -402.03425) (xy 428.712376 -402.059902)
			(xy 428.706593 -402.067057) (xy 428.700071 -402.08424) (xy 428.699676 -402.09343) (xy 428.699676 -402.251418)
			(xy 428.699182 -402.261575) (xy 428.691404 -402.280342) (xy 428.677039 -402.294706) (xy 428.658271 -402.302483)
			(xy 428.648114 -402.30298) (xy 427.931834 -402.30298) (xy 427.921667 -402.302509) (xy 427.902876 -402.294738)
			(xy 427.888491 -402.280367) (xy 427.880702 -402.261585) (xy 427.880272 -402.251418) (xy 427.880272 -402.09343)
			(xy 427.879854 -402.084244) (xy 427.873347 -402.067059) (xy 427.867572 -402.059902) (xy 427.845762 -402.034268)
			(xy 427.807811 -401.97868) (xy 427.776777 -401.918954) (xy 427.753104 -401.855947) (xy 427.737132 -401.790562)
			(xy 427.729089 -401.723737) (xy 426.600558 -401.723737) (xy 426.571964 -401.778767) (xy 426.534015 -401.834352)
			(xy 426.512228 -401.860004) (xy 426.506438 -401.867154) (xy 426.499922 -401.884341) (xy 426.499528 -401.893532)
			(xy 426.499528 -402.3868) (xy 426.499932 -402.395988) (xy 426.506449 -402.413173) (xy 426.512228 -402.420328)
			(xy 426.53397 -402.446019) (xy 426.571922 -402.501599) (xy 426.602959 -402.561317) (xy 426.626636 -402.624316)
			(xy 426.642613 -402.689694) (xy 426.650662 -402.756513) (xy 426.650666 -402.823815) (xy 426.650658 -402.823878)
			(xy 429.928702 -402.823878) (xy 429.928707 -402.75645) (xy 429.936788 -402.689508) (xy 429.952829 -402.624016)
			(xy 429.976599 -402.560917) (xy 430.007757 -402.50112) (xy 430.045852 -402.445485) (xy 430.06772 -402.41982)
			(xy 430.073535 -402.412688) (xy 430.080038 -402.395487) (xy 430.08042 -402.386292) (xy 430.08042 -401.89404)
			(xy 430.079986 -401.884855) (xy 430.073488 -401.867671) (xy 430.06772 -401.860512) (xy 430.045836 -401.834863)
			(xy 430.007746 -401.779227) (xy 429.976595 -401.719429) (xy 429.952831 -401.656329) (xy 429.936797 -401.590838)
			(xy 429.928722 -401.523898) (xy 429.928724 -401.456472) (xy 429.936802 -401.389532) (xy 429.95284 -401.324042)
			(xy 429.976608 -401.260944) (xy 430.007762 -401.201147) (xy 430.045854 -401.145513) (xy 430.06772 -401.119848)
			(xy 430.073523 -401.112708) (xy 430.080033 -401.095513) (xy 430.08042 -401.08632) (xy 430.08042 -400.92884)
			(xy 430.080849 -400.918718) (xy 430.088588 -400.900011) (xy 430.102901 -400.885695) (xy 430.121606 -400.877952)
			(xy 430.131728 -400.877532) (xy 430.848008 -400.877532) (xy 430.858135 -400.87791) (xy 430.876845 -400.885667)
			(xy 430.89116 -400.899996) (xy 430.898899 -400.918713) (xy 430.899316 -400.92884) (xy 430.899316 -401.08632)
			(xy 430.899713 -401.095509) (xy 430.906236 -401.112693) (xy 430.912016 -401.119848) (xy 430.93386 -401.14553)
			(xy 430.971948 -401.201162) (xy 431.003099 -401.260956) (xy 431.026863 -401.324051) (xy 431.0429 -401.389538)
			(xy 431.050977 -401.456474) (xy 431.050979 -401.523896) (xy 431.042905 -401.590832) (xy 431.026872 -401.65632)
			(xy 431.003111 -401.719416) (xy 431.00086 -401.723737) (xy 432.128879 -401.723737) (xy 432.128881 -401.65643)
			(xy 432.136928 -401.589605) (xy 432.152904 -401.524222) (xy 432.17658 -401.461216) (xy 432.207617 -401.401492)
			(xy 432.24557 -401.345906) (xy 432.26736 -401.320254) (xy 432.273166 -401.313116) (xy 432.279673 -401.29592)
			(xy 432.28006 -401.286726) (xy 432.28006 -400.793458) (xy 432.279657 -400.78427) (xy 432.273137 -400.767087)
			(xy 432.26736 -400.75993) (xy 432.245578 -400.734273) (xy 432.207627 -400.678688) (xy 432.176593 -400.618965)
			(xy 432.152919 -400.555961) (xy 432.136945 -400.490579) (xy 432.1289 -400.423757) (xy 432.128899 -400.356452)
			(xy 432.136943 -400.28963) (xy 432.152916 -400.224247) (xy 432.176589 -400.161243) (xy 432.207623 -400.10152)
			(xy 432.245572 -400.045934) (xy 432.26736 -400.020282) (xy 432.273154 -400.013135) (xy 432.279669 -399.995946)
			(xy 432.28006 -399.986754) (xy 432.28006 -399.828766) (xy 432.280506 -399.818603) (xy 432.288296 -399.799829)
			(xy 432.302676 -399.785464) (xy 432.321459 -399.777695) (xy 432.331622 -399.777204) (xy 433.047902 -399.777204)
			(xy 433.058056 -399.777731) (xy 433.076818 -399.7855) (xy 433.091182 -399.799855) (xy 433.098963 -399.818613)
			(xy 433.099464 -399.828766) (xy 433.099464 -399.986754) (xy 433.099905 -399.995938) (xy 433.106398 -400.013122)
			(xy 433.112164 -400.020282) (xy 433.133958 -400.045929) (xy 433.171906 -400.101516) (xy 433.202939 -400.161241)
			(xy 433.226611 -400.224246) (xy 433.242584 -400.289629) (xy 433.250627 -400.356452) (xy 433.250627 -400.423757)
			(xy 433.242582 -400.49058) (xy 433.226609 -400.555963) (xy 433.202935 -400.618968) (xy 433.171901 -400.678691)
			(xy 433.133952 -400.734278) (xy 433.112164 -400.75993) (xy 433.106368 -400.767075) (xy 433.099854 -400.784266)
			(xy 433.099464 -400.793458) (xy 433.099464 -401.286726) (xy 433.09987 -401.295913) (xy 433.106387 -401.313097)
			(xy 433.112164 -401.320254) (xy 433.13393 -401.345924) (xy 433.171879 -401.401508) (xy 433.202913 -401.461229)
			(xy 433.226587 -401.524231) (xy 433.242561 -401.589611) (xy 433.250607 -401.656432) (xy 433.250609 -401.723735)
			(xy 433.242567 -401.790556) (xy 433.226597 -401.855937) (xy 433.202927 -401.918941) (xy 433.171896 -401.978663)
			(xy 433.13395 -402.03425) (xy 433.112164 -402.059902) (xy 433.106379 -402.067056) (xy 433.099858 -402.08424)
			(xy 433.099464 -402.09343) (xy 433.099464 -402.251418) (xy 433.098982 -402.261577) (xy 433.091202 -402.280346)
			(xy 433.076833 -402.294711) (xy 433.058061 -402.302485) (xy 433.047902 -402.30298) (xy 432.331622 -402.30298)
			(xy 432.321454 -402.302518) (xy 432.302663 -402.294744) (xy 432.288278 -402.28037) (xy 432.28049 -402.261586)
			(xy 432.28006 -402.251418) (xy 432.28006 -402.09343) (xy 432.279622 -402.084246) (xy 432.273126 -402.067062)
			(xy 432.26736 -402.059902) (xy 432.24555 -402.034268) (xy 432.2076 -401.97868) (xy 432.176567 -401.918954)
			(xy 432.152894 -401.855947) (xy 432.136922 -401.790562) (xy 432.128879 -401.723737) (xy 431.00086 -401.723737)
			(xy 430.971963 -401.779212) (xy 430.933878 -401.834847) (xy 430.912016 -401.860512) (xy 430.906234 -401.867667)
			(xy 430.89971 -401.88485) (xy 430.899316 -401.89404) (xy 430.899316 -402.386292) (xy 430.899726 -402.395479)
			(xy 430.90624 -402.412664) (xy 430.912016 -402.41982) (xy 430.933832 -402.445524) (xy 430.971921 -402.501154)
			(xy 431.003073 -402.560945) (xy 431.026839 -402.624036) (xy 431.042878 -402.68952) (xy 431.050957 -402.756454)
			(xy 431.050962 -402.823818) (xy 434.329022 -402.823818) (xy 434.329026 -402.75651) (xy 434.337075 -402.689684)
			(xy 434.353052 -402.6243) (xy 434.376729 -402.561294) (xy 434.407766 -402.501568) (xy 434.445718 -402.445981)
			(xy 434.467508 -402.420328) (xy 434.473319 -402.413193) (xy 434.479825 -402.395995) (xy 434.480208 -402.3868)
			(xy 434.480208 -401.893532) (xy 434.479781 -401.884347) (xy 434.473279 -401.867162) (xy 434.467508 -401.860004)
			(xy 434.445702 -401.834368) (xy 434.407755 -401.778778) (xy 434.376725 -401.719052) (xy 434.353054 -401.656046)
			(xy 434.337084 -401.590662) (xy 434.329042 -401.523838) (xy 434.329043 -401.456532) (xy 434.337089 -401.389709)
			(xy 434.353063 -401.324326) (xy 434.376737 -401.26132) (xy 434.407771 -401.201596) (xy 434.44572 -401.146009)
			(xy 434.467508 -401.120356) (xy 434.473307 -401.113212) (xy 434.47982 -401.096021) (xy 434.480208 -401.086828)
			(xy 434.480208 -400.92884) (xy 434.480655 -400.918688) (xy 434.488438 -400.899934) (xy 434.502828 -400.885609)
			(xy 434.521616 -400.87791) (xy 434.53177 -400.877532) (xy 435.24805 -400.877532) (xy 435.258173 -400.878067)
			(xy 435.276891 -400.885777) (xy 435.291249 -400.900049) (xy 435.299071 -400.918721) (xy 435.299612 -400.92884)
			(xy 435.299612 -401.086828) (xy 435.300006 -401.096017) (xy 435.306531 -401.113201) (xy 435.312312 -401.120356)
			(xy 435.334082 -401.146024) (xy 435.372034 -401.201607) (xy 435.403071 -401.261328) (xy 435.426747 -401.32433)
			(xy 435.442723 -401.389711) (xy 435.450769 -401.456533) (xy 435.450771 -401.523837) (xy 435.442728 -401.590659)
			(xy 435.426756 -401.656041) (xy 435.403083 -401.719045) (xy 435.37205 -401.778767) (xy 435.3341 -401.834353)
			(xy 435.312312 -401.860004) (xy 435.306533 -401.867161) (xy 435.300007 -401.884343) (xy 435.299612 -401.893532)
			(xy 435.299612 -402.3868) (xy 435.30002 -402.395988) (xy 435.306535 -402.413172) (xy 435.312312 -402.420328)
			(xy 435.334054 -402.446018) (xy 435.372008 -402.501598) (xy 435.403046 -402.561316) (xy 435.426723 -402.624316)
			(xy 435.442701 -402.689694) (xy 435.45075 -402.756513) (xy 435.450754 -402.823815) (xy 435.442714 -402.890635)
			(xy 435.426745 -402.956015) (xy 435.403075 -403.019018) (xy 435.372045 -403.07874) (xy 435.334098 -403.134325)
			(xy 435.312312 -403.159976) (xy 435.306502 -403.167112) (xy 435.299995 -403.184309) (xy 435.299612 -403.193504)
			(xy 435.299612 -403.351492) (xy 435.299172 -403.361644) (xy 435.291381 -403.380394) (xy 435.27699 -403.394717)
			(xy 435.258204 -403.402419) (xy 435.24805 -403.4028) (xy 434.53177 -403.4028) (xy 434.521646 -403.402299)
			(xy 434.502932 -403.394569) (xy 434.488578 -403.380288) (xy 434.480753 -403.361613) (xy 434.480208 -403.351492)
			(xy 434.480208 -403.193504) (xy 434.479794 -403.184317) (xy 434.473283 -403.167133) (xy 434.467508 -403.159976)
			(xy 434.445674 -403.134362) (xy 434.407729 -403.07877) (xy 434.376699 -403.01904) (xy 434.353031 -402.956031)
			(xy 434.337062 -402.890644) (xy 434.329022 -402.823818) (xy 431.050962 -402.823818) (xy 431.050962 -402.823874)
			(xy 431.042891 -402.890808) (xy 431.026861 -402.956295) (xy 431.003103 -403.019389) (xy 430.971958 -403.079184)
			(xy 430.933877 -403.134819) (xy 430.912016 -403.160484) (xy 430.906203 -403.167618) (xy 430.899698 -403.184817)
			(xy 430.899316 -403.194012) (xy 430.899316 -403.351492) (xy 430.898809 -403.361598) (xy 430.891077 -403.380273)
			(xy 430.876787 -403.394568) (xy 430.858114 -403.402306) (xy 430.848008 -403.4028) (xy 430.131728 -403.4028)
			(xy 430.121607 -403.402361) (xy 430.102904 -403.394622) (xy 430.088589 -403.380313) (xy 430.080843 -403.361613)
			(xy 430.08042 -403.351492) (xy 430.08042 -403.194012) (xy 430.079999 -403.184826) (xy 430.073492 -403.167642)
			(xy 430.06772 -403.160484) (xy 430.045808 -403.134858) (xy 430.00772 -403.079218) (xy 429.97657 -403.019417)
			(xy 429.952807 -402.956315) (xy 429.936775 -402.890821) (xy 429.928702 -402.823878) (xy 426.650658 -402.823878)
			(xy 426.642626 -402.890635) (xy 426.626657 -402.956015) (xy 426.602989 -403.019017) (xy 426.571959 -403.078739)
			(xy 426.534014 -403.134324) (xy 426.512228 -403.159976) (xy 426.506408 -403.167104) (xy 426.499909 -403.184308)
			(xy 426.499528 -403.193504) (xy 426.499528 -403.351492) (xy 426.499072 -403.361642) (xy 426.491285 -403.380389)
			(xy 426.476899 -403.394712) (xy 426.458118 -403.402417) (xy 426.447966 -403.4028) (xy 425.731686 -403.4028)
			(xy 425.721563 -403.402286) (xy 425.70285 -403.394561) (xy 425.688495 -403.380284) (xy 425.68067 -403.361612)
			(xy 425.680124 -403.351492) (xy 425.680124 -403.193504) (xy 425.679707 -403.184318) (xy 425.673198 -403.167133)
			(xy 425.667424 -403.159976) (xy 425.64559 -403.134362) (xy 425.607643 -403.07877) (xy 425.576613 -403.019041)
			(xy 425.552943 -402.956032) (xy 425.536974 -402.890645) (xy 425.528934 -402.823818) (xy 422.250874 -402.823818)
			(xy 422.250874 -402.823874) (xy 422.242803 -402.890808) (xy 422.226774 -402.956294) (xy 422.203016 -403.019389)
			(xy 422.171873 -403.079184) (xy 422.133792 -403.134818) (xy 422.111932 -403.160484) (xy 422.106109 -403.16761)
			(xy 422.099612 -403.184816) (xy 422.099232 -403.194012) (xy 422.099232 -403.351492) (xy 422.098709 -403.361596)
			(xy 422.09098 -403.380268) (xy 422.076695 -403.394562) (xy 422.058028 -403.402303) (xy 422.047924 -403.4028)
			(xy 421.331644 -403.4028) (xy 421.321524 -403.402348) (xy 421.302822 -403.394614) (xy 421.288506 -403.380308)
			(xy 421.280759 -403.361611) (xy 421.280336 -403.351492) (xy 421.280336 -403.194012) (xy 421.279912 -403.184826)
			(xy 421.273407 -403.167642) (xy 421.267636 -403.160484) (xy 421.245724 -403.134858) (xy 421.207634 -403.079219)
			(xy 421.176483 -403.019418) (xy 421.15272 -402.956315) (xy 421.136687 -402.890821) (xy 421.128614 -402.823878)
			(xy 414.525968 -402.823878) (xy 414.525968 -405.623649) (xy 418.929012 -405.623649) (xy 418.929013 -405.556342)
			(xy 418.937058 -405.489518) (xy 418.953033 -405.424135) (xy 418.976709 -405.36113) (xy 419.007746 -405.301407)
			(xy 419.045698 -405.245822) (xy 419.067488 -405.22017) (xy 419.073278 -405.21302) (xy 419.079797 -405.195833)
			(xy 419.080188 -405.186642) (xy 419.080188 -404.693374) (xy 419.079793 -404.684185) (xy 419.073269 -404.667001)
			(xy 419.067488 -404.659846) (xy 419.04572 -404.634177) (xy 419.007768 -404.578594) (xy 418.976731 -404.518873)
			(xy 418.953055 -404.455871) (xy 418.937079 -404.39049) (xy 418.929032 -404.323669) (xy 418.92903 -404.256364)
			(xy 418.937073 -404.189542) (xy 418.953045 -404.124161) (xy 418.976717 -404.061157) (xy 419.007751 -404.001435)
			(xy 419.0457 -403.945849) (xy 419.067488 -403.920198) (xy 419.073267 -403.91304) (xy 419.079792 -403.895859)
			(xy 419.080188 -403.88667) (xy 419.080188 -403.728682) (xy 419.08055 -403.718503) (xy 419.088351 -403.699698)
			(xy 419.102756 -403.685313) (xy 419.12157 -403.677537) (xy 419.13175 -403.67712) (xy 419.84803 -403.67712)
			(xy 419.858187 -403.677608) (xy 419.876954 -403.685389) (xy 419.891317 -403.699756) (xy 419.899094 -403.718524)
			(xy 419.899592 -403.728682) (xy 419.899592 -403.88667) (xy 419.900018 -403.895855) (xy 419.906521 -403.91304)
			(xy 419.912292 -403.920198) (xy 419.9341 -403.945833) (xy 419.972047 -404.001422) (xy 420.003077 -404.061149)
			(xy 420.026747 -404.124155) (xy 420.042718 -404.189539) (xy 420.05076 -404.256363) (xy 420.050758 -404.32367)
			(xy 420.042712 -404.390493) (xy 420.026738 -404.455876) (xy 420.003064 -404.518882) (xy 419.97203 -404.578606)
			(xy 419.93408 -404.634193) (xy 419.912292 -404.659846) (xy 419.906492 -404.666989) (xy 419.89998 -404.684181)
			(xy 419.899592 -404.693374) (xy 419.899592 -405.186642) (xy 419.899984 -405.195831) (xy 419.90651 -405.213015)
			(xy 419.912292 -405.22017) (xy 419.934073 -405.245827) (xy 419.97202 -405.301414) (xy 420.003052 -405.361137)
			(xy 420.026723 -405.424141) (xy 420.042696 -405.489522) (xy 420.05074 -405.556343) (xy 420.050741 -405.623647)
			(xy 420.042698 -405.690469) (xy 420.026726 -405.755851) (xy 420.003055 -405.818855) (xy 419.972025 -405.878578)
			(xy 419.934078 -405.934165) (xy 419.912292 -405.959818) (xy 419.906504 -405.96697) (xy 419.899985 -405.984155)
			(xy 419.899592 -405.993346) (xy 419.899592 -406.151334) (xy 419.899095 -406.16149) (xy 419.891315 -406.180254)
			(xy 419.876951 -406.194617) (xy 419.858186 -406.202396) (xy 419.84803 -406.202896) (xy 419.13175 -406.202896)
			(xy 419.121586 -406.202396) (xy 419.102799 -406.194634) (xy 419.088413 -406.180272) (xy 419.08062 -406.161497)
			(xy 419.080188 -406.151334) (xy 419.080188 -405.993346) (xy 419.079759 -405.984161) (xy 419.073259 -405.966976)
			(xy 419.067488 -405.959818) (xy 419.045693 -405.934171) (xy 419.007741 -405.878585) (xy 418.976705 -405.818861)
			(xy 418.953031 -405.755856) (xy 418.937057 -405.690473) (xy 418.929012 -405.623649) (xy 414.525968 -405.623649)
			(xy 414.525968 -406.723789) (xy 421.128626 -406.723789) (xy 421.128629 -406.656363) (xy 421.136708 -406.589421)
			(xy 421.152748 -406.52393) (xy 421.176518 -406.460832) (xy 421.207674 -406.401035) (xy 421.245769 -406.345401)
			(xy 421.267636 -406.319736) (xy 421.273447 -406.312601) (xy 421.279952 -406.295403) (xy 421.280336 -406.286208)
			(xy 421.280336 -405.793956) (xy 421.279939 -405.784768) (xy 421.273415 -405.767584) (xy 421.267636 -405.760428)
			(xy 421.245767 -405.734767) (xy 421.207676 -405.679132) (xy 421.176523 -405.619336) (xy 421.152758 -405.556239)
			(xy 421.136722 -405.490749) (xy 421.128645 -405.423809) (xy 421.128646 -405.356385) (xy 421.136723 -405.289445)
			(xy 421.15276 -405.223956) (xy 421.176526 -405.160859) (xy 421.207679 -405.101062) (xy 421.245771 -405.045429)
			(xy 421.267636 -405.019764) (xy 421.273435 -405.012621) (xy 421.279947 -404.995429) (xy 421.280336 -404.986236)
			(xy 421.280336 -404.828756) (xy 421.28075 -404.81864) (xy 421.288509 -404.799954) (xy 421.302828 -404.785659)
			(xy 421.321527 -404.777933) (xy 421.331644 -404.777448) (xy 422.047924 -404.777448) (xy 422.058028 -404.777964)
			(xy 422.076697 -404.7857) (xy 422.090989 -404.799986) (xy 422.098732 -404.818652) (xy 422.099232 -404.828756)
			(xy 422.099232 -404.986236) (xy 422.09964 -404.995423) (xy 422.106157 -405.012607) (xy 422.111932 -405.019764)
			(xy 422.133791 -405.045433) (xy 422.171878 -405.101068) (xy 422.203027 -405.160864) (xy 422.22679 -405.22396)
			(xy 422.242825 -405.289448) (xy 422.2509 -405.356386) (xy 422.250901 -405.423808) (xy 422.242826 -405.490746)
			(xy 422.226792 -405.556234) (xy 422.203029 -405.619331) (xy 422.20075 -405.623707) (xy 423.328805 -405.623707)
			(xy 423.328805 -405.556284) (xy 423.336882 -405.489345) (xy 423.352917 -405.423856) (xy 423.376681 -405.360759)
			(xy 423.407832 -405.300962) (xy 423.44592 -405.245328) (xy 423.467784 -405.219662) (xy 423.473577 -405.212514)
			(xy 423.480094 -405.195326) (xy 423.480484 -405.186134) (xy 423.480484 -404.693882) (xy 423.480086 -404.684693)
			(xy 423.473564 -404.667509) (xy 423.467784 -404.660354) (xy 423.445942 -404.634671) (xy 423.407854 -404.579038)
			(xy 423.376703 -404.519245) (xy 423.352938 -404.45615) (xy 423.336902 -404.390663) (xy 423.328825 -404.323727)
			(xy 423.328823 -404.256306) (xy 423.336896 -404.189369) (xy 423.352929 -404.123882) (xy 423.37669 -404.060786)
			(xy 423.407837 -404.00099) (xy 423.445922 -403.945355) (xy 423.467784 -403.91969) (xy 423.473565 -403.912534)
			(xy 423.48009 -403.895352) (xy 423.480484 -403.886162) (xy 423.480484 -403.728682) (xy 423.480913 -403.718549)
			(xy 423.488655 -403.699819) (xy 423.502959 -403.685461) (xy 423.521661 -403.677651) (xy 423.531792 -403.67712)
			(xy 424.248072 -403.67712) (xy 424.258227 -403.677545) (xy 424.276983 -403.685335) (xy 424.291308 -403.699731)
			(xy 424.299005 -403.718525) (xy 424.29938 -403.728682) (xy 424.29938 -403.886162) (xy 424.299813 -403.895347)
			(xy 424.306311 -403.912531) (xy 424.31208 -403.91969) (xy 424.333966 -403.945337) (xy 424.372056 -404.000974)
			(xy 424.403207 -404.060772) (xy 424.42697 -404.123872) (xy 424.443005 -404.189363) (xy 424.451079 -404.256304)
			(xy 424.451077 -404.323729) (xy 424.442999 -404.39067) (xy 424.426961 -404.45616) (xy 424.403193 -404.519258)
			(xy 424.372039 -404.579055) (xy 424.333946 -404.634689) (xy 424.31208 -404.660354) (xy 424.306276 -404.667494)
			(xy 424.299766 -404.684688) (xy 424.29938 -404.693882) (xy 424.29938 -405.186134) (xy 424.299778 -405.195322)
			(xy 424.306301 -405.212506) (xy 424.31208 -405.219662) (xy 424.333939 -405.245332) (xy 424.372029 -405.300965)
			(xy 424.403181 -405.360761) (xy 424.426946 -405.423857) (xy 424.442983 -405.489346) (xy 424.45106 -405.556284)
			(xy 424.45106 -405.623707) (xy 424.442985 -405.690646) (xy 424.426949 -405.756134) (xy 424.403185 -405.819231)
			(xy 424.372034 -405.879027) (xy 424.333944 -405.934661) (xy 424.31208 -405.960326) (xy 424.306288 -405.967474)
			(xy 424.299771 -405.984662) (xy 424.29938 -405.993854) (xy 424.29938 -406.151334) (xy 424.298902 -406.16146)
			(xy 424.291167 -406.180179) (xy 424.276878 -406.194533) (xy 424.258196 -406.202355) (xy 424.248072 -406.202896)
			(xy 423.531792 -406.202896) (xy 423.521637 -406.202485) (xy 423.502884 -406.194686) (xy 423.48856 -406.180286)
			(xy 423.480862 -406.161491) (xy 423.480484 -406.151334) (xy 423.480484 -405.993854) (xy 423.480051 -405.984669)
			(xy 423.473553 -405.967484) (xy 423.467784 -405.960326) (xy 423.445915 -405.934665) (xy 423.407827 -405.87903)
			(xy 423.376678 -405.819233) (xy 423.352915 -405.756135) (xy 423.33688 -405.690646) (xy 423.328805 -405.623707)
			(xy 422.20075 -405.623707) (xy 422.171881 -405.679127) (xy 422.133795 -405.734762) (xy 422.111932 -405.760428)
			(xy 422.106133 -405.767571) (xy 422.099622 -405.784763) (xy 422.099232 -405.793956) (xy 422.099232 -406.286208)
			(xy 422.099654 -406.295394) (xy 422.106161 -406.312577) (xy 422.111932 -406.319736) (xy 422.133763 -406.345428)
			(xy 422.171851 -406.401059) (xy 422.203001 -406.460852) (xy 422.226766 -406.523945) (xy 422.242803 -406.589431)
			(xy 422.250881 -406.656366) (xy 422.250883 -406.72373) (xy 425.528945 -406.72373) (xy 425.528948 -406.656422)
			(xy 425.536995 -406.589598) (xy 425.552971 -406.524214) (xy 425.576647 -406.461208) (xy 425.607683 -406.401484)
			(xy 425.645635 -406.345896) (xy 425.667424 -406.320244) (xy 425.67323 -406.313105) (xy 425.679738 -406.29591)
			(xy 425.680124 -406.286716) (xy 425.680124 -405.793448) (xy 425.679685 -405.784264) (xy 425.673191 -405.76708)
			(xy 425.667424 -405.75992) (xy 425.645633 -405.734271) (xy 425.607685 -405.678684) (xy 425.576653 -405.61896)
			(xy 425.552981 -405.555955) (xy 425.537009 -405.490572) (xy 425.528965 -405.42375) (xy 425.528965 -405.356444)
			(xy 425.53701 -405.289622) (xy 425.552983 -405.22424) (xy 425.576655 -405.161235) (xy 425.607688 -405.101511)
			(xy 425.645636 -405.045924) (xy 425.667424 -405.020272) (xy 425.673218 -405.013125) (xy 425.679733 -404.995936)
			(xy 425.680124 -404.986744) (xy 425.680124 -404.828756) (xy 425.680486 -404.818596) (xy 425.688301 -404.799838)
			(xy 425.702716 -404.785515) (xy 425.721523 -404.777822) (xy 425.731686 -404.777448) (xy 426.447966 -404.777448)
			(xy 426.458091 -404.777955) (xy 426.476813 -404.785673) (xy 426.491171 -404.799953) (xy 426.49899 -404.818633)
			(xy 426.499528 -404.828756) (xy 426.499528 -404.986744) (xy 426.499911 -404.995934) (xy 426.506443 -405.013119)
			(xy 426.512228 -405.020272) (xy 426.534013 -405.045927) (xy 426.571964 -405.101512) (xy 426.602999 -405.161235)
			(xy 426.626674 -405.224239) (xy 426.642648 -405.289622) (xy 426.650693 -405.356444) (xy 426.650693 -405.42375)
			(xy 426.642649 -405.490573) (xy 426.626675 -405.555955) (xy 426.603002 -405.618959) (xy 426.600565 -405.623649)
			(xy 427.7291 -405.623649) (xy 427.729101 -405.556342) (xy 427.737146 -405.489519) (xy 427.753121 -405.424136)
			(xy 427.776796 -405.361131) (xy 427.807831 -405.301408) (xy 427.845783 -405.245822) (xy 427.867572 -405.22017)
			(xy 427.873373 -405.213028) (xy 427.879883 -405.195835) (xy 427.880272 -405.186642) (xy 427.880272 -404.693374)
			(xy 427.879881 -404.684185) (xy 427.873355 -404.667) (xy 427.867572 -404.659846) (xy 427.845805 -404.634176)
			(xy 427.807853 -404.578593) (xy 427.776817 -404.518872) (xy 427.753142 -404.45587) (xy 427.737166 -404.39049)
			(xy 427.72912 -404.323668) (xy 427.729118 -404.256365) (xy 427.73716 -404.189543) (xy 427.753132 -404.124162)
			(xy 427.776804 -404.061158) (xy 427.807836 -404.001435) (xy 427.845785 -403.94585) (xy 427.867572 -403.920198)
			(xy 427.873361 -403.913048) (xy 427.879878 -403.895861) (xy 427.880272 -403.88667) (xy 427.880272 -403.728682)
			(xy 427.88065 -403.718505) (xy 427.888447 -403.699703) (xy 427.902847 -403.685318) (xy 427.921657 -403.67754)
			(xy 427.931834 -403.67712) (xy 428.648114 -403.67712) (xy 428.65827 -403.677622) (xy 428.677036 -403.685397)
			(xy 428.6914 -403.69976) (xy 428.699178 -403.718526) (xy 428.699676 -403.728682) (xy 428.699676 -403.88667)
			(xy 428.700106 -403.895855) (xy 428.706607 -403.913039) (xy 428.712376 -403.920198) (xy 428.734185 -403.945833)
			(xy 428.772132 -404.001422) (xy 428.803164 -404.061148) (xy 428.826835 -404.124155) (xy 428.842806 -404.189539)
			(xy 428.850848 -404.256363) (xy 428.850846 -404.32367) (xy 428.8428 -404.390494) (xy 428.826825 -404.455877)
			(xy 428.80315 -404.518882) (xy 428.772115 -404.578607) (xy 428.734165 -404.634194) (xy 428.712376 -404.659846)
			(xy 428.706575 -404.666988) (xy 428.700064 -404.684181) (xy 428.699676 -404.693374) (xy 428.699676 -405.186642)
			(xy 428.700071 -405.195831) (xy 428.706596 -405.213015) (xy 428.712376 -405.22017) (xy 428.734157 -405.245827)
			(xy 428.772106 -405.301413) (xy 428.803138 -405.361136) (xy 428.826811 -405.42414) (xy 428.842784 -405.489522)
			(xy 428.850828 -405.556343) (xy 428.850829 -405.623648) (xy 428.842785 -405.69047) (xy 428.826813 -405.755851)
			(xy 428.803142 -405.818856) (xy 428.77211 -405.878579) (xy 428.734163 -405.934166) (xy 428.712376 -405.959818)
			(xy 428.706587 -405.966968) (xy 428.700068 -405.984155) (xy 428.699676 -405.993346) (xy 428.699676 -406.151334)
			(xy 428.699195 -406.161492) (xy 428.691412 -406.180259) (xy 428.677043 -406.194623) (xy 428.658272 -406.202399)
			(xy 428.648114 -406.202896) (xy 427.931834 -406.202896) (xy 427.921683 -406.202339) (xy 427.902921 -406.194583)
			(xy 427.888556 -406.180236) (xy 427.880774 -406.161485) (xy 427.880272 -406.151334) (xy 427.880272 -405.993346)
			(xy 427.879846 -405.98416) (xy 427.873344 -405.966976) (xy 427.867572 -405.959818) (xy 427.845777 -405.934171)
			(xy 427.807827 -405.878585) (xy 427.776792 -405.818861) (xy 427.753118 -405.755855) (xy 427.737144 -405.690472)
			(xy 427.7291 -405.623649) (xy 426.600565 -405.623649) (xy 426.571967 -405.678683) (xy 426.534016 -405.734268)
			(xy 426.512228 -405.75992) (xy 426.506432 -405.767065) (xy 426.499919 -405.784256) (xy 426.499528 -405.793448)
			(xy 426.499528 -406.286716) (xy 426.499924 -406.295905) (xy 426.506447 -406.313089) (xy 426.512228 -406.320244)
			(xy 426.533985 -406.345922) (xy 426.571937 -406.401504) (xy 426.602974 -406.461223) (xy 426.62665 -406.524225)
			(xy 426.642626 -406.589604) (xy 426.650673 -406.656424) (xy 426.650676 -406.723728) (xy 426.650669 -406.723789)
			(xy 429.928714 -406.723789) (xy 429.928717 -406.656363) (xy 429.936796 -406.589422) (xy 429.952835 -406.523931)
			(xy 429.976604 -406.460832) (xy 430.00776 -406.401036) (xy 430.045853 -406.345401) (xy 430.06772 -406.319736)
			(xy 430.073529 -406.312599) (xy 430.080035 -406.295402) (xy 430.08042 -406.286208) (xy 430.08042 -405.793956)
			(xy 430.080027 -405.784767) (xy 430.073501 -405.767583) (xy 430.06772 -405.760428) (xy 430.045851 -405.734766)
			(xy 430.007761 -405.679132) (xy 429.97661 -405.619335) (xy 429.952845 -405.556238) (xy 429.936809 -405.490748)
			(xy 429.928733 -405.423809) (xy 429.928734 -405.356385) (xy 429.93681 -405.289446) (xy 429.952847 -405.223956)
			(xy 429.976612 -405.160859) (xy 430.007765 -405.101063) (xy 430.045855 -405.045429) (xy 430.06772 -405.019764)
			(xy 430.073517 -405.012619) (xy 430.080031 -404.995428) (xy 430.08042 -404.986236) (xy 430.08042 -404.828756)
			(xy 430.08085 -404.818642) (xy 430.088605 -404.799959) (xy 430.102919 -404.785665) (xy 430.121613 -404.777935)
			(xy 430.131728 -404.777448) (xy 430.848008 -404.777448) (xy 430.858111 -404.777977) (xy 430.876779 -404.785708)
			(xy 430.891072 -404.799991) (xy 430.898815 -404.818654) (xy 430.899316 -404.828756) (xy 430.899316 -404.986236)
			(xy 430.899705 -404.995425) (xy 430.906233 -405.01261) (xy 430.912016 -405.019764) (xy 430.933875 -405.045433)
			(xy 430.971963 -405.101067) (xy 431.003113 -405.160863) (xy 431.026877 -405.223959) (xy 431.042912 -405.289448)
			(xy 431.050988 -405.356385) (xy 431.050989 -405.423809) (xy 431.042913 -405.490746) (xy 431.026879 -405.556235)
			(xy 431.003116 -405.619331) (xy 431.000867 -405.623648) (xy 432.128891 -405.623648) (xy 432.128892 -405.556343)
			(xy 432.136937 -405.489519) (xy 432.152911 -405.424136) (xy 432.176585 -405.361132) (xy 432.207621 -405.301408)
			(xy 432.245571 -405.245822) (xy 432.26736 -405.22017) (xy 432.273159 -405.213027) (xy 432.279671 -405.195835)
			(xy 432.28006 -405.186642) (xy 432.28006 -404.693374) (xy 432.279649 -404.684187) (xy 432.273134 -404.667004)
			(xy 432.26736 -404.659846) (xy 432.245593 -404.634176) (xy 432.207643 -404.578593) (xy 432.176607 -404.518872)
			(xy 432.152932 -404.45587) (xy 432.136957 -404.390489) (xy 432.128911 -404.323668) (xy 432.128909 -404.256365)
			(xy 432.136951 -404.189543) (xy 432.152922 -404.124162) (xy 432.176594 -404.061158) (xy 432.207626 -404.001436)
			(xy 432.245573 -403.94585) (xy 432.26736 -403.920198) (xy 432.273147 -403.913047) (xy 432.279666 -403.895861)
			(xy 432.28006 -403.88667) (xy 432.28006 -403.728682) (xy 432.28045 -403.718507) (xy 432.288245 -403.699707)
			(xy 432.302641 -403.685322) (xy 432.321446 -403.677542) (xy 432.331622 -403.67712) (xy 433.047902 -403.67712)
			(xy 433.058058 -403.677631) (xy 433.076823 -403.685403) (xy 433.091188 -403.699763) (xy 433.098965 -403.718526)
			(xy 433.099464 -403.728682) (xy 433.099464 -403.88667) (xy 433.099897 -403.895855) (xy 433.106396 -403.913039)
			(xy 433.112164 -403.920198) (xy 433.133973 -403.945832) (xy 433.171921 -404.001421) (xy 433.202954 -404.061147)
			(xy 433.226625 -404.124154) (xy 433.242596 -404.189539) (xy 433.250639 -404.256363) (xy 433.250637 -404.32367)
			(xy 433.24259 -404.390494) (xy 433.226615 -404.455877) (xy 433.20294 -404.518883) (xy 433.171904 -404.578607)
			(xy 433.133953 -404.634194) (xy 433.112164 -404.659846) (xy 433.106361 -404.666986) (xy 433.099851 -404.684181)
			(xy 433.099464 -404.693374) (xy 433.099464 -405.186642) (xy 433.099862 -405.19583) (xy 433.106385 -405.213014)
			(xy 433.112164 -405.22017) (xy 433.133946 -405.245827) (xy 433.171895 -405.301413) (xy 433.202928 -405.361136)
			(xy 433.226601 -405.42414) (xy 433.242574 -405.489521) (xy 433.250619 -405.556343) (xy 433.250619 -405.623648)
			(xy 433.242576 -405.69047) (xy 433.226604 -405.755852) (xy 433.202932 -405.818856) (xy 433.171899 -405.878579)
			(xy 433.133951 -405.934166) (xy 433.112164 -405.959818) (xy 433.106373 -405.966967) (xy 433.099856 -405.984155)
			(xy 433.099464 -405.993346) (xy 433.099464 -406.151334) (xy 433.098995 -406.161494) (xy 433.091209 -406.180263)
			(xy 433.076836 -406.194627) (xy 433.058062 -406.202401) (xy 433.047902 -406.202896) (xy 432.331622 -406.202896)
			(xy 432.32147 -406.20235) (xy 432.302708 -406.194589) (xy 432.288343 -406.180239) (xy 432.280561 -406.161486)
			(xy 432.28006 -406.151334) (xy 432.28006 -405.993346) (xy 432.279614 -405.984163) (xy 432.273124 -405.966979)
			(xy 432.26736 -405.959818) (xy 432.245566 -405.934171) (xy 432.207616 -405.878584) (xy 432.176582 -405.81886)
			(xy 432.152908 -405.755855) (xy 432.136935 -405.690472) (xy 432.128891 -405.623648) (xy 431.000867 -405.623648)
			(xy 430.971966 -405.679128) (xy 430.933879 -405.734762) (xy 430.912016 -405.760428) (xy 430.906227 -405.767579)
			(xy 430.899707 -405.784765) (xy 430.899316 -405.793956) (xy 430.899316 -406.286208) (xy 430.899719 -406.295396)
			(xy 430.906237 -406.31258) (xy 430.912016 -406.319736) (xy 430.933848 -406.345427) (xy 430.971937 -406.401059)
			(xy 431.003088 -406.460851) (xy 431.026853 -406.523945) (xy 431.04289 -406.58943) (xy 431.050968 -406.656366)
			(xy 431.050971 -406.723729) (xy 434.329033 -406.723729) (xy 434.329036 -406.656422) (xy 434.337083 -406.589598)
			(xy 434.353058 -406.524215) (xy 434.376733 -406.461209) (xy 434.407769 -406.401484) (xy 434.445719 -406.345897)
			(xy 434.467508 -406.320244) (xy 434.473312 -406.313104) (xy 434.479822 -406.295909) (xy 434.480208 -406.286716)
			(xy 434.480208 -405.793448) (xy 434.479773 -405.784263) (xy 434.473276 -405.767079) (xy 434.467508 -405.75992)
			(xy 434.445717 -405.734271) (xy 434.407771 -405.678683) (xy 434.376739 -405.618959) (xy 434.353068 -405.555954)
			(xy 434.337096 -405.490572) (xy 434.329053 -405.423749) (xy 434.329053 -405.356445) (xy 434.337097 -405.289622)
			(xy 434.35307 -405.22424) (xy 434.376742 -405.161236) (xy 434.407774 -405.101512) (xy 434.445721 -405.045925)
			(xy 434.467508 -405.020272) (xy 434.4733 -405.013124) (xy 434.479817 -404.995935) (xy 434.480208 -404.986744)
			(xy 434.480208 -404.828756) (xy 434.480586 -404.818598) (xy 434.488397 -404.799843) (xy 434.502807 -404.785521)
			(xy 434.52161 -404.777824) (xy 434.53177 -404.777448) (xy 435.24805 -404.777448) (xy 435.258175 -404.777968)
			(xy 435.276896 -404.785681) (xy 435.291254 -404.799957) (xy 435.299074 -404.818634) (xy 435.299612 -404.828756)
			(xy 435.299612 -404.986744) (xy 435.299998 -404.995934) (xy 435.306528 -405.013118) (xy 435.312312 -405.020272)
			(xy 435.334097 -405.045927) (xy 435.372049 -405.101512) (xy 435.403086 -405.161234) (xy 435.426761 -405.224239)
			(xy 435.442735 -405.289621) (xy 435.450781 -405.356444) (xy 435.450781 -405.42375) (xy 435.442736 -405.490573)
			(xy 435.426762 -405.555956) (xy 435.403088 -405.61896) (xy 435.372052 -405.678683) (xy 435.334101 -405.734269)
			(xy 435.312312 -405.75992) (xy 435.306526 -405.767073) (xy 435.300005 -405.784257) (xy 435.299612 -405.793448)
			(xy 435.299612 -406.286716) (xy 435.300012 -406.295904) (xy 435.306532 -406.313089) (xy 435.312312 -406.320244)
			(xy 435.33407 -406.345921) (xy 435.372023 -406.401503) (xy 435.40306 -406.461223) (xy 435.426737 -406.524224)
			(xy 435.442713 -406.589604) (xy 435.450761 -406.656424) (xy 435.450764 -406.723728) (xy 435.442722 -406.790549)
			(xy 435.426751 -406.85593) (xy 435.40308 -406.918933) (xy 435.372048 -406.978656) (xy 435.334099 -407.034241)
			(xy 435.312312 -407.059892) (xy 435.306538 -407.067053) (xy 435.300009 -407.084231) (xy 435.299612 -407.09342)
			(xy 435.299612 -407.251408) (xy 435.299185 -407.261561) (xy 435.291389 -407.280311) (xy 435.276994 -407.294634)
			(xy 435.258205 -407.302335) (xy 435.24805 -407.302716) (xy 434.53177 -407.302716) (xy 434.521636 -407.302297)
			(xy 434.502906 -407.294551) (xy 434.488549 -407.280244) (xy 434.480739 -407.26154) (xy 434.480208 -407.251408)
			(xy 434.480208 -407.09342) (xy 434.479786 -407.084234) (xy 434.47328 -407.06705) (xy 434.467508 -407.059892)
			(xy 434.44569 -407.034265) (xy 434.407744 -406.978674) (xy 434.376714 -406.918947) (xy 434.353044 -406.855939)
			(xy 434.337074 -406.790554) (xy 434.329033 -406.723729) (xy 431.050971 -406.723729) (xy 431.050971 -406.723786)
			(xy 431.042899 -406.790722) (xy 431.026867 -406.856209) (xy 431.003107 -406.919305) (xy 430.971961 -406.9791)
			(xy 430.933877 -407.034735) (xy 430.912016 -407.0604) (xy 430.906239 -407.067559) (xy 430.899712 -407.084739)
			(xy 430.899316 -407.093928) (xy 430.899316 -407.251408) (xy 430.898822 -407.261515) (xy 430.891084 -407.28019)
			(xy 430.87679 -407.294484) (xy 430.858115 -407.302222) (xy 430.848008 -407.302716) (xy 430.131728 -407.302716)
			(xy 430.121609 -407.302262) (xy 430.102909 -407.294526) (xy 430.088595 -407.280221) (xy 430.080845 -407.261526)
			(xy 430.08042 -407.251408) (xy 430.08042 -407.093928) (xy 430.079992 -407.084743) (xy 430.07349 -407.067559)
			(xy 430.06772 -407.0604) (xy 430.045824 -407.034761) (xy 430.007735 -406.979123) (xy 429.976584 -406.919324)
			(xy 429.952821 -406.856223) (xy 429.936787 -406.790731) (xy 429.928714 -406.723789) (xy 426.650669 -406.723789)
			(xy 426.642634 -406.790548) (xy 426.626664 -406.855929) (xy 426.602993 -406.918933) (xy 426.571962 -406.978655)
			(xy 426.534015 -407.03424) (xy 426.512228 -407.059892) (xy 426.506444 -407.067045) (xy 426.499924 -407.08423)
			(xy 426.499528 -407.09342) (xy 426.499528 -407.251408) (xy 426.499085 -407.261559) (xy 426.491292 -407.280306)
			(xy 426.476903 -407.294628) (xy 426.458119 -407.302333) (xy 426.447966 -407.302716) (xy 425.731686 -407.302716)
			(xy 425.721553 -407.302283) (xy 425.702823 -407.294543) (xy 425.688466 -407.28024) (xy 425.680655 -407.261539)
			(xy 425.680124 -407.251408) (xy 425.680124 -407.09342) (xy 425.679699 -407.084235) (xy 425.673195 -407.06705)
			(xy 425.667424 -407.059892) (xy 425.645605 -407.034266) (xy 425.607658 -406.978675) (xy 425.576627 -406.918948)
			(xy 425.552957 -406.85594) (xy 425.536987 -406.790555) (xy 425.528945 -406.72373) (xy 422.250883 -406.72373)
			(xy 422.250883 -406.723786) (xy 422.242811 -406.790722) (xy 422.22678 -406.856209) (xy 422.203021 -406.919304)
			(xy 422.171876 -406.9791) (xy 422.133793 -407.034734) (xy 422.111932 -407.0604) (xy 422.106145 -407.067551)
			(xy 422.099626 -407.084737) (xy 422.099232 -407.093928) (xy 422.099232 -407.251408) (xy 422.098722 -407.261513)
			(xy 422.090988 -407.280185) (xy 422.076699 -407.294479) (xy 422.058029 -407.302219) (xy 422.047924 -407.302716)
			(xy 421.331644 -407.302716) (xy 421.321526 -407.302248) (xy 421.302827 -407.294518) (xy 421.288512 -407.280217)
			(xy 421.280762 -407.261525) (xy 421.280336 -407.251408) (xy 421.280336 -407.093928) (xy 421.279904 -407.084743)
			(xy 421.273405 -407.067559) (xy 421.267636 -407.0604) (xy 421.245739 -407.034761) (xy 421.207649 -406.979124)
			(xy 421.176498 -406.919324) (xy 421.152734 -406.856224) (xy 421.1367 -406.790731) (xy 421.128626 -406.723789)
			(xy 414.525968 -406.723789) (xy 414.525968 -409.523827) (xy 418.928991 -409.523827) (xy 418.928995 -409.456519)
			(xy 418.937043 -409.389693) (xy 418.953021 -409.324308) (xy 418.9767 -409.261302) (xy 419.00774 -409.201577)
			(xy 419.045697 -409.145992) (xy 419.067488 -409.12034) (xy 419.073291 -409.113199) (xy 419.079802 -409.096005)
			(xy 419.080188 -409.086812) (xy 419.080188 -408.593544) (xy 419.079759 -408.584359) (xy 419.073259 -408.567174)
			(xy 419.067488 -408.560016) (xy 419.045691 -408.534371) (xy 419.007739 -408.478785) (xy 418.976704 -408.419061)
			(xy 418.953029 -408.356055) (xy 418.937055 -408.290671) (xy 418.929011 -408.223847) (xy 418.929012 -408.156541)
			(xy 418.937057 -408.089717) (xy 418.953033 -408.024333) (xy 418.976708 -407.961328) (xy 419.007745 -407.901605)
			(xy 419.045698 -407.84602) (xy 419.067488 -407.820368) (xy 419.073279 -407.813219) (xy 419.079797 -407.796031)
			(xy 419.080188 -407.78684) (xy 419.080188 -407.628852) (xy 419.080582 -407.618696) (xy 419.088391 -407.599945)
			(xy 419.102796 -407.585624) (xy 419.121592 -407.577924) (xy 419.13175 -407.577544) (xy 419.84803 -407.577544)
			(xy 419.858159 -407.578002) (xy 419.876882 -407.58574) (xy 419.891237 -407.600035) (xy 419.899055 -407.618725)
			(xy 419.899592 -407.628852) (xy 419.899592 -407.78684) (xy 419.899985 -407.796029) (xy 419.906511 -407.813213)
			(xy 419.912292 -407.820368) (xy 419.934071 -407.846027) (xy 419.972018 -407.901613) (xy 420.00305 -407.961336)
			(xy 420.026722 -408.02434) (xy 420.042694 -408.089721) (xy 420.050739 -408.156542) (xy 420.050739 -408.223846)
			(xy 420.042697 -408.290667) (xy 420.026725 -408.356049) (xy 420.003055 -408.419053) (xy 419.972024 -408.478776)
			(xy 419.934078 -408.534363) (xy 419.912292 -408.560016) (xy 419.906505 -408.567168) (xy 419.899985 -408.584353)
			(xy 419.899592 -408.593544) (xy 419.899592 -409.086812) (xy 419.899998 -409.096) (xy 419.906515 -409.113184)
			(xy 419.912292 -409.12034) (xy 419.934043 -409.146022) (xy 419.971991 -409.201605) (xy 420.003024 -409.261324)
			(xy 420.026698 -409.324325) (xy 420.042672 -409.389703) (xy 420.050719 -409.456522) (xy 420.050722 -409.523824)
			(xy 420.042682 -409.590643) (xy 420.026714 -409.656023) (xy 420.003047 -409.719026) (xy 419.972019 -409.778749)
			(xy 419.934077 -409.834336) (xy 419.912292 -409.859988) (xy 419.906475 -409.867118) (xy 419.899973 -409.88432)
			(xy 419.899592 -409.893516) (xy 419.899592 -410.051504) (xy 419.899181 -410.061659) (xy 419.891383 -410.080413)
			(xy 419.876983 -410.094737) (xy 419.858187 -410.102435) (xy 419.84803 -410.102812) (xy 419.13175 -410.102812)
			(xy 419.121633 -410.102234) (xy 419.102923 -410.094532) (xy 419.088567 -410.080274) (xy 419.080736 -410.061618)
			(xy 419.080188 -410.051504) (xy 419.080188 -409.893516) (xy 419.079773 -409.884329) (xy 419.073263 -409.867145)
			(xy 419.067488 -409.859988) (xy 419.045663 -409.834366) (xy 419.007713 -409.778776) (xy 418.976678 -409.719049)
			(xy 418.953005 -409.65604) (xy 418.937033 -409.590654) (xy 418.928991 -409.523827) (xy 414.525968 -409.523827)
			(xy 414.525968 -410.623701) (xy 421.128637 -410.623701) (xy 421.128638 -410.556275) (xy 421.136716 -410.489335)
			(xy 421.152755 -410.423845) (xy 421.176522 -410.360747) (xy 421.207677 -410.300951) (xy 421.24577 -410.245317)
			(xy 421.267636 -410.219652) (xy 421.27344 -410.212512) (xy 421.279949 -410.195317) (xy 421.280336 -410.186124)
			(xy 421.280336 -409.693872) (xy 421.279931 -409.684684) (xy 421.273413 -409.667501) (xy 421.267636 -409.660344)
			(xy 421.245783 -409.63467) (xy 421.207691 -409.579037) (xy 421.176538 -409.519243) (xy 421.152771 -409.456147)
			(xy 421.136734 -409.390659) (xy 421.128657 -409.323721) (xy 421.128656 -409.256297) (xy 421.136731 -409.189359)
			(xy 421.152766 -409.12387) (xy 421.176531 -409.060774) (xy 421.207682 -409.000978) (xy 421.245771 -408.945345)
			(xy 421.267636 -408.91968) (xy 421.273428 -408.912532) (xy 421.279945 -408.895343) (xy 421.280336 -408.886152)
			(xy 421.280336 -408.728672) (xy 421.280694 -408.718543) (xy 421.288458 -408.699832) (xy 421.302793 -408.685517)
			(xy 421.321515 -408.67778) (xy 421.331644 -408.677364) (xy 422.047924 -408.677364) (xy 422.05803 -408.677864)
			(xy 422.076702 -408.685603) (xy 422.090994 -408.699895) (xy 422.098735 -408.718566) (xy 422.099232 -408.728672)
			(xy 422.099232 -408.886152) (xy 422.09968 -408.895335) (xy 422.106169 -408.912519) (xy 422.111932 -408.91968)
			(xy 422.133807 -408.945336) (xy 422.171893 -409.000973) (xy 422.203041 -409.06077) (xy 422.226803 -409.123868)
			(xy 422.242837 -409.189358) (xy 422.250911 -409.256297) (xy 422.25091 -409.323721) (xy 422.242834 -409.39066)
			(xy 422.226798 -409.456149) (xy 422.203034 -409.519246) (xy 422.200617 -409.523886) (xy 423.328784 -409.523886)
			(xy 423.328787 -409.45646) (xy 423.336866 -409.389519) (xy 423.352905 -409.324029) (xy 423.376672 -409.26093)
			(xy 423.407826 -409.201133) (xy 423.445918 -409.145498) (xy 423.467784 -409.119832) (xy 423.47359 -409.112693)
			(xy 423.4801 -409.095498) (xy 423.480484 -409.086304) (xy 423.480484 -408.594052) (xy 423.480052 -408.584867)
			(xy 423.473554 -408.567682) (xy 423.467784 -408.560524) (xy 423.445913 -408.534865) (xy 423.407825 -408.479229)
			(xy 423.376676 -408.419432) (xy 423.352913 -408.356334) (xy 423.336878 -408.290845) (xy 423.328803 -408.223906)
			(xy 423.328804 -408.156482) (xy 423.336881 -408.089543) (xy 423.352916 -408.024054) (xy 423.376681 -407.960957)
			(xy 423.407832 -407.901161) (xy 423.44592 -407.845526) (xy 423.467784 -407.81986) (xy 423.473578 -407.812713)
			(xy 423.480095 -407.795524) (xy 423.480484 -407.786332) (xy 423.480484 -407.628852) (xy 423.480946 -407.618742)
			(xy 423.488696 -407.600066) (xy 423.503 -407.585774) (xy 423.521682 -407.578038) (xy 423.531792 -407.577544)
			(xy 424.248072 -407.577544) (xy 424.258172 -407.578106) (xy 424.276839 -407.585825) (xy 424.291133 -407.600097)
			(xy 424.298879 -407.618753) (xy 424.29938 -407.628852) (xy 424.29938 -407.786332) (xy 424.299779 -407.79552)
			(xy 424.306301 -407.812704) (xy 424.31208 -407.81986) (xy 424.333937 -407.845531) (xy 424.372027 -407.901165)
			(xy 424.403179 -407.96096) (xy 424.426945 -408.024056) (xy 424.442981 -408.089544) (xy 424.451058 -408.156482)
			(xy 424.451059 -408.223906) (xy 424.442984 -408.290844) (xy 424.426948 -408.356333) (xy 424.403184 -408.419429)
			(xy 424.372033 -408.479225) (xy 424.333944 -408.534859) (xy 424.31208 -408.560524) (xy 424.306288 -408.567673)
			(xy 424.299771 -408.584861) (xy 424.29938 -408.594052) (xy 424.29938 -409.086304) (xy 424.299792 -409.095491)
			(xy 424.306305 -409.112675) (xy 424.31208 -409.119832) (xy 424.333909 -409.145526) (xy 424.372 -409.201156)
			(xy 424.403154 -409.260948) (xy 424.426921 -409.324041) (xy 424.442959 -409.389527) (xy 424.451039 -409.456462)
			(xy 424.451042 -409.523884) (xy 424.442969 -409.59082) (xy 424.426937 -409.656307) (xy 424.403176 -409.719403)
			(xy 424.372028 -409.779198) (xy 424.333943 -409.834831) (xy 424.31208 -409.860496) (xy 424.3063 -409.867653)
			(xy 424.299776 -409.884835) (xy 424.29938 -409.894024) (xy 424.29938 -410.051504) (xy 424.298987 -410.061629)
			(xy 424.291234 -410.080337) (xy 424.27691 -410.094651) (xy 424.258197 -410.102393) (xy 424.248072 -410.102812)
			(xy 423.531792 -410.102812) (xy 423.521684 -410.102322) (xy 423.503008 -410.094584) (xy 423.488714 -410.080288)
			(xy 423.480978 -410.061612) (xy 423.480484 -410.051504) (xy 423.480484 -409.894024) (xy 423.480066 -409.884838)
			(xy 423.473558 -409.867653) (xy 423.467784 -409.860496) (xy 423.445885 -409.83486) (xy 423.407799 -409.779221)
			(xy 423.37665 -409.71942) (xy 423.352889 -409.65632) (xy 423.336856 -409.590827) (xy 423.328784 -409.523886)
			(xy 422.200617 -409.523886) (xy 422.171884 -409.579043) (xy 422.133796 -409.634678) (xy 422.111932 -409.660344)
			(xy 422.106126 -409.667482) (xy 422.099619 -409.684678) (xy 422.099232 -409.693872) (xy 422.099232 -410.186124)
			(xy 422.099646 -410.19531) (xy 422.106159 -410.212494) (xy 422.111932 -410.219652) (xy 422.133779 -410.245331)
			(xy 422.171866 -410.300964) (xy 422.203016 -410.360759) (xy 422.22678 -410.423854) (xy 422.242815 -410.489341)
			(xy 422.250892 -410.556277) (xy 422.250893 -410.623641) (xy 425.528957 -410.623641) (xy 425.528958 -410.556335)
			(xy 425.537003 -410.489512) (xy 425.552978 -410.424129) (xy 425.576652 -410.361123) (xy 425.607686 -410.301399)
			(xy 425.645636 -410.245812) (xy 425.667424 -410.22016) (xy 425.673223 -410.213017) (xy 425.679735 -410.195825)
			(xy 425.680124 -410.186632) (xy 425.680124 -409.693364) (xy 425.679726 -409.684176) (xy 425.673203 -409.666992)
			(xy 425.667424 -409.659836) (xy 425.645648 -409.634174) (xy 425.6077 -409.578589) (xy 425.576667 -409.518866)
			(xy 425.552994 -409.455863) (xy 425.537021 -409.390482) (xy 425.528976 -409.323661) (xy 425.528975 -409.256357)
			(xy 425.537018 -409.189536) (xy 425.552989 -409.124154) (xy 425.57666 -409.06115) (xy 425.607691 -409.001427)
			(xy 425.645637 -408.94584) (xy 425.667424 -408.920188) (xy 425.673211 -408.913036) (xy 425.679731 -408.895851)
			(xy 425.680124 -408.88666) (xy 425.680124 -408.728672) (xy 425.680499 -408.718513) (xy 425.688308 -408.699755)
			(xy 425.70272 -408.685432) (xy 425.721525 -408.677738) (xy 425.731686 -408.677364) (xy 426.447966 -408.677364)
			(xy 426.458093 -408.677855) (xy 426.476818 -408.685576) (xy 426.491177 -408.699862) (xy 426.498993 -408.718547)
			(xy 426.499528 -408.728672) (xy 426.499528 -408.88666) (xy 426.499951 -408.895846) (xy 426.506455 -408.913031)
			(xy 426.512228 -408.920188) (xy 426.534028 -408.94583) (xy 426.571979 -409.001417) (xy 426.603014 -409.061142)
			(xy 426.626687 -409.124148) (xy 426.64266 -409.189532) (xy 426.650704 -409.256356) (xy 426.650703 -409.323662)
			(xy 426.642657 -409.390486) (xy 426.626682 -409.45587) (xy 426.603006 -409.518875) (xy 426.600433 -409.523827)
			(xy 427.729079 -409.523827) (xy 427.729082 -409.456519) (xy 427.73713 -409.389693) (xy 427.753108 -409.324308)
			(xy 427.776786 -409.261302) (xy 427.807826 -409.201578) (xy 427.845781 -409.145992) (xy 427.867572 -409.12034)
			(xy 427.873385 -409.113207) (xy 427.879888 -409.096007) (xy 427.880272 -409.086812) (xy 427.880272 -408.593544)
			(xy 427.879847 -408.584358) (xy 427.873344 -408.567174) (xy 427.867572 -408.560016) (xy 427.845776 -408.534371)
			(xy 427.807825 -408.478784) (xy 427.77679 -408.41906) (xy 427.753116 -408.356054) (xy 427.737143 -408.290671)
			(xy 427.729099 -408.223847) (xy 427.7291 -408.156541) (xy 427.737145 -408.089717) (xy 427.75312 -408.024334)
			(xy 427.776795 -407.961329) (xy 427.807831 -407.901606) (xy 427.845783 -407.84602) (xy 427.867572 -407.820368)
			(xy 427.873373 -407.813227) (xy 427.879883 -407.796033) (xy 427.880272 -407.78684) (xy 427.880272 -407.628852)
			(xy 427.880682 -407.618698) (xy 427.888488 -407.59995) (xy 427.902887 -407.58563) (xy 427.921678 -407.577927)
			(xy 427.931834 -407.577544) (xy 428.648114 -407.577544) (xy 428.658242 -407.578015) (xy 428.676964 -407.585749)
			(xy 428.69132 -407.600039) (xy 428.699138 -407.618726) (xy 428.699676 -407.628852) (xy 428.699676 -407.78684)
			(xy 428.700072 -407.796029) (xy 428.706596 -407.813212) (xy 428.712376 -407.820368) (xy 428.734155 -407.846027)
			(xy 428.772104 -407.901613) (xy 428.803136 -407.961335) (xy 428.826809 -408.024339) (xy 428.842782 -408.08972)
			(xy 428.850827 -408.156542) (xy 428.850827 -408.223846) (xy 428.842784 -408.290668) (xy 428.826813 -408.356049)
			(xy 428.803141 -408.419054) (xy 428.77211 -408.478777) (xy 428.734163 -408.534364) (xy 428.712376 -408.560016)
			(xy 428.706587 -408.567167) (xy 428.700069 -408.584353) (xy 428.699676 -408.593544) (xy 428.699676 -409.086812)
			(xy 428.700086 -409.095999) (xy 428.7066 -409.113183) (xy 428.712376 -409.12034) (xy 428.734128 -409.146022)
			(xy 428.772077 -409.201604) (xy 428.803111 -409.261324) (xy 428.826785 -409.324324) (xy 428.84276 -409.389703)
			(xy 428.850806 -409.456522) (xy 428.85081 -409.523824) (xy 428.842769 -409.590644) (xy 428.826801 -409.656024)
			(xy 428.803133 -409.719027) (xy 428.772104 -409.778749) (xy 428.734161 -409.834335) (xy 428.712376 -409.859988)
			(xy 428.706557 -409.867117) (xy 428.700056 -409.88432) (xy 428.699676 -409.893516) (xy 428.699676 -410.051504)
			(xy 428.699281 -410.061661) (xy 428.69148 -410.080418) (xy 428.677074 -410.094742) (xy 428.658274 -410.102438)
			(xy 428.648114 -410.102812) (xy 427.931834 -410.102812) (xy 427.921716 -410.102247) (xy 427.903005 -410.09454)
			(xy 427.88865 -410.080278) (xy 427.88082 -410.061619) (xy 427.880272 -410.051504) (xy 427.880272 -409.893516)
			(xy 427.879861 -409.884329) (xy 427.873349 -409.867144) (xy 427.867572 -409.859988) (xy 427.845748 -409.834366)
			(xy 427.807798 -409.778776) (xy 427.776764 -409.719048) (xy 427.753092 -409.65604) (xy 427.73712 -409.590654)
			(xy 427.729079 -409.523827) (xy 426.600433 -409.523827) (xy 426.57197 -409.578598) (xy 426.534017 -409.634184)
			(xy 426.512228 -409.659836) (xy 426.506425 -409.666976) (xy 426.499916 -409.684171) (xy 426.499528 -409.693364)
			(xy 426.499528 -410.186632) (xy 426.499917 -410.195822) (xy 426.506445 -410.213006) (xy 426.512228 -410.22016)
			(xy 426.534001 -410.245825) (xy 426.571952 -410.301409) (xy 426.602988 -410.36113) (xy 426.626663 -410.424133)
			(xy 426.642638 -410.489514) (xy 426.650684 -410.556336) (xy 426.650686 -410.62364) (xy 426.650679 -410.623701)
			(xy 429.928725 -410.623701) (xy 429.928726 -410.556275) (xy 429.936804 -410.489336) (xy 429.952842 -410.423845)
			(xy 429.976609 -410.360748) (xy 430.007762 -410.300951) (xy 430.045854 -410.245317) (xy 430.06772 -410.219652)
			(xy 430.073522 -410.212511) (xy 430.080033 -410.195317) (xy 430.08042 -410.186124) (xy 430.08042 -409.693872)
			(xy 430.080019 -409.684684) (xy 430.073498 -409.6675) (xy 430.06772 -409.660344) (xy 430.045867 -409.634669)
			(xy 430.007777 -409.579037) (xy 429.976624 -409.519242) (xy 429.952859 -409.456146) (xy 429.936822 -409.390658)
			(xy 429.928745 -409.323721) (xy 429.928744 -409.256297) (xy 429.936819 -409.18936) (xy 429.952853 -409.123871)
			(xy 429.976617 -409.060775) (xy 430.007767 -409.000979) (xy 430.045856 -408.945345) (xy 430.06772 -408.91968)
			(xy 430.07351 -408.91253) (xy 430.080028 -408.895343) (xy 430.08042 -408.886152) (xy 430.08042 -408.728672)
			(xy 430.080863 -408.718559) (xy 430.088613 -408.699876) (xy 430.102923 -408.685582) (xy 430.121614 -408.677852)
			(xy 430.131728 -408.677364) (xy 430.848008 -408.677364) (xy 430.858113 -408.677878) (xy 430.876784 -408.685611)
			(xy 430.891077 -408.699899) (xy 430.898818 -408.718567) (xy 430.899316 -408.728672) (xy 430.899316 -408.886152)
			(xy 430.899745 -408.895337) (xy 430.906245 -408.912522) (xy 430.912016 -408.91968) (xy 430.933891 -408.945336)
			(xy 430.971979 -409.000972) (xy 431.003128 -409.06077) (xy 431.026891 -409.123868) (xy 431.042925 -409.189358)
			(xy 431.050999 -409.256297) (xy 431.050998 -409.323721) (xy 431.042922 -409.39066) (xy 431.026885 -409.456149)
			(xy 431.00312 -409.519247) (xy 431.000734 -409.523827) (xy 432.12887 -409.523827) (xy 432.128873 -409.456519)
			(xy 432.136921 -409.389693) (xy 432.152898 -409.324309) (xy 432.176576 -409.261303) (xy 432.207615 -409.201578)
			(xy 432.245569 -409.145992) (xy 432.26736 -409.12034) (xy 432.273172 -409.113206) (xy 432.279676 -409.096007)
			(xy 432.28006 -409.086812) (xy 432.28006 -408.593544) (xy 432.279615 -408.584361) (xy 432.273124 -408.567177)
			(xy 432.26736 -408.560016) (xy 432.245564 -408.53437) (xy 432.207614 -408.478784) (xy 432.17658 -408.419059)
			(xy 432.152907 -408.356054) (xy 432.136934 -408.290671) (xy 432.12889 -408.223847) (xy 432.128891 -408.156541)
			(xy 432.136936 -408.089717) (xy 432.15291 -408.024335) (xy 432.176585 -407.96133) (xy 432.20762 -407.901606)
			(xy 432.245571 -407.84602) (xy 432.26736 -407.820368) (xy 432.27316 -407.813226) (xy 432.279671 -407.796033)
			(xy 432.28006 -407.78684) (xy 432.28006 -407.628852) (xy 432.280482 -407.6187) (xy 432.288286 -407.599954)
			(xy 432.302681 -407.585634) (xy 432.321468 -407.577929) (xy 432.331622 -407.577544) (xy 433.047902 -407.577544)
			(xy 433.058029 -407.578025) (xy 433.076751 -407.585754) (xy 433.091108 -407.600042) (xy 433.098926 -407.618727)
			(xy 433.099464 -407.628852) (xy 433.099464 -407.78684) (xy 433.099863 -407.796028) (xy 433.106385 -407.813212)
			(xy 433.112164 -407.820368) (xy 433.133944 -407.846027) (xy 433.171893 -407.901612) (xy 433.202926 -407.961335)
			(xy 433.226599 -408.024339) (xy 433.242573 -408.08972) (xy 433.250618 -408.156542) (xy 433.250618 -408.223846)
			(xy 433.242575 -408.290668) (xy 433.226603 -408.35605) (xy 433.202931 -408.419054) (xy 433.171899 -408.478778)
			(xy 433.133951 -408.534364) (xy 433.112164 -408.560016) (xy 433.106374 -408.567165) (xy 433.099856 -408.584353)
			(xy 433.099464 -408.593544) (xy 433.099464 -409.086812) (xy 433.099876 -409.095999) (xy 433.106389 -409.113183)
			(xy 433.112164 -409.12034) (xy 433.133916 -409.146021) (xy 433.171866 -409.201604) (xy 433.2029 -409.261323)
			(xy 433.226575 -409.324324) (xy 433.24255 -409.389703) (xy 433.250597 -409.456522) (xy 433.250601 -409.523824)
			(xy 433.24256 -409.590644) (xy 433.226591 -409.656024) (xy 433.202922 -409.719027) (xy 433.171894 -409.77875)
			(xy 433.133949 -409.834336) (xy 433.112164 -409.859988) (xy 433.106343 -409.867116) (xy 433.099844 -409.88432)
			(xy 433.099464 -409.893516) (xy 433.099464 -410.051504) (xy 433.099081 -410.061663) (xy 433.091277 -410.080422)
			(xy 433.076868 -410.094747) (xy 433.058063 -410.10244) (xy 433.047902 -410.102812) (xy 432.331622 -410.102812)
			(xy 432.321503 -410.102257) (xy 432.302792 -410.094546) (xy 432.288437 -410.080281) (xy 432.280608 -410.06162)
			(xy 432.28006 -410.051504) (xy 432.28006 -409.893516) (xy 432.279629 -409.884331) (xy 432.273128 -409.867147)
			(xy 432.26736 -409.859988) (xy 432.245536 -409.834365) (xy 432.207587 -409.778775) (xy 432.176554 -409.719048)
			(xy 432.152882 -409.656039) (xy 432.136911 -409.590653) (xy 432.12887 -409.523827) (xy 431.000734 -409.523827)
			(xy 430.971969 -409.579043) (xy 430.93388 -409.634678) (xy 430.912016 -409.660344) (xy 430.90622 -409.66749)
			(xy 430.899705 -409.68468) (xy 430.899316 -409.693872) (xy 430.899316 -410.186124) (xy 430.899711 -410.195313)
			(xy 430.906235 -410.212497) (xy 430.912016 -410.219652) (xy 430.933864 -410.24533) (xy 430.971952 -410.300963)
			(xy 431.003102 -410.360758) (xy 431.026867 -410.423853) (xy 431.042903 -410.48934) (xy 431.05098 -410.556277)
			(xy 431.050981 -410.623641) (xy 434.329044 -410.623641) (xy 434.329046 -410.556335) (xy 434.337091 -410.489512)
			(xy 434.353065 -410.424129) (xy 434.376738 -410.361124) (xy 434.407772 -410.3014) (xy 434.44572 -410.245813)
			(xy 434.467508 -410.22016) (xy 434.473305 -410.213015) (xy 434.479819 -410.195824) (xy 434.480208 -410.186632)
			(xy 434.480208 -409.693364) (xy 434.479814 -409.684175) (xy 434.473289 -409.666991) (xy 434.467508 -409.659836)
			(xy 434.445733 -409.634174) (xy 434.407786 -409.578588) (xy 434.376754 -409.518866) (xy 434.353082 -409.455862)
			(xy 434.337109 -409.390482) (xy 434.329064 -409.323661) (xy 434.329063 -409.256357) (xy 434.337106 -409.189536)
			(xy 434.353076 -409.124155) (xy 434.376746 -409.061151) (xy 434.407777 -409.001427) (xy 434.445722 -408.945841)
			(xy 434.467508 -408.920188) (xy 434.473293 -408.913035) (xy 434.479814 -408.89585) (xy 434.480208 -408.88666)
			(xy 434.480208 -408.728672) (xy 434.480599 -408.718515) (xy 434.488405 -408.69976) (xy 434.502811 -408.685438)
			(xy 434.521611 -408.67774) (xy 434.53177 -408.677364) (xy 435.24805 -408.677364) (xy 435.258176 -408.677868)
			(xy 435.276901 -408.685584) (xy 435.29126 -408.699866) (xy 435.299077 -408.718548) (xy 435.299612 -408.728672)
			(xy 435.299612 -408.88666) (xy 435.300039 -408.895846) (xy 435.30654 -408.91303) (xy 435.312312 -408.920188)
			(xy 435.334113 -408.94583) (xy 435.372065 -409.001417) (xy 435.4031 -409.061141) (xy 435.426774 -409.124147)
			(xy 435.442748 -409.189531) (xy 435.450792 -409.256356) (xy 435.450791 -409.323662) (xy 435.442745 -409.390487)
			(xy 435.426769 -409.45587) (xy 435.403093 -409.518875) (xy 435.372055 -409.578599) (xy 435.334102 -409.634184)
			(xy 435.312312 -409.659836) (xy 435.306519 -409.666984) (xy 435.300002 -409.684172) (xy 435.299612 -409.693364)
			(xy 435.299612 -410.186632) (xy 435.300004 -410.195821) (xy 435.30653 -410.213006) (xy 435.312312 -410.22016)
			(xy 435.334085 -410.245824) (xy 435.372038 -410.301408) (xy 435.403075 -410.361129) (xy 435.42675 -410.424132)
			(xy 435.442726 -410.489514) (xy 435.450772 -410.556336) (xy 435.450774 -410.62364) (xy 435.44273 -410.690463)
			(xy 435.426758 -410.755845) (xy 435.403084 -410.818849) (xy 435.37205 -410.878571) (xy 435.3341 -410.934157)
			(xy 435.312312 -410.959808) (xy 435.306531 -410.966964) (xy 435.300007 -410.984146) (xy 435.299612 -410.993336)
			(xy 435.299612 -411.151324) (xy 435.299198 -411.161478) (xy 435.291397 -411.180229) (xy 435.276998 -411.194551)
			(xy 435.258206 -411.202252) (xy 435.24805 -411.202632) (xy 434.53177 -411.202632) (xy 434.521638 -411.202197)
			(xy 434.502911 -411.194454) (xy 434.488554 -411.180152) (xy 434.480741 -411.161454) (xy 434.480208 -411.151324)
			(xy 434.480208 -410.993336) (xy 434.479779 -410.984151) (xy 434.473278 -410.966966) (xy 434.467508 -410.959808)
			(xy 434.445706 -410.934168) (xy 434.407759 -410.878579) (xy 434.376728 -410.818854) (xy 434.353058 -410.755848)
			(xy 434.337087 -410.690464) (xy 434.329044 -410.623641) (xy 431.050981 -410.623641) (xy 431.050981 -410.623699)
			(xy 431.042907 -410.690636) (xy 431.026874 -410.756124) (xy 431.003112 -410.81922) (xy 430.971964 -410.879016)
			(xy 430.933878 -410.934651) (xy 430.912016 -410.960316) (xy 430.906232 -410.96747) (xy 430.899709 -410.984654)
			(xy 430.899316 -410.993844) (xy 430.899316 -411.151324) (xy 430.898835 -411.161432) (xy 430.891092 -411.180108)
			(xy 430.876795 -411.194401) (xy 430.858116 -411.202138) (xy 430.848008 -411.202632) (xy 430.131728 -411.202632)
			(xy 430.121611 -411.202162) (xy 430.102914 -411.194429) (xy 430.0886 -411.180129) (xy 430.080848 -411.16144)
			(xy 430.08042 -411.151324) (xy 430.08042 -410.993844) (xy 430.079984 -410.98466) (xy 430.073488 -410.967475)
			(xy 430.06772 -410.960316) (xy 430.04584 -410.934664) (xy 430.00775 -410.879028) (xy 429.976599 -410.81923)
			(xy 429.952835 -410.756132) (xy 429.9368 -410.690641) (xy 429.928725 -410.623701) (xy 426.650679 -410.623701)
			(xy 426.642643 -410.690462) (xy 426.62667 -410.755844) (xy 426.602998 -410.818848) (xy 426.571965 -410.878571)
			(xy 426.534016 -410.934156) (xy 426.512228 -410.959808) (xy 426.506437 -410.966957) (xy 426.499921 -410.984145)
			(xy 426.499528 -410.993336) (xy 426.499528 -411.151324) (xy 426.499099 -411.161476) (xy 426.4913 -411.180224)
			(xy 426.476907 -411.194545) (xy 426.45812 -411.202249) (xy 426.447966 -411.202632) (xy 425.731686 -411.202632)
			(xy 425.721555 -411.202184) (xy 425.702828 -411.194446) (xy 425.688472 -411.180148) (xy 425.680658 -411.161453)
			(xy 425.680124 -411.151324) (xy 425.680124 -410.993336) (xy 425.679691 -410.984151) (xy 425.673193 -410.966967)
			(xy 425.667424 -410.959808) (xy 425.645621 -410.934169) (xy 425.607674 -410.87858) (xy 425.576642 -410.818855)
			(xy 425.552971 -410.755848) (xy 425.536999 -410.690465) (xy 425.528957 -410.623641) (xy 422.250893 -410.623641)
			(xy 422.250893 -410.623699) (xy 422.242819 -410.690635) (xy 422.226787 -410.756123) (xy 422.203026 -410.819219)
			(xy 422.171879 -410.879015) (xy 422.133794 -410.93465) (xy 422.111932 -410.960316) (xy 422.106138 -410.967463)
			(xy 422.099624 -410.984652) (xy 422.099232 -410.993844) (xy 422.099232 -411.151324) (xy 422.098735 -411.16143)
			(xy 422.090996 -411.180103) (xy 422.076703 -411.194396) (xy 422.05803 -411.202135) (xy 422.047924 -411.202632)
			(xy 421.331644 -411.202632) (xy 421.321528 -411.202149) (xy 421.302832 -411.194421) (xy 421.288517 -411.180125)
			(xy 421.280765 -411.161439) (xy 421.280336 -411.151324) (xy 421.280336 -410.993844) (xy 421.279896 -410.98466)
			(xy 421.273402 -410.967476) (xy 421.267636 -410.960316) (xy 421.245755 -410.934664) (xy 421.207664 -410.879029)
			(xy 421.176512 -410.819231) (xy 421.152748 -410.756132) (xy 421.136712 -410.690641) (xy 421.128637 -410.623701)
			(xy 414.525968 -410.623701) (xy 414.525968 -417.366196) (xy 414.52546 -417.366196) (xy 414.52546 -417.533836)
			(xy 414.525117 -417.545925) (xy 414.517634 -417.568917) (xy 414.503411 -417.588471) (xy 414.483842 -417.602672)
			(xy 414.460842 -417.61013) (xy 414.448752 -417.610544) (xy 401.15109 -417.610544) (xy 401.138998 -417.610101)
			(xy 401.115995 -417.602639) (xy 401.096414 -417.588447) (xy 401.082164 -417.568908) (xy 401.074635 -417.545926)
			(xy 401.074128 -417.533836) (xy 326.525636 -417.533836) (xy 326.525172 -417.545885) (xy 326.517733 -417.568805)
			(xy 326.503592 -417.588317) (xy 326.484126 -417.602521) (xy 326.461229 -417.610032) (xy 326.449182 -417.610544)
			(xy 313.151012 -417.610544) (xy 313.138942 -417.610026) (xy 313.115981 -417.602571) (xy 313.096447 -417.588387)
			(xy 313.082251 -417.568862) (xy 313.074781 -417.545906) (xy 313.074304 -417.533836) (xy 313.074304 -417.379404)
			(xy 313.073796 -417.379404) (xy 273.436768 -417.379404) (xy 273.507194 -417.441568) (xy 273.606535 -417.539604)
			(xy 273.653758 -417.590986) (xy 273.692133 -417.632558) (xy 273.77424 -417.71041) (xy 273.862012 -417.781815)
			(xy 273.954943 -417.846362) (xy 274.052499 -417.90368) (xy 274.154119 -417.95344) (xy 274.259218 -417.995354)
			(xy 274.367191 -418.029182) (xy 274.477417 -418.05473) (xy 274.589263 -418.07185) (xy 274.702084 -418.080444)
			(xy 274.758658 -418.080952) (xy 465.600034 -418.080952) (xy 465.655802 -418.080429) (xy 465.767025 -418.072092)
			(xy 465.877315 -418.055466) (xy 465.986054 -418.030644) (xy 466.092633 -417.997766) (xy 466.196458 -417.957015)
			(xy 466.296947 -417.90862) (xy 466.393539 -417.85285) (xy 466.485692 -417.790018) (xy 466.572893 -417.720474)
			(xy 466.654653 -417.644609) (xy 466.730515 -417.562846) (xy 466.800054 -417.475643) (xy 466.862883 -417.383486)
			(xy 466.918649 -417.286892) (xy 466.96704 -417.186401) (xy 467.007787 -417.082575) (xy 467.04066 -416.975994)
			(xy 467.065477 -416.867254) (xy 467.082099 -416.756964) (xy 467.090432 -416.64574) (xy 467.091014 -416.589972)
			(xy 467.09203 -388.238238) (xy 467.09203 -246.488458) (xy 467.091578 -246.436469) (xy 467.084337 -246.332743)
			(xy 467.069893 -246.229773) (xy 467.048316 -246.128058) (xy 467.019711 -246.028092) (xy 466.984216 -245.930359)
			(xy 466.942005 -245.835335) (xy 466.91804 -245.789196) (xy 466.891385 -245.740526) (xy 466.831932 -245.646816)
			(xy 466.765775 -245.557714) (xy 466.693268 -245.473697) (xy 466.654388 -245.434104) (xy 464.025996 -242.805712)
			(xy 463.976572 -242.755595) (xy 463.882762 -242.650635) (xy 463.794985 -242.54058) (xy 463.713516 -242.425777)
			(xy 463.638613 -242.306586) (xy 463.57051 -242.183384) (xy 463.509422 -242.056557) (xy 463.455541 -241.926504)
			(xy 463.409037 -241.793634) (xy 463.370056 -241.658367) (xy 463.33872 -241.521126) (xy 463.315128 -241.382345)
			(xy 463.299355 -241.242459) (xy 463.291449 -241.101908) (xy 463.29092 -241.031522) (xy 463.29092 -87.588344)
			(xy 463.291412 -87.517965) (xy 463.29932 -87.377431) (xy 463.315095 -87.23756) (xy 463.33869 -87.098795)
			(xy 463.370029 -86.961571) (xy 463.409014 -86.82632) (xy 463.455522 -86.693468) (xy 463.509407 -86.563433)
			(xy 463.570498 -86.436625) (xy 463.638605 -86.313442) (xy 463.713512 -86.194272) (xy 463.794985 -86.07949)
			(xy 463.882765 -85.969457) (xy 463.976578 -85.86452) (xy 464.025996 -85.814408) (xy 466.654388 -83.185762)
			(xy 466.691681 -83.1478) (xy 466.76138 -83.067371) (xy 466.825166 -82.982176) (xy 466.882712 -82.892649)
			(xy 466.933726 -82.799245) (xy 466.977949 -82.70244) (xy 467.015155 -82.602728) (xy 467.045154 -82.500617)
			(xy 467.067793 -82.396625) (xy 467.082959 -82.291284) (xy 467.090572 -82.18513) (xy 467.091014 -82.131916)
			(xy 467.091014 -1.999996) (xy 467.090492 -1.944227) (xy 467.082157 -1.833) (xy 467.065533 -1.722707)
			(xy 467.040713 -1.613964) (xy 467.007837 -1.507381) (xy 466.967088 -1.403552) (xy 466.918693 -1.303059)
			(xy 466.862924 -1.206463) (xy 466.800093 -1.114305) (xy 466.73055 -1.0271) (xy 466.654685 -0.945336)
			(xy 466.572923 -0.869469) (xy 466.485719 -0.799925) (xy 466.393562 -0.737092) (xy 466.296967 -0.681321)
			(xy 466.196475 -0.632924) (xy 466.092647 -0.592173) (xy 465.986065 -0.559295) (xy 465.877323 -0.534473)
			(xy 465.76703 -0.517846) (xy 465.655803 -0.509509) (xy 465.600034 -0.509016) (xy 446.265046 -0.509016)
			(xy 446.209275 -0.509523) (xy 446.098046 -0.517855) (xy 445.98775 -0.534476) (xy 445.879004 -0.559294)
			(xy 445.772418 -0.592168) (xy 445.668586 -0.632916) (xy 445.568089 -0.68131) (xy 445.471491 -0.737079)
			(xy 445.37933 -0.79991) (xy 445.292122 -0.869454) (xy 445.210355 -0.945319) (xy 445.134486 -1.027084)
			(xy 445.06494 -1.114289) (xy 445.002105 -1.206448) (xy 444.946333 -1.303045) (xy 444.897936 -1.40354)
			(xy 444.857185 -1.50737) (xy 444.824307 -1.613956) (xy 444.799486 -1.722701) (xy 444.782861 -1.832996)
			(xy 444.774525 -1.944225) (xy 444.774066 -1.999996) (xy 444.774066 -11.850116) (xy 444.773596 -11.903993)
			(xy 444.765907 -12.011472) (xy 444.750571 -12.118128) (xy 444.727665 -12.223419) (xy 444.697306 -12.326808)
			(xy 444.659648 -12.427767) (xy 444.614884 -12.525782) (xy 444.563242 -12.620354) (xy 444.504984 -12.711001)
			(xy 444.440408 -12.797261) (xy 444.369843 -12.878695) (xy 444.293648 -12.954886) (xy 444.212211 -13.025448)
			(xy 444.125949 -13.09002) (xy 444.035299 -13.148274) (xy 443.940725 -13.199913) (xy 443.842708 -13.244673)
			(xy 443.741747 -13.282326) (xy 443.638357 -13.312681) (xy 443.533065 -13.335582) (xy 443.426408 -13.350914)
			(xy 443.318929 -13.358598) (xy 443.265052 -13.35913) (xy 435.265068 -13.35913) (xy 435.211191 -13.358648)
			(xy 435.103712 -13.350959) (xy 434.997055 -13.335622) (xy 434.891765 -13.312715) (xy 434.788376 -13.282356)
			(xy 434.687417 -13.244699) (xy 434.589401 -13.199935) (xy 434.494828 -13.148293) (xy 434.404181 -13.090036)
			(xy 434.31792 -13.025461) (xy 434.236485 -12.954897) (xy 434.160292 -12.878703) (xy 434.089729 -12.797268)
			(xy 434.025155 -12.711006) (xy 433.966899 -12.620358) (xy 433.915258 -12.525785) (xy 433.870495 -12.427769)
			(xy 433.832839 -12.326809) (xy 433.802481 -12.22342) (xy 433.779575 -12.118129) (xy 433.764239 -12.011472)
			(xy 433.756551 -11.903993) (xy 433.756054 -11.850116) (xy 433.756054 -1.999996) (xy 433.755545 -1.944227)
			(xy 433.74721 -1.833001) (xy 433.730585 -1.722708) (xy 433.705765 -1.613967) (xy 433.672888 -1.507384)
			(xy 433.632138 -1.403557) (xy 433.583743 -1.303065) (xy 433.527973 -1.20647) (xy 433.465141 -1.114314)
			(xy 433.395597 -1.02711) (xy 433.319731 -0.945348) (xy 433.237967 -0.869483) (xy 433.150762 -0.799942)
			(xy 433.058604 -0.737111) (xy 432.962009 -0.681343) (xy 432.861516 -0.63295) (xy 432.757687 -0.592202)
			(xy 432.651104 -0.559327) (xy 432.542362 -0.534509) (xy 432.432069 -0.517887) (xy 432.320843 -0.509554)
			(xy 432.265074 -0.509016) (xy 420.265098 -0.509016) (xy 420.209329 -0.509538) (xy 420.098103 -0.517873)
			(xy 419.987811 -0.534497) (xy 419.879069 -0.559317) (xy 419.772486 -0.592193) (xy 419.668658 -0.632943)
			(xy 419.568166 -0.681337) (xy 419.471571 -0.737106) (xy 419.379414 -0.799938) (xy 419.29221 -0.869481)
			(xy 419.210447 -0.945346) (xy 419.134582 -1.027109) (xy 419.065039 -1.114313) (xy 419.002207 -1.20647)
			(xy 418.946438 -1.303064) (xy 418.898043 -1.403557) (xy 418.857294 -1.507384) (xy 418.824417 -1.613967)
			(xy 418.799597 -1.722709) (xy 418.782973 -1.833001) (xy 418.774638 -1.944227) (xy 418.774118 -1.999996)
			(xy 418.774118 -11.850116) (xy 418.773637 -11.903993) (xy 418.765948 -12.011473) (xy 418.750612 -12.11813)
			(xy 418.727707 -12.223421) (xy 418.697348 -12.32681) (xy 418.659691 -12.42777) (xy 418.614928 -12.525787)
			(xy 418.563286 -12.62036) (xy 418.505029 -12.711008) (xy 418.440454 -12.79727) (xy 418.36989 -12.878704)
			(xy 418.293696 -12.954898) (xy 418.21226 -13.025462) (xy 418.125998 -13.090036) (xy 418.03535 -13.148292)
			(xy 417.940776 -13.199933) (xy 417.842759 -13.244696) (xy 417.741799 -13.282352) (xy 417.63841 -13.31271)
			(xy 417.533118 -13.335615) (xy 417.426461 -13.35095) (xy 417.318981 -13.358637) (xy 417.265104 -13.35913)
			(xy 409.26512 -13.35913) (xy 409.211242 -13.358661) (xy 409.103759 -13.350975) (xy 408.997099 -13.335641)
			(xy 408.891804 -13.312737) (xy 408.788412 -13.28238) (xy 408.687448 -13.244724) (xy 408.589429 -13.199961)
			(xy 408.494852 -13.14832) (xy 408.404201 -13.090063) (xy 408.317936 -13.025488) (xy 408.236498 -12.954923)
			(xy 408.160301 -12.878728) (xy 408.089735 -12.797292) (xy 408.025157 -12.711029) (xy 407.966898 -12.620379)
			(xy 407.915255 -12.525803) (xy 407.87049 -12.427785) (xy 407.832832 -12.326822) (xy 407.802472 -12.223431)
			(xy 407.779565 -12.118137) (xy 407.764229 -12.011477) (xy 407.75654 -11.903994) (xy 407.756106 -11.850116)
			(xy 407.756106 -1.999996) (xy 407.755584 -1.944227) (xy 407.747249 -1.833) (xy 407.730625 -1.722707)
			(xy 407.705805 -1.613965) (xy 407.672929 -1.507382) (xy 407.632179 -1.403554) (xy 407.583785 -1.303061)
			(xy 407.528016 -1.206465) (xy 407.465185 -1.114307) (xy 407.395642 -1.027103) (xy 407.319777 -0.945339)
			(xy 407.238014 -0.869472) (xy 407.15081 -0.799929) (xy 407.058653 -0.737096) (xy 406.962059 -0.681325)
			(xy 406.861567 -0.632929) (xy 406.757739 -0.592179) (xy 406.651156 -0.559301) (xy 406.542414 -0.534479)
			(xy 406.432122 -0.517854) (xy 406.320895 -0.509516) (xy 406.265126 -0.509016) (xy 394.264896 -0.509016)
			(xy 394.209127 -0.509538) (xy 394.097901 -0.517873) (xy 393.987609 -0.534497) (xy 393.878867 -0.559317)
			(xy 393.772285 -0.592194) (xy 393.668457 -0.632943) (xy 393.567965 -0.681338) (xy 393.47137 -0.737107)
			(xy 393.379213 -0.799938) (xy 393.292009 -0.869481) (xy 393.210246 -0.945346) (xy 393.134381 -1.027109)
			(xy 393.064838 -1.114313) (xy 393.002007 -1.20647) (xy 392.946238 -1.303065) (xy 392.897843 -1.403557)
			(xy 392.857094 -1.507385) (xy 392.824217 -1.613967) (xy 392.799397 -1.722709) (xy 392.782773 -1.833001)
			(xy 392.774438 -1.944227) (xy 392.773916 -1.999996) (xy 392.773916 -11.850116) (xy 392.773435 -11.903993)
			(xy 392.765746 -12.011473) (xy 392.75041 -12.11813) (xy 392.727505 -12.223421) (xy 392.697146 -12.32681)
			(xy 392.659489 -12.42777) (xy 392.614726 -12.525786) (xy 392.563084 -12.62036) (xy 392.504827 -12.711008)
			(xy 392.440252 -12.797269) (xy 392.369688 -12.878704) (xy 392.293494 -12.954897) (xy 392.212058 -13.025461)
			(xy 392.125796 -13.090035) (xy 392.035148 -13.148291) (xy 391.940574 -13.199932) (xy 391.842557 -13.244694)
			(xy 391.741597 -13.28235) (xy 391.638208 -13.312708) (xy 391.532916 -13.335613) (xy 391.426259 -13.350948)
			(xy 391.318779 -13.358635) (xy 391.264902 -13.35913) (xy 383.264918 -13.35913) (xy 383.21104 -13.358661)
			(xy 383.103557 -13.350975) (xy 382.996897 -13.335641) (xy 382.891603 -13.312737) (xy 382.78821 -13.282379)
			(xy 382.687247 -13.244723) (xy 382.589228 -13.199961) (xy 382.494651 -13.148319) (xy 382.404 -13.090063)
			(xy 382.317735 -13.025487) (xy 382.236297 -12.954923) (xy 382.160101 -12.878728) (xy 382.089534 -12.797291)
			(xy 382.024957 -12.711028) (xy 381.966698 -12.620378) (xy 381.915055 -12.525803) (xy 381.87029 -12.427784)
			(xy 381.832632 -12.326822) (xy 381.802272 -12.22343) (xy 381.779365 -12.118136) (xy 381.764029 -12.011477)
			(xy 381.75634 -11.903994) (xy 381.755904 -11.850116) (xy 381.755904 -1.999996) (xy 381.755382 -1.944227)
			(xy 381.747047 -1.833) (xy 381.730423 -1.722707) (xy 381.705603 -1.613965) (xy 381.672727 -1.507382)
			(xy 381.631977 -1.403554) (xy 381.583583 -1.303061) (xy 381.527814 -1.206466) (xy 381.464982 -1.114308)
			(xy 381.39544 -1.027103) (xy 381.319575 -0.945339) (xy 381.237812 -0.869473) (xy 381.150608 -0.799929)
			(xy 381.058451 -0.737097) (xy 380.961857 -0.681327) (xy 380.861364 -0.632931) (xy 380.757537 -0.59218)
			(xy 380.650954 -0.559302) (xy 380.542212 -0.534481) (xy 380.43192 -0.517855) (xy 380.320693 -0.509518)
			(xy 380.264924 -0.509016) (xy 368.264948 -0.509016) (xy 368.209177 -0.509523) (xy 368.097948 -0.517855)
			(xy 367.987651 -0.534476) (xy 367.878906 -0.559293) (xy 367.772319 -0.592168) (xy 367.668487 -0.632916)
			(xy 367.567991 -0.681309) (xy 367.471392 -0.737078) (xy 367.379231 -0.79991) (xy 367.292023 -0.869453)
			(xy 367.210256 -0.945319) (xy 367.134387 -1.027083) (xy 367.06484 -1.114289) (xy 367.002006 -1.206448)
			(xy 366.946234 -1.303045) (xy 366.897837 -1.403539) (xy 366.857085 -1.50737) (xy 366.824207 -1.613956)
			(xy 366.799386 -1.7227) (xy 366.782761 -1.832996) (xy 366.774425 -1.944225) (xy 366.773968 -1.999996)
			(xy 366.773968 -11.850116) (xy 366.773498 -11.903993) (xy 366.765809 -12.011472) (xy 366.750473 -12.118129)
			(xy 366.727567 -12.223419) (xy 366.697208 -12.326808) (xy 366.65955 -12.427767) (xy 366.614786 -12.525783)
			(xy 366.563144 -12.620355) (xy 366.504886 -12.711002) (xy 366.44031 -12.797262) (xy 366.369745 -12.878695)
			(xy 366.29355 -12.954887) (xy 366.212114 -13.025449) (xy 366.125851 -13.090021) (xy 366.035201 -13.148275)
			(xy 365.940627 -13.199914) (xy 365.84261 -13.244674) (xy 365.741649 -13.282327) (xy 365.638259 -13.312682)
			(xy 365.532968 -13.335584) (xy 365.42631 -13.350916) (xy 365.318831 -13.3586) (xy 365.264954 -13.35913)
			(xy 357.26497 -13.35913) (xy 357.211093 -13.358648) (xy 357.103614 -13.350959) (xy 356.996957 -13.335622)
			(xy 356.891666 -13.312716) (xy 356.788278 -13.282357) (xy 356.687318 -13.244699) (xy 356.589302 -13.199936)
			(xy 356.494729 -13.148294) (xy 356.404082 -13.090037) (xy 356.317821 -13.025462) (xy 356.236386 -12.954897)
			(xy 356.160193 -12.878704) (xy 356.08963 -12.797268) (xy 356.025055 -12.711007) (xy 355.966799 -12.620359)
			(xy 355.915158 -12.525785) (xy 355.870395 -12.427769) (xy 355.832739 -12.326809) (xy 355.802381 -12.22342)
			(xy 355.779475 -12.118129) (xy 355.764139 -12.011472) (xy 355.756451 -11.903993) (xy 355.755956 -11.850116)
			(xy 355.755956 -1.999996) (xy 355.755447 -1.944227) (xy 355.747112 -1.833001) (xy 355.730487 -1.722708)
			(xy 355.705667 -1.613967) (xy 355.67279 -1.507384) (xy 355.63204 -1.403556) (xy 355.583645 -1.303064)
			(xy 355.527875 -1.20647) (xy 355.465043 -1.114313) (xy 355.395499 -1.02711) (xy 355.319633 -0.945347)
			(xy 355.237869 -0.869483) (xy 355.150664 -0.799941) (xy 355.058507 -0.73711) (xy 354.961911 -0.681342)
			(xy 354.861418 -0.632949) (xy 354.757589 -0.5922) (xy 354.651006 -0.559325) (xy 354.542264 -0.534507)
			(xy 354.431972 -0.517885) (xy 354.320745 -0.509552) (xy 354.264976 -0.509016) (xy 330.164948 -0.509016)
			(xy 330.109177 -0.509523) (xy 329.997948 -0.517855) (xy 329.887651 -0.534476) (xy 329.778906 -0.559293)
			(xy 329.672319 -0.592168) (xy 329.568487 -0.632916) (xy 329.467991 -0.681309) (xy 329.371392 -0.737078)
			(xy 329.279231 -0.79991) (xy 329.192023 -0.869453) (xy 329.110256 -0.945319) (xy 329.034387 -1.027083)
			(xy 328.96484 -1.114289) (xy 328.902006 -1.206448) (xy 328.846234 -1.303045) (xy 328.797837 -1.403539)
			(xy 328.757085 -1.50737) (xy 328.724207 -1.613956) (xy 328.699386 -1.7227) (xy 328.682761 -1.832996)
			(xy 328.674425 -1.944225) (xy 328.673968 -1.999996) (xy 328.673968 -11.850116) (xy 328.673498 -11.903993)
			(xy 328.665809 -12.011472) (xy 328.650473 -12.118129) (xy 328.627567 -12.223419) (xy 328.597208 -12.326808)
			(xy 328.55955 -12.427767) (xy 328.514786 -12.525783) (xy 328.463144 -12.620355) (xy 328.404886 -12.711002)
			(xy 328.34031 -12.797262) (xy 328.269745 -12.878695) (xy 328.19355 -12.954887) (xy 328.112114 -13.025449)
			(xy 328.025851 -13.090021) (xy 327.935201 -13.148275) (xy 327.840627 -13.199914) (xy 327.74261 -13.244674)
			(xy 327.641649 -13.282327) (xy 327.538259 -13.312682) (xy 327.432968 -13.335584) (xy 327.32631 -13.350916)
			(xy 327.218831 -13.3586) (xy 327.164954 -13.35913) (xy 319.16497 -13.35913) (xy 319.111093 -13.358648)
			(xy 319.003614 -13.350959) (xy 318.896957 -13.335622) (xy 318.791666 -13.312716) (xy 318.688278 -13.282357)
			(xy 318.587318 -13.244699) (xy 318.489302 -13.199936) (xy 318.394729 -13.148294) (xy 318.304082 -13.090037)
			(xy 318.217821 -13.025462) (xy 318.136386 -12.954897) (xy 318.060193 -12.878704) (xy 317.98963 -12.797268)
			(xy 317.925055 -12.711007) (xy 317.866799 -12.620359) (xy 317.815158 -12.525785) (xy 317.770395 -12.427769)
			(xy 317.732739 -12.326809) (xy 317.702381 -12.22342) (xy 317.679475 -12.118129) (xy 317.664139 -12.011472)
			(xy 317.656451 -11.903993) (xy 317.655956 -11.850116) (xy 317.655956 -1.999996) (xy 317.655447 -1.944227)
			(xy 317.647112 -1.833001) (xy 317.630487 -1.722708) (xy 317.605667 -1.613967) (xy 317.57279 -1.507384)
			(xy 317.53204 -1.403556) (xy 317.483645 -1.303064) (xy 317.427875 -1.20647) (xy 317.365043 -1.114313)
			(xy 317.295499 -1.02711) (xy 317.219633 -0.945347) (xy 317.137869 -0.869483) (xy 317.050664 -0.799941)
			(xy 316.958507 -0.73711) (xy 316.861911 -0.681342) (xy 316.761418 -0.632949) (xy 316.657589 -0.5922)
			(xy 316.551006 -0.559325) (xy 316.442264 -0.534507) (xy 316.331972 -0.517885) (xy 316.220745 -0.509552)
			(xy 316.164976 -0.509016) (xy 304.165 -0.509016) (xy 304.109231 -0.509537) (xy 303.998005 -0.517873)
			(xy 303.887712 -0.534497) (xy 303.778971 -0.559316) (xy 303.672388 -0.592193) (xy 303.56856 -0.632942)
			(xy 303.468067 -0.681336) (xy 303.371472 -0.737105) (xy 303.279315 -0.799937) (xy 303.192111 -0.86948)
			(xy 303.110348 -0.945345) (xy 303.034482 -1.027108) (xy 302.964939 -1.114312) (xy 302.902108 -1.206469)
			(xy 302.846338 -1.303064) (xy 302.797944 -1.403556) (xy 302.757194 -1.507384) (xy 302.724317 -1.613967)
			(xy 302.699497 -1.722708) (xy 302.682873 -1.833001) (xy 302.674538 -1.944227) (xy 302.67402 -1.999996)
			(xy 302.67402 -11.850116) (xy 302.673539 -11.903993) (xy 302.66585 -12.011473) (xy 302.650514 -12.11813)
			(xy 302.627609 -12.223422) (xy 302.59725 -12.326811) (xy 302.559593 -12.427771) (xy 302.51483 -12.525787)
			(xy 302.463188 -12.62036) (xy 302.404931 -12.711009) (xy 302.340356 -12.79727) (xy 302.269792 -12.878705)
			(xy 302.193598 -12.954899) (xy 302.112162 -13.025462) (xy 302.025901 -13.090037) (xy 301.935252 -13.148293)
			(xy 301.840678 -13.199934) (xy 301.742661 -13.244697) (xy 301.641701 -13.282353) (xy 301.538312 -13.312711)
			(xy 301.43302 -13.335616) (xy 301.326363 -13.350952) (xy 301.218883 -13.358639) (xy 301.165006 -13.35913)
			(xy 293.165022 -13.35913) (xy 293.111143 -13.358661) (xy 293.003661 -13.350975) (xy 292.897001 -13.335641)
			(xy 292.791706 -13.312737) (xy 292.688313 -13.28238) (xy 292.58735 -13.244724) (xy 292.48933 -13.199962)
			(xy 292.394753 -13.148321) (xy 292.304102 -13.090064) (xy 292.217837 -13.025489) (xy 292.136399 -12.954924)
			(xy 292.060202 -12.878729) (xy 291.989635 -12.797293) (xy 291.925058 -12.71103) (xy 291.866799 -12.620379)
			(xy 291.815155 -12.525804) (xy 291.77039 -12.427785) (xy 291.732732 -12.326823) (xy 291.702372 -12.223431)
			(xy 291.679465 -12.118137) (xy 291.664129 -12.011477) (xy 291.65644 -11.903994) (xy 291.656008 -11.850116)
			(xy 291.656008 -1.999996) (xy 291.655486 -1.944227) (xy 291.647151 -1.833) (xy 291.630527 -1.722707)
			(xy 291.605707 -1.613965) (xy 291.572831 -1.507382) (xy 291.532081 -1.403553) (xy 291.483687 -1.30306)
			(xy 291.427918 -1.206465) (xy 291.365087 -1.114307) (xy 291.295544 -1.027102) (xy 291.219679 -0.945338)
			(xy 291.137916 -0.869472) (xy 291.050712 -0.799928) (xy 290.958556 -0.737095) (xy 290.861961 -0.681324)
			(xy 290.761469 -0.632928) (xy 290.657641 -0.592177) (xy 290.551058 -0.559299) (xy 290.442316 -0.534478)
			(xy 290.332024 -0.517852) (xy 290.220797 -0.509515) (xy 290.165028 -0.509016) (xy 278.165052 -0.509016)
			(xy 278.109284 -0.509539) (xy 277.99806 -0.517878) (xy 277.887771 -0.534504) (xy 277.779032 -0.559327)
			(xy 277.672452 -0.592205) (xy 277.568627 -0.632956) (xy 277.468138 -0.681352) (xy 277.371546 -0.737122)
			(xy 277.279392 -0.799954) (xy 277.192191 -0.869497) (xy 277.110431 -0.945362) (xy 277.034568 -1.027125)
			(xy 276.965028 -1.114328) (xy 276.902198 -1.206484) (xy 276.846431 -1.303077) (xy 276.798039 -1.403568)
			(xy 276.75729 -1.507394) (xy 276.724415 -1.613974) (xy 276.699596 -1.722714) (xy 276.682973 -1.833004)
			(xy 276.674638 -1.944228) (xy 276.674072 -1.999996) (xy 276.674072 -11.850116) (xy 276.673602 -11.903993)
			(xy 276.665913 -12.011472) (xy 276.650577 -12.118129) (xy 276.627671 -12.22342) (xy 276.597312 -12.326808)
			(xy 276.559654 -12.427768) (xy 276.51489 -12.525783) (xy 276.463248 -12.620356) (xy 276.40499 -12.711003)
			(xy 276.340414 -12.797263) (xy 276.269849 -12.878697) (xy 276.193654 -12.954889) (xy 276.112218 -13.025451)
			(xy 276.025955 -13.090023) (xy 275.935306 -13.148277) (xy 275.840731 -13.199916) (xy 275.742714 -13.244676)
			(xy 275.641753 -13.28233) (xy 275.538364 -13.312685) (xy 275.433072 -13.335587) (xy 275.326414 -13.35092)
			(xy 275.218935 -13.358604) (xy 275.165058 -13.35913) (xy 267.165074 -13.35913) (xy 267.111197 -13.358648)
			(xy 267.003718 -13.350959) (xy 266.897061 -13.335623) (xy 266.791769 -13.312717) (xy 266.688381 -13.282358)
			(xy 266.587421 -13.2447) (xy 266.489405 -13.199937) (xy 266.394832 -13.148295) (xy 266.304184 -13.090038)
			(xy 266.217923 -13.025463) (xy 266.136488 -12.954899) (xy 266.060294 -12.878705) (xy 265.989731 -12.79727)
			(xy 265.925156 -12.711008) (xy 265.8669 -12.62036) (xy 265.815259 -12.525786) (xy 265.770496 -12.42777)
			(xy 265.732839 -12.32681) (xy 265.702481 -12.223421) (xy 265.679575 -12.11813) (xy 265.664239 -12.011472)
			(xy 265.656551 -11.903993) (xy 265.65606 -11.850116) (xy 265.65606 -1.999996) (xy 265.655551 -1.944227)
			(xy 265.647216 -1.833) (xy 265.630591 -1.722708) (xy 265.605771 -1.613966) (xy 265.572894 -1.507384)
			(xy 265.532144 -1.403556) (xy 265.483749 -1.303063) (xy 265.427979 -1.206469) (xy 265.365147 -1.114312)
			(xy 265.295603 -1.027108) (xy 265.219737 -0.945346) (xy 265.137973 -0.869481) (xy 265.050769 -0.799939)
			(xy 264.958611 -0.737108) (xy 264.862015 -0.68134) (xy 264.761522 -0.632946) (xy 264.657694 -0.592198)
			(xy 264.55111 -0.559322) (xy 264.442368 -0.534504) (xy 264.332076 -0.517882) (xy 264.220849 -0.509548)
			(xy 264.16508 -0.509016) (xy 252.165104 -0.509016) (xy 252.109335 -0.509537) (xy 251.998108 -0.517872)
			(xy 251.887816 -0.534496) (xy 251.779074 -0.559315) (xy 251.672491 -0.592191) (xy 251.568663 -0.632941)
			(xy 251.46817 -0.681335) (xy 251.371575 -0.737104) (xy 251.279417 -0.799936) (xy 251.192213 -0.869478)
			(xy 251.110449 -0.945344) (xy 251.034584 -1.027107) (xy 250.96504 -1.114311) (xy 250.902208 -1.206468)
			(xy 250.846439 -1.303063) (xy 250.798044 -1.403555) (xy 250.757294 -1.507383) (xy 250.724417 -1.613966)
			(xy 250.699597 -1.722708) (xy 250.682973 -1.833) (xy 250.674638 -1.944227) (xy 250.674124 -1.999996)
			(xy 250.674124 -11.850116) (xy 250.673643 -11.903993) (xy 250.665954 -12.011473) (xy 250.650618 -12.11813)
			(xy 250.627713 -12.223422) (xy 250.597354 -12.326811) (xy 250.559697 -12.427771) (xy 250.514934 -12.525788)
			(xy 250.463292 -12.620361) (xy 250.405035 -12.71101) (xy 250.34046 -12.797271) (xy 250.269896 -12.878706)
			(xy 250.193702 -12.9549) (xy 250.112267 -13.025464) (xy 250.026005 -13.090039) (xy 249.935356 -13.148295)
			(xy 249.840782 -13.199936) (xy 249.742766 -13.244699) (xy 249.641806 -13.282356) (xy 249.538416 -13.312714)
			(xy 249.433124 -13.33562) (xy 249.326467 -13.350955) (xy 249.218987 -13.358643) (xy 249.16511 -13.35913)
			(xy 241.164872 -13.35913) (xy 241.110999 -13.358634) (xy 241.003529 -13.35092) (xy 240.896884 -13.335561)
			(xy 240.791604 -13.312636) (xy 240.688228 -13.282262) (xy 240.587282 -13.244593) (xy 240.489278 -13.199821)
			(xy 240.394717 -13.148173) (xy 240.30408 -13.089914) (xy 240.217828 -13.02534) (xy 240.136401 -12.954778)
			(xy 240.060213 -12.87859) (xy 239.989653 -12.797163) (xy 239.925079 -12.71091) (xy 239.86682 -12.620273)
			(xy 239.815174 -12.525711) (xy 239.770403 -12.427707) (xy 239.732734 -12.32676) (xy 239.702361 -12.223384)
			(xy 239.679436 -12.118105) (xy 239.664079 -12.011459) (xy 239.656365 -11.903989) (xy 239.655858 -11.850116)
			(xy 239.655858 -1.999996) (xy 239.655349 -1.944227) (xy 239.647014 -1.833001) (xy 239.630389 -1.722708)
			(xy 239.605569 -1.613967) (xy 239.572692 -1.507384) (xy 239.531942 -1.403556) (xy 239.483547 -1.303064)
			(xy 239.427777 -1.206469) (xy 239.364945 -1.114313) (xy 239.295401 -1.027109) (xy 239.219535 -0.945346)
			(xy 239.137771 -0.869482) (xy 239.050567 -0.79994) (xy 238.958409 -0.737109) (xy 238.861813 -0.681341)
			(xy 238.76132 -0.632947) (xy 238.657492 -0.592199) (xy 238.550908 -0.559324) (xy 238.442166 -0.534506)
			(xy 238.331874 -0.517883) (xy 238.220647 -0.50955) (xy 238.164878 -0.509016) (xy 214.065104 -0.509016)
			(xy 214.009335 -0.509537) (xy 213.898108 -0.517872) (xy 213.787816 -0.534496) (xy 213.679074 -0.559315)
			(xy 213.572491 -0.592191) (xy 213.468663 -0.632941) (xy 213.36817 -0.681335) (xy 213.271575 -0.737104)
			(xy 213.179417 -0.799936) (xy 213.092213 -0.869478) (xy 213.010449 -0.945344) (xy 212.934584 -1.027107)
			(xy 212.86504 -1.114311) (xy 212.802208 -1.206468) (xy 212.746439 -1.303063) (xy 212.698044 -1.403555)
			(xy 212.657294 -1.507383) (xy 212.624417 -1.613966) (xy 212.599597 -1.722708) (xy 212.582973 -1.833)
			(xy 212.574638 -1.944227) (xy 212.574124 -1.999996) (xy 212.574124 -11.850116) (xy 212.573643 -11.903993)
			(xy 212.565954 -12.011473) (xy 212.550618 -12.11813) (xy 212.527713 -12.223422) (xy 212.497354 -12.326811)
			(xy 212.459697 -12.427771) (xy 212.414934 -12.525788) (xy 212.363292 -12.620361) (xy 212.305035 -12.71101)
			(xy 212.24046 -12.797271) (xy 212.169896 -12.878706) (xy 212.093702 -12.9549) (xy 212.012267 -13.025464)
			(xy 211.926005 -13.090039) (xy 211.835356 -13.148295) (xy 211.740782 -13.199936) (xy 211.642766 -13.244699)
			(xy 211.541806 -13.282356) (xy 211.438416 -13.312714) (xy 211.333124 -13.33562) (xy 211.226467 -13.350955)
			(xy 211.118987 -13.358643) (xy 211.06511 -13.35913) (xy 203.064872 -13.35913) (xy 203.010999 -13.358634)
			(xy 202.903529 -13.35092) (xy 202.796884 -13.335561) (xy 202.691604 -13.312636) (xy 202.588228 -13.282262)
			(xy 202.487282 -13.244593) (xy 202.389278 -13.199821) (xy 202.294717 -13.148173) (xy 202.20408 -13.089914)
			(xy 202.117828 -13.02534) (xy 202.036401 -12.954778) (xy 201.960213 -12.87859) (xy 201.889653 -12.797163)
			(xy 201.825079 -12.71091) (xy 201.76682 -12.620273) (xy 201.715174 -12.525711) (xy 201.670403 -12.427707)
			(xy 201.632734 -12.32676) (xy 201.602361 -12.223384) (xy 201.579436 -12.118105) (xy 201.564079 -12.011459)
			(xy 201.556365 -11.903989) (xy 201.555858 -11.850116) (xy 201.555858 -1.999996) (xy 201.555349 -1.944227)
			(xy 201.547014 -1.833001) (xy 201.530389 -1.722708) (xy 201.505569 -1.613967) (xy 201.472692 -1.507384)
			(xy 201.431942 -1.403556) (xy 201.383547 -1.303064) (xy 201.327777 -1.206469) (xy 201.264945 -1.114313)
			(xy 201.195401 -1.027109) (xy 201.119535 -0.945346) (xy 201.037771 -0.869482) (xy 200.950567 -0.79994)
			(xy 200.858409 -0.737109) (xy 200.761813 -0.681341) (xy 200.66132 -0.632947) (xy 200.557492 -0.592199)
			(xy 200.450908 -0.559324) (xy 200.342166 -0.534506) (xy 200.231874 -0.517883) (xy 200.120647 -0.50955)
			(xy 200.064878 -0.509016) (xy 188.064902 -0.509016) (xy 188.009133 -0.509537) (xy 187.897906 -0.517873)
			(xy 187.787614 -0.534496) (xy 187.678872 -0.559316) (xy 187.572289 -0.592192) (xy 187.468461 -0.632941)
			(xy 187.367969 -0.681336) (xy 187.271374 -0.737105) (xy 187.179216 -0.799936) (xy 187.092012 -0.869479)
			(xy 187.010248 -0.945344) (xy 186.934383 -1.027107) (xy 186.86484 -1.114311) (xy 186.802008 -1.206468)
			(xy 186.746239 -1.303063) (xy 186.697844 -1.403556) (xy 186.657094 -1.507384) (xy 186.624217 -1.613966)
			(xy 186.599397 -1.722708) (xy 186.582773 -1.833001) (xy 186.574438 -1.944227) (xy 186.573922 -1.999996)
			(xy 186.573922 -11.850116) (xy 186.573441 -11.903993) (xy 186.565752 -12.011473) (xy 186.550416 -12.11813)
			(xy 186.527511 -12.223422) (xy 186.497152 -12.326811) (xy 186.459495 -12.427771) (xy 186.414732 -12.525787)
			(xy 186.36309 -12.620361) (xy 186.304833 -12.711009) (xy 186.240258 -12.797271) (xy 186.169694 -12.878706)
			(xy 186.0935 -12.954899) (xy 186.012065 -13.025463) (xy 185.925803 -13.090038) (xy 185.835154 -13.148294)
			(xy 185.74058 -13.199935) (xy 185.642564 -13.244698) (xy 185.541603 -13.282355) (xy 185.438214 -13.312713)
			(xy 185.332922 -13.335618) (xy 185.226265 -13.350953) (xy 185.118785 -13.358641) (xy 185.064908 -13.35913)
			(xy 177.064924 -13.35913) (xy 177.011045 -13.358661) (xy 176.903563 -13.350975) (xy 176.796902 -13.335642)
			(xy 176.691607 -13.312738) (xy 176.588215 -13.282381) (xy 176.487251 -13.244725) (xy 176.389231 -13.199962)
			(xy 176.294654 -13.148321) (xy 176.204003 -13.090065) (xy 176.117738 -13.025489) (xy 176.036299 -12.954925)
			(xy 175.960103 -12.87873) (xy 175.889536 -12.797293) (xy 175.824958 -12.71103) (xy 175.766699 -12.62038)
			(xy 175.715056 -12.525804) (xy 175.67029 -12.427786) (xy 175.632632 -12.326823) (xy 175.602272 -12.223431)
			(xy 175.579365 -12.118137) (xy 175.564029 -12.011477) (xy 175.55634 -11.903995) (xy 175.55591 -11.850116)
			(xy 175.55591 -1.999996) (xy 175.555388 -1.944227) (xy 175.547053 -1.833) (xy 175.530429 -1.722707)
			(xy 175.505609 -1.613965) (xy 175.472733 -1.507381) (xy 175.431983 -1.403553) (xy 175.383589 -1.30306)
			(xy 175.32782 -1.206464) (xy 175.264989 -1.114306) (xy 175.195446 -1.027101) (xy 175.119581 -0.945337)
			(xy 175.037818 -0.869471) (xy 174.950615 -0.799927) (xy 174.858458 -0.737094) (xy 174.761863 -0.681323)
			(xy 174.661371 -0.632927) (xy 174.557543 -0.592176) (xy 174.45096 -0.559298) (xy 174.342219 -0.534476)
			(xy 174.231926 -0.51785) (xy 174.120699 -0.509513) (xy 174.06493 -0.509016) (xy 162.064954 -0.509016)
			(xy 162.009186 -0.509539) (xy 161.897962 -0.517878) (xy 161.787672 -0.534504) (xy 161.678934 -0.559326)
			(xy 161.572354 -0.592204) (xy 161.468529 -0.632956) (xy 161.368039 -0.681351) (xy 161.271447 -0.737121)
			(xy 161.179293 -0.799953) (xy 161.092092 -0.869496) (xy 161.010331 -0.945361) (xy 160.934469 -1.027124)
			(xy 160.864928 -1.114327) (xy 160.802099 -1.206483) (xy 160.746332 -1.303076) (xy 160.697939 -1.403567)
			(xy 160.657191 -1.507393) (xy 160.624315 -1.613974) (xy 160.599496 -1.722714) (xy 160.582873 -1.833004)
			(xy 160.574538 -1.944228) (xy 160.573974 -1.999996) (xy 160.573974 -11.850116) (xy 160.573504 -11.903993)
			(xy 160.565815 -12.011472) (xy 160.550479 -12.118129) (xy 160.527573 -12.22342) (xy 160.497214 -12.326809)
			(xy 160.459556 -12.427768) (xy 160.414792 -12.525784) (xy 160.36315 -12.620356) (xy 160.304892 -12.711003)
			(xy 160.240316 -12.797264) (xy 160.169751 -12.878697) (xy 160.093556 -12.954889) (xy 160.01212 -13.025452)
			(xy 159.925857 -13.090024) (xy 159.835208 -13.148278) (xy 159.740634 -13.199917) (xy 159.642616 -13.244678)
			(xy 159.541655 -13.282332) (xy 159.438266 -13.312687) (xy 159.332974 -13.335589) (xy 159.226316 -13.350921)
			(xy 159.118837 -13.358606) (xy 159.06496 -13.35913) (xy 151.064976 -13.35913) (xy 151.011099 -13.358648)
			(xy 150.903619 -13.35096) (xy 150.796962 -13.335623) (xy 150.691671 -13.312717) (xy 150.588282 -13.282358)
			(xy 150.487322 -13.244701) (xy 150.389306 -13.199937) (xy 150.294733 -13.148296) (xy 150.204085 -13.090039)
			(xy 150.117823 -13.025464) (xy 150.036389 -12.954899) (xy 149.960195 -12.878706) (xy 149.889631 -12.79727)
			(xy 149.825057 -12.711009) (xy 149.7668 -12.62036) (xy 149.715159 -12.525787) (xy 149.670396 -12.42777)
			(xy 149.632739 -12.32681) (xy 149.602381 -12.223421) (xy 149.579475 -12.11813) (xy 149.564139 -12.011473)
			(xy 149.556451 -11.903993) (xy 149.555962 -11.850116) (xy 149.555962 -1.999996) (xy 149.555453 -1.944227)
			(xy 149.547118 -1.833) (xy 149.530493 -1.722708) (xy 149.505673 -1.613966) (xy 149.472796 -1.507383)
			(xy 149.432046 -1.403555) (xy 149.383651 -1.303063) (xy 149.327881 -1.206468) (xy 149.265049 -1.114311)
			(xy 149.195505 -1.027108) (xy 149.11964 -0.945345) (xy 149.037876 -0.86948) (xy 148.950671 -0.799938)
			(xy 148.858513 -0.737107) (xy 148.761917 -0.681339) (xy 148.661424 -0.632945) (xy 148.557596 -0.592196)
			(xy 148.451013 -0.559321) (xy 148.34227 -0.534503) (xy 148.231978 -0.51788) (xy 148.120751 -0.509546)
			(xy 148.064982 -0.509016) (xy 136.065006 -0.509016) (xy 136.009236 -0.509524) (xy 135.898009 -0.517859)
			(xy 135.787715 -0.534483) (xy 135.678972 -0.559302) (xy 135.572388 -0.592179) (xy 135.468559 -0.632928)
			(xy 135.368065 -0.681323) (xy 135.271469 -0.737092) (xy 135.17931 -0.799924) (xy 135.092105 -0.869468)
			(xy 135.010341 -0.945334) (xy 134.934474 -1.027098) (xy 134.86493 -1.114302) (xy 134.802098 -1.20646)
			(xy 134.746328 -1.303056) (xy 134.697932 -1.403549) (xy 134.657182 -1.507378) (xy 134.624305 -1.613962)
			(xy 134.599485 -1.722705) (xy 134.58286 -1.832999) (xy 134.574525 -1.944226) (xy 134.574026 -1.999996)
			(xy 134.574026 -11.850116) (xy 134.573545 -11.903993) (xy 134.565856 -12.011473) (xy 134.55052 -12.11813)
			(xy 134.527615 -12.223422) (xy 134.497256 -12.326811) (xy 134.459599 -12.427772) (xy 134.414836 -12.525788)
			(xy 134.363194 -12.620362) (xy 134.304937 -12.71101) (xy 134.240362 -12.797272) (xy 134.169798 -12.878707)
			(xy 134.093604 -12.954901) (xy 134.012169 -13.025465) (xy 133.925907 -13.09004) (xy 133.835258 -13.148296)
			(xy 133.740685 -13.199938) (xy 133.642668 -13.244701) (xy 133.541708 -13.282357) (xy 133.438318 -13.312716)
			(xy 133.333026 -13.335621) (xy 133.226369 -13.350957) (xy 133.118889 -13.358645) (xy 133.065012 -13.35913)
			(xy 125.065028 -13.35913) (xy 125.011149 -13.358661) (xy 124.903666 -13.350976) (xy 124.797006 -13.335642)
			(xy 124.691711 -13.312739) (xy 124.588318 -13.282382) (xy 124.487354 -13.244726) (xy 124.389334 -13.199964)
			(xy 124.294757 -13.148323) (xy 124.204105 -13.090066) (xy 124.11784 -13.025491) (xy 124.036401 -12.954926)
			(xy 123.960204 -12.878731) (xy 123.889637 -12.797295) (xy 123.825059 -12.711032) (xy 123.7668 -12.620381)
			(xy 123.715156 -12.525806) (xy 123.670391 -12.427787) (xy 123.632732 -12.326824) (xy 123.602372 -12.223432)
			(xy 123.579466 -12.118138) (xy 123.564129 -12.011477) (xy 123.55644 -11.903995) (xy 123.556014 -11.850116)
			(xy 123.556014 -1.999996) (xy 123.555492 -1.944227) (xy 123.547157 -1.833) (xy 123.530533 -1.722707)
			(xy 123.505713 -1.613964) (xy 123.472837 -1.507381) (xy 123.432088 -1.403552) (xy 123.383693 -1.303059)
			(xy 123.327924 -1.206463) (xy 123.265093 -1.114305) (xy 123.19555 -1.0271) (xy 123.119685 -0.945336)
			(xy 123.037923 -0.869469) (xy 122.950719 -0.799925) (xy 122.858562 -0.737092) (xy 122.761967 -0.681321)
			(xy 122.661475 -0.632924) (xy 122.557647 -0.592173) (xy 122.451065 -0.559295) (xy 122.342323 -0.534473)
			(xy 122.23203 -0.517846) (xy 122.120803 -0.509509) (xy 122.065034 -0.509016) (xy 97.965006 -0.509016)
			(xy 97.909236 -0.509524) (xy 97.798009 -0.517859) (xy 97.687715 -0.534483) (xy 97.578972 -0.559302)
			(xy 97.472388 -0.592179) (xy 97.368559 -0.632928) (xy 97.268065 -0.681323) (xy 97.171469 -0.737092)
			(xy 97.07931 -0.799924) (xy 96.992105 -0.869468) (xy 96.910341 -0.945334) (xy 96.834474 -1.027098)
			(xy 96.76493 -1.114302) (xy 96.702098 -1.20646) (xy 96.646328 -1.303056) (xy 96.597932 -1.403549)
			(xy 96.557182 -1.507378) (xy 96.524305 -1.613962) (xy 96.499485 -1.722705) (xy 96.48286 -1.832999)
			(xy 96.474525 -1.944226) (xy 96.474026 -1.999996) (xy 96.474026 -11.850116) (xy 96.473545 -11.903993)
			(xy 96.465856 -12.011473) (xy 96.45052 -12.11813) (xy 96.427615 -12.223422) (xy 96.397256 -12.326811)
			(xy 96.359599 -12.427772) (xy 96.314836 -12.525788) (xy 96.263194 -12.620362) (xy 96.204937 -12.71101)
			(xy 96.140362 -12.797272) (xy 96.069798 -12.878707) (xy 95.993604 -12.954901) (xy 95.912169 -13.025465)
			(xy 95.825907 -13.09004) (xy 95.735258 -13.148296) (xy 95.640685 -13.199938) (xy 95.542668 -13.244701)
			(xy 95.441708 -13.282357) (xy 95.338318 -13.312716) (xy 95.233026 -13.335621) (xy 95.126369 -13.350957)
			(xy 95.018889 -13.358645) (xy 94.965012 -13.35913) (xy 86.965028 -13.35913) (xy 86.911149 -13.358661)
			(xy 86.803666 -13.350976) (xy 86.697006 -13.335642) (xy 86.591711 -13.312739) (xy 86.488318 -13.282382)
			(xy 86.387354 -13.244726) (xy 86.289334 -13.199964) (xy 86.194757 -13.148323) (xy 86.104105 -13.090066)
			(xy 86.01784 -13.025491) (xy 85.936401 -12.954926) (xy 85.860204 -12.878731) (xy 85.789637 -12.797295)
			(xy 85.725059 -12.711032) (xy 85.6668 -12.620381) (xy 85.615156 -12.525806) (xy 85.570391 -12.427787)
			(xy 85.532732 -12.326824) (xy 85.502372 -12.223432) (xy 85.479466 -12.118138) (xy 85.464129 -12.011477)
			(xy 85.45644 -11.903995) (xy 85.456014 -11.850116) (xy 85.456014 -1.999996) (xy 85.455492 -1.944227)
			(xy 85.447157 -1.833) (xy 85.430533 -1.722707) (xy 85.405713 -1.613964) (xy 85.372837 -1.507381)
			(xy 85.332088 -1.403552) (xy 85.283693 -1.303059) (xy 85.227924 -1.206463) (xy 85.165093 -1.114305)
			(xy 85.09555 -1.0271) (xy 85.019685 -0.945336) (xy 84.937923 -0.869469) (xy 84.850719 -0.799925)
			(xy 84.758562 -0.737092) (xy 84.661967 -0.681321) (xy 84.561475 -0.632924) (xy 84.457647 -0.592173)
			(xy 84.351065 -0.559295) (xy 84.242323 -0.534473) (xy 84.13203 -0.517846) (xy 84.020803 -0.509509)
			(xy 83.965034 -0.509016) (xy 71.965058 -0.509016) (xy 71.90929 -0.509539) (xy 71.798066 -0.517877)
			(xy 71.687776 -0.534503) (xy 71.579037 -0.559325) (xy 71.472457 -0.592203) (xy 71.368631 -0.632954)
			(xy 71.268142 -0.68135) (xy 71.17155 -0.73712) (xy 71.079395 -0.799952) (xy 70.992194 -0.869495)
			(xy 70.910433 -0.94536) (xy 70.83457 -1.027122) (xy 70.765029 -1.114326) (xy 70.7022 -1.206482) (xy 70.646432 -1.303075)
			(xy 70.598039 -1.403566) (xy 70.557291 -1.507392) (xy 70.524415 -1.613974) (xy 70.499596 -1.722713)
			(xy 70.482973 -1.833004) (xy 70.474638 -1.944228) (xy 70.474078 -1.999996) (xy 70.474078 -11.850116)
			(xy 70.473608 -11.903993) (xy 70.465919 -12.011472) (xy 70.450583 -12.118129) (xy 70.427677 -12.22342)
			(xy 70.397318 -12.326809) (xy 70.35966 -12.427769) (xy 70.314896 -12.525784) (xy 70.263254 -12.620357)
			(xy 70.204996 -12.711004) (xy 70.140421 -12.797265) (xy 70.069855 -12.878699) (xy 69.993661 -12.954891)
			(xy 69.912224 -13.025453) (xy 69.825962 -13.090026) (xy 69.735312 -13.148281) (xy 69.640738 -13.19992)
			(xy 69.542721 -13.24468) (xy 69.44176 -13.282334) (xy 69.33837 -13.31269) (xy 69.233078 -13.335592)
			(xy 69.126421 -13.350925) (xy 69.018941 -13.358609) (xy 68.965064 -13.35913) (xy 60.96508 -13.35913)
			(xy 60.911203 -13.358648) (xy 60.803723 -13.35096) (xy 60.697066 -13.335624) (xy 60.591774 -13.312718)
			(xy 60.488385 -13.282359) (xy 60.387425 -13.244702) (xy 60.289409 -13.199939) (xy 60.194835 -13.148297)
			(xy 60.104187 -13.09004) (xy 60.017925 -13.025465) (xy 59.93649 -12.954901) (xy 59.860296 -12.878707)
			(xy 59.789732 -12.797272) (xy 59.725157 -12.71101) (xy 59.666901 -12.620361) (xy 59.61526 -12.525788)
			(xy 59.570496 -12.427771) (xy 59.53284 -12.326811) (xy 59.502481 -12.223422) (xy 59.479575 -12.11813)
			(xy 59.464239 -12.011473) (xy 59.456551 -11.903993) (xy 59.456066 -11.850116) (xy 59.456066 -1.999996)
			(xy 59.455557 -1.944227) (xy 59.447222 -1.833) (xy 59.430597 -1.722708) (xy 59.405777 -1.613966)
			(xy 59.3729 -1.507383) (xy 59.33215 -1.403555) (xy 59.283755 -1.303062) (xy 59.227986 -1.206467)
			(xy 59.165153 -1.11431) (xy 59.09561 -1.027107) (xy 59.019744 -0.945344) (xy 58.93798 -0.869479)
			(xy 58.850775 -0.799936) (xy 58.758617 -0.737105) (xy 58.662022 -0.681336) (xy 58.561529 -0.632942)
			(xy 58.4577 -0.592194) (xy 58.351117 -0.559318) (xy 58.242375 -0.534499) (xy 58.132082 -0.517876)
			(xy 58.020855 -0.509542) (xy 57.965086 -0.509016) (xy 45.96511 -0.509016) (xy 45.90934 -0.509524)
			(xy 45.798112 -0.517859) (xy 45.687819 -0.534482) (xy 45.579075 -0.559301) (xy 45.472491 -0.592178)
			(xy 45.368661 -0.632927) (xy 45.268167 -0.681322) (xy 45.171571 -0.737091) (xy 45.079412 -0.799923)
			(xy 44.992207 -0.869466) (xy 44.910442 -0.945332) (xy 44.834576 -1.027096) (xy 44.765031 -1.114301)
			(xy 44.702198 -1.206459) (xy 44.646428 -1.303055) (xy 44.598033 -1.403549) (xy 44.557282 -1.507378)
			(xy 44.524405 -1.613962) (xy 44.499585 -1.722705) (xy 44.48296 -1.832999) (xy 44.474625 -1.944226)
			(xy 44.47413 -1.999996) (xy 44.47413 -11.850116) (xy 44.473649 -11.903993) (xy 44.46596 -12.011473)
			(xy 44.450624 -12.118131) (xy 44.427719 -12.223422) (xy 44.39736 -12.326812) (xy 44.359703 -12.427772)
			(xy 44.31494 -12.525789) (xy 44.263298 -12.620363) (xy 44.205042 -12.711011) (xy 44.140467 -12.797273)
			(xy 44.069902 -12.878708) (xy 43.993708 -12.954902) (xy 43.912273 -13.025467) (xy 43.826011 -13.090042)
			(xy 43.735363 -13.148298) (xy 43.640789 -13.19994) (xy 43.542772 -13.244703) (xy 43.441812 -13.28236)
			(xy 43.338422 -13.312719) (xy 43.233131 -13.335624) (xy 43.126473 -13.35096) (xy 43.018993 -13.358649)
			(xy 42.965116 -13.35913) (xy 34.964878 -13.35913) (xy 34.911001 -13.358648) (xy 34.803521 -13.35096)
			(xy 34.696864 -13.335624) (xy 34.591573 -13.312718) (xy 34.488184 -13.282359) (xy 34.387224 -13.244702)
			(xy 34.289207 -13.199938) (xy 34.194634 -13.148296) (xy 34.103986 -13.09004) (xy 34.017724 -13.025464)
			(xy 33.936289 -12.9549) (xy 33.860096 -12.878706) (xy 33.789532 -12.797271) (xy 33.724957 -12.711009)
			(xy 33.666701 -12.620361) (xy 33.615059 -12.525787) (xy 33.570296 -12.427771) (xy 33.532639 -12.326811)
			(xy 33.502281 -12.223422) (xy 33.479375 -12.11813) (xy 33.464039 -12.011473) (xy 33.456351 -11.903993)
			(xy 33.455864 -11.850116) (xy 33.455864 -1.999996) (xy 33.455355 -1.944227) (xy 33.44702 -1.833)
			(xy 33.430395 -1.722708) (xy 33.405575 -1.613966) (xy 33.372698 -1.507383) (xy 33.331948 -1.403555)
			(xy 33.283553 -1.303063) (xy 33.227783 -1.206468) (xy 33.164951 -1.114311) (xy 33.095408 -1.027107)
			(xy 33.019542 -0.945344) (xy 32.937778 -0.869479) (xy 32.850573 -0.799937) (xy 32.758415 -0.737106)
			(xy 32.66182 -0.681337) (xy 32.561327 -0.632944) (xy 32.457498 -0.592195) (xy 32.350915 -0.559319)
			(xy 32.242173 -0.534501) (xy 32.13188 -0.517878) (xy 32.020653 -0.509544) (xy 31.964884 -0.509016)
			(xy 19.964908 -0.509016) (xy 19.909138 -0.509524) (xy 19.797911 -0.517859) (xy 19.687617 -0.534483)
			(xy 19.578874 -0.559302) (xy 19.472289 -0.592178) (xy 19.36846 -0.632928) (xy 19.267966 -0.681322)
			(xy 19.17137 -0.737092) (xy 19.079211 -0.799924) (xy 18.992006 -0.869467) (xy 18.910241 -0.945333)
			(xy 18.834375 -1.027097) (xy 18.764831 -1.114302) (xy 18.701998 -1.20646) (xy 18.646228 -1.303056)
			(xy 18.597832 -1.403549) (xy 18.557082 -1.507378) (xy 18.524205 -1.613962) (xy 18.499385 -1.722705)
			(xy 18.48276 -1.832999) (xy 18.474425 -1.944226) (xy 18.473928 -1.999996) (xy 18.473928 -11.850116)
			(xy 18.473447 -11.903994) (xy 18.46576 -12.011474) (xy 18.450426 -12.118132) (xy 18.427521 -12.223425)
			(xy 18.397163 -12.326815) (xy 18.359507 -12.427777) (xy 18.314744 -12.525794) (xy 18.263103 -12.620369)
			(xy 18.204846 -12.711018) (xy 18.140271 -12.797281) (xy 18.069707 -12.878717) (xy 17.993513 -12.954911)
			(xy 17.912077 -13.025476) (xy 17.825815 -13.090052) (xy 17.735166 -13.148309) (xy 17.640591 -13.19995)
			(xy 17.542574 -13.244714) (xy 17.441613 -13.282371) (xy 17.338223 -13.312729) (xy 17.23293 -13.335634)
			(xy 17.126272 -13.35097) (xy 17.018792 -13.358657) (xy 16.964914 -13.35913) (xy 8.96493 -13.35913)
			(xy 8.911052 -13.35866) (xy 8.803571 -13.350973) (xy 8.696913 -13.335638) (xy 8.59162 -13.312733)
			(xy 8.488229 -13.282374) (xy 8.387268 -13.244718) (xy 8.28925 -13.199954) (xy 8.194675 -13.148313)
			(xy 8.104026 -13.090055) (xy 8.017763 -13.02548) (xy 7.936327 -12.954915) (xy 7.860132 -12.87872)
			(xy 7.789568 -12.797284) (xy 7.724992 -12.711021) (xy 7.666735 -12.620371) (xy 7.615094 -12.525797)
			(xy 7.570331 -12.427779) (xy 7.532674 -12.326817) (xy 7.502316 -12.223426) (xy 7.479412 -12.118133)
			(xy 7.464077 -12.011475) (xy 7.45639 -11.903994) (xy 7.455916 -11.850116) (xy 7.455916 -1.999996)
			(xy 7.455394 -1.944227) (xy 7.447059 -1.833001) (xy 7.430435 -1.722709) (xy 7.405615 -1.613968) (xy 7.372738 -1.507386)
			(xy 7.331989 -1.403558) (xy 7.283594 -1.303066) (xy 7.227825 -1.206472) (xy 7.164993 -1.114315) (xy 7.09545 -1.027112)
			(xy 7.019585 -0.945349) (xy 6.937822 -0.869484) (xy 6.850618 -0.799942) (xy 6.758461 -0.737111) (xy 6.661866 -0.681342)
			(xy 6.561374 -0.632948) (xy 6.457547 -0.592199) (xy 6.350964 -0.559323) (xy 6.242223 -0.534504) (xy 6.131931 -0.51788)
			(xy 6.020705 -0.509545) (xy 5.964936 -0.509016) (xy 4.689348 -0.509016) (xy 4.688332 -0.508) (xy 3.140456 -0.508)
			(xy 3.13944 -0.509016) (xy 1.999996 -0.509016) (xy 1.944227 -0.509538) (xy 1.833001 -0.517873) (xy 1.722709 -0.534497)
			(xy 1.613967 -0.559317) (xy 1.507385 -0.592194) (xy 1.403557 -0.632943) (xy 1.303065 -0.681338) (xy 1.20647 -0.737107)
			(xy 1.114313 -0.799938) (xy 1.027109 -0.869481) (xy 0.945346 -0.945346) (xy 0.869481 -1.027109) (xy 0.799938 -1.114313)
			(xy 0.737107 -1.20647) (xy 0.681338 -1.303065) (xy 0.632943 -1.403557) (xy 0.592194 -1.507385) (xy 0.559317 -1.613967)
			(xy 0.534497 -1.722709) (xy 0.517873 -1.833001) (xy 0.509538 -1.944227) (xy 0.509016 -1.999996) (xy 0.509016 -15.200122)
			(xy 459.541372 -15.200122) (xy 459.541372 -13.599922) (xy 459.54188 -13.535242) (xy 459.550003 -13.406136)
			(xy 459.566216 -13.277796) (xy 459.590456 -13.150726) (xy 459.622626 -13.02543) (xy 459.662601 -12.9024)
			(xy 459.710222 -12.782124) (xy 459.765301 -12.665075) (xy 459.827621 -12.551715) (xy 459.896936 -12.442492)
			(xy 459.972972 -12.337837) (xy 460.05543 -12.238163) (xy 460.143983 -12.143863) (xy 460.238283 -12.05531)
			(xy 460.337957 -11.972852) (xy 460.442612 -11.896816) (xy 460.551835 -11.827501) (xy 460.665195 -11.765181)
			(xy 460.782244 -11.710102) (xy 460.90252 -11.662481) (xy 461.02555 -11.622506) (xy 461.150846 -11.590336)
			(xy 461.277916 -11.566096) (xy 461.406256 -11.549883) (xy 461.535362 -11.54176) (xy 461.664722 -11.54176)
			(xy 461.793828 -11.549883) (xy 461.922168 -11.566096) (xy 462.049238 -11.590336) (xy 462.174534 -11.622506)
			(xy 462.297564 -11.662481) (xy 462.41784 -11.710102) (xy 462.534889 -11.765181) (xy 462.648249 -11.827501)
			(xy 462.757472 -11.896816) (xy 462.862127 -11.972852) (xy 462.961801 -12.05531) (xy 463.056101 -12.143863)
			(xy 463.144654 -12.238163) (xy 463.227112 -12.337837) (xy 463.303148 -12.442492) (xy 463.372463 -12.551715)
			(xy 463.434783 -12.665075) (xy 463.489862 -12.782124) (xy 463.537483 -12.9024) (xy 463.577458 -13.02543)
			(xy 463.609628 -13.150726) (xy 463.633868 -13.277796) (xy 463.650081 -13.406136) (xy 463.658204 -13.535242)
			(xy 463.658712 -13.599922) (xy 463.658712 -15.200122) (xy 463.658204 -15.264802) (xy 463.650081 -15.393908)
			(xy 463.633868 -15.522248) (xy 463.609628 -15.649318) (xy 463.577458 -15.774614) (xy 463.537483 -15.897644)
			(xy 463.489862 -16.01792) (xy 463.434783 -16.134969) (xy 463.372463 -16.248329) (xy 463.303148 -16.357552)
			(xy 463.227112 -16.462207) (xy 463.144654 -16.561881) (xy 463.056101 -16.656181) (xy 462.961801 -16.744734)
			(xy 462.862127 -16.827192) (xy 462.757472 -16.903228) (xy 462.648249 -16.972543) (xy 462.534889 -17.034863)
			(xy 462.41784 -17.089942) (xy 462.297564 -17.137563) (xy 462.174534 -17.177538) (xy 462.049238 -17.209708)
			(xy 461.922168 -17.233948) (xy 461.793828 -17.250161) (xy 461.664722 -17.258284) (xy 461.535362 -17.258284)
			(xy 461.406256 -17.250161) (xy 461.277916 -17.233948) (xy 461.150846 -17.209708) (xy 461.02555 -17.177538)
			(xy 460.90252 -17.137563) (xy 460.782244 -17.089942) (xy 460.665195 -17.034863) (xy 460.551835 -16.972543)
			(xy 460.442612 -16.903228) (xy 460.337957 -16.827192) (xy 460.238283 -16.744734) (xy 460.143983 -16.656181)
			(xy 460.05543 -16.561881) (xy 459.972972 -16.462207) (xy 459.896936 -16.357552) (xy 459.827621 -16.248329)
			(xy 459.765301 -16.134969) (xy 459.710222 -16.01792) (xy 459.662601 -15.897644) (xy 459.622626 -15.774614)
			(xy 459.590456 -15.649318) (xy 459.566216 -15.522248) (xy 459.550003 -15.393908) (xy 459.54188 -15.264802)
			(xy 459.541372 -15.200122) (xy 0.509016 -15.200122) (xy 0.509016 -16.969994) (xy 13.748265 -16.969994)
			(xy 13.75227 -16.882086) (xy 13.764253 -16.794906) (xy 13.784113 -16.709177) (xy 13.811688 -16.625609)
			(xy 13.846747 -16.544895) (xy 13.889 -16.467703) (xy 13.938098 -16.394674) (xy 13.993634 -16.326412)
			(xy 14.055146 -16.263482) (xy 14.122127 -16.206408) (xy 14.19402 -16.15566) (xy 14.270229 -16.11166)
			(xy 14.350124 -16.074773) (xy 14.433043 -16.045304) (xy 14.518298 -16.023497) (xy 14.605182 -16.009533)
			(xy 14.692976 -16.003527) (xy 14.780953 -16.005531) (xy 14.868383 -16.015526) (xy 14.954542 -16.03343)
			(xy 15.038716 -16.059094) (xy 15.120207 -16.092307) (xy 15.198341 -16.132793) (xy 15.272469 -16.180215)
			(xy 15.341977 -16.234182) (xy 15.406291 -16.294247) (xy 15.464875 -16.359911) (xy 15.517246 -16.43063)
			(xy 15.562969 -16.505818) (xy 15.601666 -16.584853) (xy 15.633015 -16.667079) (xy 15.656757 -16.751815)
			(xy 15.672695 -16.838359) (xy 15.680697 -16.925994) (xy 15.681198 -16.969994) (xy 39.748213 -16.969994)
			(xy 39.752218 -16.882086) (xy 39.764201 -16.794906) (xy 39.784061 -16.709177) (xy 39.811636 -16.625609)
			(xy 39.846695 -16.544895) (xy 39.888948 -16.467703) (xy 39.938046 -16.394674) (xy 39.993582 -16.326412)
			(xy 40.055094 -16.263482) (xy 40.122075 -16.206408) (xy 40.193968 -16.15566) (xy 40.270177 -16.11166)
			(xy 40.350072 -16.074773) (xy 40.432991 -16.045304) (xy 40.518246 -16.023497) (xy 40.60513 -16.009533)
			(xy 40.692924 -16.003527) (xy 40.780901 -16.005531) (xy 40.868331 -16.015526) (xy 40.95449 -16.03343)
			(xy 41.038664 -16.059094) (xy 41.120155 -16.092307) (xy 41.198289 -16.132793) (xy 41.272417 -16.180215)
			(xy 41.341925 -16.234182) (xy 41.406239 -16.294247) (xy 41.464823 -16.359911) (xy 41.517194 -16.43063)
			(xy 41.562917 -16.505818) (xy 41.601614 -16.584853) (xy 41.632963 -16.667079) (xy 41.656705 -16.751815)
			(xy 41.672643 -16.838359) (xy 41.680645 -16.925994) (xy 41.681146 -16.969994) (xy 65.748161 -16.969994)
			(xy 65.752166 -16.882086) (xy 65.764149 -16.794906) (xy 65.784009 -16.709177) (xy 65.811584 -16.625609)
			(xy 65.846643 -16.544895) (xy 65.888896 -16.467703) (xy 65.937994 -16.394674) (xy 65.99353 -16.326412)
			(xy 66.055042 -16.263482) (xy 66.122023 -16.206408) (xy 66.193916 -16.15566) (xy 66.270125 -16.11166)
			(xy 66.35002 -16.074773) (xy 66.432939 -16.045304) (xy 66.518194 -16.023497) (xy 66.605078 -16.009533)
			(xy 66.692872 -16.003527) (xy 66.780849 -16.005531) (xy 66.868279 -16.015526) (xy 66.954438 -16.03343)
			(xy 67.038612 -16.059094) (xy 67.120103 -16.092307) (xy 67.198237 -16.132793) (xy 67.272365 -16.180215)
			(xy 67.341873 -16.234182) (xy 67.406187 -16.294247) (xy 67.464771 -16.359911) (xy 67.517142 -16.43063)
			(xy 67.562865 -16.505818) (xy 67.601562 -16.584853) (xy 67.632911 -16.667079) (xy 67.656653 -16.751815)
			(xy 67.672591 -16.838359) (xy 67.680593 -16.925994) (xy 67.681094 -16.969994) (xy 91.748109 -16.969994)
			(xy 91.752114 -16.882086) (xy 91.764097 -16.794906) (xy 91.783957 -16.709177) (xy 91.811532 -16.625609)
			(xy 91.846591 -16.544895) (xy 91.888844 -16.467703) (xy 91.937942 -16.394674) (xy 91.993478 -16.326412)
			(xy 92.05499 -16.263482) (xy 92.121971 -16.206408) (xy 92.193864 -16.15566) (xy 92.270073 -16.11166)
			(xy 92.349968 -16.074773) (xy 92.432887 -16.045304) (xy 92.518142 -16.023497) (xy 92.605026 -16.009533)
			(xy 92.69282 -16.003527) (xy 92.780797 -16.005531) (xy 92.868227 -16.015526) (xy 92.954386 -16.03343)
			(xy 93.03856 -16.059094) (xy 93.120051 -16.092307) (xy 93.198185 -16.132793) (xy 93.272313 -16.180215)
			(xy 93.341821 -16.234182) (xy 93.406135 -16.294247) (xy 93.464719 -16.359911) (xy 93.51709 -16.43063)
			(xy 93.562813 -16.505818) (xy 93.60151 -16.584853) (xy 93.632859 -16.667079) (xy 93.656601 -16.751815)
			(xy 93.672539 -16.838359) (xy 93.680541 -16.925994) (xy 93.681042 -16.969994) (xy 129.848363 -16.969994)
			(xy 129.852368 -16.882086) (xy 129.864351 -16.794906) (xy 129.884211 -16.709177) (xy 129.911786 -16.625609)
			(xy 129.946845 -16.544895) (xy 129.989098 -16.467703) (xy 130.038196 -16.394674) (xy 130.093732 -16.326412)
			(xy 130.155244 -16.263482) (xy 130.222225 -16.206408) (xy 130.294118 -16.15566) (xy 130.370327 -16.11166)
			(xy 130.450222 -16.074773) (xy 130.533141 -16.045304) (xy 130.618396 -16.023497) (xy 130.70528 -16.009533)
			(xy 130.793074 -16.003527) (xy 130.881051 -16.005531) (xy 130.968481 -16.015526) (xy 131.05464 -16.03343)
			(xy 131.138814 -16.059094) (xy 131.220305 -16.092307) (xy 131.298439 -16.132793) (xy 131.372567 -16.180215)
			(xy 131.442075 -16.234182) (xy 131.506389 -16.294247) (xy 131.564973 -16.359911) (xy 131.617344 -16.43063)
			(xy 131.663067 -16.505818) (xy 131.701764 -16.584853) (xy 131.733113 -16.667079) (xy 131.756855 -16.751815)
			(xy 131.772793 -16.838359) (xy 131.780795 -16.925994) (xy 131.781296 -16.969994) (xy 155.848311 -16.969994)
			(xy 155.852316 -16.882086) (xy 155.864299 -16.794906) (xy 155.884159 -16.709177) (xy 155.911734 -16.625609)
			(xy 155.946793 -16.544895) (xy 155.989046 -16.467703) (xy 156.038144 -16.394674) (xy 156.09368 -16.326412)
			(xy 156.155192 -16.263482) (xy 156.222173 -16.206408) (xy 156.294066 -16.15566) (xy 156.370275 -16.11166)
			(xy 156.45017 -16.074773) (xy 156.533089 -16.045304) (xy 156.618344 -16.023497) (xy 156.705228 -16.009533)
			(xy 156.793022 -16.003527) (xy 156.880999 -16.005531) (xy 156.968429 -16.015526) (xy 157.054588 -16.03343)
			(xy 157.138762 -16.059094) (xy 157.220253 -16.092307) (xy 157.298387 -16.132793) (xy 157.372515 -16.180215)
			(xy 157.442023 -16.234182) (xy 157.506337 -16.294247) (xy 157.564921 -16.359911) (xy 157.617292 -16.43063)
			(xy 157.663015 -16.505818) (xy 157.701712 -16.584853) (xy 157.733061 -16.667079) (xy 157.756803 -16.751815)
			(xy 157.772741 -16.838359) (xy 157.780743 -16.925994) (xy 157.781244 -16.969994) (xy 181.848259 -16.969994)
			(xy 181.852264 -16.882086) (xy 181.864247 -16.794906) (xy 181.884107 -16.709177) (xy 181.911682 -16.625609)
			(xy 181.946741 -16.544895) (xy 181.988994 -16.467703) (xy 182.038092 -16.394674) (xy 182.093628 -16.326412)
			(xy 182.15514 -16.263482) (xy 182.222121 -16.206408) (xy 182.294014 -16.15566) (xy 182.370223 -16.11166)
			(xy 182.450118 -16.074773) (xy 182.533037 -16.045304) (xy 182.618292 -16.023497) (xy 182.705176 -16.009533)
			(xy 182.79297 -16.003527) (xy 182.880947 -16.005531) (xy 182.968377 -16.015526) (xy 183.054536 -16.03343)
			(xy 183.13871 -16.059094) (xy 183.220201 -16.092307) (xy 183.298335 -16.132793) (xy 183.372463 -16.180215)
			(xy 183.441971 -16.234182) (xy 183.506285 -16.294247) (xy 183.564869 -16.359911) (xy 183.61724 -16.43063)
			(xy 183.662963 -16.505818) (xy 183.70166 -16.584853) (xy 183.733009 -16.667079) (xy 183.756751 -16.751815)
			(xy 183.772689 -16.838359) (xy 183.780691 -16.925994) (xy 183.781192 -16.969994) (xy 207.848207 -16.969994)
			(xy 207.852212 -16.882086) (xy 207.864195 -16.794906) (xy 207.884055 -16.709177) (xy 207.91163 -16.625609)
			(xy 207.946689 -16.544895) (xy 207.988942 -16.467703) (xy 208.03804 -16.394674) (xy 208.093576 -16.326412)
			(xy 208.155088 -16.263482) (xy 208.222069 -16.206408) (xy 208.293962 -16.15566) (xy 208.370171 -16.11166)
			(xy 208.450066 -16.074773) (xy 208.532985 -16.045304) (xy 208.61824 -16.023497) (xy 208.705124 -16.009533)
			(xy 208.792918 -16.003527) (xy 208.880895 -16.005531) (xy 208.968325 -16.015526) (xy 209.054484 -16.03343)
			(xy 209.138658 -16.059094) (xy 209.220149 -16.092307) (xy 209.298283 -16.132793) (xy 209.372411 -16.180215)
			(xy 209.441919 -16.234182) (xy 209.506233 -16.294247) (xy 209.564817 -16.359911) (xy 209.617188 -16.43063)
			(xy 209.662911 -16.505818) (xy 209.701608 -16.584853) (xy 209.732957 -16.667079) (xy 209.756699 -16.751815)
			(xy 209.772637 -16.838359) (xy 209.780639 -16.925994) (xy 209.78114 -16.969994) (xy 245.948207 -16.969994)
			(xy 245.952212 -16.882086) (xy 245.964195 -16.794906) (xy 245.984055 -16.709177) (xy 246.01163 -16.625609)
			(xy 246.046689 -16.544895) (xy 246.088942 -16.467703) (xy 246.13804 -16.394674) (xy 246.193576 -16.326412)
			(xy 246.255088 -16.263482) (xy 246.322069 -16.206408) (xy 246.393962 -16.15566) (xy 246.470171 -16.11166)
			(xy 246.550066 -16.074773) (xy 246.632985 -16.045304) (xy 246.71824 -16.023497) (xy 246.805124 -16.009533)
			(xy 246.892918 -16.003527) (xy 246.980895 -16.005531) (xy 247.068325 -16.015526) (xy 247.154484 -16.03343)
			(xy 247.238658 -16.059094) (xy 247.320149 -16.092307) (xy 247.398283 -16.132793) (xy 247.472411 -16.180215)
			(xy 247.541919 -16.234182) (xy 247.606233 -16.294247) (xy 247.664817 -16.359911) (xy 247.717188 -16.43063)
			(xy 247.762911 -16.505818) (xy 247.801608 -16.584853) (xy 247.832957 -16.667079) (xy 247.856699 -16.751815)
			(xy 247.872637 -16.838359) (xy 247.880639 -16.925994) (xy 247.88114 -16.969994) (xy 271.948155 -16.969994)
			(xy 271.95216 -16.882086) (xy 271.964143 -16.794906) (xy 271.984003 -16.709177) (xy 272.011578 -16.625609)
			(xy 272.046637 -16.544895) (xy 272.08889 -16.467703) (xy 272.137988 -16.394674) (xy 272.193524 -16.326412)
			(xy 272.255036 -16.263482) (xy 272.322017 -16.206408) (xy 272.39391 -16.15566) (xy 272.470119 -16.11166)
			(xy 272.550014 -16.074773) (xy 272.632933 -16.045304) (xy 272.718188 -16.023497) (xy 272.805072 -16.009533)
			(xy 272.892866 -16.003527) (xy 272.980843 -16.005531) (xy 273.068273 -16.015526) (xy 273.154432 -16.03343)
			(xy 273.238606 -16.059094) (xy 273.320097 -16.092307) (xy 273.398231 -16.132793) (xy 273.472359 -16.180215)
			(xy 273.541867 -16.234182) (xy 273.606181 -16.294247) (xy 273.664765 -16.359911) (xy 273.717136 -16.43063)
			(xy 273.762859 -16.505818) (xy 273.801556 -16.584853) (xy 273.832905 -16.667079) (xy 273.856647 -16.751815)
			(xy 273.872585 -16.838359) (xy 273.880587 -16.925994) (xy 273.881088 -16.969994) (xy 297.948103 -16.969994)
			(xy 297.952108 -16.882086) (xy 297.964091 -16.794906) (xy 297.983951 -16.709177) (xy 298.011526 -16.625609)
			(xy 298.046585 -16.544895) (xy 298.088838 -16.467703) (xy 298.137936 -16.394674) (xy 298.193472 -16.326412)
			(xy 298.254984 -16.263482) (xy 298.321965 -16.206408) (xy 298.393858 -16.15566) (xy 298.470067 -16.11166)
			(xy 298.549962 -16.074773) (xy 298.632881 -16.045304) (xy 298.718136 -16.023497) (xy 298.80502 -16.009533)
			(xy 298.892814 -16.003527) (xy 298.980791 -16.005531) (xy 299.068221 -16.015526) (xy 299.15438 -16.03343)
			(xy 299.238554 -16.059094) (xy 299.320045 -16.092307) (xy 299.398179 -16.132793) (xy 299.472307 -16.180215)
			(xy 299.541815 -16.234182) (xy 299.606129 -16.294247) (xy 299.664713 -16.359911) (xy 299.717084 -16.43063)
			(xy 299.762807 -16.505818) (xy 299.801504 -16.584853) (xy 299.832853 -16.667079) (xy 299.856595 -16.751815)
			(xy 299.872533 -16.838359) (xy 299.880535 -16.925994) (xy 299.881036 -16.969994) (xy 323.948051 -16.969994)
			(xy 323.952056 -16.882086) (xy 323.964039 -16.794906) (xy 323.983899 -16.709177) (xy 324.011474 -16.625609)
			(xy 324.046533 -16.544895) (xy 324.088786 -16.467703) (xy 324.137884 -16.394674) (xy 324.19342 -16.326412)
			(xy 324.254932 -16.263482) (xy 324.321913 -16.206408) (xy 324.393806 -16.15566) (xy 324.470015 -16.11166)
			(xy 324.54991 -16.074773) (xy 324.632829 -16.045304) (xy 324.718084 -16.023497) (xy 324.804968 -16.009533)
			(xy 324.892762 -16.003527) (xy 324.980739 -16.005531) (xy 325.068169 -16.015526) (xy 325.154328 -16.03343)
			(xy 325.238502 -16.059094) (xy 325.319993 -16.092307) (xy 325.398127 -16.132793) (xy 325.472255 -16.180215)
			(xy 325.541763 -16.234182) (xy 325.606077 -16.294247) (xy 325.664661 -16.359911) (xy 325.717032 -16.43063)
			(xy 325.762755 -16.505818) (xy 325.801452 -16.584853) (xy 325.832801 -16.667079) (xy 325.856543 -16.751815)
			(xy 325.872481 -16.838359) (xy 325.880483 -16.925994) (xy 325.880984 -16.969994) (xy 362.048305 -16.969994)
			(xy 362.05231 -16.882086) (xy 362.064293 -16.794906) (xy 362.084153 -16.709177) (xy 362.111728 -16.625609)
			(xy 362.146787 -16.544895) (xy 362.18904 -16.467703) (xy 362.238138 -16.394674) (xy 362.293674 -16.326412)
			(xy 362.355186 -16.263482) (xy 362.422167 -16.206408) (xy 362.49406 -16.15566) (xy 362.570269 -16.11166)
			(xy 362.650164 -16.074773) (xy 362.733083 -16.045304) (xy 362.818338 -16.023497) (xy 362.905222 -16.009533)
			(xy 362.993016 -16.003527) (xy 363.080993 -16.005531) (xy 363.168423 -16.015526) (xy 363.254582 -16.03343)
			(xy 363.338756 -16.059094) (xy 363.420247 -16.092307) (xy 363.498381 -16.132793) (xy 363.572509 -16.180215)
			(xy 363.642017 -16.234182) (xy 363.706331 -16.294247) (xy 363.764915 -16.359911) (xy 363.817286 -16.43063)
			(xy 363.863009 -16.505818) (xy 363.901706 -16.584853) (xy 363.933055 -16.667079) (xy 363.956797 -16.751815)
			(xy 363.972735 -16.838359) (xy 363.980737 -16.925994) (xy 363.981238 -16.969994) (xy 388.048253 -16.969994)
			(xy 388.052258 -16.882086) (xy 388.064241 -16.794906) (xy 388.084101 -16.709177) (xy 388.111676 -16.625609)
			(xy 388.146735 -16.544895) (xy 388.188988 -16.467703) (xy 388.238086 -16.394674) (xy 388.293622 -16.326412)
			(xy 388.355134 -16.263482) (xy 388.422115 -16.206408) (xy 388.494008 -16.15566) (xy 388.570217 -16.11166)
			(xy 388.650112 -16.074773) (xy 388.733031 -16.045304) (xy 388.818286 -16.023497) (xy 388.90517 -16.009533)
			(xy 388.992964 -16.003527) (xy 389.080941 -16.005531) (xy 389.168371 -16.015526) (xy 389.25453 -16.03343)
			(xy 389.338704 -16.059094) (xy 389.420195 -16.092307) (xy 389.498329 -16.132793) (xy 389.572457 -16.180215)
			(xy 389.641965 -16.234182) (xy 389.706279 -16.294247) (xy 389.764863 -16.359911) (xy 389.817234 -16.43063)
			(xy 389.862957 -16.505818) (xy 389.901654 -16.584853) (xy 389.933003 -16.667079) (xy 389.956745 -16.751815)
			(xy 389.972683 -16.838359) (xy 389.980685 -16.925994) (xy 389.981186 -16.969994) (xy 414.048201 -16.969994)
			(xy 414.052206 -16.882086) (xy 414.064189 -16.794906) (xy 414.084049 -16.709177) (xy 414.111624 -16.625609)
			(xy 414.146683 -16.544895) (xy 414.188936 -16.467703) (xy 414.238034 -16.394674) (xy 414.29357 -16.326412)
			(xy 414.355082 -16.263482) (xy 414.422063 -16.206408) (xy 414.493956 -16.15566) (xy 414.570165 -16.11166)
			(xy 414.65006 -16.074773) (xy 414.732979 -16.045304) (xy 414.818234 -16.023497) (xy 414.905118 -16.009533)
			(xy 414.992912 -16.003527) (xy 415.080889 -16.005531) (xy 415.168319 -16.015526) (xy 415.254478 -16.03343)
			(xy 415.338652 -16.059094) (xy 415.420143 -16.092307) (xy 415.498277 -16.132793) (xy 415.572405 -16.180215)
			(xy 415.641913 -16.234182) (xy 415.706227 -16.294247) (xy 415.764811 -16.359911) (xy 415.817182 -16.43063)
			(xy 415.862905 -16.505818) (xy 415.901602 -16.584853) (xy 415.932951 -16.667079) (xy 415.956693 -16.751815)
			(xy 415.972631 -16.838359) (xy 415.980633 -16.925994) (xy 415.981134 -16.969994) (xy 440.048149 -16.969994)
			(xy 440.052154 -16.882086) (xy 440.064137 -16.794906) (xy 440.083997 -16.709177) (xy 440.111572 -16.625609)
			(xy 440.146631 -16.544895) (xy 440.188884 -16.467703) (xy 440.237982 -16.394674) (xy 440.293518 -16.326412)
			(xy 440.35503 -16.263482) (xy 440.422011 -16.206408) (xy 440.493904 -16.15566) (xy 440.570113 -16.11166)
			(xy 440.650008 -16.074773) (xy 440.732927 -16.045304) (xy 440.818182 -16.023497) (xy 440.905066 -16.009533)
			(xy 440.99286 -16.003527) (xy 441.080837 -16.005531) (xy 441.168267 -16.015526) (xy 441.254426 -16.03343)
			(xy 441.3386 -16.059094) (xy 441.420091 -16.092307) (xy 441.498225 -16.132793) (xy 441.572353 -16.180215)
			(xy 441.641861 -16.234182) (xy 441.706175 -16.294247) (xy 441.764759 -16.359911) (xy 441.81713 -16.43063)
			(xy 441.862853 -16.505818) (xy 441.90155 -16.584853) (xy 441.932899 -16.667079) (xy 441.956641 -16.751815)
			(xy 441.972579 -16.838359) (xy 441.980581 -16.925994) (xy 441.981082 -16.969994) (xy 441.980581 -17.013994)
			(xy 441.972579 -17.101629) (xy 441.956641 -17.188173) (xy 441.932899 -17.272909) (xy 441.90155 -17.355135)
			(xy 441.862853 -17.43417) (xy 441.81713 -17.509358) (xy 441.764759 -17.580077) (xy 441.706175 -17.645741)
			(xy 441.641861 -17.705806) (xy 441.572353 -17.759773) (xy 441.498225 -17.807195) (xy 441.420091 -17.847681)
			(xy 441.3386 -17.880894) (xy 441.254426 -17.906558) (xy 441.168267 -17.924462) (xy 441.080837 -17.934457)
			(xy 440.99286 -17.936461) (xy 440.905066 -17.930455) (xy 440.818182 -17.916491) (xy 440.732927 -17.894684)
			(xy 440.650008 -17.865215) (xy 440.570113 -17.828328) (xy 440.493904 -17.784328) (xy 440.422011 -17.73358)
			(xy 440.35503 -17.676506) (xy 440.293518 -17.613576) (xy 440.237982 -17.545314) (xy 440.188884 -17.472285)
			(xy 440.146631 -17.395093) (xy 440.111572 -17.314379) (xy 440.083997 -17.230811) (xy 440.064137 -17.145082)
			(xy 440.052154 -17.057902) (xy 440.048149 -16.969994) (xy 415.981134 -16.969994) (xy 415.980633 -17.013994)
			(xy 415.972631 -17.101629) (xy 415.956693 -17.188173) (xy 415.932951 -17.272909) (xy 415.901602 -17.355135)
			(xy 415.862905 -17.43417) (xy 415.817182 -17.509358) (xy 415.764811 -17.580077) (xy 415.706227 -17.645741)
			(xy 415.641913 -17.705806) (xy 415.572405 -17.759773) (xy 415.498277 -17.807195) (xy 415.420143 -17.847681)
			(xy 415.338652 -17.880894) (xy 415.254478 -17.906558) (xy 415.168319 -17.924462) (xy 415.080889 -17.934457)
			(xy 414.992912 -17.936461) (xy 414.905118 -17.930455) (xy 414.818234 -17.916491) (xy 414.732979 -17.894684)
			(xy 414.65006 -17.865215) (xy 414.570165 -17.828328) (xy 414.493956 -17.784328) (xy 414.422063 -17.73358)
			(xy 414.355082 -17.676506) (xy 414.29357 -17.613576) (xy 414.238034 -17.545314) (xy 414.188936 -17.472285)
			(xy 414.146683 -17.395093) (xy 414.111624 -17.314379) (xy 414.084049 -17.230811) (xy 414.064189 -17.145082)
			(xy 414.052206 -17.057902) (xy 414.048201 -16.969994) (xy 389.981186 -16.969994) (xy 389.980685 -17.013994)
			(xy 389.972683 -17.101629) (xy 389.956745 -17.188173) (xy 389.933003 -17.272909) (xy 389.901654 -17.355135)
			(xy 389.862957 -17.43417) (xy 389.817234 -17.509358) (xy 389.764863 -17.580077) (xy 389.706279 -17.645741)
			(xy 389.641965 -17.705806) (xy 389.572457 -17.759773) (xy 389.498329 -17.807195) (xy 389.420195 -17.847681)
			(xy 389.338704 -17.880894) (xy 389.25453 -17.906558) (xy 389.168371 -17.924462) (xy 389.080941 -17.934457)
			(xy 388.992964 -17.936461) (xy 388.90517 -17.930455) (xy 388.818286 -17.916491) (xy 388.733031 -17.894684)
			(xy 388.650112 -17.865215) (xy 388.570217 -17.828328) (xy 388.494008 -17.784328) (xy 388.422115 -17.73358)
			(xy 388.355134 -17.676506) (xy 388.293622 -17.613576) (xy 388.238086 -17.545314) (xy 388.188988 -17.472285)
			(xy 388.146735 -17.395093) (xy 388.111676 -17.314379) (xy 388.084101 -17.230811) (xy 388.064241 -17.145082)
			(xy 388.052258 -17.057902) (xy 388.048253 -16.969994) (xy 363.981238 -16.969994) (xy 363.980737 -17.013994)
			(xy 363.972735 -17.101629) (xy 363.956797 -17.188173) (xy 363.933055 -17.272909) (xy 363.901706 -17.355135)
			(xy 363.863009 -17.43417) (xy 363.817286 -17.509358) (xy 363.764915 -17.580077) (xy 363.706331 -17.645741)
			(xy 363.642017 -17.705806) (xy 363.572509 -17.759773) (xy 363.498381 -17.807195) (xy 363.420247 -17.847681)
			(xy 363.338756 -17.880894) (xy 363.254582 -17.906558) (xy 363.168423 -17.924462) (xy 363.080993 -17.934457)
			(xy 362.993016 -17.936461) (xy 362.905222 -17.930455) (xy 362.818338 -17.916491) (xy 362.733083 -17.894684)
			(xy 362.650164 -17.865215) (xy 362.570269 -17.828328) (xy 362.49406 -17.784328) (xy 362.422167 -17.73358)
			(xy 362.355186 -17.676506) (xy 362.293674 -17.613576) (xy 362.238138 -17.545314) (xy 362.18904 -17.472285)
			(xy 362.146787 -17.395093) (xy 362.111728 -17.314379) (xy 362.084153 -17.230811) (xy 362.064293 -17.145082)
			(xy 362.05231 -17.057902) (xy 362.048305 -16.969994) (xy 325.880984 -16.969994) (xy 325.880483 -17.013994)
			(xy 325.872481 -17.101629) (xy 325.856543 -17.188173) (xy 325.832801 -17.272909) (xy 325.801452 -17.355135)
			(xy 325.762755 -17.43417) (xy 325.717032 -17.509358) (xy 325.664661 -17.580077) (xy 325.606077 -17.645741)
			(xy 325.541763 -17.705806) (xy 325.472255 -17.759773) (xy 325.398127 -17.807195) (xy 325.319993 -17.847681)
			(xy 325.238502 -17.880894) (xy 325.154328 -17.906558) (xy 325.068169 -17.924462) (xy 324.980739 -17.934457)
			(xy 324.892762 -17.936461) (xy 324.804968 -17.930455) (xy 324.718084 -17.916491) (xy 324.632829 -17.894684)
			(xy 324.54991 -17.865215) (xy 324.470015 -17.828328) (xy 324.393806 -17.784328) (xy 324.321913 -17.73358)
			(xy 324.254932 -17.676506) (xy 324.19342 -17.613576) (xy 324.137884 -17.545314) (xy 324.088786 -17.472285)
			(xy 324.046533 -17.395093) (xy 324.011474 -17.314379) (xy 323.983899 -17.230811) (xy 323.964039 -17.145082)
			(xy 323.952056 -17.057902) (xy 323.948051 -16.969994) (xy 299.881036 -16.969994) (xy 299.880535 -17.013994)
			(xy 299.872533 -17.101629) (xy 299.856595 -17.188173) (xy 299.832853 -17.272909) (xy 299.801504 -17.355135)
			(xy 299.762807 -17.43417) (xy 299.717084 -17.509358) (xy 299.664713 -17.580077) (xy 299.606129 -17.645741)
			(xy 299.541815 -17.705806) (xy 299.472307 -17.759773) (xy 299.398179 -17.807195) (xy 299.320045 -17.847681)
			(xy 299.238554 -17.880894) (xy 299.15438 -17.906558) (xy 299.068221 -17.924462) (xy 298.980791 -17.934457)
			(xy 298.892814 -17.936461) (xy 298.80502 -17.930455) (xy 298.718136 -17.916491) (xy 298.632881 -17.894684)
			(xy 298.549962 -17.865215) (xy 298.470067 -17.828328) (xy 298.393858 -17.784328) (xy 298.321965 -17.73358)
			(xy 298.254984 -17.676506) (xy 298.193472 -17.613576) (xy 298.137936 -17.545314) (xy 298.088838 -17.472285)
			(xy 298.046585 -17.395093) (xy 298.011526 -17.314379) (xy 297.983951 -17.230811) (xy 297.964091 -17.145082)
			(xy 297.952108 -17.057902) (xy 297.948103 -16.969994) (xy 273.881088 -16.969994) (xy 273.880587 -17.013994)
			(xy 273.872585 -17.101629) (xy 273.856647 -17.188173) (xy 273.832905 -17.272909) (xy 273.801556 -17.355135)
			(xy 273.762859 -17.43417) (xy 273.717136 -17.509358) (xy 273.664765 -17.580077) (xy 273.606181 -17.645741)
			(xy 273.541867 -17.705806) (xy 273.472359 -17.759773) (xy 273.398231 -17.807195) (xy 273.320097 -17.847681)
			(xy 273.238606 -17.880894) (xy 273.154432 -17.906558) (xy 273.068273 -17.924462) (xy 272.980843 -17.934457)
			(xy 272.892866 -17.936461) (xy 272.805072 -17.930455) (xy 272.718188 -17.916491) (xy 272.632933 -17.894684)
			(xy 272.550014 -17.865215) (xy 272.470119 -17.828328) (xy 272.39391 -17.784328) (xy 272.322017 -17.73358)
			(xy 272.255036 -17.676506) (xy 272.193524 -17.613576) (xy 272.137988 -17.545314) (xy 272.08889 -17.472285)
			(xy 272.046637 -17.395093) (xy 272.011578 -17.314379) (xy 271.984003 -17.230811) (xy 271.964143 -17.145082)
			(xy 271.95216 -17.057902) (xy 271.948155 -16.969994) (xy 247.88114 -16.969994) (xy 247.880639 -17.013994)
			(xy 247.872637 -17.101629) (xy 247.856699 -17.188173) (xy 247.832957 -17.272909) (xy 247.801608 -17.355135)
			(xy 247.762911 -17.43417) (xy 247.717188 -17.509358) (xy 247.664817 -17.580077) (xy 247.606233 -17.645741)
			(xy 247.541919 -17.705806) (xy 247.472411 -17.759773) (xy 247.398283 -17.807195) (xy 247.320149 -17.847681)
			(xy 247.238658 -17.880894) (xy 247.154484 -17.906558) (xy 247.068325 -17.924462) (xy 246.980895 -17.934457)
			(xy 246.892918 -17.936461) (xy 246.805124 -17.930455) (xy 246.71824 -17.916491) (xy 246.632985 -17.894684)
			(xy 246.550066 -17.865215) (xy 246.470171 -17.828328) (xy 246.393962 -17.784328) (xy 246.322069 -17.73358)
			(xy 246.255088 -17.676506) (xy 246.193576 -17.613576) (xy 246.13804 -17.545314) (xy 246.088942 -17.472285)
			(xy 246.046689 -17.395093) (xy 246.01163 -17.314379) (xy 245.984055 -17.230811) (xy 245.964195 -17.145082)
			(xy 245.952212 -17.057902) (xy 245.948207 -16.969994) (xy 209.78114 -16.969994) (xy 209.780639 -17.013994)
			(xy 209.772637 -17.101629) (xy 209.756699 -17.188173) (xy 209.732957 -17.272909) (xy 209.701608 -17.355135)
			(xy 209.662911 -17.43417) (xy 209.617188 -17.509358) (xy 209.564817 -17.580077) (xy 209.506233 -17.645741)
			(xy 209.441919 -17.705806) (xy 209.372411 -17.759773) (xy 209.298283 -17.807195) (xy 209.220149 -17.847681)
			(xy 209.138658 -17.880894) (xy 209.054484 -17.906558) (xy 208.968325 -17.924462) (xy 208.880895 -17.934457)
			(xy 208.792918 -17.936461) (xy 208.705124 -17.930455) (xy 208.61824 -17.916491) (xy 208.532985 -17.894684)
			(xy 208.450066 -17.865215) (xy 208.370171 -17.828328) (xy 208.293962 -17.784328) (xy 208.222069 -17.73358)
			(xy 208.155088 -17.676506) (xy 208.093576 -17.613576) (xy 208.03804 -17.545314) (xy 207.988942 -17.472285)
			(xy 207.946689 -17.395093) (xy 207.91163 -17.314379) (xy 207.884055 -17.230811) (xy 207.864195 -17.145082)
			(xy 207.852212 -17.057902) (xy 207.848207 -16.969994) (xy 183.781192 -16.969994) (xy 183.780691 -17.013994)
			(xy 183.772689 -17.101629) (xy 183.756751 -17.188173) (xy 183.733009 -17.272909) (xy 183.70166 -17.355135)
			(xy 183.662963 -17.43417) (xy 183.61724 -17.509358) (xy 183.564869 -17.580077) (xy 183.506285 -17.645741)
			(xy 183.441971 -17.705806) (xy 183.372463 -17.759773) (xy 183.298335 -17.807195) (xy 183.220201 -17.847681)
			(xy 183.13871 -17.880894) (xy 183.054536 -17.906558) (xy 182.968377 -17.924462) (xy 182.880947 -17.934457)
			(xy 182.79297 -17.936461) (xy 182.705176 -17.930455) (xy 182.618292 -17.916491) (xy 182.533037 -17.894684)
			(xy 182.450118 -17.865215) (xy 182.370223 -17.828328) (xy 182.294014 -17.784328) (xy 182.222121 -17.73358)
			(xy 182.15514 -17.676506) (xy 182.093628 -17.613576) (xy 182.038092 -17.545314) (xy 181.988994 -17.472285)
			(xy 181.946741 -17.395093) (xy 181.911682 -17.314379) (xy 181.884107 -17.230811) (xy 181.864247 -17.145082)
			(xy 181.852264 -17.057902) (xy 181.848259 -16.969994) (xy 157.781244 -16.969994) (xy 157.780743 -17.013994)
			(xy 157.772741 -17.101629) (xy 157.756803 -17.188173) (xy 157.733061 -17.272909) (xy 157.701712 -17.355135)
			(xy 157.663015 -17.43417) (xy 157.617292 -17.509358) (xy 157.564921 -17.580077) (xy 157.506337 -17.645741)
			(xy 157.442023 -17.705806) (xy 157.372515 -17.759773) (xy 157.298387 -17.807195) (xy 157.220253 -17.847681)
			(xy 157.138762 -17.880894) (xy 157.054588 -17.906558) (xy 156.968429 -17.924462) (xy 156.880999 -17.934457)
			(xy 156.793022 -17.936461) (xy 156.705228 -17.930455) (xy 156.618344 -17.916491) (xy 156.533089 -17.894684)
			(xy 156.45017 -17.865215) (xy 156.370275 -17.828328) (xy 156.294066 -17.784328) (xy 156.222173 -17.73358)
			(xy 156.155192 -17.676506) (xy 156.09368 -17.613576) (xy 156.038144 -17.545314) (xy 155.989046 -17.472285)
			(xy 155.946793 -17.395093) (xy 155.911734 -17.314379) (xy 155.884159 -17.230811) (xy 155.864299 -17.145082)
			(xy 155.852316 -17.057902) (xy 155.848311 -16.969994) (xy 131.781296 -16.969994) (xy 131.780795 -17.013994)
			(xy 131.772793 -17.101629) (xy 131.756855 -17.188173) (xy 131.733113 -17.272909) (xy 131.701764 -17.355135)
			(xy 131.663067 -17.43417) (xy 131.617344 -17.509358) (xy 131.564973 -17.580077) (xy 131.506389 -17.645741)
			(xy 131.442075 -17.705806) (xy 131.372567 -17.759773) (xy 131.298439 -17.807195) (xy 131.220305 -17.847681)
			(xy 131.138814 -17.880894) (xy 131.05464 -17.906558) (xy 130.968481 -17.924462) (xy 130.881051 -17.934457)
			(xy 130.793074 -17.936461) (xy 130.70528 -17.930455) (xy 130.618396 -17.916491) (xy 130.533141 -17.894684)
			(xy 130.450222 -17.865215) (xy 130.370327 -17.828328) (xy 130.294118 -17.784328) (xy 130.222225 -17.73358)
			(xy 130.155244 -17.676506) (xy 130.093732 -17.613576) (xy 130.038196 -17.545314) (xy 129.989098 -17.472285)
			(xy 129.946845 -17.395093) (xy 129.911786 -17.314379) (xy 129.884211 -17.230811) (xy 129.864351 -17.145082)
			(xy 129.852368 -17.057902) (xy 129.848363 -16.969994) (xy 93.681042 -16.969994) (xy 93.680541 -17.013994)
			(xy 93.672539 -17.101629) (xy 93.656601 -17.188173) (xy 93.632859 -17.272909) (xy 93.60151 -17.355135)
			(xy 93.562813 -17.43417) (xy 93.51709 -17.509358) (xy 93.464719 -17.580077) (xy 93.406135 -17.645741)
			(xy 93.341821 -17.705806) (xy 93.272313 -17.759773) (xy 93.198185 -17.807195) (xy 93.120051 -17.847681)
			(xy 93.03856 -17.880894) (xy 92.954386 -17.906558) (xy 92.868227 -17.924462) (xy 92.780797 -17.934457)
			(xy 92.69282 -17.936461) (xy 92.605026 -17.930455) (xy 92.518142 -17.916491) (xy 92.432887 -17.894684)
			(xy 92.349968 -17.865215) (xy 92.270073 -17.828328) (xy 92.193864 -17.784328) (xy 92.121971 -17.73358)
			(xy 92.05499 -17.676506) (xy 91.993478 -17.613576) (xy 91.937942 -17.545314) (xy 91.888844 -17.472285)
			(xy 91.846591 -17.395093) (xy 91.811532 -17.314379) (xy 91.783957 -17.230811) (xy 91.764097 -17.145082)
			(xy 91.752114 -17.057902) (xy 91.748109 -16.969994) (xy 67.681094 -16.969994) (xy 67.680593 -17.013994)
			(xy 67.672591 -17.101629) (xy 67.656653 -17.188173) (xy 67.632911 -17.272909) (xy 67.601562 -17.355135)
			(xy 67.562865 -17.43417) (xy 67.517142 -17.509358) (xy 67.464771 -17.580077) (xy 67.406187 -17.645741)
			(xy 67.341873 -17.705806) (xy 67.272365 -17.759773) (xy 67.198237 -17.807195) (xy 67.120103 -17.847681)
			(xy 67.038612 -17.880894) (xy 66.954438 -17.906558) (xy 66.868279 -17.924462) (xy 66.780849 -17.934457)
			(xy 66.692872 -17.936461) (xy 66.605078 -17.930455) (xy 66.518194 -17.916491) (xy 66.432939 -17.894684)
			(xy 66.35002 -17.865215) (xy 66.270125 -17.828328) (xy 66.193916 -17.784328) (xy 66.122023 -17.73358)
			(xy 66.055042 -17.676506) (xy 65.99353 -17.613576) (xy 65.937994 -17.545314) (xy 65.888896 -17.472285)
			(xy 65.846643 -17.395093) (xy 65.811584 -17.314379) (xy 65.784009 -17.230811) (xy 65.764149 -17.145082)
			(xy 65.752166 -17.057902) (xy 65.748161 -16.969994) (xy 41.681146 -16.969994) (xy 41.680645 -17.013994)
			(xy 41.672643 -17.101629) (xy 41.656705 -17.188173) (xy 41.632963 -17.272909) (xy 41.601614 -17.355135)
			(xy 41.562917 -17.43417) (xy 41.517194 -17.509358) (xy 41.464823 -17.580077) (xy 41.406239 -17.645741)
			(xy 41.341925 -17.705806) (xy 41.272417 -17.759773) (xy 41.198289 -17.807195) (xy 41.120155 -17.847681)
			(xy 41.038664 -17.880894) (xy 40.95449 -17.906558) (xy 40.868331 -17.924462) (xy 40.780901 -17.934457)
			(xy 40.692924 -17.936461) (xy 40.60513 -17.930455) (xy 40.518246 -17.916491) (xy 40.432991 -17.894684)
			(xy 40.350072 -17.865215) (xy 40.270177 -17.828328) (xy 40.193968 -17.784328) (xy 40.122075 -17.73358)
			(xy 40.055094 -17.676506) (xy 39.993582 -17.613576) (xy 39.938046 -17.545314) (xy 39.888948 -17.472285)
			(xy 39.846695 -17.395093) (xy 39.811636 -17.314379) (xy 39.784061 -17.230811) (xy 39.764201 -17.145082)
			(xy 39.752218 -17.057902) (xy 39.748213 -16.969994) (xy 15.681198 -16.969994) (xy 15.680697 -17.013994)
			(xy 15.672695 -17.101629) (xy 15.656757 -17.188173) (xy 15.633015 -17.272909) (xy 15.601666 -17.355135)
			(xy 15.562969 -17.43417) (xy 15.517246 -17.509358) (xy 15.464875 -17.580077) (xy 15.406291 -17.645741)
			(xy 15.341977 -17.705806) (xy 15.272469 -17.759773) (xy 15.198341 -17.807195) (xy 15.120207 -17.847681)
			(xy 15.038716 -17.880894) (xy 14.954542 -17.906558) (xy 14.868383 -17.924462) (xy 14.780953 -17.934457)
			(xy 14.692976 -17.936461) (xy 14.605182 -17.930455) (xy 14.518298 -17.916491) (xy 14.433043 -17.894684)
			(xy 14.350124 -17.865215) (xy 14.270229 -17.828328) (xy 14.19402 -17.784328) (xy 14.122127 -17.73358)
			(xy 14.055146 -17.676506) (xy 13.993634 -17.613576) (xy 13.938098 -17.545314) (xy 13.889 -17.472285)
			(xy 13.846747 -17.395093) (xy 13.811688 -17.314379) (xy 13.784113 -17.230811) (xy 13.764253 -17.145082)
			(xy 13.75227 -17.057902) (xy 13.748265 -16.969994) (xy 0.509016 -16.969994) (xy 0.509016 -27.342846)
			(xy 16.523716 -27.342846) (xy 16.523716 -26.479246) (xy 16.524206 -26.449278) (xy 16.532029 -26.389856)
			(xy 16.547542 -26.331963) (xy 16.570478 -26.27659) (xy 16.600445 -26.224684) (xy 16.636932 -26.177134)
			(xy 16.679312 -26.134754) (xy 16.726862 -26.098267) (xy 16.778768 -26.0683) (xy 16.834141 -26.045364)
			(xy 16.892034 -26.029851) (xy 16.951456 -26.022028) (xy 17.011392 -26.022028) (xy 17.070814 -26.029851)
			(xy 17.128707 -26.045364) (xy 17.18408 -26.0683) (xy 17.235986 -26.098267) (xy 17.283536 -26.134754)
			(xy 17.325916 -26.177134) (xy 17.362403 -26.224684) (xy 17.39237 -26.27659) (xy 17.415306 -26.331963)
			(xy 17.430819 -26.389856) (xy 17.438642 -26.449278) (xy 17.439132 -26.479246) (xy 17.439132 -27.342846)
			(xy 42.523664 -27.342846) (xy 42.523664 -26.479246) (xy 42.524154 -26.449278) (xy 42.531977 -26.389856)
			(xy 42.54749 -26.331963) (xy 42.570426 -26.27659) (xy 42.600393 -26.224684) (xy 42.63688 -26.177134)
			(xy 42.67926 -26.134754) (xy 42.72681 -26.098267) (xy 42.778716 -26.0683) (xy 42.834089 -26.045364)
			(xy 42.891982 -26.029851) (xy 42.951404 -26.022028) (xy 43.01134 -26.022028) (xy 43.070762 -26.029851)
			(xy 43.128655 -26.045364) (xy 43.184028 -26.0683) (xy 43.235934 -26.098267) (xy 43.283484 -26.134754)
			(xy 43.325864 -26.177134) (xy 43.362351 -26.224684) (xy 43.392318 -26.27659) (xy 43.415254 -26.331963)
			(xy 43.430767 -26.389856) (xy 43.43859 -26.449278) (xy 43.43908 -26.479246) (xy 43.43908 -27.342846)
			(xy 68.523612 -27.342846) (xy 68.523612 -26.479246) (xy 68.524102 -26.449278) (xy 68.531925 -26.389856)
			(xy 68.547438 -26.331963) (xy 68.570374 -26.27659) (xy 68.600341 -26.224684) (xy 68.636828 -26.177134)
			(xy 68.679208 -26.134754) (xy 68.726758 -26.098267) (xy 68.778664 -26.0683) (xy 68.834037 -26.045364)
			(xy 68.89193 -26.029851) (xy 68.951352 -26.022028) (xy 69.011288 -26.022028) (xy 69.07071 -26.029851)
			(xy 69.128603 -26.045364) (xy 69.183976 -26.0683) (xy 69.235882 -26.098267) (xy 69.283432 -26.134754)
			(xy 69.325812 -26.177134) (xy 69.362299 -26.224684) (xy 69.392266 -26.27659) (xy 69.415202 -26.331963)
			(xy 69.430715 -26.389856) (xy 69.438538 -26.449278) (xy 69.439028 -26.479246) (xy 69.439028 -27.342846)
			(xy 94.52356 -27.342846) (xy 94.52356 -26.479246) (xy 94.52405 -26.449278) (xy 94.531873 -26.389856)
			(xy 94.547386 -26.331963) (xy 94.570322 -26.27659) (xy 94.600289 -26.224684) (xy 94.636776 -26.177134)
			(xy 94.679156 -26.134754) (xy 94.726706 -26.098267) (xy 94.778612 -26.0683) (xy 94.833985 -26.045364)
			(xy 94.891878 -26.029851) (xy 94.9513 -26.022028) (xy 95.011236 -26.022028) (xy 95.070658 -26.029851)
			(xy 95.128551 -26.045364) (xy 95.183924 -26.0683) (xy 95.23583 -26.098267) (xy 95.28338 -26.134754)
			(xy 95.32576 -26.177134) (xy 95.362247 -26.224684) (xy 95.392214 -26.27659) (xy 95.41515 -26.331963)
			(xy 95.430663 -26.389856) (xy 95.438486 -26.449278) (xy 95.438976 -26.479246) (xy 95.438976 -27.342846)
			(xy 132.62356 -27.342846) (xy 132.62356 -26.479246) (xy 132.62405 -26.449262) (xy 132.631878 -26.389806)
			(xy 132.647399 -26.331881) (xy 132.670348 -26.276477) (xy 132.700332 -26.224543) (xy 132.736838 -26.176967)
			(xy 132.779243 -26.134562) (xy 132.826819 -26.098056) (xy 132.878753 -26.068072) (xy 132.934157 -26.045123)
			(xy 132.992082 -26.029602) (xy 133.051538 -26.021774) (xy 133.111506 -26.021774) (xy 133.170962 -26.029602)
			(xy 133.228887 -26.045123) (xy 133.284291 -26.068072) (xy 133.336225 -26.098056) (xy 133.383801 -26.134562)
			(xy 133.426206 -26.176967) (xy 133.462712 -26.224543) (xy 133.492696 -26.276477) (xy 133.515645 -26.331881)
			(xy 133.531166 -26.389806) (xy 133.538994 -26.449262) (xy 133.539484 -26.479246) (xy 133.539484 -27.342846)
			(xy 158.623508 -27.342846) (xy 158.623508 -26.479246) (xy 158.623998 -26.449262) (xy 158.631826 -26.389806)
			(xy 158.647347 -26.331881) (xy 158.670296 -26.276477) (xy 158.70028 -26.224543) (xy 158.736786 -26.176967)
			(xy 158.779191 -26.134562) (xy 158.826767 -26.098056) (xy 158.878701 -26.068072) (xy 158.934105 -26.045123)
			(xy 158.99203 -26.029602) (xy 159.051486 -26.021774) (xy 159.111454 -26.021774) (xy 159.17091 -26.029602)
			(xy 159.228835 -26.045123) (xy 159.284239 -26.068072) (xy 159.336173 -26.098056) (xy 159.383749 -26.134562)
			(xy 159.426154 -26.176967) (xy 159.46266 -26.224543) (xy 159.492644 -26.276477) (xy 159.515593 -26.331881)
			(xy 159.531114 -26.389806) (xy 159.538942 -26.449262) (xy 159.539432 -26.479246) (xy 159.539432 -27.342846)
			(xy 184.623456 -27.342846) (xy 184.623456 -26.479246) (xy 184.623946 -26.449262) (xy 184.631774 -26.389806)
			(xy 184.647295 -26.331881) (xy 184.670244 -26.276477) (xy 184.700228 -26.224543) (xy 184.736734 -26.176967)
			(xy 184.779139 -26.134562) (xy 184.826715 -26.098056) (xy 184.878649 -26.068072) (xy 184.934053 -26.045123)
			(xy 184.991978 -26.029602) (xy 185.051434 -26.021774) (xy 185.111402 -26.021774) (xy 185.170858 -26.029602)
			(xy 185.228783 -26.045123) (xy 185.284187 -26.068072) (xy 185.336121 -26.098056) (xy 185.383697 -26.134562)
			(xy 185.426102 -26.176967) (xy 185.462608 -26.224543) (xy 185.492592 -26.276477) (xy 185.515541 -26.331881)
			(xy 185.531062 -26.389806) (xy 185.53889 -26.449262) (xy 185.53938 -26.479246) (xy 185.53938 -27.342846)
			(xy 210.623404 -27.342846) (xy 210.623404 -26.479246) (xy 210.623894 -26.449262) (xy 210.631722 -26.389806)
			(xy 210.647243 -26.331881) (xy 210.670192 -26.276477) (xy 210.700176 -26.224543) (xy 210.736682 -26.176967)
			(xy 210.779087 -26.134562) (xy 210.826663 -26.098056) (xy 210.878597 -26.068072) (xy 210.934001 -26.045123)
			(xy 210.991926 -26.029602) (xy 211.051382 -26.021774) (xy 211.11135 -26.021774) (xy 211.170806 -26.029602)
			(xy 211.228731 -26.045123) (xy 211.284135 -26.068072) (xy 211.336069 -26.098056) (xy 211.383645 -26.134562)
			(xy 211.42605 -26.176967) (xy 211.462556 -26.224543) (xy 211.49254 -26.276477) (xy 211.515489 -26.331881)
			(xy 211.53101 -26.389806) (xy 211.538838 -26.449262) (xy 211.539328 -26.479246) (xy 211.539328 -27.342846)
			(xy 248.723404 -27.342846) (xy 248.723404 -26.479246) (xy 248.723894 -26.449262) (xy 248.731722 -26.389806)
			(xy 248.747243 -26.331881) (xy 248.770192 -26.276477) (xy 248.800176 -26.224543) (xy 248.836682 -26.176967)
			(xy 248.879087 -26.134562) (xy 248.926663 -26.098056) (xy 248.978597 -26.068072) (xy 249.034001 -26.045123)
			(xy 249.091926 -26.029602) (xy 249.151382 -26.021774) (xy 249.21135 -26.021774) (xy 249.270806 -26.029602)
			(xy 249.328731 -26.045123) (xy 249.384135 -26.068072) (xy 249.436069 -26.098056) (xy 249.483645 -26.134562)
			(xy 249.52605 -26.176967) (xy 249.562556 -26.224543) (xy 249.59254 -26.276477) (xy 249.615489 -26.331881)
			(xy 249.63101 -26.389806) (xy 249.638838 -26.449262) (xy 249.639328 -26.479246) (xy 249.639328 -27.342846)
			(xy 274.723352 -27.342846) (xy 274.723352 -26.479246) (xy 274.723842 -26.449262) (xy 274.73167 -26.389806)
			(xy 274.747191 -26.331881) (xy 274.77014 -26.276477) (xy 274.800124 -26.224543) (xy 274.83663 -26.176967)
			(xy 274.879035 -26.134562) (xy 274.926611 -26.098056) (xy 274.978545 -26.068072) (xy 275.033949 -26.045123)
			(xy 275.091874 -26.029602) (xy 275.15133 -26.021774) (xy 275.211298 -26.021774) (xy 275.270754 -26.029602)
			(xy 275.328679 -26.045123) (xy 275.384083 -26.068072) (xy 275.436017 -26.098056) (xy 275.483593 -26.134562)
			(xy 275.525998 -26.176967) (xy 275.562504 -26.224543) (xy 275.592488 -26.276477) (xy 275.615437 -26.331881)
			(xy 275.630958 -26.389806) (xy 275.638786 -26.449262) (xy 275.639276 -26.479246) (xy 275.639276 -27.342846)
			(xy 300.7233 -27.342846) (xy 300.7233 -26.479246) (xy 300.72379 -26.449262) (xy 300.731618 -26.389806)
			(xy 300.747139 -26.331881) (xy 300.770088 -26.276477) (xy 300.800072 -26.224543) (xy 300.836578 -26.176967)
			(xy 300.878983 -26.134562) (xy 300.926559 -26.098056) (xy 300.978493 -26.068072) (xy 301.033897 -26.045123)
			(xy 301.091822 -26.029602) (xy 301.151278 -26.021774) (xy 301.211246 -26.021774) (xy 301.270702 -26.029602)
			(xy 301.328627 -26.045123) (xy 301.384031 -26.068072) (xy 301.435965 -26.098056) (xy 301.483541 -26.134562)
			(xy 301.525946 -26.176967) (xy 301.562452 -26.224543) (xy 301.592436 -26.276477) (xy 301.615385 -26.331881)
			(xy 301.630906 -26.389806) (xy 301.638734 -26.449262) (xy 301.639224 -26.479246) (xy 301.639224 -27.342846)
			(xy 326.723248 -27.342846) (xy 326.723248 -26.479246) (xy 326.723738 -26.449262) (xy 326.731566 -26.389806)
			(xy 326.747087 -26.331881) (xy 326.770036 -26.276477) (xy 326.80002 -26.224543) (xy 326.836526 -26.176967)
			(xy 326.878931 -26.134562) (xy 326.926507 -26.098056) (xy 326.978441 -26.068072) (xy 327.033845 -26.045123)
			(xy 327.09177 -26.029602) (xy 327.151226 -26.021774) (xy 327.211194 -26.021774) (xy 327.27065 -26.029602)
			(xy 327.328575 -26.045123) (xy 327.383979 -26.068072) (xy 327.435913 -26.098056) (xy 327.483489 -26.134562)
			(xy 327.525894 -26.176967) (xy 327.5624 -26.224543) (xy 327.592384 -26.276477) (xy 327.615333 -26.331881)
			(xy 327.630854 -26.389806) (xy 327.638682 -26.449262) (xy 327.639172 -26.479246) (xy 327.639172 -27.342846)
			(xy 364.823756 -27.342846) (xy 364.823756 -26.479246) (xy 364.824246 -26.449278) (xy 364.832069 -26.389856)
			(xy 364.847582 -26.331963) (xy 364.870518 -26.27659) (xy 364.900485 -26.224684) (xy 364.936972 -26.177134)
			(xy 364.979352 -26.134754) (xy 365.026902 -26.098267) (xy 365.078808 -26.0683) (xy 365.134181 -26.045364)
			(xy 365.192074 -26.029851) (xy 365.251496 -26.022028) (xy 365.311432 -26.022028) (xy 365.370854 -26.029851)
			(xy 365.428747 -26.045364) (xy 365.48412 -26.0683) (xy 365.536026 -26.098267) (xy 365.583576 -26.134754)
			(xy 365.625956 -26.177134) (xy 365.662443 -26.224684) (xy 365.69241 -26.27659) (xy 365.715346 -26.331963)
			(xy 365.730859 -26.389856) (xy 365.738682 -26.449278) (xy 365.739172 -26.479246) (xy 365.739172 -27.342846)
			(xy 390.823704 -27.342846) (xy 390.823704 -26.479246) (xy 390.824194 -26.449278) (xy 390.832017 -26.389856)
			(xy 390.84753 -26.331963) (xy 390.870466 -26.27659) (xy 390.900433 -26.224684) (xy 390.93692 -26.177134)
			(xy 390.9793 -26.134754) (xy 391.02685 -26.098267) (xy 391.078756 -26.0683) (xy 391.134129 -26.045364)
			(xy 391.192022 -26.029851) (xy 391.251444 -26.022028) (xy 391.31138 -26.022028) (xy 391.370802 -26.029851)
			(xy 391.428695 -26.045364) (xy 391.484068 -26.0683) (xy 391.535974 -26.098267) (xy 391.583524 -26.134754)
			(xy 391.625904 -26.177134) (xy 391.662391 -26.224684) (xy 391.692358 -26.27659) (xy 391.715294 -26.331963)
			(xy 391.730807 -26.389856) (xy 391.73863 -26.449278) (xy 391.73912 -26.479246) (xy 391.73912 -27.342846)
			(xy 416.823652 -27.342846) (xy 416.823652 -26.479246) (xy 416.824142 -26.449278) (xy 416.831965 -26.389856)
			(xy 416.847478 -26.331963) (xy 416.870414 -26.27659) (xy 416.900381 -26.224684) (xy 416.936868 -26.177134)
			(xy 416.979248 -26.134754) (xy 417.026798 -26.098267) (xy 417.078704 -26.0683) (xy 417.134077 -26.045364)
			(xy 417.19197 -26.029851) (xy 417.251392 -26.022028) (xy 417.311328 -26.022028) (xy 417.37075 -26.029851)
			(xy 417.428643 -26.045364) (xy 417.484016 -26.0683) (xy 417.535922 -26.098267) (xy 417.583472 -26.134754)
			(xy 417.625852 -26.177134) (xy 417.662339 -26.224684) (xy 417.692306 -26.27659) (xy 417.715242 -26.331963)
			(xy 417.730755 -26.389856) (xy 417.738578 -26.449278) (xy 417.739068 -26.479246) (xy 417.739068 -27.342846)
			(xy 442.8236 -27.342846) (xy 442.8236 -26.479246) (xy 442.82409 -26.449278) (xy 442.831913 -26.389856)
			(xy 442.847426 -26.331963) (xy 442.870362 -26.27659) (xy 442.900329 -26.224684) (xy 442.936816 -26.177134)
			(xy 442.979196 -26.134754) (xy 443.026746 -26.098267) (xy 443.078652 -26.0683) (xy 443.134025 -26.045364)
			(xy 443.191918 -26.029851) (xy 443.25134 -26.022028) (xy 443.311276 -26.022028) (xy 443.370698 -26.029851)
			(xy 443.428591 -26.045364) (xy 443.483964 -26.0683) (xy 443.53587 -26.098267) (xy 443.58342 -26.134754)
			(xy 443.6258 -26.177134) (xy 443.662287 -26.224684) (xy 443.692254 -26.27659) (xy 443.71519 -26.331963)
			(xy 443.730703 -26.389856) (xy 443.738526 -26.449278) (xy 443.739016 -26.479246) (xy 443.739016 -27.342846)
			(xy 443.738526 -27.372814) (xy 443.730703 -27.432236) (xy 443.71519 -27.490129) (xy 443.692254 -27.545502)
			(xy 443.662287 -27.597408) (xy 443.6258 -27.644958) (xy 443.58342 -27.687338) (xy 443.53587 -27.723825)
			(xy 443.483964 -27.753792) (xy 443.428591 -27.776728) (xy 443.370698 -27.792241) (xy 443.311276 -27.800064)
			(xy 443.25134 -27.800064) (xy 443.191918 -27.792241) (xy 443.134025 -27.776728) (xy 443.078652 -27.753792)
			(xy 443.026746 -27.723825) (xy 442.979196 -27.687338) (xy 442.936816 -27.644958) (xy 442.900329 -27.597408)
			(xy 442.870362 -27.545502) (xy 442.847426 -27.490129) (xy 442.831913 -27.432236) (xy 442.82409 -27.372814)
			(xy 442.8236 -27.342846) (xy 417.739068 -27.342846) (xy 417.738578 -27.372814) (xy 417.730755 -27.432236)
			(xy 417.715242 -27.490129) (xy 417.692306 -27.545502) (xy 417.662339 -27.597408) (xy 417.625852 -27.644958)
			(xy 417.583472 -27.687338) (xy 417.535922 -27.723825) (xy 417.484016 -27.753792) (xy 417.428643 -27.776728)
			(xy 417.37075 -27.792241) (xy 417.311328 -27.800064) (xy 417.251392 -27.800064) (xy 417.19197 -27.792241)
			(xy 417.134077 -27.776728) (xy 417.078704 -27.753792) (xy 417.026798 -27.723825) (xy 416.979248 -27.687338)
			(xy 416.936868 -27.644958) (xy 416.900381 -27.597408) (xy 416.870414 -27.545502) (xy 416.847478 -27.490129)
			(xy 416.831965 -27.432236) (xy 416.824142 -27.372814) (xy 416.823652 -27.342846) (xy 391.73912 -27.342846)
			(xy 391.73863 -27.372814) (xy 391.730807 -27.432236) (xy 391.715294 -27.490129) (xy 391.692358 -27.545502)
			(xy 391.662391 -27.597408) (xy 391.625904 -27.644958) (xy 391.583524 -27.687338) (xy 391.535974 -27.723825)
			(xy 391.484068 -27.753792) (xy 391.428695 -27.776728) (xy 391.370802 -27.792241) (xy 391.31138 -27.800064)
			(xy 391.251444 -27.800064) (xy 391.192022 -27.792241) (xy 391.134129 -27.776728) (xy 391.078756 -27.753792)
			(xy 391.02685 -27.723825) (xy 390.9793 -27.687338) (xy 390.93692 -27.644958) (xy 390.900433 -27.597408)
			(xy 390.870466 -27.545502) (xy 390.84753 -27.490129) (xy 390.832017 -27.432236) (xy 390.824194 -27.372814)
			(xy 390.823704 -27.342846) (xy 365.739172 -27.342846) (xy 365.738682 -27.372814) (xy 365.730859 -27.432236)
			(xy 365.715346 -27.490129) (xy 365.69241 -27.545502) (xy 365.662443 -27.597408) (xy 365.625956 -27.644958)
			(xy 365.583576 -27.687338) (xy 365.536026 -27.723825) (xy 365.48412 -27.753792) (xy 365.428747 -27.776728)
			(xy 365.370854 -27.792241) (xy 365.311432 -27.800064) (xy 365.251496 -27.800064) (xy 365.192074 -27.792241)
			(xy 365.134181 -27.776728) (xy 365.078808 -27.753792) (xy 365.026902 -27.723825) (xy 364.979352 -27.687338)
			(xy 364.936972 -27.644958) (xy 364.900485 -27.597408) (xy 364.870518 -27.545502) (xy 364.847582 -27.490129)
			(xy 364.832069 -27.432236) (xy 364.824246 -27.372814) (xy 364.823756 -27.342846) (xy 327.639172 -27.342846)
			(xy 327.638682 -27.37283) (xy 327.630854 -27.432286) (xy 327.615333 -27.490211) (xy 327.592384 -27.545615)
			(xy 327.5624 -27.597549) (xy 327.525894 -27.645125) (xy 327.483489 -27.68753) (xy 327.435913 -27.724036)
			(xy 327.383979 -27.75402) (xy 327.328575 -27.776969) (xy 327.27065 -27.79249) (xy 327.211194 -27.800318)
			(xy 327.151226 -27.800318) (xy 327.09177 -27.79249) (xy 327.033845 -27.776969) (xy 326.978441 -27.75402)
			(xy 326.926507 -27.724036) (xy 326.878931 -27.68753) (xy 326.836526 -27.645125) (xy 326.80002 -27.597549)
			(xy 326.770036 -27.545615) (xy 326.747087 -27.490211) (xy 326.731566 -27.432286) (xy 326.723738 -27.37283)
			(xy 326.723248 -27.342846) (xy 301.639224 -27.342846) (xy 301.638734 -27.37283) (xy 301.630906 -27.432286)
			(xy 301.615385 -27.490211) (xy 301.592436 -27.545615) (xy 301.562452 -27.597549) (xy 301.525946 -27.645125)
			(xy 301.483541 -27.68753) (xy 301.435965 -27.724036) (xy 301.384031 -27.75402) (xy 301.328627 -27.776969)
			(xy 301.270702 -27.79249) (xy 301.211246 -27.800318) (xy 301.151278 -27.800318) (xy 301.091822 -27.79249)
			(xy 301.033897 -27.776969) (xy 300.978493 -27.75402) (xy 300.926559 -27.724036) (xy 300.878983 -27.68753)
			(xy 300.836578 -27.645125) (xy 300.800072 -27.597549) (xy 300.770088 -27.545615) (xy 300.747139 -27.490211)
			(xy 300.731618 -27.432286) (xy 300.72379 -27.37283) (xy 300.7233 -27.342846) (xy 275.639276 -27.342846)
			(xy 275.638786 -27.37283) (xy 275.630958 -27.432286) (xy 275.615437 -27.490211) (xy 275.592488 -27.545615)
			(xy 275.562504 -27.597549) (xy 275.525998 -27.645125) (xy 275.483593 -27.68753) (xy 275.436017 -27.724036)
			(xy 275.384083 -27.75402) (xy 275.328679 -27.776969) (xy 275.270754 -27.79249) (xy 275.211298 -27.800318)
			(xy 275.15133 -27.800318) (xy 275.091874 -27.79249) (xy 275.033949 -27.776969) (xy 274.978545 -27.75402)
			(xy 274.926611 -27.724036) (xy 274.879035 -27.68753) (xy 274.83663 -27.645125) (xy 274.800124 -27.597549)
			(xy 274.77014 -27.545615) (xy 274.747191 -27.490211) (xy 274.73167 -27.432286) (xy 274.723842 -27.37283)
			(xy 274.723352 -27.342846) (xy 249.639328 -27.342846) (xy 249.638838 -27.37283) (xy 249.63101 -27.432286)
			(xy 249.615489 -27.490211) (xy 249.59254 -27.545615) (xy 249.562556 -27.597549) (xy 249.52605 -27.645125)
			(xy 249.483645 -27.68753) (xy 249.436069 -27.724036) (xy 249.384135 -27.75402) (xy 249.328731 -27.776969)
			(xy 249.270806 -27.79249) (xy 249.21135 -27.800318) (xy 249.151382 -27.800318) (xy 249.091926 -27.79249)
			(xy 249.034001 -27.776969) (xy 248.978597 -27.75402) (xy 248.926663 -27.724036) (xy 248.879087 -27.68753)
			(xy 248.836682 -27.645125) (xy 248.800176 -27.597549) (xy 248.770192 -27.545615) (xy 248.747243 -27.490211)
			(xy 248.731722 -27.432286) (xy 248.723894 -27.37283) (xy 248.723404 -27.342846) (xy 211.539328 -27.342846)
			(xy 211.538838 -27.37283) (xy 211.53101 -27.432286) (xy 211.515489 -27.490211) (xy 211.49254 -27.545615)
			(xy 211.462556 -27.597549) (xy 211.42605 -27.645125) (xy 211.383645 -27.68753) (xy 211.336069 -27.724036)
			(xy 211.284135 -27.75402) (xy 211.228731 -27.776969) (xy 211.170806 -27.79249) (xy 211.11135 -27.800318)
			(xy 211.051382 -27.800318) (xy 210.991926 -27.79249) (xy 210.934001 -27.776969) (xy 210.878597 -27.75402)
			(xy 210.826663 -27.724036) (xy 210.779087 -27.68753) (xy 210.736682 -27.645125) (xy 210.700176 -27.597549)
			(xy 210.670192 -27.545615) (xy 210.647243 -27.490211) (xy 210.631722 -27.432286) (xy 210.623894 -27.37283)
			(xy 210.623404 -27.342846) (xy 185.53938 -27.342846) (xy 185.53889 -27.37283) (xy 185.531062 -27.432286)
			(xy 185.515541 -27.490211) (xy 185.492592 -27.545615) (xy 185.462608 -27.597549) (xy 185.426102 -27.645125)
			(xy 185.383697 -27.68753) (xy 185.336121 -27.724036) (xy 185.284187 -27.75402) (xy 185.228783 -27.776969)
			(xy 185.170858 -27.79249) (xy 185.111402 -27.800318) (xy 185.051434 -27.800318) (xy 184.991978 -27.79249)
			(xy 184.934053 -27.776969) (xy 184.878649 -27.75402) (xy 184.826715 -27.724036) (xy 184.779139 -27.68753)
			(xy 184.736734 -27.645125) (xy 184.700228 -27.597549) (xy 184.670244 -27.545615) (xy 184.647295 -27.490211)
			(xy 184.631774 -27.432286) (xy 184.623946 -27.37283) (xy 184.623456 -27.342846) (xy 159.539432 -27.342846)
			(xy 159.538942 -27.37283) (xy 159.531114 -27.432286) (xy 159.515593 -27.490211) (xy 159.492644 -27.545615)
			(xy 159.46266 -27.597549) (xy 159.426154 -27.645125) (xy 159.383749 -27.68753) (xy 159.336173 -27.724036)
			(xy 159.284239 -27.75402) (xy 159.228835 -27.776969) (xy 159.17091 -27.79249) (xy 159.111454 -27.800318)
			(xy 159.051486 -27.800318) (xy 158.99203 -27.79249) (xy 158.934105 -27.776969) (xy 158.878701 -27.75402)
			(xy 158.826767 -27.724036) (xy 158.779191 -27.68753) (xy 158.736786 -27.645125) (xy 158.70028 -27.597549)
			(xy 158.670296 -27.545615) (xy 158.647347 -27.490211) (xy 158.631826 -27.432286) (xy 158.623998 -27.37283)
			(xy 158.623508 -27.342846) (xy 133.539484 -27.342846) (xy 133.538994 -27.37283) (xy 133.531166 -27.432286)
			(xy 133.515645 -27.490211) (xy 133.492696 -27.545615) (xy 133.462712 -27.597549) (xy 133.426206 -27.645125)
			(xy 133.383801 -27.68753) (xy 133.336225 -27.724036) (xy 133.284291 -27.75402) (xy 133.228887 -27.776969)
			(xy 133.170962 -27.79249) (xy 133.111506 -27.800318) (xy 133.051538 -27.800318) (xy 132.992082 -27.79249)
			(xy 132.934157 -27.776969) (xy 132.878753 -27.75402) (xy 132.826819 -27.724036) (xy 132.779243 -27.68753)
			(xy 132.736838 -27.645125) (xy 132.700332 -27.597549) (xy 132.670348 -27.545615) (xy 132.647399 -27.490211)
			(xy 132.631878 -27.432286) (xy 132.62405 -27.37283) (xy 132.62356 -27.342846) (xy 95.438976 -27.342846)
			(xy 95.438486 -27.372814) (xy 95.430663 -27.432236) (xy 95.41515 -27.490129) (xy 95.392214 -27.545502)
			(xy 95.362247 -27.597408) (xy 95.32576 -27.644958) (xy 95.28338 -27.687338) (xy 95.23583 -27.723825)
			(xy 95.183924 -27.753792) (xy 95.128551 -27.776728) (xy 95.070658 -27.792241) (xy 95.011236 -27.800064)
			(xy 94.9513 -27.800064) (xy 94.891878 -27.792241) (xy 94.833985 -27.776728) (xy 94.778612 -27.753792)
			(xy 94.726706 -27.723825) (xy 94.679156 -27.687338) (xy 94.636776 -27.644958) (xy 94.600289 -27.597408)
			(xy 94.570322 -27.545502) (xy 94.547386 -27.490129) (xy 94.531873 -27.432236) (xy 94.52405 -27.372814)
			(xy 94.52356 -27.342846) (xy 69.439028 -27.342846) (xy 69.438538 -27.372814) (xy 69.430715 -27.432236)
			(xy 69.415202 -27.490129) (xy 69.392266 -27.545502) (xy 69.362299 -27.597408) (xy 69.325812 -27.644958)
			(xy 69.283432 -27.687338) (xy 69.235882 -27.723825) (xy 69.183976 -27.753792) (xy 69.128603 -27.776728)
			(xy 69.07071 -27.792241) (xy 69.011288 -27.800064) (xy 68.951352 -27.800064) (xy 68.89193 -27.792241)
			(xy 68.834037 -27.776728) (xy 68.778664 -27.753792) (xy 68.726758 -27.723825) (xy 68.679208 -27.687338)
			(xy 68.636828 -27.644958) (xy 68.600341 -27.597408) (xy 68.570374 -27.545502) (xy 68.547438 -27.490129)
			(xy 68.531925 -27.432236) (xy 68.524102 -27.372814) (xy 68.523612 -27.342846) (xy 43.43908 -27.342846)
			(xy 43.43859 -27.372814) (xy 43.430767 -27.432236) (xy 43.415254 -27.490129) (xy 43.392318 -27.545502)
			(xy 43.362351 -27.597408) (xy 43.325864 -27.644958) (xy 43.283484 -27.687338) (xy 43.235934 -27.723825)
			(xy 43.184028 -27.753792) (xy 43.128655 -27.776728) (xy 43.070762 -27.792241) (xy 43.01134 -27.800064)
			(xy 42.951404 -27.800064) (xy 42.891982 -27.792241) (xy 42.834089 -27.776728) (xy 42.778716 -27.753792)
			(xy 42.72681 -27.723825) (xy 42.67926 -27.687338) (xy 42.63688 -27.644958) (xy 42.600393 -27.597408)
			(xy 42.570426 -27.545502) (xy 42.54749 -27.490129) (xy 42.531977 -27.432236) (xy 42.524154 -27.372814)
			(xy 42.523664 -27.342846) (xy 17.439132 -27.342846) (xy 17.438642 -27.372814) (xy 17.430819 -27.432236)
			(xy 17.415306 -27.490129) (xy 17.39237 -27.545502) (xy 17.362403 -27.597408) (xy 17.325916 -27.644958)
			(xy 17.283536 -27.687338) (xy 17.235986 -27.723825) (xy 17.18408 -27.753792) (xy 17.128707 -27.776728)
			(xy 17.070814 -27.792241) (xy 17.011392 -27.800064) (xy 16.951456 -27.800064) (xy 16.892034 -27.792241)
			(xy 16.834141 -27.776728) (xy 16.778768 -27.753792) (xy 16.726862 -27.723825) (xy 16.679312 -27.687338)
			(xy 16.636932 -27.644958) (xy 16.600445 -27.597408) (xy 16.570478 -27.545502) (xy 16.547542 -27.490129)
			(xy 16.532029 -27.432236) (xy 16.524206 -27.372814) (xy 16.523716 -27.342846) (xy 0.509016 -27.342846)
			(xy 0.509016 -29.12237) (xy 8.607044 -29.12237) (xy 8.607044 -28.25877) (xy 8.607534 -28.228802)
			(xy 8.615357 -28.16938) (xy 8.63087 -28.111487) (xy 8.653806 -28.056114) (xy 8.683773 -28.004208)
			(xy 8.72026 -27.956658) (xy 8.76264 -27.914278) (xy 8.81019 -27.877791) (xy 8.862096 -27.847824)
			(xy 8.917469 -27.824888) (xy 8.975362 -27.809375) (xy 9.034784 -27.801552) (xy 9.09472 -27.801552)
			(xy 9.154142 -27.809375) (xy 9.212035 -27.824888) (xy 9.267408 -27.847824) (xy 9.319314 -27.877791)
			(xy 9.366864 -27.914278) (xy 9.409244 -27.956658) (xy 9.445731 -28.004208) (xy 9.475698 -28.056114)
			(xy 9.498634 -28.111487) (xy 9.514147 -28.16938) (xy 9.52197 -28.228802) (xy 9.52246 -28.25877) (xy 9.52246 -29.114242)
			(xy 18.847308 -29.114242) (xy 18.847308 -28.250642) (xy 18.847798 -28.220658) (xy 18.855626 -28.161202)
			(xy 18.871147 -28.103277) (xy 18.894096 -28.047873) (xy 18.92408 -27.995939) (xy 18.960586 -27.948363)
			(xy 19.002991 -27.905958) (xy 19.050567 -27.869452) (xy 19.102501 -27.839468) (xy 19.157905 -27.816519)
			(xy 19.21583 -27.800998) (xy 19.275286 -27.79317) (xy 19.335254 -27.79317) (xy 19.39471 -27.800998)
			(xy 19.452635 -27.816519) (xy 19.508039 -27.839468) (xy 19.559973 -27.869452) (xy 19.607549 -27.905958)
			(xy 19.649954 -27.948363) (xy 19.68646 -27.995939) (xy 19.716444 -28.047873) (xy 19.739393 -28.103277)
			(xy 19.754914 -28.161202) (xy 19.762742 -28.220658) (xy 19.763232 -28.250642) (xy 19.763232 -29.114242)
			(xy 19.763099 -29.12237) (xy 34.606992 -29.12237) (xy 34.606992 -28.25877) (xy 34.607482 -28.228802)
			(xy 34.615305 -28.16938) (xy 34.630818 -28.111487) (xy 34.653754 -28.056114) (xy 34.683721 -28.004208)
			(xy 34.720208 -27.956658) (xy 34.762588 -27.914278) (xy 34.810138 -27.877791) (xy 34.862044 -27.847824)
			(xy 34.917417 -27.824888) (xy 34.97531 -27.809375) (xy 35.034732 -27.801552) (xy 35.094668 -27.801552)
			(xy 35.15409 -27.809375) (xy 35.211983 -27.824888) (xy 35.267356 -27.847824) (xy 35.319262 -27.877791)
			(xy 35.366812 -27.914278) (xy 35.409192 -27.956658) (xy 35.445679 -28.004208) (xy 35.475646 -28.056114)
			(xy 35.498582 -28.111487) (xy 35.514095 -28.16938) (xy 35.521918 -28.228802) (xy 35.522408 -28.25877)
			(xy 35.522408 -29.114242) (xy 44.847256 -29.114242) (xy 44.847256 -28.250642) (xy 44.847746 -28.220658)
			(xy 44.855574 -28.161202) (xy 44.871095 -28.103277) (xy 44.894044 -28.047873) (xy 44.924028 -27.995939)
			(xy 44.960534 -27.948363) (xy 45.002939 -27.905958) (xy 45.050515 -27.869452) (xy 45.102449 -27.839468)
			(xy 45.157853 -27.816519) (xy 45.215778 -27.800998) (xy 45.275234 -27.79317) (xy 45.335202 -27.79317)
			(xy 45.394658 -27.800998) (xy 45.452583 -27.816519) (xy 45.507987 -27.839468) (xy 45.559921 -27.869452)
			(xy 45.607497 -27.905958) (xy 45.649902 -27.948363) (xy 45.686408 -27.995939) (xy 45.716392 -28.047873)
			(xy 45.739341 -28.103277) (xy 45.754862 -28.161202) (xy 45.76269 -28.220658) (xy 45.76318 -28.250642)
			(xy 45.76318 -29.114242) (xy 45.763047 -29.12237) (xy 60.60694 -29.12237) (xy 60.60694 -28.25877)
			(xy 60.60743 -28.228802) (xy 60.615253 -28.16938) (xy 60.630766 -28.111487) (xy 60.653702 -28.056114)
			(xy 60.683669 -28.004208) (xy 60.720156 -27.956658) (xy 60.762536 -27.914278) (xy 60.810086 -27.877791)
			(xy 60.861992 -27.847824) (xy 60.917365 -27.824888) (xy 60.975258 -27.809375) (xy 61.03468 -27.801552)
			(xy 61.094616 -27.801552) (xy 61.154038 -27.809375) (xy 61.211931 -27.824888) (xy 61.267304 -27.847824)
			(xy 61.31921 -27.877791) (xy 61.36676 -27.914278) (xy 61.40914 -27.956658) (xy 61.445627 -28.004208)
			(xy 61.475594 -28.056114) (xy 61.49853 -28.111487) (xy 61.514043 -28.16938) (xy 61.521866 -28.228802)
			(xy 61.522356 -28.25877) (xy 61.522356 -29.114242) (xy 70.847204 -29.114242) (xy 70.847204 -28.250642)
			(xy 70.847694 -28.220658) (xy 70.855522 -28.161202) (xy 70.871043 -28.103277) (xy 70.893992 -28.047873)
			(xy 70.923976 -27.995939) (xy 70.960482 -27.948363) (xy 71.002887 -27.905958) (xy 71.050463 -27.869452)
			(xy 71.102397 -27.839468) (xy 71.157801 -27.816519) (xy 71.215726 -27.800998) (xy 71.275182 -27.79317)
			(xy 71.33515 -27.79317) (xy 71.394606 -27.800998) (xy 71.452531 -27.816519) (xy 71.507935 -27.839468)
			(xy 71.559869 -27.869452) (xy 71.607445 -27.905958) (xy 71.64985 -27.948363) (xy 71.686356 -27.995939)
			(xy 71.71634 -28.047873) (xy 71.739289 -28.103277) (xy 71.75481 -28.161202) (xy 71.762638 -28.220658)
			(xy 71.763128 -28.250642) (xy 71.763128 -29.114242) (xy 71.762995 -29.12237) (xy 86.606888 -29.12237)
			(xy 86.606888 -28.25877) (xy 86.607378 -28.228802) (xy 86.615201 -28.16938) (xy 86.630714 -28.111487)
			(xy 86.65365 -28.056114) (xy 86.683617 -28.004208) (xy 86.720104 -27.956658) (xy 86.762484 -27.914278)
			(xy 86.810034 -27.877791) (xy 86.86194 -27.847824) (xy 86.917313 -27.824888) (xy 86.975206 -27.809375)
			(xy 87.034628 -27.801552) (xy 87.094564 -27.801552) (xy 87.153986 -27.809375) (xy 87.211879 -27.824888)
			(xy 87.267252 -27.847824) (xy 87.319158 -27.877791) (xy 87.366708 -27.914278) (xy 87.409088 -27.956658)
			(xy 87.445575 -28.004208) (xy 87.475542 -28.056114) (xy 87.498478 -28.111487) (xy 87.513991 -28.16938)
			(xy 87.521814 -28.228802) (xy 87.522304 -28.25877) (xy 87.522304 -29.114242) (xy 96.847152 -29.114242)
			(xy 96.847152 -28.250642) (xy 96.847642 -28.220658) (xy 96.85547 -28.161202) (xy 96.870991 -28.103277)
			(xy 96.89394 -28.047873) (xy 96.923924 -27.995939) (xy 96.96043 -27.948363) (xy 97.002835 -27.905958)
			(xy 97.050411 -27.869452) (xy 97.102345 -27.839468) (xy 97.157749 -27.816519) (xy 97.215674 -27.800998)
			(xy 97.27513 -27.79317) (xy 97.335098 -27.79317) (xy 97.394554 -27.800998) (xy 97.452479 -27.816519)
			(xy 97.507883 -27.839468) (xy 97.559817 -27.869452) (xy 97.607393 -27.905958) (xy 97.649798 -27.948363)
			(xy 97.686304 -27.995939) (xy 97.716288 -28.047873) (xy 97.739237 -28.103277) (xy 97.754758 -28.161202)
			(xy 97.762586 -28.220658) (xy 97.763076 -28.250642) (xy 97.763076 -29.114242) (xy 97.762943 -29.12237)
			(xy 124.706888 -29.12237) (xy 124.706888 -28.25877) (xy 124.707378 -28.228786) (xy 124.715206 -28.16933)
			(xy 124.730727 -28.111405) (xy 124.753676 -28.056001) (xy 124.78366 -28.004067) (xy 124.820166 -27.956491)
			(xy 124.862571 -27.914086) (xy 124.910147 -27.87758) (xy 124.962081 -27.847596) (xy 125.017485 -27.824647)
			(xy 125.07541 -27.809126) (xy 125.134866 -27.801298) (xy 125.194834 -27.801298) (xy 125.25429 -27.809126)
			(xy 125.312215 -27.824647) (xy 125.367619 -27.847596) (xy 125.419553 -27.87758) (xy 125.467129 -27.914086)
			(xy 125.509534 -27.956491) (xy 125.54604 -28.004067) (xy 125.576024 -28.056001) (xy 125.598973 -28.111405)
			(xy 125.614494 -28.16933) (xy 125.622322 -28.228786) (xy 125.622812 -28.25877) (xy 125.622812 -29.114242)
			(xy 134.94766 -29.114242) (xy 134.94766 -28.250642) (xy 134.94815 -28.220674) (xy 134.955973 -28.161252)
			(xy 134.971486 -28.103359) (xy 134.994422 -28.047986) (xy 135.024389 -27.99608) (xy 135.060876 -27.94853)
			(xy 135.103256 -27.90615) (xy 135.150806 -27.869663) (xy 135.202712 -27.839696) (xy 135.258085 -27.81676)
			(xy 135.315978 -27.801247) (xy 135.3754 -27.793424) (xy 135.435336 -27.793424) (xy 135.494758 -27.801247)
			(xy 135.552651 -27.81676) (xy 135.608024 -27.839696) (xy 135.65993 -27.869663) (xy 135.70748 -27.90615)
			(xy 135.74986 -27.94853) (xy 135.786347 -27.99608) (xy 135.816314 -28.047986) (xy 135.83925 -28.103359)
			(xy 135.854763 -28.161252) (xy 135.862586 -28.220674) (xy 135.863076 -28.250642) (xy 135.863076 -29.114242)
			(xy 135.862943 -29.12237) (xy 150.706836 -29.12237) (xy 150.706836 -28.25877) (xy 150.707326 -28.228786)
			(xy 150.715154 -28.16933) (xy 150.730675 -28.111405) (xy 150.753624 -28.056001) (xy 150.783608 -28.004067)
			(xy 150.820114 -27.956491) (xy 150.862519 -27.914086) (xy 150.910095 -27.87758) (xy 150.962029 -27.847596)
			(xy 151.017433 -27.824647) (xy 151.075358 -27.809126) (xy 151.134814 -27.801298) (xy 151.194782 -27.801298)
			(xy 151.254238 -27.809126) (xy 151.312163 -27.824647) (xy 151.367567 -27.847596) (xy 151.419501 -27.87758)
			(xy 151.467077 -27.914086) (xy 151.509482 -27.956491) (xy 151.545988 -28.004067) (xy 151.575972 -28.056001)
			(xy 151.598921 -28.111405) (xy 151.614442 -28.16933) (xy 151.62227 -28.228786) (xy 151.62276 -28.25877)
			(xy 151.62276 -29.114242) (xy 160.947608 -29.114242) (xy 160.947608 -28.250642) (xy 160.948098 -28.220674)
			(xy 160.955921 -28.161252) (xy 160.971434 -28.103359) (xy 160.99437 -28.047986) (xy 161.024337 -27.99608)
			(xy 161.060824 -27.94853) (xy 161.103204 -27.90615) (xy 161.150754 -27.869663) (xy 161.20266 -27.839696)
			(xy 161.258033 -27.81676) (xy 161.315926 -27.801247) (xy 161.375348 -27.793424) (xy 161.435284 -27.793424)
			(xy 161.494706 -27.801247) (xy 161.552599 -27.81676) (xy 161.607972 -27.839696) (xy 161.659878 -27.869663)
			(xy 161.707428 -27.90615) (xy 161.749808 -27.94853) (xy 161.786295 -27.99608) (xy 161.816262 -28.047986)
			(xy 161.839198 -28.103359) (xy 161.854711 -28.161252) (xy 161.862534 -28.220674) (xy 161.863024 -28.250642)
			(xy 161.863024 -29.114242) (xy 161.862891 -29.12237) (xy 176.706784 -29.12237) (xy 176.706784 -28.25877)
			(xy 176.707274 -28.228786) (xy 176.715102 -28.16933) (xy 176.730623 -28.111405) (xy 176.753572 -28.056001)
			(xy 176.783556 -28.004067) (xy 176.820062 -27.956491) (xy 176.862467 -27.914086) (xy 176.910043 -27.87758)
			(xy 176.961977 -27.847596) (xy 177.017381 -27.824647) (xy 177.075306 -27.809126) (xy 177.134762 -27.801298)
			(xy 177.19473 -27.801298) (xy 177.254186 -27.809126) (xy 177.312111 -27.824647) (xy 177.367515 -27.847596)
			(xy 177.419449 -27.87758) (xy 177.467025 -27.914086) (xy 177.50943 -27.956491) (xy 177.545936 -28.004067)
			(xy 177.57592 -28.056001) (xy 177.598869 -28.111405) (xy 177.61439 -28.16933) (xy 177.622218 -28.228786)
			(xy 177.622708 -28.25877) (xy 177.622708 -29.114242) (xy 186.947556 -29.114242) (xy 186.947556 -28.250642)
			(xy 186.948046 -28.220674) (xy 186.955869 -28.161252) (xy 186.971382 -28.103359) (xy 186.994318 -28.047986)
			(xy 187.024285 -27.99608) (xy 187.060772 -27.94853) (xy 187.103152 -27.90615) (xy 187.150702 -27.869663)
			(xy 187.202608 -27.839696) (xy 187.257981 -27.81676) (xy 187.315874 -27.801247) (xy 187.375296 -27.793424)
			(xy 187.435232 -27.793424) (xy 187.494654 -27.801247) (xy 187.552547 -27.81676) (xy 187.60792 -27.839696)
			(xy 187.659826 -27.869663) (xy 187.707376 -27.90615) (xy 187.749756 -27.94853) (xy 187.786243 -27.99608)
			(xy 187.81621 -28.047986) (xy 187.839146 -28.103359) (xy 187.854659 -28.161252) (xy 187.862482 -28.220674)
			(xy 187.862972 -28.250642) (xy 187.862972 -29.114242) (xy 187.862839 -29.12237) (xy 202.706732 -29.12237)
			(xy 202.706732 -28.25877) (xy 202.707222 -28.228786) (xy 202.71505 -28.16933) (xy 202.730571 -28.111405)
			(xy 202.75352 -28.056001) (xy 202.783504 -28.004067) (xy 202.82001 -27.956491) (xy 202.862415 -27.914086)
			(xy 202.909991 -27.87758) (xy 202.961925 -27.847596) (xy 203.017329 -27.824647) (xy 203.075254 -27.809126)
			(xy 203.13471 -27.801298) (xy 203.194678 -27.801298) (xy 203.254134 -27.809126) (xy 203.312059 -27.824647)
			(xy 203.367463 -27.847596) (xy 203.419397 -27.87758) (xy 203.466973 -27.914086) (xy 203.509378 -27.956491)
			(xy 203.545884 -28.004067) (xy 203.575868 -28.056001) (xy 203.598817 -28.111405) (xy 203.614338 -28.16933)
			(xy 203.622166 -28.228786) (xy 203.622656 -28.25877) (xy 203.622656 -29.114242) (xy 212.947504 -29.114242)
			(xy 212.947504 -28.250642) (xy 212.947994 -28.220674) (xy 212.955817 -28.161252) (xy 212.97133 -28.103359)
			(xy 212.994266 -28.047986) (xy 213.024233 -27.99608) (xy 213.06072 -27.94853) (xy 213.1031 -27.90615)
			(xy 213.15065 -27.869663) (xy 213.202556 -27.839696) (xy 213.257929 -27.81676) (xy 213.315822 -27.801247)
			(xy 213.375244 -27.793424) (xy 213.43518 -27.793424) (xy 213.494602 -27.801247) (xy 213.552495 -27.81676)
			(xy 213.607868 -27.839696) (xy 213.659774 -27.869663) (xy 213.707324 -27.90615) (xy 213.749704 -27.94853)
			(xy 213.786191 -27.99608) (xy 213.816158 -28.047986) (xy 213.839094 -28.103359) (xy 213.854607 -28.161252)
			(xy 213.86243 -28.220674) (xy 213.86292 -28.250642) (xy 213.86292 -29.114242) (xy 213.862787 -29.12237)
			(xy 240.806732 -29.12237) (xy 240.806732 -28.25877) (xy 240.807222 -28.228786) (xy 240.81505 -28.16933)
			(xy 240.830571 -28.111405) (xy 240.85352 -28.056001) (xy 240.883504 -28.004067) (xy 240.92001 -27.956491)
			(xy 240.962415 -27.914086) (xy 241.009991 -27.87758) (xy 241.061925 -27.847596) (xy 241.117329 -27.824647)
			(xy 241.175254 -27.809126) (xy 241.23471 -27.801298) (xy 241.294678 -27.801298) (xy 241.354134 -27.809126)
			(xy 241.412059 -27.824647) (xy 241.467463 -27.847596) (xy 241.519397 -27.87758) (xy 241.566973 -27.914086)
			(xy 241.609378 -27.956491) (xy 241.645884 -28.004067) (xy 241.675868 -28.056001) (xy 241.698817 -28.111405)
			(xy 241.714338 -28.16933) (xy 241.722166 -28.228786) (xy 241.722656 -28.25877) (xy 241.722656 -29.114242)
			(xy 251.047504 -29.114242) (xy 251.047504 -28.250642) (xy 251.047994 -28.220674) (xy 251.055817 -28.161252)
			(xy 251.07133 -28.103359) (xy 251.094266 -28.047986) (xy 251.124233 -27.99608) (xy 251.16072 -27.94853)
			(xy 251.2031 -27.90615) (xy 251.25065 -27.869663) (xy 251.302556 -27.839696) (xy 251.357929 -27.81676)
			(xy 251.415822 -27.801247) (xy 251.475244 -27.793424) (xy 251.53518 -27.793424) (xy 251.594602 -27.801247)
			(xy 251.652495 -27.81676) (xy 251.707868 -27.839696) (xy 251.759774 -27.869663) (xy 251.807324 -27.90615)
			(xy 251.849704 -27.94853) (xy 251.886191 -27.99608) (xy 251.916158 -28.047986) (xy 251.939094 -28.103359)
			(xy 251.954607 -28.161252) (xy 251.96243 -28.220674) (xy 251.96292 -28.250642) (xy 251.96292 -29.114242)
			(xy 251.962787 -29.12237) (xy 266.80668 -29.12237) (xy 266.80668 -28.25877) (xy 266.80717 -28.228786)
			(xy 266.814998 -28.16933) (xy 266.830519 -28.111405) (xy 266.853468 -28.056001) (xy 266.883452 -28.004067)
			(xy 266.919958 -27.956491) (xy 266.962363 -27.914086) (xy 267.009939 -27.87758) (xy 267.061873 -27.847596)
			(xy 267.117277 -27.824647) (xy 267.175202 -27.809126) (xy 267.234658 -27.801298) (xy 267.294626 -27.801298)
			(xy 267.354082 -27.809126) (xy 267.412007 -27.824647) (xy 267.467411 -27.847596) (xy 267.519345 -27.87758)
			(xy 267.566921 -27.914086) (xy 267.609326 -27.956491) (xy 267.645832 -28.004067) (xy 267.675816 -28.056001)
			(xy 267.698765 -28.111405) (xy 267.714286 -28.16933) (xy 267.722114 -28.228786) (xy 267.722604 -28.25877)
			(xy 267.722604 -29.114242) (xy 277.047452 -29.114242) (xy 277.047452 -28.250642) (xy 277.047942 -28.220674)
			(xy 277.055765 -28.161252) (xy 277.071278 -28.103359) (xy 277.094214 -28.047986) (xy 277.124181 -27.99608)
			(xy 277.160668 -27.94853) (xy 277.203048 -27.90615) (xy 277.250598 -27.869663) (xy 277.302504 -27.839696)
			(xy 277.357877 -27.81676) (xy 277.41577 -27.801247) (xy 277.475192 -27.793424) (xy 277.535128 -27.793424)
			(xy 277.59455 -27.801247) (xy 277.652443 -27.81676) (xy 277.707816 -27.839696) (xy 277.759722 -27.869663)
			(xy 277.807272 -27.90615) (xy 277.849652 -27.94853) (xy 277.886139 -27.99608) (xy 277.916106 -28.047986)
			(xy 277.939042 -28.103359) (xy 277.954555 -28.161252) (xy 277.962378 -28.220674) (xy 277.962868 -28.250642)
			(xy 277.962868 -29.114242) (xy 277.962735 -29.12237) (xy 292.806628 -29.12237) (xy 292.806628 -28.25877)
			(xy 292.807118 -28.228786) (xy 292.814946 -28.16933) (xy 292.830467 -28.111405) (xy 292.853416 -28.056001)
			(xy 292.8834 -28.004067) (xy 292.919906 -27.956491) (xy 292.962311 -27.914086) (xy 293.009887 -27.87758)
			(xy 293.061821 -27.847596) (xy 293.117225 -27.824647) (xy 293.17515 -27.809126) (xy 293.234606 -27.801298)
			(xy 293.294574 -27.801298) (xy 293.35403 -27.809126) (xy 293.411955 -27.824647) (xy 293.467359 -27.847596)
			(xy 293.519293 -27.87758) (xy 293.566869 -27.914086) (xy 293.609274 -27.956491) (xy 293.64578 -28.004067)
			(xy 293.675764 -28.056001) (xy 293.698713 -28.111405) (xy 293.714234 -28.16933) (xy 293.722062 -28.228786)
			(xy 293.722552 -28.25877) (xy 293.722552 -29.114242) (xy 303.0474 -29.114242) (xy 303.0474 -28.250642)
			(xy 303.04789 -28.220674) (xy 303.055713 -28.161252) (xy 303.071226 -28.103359) (xy 303.094162 -28.047986)
			(xy 303.124129 -27.99608) (xy 303.160616 -27.94853) (xy 303.202996 -27.90615) (xy 303.250546 -27.869663)
			(xy 303.302452 -27.839696) (xy 303.357825 -27.81676) (xy 303.415718 -27.801247) (xy 303.47514 -27.793424)
			(xy 303.535076 -27.793424) (xy 303.594498 -27.801247) (xy 303.652391 -27.81676) (xy 303.707764 -27.839696)
			(xy 303.75967 -27.869663) (xy 303.80722 -27.90615) (xy 303.8496 -27.94853) (xy 303.886087 -27.99608)
			(xy 303.916054 -28.047986) (xy 303.93899 -28.103359) (xy 303.954503 -28.161252) (xy 303.962326 -28.220674)
			(xy 303.962816 -28.250642) (xy 303.962816 -29.114242) (xy 303.962683 -29.12237) (xy 318.806576 -29.12237)
			(xy 318.806576 -28.25877) (xy 318.807066 -28.228786) (xy 318.814894 -28.16933) (xy 318.830415 -28.111405)
			(xy 318.853364 -28.056001) (xy 318.883348 -28.004067) (xy 318.919854 -27.956491) (xy 318.962259 -27.914086)
			(xy 319.009835 -27.87758) (xy 319.061769 -27.847596) (xy 319.117173 -27.824647) (xy 319.175098 -27.809126)
			(xy 319.234554 -27.801298) (xy 319.294522 -27.801298) (xy 319.353978 -27.809126) (xy 319.411903 -27.824647)
			(xy 319.467307 -27.847596) (xy 319.519241 -27.87758) (xy 319.566817 -27.914086) (xy 319.609222 -27.956491)
			(xy 319.645728 -28.004067) (xy 319.675712 -28.056001) (xy 319.698661 -28.111405) (xy 319.714182 -28.16933)
			(xy 319.72201 -28.228786) (xy 319.7225 -28.25877) (xy 319.7225 -29.114242) (xy 329.047348 -29.114242)
			(xy 329.047348 -28.250642) (xy 329.047838 -28.220674) (xy 329.055661 -28.161252) (xy 329.071174 -28.103359)
			(xy 329.09411 -28.047986) (xy 329.124077 -27.99608) (xy 329.160564 -27.94853) (xy 329.202944 -27.90615)
			(xy 329.250494 -27.869663) (xy 329.3024 -27.839696) (xy 329.357773 -27.81676) (xy 329.415666 -27.801247)
			(xy 329.475088 -27.793424) (xy 329.535024 -27.793424) (xy 329.594446 -27.801247) (xy 329.652339 -27.81676)
			(xy 329.707712 -27.839696) (xy 329.759618 -27.869663) (xy 329.807168 -27.90615) (xy 329.849548 -27.94853)
			(xy 329.886035 -27.99608) (xy 329.916002 -28.047986) (xy 329.938938 -28.103359) (xy 329.954451 -28.161252)
			(xy 329.962274 -28.220674) (xy 329.962764 -28.250642) (xy 329.962764 -29.114242) (xy 329.962631 -29.12237)
			(xy 356.907084 -29.12237) (xy 356.907084 -28.25877) (xy 356.907574 -28.228802) (xy 356.915397 -28.16938)
			(xy 356.93091 -28.111487) (xy 356.953846 -28.056114) (xy 356.983813 -28.004208) (xy 357.0203 -27.956658)
			(xy 357.06268 -27.914278) (xy 357.11023 -27.877791) (xy 357.162136 -27.847824) (xy 357.217509 -27.824888)
			(xy 357.275402 -27.809375) (xy 357.334824 -27.801552) (xy 357.39476 -27.801552) (xy 357.454182 -27.809375)
			(xy 357.512075 -27.824888) (xy 357.567448 -27.847824) (xy 357.619354 -27.877791) (xy 357.666904 -27.914278)
			(xy 357.709284 -27.956658) (xy 357.745771 -28.004208) (xy 357.775738 -28.056114) (xy 357.798674 -28.111487)
			(xy 357.814187 -28.16938) (xy 357.82201 -28.228802) (xy 357.8225 -28.25877) (xy 357.8225 -29.114242)
			(xy 367.147348 -29.114242) (xy 367.147348 -28.250642) (xy 367.147838 -28.220658) (xy 367.155666 -28.161202)
			(xy 367.171187 -28.103277) (xy 367.194136 -28.047873) (xy 367.22412 -27.995939) (xy 367.260626 -27.948363)
			(xy 367.303031 -27.905958) (xy 367.350607 -27.869452) (xy 367.402541 -27.839468) (xy 367.457945 -27.816519)
			(xy 367.51587 -27.800998) (xy 367.575326 -27.79317) (xy 367.635294 -27.79317) (xy 367.69475 -27.800998)
			(xy 367.752675 -27.816519) (xy 367.808079 -27.839468) (xy 367.860013 -27.869452) (xy 367.907589 -27.905958)
			(xy 367.949994 -27.948363) (xy 367.9865 -27.995939) (xy 368.016484 -28.047873) (xy 368.039433 -28.103277)
			(xy 368.054954 -28.161202) (xy 368.062782 -28.220658) (xy 368.063272 -28.250642) (xy 368.063272 -29.114242)
			(xy 368.063139 -29.12237) (xy 382.907032 -29.12237) (xy 382.907032 -28.25877) (xy 382.907522 -28.228802)
			(xy 382.915345 -28.16938) (xy 382.930858 -28.111487) (xy 382.953794 -28.056114) (xy 382.983761 -28.004208)
			(xy 383.020248 -27.956658) (xy 383.062628 -27.914278) (xy 383.110178 -27.877791) (xy 383.162084 -27.847824)
			(xy 383.217457 -27.824888) (xy 383.27535 -27.809375) (xy 383.334772 -27.801552) (xy 383.394708 -27.801552)
			(xy 383.45413 -27.809375) (xy 383.512023 -27.824888) (xy 383.567396 -27.847824) (xy 383.619302 -27.877791)
			(xy 383.666852 -27.914278) (xy 383.709232 -27.956658) (xy 383.745719 -28.004208) (xy 383.775686 -28.056114)
			(xy 383.798622 -28.111487) (xy 383.814135 -28.16938) (xy 383.821958 -28.228802) (xy 383.822448 -28.25877)
			(xy 383.822448 -29.114242) (xy 393.147296 -29.114242) (xy 393.147296 -28.250642) (xy 393.147786 -28.220658)
			(xy 393.155614 -28.161202) (xy 393.171135 -28.103277) (xy 393.194084 -28.047873) (xy 393.224068 -27.995939)
			(xy 393.260574 -27.948363) (xy 393.302979 -27.905958) (xy 393.350555 -27.869452) (xy 393.402489 -27.839468)
			(xy 393.457893 -27.816519) (xy 393.515818 -27.800998) (xy 393.575274 -27.79317) (xy 393.635242 -27.79317)
			(xy 393.694698 -27.800998) (xy 393.752623 -27.816519) (xy 393.808027 -27.839468) (xy 393.859961 -27.869452)
			(xy 393.907537 -27.905958) (xy 393.949942 -27.948363) (xy 393.986448 -27.995939) (xy 394.016432 -28.047873)
			(xy 394.039381 -28.103277) (xy 394.054902 -28.161202) (xy 394.06273 -28.220658) (xy 394.06322 -28.250642)
			(xy 394.06322 -29.114242) (xy 394.063087 -29.12237) (xy 408.90698 -29.12237) (xy 408.90698 -28.25877)
			(xy 408.90747 -28.228802) (xy 408.915293 -28.16938) (xy 408.930806 -28.111487) (xy 408.953742 -28.056114)
			(xy 408.983709 -28.004208) (xy 409.020196 -27.956658) (xy 409.062576 -27.914278) (xy 409.110126 -27.877791)
			(xy 409.162032 -27.847824) (xy 409.217405 -27.824888) (xy 409.275298 -27.809375) (xy 409.33472 -27.801552)
			(xy 409.394656 -27.801552) (xy 409.454078 -27.809375) (xy 409.511971 -27.824888) (xy 409.567344 -27.847824)
			(xy 409.61925 -27.877791) (xy 409.6668 -27.914278) (xy 409.70918 -27.956658) (xy 409.745667 -28.004208)
			(xy 409.775634 -28.056114) (xy 409.79857 -28.111487) (xy 409.814083 -28.16938) (xy 409.821906 -28.228802)
			(xy 409.822396 -28.25877) (xy 409.822396 -29.114242) (xy 419.147244 -29.114242) (xy 419.147244 -28.250642)
			(xy 419.147734 -28.220658) (xy 419.155562 -28.161202) (xy 419.171083 -28.103277) (xy 419.194032 -28.047873)
			(xy 419.224016 -27.995939) (xy 419.260522 -27.948363) (xy 419.302927 -27.905958) (xy 419.350503 -27.869452)
			(xy 419.402437 -27.839468) (xy 419.457841 -27.816519) (xy 419.515766 -27.800998) (xy 419.575222 -27.79317)
			(xy 419.63519 -27.79317) (xy 419.694646 -27.800998) (xy 419.752571 -27.816519) (xy 419.807975 -27.839468)
			(xy 419.859909 -27.869452) (xy 419.907485 -27.905958) (xy 419.94989 -27.948363) (xy 419.986396 -27.995939)
			(xy 420.01638 -28.047873) (xy 420.039329 -28.103277) (xy 420.05485 -28.161202) (xy 420.062678 -28.220658)
			(xy 420.063168 -28.250642) (xy 420.063168 -29.114242) (xy 420.063035 -29.12237) (xy 434.906928 -29.12237)
			(xy 434.906928 -28.25877) (xy 434.907418 -28.228802) (xy 434.915241 -28.16938) (xy 434.930754 -28.111487)
			(xy 434.95369 -28.056114) (xy 434.983657 -28.004208) (xy 435.020144 -27.956658) (xy 435.062524 -27.914278)
			(xy 435.110074 -27.877791) (xy 435.16198 -27.847824) (xy 435.217353 -27.824888) (xy 435.275246 -27.809375)
			(xy 435.334668 -27.801552) (xy 435.394604 -27.801552) (xy 435.454026 -27.809375) (xy 435.511919 -27.824888)
			(xy 435.567292 -27.847824) (xy 435.619198 -27.877791) (xy 435.666748 -27.914278) (xy 435.709128 -27.956658)
			(xy 435.745615 -28.004208) (xy 435.775582 -28.056114) (xy 435.798518 -28.111487) (xy 435.814031 -28.16938)
			(xy 435.821854 -28.228802) (xy 435.822344 -28.25877) (xy 435.822344 -29.114242) (xy 445.147192 -29.114242)
			(xy 445.147192 -28.250642) (xy 445.147682 -28.220658) (xy 445.15551 -28.161202) (xy 445.171031 -28.103277)
			(xy 445.19398 -28.047873) (xy 445.223964 -27.995939) (xy 445.26047 -27.948363) (xy 445.302875 -27.905958)
			(xy 445.350451 -27.869452) (xy 445.402385 -27.839468) (xy 445.457789 -27.816519) (xy 445.515714 -27.800998)
			(xy 445.57517 -27.79317) (xy 445.635138 -27.79317) (xy 445.694594 -27.800998) (xy 445.752519 -27.816519)
			(xy 445.807923 -27.839468) (xy 445.859857 -27.869452) (xy 445.907433 -27.905958) (xy 445.949838 -27.948363)
			(xy 445.986344 -27.995939) (xy 446.016328 -28.047873) (xy 446.039277 -28.103277) (xy 446.054798 -28.161202)
			(xy 446.062626 -28.220658) (xy 446.063116 -28.250642) (xy 446.063116 -29.114242) (xy 446.062626 -29.144226)
			(xy 446.054798 -29.203682) (xy 446.039277 -29.261607) (xy 446.016328 -29.317011) (xy 445.986344 -29.368945)
			(xy 445.949838 -29.416521) (xy 445.907433 -29.458926) (xy 445.859857 -29.495432) (xy 445.807923 -29.525416)
			(xy 445.752519 -29.548365) (xy 445.694594 -29.563886) (xy 445.635138 -29.571714) (xy 445.57517 -29.571714)
			(xy 445.515714 -29.563886) (xy 445.457789 -29.548365) (xy 445.402385 -29.525416) (xy 445.350451 -29.495432)
			(xy 445.302875 -29.458926) (xy 445.26047 -29.416521) (xy 445.223964 -29.368945) (xy 445.19398 -29.317011)
			(xy 445.171031 -29.261607) (xy 445.15551 -29.203682) (xy 445.147682 -29.144226) (xy 445.147192 -29.114242)
			(xy 435.822344 -29.114242) (xy 435.822344 -29.12237) (xy 435.821854 -29.152338) (xy 435.814031 -29.21176)
			(xy 435.798518 -29.269653) (xy 435.775582 -29.325026) (xy 435.745615 -29.376932) (xy 435.709128 -29.424482)
			(xy 435.666748 -29.466862) (xy 435.619198 -29.503349) (xy 435.567292 -29.533316) (xy 435.511919 -29.556252)
			(xy 435.454026 -29.571765) (xy 435.394604 -29.579588) (xy 435.334668 -29.579588) (xy 435.275246 -29.571765)
			(xy 435.217353 -29.556252) (xy 435.16198 -29.533316) (xy 435.110074 -29.503349) (xy 435.062524 -29.466862)
			(xy 435.020144 -29.424482) (xy 434.983657 -29.376932) (xy 434.95369 -29.325026) (xy 434.930754 -29.269653)
			(xy 434.915241 -29.21176) (xy 434.907418 -29.152338) (xy 434.906928 -29.12237) (xy 420.063035 -29.12237)
			(xy 420.062678 -29.144226) (xy 420.05485 -29.203682) (xy 420.039329 -29.261607) (xy 420.01638 -29.317011)
			(xy 419.986396 -29.368945) (xy 419.94989 -29.416521) (xy 419.907485 -29.458926) (xy 419.859909 -29.495432)
			(xy 419.807975 -29.525416) (xy 419.752571 -29.548365) (xy 419.694646 -29.563886) (xy 419.63519 -29.571714)
			(xy 419.575222 -29.571714) (xy 419.515766 -29.563886) (xy 419.457841 -29.548365) (xy 419.402437 -29.525416)
			(xy 419.350503 -29.495432) (xy 419.302927 -29.458926) (xy 419.260522 -29.416521) (xy 419.224016 -29.368945)
			(xy 419.194032 -29.317011) (xy 419.171083 -29.261607) (xy 419.155562 -29.203682) (xy 419.147734 -29.144226)
			(xy 419.147244 -29.114242) (xy 409.822396 -29.114242) (xy 409.822396 -29.12237) (xy 409.821906 -29.152338)
			(xy 409.814083 -29.21176) (xy 409.79857 -29.269653) (xy 409.775634 -29.325026) (xy 409.745667 -29.376932)
			(xy 409.70918 -29.424482) (xy 409.6668 -29.466862) (xy 409.61925 -29.503349) (xy 409.567344 -29.533316)
			(xy 409.511971 -29.556252) (xy 409.454078 -29.571765) (xy 409.394656 -29.579588) (xy 409.33472 -29.579588)
			(xy 409.275298 -29.571765) (xy 409.217405 -29.556252) (xy 409.162032 -29.533316) (xy 409.110126 -29.503349)
			(xy 409.062576 -29.466862) (xy 409.020196 -29.424482) (xy 408.983709 -29.376932) (xy 408.953742 -29.325026)
			(xy 408.930806 -29.269653) (xy 408.915293 -29.21176) (xy 408.90747 -29.152338) (xy 408.90698 -29.12237)
			(xy 394.063087 -29.12237) (xy 394.06273 -29.144226) (xy 394.054902 -29.203682) (xy 394.039381 -29.261607)
			(xy 394.016432 -29.317011) (xy 393.986448 -29.368945) (xy 393.949942 -29.416521) (xy 393.907537 -29.458926)
			(xy 393.859961 -29.495432) (xy 393.808027 -29.525416) (xy 393.752623 -29.548365) (xy 393.694698 -29.563886)
			(xy 393.635242 -29.571714) (xy 393.575274 -29.571714) (xy 393.515818 -29.563886) (xy 393.457893 -29.548365)
			(xy 393.402489 -29.525416) (xy 393.350555 -29.495432) (xy 393.302979 -29.458926) (xy 393.260574 -29.416521)
			(xy 393.224068 -29.368945) (xy 393.194084 -29.317011) (xy 393.171135 -29.261607) (xy 393.155614 -29.203682)
			(xy 393.147786 -29.144226) (xy 393.147296 -29.114242) (xy 383.822448 -29.114242) (xy 383.822448 -29.12237)
			(xy 383.821958 -29.152338) (xy 383.814135 -29.21176) (xy 383.798622 -29.269653) (xy 383.775686 -29.325026)
			(xy 383.745719 -29.376932) (xy 383.709232 -29.424482) (xy 383.666852 -29.466862) (xy 383.619302 -29.503349)
			(xy 383.567396 -29.533316) (xy 383.512023 -29.556252) (xy 383.45413 -29.571765) (xy 383.394708 -29.579588)
			(xy 383.334772 -29.579588) (xy 383.27535 -29.571765) (xy 383.217457 -29.556252) (xy 383.162084 -29.533316)
			(xy 383.110178 -29.503349) (xy 383.062628 -29.466862) (xy 383.020248 -29.424482) (xy 382.983761 -29.376932)
			(xy 382.953794 -29.325026) (xy 382.930858 -29.269653) (xy 382.915345 -29.21176) (xy 382.907522 -29.152338)
			(xy 382.907032 -29.12237) (xy 368.063139 -29.12237) (xy 368.062782 -29.144226) (xy 368.054954 -29.203682)
			(xy 368.039433 -29.261607) (xy 368.016484 -29.317011) (xy 367.9865 -29.368945) (xy 367.949994 -29.416521)
			(xy 367.907589 -29.458926) (xy 367.860013 -29.495432) (xy 367.808079 -29.525416) (xy 367.752675 -29.548365)
			(xy 367.69475 -29.563886) (xy 367.635294 -29.571714) (xy 367.575326 -29.571714) (xy 367.51587 -29.563886)
			(xy 367.457945 -29.548365) (xy 367.402541 -29.525416) (xy 367.350607 -29.495432) (xy 367.303031 -29.458926)
			(xy 367.260626 -29.416521) (xy 367.22412 -29.368945) (xy 367.194136 -29.317011) (xy 367.171187 -29.261607)
			(xy 367.155666 -29.203682) (xy 367.147838 -29.144226) (xy 367.147348 -29.114242) (xy 357.8225 -29.114242)
			(xy 357.8225 -29.12237) (xy 357.82201 -29.152338) (xy 357.814187 -29.21176) (xy 357.798674 -29.269653)
			(xy 357.775738 -29.325026) (xy 357.745771 -29.376932) (xy 357.709284 -29.424482) (xy 357.666904 -29.466862)
			(xy 357.619354 -29.503349) (xy 357.567448 -29.533316) (xy 357.512075 -29.556252) (xy 357.454182 -29.571765)
			(xy 357.39476 -29.579588) (xy 357.334824 -29.579588) (xy 357.275402 -29.571765) (xy 357.217509 -29.556252)
			(xy 357.162136 -29.533316) (xy 357.11023 -29.503349) (xy 357.06268 -29.466862) (xy 357.0203 -29.424482)
			(xy 356.983813 -29.376932) (xy 356.953846 -29.325026) (xy 356.93091 -29.269653) (xy 356.915397 -29.21176)
			(xy 356.907574 -29.152338) (xy 356.907084 -29.12237) (xy 329.962631 -29.12237) (xy 329.962274 -29.14421)
			(xy 329.954451 -29.203632) (xy 329.938938 -29.261525) (xy 329.916002 -29.316898) (xy 329.886035 -29.368804)
			(xy 329.849548 -29.416354) (xy 329.807168 -29.458734) (xy 329.759618 -29.495221) (xy 329.707712 -29.525188)
			(xy 329.652339 -29.548124) (xy 329.594446 -29.563637) (xy 329.535024 -29.57146) (xy 329.475088 -29.57146)
			(xy 329.415666 -29.563637) (xy 329.357773 -29.548124) (xy 329.3024 -29.525188) (xy 329.250494 -29.495221)
			(xy 329.202944 -29.458734) (xy 329.160564 -29.416354) (xy 329.124077 -29.368804) (xy 329.09411 -29.316898)
			(xy 329.071174 -29.261525) (xy 329.055661 -29.203632) (xy 329.047838 -29.14421) (xy 329.047348 -29.114242)
			(xy 319.7225 -29.114242) (xy 319.7225 -29.12237) (xy 319.72201 -29.152354) (xy 319.714182 -29.21181)
			(xy 319.698661 -29.269735) (xy 319.675712 -29.325139) (xy 319.645728 -29.377073) (xy 319.609222 -29.424649)
			(xy 319.566817 -29.467054) (xy 319.519241 -29.50356) (xy 319.467307 -29.533544) (xy 319.411903 -29.556493)
			(xy 319.353978 -29.572014) (xy 319.294522 -29.579842) (xy 319.234554 -29.579842) (xy 319.175098 -29.572014)
			(xy 319.117173 -29.556493) (xy 319.061769 -29.533544) (xy 319.009835 -29.50356) (xy 318.962259 -29.467054)
			(xy 318.919854 -29.424649) (xy 318.883348 -29.377073) (xy 318.853364 -29.325139) (xy 318.830415 -29.269735)
			(xy 318.814894 -29.21181) (xy 318.807066 -29.152354) (xy 318.806576 -29.12237) (xy 303.962683 -29.12237)
			(xy 303.962326 -29.14421) (xy 303.954503 -29.203632) (xy 303.93899 -29.261525) (xy 303.916054 -29.316898)
			(xy 303.886087 -29.368804) (xy 303.8496 -29.416354) (xy 303.80722 -29.458734) (xy 303.75967 -29.495221)
			(xy 303.707764 -29.525188) (xy 303.652391 -29.548124) (xy 303.594498 -29.563637) (xy 303.535076 -29.57146)
			(xy 303.47514 -29.57146) (xy 303.415718 -29.563637) (xy 303.357825 -29.548124) (xy 303.302452 -29.525188)
			(xy 303.250546 -29.495221) (xy 303.202996 -29.458734) (xy 303.160616 -29.416354) (xy 303.124129 -29.368804)
			(xy 303.094162 -29.316898) (xy 303.071226 -29.261525) (xy 303.055713 -29.203632) (xy 303.04789 -29.14421)
			(xy 303.0474 -29.114242) (xy 293.722552 -29.114242) (xy 293.722552 -29.12237) (xy 293.722062 -29.152354)
			(xy 293.714234 -29.21181) (xy 293.698713 -29.269735) (xy 293.675764 -29.325139) (xy 293.64578 -29.377073)
			(xy 293.609274 -29.424649) (xy 293.566869 -29.467054) (xy 293.519293 -29.50356) (xy 293.467359 -29.533544)
			(xy 293.411955 -29.556493) (xy 293.35403 -29.572014) (xy 293.294574 -29.579842) (xy 293.234606 -29.579842)
			(xy 293.17515 -29.572014) (xy 293.117225 -29.556493) (xy 293.061821 -29.533544) (xy 293.009887 -29.50356)
			(xy 292.962311 -29.467054) (xy 292.919906 -29.424649) (xy 292.8834 -29.377073) (xy 292.853416 -29.325139)
			(xy 292.830467 -29.269735) (xy 292.814946 -29.21181) (xy 292.807118 -29.152354) (xy 292.806628 -29.12237)
			(xy 277.962735 -29.12237) (xy 277.962378 -29.14421) (xy 277.954555 -29.203632) (xy 277.939042 -29.261525)
			(xy 277.916106 -29.316898) (xy 277.886139 -29.368804) (xy 277.849652 -29.416354) (xy 277.807272 -29.458734)
			(xy 277.759722 -29.495221) (xy 277.707816 -29.525188) (xy 277.652443 -29.548124) (xy 277.59455 -29.563637)
			(xy 277.535128 -29.57146) (xy 277.475192 -29.57146) (xy 277.41577 -29.563637) (xy 277.357877 -29.548124)
			(xy 277.302504 -29.525188) (xy 277.250598 -29.495221) (xy 277.203048 -29.458734) (xy 277.160668 -29.416354)
			(xy 277.124181 -29.368804) (xy 277.094214 -29.316898) (xy 277.071278 -29.261525) (xy 277.055765 -29.203632)
			(xy 277.047942 -29.14421) (xy 277.047452 -29.114242) (xy 267.722604 -29.114242) (xy 267.722604 -29.12237)
			(xy 267.722114 -29.152354) (xy 267.714286 -29.21181) (xy 267.698765 -29.269735) (xy 267.675816 -29.325139)
			(xy 267.645832 -29.377073) (xy 267.609326 -29.424649) (xy 267.566921 -29.467054) (xy 267.519345 -29.50356)
			(xy 267.467411 -29.533544) (xy 267.412007 -29.556493) (xy 267.354082 -29.572014) (xy 267.294626 -29.579842)
			(xy 267.234658 -29.579842) (xy 267.175202 -29.572014) (xy 267.117277 -29.556493) (xy 267.061873 -29.533544)
			(xy 267.009939 -29.50356) (xy 266.962363 -29.467054) (xy 266.919958 -29.424649) (xy 266.883452 -29.377073)
			(xy 266.853468 -29.325139) (xy 266.830519 -29.269735) (xy 266.814998 -29.21181) (xy 266.80717 -29.152354)
			(xy 266.80668 -29.12237) (xy 251.962787 -29.12237) (xy 251.96243 -29.14421) (xy 251.954607 -29.203632)
			(xy 251.939094 -29.261525) (xy 251.916158 -29.316898) (xy 251.886191 -29.368804) (xy 251.849704 -29.416354)
			(xy 251.807324 -29.458734) (xy 251.759774 -29.495221) (xy 251.707868 -29.525188) (xy 251.652495 -29.548124)
			(xy 251.594602 -29.563637) (xy 251.53518 -29.57146) (xy 251.475244 -29.57146) (xy 251.415822 -29.563637)
			(xy 251.357929 -29.548124) (xy 251.302556 -29.525188) (xy 251.25065 -29.495221) (xy 251.2031 -29.458734)
			(xy 251.16072 -29.416354) (xy 251.124233 -29.368804) (xy 251.094266 -29.316898) (xy 251.07133 -29.261525)
			(xy 251.055817 -29.203632) (xy 251.047994 -29.14421) (xy 251.047504 -29.114242) (xy 241.722656 -29.114242)
			(xy 241.722656 -29.12237) (xy 241.722166 -29.152354) (xy 241.714338 -29.21181) (xy 241.698817 -29.269735)
			(xy 241.675868 -29.325139) (xy 241.645884 -29.377073) (xy 241.609378 -29.424649) (xy 241.566973 -29.467054)
			(xy 241.519397 -29.50356) (xy 241.467463 -29.533544) (xy 241.412059 -29.556493) (xy 241.354134 -29.572014)
			(xy 241.294678 -29.579842) (xy 241.23471 -29.579842) (xy 241.175254 -29.572014) (xy 241.117329 -29.556493)
			(xy 241.061925 -29.533544) (xy 241.009991 -29.50356) (xy 240.962415 -29.467054) (xy 240.92001 -29.424649)
			(xy 240.883504 -29.377073) (xy 240.85352 -29.325139) (xy 240.830571 -29.269735) (xy 240.81505 -29.21181)
			(xy 240.807222 -29.152354) (xy 240.806732 -29.12237) (xy 213.862787 -29.12237) (xy 213.86243 -29.14421)
			(xy 213.854607 -29.203632) (xy 213.839094 -29.261525) (xy 213.816158 -29.316898) (xy 213.786191 -29.368804)
			(xy 213.749704 -29.416354) (xy 213.707324 -29.458734) (xy 213.659774 -29.495221) (xy 213.607868 -29.525188)
			(xy 213.552495 -29.548124) (xy 213.494602 -29.563637) (xy 213.43518 -29.57146) (xy 213.375244 -29.57146)
			(xy 213.315822 -29.563637) (xy 213.257929 -29.548124) (xy 213.202556 -29.525188) (xy 213.15065 -29.495221)
			(xy 213.1031 -29.458734) (xy 213.06072 -29.416354) (xy 213.024233 -29.368804) (xy 212.994266 -29.316898)
			(xy 212.97133 -29.261525) (xy 212.955817 -29.203632) (xy 212.947994 -29.14421) (xy 212.947504 -29.114242)
			(xy 203.622656 -29.114242) (xy 203.622656 -29.12237) (xy 203.622166 -29.152354) (xy 203.614338 -29.21181)
			(xy 203.598817 -29.269735) (xy 203.575868 -29.325139) (xy 203.545884 -29.377073) (xy 203.509378 -29.424649)
			(xy 203.466973 -29.467054) (xy 203.419397 -29.50356) (xy 203.367463 -29.533544) (xy 203.312059 -29.556493)
			(xy 203.254134 -29.572014) (xy 203.194678 -29.579842) (xy 203.13471 -29.579842) (xy 203.075254 -29.572014)
			(xy 203.017329 -29.556493) (xy 202.961925 -29.533544) (xy 202.909991 -29.50356) (xy 202.862415 -29.467054)
			(xy 202.82001 -29.424649) (xy 202.783504 -29.377073) (xy 202.75352 -29.325139) (xy 202.730571 -29.269735)
			(xy 202.71505 -29.21181) (xy 202.707222 -29.152354) (xy 202.706732 -29.12237) (xy 187.862839 -29.12237)
			(xy 187.862482 -29.14421) (xy 187.854659 -29.203632) (xy 187.839146 -29.261525) (xy 187.81621 -29.316898)
			(xy 187.786243 -29.368804) (xy 187.749756 -29.416354) (xy 187.707376 -29.458734) (xy 187.659826 -29.495221)
			(xy 187.60792 -29.525188) (xy 187.552547 -29.548124) (xy 187.494654 -29.563637) (xy 187.435232 -29.57146)
			(xy 187.375296 -29.57146) (xy 187.315874 -29.563637) (xy 187.257981 -29.548124) (xy 187.202608 -29.525188)
			(xy 187.150702 -29.495221) (xy 187.103152 -29.458734) (xy 187.060772 -29.416354) (xy 187.024285 -29.368804)
			(xy 186.994318 -29.316898) (xy 186.971382 -29.261525) (xy 186.955869 -29.203632) (xy 186.948046 -29.14421)
			(xy 186.947556 -29.114242) (xy 177.622708 -29.114242) (xy 177.622708 -29.12237) (xy 177.622218 -29.152354)
			(xy 177.61439 -29.21181) (xy 177.598869 -29.269735) (xy 177.57592 -29.325139) (xy 177.545936 -29.377073)
			(xy 177.50943 -29.424649) (xy 177.467025 -29.467054) (xy 177.419449 -29.50356) (xy 177.367515 -29.533544)
			(xy 177.312111 -29.556493) (xy 177.254186 -29.572014) (xy 177.19473 -29.579842) (xy 177.134762 -29.579842)
			(xy 177.075306 -29.572014) (xy 177.017381 -29.556493) (xy 176.961977 -29.533544) (xy 176.910043 -29.50356)
			(xy 176.862467 -29.467054) (xy 176.820062 -29.424649) (xy 176.783556 -29.377073) (xy 176.753572 -29.325139)
			(xy 176.730623 -29.269735) (xy 176.715102 -29.21181) (xy 176.707274 -29.152354) (xy 176.706784 -29.12237)
			(xy 161.862891 -29.12237) (xy 161.862534 -29.14421) (xy 161.854711 -29.203632) (xy 161.839198 -29.261525)
			(xy 161.816262 -29.316898) (xy 161.786295 -29.368804) (xy 161.749808 -29.416354) (xy 161.707428 -29.458734)
			(xy 161.659878 -29.495221) (xy 161.607972 -29.525188) (xy 161.552599 -29.548124) (xy 161.494706 -29.563637)
			(xy 161.435284 -29.57146) (xy 161.375348 -29.57146) (xy 161.315926 -29.563637) (xy 161.258033 -29.548124)
			(xy 161.20266 -29.525188) (xy 161.150754 -29.495221) (xy 161.103204 -29.458734) (xy 161.060824 -29.416354)
			(xy 161.024337 -29.368804) (xy 160.99437 -29.316898) (xy 160.971434 -29.261525) (xy 160.955921 -29.203632)
			(xy 160.948098 -29.14421) (xy 160.947608 -29.114242) (xy 151.62276 -29.114242) (xy 151.62276 -29.12237)
			(xy 151.62227 -29.152354) (xy 151.614442 -29.21181) (xy 151.598921 -29.269735) (xy 151.575972 -29.325139)
			(xy 151.545988 -29.377073) (xy 151.509482 -29.424649) (xy 151.467077 -29.467054) (xy 151.419501 -29.50356)
			(xy 151.367567 -29.533544) (xy 151.312163 -29.556493) (xy 151.254238 -29.572014) (xy 151.194782 -29.579842)
			(xy 151.134814 -29.579842) (xy 151.075358 -29.572014) (xy 151.017433 -29.556493) (xy 150.962029 -29.533544)
			(xy 150.910095 -29.50356) (xy 150.862519 -29.467054) (xy 150.820114 -29.424649) (xy 150.783608 -29.377073)
			(xy 150.753624 -29.325139) (xy 150.730675 -29.269735) (xy 150.715154 -29.21181) (xy 150.707326 -29.152354)
			(xy 150.706836 -29.12237) (xy 135.862943 -29.12237) (xy 135.862586 -29.14421) (xy 135.854763 -29.203632)
			(xy 135.83925 -29.261525) (xy 135.816314 -29.316898) (xy 135.786347 -29.368804) (xy 135.74986 -29.416354)
			(xy 135.70748 -29.458734) (xy 135.65993 -29.495221) (xy 135.608024 -29.525188) (xy 135.552651 -29.548124)
			(xy 135.494758 -29.563637) (xy 135.435336 -29.57146) (xy 135.3754 -29.57146) (xy 135.315978 -29.563637)
			(xy 135.258085 -29.548124) (xy 135.202712 -29.525188) (xy 135.150806 -29.495221) (xy 135.103256 -29.458734)
			(xy 135.060876 -29.416354) (xy 135.024389 -29.368804) (xy 134.994422 -29.316898) (xy 134.971486 -29.261525)
			(xy 134.955973 -29.203632) (xy 134.94815 -29.14421) (xy 134.94766 -29.114242) (xy 125.622812 -29.114242)
			(xy 125.622812 -29.12237) (xy 125.622322 -29.152354) (xy 125.614494 -29.21181) (xy 125.598973 -29.269735)
			(xy 125.576024 -29.325139) (xy 125.54604 -29.377073) (xy 125.509534 -29.424649) (xy 125.467129 -29.467054)
			(xy 125.419553 -29.50356) (xy 125.367619 -29.533544) (xy 125.312215 -29.556493) (xy 125.25429 -29.572014)
			(xy 125.194834 -29.579842) (xy 125.134866 -29.579842) (xy 125.07541 -29.572014) (xy 125.017485 -29.556493)
			(xy 124.962081 -29.533544) (xy 124.910147 -29.50356) (xy 124.862571 -29.467054) (xy 124.820166 -29.424649)
			(xy 124.78366 -29.377073) (xy 124.753676 -29.325139) (xy 124.730727 -29.269735) (xy 124.715206 -29.21181)
			(xy 124.707378 -29.152354) (xy 124.706888 -29.12237) (xy 97.762943 -29.12237) (xy 97.762586 -29.144226)
			(xy 97.754758 -29.203682) (xy 97.739237 -29.261607) (xy 97.716288 -29.317011) (xy 97.686304 -29.368945)
			(xy 97.649798 -29.416521) (xy 97.607393 -29.458926) (xy 97.559817 -29.495432) (xy 97.507883 -29.525416)
			(xy 97.452479 -29.548365) (xy 97.394554 -29.563886) (xy 97.335098 -29.571714) (xy 97.27513 -29.571714)
			(xy 97.215674 -29.563886) (xy 97.157749 -29.548365) (xy 97.102345 -29.525416) (xy 97.050411 -29.495432)
			(xy 97.002835 -29.458926) (xy 96.96043 -29.416521) (xy 96.923924 -29.368945) (xy 96.89394 -29.317011)
			(xy 96.870991 -29.261607) (xy 96.85547 -29.203682) (xy 96.847642 -29.144226) (xy 96.847152 -29.114242)
			(xy 87.522304 -29.114242) (xy 87.522304 -29.12237) (xy 87.521814 -29.152338) (xy 87.513991 -29.21176)
			(xy 87.498478 -29.269653) (xy 87.475542 -29.325026) (xy 87.445575 -29.376932) (xy 87.409088 -29.424482)
			(xy 87.366708 -29.466862) (xy 87.319158 -29.503349) (xy 87.267252 -29.533316) (xy 87.211879 -29.556252)
			(xy 87.153986 -29.571765) (xy 87.094564 -29.579588) (xy 87.034628 -29.579588) (xy 86.975206 -29.571765)
			(xy 86.917313 -29.556252) (xy 86.86194 -29.533316) (xy 86.810034 -29.503349) (xy 86.762484 -29.466862)
			(xy 86.720104 -29.424482) (xy 86.683617 -29.376932) (xy 86.65365 -29.325026) (xy 86.630714 -29.269653)
			(xy 86.615201 -29.21176) (xy 86.607378 -29.152338) (xy 86.606888 -29.12237) (xy 71.762995 -29.12237)
			(xy 71.762638 -29.144226) (xy 71.75481 -29.203682) (xy 71.739289 -29.261607) (xy 71.71634 -29.317011)
			(xy 71.686356 -29.368945) (xy 71.64985 -29.416521) (xy 71.607445 -29.458926) (xy 71.559869 -29.495432)
			(xy 71.507935 -29.525416) (xy 71.452531 -29.548365) (xy 71.394606 -29.563886) (xy 71.33515 -29.571714)
			(xy 71.275182 -29.571714) (xy 71.215726 -29.563886) (xy 71.157801 -29.548365) (xy 71.102397 -29.525416)
			(xy 71.050463 -29.495432) (xy 71.002887 -29.458926) (xy 70.960482 -29.416521) (xy 70.923976 -29.368945)
			(xy 70.893992 -29.317011) (xy 70.871043 -29.261607) (xy 70.855522 -29.203682) (xy 70.847694 -29.144226)
			(xy 70.847204 -29.114242) (xy 61.522356 -29.114242) (xy 61.522356 -29.12237) (xy 61.521866 -29.152338)
			(xy 61.514043 -29.21176) (xy 61.49853 -29.269653) (xy 61.475594 -29.325026) (xy 61.445627 -29.376932)
			(xy 61.40914 -29.424482) (xy 61.36676 -29.466862) (xy 61.31921 -29.503349) (xy 61.267304 -29.533316)
			(xy 61.211931 -29.556252) (xy 61.154038 -29.571765) (xy 61.094616 -29.579588) (xy 61.03468 -29.579588)
			(xy 60.975258 -29.571765) (xy 60.917365 -29.556252) (xy 60.861992 -29.533316) (xy 60.810086 -29.503349)
			(xy 60.762536 -29.466862) (xy 60.720156 -29.424482) (xy 60.683669 -29.376932) (xy 60.653702 -29.325026)
			(xy 60.630766 -29.269653) (xy 60.615253 -29.21176) (xy 60.60743 -29.152338) (xy 60.60694 -29.12237)
			(xy 45.763047 -29.12237) (xy 45.76269 -29.144226) (xy 45.754862 -29.203682) (xy 45.739341 -29.261607)
			(xy 45.716392 -29.317011) (xy 45.686408 -29.368945) (xy 45.649902 -29.416521) (xy 45.607497 -29.458926)
			(xy 45.559921 -29.495432) (xy 45.507987 -29.525416) (xy 45.452583 -29.548365) (xy 45.394658 -29.563886)
			(xy 45.335202 -29.571714) (xy 45.275234 -29.571714) (xy 45.215778 -29.563886) (xy 45.157853 -29.548365)
			(xy 45.102449 -29.525416) (xy 45.050515 -29.495432) (xy 45.002939 -29.458926) (xy 44.960534 -29.416521)
			(xy 44.924028 -29.368945) (xy 44.894044 -29.317011) (xy 44.871095 -29.261607) (xy 44.855574 -29.203682)
			(xy 44.847746 -29.144226) (xy 44.847256 -29.114242) (xy 35.522408 -29.114242) (xy 35.522408 -29.12237)
			(xy 35.521918 -29.152338) (xy 35.514095 -29.21176) (xy 35.498582 -29.269653) (xy 35.475646 -29.325026)
			(xy 35.445679 -29.376932) (xy 35.409192 -29.424482) (xy 35.366812 -29.466862) (xy 35.319262 -29.503349)
			(xy 35.267356 -29.533316) (xy 35.211983 -29.556252) (xy 35.15409 -29.571765) (xy 35.094668 -29.579588)
			(xy 35.034732 -29.579588) (xy 34.97531 -29.571765) (xy 34.917417 -29.556252) (xy 34.862044 -29.533316)
			(xy 34.810138 -29.503349) (xy 34.762588 -29.466862) (xy 34.720208 -29.424482) (xy 34.683721 -29.376932)
			(xy 34.653754 -29.325026) (xy 34.630818 -29.269653) (xy 34.615305 -29.21176) (xy 34.607482 -29.152338)
			(xy 34.606992 -29.12237) (xy 19.763099 -29.12237) (xy 19.762742 -29.144226) (xy 19.754914 -29.203682)
			(xy 19.739393 -29.261607) (xy 19.716444 -29.317011) (xy 19.68646 -29.368945) (xy 19.649954 -29.416521)
			(xy 19.607549 -29.458926) (xy 19.559973 -29.495432) (xy 19.508039 -29.525416) (xy 19.452635 -29.548365)
			(xy 19.39471 -29.563886) (xy 19.335254 -29.571714) (xy 19.275286 -29.571714) (xy 19.21583 -29.563886)
			(xy 19.157905 -29.548365) (xy 19.102501 -29.525416) (xy 19.050567 -29.495432) (xy 19.002991 -29.458926)
			(xy 18.960586 -29.416521) (xy 18.92408 -29.368945) (xy 18.894096 -29.317011) (xy 18.871147 -29.261607)
			(xy 18.855626 -29.203682) (xy 18.847798 -29.144226) (xy 18.847308 -29.114242) (xy 9.52246 -29.114242)
			(xy 9.52246 -29.12237) (xy 9.52197 -29.152338) (xy 9.514147 -29.21176) (xy 9.498634 -29.269653) (xy 9.475698 -29.325026)
			(xy 9.445731 -29.376932) (xy 9.409244 -29.424482) (xy 9.366864 -29.466862) (xy 9.319314 -29.503349)
			(xy 9.267408 -29.533316) (xy 9.212035 -29.556252) (xy 9.154142 -29.571765) (xy 9.09472 -29.579588)
			(xy 9.034784 -29.579588) (xy 8.975362 -29.571765) (xy 8.917469 -29.556252) (xy 8.862096 -29.533316)
			(xy 8.81019 -29.503349) (xy 8.76264 -29.466862) (xy 8.72026 -29.424482) (xy 8.683773 -29.376932)
			(xy 8.653806 -29.325026) (xy 8.63087 -29.269653) (xy 8.615357 -29.21176) (xy 8.607534 -29.152338)
			(xy 8.607044 -29.12237) (xy 0.509016 -29.12237) (xy 0.509016 -30.922468) (xy 6.752844 -30.922468)
			(xy 6.752844 -30.058868) (xy 6.753334 -30.0289) (xy 6.761157 -29.969478) (xy 6.77667 -29.911585)
			(xy 6.799606 -29.856212) (xy 6.829573 -29.804306) (xy 6.86606 -29.756756) (xy 6.90844 -29.714376)
			(xy 6.95599 -29.677889) (xy 7.007896 -29.647922) (xy 7.063269 -29.624986) (xy 7.121162 -29.609473)
			(xy 7.180584 -29.60165) (xy 7.24052 -29.60165) (xy 7.299942 -29.609473) (xy 7.357835 -29.624986)
			(xy 7.413208 -29.647922) (xy 7.465114 -29.677889) (xy 7.512664 -29.714376) (xy 7.555044 -29.756756)
			(xy 7.591531 -29.804306) (xy 7.621498 -29.856212) (xy 7.644434 -29.911585) (xy 7.659947 -29.969478)
			(xy 7.66777 -30.0289) (xy 7.66826 -30.058868) (xy 7.66826 -30.92069) (xy 21.489416 -30.92069) (xy 21.489416 -30.05709)
			(xy 21.489906 -30.027106) (xy 21.497734 -29.96765) (xy 21.513255 -29.909725) (xy 21.536204 -29.854321)
			(xy 21.566188 -29.802387) (xy 21.602694 -29.754811) (xy 21.645099 -29.712406) (xy 21.692675 -29.6759)
			(xy 21.744609 -29.645916) (xy 21.800013 -29.622967) (xy 21.857938 -29.607446) (xy 21.917394 -29.599618)
			(xy 21.977362 -29.599618) (xy 22.036818 -29.607446) (xy 22.094743 -29.622967) (xy 22.150147 -29.645916)
			(xy 22.202081 -29.6759) (xy 22.249657 -29.712406) (xy 22.292062 -29.754811) (xy 22.328568 -29.802387)
			(xy 22.358552 -29.854321) (xy 22.381501 -29.909725) (xy 22.397022 -29.96765) (xy 22.40485 -30.027106)
			(xy 22.40534 -30.05709) (xy 22.40534 -30.92069) (xy 22.405311 -30.922468) (xy 32.752792 -30.922468)
			(xy 32.752792 -30.058868) (xy 32.753282 -30.0289) (xy 32.761105 -29.969478) (xy 32.776618 -29.911585)
			(xy 32.799554 -29.856212) (xy 32.829521 -29.804306) (xy 32.866008 -29.756756) (xy 32.908388 -29.714376)
			(xy 32.955938 -29.677889) (xy 33.007844 -29.647922) (xy 33.063217 -29.624986) (xy 33.12111 -29.609473)
			(xy 33.180532 -29.60165) (xy 33.240468 -29.60165) (xy 33.29989 -29.609473) (xy 33.357783 -29.624986)
			(xy 33.413156 -29.647922) (xy 33.465062 -29.677889) (xy 33.512612 -29.714376) (xy 33.554992 -29.756756)
			(xy 33.591479 -29.804306) (xy 33.621446 -29.856212) (xy 33.644382 -29.911585) (xy 33.659895 -29.969478)
			(xy 33.667718 -30.0289) (xy 33.668208 -30.058868) (xy 33.668208 -30.92069) (xy 47.489364 -30.92069)
			(xy 47.489364 -30.05709) (xy 47.489854 -30.027106) (xy 47.497682 -29.96765) (xy 47.513203 -29.909725)
			(xy 47.536152 -29.854321) (xy 47.566136 -29.802387) (xy 47.602642 -29.754811) (xy 47.645047 -29.712406)
			(xy 47.692623 -29.6759) (xy 47.744557 -29.645916) (xy 47.799961 -29.622967) (xy 47.857886 -29.607446)
			(xy 47.917342 -29.599618) (xy 47.97731 -29.599618) (xy 48.036766 -29.607446) (xy 48.094691 -29.622967)
			(xy 48.150095 -29.645916) (xy 48.202029 -29.6759) (xy 48.249605 -29.712406) (xy 48.29201 -29.754811)
			(xy 48.328516 -29.802387) (xy 48.3585 -29.854321) (xy 48.381449 -29.909725) (xy 48.39697 -29.96765)
			(xy 48.404798 -30.027106) (xy 48.405288 -30.05709) (xy 48.405288 -30.92069) (xy 48.405259 -30.922468)
			(xy 58.75274 -30.922468) (xy 58.75274 -30.058868) (xy 58.75323 -30.0289) (xy 58.761053 -29.969478)
			(xy 58.776566 -29.911585) (xy 58.799502 -29.856212) (xy 58.829469 -29.804306) (xy 58.865956 -29.756756)
			(xy 58.908336 -29.714376) (xy 58.955886 -29.677889) (xy 59.007792 -29.647922) (xy 59.063165 -29.624986)
			(xy 59.121058 -29.609473) (xy 59.18048 -29.60165) (xy 59.240416 -29.60165) (xy 59.299838 -29.609473)
			(xy 59.357731 -29.624986) (xy 59.413104 -29.647922) (xy 59.46501 -29.677889) (xy 59.51256 -29.714376)
			(xy 59.55494 -29.756756) (xy 59.591427 -29.804306) (xy 59.621394 -29.856212) (xy 59.64433 -29.911585)
			(xy 59.659843 -29.969478) (xy 59.667666 -30.0289) (xy 59.668156 -30.058868) (xy 59.668156 -30.92069)
			(xy 73.489312 -30.92069) (xy 73.489312 -30.05709) (xy 73.489802 -30.027106) (xy 73.49763 -29.96765)
			(xy 73.513151 -29.909725) (xy 73.5361 -29.854321) (xy 73.566084 -29.802387) (xy 73.60259 -29.754811)
			(xy 73.644995 -29.712406) (xy 73.692571 -29.6759) (xy 73.744505 -29.645916) (xy 73.799909 -29.622967)
			(xy 73.857834 -29.607446) (xy 73.91729 -29.599618) (xy 73.977258 -29.599618) (xy 74.036714 -29.607446)
			(xy 74.094639 -29.622967) (xy 74.150043 -29.645916) (xy 74.201977 -29.6759) (xy 74.249553 -29.712406)
			(xy 74.291958 -29.754811) (xy 74.328464 -29.802387) (xy 74.358448 -29.854321) (xy 74.381397 -29.909725)
			(xy 74.396918 -29.96765) (xy 74.404746 -30.027106) (xy 74.405236 -30.05709) (xy 74.405236 -30.92069)
			(xy 74.405207 -30.922468) (xy 84.752688 -30.922468) (xy 84.752688 -30.058868) (xy 84.753178 -30.0289)
			(xy 84.761001 -29.969478) (xy 84.776514 -29.911585) (xy 84.79945 -29.856212) (xy 84.829417 -29.804306)
			(xy 84.865904 -29.756756) (xy 84.908284 -29.714376) (xy 84.955834 -29.677889) (xy 85.00774 -29.647922)
			(xy 85.063113 -29.624986) (xy 85.121006 -29.609473) (xy 85.180428 -29.60165) (xy 85.240364 -29.60165)
			(xy 85.299786 -29.609473) (xy 85.357679 -29.624986) (xy 85.413052 -29.647922) (xy 85.464958 -29.677889)
			(xy 85.512508 -29.714376) (xy 85.554888 -29.756756) (xy 85.591375 -29.804306) (xy 85.621342 -29.856212)
			(xy 85.644278 -29.911585) (xy 85.659791 -29.969478) (xy 85.667614 -30.0289) (xy 85.668104 -30.058868)
			(xy 85.668104 -30.92069) (xy 99.48926 -30.92069) (xy 99.48926 -30.05709) (xy 99.48975 -30.027106)
			(xy 99.497578 -29.96765) (xy 99.513099 -29.909725) (xy 99.536048 -29.854321) (xy 99.566032 -29.802387)
			(xy 99.602538 -29.754811) (xy 99.644943 -29.712406) (xy 99.692519 -29.6759) (xy 99.744453 -29.645916)
			(xy 99.799857 -29.622967) (xy 99.857782 -29.607446) (xy 99.917238 -29.599618) (xy 99.977206 -29.599618)
			(xy 100.036662 -29.607446) (xy 100.094587 -29.622967) (xy 100.149991 -29.645916) (xy 100.201925 -29.6759)
			(xy 100.249501 -29.712406) (xy 100.291906 -29.754811) (xy 100.328412 -29.802387) (xy 100.358396 -29.854321)
			(xy 100.381345 -29.909725) (xy 100.396866 -29.96765) (xy 100.404694 -30.027106) (xy 100.405184 -30.05709)
			(xy 100.405184 -30.92069) (xy 100.405155 -30.922468) (xy 122.852688 -30.922468) (xy 122.852688 -30.058868)
			(xy 122.853178 -30.028884) (xy 122.861006 -29.969428) (xy 122.876527 -29.911503) (xy 122.899476 -29.856099)
			(xy 122.92946 -29.804165) (xy 122.965966 -29.756589) (xy 123.008371 -29.714184) (xy 123.055947 -29.677678)
			(xy 123.107881 -29.647694) (xy 123.163285 -29.624745) (xy 123.22121 -29.609224) (xy 123.280666 -29.601396)
			(xy 123.340634 -29.601396) (xy 123.40009 -29.609224) (xy 123.458015 -29.624745) (xy 123.513419 -29.647694)
			(xy 123.565353 -29.677678) (xy 123.612929 -29.714184) (xy 123.655334 -29.756589) (xy 123.69184 -29.804165)
			(xy 123.721824 -29.856099) (xy 123.744773 -29.911503) (xy 123.760294 -29.969428) (xy 123.768122 -30.028884)
			(xy 123.768612 -30.058868) (xy 123.768612 -30.92069) (xy 137.589768 -30.92069) (xy 137.589768 -30.05709)
			(xy 137.590258 -30.027122) (xy 137.598081 -29.9677) (xy 137.613594 -29.909807) (xy 137.63653 -29.854434)
			(xy 137.666497 -29.802528) (xy 137.702984 -29.754978) (xy 137.745364 -29.712598) (xy 137.792914 -29.676111)
			(xy 137.84482 -29.646144) (xy 137.900193 -29.623208) (xy 137.958086 -29.607695) (xy 138.017508 -29.599872)
			(xy 138.077444 -29.599872) (xy 138.136866 -29.607695) (xy 138.194759 -29.623208) (xy 138.250132 -29.646144)
			(xy 138.302038 -29.676111) (xy 138.349588 -29.712598) (xy 138.391968 -29.754978) (xy 138.428455 -29.802528)
			(xy 138.458422 -29.854434) (xy 138.481358 -29.909807) (xy 138.496871 -29.9677) (xy 138.504694 -30.027122)
			(xy 138.505184 -30.05709) (xy 138.505184 -30.92069) (xy 138.505155 -30.922468) (xy 148.852636 -30.922468)
			(xy 148.852636 -30.058868) (xy 148.853126 -30.028884) (xy 148.860954 -29.969428) (xy 148.876475 -29.911503)
			(xy 148.899424 -29.856099) (xy 148.929408 -29.804165) (xy 148.965914 -29.756589) (xy 149.008319 -29.714184)
			(xy 149.055895 -29.677678) (xy 149.107829 -29.647694) (xy 149.163233 -29.624745) (xy 149.221158 -29.609224)
			(xy 149.280614 -29.601396) (xy 149.340582 -29.601396) (xy 149.400038 -29.609224) (xy 149.457963 -29.624745)
			(xy 149.513367 -29.647694) (xy 149.565301 -29.677678) (xy 149.612877 -29.714184) (xy 149.655282 -29.756589)
			(xy 149.691788 -29.804165) (xy 149.721772 -29.856099) (xy 149.744721 -29.911503) (xy 149.760242 -29.969428)
			(xy 149.76807 -30.028884) (xy 149.76856 -30.058868) (xy 149.76856 -30.92069) (xy 163.589716 -30.92069)
			(xy 163.589716 -30.05709) (xy 163.590206 -30.027122) (xy 163.598029 -29.9677) (xy 163.613542 -29.909807)
			(xy 163.636478 -29.854434) (xy 163.666445 -29.802528) (xy 163.702932 -29.754978) (xy 163.745312 -29.712598)
			(xy 163.792862 -29.676111) (xy 163.844768 -29.646144) (xy 163.900141 -29.623208) (xy 163.958034 -29.607695)
			(xy 164.017456 -29.599872) (xy 164.077392 -29.599872) (xy 164.136814 -29.607695) (xy 164.194707 -29.623208)
			(xy 164.25008 -29.646144) (xy 164.301986 -29.676111) (xy 164.349536 -29.712598) (xy 164.391916 -29.754978)
			(xy 164.428403 -29.802528) (xy 164.45837 -29.854434) (xy 164.481306 -29.909807) (xy 164.496819 -29.9677)
			(xy 164.504642 -30.027122) (xy 164.505132 -30.05709) (xy 164.505132 -30.92069) (xy 164.505103 -30.922468)
			(xy 174.852584 -30.922468) (xy 174.852584 -30.058868) (xy 174.853074 -30.028884) (xy 174.860902 -29.969428)
			(xy 174.876423 -29.911503) (xy 174.899372 -29.856099) (xy 174.929356 -29.804165) (xy 174.965862 -29.756589)
			(xy 175.008267 -29.714184) (xy 175.055843 -29.677678) (xy 175.107777 -29.647694) (xy 175.163181 -29.624745)
			(xy 175.221106 -29.609224) (xy 175.280562 -29.601396) (xy 175.34053 -29.601396) (xy 175.399986 -29.609224)
			(xy 175.457911 -29.624745) (xy 175.513315 -29.647694) (xy 175.565249 -29.677678) (xy 175.612825 -29.714184)
			(xy 175.65523 -29.756589) (xy 175.691736 -29.804165) (xy 175.72172 -29.856099) (xy 175.744669 -29.911503)
			(xy 175.76019 -29.969428) (xy 175.768018 -30.028884) (xy 175.768508 -30.058868) (xy 175.768508 -30.92069)
			(xy 189.589664 -30.92069) (xy 189.589664 -30.05709) (xy 189.590154 -30.027122) (xy 189.597977 -29.9677)
			(xy 189.61349 -29.909807) (xy 189.636426 -29.854434) (xy 189.666393 -29.802528) (xy 189.70288 -29.754978)
			(xy 189.74526 -29.712598) (xy 189.79281 -29.676111) (xy 189.844716 -29.646144) (xy 189.900089 -29.623208)
			(xy 189.957982 -29.607695) (xy 190.017404 -29.599872) (xy 190.07734 -29.599872) (xy 190.136762 -29.607695)
			(xy 190.194655 -29.623208) (xy 190.250028 -29.646144) (xy 190.301934 -29.676111) (xy 190.349484 -29.712598)
			(xy 190.391864 -29.754978) (xy 190.428351 -29.802528) (xy 190.458318 -29.854434) (xy 190.481254 -29.909807)
			(xy 190.496767 -29.9677) (xy 190.50459 -30.027122) (xy 190.50508 -30.05709) (xy 190.50508 -30.92069)
			(xy 190.505051 -30.922468) (xy 200.852532 -30.922468) (xy 200.852532 -30.058868) (xy 200.853022 -30.028884)
			(xy 200.86085 -29.969428) (xy 200.876371 -29.911503) (xy 200.89932 -29.856099) (xy 200.929304 -29.804165)
			(xy 200.96581 -29.756589) (xy 201.008215 -29.714184) (xy 201.055791 -29.677678) (xy 201.107725 -29.647694)
			(xy 201.163129 -29.624745) (xy 201.221054 -29.609224) (xy 201.28051 -29.601396) (xy 201.340478 -29.601396)
			(xy 201.399934 -29.609224) (xy 201.457859 -29.624745) (xy 201.513263 -29.647694) (xy 201.565197 -29.677678)
			(xy 201.612773 -29.714184) (xy 201.655178 -29.756589) (xy 201.691684 -29.804165) (xy 201.721668 -29.856099)
			(xy 201.744617 -29.911503) (xy 201.760138 -29.969428) (xy 201.767966 -30.028884) (xy 201.768456 -30.058868)
			(xy 201.768456 -30.92069) (xy 215.589612 -30.92069) (xy 215.589612 -30.05709) (xy 215.590102 -30.027122)
			(xy 215.597925 -29.9677) (xy 215.613438 -29.909807) (xy 215.636374 -29.854434) (xy 215.666341 -29.802528)
			(xy 215.702828 -29.754978) (xy 215.745208 -29.712598) (xy 215.792758 -29.676111) (xy 215.844664 -29.646144)
			(xy 215.900037 -29.623208) (xy 215.95793 -29.607695) (xy 216.017352 -29.599872) (xy 216.077288 -29.599872)
			(xy 216.13671 -29.607695) (xy 216.194603 -29.623208) (xy 216.249976 -29.646144) (xy 216.301882 -29.676111)
			(xy 216.349432 -29.712598) (xy 216.391812 -29.754978) (xy 216.428299 -29.802528) (xy 216.458266 -29.854434)
			(xy 216.481202 -29.909807) (xy 216.496715 -29.9677) (xy 216.504538 -30.027122) (xy 216.505028 -30.05709)
			(xy 216.505028 -30.92069) (xy 216.504999 -30.922468) (xy 238.952532 -30.922468) (xy 238.952532 -30.058868)
			(xy 238.953022 -30.028884) (xy 238.96085 -29.969428) (xy 238.976371 -29.911503) (xy 238.99932 -29.856099)
			(xy 239.029304 -29.804165) (xy 239.06581 -29.756589) (xy 239.108215 -29.714184) (xy 239.155791 -29.677678)
			(xy 239.207725 -29.647694) (xy 239.263129 -29.624745) (xy 239.321054 -29.609224) (xy 239.38051 -29.601396)
			(xy 239.440478 -29.601396) (xy 239.499934 -29.609224) (xy 239.557859 -29.624745) (xy 239.613263 -29.647694)
			(xy 239.665197 -29.677678) (xy 239.712773 -29.714184) (xy 239.755178 -29.756589) (xy 239.791684 -29.804165)
			(xy 239.821668 -29.856099) (xy 239.844617 -29.911503) (xy 239.860138 -29.969428) (xy 239.867966 -30.028884)
			(xy 239.868456 -30.058868) (xy 239.868456 -30.92069) (xy 253.689612 -30.92069) (xy 253.689612 -30.05709)
			(xy 253.690102 -30.027122) (xy 253.697925 -29.9677) (xy 253.713438 -29.909807) (xy 253.736374 -29.854434)
			(xy 253.766341 -29.802528) (xy 253.802828 -29.754978) (xy 253.845208 -29.712598) (xy 253.892758 -29.676111)
			(xy 253.944664 -29.646144) (xy 254.000037 -29.623208) (xy 254.05793 -29.607695) (xy 254.117352 -29.599872)
			(xy 254.177288 -29.599872) (xy 254.23671 -29.607695) (xy 254.294603 -29.623208) (xy 254.349976 -29.646144)
			(xy 254.401882 -29.676111) (xy 254.449432 -29.712598) (xy 254.491812 -29.754978) (xy 254.528299 -29.802528)
			(xy 254.558266 -29.854434) (xy 254.581202 -29.909807) (xy 254.596715 -29.9677) (xy 254.604538 -30.027122)
			(xy 254.605028 -30.05709) (xy 254.605028 -30.92069) (xy 254.604999 -30.922468) (xy 264.95248 -30.922468)
			(xy 264.95248 -30.058868) (xy 264.95297 -30.028884) (xy 264.960798 -29.969428) (xy 264.976319 -29.911503)
			(xy 264.999268 -29.856099) (xy 265.029252 -29.804165) (xy 265.065758 -29.756589) (xy 265.108163 -29.714184)
			(xy 265.155739 -29.677678) (xy 265.207673 -29.647694) (xy 265.263077 -29.624745) (xy 265.321002 -29.609224)
			(xy 265.380458 -29.601396) (xy 265.440426 -29.601396) (xy 265.499882 -29.609224) (xy 265.557807 -29.624745)
			(xy 265.613211 -29.647694) (xy 265.665145 -29.677678) (xy 265.712721 -29.714184) (xy 265.755126 -29.756589)
			(xy 265.791632 -29.804165) (xy 265.821616 -29.856099) (xy 265.844565 -29.911503) (xy 265.860086 -29.969428)
			(xy 265.867914 -30.028884) (xy 265.868404 -30.058868) (xy 265.868404 -30.92069) (xy 279.68956 -30.92069)
			(xy 279.68956 -30.05709) (xy 279.69005 -30.027122) (xy 279.697873 -29.9677) (xy 279.713386 -29.909807)
			(xy 279.736322 -29.854434) (xy 279.766289 -29.802528) (xy 279.802776 -29.754978) (xy 279.845156 -29.712598)
			(xy 279.892706 -29.676111) (xy 279.944612 -29.646144) (xy 279.999985 -29.623208) (xy 280.057878 -29.607695)
			(xy 280.1173 -29.599872) (xy 280.177236 -29.599872) (xy 280.236658 -29.607695) (xy 280.294551 -29.623208)
			(xy 280.349924 -29.646144) (xy 280.40183 -29.676111) (xy 280.44938 -29.712598) (xy 280.49176 -29.754978)
			(xy 280.528247 -29.802528) (xy 280.558214 -29.854434) (xy 280.58115 -29.909807) (xy 280.596663 -29.9677)
			(xy 280.604486 -30.027122) (xy 280.604976 -30.05709) (xy 280.604976 -30.92069) (xy 280.604947 -30.922468)
			(xy 290.952428 -30.922468) (xy 290.952428 -30.058868) (xy 290.952918 -30.028884) (xy 290.960746 -29.969428)
			(xy 290.976267 -29.911503) (xy 290.999216 -29.856099) (xy 291.0292 -29.804165) (xy 291.065706 -29.756589)
			(xy 291.108111 -29.714184) (xy 291.155687 -29.677678) (xy 291.207621 -29.647694) (xy 291.263025 -29.624745)
			(xy 291.32095 -29.609224) (xy 291.380406 -29.601396) (xy 291.440374 -29.601396) (xy 291.49983 -29.609224)
			(xy 291.557755 -29.624745) (xy 291.613159 -29.647694) (xy 291.665093 -29.677678) (xy 291.712669 -29.714184)
			(xy 291.755074 -29.756589) (xy 291.79158 -29.804165) (xy 291.821564 -29.856099) (xy 291.844513 -29.911503)
			(xy 291.860034 -29.969428) (xy 291.867862 -30.028884) (xy 291.868352 -30.058868) (xy 291.868352 -30.92069)
			(xy 305.689508 -30.92069) (xy 305.689508 -30.05709) (xy 305.689998 -30.027122) (xy 305.697821 -29.9677)
			(xy 305.713334 -29.909807) (xy 305.73627 -29.854434) (xy 305.766237 -29.802528) (xy 305.802724 -29.754978)
			(xy 305.845104 -29.712598) (xy 305.892654 -29.676111) (xy 305.94456 -29.646144) (xy 305.999933 -29.623208)
			(xy 306.057826 -29.607695) (xy 306.117248 -29.599872) (xy 306.177184 -29.599872) (xy 306.236606 -29.607695)
			(xy 306.294499 -29.623208) (xy 306.349872 -29.646144) (xy 306.401778 -29.676111) (xy 306.449328 -29.712598)
			(xy 306.491708 -29.754978) (xy 306.528195 -29.802528) (xy 306.558162 -29.854434) (xy 306.581098 -29.909807)
			(xy 306.596611 -29.9677) (xy 306.604434 -30.027122) (xy 306.604924 -30.05709) (xy 306.604924 -30.92069)
			(xy 306.604895 -30.922468) (xy 316.952376 -30.922468) (xy 316.952376 -30.058868) (xy 316.952866 -30.028884)
			(xy 316.960694 -29.969428) (xy 316.976215 -29.911503) (xy 316.999164 -29.856099) (xy 317.029148 -29.804165)
			(xy 317.065654 -29.756589) (xy 317.108059 -29.714184) (xy 317.155635 -29.677678) (xy 317.207569 -29.647694)
			(xy 317.262973 -29.624745) (xy 317.320898 -29.609224) (xy 317.380354 -29.601396) (xy 317.440322 -29.601396)
			(xy 317.499778 -29.609224) (xy 317.557703 -29.624745) (xy 317.613107 -29.647694) (xy 317.665041 -29.677678)
			(xy 317.712617 -29.714184) (xy 317.755022 -29.756589) (xy 317.791528 -29.804165) (xy 317.821512 -29.856099)
			(xy 317.844461 -29.911503) (xy 317.859982 -29.969428) (xy 317.86781 -30.028884) (xy 317.8683 -30.058868)
			(xy 317.8683 -30.92069) (xy 331.689456 -30.92069) (xy 331.689456 -30.05709) (xy 331.689946 -30.027122)
			(xy 331.697769 -29.9677) (xy 331.713282 -29.909807) (xy 331.736218 -29.854434) (xy 331.766185 -29.802528)
			(xy 331.802672 -29.754978) (xy 331.845052 -29.712598) (xy 331.892602 -29.676111) (xy 331.944508 -29.646144)
			(xy 331.999881 -29.623208) (xy 332.057774 -29.607695) (xy 332.117196 -29.599872) (xy 332.177132 -29.599872)
			(xy 332.236554 -29.607695) (xy 332.294447 -29.623208) (xy 332.34982 -29.646144) (xy 332.401726 -29.676111)
			(xy 332.449276 -29.712598) (xy 332.491656 -29.754978) (xy 332.528143 -29.802528) (xy 332.55811 -29.854434)
			(xy 332.581046 -29.909807) (xy 332.596559 -29.9677) (xy 332.604382 -30.027122) (xy 332.604872 -30.05709)
			(xy 332.604872 -30.92069) (xy 332.604843 -30.922468) (xy 355.052884 -30.922468) (xy 355.052884 -30.058868)
			(xy 355.053374 -30.0289) (xy 355.061197 -29.969478) (xy 355.07671 -29.911585) (xy 355.099646 -29.856212)
			(xy 355.129613 -29.804306) (xy 355.1661 -29.756756) (xy 355.20848 -29.714376) (xy 355.25603 -29.677889)
			(xy 355.307936 -29.647922) (xy 355.363309 -29.624986) (xy 355.421202 -29.609473) (xy 355.480624 -29.60165)
			(xy 355.54056 -29.60165) (xy 355.599982 -29.609473) (xy 355.657875 -29.624986) (xy 355.713248 -29.647922)
			(xy 355.765154 -29.677889) (xy 355.812704 -29.714376) (xy 355.855084 -29.756756) (xy 355.891571 -29.804306)
			(xy 355.921538 -29.856212) (xy 355.944474 -29.911585) (xy 355.959987 -29.969478) (xy 355.96781 -30.0289)
			(xy 355.9683 -30.058868) (xy 355.9683 -30.92069) (xy 369.789456 -30.92069) (xy 369.789456 -30.05709)
			(xy 369.789946 -30.027106) (xy 369.797774 -29.96765) (xy 369.813295 -29.909725) (xy 369.836244 -29.854321)
			(xy 369.866228 -29.802387) (xy 369.902734 -29.754811) (xy 369.945139 -29.712406) (xy 369.992715 -29.6759)
			(xy 370.044649 -29.645916) (xy 370.100053 -29.622967) (xy 370.157978 -29.607446) (xy 370.217434 -29.599618)
			(xy 370.277402 -29.599618) (xy 370.336858 -29.607446) (xy 370.394783 -29.622967) (xy 370.450187 -29.645916)
			(xy 370.502121 -29.6759) (xy 370.549697 -29.712406) (xy 370.592102 -29.754811) (xy 370.628608 -29.802387)
			(xy 370.658592 -29.854321) (xy 370.681541 -29.909725) (xy 370.697062 -29.96765) (xy 370.70489 -30.027106)
			(xy 370.70538 -30.05709) (xy 370.70538 -30.92069) (xy 370.705351 -30.922468) (xy 381.052832 -30.922468)
			(xy 381.052832 -30.058868) (xy 381.053322 -30.0289) (xy 381.061145 -29.969478) (xy 381.076658 -29.911585)
			(xy 381.099594 -29.856212) (xy 381.129561 -29.804306) (xy 381.166048 -29.756756) (xy 381.208428 -29.714376)
			(xy 381.255978 -29.677889) (xy 381.307884 -29.647922) (xy 381.363257 -29.624986) (xy 381.42115 -29.609473)
			(xy 381.480572 -29.60165) (xy 381.540508 -29.60165) (xy 381.59993 -29.609473) (xy 381.657823 -29.624986)
			(xy 381.713196 -29.647922) (xy 381.765102 -29.677889) (xy 381.812652 -29.714376) (xy 381.855032 -29.756756)
			(xy 381.891519 -29.804306) (xy 381.921486 -29.856212) (xy 381.944422 -29.911585) (xy 381.959935 -29.969478)
			(xy 381.967758 -30.0289) (xy 381.968248 -30.058868) (xy 381.968248 -30.92069) (xy 395.789404 -30.92069)
			(xy 395.789404 -30.05709) (xy 395.789894 -30.027106) (xy 395.797722 -29.96765) (xy 395.813243 -29.909725)
			(xy 395.836192 -29.854321) (xy 395.866176 -29.802387) (xy 395.902682 -29.754811) (xy 395.945087 -29.712406)
			(xy 395.992663 -29.6759) (xy 396.044597 -29.645916) (xy 396.100001 -29.622967) (xy 396.157926 -29.607446)
			(xy 396.217382 -29.599618) (xy 396.27735 -29.599618) (xy 396.336806 -29.607446) (xy 396.394731 -29.622967)
			(xy 396.450135 -29.645916) (xy 396.502069 -29.6759) (xy 396.549645 -29.712406) (xy 396.59205 -29.754811)
			(xy 396.628556 -29.802387) (xy 396.65854 -29.854321) (xy 396.681489 -29.909725) (xy 396.69701 -29.96765)
			(xy 396.704838 -30.027106) (xy 396.705328 -30.05709) (xy 396.705328 -30.92069) (xy 396.705299 -30.922468)
			(xy 407.05278 -30.922468) (xy 407.05278 -30.058868) (xy 407.05327 -30.0289) (xy 407.061093 -29.969478)
			(xy 407.076606 -29.911585) (xy 407.099542 -29.856212) (xy 407.129509 -29.804306) (xy 407.165996 -29.756756)
			(xy 407.208376 -29.714376) (xy 407.255926 -29.677889) (xy 407.307832 -29.647922) (xy 407.363205 -29.624986)
			(xy 407.421098 -29.609473) (xy 407.48052 -29.60165) (xy 407.540456 -29.60165) (xy 407.599878 -29.609473)
			(xy 407.657771 -29.624986) (xy 407.713144 -29.647922) (xy 407.76505 -29.677889) (xy 407.8126 -29.714376)
			(xy 407.85498 -29.756756) (xy 407.891467 -29.804306) (xy 407.921434 -29.856212) (xy 407.94437 -29.911585)
			(xy 407.959883 -29.969478) (xy 407.967706 -30.0289) (xy 407.968196 -30.058868) (xy 407.968196 -30.92069)
			(xy 421.789352 -30.92069) (xy 421.789352 -30.05709) (xy 421.789842 -30.027106) (xy 421.79767 -29.96765)
			(xy 421.813191 -29.909725) (xy 421.83614 -29.854321) (xy 421.866124 -29.802387) (xy 421.90263 -29.754811)
			(xy 421.945035 -29.712406) (xy 421.992611 -29.6759) (xy 422.044545 -29.645916) (xy 422.099949 -29.622967)
			(xy 422.157874 -29.607446) (xy 422.21733 -29.599618) (xy 422.277298 -29.599618) (xy 422.336754 -29.607446)
			(xy 422.394679 -29.622967) (xy 422.450083 -29.645916) (xy 422.502017 -29.6759) (xy 422.549593 -29.712406)
			(xy 422.591998 -29.754811) (xy 422.628504 -29.802387) (xy 422.658488 -29.854321) (xy 422.681437 -29.909725)
			(xy 422.696958 -29.96765) (xy 422.704786 -30.027106) (xy 422.705276 -30.05709) (xy 422.705276 -30.92069)
			(xy 422.705247 -30.922468) (xy 433.052728 -30.922468) (xy 433.052728 -30.058868) (xy 433.053218 -30.0289)
			(xy 433.061041 -29.969478) (xy 433.076554 -29.911585) (xy 433.09949 -29.856212) (xy 433.129457 -29.804306)
			(xy 433.165944 -29.756756) (xy 433.208324 -29.714376) (xy 433.255874 -29.677889) (xy 433.30778 -29.647922)
			(xy 433.363153 -29.624986) (xy 433.421046 -29.609473) (xy 433.480468 -29.60165) (xy 433.540404 -29.60165)
			(xy 433.599826 -29.609473) (xy 433.657719 -29.624986) (xy 433.713092 -29.647922) (xy 433.764998 -29.677889)
			(xy 433.812548 -29.714376) (xy 433.854928 -29.756756) (xy 433.891415 -29.804306) (xy 433.921382 -29.856212)
			(xy 433.944318 -29.911585) (xy 433.959831 -29.969478) (xy 433.967654 -30.0289) (xy 433.968144 -30.058868)
			(xy 433.968144 -30.92069) (xy 447.7893 -30.92069) (xy 447.7893 -30.05709) (xy 447.78979 -30.027106)
			(xy 447.797618 -29.96765) (xy 447.813139 -29.909725) (xy 447.836088 -29.854321) (xy 447.866072 -29.802387)
			(xy 447.902578 -29.754811) (xy 447.944983 -29.712406) (xy 447.992559 -29.6759) (xy 448.044493 -29.645916)
			(xy 448.099897 -29.622967) (xy 448.157822 -29.607446) (xy 448.217278 -29.599618) (xy 448.277246 -29.599618)
			(xy 448.336702 -29.607446) (xy 448.394627 -29.622967) (xy 448.450031 -29.645916) (xy 448.501965 -29.6759)
			(xy 448.549541 -29.712406) (xy 448.591946 -29.754811) (xy 448.628452 -29.802387) (xy 448.658436 -29.854321)
			(xy 448.681385 -29.909725) (xy 448.696906 -29.96765) (xy 448.704734 -30.027106) (xy 448.705224 -30.05709)
			(xy 448.705224 -30.745738) (xy 457.614517 -30.745738) (xy 457.614517 -30.616598) (xy 457.622467 -30.487703)
			(xy 457.638337 -30.359543) (xy 457.662066 -30.232602) (xy 457.693565 -30.107363) (xy 457.732714 -29.9843)
			(xy 457.779365 -29.863881) (xy 457.83334 -29.746562) (xy 457.894435 -29.632788) (xy 457.962418 -29.522991)
			(xy 458.037032 -29.417588) (xy 458.117993 -29.316978) (xy 458.204993 -29.221543) (xy 458.297704 -29.131644)
			(xy 458.395774 -29.047623) (xy 458.498829 -28.969799) (xy 458.60648 -28.898467) (xy 458.718319 -28.833897)
			(xy 458.83392 -28.776335) (xy 458.952845 -28.725998) (xy 459.074644 -28.683078) (xy 459.198854 -28.647737)
			(xy 459.325003 -28.62011) (xy 459.452615 -28.600301) (xy 459.581204 -28.588385) (xy 459.710282 -28.584409)
			(xy 459.83936 -28.588385) (xy 459.967949 -28.600301) (xy 460.095561 -28.62011) (xy 460.22171 -28.647737)
			(xy 460.34592 -28.683078) (xy 460.467719 -28.725998) (xy 460.586644 -28.776335) (xy 460.702245 -28.833897)
			(xy 460.814084 -28.898467) (xy 460.921735 -28.969799) (xy 461.02479 -29.047623) (xy 461.12286 -29.131644)
			(xy 461.215571 -29.221543) (xy 461.302571 -29.316978) (xy 461.383532 -29.417588) (xy 461.458146 -29.522991)
			(xy 461.526129 -29.632788) (xy 461.587224 -29.746562) (xy 461.641199 -29.863881) (xy 461.68785 -29.9843)
			(xy 461.726999 -30.107363) (xy 461.758498 -30.232602) (xy 461.782227 -30.359543) (xy 461.798097 -30.487703)
			(xy 461.806047 -30.616598) (xy 461.806544 -30.681168) (xy 461.806047 -30.745738) (xy 461.798097 -30.874633)
			(xy 461.782227 -31.002793) (xy 461.758498 -31.129734) (xy 461.726999 -31.254973) (xy 461.68785 -31.378036)
			(xy 461.641199 -31.498455) (xy 461.587224 -31.615774) (xy 461.526129 -31.729548) (xy 461.458146 -31.839345)
			(xy 461.383532 -31.944748) (xy 461.302571 -32.045358) (xy 461.215571 -32.140793) (xy 461.12286 -32.230692)
			(xy 461.02479 -32.314713) (xy 460.921735 -32.392537) (xy 460.814084 -32.463869) (xy 460.702245 -32.528439)
			(xy 460.586644 -32.586001) (xy 460.467719 -32.636338) (xy 460.34592 -32.679258) (xy 460.22171 -32.714599)
			(xy 460.095561 -32.742226) (xy 459.967949 -32.762035) (xy 459.83936 -32.773951) (xy 459.710282 -32.777928)
			(xy 459.581204 -32.773951) (xy 459.452615 -32.762035) (xy 459.325003 -32.742226) (xy 459.198854 -32.714599)
			(xy 459.074644 -32.679258) (xy 458.952845 -32.636338) (xy 458.83392 -32.586001) (xy 458.718319 -32.528439)
			(xy 458.60648 -32.463869) (xy 458.498829 -32.392537) (xy 458.395774 -32.314713) (xy 458.297704 -32.230692)
			(xy 458.204993 -32.140793) (xy 458.117993 -32.045358) (xy 458.037032 -31.944748) (xy 457.962418 -31.839345)
			(xy 457.894435 -31.729548) (xy 457.83334 -31.615774) (xy 457.779365 -31.498455) (xy 457.732714 -31.378036)
			(xy 457.693565 -31.254973) (xy 457.662066 -31.129734) (xy 457.638337 -31.002793) (xy 457.622467 -30.874633)
			(xy 457.614517 -30.745738) (xy 448.705224 -30.745738) (xy 448.705224 -30.92069) (xy 448.704734 -30.950674)
			(xy 448.696906 -31.01013) (xy 448.681385 -31.068055) (xy 448.658436 -31.123459) (xy 448.628452 -31.175393)
			(xy 448.591946 -31.222969) (xy 448.549541 -31.265374) (xy 448.501965 -31.30188) (xy 448.450031 -31.331864)
			(xy 448.394627 -31.354813) (xy 448.336702 -31.370334) (xy 448.277246 -31.378162) (xy 448.217278 -31.378162)
			(xy 448.157822 -31.370334) (xy 448.099897 -31.354813) (xy 448.044493 -31.331864) (xy 447.992559 -31.30188)
			(xy 447.944983 -31.265374) (xy 447.902578 -31.222969) (xy 447.866072 -31.175393) (xy 447.836088 -31.123459)
			(xy 447.813139 -31.068055) (xy 447.797618 -31.01013) (xy 447.78979 -30.950674) (xy 447.7893 -30.92069)
			(xy 433.968144 -30.92069) (xy 433.968144 -30.922468) (xy 433.967654 -30.952436) (xy 433.959831 -31.011858)
			(xy 433.944318 -31.069751) (xy 433.921382 -31.125124) (xy 433.891415 -31.17703) (xy 433.854928 -31.22458)
			(xy 433.812548 -31.26696) (xy 433.764998 -31.303447) (xy 433.713092 -31.333414) (xy 433.657719 -31.35635)
			(xy 433.599826 -31.371863) (xy 433.540404 -31.379686) (xy 433.480468 -31.379686) (xy 433.421046 -31.371863)
			(xy 433.363153 -31.35635) (xy 433.30778 -31.333414) (xy 433.255874 -31.303447) (xy 433.208324 -31.26696)
			(xy 433.165944 -31.22458) (xy 433.129457 -31.17703) (xy 433.09949 -31.125124) (xy 433.076554 -31.069751)
			(xy 433.061041 -31.011858) (xy 433.053218 -30.952436) (xy 433.052728 -30.922468) (xy 422.705247 -30.922468)
			(xy 422.704786 -30.950674) (xy 422.696958 -31.01013) (xy 422.681437 -31.068055) (xy 422.658488 -31.123459)
			(xy 422.628504 -31.175393) (xy 422.591998 -31.222969) (xy 422.549593 -31.265374) (xy 422.502017 -31.30188)
			(xy 422.450083 -31.331864) (xy 422.394679 -31.354813) (xy 422.336754 -31.370334) (xy 422.277298 -31.378162)
			(xy 422.21733 -31.378162) (xy 422.157874 -31.370334) (xy 422.099949 -31.354813) (xy 422.044545 -31.331864)
			(xy 421.992611 -31.30188) (xy 421.945035 -31.265374) (xy 421.90263 -31.222969) (xy 421.866124 -31.175393)
			(xy 421.83614 -31.123459) (xy 421.813191 -31.068055) (xy 421.79767 -31.01013) (xy 421.789842 -30.950674)
			(xy 421.789352 -30.92069) (xy 407.968196 -30.92069) (xy 407.968196 -30.922468) (xy 407.967706 -30.952436)
			(xy 407.959883 -31.011858) (xy 407.94437 -31.069751) (xy 407.921434 -31.125124) (xy 407.891467 -31.17703)
			(xy 407.85498 -31.22458) (xy 407.8126 -31.26696) (xy 407.76505 -31.303447) (xy 407.713144 -31.333414)
			(xy 407.657771 -31.35635) (xy 407.599878 -31.371863) (xy 407.540456 -31.379686) (xy 407.48052 -31.379686)
			(xy 407.421098 -31.371863) (xy 407.363205 -31.35635) (xy 407.307832 -31.333414) (xy 407.255926 -31.303447)
			(xy 407.208376 -31.26696) (xy 407.165996 -31.22458) (xy 407.129509 -31.17703) (xy 407.099542 -31.125124)
			(xy 407.076606 -31.069751) (xy 407.061093 -31.011858) (xy 407.05327 -30.952436) (xy 407.05278 -30.922468)
			(xy 396.705299 -30.922468) (xy 396.704838 -30.950674) (xy 396.69701 -31.01013) (xy 396.681489 -31.068055)
			(xy 396.65854 -31.123459) (xy 396.628556 -31.175393) (xy 396.59205 -31.222969) (xy 396.549645 -31.265374)
			(xy 396.502069 -31.30188) (xy 396.450135 -31.331864) (xy 396.394731 -31.354813) (xy 396.336806 -31.370334)
			(xy 396.27735 -31.378162) (xy 396.217382 -31.378162) (xy 396.157926 -31.370334) (xy 396.100001 -31.354813)
			(xy 396.044597 -31.331864) (xy 395.992663 -31.30188) (xy 395.945087 -31.265374) (xy 395.902682 -31.222969)
			(xy 395.866176 -31.175393) (xy 395.836192 -31.123459) (xy 395.813243 -31.068055) (xy 395.797722 -31.01013)
			(xy 395.789894 -30.950674) (xy 395.789404 -30.92069) (xy 381.968248 -30.92069) (xy 381.968248 -30.922468)
			(xy 381.967758 -30.952436) (xy 381.959935 -31.011858) (xy 381.944422 -31.069751) (xy 381.921486 -31.125124)
			(xy 381.891519 -31.17703) (xy 381.855032 -31.22458) (xy 381.812652 -31.26696) (xy 381.765102 -31.303447)
			(xy 381.713196 -31.333414) (xy 381.657823 -31.35635) (xy 381.59993 -31.371863) (xy 381.540508 -31.379686)
			(xy 381.480572 -31.379686) (xy 381.42115 -31.371863) (xy 381.363257 -31.35635) (xy 381.307884 -31.333414)
			(xy 381.255978 -31.303447) (xy 381.208428 -31.26696) (xy 381.166048 -31.22458) (xy 381.129561 -31.17703)
			(xy 381.099594 -31.125124) (xy 381.076658 -31.069751) (xy 381.061145 -31.011858) (xy 381.053322 -30.952436)
			(xy 381.052832 -30.922468) (xy 370.705351 -30.922468) (xy 370.70489 -30.950674) (xy 370.697062 -31.01013)
			(xy 370.681541 -31.068055) (xy 370.658592 -31.123459) (xy 370.628608 -31.175393) (xy 370.592102 -31.222969)
			(xy 370.549697 -31.265374) (xy 370.502121 -31.30188) (xy 370.450187 -31.331864) (xy 370.394783 -31.354813)
			(xy 370.336858 -31.370334) (xy 370.277402 -31.378162) (xy 370.217434 -31.378162) (xy 370.157978 -31.370334)
			(xy 370.100053 -31.354813) (xy 370.044649 -31.331864) (xy 369.992715 -31.30188) (xy 369.945139 -31.265374)
			(xy 369.902734 -31.222969) (xy 369.866228 -31.175393) (xy 369.836244 -31.123459) (xy 369.813295 -31.068055)
			(xy 369.797774 -31.01013) (xy 369.789946 -30.950674) (xy 369.789456 -30.92069) (xy 355.9683 -30.92069)
			(xy 355.9683 -30.922468) (xy 355.96781 -30.952436) (xy 355.959987 -31.011858) (xy 355.944474 -31.069751)
			(xy 355.921538 -31.125124) (xy 355.891571 -31.17703) (xy 355.855084 -31.22458) (xy 355.812704 -31.26696)
			(xy 355.765154 -31.303447) (xy 355.713248 -31.333414) (xy 355.657875 -31.35635) (xy 355.599982 -31.371863)
			(xy 355.54056 -31.379686) (xy 355.480624 -31.379686) (xy 355.421202 -31.371863) (xy 355.363309 -31.35635)
			(xy 355.307936 -31.333414) (xy 355.25603 -31.303447) (xy 355.20848 -31.26696) (xy 355.1661 -31.22458)
			(xy 355.129613 -31.17703) (xy 355.099646 -31.125124) (xy 355.07671 -31.069751) (xy 355.061197 -31.011858)
			(xy 355.053374 -30.952436) (xy 355.052884 -30.922468) (xy 332.604843 -30.922468) (xy 332.604382 -30.950658)
			(xy 332.596559 -31.01008) (xy 332.581046 -31.067973) (xy 332.55811 -31.123346) (xy 332.528143 -31.175252)
			(xy 332.491656 -31.222802) (xy 332.449276 -31.265182) (xy 332.401726 -31.301669) (xy 332.34982 -31.331636)
			(xy 332.294447 -31.354572) (xy 332.236554 -31.370085) (xy 332.177132 -31.377908) (xy 332.117196 -31.377908)
			(xy 332.057774 -31.370085) (xy 331.999881 -31.354572) (xy 331.944508 -31.331636) (xy 331.892602 -31.301669)
			(xy 331.845052 -31.265182) (xy 331.802672 -31.222802) (xy 331.766185 -31.175252) (xy 331.736218 -31.123346)
			(xy 331.713282 -31.067973) (xy 331.697769 -31.01008) (xy 331.689946 -30.950658) (xy 331.689456 -30.92069)
			(xy 317.8683 -30.92069) (xy 317.8683 -30.922468) (xy 317.86781 -30.952452) (xy 317.859982 -31.011908)
			(xy 317.844461 -31.069833) (xy 317.821512 -31.125237) (xy 317.791528 -31.177171) (xy 317.755022 -31.224747)
			(xy 317.712617 -31.267152) (xy 317.665041 -31.303658) (xy 317.613107 -31.333642) (xy 317.557703 -31.356591)
			(xy 317.499778 -31.372112) (xy 317.440322 -31.37994) (xy 317.380354 -31.37994) (xy 317.320898 -31.372112)
			(xy 317.262973 -31.356591) (xy 317.207569 -31.333642) (xy 317.155635 -31.303658) (xy 317.108059 -31.267152)
			(xy 317.065654 -31.224747) (xy 317.029148 -31.177171) (xy 316.999164 -31.125237) (xy 316.976215 -31.069833)
			(xy 316.960694 -31.011908) (xy 316.952866 -30.952452) (xy 316.952376 -30.922468) (xy 306.604895 -30.922468)
			(xy 306.604434 -30.950658) (xy 306.596611 -31.01008) (xy 306.581098 -31.067973) (xy 306.558162 -31.123346)
			(xy 306.528195 -31.175252) (xy 306.491708 -31.222802) (xy 306.449328 -31.265182) (xy 306.401778 -31.301669)
			(xy 306.349872 -31.331636) (xy 306.294499 -31.354572) (xy 306.236606 -31.370085) (xy 306.177184 -31.377908)
			(xy 306.117248 -31.377908) (xy 306.057826 -31.370085) (xy 305.999933 -31.354572) (xy 305.94456 -31.331636)
			(xy 305.892654 -31.301669) (xy 305.845104 -31.265182) (xy 305.802724 -31.222802) (xy 305.766237 -31.175252)
			(xy 305.73627 -31.123346) (xy 305.713334 -31.067973) (xy 305.697821 -31.01008) (xy 305.689998 -30.950658)
			(xy 305.689508 -30.92069) (xy 291.868352 -30.92069) (xy 291.868352 -30.922468) (xy 291.867862 -30.952452)
			(xy 291.860034 -31.011908) (xy 291.844513 -31.069833) (xy 291.821564 -31.125237) (xy 291.79158 -31.177171)
			(xy 291.755074 -31.224747) (xy 291.712669 -31.267152) (xy 291.665093 -31.303658) (xy 291.613159 -31.333642)
			(xy 291.557755 -31.356591) (xy 291.49983 -31.372112) (xy 291.440374 -31.37994) (xy 291.380406 -31.37994)
			(xy 291.32095 -31.372112) (xy 291.263025 -31.356591) (xy 291.207621 -31.333642) (xy 291.155687 -31.303658)
			(xy 291.108111 -31.267152) (xy 291.065706 -31.224747) (xy 291.0292 -31.177171) (xy 290.999216 -31.125237)
			(xy 290.976267 -31.069833) (xy 290.960746 -31.011908) (xy 290.952918 -30.952452) (xy 290.952428 -30.922468)
			(xy 280.604947 -30.922468) (xy 280.604486 -30.950658) (xy 280.596663 -31.01008) (xy 280.58115 -31.067973)
			(xy 280.558214 -31.123346) (xy 280.528247 -31.175252) (xy 280.49176 -31.222802) (xy 280.44938 -31.265182)
			(xy 280.40183 -31.301669) (xy 280.349924 -31.331636) (xy 280.294551 -31.354572) (xy 280.236658 -31.370085)
			(xy 280.177236 -31.377908) (xy 280.1173 -31.377908) (xy 280.057878 -31.370085) (xy 279.999985 -31.354572)
			(xy 279.944612 -31.331636) (xy 279.892706 -31.301669) (xy 279.845156 -31.265182) (xy 279.802776 -31.222802)
			(xy 279.766289 -31.175252) (xy 279.736322 -31.123346) (xy 279.713386 -31.067973) (xy 279.697873 -31.01008)
			(xy 279.69005 -30.950658) (xy 279.68956 -30.92069) (xy 265.868404 -30.92069) (xy 265.868404 -30.922468)
			(xy 265.867914 -30.952452) (xy 265.860086 -31.011908) (xy 265.844565 -31.069833) (xy 265.821616 -31.125237)
			(xy 265.791632 -31.177171) (xy 265.755126 -31.224747) (xy 265.712721 -31.267152) (xy 265.665145 -31.303658)
			(xy 265.613211 -31.333642) (xy 265.557807 -31.356591) (xy 265.499882 -31.372112) (xy 265.440426 -31.37994)
			(xy 265.380458 -31.37994) (xy 265.321002 -31.372112) (xy 265.263077 -31.356591) (xy 265.207673 -31.333642)
			(xy 265.155739 -31.303658) (xy 265.108163 -31.267152) (xy 265.065758 -31.224747) (xy 265.029252 -31.177171)
			(xy 264.999268 -31.125237) (xy 264.976319 -31.069833) (xy 264.960798 -31.011908) (xy 264.95297 -30.952452)
			(xy 264.95248 -30.922468) (xy 254.604999 -30.922468) (xy 254.604538 -30.950658) (xy 254.596715 -31.01008)
			(xy 254.581202 -31.067973) (xy 254.558266 -31.123346) (xy 254.528299 -31.175252) (xy 254.491812 -31.222802)
			(xy 254.449432 -31.265182) (xy 254.401882 -31.301669) (xy 254.349976 -31.331636) (xy 254.294603 -31.354572)
			(xy 254.23671 -31.370085) (xy 254.177288 -31.377908) (xy 254.117352 -31.377908) (xy 254.05793 -31.370085)
			(xy 254.000037 -31.354572) (xy 253.944664 -31.331636) (xy 253.892758 -31.301669) (xy 253.845208 -31.265182)
			(xy 253.802828 -31.222802) (xy 253.766341 -31.175252) (xy 253.736374 -31.123346) (xy 253.713438 -31.067973)
			(xy 253.697925 -31.01008) (xy 253.690102 -30.950658) (xy 253.689612 -30.92069) (xy 239.868456 -30.92069)
			(xy 239.868456 -30.922468) (xy 239.867966 -30.952452) (xy 239.860138 -31.011908) (xy 239.844617 -31.069833)
			(xy 239.821668 -31.125237) (xy 239.791684 -31.177171) (xy 239.755178 -31.224747) (xy 239.712773 -31.267152)
			(xy 239.665197 -31.303658) (xy 239.613263 -31.333642) (xy 239.557859 -31.356591) (xy 239.499934 -31.372112)
			(xy 239.440478 -31.37994) (xy 239.38051 -31.37994) (xy 239.321054 -31.372112) (xy 239.263129 -31.356591)
			(xy 239.207725 -31.333642) (xy 239.155791 -31.303658) (xy 239.108215 -31.267152) (xy 239.06581 -31.224747)
			(xy 239.029304 -31.177171) (xy 238.99932 -31.125237) (xy 238.976371 -31.069833) (xy 238.96085 -31.011908)
			(xy 238.953022 -30.952452) (xy 238.952532 -30.922468) (xy 216.504999 -30.922468) (xy 216.504538 -30.950658)
			(xy 216.496715 -31.01008) (xy 216.481202 -31.067973) (xy 216.458266 -31.123346) (xy 216.428299 -31.175252)
			(xy 216.391812 -31.222802) (xy 216.349432 -31.265182) (xy 216.301882 -31.301669) (xy 216.249976 -31.331636)
			(xy 216.194603 -31.354572) (xy 216.13671 -31.370085) (xy 216.077288 -31.377908) (xy 216.017352 -31.377908)
			(xy 215.95793 -31.370085) (xy 215.900037 -31.354572) (xy 215.844664 -31.331636) (xy 215.792758 -31.301669)
			(xy 215.745208 -31.265182) (xy 215.702828 -31.222802) (xy 215.666341 -31.175252) (xy 215.636374 -31.123346)
			(xy 215.613438 -31.067973) (xy 215.597925 -31.01008) (xy 215.590102 -30.950658) (xy 215.589612 -30.92069)
			(xy 201.768456 -30.92069) (xy 201.768456 -30.922468) (xy 201.767966 -30.952452) (xy 201.760138 -31.011908)
			(xy 201.744617 -31.069833) (xy 201.721668 -31.125237) (xy 201.691684 -31.177171) (xy 201.655178 -31.224747)
			(xy 201.612773 -31.267152) (xy 201.565197 -31.303658) (xy 201.513263 -31.333642) (xy 201.457859 -31.356591)
			(xy 201.399934 -31.372112) (xy 201.340478 -31.37994) (xy 201.28051 -31.37994) (xy 201.221054 -31.372112)
			(xy 201.163129 -31.356591) (xy 201.107725 -31.333642) (xy 201.055791 -31.303658) (xy 201.008215 -31.267152)
			(xy 200.96581 -31.224747) (xy 200.929304 -31.177171) (xy 200.89932 -31.125237) (xy 200.876371 -31.069833)
			(xy 200.86085 -31.011908) (xy 200.853022 -30.952452) (xy 200.852532 -30.922468) (xy 190.505051 -30.922468)
			(xy 190.50459 -30.950658) (xy 190.496767 -31.01008) (xy 190.481254 -31.067973) (xy 190.458318 -31.123346)
			(xy 190.428351 -31.175252) (xy 190.391864 -31.222802) (xy 190.349484 -31.265182) (xy 190.301934 -31.301669)
			(xy 190.250028 -31.331636) (xy 190.194655 -31.354572) (xy 190.136762 -31.370085) (xy 190.07734 -31.377908)
			(xy 190.017404 -31.377908) (xy 189.957982 -31.370085) (xy 189.900089 -31.354572) (xy 189.844716 -31.331636)
			(xy 189.79281 -31.301669) (xy 189.74526 -31.265182) (xy 189.70288 -31.222802) (xy 189.666393 -31.175252)
			(xy 189.636426 -31.123346) (xy 189.61349 -31.067973) (xy 189.597977 -31.01008) (xy 189.590154 -30.950658)
			(xy 189.589664 -30.92069) (xy 175.768508 -30.92069) (xy 175.768508 -30.922468) (xy 175.768018 -30.952452)
			(xy 175.76019 -31.011908) (xy 175.744669 -31.069833) (xy 175.72172 -31.125237) (xy 175.691736 -31.177171)
			(xy 175.65523 -31.224747) (xy 175.612825 -31.267152) (xy 175.565249 -31.303658) (xy 175.513315 -31.333642)
			(xy 175.457911 -31.356591) (xy 175.399986 -31.372112) (xy 175.34053 -31.37994) (xy 175.280562 -31.37994)
			(xy 175.221106 -31.372112) (xy 175.163181 -31.356591) (xy 175.107777 -31.333642) (xy 175.055843 -31.303658)
			(xy 175.008267 -31.267152) (xy 174.965862 -31.224747) (xy 174.929356 -31.177171) (xy 174.899372 -31.125237)
			(xy 174.876423 -31.069833) (xy 174.860902 -31.011908) (xy 174.853074 -30.952452) (xy 174.852584 -30.922468)
			(xy 164.505103 -30.922468) (xy 164.504642 -30.950658) (xy 164.496819 -31.01008) (xy 164.481306 -31.067973)
			(xy 164.45837 -31.123346) (xy 164.428403 -31.175252) (xy 164.391916 -31.222802) (xy 164.349536 -31.265182)
			(xy 164.301986 -31.301669) (xy 164.25008 -31.331636) (xy 164.194707 -31.354572) (xy 164.136814 -31.370085)
			(xy 164.077392 -31.377908) (xy 164.017456 -31.377908) (xy 163.958034 -31.370085) (xy 163.900141 -31.354572)
			(xy 163.844768 -31.331636) (xy 163.792862 -31.301669) (xy 163.745312 -31.265182) (xy 163.702932 -31.222802)
			(xy 163.666445 -31.175252) (xy 163.636478 -31.123346) (xy 163.613542 -31.067973) (xy 163.598029 -31.01008)
			(xy 163.590206 -30.950658) (xy 163.589716 -30.92069) (xy 149.76856 -30.92069) (xy 149.76856 -30.922468)
			(xy 149.76807 -30.952452) (xy 149.760242 -31.011908) (xy 149.744721 -31.069833) (xy 149.721772 -31.125237)
			(xy 149.691788 -31.177171) (xy 149.655282 -31.224747) (xy 149.612877 -31.267152) (xy 149.565301 -31.303658)
			(xy 149.513367 -31.333642) (xy 149.457963 -31.356591) (xy 149.400038 -31.372112) (xy 149.340582 -31.37994)
			(xy 149.280614 -31.37994) (xy 149.221158 -31.372112) (xy 149.163233 -31.356591) (xy 149.107829 -31.333642)
			(xy 149.055895 -31.303658) (xy 149.008319 -31.267152) (xy 148.965914 -31.224747) (xy 148.929408 -31.177171)
			(xy 148.899424 -31.125237) (xy 148.876475 -31.069833) (xy 148.860954 -31.011908) (xy 148.853126 -30.952452)
			(xy 148.852636 -30.922468) (xy 138.505155 -30.922468) (xy 138.504694 -30.950658) (xy 138.496871 -31.01008)
			(xy 138.481358 -31.067973) (xy 138.458422 -31.123346) (xy 138.428455 -31.175252) (xy 138.391968 -31.222802)
			(xy 138.349588 -31.265182) (xy 138.302038 -31.301669) (xy 138.250132 -31.331636) (xy 138.194759 -31.354572)
			(xy 138.136866 -31.370085) (xy 138.077444 -31.377908) (xy 138.017508 -31.377908) (xy 137.958086 -31.370085)
			(xy 137.900193 -31.354572) (xy 137.84482 -31.331636) (xy 137.792914 -31.301669) (xy 137.745364 -31.265182)
			(xy 137.702984 -31.222802) (xy 137.666497 -31.175252) (xy 137.63653 -31.123346) (xy 137.613594 -31.067973)
			(xy 137.598081 -31.01008) (xy 137.590258 -30.950658) (xy 137.589768 -30.92069) (xy 123.768612 -30.92069)
			(xy 123.768612 -30.922468) (xy 123.768122 -30.952452) (xy 123.760294 -31.011908) (xy 123.744773 -31.069833)
			(xy 123.721824 -31.125237) (xy 123.69184 -31.177171) (xy 123.655334 -31.224747) (xy 123.612929 -31.267152)
			(xy 123.565353 -31.303658) (xy 123.513419 -31.333642) (xy 123.458015 -31.356591) (xy 123.40009 -31.372112)
			(xy 123.340634 -31.37994) (xy 123.280666 -31.37994) (xy 123.22121 -31.372112) (xy 123.163285 -31.356591)
			(xy 123.107881 -31.333642) (xy 123.055947 -31.303658) (xy 123.008371 -31.267152) (xy 122.965966 -31.224747)
			(xy 122.92946 -31.177171) (xy 122.899476 -31.125237) (xy 122.876527 -31.069833) (xy 122.861006 -31.011908)
			(xy 122.853178 -30.952452) (xy 122.852688 -30.922468) (xy 100.405155 -30.922468) (xy 100.404694 -30.950674)
			(xy 100.396866 -31.01013) (xy 100.381345 -31.068055) (xy 100.358396 -31.123459) (xy 100.328412 -31.175393)
			(xy 100.291906 -31.222969) (xy 100.249501 -31.265374) (xy 100.201925 -31.30188) (xy 100.149991 -31.331864)
			(xy 100.094587 -31.354813) (xy 100.036662 -31.370334) (xy 99.977206 -31.378162) (xy 99.917238 -31.378162)
			(xy 99.857782 -31.370334) (xy 99.799857 -31.354813) (xy 99.744453 -31.331864) (xy 99.692519 -31.30188)
			(xy 99.644943 -31.265374) (xy 99.602538 -31.222969) (xy 99.566032 -31.175393) (xy 99.536048 -31.123459)
			(xy 99.513099 -31.068055) (xy 99.497578 -31.01013) (xy 99.48975 -30.950674) (xy 99.48926 -30.92069)
			(xy 85.668104 -30.92069) (xy 85.668104 -30.922468) (xy 85.667614 -30.952436) (xy 85.659791 -31.011858)
			(xy 85.644278 -31.069751) (xy 85.621342 -31.125124) (xy 85.591375 -31.17703) (xy 85.554888 -31.22458)
			(xy 85.512508 -31.26696) (xy 85.464958 -31.303447) (xy 85.413052 -31.333414) (xy 85.357679 -31.35635)
			(xy 85.299786 -31.371863) (xy 85.240364 -31.379686) (xy 85.180428 -31.379686) (xy 85.121006 -31.371863)
			(xy 85.063113 -31.35635) (xy 85.00774 -31.333414) (xy 84.955834 -31.303447) (xy 84.908284 -31.26696)
			(xy 84.865904 -31.22458) (xy 84.829417 -31.17703) (xy 84.79945 -31.125124) (xy 84.776514 -31.069751)
			(xy 84.761001 -31.011858) (xy 84.753178 -30.952436) (xy 84.752688 -30.922468) (xy 74.405207 -30.922468)
			(xy 74.404746 -30.950674) (xy 74.396918 -31.01013) (xy 74.381397 -31.068055) (xy 74.358448 -31.123459)
			(xy 74.328464 -31.175393) (xy 74.291958 -31.222969) (xy 74.249553 -31.265374) (xy 74.201977 -31.30188)
			(xy 74.150043 -31.331864) (xy 74.094639 -31.354813) (xy 74.036714 -31.370334) (xy 73.977258 -31.378162)
			(xy 73.91729 -31.378162) (xy 73.857834 -31.370334) (xy 73.799909 -31.354813) (xy 73.744505 -31.331864)
			(xy 73.692571 -31.30188) (xy 73.644995 -31.265374) (xy 73.60259 -31.222969) (xy 73.566084 -31.175393)
			(xy 73.5361 -31.123459) (xy 73.513151 -31.068055) (xy 73.49763 -31.01013) (xy 73.489802 -30.950674)
			(xy 73.489312 -30.92069) (xy 59.668156 -30.92069) (xy 59.668156 -30.922468) (xy 59.667666 -30.952436)
			(xy 59.659843 -31.011858) (xy 59.64433 -31.069751) (xy 59.621394 -31.125124) (xy 59.591427 -31.17703)
			(xy 59.55494 -31.22458) (xy 59.51256 -31.26696) (xy 59.46501 -31.303447) (xy 59.413104 -31.333414)
			(xy 59.357731 -31.35635) (xy 59.299838 -31.371863) (xy 59.240416 -31.379686) (xy 59.18048 -31.379686)
			(xy 59.121058 -31.371863) (xy 59.063165 -31.35635) (xy 59.007792 -31.333414) (xy 58.955886 -31.303447)
			(xy 58.908336 -31.26696) (xy 58.865956 -31.22458) (xy 58.829469 -31.17703) (xy 58.799502 -31.125124)
			(xy 58.776566 -31.069751) (xy 58.761053 -31.011858) (xy 58.75323 -30.952436) (xy 58.75274 -30.922468)
			(xy 48.405259 -30.922468) (xy 48.404798 -30.950674) (xy 48.39697 -31.01013) (xy 48.381449 -31.068055)
			(xy 48.3585 -31.123459) (xy 48.328516 -31.175393) (xy 48.29201 -31.222969) (xy 48.249605 -31.265374)
			(xy 48.202029 -31.30188) (xy 48.150095 -31.331864) (xy 48.094691 -31.354813) (xy 48.036766 -31.370334)
			(xy 47.97731 -31.378162) (xy 47.917342 -31.378162) (xy 47.857886 -31.370334) (xy 47.799961 -31.354813)
			(xy 47.744557 -31.331864) (xy 47.692623 -31.30188) (xy 47.645047 -31.265374) (xy 47.602642 -31.222969)
			(xy 47.566136 -31.175393) (xy 47.536152 -31.123459) (xy 47.513203 -31.068055) (xy 47.497682 -31.01013)
			(xy 47.489854 -30.950674) (xy 47.489364 -30.92069) (xy 33.668208 -30.92069) (xy 33.668208 -30.922468)
			(xy 33.667718 -30.952436) (xy 33.659895 -31.011858) (xy 33.644382 -31.069751) (xy 33.621446 -31.125124)
			(xy 33.591479 -31.17703) (xy 33.554992 -31.22458) (xy 33.512612 -31.26696) (xy 33.465062 -31.303447)
			(xy 33.413156 -31.333414) (xy 33.357783 -31.35635) (xy 33.29989 -31.371863) (xy 33.240468 -31.379686)
			(xy 33.180532 -31.379686) (xy 33.12111 -31.371863) (xy 33.063217 -31.35635) (xy 33.007844 -31.333414)
			(xy 32.955938 -31.303447) (xy 32.908388 -31.26696) (xy 32.866008 -31.22458) (xy 32.829521 -31.17703)
			(xy 32.799554 -31.125124) (xy 32.776618 -31.069751) (xy 32.761105 -31.011858) (xy 32.753282 -30.952436)
			(xy 32.752792 -30.922468) (xy 22.405311 -30.922468) (xy 22.40485 -30.950674) (xy 22.397022 -31.01013)
			(xy 22.381501 -31.068055) (xy 22.358552 -31.123459) (xy 22.328568 -31.175393) (xy 22.292062 -31.222969)
			(xy 22.249657 -31.265374) (xy 22.202081 -31.30188) (xy 22.150147 -31.331864) (xy 22.094743 -31.354813)
			(xy 22.036818 -31.370334) (xy 21.977362 -31.378162) (xy 21.917394 -31.378162) (xy 21.857938 -31.370334)
			(xy 21.800013 -31.354813) (xy 21.744609 -31.331864) (xy 21.692675 -31.30188) (xy 21.645099 -31.265374)
			(xy 21.602694 -31.222969) (xy 21.566188 -31.175393) (xy 21.536204 -31.123459) (xy 21.513255 -31.068055)
			(xy 21.497734 -31.01013) (xy 21.489906 -30.950674) (xy 21.489416 -30.92069) (xy 7.66826 -30.92069)
			(xy 7.66826 -30.922468) (xy 7.66777 -30.952436) (xy 7.659947 -31.011858) (xy 7.644434 -31.069751)
			(xy 7.621498 -31.125124) (xy 7.591531 -31.17703) (xy 7.555044 -31.22458) (xy 7.512664 -31.26696)
			(xy 7.465114 -31.303447) (xy 7.413208 -31.333414) (xy 7.357835 -31.35635) (xy 7.299942 -31.371863)
			(xy 7.24052 -31.379686) (xy 7.180584 -31.379686) (xy 7.121162 -31.371863) (xy 7.063269 -31.35635)
			(xy 7.007896 -31.333414) (xy 6.95599 -31.303447) (xy 6.90844 -31.26696) (xy 6.86606 -31.22458) (xy 6.829573 -31.17703)
			(xy 6.799606 -31.125124) (xy 6.77667 -31.069751) (xy 6.761157 -31.011858) (xy 6.753334 -30.952436)
			(xy 6.752844 -30.922468) (xy 0.509016 -30.922468) (xy 0.509016 -32.722312) (xy 8.607044 -32.722312)
			(xy 8.607044 -31.858712) (xy 8.607534 -31.828744) (xy 8.615357 -31.769322) (xy 8.63087 -31.711429)
			(xy 8.653806 -31.656056) (xy 8.683773 -31.60415) (xy 8.72026 -31.5566) (xy 8.76264 -31.51422) (xy 8.81019 -31.477733)
			(xy 8.862096 -31.447766) (xy 8.917469 -31.42483) (xy 8.975362 -31.409317) (xy 9.034784 -31.401494)
			(xy 9.09472 -31.401494) (xy 9.154142 -31.409317) (xy 9.212035 -31.42483) (xy 9.267408 -31.447766)
			(xy 9.319314 -31.477733) (xy 9.366864 -31.51422) (xy 9.409244 -31.5566) (xy 9.445731 -31.60415) (xy 9.475698 -31.656056)
			(xy 9.498634 -31.711429) (xy 9.514147 -31.769322) (xy 9.52197 -31.828744) (xy 9.52246 -31.858712)
			(xy 9.52246 -32.714184) (xy 18.847308 -32.714184) (xy 18.847308 -31.850584) (xy 18.847798 -31.8206)
			(xy 18.855626 -31.761144) (xy 18.871147 -31.703219) (xy 18.894096 -31.647815) (xy 18.92408 -31.595881)
			(xy 18.960586 -31.548305) (xy 19.002991 -31.5059) (xy 19.050567 -31.469394) (xy 19.102501 -31.43941)
			(xy 19.157905 -31.416461) (xy 19.21583 -31.40094) (xy 19.275286 -31.393112) (xy 19.335254 -31.393112)
			(xy 19.39471 -31.40094) (xy 19.452635 -31.416461) (xy 19.508039 -31.43941) (xy 19.559973 -31.469394)
			(xy 19.607549 -31.5059) (xy 19.649954 -31.548305) (xy 19.68646 -31.595881) (xy 19.716444 -31.647815)
			(xy 19.739393 -31.703219) (xy 19.754914 -31.761144) (xy 19.762742 -31.8206) (xy 19.763232 -31.850584)
			(xy 19.763232 -32.714184) (xy 19.763099 -32.722312) (xy 34.606992 -32.722312) (xy 34.606992 -31.858712)
			(xy 34.607482 -31.828744) (xy 34.615305 -31.769322) (xy 34.630818 -31.711429) (xy 34.653754 -31.656056)
			(xy 34.683721 -31.60415) (xy 34.720208 -31.5566) (xy 34.762588 -31.51422) (xy 34.810138 -31.477733)
			(xy 34.862044 -31.447766) (xy 34.917417 -31.42483) (xy 34.97531 -31.409317) (xy 35.034732 -31.401494)
			(xy 35.094668 -31.401494) (xy 35.15409 -31.409317) (xy 35.211983 -31.42483) (xy 35.267356 -31.447766)
			(xy 35.319262 -31.477733) (xy 35.366812 -31.51422) (xy 35.409192 -31.5566) (xy 35.445679 -31.60415)
			(xy 35.475646 -31.656056) (xy 35.498582 -31.711429) (xy 35.514095 -31.769322) (xy 35.521918 -31.828744)
			(xy 35.522408 -31.858712) (xy 35.522408 -32.714184) (xy 44.847256 -32.714184) (xy 44.847256 -31.850584)
			(xy 44.847746 -31.8206) (xy 44.855574 -31.761144) (xy 44.871095 -31.703219) (xy 44.894044 -31.647815)
			(xy 44.924028 -31.595881) (xy 44.960534 -31.548305) (xy 45.002939 -31.5059) (xy 45.050515 -31.469394)
			(xy 45.102449 -31.43941) (xy 45.157853 -31.416461) (xy 45.215778 -31.40094) (xy 45.275234 -31.393112)
			(xy 45.335202 -31.393112) (xy 45.394658 -31.40094) (xy 45.452583 -31.416461) (xy 45.507987 -31.43941)
			(xy 45.559921 -31.469394) (xy 45.607497 -31.5059) (xy 45.649902 -31.548305) (xy 45.686408 -31.595881)
			(xy 45.716392 -31.647815) (xy 45.739341 -31.703219) (xy 45.754862 -31.761144) (xy 45.76269 -31.8206)
			(xy 45.76318 -31.850584) (xy 45.76318 -32.714184) (xy 45.763047 -32.722312) (xy 60.60694 -32.722312)
			(xy 60.60694 -31.858712) (xy 60.60743 -31.828744) (xy 60.615253 -31.769322) (xy 60.630766 -31.711429)
			(xy 60.653702 -31.656056) (xy 60.683669 -31.60415) (xy 60.720156 -31.5566) (xy 60.762536 -31.51422)
			(xy 60.810086 -31.477733) (xy 60.861992 -31.447766) (xy 60.917365 -31.42483) (xy 60.975258 -31.409317)
			(xy 61.03468 -31.401494) (xy 61.094616 -31.401494) (xy 61.154038 -31.409317) (xy 61.211931 -31.42483)
			(xy 61.267304 -31.447766) (xy 61.31921 -31.477733) (xy 61.36676 -31.51422) (xy 61.40914 -31.5566)
			(xy 61.445627 -31.60415) (xy 61.475594 -31.656056) (xy 61.49853 -31.711429) (xy 61.514043 -31.769322)
			(xy 61.521866 -31.828744) (xy 61.522356 -31.858712) (xy 61.522356 -32.714184) (xy 70.847204 -32.714184)
			(xy 70.847204 -31.850584) (xy 70.847694 -31.8206) (xy 70.855522 -31.761144) (xy 70.871043 -31.703219)
			(xy 70.893992 -31.647815) (xy 70.923976 -31.595881) (xy 70.960482 -31.548305) (xy 71.002887 -31.5059)
			(xy 71.050463 -31.469394) (xy 71.102397 -31.43941) (xy 71.157801 -31.416461) (xy 71.215726 -31.40094)
			(xy 71.275182 -31.393112) (xy 71.33515 -31.393112) (xy 71.394606 -31.40094) (xy 71.452531 -31.416461)
			(xy 71.507935 -31.43941) (xy 71.559869 -31.469394) (xy 71.607445 -31.5059) (xy 71.64985 -31.548305)
			(xy 71.686356 -31.595881) (xy 71.71634 -31.647815) (xy 71.739289 -31.703219) (xy 71.75481 -31.761144)
			(xy 71.762638 -31.8206) (xy 71.763128 -31.850584) (xy 71.763128 -32.714184) (xy 71.762995 -32.722312)
			(xy 86.606888 -32.722312) (xy 86.606888 -31.858712) (xy 86.607378 -31.828744) (xy 86.615201 -31.769322)
			(xy 86.630714 -31.711429) (xy 86.65365 -31.656056) (xy 86.683617 -31.60415) (xy 86.720104 -31.5566)
			(xy 86.762484 -31.51422) (xy 86.810034 -31.477733) (xy 86.86194 -31.447766) (xy 86.917313 -31.42483)
			(xy 86.975206 -31.409317) (xy 87.034628 -31.401494) (xy 87.094564 -31.401494) (xy 87.153986 -31.409317)
			(xy 87.211879 -31.42483) (xy 87.267252 -31.447766) (xy 87.319158 -31.477733) (xy 87.366708 -31.51422)
			(xy 87.409088 -31.5566) (xy 87.445575 -31.60415) (xy 87.475542 -31.656056) (xy 87.498478 -31.711429)
			(xy 87.513991 -31.769322) (xy 87.521814 -31.828744) (xy 87.522304 -31.858712) (xy 87.522304 -32.714184)
			(xy 96.847152 -32.714184) (xy 96.847152 -31.850584) (xy 96.847642 -31.8206) (xy 96.85547 -31.761144)
			(xy 96.870991 -31.703219) (xy 96.89394 -31.647815) (xy 96.923924 -31.595881) (xy 96.96043 -31.548305)
			(xy 97.002835 -31.5059) (xy 97.050411 -31.469394) (xy 97.102345 -31.43941) (xy 97.157749 -31.416461)
			(xy 97.215674 -31.40094) (xy 97.27513 -31.393112) (xy 97.335098 -31.393112) (xy 97.394554 -31.40094)
			(xy 97.452479 -31.416461) (xy 97.507883 -31.43941) (xy 97.559817 -31.469394) (xy 97.607393 -31.5059)
			(xy 97.649798 -31.548305) (xy 97.686304 -31.595881) (xy 97.716288 -31.647815) (xy 97.739237 -31.703219)
			(xy 97.754758 -31.761144) (xy 97.762586 -31.8206) (xy 97.763076 -31.850584) (xy 97.763076 -32.714184)
			(xy 97.762943 -32.722312) (xy 124.706888 -32.722312) (xy 124.706888 -31.858712) (xy 124.707378 -31.828728)
			(xy 124.715206 -31.769272) (xy 124.730727 -31.711347) (xy 124.753676 -31.655943) (xy 124.78366 -31.604009)
			(xy 124.820166 -31.556433) (xy 124.862571 -31.514028) (xy 124.910147 -31.477522) (xy 124.962081 -31.447538)
			(xy 125.017485 -31.424589) (xy 125.07541 -31.409068) (xy 125.134866 -31.40124) (xy 125.194834 -31.40124)
			(xy 125.25429 -31.409068) (xy 125.312215 -31.424589) (xy 125.367619 -31.447538) (xy 125.419553 -31.477522)
			(xy 125.467129 -31.514028) (xy 125.509534 -31.556433) (xy 125.54604 -31.604009) (xy 125.576024 -31.655943)
			(xy 125.598973 -31.711347) (xy 125.614494 -31.769272) (xy 125.622322 -31.828728) (xy 125.622812 -31.858712)
			(xy 125.622812 -32.714184) (xy 134.94766 -32.714184) (xy 134.94766 -31.850584) (xy 134.94815 -31.820616)
			(xy 134.955973 -31.761194) (xy 134.971486 -31.703301) (xy 134.994422 -31.647928) (xy 135.024389 -31.596022)
			(xy 135.060876 -31.548472) (xy 135.103256 -31.506092) (xy 135.150806 -31.469605) (xy 135.202712 -31.439638)
			(xy 135.258085 -31.416702) (xy 135.315978 -31.401189) (xy 135.3754 -31.393366) (xy 135.435336 -31.393366)
			(xy 135.494758 -31.401189) (xy 135.552651 -31.416702) (xy 135.608024 -31.439638) (xy 135.65993 -31.469605)
			(xy 135.70748 -31.506092) (xy 135.74986 -31.548472) (xy 135.786347 -31.596022) (xy 135.816314 -31.647928)
			(xy 135.83925 -31.703301) (xy 135.854763 -31.761194) (xy 135.862586 -31.820616) (xy 135.863076 -31.850584)
			(xy 135.863076 -32.714184) (xy 135.862943 -32.722312) (xy 150.706836 -32.722312) (xy 150.706836 -31.858712)
			(xy 150.707326 -31.828728) (xy 150.715154 -31.769272) (xy 150.730675 -31.711347) (xy 150.753624 -31.655943)
			(xy 150.783608 -31.604009) (xy 150.820114 -31.556433) (xy 150.862519 -31.514028) (xy 150.910095 -31.477522)
			(xy 150.962029 -31.447538) (xy 151.017433 -31.424589) (xy 151.075358 -31.409068) (xy 151.134814 -31.40124)
			(xy 151.194782 -31.40124) (xy 151.254238 -31.409068) (xy 151.312163 -31.424589) (xy 151.367567 -31.447538)
			(xy 151.419501 -31.477522) (xy 151.467077 -31.514028) (xy 151.509482 -31.556433) (xy 151.545988 -31.604009)
			(xy 151.575972 -31.655943) (xy 151.598921 -31.711347) (xy 151.614442 -31.769272) (xy 151.62227 -31.828728)
			(xy 151.62276 -31.858712) (xy 151.62276 -32.714184) (xy 160.947608 -32.714184) (xy 160.947608 -31.850584)
			(xy 160.948098 -31.820616) (xy 160.955921 -31.761194) (xy 160.971434 -31.703301) (xy 160.99437 -31.647928)
			(xy 161.024337 -31.596022) (xy 161.060824 -31.548472) (xy 161.103204 -31.506092) (xy 161.150754 -31.469605)
			(xy 161.20266 -31.439638) (xy 161.258033 -31.416702) (xy 161.315926 -31.401189) (xy 161.375348 -31.393366)
			(xy 161.435284 -31.393366) (xy 161.494706 -31.401189) (xy 161.552599 -31.416702) (xy 161.607972 -31.439638)
			(xy 161.659878 -31.469605) (xy 161.707428 -31.506092) (xy 161.749808 -31.548472) (xy 161.786295 -31.596022)
			(xy 161.816262 -31.647928) (xy 161.839198 -31.703301) (xy 161.854711 -31.761194) (xy 161.862534 -31.820616)
			(xy 161.863024 -31.850584) (xy 161.863024 -32.714184) (xy 161.862891 -32.722312) (xy 176.706784 -32.722312)
			(xy 176.706784 -31.858712) (xy 176.707274 -31.828728) (xy 176.715102 -31.769272) (xy 176.730623 -31.711347)
			(xy 176.753572 -31.655943) (xy 176.783556 -31.604009) (xy 176.820062 -31.556433) (xy 176.862467 -31.514028)
			(xy 176.910043 -31.477522) (xy 176.961977 -31.447538) (xy 177.017381 -31.424589) (xy 177.075306 -31.409068)
			(xy 177.134762 -31.40124) (xy 177.19473 -31.40124) (xy 177.254186 -31.409068) (xy 177.312111 -31.424589)
			(xy 177.367515 -31.447538) (xy 177.419449 -31.477522) (xy 177.467025 -31.514028) (xy 177.50943 -31.556433)
			(xy 177.545936 -31.604009) (xy 177.57592 -31.655943) (xy 177.598869 -31.711347) (xy 177.61439 -31.769272)
			(xy 177.622218 -31.828728) (xy 177.622708 -31.858712) (xy 177.622708 -32.714184) (xy 186.947556 -32.714184)
			(xy 186.947556 -31.850584) (xy 186.948046 -31.820616) (xy 186.955869 -31.761194) (xy 186.971382 -31.703301)
			(xy 186.994318 -31.647928) (xy 187.024285 -31.596022) (xy 187.060772 -31.548472) (xy 187.103152 -31.506092)
			(xy 187.150702 -31.469605) (xy 187.202608 -31.439638) (xy 187.257981 -31.416702) (xy 187.315874 -31.401189)
			(xy 187.375296 -31.393366) (xy 187.435232 -31.393366) (xy 187.494654 -31.401189) (xy 187.552547 -31.416702)
			(xy 187.60792 -31.439638) (xy 187.659826 -31.469605) (xy 187.707376 -31.506092) (xy 187.749756 -31.548472)
			(xy 187.786243 -31.596022) (xy 187.81621 -31.647928) (xy 187.839146 -31.703301) (xy 187.854659 -31.761194)
			(xy 187.862482 -31.820616) (xy 187.862972 -31.850584) (xy 187.862972 -32.714184) (xy 187.862839 -32.722312)
			(xy 202.706732 -32.722312) (xy 202.706732 -31.858712) (xy 202.707222 -31.828728) (xy 202.71505 -31.769272)
			(xy 202.730571 -31.711347) (xy 202.75352 -31.655943) (xy 202.783504 -31.604009) (xy 202.82001 -31.556433)
			(xy 202.862415 -31.514028) (xy 202.909991 -31.477522) (xy 202.961925 -31.447538) (xy 203.017329 -31.424589)
			(xy 203.075254 -31.409068) (xy 203.13471 -31.40124) (xy 203.194678 -31.40124) (xy 203.254134 -31.409068)
			(xy 203.312059 -31.424589) (xy 203.367463 -31.447538) (xy 203.419397 -31.477522) (xy 203.466973 -31.514028)
			(xy 203.509378 -31.556433) (xy 203.545884 -31.604009) (xy 203.575868 -31.655943) (xy 203.598817 -31.711347)
			(xy 203.614338 -31.769272) (xy 203.622166 -31.828728) (xy 203.622656 -31.858712) (xy 203.622656 -32.714184)
			(xy 212.947504 -32.714184) (xy 212.947504 -31.850584) (xy 212.947994 -31.820616) (xy 212.955817 -31.761194)
			(xy 212.97133 -31.703301) (xy 212.994266 -31.647928) (xy 213.024233 -31.596022) (xy 213.06072 -31.548472)
			(xy 213.1031 -31.506092) (xy 213.15065 -31.469605) (xy 213.202556 -31.439638) (xy 213.257929 -31.416702)
			(xy 213.315822 -31.401189) (xy 213.375244 -31.393366) (xy 213.43518 -31.393366) (xy 213.494602 -31.401189)
			(xy 213.552495 -31.416702) (xy 213.607868 -31.439638) (xy 213.659774 -31.469605) (xy 213.707324 -31.506092)
			(xy 213.749704 -31.548472) (xy 213.786191 -31.596022) (xy 213.816158 -31.647928) (xy 213.839094 -31.703301)
			(xy 213.854607 -31.761194) (xy 213.86243 -31.820616) (xy 213.86292 -31.850584) (xy 213.86292 -32.714184)
			(xy 213.862787 -32.722312) (xy 240.806732 -32.722312) (xy 240.806732 -31.858712) (xy 240.807222 -31.828728)
			(xy 240.81505 -31.769272) (xy 240.830571 -31.711347) (xy 240.85352 -31.655943) (xy 240.883504 -31.604009)
			(xy 240.92001 -31.556433) (xy 240.962415 -31.514028) (xy 241.009991 -31.477522) (xy 241.061925 -31.447538)
			(xy 241.117329 -31.424589) (xy 241.175254 -31.409068) (xy 241.23471 -31.40124) (xy 241.294678 -31.40124)
			(xy 241.354134 -31.409068) (xy 241.412059 -31.424589) (xy 241.467463 -31.447538) (xy 241.519397 -31.477522)
			(xy 241.566973 -31.514028) (xy 241.609378 -31.556433) (xy 241.645884 -31.604009) (xy 241.675868 -31.655943)
			(xy 241.698817 -31.711347) (xy 241.714338 -31.769272) (xy 241.722166 -31.828728) (xy 241.722656 -31.858712)
			(xy 241.722656 -32.714184) (xy 251.047504 -32.714184) (xy 251.047504 -31.850584) (xy 251.047994 -31.820616)
			(xy 251.055817 -31.761194) (xy 251.07133 -31.703301) (xy 251.094266 -31.647928) (xy 251.124233 -31.596022)
			(xy 251.16072 -31.548472) (xy 251.2031 -31.506092) (xy 251.25065 -31.469605) (xy 251.302556 -31.439638)
			(xy 251.357929 -31.416702) (xy 251.415822 -31.401189) (xy 251.475244 -31.393366) (xy 251.53518 -31.393366)
			(xy 251.594602 -31.401189) (xy 251.652495 -31.416702) (xy 251.707868 -31.439638) (xy 251.759774 -31.469605)
			(xy 251.807324 -31.506092) (xy 251.849704 -31.548472) (xy 251.886191 -31.596022) (xy 251.916158 -31.647928)
			(xy 251.939094 -31.703301) (xy 251.954607 -31.761194) (xy 251.96243 -31.820616) (xy 251.96292 -31.850584)
			(xy 251.96292 -32.714184) (xy 251.962787 -32.722312) (xy 266.80668 -32.722312) (xy 266.80668 -31.858712)
			(xy 266.80717 -31.828728) (xy 266.814998 -31.769272) (xy 266.830519 -31.711347) (xy 266.853468 -31.655943)
			(xy 266.883452 -31.604009) (xy 266.919958 -31.556433) (xy 266.962363 -31.514028) (xy 267.009939 -31.477522)
			(xy 267.061873 -31.447538) (xy 267.117277 -31.424589) (xy 267.175202 -31.409068) (xy 267.234658 -31.40124)
			(xy 267.294626 -31.40124) (xy 267.354082 -31.409068) (xy 267.412007 -31.424589) (xy 267.467411 -31.447538)
			(xy 267.519345 -31.477522) (xy 267.566921 -31.514028) (xy 267.609326 -31.556433) (xy 267.645832 -31.604009)
			(xy 267.675816 -31.655943) (xy 267.698765 -31.711347) (xy 267.714286 -31.769272) (xy 267.722114 -31.828728)
			(xy 267.722604 -31.858712) (xy 267.722604 -32.714184) (xy 277.047452 -32.714184) (xy 277.047452 -31.850584)
			(xy 277.047942 -31.820616) (xy 277.055765 -31.761194) (xy 277.071278 -31.703301) (xy 277.094214 -31.647928)
			(xy 277.124181 -31.596022) (xy 277.160668 -31.548472) (xy 277.203048 -31.506092) (xy 277.250598 -31.469605)
			(xy 277.302504 -31.439638) (xy 277.357877 -31.416702) (xy 277.41577 -31.401189) (xy 277.475192 -31.393366)
			(xy 277.535128 -31.393366) (xy 277.59455 -31.401189) (xy 277.652443 -31.416702) (xy 277.707816 -31.439638)
			(xy 277.759722 -31.469605) (xy 277.807272 -31.506092) (xy 277.849652 -31.548472) (xy 277.886139 -31.596022)
			(xy 277.916106 -31.647928) (xy 277.939042 -31.703301) (xy 277.954555 -31.761194) (xy 277.962378 -31.820616)
			(xy 277.962868 -31.850584) (xy 277.962868 -32.714184) (xy 277.962735 -32.722312) (xy 292.806628 -32.722312)
			(xy 292.806628 -31.858712) (xy 292.807118 -31.828728) (xy 292.814946 -31.769272) (xy 292.830467 -31.711347)
			(xy 292.853416 -31.655943) (xy 292.8834 -31.604009) (xy 292.919906 -31.556433) (xy 292.962311 -31.514028)
			(xy 293.009887 -31.477522) (xy 293.061821 -31.447538) (xy 293.117225 -31.424589) (xy 293.17515 -31.409068)
			(xy 293.234606 -31.40124) (xy 293.294574 -31.40124) (xy 293.35403 -31.409068) (xy 293.411955 -31.424589)
			(xy 293.467359 -31.447538) (xy 293.519293 -31.477522) (xy 293.566869 -31.514028) (xy 293.609274 -31.556433)
			(xy 293.64578 -31.604009) (xy 293.675764 -31.655943) (xy 293.698713 -31.711347) (xy 293.714234 -31.769272)
			(xy 293.722062 -31.828728) (xy 293.722552 -31.858712) (xy 293.722552 -32.714184) (xy 303.0474 -32.714184)
			(xy 303.0474 -31.850584) (xy 303.04789 -31.820616) (xy 303.055713 -31.761194) (xy 303.071226 -31.703301)
			(xy 303.094162 -31.647928) (xy 303.124129 -31.596022) (xy 303.160616 -31.548472) (xy 303.202996 -31.506092)
			(xy 303.250546 -31.469605) (xy 303.302452 -31.439638) (xy 303.357825 -31.416702) (xy 303.415718 -31.401189)
			(xy 303.47514 -31.393366) (xy 303.535076 -31.393366) (xy 303.594498 -31.401189) (xy 303.652391 -31.416702)
			(xy 303.707764 -31.439638) (xy 303.75967 -31.469605) (xy 303.80722 -31.506092) (xy 303.8496 -31.548472)
			(xy 303.886087 -31.596022) (xy 303.916054 -31.647928) (xy 303.93899 -31.703301) (xy 303.954503 -31.761194)
			(xy 303.962326 -31.820616) (xy 303.962816 -31.850584) (xy 303.962816 -32.714184) (xy 303.962683 -32.722312)
			(xy 318.806576 -32.722312) (xy 318.806576 -31.858712) (xy 318.807066 -31.828728) (xy 318.814894 -31.769272)
			(xy 318.830415 -31.711347) (xy 318.853364 -31.655943) (xy 318.883348 -31.604009) (xy 318.919854 -31.556433)
			(xy 318.962259 -31.514028) (xy 319.009835 -31.477522) (xy 319.061769 -31.447538) (xy 319.117173 -31.424589)
			(xy 319.175098 -31.409068) (xy 319.234554 -31.40124) (xy 319.294522 -31.40124) (xy 319.353978 -31.409068)
			(xy 319.411903 -31.424589) (xy 319.467307 -31.447538) (xy 319.519241 -31.477522) (xy 319.566817 -31.514028)
			(xy 319.609222 -31.556433) (xy 319.645728 -31.604009) (xy 319.675712 -31.655943) (xy 319.698661 -31.711347)
			(xy 319.714182 -31.769272) (xy 319.72201 -31.828728) (xy 319.7225 -31.858712) (xy 319.7225 -32.714184)
			(xy 329.047348 -32.714184) (xy 329.047348 -31.850584) (xy 329.047838 -31.820616) (xy 329.055661 -31.761194)
			(xy 329.071174 -31.703301) (xy 329.09411 -31.647928) (xy 329.124077 -31.596022) (xy 329.160564 -31.548472)
			(xy 329.202944 -31.506092) (xy 329.250494 -31.469605) (xy 329.3024 -31.439638) (xy 329.357773 -31.416702)
			(xy 329.415666 -31.401189) (xy 329.475088 -31.393366) (xy 329.535024 -31.393366) (xy 329.594446 -31.401189)
			(xy 329.652339 -31.416702) (xy 329.707712 -31.439638) (xy 329.759618 -31.469605) (xy 329.807168 -31.506092)
			(xy 329.849548 -31.548472) (xy 329.886035 -31.596022) (xy 329.916002 -31.647928) (xy 329.938938 -31.703301)
			(xy 329.954451 -31.761194) (xy 329.962274 -31.820616) (xy 329.962764 -31.850584) (xy 329.962764 -32.714184)
			(xy 329.962631 -32.722312) (xy 356.907084 -32.722312) (xy 356.907084 -31.858712) (xy 356.907574 -31.828744)
			(xy 356.915397 -31.769322) (xy 356.93091 -31.711429) (xy 356.953846 -31.656056) (xy 356.983813 -31.60415)
			(xy 357.0203 -31.5566) (xy 357.06268 -31.51422) (xy 357.11023 -31.477733) (xy 357.162136 -31.447766)
			(xy 357.217509 -31.42483) (xy 357.275402 -31.409317) (xy 357.334824 -31.401494) (xy 357.39476 -31.401494)
			(xy 357.454182 -31.409317) (xy 357.512075 -31.42483) (xy 357.567448 -31.447766) (xy 357.619354 -31.477733)
			(xy 357.666904 -31.51422) (xy 357.709284 -31.5566) (xy 357.745771 -31.60415) (xy 357.775738 -31.656056)
			(xy 357.798674 -31.711429) (xy 357.814187 -31.769322) (xy 357.82201 -31.828744) (xy 357.8225 -31.858712)
			(xy 357.8225 -32.714184) (xy 367.147348 -32.714184) (xy 367.147348 -31.850584) (xy 367.147838 -31.8206)
			(xy 367.155666 -31.761144) (xy 367.171187 -31.703219) (xy 367.194136 -31.647815) (xy 367.22412 -31.595881)
			(xy 367.260626 -31.548305) (xy 367.303031 -31.5059) (xy 367.350607 -31.469394) (xy 367.402541 -31.43941)
			(xy 367.457945 -31.416461) (xy 367.51587 -31.40094) (xy 367.575326 -31.393112) (xy 367.635294 -31.393112)
			(xy 367.69475 -31.40094) (xy 367.752675 -31.416461) (xy 367.808079 -31.43941) (xy 367.860013 -31.469394)
			(xy 367.907589 -31.5059) (xy 367.949994 -31.548305) (xy 367.9865 -31.595881) (xy 368.016484 -31.647815)
			(xy 368.039433 -31.703219) (xy 368.054954 -31.761144) (xy 368.062782 -31.8206) (xy 368.063272 -31.850584)
			(xy 368.063272 -32.714184) (xy 368.063139 -32.722312) (xy 382.907032 -32.722312) (xy 382.907032 -31.858712)
			(xy 382.907522 -31.828744) (xy 382.915345 -31.769322) (xy 382.930858 -31.711429) (xy 382.953794 -31.656056)
			(xy 382.983761 -31.60415) (xy 383.020248 -31.5566) (xy 383.062628 -31.51422) (xy 383.110178 -31.477733)
			(xy 383.162084 -31.447766) (xy 383.217457 -31.42483) (xy 383.27535 -31.409317) (xy 383.334772 -31.401494)
			(xy 383.394708 -31.401494) (xy 383.45413 -31.409317) (xy 383.512023 -31.42483) (xy 383.567396 -31.447766)
			(xy 383.619302 -31.477733) (xy 383.666852 -31.51422) (xy 383.709232 -31.5566) (xy 383.745719 -31.60415)
			(xy 383.775686 -31.656056) (xy 383.798622 -31.711429) (xy 383.814135 -31.769322) (xy 383.821958 -31.828744)
			(xy 383.822448 -31.858712) (xy 383.822448 -32.714184) (xy 393.147296 -32.714184) (xy 393.147296 -31.850584)
			(xy 393.147786 -31.8206) (xy 393.155614 -31.761144) (xy 393.171135 -31.703219) (xy 393.194084 -31.647815)
			(xy 393.224068 -31.595881) (xy 393.260574 -31.548305) (xy 393.302979 -31.5059) (xy 393.350555 -31.469394)
			(xy 393.402489 -31.43941) (xy 393.457893 -31.416461) (xy 393.515818 -31.40094) (xy 393.575274 -31.393112)
			(xy 393.635242 -31.393112) (xy 393.694698 -31.40094) (xy 393.752623 -31.416461) (xy 393.808027 -31.43941)
			(xy 393.859961 -31.469394) (xy 393.907537 -31.5059) (xy 393.949942 -31.548305) (xy 393.986448 -31.595881)
			(xy 394.016432 -31.647815) (xy 394.039381 -31.703219) (xy 394.054902 -31.761144) (xy 394.06273 -31.8206)
			(xy 394.06322 -31.850584) (xy 394.06322 -32.714184) (xy 394.063087 -32.722312) (xy 408.90698 -32.722312)
			(xy 408.90698 -31.858712) (xy 408.90747 -31.828744) (xy 408.915293 -31.769322) (xy 408.930806 -31.711429)
			(xy 408.953742 -31.656056) (xy 408.983709 -31.60415) (xy 409.020196 -31.5566) (xy 409.062576 -31.51422)
			(xy 409.110126 -31.477733) (xy 409.162032 -31.447766) (xy 409.217405 -31.42483) (xy 409.275298 -31.409317)
			(xy 409.33472 -31.401494) (xy 409.394656 -31.401494) (xy 409.454078 -31.409317) (xy 409.511971 -31.42483)
			(xy 409.567344 -31.447766) (xy 409.61925 -31.477733) (xy 409.6668 -31.51422) (xy 409.70918 -31.5566)
			(xy 409.745667 -31.60415) (xy 409.775634 -31.656056) (xy 409.79857 -31.711429) (xy 409.814083 -31.769322)
			(xy 409.821906 -31.828744) (xy 409.822396 -31.858712) (xy 409.822396 -32.714184) (xy 419.147244 -32.714184)
			(xy 419.147244 -31.850584) (xy 419.147734 -31.8206) (xy 419.155562 -31.761144) (xy 419.171083 -31.703219)
			(xy 419.194032 -31.647815) (xy 419.224016 -31.595881) (xy 419.260522 -31.548305) (xy 419.302927 -31.5059)
			(xy 419.350503 -31.469394) (xy 419.402437 -31.43941) (xy 419.457841 -31.416461) (xy 419.515766 -31.40094)
			(xy 419.575222 -31.393112) (xy 419.63519 -31.393112) (xy 419.694646 -31.40094) (xy 419.752571 -31.416461)
			(xy 419.807975 -31.43941) (xy 419.859909 -31.469394) (xy 419.907485 -31.5059) (xy 419.94989 -31.548305)
			(xy 419.986396 -31.595881) (xy 420.01638 -31.647815) (xy 420.039329 -31.703219) (xy 420.05485 -31.761144)
			(xy 420.062678 -31.8206) (xy 420.063168 -31.850584) (xy 420.063168 -32.714184) (xy 420.063035 -32.722312)
			(xy 434.906928 -32.722312) (xy 434.906928 -31.858712) (xy 434.907418 -31.828744) (xy 434.915241 -31.769322)
			(xy 434.930754 -31.711429) (xy 434.95369 -31.656056) (xy 434.983657 -31.60415) (xy 435.020144 -31.5566)
			(xy 435.062524 -31.51422) (xy 435.110074 -31.477733) (xy 435.16198 -31.447766) (xy 435.217353 -31.42483)
			(xy 435.275246 -31.409317) (xy 435.334668 -31.401494) (xy 435.394604 -31.401494) (xy 435.454026 -31.409317)
			(xy 435.511919 -31.42483) (xy 435.567292 -31.447766) (xy 435.619198 -31.477733) (xy 435.666748 -31.51422)
			(xy 435.709128 -31.5566) (xy 435.745615 -31.60415) (xy 435.775582 -31.656056) (xy 435.798518 -31.711429)
			(xy 435.814031 -31.769322) (xy 435.821854 -31.828744) (xy 435.822344 -31.858712) (xy 435.822344 -32.714184)
			(xy 445.147192 -32.714184) (xy 445.147192 -31.850584) (xy 445.147682 -31.8206) (xy 445.15551 -31.761144)
			(xy 445.171031 -31.703219) (xy 445.19398 -31.647815) (xy 445.223964 -31.595881) (xy 445.26047 -31.548305)
			(xy 445.302875 -31.5059) (xy 445.350451 -31.469394) (xy 445.402385 -31.43941) (xy 445.457789 -31.416461)
			(xy 445.515714 -31.40094) (xy 445.57517 -31.393112) (xy 445.635138 -31.393112) (xy 445.694594 -31.40094)
			(xy 445.752519 -31.416461) (xy 445.807923 -31.43941) (xy 445.859857 -31.469394) (xy 445.907433 -31.5059)
			(xy 445.949838 -31.548305) (xy 445.986344 -31.595881) (xy 446.016328 -31.647815) (xy 446.039277 -31.703219)
			(xy 446.054798 -31.761144) (xy 446.062626 -31.8206) (xy 446.063116 -31.850584) (xy 446.063116 -32.714184)
			(xy 446.062626 -32.744168) (xy 446.054798 -32.803624) (xy 446.039277 -32.861549) (xy 446.016328 -32.916953)
			(xy 445.986344 -32.968887) (xy 445.949838 -33.016463) (xy 445.907433 -33.058868) (xy 445.859857 -33.095374)
			(xy 445.807923 -33.125358) (xy 445.752519 -33.148307) (xy 445.694594 -33.163828) (xy 445.635138 -33.171656)
			(xy 445.57517 -33.171656) (xy 445.515714 -33.163828) (xy 445.457789 -33.148307) (xy 445.402385 -33.125358)
			(xy 445.350451 -33.095374) (xy 445.302875 -33.058868) (xy 445.26047 -33.016463) (xy 445.223964 -32.968887)
			(xy 445.19398 -32.916953) (xy 445.171031 -32.861549) (xy 445.15551 -32.803624) (xy 445.147682 -32.744168)
			(xy 445.147192 -32.714184) (xy 435.822344 -32.714184) (xy 435.822344 -32.722312) (xy 435.821854 -32.75228)
			(xy 435.814031 -32.811702) (xy 435.798518 -32.869595) (xy 435.775582 -32.924968) (xy 435.745615 -32.976874)
			(xy 435.709128 -33.024424) (xy 435.666748 -33.066804) (xy 435.619198 -33.103291) (xy 435.567292 -33.133258)
			(xy 435.511919 -33.156194) (xy 435.454026 -33.171707) (xy 435.394604 -33.17953) (xy 435.334668 -33.17953)
			(xy 435.275246 -33.171707) (xy 435.217353 -33.156194) (xy 435.16198 -33.133258) (xy 435.110074 -33.103291)
			(xy 435.062524 -33.066804) (xy 435.020144 -33.024424) (xy 434.983657 -32.976874) (xy 434.95369 -32.924968)
			(xy 434.930754 -32.869595) (xy 434.915241 -32.811702) (xy 434.907418 -32.75228) (xy 434.906928 -32.722312)
			(xy 420.063035 -32.722312) (xy 420.062678 -32.744168) (xy 420.05485 -32.803624) (xy 420.039329 -32.861549)
			(xy 420.01638 -32.916953) (xy 419.986396 -32.968887) (xy 419.94989 -33.016463) (xy 419.907485 -33.058868)
			(xy 419.859909 -33.095374) (xy 419.807975 -33.125358) (xy 419.752571 -33.148307) (xy 419.694646 -33.163828)
			(xy 419.63519 -33.171656) (xy 419.575222 -33.171656) (xy 419.515766 -33.163828) (xy 419.457841 -33.148307)
			(xy 419.402437 -33.125358) (xy 419.350503 -33.095374) (xy 419.302927 -33.058868) (xy 419.260522 -33.016463)
			(xy 419.224016 -32.968887) (xy 419.194032 -32.916953) (xy 419.171083 -32.861549) (xy 419.155562 -32.803624)
			(xy 419.147734 -32.744168) (xy 419.147244 -32.714184) (xy 409.822396 -32.714184) (xy 409.822396 -32.722312)
			(xy 409.821906 -32.75228) (xy 409.814083 -32.811702) (xy 409.79857 -32.869595) (xy 409.775634 -32.924968)
			(xy 409.745667 -32.976874) (xy 409.70918 -33.024424) (xy 409.6668 -33.066804) (xy 409.61925 -33.103291)
			(xy 409.567344 -33.133258) (xy 409.511971 -33.156194) (xy 409.454078 -33.171707) (xy 409.394656 -33.17953)
			(xy 409.33472 -33.17953) (xy 409.275298 -33.171707) (xy 409.217405 -33.156194) (xy 409.162032 -33.133258)
			(xy 409.110126 -33.103291) (xy 409.062576 -33.066804) (xy 409.020196 -33.024424) (xy 408.983709 -32.976874)
			(xy 408.953742 -32.924968) (xy 408.930806 -32.869595) (xy 408.915293 -32.811702) (xy 408.90747 -32.75228)
			(xy 408.90698 -32.722312) (xy 394.063087 -32.722312) (xy 394.06273 -32.744168) (xy 394.054902 -32.803624)
			(xy 394.039381 -32.861549) (xy 394.016432 -32.916953) (xy 393.986448 -32.968887) (xy 393.949942 -33.016463)
			(xy 393.907537 -33.058868) (xy 393.859961 -33.095374) (xy 393.808027 -33.125358) (xy 393.752623 -33.148307)
			(xy 393.694698 -33.163828) (xy 393.635242 -33.171656) (xy 393.575274 -33.171656) (xy 393.515818 -33.163828)
			(xy 393.457893 -33.148307) (xy 393.402489 -33.125358) (xy 393.350555 -33.095374) (xy 393.302979 -33.058868)
			(xy 393.260574 -33.016463) (xy 393.224068 -32.968887) (xy 393.194084 -32.916953) (xy 393.171135 -32.861549)
			(xy 393.155614 -32.803624) (xy 393.147786 -32.744168) (xy 393.147296 -32.714184) (xy 383.822448 -32.714184)
			(xy 383.822448 -32.722312) (xy 383.821958 -32.75228) (xy 383.814135 -32.811702) (xy 383.798622 -32.869595)
			(xy 383.775686 -32.924968) (xy 383.745719 -32.976874) (xy 383.709232 -33.024424) (xy 383.666852 -33.066804)
			(xy 383.619302 -33.103291) (xy 383.567396 -33.133258) (xy 383.512023 -33.156194) (xy 383.45413 -33.171707)
			(xy 383.394708 -33.17953) (xy 383.334772 -33.17953) (xy 383.27535 -33.171707) (xy 383.217457 -33.156194)
			(xy 383.162084 -33.133258) (xy 383.110178 -33.103291) (xy 383.062628 -33.066804) (xy 383.020248 -33.024424)
			(xy 382.983761 -32.976874) (xy 382.953794 -32.924968) (xy 382.930858 -32.869595) (xy 382.915345 -32.811702)
			(xy 382.907522 -32.75228) (xy 382.907032 -32.722312) (xy 368.063139 -32.722312) (xy 368.062782 -32.744168)
			(xy 368.054954 -32.803624) (xy 368.039433 -32.861549) (xy 368.016484 -32.916953) (xy 367.9865 -32.968887)
			(xy 367.949994 -33.016463) (xy 367.907589 -33.058868) (xy 367.860013 -33.095374) (xy 367.808079 -33.125358)
			(xy 367.752675 -33.148307) (xy 367.69475 -33.163828) (xy 367.635294 -33.171656) (xy 367.575326 -33.171656)
			(xy 367.51587 -33.163828) (xy 367.457945 -33.148307) (xy 367.402541 -33.125358) (xy 367.350607 -33.095374)
			(xy 367.303031 -33.058868) (xy 367.260626 -33.016463) (xy 367.22412 -32.968887) (xy 367.194136 -32.916953)
			(xy 367.171187 -32.861549) (xy 367.155666 -32.803624) (xy 367.147838 -32.744168) (xy 367.147348 -32.714184)
			(xy 357.8225 -32.714184) (xy 357.8225 -32.722312) (xy 357.82201 -32.75228) (xy 357.814187 -32.811702)
			(xy 357.798674 -32.869595) (xy 357.775738 -32.924968) (xy 357.745771 -32.976874) (xy 357.709284 -33.024424)
			(xy 357.666904 -33.066804) (xy 357.619354 -33.103291) (xy 357.567448 -33.133258) (xy 357.512075 -33.156194)
			(xy 357.454182 -33.171707) (xy 357.39476 -33.17953) (xy 357.334824 -33.17953) (xy 357.275402 -33.171707)
			(xy 357.217509 -33.156194) (xy 357.162136 -33.133258) (xy 357.11023 -33.103291) (xy 357.06268 -33.066804)
			(xy 357.0203 -33.024424) (xy 356.983813 -32.976874) (xy 356.953846 -32.924968) (xy 356.93091 -32.869595)
			(xy 356.915397 -32.811702) (xy 356.907574 -32.75228) (xy 356.907084 -32.722312) (xy 329.962631 -32.722312)
			(xy 329.962274 -32.744152) (xy 329.954451 -32.803574) (xy 329.938938 -32.861467) (xy 329.916002 -32.91684)
			(xy 329.886035 -32.968746) (xy 329.849548 -33.016296) (xy 329.807168 -33.058676) (xy 329.759618 -33.095163)
			(xy 329.707712 -33.12513) (xy 329.652339 -33.148066) (xy 329.594446 -33.163579) (xy 329.535024 -33.171402)
			(xy 329.475088 -33.171402) (xy 329.415666 -33.163579) (xy 329.357773 -33.148066) (xy 329.3024 -33.12513)
			(xy 329.250494 -33.095163) (xy 329.202944 -33.058676) (xy 329.160564 -33.016296) (xy 329.124077 -32.968746)
			(xy 329.09411 -32.91684) (xy 329.071174 -32.861467) (xy 329.055661 -32.803574) (xy 329.047838 -32.744152)
			(xy 329.047348 -32.714184) (xy 319.7225 -32.714184) (xy 319.7225 -32.722312) (xy 319.72201 -32.752296)
			(xy 319.714182 -32.811752) (xy 319.698661 -32.869677) (xy 319.675712 -32.925081) (xy 319.645728 -32.977015)
			(xy 319.609222 -33.024591) (xy 319.566817 -33.066996) (xy 319.519241 -33.103502) (xy 319.467307 -33.133486)
			(xy 319.411903 -33.156435) (xy 319.353978 -33.171956) (xy 319.294522 -33.179784) (xy 319.234554 -33.179784)
			(xy 319.175098 -33.171956) (xy 319.117173 -33.156435) (xy 319.061769 -33.133486) (xy 319.009835 -33.103502)
			(xy 318.962259 -33.066996) (xy 318.919854 -33.024591) (xy 318.883348 -32.977015) (xy 318.853364 -32.925081)
			(xy 318.830415 -32.869677) (xy 318.814894 -32.811752) (xy 318.807066 -32.752296) (xy 318.806576 -32.722312)
			(xy 303.962683 -32.722312) (xy 303.962326 -32.744152) (xy 303.954503 -32.803574) (xy 303.93899 -32.861467)
			(xy 303.916054 -32.91684) (xy 303.886087 -32.968746) (xy 303.8496 -33.016296) (xy 303.80722 -33.058676)
			(xy 303.75967 -33.095163) (xy 303.707764 -33.12513) (xy 303.652391 -33.148066) (xy 303.594498 -33.163579)
			(xy 303.535076 -33.171402) (xy 303.47514 -33.171402) (xy 303.415718 -33.163579) (xy 303.357825 -33.148066)
			(xy 303.302452 -33.12513) (xy 303.250546 -33.095163) (xy 303.202996 -33.058676) (xy 303.160616 -33.016296)
			(xy 303.124129 -32.968746) (xy 303.094162 -32.91684) (xy 303.071226 -32.861467) (xy 303.055713 -32.803574)
			(xy 303.04789 -32.744152) (xy 303.0474 -32.714184) (xy 293.722552 -32.714184) (xy 293.722552 -32.722312)
			(xy 293.722062 -32.752296) (xy 293.714234 -32.811752) (xy 293.698713 -32.869677) (xy 293.675764 -32.925081)
			(xy 293.64578 -32.977015) (xy 293.609274 -33.024591) (xy 293.566869 -33.066996) (xy 293.519293 -33.103502)
			(xy 293.467359 -33.133486) (xy 293.411955 -33.156435) (xy 293.35403 -33.171956) (xy 293.294574 -33.179784)
			(xy 293.234606 -33.179784) (xy 293.17515 -33.171956) (xy 293.117225 -33.156435) (xy 293.061821 -33.133486)
			(xy 293.009887 -33.103502) (xy 292.962311 -33.066996) (xy 292.919906 -33.024591) (xy 292.8834 -32.977015)
			(xy 292.853416 -32.925081) (xy 292.830467 -32.869677) (xy 292.814946 -32.811752) (xy 292.807118 -32.752296)
			(xy 292.806628 -32.722312) (xy 277.962735 -32.722312) (xy 277.962378 -32.744152) (xy 277.954555 -32.803574)
			(xy 277.939042 -32.861467) (xy 277.916106 -32.91684) (xy 277.886139 -32.968746) (xy 277.849652 -33.016296)
			(xy 277.807272 -33.058676) (xy 277.759722 -33.095163) (xy 277.707816 -33.12513) (xy 277.652443 -33.148066)
			(xy 277.59455 -33.163579) (xy 277.535128 -33.171402) (xy 277.475192 -33.171402) (xy 277.41577 -33.163579)
			(xy 277.357877 -33.148066) (xy 277.302504 -33.12513) (xy 277.250598 -33.095163) (xy 277.203048 -33.058676)
			(xy 277.160668 -33.016296) (xy 277.124181 -32.968746) (xy 277.094214 -32.91684) (xy 277.071278 -32.861467)
			(xy 277.055765 -32.803574) (xy 277.047942 -32.744152) (xy 277.047452 -32.714184) (xy 267.722604 -32.714184)
			(xy 267.722604 -32.722312) (xy 267.722114 -32.752296) (xy 267.714286 -32.811752) (xy 267.698765 -32.869677)
			(xy 267.675816 -32.925081) (xy 267.645832 -32.977015) (xy 267.609326 -33.024591) (xy 267.566921 -33.066996)
			(xy 267.519345 -33.103502) (xy 267.467411 -33.133486) (xy 267.412007 -33.156435) (xy 267.354082 -33.171956)
			(xy 267.294626 -33.179784) (xy 267.234658 -33.179784) (xy 267.175202 -33.171956) (xy 267.117277 -33.156435)
			(xy 267.061873 -33.133486) (xy 267.009939 -33.103502) (xy 266.962363 -33.066996) (xy 266.919958 -33.024591)
			(xy 266.883452 -32.977015) (xy 266.853468 -32.925081) (xy 266.830519 -32.869677) (xy 266.814998 -32.811752)
			(xy 266.80717 -32.752296) (xy 266.80668 -32.722312) (xy 251.962787 -32.722312) (xy 251.96243 -32.744152)
			(xy 251.954607 -32.803574) (xy 251.939094 -32.861467) (xy 251.916158 -32.91684) (xy 251.886191 -32.968746)
			(xy 251.849704 -33.016296) (xy 251.807324 -33.058676) (xy 251.759774 -33.095163) (xy 251.707868 -33.12513)
			(xy 251.652495 -33.148066) (xy 251.594602 -33.163579) (xy 251.53518 -33.171402) (xy 251.475244 -33.171402)
			(xy 251.415822 -33.163579) (xy 251.357929 -33.148066) (xy 251.302556 -33.12513) (xy 251.25065 -33.095163)
			(xy 251.2031 -33.058676) (xy 251.16072 -33.016296) (xy 251.124233 -32.968746) (xy 251.094266 -32.91684)
			(xy 251.07133 -32.861467) (xy 251.055817 -32.803574) (xy 251.047994 -32.744152) (xy 251.047504 -32.714184)
			(xy 241.722656 -32.714184) (xy 241.722656 -32.722312) (xy 241.722166 -32.752296) (xy 241.714338 -32.811752)
			(xy 241.698817 -32.869677) (xy 241.675868 -32.925081) (xy 241.645884 -32.977015) (xy 241.609378 -33.024591)
			(xy 241.566973 -33.066996) (xy 241.519397 -33.103502) (xy 241.467463 -33.133486) (xy 241.412059 -33.156435)
			(xy 241.354134 -33.171956) (xy 241.294678 -33.179784) (xy 241.23471 -33.179784) (xy 241.175254 -33.171956)
			(xy 241.117329 -33.156435) (xy 241.061925 -33.133486) (xy 241.009991 -33.103502) (xy 240.962415 -33.066996)
			(xy 240.92001 -33.024591) (xy 240.883504 -32.977015) (xy 240.85352 -32.925081) (xy 240.830571 -32.869677)
			(xy 240.81505 -32.811752) (xy 240.807222 -32.752296) (xy 240.806732 -32.722312) (xy 213.862787 -32.722312)
			(xy 213.86243 -32.744152) (xy 213.854607 -32.803574) (xy 213.839094 -32.861467) (xy 213.816158 -32.91684)
			(xy 213.786191 -32.968746) (xy 213.749704 -33.016296) (xy 213.707324 -33.058676) (xy 213.659774 -33.095163)
			(xy 213.607868 -33.12513) (xy 213.552495 -33.148066) (xy 213.494602 -33.163579) (xy 213.43518 -33.171402)
			(xy 213.375244 -33.171402) (xy 213.315822 -33.163579) (xy 213.257929 -33.148066) (xy 213.202556 -33.12513)
			(xy 213.15065 -33.095163) (xy 213.1031 -33.058676) (xy 213.06072 -33.016296) (xy 213.024233 -32.968746)
			(xy 212.994266 -32.91684) (xy 212.97133 -32.861467) (xy 212.955817 -32.803574) (xy 212.947994 -32.744152)
			(xy 212.947504 -32.714184) (xy 203.622656 -32.714184) (xy 203.622656 -32.722312) (xy 203.622166 -32.752296)
			(xy 203.614338 -32.811752) (xy 203.598817 -32.869677) (xy 203.575868 -32.925081) (xy 203.545884 -32.977015)
			(xy 203.509378 -33.024591) (xy 203.466973 -33.066996) (xy 203.419397 -33.103502) (xy 203.367463 -33.133486)
			(xy 203.312059 -33.156435) (xy 203.254134 -33.171956) (xy 203.194678 -33.179784) (xy 203.13471 -33.179784)
			(xy 203.075254 -33.171956) (xy 203.017329 -33.156435) (xy 202.961925 -33.133486) (xy 202.909991 -33.103502)
			(xy 202.862415 -33.066996) (xy 202.82001 -33.024591) (xy 202.783504 -32.977015) (xy 202.75352 -32.925081)
			(xy 202.730571 -32.869677) (xy 202.71505 -32.811752) (xy 202.707222 -32.752296) (xy 202.706732 -32.722312)
			(xy 187.862839 -32.722312) (xy 187.862482 -32.744152) (xy 187.854659 -32.803574) (xy 187.839146 -32.861467)
			(xy 187.81621 -32.91684) (xy 187.786243 -32.968746) (xy 187.749756 -33.016296) (xy 187.707376 -33.058676)
			(xy 187.659826 -33.095163) (xy 187.60792 -33.12513) (xy 187.552547 -33.148066) (xy 187.494654 -33.163579)
			(xy 187.435232 -33.171402) (xy 187.375296 -33.171402) (xy 187.315874 -33.163579) (xy 187.257981 -33.148066)
			(xy 187.202608 -33.12513) (xy 187.150702 -33.095163) (xy 187.103152 -33.058676) (xy 187.060772 -33.016296)
			(xy 187.024285 -32.968746) (xy 186.994318 -32.91684) (xy 186.971382 -32.861467) (xy 186.955869 -32.803574)
			(xy 186.948046 -32.744152) (xy 186.947556 -32.714184) (xy 177.622708 -32.714184) (xy 177.622708 -32.722312)
			(xy 177.622218 -32.752296) (xy 177.61439 -32.811752) (xy 177.598869 -32.869677) (xy 177.57592 -32.925081)
			(xy 177.545936 -32.977015) (xy 177.50943 -33.024591) (xy 177.467025 -33.066996) (xy 177.419449 -33.103502)
			(xy 177.367515 -33.133486) (xy 177.312111 -33.156435) (xy 177.254186 -33.171956) (xy 177.19473 -33.179784)
			(xy 177.134762 -33.179784) (xy 177.075306 -33.171956) (xy 177.017381 -33.156435) (xy 176.961977 -33.133486)
			(xy 176.910043 -33.103502) (xy 176.862467 -33.066996) (xy 176.820062 -33.024591) (xy 176.783556 -32.977015)
			(xy 176.753572 -32.925081) (xy 176.730623 -32.869677) (xy 176.715102 -32.811752) (xy 176.707274 -32.752296)
			(xy 176.706784 -32.722312) (xy 161.862891 -32.722312) (xy 161.862534 -32.744152) (xy 161.854711 -32.803574)
			(xy 161.839198 -32.861467) (xy 161.816262 -32.91684) (xy 161.786295 -32.968746) (xy 161.749808 -33.016296)
			(xy 161.707428 -33.058676) (xy 161.659878 -33.095163) (xy 161.607972 -33.12513) (xy 161.552599 -33.148066)
			(xy 161.494706 -33.163579) (xy 161.435284 -33.171402) (xy 161.375348 -33.171402) (xy 161.315926 -33.163579)
			(xy 161.258033 -33.148066) (xy 161.20266 -33.12513) (xy 161.150754 -33.095163) (xy 161.103204 -33.058676)
			(xy 161.060824 -33.016296) (xy 161.024337 -32.968746) (xy 160.99437 -32.91684) (xy 160.971434 -32.861467)
			(xy 160.955921 -32.803574) (xy 160.948098 -32.744152) (xy 160.947608 -32.714184) (xy 151.62276 -32.714184)
			(xy 151.62276 -32.722312) (xy 151.62227 -32.752296) (xy 151.614442 -32.811752) (xy 151.598921 -32.869677)
			(xy 151.575972 -32.925081) (xy 151.545988 -32.977015) (xy 151.509482 -33.024591) (xy 151.467077 -33.066996)
			(xy 151.419501 -33.103502) (xy 151.367567 -33.133486) (xy 151.312163 -33.156435) (xy 151.254238 -33.171956)
			(xy 151.194782 -33.179784) (xy 151.134814 -33.179784) (xy 151.075358 -33.171956) (xy 151.017433 -33.156435)
			(xy 150.962029 -33.133486) (xy 150.910095 -33.103502) (xy 150.862519 -33.066996) (xy 150.820114 -33.024591)
			(xy 150.783608 -32.977015) (xy 150.753624 -32.925081) (xy 150.730675 -32.869677) (xy 150.715154 -32.811752)
			(xy 150.707326 -32.752296) (xy 150.706836 -32.722312) (xy 135.862943 -32.722312) (xy 135.862586 -32.744152)
			(xy 135.854763 -32.803574) (xy 135.83925 -32.861467) (xy 135.816314 -32.91684) (xy 135.786347 -32.968746)
			(xy 135.74986 -33.016296) (xy 135.70748 -33.058676) (xy 135.65993 -33.095163) (xy 135.608024 -33.12513)
			(xy 135.552651 -33.148066) (xy 135.494758 -33.163579) (xy 135.435336 -33.171402) (xy 135.3754 -33.171402)
			(xy 135.315978 -33.163579) (xy 135.258085 -33.148066) (xy 135.202712 -33.12513) (xy 135.150806 -33.095163)
			(xy 135.103256 -33.058676) (xy 135.060876 -33.016296) (xy 135.024389 -32.968746) (xy 134.994422 -32.91684)
			(xy 134.971486 -32.861467) (xy 134.955973 -32.803574) (xy 134.94815 -32.744152) (xy 134.94766 -32.714184)
			(xy 125.622812 -32.714184) (xy 125.622812 -32.722312) (xy 125.622322 -32.752296) (xy 125.614494 -32.811752)
			(xy 125.598973 -32.869677) (xy 125.576024 -32.925081) (xy 125.54604 -32.977015) (xy 125.509534 -33.024591)
			(xy 125.467129 -33.066996) (xy 125.419553 -33.103502) (xy 125.367619 -33.133486) (xy 125.312215 -33.156435)
			(xy 125.25429 -33.171956) (xy 125.194834 -33.179784) (xy 125.134866 -33.179784) (xy 125.07541 -33.171956)
			(xy 125.017485 -33.156435) (xy 124.962081 -33.133486) (xy 124.910147 -33.103502) (xy 124.862571 -33.066996)
			(xy 124.820166 -33.024591) (xy 124.78366 -32.977015) (xy 124.753676 -32.925081) (xy 124.730727 -32.869677)
			(xy 124.715206 -32.811752) (xy 124.707378 -32.752296) (xy 124.706888 -32.722312) (xy 97.762943 -32.722312)
			(xy 97.762586 -32.744168) (xy 97.754758 -32.803624) (xy 97.739237 -32.861549) (xy 97.716288 -32.916953)
			(xy 97.686304 -32.968887) (xy 97.649798 -33.016463) (xy 97.607393 -33.058868) (xy 97.559817 -33.095374)
			(xy 97.507883 -33.125358) (xy 97.452479 -33.148307) (xy 97.394554 -33.163828) (xy 97.335098 -33.171656)
			(xy 97.27513 -33.171656) (xy 97.215674 -33.163828) (xy 97.157749 -33.148307) (xy 97.102345 -33.125358)
			(xy 97.050411 -33.095374) (xy 97.002835 -33.058868) (xy 96.96043 -33.016463) (xy 96.923924 -32.968887)
			(xy 96.89394 -32.916953) (xy 96.870991 -32.861549) (xy 96.85547 -32.803624) (xy 96.847642 -32.744168)
			(xy 96.847152 -32.714184) (xy 87.522304 -32.714184) (xy 87.522304 -32.722312) (xy 87.521814 -32.75228)
			(xy 87.513991 -32.811702) (xy 87.498478 -32.869595) (xy 87.475542 -32.924968) (xy 87.445575 -32.976874)
			(xy 87.409088 -33.024424) (xy 87.366708 -33.066804) (xy 87.319158 -33.103291) (xy 87.267252 -33.133258)
			(xy 87.211879 -33.156194) (xy 87.153986 -33.171707) (xy 87.094564 -33.17953) (xy 87.034628 -33.17953)
			(xy 86.975206 -33.171707) (xy 86.917313 -33.156194) (xy 86.86194 -33.133258) (xy 86.810034 -33.103291)
			(xy 86.762484 -33.066804) (xy 86.720104 -33.024424) (xy 86.683617 -32.976874) (xy 86.65365 -32.924968)
			(xy 86.630714 -32.869595) (xy 86.615201 -32.811702) (xy 86.607378 -32.75228) (xy 86.606888 -32.722312)
			(xy 71.762995 -32.722312) (xy 71.762638 -32.744168) (xy 71.75481 -32.803624) (xy 71.739289 -32.861549)
			(xy 71.71634 -32.916953) (xy 71.686356 -32.968887) (xy 71.64985 -33.016463) (xy 71.607445 -33.058868)
			(xy 71.559869 -33.095374) (xy 71.507935 -33.125358) (xy 71.452531 -33.148307) (xy 71.394606 -33.163828)
			(xy 71.33515 -33.171656) (xy 71.275182 -33.171656) (xy 71.215726 -33.163828) (xy 71.157801 -33.148307)
			(xy 71.102397 -33.125358) (xy 71.050463 -33.095374) (xy 71.002887 -33.058868) (xy 70.960482 -33.016463)
			(xy 70.923976 -32.968887) (xy 70.893992 -32.916953) (xy 70.871043 -32.861549) (xy 70.855522 -32.803624)
			(xy 70.847694 -32.744168) (xy 70.847204 -32.714184) (xy 61.522356 -32.714184) (xy 61.522356 -32.722312)
			(xy 61.521866 -32.75228) (xy 61.514043 -32.811702) (xy 61.49853 -32.869595) (xy 61.475594 -32.924968)
			(xy 61.445627 -32.976874) (xy 61.40914 -33.024424) (xy 61.36676 -33.066804) (xy 61.31921 -33.103291)
			(xy 61.267304 -33.133258) (xy 61.211931 -33.156194) (xy 61.154038 -33.171707) (xy 61.094616 -33.17953)
			(xy 61.03468 -33.17953) (xy 60.975258 -33.171707) (xy 60.917365 -33.156194) (xy 60.861992 -33.133258)
			(xy 60.810086 -33.103291) (xy 60.762536 -33.066804) (xy 60.720156 -33.024424) (xy 60.683669 -32.976874)
			(xy 60.653702 -32.924968) (xy 60.630766 -32.869595) (xy 60.615253 -32.811702) (xy 60.60743 -32.75228)
			(xy 60.60694 -32.722312) (xy 45.763047 -32.722312) (xy 45.76269 -32.744168) (xy 45.754862 -32.803624)
			(xy 45.739341 -32.861549) (xy 45.716392 -32.916953) (xy 45.686408 -32.968887) (xy 45.649902 -33.016463)
			(xy 45.607497 -33.058868) (xy 45.559921 -33.095374) (xy 45.507987 -33.125358) (xy 45.452583 -33.148307)
			(xy 45.394658 -33.163828) (xy 45.335202 -33.171656) (xy 45.275234 -33.171656) (xy 45.215778 -33.163828)
			(xy 45.157853 -33.148307) (xy 45.102449 -33.125358) (xy 45.050515 -33.095374) (xy 45.002939 -33.058868)
			(xy 44.960534 -33.016463) (xy 44.924028 -32.968887) (xy 44.894044 -32.916953) (xy 44.871095 -32.861549)
			(xy 44.855574 -32.803624) (xy 44.847746 -32.744168) (xy 44.847256 -32.714184) (xy 35.522408 -32.714184)
			(xy 35.522408 -32.722312) (xy 35.521918 -32.75228) (xy 35.514095 -32.811702) (xy 35.498582 -32.869595)
			(xy 35.475646 -32.924968) (xy 35.445679 -32.976874) (xy 35.409192 -33.024424) (xy 35.366812 -33.066804)
			(xy 35.319262 -33.103291) (xy 35.267356 -33.133258) (xy 35.211983 -33.156194) (xy 35.15409 -33.171707)
			(xy 35.094668 -33.17953) (xy 35.034732 -33.17953) (xy 34.97531 -33.171707) (xy 34.917417 -33.156194)
			(xy 34.862044 -33.133258) (xy 34.810138 -33.103291) (xy 34.762588 -33.066804) (xy 34.720208 -33.024424)
			(xy 34.683721 -32.976874) (xy 34.653754 -32.924968) (xy 34.630818 -32.869595) (xy 34.615305 -32.811702)
			(xy 34.607482 -32.75228) (xy 34.606992 -32.722312) (xy 19.763099 -32.722312) (xy 19.762742 -32.744168)
			(xy 19.754914 -32.803624) (xy 19.739393 -32.861549) (xy 19.716444 -32.916953) (xy 19.68646 -32.968887)
			(xy 19.649954 -33.016463) (xy 19.607549 -33.058868) (xy 19.559973 -33.095374) (xy 19.508039 -33.125358)
			(xy 19.452635 -33.148307) (xy 19.39471 -33.163828) (xy 19.335254 -33.171656) (xy 19.275286 -33.171656)
			(xy 19.21583 -33.163828) (xy 19.157905 -33.148307) (xy 19.102501 -33.125358) (xy 19.050567 -33.095374)
			(xy 19.002991 -33.058868) (xy 18.960586 -33.016463) (xy 18.92408 -32.968887) (xy 18.894096 -32.916953)
			(xy 18.871147 -32.861549) (xy 18.855626 -32.803624) (xy 18.847798 -32.744168) (xy 18.847308 -32.714184)
			(xy 9.52246 -32.714184) (xy 9.52246 -32.722312) (xy 9.52197 -32.75228) (xy 9.514147 -32.811702) (xy 9.498634 -32.869595)
			(xy 9.475698 -32.924968) (xy 9.445731 -32.976874) (xy 9.409244 -33.024424) (xy 9.366864 -33.066804)
			(xy 9.319314 -33.103291) (xy 9.267408 -33.133258) (xy 9.212035 -33.156194) (xy 9.154142 -33.171707)
			(xy 9.09472 -33.17953) (xy 9.034784 -33.17953) (xy 8.975362 -33.171707) (xy 8.917469 -33.156194)
			(xy 8.862096 -33.133258) (xy 8.81019 -33.103291) (xy 8.76264 -33.066804) (xy 8.72026 -33.024424)
			(xy 8.683773 -32.976874) (xy 8.653806 -32.924968) (xy 8.63087 -32.869595) (xy 8.615357 -32.811702)
			(xy 8.607534 -32.75228) (xy 8.607044 -32.722312) (xy 0.509016 -32.722312) (xy 0.509016 -34.52241)
			(xy 6.752844 -34.52241) (xy 6.752844 -33.65881) (xy 6.753334 -33.628842) (xy 6.761157 -33.56942)
			(xy 6.77667 -33.511527) (xy 6.799606 -33.456154) (xy 6.829573 -33.404248) (xy 6.86606 -33.356698)
			(xy 6.90844 -33.314318) (xy 6.95599 -33.277831) (xy 7.007896 -33.247864) (xy 7.063269 -33.224928)
			(xy 7.121162 -33.209415) (xy 7.180584 -33.201592) (xy 7.24052 -33.201592) (xy 7.299942 -33.209415)
			(xy 7.357835 -33.224928) (xy 7.413208 -33.247864) (xy 7.465114 -33.277831) (xy 7.512664 -33.314318)
			(xy 7.555044 -33.356698) (xy 7.591531 -33.404248) (xy 7.621498 -33.456154) (xy 7.644434 -33.511527)
			(xy 7.659947 -33.56942) (xy 7.66777 -33.628842) (xy 7.66826 -33.65881) (xy 7.66826 -34.520886) (xy 21.489416 -34.520886)
			(xy 21.489416 -33.657286) (xy 21.489906 -33.627302) (xy 21.497734 -33.567846) (xy 21.513255 -33.509921)
			(xy 21.536204 -33.454517) (xy 21.566188 -33.402583) (xy 21.602694 -33.355007) (xy 21.645099 -33.312602)
			(xy 21.692675 -33.276096) (xy 21.744609 -33.246112) (xy 21.800013 -33.223163) (xy 21.857938 -33.207642)
			(xy 21.917394 -33.199814) (xy 21.977362 -33.199814) (xy 22.036818 -33.207642) (xy 22.094743 -33.223163)
			(xy 22.150147 -33.246112) (xy 22.202081 -33.276096) (xy 22.249657 -33.312602) (xy 22.292062 -33.355007)
			(xy 22.328568 -33.402583) (xy 22.358552 -33.454517) (xy 22.381501 -33.509921) (xy 22.397022 -33.567846)
			(xy 22.40485 -33.627302) (xy 22.40534 -33.657286) (xy 22.40534 -34.520886) (xy 22.405315 -34.52241)
			(xy 32.752792 -34.52241) (xy 32.752792 -33.65881) (xy 32.753282 -33.628842) (xy 32.761105 -33.56942)
			(xy 32.776618 -33.511527) (xy 32.799554 -33.456154) (xy 32.829521 -33.404248) (xy 32.866008 -33.356698)
			(xy 32.908388 -33.314318) (xy 32.955938 -33.277831) (xy 33.007844 -33.247864) (xy 33.063217 -33.224928)
			(xy 33.12111 -33.209415) (xy 33.180532 -33.201592) (xy 33.240468 -33.201592) (xy 33.29989 -33.209415)
			(xy 33.357783 -33.224928) (xy 33.413156 -33.247864) (xy 33.465062 -33.277831) (xy 33.512612 -33.314318)
			(xy 33.554992 -33.356698) (xy 33.591479 -33.404248) (xy 33.621446 -33.456154) (xy 33.644382 -33.511527)
			(xy 33.659895 -33.56942) (xy 33.667718 -33.628842) (xy 33.668208 -33.65881) (xy 33.668208 -34.520886)
			(xy 47.489364 -34.520886) (xy 47.489364 -33.657286) (xy 47.489854 -33.627302) (xy 47.497682 -33.567846)
			(xy 47.513203 -33.509921) (xy 47.536152 -33.454517) (xy 47.566136 -33.402583) (xy 47.602642 -33.355007)
			(xy 47.645047 -33.312602) (xy 47.692623 -33.276096) (xy 47.744557 -33.246112) (xy 47.799961 -33.223163)
			(xy 47.857886 -33.207642) (xy 47.917342 -33.199814) (xy 47.97731 -33.199814) (xy 48.036766 -33.207642)
			(xy 48.094691 -33.223163) (xy 48.150095 -33.246112) (xy 48.202029 -33.276096) (xy 48.249605 -33.312602)
			(xy 48.29201 -33.355007) (xy 48.328516 -33.402583) (xy 48.3585 -33.454517) (xy 48.381449 -33.509921)
			(xy 48.39697 -33.567846) (xy 48.404798 -33.627302) (xy 48.405288 -33.657286) (xy 48.405288 -34.520886)
			(xy 48.405263 -34.52241) (xy 58.75274 -34.52241) (xy 58.75274 -33.65881) (xy 58.75323 -33.628842)
			(xy 58.761053 -33.56942) (xy 58.776566 -33.511527) (xy 58.799502 -33.456154) (xy 58.829469 -33.404248)
			(xy 58.865956 -33.356698) (xy 58.908336 -33.314318) (xy 58.955886 -33.277831) (xy 59.007792 -33.247864)
			(xy 59.063165 -33.224928) (xy 59.121058 -33.209415) (xy 59.18048 -33.201592) (xy 59.240416 -33.201592)
			(xy 59.299838 -33.209415) (xy 59.357731 -33.224928) (xy 59.413104 -33.247864) (xy 59.46501 -33.277831)
			(xy 59.51256 -33.314318) (xy 59.55494 -33.356698) (xy 59.591427 -33.404248) (xy 59.621394 -33.456154)
			(xy 59.64433 -33.511527) (xy 59.659843 -33.56942) (xy 59.667666 -33.628842) (xy 59.668156 -33.65881)
			(xy 59.668156 -34.520886) (xy 73.489312 -34.520886) (xy 73.489312 -33.657286) (xy 73.489802 -33.627302)
			(xy 73.49763 -33.567846) (xy 73.513151 -33.509921) (xy 73.5361 -33.454517) (xy 73.566084 -33.402583)
			(xy 73.60259 -33.355007) (xy 73.644995 -33.312602) (xy 73.692571 -33.276096) (xy 73.744505 -33.246112)
			(xy 73.799909 -33.223163) (xy 73.857834 -33.207642) (xy 73.91729 -33.199814) (xy 73.977258 -33.199814)
			(xy 74.036714 -33.207642) (xy 74.094639 -33.223163) (xy 74.150043 -33.246112) (xy 74.201977 -33.276096)
			(xy 74.249553 -33.312602) (xy 74.291958 -33.355007) (xy 74.328464 -33.402583) (xy 74.358448 -33.454517)
			(xy 74.381397 -33.509921) (xy 74.396918 -33.567846) (xy 74.404746 -33.627302) (xy 74.405236 -33.657286)
			(xy 74.405236 -34.520886) (xy 74.405211 -34.52241) (xy 84.752688 -34.52241) (xy 84.752688 -33.65881)
			(xy 84.753178 -33.628842) (xy 84.761001 -33.56942) (xy 84.776514 -33.511527) (xy 84.79945 -33.456154)
			(xy 84.829417 -33.404248) (xy 84.865904 -33.356698) (xy 84.908284 -33.314318) (xy 84.955834 -33.277831)
			(xy 85.00774 -33.247864) (xy 85.063113 -33.224928) (xy 85.121006 -33.209415) (xy 85.180428 -33.201592)
			(xy 85.240364 -33.201592) (xy 85.299786 -33.209415) (xy 85.357679 -33.224928) (xy 85.413052 -33.247864)
			(xy 85.464958 -33.277831) (xy 85.512508 -33.314318) (xy 85.554888 -33.356698) (xy 85.591375 -33.404248)
			(xy 85.621342 -33.456154) (xy 85.644278 -33.511527) (xy 85.659791 -33.56942) (xy 85.667614 -33.628842)
			(xy 85.668104 -33.65881) (xy 85.668104 -34.520886) (xy 99.48926 -34.520886) (xy 99.48926 -33.657286)
			(xy 99.48975 -33.627302) (xy 99.497578 -33.567846) (xy 99.513099 -33.509921) (xy 99.536048 -33.454517)
			(xy 99.566032 -33.402583) (xy 99.602538 -33.355007) (xy 99.644943 -33.312602) (xy 99.692519 -33.276096)
			(xy 99.744453 -33.246112) (xy 99.799857 -33.223163) (xy 99.857782 -33.207642) (xy 99.917238 -33.199814)
			(xy 99.977206 -33.199814) (xy 100.036662 -33.207642) (xy 100.094587 -33.223163) (xy 100.149991 -33.246112)
			(xy 100.201925 -33.276096) (xy 100.249501 -33.312602) (xy 100.291906 -33.355007) (xy 100.328412 -33.402583)
			(xy 100.358396 -33.454517) (xy 100.381345 -33.509921) (xy 100.396866 -33.567846) (xy 100.404694 -33.627302)
			(xy 100.405184 -33.657286) (xy 100.405184 -34.520886) (xy 100.405159 -34.52241) (xy 122.852688 -34.52241)
			(xy 122.852688 -33.65881) (xy 122.853178 -33.628826) (xy 122.861006 -33.56937) (xy 122.876527 -33.511445)
			(xy 122.899476 -33.456041) (xy 122.92946 -33.404107) (xy 122.965966 -33.356531) (xy 123.008371 -33.314126)
			(xy 123.055947 -33.27762) (xy 123.107881 -33.247636) (xy 123.163285 -33.224687) (xy 123.22121 -33.209166)
			(xy 123.280666 -33.201338) (xy 123.340634 -33.201338) (xy 123.40009 -33.209166) (xy 123.458015 -33.224687)
			(xy 123.513419 -33.247636) (xy 123.565353 -33.27762) (xy 123.612929 -33.314126) (xy 123.655334 -33.356531)
			(xy 123.69184 -33.404107) (xy 123.721824 -33.456041) (xy 123.744773 -33.511445) (xy 123.760294 -33.56937)
			(xy 123.768122 -33.628826) (xy 123.768612 -33.65881) (xy 123.768612 -34.520886) (xy 137.589768 -34.520886)
			(xy 137.589768 -33.657286) (xy 137.590258 -33.627318) (xy 137.598081 -33.567896) (xy 137.613594 -33.510003)
			(xy 137.63653 -33.45463) (xy 137.666497 -33.402724) (xy 137.702984 -33.355174) (xy 137.745364 -33.312794)
			(xy 137.792914 -33.276307) (xy 137.84482 -33.24634) (xy 137.900193 -33.223404) (xy 137.958086 -33.207891)
			(xy 138.017508 -33.200068) (xy 138.077444 -33.200068) (xy 138.136866 -33.207891) (xy 138.194759 -33.223404)
			(xy 138.250132 -33.24634) (xy 138.302038 -33.276307) (xy 138.349588 -33.312794) (xy 138.391968 -33.355174)
			(xy 138.428455 -33.402724) (xy 138.458422 -33.45463) (xy 138.481358 -33.510003) (xy 138.496871 -33.567896)
			(xy 138.504694 -33.627318) (xy 138.505184 -33.657286) (xy 138.505184 -34.520886) (xy 138.505159 -34.52241)
			(xy 148.852636 -34.52241) (xy 148.852636 -33.65881) (xy 148.853126 -33.628826) (xy 148.860954 -33.56937)
			(xy 148.876475 -33.511445) (xy 148.899424 -33.456041) (xy 148.929408 -33.404107) (xy 148.965914 -33.356531)
			(xy 149.008319 -33.314126) (xy 149.055895 -33.27762) (xy 149.107829 -33.247636) (xy 149.163233 -33.224687)
			(xy 149.221158 -33.209166) (xy 149.280614 -33.201338) (xy 149.340582 -33.201338) (xy 149.400038 -33.209166)
			(xy 149.457963 -33.224687) (xy 149.513367 -33.247636) (xy 149.565301 -33.27762) (xy 149.612877 -33.314126)
			(xy 149.655282 -33.356531) (xy 149.691788 -33.404107) (xy 149.721772 -33.456041) (xy 149.744721 -33.511445)
			(xy 149.760242 -33.56937) (xy 149.76807 -33.628826) (xy 149.76856 -33.65881) (xy 149.76856 -34.520886)
			(xy 163.589716 -34.520886) (xy 163.589716 -33.657286) (xy 163.590206 -33.627318) (xy 163.598029 -33.567896)
			(xy 163.613542 -33.510003) (xy 163.636478 -33.45463) (xy 163.666445 -33.402724) (xy 163.702932 -33.355174)
			(xy 163.745312 -33.312794) (xy 163.792862 -33.276307) (xy 163.844768 -33.24634) (xy 163.900141 -33.223404)
			(xy 163.958034 -33.207891) (xy 164.017456 -33.200068) (xy 164.077392 -33.200068) (xy 164.136814 -33.207891)
			(xy 164.194707 -33.223404) (xy 164.25008 -33.24634) (xy 164.301986 -33.276307) (xy 164.349536 -33.312794)
			(xy 164.391916 -33.355174) (xy 164.428403 -33.402724) (xy 164.45837 -33.45463) (xy 164.481306 -33.510003)
			(xy 164.496819 -33.567896) (xy 164.504642 -33.627318) (xy 164.505132 -33.657286) (xy 164.505132 -34.520886)
			(xy 164.505107 -34.52241) (xy 174.852584 -34.52241) (xy 174.852584 -33.65881) (xy 174.853074 -33.628826)
			(xy 174.860902 -33.56937) (xy 174.876423 -33.511445) (xy 174.899372 -33.456041) (xy 174.929356 -33.404107)
			(xy 174.965862 -33.356531) (xy 175.008267 -33.314126) (xy 175.055843 -33.27762) (xy 175.107777 -33.247636)
			(xy 175.163181 -33.224687) (xy 175.221106 -33.209166) (xy 175.280562 -33.201338) (xy 175.34053 -33.201338)
			(xy 175.399986 -33.209166) (xy 175.457911 -33.224687) (xy 175.513315 -33.247636) (xy 175.565249 -33.27762)
			(xy 175.612825 -33.314126) (xy 175.65523 -33.356531) (xy 175.691736 -33.404107) (xy 175.72172 -33.456041)
			(xy 175.744669 -33.511445) (xy 175.76019 -33.56937) (xy 175.768018 -33.628826) (xy 175.768508 -33.65881)
			(xy 175.768508 -34.520886) (xy 189.589664 -34.520886) (xy 189.589664 -33.657286) (xy 189.590154 -33.627318)
			(xy 189.597977 -33.567896) (xy 189.61349 -33.510003) (xy 189.636426 -33.45463) (xy 189.666393 -33.402724)
			(xy 189.70288 -33.355174) (xy 189.74526 -33.312794) (xy 189.79281 -33.276307) (xy 189.844716 -33.24634)
			(xy 189.900089 -33.223404) (xy 189.957982 -33.207891) (xy 190.017404 -33.200068) (xy 190.07734 -33.200068)
			(xy 190.136762 -33.207891) (xy 190.194655 -33.223404) (xy 190.250028 -33.24634) (xy 190.301934 -33.276307)
			(xy 190.349484 -33.312794) (xy 190.391864 -33.355174) (xy 190.428351 -33.402724) (xy 190.458318 -33.45463)
			(xy 190.481254 -33.510003) (xy 190.496767 -33.567896) (xy 190.50459 -33.627318) (xy 190.50508 -33.657286)
			(xy 190.50508 -34.520886) (xy 190.505055 -34.52241) (xy 200.852532 -34.52241) (xy 200.852532 -33.65881)
			(xy 200.853022 -33.628826) (xy 200.86085 -33.56937) (xy 200.876371 -33.511445) (xy 200.89932 -33.456041)
			(xy 200.929304 -33.404107) (xy 200.96581 -33.356531) (xy 201.008215 -33.314126) (xy 201.055791 -33.27762)
			(xy 201.107725 -33.247636) (xy 201.163129 -33.224687) (xy 201.221054 -33.209166) (xy 201.28051 -33.201338)
			(xy 201.340478 -33.201338) (xy 201.399934 -33.209166) (xy 201.457859 -33.224687) (xy 201.513263 -33.247636)
			(xy 201.565197 -33.27762) (xy 201.612773 -33.314126) (xy 201.655178 -33.356531) (xy 201.691684 -33.404107)
			(xy 201.721668 -33.456041) (xy 201.744617 -33.511445) (xy 201.760138 -33.56937) (xy 201.767966 -33.628826)
			(xy 201.768456 -33.65881) (xy 201.768456 -34.520886) (xy 215.589612 -34.520886) (xy 215.589612 -33.657286)
			(xy 215.590102 -33.627318) (xy 215.597925 -33.567896) (xy 215.613438 -33.510003) (xy 215.636374 -33.45463)
			(xy 215.666341 -33.402724) (xy 215.702828 -33.355174) (xy 215.745208 -33.312794) (xy 215.792758 -33.276307)
			(xy 215.844664 -33.24634) (xy 215.900037 -33.223404) (xy 215.95793 -33.207891) (xy 216.017352 -33.200068)
			(xy 216.077288 -33.200068) (xy 216.13671 -33.207891) (xy 216.194603 -33.223404) (xy 216.249976 -33.24634)
			(xy 216.301882 -33.276307) (xy 216.349432 -33.312794) (xy 216.391812 -33.355174) (xy 216.428299 -33.402724)
			(xy 216.458266 -33.45463) (xy 216.481202 -33.510003) (xy 216.496715 -33.567896) (xy 216.504538 -33.627318)
			(xy 216.505028 -33.657286) (xy 216.505028 -34.520886) (xy 216.505003 -34.52241) (xy 238.952532 -34.52241)
			(xy 238.952532 -33.65881) (xy 238.953022 -33.628826) (xy 238.96085 -33.56937) (xy 238.976371 -33.511445)
			(xy 238.99932 -33.456041) (xy 239.029304 -33.404107) (xy 239.06581 -33.356531) (xy 239.108215 -33.314126)
			(xy 239.155791 -33.27762) (xy 239.207725 -33.247636) (xy 239.263129 -33.224687) (xy 239.321054 -33.209166)
			(xy 239.38051 -33.201338) (xy 239.440478 -33.201338) (xy 239.499934 -33.209166) (xy 239.557859 -33.224687)
			(xy 239.613263 -33.247636) (xy 239.665197 -33.27762) (xy 239.712773 -33.314126) (xy 239.755178 -33.356531)
			(xy 239.791684 -33.404107) (xy 239.821668 -33.456041) (xy 239.844617 -33.511445) (xy 239.860138 -33.56937)
			(xy 239.867966 -33.628826) (xy 239.868456 -33.65881) (xy 239.868456 -34.520886) (xy 253.689612 -34.520886)
			(xy 253.689612 -33.657286) (xy 253.690102 -33.627318) (xy 253.697925 -33.567896) (xy 253.713438 -33.510003)
			(xy 253.736374 -33.45463) (xy 253.766341 -33.402724) (xy 253.802828 -33.355174) (xy 253.845208 -33.312794)
			(xy 253.892758 -33.276307) (xy 253.944664 -33.24634) (xy 254.000037 -33.223404) (xy 254.05793 -33.207891)
			(xy 254.117352 -33.200068) (xy 254.177288 -33.200068) (xy 254.23671 -33.207891) (xy 254.294603 -33.223404)
			(xy 254.349976 -33.24634) (xy 254.401882 -33.276307) (xy 254.449432 -33.312794) (xy 254.491812 -33.355174)
			(xy 254.528299 -33.402724) (xy 254.558266 -33.45463) (xy 254.581202 -33.510003) (xy 254.596715 -33.567896)
			(xy 254.604538 -33.627318) (xy 254.605028 -33.657286) (xy 254.605028 -34.520886) (xy 254.605003 -34.52241)
			(xy 264.95248 -34.52241) (xy 264.95248 -33.65881) (xy 264.95297 -33.628826) (xy 264.960798 -33.56937)
			(xy 264.976319 -33.511445) (xy 264.999268 -33.456041) (xy 265.029252 -33.404107) (xy 265.065758 -33.356531)
			(xy 265.108163 -33.314126) (xy 265.155739 -33.27762) (xy 265.207673 -33.247636) (xy 265.263077 -33.224687)
			(xy 265.321002 -33.209166) (xy 265.380458 -33.201338) (xy 265.440426 -33.201338) (xy 265.499882 -33.209166)
			(xy 265.557807 -33.224687) (xy 265.613211 -33.247636) (xy 265.665145 -33.27762) (xy 265.712721 -33.314126)
			(xy 265.755126 -33.356531) (xy 265.791632 -33.404107) (xy 265.821616 -33.456041) (xy 265.844565 -33.511445)
			(xy 265.860086 -33.56937) (xy 265.867914 -33.628826) (xy 265.868404 -33.65881) (xy 265.868404 -34.520886)
			(xy 279.68956 -34.520886) (xy 279.68956 -33.657286) (xy 279.69005 -33.627318) (xy 279.697873 -33.567896)
			(xy 279.713386 -33.510003) (xy 279.736322 -33.45463) (xy 279.766289 -33.402724) (xy 279.802776 -33.355174)
			(xy 279.845156 -33.312794) (xy 279.892706 -33.276307) (xy 279.944612 -33.24634) (xy 279.999985 -33.223404)
			(xy 280.057878 -33.207891) (xy 280.1173 -33.200068) (xy 280.177236 -33.200068) (xy 280.236658 -33.207891)
			(xy 280.294551 -33.223404) (xy 280.349924 -33.24634) (xy 280.40183 -33.276307) (xy 280.44938 -33.312794)
			(xy 280.49176 -33.355174) (xy 280.528247 -33.402724) (xy 280.558214 -33.45463) (xy 280.58115 -33.510003)
			(xy 280.596663 -33.567896) (xy 280.604486 -33.627318) (xy 280.604976 -33.657286) (xy 280.604976 -34.520886)
			(xy 280.604951 -34.52241) (xy 290.952428 -34.52241) (xy 290.952428 -33.65881) (xy 290.952918 -33.628826)
			(xy 290.960746 -33.56937) (xy 290.976267 -33.511445) (xy 290.999216 -33.456041) (xy 291.0292 -33.404107)
			(xy 291.065706 -33.356531) (xy 291.108111 -33.314126) (xy 291.155687 -33.27762) (xy 291.207621 -33.247636)
			(xy 291.263025 -33.224687) (xy 291.32095 -33.209166) (xy 291.380406 -33.201338) (xy 291.440374 -33.201338)
			(xy 291.49983 -33.209166) (xy 291.557755 -33.224687) (xy 291.613159 -33.247636) (xy 291.665093 -33.27762)
			(xy 291.712669 -33.314126) (xy 291.755074 -33.356531) (xy 291.79158 -33.404107) (xy 291.821564 -33.456041)
			(xy 291.844513 -33.511445) (xy 291.860034 -33.56937) (xy 291.867862 -33.628826) (xy 291.868352 -33.65881)
			(xy 291.868352 -34.520886) (xy 305.689508 -34.520886) (xy 305.689508 -33.657286) (xy 305.689998 -33.627318)
			(xy 305.697821 -33.567896) (xy 305.713334 -33.510003) (xy 305.73627 -33.45463) (xy 305.766237 -33.402724)
			(xy 305.802724 -33.355174) (xy 305.845104 -33.312794) (xy 305.892654 -33.276307) (xy 305.94456 -33.24634)
			(xy 305.999933 -33.223404) (xy 306.057826 -33.207891) (xy 306.117248 -33.200068) (xy 306.177184 -33.200068)
			(xy 306.236606 -33.207891) (xy 306.294499 -33.223404) (xy 306.349872 -33.24634) (xy 306.401778 -33.276307)
			(xy 306.449328 -33.312794) (xy 306.491708 -33.355174) (xy 306.528195 -33.402724) (xy 306.558162 -33.45463)
			(xy 306.581098 -33.510003) (xy 306.596611 -33.567896) (xy 306.604434 -33.627318) (xy 306.604924 -33.657286)
			(xy 306.604924 -34.520886) (xy 306.604899 -34.52241) (xy 316.952376 -34.52241) (xy 316.952376 -33.65881)
			(xy 316.952866 -33.628826) (xy 316.960694 -33.56937) (xy 316.976215 -33.511445) (xy 316.999164 -33.456041)
			(xy 317.029148 -33.404107) (xy 317.065654 -33.356531) (xy 317.108059 -33.314126) (xy 317.155635 -33.27762)
			(xy 317.207569 -33.247636) (xy 317.262973 -33.224687) (xy 317.320898 -33.209166) (xy 317.380354 -33.201338)
			(xy 317.440322 -33.201338) (xy 317.499778 -33.209166) (xy 317.557703 -33.224687) (xy 317.613107 -33.247636)
			(xy 317.665041 -33.27762) (xy 317.712617 -33.314126) (xy 317.755022 -33.356531) (xy 317.791528 -33.404107)
			(xy 317.821512 -33.456041) (xy 317.844461 -33.511445) (xy 317.859982 -33.56937) (xy 317.86781 -33.628826)
			(xy 317.8683 -33.65881) (xy 317.8683 -34.520886) (xy 331.689456 -34.520886) (xy 331.689456 -33.657286)
			(xy 331.689946 -33.627318) (xy 331.697769 -33.567896) (xy 331.713282 -33.510003) (xy 331.736218 -33.45463)
			(xy 331.766185 -33.402724) (xy 331.802672 -33.355174) (xy 331.845052 -33.312794) (xy 331.892602 -33.276307)
			(xy 331.944508 -33.24634) (xy 331.999881 -33.223404) (xy 332.057774 -33.207891) (xy 332.117196 -33.200068)
			(xy 332.177132 -33.200068) (xy 332.236554 -33.207891) (xy 332.294447 -33.223404) (xy 332.34982 -33.24634)
			(xy 332.401726 -33.276307) (xy 332.449276 -33.312794) (xy 332.491656 -33.355174) (xy 332.528143 -33.402724)
			(xy 332.55811 -33.45463) (xy 332.581046 -33.510003) (xy 332.596559 -33.567896) (xy 332.604382 -33.627318)
			(xy 332.604872 -33.657286) (xy 332.604872 -34.520886) (xy 332.604847 -34.52241) (xy 355.052884 -34.52241)
			(xy 355.052884 -33.65881) (xy 355.053374 -33.628842) (xy 355.061197 -33.56942) (xy 355.07671 -33.511527)
			(xy 355.099646 -33.456154) (xy 355.129613 -33.404248) (xy 355.1661 -33.356698) (xy 355.20848 -33.314318)
			(xy 355.25603 -33.277831) (xy 355.307936 -33.247864) (xy 355.363309 -33.224928) (xy 355.421202 -33.209415)
			(xy 355.480624 -33.201592) (xy 355.54056 -33.201592) (xy 355.599982 -33.209415) (xy 355.657875 -33.224928)
			(xy 355.713248 -33.247864) (xy 355.765154 -33.277831) (xy 355.812704 -33.314318) (xy 355.855084 -33.356698)
			(xy 355.891571 -33.404248) (xy 355.921538 -33.456154) (xy 355.944474 -33.511527) (xy 355.959987 -33.56942)
			(xy 355.96781 -33.628842) (xy 355.9683 -33.65881) (xy 355.9683 -34.520886) (xy 369.789456 -34.520886)
			(xy 369.789456 -33.657286) (xy 369.789946 -33.627302) (xy 369.797774 -33.567846) (xy 369.813295 -33.509921)
			(xy 369.836244 -33.454517) (xy 369.866228 -33.402583) (xy 369.902734 -33.355007) (xy 369.945139 -33.312602)
			(xy 369.992715 -33.276096) (xy 370.044649 -33.246112) (xy 370.100053 -33.223163) (xy 370.157978 -33.207642)
			(xy 370.217434 -33.199814) (xy 370.277402 -33.199814) (xy 370.336858 -33.207642) (xy 370.394783 -33.223163)
			(xy 370.450187 -33.246112) (xy 370.502121 -33.276096) (xy 370.549697 -33.312602) (xy 370.592102 -33.355007)
			(xy 370.628608 -33.402583) (xy 370.658592 -33.454517) (xy 370.681541 -33.509921) (xy 370.697062 -33.567846)
			(xy 370.70489 -33.627302) (xy 370.70538 -33.657286) (xy 370.70538 -34.520886) (xy 370.705355 -34.52241)
			(xy 381.052832 -34.52241) (xy 381.052832 -33.65881) (xy 381.053322 -33.628842) (xy 381.061145 -33.56942)
			(xy 381.076658 -33.511527) (xy 381.099594 -33.456154) (xy 381.129561 -33.404248) (xy 381.166048 -33.356698)
			(xy 381.208428 -33.314318) (xy 381.255978 -33.277831) (xy 381.307884 -33.247864) (xy 381.363257 -33.224928)
			(xy 381.42115 -33.209415) (xy 381.480572 -33.201592) (xy 381.540508 -33.201592) (xy 381.59993 -33.209415)
			(xy 381.657823 -33.224928) (xy 381.713196 -33.247864) (xy 381.765102 -33.277831) (xy 381.812652 -33.314318)
			(xy 381.855032 -33.356698) (xy 381.891519 -33.404248) (xy 381.921486 -33.456154) (xy 381.944422 -33.511527)
			(xy 381.959935 -33.56942) (xy 381.967758 -33.628842) (xy 381.968248 -33.65881) (xy 381.968248 -34.520886)
			(xy 395.789404 -34.520886) (xy 395.789404 -33.657286) (xy 395.789894 -33.627302) (xy 395.797722 -33.567846)
			(xy 395.813243 -33.509921) (xy 395.836192 -33.454517) (xy 395.866176 -33.402583) (xy 395.902682 -33.355007)
			(xy 395.945087 -33.312602) (xy 395.992663 -33.276096) (xy 396.044597 -33.246112) (xy 396.100001 -33.223163)
			(xy 396.157926 -33.207642) (xy 396.217382 -33.199814) (xy 396.27735 -33.199814) (xy 396.336806 -33.207642)
			(xy 396.394731 -33.223163) (xy 396.450135 -33.246112) (xy 396.502069 -33.276096) (xy 396.549645 -33.312602)
			(xy 396.59205 -33.355007) (xy 396.628556 -33.402583) (xy 396.65854 -33.454517) (xy 396.681489 -33.509921)
			(xy 396.69701 -33.567846) (xy 396.704838 -33.627302) (xy 396.705328 -33.657286) (xy 396.705328 -34.520886)
			(xy 396.705303 -34.52241) (xy 407.05278 -34.52241) (xy 407.05278 -33.65881) (xy 407.05327 -33.628842)
			(xy 407.061093 -33.56942) (xy 407.076606 -33.511527) (xy 407.099542 -33.456154) (xy 407.129509 -33.404248)
			(xy 407.165996 -33.356698) (xy 407.208376 -33.314318) (xy 407.255926 -33.277831) (xy 407.307832 -33.247864)
			(xy 407.363205 -33.224928) (xy 407.421098 -33.209415) (xy 407.48052 -33.201592) (xy 407.540456 -33.201592)
			(xy 407.599878 -33.209415) (xy 407.657771 -33.224928) (xy 407.713144 -33.247864) (xy 407.76505 -33.277831)
			(xy 407.8126 -33.314318) (xy 407.85498 -33.356698) (xy 407.891467 -33.404248) (xy 407.921434 -33.456154)
			(xy 407.94437 -33.511527) (xy 407.959883 -33.56942) (xy 407.967706 -33.628842) (xy 407.968196 -33.65881)
			(xy 407.968196 -34.520886) (xy 421.789352 -34.520886) (xy 421.789352 -33.657286) (xy 421.789842 -33.627302)
			(xy 421.79767 -33.567846) (xy 421.813191 -33.509921) (xy 421.83614 -33.454517) (xy 421.866124 -33.402583)
			(xy 421.90263 -33.355007) (xy 421.945035 -33.312602) (xy 421.992611 -33.276096) (xy 422.044545 -33.246112)
			(xy 422.099949 -33.223163) (xy 422.157874 -33.207642) (xy 422.21733 -33.199814) (xy 422.277298 -33.199814)
			(xy 422.336754 -33.207642) (xy 422.394679 -33.223163) (xy 422.450083 -33.246112) (xy 422.502017 -33.276096)
			(xy 422.549593 -33.312602) (xy 422.591998 -33.355007) (xy 422.628504 -33.402583) (xy 422.658488 -33.454517)
			(xy 422.681437 -33.509921) (xy 422.696958 -33.567846) (xy 422.704786 -33.627302) (xy 422.705276 -33.657286)
			(xy 422.705276 -34.520886) (xy 422.705251 -34.52241) (xy 433.052728 -34.52241) (xy 433.052728 -33.65881)
			(xy 433.053218 -33.628842) (xy 433.061041 -33.56942) (xy 433.076554 -33.511527) (xy 433.09949 -33.456154)
			(xy 433.129457 -33.404248) (xy 433.165944 -33.356698) (xy 433.208324 -33.314318) (xy 433.255874 -33.277831)
			(xy 433.30778 -33.247864) (xy 433.363153 -33.224928) (xy 433.421046 -33.209415) (xy 433.480468 -33.201592)
			(xy 433.540404 -33.201592) (xy 433.599826 -33.209415) (xy 433.657719 -33.224928) (xy 433.713092 -33.247864)
			(xy 433.764998 -33.277831) (xy 433.812548 -33.314318) (xy 433.854928 -33.356698) (xy 433.891415 -33.404248)
			(xy 433.921382 -33.456154) (xy 433.944318 -33.511527) (xy 433.959831 -33.56942) (xy 433.967654 -33.628842)
			(xy 433.968144 -33.65881) (xy 433.968144 -34.520886) (xy 447.7893 -34.520886) (xy 447.7893 -33.657286)
			(xy 447.78979 -33.627302) (xy 447.797618 -33.567846) (xy 447.813139 -33.509921) (xy 447.836088 -33.454517)
			(xy 447.866072 -33.402583) (xy 447.902578 -33.355007) (xy 447.944983 -33.312602) (xy 447.992559 -33.276096)
			(xy 448.044493 -33.246112) (xy 448.099897 -33.223163) (xy 448.157822 -33.207642) (xy 448.217278 -33.199814)
			(xy 448.277246 -33.199814) (xy 448.336702 -33.207642) (xy 448.394627 -33.223163) (xy 448.450031 -33.246112)
			(xy 448.501965 -33.276096) (xy 448.549541 -33.312602) (xy 448.591946 -33.355007) (xy 448.628452 -33.402583)
			(xy 448.658436 -33.454517) (xy 448.681385 -33.509921) (xy 448.696906 -33.567846) (xy 448.704734 -33.627302)
			(xy 448.705224 -33.657286) (xy 448.705224 -34.520886) (xy 448.704734 -34.55087) (xy 448.696906 -34.610326)
			(xy 448.681385 -34.668251) (xy 448.658436 -34.723655) (xy 448.628452 -34.775589) (xy 448.591946 -34.823165)
			(xy 448.549541 -34.86557) (xy 448.501965 -34.902076) (xy 448.450031 -34.93206) (xy 448.394627 -34.955009)
			(xy 448.336702 -34.97053) (xy 448.277246 -34.978358) (xy 448.217278 -34.978358) (xy 448.157822 -34.97053)
			(xy 448.099897 -34.955009) (xy 448.044493 -34.93206) (xy 447.992559 -34.902076) (xy 447.944983 -34.86557)
			(xy 447.902578 -34.823165) (xy 447.866072 -34.775589) (xy 447.836088 -34.723655) (xy 447.813139 -34.668251)
			(xy 447.797618 -34.610326) (xy 447.78979 -34.55087) (xy 447.7893 -34.520886) (xy 433.968144 -34.520886)
			(xy 433.968144 -34.52241) (xy 433.967654 -34.552378) (xy 433.959831 -34.6118) (xy 433.944318 -34.669693)
			(xy 433.921382 -34.725066) (xy 433.891415 -34.776972) (xy 433.854928 -34.824522) (xy 433.812548 -34.866902)
			(xy 433.764998 -34.903389) (xy 433.713092 -34.933356) (xy 433.657719 -34.956292) (xy 433.599826 -34.971805)
			(xy 433.540404 -34.979628) (xy 433.480468 -34.979628) (xy 433.421046 -34.971805) (xy 433.363153 -34.956292)
			(xy 433.30778 -34.933356) (xy 433.255874 -34.903389) (xy 433.208324 -34.866902) (xy 433.165944 -34.824522)
			(xy 433.129457 -34.776972) (xy 433.09949 -34.725066) (xy 433.076554 -34.669693) (xy 433.061041 -34.6118)
			(xy 433.053218 -34.552378) (xy 433.052728 -34.52241) (xy 422.705251 -34.52241) (xy 422.704786 -34.55087)
			(xy 422.696958 -34.610326) (xy 422.681437 -34.668251) (xy 422.658488 -34.723655) (xy 422.628504 -34.775589)
			(xy 422.591998 -34.823165) (xy 422.549593 -34.86557) (xy 422.502017 -34.902076) (xy 422.450083 -34.93206)
			(xy 422.394679 -34.955009) (xy 422.336754 -34.97053) (xy 422.277298 -34.978358) (xy 422.21733 -34.978358)
			(xy 422.157874 -34.97053) (xy 422.099949 -34.955009) (xy 422.044545 -34.93206) (xy 421.992611 -34.902076)
			(xy 421.945035 -34.86557) (xy 421.90263 -34.823165) (xy 421.866124 -34.775589) (xy 421.83614 -34.723655)
			(xy 421.813191 -34.668251) (xy 421.79767 -34.610326) (xy 421.789842 -34.55087) (xy 421.789352 -34.520886)
			(xy 407.968196 -34.520886) (xy 407.968196 -34.52241) (xy 407.967706 -34.552378) (xy 407.959883 -34.6118)
			(xy 407.94437 -34.669693) (xy 407.921434 -34.725066) (xy 407.891467 -34.776972) (xy 407.85498 -34.824522)
			(xy 407.8126 -34.866902) (xy 407.76505 -34.903389) (xy 407.713144 -34.933356) (xy 407.657771 -34.956292)
			(xy 407.599878 -34.971805) (xy 407.540456 -34.979628) (xy 407.48052 -34.979628) (xy 407.421098 -34.971805)
			(xy 407.363205 -34.956292) (xy 407.307832 -34.933356) (xy 407.255926 -34.903389) (xy 407.208376 -34.866902)
			(xy 407.165996 -34.824522) (xy 407.129509 -34.776972) (xy 407.099542 -34.725066) (xy 407.076606 -34.669693)
			(xy 407.061093 -34.6118) (xy 407.05327 -34.552378) (xy 407.05278 -34.52241) (xy 396.705303 -34.52241)
			(xy 396.704838 -34.55087) (xy 396.69701 -34.610326) (xy 396.681489 -34.668251) (xy 396.65854 -34.723655)
			(xy 396.628556 -34.775589) (xy 396.59205 -34.823165) (xy 396.549645 -34.86557) (xy 396.502069 -34.902076)
			(xy 396.450135 -34.93206) (xy 396.394731 -34.955009) (xy 396.336806 -34.97053) (xy 396.27735 -34.978358)
			(xy 396.217382 -34.978358) (xy 396.157926 -34.97053) (xy 396.100001 -34.955009) (xy 396.044597 -34.93206)
			(xy 395.992663 -34.902076) (xy 395.945087 -34.86557) (xy 395.902682 -34.823165) (xy 395.866176 -34.775589)
			(xy 395.836192 -34.723655) (xy 395.813243 -34.668251) (xy 395.797722 -34.610326) (xy 395.789894 -34.55087)
			(xy 395.789404 -34.520886) (xy 381.968248 -34.520886) (xy 381.968248 -34.52241) (xy 381.967758 -34.552378)
			(xy 381.959935 -34.6118) (xy 381.944422 -34.669693) (xy 381.921486 -34.725066) (xy 381.891519 -34.776972)
			(xy 381.855032 -34.824522) (xy 381.812652 -34.866902) (xy 381.765102 -34.903389) (xy 381.713196 -34.933356)
			(xy 381.657823 -34.956292) (xy 381.59993 -34.971805) (xy 381.540508 -34.979628) (xy 381.480572 -34.979628)
			(xy 381.42115 -34.971805) (xy 381.363257 -34.956292) (xy 381.307884 -34.933356) (xy 381.255978 -34.903389)
			(xy 381.208428 -34.866902) (xy 381.166048 -34.824522) (xy 381.129561 -34.776972) (xy 381.099594 -34.725066)
			(xy 381.076658 -34.669693) (xy 381.061145 -34.6118) (xy 381.053322 -34.552378) (xy 381.052832 -34.52241)
			(xy 370.705355 -34.52241) (xy 370.70489 -34.55087) (xy 370.697062 -34.610326) (xy 370.681541 -34.668251)
			(xy 370.658592 -34.723655) (xy 370.628608 -34.775589) (xy 370.592102 -34.823165) (xy 370.549697 -34.86557)
			(xy 370.502121 -34.902076) (xy 370.450187 -34.93206) (xy 370.394783 -34.955009) (xy 370.336858 -34.97053)
			(xy 370.277402 -34.978358) (xy 370.217434 -34.978358) (xy 370.157978 -34.97053) (xy 370.100053 -34.955009)
			(xy 370.044649 -34.93206) (xy 369.992715 -34.902076) (xy 369.945139 -34.86557) (xy 369.902734 -34.823165)
			(xy 369.866228 -34.775589) (xy 369.836244 -34.723655) (xy 369.813295 -34.668251) (xy 369.797774 -34.610326)
			(xy 369.789946 -34.55087) (xy 369.789456 -34.520886) (xy 355.9683 -34.520886) (xy 355.9683 -34.52241)
			(xy 355.96781 -34.552378) (xy 355.959987 -34.6118) (xy 355.944474 -34.669693) (xy 355.921538 -34.725066)
			(xy 355.891571 -34.776972) (xy 355.855084 -34.824522) (xy 355.812704 -34.866902) (xy 355.765154 -34.903389)
			(xy 355.713248 -34.933356) (xy 355.657875 -34.956292) (xy 355.599982 -34.971805) (xy 355.54056 -34.979628)
			(xy 355.480624 -34.979628) (xy 355.421202 -34.971805) (xy 355.363309 -34.956292) (xy 355.307936 -34.933356)
			(xy 355.25603 -34.903389) (xy 355.20848 -34.866902) (xy 355.1661 -34.824522) (xy 355.129613 -34.776972)
			(xy 355.099646 -34.725066) (xy 355.07671 -34.669693) (xy 355.061197 -34.6118) (xy 355.053374 -34.552378)
			(xy 355.052884 -34.52241) (xy 332.604847 -34.52241) (xy 332.604382 -34.550854) (xy 332.596559 -34.610276)
			(xy 332.581046 -34.668169) (xy 332.55811 -34.723542) (xy 332.528143 -34.775448) (xy 332.491656 -34.822998)
			(xy 332.449276 -34.865378) (xy 332.401726 -34.901865) (xy 332.34982 -34.931832) (xy 332.294447 -34.954768)
			(xy 332.236554 -34.970281) (xy 332.177132 -34.978104) (xy 332.117196 -34.978104) (xy 332.057774 -34.970281)
			(xy 331.999881 -34.954768) (xy 331.944508 -34.931832) (xy 331.892602 -34.901865) (xy 331.845052 -34.865378)
			(xy 331.802672 -34.822998) (xy 331.766185 -34.775448) (xy 331.736218 -34.723542) (xy 331.713282 -34.668169)
			(xy 331.697769 -34.610276) (xy 331.689946 -34.550854) (xy 331.689456 -34.520886) (xy 317.8683 -34.520886)
			(xy 317.8683 -34.52241) (xy 317.86781 -34.552394) (xy 317.859982 -34.61185) (xy 317.844461 -34.669775)
			(xy 317.821512 -34.725179) (xy 317.791528 -34.777113) (xy 317.755022 -34.824689) (xy 317.712617 -34.867094)
			(xy 317.665041 -34.9036) (xy 317.613107 -34.933584) (xy 317.557703 -34.956533) (xy 317.499778 -34.972054)
			(xy 317.440322 -34.979882) (xy 317.380354 -34.979882) (xy 317.320898 -34.972054) (xy 317.262973 -34.956533)
			(xy 317.207569 -34.933584) (xy 317.155635 -34.9036) (xy 317.108059 -34.867094) (xy 317.065654 -34.824689)
			(xy 317.029148 -34.777113) (xy 316.999164 -34.725179) (xy 316.976215 -34.669775) (xy 316.960694 -34.61185)
			(xy 316.952866 -34.552394) (xy 316.952376 -34.52241) (xy 306.604899 -34.52241) (xy 306.604434 -34.550854)
			(xy 306.596611 -34.610276) (xy 306.581098 -34.668169) (xy 306.558162 -34.723542) (xy 306.528195 -34.775448)
			(xy 306.491708 -34.822998) (xy 306.449328 -34.865378) (xy 306.401778 -34.901865) (xy 306.349872 -34.931832)
			(xy 306.294499 -34.954768) (xy 306.236606 -34.970281) (xy 306.177184 -34.978104) (xy 306.117248 -34.978104)
			(xy 306.057826 -34.970281) (xy 305.999933 -34.954768) (xy 305.94456 -34.931832) (xy 305.892654 -34.901865)
			(xy 305.845104 -34.865378) (xy 305.802724 -34.822998) (xy 305.766237 -34.775448) (xy 305.73627 -34.723542)
			(xy 305.713334 -34.668169) (xy 305.697821 -34.610276) (xy 305.689998 -34.550854) (xy 305.689508 -34.520886)
			(xy 291.868352 -34.520886) (xy 291.868352 -34.52241) (xy 291.867862 -34.552394) (xy 291.860034 -34.61185)
			(xy 291.844513 -34.669775) (xy 291.821564 -34.725179) (xy 291.79158 -34.777113) (xy 291.755074 -34.824689)
			(xy 291.712669 -34.867094) (xy 291.665093 -34.9036) (xy 291.613159 -34.933584) (xy 291.557755 -34.956533)
			(xy 291.49983 -34.972054) (xy 291.440374 -34.979882) (xy 291.380406 -34.979882) (xy 291.32095 -34.972054)
			(xy 291.263025 -34.956533) (xy 291.207621 -34.933584) (xy 291.155687 -34.9036) (xy 291.108111 -34.867094)
			(xy 291.065706 -34.824689) (xy 291.0292 -34.777113) (xy 290.999216 -34.725179) (xy 290.976267 -34.669775)
			(xy 290.960746 -34.61185) (xy 290.952918 -34.552394) (xy 290.952428 -34.52241) (xy 280.604951 -34.52241)
			(xy 280.604486 -34.550854) (xy 280.596663 -34.610276) (xy 280.58115 -34.668169) (xy 280.558214 -34.723542)
			(xy 280.528247 -34.775448) (xy 280.49176 -34.822998) (xy 280.44938 -34.865378) (xy 280.40183 -34.901865)
			(xy 280.349924 -34.931832) (xy 280.294551 -34.954768) (xy 280.236658 -34.970281) (xy 280.177236 -34.978104)
			(xy 280.1173 -34.978104) (xy 280.057878 -34.970281) (xy 279.999985 -34.954768) (xy 279.944612 -34.931832)
			(xy 279.892706 -34.901865) (xy 279.845156 -34.865378) (xy 279.802776 -34.822998) (xy 279.766289 -34.775448)
			(xy 279.736322 -34.723542) (xy 279.713386 -34.668169) (xy 279.697873 -34.610276) (xy 279.69005 -34.550854)
			(xy 279.68956 -34.520886) (xy 265.868404 -34.520886) (xy 265.868404 -34.52241) (xy 265.867914 -34.552394)
			(xy 265.860086 -34.61185) (xy 265.844565 -34.669775) (xy 265.821616 -34.725179) (xy 265.791632 -34.777113)
			(xy 265.755126 -34.824689) (xy 265.712721 -34.867094) (xy 265.665145 -34.9036) (xy 265.613211 -34.933584)
			(xy 265.557807 -34.956533) (xy 265.499882 -34.972054) (xy 265.440426 -34.979882) (xy 265.380458 -34.979882)
			(xy 265.321002 -34.972054) (xy 265.263077 -34.956533) (xy 265.207673 -34.933584) (xy 265.155739 -34.9036)
			(xy 265.108163 -34.867094) (xy 265.065758 -34.824689) (xy 265.029252 -34.777113) (xy 264.999268 -34.725179)
			(xy 264.976319 -34.669775) (xy 264.960798 -34.61185) (xy 264.95297 -34.552394) (xy 264.95248 -34.52241)
			(xy 254.605003 -34.52241) (xy 254.604538 -34.550854) (xy 254.596715 -34.610276) (xy 254.581202 -34.668169)
			(xy 254.558266 -34.723542) (xy 254.528299 -34.775448) (xy 254.491812 -34.822998) (xy 254.449432 -34.865378)
			(xy 254.401882 -34.901865) (xy 254.349976 -34.931832) (xy 254.294603 -34.954768) (xy 254.23671 -34.970281)
			(xy 254.177288 -34.978104) (xy 254.117352 -34.978104) (xy 254.05793 -34.970281) (xy 254.000037 -34.954768)
			(xy 253.944664 -34.931832) (xy 253.892758 -34.901865) (xy 253.845208 -34.865378) (xy 253.802828 -34.822998)
			(xy 253.766341 -34.775448) (xy 253.736374 -34.723542) (xy 253.713438 -34.668169) (xy 253.697925 -34.610276)
			(xy 253.690102 -34.550854) (xy 253.689612 -34.520886) (xy 239.868456 -34.520886) (xy 239.868456 -34.52241)
			(xy 239.867966 -34.552394) (xy 239.860138 -34.61185) (xy 239.844617 -34.669775) (xy 239.821668 -34.725179)
			(xy 239.791684 -34.777113) (xy 239.755178 -34.824689) (xy 239.712773 -34.867094) (xy 239.665197 -34.9036)
			(xy 239.613263 -34.933584) (xy 239.557859 -34.956533) (xy 239.499934 -34.972054) (xy 239.440478 -34.979882)
			(xy 239.38051 -34.979882) (xy 239.321054 -34.972054) (xy 239.263129 -34.956533) (xy 239.207725 -34.933584)
			(xy 239.155791 -34.9036) (xy 239.108215 -34.867094) (xy 239.06581 -34.824689) (xy 239.029304 -34.777113)
			(xy 238.99932 -34.725179) (xy 238.976371 -34.669775) (xy 238.96085 -34.61185) (xy 238.953022 -34.552394)
			(xy 238.952532 -34.52241) (xy 216.505003 -34.52241) (xy 216.504538 -34.550854) (xy 216.496715 -34.610276)
			(xy 216.481202 -34.668169) (xy 216.458266 -34.723542) (xy 216.428299 -34.775448) (xy 216.391812 -34.822998)
			(xy 216.349432 -34.865378) (xy 216.301882 -34.901865) (xy 216.249976 -34.931832) (xy 216.194603 -34.954768)
			(xy 216.13671 -34.970281) (xy 216.077288 -34.978104) (xy 216.017352 -34.978104) (xy 215.95793 -34.970281)
			(xy 215.900037 -34.954768) (xy 215.844664 -34.931832) (xy 215.792758 -34.901865) (xy 215.745208 -34.865378)
			(xy 215.702828 -34.822998) (xy 215.666341 -34.775448) (xy 215.636374 -34.723542) (xy 215.613438 -34.668169)
			(xy 215.597925 -34.610276) (xy 215.590102 -34.550854) (xy 215.589612 -34.520886) (xy 201.768456 -34.520886)
			(xy 201.768456 -34.52241) (xy 201.767966 -34.552394) (xy 201.760138 -34.61185) (xy 201.744617 -34.669775)
			(xy 201.721668 -34.725179) (xy 201.691684 -34.777113) (xy 201.655178 -34.824689) (xy 201.612773 -34.867094)
			(xy 201.565197 -34.9036) (xy 201.513263 -34.933584) (xy 201.457859 -34.956533) (xy 201.399934 -34.972054)
			(xy 201.340478 -34.979882) (xy 201.28051 -34.979882) (xy 201.221054 -34.972054) (xy 201.163129 -34.956533)
			(xy 201.107725 -34.933584) (xy 201.055791 -34.9036) (xy 201.008215 -34.867094) (xy 200.96581 -34.824689)
			(xy 200.929304 -34.777113) (xy 200.89932 -34.725179) (xy 200.876371 -34.669775) (xy 200.86085 -34.61185)
			(xy 200.853022 -34.552394) (xy 200.852532 -34.52241) (xy 190.505055 -34.52241) (xy 190.50459 -34.550854)
			(xy 190.496767 -34.610276) (xy 190.481254 -34.668169) (xy 190.458318 -34.723542) (xy 190.428351 -34.775448)
			(xy 190.391864 -34.822998) (xy 190.349484 -34.865378) (xy 190.301934 -34.901865) (xy 190.250028 -34.931832)
			(xy 190.194655 -34.954768) (xy 190.136762 -34.970281) (xy 190.07734 -34.978104) (xy 190.017404 -34.978104)
			(xy 189.957982 -34.970281) (xy 189.900089 -34.954768) (xy 189.844716 -34.931832) (xy 189.79281 -34.901865)
			(xy 189.74526 -34.865378) (xy 189.70288 -34.822998) (xy 189.666393 -34.775448) (xy 189.636426 -34.723542)
			(xy 189.61349 -34.668169) (xy 189.597977 -34.610276) (xy 189.590154 -34.550854) (xy 189.589664 -34.520886)
			(xy 175.768508 -34.520886) (xy 175.768508 -34.52241) (xy 175.768018 -34.552394) (xy 175.76019 -34.61185)
			(xy 175.744669 -34.669775) (xy 175.72172 -34.725179) (xy 175.691736 -34.777113) (xy 175.65523 -34.824689)
			(xy 175.612825 -34.867094) (xy 175.565249 -34.9036) (xy 175.513315 -34.933584) (xy 175.457911 -34.956533)
			(xy 175.399986 -34.972054) (xy 175.34053 -34.979882) (xy 175.280562 -34.979882) (xy 175.221106 -34.972054)
			(xy 175.163181 -34.956533) (xy 175.107777 -34.933584) (xy 175.055843 -34.9036) (xy 175.008267 -34.867094)
			(xy 174.965862 -34.824689) (xy 174.929356 -34.777113) (xy 174.899372 -34.725179) (xy 174.876423 -34.669775)
			(xy 174.860902 -34.61185) (xy 174.853074 -34.552394) (xy 174.852584 -34.52241) (xy 164.505107 -34.52241)
			(xy 164.504642 -34.550854) (xy 164.496819 -34.610276) (xy 164.481306 -34.668169) (xy 164.45837 -34.723542)
			(xy 164.428403 -34.775448) (xy 164.391916 -34.822998) (xy 164.349536 -34.865378) (xy 164.301986 -34.901865)
			(xy 164.25008 -34.931832) (xy 164.194707 -34.954768) (xy 164.136814 -34.970281) (xy 164.077392 -34.978104)
			(xy 164.017456 -34.978104) (xy 163.958034 -34.970281) (xy 163.900141 -34.954768) (xy 163.844768 -34.931832)
			(xy 163.792862 -34.901865) (xy 163.745312 -34.865378) (xy 163.702932 -34.822998) (xy 163.666445 -34.775448)
			(xy 163.636478 -34.723542) (xy 163.613542 -34.668169) (xy 163.598029 -34.610276) (xy 163.590206 -34.550854)
			(xy 163.589716 -34.520886) (xy 149.76856 -34.520886) (xy 149.76856 -34.52241) (xy 149.76807 -34.552394)
			(xy 149.760242 -34.61185) (xy 149.744721 -34.669775) (xy 149.721772 -34.725179) (xy 149.691788 -34.777113)
			(xy 149.655282 -34.824689) (xy 149.612877 -34.867094) (xy 149.565301 -34.9036) (xy 149.513367 -34.933584)
			(xy 149.457963 -34.956533) (xy 149.400038 -34.972054) (xy 149.340582 -34.979882) (xy 149.280614 -34.979882)
			(xy 149.221158 -34.972054) (xy 149.163233 -34.956533) (xy 149.107829 -34.933584) (xy 149.055895 -34.9036)
			(xy 149.008319 -34.867094) (xy 148.965914 -34.824689) (xy 148.929408 -34.777113) (xy 148.899424 -34.725179)
			(xy 148.876475 -34.669775) (xy 148.860954 -34.61185) (xy 148.853126 -34.552394) (xy 148.852636 -34.52241)
			(xy 138.505159 -34.52241) (xy 138.504694 -34.550854) (xy 138.496871 -34.610276) (xy 138.481358 -34.668169)
			(xy 138.458422 -34.723542) (xy 138.428455 -34.775448) (xy 138.391968 -34.822998) (xy 138.349588 -34.865378)
			(xy 138.302038 -34.901865) (xy 138.250132 -34.931832) (xy 138.194759 -34.954768) (xy 138.136866 -34.970281)
			(xy 138.077444 -34.978104) (xy 138.017508 -34.978104) (xy 137.958086 -34.970281) (xy 137.900193 -34.954768)
			(xy 137.84482 -34.931832) (xy 137.792914 -34.901865) (xy 137.745364 -34.865378) (xy 137.702984 -34.822998)
			(xy 137.666497 -34.775448) (xy 137.63653 -34.723542) (xy 137.613594 -34.668169) (xy 137.598081 -34.610276)
			(xy 137.590258 -34.550854) (xy 137.589768 -34.520886) (xy 123.768612 -34.520886) (xy 123.768612 -34.52241)
			(xy 123.768122 -34.552394) (xy 123.760294 -34.61185) (xy 123.744773 -34.669775) (xy 123.721824 -34.725179)
			(xy 123.69184 -34.777113) (xy 123.655334 -34.824689) (xy 123.612929 -34.867094) (xy 123.565353 -34.9036)
			(xy 123.513419 -34.933584) (xy 123.458015 -34.956533) (xy 123.40009 -34.972054) (xy 123.340634 -34.979882)
			(xy 123.280666 -34.979882) (xy 123.22121 -34.972054) (xy 123.163285 -34.956533) (xy 123.107881 -34.933584)
			(xy 123.055947 -34.9036) (xy 123.008371 -34.867094) (xy 122.965966 -34.824689) (xy 122.92946 -34.777113)
			(xy 122.899476 -34.725179) (xy 122.876527 -34.669775) (xy 122.861006 -34.61185) (xy 122.853178 -34.552394)
			(xy 122.852688 -34.52241) (xy 100.405159 -34.52241) (xy 100.404694 -34.55087) (xy 100.396866 -34.610326)
			(xy 100.381345 -34.668251) (xy 100.358396 -34.723655) (xy 100.328412 -34.775589) (xy 100.291906 -34.823165)
			(xy 100.249501 -34.86557) (xy 100.201925 -34.902076) (xy 100.149991 -34.93206) (xy 100.094587 -34.955009)
			(xy 100.036662 -34.97053) (xy 99.977206 -34.978358) (xy 99.917238 -34.978358) (xy 99.857782 -34.97053)
			(xy 99.799857 -34.955009) (xy 99.744453 -34.93206) (xy 99.692519 -34.902076) (xy 99.644943 -34.86557)
			(xy 99.602538 -34.823165) (xy 99.566032 -34.775589) (xy 99.536048 -34.723655) (xy 99.513099 -34.668251)
			(xy 99.497578 -34.610326) (xy 99.48975 -34.55087) (xy 99.48926 -34.520886) (xy 85.668104 -34.520886)
			(xy 85.668104 -34.52241) (xy 85.667614 -34.552378) (xy 85.659791 -34.6118) (xy 85.644278 -34.669693)
			(xy 85.621342 -34.725066) (xy 85.591375 -34.776972) (xy 85.554888 -34.824522) (xy 85.512508 -34.866902)
			(xy 85.464958 -34.903389) (xy 85.413052 -34.933356) (xy 85.357679 -34.956292) (xy 85.299786 -34.971805)
			(xy 85.240364 -34.979628) (xy 85.180428 -34.979628) (xy 85.121006 -34.971805) (xy 85.063113 -34.956292)
			(xy 85.00774 -34.933356) (xy 84.955834 -34.903389) (xy 84.908284 -34.866902) (xy 84.865904 -34.824522)
			(xy 84.829417 -34.776972) (xy 84.79945 -34.725066) (xy 84.776514 -34.669693) (xy 84.761001 -34.6118)
			(xy 84.753178 -34.552378) (xy 84.752688 -34.52241) (xy 74.405211 -34.52241) (xy 74.404746 -34.55087)
			(xy 74.396918 -34.610326) (xy 74.381397 -34.668251) (xy 74.358448 -34.723655) (xy 74.328464 -34.775589)
			(xy 74.291958 -34.823165) (xy 74.249553 -34.86557) (xy 74.201977 -34.902076) (xy 74.150043 -34.93206)
			(xy 74.094639 -34.955009) (xy 74.036714 -34.97053) (xy 73.977258 -34.978358) (xy 73.91729 -34.978358)
			(xy 73.857834 -34.97053) (xy 73.799909 -34.955009) (xy 73.744505 -34.93206) (xy 73.692571 -34.902076)
			(xy 73.644995 -34.86557) (xy 73.60259 -34.823165) (xy 73.566084 -34.775589) (xy 73.5361 -34.723655)
			(xy 73.513151 -34.668251) (xy 73.49763 -34.610326) (xy 73.489802 -34.55087) (xy 73.489312 -34.520886)
			(xy 59.668156 -34.520886) (xy 59.668156 -34.52241) (xy 59.667666 -34.552378) (xy 59.659843 -34.6118)
			(xy 59.64433 -34.669693) (xy 59.621394 -34.725066) (xy 59.591427 -34.776972) (xy 59.55494 -34.824522)
			(xy 59.51256 -34.866902) (xy 59.46501 -34.903389) (xy 59.413104 -34.933356) (xy 59.357731 -34.956292)
			(xy 59.299838 -34.971805) (xy 59.240416 -34.979628) (xy 59.18048 -34.979628) (xy 59.121058 -34.971805)
			(xy 59.063165 -34.956292) (xy 59.007792 -34.933356) (xy 58.955886 -34.903389) (xy 58.908336 -34.866902)
			(xy 58.865956 -34.824522) (xy 58.829469 -34.776972) (xy 58.799502 -34.725066) (xy 58.776566 -34.669693)
			(xy 58.761053 -34.6118) (xy 58.75323 -34.552378) (xy 58.75274 -34.52241) (xy 48.405263 -34.52241)
			(xy 48.404798 -34.55087) (xy 48.39697 -34.610326) (xy 48.381449 -34.668251) (xy 48.3585 -34.723655)
			(xy 48.328516 -34.775589) (xy 48.29201 -34.823165) (xy 48.249605 -34.86557) (xy 48.202029 -34.902076)
			(xy 48.150095 -34.93206) (xy 48.094691 -34.955009) (xy 48.036766 -34.97053) (xy 47.97731 -34.978358)
			(xy 47.917342 -34.978358) (xy 47.857886 -34.97053) (xy 47.799961 -34.955009) (xy 47.744557 -34.93206)
			(xy 47.692623 -34.902076) (xy 47.645047 -34.86557) (xy 47.602642 -34.823165) (xy 47.566136 -34.775589)
			(xy 47.536152 -34.723655) (xy 47.513203 -34.668251) (xy 47.497682 -34.610326) (xy 47.489854 -34.55087)
			(xy 47.489364 -34.520886) (xy 33.668208 -34.520886) (xy 33.668208 -34.52241) (xy 33.667718 -34.552378)
			(xy 33.659895 -34.6118) (xy 33.644382 -34.669693) (xy 33.621446 -34.725066) (xy 33.591479 -34.776972)
			(xy 33.554992 -34.824522) (xy 33.512612 -34.866902) (xy 33.465062 -34.903389) (xy 33.413156 -34.933356)
			(xy 33.357783 -34.956292) (xy 33.29989 -34.971805) (xy 33.240468 -34.979628) (xy 33.180532 -34.979628)
			(xy 33.12111 -34.971805) (xy 33.063217 -34.956292) (xy 33.007844 -34.933356) (xy 32.955938 -34.903389)
			(xy 32.908388 -34.866902) (xy 32.866008 -34.824522) (xy 32.829521 -34.776972) (xy 32.799554 -34.725066)
			(xy 32.776618 -34.669693) (xy 32.761105 -34.6118) (xy 32.753282 -34.552378) (xy 32.752792 -34.52241)
			(xy 22.405315 -34.52241) (xy 22.40485 -34.55087) (xy 22.397022 -34.610326) (xy 22.381501 -34.668251)
			(xy 22.358552 -34.723655) (xy 22.328568 -34.775589) (xy 22.292062 -34.823165) (xy 22.249657 -34.86557)
			(xy 22.202081 -34.902076) (xy 22.150147 -34.93206) (xy 22.094743 -34.955009) (xy 22.036818 -34.97053)
			(xy 21.977362 -34.978358) (xy 21.917394 -34.978358) (xy 21.857938 -34.97053) (xy 21.800013 -34.955009)
			(xy 21.744609 -34.93206) (xy 21.692675 -34.902076) (xy 21.645099 -34.86557) (xy 21.602694 -34.823165)
			(xy 21.566188 -34.775589) (xy 21.536204 -34.723655) (xy 21.513255 -34.668251) (xy 21.497734 -34.610326)
			(xy 21.489906 -34.55087) (xy 21.489416 -34.520886) (xy 7.66826 -34.520886) (xy 7.66826 -34.52241)
			(xy 7.66777 -34.552378) (xy 7.659947 -34.6118) (xy 7.644434 -34.669693) (xy 7.621498 -34.725066)
			(xy 7.591531 -34.776972) (xy 7.555044 -34.824522) (xy 7.512664 -34.866902) (xy 7.465114 -34.903389)
			(xy 7.413208 -34.933356) (xy 7.357835 -34.956292) (xy 7.299942 -34.971805) (xy 7.24052 -34.979628)
			(xy 7.180584 -34.979628) (xy 7.121162 -34.971805) (xy 7.063269 -34.956292) (xy 7.007896 -34.933356)
			(xy 6.95599 -34.903389) (xy 6.90844 -34.866902) (xy 6.86606 -34.824522) (xy 6.829573 -34.776972)
			(xy 6.799606 -34.725066) (xy 6.77667 -34.669693) (xy 6.761157 -34.6118) (xy 6.753334 -34.552378)
			(xy 6.752844 -34.52241) (xy 0.509016 -34.52241) (xy 0.509016 -36.60013) (xy 11.998205 -36.60013)
			(xy 12.00221 -36.512222) (xy 12.014193 -36.425042) (xy 12.034053 -36.339313) (xy 12.061628 -36.255745)
			(xy 12.096687 -36.175031) (xy 12.13894 -36.097839) (xy 12.188038 -36.02481) (xy 12.243574 -35.956548)
			(xy 12.305086 -35.893618) (xy 12.372067 -35.836544) (xy 12.44396 -35.785796) (xy 12.520169 -35.741796)
			(xy 12.600064 -35.704909) (xy 12.682983 -35.67544) (xy 12.768238 -35.653633) (xy 12.855122 -35.639669)
			(xy 12.942916 -35.633663) (xy 13.030893 -35.635667) (xy 13.118323 -35.645662) (xy 13.204482 -35.663566)
			(xy 13.288656 -35.68923) (xy 13.370147 -35.722443) (xy 13.448281 -35.762929) (xy 13.522409 -35.810351)
			(xy 13.591917 -35.864318) (xy 13.656231 -35.924383) (xy 13.714815 -35.990047) (xy 13.767186 -36.060766)
			(xy 13.812909 -36.135954) (xy 13.851606 -36.214989) (xy 13.882955 -36.297215) (xy 13.906697 -36.381951)
			(xy 13.922635 -36.468495) (xy 13.930637 -36.55613) (xy 13.931138 -36.60013) (xy 37.998153 -36.60013)
			(xy 38.002158 -36.512222) (xy 38.014141 -36.425042) (xy 38.034001 -36.339313) (xy 38.061576 -36.255745)
			(xy 38.096635 -36.175031) (xy 38.138888 -36.097839) (xy 38.187986 -36.02481) (xy 38.243522 -35.956548)
			(xy 38.305034 -35.893618) (xy 38.372015 -35.836544) (xy 38.443908 -35.785796) (xy 38.520117 -35.741796)
			(xy 38.600012 -35.704909) (xy 38.682931 -35.67544) (xy 38.768186 -35.653633) (xy 38.85507 -35.639669)
			(xy 38.942864 -35.633663) (xy 39.030841 -35.635667) (xy 39.118271 -35.645662) (xy 39.20443 -35.663566)
			(xy 39.288604 -35.68923) (xy 39.370095 -35.722443) (xy 39.448229 -35.762929) (xy 39.522357 -35.810351)
			(xy 39.591865 -35.864318) (xy 39.656179 -35.924383) (xy 39.714763 -35.990047) (xy 39.767134 -36.060766)
			(xy 39.812857 -36.135954) (xy 39.851554 -36.214989) (xy 39.882903 -36.297215) (xy 39.906645 -36.381951)
			(xy 39.922583 -36.468495) (xy 39.930585 -36.55613) (xy 39.931086 -36.60013) (xy 63.998101 -36.60013)
			(xy 64.002106 -36.512222) (xy 64.014089 -36.425042) (xy 64.033949 -36.339313) (xy 64.061524 -36.255745)
			(xy 64.096583 -36.175031) (xy 64.138836 -36.097839) (xy 64.187934 -36.02481) (xy 64.24347 -35.956548)
			(xy 64.304982 -35.893618) (xy 64.371963 -35.836544) (xy 64.443856 -35.785796) (xy 64.520065 -35.741796)
			(xy 64.59996 -35.704909) (xy 64.682879 -35.67544) (xy 64.768134 -35.653633) (xy 64.855018 -35.639669)
			(xy 64.942812 -35.633663) (xy 65.030789 -35.635667) (xy 65.118219 -35.645662) (xy 65.204378 -35.663566)
			(xy 65.288552 -35.68923) (xy 65.370043 -35.722443) (xy 65.448177 -35.762929) (xy 65.522305 -35.810351)
			(xy 65.591813 -35.864318) (xy 65.656127 -35.924383) (xy 65.714711 -35.990047) (xy 65.767082 -36.060766)
			(xy 65.812805 -36.135954) (xy 65.851502 -36.214989) (xy 65.882851 -36.297215) (xy 65.906593 -36.381951)
			(xy 65.922531 -36.468495) (xy 65.930533 -36.55613) (xy 65.931034 -36.60013) (xy 89.998049 -36.60013)
			(xy 90.002054 -36.512222) (xy 90.014037 -36.425042) (xy 90.033897 -36.339313) (xy 90.061472 -36.255745)
			(xy 90.096531 -36.175031) (xy 90.138784 -36.097839) (xy 90.187882 -36.02481) (xy 90.243418 -35.956548)
			(xy 90.30493 -35.893618) (xy 90.371911 -35.836544) (xy 90.443804 -35.785796) (xy 90.520013 -35.741796)
			(xy 90.599908 -35.704909) (xy 90.682827 -35.67544) (xy 90.768082 -35.653633) (xy 90.854966 -35.639669)
			(xy 90.94276 -35.633663) (xy 91.030737 -35.635667) (xy 91.118167 -35.645662) (xy 91.204326 -35.663566)
			(xy 91.2885 -35.68923) (xy 91.369991 -35.722443) (xy 91.448125 -35.762929) (xy 91.522253 -35.810351)
			(xy 91.591761 -35.864318) (xy 91.656075 -35.924383) (xy 91.714659 -35.990047) (xy 91.76703 -36.060766)
			(xy 91.812753 -36.135954) (xy 91.85145 -36.214989) (xy 91.882799 -36.297215) (xy 91.906541 -36.381951)
			(xy 91.922479 -36.468495) (xy 91.930481 -36.55613) (xy 91.930982 -36.60013) (xy 128.098303 -36.60013)
			(xy 128.102308 -36.512222) (xy 128.114291 -36.425042) (xy 128.134151 -36.339313) (xy 128.161726 -36.255745)
			(xy 128.196785 -36.175031) (xy 128.239038 -36.097839) (xy 128.288136 -36.02481) (xy 128.343672 -35.956548)
			(xy 128.405184 -35.893618) (xy 128.472165 -35.836544) (xy 128.544058 -35.785796) (xy 128.620267 -35.741796)
			(xy 128.700162 -35.704909) (xy 128.783081 -35.67544) (xy 128.868336 -35.653633) (xy 128.95522 -35.639669)
			(xy 129.043014 -35.633663) (xy 129.130991 -35.635667) (xy 129.218421 -35.645662) (xy 129.30458 -35.663566)
			(xy 129.388754 -35.68923) (xy 129.470245 -35.722443) (xy 129.548379 -35.762929) (xy 129.622507 -35.810351)
			(xy 129.692015 -35.864318) (xy 129.756329 -35.924383) (xy 129.814913 -35.990047) (xy 129.867284 -36.060766)
			(xy 129.913007 -36.135954) (xy 129.951704 -36.214989) (xy 129.983053 -36.297215) (xy 130.006795 -36.381951)
			(xy 130.022733 -36.468495) (xy 130.030735 -36.55613) (xy 130.031236 -36.60013) (xy 154.098251 -36.60013)
			(xy 154.102256 -36.512222) (xy 154.114239 -36.425042) (xy 154.134099 -36.339313) (xy 154.161674 -36.255745)
			(xy 154.196733 -36.175031) (xy 154.238986 -36.097839) (xy 154.288084 -36.02481) (xy 154.34362 -35.956548)
			(xy 154.405132 -35.893618) (xy 154.472113 -35.836544) (xy 154.544006 -35.785796) (xy 154.620215 -35.741796)
			(xy 154.70011 -35.704909) (xy 154.783029 -35.67544) (xy 154.868284 -35.653633) (xy 154.955168 -35.639669)
			(xy 155.042962 -35.633663) (xy 155.130939 -35.635667) (xy 155.218369 -35.645662) (xy 155.304528 -35.663566)
			(xy 155.388702 -35.68923) (xy 155.470193 -35.722443) (xy 155.548327 -35.762929) (xy 155.622455 -35.810351)
			(xy 155.691963 -35.864318) (xy 155.756277 -35.924383) (xy 155.814861 -35.990047) (xy 155.867232 -36.060766)
			(xy 155.912955 -36.135954) (xy 155.951652 -36.214989) (xy 155.983001 -36.297215) (xy 156.006743 -36.381951)
			(xy 156.022681 -36.468495) (xy 156.030683 -36.55613) (xy 156.031184 -36.60013) (xy 180.098199 -36.60013)
			(xy 180.102204 -36.512222) (xy 180.114187 -36.425042) (xy 180.134047 -36.339313) (xy 180.161622 -36.255745)
			(xy 180.196681 -36.175031) (xy 180.238934 -36.097839) (xy 180.288032 -36.02481) (xy 180.343568 -35.956548)
			(xy 180.40508 -35.893618) (xy 180.472061 -35.836544) (xy 180.543954 -35.785796) (xy 180.620163 -35.741796)
			(xy 180.700058 -35.704909) (xy 180.782977 -35.67544) (xy 180.868232 -35.653633) (xy 180.955116 -35.639669)
			(xy 181.04291 -35.633663) (xy 181.130887 -35.635667) (xy 181.218317 -35.645662) (xy 181.304476 -35.663566)
			(xy 181.38865 -35.68923) (xy 181.470141 -35.722443) (xy 181.548275 -35.762929) (xy 181.622403 -35.810351)
			(xy 181.691911 -35.864318) (xy 181.756225 -35.924383) (xy 181.814809 -35.990047) (xy 181.86718 -36.060766)
			(xy 181.912903 -36.135954) (xy 181.9516 -36.214989) (xy 181.982949 -36.297215) (xy 182.006691 -36.381951)
			(xy 182.022629 -36.468495) (xy 182.030631 -36.55613) (xy 182.031132 -36.60013) (xy 206.098655 -36.60013)
			(xy 206.102659 -36.512245) (xy 206.114639 -36.425088) (xy 206.134494 -36.339381) (xy 206.162061 -36.255836)
			(xy 206.197111 -36.175143) (xy 206.239353 -36.097971) (xy 206.288438 -36.024961) (xy 206.343959 -35.956717)
			(xy 206.405456 -35.893804) (xy 206.472418 -35.836744) (xy 206.544292 -35.78601) (xy 206.620482 -35.742022)
			(xy 206.700356 -35.705144) (xy 206.783253 -35.675683) (xy 206.868485 -35.653881) (xy 206.955347 -35.639921)
			(xy 207.043118 -35.633917) (xy 207.131072 -35.63592) (xy 207.218479 -35.645912) (xy 207.304615 -35.663812)
			(xy 207.388767 -35.68947) (xy 207.470237 -35.722674) (xy 207.54835 -35.763148) (xy 207.622458 -35.810559)
			(xy 207.691949 -35.864512) (xy 207.756245 -35.92456) (xy 207.814814 -35.990207) (xy 207.867171 -36.060907)
			(xy 207.912883 -36.136076) (xy 207.951569 -36.21509) (xy 207.98291 -36.297295) (xy 208.006645 -36.382009)
			(xy 208.022579 -36.46853) (xy 208.030579 -36.556142) (xy 208.03108 -36.60013) (xy 244.198655 -36.60013)
			(xy 244.202659 -36.512245) (xy 244.214639 -36.425088) (xy 244.234494 -36.339381) (xy 244.262061 -36.255836)
			(xy 244.297111 -36.175143) (xy 244.339353 -36.097971) (xy 244.388438 -36.024961) (xy 244.443959 -35.956717)
			(xy 244.505456 -35.893804) (xy 244.572418 -35.836744) (xy 244.644292 -35.78601) (xy 244.720482 -35.742022)
			(xy 244.800356 -35.705144) (xy 244.883253 -35.675683) (xy 244.968485 -35.653881) (xy 245.055347 -35.639921)
			(xy 245.143118 -35.633917) (xy 245.231072 -35.63592) (xy 245.318479 -35.645912) (xy 245.404615 -35.663812)
			(xy 245.488767 -35.68947) (xy 245.570237 -35.722674) (xy 245.64835 -35.763148) (xy 245.722458 -35.810559)
			(xy 245.791949 -35.864512) (xy 245.856245 -35.92456) (xy 245.914814 -35.990207) (xy 245.967171 -36.060907)
			(xy 246.012883 -36.136076) (xy 246.051569 -36.21509) (xy 246.08291 -36.297295) (xy 246.106645 -36.382009)
			(xy 246.122579 -36.46853) (xy 246.130579 -36.556142) (xy 246.13108 -36.60013) (xy 270.198603 -36.60013)
			(xy 270.202607 -36.512245) (xy 270.214587 -36.425088) (xy 270.234442 -36.339381) (xy 270.262009 -36.255836)
			(xy 270.297059 -36.175143) (xy 270.339301 -36.097971) (xy 270.388386 -36.024961) (xy 270.443907 -35.956717)
			(xy 270.505404 -35.893804) (xy 270.572366 -35.836744) (xy 270.64424 -35.78601) (xy 270.72043 -35.742022)
			(xy 270.800304 -35.705144) (xy 270.883201 -35.675683) (xy 270.968433 -35.653881) (xy 271.055295 -35.639921)
			(xy 271.143066 -35.633917) (xy 271.23102 -35.63592) (xy 271.318427 -35.645912) (xy 271.404563 -35.663812)
			(xy 271.488715 -35.68947) (xy 271.570185 -35.722674) (xy 271.648298 -35.763148) (xy 271.722406 -35.810559)
			(xy 271.791897 -35.864512) (xy 271.856193 -35.92456) (xy 271.914762 -35.990207) (xy 271.967119 -36.060907)
			(xy 272.012831 -36.136076) (xy 272.051517 -36.21509) (xy 272.082858 -36.297295) (xy 272.106593 -36.382009)
			(xy 272.122527 -36.46853) (xy 272.130527 -36.556142) (xy 272.131028 -36.60013) (xy 296.198551 -36.60013)
			(xy 296.202555 -36.512245) (xy 296.214535 -36.425088) (xy 296.23439 -36.339381) (xy 296.261957 -36.255836)
			(xy 296.297007 -36.175143) (xy 296.339249 -36.097971) (xy 296.388334 -36.024961) (xy 296.443855 -35.956717)
			(xy 296.505352 -35.893804) (xy 296.572314 -35.836744) (xy 296.644188 -35.78601) (xy 296.720378 -35.742022)
			(xy 296.800252 -35.705144) (xy 296.883149 -35.675683) (xy 296.968381 -35.653881) (xy 297.055243 -35.639921)
			(xy 297.143014 -35.633917) (xy 297.230968 -35.63592) (xy 297.318375 -35.645912) (xy 297.404511 -35.663812)
			(xy 297.488663 -35.68947) (xy 297.570133 -35.722674) (xy 297.648246 -35.763148) (xy 297.722354 -35.810559)
			(xy 297.791845 -35.864512) (xy 297.856141 -35.92456) (xy 297.91471 -35.990207) (xy 297.967067 -36.060907)
			(xy 298.012779 -36.136076) (xy 298.051465 -36.21509) (xy 298.082806 -36.297295) (xy 298.106541 -36.382009)
			(xy 298.122475 -36.46853) (xy 298.130475 -36.556142) (xy 298.130976 -36.60013) (xy 322.197991 -36.60013)
			(xy 322.201996 -36.512222) (xy 322.213979 -36.425042) (xy 322.233839 -36.339313) (xy 322.261414 -36.255745)
			(xy 322.296473 -36.175031) (xy 322.338726 -36.097839) (xy 322.387824 -36.02481) (xy 322.44336 -35.956548)
			(xy 322.504872 -35.893618) (xy 322.571853 -35.836544) (xy 322.643746 -35.785796) (xy 322.719955 -35.741796)
			(xy 322.79985 -35.704909) (xy 322.882769 -35.67544) (xy 322.968024 -35.653633) (xy 323.054908 -35.639669)
			(xy 323.142702 -35.633663) (xy 323.230679 -35.635667) (xy 323.318109 -35.645662) (xy 323.404268 -35.663566)
			(xy 323.488442 -35.68923) (xy 323.569933 -35.722443) (xy 323.648067 -35.762929) (xy 323.722195 -35.810351)
			(xy 323.791703 -35.864318) (xy 323.856017 -35.924383) (xy 323.914601 -35.990047) (xy 323.966972 -36.060766)
			(xy 324.012695 -36.135954) (xy 324.051392 -36.214989) (xy 324.082741 -36.297215) (xy 324.106483 -36.381951)
			(xy 324.122421 -36.468495) (xy 324.130423 -36.55613) (xy 324.130924 -36.60013) (xy 360.298245 -36.60013)
			(xy 360.30225 -36.512222) (xy 360.314233 -36.425042) (xy 360.334093 -36.339313) (xy 360.361668 -36.255745)
			(xy 360.396727 -36.175031) (xy 360.43898 -36.097839) (xy 360.488078 -36.02481) (xy 360.543614 -35.956548)
			(xy 360.605126 -35.893618) (xy 360.672107 -35.836544) (xy 360.744 -35.785796) (xy 360.820209 -35.741796)
			(xy 360.900104 -35.704909) (xy 360.983023 -35.67544) (xy 361.068278 -35.653633) (xy 361.155162 -35.639669)
			(xy 361.242956 -35.633663) (xy 361.330933 -35.635667) (xy 361.418363 -35.645662) (xy 361.504522 -35.663566)
			(xy 361.588696 -35.68923) (xy 361.670187 -35.722443) (xy 361.748321 -35.762929) (xy 361.822449 -35.810351)
			(xy 361.891957 -35.864318) (xy 361.956271 -35.924383) (xy 362.014855 -35.990047) (xy 362.067226 -36.060766)
			(xy 362.112949 -36.135954) (xy 362.151646 -36.214989) (xy 362.182995 -36.297215) (xy 362.206737 -36.381951)
			(xy 362.222675 -36.468495) (xy 362.230677 -36.55613) (xy 362.231178 -36.60013) (xy 386.298193 -36.60013)
			(xy 386.302198 -36.512222) (xy 386.314181 -36.425042) (xy 386.334041 -36.339313) (xy 386.361616 -36.255745)
			(xy 386.396675 -36.175031) (xy 386.438928 -36.097839) (xy 386.488026 -36.02481) (xy 386.543562 -35.956548)
			(xy 386.605074 -35.893618) (xy 386.672055 -35.836544) (xy 386.743948 -35.785796) (xy 386.820157 -35.741796)
			(xy 386.900052 -35.704909) (xy 386.982971 -35.67544) (xy 387.068226 -35.653633) (xy 387.15511 -35.639669)
			(xy 387.242904 -35.633663) (xy 387.330881 -35.635667) (xy 387.418311 -35.645662) (xy 387.50447 -35.663566)
			(xy 387.588644 -35.68923) (xy 387.670135 -35.722443) (xy 387.748269 -35.762929) (xy 387.822397 -35.810351)
			(xy 387.891905 -35.864318) (xy 387.956219 -35.924383) (xy 388.014803 -35.990047) (xy 388.067174 -36.060766)
			(xy 388.112897 -36.135954) (xy 388.151594 -36.214989) (xy 388.182943 -36.297215) (xy 388.206685 -36.381951)
			(xy 388.222623 -36.468495) (xy 388.230625 -36.55613) (xy 388.231126 -36.60013) (xy 412.298649 -36.60013)
			(xy 412.302653 -36.512245) (xy 412.314633 -36.425088) (xy 412.334488 -36.339381) (xy 412.362055 -36.255836)
			(xy 412.397105 -36.175143) (xy 412.439347 -36.097971) (xy 412.488432 -36.024961) (xy 412.543953 -35.956717)
			(xy 412.60545 -35.893804) (xy 412.672412 -35.836744) (xy 412.744286 -35.78601) (xy 412.820476 -35.742022)
			(xy 412.90035 -35.705144) (xy 412.983247 -35.675683) (xy 413.068479 -35.653881) (xy 413.155341 -35.639921)
			(xy 413.243112 -35.633917) (xy 413.331066 -35.63592) (xy 413.418473 -35.645912) (xy 413.504609 -35.663812)
			(xy 413.588761 -35.68947) (xy 413.670231 -35.722674) (xy 413.748344 -35.763148) (xy 413.822452 -35.810559)
			(xy 413.891943 -35.864512) (xy 413.956239 -35.92456) (xy 414.014808 -35.990207) (xy 414.067165 -36.060907)
			(xy 414.112877 -36.136076) (xy 414.151563 -36.21509) (xy 414.182904 -36.297295) (xy 414.206639 -36.382009)
			(xy 414.222573 -36.46853) (xy 414.230573 -36.556142) (xy 414.231074 -36.60013) (xy 438.298597 -36.60013)
			(xy 438.302601 -36.512245) (xy 438.314581 -36.425088) (xy 438.334436 -36.339381) (xy 438.362003 -36.255836)
			(xy 438.397053 -36.175143) (xy 438.439295 -36.097971) (xy 438.48838 -36.024961) (xy 438.543901 -35.956717)
			(xy 438.605398 -35.893804) (xy 438.67236 -35.836744) (xy 438.744234 -35.78601) (xy 438.820424 -35.742022)
			(xy 438.900298 -35.705144) (xy 438.983195 -35.675683) (xy 439.068427 -35.653881) (xy 439.155289 -35.639921)
			(xy 439.24306 -35.633917) (xy 439.331014 -35.63592) (xy 439.418421 -35.645912) (xy 439.504557 -35.663812)
			(xy 439.588709 -35.68947) (xy 439.670179 -35.722674) (xy 439.748292 -35.763148) (xy 439.8224 -35.810559)
			(xy 439.891891 -35.864512) (xy 439.956187 -35.92456) (xy 440.014756 -35.990207) (xy 440.067113 -36.060907)
			(xy 440.112825 -36.136076) (xy 440.151511 -36.21509) (xy 440.182852 -36.297295) (xy 440.206587 -36.382009)
			(xy 440.222521 -36.46853) (xy 440.230521 -36.556142) (xy 440.231022 -36.60013) (xy 440.230521 -36.644118)
			(xy 440.222521 -36.73173) (xy 440.206587 -36.818251) (xy 440.182852 -36.902965) (xy 440.151511 -36.98517)
			(xy 440.112825 -37.064184) (xy 440.067113 -37.139353) (xy 440.014756 -37.210053) (xy 439.956187 -37.2757)
			(xy 439.891891 -37.335748) (xy 439.8224 -37.389701) (xy 439.748292 -37.437112) (xy 439.670179 -37.477586)
			(xy 439.588709 -37.51079) (xy 439.504557 -37.536448) (xy 439.418421 -37.554348) (xy 439.331014 -37.56434)
			(xy 439.24306 -37.566343) (xy 439.155289 -37.560339) (xy 439.068427 -37.546379) (xy 438.983195 -37.524577)
			(xy 438.900298 -37.495116) (xy 438.820424 -37.458238) (xy 438.744234 -37.41425) (xy 438.67236 -37.363516)
			(xy 438.605398 -37.306456) (xy 438.543901 -37.243543) (xy 438.48838 -37.175299) (xy 438.439295 -37.102289)
			(xy 438.397053 -37.025117) (xy 438.362003 -36.944424) (xy 438.334436 -36.860879) (xy 438.314581 -36.775172)
			(xy 438.302601 -36.688015) (xy 438.298597 -36.60013) (xy 414.231074 -36.60013) (xy 414.230573 -36.644118)
			(xy 414.222573 -36.73173) (xy 414.206639 -36.818251) (xy 414.182904 -36.902965) (xy 414.151563 -36.98517)
			(xy 414.112877 -37.064184) (xy 414.067165 -37.139353) (xy 414.014808 -37.210053) (xy 413.956239 -37.2757)
			(xy 413.891943 -37.335748) (xy 413.822452 -37.389701) (xy 413.748344 -37.437112) (xy 413.670231 -37.477586)
			(xy 413.588761 -37.51079) (xy 413.504609 -37.536448) (xy 413.418473 -37.554348) (xy 413.331066 -37.56434)
			(xy 413.243112 -37.566343) (xy 413.155341 -37.560339) (xy 413.068479 -37.546379) (xy 412.983247 -37.524577)
			(xy 412.90035 -37.495116) (xy 412.820476 -37.458238) (xy 412.744286 -37.41425) (xy 412.672412 -37.363516)
			(xy 412.60545 -37.306456) (xy 412.543953 -37.243543) (xy 412.488432 -37.175299) (xy 412.439347 -37.102289)
			(xy 412.397105 -37.025117) (xy 412.362055 -36.944424) (xy 412.334488 -36.860879) (xy 412.314633 -36.775172)
			(xy 412.302653 -36.688015) (xy 412.298649 -36.60013) (xy 388.231126 -36.60013) (xy 388.230625 -36.64413)
			(xy 388.222623 -36.731765) (xy 388.206685 -36.818309) (xy 388.182943 -36.903045) (xy 388.151594 -36.985271)
			(xy 388.112897 -37.064306) (xy 388.067174 -37.139494) (xy 388.014803 -37.210213) (xy 387.956219 -37.275877)
			(xy 387.891905 -37.335942) (xy 387.822397 -37.389909) (xy 387.748269 -37.437331) (xy 387.670135 -37.477817)
			(xy 387.588644 -37.51103) (xy 387.50447 -37.536694) (xy 387.418311 -37.554598) (xy 387.330881 -37.564593)
			(xy 387.242904 -37.566597) (xy 387.15511 -37.560591) (xy 387.068226 -37.546627) (xy 386.982971 -37.52482)
			(xy 386.900052 -37.495351) (xy 386.820157 -37.458464) (xy 386.743948 -37.414464) (xy 386.672055 -37.363716)
			(xy 386.605074 -37.306642) (xy 386.543562 -37.243712) (xy 386.488026 -37.17545) (xy 386.438928 -37.102421)
			(xy 386.396675 -37.025229) (xy 386.361616 -36.944515) (xy 386.334041 -36.860947) (xy 386.314181 -36.775218)
			(xy 386.302198 -36.688038) (xy 386.298193 -36.60013) (xy 362.231178 -36.60013) (xy 362.230677 -36.64413)
			(xy 362.222675 -36.731765) (xy 362.206737 -36.818309) (xy 362.182995 -36.903045) (xy 362.151646 -36.985271)
			(xy 362.112949 -37.064306) (xy 362.067226 -37.139494) (xy 362.014855 -37.210213) (xy 361.956271 -37.275877)
			(xy 361.891957 -37.335942) (xy 361.822449 -37.389909) (xy 361.748321 -37.437331) (xy 361.670187 -37.477817)
			(xy 361.588696 -37.51103) (xy 361.504522 -37.536694) (xy 361.418363 -37.554598) (xy 361.330933 -37.564593)
			(xy 361.242956 -37.566597) (xy 361.155162 -37.560591) (xy 361.068278 -37.546627) (xy 360.983023 -37.52482)
			(xy 360.900104 -37.495351) (xy 360.820209 -37.458464) (xy 360.744 -37.414464) (xy 360.672107 -37.363716)
			(xy 360.605126 -37.306642) (xy 360.543614 -37.243712) (xy 360.488078 -37.17545) (xy 360.43898 -37.102421)
			(xy 360.396727 -37.025229) (xy 360.361668 -36.944515) (xy 360.334093 -36.860947) (xy 360.314233 -36.775218)
			(xy 360.30225 -36.688038) (xy 360.298245 -36.60013) (xy 324.130924 -36.60013) (xy 324.130423 -36.64413)
			(xy 324.122421 -36.731765) (xy 324.106483 -36.818309) (xy 324.082741 -36.903045) (xy 324.051392 -36.985271)
			(xy 324.012695 -37.064306) (xy 323.966972 -37.139494) (xy 323.914601 -37.210213) (xy 323.856017 -37.275877)
			(xy 323.791703 -37.335942) (xy 323.722195 -37.389909) (xy 323.648067 -37.437331) (xy 323.569933 -37.477817)
			(xy 323.488442 -37.51103) (xy 323.404268 -37.536694) (xy 323.318109 -37.554598) (xy 323.230679 -37.564593)
			(xy 323.142702 -37.566597) (xy 323.054908 -37.560591) (xy 322.968024 -37.546627) (xy 322.882769 -37.52482)
			(xy 322.79985 -37.495351) (xy 322.719955 -37.458464) (xy 322.643746 -37.414464) (xy 322.571853 -37.363716)
			(xy 322.504872 -37.306642) (xy 322.44336 -37.243712) (xy 322.387824 -37.17545) (xy 322.338726 -37.102421)
			(xy 322.296473 -37.025229) (xy 322.261414 -36.944515) (xy 322.233839 -36.860947) (xy 322.213979 -36.775218)
			(xy 322.201996 -36.688038) (xy 322.197991 -36.60013) (xy 298.130976 -36.60013) (xy 298.130475 -36.644118)
			(xy 298.122475 -36.73173) (xy 298.106541 -36.818251) (xy 298.082806 -36.902965) (xy 298.051465 -36.98517)
			(xy 298.012779 -37.064184) (xy 297.967067 -37.139353) (xy 297.91471 -37.210053) (xy 297.856141 -37.2757)
			(xy 297.791845 -37.335748) (xy 297.722354 -37.389701) (xy 297.648246 -37.437112) (xy 297.570133 -37.477586)
			(xy 297.488663 -37.51079) (xy 297.404511 -37.536448) (xy 297.318375 -37.554348) (xy 297.230968 -37.56434)
			(xy 297.143014 -37.566343) (xy 297.055243 -37.560339) (xy 296.968381 -37.546379) (xy 296.883149 -37.524577)
			(xy 296.800252 -37.495116) (xy 296.720378 -37.458238) (xy 296.644188 -37.41425) (xy 296.572314 -37.363516)
			(xy 296.505352 -37.306456) (xy 296.443855 -37.243543) (xy 296.388334 -37.175299) (xy 296.339249 -37.102289)
			(xy 296.297007 -37.025117) (xy 296.261957 -36.944424) (xy 296.23439 -36.860879) (xy 296.214535 -36.775172)
			(xy 296.202555 -36.688015) (xy 296.198551 -36.60013) (xy 272.131028 -36.60013) (xy 272.130527 -36.644118)
			(xy 272.122527 -36.73173) (xy 272.106593 -36.818251) (xy 272.082858 -36.902965) (xy 272.051517 -36.98517)
			(xy 272.012831 -37.064184) (xy 271.967119 -37.139353) (xy 271.914762 -37.210053) (xy 271.856193 -37.2757)
			(xy 271.791897 -37.335748) (xy 271.722406 -37.389701) (xy 271.648298 -37.437112) (xy 271.570185 -37.477586)
			(xy 271.488715 -37.51079) (xy 271.404563 -37.536448) (xy 271.318427 -37.554348) (xy 271.23102 -37.56434)
			(xy 271.143066 -37.566343) (xy 271.055295 -37.560339) (xy 270.968433 -37.546379) (xy 270.883201 -37.524577)
			(xy 270.800304 -37.495116) (xy 270.72043 -37.458238) (xy 270.64424 -37.41425) (xy 270.572366 -37.363516)
			(xy 270.505404 -37.306456) (xy 270.443907 -37.243543) (xy 270.388386 -37.175299) (xy 270.339301 -37.102289)
			(xy 270.297059 -37.025117) (xy 270.262009 -36.944424) (xy 270.234442 -36.860879) (xy 270.214587 -36.775172)
			(xy 270.202607 -36.688015) (xy 270.198603 -36.60013) (xy 246.13108 -36.60013) (xy 246.130579 -36.644118)
			(xy 246.122579 -36.73173) (xy 246.106645 -36.818251) (xy 246.08291 -36.902965) (xy 246.051569 -36.98517)
			(xy 246.012883 -37.064184) (xy 245.967171 -37.139353) (xy 245.914814 -37.210053) (xy 245.856245 -37.2757)
			(xy 245.791949 -37.335748) (xy 245.722458 -37.389701) (xy 245.64835 -37.437112) (xy 245.570237 -37.477586)
			(xy 245.488767 -37.51079) (xy 245.404615 -37.536448) (xy 245.318479 -37.554348) (xy 245.231072 -37.56434)
			(xy 245.143118 -37.566343) (xy 245.055347 -37.560339) (xy 244.968485 -37.546379) (xy 244.883253 -37.524577)
			(xy 244.800356 -37.495116) (xy 244.720482 -37.458238) (xy 244.644292 -37.41425) (xy 244.572418 -37.363516)
			(xy 244.505456 -37.306456) (xy 244.443959 -37.243543) (xy 244.388438 -37.175299) (xy 244.339353 -37.102289)
			(xy 244.297111 -37.025117) (xy 244.262061 -36.944424) (xy 244.234494 -36.860879) (xy 244.214639 -36.775172)
			(xy 244.202659 -36.688015) (xy 244.198655 -36.60013) (xy 208.03108 -36.60013) (xy 208.030579 -36.644118)
			(xy 208.022579 -36.73173) (xy 208.006645 -36.818251) (xy 207.98291 -36.902965) (xy 207.951569 -36.98517)
			(xy 207.912883 -37.064184) (xy 207.867171 -37.139353) (xy 207.814814 -37.210053) (xy 207.756245 -37.2757)
			(xy 207.691949 -37.335748) (xy 207.622458 -37.389701) (xy 207.54835 -37.437112) (xy 207.470237 -37.477586)
			(xy 207.388767 -37.51079) (xy 207.304615 -37.536448) (xy 207.218479 -37.554348) (xy 207.131072 -37.56434)
			(xy 207.043118 -37.566343) (xy 206.955347 -37.560339) (xy 206.868485 -37.546379) (xy 206.783253 -37.524577)
			(xy 206.700356 -37.495116) (xy 206.620482 -37.458238) (xy 206.544292 -37.41425) (xy 206.472418 -37.363516)
			(xy 206.405456 -37.306456) (xy 206.343959 -37.243543) (xy 206.288438 -37.175299) (xy 206.239353 -37.102289)
			(xy 206.197111 -37.025117) (xy 206.162061 -36.944424) (xy 206.134494 -36.860879) (xy 206.114639 -36.775172)
			(xy 206.102659 -36.688015) (xy 206.098655 -36.60013) (xy 182.031132 -36.60013) (xy 182.030631 -36.64413)
			(xy 182.022629 -36.731765) (xy 182.006691 -36.818309) (xy 181.982949 -36.903045) (xy 181.9516 -36.985271)
			(xy 181.912903 -37.064306) (xy 181.86718 -37.139494) (xy 181.814809 -37.210213) (xy 181.756225 -37.275877)
			(xy 181.691911 -37.335942) (xy 181.622403 -37.389909) (xy 181.548275 -37.437331) (xy 181.470141 -37.477817)
			(xy 181.38865 -37.51103) (xy 181.304476 -37.536694) (xy 181.218317 -37.554598) (xy 181.130887 -37.564593)
			(xy 181.04291 -37.566597) (xy 180.955116 -37.560591) (xy 180.868232 -37.546627) (xy 180.782977 -37.52482)
			(xy 180.700058 -37.495351) (xy 180.620163 -37.458464) (xy 180.543954 -37.414464) (xy 180.472061 -37.363716)
			(xy 180.40508 -37.306642) (xy 180.343568 -37.243712) (xy 180.288032 -37.17545) (xy 180.238934 -37.102421)
			(xy 180.196681 -37.025229) (xy 180.161622 -36.944515) (xy 180.134047 -36.860947) (xy 180.114187 -36.775218)
			(xy 180.102204 -36.688038) (xy 180.098199 -36.60013) (xy 156.031184 -36.60013) (xy 156.030683 -36.64413)
			(xy 156.022681 -36.731765) (xy 156.006743 -36.818309) (xy 155.983001 -36.903045) (xy 155.951652 -36.985271)
			(xy 155.912955 -37.064306) (xy 155.867232 -37.139494) (xy 155.814861 -37.210213) (xy 155.756277 -37.275877)
			(xy 155.691963 -37.335942) (xy 155.622455 -37.389909) (xy 155.548327 -37.437331) (xy 155.470193 -37.477817)
			(xy 155.388702 -37.51103) (xy 155.304528 -37.536694) (xy 155.218369 -37.554598) (xy 155.130939 -37.564593)
			(xy 155.042962 -37.566597) (xy 154.955168 -37.560591) (xy 154.868284 -37.546627) (xy 154.783029 -37.52482)
			(xy 154.70011 -37.495351) (xy 154.620215 -37.458464) (xy 154.544006 -37.414464) (xy 154.472113 -37.363716)
			(xy 154.405132 -37.306642) (xy 154.34362 -37.243712) (xy 154.288084 -37.17545) (xy 154.238986 -37.102421)
			(xy 154.196733 -37.025229) (xy 154.161674 -36.944515) (xy 154.134099 -36.860947) (xy 154.114239 -36.775218)
			(xy 154.102256 -36.688038) (xy 154.098251 -36.60013) (xy 130.031236 -36.60013) (xy 130.030735 -36.64413)
			(xy 130.022733 -36.731765) (xy 130.006795 -36.818309) (xy 129.983053 -36.903045) (xy 129.951704 -36.985271)
			(xy 129.913007 -37.064306) (xy 129.867284 -37.139494) (xy 129.814913 -37.210213) (xy 129.756329 -37.275877)
			(xy 129.692015 -37.335942) (xy 129.622507 -37.389909) (xy 129.548379 -37.437331) (xy 129.470245 -37.477817)
			(xy 129.388754 -37.51103) (xy 129.30458 -37.536694) (xy 129.218421 -37.554598) (xy 129.130991 -37.564593)
			(xy 129.043014 -37.566597) (xy 128.95522 -37.560591) (xy 128.868336 -37.546627) (xy 128.783081 -37.52482)
			(xy 128.700162 -37.495351) (xy 128.620267 -37.458464) (xy 128.544058 -37.414464) (xy 128.472165 -37.363716)
			(xy 128.405184 -37.306642) (xy 128.343672 -37.243712) (xy 128.288136 -37.17545) (xy 128.239038 -37.102421)
			(xy 128.196785 -37.025229) (xy 128.161726 -36.944515) (xy 128.134151 -36.860947) (xy 128.114291 -36.775218)
			(xy 128.102308 -36.688038) (xy 128.098303 -36.60013) (xy 91.930982 -36.60013) (xy 91.930481 -36.64413)
			(xy 91.922479 -36.731765) (xy 91.906541 -36.818309) (xy 91.882799 -36.903045) (xy 91.85145 -36.985271)
			(xy 91.812753 -37.064306) (xy 91.76703 -37.139494) (xy 91.714659 -37.210213) (xy 91.656075 -37.275877)
			(xy 91.591761 -37.335942) (xy 91.522253 -37.389909) (xy 91.448125 -37.437331) (xy 91.369991 -37.477817)
			(xy 91.2885 -37.51103) (xy 91.204326 -37.536694) (xy 91.118167 -37.554598) (xy 91.030737 -37.564593)
			(xy 90.94276 -37.566597) (xy 90.854966 -37.560591) (xy 90.768082 -37.546627) (xy 90.682827 -37.52482)
			(xy 90.599908 -37.495351) (xy 90.520013 -37.458464) (xy 90.443804 -37.414464) (xy 90.371911 -37.363716)
			(xy 90.30493 -37.306642) (xy 90.243418 -37.243712) (xy 90.187882 -37.17545) (xy 90.138784 -37.102421)
			(xy 90.096531 -37.025229) (xy 90.061472 -36.944515) (xy 90.033897 -36.860947) (xy 90.014037 -36.775218)
			(xy 90.002054 -36.688038) (xy 89.998049 -36.60013) (xy 65.931034 -36.60013) (xy 65.930533 -36.64413)
			(xy 65.922531 -36.731765) (xy 65.906593 -36.818309) (xy 65.882851 -36.903045) (xy 65.851502 -36.985271)
			(xy 65.812805 -37.064306) (xy 65.767082 -37.139494) (xy 65.714711 -37.210213) (xy 65.656127 -37.275877)
			(xy 65.591813 -37.335942) (xy 65.522305 -37.389909) (xy 65.448177 -37.437331) (xy 65.370043 -37.477817)
			(xy 65.288552 -37.51103) (xy 65.204378 -37.536694) (xy 65.118219 -37.554598) (xy 65.030789 -37.564593)
			(xy 64.942812 -37.566597) (xy 64.855018 -37.560591) (xy 64.768134 -37.546627) (xy 64.682879 -37.52482)
			(xy 64.59996 -37.495351) (xy 64.520065 -37.458464) (xy 64.443856 -37.414464) (xy 64.371963 -37.363716)
			(xy 64.304982 -37.306642) (xy 64.24347 -37.243712) (xy 64.187934 -37.17545) (xy 64.138836 -37.102421)
			(xy 64.096583 -37.025229) (xy 64.061524 -36.944515) (xy 64.033949 -36.860947) (xy 64.014089 -36.775218)
			(xy 64.002106 -36.688038) (xy 63.998101 -36.60013) (xy 39.931086 -36.60013) (xy 39.930585 -36.64413)
			(xy 39.922583 -36.731765) (xy 39.906645 -36.818309) (xy 39.882903 -36.903045) (xy 39.851554 -36.985271)
			(xy 39.812857 -37.064306) (xy 39.767134 -37.139494) (xy 39.714763 -37.210213) (xy 39.656179 -37.275877)
			(xy 39.591865 -37.335942) (xy 39.522357 -37.389909) (xy 39.448229 -37.437331) (xy 39.370095 -37.477817)
			(xy 39.288604 -37.51103) (xy 39.20443 -37.536694) (xy 39.118271 -37.554598) (xy 39.030841 -37.564593)
			(xy 38.942864 -37.566597) (xy 38.85507 -37.560591) (xy 38.768186 -37.546627) (xy 38.682931 -37.52482)
			(xy 38.600012 -37.495351) (xy 38.520117 -37.458464) (xy 38.443908 -37.414464) (xy 38.372015 -37.363716)
			(xy 38.305034 -37.306642) (xy 38.243522 -37.243712) (xy 38.187986 -37.17545) (xy 38.138888 -37.102421)
			(xy 38.096635 -37.025229) (xy 38.061576 -36.944515) (xy 38.034001 -36.860947) (xy 38.014141 -36.775218)
			(xy 38.002158 -36.688038) (xy 37.998153 -36.60013) (xy 13.931138 -36.60013) (xy 13.930637 -36.64413)
			(xy 13.922635 -36.731765) (xy 13.906697 -36.818309) (xy 13.882955 -36.903045) (xy 13.851606 -36.985271)
			(xy 13.812909 -37.064306) (xy 13.767186 -37.139494) (xy 13.714815 -37.210213) (xy 13.656231 -37.275877)
			(xy 13.591917 -37.335942) (xy 13.522409 -37.389909) (xy 13.448281 -37.437331) (xy 13.370147 -37.477817)
			(xy 13.288656 -37.51103) (xy 13.204482 -37.536694) (xy 13.118323 -37.554598) (xy 13.030893 -37.564593)
			(xy 12.942916 -37.566597) (xy 12.855122 -37.560591) (xy 12.768238 -37.546627) (xy 12.682983 -37.52482)
			(xy 12.600064 -37.495351) (xy 12.520169 -37.458464) (xy 12.44396 -37.414464) (xy 12.372067 -37.363716)
			(xy 12.305086 -37.306642) (xy 12.243574 -37.243712) (xy 12.188038 -37.17545) (xy 12.13894 -37.102421)
			(xy 12.096687 -37.025229) (xy 12.061628 -36.944515) (xy 12.034053 -36.860947) (xy 12.014193 -36.775218)
			(xy 12.00221 -36.688038) (xy 11.998205 -36.60013) (xy 0.509016 -36.60013) (xy 0.509016 -58.698471)
			(xy 229.808523 -58.698471) (xy 229.808523 -58.601777) (xy 229.816508 -58.505414) (xy 229.832424 -58.410039)
			(xy 229.85616 -58.316305) (xy 229.887557 -58.22485) (xy 229.926398 -58.136301) (xy 229.972419 -58.051261)
			(xy 230.025305 -57.970313) (xy 230.084696 -57.894008) (xy 230.150184 -57.822868) (xy 230.221324 -57.75738)
			(xy 230.297629 -57.697989) (xy 230.378577 -57.645103) (xy 230.463617 -57.599082) (xy 230.552166 -57.560241)
			(xy 230.643621 -57.528844) (xy 230.737355 -57.505108) (xy 230.83273 -57.489192) (xy 230.929093 -57.481207)
			(xy 231.025787 -57.481207) (xy 231.12215 -57.489192) (xy 231.217525 -57.505108) (xy 231.311259 -57.528844)
			(xy 231.402714 -57.560241) (xy 231.491263 -57.599082) (xy 231.576303 -57.645103) (xy 231.657251 -57.697989)
			(xy 231.733556 -57.75738) (xy 231.804696 -57.822868) (xy 231.870184 -57.894008) (xy 231.929575 -57.970313)
			(xy 231.982461 -58.051261) (xy 232.028482 -58.136301) (xy 232.067323 -58.22485) (xy 232.09872 -58.316305)
			(xy 232.122456 -58.410039) (xy 232.138372 -58.505414) (xy 232.146357 -58.601777) (xy 232.146856 -58.650124)
			(xy 232.146357 -58.698471) (xy 232.138372 -58.794834) (xy 232.122456 -58.890209) (xy 232.09872 -58.983943)
			(xy 232.067323 -59.075398) (xy 232.028482 -59.163947) (xy 231.982461 -59.248987) (xy 231.929575 -59.329935)
			(xy 231.870184 -59.40624) (xy 231.804696 -59.47738) (xy 231.733556 -59.542868) (xy 231.657251 -59.602259)
			(xy 231.576303 -59.655145) (xy 231.491263 -59.701166) (xy 231.402714 -59.740007) (xy 231.311259 -59.771404)
			(xy 231.217525 -59.79514) (xy 231.12215 -59.811056) (xy 231.025787 -59.819041) (xy 230.929093 -59.819041)
			(xy 230.83273 -59.811056) (xy 230.737355 -59.79514) (xy 230.643621 -59.771404) (xy 230.552166 -59.740007)
			(xy 230.463617 -59.701166) (xy 230.378577 -59.655145) (xy 230.297629 -59.602259) (xy 230.221324 -59.542868)
			(xy 230.150184 -59.47738) (xy 230.084696 -59.40624) (xy 230.025305 -59.329935) (xy 229.972419 -59.248987)
			(xy 229.926398 -59.163947) (xy 229.887557 -59.075398) (xy 229.85616 -58.983943) (xy 229.832424 -58.890209)
			(xy 229.816508 -58.794834) (xy 229.808523 -58.698471) (xy 0.509016 -58.698471) (xy 0.509016 -60.13196)
			(xy 226.436428 -60.13196) (xy 226.436428 -59.26836) (xy 226.436918 -59.238392) (xy 226.444741 -59.17897)
			(xy 226.460254 -59.121077) (xy 226.48319 -59.065704) (xy 226.513157 -59.013798) (xy 226.549644 -58.966248)
			(xy 226.592024 -58.923868) (xy 226.639574 -58.887381) (xy 226.69148 -58.857414) (xy 226.746853 -58.834478)
			(xy 226.804746 -58.818965) (xy 226.864168 -58.811142) (xy 226.924104 -58.811142) (xy 226.983526 -58.818965)
			(xy 227.041419 -58.834478) (xy 227.096792 -58.857414) (xy 227.148698 -58.887381) (xy 227.196248 -58.923868)
			(xy 227.238628 -58.966248) (xy 227.275115 -59.013798) (xy 227.305082 -59.065704) (xy 227.328018 -59.121077)
			(xy 227.343531 -59.17897) (xy 227.351354 -59.238392) (xy 227.351844 -59.26836) (xy 227.351844 -60.13196)
			(xy 227.351354 -60.161928) (xy 227.343531 -60.22135) (xy 227.328018 -60.279243) (xy 227.305082 -60.334616)
			(xy 227.275115 -60.386522) (xy 227.238628 -60.434072) (xy 227.196248 -60.476452) (xy 227.148698 -60.512939)
			(xy 227.096792 -60.542906) (xy 227.041419 -60.565842) (xy 226.983526 -60.581355) (xy 226.924104 -60.589178)
			(xy 226.864168 -60.589178) (xy 226.804746 -60.581355) (xy 226.746853 -60.565842) (xy 226.69148 -60.542906)
			(xy 226.639574 -60.512939) (xy 226.592024 -60.476452) (xy 226.549644 -60.434072) (xy 226.513157 -60.386522)
			(xy 226.48319 -60.334616) (xy 226.460254 -60.279243) (xy 226.444741 -60.22135) (xy 226.436918 -60.161928)
			(xy 226.436428 -60.13196) (xy 0.509016 -60.13196) (xy 0.509016 -69.798271) (xy 229.808523 -69.798271)
			(xy 229.808523 -69.701577) (xy 229.816508 -69.605214) (xy 229.832424 -69.509839) (xy 229.85616 -69.416105)
			(xy 229.887557 -69.32465) (xy 229.926398 -69.236101) (xy 229.972419 -69.151061) (xy 230.025305 -69.070113)
			(xy 230.084696 -68.993808) (xy 230.150184 -68.922668) (xy 230.221324 -68.85718) (xy 230.297629 -68.797789)
			(xy 230.378577 -68.744903) (xy 230.463617 -68.698882) (xy 230.552166 -68.660041) (xy 230.643621 -68.628644)
			(xy 230.737355 -68.604908) (xy 230.83273 -68.588992) (xy 230.929093 -68.581007) (xy 231.025787 -68.581007)
			(xy 231.12215 -68.588992) (xy 231.217525 -68.604908) (xy 231.311259 -68.628644) (xy 231.402714 -68.660041)
			(xy 231.491263 -68.698882) (xy 231.576303 -68.744903) (xy 231.657251 -68.797789) (xy 231.733556 -68.85718)
			(xy 231.804696 -68.922668) (xy 231.870184 -68.993808) (xy 231.929575 -69.070113) (xy 231.982461 -69.151061)
			(xy 232.028482 -69.236101) (xy 232.067323 -69.32465) (xy 232.09872 -69.416105) (xy 232.122456 -69.509839)
			(xy 232.138372 -69.605214) (xy 232.146357 -69.701577) (xy 232.146856 -69.749924) (xy 232.146357 -69.798271)
			(xy 232.138372 -69.894634) (xy 232.122456 -69.990009) (xy 232.09872 -70.083743) (xy 232.067323 -70.175198)
			(xy 232.028482 -70.263747) (xy 231.982461 -70.348787) (xy 231.929575 -70.429735) (xy 231.870184 -70.50604)
			(xy 231.804696 -70.57718) (xy 231.733556 -70.642668) (xy 231.657251 -70.702059) (xy 231.576303 -70.754945)
			(xy 231.491263 -70.800966) (xy 231.402714 -70.839807) (xy 231.311259 -70.871204) (xy 231.217525 -70.89494)
			(xy 231.12215 -70.910856) (xy 231.025787 -70.918841) (xy 230.929093 -70.918841) (xy 230.83273 -70.910856)
			(xy 230.737355 -70.89494) (xy 230.643621 -70.871204) (xy 230.552166 -70.839807) (xy 230.463617 -70.800966)
			(xy 230.378577 -70.754945) (xy 230.297629 -70.702059) (xy 230.221324 -70.642668) (xy 230.150184 -70.57718)
			(xy 230.084696 -70.50604) (xy 230.025305 -70.429735) (xy 229.972419 -70.348787) (xy 229.926398 -70.263747)
			(xy 229.887557 -70.175198) (xy 229.85616 -70.083743) (xy 229.832424 -69.990009) (xy 229.816508 -69.894634)
			(xy 229.808523 -69.798271) (xy 0.509016 -69.798271) (xy 0.509016 -75.288385) (xy 262.150829 -75.288385)
			(xy 262.150829 -75.228415) (xy 262.158657 -75.168959) (xy 262.174178 -75.111033) (xy 262.197128 -75.055628)
			(xy 262.227114 -75.003693) (xy 262.263621 -74.956116) (xy 262.306027 -74.913712) (xy 262.353605 -74.877206)
			(xy 262.405541 -74.847222) (xy 262.460946 -74.824274) (xy 262.518872 -74.808754) (xy 262.578329 -74.800928)
			(xy 262.608314 -74.80046) (xy 263.471914 -74.80046) (xy 263.501899 -74.800907) (xy 263.561356 -74.808736)
			(xy 263.619283 -74.824259) (xy 263.674687 -74.84721) (xy 263.726623 -74.877196) (xy 263.7742 -74.913705)
			(xy 263.816604 -74.956111) (xy 263.853111 -75.003689) (xy 263.883096 -75.055625) (xy 263.906045 -75.111031)
			(xy 263.921566 -75.168958) (xy 263.929394 -75.228415) (xy 263.929394 -75.288385) (xy 263.921566 -75.347842)
			(xy 263.906045 -75.405769) (xy 263.883096 -75.461175) (xy 263.853111 -75.513111) (xy 263.816604 -75.560689)
			(xy 263.7742 -75.603095) (xy 263.726623 -75.639604) (xy 263.674687 -75.66959) (xy 263.619283 -75.692541)
			(xy 263.561356 -75.708064) (xy 263.501899 -75.715893) (xy 263.471914 -75.716384) (xy 262.608314 -75.716384)
			(xy 262.578329 -75.715872) (xy 262.518872 -75.708046) (xy 262.460946 -75.692526) (xy 262.405541 -75.669578)
			(xy 262.353605 -75.639594) (xy 262.306027 -75.603088) (xy 262.263621 -75.560684) (xy 262.227114 -75.513107)
			(xy 262.197128 -75.461172) (xy 262.174178 -75.405767) (xy 262.158657 -75.347841) (xy 262.150829 -75.288385)
			(xy 0.509016 -75.288385) (xy 0.509016 -76.826085) (xy 229.640845 -76.826085) (xy 229.640845 -76.766115)
			(xy 229.648673 -76.706658) (xy 229.664196 -76.648731) (xy 229.687147 -76.593327) (xy 229.717134 -76.541392)
			(xy 229.753643 -76.493816) (xy 229.796051 -76.451413) (xy 229.84363 -76.414908) (xy 229.895568 -76.384926)
			(xy 229.950975 -76.361981) (xy 230.008903 -76.346464) (xy 230.068361 -76.338642) (xy 230.098346 -76.338176)
			(xy 230.961946 -76.338176) (xy 230.991931 -76.338593) (xy 231.051387 -76.346426) (xy 231.109312 -76.361952)
			(xy 231.164715 -76.384906) (xy 231.216648 -76.414894) (xy 231.264223 -76.451404) (xy 231.306626 -76.493811)
			(xy 231.343131 -76.54139) (xy 231.373114 -76.593326) (xy 231.396063 -76.648732) (xy 231.411583 -76.706658)
			(xy 231.41941 -76.766115) (xy 231.41941 -76.826085) (xy 231.411583 -76.885542) (xy 231.396063 -76.943468)
			(xy 231.373114 -76.998874) (xy 231.343131 -77.05081) (xy 231.306626 -77.098389) (xy 231.264223 -77.140796)
			(xy 231.216648 -77.177306) (xy 231.164715 -77.207294) (xy 231.109312 -77.230248) (xy 231.051387 -77.245774)
			(xy 230.991931 -77.253607) (xy 230.961946 -77.2541) (xy 230.098346 -77.2541) (xy 230.068361 -77.253558)
			(xy 230.008903 -77.245736) (xy 229.950975 -77.230219) (xy 229.895568 -77.207274) (xy 229.84363 -77.177292)
			(xy 229.796051 -77.140787) (xy 229.753643 -77.098384) (xy 229.717134 -77.050808) (xy 229.687147 -76.998873)
			(xy 229.664196 -76.943469) (xy 229.648673 -76.885542) (xy 229.640845 -76.826085) (xy 0.509016 -76.826085)
			(xy 0.509016 -77.365367) (xy 105.150162 -77.365367) (xy 105.150162 -77.305433) (xy 105.157985 -77.246011)
			(xy 105.173496 -77.188119) (xy 105.19643 -77.132746) (xy 105.226396 -77.08084) (xy 105.26288 -77.03329)
			(xy 105.305258 -76.990908) (xy 105.352805 -76.954419) (xy 105.404708 -76.924449) (xy 105.460079 -76.901509)
			(xy 105.51797 -76.885993) (xy 105.577391 -76.878165) (xy 105.607358 -76.877672) (xy 106.470958 -76.877672)
			(xy 106.500928 -76.878178) (xy 106.560354 -76.885997) (xy 106.618252 -76.901506) (xy 106.67363 -76.92444)
			(xy 106.72554 -76.954406) (xy 106.773095 -76.990892) (xy 106.81548 -77.033273) (xy 106.851971 -77.080825)
			(xy 106.881942 -77.132732) (xy 106.904881 -77.188108) (xy 106.920395 -77.246004) (xy 106.928219 -77.305431)
			(xy 106.928219 -77.365367) (xy 109.150162 -77.365367) (xy 109.150162 -77.305433) (xy 109.157984 -77.246012)
			(xy 109.173495 -77.18812) (xy 109.196429 -77.132748) (xy 109.226394 -77.080843) (xy 109.262878 -77.033292)
			(xy 109.305255 -76.990911) (xy 109.352801 -76.954422) (xy 109.404703 -76.924452) (xy 109.460073 -76.901511)
			(xy 109.517963 -76.885994) (xy 109.577383 -76.878165) (xy 109.60735 -76.877672) (xy 110.47095 -76.877672)
			(xy 110.50092 -76.878178) (xy 110.560347 -76.885996) (xy 110.618246 -76.901504) (xy 110.673625 -76.924437)
			(xy 110.725536 -76.954403) (xy 110.773092 -76.990889) (xy 110.815478 -77.03327) (xy 110.851969 -77.080822)
			(xy 110.881941 -77.13273) (xy 110.90488 -77.188107) (xy 110.920395 -77.246003) (xy 110.928219 -77.30543)
			(xy 110.928219 -77.36537) (xy 110.920395 -77.424797) (xy 110.90488 -77.482693) (xy 110.881941 -77.53807)
			(xy 110.851969 -77.589978) (xy 110.815478 -77.63753) (xy 110.773092 -77.679911) (xy 110.725536 -77.716397)
			(xy 110.673625 -77.746363) (xy 110.618246 -77.769296) (xy 110.560347 -77.784804) (xy 110.50092 -77.792622)
			(xy 110.47095 -77.793088) (xy 109.60735 -77.793088) (xy 109.577383 -77.792635) (xy 109.517963 -77.784806)
			(xy 109.460073 -77.769289) (xy 109.404703 -77.746348) (xy 109.352801 -77.716378) (xy 109.305255 -77.679889)
			(xy 109.262878 -77.637508) (xy 109.226394 -77.589957) (xy 109.196429 -77.538052) (xy 109.173495 -77.48268)
			(xy 109.157984 -77.424788) (xy 109.150162 -77.365367) (xy 106.928219 -77.365367) (xy 106.928219 -77.365369)
			(xy 106.920395 -77.424796) (xy 106.904881 -77.482692) (xy 106.881942 -77.538068) (xy 106.851971 -77.589975)
			(xy 106.81548 -77.637527) (xy 106.773095 -77.679908) (xy 106.72554 -77.716394) (xy 106.67363 -77.74636)
			(xy 106.618252 -77.769294) (xy 106.560354 -77.784803) (xy 106.500928 -77.792622) (xy 106.470958 -77.793088)
			(xy 105.607358 -77.793088) (xy 105.577391 -77.792635) (xy 105.51797 -77.784807) (xy 105.460079 -77.769291)
			(xy 105.404708 -77.746351) (xy 105.352805 -77.716381) (xy 105.305258 -77.679892) (xy 105.26288 -77.63751)
			(xy 105.226396 -77.58996) (xy 105.19643 -77.538054) (xy 105.173496 -77.482681) (xy 105.157985 -77.424789)
			(xy 105.150162 -77.365367) (xy 0.509016 -77.365367) (xy 0.509016 -78.127367) (xy 107.150162 -78.127367)
			(xy 107.150162 -78.067433) (xy 107.157984 -78.008012) (xy 107.173496 -77.950119) (xy 107.19643 -77.894747)
			(xy 107.226395 -77.842842) (xy 107.262879 -77.795291) (xy 107.305256 -77.752909) (xy 107.352803 -77.716421)
			(xy 107.404706 -77.68645) (xy 107.460076 -77.66351) (xy 107.517966 -77.647993) (xy 107.577387 -77.640165)
			(xy 107.607354 -77.639672) (xy 108.470954 -77.639672) (xy 108.500924 -77.640178) (xy 108.560351 -77.647996)
			(xy 108.618249 -77.663505) (xy 108.673627 -77.686438) (xy 108.725538 -77.716405) (xy 108.773094 -77.752891)
			(xy 108.815479 -77.795272) (xy 108.85197 -77.842823) (xy 108.881941 -77.894731) (xy 108.90488 -77.950107)
			(xy 108.920395 -78.008004) (xy 108.928219 -78.06743) (xy 108.928219 -78.12737) (xy 108.920395 -78.186796)
			(xy 108.90488 -78.244693) (xy 108.881941 -78.300069) (xy 108.85197 -78.351977) (xy 108.815479 -78.399528)
			(xy 108.773093 -78.441909) (xy 108.725538 -78.478395) (xy 108.673627 -78.508362) (xy 108.618249 -78.531295)
			(xy 108.560351 -78.546804) (xy 108.500924 -78.554622) (xy 108.470954 -78.555088) (xy 107.607354 -78.555088)
			(xy 107.577387 -78.554635) (xy 107.517966 -78.546807) (xy 107.460076 -78.53129) (xy 107.404706 -78.50835)
			(xy 107.352803 -78.478379) (xy 107.305256 -78.441891) (xy 107.262879 -78.399509) (xy 107.226395 -78.351958)
			(xy 107.19643 -78.300053) (xy 107.173496 -78.244681) (xy 107.157984 -78.186788) (xy 107.150162 -78.127367)
			(xy 0.509016 -78.127367) (xy 0.509016 -79.238094) (xy 227.9777 -79.238094) (xy 227.9777 -78.374494)
			(xy 227.97819 -78.344526) (xy 227.986013 -78.285104) (xy 228.001526 -78.227211) (xy 228.024462 -78.171838)
			(xy 228.054429 -78.119932) (xy 228.090916 -78.072382) (xy 228.133296 -78.030002) (xy 228.180846 -77.993515)
			(xy 228.232752 -77.963548) (xy 228.288125 -77.940612) (xy 228.346018 -77.925099) (xy 228.40544 -77.917276)
			(xy 228.465376 -77.917276) (xy 228.524798 -77.925099) (xy 228.582691 -77.940612) (xy 228.638064 -77.963548)
			(xy 228.68997 -77.993515) (xy 228.73752 -78.030002) (xy 228.7799 -78.072382) (xy 228.816387 -78.119932)
			(xy 228.83413 -78.150664) (xy 336.40703 -78.150664) (xy 336.40703 -78.090736) (xy 336.414852 -78.031319)
			(xy 336.430363 -77.973433) (xy 336.453297 -77.918066) (xy 336.483261 -77.866166) (xy 336.519743 -77.818621)
			(xy 336.562119 -77.776245) (xy 336.609664 -77.739762) (xy 336.661564 -77.709797) (xy 336.716931 -77.686864)
			(xy 336.774817 -77.671353) (xy 336.834234 -77.66353) (xy 336.864198 -77.66304) (xy 337.727798 -77.66304)
			(xy 337.75777 -77.663413) (xy 337.817202 -77.671237) (xy 337.875104 -77.686751) (xy 337.930486 -77.709691)
			(xy 337.982399 -77.739663) (xy 338.029957 -77.776155) (xy 338.072344 -77.818542) (xy 338.108836 -77.866099)
			(xy 338.138808 -77.918013) (xy 338.161748 -77.973394) (xy 338.177263 -78.031296) (xy 338.185087 -78.090728)
			(xy 338.185087 -78.150672) (xy 338.177263 -78.210104) (xy 338.161748 -78.268006) (xy 338.138808 -78.323387)
			(xy 338.108836 -78.375301) (xy 338.072344 -78.422858) (xy 338.029957 -78.465245) (xy 337.982399 -78.501737)
			(xy 337.930486 -78.531709) (xy 337.875104 -78.554649) (xy 337.817202 -78.570163) (xy 337.75777 -78.577987)
			(xy 337.727798 -78.578456) (xy 336.864198 -78.578456) (xy 336.834234 -78.57787) (xy 336.774817 -78.570047)
			(xy 336.716931 -78.554536) (xy 336.661564 -78.531603) (xy 336.609664 -78.501638) (xy 336.562119 -78.465155)
			(xy 336.519743 -78.422779) (xy 336.483261 -78.375234) (xy 336.453297 -78.323334) (xy 336.430363 -78.267967)
			(xy 336.414852 -78.210081) (xy 336.40703 -78.150664) (xy 228.83413 -78.150664) (xy 228.846354 -78.171838)
			(xy 228.86929 -78.227211) (xy 228.884803 -78.285104) (xy 228.892626 -78.344526) (xy 228.893116 -78.374494)
			(xy 228.893116 -79.238094) (xy 228.892626 -79.268062) (xy 228.884803 -79.327484) (xy 228.86929 -79.385377)
			(xy 228.846354 -79.44075) (xy 228.816387 -79.492656) (xy 228.7799 -79.540206) (xy 228.73752 -79.582586)
			(xy 228.68997 -79.619073) (xy 228.638064 -79.64904) (xy 228.582691 -79.671976) (xy 228.524798 -79.687489)
			(xy 228.465376 -79.695312) (xy 228.40544 -79.695312) (xy 228.346018 -79.687489) (xy 228.288125 -79.671976)
			(xy 228.232752 -79.64904) (xy 228.180846 -79.619073) (xy 228.133296 -79.582586) (xy 228.090916 -79.540206)
			(xy 228.054429 -79.492656) (xy 228.024462 -79.44075) (xy 228.001526 -79.385377) (xy 227.986013 -79.327484)
			(xy 227.97819 -79.268062) (xy 227.9777 -79.238094) (xy 0.509016 -79.238094) (xy 0.509016 -80.183482)
			(xy 237.540292 -80.183482) (xy 237.540292 -79.319882) (xy 237.540782 -79.289914) (xy 237.548605 -79.230492)
			(xy 237.564118 -79.172599) (xy 237.587054 -79.117226) (xy 237.617021 -79.06532) (xy 237.653508 -79.01777)
			(xy 237.695888 -78.97539) (xy 237.743438 -78.938903) (xy 237.795344 -78.908936) (xy 237.850717 -78.886)
			(xy 237.90861 -78.870487) (xy 237.968032 -78.862664) (xy 238.027968 -78.862664) (xy 238.08739 -78.870487)
			(xy 238.145283 -78.886) (xy 238.200656 -78.908936) (xy 238.207117 -78.912666) (xy 334.407009 -78.912666)
			(xy 334.407009 -78.852734) (xy 334.414832 -78.793315) (xy 334.430343 -78.735425) (xy 334.453278 -78.680055)
			(xy 334.483244 -78.628153) (xy 334.519729 -78.580606) (xy 334.562107 -78.538227) (xy 334.609654 -78.501743)
			(xy 334.661557 -78.471777) (xy 334.716927 -78.448843) (xy 334.774817 -78.433331) (xy 334.834236 -78.425509)
			(xy 334.864202 -78.42504) (xy 335.727802 -78.42504) (xy 335.757773 -78.425434) (xy 335.817201 -78.433258)
			(xy 335.8751 -78.448773) (xy 335.930479 -78.471711) (xy 335.982389 -78.501682) (xy 336.029944 -78.538172)
			(xy 336.072329 -78.580557) (xy 336.108819 -78.628112) (xy 336.13879 -78.680023) (xy 336.161728 -78.735402)
			(xy 336.177242 -78.793301) (xy 336.185066 -78.852729) (xy 336.185066 -78.912664) (xy 338.40703 -78.912664)
			(xy 338.40703 -78.852736) (xy 338.414852 -78.79332) (xy 338.430363 -78.735433) (xy 338.453296 -78.680067)
			(xy 338.48326 -78.628167) (xy 338.519742 -78.580622) (xy 338.562118 -78.538246) (xy 338.609662 -78.501763)
			(xy 338.661561 -78.471799) (xy 338.716928 -78.448865) (xy 338.774814 -78.433353) (xy 338.83423 -78.42553)
			(xy 338.864194 -78.42504) (xy 339.727794 -78.42504) (xy 339.757766 -78.425412) (xy 339.817199 -78.433236)
			(xy 339.875101 -78.44875) (xy 339.930483 -78.47169) (xy 339.982397 -78.501662) (xy 340.029955 -78.538153)
			(xy 340.072343 -78.580541) (xy 340.108835 -78.628098) (xy 340.138808 -78.680011) (xy 340.161748 -78.735393)
			(xy 340.177263 -78.793296) (xy 340.185087 -78.852728) (xy 340.185087 -78.912672) (xy 340.177263 -78.972104)
			(xy 340.161748 -79.030007) (xy 340.138808 -79.085389) (xy 340.108835 -79.137302) (xy 340.072343 -79.184859)
			(xy 340.029955 -79.227247) (xy 339.982397 -79.263738) (xy 339.930483 -79.29371) (xy 339.875101 -79.31665)
			(xy 339.817199 -79.332164) (xy 339.757766 -79.339988) (xy 339.727794 -79.340456) (xy 338.864194 -79.340456)
			(xy 338.83423 -79.33987) (xy 338.774814 -79.332047) (xy 338.716928 -79.316535) (xy 338.661561 -79.293601)
			(xy 338.609662 -79.263637) (xy 338.562118 -79.227154) (xy 338.519742 -79.184778) (xy 338.48326 -79.137233)
			(xy 338.453296 -79.085333) (xy 338.430363 -79.029967) (xy 338.414852 -78.97208) (xy 338.40703 -78.912664)
			(xy 336.185066 -78.912664) (xy 336.185066 -78.912671) (xy 336.177242 -78.972099) (xy 336.161728 -79.029998)
			(xy 336.13879 -79.085377) (xy 336.108819 -79.137288) (xy 336.072329 -79.184843) (xy 336.029944 -79.227228)
			(xy 335.982389 -79.263718) (xy 335.930479 -79.293689) (xy 335.8751 -79.316627) (xy 335.817201 -79.332142)
			(xy 335.757773 -79.339966) (xy 335.727802 -79.340456) (xy 334.864202 -79.340456) (xy 334.834236 -79.339891)
			(xy 334.774817 -79.332069) (xy 334.716927 -79.316557) (xy 334.661557 -79.293623) (xy 334.609654 -79.263657)
			(xy 334.562107 -79.227173) (xy 334.519729 -79.184794) (xy 334.483244 -79.137247) (xy 334.453278 -79.085345)
			(xy 334.430343 -79.029975) (xy 334.414832 -78.972085) (xy 334.407009 -78.912666) (xy 238.207117 -78.912666)
			(xy 238.252562 -78.938903) (xy 238.300112 -78.97539) (xy 238.342492 -79.01777) (xy 238.378979 -79.06532)
			(xy 238.408946 -79.117226) (xy 238.431882 -79.172599) (xy 238.447395 -79.230492) (xy 238.455218 -79.289914)
			(xy 238.455708 -79.319882) (xy 238.455708 -80.183482) (xy 238.455218 -80.21345) (xy 238.447395 -80.272872)
			(xy 238.431882 -80.330765) (xy 238.408946 -80.386138) (xy 238.378979 -80.438044) (xy 238.342492 -80.485594)
			(xy 238.300112 -80.527974) (xy 238.252562 -80.564461) (xy 238.200656 -80.594428) (xy 238.145283 -80.617364)
			(xy 238.08739 -80.632877) (xy 238.027968 -80.6407) (xy 237.968032 -80.6407) (xy 237.90861 -80.632877)
			(xy 237.850717 -80.617364) (xy 237.795344 -80.594428) (xy 237.743438 -80.564461) (xy 237.695888 -80.527974)
			(xy 237.653508 -80.485594) (xy 237.617021 -80.438044) (xy 237.587054 -80.386138) (xy 237.564118 -80.330765)
			(xy 237.548605 -80.272872) (xy 237.540782 -80.21345) (xy 237.540292 -80.183482) (xy 0.509016 -80.183482)
			(xy 0.509016 -82.131916) (xy 0.5095 -82.185129) (xy 0.517108 -82.291282) (xy 0.532268 -82.396623)
			(xy 0.554903 -82.500614) (xy 0.584898 -82.602726) (xy 0.622099 -82.702438) (xy 0.666318 -82.799243)
			(xy 0.717328 -82.892647) (xy 0.774871 -82.982175) (xy 0.838652 -83.067371) (xy 0.908348 -83.147801)
			(xy 0.945642 -83.185762) (xy 2.78524 -85.025538) (xy 44.856389 -85.025538) (xy 44.856389 -84.896398)
			(xy 44.864339 -84.767503) (xy 44.880209 -84.639343) (xy 44.903938 -84.512402) (xy 44.935437 -84.387163)
			(xy 44.974586 -84.2641) (xy 45.021237 -84.143681) (xy 45.075212 -84.026362) (xy 45.136307 -83.912588)
			(xy 45.20429 -83.802791) (xy 45.278904 -83.697388) (xy 45.359865 -83.596778) (xy 45.446865 -83.501343)
			(xy 45.539576 -83.411444) (xy 45.637646 -83.327423) (xy 45.740701 -83.249599) (xy 45.848352 -83.178267)
			(xy 45.960191 -83.113697) (xy 46.075792 -83.056135) (xy 46.194717 -83.005798) (xy 46.316516 -82.962878)
			(xy 46.440726 -82.927537) (xy 46.566875 -82.89991) (xy 46.694487 -82.880101) (xy 46.823076 -82.868185)
			(xy 46.952154 -82.864209) (xy 47.081232 -82.868185) (xy 47.209821 -82.880101) (xy 47.337433 -82.89991)
			(xy 47.463582 -82.927537) (xy 47.587792 -82.962878) (xy 47.709591 -83.005798) (xy 47.828516 -83.056135)
			(xy 47.944117 -83.113697) (xy 48.055956 -83.178267) (xy 48.163607 -83.249599) (xy 48.266662 -83.327423)
			(xy 48.303507 -83.35899) (xy 116.623592 -83.35899) (xy 116.623592 -82.49539) (xy 116.624082 -82.465422)
			(xy 116.631905 -82.406) (xy 116.647418 -82.348107) (xy 116.670354 -82.292734) (xy 116.700321 -82.240828)
			(xy 116.736808 -82.193278) (xy 116.779188 -82.150898) (xy 116.826738 -82.114411) (xy 116.878644 -82.084444)
			(xy 116.934017 -82.061508) (xy 116.99191 -82.045995) (xy 117.051332 -82.038172) (xy 117.111268 -82.038172)
			(xy 117.17069 -82.045995) (xy 117.228583 -82.061508) (xy 117.283956 -82.084444) (xy 117.335862 -82.114411)
			(xy 117.383412 -82.150898) (xy 117.425792 -82.193278) (xy 117.462279 -82.240828) (xy 117.492246 -82.292734)
			(xy 117.515182 -82.348107) (xy 117.530695 -82.406) (xy 117.538518 -82.465422) (xy 117.539008 -82.49539)
			(xy 117.539008 -83.35899) (xy 117.538875 -83.367118) (xy 232.68432 -83.367118) (xy 232.68432 -82.503518)
			(xy 232.68481 -82.47355) (xy 232.692633 -82.414128) (xy 232.708146 -82.356235) (xy 232.731082 -82.300862)
			(xy 232.761049 -82.248956) (xy 232.797536 -82.201406) (xy 232.839916 -82.159026) (xy 232.887466 -82.122539)
			(xy 232.939372 -82.092572) (xy 232.994745 -82.069636) (xy 233.052638 -82.054123) (xy 233.11206 -82.0463)
			(xy 233.171996 -82.0463) (xy 233.231418 -82.054123) (xy 233.289311 -82.069636) (xy 233.344684 -82.092572)
			(xy 233.39659 -82.122539) (xy 233.44414 -82.159026) (xy 233.48652 -82.201406) (xy 233.523007 -82.248956)
			(xy 233.552974 -82.300862) (xy 233.568014 -82.337171) (xy 238.132537 -82.337171) (xy 238.132537 -82.277229)
			(xy 238.140362 -82.217799) (xy 238.155876 -82.159898) (xy 238.178816 -82.104519) (xy 238.208788 -82.052607)
			(xy 238.24528 -82.005052) (xy 238.287667 -81.962667) (xy 238.335224 -81.926177) (xy 238.387137 -81.896207)
			(xy 238.442517 -81.87327) (xy 238.500418 -81.857758) (xy 238.559849 -81.849936) (xy 238.58982 -81.849468)
			(xy 239.45342 -81.849468) (xy 239.483385 -81.850007) (xy 239.542803 -81.857832) (xy 239.600691 -81.873345)
			(xy 239.656058 -81.896282) (xy 239.707959 -81.926248) (xy 239.755504 -81.962733) (xy 239.769238 -81.976468)
			(xy 273.798284 -81.976468) (xy 273.798284 -81.112868) (xy 273.798774 -81.0829) (xy 273.806597 -81.023478)
			(xy 273.82211 -80.965585) (xy 273.845046 -80.910212) (xy 273.875013 -80.858306) (xy 273.9115 -80.810756)
			(xy 273.95388 -80.768376) (xy 274.00143 -80.731889) (xy 274.053336 -80.701922) (xy 274.108709 -80.678986)
			(xy 274.166602 -80.663473) (xy 274.226024 -80.65565) (xy 274.28596 -80.65565) (xy 274.345382 -80.663473)
			(xy 274.403275 -80.678986) (xy 274.458648 -80.701922) (xy 274.510554 -80.731889) (xy 274.558104 -80.768376)
			(xy 274.600484 -80.810756) (xy 274.636971 -80.858306) (xy 274.666938 -80.910212) (xy 274.689874 -80.965585)
			(xy 274.705387 -81.023478) (xy 274.71321 -81.0829) (xy 274.7137 -81.112868) (xy 274.7137 -81.976468)
			(xy 274.71321 -82.006436) (xy 274.705387 -82.065858) (xy 274.689874 -82.123751) (xy 274.666938 -82.179124)
			(xy 274.636971 -82.23103) (xy 274.600484 -82.27858) (xy 274.558104 -82.32096) (xy 274.510554 -82.357447)
			(xy 274.458648 -82.387414) (xy 274.403275 -82.41035) (xy 274.345382 -82.425863) (xy 274.28596 -82.433686)
			(xy 274.226024 -82.433686) (xy 274.166602 -82.425863) (xy 274.108709 -82.41035) (xy 274.053336 -82.387414)
			(xy 274.00143 -82.357447) (xy 273.95388 -82.32096) (xy 273.9115 -82.27858) (xy 273.875013 -82.23103)
			(xy 273.845046 -82.179124) (xy 273.82211 -82.123751) (xy 273.806597 -82.065858) (xy 273.798774 -82.006436)
			(xy 273.798284 -81.976468) (xy 239.769238 -81.976468) (xy 239.79788 -82.005111) (xy 239.834363 -82.052658)
			(xy 239.864327 -82.10456) (xy 239.887261 -82.159928) (xy 239.902772 -82.217817) (xy 239.910594 -82.277235)
			(xy 239.910594 -82.337165) (xy 239.902772 -82.396583) (xy 239.887261 -82.454472) (xy 239.864327 -82.50984)
			(xy 239.834363 -82.561742) (xy 239.79788 -82.609289) (xy 239.755504 -82.651667) (xy 239.707959 -82.688152)
			(xy 239.656058 -82.718118) (xy 239.600691 -82.741055) (xy 239.542803 -82.756568) (xy 239.483385 -82.764393)
			(xy 239.45342 -82.764884) (xy 238.58982 -82.764884) (xy 238.559849 -82.764464) (xy 238.500418 -82.756642)
			(xy 238.442517 -82.74113) (xy 238.387137 -82.718193) (xy 238.335224 -82.688223) (xy 238.287667 -82.651733)
			(xy 238.24528 -82.609348) (xy 238.208788 -82.561793) (xy 238.178816 -82.509881) (xy 238.155876 -82.454502)
			(xy 238.140362 -82.396601) (xy 238.132537 -82.337171) (xy 233.568014 -82.337171) (xy 233.57591 -82.356235)
			(xy 233.591423 -82.414128) (xy 233.599246 -82.47355) (xy 233.599736 -82.503518) (xy 233.599736 -83.367118)
			(xy 233.599246 -83.397086) (xy 233.591423 -83.456508) (xy 233.57591 -83.514401) (xy 233.552974 -83.569774)
			(xy 233.523007 -83.62168) (xy 233.48652 -83.66923) (xy 233.44414 -83.71161) (xy 233.39659 -83.748097)
			(xy 233.344684 -83.778064) (xy 233.289311 -83.801) (xy 233.231418 -83.816513) (xy 233.171996 -83.824336)
			(xy 233.11206 -83.824336) (xy 233.052638 -83.816513) (xy 232.994745 -83.801) (xy 232.939372 -83.778064)
			(xy 232.887466 -83.748097) (xy 232.839916 -83.71161) (xy 232.797536 -83.66923) (xy 232.761049 -83.62168)
			(xy 232.731082 -83.569774) (xy 232.708146 -83.514401) (xy 232.692633 -83.456508) (xy 232.68481 -83.397086)
			(xy 232.68432 -83.367118) (xy 117.538875 -83.367118) (xy 117.538518 -83.388958) (xy 117.530695 -83.44838)
			(xy 117.515182 -83.506273) (xy 117.492246 -83.561646) (xy 117.462279 -83.613552) (xy 117.425792 -83.661102)
			(xy 117.383412 -83.703482) (xy 117.335862 -83.739969) (xy 117.283956 -83.769936) (xy 117.228583 -83.792872)
			(xy 117.17069 -83.808385) (xy 117.111268 -83.816208) (xy 117.051332 -83.816208) (xy 116.99191 -83.808385)
			(xy 116.934017 -83.792872) (xy 116.878644 -83.769936) (xy 116.826738 -83.739969) (xy 116.779188 -83.703482)
			(xy 116.736808 -83.661102) (xy 116.700321 -83.613552) (xy 116.670354 -83.561646) (xy 116.647418 -83.506273)
			(xy 116.631905 -83.44838) (xy 116.624082 -83.388958) (xy 116.623592 -83.35899) (xy 48.303507 -83.35899)
			(xy 48.364732 -83.411444) (xy 48.457443 -83.501343) (xy 48.544443 -83.596778) (xy 48.625404 -83.697388)
			(xy 48.700018 -83.802791) (xy 48.768001 -83.912588) (xy 48.829096 -84.026362) (xy 48.883071 -84.143681)
			(xy 48.929722 -84.2641) (xy 48.968871 -84.387163) (xy 49.00037 -84.512402) (xy 49.024099 -84.639343)
			(xy 49.039969 -84.767503) (xy 49.047919 -84.896398) (xy 49.048416 -84.960968) (xy 49.047919 -85.025538)
			(xy 49.039969 -85.154433) (xy 49.024099 -85.282593) (xy 49.009819 -85.358986) (xy 117.385592 -85.358986)
			(xy 117.385592 -84.495386) (xy 117.386082 -84.465418) (xy 117.393905 -84.405996) (xy 117.409418 -84.348103)
			(xy 117.432354 -84.29273) (xy 117.462321 -84.240824) (xy 117.498808 -84.193274) (xy 117.541188 -84.150894)
			(xy 117.588738 -84.114407) (xy 117.640644 -84.08444) (xy 117.696017 -84.061504) (xy 117.75391 -84.045991)
			(xy 117.813332 -84.038168) (xy 117.873268 -84.038168) (xy 117.93269 -84.045991) (xy 117.990583 -84.061504)
			(xy 118.045956 -84.08444) (xy 118.097862 -84.114407) (xy 118.145412 -84.150894) (xy 118.187792 -84.193274)
			(xy 118.224279 -84.240824) (xy 118.254246 -84.29273) (xy 118.277182 -84.348103) (xy 118.292695 -84.405996)
			(xy 118.300518 -84.465418) (xy 118.301008 -84.495386) (xy 118.301008 -85.358986) (xy 118.300518 -85.388954)
			(xy 118.292695 -85.448376) (xy 118.289959 -85.458587) (xy 232.264389 -85.458587) (xy 232.264389 -85.398613)
			(xy 232.272218 -85.339151) (xy 232.28774 -85.28122) (xy 232.310692 -85.225811) (xy 232.34068 -85.173871)
			(xy 232.377191 -85.126291) (xy 232.4196 -85.083883) (xy 232.467181 -85.047373) (xy 232.519122 -85.017387)
			(xy 232.574531 -84.994437) (xy 232.632463 -84.978915) (xy 232.691925 -84.971088) (xy 232.721912 -84.97062)
			(xy 233.585512 -84.97062) (xy 233.615495 -84.971147) (xy 233.674947 -84.978975) (xy 233.732868 -84.994497)
			(xy 233.788268 -85.017445) (xy 233.840199 -85.047429) (xy 233.887772 -85.083934) (xy 233.930174 -85.126337)
			(xy 233.963295 -85.169502) (xy 238.555276 -85.169502) (xy 238.555276 -84.305902) (xy 238.555766 -84.275918)
			(xy 238.563594 -84.216462) (xy 238.579115 -84.158537) (xy 238.602064 -84.103133) (xy 238.632048 -84.051199)
			(xy 238.668554 -84.003623) (xy 238.710959 -83.961218) (xy 238.758535 -83.924712) (xy 238.810469 -83.894728)
			(xy 238.865873 -83.871779) (xy 238.923798 -83.856258) (xy 238.983254 -83.84843) (xy 239.043222 -83.84843)
			(xy 239.102678 -83.856258) (xy 239.160603 -83.871779) (xy 239.216007 -83.894728) (xy 239.267941 -83.924712)
			(xy 239.315517 -83.961218) (xy 239.357922 -84.003623) (xy 239.394428 -84.051199) (xy 239.424412 -84.103133)
			(xy 239.447361 -84.158537) (xy 239.462882 -84.216462) (xy 239.46603 -84.24037) (xy 273.951192 -84.24037)
			(xy 273.951192 -83.37677) (xy 273.951682 -83.346786) (xy 273.95951 -83.28733) (xy 273.975031 -83.229405)
			(xy 273.99798 -83.174001) (xy 274.027964 -83.122067) (xy 274.06447 -83.074491) (xy 274.106875 -83.032086)
			(xy 274.154451 -82.99558) (xy 274.206385 -82.965596) (xy 274.261789 -82.942647) (xy 274.319714 -82.927126)
			(xy 274.37917 -82.919298) (xy 274.439138 -82.919298) (xy 274.498594 -82.927126) (xy 274.556519 -82.942647)
			(xy 274.611923 -82.965596) (xy 274.663857 -82.99558) (xy 274.711433 -83.032086) (xy 274.753838 -83.074491)
			(xy 274.790344 -83.122067) (xy 274.820328 -83.174001) (xy 274.843277 -83.229405) (xy 274.858798 -83.28733)
			(xy 274.866626 -83.346786) (xy 274.867116 -83.37677) (xy 274.867116 -84.144612) (xy 345.879928 -84.144612)
			(xy 345.879928 -83.281012) (xy 345.880418 -83.251028) (xy 345.888246 -83.191572) (xy 345.903767 -83.133647)
			(xy 345.926716 -83.078243) (xy 345.9567 -83.026309) (xy 345.993206 -82.978733) (xy 346.035611 -82.936328)
			(xy 346.083187 -82.899822) (xy 346.135121 -82.869838) (xy 346.190525 -82.846889) (xy 346.24845 -82.831368)
			(xy 346.307906 -82.82354) (xy 346.367874 -82.82354) (xy 346.42733 -82.831368) (xy 346.485255 -82.846889)
			(xy 346.540659 -82.869838) (xy 346.592593 -82.899822) (xy 346.640169 -82.936328) (xy 346.682574 -82.978733)
			(xy 346.71908 -83.026309) (xy 346.749064 -83.078243) (xy 346.772013 -83.133647) (xy 346.787534 -83.191572)
			(xy 346.795362 -83.251028) (xy 346.795852 -83.281012) (xy 346.795852 -84.144612) (xy 346.795362 -84.174596)
			(xy 346.787534 -84.234052) (xy 346.772013 -84.291977) (xy 346.749064 -84.347381) (xy 346.71908 -84.399315)
			(xy 346.682574 -84.446891) (xy 346.640169 -84.489296) (xy 346.592593 -84.525802) (xy 346.540659 -84.555786)
			(xy 346.485255 -84.578735) (xy 346.42733 -84.594256) (xy 346.367874 -84.602084) (xy 346.307906 -84.602084)
			(xy 346.24845 -84.594256) (xy 346.190525 -84.578735) (xy 346.135121 -84.555786) (xy 346.083187 -84.525802)
			(xy 346.035611 -84.489296) (xy 345.993206 -84.446891) (xy 345.9567 -84.399315) (xy 345.926716 -84.347381)
			(xy 345.903767 -84.291977) (xy 345.888246 -84.234052) (xy 345.880418 -84.174596) (xy 345.879928 -84.144612)
			(xy 274.867116 -84.144612) (xy 274.867116 -84.24037) (xy 274.866626 -84.270354) (xy 274.858798 -84.32981)
			(xy 274.843277 -84.387735) (xy 274.820328 -84.443139) (xy 274.790344 -84.495073) (xy 274.753838 -84.542649)
			(xy 274.711433 -84.585054) (xy 274.663857 -84.62156) (xy 274.611923 -84.651544) (xy 274.556519 -84.674493)
			(xy 274.498594 -84.690014) (xy 274.439138 -84.697842) (xy 274.37917 -84.697842) (xy 274.319714 -84.690014)
			(xy 274.261789 -84.674493) (xy 274.206385 -84.651544) (xy 274.154451 -84.62156) (xy 274.106875 -84.585054)
			(xy 274.06447 -84.542649) (xy 274.027964 -84.495073) (xy 273.99798 -84.443139) (xy 273.975031 -84.387735)
			(xy 273.95951 -84.32981) (xy 273.951682 -84.270354) (xy 273.951192 -84.24037) (xy 239.46603 -84.24037)
			(xy 239.47071 -84.275918) (xy 239.4712 -84.305902) (xy 239.4712 -85.169502) (xy 239.47071 -85.199486)
			(xy 239.462882 -85.258942) (xy 239.447361 -85.316867) (xy 239.424412 -85.372271) (xy 239.394428 -85.424205)
			(xy 239.357922 -85.471781) (xy 239.315517 -85.514186) (xy 239.267941 -85.550692) (xy 239.216007 -85.580676)
			(xy 239.160603 -85.603625) (xy 239.102678 -85.619146) (xy 239.043222 -85.626974) (xy 238.983254 -85.626974)
			(xy 238.923798 -85.619146) (xy 238.865873 -85.603625) (xy 238.810469 -85.580676) (xy 238.758535 -85.550692)
			(xy 238.710959 -85.514186) (xy 238.668554 -85.471781) (xy 238.632048 -85.424205) (xy 238.602064 -85.372271)
			(xy 238.579115 -85.316867) (xy 238.563594 -85.258942) (xy 238.555766 -85.199486) (xy 238.555276 -85.169502)
			(xy 233.963295 -85.169502) (xy 233.966678 -85.173911) (xy 233.99666 -85.225842) (xy 234.019607 -85.281243)
			(xy 234.035127 -85.339165) (xy 234.042954 -85.398617) (xy 234.042954 -85.458583) (xy 234.035127 -85.518035)
			(xy 234.019607 -85.575957) (xy 233.99666 -85.631358) (xy 233.966678 -85.683289) (xy 233.930174 -85.730863)
			(xy 233.887772 -85.773266) (xy 233.840199 -85.809771) (xy 233.788268 -85.839755) (xy 233.732868 -85.862703)
			(xy 233.674947 -85.878225) (xy 233.615495 -85.886053) (xy 233.585512 -85.886544) (xy 232.721912 -85.886544)
			(xy 232.691925 -85.886112) (xy 232.632463 -85.878285) (xy 232.574531 -85.862763) (xy 232.519122 -85.839813)
			(xy 232.467181 -85.809827) (xy 232.4196 -85.773317) (xy 232.377191 -85.730909) (xy 232.34068 -85.683329)
			(xy 232.310692 -85.631389) (xy 232.28774 -85.57598) (xy 232.272218 -85.518049) (xy 232.264389 -85.458587)
			(xy 118.289959 -85.458587) (xy 118.277182 -85.506269) (xy 118.254246 -85.561642) (xy 118.224279 -85.613548)
			(xy 118.187792 -85.661098) (xy 118.145412 -85.703478) (xy 118.097862 -85.739965) (xy 118.045956 -85.769932)
			(xy 117.990583 -85.792868) (xy 117.93269 -85.808381) (xy 117.873268 -85.816204) (xy 117.813332 -85.816204)
			(xy 117.75391 -85.808381) (xy 117.696017 -85.792868) (xy 117.640644 -85.769932) (xy 117.588738 -85.739965)
			(xy 117.541188 -85.703478) (xy 117.498808 -85.661098) (xy 117.462321 -85.613548) (xy 117.432354 -85.561642)
			(xy 117.409418 -85.506269) (xy 117.393905 -85.448376) (xy 117.386082 -85.388954) (xy 117.385592 -85.358986)
			(xy 49.009819 -85.358986) (xy 49.00037 -85.409534) (xy 48.968871 -85.534773) (xy 48.929722 -85.657836)
			(xy 48.883071 -85.778255) (xy 48.829096 -85.895574) (xy 48.768001 -86.009348) (xy 48.700018 -86.119145)
			(xy 48.625404 -86.224548) (xy 48.544443 -86.325158) (xy 48.457443 -86.420593) (xy 48.364732 -86.510492)
			(xy 48.266662 -86.594513) (xy 48.163607 -86.672337) (xy 48.055956 -86.743669) (xy 47.944117 -86.808239)
			(xy 47.937853 -86.811358) (xy 99.84232 -86.811358) (xy 99.84232 -85.947758) (xy 99.84281 -85.917774)
			(xy 99.850638 -85.858318) (xy 99.866159 -85.800393) (xy 99.889108 -85.744989) (xy 99.919092 -85.693055)
			(xy 99.955598 -85.645479) (xy 99.998003 -85.603074) (xy 100.045579 -85.566568) (xy 100.097513 -85.536584)
			(xy 100.152917 -85.513635) (xy 100.210842 -85.498114) (xy 100.270298 -85.490286) (xy 100.330266 -85.490286)
			(xy 100.389722 -85.498114) (xy 100.447647 -85.513635) (xy 100.503051 -85.536584) (xy 100.554985 -85.566568)
			(xy 100.602561 -85.603074) (xy 100.644966 -85.645479) (xy 100.681472 -85.693055) (xy 100.711456 -85.744989)
			(xy 100.734405 -85.800393) (xy 100.749926 -85.858318) (xy 100.757754 -85.917774) (xy 100.758244 -85.947758)
			(xy 100.758244 -86.811358) (xy 100.757754 -86.841342) (xy 100.749926 -86.900798) (xy 100.734405 -86.958723)
			(xy 100.711456 -87.014127) (xy 100.681472 -87.066061) (xy 100.644966 -87.113637) (xy 100.602561 -87.156042)
			(xy 100.554985 -87.192548) (xy 100.503051 -87.222532) (xy 100.447647 -87.245481) (xy 100.389722 -87.261002)
			(xy 100.330266 -87.26883) (xy 100.270298 -87.26883) (xy 100.210842 -87.261002) (xy 100.152917 -87.245481)
			(xy 100.097513 -87.222532) (xy 100.045579 -87.192548) (xy 99.998003 -87.156042) (xy 99.955598 -87.113637)
			(xy 99.919092 -87.066061) (xy 99.889108 -87.014127) (xy 99.866159 -86.958723) (xy 99.850638 -86.900798)
			(xy 99.84281 -86.841342) (xy 99.84232 -86.811358) (xy 47.937853 -86.811358) (xy 47.828516 -86.865801)
			(xy 47.709591 -86.916138) (xy 47.587792 -86.959058) (xy 47.463582 -86.994399) (xy 47.337433 -87.022026)
			(xy 47.209821 -87.041835) (xy 47.081232 -87.053751) (xy 46.952154 -87.057728) (xy 46.823076 -87.053751)
			(xy 46.694487 -87.041835) (xy 46.566875 -87.022026) (xy 46.440726 -86.994399) (xy 46.316516 -86.959058)
			(xy 46.194717 -86.916138) (xy 46.075792 -86.865801) (xy 45.960191 -86.808239) (xy 45.848352 -86.743669)
			(xy 45.740701 -86.672337) (xy 45.637646 -86.594513) (xy 45.539576 -86.510492) (xy 45.446865 -86.420593)
			(xy 45.359865 -86.325158) (xy 45.278904 -86.224548) (xy 45.20429 -86.119145) (xy 45.136307 -86.009348)
			(xy 45.075212 -85.895574) (xy 45.021237 -85.778255) (xy 44.974586 -85.657836) (xy 44.935437 -85.534773)
			(xy 44.903938 -85.409534) (xy 44.880209 -85.282593) (xy 44.864339 -85.154433) (xy 44.856389 -85.025538)
			(xy 2.78524 -85.025538) (xy 3.574034 -85.814408) (xy 3.623456 -85.864516) (xy 3.717262 -85.969457)
			(xy 3.805036 -86.079494) (xy 3.886503 -86.194278) (xy 3.961406 -86.31345) (xy 4.029509 -86.436634)
			(xy 4.090598 -86.563442) (xy 4.144481 -86.693477) (xy 4.190988 -86.826327) (xy 4.229973 -86.961577)
			(xy 4.261314 -87.0988) (xy 4.284912 -87.237564) (xy 4.29861 -87.358982) (xy 116.623592 -87.358982)
			(xy 116.623592 -86.495382) (xy 116.624082 -86.465414) (xy 116.631905 -86.405992) (xy 116.647418 -86.348099)
			(xy 116.670354 -86.292726) (xy 116.700321 -86.24082) (xy 116.736808 -86.19327) (xy 116.779188 -86.15089)
			(xy 116.826738 -86.114403) (xy 116.878644 -86.084436) (xy 116.934017 -86.0615) (xy 116.99191 -86.045987)
			(xy 117.051332 -86.038164) (xy 117.111268 -86.038164) (xy 117.17069 -86.045987) (xy 117.228583 -86.0615)
			(xy 117.283956 -86.084436) (xy 117.335862 -86.114403) (xy 117.383412 -86.15089) (xy 117.425792 -86.19327)
			(xy 117.462279 -86.24082) (xy 117.492246 -86.292726) (xy 117.515182 -86.348099) (xy 117.530695 -86.405992)
			(xy 117.538518 -86.465414) (xy 117.539008 -86.495382) (xy 117.539008 -87.358982) (xy 117.538518 -87.38895)
			(xy 117.531262 -87.444066) (xy 232.194882 -87.444066) (xy 232.194882 -87.384134) (xy 232.202704 -87.324714)
			(xy 232.218215 -87.266824) (xy 232.241149 -87.211454) (xy 232.271114 -87.15955) (xy 232.307596 -87.112002)
			(xy 232.349973 -87.069621) (xy 232.397519 -87.033135) (xy 232.44942 -87.003166) (xy 232.504788 -86.980227)
			(xy 232.562677 -86.964712) (xy 232.622096 -86.956884) (xy 232.652062 -86.956392) (xy 233.515662 -86.956392)
			(xy 233.545633 -86.956859) (xy 233.605062 -86.964678) (xy 233.662961 -86.980188) (xy 233.718341 -87.003123)
			(xy 233.770254 -87.033091) (xy 233.81781 -87.069578) (xy 233.860197 -87.111961) (xy 233.896688 -87.159515)
			(xy 233.92666 -87.211425) (xy 233.9496 -87.266803) (xy 233.965115 -87.324701) (xy 233.972939 -87.384129)
			(xy 233.972939 -87.416385) (xy 234.381521 -87.416385) (xy 234.381521 -87.356415) (xy 234.389349 -87.296959)
			(xy 234.40487 -87.239032) (xy 234.42782 -87.183628) (xy 234.457804 -87.131692) (xy 234.494312 -87.084115)
			(xy 234.536717 -87.04171) (xy 234.584294 -87.005203) (xy 234.636229 -86.975219) (xy 234.691634 -86.952269)
			(xy 234.749561 -86.936748) (xy 234.809017 -86.928921) (xy 234.839002 -86.928452) (xy 235.702602 -86.928452)
			(xy 235.732587 -86.928914) (xy 235.792044 -86.936742) (xy 235.849971 -86.952264) (xy 235.905376 -86.975214)
			(xy 235.957312 -87.005199) (xy 236.004889 -87.041707) (xy 236.047295 -87.084112) (xy 236.083802 -87.13169)
			(xy 236.113787 -87.183626) (xy 236.136737 -87.239031) (xy 236.152258 -87.296958) (xy 236.155843 -87.324184)
			(xy 330.477876 -87.324184) (xy 330.477876 -86.460584) (xy 330.478366 -86.430616) (xy 330.486189 -86.371194)
			(xy 330.501702 -86.313301) (xy 330.524638 -86.257928) (xy 330.554605 -86.206022) (xy 330.591092 -86.158472)
			(xy 330.633472 -86.116092) (xy 330.681022 -86.079605) (xy 330.732928 -86.049638) (xy 330.788301 -86.026702)
			(xy 330.846194 -86.011189) (xy 330.905616 -86.003366) (xy 330.965552 -86.003366) (xy 331.024974 -86.011189)
			(xy 331.082867 -86.026702) (xy 331.13824 -86.049638) (xy 331.190146 -86.079605) (xy 331.237696 -86.116092)
			(xy 331.266212 -86.144608) (xy 346.641928 -86.144608) (xy 346.641928 -85.281008) (xy 346.642418 -85.251024)
			(xy 346.650246 -85.191568) (xy 346.665767 -85.133643) (xy 346.688716 -85.078239) (xy 346.7187 -85.026305)
			(xy 346.755206 -84.978729) (xy 346.797611 -84.936324) (xy 346.845187 -84.899818) (xy 346.897121 -84.869834)
			(xy 346.952525 -84.846885) (xy 347.01045 -84.831364) (xy 347.069906 -84.823536) (xy 347.129874 -84.823536)
			(xy 347.18933 -84.831364) (xy 347.247255 -84.846885) (xy 347.302659 -84.869834) (xy 347.354593 -84.899818)
			(xy 347.402169 -84.936324) (xy 347.444574 -84.978729) (xy 347.48108 -85.026305) (xy 347.511064 -85.078239)
			(xy 347.534013 -85.133643) (xy 347.549534 -85.191568) (xy 347.557362 -85.251024) (xy 347.557852 -85.281008)
			(xy 347.557852 -86.144608) (xy 347.557362 -86.174592) (xy 347.549534 -86.234048) (xy 347.534013 -86.291973)
			(xy 347.511064 -86.347377) (xy 347.48108 -86.399311) (xy 347.444574 -86.446887) (xy 347.402169 -86.489292)
			(xy 347.354593 -86.525798) (xy 347.302659 -86.555782) (xy 347.247255 -86.578731) (xy 347.18933 -86.594252)
			(xy 347.129874 -86.60208) (xy 347.069906 -86.60208) (xy 347.01045 -86.594252) (xy 346.952525 -86.578731)
			(xy 346.897121 -86.555782) (xy 346.845187 -86.525798) (xy 346.797611 -86.489292) (xy 346.755206 -86.446887)
			(xy 346.7187 -86.399311) (xy 346.688716 -86.347377) (xy 346.665767 -86.291973) (xy 346.650246 -86.234048)
			(xy 346.642418 -86.174592) (xy 346.641928 -86.144608) (xy 331.266212 -86.144608) (xy 331.280076 -86.158472)
			(xy 331.316563 -86.206022) (xy 331.34653 -86.257928) (xy 331.369466 -86.313301) (xy 331.384979 -86.371194)
			(xy 331.392802 -86.430616) (xy 331.393292 -86.460584) (xy 331.393292 -87.324184) (xy 331.392802 -87.354152)
			(xy 331.384979 -87.413574) (xy 331.369466 -87.471467) (xy 331.34653 -87.52684) (xy 331.316563 -87.578746)
			(xy 331.280076 -87.626296) (xy 331.237696 -87.668676) (xy 331.190146 -87.705163) (xy 331.13824 -87.73513)
			(xy 331.082867 -87.758066) (xy 331.024974 -87.773579) (xy 330.965552 -87.781402) (xy 330.905616 -87.781402)
			(xy 330.846194 -87.773579) (xy 330.788301 -87.758066) (xy 330.732928 -87.73513) (xy 330.681022 -87.705163)
			(xy 330.633472 -87.668676) (xy 330.591092 -87.626296) (xy 330.554605 -87.578746) (xy 330.524638 -87.52684)
			(xy 330.501702 -87.471467) (xy 330.486189 -87.413574) (xy 330.478366 -87.354152) (xy 330.477876 -87.324184)
			(xy 236.155843 -87.324184) (xy 236.160086 -87.356415) (xy 236.160086 -87.416385) (xy 236.152258 -87.475842)
			(xy 236.136737 -87.533769) (xy 236.113787 -87.589174) (xy 236.083802 -87.64111) (xy 236.047295 -87.688688)
			(xy 236.004889 -87.731093) (xy 235.957312 -87.767601) (xy 235.905376 -87.797586) (xy 235.849971 -87.820536)
			(xy 235.792044 -87.836058) (xy 235.732587 -87.843886) (xy 235.702602 -87.844376) (xy 234.839002 -87.844376)
			(xy 234.809017 -87.843879) (xy 234.749561 -87.836052) (xy 234.691634 -87.820531) (xy 234.636229 -87.797581)
			(xy 234.584294 -87.767597) (xy 234.536717 -87.73109) (xy 234.494312 -87.688685) (xy 234.457804 -87.641108)
			(xy 234.42782 -87.589172) (xy 234.40487 -87.533768) (xy 234.389349 -87.475841) (xy 234.381521 -87.416385)
			(xy 233.972939 -87.416385) (xy 233.972939 -87.444071) (xy 233.965115 -87.503499) (xy 233.9496 -87.561397)
			(xy 233.92666 -87.616775) (xy 233.896688 -87.668685) (xy 233.860197 -87.716239) (xy 233.81781 -87.758622)
			(xy 233.770254 -87.795109) (xy 233.718341 -87.825077) (xy 233.662961 -87.848012) (xy 233.605062 -87.863522)
			(xy 233.545633 -87.871341) (xy 233.515662 -87.871808) (xy 232.652062 -87.871808) (xy 232.622096 -87.871316)
			(xy 232.562677 -87.863488) (xy 232.504788 -87.847973) (xy 232.44942 -87.825034) (xy 232.397519 -87.795065)
			(xy 232.349973 -87.758579) (xy 232.307596 -87.716198) (xy 232.271114 -87.66865) (xy 232.241149 -87.616746)
			(xy 232.218215 -87.561376) (xy 232.202704 -87.503486) (xy 232.194882 -87.444066) (xy 117.531262 -87.444066)
			(xy 117.530695 -87.448372) (xy 117.515182 -87.506265) (xy 117.492246 -87.561638) (xy 117.462279 -87.613544)
			(xy 117.425792 -87.661094) (xy 117.383412 -87.703474) (xy 117.335862 -87.739961) (xy 117.283956 -87.769928)
			(xy 117.228583 -87.792864) (xy 117.17069 -87.808377) (xy 117.111268 -87.8162) (xy 117.051332 -87.8162)
			(xy 116.99191 -87.808377) (xy 116.934017 -87.792864) (xy 116.878644 -87.769928) (xy 116.826738 -87.739961)
			(xy 116.779188 -87.703474) (xy 116.736808 -87.661094) (xy 116.700321 -87.613544) (xy 116.670354 -87.561638)
			(xy 116.647418 -87.506265) (xy 116.631905 -87.448372) (xy 116.624082 -87.38895) (xy 116.623592 -87.358982)
			(xy 4.29861 -87.358982) (xy 4.300692 -87.377432) (xy 4.308605 -87.517966) (xy 4.30911 -87.588344)
			(xy 4.30911 -88.006187) (xy 238.124409 -88.006187) (xy 238.124409 -87.946213) (xy 238.132238 -87.886751)
			(xy 238.147762 -87.82882) (xy 238.170714 -87.773411) (xy 238.200704 -87.721472) (xy 238.237216 -87.673892)
			(xy 238.279627 -87.631486) (xy 238.32721 -87.594978) (xy 238.379152 -87.564994) (xy 238.434563 -87.542047)
			(xy 238.492496 -87.526529) (xy 238.551959 -87.518706) (xy 238.581946 -87.51824) (xy 239.445546 -87.51824)
			(xy 239.475528 -87.518729) (xy 239.53498 -87.526561) (xy 239.5929 -87.542086) (xy 239.648299 -87.565038)
			(xy 239.700228 -87.595024) (xy 239.747799 -87.631531) (xy 239.790199 -87.673935) (xy 239.826701 -87.72151)
			(xy 239.856682 -87.773442) (xy 239.879628 -87.828843) (xy 239.895148 -87.886765) (xy 239.902974 -87.946217)
			(xy 239.902974 -88.006183) (xy 239.895148 -88.065635) (xy 239.879628 -88.123557) (xy 239.870911 -88.144604)
			(xy 345.879928 -88.144604) (xy 345.879928 -87.281004) (xy 345.880418 -87.25102) (xy 345.888246 -87.191564)
			(xy 345.903767 -87.133639) (xy 345.926716 -87.078235) (xy 345.9567 -87.026301) (xy 345.993206 -86.978725)
			(xy 346.035611 -86.93632) (xy 346.083187 -86.899814) (xy 346.135121 -86.86983) (xy 346.190525 -86.846881)
			(xy 346.24845 -86.83136) (xy 346.307906 -86.823532) (xy 346.367874 -86.823532) (xy 346.42733 -86.83136)
			(xy 346.485255 -86.846881) (xy 346.540659 -86.86983) (xy 346.592593 -86.899814) (xy 346.640169 -86.93632)
			(xy 346.682574 -86.978725) (xy 346.71908 -87.026301) (xy 346.749064 -87.078235) (xy 346.772013 -87.133639)
			(xy 346.787534 -87.191564) (xy 346.795362 -87.25102) (xy 346.795852 -87.281004) (xy 346.795852 -88.144604)
			(xy 346.795362 -88.174588) (xy 346.787534 -88.234044) (xy 346.772013 -88.291969) (xy 346.749064 -88.347373)
			(xy 346.71908 -88.399307) (xy 346.682574 -88.446883) (xy 346.640169 -88.489288) (xy 346.592593 -88.525794)
			(xy 346.540659 -88.555778) (xy 346.485255 -88.578727) (xy 346.42733 -88.594248) (xy 346.367874 -88.602076)
			(xy 346.307906 -88.602076) (xy 346.24845 -88.594248) (xy 346.190525 -88.578727) (xy 346.135121 -88.555778)
			(xy 346.083187 -88.525794) (xy 346.035611 -88.489288) (xy 345.993206 -88.446883) (xy 345.9567 -88.399307)
			(xy 345.926716 -88.347373) (xy 345.903767 -88.291969) (xy 345.888246 -88.234044) (xy 345.880418 -88.174588)
			(xy 345.879928 -88.144604) (xy 239.870911 -88.144604) (xy 239.856682 -88.178958) (xy 239.826701 -88.23089)
			(xy 239.790199 -88.278465) (xy 239.747799 -88.320869) (xy 239.700228 -88.357376) (xy 239.648299 -88.387362)
			(xy 239.5929 -88.410314) (xy 239.53498 -88.425839) (xy 239.475528 -88.433671) (xy 239.445546 -88.434164)
			(xy 238.581946 -88.434164) (xy 238.551959 -88.433694) (xy 238.492496 -88.425871) (xy 238.434563 -88.410353)
			(xy 238.379152 -88.387406) (xy 238.32721 -88.357422) (xy 238.279627 -88.320914) (xy 238.237216 -88.278508)
			(xy 238.200704 -88.230928) (xy 238.170714 -88.178989) (xy 238.147762 -88.12358) (xy 238.132238 -88.065649)
			(xy 238.124409 -88.006187) (xy 4.30911 -88.006187) (xy 4.30911 -89.358978) (xy 117.385592 -89.358978)
			(xy 117.385592 -88.495378) (xy 117.386082 -88.46541) (xy 117.393905 -88.405988) (xy 117.409418 -88.348095)
			(xy 117.432354 -88.292722) (xy 117.462321 -88.240816) (xy 117.498808 -88.193266) (xy 117.541188 -88.150886)
			(xy 117.588738 -88.114399) (xy 117.640644 -88.084432) (xy 117.696017 -88.061496) (xy 117.75391 -88.045983)
			(xy 117.813332 -88.03816) (xy 117.873268 -88.03816) (xy 117.93269 -88.045983) (xy 117.990583 -88.061496)
			(xy 118.045956 -88.084432) (xy 118.097862 -88.114399) (xy 118.145412 -88.150886) (xy 118.187792 -88.193266)
			(xy 118.224279 -88.240816) (xy 118.254246 -88.292722) (xy 118.277182 -88.348095) (xy 118.292695 -88.405988)
			(xy 118.300518 -88.46541) (xy 118.301008 -88.495378) (xy 118.301008 -89.358978) (xy 118.300518 -89.388946)
			(xy 118.292695 -89.448368) (xy 118.277182 -89.506261) (xy 118.254246 -89.561634) (xy 118.224279 -89.61354)
			(xy 118.187792 -89.66109) (xy 118.145412 -89.70347) (xy 118.097862 -89.739957) (xy 118.045956 -89.769924)
			(xy 117.990583 -89.79286) (xy 117.93269 -89.808373) (xy 117.873268 -89.816196) (xy 117.813332 -89.816196)
			(xy 117.75391 -89.808373) (xy 117.696017 -89.79286) (xy 117.640644 -89.769924) (xy 117.588738 -89.739957)
			(xy 117.541188 -89.70347) (xy 117.498808 -89.66109) (xy 117.462321 -89.61354) (xy 117.432354 -89.561634)
			(xy 117.409418 -89.506261) (xy 117.393905 -89.448368) (xy 117.386082 -89.388946) (xy 117.385592 -89.358978)
			(xy 4.30911 -89.358978) (xy 4.30911 -90.1446) (xy 346.641928 -90.1446) (xy 346.641928 -89.281) (xy 346.642418 -89.251016)
			(xy 346.650246 -89.19156) (xy 346.665767 -89.133635) (xy 346.688716 -89.078231) (xy 346.7187 -89.026297)
			(xy 346.755206 -88.978721) (xy 346.797611 -88.936316) (xy 346.845187 -88.89981) (xy 346.897121 -88.869826)
			(xy 346.952525 -88.846877) (xy 347.01045 -88.831356) (xy 347.069906 -88.823528) (xy 347.129874 -88.823528)
			(xy 347.18933 -88.831356) (xy 347.247255 -88.846877) (xy 347.302659 -88.869826) (xy 347.354593 -88.89981)
			(xy 347.402169 -88.936316) (xy 347.444574 -88.978721) (xy 347.48108 -89.026297) (xy 347.511064 -89.078231)
			(xy 347.534013 -89.133635) (xy 347.549534 -89.19156) (xy 347.557362 -89.251016) (xy 347.557852 -89.281)
			(xy 347.557852 -90.1446) (xy 347.557362 -90.174584) (xy 347.549534 -90.23404) (xy 347.534013 -90.291965)
			(xy 347.511064 -90.347369) (xy 347.48108 -90.399303) (xy 347.444574 -90.446879) (xy 347.402169 -90.489284)
			(xy 347.354593 -90.52579) (xy 347.302659 -90.555774) (xy 347.247255 -90.578723) (xy 347.18933 -90.594244)
			(xy 347.129874 -90.602072) (xy 347.069906 -90.602072) (xy 347.01045 -90.594244) (xy 346.952525 -90.578723)
			(xy 346.897121 -90.555774) (xy 346.845187 -90.52579) (xy 346.797611 -90.489284) (xy 346.755206 -90.446879)
			(xy 346.7187 -90.399303) (xy 346.688716 -90.347369) (xy 346.665767 -90.291965) (xy 346.650246 -90.23404)
			(xy 346.642418 -90.174584) (xy 346.641928 -90.1446) (xy 4.30911 -90.1446) (xy 4.30911 -94.088485)
			(xy 109.149614 -94.088485) (xy 109.149614 -94.028515) (xy 109.157442 -93.969058) (xy 109.172963 -93.911131)
			(xy 109.195912 -93.855726) (xy 109.225897 -93.80379) (xy 109.262405 -93.756213) (xy 109.30481 -93.713807)
			(xy 109.352387 -93.6773) (xy 109.404322 -93.647314) (xy 109.459727 -93.624364) (xy 109.517654 -93.608843)
			(xy 109.577111 -93.601014) (xy 109.607096 -93.600524) (xy 110.470696 -93.600524) (xy 110.500681 -93.601021)
			(xy 110.560138 -93.608848) (xy 110.618064 -93.624369) (xy 110.673469 -93.647318) (xy 110.725405 -93.677303)
			(xy 110.772982 -93.71381) (xy 110.815388 -93.756215) (xy 110.851895 -93.803792) (xy 110.88188 -93.855727)
			(xy 110.90483 -93.911132) (xy 110.920351 -93.969058) (xy 110.928179 -94.028515) (xy 110.928179 -94.088485)
			(xy 110.920351 -94.147942) (xy 110.90483 -94.205868) (xy 110.88188 -94.261273) (xy 110.851895 -94.313208)
			(xy 110.815388 -94.360785) (xy 110.772982 -94.40319) (xy 110.725405 -94.439697) (xy 110.673469 -94.469682)
			(xy 110.618064 -94.492631) (xy 110.560138 -94.508152) (xy 110.500681 -94.515979) (xy 110.470696 -94.516448)
			(xy 109.607096 -94.516448) (xy 109.577111 -94.515986) (xy 109.517654 -94.508157) (xy 109.459727 -94.492636)
			(xy 109.404322 -94.469686) (xy 109.352387 -94.4397) (xy 109.30481 -94.403193) (xy 109.262405 -94.360787)
			(xy 109.225897 -94.31321) (xy 109.195912 -94.261274) (xy 109.172963 -94.205869) (xy 109.157442 -94.147942)
			(xy 109.149614 -94.088485) (xy 4.30911 -94.088485) (xy 4.30911 -95.214948) (xy 47.274239 -95.214948)
			(xy 47.278194 -95.123111) (xy 47.290029 -95.031954) (xy 47.309656 -94.942151) (xy 47.33693 -94.854369)
			(xy 47.37165 -94.769255) (xy 47.413558 -94.687442) (xy 47.462344 -94.609534) (xy 47.517647 -94.536109)
			(xy 47.579057 -94.467709) (xy 47.646119 -94.404842) (xy 47.718338 -94.347972) (xy 47.795178 -94.297521)
			(xy 47.876071 -94.253862) (xy 47.960417 -94.217319) (xy 48.047593 -94.188162) (xy 48.136952 -94.166608)
			(xy 48.227833 -94.152814) (xy 48.319564 -94.146884) (xy 48.411465 -94.148862) (xy 48.502856 -94.158733)
			(xy 48.59306 -94.176423) (xy 48.681409 -94.201803) (xy 48.767249 -94.234683) (xy 48.849945 -94.274821)
			(xy 48.928885 -94.32192) (xy 49.003483 -94.37563) (xy 49.073189 -94.435554) (xy 49.137484 -94.501248)
			(xy 49.195895 -94.572226) (xy 49.247987 -94.647963) (xy 49.293376 -94.727898) (xy 49.331726 -94.811438)
			(xy 49.362751 -94.897966) (xy 49.386224 -94.986841) (xy 49.40197 -95.077405) (xy 49.409872 -95.168987)
			(xy 49.410366 -95.214948) (xy 71.639189 -95.214948) (xy 71.643144 -95.123111) (xy 71.654979 -95.031954)
			(xy 71.674606 -94.942151) (xy 71.70188 -94.854369) (xy 71.7366 -94.769255) (xy 71.778508 -94.687442)
			(xy 71.827294 -94.609534) (xy 71.882597 -94.536109) (xy 71.944007 -94.467709) (xy 72.011069 -94.404842)
			(xy 72.083288 -94.347972) (xy 72.160128 -94.297521) (xy 72.241021 -94.253862) (xy 72.325367 -94.217319)
			(xy 72.412543 -94.188162) (xy 72.501902 -94.166608) (xy 72.592783 -94.152814) (xy 72.684514 -94.146884)
			(xy 72.776415 -94.148862) (xy 72.867806 -94.158733) (xy 72.95801 -94.176423) (xy 73.046359 -94.201803)
			(xy 73.132199 -94.234683) (xy 73.214895 -94.274821) (xy 73.293835 -94.32192) (xy 73.368433 -94.37563)
			(xy 73.438139 -94.435554) (xy 73.502434 -94.501248) (xy 73.560845 -94.572226) (xy 73.612937 -94.647963)
			(xy 73.658326 -94.727898) (xy 73.696676 -94.811438) (xy 73.727701 -94.897966) (xy 73.751174 -94.986841)
			(xy 73.76692 -95.077405) (xy 73.774822 -95.168987) (xy 73.775316 -95.214948) (xy 73.774822 -95.260909)
			(xy 73.774772 -95.261486) (xy 163.375394 -95.261486) (xy 163.375394 -95.168314) (xy 163.383515 -95.075496)
			(xy 163.399694 -94.983738) (xy 163.423808 -94.893741) (xy 163.455675 -94.806187) (xy 163.495052 -94.721744)
			(xy 163.541638 -94.641054) (xy 163.595079 -94.564731) (xy 163.654969 -94.493357) (xy 163.720852 -94.427473)
			(xy 163.792226 -94.367583) (xy 163.868549 -94.314141) (xy 163.949238 -94.267554) (xy 164.033681 -94.228178)
			(xy 164.121235 -94.19631) (xy 164.211233 -94.172195) (xy 164.30299 -94.156015) (xy 164.395808 -94.147894)
			(xy 164.442394 -94.147386) (xy 164.442648 -94.147386) (xy 164.489237 -94.1478) (xy 164.582061 -94.155925)
			(xy 164.673824 -94.172109) (xy 164.763826 -94.196229) (xy 164.851385 -94.228101) (xy 164.935832 -94.267483)
			(xy 165.016526 -94.314074) (xy 165.092852 -94.367522) (xy 165.164229 -94.427418) (xy 165.230115 -94.493306)
			(xy 165.290008 -94.564687) (xy 165.343451 -94.641015) (xy 165.390039 -94.721711) (xy 165.429417 -94.80616)
			(xy 165.461286 -94.893719) (xy 165.485401 -94.983723) (xy 165.501581 -95.075487) (xy 165.509702 -95.168311)
			(xy 165.509702 -95.214948) (xy 187.739796 -95.214948) (xy 187.743748 -95.123155) (xy 187.755578 -95.032041)
			(xy 187.775195 -94.942281) (xy 187.802457 -94.85454) (xy 187.83716 -94.769468) (xy 187.879048 -94.687693)
			(xy 187.927811 -94.609822) (xy 187.983087 -94.536432) (xy 188.044468 -94.468065) (xy 188.111499 -94.405227)
			(xy 188.183683 -94.348385) (xy 188.260487 -94.297958) (xy 188.341341 -94.25432) (xy 188.425647 -94.217794)
			(xy 188.512781 -94.188651) (xy 188.602098 -94.167106) (xy 188.692936 -94.15332) (xy 188.784623 -94.147393)
			(xy 188.87648 -94.14937) (xy 188.967828 -94.159236) (xy 189.057988 -94.176918) (xy 189.146296 -94.202285)
			(xy 189.232095 -94.23515) (xy 189.314752 -94.275269) (xy 189.393654 -94.322345) (xy 189.468217 -94.376029)
			(xy 189.537889 -94.435925) (xy 189.602154 -94.501588) (xy 189.660537 -94.572532) (xy 189.712604 -94.648233)
			(xy 189.757972 -94.72813) (xy 189.796303 -94.81163) (xy 189.827314 -94.898117) (xy 189.850775 -94.98695)
			(xy 189.866514 -95.07747) (xy 189.874412 -95.169009) (xy 189.874906 -95.214948) (xy 279.474181 -95.214948)
			(xy 279.478136 -95.123111) (xy 279.489971 -95.031954) (xy 279.509598 -94.942151) (xy 279.536872 -94.854369)
			(xy 279.571592 -94.769255) (xy 279.6135 -94.687442) (xy 279.662286 -94.609534) (xy 279.717589 -94.536109)
			(xy 279.778999 -94.467709) (xy 279.846061 -94.404842) (xy 279.91828 -94.347972) (xy 279.99512 -94.297521)
			(xy 280.076013 -94.253862) (xy 280.160359 -94.217319) (xy 280.247535 -94.188162) (xy 280.336894 -94.166608)
			(xy 280.427775 -94.152814) (xy 280.519506 -94.146884) (xy 280.611407 -94.148862) (xy 280.702798 -94.158733)
			(xy 280.793002 -94.176423) (xy 280.881351 -94.201803) (xy 280.967191 -94.234683) (xy 281.049887 -94.274821)
			(xy 281.128827 -94.32192) (xy 281.203425 -94.37563) (xy 281.273131 -94.435554) (xy 281.337426 -94.501248)
			(xy 281.395837 -94.572226) (xy 281.447929 -94.647963) (xy 281.493318 -94.727898) (xy 281.531668 -94.811438)
			(xy 281.562693 -94.897966) (xy 281.586166 -94.986841) (xy 281.601912 -95.077405) (xy 281.609814 -95.168987)
			(xy 281.610308 -95.214948) (xy 303.839131 -95.214948) (xy 303.843086 -95.123111) (xy 303.854921 -95.031954)
			(xy 303.874548 -94.942151) (xy 303.901822 -94.854369) (xy 303.936542 -94.769255) (xy 303.97845 -94.687442)
			(xy 304.027236 -94.609534) (xy 304.082539 -94.536109) (xy 304.143949 -94.467709) (xy 304.211011 -94.404842)
			(xy 304.28323 -94.347972) (xy 304.36007 -94.297521) (xy 304.440963 -94.253862) (xy 304.525309 -94.217319)
			(xy 304.612485 -94.188162) (xy 304.701844 -94.166608) (xy 304.792725 -94.152814) (xy 304.884456 -94.146884)
			(xy 304.976357 -94.148862) (xy 305.067748 -94.158733) (xy 305.157952 -94.176423) (xy 305.246301 -94.201803)
			(xy 305.332141 -94.234683) (xy 305.414837 -94.274821) (xy 305.493777 -94.32192) (xy 305.568375 -94.37563)
			(xy 305.638081 -94.435554) (xy 305.702376 -94.501248) (xy 305.760787 -94.572226) (xy 305.812879 -94.647963)
			(xy 305.858268 -94.727898) (xy 305.896618 -94.811438) (xy 305.91901 -94.87389) (xy 338.405861 -94.87389)
			(xy 338.405861 -94.81391) (xy 338.413691 -94.754443) (xy 338.429215 -94.696507) (xy 338.45217 -94.641093)
			(xy 338.482161 -94.58915) (xy 338.518676 -94.541565) (xy 338.561089 -94.499155) (xy 338.608676 -94.462643)
			(xy 338.660622 -94.432655) (xy 338.716037 -94.409705) (xy 338.773975 -94.394184) (xy 338.833442 -94.386359)
			(xy 338.863432 -94.385892) (xy 339.727032 -94.385892) (xy 339.757012 -94.386476) (xy 339.816458 -94.394306)
			(xy 339.874374 -94.409828) (xy 339.929769 -94.432777) (xy 339.981694 -94.462759) (xy 340.029262 -94.499262)
			(xy 340.071659 -94.541662) (xy 340.108159 -94.589232) (xy 340.138137 -94.64116) (xy 340.161082 -94.696556)
			(xy 340.1766 -94.754473) (xy 340.184426 -94.81392) (xy 340.184426 -94.87388) (xy 340.1766 -94.933327)
			(xy 340.161082 -94.991244) (xy 340.138137 -95.04664) (xy 340.108159 -95.098568) (xy 340.071659 -95.146138)
			(xy 340.029262 -95.188538) (xy 339.994846 -95.214948) (xy 395.574279 -95.214948) (xy 395.578234 -95.123111)
			(xy 395.590069 -95.031954) (xy 395.609696 -94.942151) (xy 395.63697 -94.854369) (xy 395.67169 -94.769255)
			(xy 395.713598 -94.687442) (xy 395.762384 -94.609534) (xy 395.817687 -94.536109) (xy 395.879097 -94.467709)
			(xy 395.946159 -94.404842) (xy 396.018378 -94.347972) (xy 396.095218 -94.297521) (xy 396.176111 -94.253862)
			(xy 396.260457 -94.217319) (xy 396.347633 -94.188162) (xy 396.436992 -94.166608) (xy 396.527873 -94.152814)
			(xy 396.619604 -94.146884) (xy 396.711505 -94.148862) (xy 396.802896 -94.158733) (xy 396.8931 -94.176423)
			(xy 396.981449 -94.201803) (xy 397.067289 -94.234683) (xy 397.149985 -94.274821) (xy 397.228925 -94.32192)
			(xy 397.303523 -94.37563) (xy 397.373229 -94.435554) (xy 397.437524 -94.501248) (xy 397.495935 -94.572226)
			(xy 397.548027 -94.647963) (xy 397.593416 -94.727898) (xy 397.631766 -94.811438) (xy 397.662791 -94.897966)
			(xy 397.686264 -94.986841) (xy 397.70201 -95.077405) (xy 397.709912 -95.168987) (xy 397.710406 -95.214948)
			(xy 419.939229 -95.214948) (xy 419.943184 -95.123111) (xy 419.955019 -95.031954) (xy 419.974646 -94.942151)
			(xy 420.00192 -94.854369) (xy 420.03664 -94.769255) (xy 420.078548 -94.687442) (xy 420.127334 -94.609534)
			(xy 420.182637 -94.536109) (xy 420.244047 -94.467709) (xy 420.311109 -94.404842) (xy 420.383328 -94.347972)
			(xy 420.460168 -94.297521) (xy 420.541061 -94.253862) (xy 420.625407 -94.217319) (xy 420.712583 -94.188162)
			(xy 420.801942 -94.166608) (xy 420.892823 -94.152814) (xy 420.984554 -94.146884) (xy 421.076455 -94.148862)
			(xy 421.167846 -94.158733) (xy 421.25805 -94.176423) (xy 421.346399 -94.201803) (xy 421.432239 -94.234683)
			(xy 421.514935 -94.274821) (xy 421.593875 -94.32192) (xy 421.668473 -94.37563) (xy 421.738179 -94.435554)
			(xy 421.802474 -94.501248) (xy 421.860885 -94.572226) (xy 421.912977 -94.647963) (xy 421.958366 -94.727898)
			(xy 421.996716 -94.811438) (xy 422.027741 -94.897966) (xy 422.051214 -94.986841) (xy 422.06696 -95.077405)
			(xy 422.074862 -95.168987) (xy 422.075356 -95.214948) (xy 422.074862 -95.260909) (xy 422.06696 -95.352491)
			(xy 422.051214 -95.443055) (xy 422.027741 -95.53193) (xy 421.996716 -95.618458) (xy 421.958366 -95.701998)
			(xy 421.912977 -95.781933) (xy 421.860885 -95.85767) (xy 421.802474 -95.928648) (xy 421.738179 -95.994342)
			(xy 421.668473 -96.054266) (xy 421.593875 -96.107976) (xy 421.514935 -96.155075) (xy 421.432239 -96.195213)
			(xy 421.346399 -96.228093) (xy 421.25805 -96.253473) (xy 421.167846 -96.271163) (xy 421.076455 -96.281034)
			(xy 420.984554 -96.283012) (xy 420.892823 -96.277082) (xy 420.801942 -96.263288) (xy 420.712583 -96.241734)
			(xy 420.625407 -96.212577) (xy 420.541061 -96.176034) (xy 420.460168 -96.132375) (xy 420.383328 -96.081924)
			(xy 420.311109 -96.025054) (xy 420.244047 -95.962187) (xy 420.182637 -95.893787) (xy 420.127334 -95.820362)
			(xy 420.078548 -95.742454) (xy 420.03664 -95.660641) (xy 420.00192 -95.575527) (xy 419.974646 -95.487745)
			(xy 419.955019 -95.397942) (xy 419.943184 -95.306785) (xy 419.939229 -95.214948) (xy 397.710406 -95.214948)
			(xy 397.709912 -95.260909) (xy 397.70201 -95.352491) (xy 397.686264 -95.443055) (xy 397.662791 -95.53193)
			(xy 397.631766 -95.618458) (xy 397.593416 -95.701998) (xy 397.548027 -95.781933) (xy 397.495935 -95.85767)
			(xy 397.437524 -95.928648) (xy 397.373229 -95.994342) (xy 397.303523 -96.054266) (xy 397.228925 -96.107976)
			(xy 397.149985 -96.155075) (xy 397.067289 -96.195213) (xy 396.981449 -96.228093) (xy 396.8931 -96.253473)
			(xy 396.802896 -96.271163) (xy 396.711505 -96.281034) (xy 396.619604 -96.283012) (xy 396.527873 -96.277082)
			(xy 396.436992 -96.263288) (xy 396.347633 -96.241734) (xy 396.260457 -96.212577) (xy 396.176111 -96.176034)
			(xy 396.095218 -96.132375) (xy 396.018378 -96.081924) (xy 395.946159 -96.025054) (xy 395.879097 -95.962187)
			(xy 395.817687 -95.893787) (xy 395.762384 -95.820362) (xy 395.713598 -95.742454) (xy 395.67169 -95.660641)
			(xy 395.63697 -95.575527) (xy 395.609696 -95.487745) (xy 395.590069 -95.397942) (xy 395.578234 -95.306785)
			(xy 395.574279 -95.214948) (xy 339.994846 -95.214948) (xy 339.981694 -95.225041) (xy 339.929769 -95.255023)
			(xy 339.874374 -95.277972) (xy 339.816458 -95.293494) (xy 339.757012 -95.301324) (xy 339.727032 -95.301816)
			(xy 338.863432 -95.301816) (xy 338.833442 -95.301441) (xy 338.773975 -95.293616) (xy 338.716037 -95.278095)
			(xy 338.660622 -95.255145) (xy 338.608676 -95.225157) (xy 338.561089 -95.188645) (xy 338.518676 -95.146235)
			(xy 338.482161 -95.09865) (xy 338.45217 -95.046707) (xy 338.429215 -94.991293) (xy 338.413691 -94.933357)
			(xy 338.405861 -94.87389) (xy 305.91901 -94.87389) (xy 305.927643 -94.897966) (xy 305.951116 -94.986841)
			(xy 305.966862 -95.077405) (xy 305.974764 -95.168987) (xy 305.975258 -95.214948) (xy 305.974764 -95.260909)
			(xy 305.966862 -95.352491) (xy 305.951116 -95.443055) (xy 305.927643 -95.53193) (xy 305.896618 -95.618458)
			(xy 305.858268 -95.701998) (xy 305.812879 -95.781933) (xy 305.760787 -95.85767) (xy 305.702376 -95.928648)
			(xy 305.638081 -95.994342) (xy 305.568375 -96.054266) (xy 305.493777 -96.107976) (xy 305.414837 -96.155075)
			(xy 305.332141 -96.195213) (xy 305.246301 -96.228093) (xy 305.157952 -96.253473) (xy 305.067748 -96.271163)
			(xy 304.976357 -96.281034) (xy 304.884456 -96.283012) (xy 304.792725 -96.277082) (xy 304.701844 -96.263288)
			(xy 304.612485 -96.241734) (xy 304.525309 -96.212577) (xy 304.440963 -96.176034) (xy 304.36007 -96.132375)
			(xy 304.28323 -96.081924) (xy 304.211011 -96.025054) (xy 304.143949 -95.962187) (xy 304.082539 -95.893787)
			(xy 304.027236 -95.820362) (xy 303.97845 -95.742454) (xy 303.936542 -95.660641) (xy 303.901822 -95.575527)
			(xy 303.874548 -95.487745) (xy 303.854921 -95.397942) (xy 303.843086 -95.306785) (xy 303.839131 -95.214948)
			(xy 281.610308 -95.214948) (xy 281.609814 -95.260909) (xy 281.601912 -95.352491) (xy 281.586166 -95.443055)
			(xy 281.562693 -95.53193) (xy 281.531668 -95.618458) (xy 281.493318 -95.701998) (xy 281.447929 -95.781933)
			(xy 281.395837 -95.85767) (xy 281.337426 -95.928648) (xy 281.273131 -95.994342) (xy 281.203425 -96.054266)
			(xy 281.128827 -96.107976) (xy 281.049887 -96.155075) (xy 280.967191 -96.195213) (xy 280.881351 -96.228093)
			(xy 280.793002 -96.253473) (xy 280.702798 -96.271163) (xy 280.611407 -96.281034) (xy 280.519506 -96.283012)
			(xy 280.427775 -96.277082) (xy 280.336894 -96.263288) (xy 280.247535 -96.241734) (xy 280.160359 -96.212577)
			(xy 280.076013 -96.176034) (xy 279.99512 -96.132375) (xy 279.91828 -96.081924) (xy 279.846061 -96.025054)
			(xy 279.778999 -95.962187) (xy 279.717589 -95.893787) (xy 279.662286 -95.820362) (xy 279.6135 -95.742454)
			(xy 279.571592 -95.660641) (xy 279.536872 -95.575527) (xy 279.509598 -95.487745) (xy 279.489971 -95.397942)
			(xy 279.478136 -95.306785) (xy 279.474181 -95.214948) (xy 189.874906 -95.214948) (xy 189.874412 -95.260887)
			(xy 189.866514 -95.352426) (xy 189.850775 -95.442946) (xy 189.827314 -95.531779) (xy 189.796303 -95.618266)
			(xy 189.757972 -95.701766) (xy 189.712604 -95.781663) (xy 189.660537 -95.857364) (xy 189.602154 -95.928308)
			(xy 189.537889 -95.993971) (xy 189.468217 -96.053867) (xy 189.393654 -96.107551) (xy 189.314752 -96.154627)
			(xy 189.232095 -96.194746) (xy 189.146296 -96.227611) (xy 189.057988 -96.252978) (xy 188.967828 -96.27066)
			(xy 188.87648 -96.280526) (xy 188.784623 -96.282503) (xy 188.692936 -96.276576) (xy 188.602098 -96.26279)
			(xy 188.512781 -96.241245) (xy 188.425647 -96.212102) (xy 188.341341 -96.175576) (xy 188.260487 -96.131938)
			(xy 188.183683 -96.081511) (xy 188.111499 -96.024669) (xy 188.044468 -95.961831) (xy 187.983087 -95.893464)
			(xy 187.927811 -95.820074) (xy 187.879048 -95.742203) (xy 187.83716 -95.660428) (xy 187.802457 -95.575356)
			(xy 187.775195 -95.487615) (xy 187.755578 -95.397855) (xy 187.743748 -95.306741) (xy 187.739796 -95.214948)
			(xy 165.509702 -95.214948) (xy 165.509702 -95.261489) (xy 165.501581 -95.354313) (xy 165.485401 -95.446077)
			(xy 165.461286 -95.536081) (xy 165.429417 -95.62364) (xy 165.390039 -95.708089) (xy 165.343451 -95.788785)
			(xy 165.290008 -95.865113) (xy 165.230115 -95.936494) (xy 165.164229 -96.002382) (xy 165.092852 -96.062278)
			(xy 165.016526 -96.115726) (xy 164.935832 -96.162317) (xy 164.851385 -96.201699) (xy 164.763826 -96.233571)
			(xy 164.673824 -96.257691) (xy 164.582061 -96.273875) (xy 164.489237 -96.282) (xy 164.442648 -96.28251)
			(xy 164.442394 -96.28251) (xy 164.395808 -96.281906) (xy 164.30299 -96.273785) (xy 164.211233 -96.257605)
			(xy 164.121235 -96.23349) (xy 164.033681 -96.201622) (xy 163.949238 -96.162246) (xy 163.868549 -96.115659)
			(xy 163.792226 -96.062217) (xy 163.720852 -96.002327) (xy 163.654969 -95.936443) (xy 163.595079 -95.865069)
			(xy 163.541638 -95.788746) (xy 163.495052 -95.708056) (xy 163.455675 -95.623613) (xy 163.423808 -95.536059)
			(xy 163.399694 -95.446062) (xy 163.383515 -95.354304) (xy 163.375394 -95.261486) (xy 73.774772 -95.261486)
			(xy 73.76692 -95.352491) (xy 73.751174 -95.443055) (xy 73.727701 -95.53193) (xy 73.696676 -95.618458)
			(xy 73.658326 -95.701998) (xy 73.612937 -95.781933) (xy 73.560845 -95.85767) (xy 73.502434 -95.928648)
			(xy 73.438139 -95.994342) (xy 73.368433 -96.054266) (xy 73.293835 -96.107976) (xy 73.214895 -96.155075)
			(xy 73.132199 -96.195213) (xy 73.046359 -96.228093) (xy 72.95801 -96.253473) (xy 72.867806 -96.271163)
			(xy 72.776415 -96.281034) (xy 72.684514 -96.283012) (xy 72.592783 -96.277082) (xy 72.501902 -96.263288)
			(xy 72.412543 -96.241734) (xy 72.325367 -96.212577) (xy 72.241021 -96.176034) (xy 72.160128 -96.132375)
			(xy 72.083288 -96.081924) (xy 72.011069 -96.025054) (xy 71.944007 -95.962187) (xy 71.882597 -95.893787)
			(xy 71.827294 -95.820362) (xy 71.778508 -95.742454) (xy 71.7366 -95.660641) (xy 71.70188 -95.575527)
			(xy 71.674606 -95.487745) (xy 71.654979 -95.397942) (xy 71.643144 -95.306785) (xy 71.639189 -95.214948)
			(xy 49.410366 -95.214948) (xy 49.409872 -95.260909) (xy 49.40197 -95.352491) (xy 49.386224 -95.443055)
			(xy 49.362751 -95.53193) (xy 49.331726 -95.618458) (xy 49.293376 -95.701998) (xy 49.247987 -95.781933)
			(xy 49.195895 -95.85767) (xy 49.137484 -95.928648) (xy 49.073189 -95.994342) (xy 49.003483 -96.054266)
			(xy 48.928885 -96.107976) (xy 48.849945 -96.155075) (xy 48.767249 -96.195213) (xy 48.681409 -96.228093)
			(xy 48.59306 -96.253473) (xy 48.502856 -96.271163) (xy 48.411465 -96.281034) (xy 48.319564 -96.283012)
			(xy 48.227833 -96.277082) (xy 48.136952 -96.263288) (xy 48.047593 -96.241734) (xy 47.960417 -96.212577)
			(xy 47.876071 -96.176034) (xy 47.795178 -96.132375) (xy 47.718338 -96.081924) (xy 47.646119 -96.025054)
			(xy 47.579057 -95.962187) (xy 47.517647 -95.893787) (xy 47.462344 -95.820362) (xy 47.413558 -95.742454)
			(xy 47.37165 -95.660641) (xy 47.33693 -95.575527) (xy 47.309656 -95.487745) (xy 47.290029 -95.397942)
			(xy 47.278194 -95.306785) (xy 47.274239 -95.214948) (xy 4.30911 -95.214948) (xy 4.30911 -98.766863)
			(xy 206.090008 -98.766863) (xy 206.090008 -98.633301) (xy 206.098072 -98.499983) (xy 206.114172 -98.367395)
			(xy 206.138247 -98.236021) (xy 206.17021 -98.10634) (xy 206.209945 -97.978826) (xy 206.257307 -97.853943)
			(xy 206.312122 -97.732148) (xy 206.374192 -97.613885) (xy 206.443288 -97.499586) (xy 206.51916 -97.389666)
			(xy 206.60153 -97.284529) (xy 206.690098 -97.184556) (xy 206.78454 -97.090114) (xy 206.884513 -97.001546)
			(xy 206.98965 -96.919176) (xy 207.09957 -96.843304) (xy 207.213869 -96.774208) (xy 207.332132 -96.712138)
			(xy 207.453927 -96.657323) (xy 207.57881 -96.609961) (xy 207.706324 -96.570226) (xy 207.836005 -96.538263)
			(xy 207.967379 -96.514188) (xy 208.099967 -96.498088) (xy 208.233285 -96.490024) (xy 208.366847 -96.490024)
			(xy 208.500165 -96.498088) (xy 208.632753 -96.514188) (xy 208.764127 -96.538263) (xy 208.893808 -96.570226)
			(xy 209.021322 -96.609961) (xy 209.146205 -96.657323) (xy 209.268 -96.712138) (xy 209.386263 -96.774208)
			(xy 209.500562 -96.843304) (xy 209.610482 -96.919176) (xy 209.715619 -97.001546) (xy 209.815592 -97.090114)
			(xy 209.910034 -97.184556) (xy 209.998602 -97.284529) (xy 210.080972 -97.389666) (xy 210.156844 -97.499586)
			(xy 210.22594 -97.613885) (xy 210.28801 -97.732148) (xy 210.342825 -97.853943) (xy 210.390187 -97.978826)
			(xy 210.429922 -98.10634) (xy 210.461885 -98.236021) (xy 210.48596 -98.367395) (xy 210.50206 -98.499983)
			(xy 210.510124 -98.633301) (xy 210.510628 -98.700082) (xy 210.510124 -98.766863) (xy 257.089906 -98.766863)
			(xy 257.089906 -98.633301) (xy 257.09797 -98.499983) (xy 257.11407 -98.367395) (xy 257.138145 -98.236021)
			(xy 257.170108 -98.10634) (xy 257.209843 -97.978826) (xy 257.257205 -97.853943) (xy 257.31202 -97.732148)
			(xy 257.37409 -97.613885) (xy 257.443186 -97.499586) (xy 257.519058 -97.389666) (xy 257.601428 -97.284529)
			(xy 257.689996 -97.184556) (xy 257.784438 -97.090114) (xy 257.884411 -97.001546) (xy 257.989548 -96.919176)
			(xy 258.099468 -96.843304) (xy 258.213767 -96.774208) (xy 258.33203 -96.712138) (xy 258.453825 -96.657323)
			(xy 258.578708 -96.609961) (xy 258.706222 -96.570226) (xy 258.835903 -96.538263) (xy 258.967277 -96.514188)
			(xy 259.099865 -96.498088) (xy 259.233183 -96.490024) (xy 259.366745 -96.490024) (xy 259.500063 -96.498088)
			(xy 259.632651 -96.514188) (xy 259.764025 -96.538263) (xy 259.893706 -96.570226) (xy 260.02122 -96.609961)
			(xy 260.146103 -96.657323) (xy 260.267898 -96.712138) (xy 260.386161 -96.774208) (xy 260.50046 -96.843304)
			(xy 260.61038 -96.919176) (xy 260.715517 -97.001546) (xy 260.81549 -97.090114) (xy 260.909932 -97.184556)
			(xy 260.9985 -97.284529) (xy 261.08087 -97.389666) (xy 261.156742 -97.499586) (xy 261.225838 -97.613885)
			(xy 261.287908 -97.732148) (xy 261.342723 -97.853943) (xy 261.390085 -97.978826) (xy 261.42982 -98.10634)
			(xy 261.461783 -98.236021) (xy 261.485858 -98.367395) (xy 261.501958 -98.499983) (xy 261.510022 -98.633301)
			(xy 261.510526 -98.700082) (xy 261.510022 -98.766863) (xy 261.501958 -98.900181) (xy 261.485858 -99.032769)
			(xy 261.461783 -99.164143) (xy 261.42982 -99.293824) (xy 261.390085 -99.421338) (xy 261.342723 -99.546221)
			(xy 261.287908 -99.668016) (xy 261.225838 -99.786279) (xy 261.156742 -99.900578) (xy 261.08087 -100.010498)
			(xy 260.9985 -100.115635) (xy 260.943379 -100.177854) (xy 269.509748 -100.177854) (xy 269.509748 -99.314254)
			(xy 269.510238 -99.28427) (xy 269.518066 -99.224814) (xy 269.533587 -99.166889) (xy 269.556536 -99.111485)
			(xy 269.58652 -99.059551) (xy 269.623026 -99.011975) (xy 269.665431 -98.96957) (xy 269.713007 -98.933064)
			(xy 269.764941 -98.90308) (xy 269.820345 -98.880131) (xy 269.87827 -98.86461) (xy 269.937726 -98.856782)
			(xy 269.997694 -98.856782) (xy 270.05715 -98.86461) (xy 270.115075 -98.880131) (xy 270.170479 -98.90308)
			(xy 270.222413 -98.933064) (xy 270.269989 -98.96957) (xy 270.312394 -99.011975) (xy 270.3489 -99.059551)
			(xy 270.378884 -99.111485) (xy 270.401833 -99.166889) (xy 270.417354 -99.224814) (xy 270.425182 -99.28427)
			(xy 270.425672 -99.314254) (xy 270.425672 -100.17633) (xy 285.8389 -100.17633) (xy 285.8389 -99.31273)
			(xy 285.83939 -99.282746) (xy 285.847218 -99.22329) (xy 285.862739 -99.165365) (xy 285.885688 -99.109961)
			(xy 285.915672 -99.058027) (xy 285.952178 -99.010451) (xy 285.994583 -98.968046) (xy 286.042159 -98.93154)
			(xy 286.094093 -98.901556) (xy 286.149497 -98.878607) (xy 286.207422 -98.863086) (xy 286.266878 -98.855258)
			(xy 286.326846 -98.855258) (xy 286.386302 -98.863086) (xy 286.444227 -98.878607) (xy 286.499631 -98.901556)
			(xy 286.551565 -98.93154) (xy 286.599141 -98.968046) (xy 286.641546 -99.010451) (xy 286.678052 -99.058027)
			(xy 286.708036 -99.109961) (xy 286.730985 -99.165365) (xy 286.746506 -99.22329) (xy 286.754334 -99.282746)
			(xy 286.754824 -99.31273) (xy 286.754824 -100.17633) (xy 286.754799 -100.177854) (xy 385.6101 -100.177854)
			(xy 385.6101 -99.314254) (xy 385.61059 -99.284286) (xy 385.618413 -99.224864) (xy 385.633926 -99.166971)
			(xy 385.656862 -99.111598) (xy 385.686829 -99.059692) (xy 385.723316 -99.012142) (xy 385.765696 -98.969762)
			(xy 385.813246 -98.933275) (xy 385.865152 -98.903308) (xy 385.920525 -98.880372) (xy 385.978418 -98.864859)
			(xy 386.03784 -98.857036) (xy 386.097776 -98.857036) (xy 386.157198 -98.864859) (xy 386.215091 -98.880372)
			(xy 386.270464 -98.903308) (xy 386.32237 -98.933275) (xy 386.36992 -98.969762) (xy 386.4123 -99.012142)
			(xy 386.448787 -99.059692) (xy 386.478754 -99.111598) (xy 386.50169 -99.166971) (xy 386.517203 -99.224864)
			(xy 386.525026 -99.284286) (xy 386.525516 -99.314254) (xy 386.525516 -100.17633) (xy 401.939252 -100.17633)
			(xy 401.939252 -99.31273) (xy 401.939742 -99.282762) (xy 401.947565 -99.22334) (xy 401.963078 -99.165447)
			(xy 401.986014 -99.110074) (xy 402.015981 -99.058168) (xy 402.052468 -99.010618) (xy 402.094848 -98.968238)
			(xy 402.142398 -98.931751) (xy 402.194304 -98.901784) (xy 402.249677 -98.878848) (xy 402.30757 -98.863335)
			(xy 402.366992 -98.855512) (xy 402.426928 -98.855512) (xy 402.48635 -98.863335) (xy 402.544243 -98.878848)
			(xy 402.599616 -98.901784) (xy 402.651522 -98.931751) (xy 402.699072 -98.968238) (xy 402.741452 -99.010618)
			(xy 402.777939 -99.058168) (xy 402.807906 -99.110074) (xy 402.830842 -99.165447) (xy 402.846355 -99.22334)
			(xy 402.854178 -99.282762) (xy 402.854668 -99.31273) (xy 402.854668 -100.17633) (xy 402.854178 -100.206298)
			(xy 402.846355 -100.26572) (xy 402.830842 -100.323613) (xy 402.807906 -100.378986) (xy 402.777939 -100.430892)
			(xy 402.741452 -100.478442) (xy 402.699072 -100.520822) (xy 402.651522 -100.557309) (xy 402.599616 -100.587276)
			(xy 402.544243 -100.610212) (xy 402.48635 -100.625725) (xy 402.426928 -100.633548) (xy 402.366992 -100.633548)
			(xy 402.30757 -100.625725) (xy 402.249677 -100.610212) (xy 402.194304 -100.587276) (xy 402.142398 -100.557309)
			(xy 402.094848 -100.520822) (xy 402.052468 -100.478442) (xy 402.015981 -100.430892) (xy 401.986014 -100.378986)
			(xy 401.963078 -100.323613) (xy 401.947565 -100.26572) (xy 401.939742 -100.206298) (xy 401.939252 -100.17633)
			(xy 386.525516 -100.17633) (xy 386.525516 -100.177854) (xy 386.525026 -100.207822) (xy 386.517203 -100.267244)
			(xy 386.50169 -100.325137) (xy 386.478754 -100.38051) (xy 386.448787 -100.432416) (xy 386.4123 -100.479966)
			(xy 386.36992 -100.522346) (xy 386.32237 -100.558833) (xy 386.270464 -100.5888) (xy 386.215091 -100.611736)
			(xy 386.157198 -100.627249) (xy 386.097776 -100.635072) (xy 386.03784 -100.635072) (xy 385.978418 -100.627249)
			(xy 385.920525 -100.611736) (xy 385.865152 -100.5888) (xy 385.813246 -100.558833) (xy 385.765696 -100.522346)
			(xy 385.723316 -100.479966) (xy 385.686829 -100.432416) (xy 385.656862 -100.38051) (xy 385.633926 -100.325137)
			(xy 385.618413 -100.267244) (xy 385.61059 -100.207822) (xy 385.6101 -100.177854) (xy 286.754799 -100.177854)
			(xy 286.754334 -100.206314) (xy 286.746506 -100.26577) (xy 286.730985 -100.323695) (xy 286.708036 -100.379099)
			(xy 286.678052 -100.431033) (xy 286.641546 -100.478609) (xy 286.599141 -100.521014) (xy 286.551565 -100.55752)
			(xy 286.499631 -100.587504) (xy 286.444227 -100.610453) (xy 286.386302 -100.625974) (xy 286.326846 -100.633802)
			(xy 286.266878 -100.633802) (xy 286.207422 -100.625974) (xy 286.149497 -100.610453) (xy 286.094093 -100.587504)
			(xy 286.042159 -100.55752) (xy 285.994583 -100.521014) (xy 285.952178 -100.478609) (xy 285.915672 -100.431033)
			(xy 285.885688 -100.379099) (xy 285.862739 -100.323695) (xy 285.847218 -100.26577) (xy 285.83939 -100.206314)
			(xy 285.8389 -100.17633) (xy 270.425672 -100.17633) (xy 270.425672 -100.177854) (xy 270.425182 -100.207838)
			(xy 270.417354 -100.267294) (xy 270.401833 -100.325219) (xy 270.378884 -100.380623) (xy 270.3489 -100.432557)
			(xy 270.312394 -100.480133) (xy 270.269989 -100.522538) (xy 270.222413 -100.559044) (xy 270.170479 -100.589028)
			(xy 270.115075 -100.611977) (xy 270.05715 -100.627498) (xy 269.997694 -100.635326) (xy 269.937726 -100.635326)
			(xy 269.87827 -100.627498) (xy 269.820345 -100.611977) (xy 269.764941 -100.589028) (xy 269.713007 -100.559044)
			(xy 269.665431 -100.522538) (xy 269.623026 -100.480133) (xy 269.58652 -100.432557) (xy 269.556536 -100.380623)
			(xy 269.533587 -100.325219) (xy 269.518066 -100.267294) (xy 269.510238 -100.207838) (xy 269.509748 -100.177854)
			(xy 260.943379 -100.177854) (xy 260.909932 -100.215608) (xy 260.81549 -100.31005) (xy 260.715517 -100.398618)
			(xy 260.61038 -100.480988) (xy 260.50046 -100.55686) (xy 260.386161 -100.625956) (xy 260.267898 -100.688026)
			(xy 260.146103 -100.742841) (xy 260.02122 -100.790203) (xy 259.893706 -100.829938) (xy 259.764025 -100.861901)
			(xy 259.632651 -100.885976) (xy 259.500063 -100.902076) (xy 259.366745 -100.91014) (xy 259.233183 -100.91014)
			(xy 259.099865 -100.902076) (xy 258.967277 -100.885976) (xy 258.835903 -100.861901) (xy 258.706222 -100.829938)
			(xy 258.578708 -100.790203) (xy 258.453825 -100.742841) (xy 258.33203 -100.688026) (xy 258.213767 -100.625956)
			(xy 258.099468 -100.55686) (xy 257.989548 -100.480988) (xy 257.884411 -100.398618) (xy 257.784438 -100.31005)
			(xy 257.689996 -100.215608) (xy 257.601428 -100.115635) (xy 257.519058 -100.010498) (xy 257.443186 -99.900578)
			(xy 257.37409 -99.786279) (xy 257.31202 -99.668016) (xy 257.257205 -99.546221) (xy 257.209843 -99.421338)
			(xy 257.170108 -99.293824) (xy 257.138145 -99.164143) (xy 257.11407 -99.032769) (xy 257.09797 -98.900181)
			(xy 257.089906 -98.766863) (xy 210.510124 -98.766863) (xy 210.50206 -98.900181) (xy 210.48596 -99.032769)
			(xy 210.461885 -99.164143) (xy 210.429922 -99.293824) (xy 210.390187 -99.421338) (xy 210.342825 -99.546221)
			(xy 210.28801 -99.668016) (xy 210.22594 -99.786279) (xy 210.156844 -99.900578) (xy 210.080972 -100.010498)
			(xy 209.998602 -100.115635) (xy 209.910034 -100.215608) (xy 209.815592 -100.31005) (xy 209.715619 -100.398618)
			(xy 209.610482 -100.480988) (xy 209.500562 -100.55686) (xy 209.386263 -100.625956) (xy 209.268 -100.688026)
			(xy 209.146205 -100.742841) (xy 209.021322 -100.790203) (xy 208.893808 -100.829938) (xy 208.764127 -100.861901)
			(xy 208.632753 -100.885976) (xy 208.500165 -100.902076) (xy 208.366847 -100.91014) (xy 208.233285 -100.91014)
			(xy 208.099967 -100.902076) (xy 207.967379 -100.885976) (xy 207.836005 -100.861901) (xy 207.706324 -100.829938)
			(xy 207.57881 -100.790203) (xy 207.453927 -100.742841) (xy 207.332132 -100.688026) (xy 207.213869 -100.625956)
			(xy 207.09957 -100.55686) (xy 206.98965 -100.480988) (xy 206.884513 -100.398618) (xy 206.78454 -100.31005)
			(xy 206.690098 -100.215608) (xy 206.60153 -100.115635) (xy 206.51916 -100.010498) (xy 206.443288 -99.900578)
			(xy 206.374192 -99.786279) (xy 206.312122 -99.668016) (xy 206.257307 -99.546221) (xy 206.209945 -99.421338)
			(xy 206.17021 -99.293824) (xy 206.138247 -99.164143) (xy 206.114172 -99.032769) (xy 206.098072 -98.900181)
			(xy 206.090008 -98.766863) (xy 4.30911 -98.766863) (xy 4.30911 -100.177854) (xy 37.31006 -100.177854)
			(xy 37.31006 -99.314254) (xy 37.31055 -99.284286) (xy 37.318373 -99.224864) (xy 37.333886 -99.166971)
			(xy 37.356822 -99.111598) (xy 37.386789 -99.059692) (xy 37.423276 -99.012142) (xy 37.465656 -98.969762)
			(xy 37.513206 -98.933275) (xy 37.565112 -98.903308) (xy 37.620485 -98.880372) (xy 37.678378 -98.864859)
			(xy 37.7378 -98.857036) (xy 37.797736 -98.857036) (xy 37.857158 -98.864859) (xy 37.915051 -98.880372)
			(xy 37.970424 -98.903308) (xy 38.02233 -98.933275) (xy 38.06988 -98.969762) (xy 38.11226 -99.012142)
			(xy 38.148747 -99.059692) (xy 38.178714 -99.111598) (xy 38.20165 -99.166971) (xy 38.217163 -99.224864)
			(xy 38.224986 -99.284286) (xy 38.225476 -99.314254) (xy 38.225476 -100.17633) (xy 53.639212 -100.17633)
			(xy 53.639212 -99.31273) (xy 53.639702 -99.282762) (xy 53.647525 -99.22334) (xy 53.663038 -99.165447)
			(xy 53.685974 -99.110074) (xy 53.715941 -99.058168) (xy 53.752428 -99.010618) (xy 53.794808 -98.968238)
			(xy 53.842358 -98.931751) (xy 53.894264 -98.901784) (xy 53.949637 -98.878848) (xy 54.00753 -98.863335)
			(xy 54.066952 -98.855512) (xy 54.126888 -98.855512) (xy 54.18631 -98.863335) (xy 54.244203 -98.878848)
			(xy 54.299576 -98.901784) (xy 54.351482 -98.931751) (xy 54.399032 -98.968238) (xy 54.441412 -99.010618)
			(xy 54.477899 -99.058168) (xy 54.507866 -99.110074) (xy 54.530802 -99.165447) (xy 54.546315 -99.22334)
			(xy 54.554138 -99.282762) (xy 54.554628 -99.31273) (xy 54.554628 -100.17633) (xy 54.554603 -100.177854)
			(xy 153.409904 -100.177854) (xy 153.409904 -99.314254) (xy 153.410394 -99.28427) (xy 153.418222 -99.224814)
			(xy 153.433743 -99.166889) (xy 153.456692 -99.111485) (xy 153.486676 -99.059551) (xy 153.523182 -99.011975)
			(xy 153.565587 -98.96957) (xy 153.613163 -98.933064) (xy 153.665097 -98.90308) (xy 153.720501 -98.880131)
			(xy 153.778426 -98.86461) (xy 153.837882 -98.856782) (xy 153.89785 -98.856782) (xy 153.957306 -98.86461)
			(xy 154.015231 -98.880131) (xy 154.070635 -98.90308) (xy 154.122569 -98.933064) (xy 154.170145 -98.96957)
			(xy 154.21255 -99.011975) (xy 154.249056 -99.059551) (xy 154.27904 -99.111485) (xy 154.301989 -99.166889)
			(xy 154.31751 -99.224814) (xy 154.325338 -99.28427) (xy 154.325828 -99.314254) (xy 154.325828 -100.17633)
			(xy 169.739056 -100.17633) (xy 169.739056 -99.31273) (xy 169.739546 -99.282746) (xy 169.747374 -99.22329)
			(xy 169.762895 -99.165365) (xy 169.785844 -99.109961) (xy 169.815828 -99.058027) (xy 169.852334 -99.010451)
			(xy 169.894739 -98.968046) (xy 169.942315 -98.93154) (xy 169.994249 -98.901556) (xy 170.049653 -98.878607)
			(xy 170.107578 -98.863086) (xy 170.167034 -98.855258) (xy 170.227002 -98.855258) (xy 170.286458 -98.863086)
			(xy 170.344383 -98.878607) (xy 170.399787 -98.901556) (xy 170.451721 -98.93154) (xy 170.499297 -98.968046)
			(xy 170.541702 -99.010451) (xy 170.578208 -99.058027) (xy 170.608192 -99.109961) (xy 170.631141 -99.165365)
			(xy 170.646662 -99.22329) (xy 170.65449 -99.282746) (xy 170.65498 -99.31273) (xy 170.65498 -100.17633)
			(xy 170.65449 -100.206314) (xy 170.646662 -100.26577) (xy 170.631141 -100.323695) (xy 170.608192 -100.379099)
			(xy 170.578208 -100.431033) (xy 170.541702 -100.478609) (xy 170.499297 -100.521014) (xy 170.451721 -100.55752)
			(xy 170.399787 -100.587504) (xy 170.344383 -100.610453) (xy 170.286458 -100.625974) (xy 170.227002 -100.633802)
			(xy 170.167034 -100.633802) (xy 170.107578 -100.625974) (xy 170.049653 -100.610453) (xy 169.994249 -100.587504)
			(xy 169.942315 -100.55752) (xy 169.894739 -100.521014) (xy 169.852334 -100.478609) (xy 169.815828 -100.431033)
			(xy 169.785844 -100.379099) (xy 169.762895 -100.323695) (xy 169.747374 -100.26577) (xy 169.739546 -100.206314)
			(xy 169.739056 -100.17633) (xy 154.325828 -100.17633) (xy 154.325828 -100.177854) (xy 154.325338 -100.207838)
			(xy 154.31751 -100.267294) (xy 154.301989 -100.325219) (xy 154.27904 -100.380623) (xy 154.249056 -100.432557)
			(xy 154.21255 -100.480133) (xy 154.170145 -100.522538) (xy 154.122569 -100.559044) (xy 154.070635 -100.589028)
			(xy 154.015231 -100.611977) (xy 153.957306 -100.627498) (xy 153.89785 -100.635326) (xy 153.837882 -100.635326)
			(xy 153.778426 -100.627498) (xy 153.720501 -100.611977) (xy 153.665097 -100.589028) (xy 153.613163 -100.559044)
			(xy 153.565587 -100.522538) (xy 153.523182 -100.480133) (xy 153.486676 -100.432557) (xy 153.456692 -100.380623)
			(xy 153.433743 -100.325219) (xy 153.418222 -100.267294) (xy 153.410394 -100.207838) (xy 153.409904 -100.177854)
			(xy 54.554603 -100.177854) (xy 54.554138 -100.206298) (xy 54.546315 -100.26572) (xy 54.530802 -100.323613)
			(xy 54.507866 -100.378986) (xy 54.477899 -100.430892) (xy 54.441412 -100.478442) (xy 54.399032 -100.520822)
			(xy 54.351482 -100.557309) (xy 54.299576 -100.587276) (xy 54.244203 -100.610212) (xy 54.18631 -100.625725)
			(xy 54.126888 -100.633548) (xy 54.066952 -100.633548) (xy 54.00753 -100.625725) (xy 53.949637 -100.610212)
			(xy 53.894264 -100.587276) (xy 53.842358 -100.557309) (xy 53.794808 -100.520822) (xy 53.752428 -100.478442)
			(xy 53.715941 -100.430892) (xy 53.685974 -100.378986) (xy 53.663038 -100.323613) (xy 53.647525 -100.26572)
			(xy 53.639702 -100.206298) (xy 53.639212 -100.17633) (xy 38.225476 -100.17633) (xy 38.225476 -100.177854)
			(xy 38.224986 -100.207822) (xy 38.217163 -100.267244) (xy 38.20165 -100.325137) (xy 38.178714 -100.38051)
			(xy 38.148747 -100.432416) (xy 38.11226 -100.479966) (xy 38.06988 -100.522346) (xy 38.02233 -100.558833)
			(xy 37.970424 -100.5888) (xy 37.915051 -100.611736) (xy 37.857158 -100.627249) (xy 37.797736 -100.635072)
			(xy 37.7378 -100.635072) (xy 37.678378 -100.627249) (xy 37.620485 -100.611736) (xy 37.565112 -100.5888)
			(xy 37.513206 -100.558833) (xy 37.465656 -100.522346) (xy 37.423276 -100.479966) (xy 37.386789 -100.432416)
			(xy 37.356822 -100.38051) (xy 37.333886 -100.325137) (xy 37.318373 -100.267244) (xy 37.31055 -100.207822)
			(xy 37.31006 -100.177854) (xy 4.30911 -100.177854) (xy 4.30911 -101.984302) (xy 35.277552 -101.984302)
			(xy 35.277552 -101.120702) (xy 35.278042 -101.090734) (xy 35.285865 -101.031312) (xy 35.301378 -100.973419)
			(xy 35.324314 -100.918046) (xy 35.354281 -100.86614) (xy 35.390768 -100.81859) (xy 35.433148 -100.77621)
			(xy 35.480698 -100.739723) (xy 35.532604 -100.709756) (xy 35.587977 -100.68682) (xy 35.64587 -100.671307)
			(xy 35.705292 -100.663484) (xy 35.765228 -100.663484) (xy 35.82465 -100.671307) (xy 35.882543 -100.68682)
			(xy 35.937916 -100.709756) (xy 35.989822 -100.739723) (xy 36.037372 -100.77621) (xy 36.079752 -100.81859)
			(xy 36.116239 -100.86614) (xy 36.146206 -100.918046) (xy 36.169142 -100.973419) (xy 36.184655 -101.031312)
			(xy 36.192478 -101.090734) (xy 36.192968 -101.120702) (xy 36.192968 -101.976428) (xy 51.785012 -101.976428)
			(xy 51.785012 -101.112828) (xy 51.785502 -101.08286) (xy 51.793325 -101.023438) (xy 51.808838 -100.965545)
			(xy 51.831774 -100.910172) (xy 51.861741 -100.858266) (xy 51.898228 -100.810716) (xy 51.940608 -100.768336)
			(xy 51.988158 -100.731849) (xy 52.040064 -100.701882) (xy 52.095437 -100.678946) (xy 52.15333 -100.663433)
			(xy 52.212752 -100.65561) (xy 52.272688 -100.65561) (xy 52.33211 -100.663433) (xy 52.390003 -100.678946)
			(xy 52.445376 -100.701882) (xy 52.497282 -100.731849) (xy 52.544832 -100.768336) (xy 52.587212 -100.810716)
			(xy 52.623699 -100.858266) (xy 52.653666 -100.910172) (xy 52.676602 -100.965545) (xy 52.692115 -101.023438)
			(xy 52.699938 -101.08286) (xy 52.700428 -101.112828) (xy 52.700428 -101.976428) (xy 52.700299 -101.984302)
			(xy 151.377396 -101.984302) (xy 151.377396 -101.120702) (xy 151.377886 -101.090718) (xy 151.385714 -101.031262)
			(xy 151.401235 -100.973337) (xy 151.424184 -100.917933) (xy 151.454168 -100.865999) (xy 151.490674 -100.818423)
			(xy 151.533079 -100.776018) (xy 151.580655 -100.739512) (xy 151.632589 -100.709528) (xy 151.687993 -100.686579)
			(xy 151.745918 -100.671058) (xy 151.805374 -100.66323) (xy 151.865342 -100.66323) (xy 151.924798 -100.671058)
			(xy 151.982723 -100.686579) (xy 152.038127 -100.709528) (xy 152.090061 -100.739512) (xy 152.137637 -100.776018)
			(xy 152.180042 -100.818423) (xy 152.216548 -100.865999) (xy 152.246532 -100.917933) (xy 152.269481 -100.973337)
			(xy 152.285002 -101.031262) (xy 152.29283 -101.090718) (xy 152.29332 -101.120702) (xy 152.29332 -101.976428)
			(xy 167.884856 -101.976428) (xy 167.884856 -101.112828) (xy 167.885346 -101.082844) (xy 167.893174 -101.023388)
			(xy 167.908695 -100.965463) (xy 167.931644 -100.910059) (xy 167.961628 -100.858125) (xy 167.998134 -100.810549)
			(xy 168.040539 -100.768144) (xy 168.088115 -100.731638) (xy 168.140049 -100.701654) (xy 168.195453 -100.678705)
			(xy 168.253378 -100.663184) (xy 168.312834 -100.655356) (xy 168.372802 -100.655356) (xy 168.432258 -100.663184)
			(xy 168.490183 -100.678705) (xy 168.545587 -100.701654) (xy 168.597521 -100.731638) (xy 168.645097 -100.768144)
			(xy 168.687502 -100.810549) (xy 168.724008 -100.858125) (xy 168.753992 -100.910059) (xy 168.776941 -100.965463)
			(xy 168.792462 -101.023388) (xy 168.80029 -101.082844) (xy 168.80078 -101.112828) (xy 168.80078 -101.976428)
			(xy 168.800651 -101.984302) (xy 267.47724 -101.984302) (xy 267.47724 -101.120702) (xy 267.47773 -101.090718)
			(xy 267.485558 -101.031262) (xy 267.501079 -100.973337) (xy 267.524028 -100.917933) (xy 267.554012 -100.865999)
			(xy 267.590518 -100.818423) (xy 267.632923 -100.776018) (xy 267.680499 -100.739512) (xy 267.732433 -100.709528)
			(xy 267.787837 -100.686579) (xy 267.845762 -100.671058) (xy 267.905218 -100.66323) (xy 267.965186 -100.66323)
			(xy 268.024642 -100.671058) (xy 268.082567 -100.686579) (xy 268.137971 -100.709528) (xy 268.189905 -100.739512)
			(xy 268.237481 -100.776018) (xy 268.279886 -100.818423) (xy 268.316392 -100.865999) (xy 268.346376 -100.917933)
			(xy 268.369325 -100.973337) (xy 268.384846 -101.031262) (xy 268.392674 -101.090718) (xy 268.393164 -101.120702)
			(xy 268.393164 -101.976428) (xy 283.9847 -101.976428) (xy 283.9847 -101.112828) (xy 283.98519 -101.082844)
			(xy 283.993018 -101.023388) (xy 284.008539 -100.965463) (xy 284.031488 -100.910059) (xy 284.061472 -100.858125)
			(xy 284.097978 -100.810549) (xy 284.140383 -100.768144) (xy 284.187959 -100.731638) (xy 284.239893 -100.701654)
			(xy 284.295297 -100.678705) (xy 284.353222 -100.663184) (xy 284.412678 -100.655356) (xy 284.472646 -100.655356)
			(xy 284.532102 -100.663184) (xy 284.590027 -100.678705) (xy 284.645431 -100.701654) (xy 284.697365 -100.731638)
			(xy 284.744941 -100.768144) (xy 284.787346 -100.810549) (xy 284.823852 -100.858125) (xy 284.853836 -100.910059)
			(xy 284.876785 -100.965463) (xy 284.892306 -101.023388) (xy 284.900134 -101.082844) (xy 284.900624 -101.112828)
			(xy 284.900624 -101.976428) (xy 284.900495 -101.984302) (xy 383.577592 -101.984302) (xy 383.577592 -101.120702)
			(xy 383.578082 -101.090734) (xy 383.585905 -101.031312) (xy 383.601418 -100.973419) (xy 383.624354 -100.918046)
			(xy 383.654321 -100.86614) (xy 383.690808 -100.81859) (xy 383.733188 -100.77621) (xy 383.780738 -100.739723)
			(xy 383.832644 -100.709756) (xy 383.888017 -100.68682) (xy 383.94591 -100.671307) (xy 384.005332 -100.663484)
			(xy 384.065268 -100.663484) (xy 384.12469 -100.671307) (xy 384.182583 -100.68682) (xy 384.237956 -100.709756)
			(xy 384.289862 -100.739723) (xy 384.337412 -100.77621) (xy 384.379792 -100.81859) (xy 384.416279 -100.86614)
			(xy 384.446246 -100.918046) (xy 384.469182 -100.973419) (xy 384.484695 -101.031312) (xy 384.492518 -101.090734)
			(xy 384.493008 -101.120702) (xy 384.493008 -101.976428) (xy 400.085052 -101.976428) (xy 400.085052 -101.112828)
			(xy 400.085542 -101.08286) (xy 400.093365 -101.023438) (xy 400.108878 -100.965545) (xy 400.131814 -100.910172)
			(xy 400.161781 -100.858266) (xy 400.198268 -100.810716) (xy 400.240648 -100.768336) (xy 400.288198 -100.731849)
			(xy 400.340104 -100.701882) (xy 400.395477 -100.678946) (xy 400.45337 -100.663433) (xy 400.512792 -100.65561)
			(xy 400.572728 -100.65561) (xy 400.63215 -100.663433) (xy 400.690043 -100.678946) (xy 400.745416 -100.701882)
			(xy 400.797322 -100.731849) (xy 400.844872 -100.768336) (xy 400.887252 -100.810716) (xy 400.923739 -100.858266)
			(xy 400.953706 -100.910172) (xy 400.976642 -100.965545) (xy 400.992155 -101.023438) (xy 400.999978 -101.08286)
			(xy 401.000468 -101.112828) (xy 401.000468 -101.976428) (xy 400.999978 -102.006396) (xy 400.992155 -102.065818)
			(xy 400.976642 -102.123711) (xy 400.953706 -102.179084) (xy 400.923739 -102.23099) (xy 400.887252 -102.27854)
			(xy 400.844872 -102.32092) (xy 400.797322 -102.357407) (xy 400.745416 -102.387374) (xy 400.690043 -102.41031)
			(xy 400.63215 -102.425823) (xy 400.572728 -102.433646) (xy 400.512792 -102.433646) (xy 400.45337 -102.425823)
			(xy 400.395477 -102.41031) (xy 400.340104 -102.387374) (xy 400.288198 -102.357407) (xy 400.240648 -102.32092)
			(xy 400.198268 -102.27854) (xy 400.161781 -102.23099) (xy 400.131814 -102.179084) (xy 400.108878 -102.123711)
			(xy 400.093365 -102.065818) (xy 400.085542 -102.006396) (xy 400.085052 -101.976428) (xy 384.493008 -101.976428)
			(xy 384.493008 -101.984302) (xy 384.492518 -102.01427) (xy 384.484695 -102.073692) (xy 384.469182 -102.131585)
			(xy 384.446246 -102.186958) (xy 384.416279 -102.238864) (xy 384.379792 -102.286414) (xy 384.337412 -102.328794)
			(xy 384.289862 -102.365281) (xy 384.237956 -102.395248) (xy 384.182583 -102.418184) (xy 384.12469 -102.433697)
			(xy 384.065268 -102.44152) (xy 384.005332 -102.44152) (xy 383.94591 -102.433697) (xy 383.888017 -102.418184)
			(xy 383.832644 -102.395248) (xy 383.780738 -102.365281) (xy 383.733188 -102.328794) (xy 383.690808 -102.286414)
			(xy 383.654321 -102.238864) (xy 383.624354 -102.186958) (xy 383.601418 -102.131585) (xy 383.585905 -102.073692)
			(xy 383.578082 -102.01427) (xy 383.577592 -101.984302) (xy 284.900495 -101.984302) (xy 284.900134 -102.006412)
			(xy 284.892306 -102.065868) (xy 284.876785 -102.123793) (xy 284.853836 -102.179197) (xy 284.823852 -102.231131)
			(xy 284.787346 -102.278707) (xy 284.744941 -102.321112) (xy 284.697365 -102.357618) (xy 284.645431 -102.387602)
			(xy 284.590027 -102.410551) (xy 284.532102 -102.426072) (xy 284.472646 -102.4339) (xy 284.412678 -102.4339)
			(xy 284.353222 -102.426072) (xy 284.295297 -102.410551) (xy 284.239893 -102.387602) (xy 284.187959 -102.357618)
			(xy 284.140383 -102.321112) (xy 284.097978 -102.278707) (xy 284.061472 -102.231131) (xy 284.031488 -102.179197)
			(xy 284.008539 -102.123793) (xy 283.993018 -102.065868) (xy 283.98519 -102.006412) (xy 283.9847 -101.976428)
			(xy 268.393164 -101.976428) (xy 268.393164 -101.984302) (xy 268.392674 -102.014286) (xy 268.384846 -102.073742)
			(xy 268.369325 -102.131667) (xy 268.346376 -102.187071) (xy 268.316392 -102.239005) (xy 268.279886 -102.286581)
			(xy 268.237481 -102.328986) (xy 268.189905 -102.365492) (xy 268.137971 -102.395476) (xy 268.082567 -102.418425)
			(xy 268.024642 -102.433946) (xy 267.965186 -102.441774) (xy 267.905218 -102.441774) (xy 267.845762 -102.433946)
			(xy 267.787837 -102.418425) (xy 267.732433 -102.395476) (xy 267.680499 -102.365492) (xy 267.632923 -102.328986)
			(xy 267.590518 -102.286581) (xy 267.554012 -102.239005) (xy 267.524028 -102.187071) (xy 267.501079 -102.131667)
			(xy 267.485558 -102.073742) (xy 267.47773 -102.014286) (xy 267.47724 -101.984302) (xy 168.800651 -101.984302)
			(xy 168.80029 -102.006412) (xy 168.792462 -102.065868) (xy 168.776941 -102.123793) (xy 168.753992 -102.179197)
			(xy 168.724008 -102.231131) (xy 168.687502 -102.278707) (xy 168.645097 -102.321112) (xy 168.597521 -102.357618)
			(xy 168.545587 -102.387602) (xy 168.490183 -102.410551) (xy 168.432258 -102.426072) (xy 168.372802 -102.4339)
			(xy 168.312834 -102.4339) (xy 168.253378 -102.426072) (xy 168.195453 -102.410551) (xy 168.140049 -102.387602)
			(xy 168.088115 -102.357618) (xy 168.040539 -102.321112) (xy 167.998134 -102.278707) (xy 167.961628 -102.231131)
			(xy 167.931644 -102.179197) (xy 167.908695 -102.123793) (xy 167.893174 -102.065868) (xy 167.885346 -102.006412)
			(xy 167.884856 -101.976428) (xy 152.29332 -101.976428) (xy 152.29332 -101.984302) (xy 152.29283 -102.014286)
			(xy 152.285002 -102.073742) (xy 152.269481 -102.131667) (xy 152.246532 -102.187071) (xy 152.216548 -102.239005)
			(xy 152.180042 -102.286581) (xy 152.137637 -102.328986) (xy 152.090061 -102.365492) (xy 152.038127 -102.395476)
			(xy 151.982723 -102.418425) (xy 151.924798 -102.433946) (xy 151.865342 -102.441774) (xy 151.805374 -102.441774)
			(xy 151.745918 -102.433946) (xy 151.687993 -102.418425) (xy 151.632589 -102.395476) (xy 151.580655 -102.365492)
			(xy 151.533079 -102.328986) (xy 151.490674 -102.286581) (xy 151.454168 -102.239005) (xy 151.424184 -102.187071)
			(xy 151.401235 -102.131667) (xy 151.385714 -102.073742) (xy 151.377886 -102.014286) (xy 151.377396 -101.984302)
			(xy 52.700299 -101.984302) (xy 52.699938 -102.006396) (xy 52.692115 -102.065818) (xy 52.676602 -102.123711)
			(xy 52.653666 -102.179084) (xy 52.623699 -102.23099) (xy 52.587212 -102.27854) (xy 52.544832 -102.32092)
			(xy 52.497282 -102.357407) (xy 52.445376 -102.387374) (xy 52.390003 -102.41031) (xy 52.33211 -102.425823)
			(xy 52.272688 -102.433646) (xy 52.212752 -102.433646) (xy 52.15333 -102.425823) (xy 52.095437 -102.41031)
			(xy 52.040064 -102.387374) (xy 51.988158 -102.357407) (xy 51.940608 -102.32092) (xy 51.898228 -102.27854)
			(xy 51.861741 -102.23099) (xy 51.831774 -102.179084) (xy 51.808838 -102.123711) (xy 51.793325 -102.065818)
			(xy 51.785502 -102.006396) (xy 51.785012 -101.976428) (xy 36.192968 -101.976428) (xy 36.192968 -101.984302)
			(xy 36.192478 -102.01427) (xy 36.184655 -102.073692) (xy 36.169142 -102.131585) (xy 36.146206 -102.186958)
			(xy 36.116239 -102.238864) (xy 36.079752 -102.286414) (xy 36.037372 -102.328794) (xy 35.989822 -102.365281)
			(xy 35.937916 -102.395248) (xy 35.882543 -102.418184) (xy 35.82465 -102.433697) (xy 35.765228 -102.44152)
			(xy 35.705292 -102.44152) (xy 35.64587 -102.433697) (xy 35.587977 -102.418184) (xy 35.532604 -102.395248)
			(xy 35.480698 -102.365281) (xy 35.433148 -102.328794) (xy 35.390768 -102.286414) (xy 35.354281 -102.238864)
			(xy 35.324314 -102.186958) (xy 35.301378 -102.131585) (xy 35.285865 -102.073692) (xy 35.278042 -102.01427)
			(xy 35.277552 -101.984302) (xy 4.30911 -101.984302) (xy 4.30911 -103.777796) (xy 37.31006 -103.777796)
			(xy 37.31006 -102.914196) (xy 37.31055 -102.884228) (xy 37.318373 -102.824806) (xy 37.333886 -102.766913)
			(xy 37.356822 -102.71154) (xy 37.386789 -102.659634) (xy 37.423276 -102.612084) (xy 37.465656 -102.569704)
			(xy 37.513206 -102.533217) (xy 37.565112 -102.50325) (xy 37.620485 -102.480314) (xy 37.678378 -102.464801)
			(xy 37.7378 -102.456978) (xy 37.797736 -102.456978) (xy 37.857158 -102.464801) (xy 37.915051 -102.480314)
			(xy 37.970424 -102.50325) (xy 38.02233 -102.533217) (xy 38.06988 -102.569704) (xy 38.11226 -102.612084)
			(xy 38.148747 -102.659634) (xy 38.178714 -102.71154) (xy 38.20165 -102.766913) (xy 38.217163 -102.824806)
			(xy 38.224986 -102.884228) (xy 38.225476 -102.914196) (xy 38.225476 -103.776272) (xy 53.639212 -103.776272)
			(xy 53.639212 -102.912672) (xy 53.639702 -102.882704) (xy 53.647525 -102.823282) (xy 53.663038 -102.765389)
			(xy 53.685974 -102.710016) (xy 53.715941 -102.65811) (xy 53.752428 -102.61056) (xy 53.794808 -102.56818)
			(xy 53.842358 -102.531693) (xy 53.894264 -102.501726) (xy 53.949637 -102.47879) (xy 54.00753 -102.463277)
			(xy 54.066952 -102.455454) (xy 54.126888 -102.455454) (xy 54.18631 -102.463277) (xy 54.244203 -102.47879)
			(xy 54.299576 -102.501726) (xy 54.351482 -102.531693) (xy 54.399032 -102.56818) (xy 54.441412 -102.61056)
			(xy 54.477899 -102.65811) (xy 54.507866 -102.710016) (xy 54.530802 -102.765389) (xy 54.546315 -102.823282)
			(xy 54.554138 -102.882704) (xy 54.554628 -102.912672) (xy 54.554628 -103.776272) (xy 54.554603 -103.777796)
			(xy 153.409904 -103.777796) (xy 153.409904 -102.914196) (xy 153.410394 -102.884212) (xy 153.418222 -102.824756)
			(xy 153.433743 -102.766831) (xy 153.456692 -102.711427) (xy 153.486676 -102.659493) (xy 153.523182 -102.611917)
			(xy 153.565587 -102.569512) (xy 153.613163 -102.533006) (xy 153.665097 -102.503022) (xy 153.720501 -102.480073)
			(xy 153.778426 -102.464552) (xy 153.837882 -102.456724) (xy 153.89785 -102.456724) (xy 153.957306 -102.464552)
			(xy 154.015231 -102.480073) (xy 154.070635 -102.503022) (xy 154.122569 -102.533006) (xy 154.170145 -102.569512)
			(xy 154.21255 -102.611917) (xy 154.249056 -102.659493) (xy 154.27904 -102.711427) (xy 154.301989 -102.766831)
			(xy 154.31751 -102.824756) (xy 154.325338 -102.884212) (xy 154.325828 -102.914196) (xy 154.325828 -103.776272)
			(xy 169.739056 -103.776272) (xy 169.739056 -102.912672) (xy 169.739546 -102.882688) (xy 169.747374 -102.823232)
			(xy 169.762895 -102.765307) (xy 169.785844 -102.709903) (xy 169.815828 -102.657969) (xy 169.852334 -102.610393)
			(xy 169.894739 -102.567988) (xy 169.942315 -102.531482) (xy 169.994249 -102.501498) (xy 170.049653 -102.478549)
			(xy 170.107578 -102.463028) (xy 170.167034 -102.4552) (xy 170.227002 -102.4552) (xy 170.286458 -102.463028)
			(xy 170.344383 -102.478549) (xy 170.399787 -102.501498) (xy 170.451721 -102.531482) (xy 170.499297 -102.567988)
			(xy 170.541702 -102.610393) (xy 170.578208 -102.657969) (xy 170.608192 -102.709903) (xy 170.631141 -102.765307)
			(xy 170.646662 -102.823232) (xy 170.65449 -102.882688) (xy 170.65498 -102.912672) (xy 170.65498 -103.776272)
			(xy 170.654955 -103.777796) (xy 269.509748 -103.777796) (xy 269.509748 -102.914196) (xy 269.510238 -102.884212)
			(xy 269.518066 -102.824756) (xy 269.533587 -102.766831) (xy 269.556536 -102.711427) (xy 269.58652 -102.659493)
			(xy 269.623026 -102.611917) (xy 269.665431 -102.569512) (xy 269.713007 -102.533006) (xy 269.764941 -102.503022)
			(xy 269.820345 -102.480073) (xy 269.87827 -102.464552) (xy 269.937726 -102.456724) (xy 269.997694 -102.456724)
			(xy 270.05715 -102.464552) (xy 270.115075 -102.480073) (xy 270.170479 -102.503022) (xy 270.222413 -102.533006)
			(xy 270.269989 -102.569512) (xy 270.312394 -102.611917) (xy 270.3489 -102.659493) (xy 270.378884 -102.711427)
			(xy 270.401833 -102.766831) (xy 270.417354 -102.824756) (xy 270.425182 -102.884212) (xy 270.425672 -102.914196)
			(xy 270.425672 -103.776272) (xy 285.8389 -103.776272) (xy 285.8389 -102.912672) (xy 285.83939 -102.882688)
			(xy 285.847218 -102.823232) (xy 285.862739 -102.765307) (xy 285.885688 -102.709903) (xy 285.915672 -102.657969)
			(xy 285.952178 -102.610393) (xy 285.994583 -102.567988) (xy 286.042159 -102.531482) (xy 286.094093 -102.501498)
			(xy 286.149497 -102.478549) (xy 286.207422 -102.463028) (xy 286.266878 -102.4552) (xy 286.326846 -102.4552)
			(xy 286.386302 -102.463028) (xy 286.444227 -102.478549) (xy 286.499631 -102.501498) (xy 286.551565 -102.531482)
			(xy 286.599141 -102.567988) (xy 286.641546 -102.610393) (xy 286.678052 -102.657969) (xy 286.708036 -102.709903)
			(xy 286.730985 -102.765307) (xy 286.746506 -102.823232) (xy 286.754334 -102.882688) (xy 286.754824 -102.912672)
			(xy 286.754824 -103.776272) (xy 286.754799 -103.777796) (xy 385.6101 -103.777796) (xy 385.6101 -102.914196)
			(xy 385.61059 -102.884228) (xy 385.618413 -102.824806) (xy 385.633926 -102.766913) (xy 385.656862 -102.71154)
			(xy 385.686829 -102.659634) (xy 385.723316 -102.612084) (xy 385.765696 -102.569704) (xy 385.813246 -102.533217)
			(xy 385.865152 -102.50325) (xy 385.920525 -102.480314) (xy 385.978418 -102.464801) (xy 386.03784 -102.456978)
			(xy 386.097776 -102.456978) (xy 386.157198 -102.464801) (xy 386.215091 -102.480314) (xy 386.270464 -102.50325)
			(xy 386.32237 -102.533217) (xy 386.36992 -102.569704) (xy 386.4123 -102.612084) (xy 386.448787 -102.659634)
			(xy 386.478754 -102.71154) (xy 386.50169 -102.766913) (xy 386.517203 -102.824806) (xy 386.525026 -102.884228)
			(xy 386.525516 -102.914196) (xy 386.525516 -103.776272) (xy 401.939252 -103.776272) (xy 401.939252 -102.912672)
			(xy 401.939742 -102.882704) (xy 401.947565 -102.823282) (xy 401.963078 -102.765389) (xy 401.986014 -102.710016)
			(xy 402.015981 -102.65811) (xy 402.052468 -102.61056) (xy 402.094848 -102.56818) (xy 402.142398 -102.531693)
			(xy 402.194304 -102.501726) (xy 402.249677 -102.47879) (xy 402.30757 -102.463277) (xy 402.366992 -102.455454)
			(xy 402.426928 -102.455454) (xy 402.48635 -102.463277) (xy 402.544243 -102.47879) (xy 402.599616 -102.501726)
			(xy 402.651522 -102.531693) (xy 402.699072 -102.56818) (xy 402.741452 -102.61056) (xy 402.777939 -102.65811)
			(xy 402.807906 -102.710016) (xy 402.830842 -102.765389) (xy 402.846355 -102.823282) (xy 402.854178 -102.882704)
			(xy 402.854668 -102.912672) (xy 402.854668 -103.776272) (xy 402.854178 -103.80624) (xy 402.846355 -103.865662)
			(xy 402.830842 -103.923555) (xy 402.807906 -103.978928) (xy 402.777939 -104.030834) (xy 402.741452 -104.078384)
			(xy 402.699072 -104.120764) (xy 402.651522 -104.157251) (xy 402.599616 -104.187218) (xy 402.544243 -104.210154)
			(xy 402.48635 -104.225667) (xy 402.426928 -104.23349) (xy 402.366992 -104.23349) (xy 402.30757 -104.225667)
			(xy 402.249677 -104.210154) (xy 402.194304 -104.187218) (xy 402.142398 -104.157251) (xy 402.094848 -104.120764)
			(xy 402.052468 -104.078384) (xy 402.015981 -104.030834) (xy 401.986014 -103.978928) (xy 401.963078 -103.923555)
			(xy 401.947565 -103.865662) (xy 401.939742 -103.80624) (xy 401.939252 -103.776272) (xy 386.525516 -103.776272)
			(xy 386.525516 -103.777796) (xy 386.525026 -103.807764) (xy 386.517203 -103.867186) (xy 386.50169 -103.925079)
			(xy 386.478754 -103.980452) (xy 386.448787 -104.032358) (xy 386.4123 -104.079908) (xy 386.36992 -104.122288)
			(xy 386.32237 -104.158775) (xy 386.270464 -104.188742) (xy 386.215091 -104.211678) (xy 386.157198 -104.227191)
			(xy 386.097776 -104.235014) (xy 386.03784 -104.235014) (xy 385.978418 -104.227191) (xy 385.920525 -104.211678)
			(xy 385.865152 -104.188742) (xy 385.813246 -104.158775) (xy 385.765696 -104.122288) (xy 385.723316 -104.079908)
			(xy 385.686829 -104.032358) (xy 385.656862 -103.980452) (xy 385.633926 -103.925079) (xy 385.618413 -103.867186)
			(xy 385.61059 -103.807764) (xy 385.6101 -103.777796) (xy 286.754799 -103.777796) (xy 286.754334 -103.806256)
			(xy 286.746506 -103.865712) (xy 286.730985 -103.923637) (xy 286.708036 -103.979041) (xy 286.678052 -104.030975)
			(xy 286.641546 -104.078551) (xy 286.599141 -104.120956) (xy 286.551565 -104.157462) (xy 286.499631 -104.187446)
			(xy 286.444227 -104.210395) (xy 286.386302 -104.225916) (xy 286.326846 -104.233744) (xy 286.266878 -104.233744)
			(xy 286.207422 -104.225916) (xy 286.149497 -104.210395) (xy 286.094093 -104.187446) (xy 286.042159 -104.157462)
			(xy 285.994583 -104.120956) (xy 285.952178 -104.078551) (xy 285.915672 -104.030975) (xy 285.885688 -103.979041)
			(xy 285.862739 -103.923637) (xy 285.847218 -103.865712) (xy 285.83939 -103.806256) (xy 285.8389 -103.776272)
			(xy 270.425672 -103.776272) (xy 270.425672 -103.777796) (xy 270.425182 -103.80778) (xy 270.417354 -103.867236)
			(xy 270.401833 -103.925161) (xy 270.378884 -103.980565) (xy 270.3489 -104.032499) (xy 270.312394 -104.080075)
			(xy 270.269989 -104.12248) (xy 270.222413 -104.158986) (xy 270.170479 -104.18897) (xy 270.115075 -104.211919)
			(xy 270.05715 -104.22744) (xy 269.997694 -104.235268) (xy 269.937726 -104.235268) (xy 269.87827 -104.22744)
			(xy 269.820345 -104.211919) (xy 269.764941 -104.18897) (xy 269.713007 -104.158986) (xy 269.665431 -104.12248)
			(xy 269.623026 -104.080075) (xy 269.58652 -104.032499) (xy 269.556536 -103.980565) (xy 269.533587 -103.925161)
			(xy 269.518066 -103.867236) (xy 269.510238 -103.80778) (xy 269.509748 -103.777796) (xy 170.654955 -103.777796)
			(xy 170.65449 -103.806256) (xy 170.646662 -103.865712) (xy 170.631141 -103.923637) (xy 170.608192 -103.979041)
			(xy 170.578208 -104.030975) (xy 170.541702 -104.078551) (xy 170.499297 -104.120956) (xy 170.451721 -104.157462)
			(xy 170.399787 -104.187446) (xy 170.344383 -104.210395) (xy 170.286458 -104.225916) (xy 170.227002 -104.233744)
			(xy 170.167034 -104.233744) (xy 170.107578 -104.225916) (xy 170.049653 -104.210395) (xy 169.994249 -104.187446)
			(xy 169.942315 -104.157462) (xy 169.894739 -104.120956) (xy 169.852334 -104.078551) (xy 169.815828 -104.030975)
			(xy 169.785844 -103.979041) (xy 169.762895 -103.923637) (xy 169.747374 -103.865712) (xy 169.739546 -103.806256)
			(xy 169.739056 -103.776272) (xy 154.325828 -103.776272) (xy 154.325828 -103.777796) (xy 154.325338 -103.80778)
			(xy 154.31751 -103.867236) (xy 154.301989 -103.925161) (xy 154.27904 -103.980565) (xy 154.249056 -104.032499)
			(xy 154.21255 -104.080075) (xy 154.170145 -104.12248) (xy 154.122569 -104.158986) (xy 154.070635 -104.18897)
			(xy 154.015231 -104.211919) (xy 153.957306 -104.22744) (xy 153.89785 -104.235268) (xy 153.837882 -104.235268)
			(xy 153.778426 -104.22744) (xy 153.720501 -104.211919) (xy 153.665097 -104.18897) (xy 153.613163 -104.158986)
			(xy 153.565587 -104.12248) (xy 153.523182 -104.080075) (xy 153.486676 -104.032499) (xy 153.456692 -103.980565)
			(xy 153.433743 -103.925161) (xy 153.418222 -103.867236) (xy 153.410394 -103.80778) (xy 153.409904 -103.777796)
			(xy 54.554603 -103.777796) (xy 54.554138 -103.80624) (xy 54.546315 -103.865662) (xy 54.530802 -103.923555)
			(xy 54.507866 -103.978928) (xy 54.477899 -104.030834) (xy 54.441412 -104.078384) (xy 54.399032 -104.120764)
			(xy 54.351482 -104.157251) (xy 54.299576 -104.187218) (xy 54.244203 -104.210154) (xy 54.18631 -104.225667)
			(xy 54.126888 -104.23349) (xy 54.066952 -104.23349) (xy 54.00753 -104.225667) (xy 53.949637 -104.210154)
			(xy 53.894264 -104.187218) (xy 53.842358 -104.157251) (xy 53.794808 -104.120764) (xy 53.752428 -104.078384)
			(xy 53.715941 -104.030834) (xy 53.685974 -103.978928) (xy 53.663038 -103.923555) (xy 53.647525 -103.865662)
			(xy 53.639702 -103.80624) (xy 53.639212 -103.776272) (xy 38.225476 -103.776272) (xy 38.225476 -103.777796)
			(xy 38.224986 -103.807764) (xy 38.217163 -103.867186) (xy 38.20165 -103.925079) (xy 38.178714 -103.980452)
			(xy 38.148747 -104.032358) (xy 38.11226 -104.079908) (xy 38.06988 -104.122288) (xy 38.02233 -104.158775)
			(xy 37.970424 -104.188742) (xy 37.915051 -104.211678) (xy 37.857158 -104.227191) (xy 37.797736 -104.235014)
			(xy 37.7378 -104.235014) (xy 37.678378 -104.227191) (xy 37.620485 -104.211678) (xy 37.565112 -104.188742)
			(xy 37.513206 -104.158775) (xy 37.465656 -104.122288) (xy 37.423276 -104.079908) (xy 37.386789 -104.032358)
			(xy 37.356822 -103.980452) (xy 37.333886 -103.925079) (xy 37.318373 -103.867186) (xy 37.31055 -103.807764)
			(xy 37.31006 -103.777796) (xy 4.30911 -103.777796) (xy 4.30911 -105.584498) (xy 34.667952 -105.584498)
			(xy 34.667952 -104.720898) (xy 34.668442 -104.69093) (xy 34.676265 -104.631508) (xy 34.691778 -104.573615)
			(xy 34.714714 -104.518242) (xy 34.744681 -104.466336) (xy 34.781168 -104.418786) (xy 34.823548 -104.376406)
			(xy 34.871098 -104.339919) (xy 34.923004 -104.309952) (xy 34.978377 -104.287016) (xy 35.03627 -104.271503)
			(xy 35.095692 -104.26368) (xy 35.155628 -104.26368) (xy 35.21505 -104.271503) (xy 35.272943 -104.287016)
			(xy 35.328316 -104.309952) (xy 35.380222 -104.339919) (xy 35.427772 -104.376406) (xy 35.470152 -104.418786)
			(xy 35.506639 -104.466336) (xy 35.536606 -104.518242) (xy 35.559542 -104.573615) (xy 35.575055 -104.631508)
			(xy 35.582878 -104.69093) (xy 35.583368 -104.720898) (xy 35.583368 -105.57637) (xy 51.785012 -105.57637)
			(xy 51.785012 -104.71277) (xy 51.785502 -104.682802) (xy 51.793325 -104.62338) (xy 51.808838 -104.565487)
			(xy 51.831774 -104.510114) (xy 51.861741 -104.458208) (xy 51.898228 -104.410658) (xy 51.940608 -104.368278)
			(xy 51.988158 -104.331791) (xy 52.040064 -104.301824) (xy 52.095437 -104.278888) (xy 52.15333 -104.263375)
			(xy 52.212752 -104.255552) (xy 52.272688 -104.255552) (xy 52.33211 -104.263375) (xy 52.390003 -104.278888)
			(xy 52.445376 -104.301824) (xy 52.497282 -104.331791) (xy 52.544832 -104.368278) (xy 52.587212 -104.410658)
			(xy 52.623699 -104.458208) (xy 52.653666 -104.510114) (xy 52.676602 -104.565487) (xy 52.692115 -104.62338)
			(xy 52.699938 -104.682802) (xy 52.700428 -104.71277) (xy 52.700428 -105.57637) (xy 52.700295 -105.584498)
			(xy 150.767796 -105.584498) (xy 150.767796 -104.720898) (xy 150.768286 -104.690914) (xy 150.776114 -104.631458)
			(xy 150.791635 -104.573533) (xy 150.814584 -104.518129) (xy 150.844568 -104.466195) (xy 150.881074 -104.418619)
			(xy 150.923479 -104.376214) (xy 150.971055 -104.339708) (xy 151.022989 -104.309724) (xy 151.078393 -104.286775)
			(xy 151.136318 -104.271254) (xy 151.195774 -104.263426) (xy 151.255742 -104.263426) (xy 151.315198 -104.271254)
			(xy 151.373123 -104.286775) (xy 151.428527 -104.309724) (xy 151.480461 -104.339708) (xy 151.528037 -104.376214)
			(xy 151.570442 -104.418619) (xy 151.606948 -104.466195) (xy 151.636932 -104.518129) (xy 151.659881 -104.573533)
			(xy 151.675402 -104.631458) (xy 151.68323 -104.690914) (xy 151.68372 -104.720898) (xy 151.68372 -105.57637)
			(xy 167.884856 -105.57637) (xy 167.884856 -104.71277) (xy 167.885346 -104.682786) (xy 167.893174 -104.62333)
			(xy 167.908695 -104.565405) (xy 167.931644 -104.510001) (xy 167.961628 -104.458067) (xy 167.998134 -104.410491)
			(xy 168.040539 -104.368086) (xy 168.088115 -104.33158) (xy 168.140049 -104.301596) (xy 168.195453 -104.278647)
			(xy 168.253378 -104.263126) (xy 168.312834 -104.255298) (xy 168.372802 -104.255298) (xy 168.432258 -104.263126)
			(xy 168.490183 -104.278647) (xy 168.545587 -104.301596) (xy 168.597521 -104.33158) (xy 168.645097 -104.368086)
			(xy 168.687502 -104.410491) (xy 168.724008 -104.458067) (xy 168.753992 -104.510001) (xy 168.776941 -104.565405)
			(xy 168.792462 -104.62333) (xy 168.80029 -104.682786) (xy 168.80078 -104.71277) (xy 168.80078 -105.57637)
			(xy 168.800647 -105.584498) (xy 266.86764 -105.584498) (xy 266.86764 -104.720898) (xy 266.86813 -104.690914)
			(xy 266.875958 -104.631458) (xy 266.891479 -104.573533) (xy 266.914428 -104.518129) (xy 266.944412 -104.466195)
			(xy 266.980918 -104.418619) (xy 267.023323 -104.376214) (xy 267.070899 -104.339708) (xy 267.122833 -104.309724)
			(xy 267.178237 -104.286775) (xy 267.236162 -104.271254) (xy 267.295618 -104.263426) (xy 267.355586 -104.263426)
			(xy 267.415042 -104.271254) (xy 267.472967 -104.286775) (xy 267.528371 -104.309724) (xy 267.580305 -104.339708)
			(xy 267.627881 -104.376214) (xy 267.670286 -104.418619) (xy 267.706792 -104.466195) (xy 267.736776 -104.518129)
			(xy 267.759725 -104.573533) (xy 267.775246 -104.631458) (xy 267.783074 -104.690914) (xy 267.783564 -104.720898)
			(xy 267.783564 -105.57637) (xy 283.9847 -105.57637) (xy 283.9847 -104.71277) (xy 283.98519 -104.682786)
			(xy 283.993018 -104.62333) (xy 284.008539 -104.565405) (xy 284.031488 -104.510001) (xy 284.061472 -104.458067)
			(xy 284.097978 -104.410491) (xy 284.140383 -104.368086) (xy 284.187959 -104.33158) (xy 284.239893 -104.301596)
			(xy 284.295297 -104.278647) (xy 284.353222 -104.263126) (xy 284.412678 -104.255298) (xy 284.472646 -104.255298)
			(xy 284.532102 -104.263126) (xy 284.590027 -104.278647) (xy 284.645431 -104.301596) (xy 284.697365 -104.33158)
			(xy 284.744941 -104.368086) (xy 284.787346 -104.410491) (xy 284.823852 -104.458067) (xy 284.853836 -104.510001)
			(xy 284.876785 -104.565405) (xy 284.892306 -104.62333) (xy 284.900134 -104.682786) (xy 284.900624 -104.71277)
			(xy 284.900624 -105.57637) (xy 284.900491 -105.584498) (xy 382.967992 -105.584498) (xy 382.967992 -104.720898)
			(xy 382.968482 -104.69093) (xy 382.976305 -104.631508) (xy 382.991818 -104.573615) (xy 383.014754 -104.518242)
			(xy 383.044721 -104.466336) (xy 383.081208 -104.418786) (xy 383.123588 -104.376406) (xy 383.171138 -104.339919)
			(xy 383.223044 -104.309952) (xy 383.278417 -104.287016) (xy 383.33631 -104.271503) (xy 383.395732 -104.26368)
			(xy 383.455668 -104.26368) (xy 383.51509 -104.271503) (xy 383.572983 -104.287016) (xy 383.628356 -104.309952)
			(xy 383.680262 -104.339919) (xy 383.727812 -104.376406) (xy 383.770192 -104.418786) (xy 383.806679 -104.466336)
			(xy 383.836646 -104.518242) (xy 383.859582 -104.573615) (xy 383.875095 -104.631508) (xy 383.882918 -104.69093)
			(xy 383.883408 -104.720898) (xy 383.883408 -105.57637) (xy 400.085052 -105.57637) (xy 400.085052 -104.71277)
			(xy 400.085542 -104.682802) (xy 400.093365 -104.62338) (xy 400.108878 -104.565487) (xy 400.131814 -104.510114)
			(xy 400.161781 -104.458208) (xy 400.198268 -104.410658) (xy 400.240648 -104.368278) (xy 400.288198 -104.331791)
			(xy 400.340104 -104.301824) (xy 400.395477 -104.278888) (xy 400.45337 -104.263375) (xy 400.512792 -104.255552)
			(xy 400.572728 -104.255552) (xy 400.63215 -104.263375) (xy 400.690043 -104.278888) (xy 400.745416 -104.301824)
			(xy 400.797322 -104.331791) (xy 400.844872 -104.368278) (xy 400.887252 -104.410658) (xy 400.923739 -104.458208)
			(xy 400.953706 -104.510114) (xy 400.976642 -104.565487) (xy 400.992155 -104.62338) (xy 400.999978 -104.682802)
			(xy 401.000468 -104.71277) (xy 401.000468 -105.57637) (xy 400.999978 -105.606338) (xy 400.992155 -105.66576)
			(xy 400.976642 -105.723653) (xy 400.953706 -105.779026) (xy 400.923739 -105.830932) (xy 400.887252 -105.878482)
			(xy 400.844872 -105.920862) (xy 400.797322 -105.957349) (xy 400.745416 -105.987316) (xy 400.690043 -106.010252)
			(xy 400.63215 -106.025765) (xy 400.572728 -106.033588) (xy 400.512792 -106.033588) (xy 400.45337 -106.025765)
			(xy 400.395477 -106.010252) (xy 400.340104 -105.987316) (xy 400.288198 -105.957349) (xy 400.240648 -105.920862)
			(xy 400.198268 -105.878482) (xy 400.161781 -105.830932) (xy 400.131814 -105.779026) (xy 400.108878 -105.723653)
			(xy 400.093365 -105.66576) (xy 400.085542 -105.606338) (xy 400.085052 -105.57637) (xy 383.883408 -105.57637)
			(xy 383.883408 -105.584498) (xy 383.882918 -105.614466) (xy 383.875095 -105.673888) (xy 383.859582 -105.731781)
			(xy 383.836646 -105.787154) (xy 383.806679 -105.83906) (xy 383.770192 -105.88661) (xy 383.727812 -105.92899)
			(xy 383.680262 -105.965477) (xy 383.628356 -105.995444) (xy 383.572983 -106.01838) (xy 383.51509 -106.033893)
			(xy 383.455668 -106.041716) (xy 383.395732 -106.041716) (xy 383.33631 -106.033893) (xy 383.278417 -106.01838)
			(xy 383.223044 -105.995444) (xy 383.171138 -105.965477) (xy 383.123588 -105.92899) (xy 383.081208 -105.88661)
			(xy 383.044721 -105.83906) (xy 383.014754 -105.787154) (xy 382.991818 -105.731781) (xy 382.976305 -105.673888)
			(xy 382.968482 -105.614466) (xy 382.967992 -105.584498) (xy 284.900491 -105.584498) (xy 284.900134 -105.606354)
			(xy 284.892306 -105.66581) (xy 284.876785 -105.723735) (xy 284.853836 -105.779139) (xy 284.823852 -105.831073)
			(xy 284.787346 -105.878649) (xy 284.744941 -105.921054) (xy 284.697365 -105.95756) (xy 284.645431 -105.987544)
			(xy 284.590027 -106.010493) (xy 284.532102 -106.026014) (xy 284.472646 -106.033842) (xy 284.412678 -106.033842)
			(xy 284.353222 -106.026014) (xy 284.295297 -106.010493) (xy 284.239893 -105.987544) (xy 284.187959 -105.95756)
			(xy 284.140383 -105.921054) (xy 284.097978 -105.878649) (xy 284.061472 -105.831073) (xy 284.031488 -105.779139)
			(xy 284.008539 -105.723735) (xy 283.993018 -105.66581) (xy 283.98519 -105.606354) (xy 283.9847 -105.57637)
			(xy 267.783564 -105.57637) (xy 267.783564 -105.584498) (xy 267.783074 -105.614482) (xy 267.775246 -105.673938)
			(xy 267.759725 -105.731863) (xy 267.736776 -105.787267) (xy 267.706792 -105.839201) (xy 267.670286 -105.886777)
			(xy 267.627881 -105.929182) (xy 267.580305 -105.965688) (xy 267.528371 -105.995672) (xy 267.472967 -106.018621)
			(xy 267.415042 -106.034142) (xy 267.355586 -106.04197) (xy 267.295618 -106.04197) (xy 267.236162 -106.034142)
			(xy 267.178237 -106.018621) (xy 267.122833 -105.995672) (xy 267.070899 -105.965688) (xy 267.023323 -105.929182)
			(xy 266.980918 -105.886777) (xy 266.944412 -105.839201) (xy 266.914428 -105.787267) (xy 266.891479 -105.731863)
			(xy 266.875958 -105.673938) (xy 266.86813 -105.614482) (xy 266.86764 -105.584498) (xy 168.800647 -105.584498)
			(xy 168.80029 -105.606354) (xy 168.792462 -105.66581) (xy 168.776941 -105.723735) (xy 168.753992 -105.779139)
			(xy 168.724008 -105.831073) (xy 168.687502 -105.878649) (xy 168.645097 -105.921054) (xy 168.597521 -105.95756)
			(xy 168.545587 -105.987544) (xy 168.490183 -106.010493) (xy 168.432258 -106.026014) (xy 168.372802 -106.033842)
			(xy 168.312834 -106.033842) (xy 168.253378 -106.026014) (xy 168.195453 -106.010493) (xy 168.140049 -105.987544)
			(xy 168.088115 -105.95756) (xy 168.040539 -105.921054) (xy 167.998134 -105.878649) (xy 167.961628 -105.831073)
			(xy 167.931644 -105.779139) (xy 167.908695 -105.723735) (xy 167.893174 -105.66581) (xy 167.885346 -105.606354)
			(xy 167.884856 -105.57637) (xy 151.68372 -105.57637) (xy 151.68372 -105.584498) (xy 151.68323 -105.614482)
			(xy 151.675402 -105.673938) (xy 151.659881 -105.731863) (xy 151.636932 -105.787267) (xy 151.606948 -105.839201)
			(xy 151.570442 -105.886777) (xy 151.528037 -105.929182) (xy 151.480461 -105.965688) (xy 151.428527 -105.995672)
			(xy 151.373123 -106.018621) (xy 151.315198 -106.034142) (xy 151.255742 -106.04197) (xy 151.195774 -106.04197)
			(xy 151.136318 -106.034142) (xy 151.078393 -106.018621) (xy 151.022989 -105.995672) (xy 150.971055 -105.965688)
			(xy 150.923479 -105.929182) (xy 150.881074 -105.886777) (xy 150.844568 -105.839201) (xy 150.814584 -105.787267)
			(xy 150.791635 -105.731863) (xy 150.776114 -105.673938) (xy 150.768286 -105.614482) (xy 150.767796 -105.584498)
			(xy 52.700295 -105.584498) (xy 52.699938 -105.606338) (xy 52.692115 -105.66576) (xy 52.676602 -105.723653)
			(xy 52.653666 -105.779026) (xy 52.623699 -105.830932) (xy 52.587212 -105.878482) (xy 52.544832 -105.920862)
			(xy 52.497282 -105.957349) (xy 52.445376 -105.987316) (xy 52.390003 -106.010252) (xy 52.33211 -106.025765)
			(xy 52.272688 -106.033588) (xy 52.212752 -106.033588) (xy 52.15333 -106.025765) (xy 52.095437 -106.010252)
			(xy 52.040064 -105.987316) (xy 51.988158 -105.957349) (xy 51.940608 -105.920862) (xy 51.898228 -105.878482)
			(xy 51.861741 -105.830932) (xy 51.831774 -105.779026) (xy 51.808838 -105.723653) (xy 51.793325 -105.66576)
			(xy 51.785502 -105.606338) (xy 51.785012 -105.57637) (xy 35.583368 -105.57637) (xy 35.583368 -105.584498)
			(xy 35.582878 -105.614466) (xy 35.575055 -105.673888) (xy 35.559542 -105.731781) (xy 35.536606 -105.787154)
			(xy 35.506639 -105.83906) (xy 35.470152 -105.88661) (xy 35.427772 -105.92899) (xy 35.380222 -105.965477)
			(xy 35.328316 -105.995444) (xy 35.272943 -106.01838) (xy 35.21505 -106.033893) (xy 35.155628 -106.041716)
			(xy 35.095692 -106.041716) (xy 35.03627 -106.033893) (xy 34.978377 -106.01838) (xy 34.923004 -105.995444)
			(xy 34.871098 -105.965477) (xy 34.823548 -105.92899) (xy 34.781168 -105.88661) (xy 34.744681 -105.83906)
			(xy 34.714714 -105.787154) (xy 34.691778 -105.731781) (xy 34.676265 -105.673888) (xy 34.668442 -105.614466)
			(xy 34.667952 -105.584498) (xy 4.30911 -105.584498) (xy 4.30911 -107.377738) (xy 37.31006 -107.377738)
			(xy 37.31006 -106.514138) (xy 37.31055 -106.48417) (xy 37.318373 -106.424748) (xy 37.333886 -106.366855)
			(xy 37.356822 -106.311482) (xy 37.386789 -106.259576) (xy 37.423276 -106.212026) (xy 37.465656 -106.169646)
			(xy 37.513206 -106.133159) (xy 37.565112 -106.103192) (xy 37.620485 -106.080256) (xy 37.678378 -106.064743)
			(xy 37.7378 -106.05692) (xy 37.797736 -106.05692) (xy 37.857158 -106.064743) (xy 37.915051 -106.080256)
			(xy 37.970424 -106.103192) (xy 38.02233 -106.133159) (xy 38.06988 -106.169646) (xy 38.11226 -106.212026)
			(xy 38.148747 -106.259576) (xy 38.178714 -106.311482) (xy 38.20165 -106.366855) (xy 38.217163 -106.424748)
			(xy 38.224986 -106.48417) (xy 38.225476 -106.514138) (xy 38.225476 -107.376214) (xy 53.639212 -107.376214)
			(xy 53.639212 -106.512614) (xy 53.639702 -106.482646) (xy 53.647525 -106.423224) (xy 53.663038 -106.365331)
			(xy 53.685974 -106.309958) (xy 53.715941 -106.258052) (xy 53.752428 -106.210502) (xy 53.794808 -106.168122)
			(xy 53.842358 -106.131635) (xy 53.894264 -106.101668) (xy 53.949637 -106.078732) (xy 54.00753 -106.063219)
			(xy 54.066952 -106.055396) (xy 54.126888 -106.055396) (xy 54.18631 -106.063219) (xy 54.244203 -106.078732)
			(xy 54.299576 -106.101668) (xy 54.351482 -106.131635) (xy 54.399032 -106.168122) (xy 54.441412 -106.210502)
			(xy 54.477899 -106.258052) (xy 54.507866 -106.309958) (xy 54.530802 -106.365331) (xy 54.546315 -106.423224)
			(xy 54.554138 -106.482646) (xy 54.554628 -106.512614) (xy 54.554628 -107.376214) (xy 54.554603 -107.377738)
			(xy 153.409904 -107.377738) (xy 153.409904 -106.514138) (xy 153.410394 -106.484154) (xy 153.418222 -106.424698)
			(xy 153.433743 -106.366773) (xy 153.456692 -106.311369) (xy 153.486676 -106.259435) (xy 153.523182 -106.211859)
			(xy 153.565587 -106.169454) (xy 153.613163 -106.132948) (xy 153.665097 -106.102964) (xy 153.720501 -106.080015)
			(xy 153.778426 -106.064494) (xy 153.837882 -106.056666) (xy 153.89785 -106.056666) (xy 153.957306 -106.064494)
			(xy 154.015231 -106.080015) (xy 154.070635 -106.102964) (xy 154.122569 -106.132948) (xy 154.170145 -106.169454)
			(xy 154.21255 -106.211859) (xy 154.249056 -106.259435) (xy 154.27904 -106.311369) (xy 154.301989 -106.366773)
			(xy 154.31751 -106.424698) (xy 154.325338 -106.484154) (xy 154.325828 -106.514138) (xy 154.325828 -107.376214)
			(xy 169.739056 -107.376214) (xy 169.739056 -106.512614) (xy 169.739546 -106.48263) (xy 169.747374 -106.423174)
			(xy 169.762895 -106.365249) (xy 169.785844 -106.309845) (xy 169.815828 -106.257911) (xy 169.852334 -106.210335)
			(xy 169.894739 -106.16793) (xy 169.942315 -106.131424) (xy 169.994249 -106.10144) (xy 170.049653 -106.078491)
			(xy 170.107578 -106.06297) (xy 170.167034 -106.055142) (xy 170.227002 -106.055142) (xy 170.286458 -106.06297)
			(xy 170.344383 -106.078491) (xy 170.399787 -106.10144) (xy 170.451721 -106.131424) (xy 170.499297 -106.16793)
			(xy 170.541702 -106.210335) (xy 170.578208 -106.257911) (xy 170.608192 -106.309845) (xy 170.631141 -106.365249)
			(xy 170.646662 -106.423174) (xy 170.65449 -106.48263) (xy 170.65498 -106.512614) (xy 170.65498 -107.376214)
			(xy 170.654955 -107.377738) (xy 269.509748 -107.377738) (xy 269.509748 -106.514138) (xy 269.510238 -106.484154)
			(xy 269.518066 -106.424698) (xy 269.533587 -106.366773) (xy 269.556536 -106.311369) (xy 269.58652 -106.259435)
			(xy 269.623026 -106.211859) (xy 269.665431 -106.169454) (xy 269.713007 -106.132948) (xy 269.764941 -106.102964)
			(xy 269.820345 -106.080015) (xy 269.87827 -106.064494) (xy 269.937726 -106.056666) (xy 269.997694 -106.056666)
			(xy 270.05715 -106.064494) (xy 270.115075 -106.080015) (xy 270.170479 -106.102964) (xy 270.222413 -106.132948)
			(xy 270.269989 -106.169454) (xy 270.312394 -106.211859) (xy 270.3489 -106.259435) (xy 270.378884 -106.311369)
			(xy 270.401833 -106.366773) (xy 270.417354 -106.424698) (xy 270.425182 -106.484154) (xy 270.425672 -106.514138)
			(xy 270.425672 -107.376214) (xy 285.8389 -107.376214) (xy 285.8389 -106.512614) (xy 285.83939 -106.48263)
			(xy 285.847218 -106.423174) (xy 285.862739 -106.365249) (xy 285.885688 -106.309845) (xy 285.915672 -106.257911)
			(xy 285.952178 -106.210335) (xy 285.994583 -106.16793) (xy 286.042159 -106.131424) (xy 286.094093 -106.10144)
			(xy 286.149497 -106.078491) (xy 286.207422 -106.06297) (xy 286.266878 -106.055142) (xy 286.326846 -106.055142)
			(xy 286.386302 -106.06297) (xy 286.444227 -106.078491) (xy 286.499631 -106.10144) (xy 286.551565 -106.131424)
			(xy 286.599141 -106.16793) (xy 286.641546 -106.210335) (xy 286.678052 -106.257911) (xy 286.708036 -106.309845)
			(xy 286.730985 -106.365249) (xy 286.746506 -106.423174) (xy 286.754334 -106.48263) (xy 286.754824 -106.512614)
			(xy 286.754824 -107.376214) (xy 286.754799 -107.377738) (xy 385.6101 -107.377738) (xy 385.6101 -106.514138)
			(xy 385.61059 -106.48417) (xy 385.618413 -106.424748) (xy 385.633926 -106.366855) (xy 385.656862 -106.311482)
			(xy 385.686829 -106.259576) (xy 385.723316 -106.212026) (xy 385.765696 -106.169646) (xy 385.813246 -106.133159)
			(xy 385.865152 -106.103192) (xy 385.920525 -106.080256) (xy 385.978418 -106.064743) (xy 386.03784 -106.05692)
			(xy 386.097776 -106.05692) (xy 386.157198 -106.064743) (xy 386.215091 -106.080256) (xy 386.270464 -106.103192)
			(xy 386.32237 -106.133159) (xy 386.36992 -106.169646) (xy 386.4123 -106.212026) (xy 386.448787 -106.259576)
			(xy 386.478754 -106.311482) (xy 386.50169 -106.366855) (xy 386.517203 -106.424748) (xy 386.525026 -106.48417)
			(xy 386.525516 -106.514138) (xy 386.525516 -107.376214) (xy 401.939252 -107.376214) (xy 401.939252 -106.512614)
			(xy 401.939742 -106.482646) (xy 401.947565 -106.423224) (xy 401.963078 -106.365331) (xy 401.986014 -106.309958)
			(xy 402.015981 -106.258052) (xy 402.052468 -106.210502) (xy 402.094848 -106.168122) (xy 402.142398 -106.131635)
			(xy 402.194304 -106.101668) (xy 402.249677 -106.078732) (xy 402.30757 -106.063219) (xy 402.366992 -106.055396)
			(xy 402.426928 -106.055396) (xy 402.48635 -106.063219) (xy 402.544243 -106.078732) (xy 402.599616 -106.101668)
			(xy 402.651522 -106.131635) (xy 402.699072 -106.168122) (xy 402.741452 -106.210502) (xy 402.777939 -106.258052)
			(xy 402.807906 -106.309958) (xy 402.830842 -106.365331) (xy 402.846355 -106.423224) (xy 402.854178 -106.482646)
			(xy 402.854668 -106.512614) (xy 402.854668 -107.376214) (xy 402.854178 -107.406182) (xy 402.846355 -107.465604)
			(xy 402.830842 -107.523497) (xy 402.807906 -107.57887) (xy 402.777939 -107.630776) (xy 402.741452 -107.678326)
			(xy 402.699072 -107.720706) (xy 402.651522 -107.757193) (xy 402.599616 -107.78716) (xy 402.544243 -107.810096)
			(xy 402.48635 -107.825609) (xy 402.426928 -107.833432) (xy 402.366992 -107.833432) (xy 402.30757 -107.825609)
			(xy 402.249677 -107.810096) (xy 402.194304 -107.78716) (xy 402.142398 -107.757193) (xy 402.094848 -107.720706)
			(xy 402.052468 -107.678326) (xy 402.015981 -107.630776) (xy 401.986014 -107.57887) (xy 401.963078 -107.523497)
			(xy 401.947565 -107.465604) (xy 401.939742 -107.406182) (xy 401.939252 -107.376214) (xy 386.525516 -107.376214)
			(xy 386.525516 -107.377738) (xy 386.525026 -107.407706) (xy 386.517203 -107.467128) (xy 386.50169 -107.525021)
			(xy 386.478754 -107.580394) (xy 386.448787 -107.6323) (xy 386.4123 -107.67985) (xy 386.36992 -107.72223)
			(xy 386.32237 -107.758717) (xy 386.270464 -107.788684) (xy 386.215091 -107.81162) (xy 386.157198 -107.827133)
			(xy 386.097776 -107.834956) (xy 386.03784 -107.834956) (xy 385.978418 -107.827133) (xy 385.920525 -107.81162)
			(xy 385.865152 -107.788684) (xy 385.813246 -107.758717) (xy 385.765696 -107.72223) (xy 385.723316 -107.67985)
			(xy 385.686829 -107.6323) (xy 385.656862 -107.580394) (xy 385.633926 -107.525021) (xy 385.618413 -107.467128)
			(xy 385.61059 -107.407706) (xy 385.6101 -107.377738) (xy 286.754799 -107.377738) (xy 286.754334 -107.406198)
			(xy 286.746506 -107.465654) (xy 286.730985 -107.523579) (xy 286.708036 -107.578983) (xy 286.678052 -107.630917)
			(xy 286.641546 -107.678493) (xy 286.599141 -107.720898) (xy 286.551565 -107.757404) (xy 286.499631 -107.787388)
			(xy 286.444227 -107.810337) (xy 286.386302 -107.825858) (xy 286.326846 -107.833686) (xy 286.266878 -107.833686)
			(xy 286.207422 -107.825858) (xy 286.149497 -107.810337) (xy 286.094093 -107.787388) (xy 286.042159 -107.757404)
			(xy 285.994583 -107.720898) (xy 285.952178 -107.678493) (xy 285.915672 -107.630917) (xy 285.885688 -107.578983)
			(xy 285.862739 -107.523579) (xy 285.847218 -107.465654) (xy 285.83939 -107.406198) (xy 285.8389 -107.376214)
			(xy 270.425672 -107.376214) (xy 270.425672 -107.377738) (xy 270.425182 -107.407722) (xy 270.417354 -107.467178)
			(xy 270.401833 -107.525103) (xy 270.378884 -107.580507) (xy 270.3489 -107.632441) (xy 270.312394 -107.680017)
			(xy 270.269989 -107.722422) (xy 270.222413 -107.758928) (xy 270.170479 -107.788912) (xy 270.115075 -107.811861)
			(xy 270.05715 -107.827382) (xy 269.997694 -107.83521) (xy 269.937726 -107.83521) (xy 269.87827 -107.827382)
			(xy 269.820345 -107.811861) (xy 269.764941 -107.788912) (xy 269.713007 -107.758928) (xy 269.665431 -107.722422)
			(xy 269.623026 -107.680017) (xy 269.58652 -107.632441) (xy 269.556536 -107.580507) (xy 269.533587 -107.525103)
			(xy 269.518066 -107.467178) (xy 269.510238 -107.407722) (xy 269.509748 -107.377738) (xy 170.654955 -107.377738)
			(xy 170.65449 -107.406198) (xy 170.646662 -107.465654) (xy 170.631141 -107.523579) (xy 170.608192 -107.578983)
			(xy 170.578208 -107.630917) (xy 170.541702 -107.678493) (xy 170.499297 -107.720898) (xy 170.451721 -107.757404)
			(xy 170.399787 -107.787388) (xy 170.344383 -107.810337) (xy 170.286458 -107.825858) (xy 170.227002 -107.833686)
			(xy 170.167034 -107.833686) (xy 170.107578 -107.825858) (xy 170.049653 -107.810337) (xy 169.994249 -107.787388)
			(xy 169.942315 -107.757404) (xy 169.894739 -107.720898) (xy 169.852334 -107.678493) (xy 169.815828 -107.630917)
			(xy 169.785844 -107.578983) (xy 169.762895 -107.523579) (xy 169.747374 -107.465654) (xy 169.739546 -107.406198)
			(xy 169.739056 -107.376214) (xy 154.325828 -107.376214) (xy 154.325828 -107.377738) (xy 154.325338 -107.407722)
			(xy 154.31751 -107.467178) (xy 154.301989 -107.525103) (xy 154.27904 -107.580507) (xy 154.249056 -107.632441)
			(xy 154.21255 -107.680017) (xy 154.170145 -107.722422) (xy 154.122569 -107.758928) (xy 154.070635 -107.788912)
			(xy 154.015231 -107.811861) (xy 153.957306 -107.827382) (xy 153.89785 -107.83521) (xy 153.837882 -107.83521)
			(xy 153.778426 -107.827382) (xy 153.720501 -107.811861) (xy 153.665097 -107.788912) (xy 153.613163 -107.758928)
			(xy 153.565587 -107.722422) (xy 153.523182 -107.680017) (xy 153.486676 -107.632441) (xy 153.456692 -107.580507)
			(xy 153.433743 -107.525103) (xy 153.418222 -107.467178) (xy 153.410394 -107.407722) (xy 153.409904 -107.377738)
			(xy 54.554603 -107.377738) (xy 54.554138 -107.406182) (xy 54.546315 -107.465604) (xy 54.530802 -107.523497)
			(xy 54.507866 -107.57887) (xy 54.477899 -107.630776) (xy 54.441412 -107.678326) (xy 54.399032 -107.720706)
			(xy 54.351482 -107.757193) (xy 54.299576 -107.78716) (xy 54.244203 -107.810096) (xy 54.18631 -107.825609)
			(xy 54.126888 -107.833432) (xy 54.066952 -107.833432) (xy 54.00753 -107.825609) (xy 53.949637 -107.810096)
			(xy 53.894264 -107.78716) (xy 53.842358 -107.757193) (xy 53.794808 -107.720706) (xy 53.752428 -107.678326)
			(xy 53.715941 -107.630776) (xy 53.685974 -107.57887) (xy 53.663038 -107.523497) (xy 53.647525 -107.465604)
			(xy 53.639702 -107.406182) (xy 53.639212 -107.376214) (xy 38.225476 -107.376214) (xy 38.225476 -107.377738)
			(xy 38.224986 -107.407706) (xy 38.217163 -107.467128) (xy 38.20165 -107.525021) (xy 38.178714 -107.580394)
			(xy 38.148747 -107.6323) (xy 38.11226 -107.67985) (xy 38.06988 -107.72223) (xy 38.02233 -107.758717)
			(xy 37.970424 -107.788684) (xy 37.915051 -107.81162) (xy 37.857158 -107.827133) (xy 37.797736 -107.834956)
			(xy 37.7378 -107.834956) (xy 37.678378 -107.827133) (xy 37.620485 -107.81162) (xy 37.565112 -107.788684)
			(xy 37.513206 -107.758717) (xy 37.465656 -107.72223) (xy 37.423276 -107.67985) (xy 37.386789 -107.6323)
			(xy 37.356822 -107.580394) (xy 37.333886 -107.525021) (xy 37.318373 -107.467128) (xy 37.31055 -107.407706)
			(xy 37.31006 -107.377738) (xy 4.30911 -107.377738) (xy 4.30911 -109.18444) (xy 34.667952 -109.18444)
			(xy 34.667952 -108.32084) (xy 34.668442 -108.290872) (xy 34.676265 -108.23145) (xy 34.691778 -108.173557)
			(xy 34.714714 -108.118184) (xy 34.744681 -108.066278) (xy 34.781168 -108.018728) (xy 34.823548 -107.976348)
			(xy 34.871098 -107.939861) (xy 34.923004 -107.909894) (xy 34.978377 -107.886958) (xy 35.03627 -107.871445)
			(xy 35.095692 -107.863622) (xy 35.155628 -107.863622) (xy 35.21505 -107.871445) (xy 35.272943 -107.886958)
			(xy 35.328316 -107.909894) (xy 35.380222 -107.939861) (xy 35.427772 -107.976348) (xy 35.470152 -108.018728)
			(xy 35.506639 -108.066278) (xy 35.536606 -108.118184) (xy 35.559542 -108.173557) (xy 35.575055 -108.23145)
			(xy 35.582878 -108.290872) (xy 35.583368 -108.32084) (xy 35.583368 -109.176312) (xy 51.785012 -109.176312)
			(xy 51.785012 -108.312712) (xy 51.785502 -108.282744) (xy 51.793325 -108.223322) (xy 51.808838 -108.165429)
			(xy 51.831774 -108.110056) (xy 51.861741 -108.05815) (xy 51.898228 -108.0106) (xy 51.940608 -107.96822)
			(xy 51.988158 -107.931733) (xy 52.040064 -107.901766) (xy 52.095437 -107.87883) (xy 52.15333 -107.863317)
			(xy 52.212752 -107.855494) (xy 52.272688 -107.855494) (xy 52.33211 -107.863317) (xy 52.390003 -107.87883)
			(xy 52.445376 -107.901766) (xy 52.497282 -107.931733) (xy 52.544832 -107.96822) (xy 52.587212 -108.0106)
			(xy 52.623699 -108.05815) (xy 52.653666 -108.110056) (xy 52.676602 -108.165429) (xy 52.692115 -108.223322)
			(xy 52.699938 -108.282744) (xy 52.700428 -108.312712) (xy 52.700428 -109.176312) (xy 52.700295 -109.18444)
			(xy 150.767796 -109.18444) (xy 150.767796 -108.32084) (xy 150.768286 -108.290856) (xy 150.776114 -108.2314)
			(xy 150.791635 -108.173475) (xy 150.814584 -108.118071) (xy 150.844568 -108.066137) (xy 150.881074 -108.018561)
			(xy 150.923479 -107.976156) (xy 150.971055 -107.93965) (xy 151.022989 -107.909666) (xy 151.078393 -107.886717)
			(xy 151.136318 -107.871196) (xy 151.195774 -107.863368) (xy 151.255742 -107.863368) (xy 151.315198 -107.871196)
			(xy 151.373123 -107.886717) (xy 151.428527 -107.909666) (xy 151.480461 -107.93965) (xy 151.528037 -107.976156)
			(xy 151.570442 -108.018561) (xy 151.606948 -108.066137) (xy 151.636932 -108.118071) (xy 151.659881 -108.173475)
			(xy 151.675402 -108.2314) (xy 151.68323 -108.290856) (xy 151.68372 -108.32084) (xy 151.68372 -109.176312)
			(xy 167.884856 -109.176312) (xy 167.884856 -108.312712) (xy 167.885346 -108.282728) (xy 167.893174 -108.223272)
			(xy 167.908695 -108.165347) (xy 167.931644 -108.109943) (xy 167.961628 -108.058009) (xy 167.998134 -108.010433)
			(xy 168.040539 -107.968028) (xy 168.088115 -107.931522) (xy 168.140049 -107.901538) (xy 168.195453 -107.878589)
			(xy 168.253378 -107.863068) (xy 168.312834 -107.85524) (xy 168.372802 -107.85524) (xy 168.432258 -107.863068)
			(xy 168.490183 -107.878589) (xy 168.545587 -107.901538) (xy 168.597521 -107.931522) (xy 168.645097 -107.968028)
			(xy 168.687502 -108.010433) (xy 168.724008 -108.058009) (xy 168.753992 -108.109943) (xy 168.776941 -108.165347)
			(xy 168.792462 -108.223272) (xy 168.80029 -108.282728) (xy 168.80078 -108.312712) (xy 168.80078 -109.176312)
			(xy 168.800647 -109.18444) (xy 266.86764 -109.18444) (xy 266.86764 -108.32084) (xy 266.86813 -108.290856)
			(xy 266.875958 -108.2314) (xy 266.891479 -108.173475) (xy 266.914428 -108.118071) (xy 266.944412 -108.066137)
			(xy 266.980918 -108.018561) (xy 267.023323 -107.976156) (xy 267.070899 -107.93965) (xy 267.122833 -107.909666)
			(xy 267.178237 -107.886717) (xy 267.236162 -107.871196) (xy 267.295618 -107.863368) (xy 267.355586 -107.863368)
			(xy 267.415042 -107.871196) (xy 267.472967 -107.886717) (xy 267.528371 -107.909666) (xy 267.580305 -107.93965)
			(xy 267.627881 -107.976156) (xy 267.670286 -108.018561) (xy 267.706792 -108.066137) (xy 267.736776 -108.118071)
			(xy 267.759725 -108.173475) (xy 267.775246 -108.2314) (xy 267.783074 -108.290856) (xy 267.783564 -108.32084)
			(xy 267.783564 -109.176312) (xy 283.9847 -109.176312) (xy 283.9847 -108.312712) (xy 283.98519 -108.282728)
			(xy 283.993018 -108.223272) (xy 284.008539 -108.165347) (xy 284.031488 -108.109943) (xy 284.061472 -108.058009)
			(xy 284.097978 -108.010433) (xy 284.140383 -107.968028) (xy 284.187959 -107.931522) (xy 284.239893 -107.901538)
			(xy 284.295297 -107.878589) (xy 284.353222 -107.863068) (xy 284.412678 -107.85524) (xy 284.472646 -107.85524)
			(xy 284.532102 -107.863068) (xy 284.590027 -107.878589) (xy 284.645431 -107.901538) (xy 284.697365 -107.931522)
			(xy 284.744941 -107.968028) (xy 284.787346 -108.010433) (xy 284.823852 -108.058009) (xy 284.853836 -108.109943)
			(xy 284.876785 -108.165347) (xy 284.892306 -108.223272) (xy 284.900134 -108.282728) (xy 284.900624 -108.312712)
			(xy 284.900624 -109.176312) (xy 284.900491 -109.18444) (xy 382.967992 -109.18444) (xy 382.967992 -108.32084)
			(xy 382.968482 -108.290872) (xy 382.976305 -108.23145) (xy 382.991818 -108.173557) (xy 383.014754 -108.118184)
			(xy 383.044721 -108.066278) (xy 383.081208 -108.018728) (xy 383.123588 -107.976348) (xy 383.171138 -107.939861)
			(xy 383.223044 -107.909894) (xy 383.278417 -107.886958) (xy 383.33631 -107.871445) (xy 383.395732 -107.863622)
			(xy 383.455668 -107.863622) (xy 383.51509 -107.871445) (xy 383.572983 -107.886958) (xy 383.628356 -107.909894)
			(xy 383.680262 -107.939861) (xy 383.727812 -107.976348) (xy 383.770192 -108.018728) (xy 383.806679 -108.066278)
			(xy 383.836646 -108.118184) (xy 383.859582 -108.173557) (xy 383.875095 -108.23145) (xy 383.882918 -108.290872)
			(xy 383.883408 -108.32084) (xy 383.883408 -109.176312) (xy 400.085052 -109.176312) (xy 400.085052 -108.312712)
			(xy 400.085542 -108.282744) (xy 400.093365 -108.223322) (xy 400.108878 -108.165429) (xy 400.131814 -108.110056)
			(xy 400.161781 -108.05815) (xy 400.198268 -108.0106) (xy 400.240648 -107.96822) (xy 400.288198 -107.931733)
			(xy 400.340104 -107.901766) (xy 400.395477 -107.87883) (xy 400.45337 -107.863317) (xy 400.512792 -107.855494)
			(xy 400.572728 -107.855494) (xy 400.63215 -107.863317) (xy 400.690043 -107.87883) (xy 400.745416 -107.901766)
			(xy 400.797322 -107.931733) (xy 400.844872 -107.96822) (xy 400.887252 -108.0106) (xy 400.923739 -108.05815)
			(xy 400.953706 -108.110056) (xy 400.976642 -108.165429) (xy 400.992155 -108.223322) (xy 400.999978 -108.282744)
			(xy 401.000468 -108.312712) (xy 401.000468 -109.176312) (xy 400.999978 -109.20628) (xy 400.992155 -109.265702)
			(xy 400.976642 -109.323595) (xy 400.953706 -109.378968) (xy 400.923739 -109.430874) (xy 400.887252 -109.478424)
			(xy 400.844872 -109.520804) (xy 400.797322 -109.557291) (xy 400.745416 -109.587258) (xy 400.690043 -109.610194)
			(xy 400.63215 -109.625707) (xy 400.572728 -109.63353) (xy 400.512792 -109.63353) (xy 400.45337 -109.625707)
			(xy 400.395477 -109.610194) (xy 400.340104 -109.587258) (xy 400.288198 -109.557291) (xy 400.240648 -109.520804)
			(xy 400.198268 -109.478424) (xy 400.161781 -109.430874) (xy 400.131814 -109.378968) (xy 400.108878 -109.323595)
			(xy 400.093365 -109.265702) (xy 400.085542 -109.20628) (xy 400.085052 -109.176312) (xy 383.883408 -109.176312)
			(xy 383.883408 -109.18444) (xy 383.882918 -109.214408) (xy 383.875095 -109.27383) (xy 383.859582 -109.331723)
			(xy 383.836646 -109.387096) (xy 383.806679 -109.439002) (xy 383.770192 -109.486552) (xy 383.727812 -109.528932)
			(xy 383.680262 -109.565419) (xy 383.628356 -109.595386) (xy 383.572983 -109.618322) (xy 383.51509 -109.633835)
			(xy 383.455668 -109.641658) (xy 383.395732 -109.641658) (xy 383.33631 -109.633835) (xy 383.278417 -109.618322)
			(xy 383.223044 -109.595386) (xy 383.171138 -109.565419) (xy 383.123588 -109.528932) (xy 383.081208 -109.486552)
			(xy 383.044721 -109.439002) (xy 383.014754 -109.387096) (xy 382.991818 -109.331723) (xy 382.976305 -109.27383)
			(xy 382.968482 -109.214408) (xy 382.967992 -109.18444) (xy 284.900491 -109.18444) (xy 284.900134 -109.206296)
			(xy 284.892306 -109.265752) (xy 284.876785 -109.323677) (xy 284.853836 -109.379081) (xy 284.823852 -109.431015)
			(xy 284.787346 -109.478591) (xy 284.744941 -109.520996) (xy 284.697365 -109.557502) (xy 284.645431 -109.587486)
			(xy 284.590027 -109.610435) (xy 284.532102 -109.625956) (xy 284.472646 -109.633784) (xy 284.412678 -109.633784)
			(xy 284.353222 -109.625956) (xy 284.295297 -109.610435) (xy 284.239893 -109.587486) (xy 284.187959 -109.557502)
			(xy 284.140383 -109.520996) (xy 284.097978 -109.478591) (xy 284.061472 -109.431015) (xy 284.031488 -109.379081)
			(xy 284.008539 -109.323677) (xy 283.993018 -109.265752) (xy 283.98519 -109.206296) (xy 283.9847 -109.176312)
			(xy 267.783564 -109.176312) (xy 267.783564 -109.18444) (xy 267.783074 -109.214424) (xy 267.775246 -109.27388)
			(xy 267.759725 -109.331805) (xy 267.736776 -109.387209) (xy 267.706792 -109.439143) (xy 267.670286 -109.486719)
			(xy 267.627881 -109.529124) (xy 267.580305 -109.56563) (xy 267.528371 -109.595614) (xy 267.472967 -109.618563)
			(xy 267.415042 -109.634084) (xy 267.355586 -109.641912) (xy 267.295618 -109.641912) (xy 267.236162 -109.634084)
			(xy 267.178237 -109.618563) (xy 267.122833 -109.595614) (xy 267.070899 -109.56563) (xy 267.023323 -109.529124)
			(xy 266.980918 -109.486719) (xy 266.944412 -109.439143) (xy 266.914428 -109.387209) (xy 266.891479 -109.331805)
			(xy 266.875958 -109.27388) (xy 266.86813 -109.214424) (xy 266.86764 -109.18444) (xy 168.800647 -109.18444)
			(xy 168.80029 -109.206296) (xy 168.792462 -109.265752) (xy 168.776941 -109.323677) (xy 168.753992 -109.379081)
			(xy 168.724008 -109.431015) (xy 168.687502 -109.478591) (xy 168.645097 -109.520996) (xy 168.597521 -109.557502)
			(xy 168.545587 -109.587486) (xy 168.490183 -109.610435) (xy 168.432258 -109.625956) (xy 168.372802 -109.633784)
			(xy 168.312834 -109.633784) (xy 168.253378 -109.625956) (xy 168.195453 -109.610435) (xy 168.140049 -109.587486)
			(xy 168.088115 -109.557502) (xy 168.040539 -109.520996) (xy 167.998134 -109.478591) (xy 167.961628 -109.431015)
			(xy 167.931644 -109.379081) (xy 167.908695 -109.323677) (xy 167.893174 -109.265752) (xy 167.885346 -109.206296)
			(xy 167.884856 -109.176312) (xy 151.68372 -109.176312) (xy 151.68372 -109.18444) (xy 151.68323 -109.214424)
			(xy 151.675402 -109.27388) (xy 151.659881 -109.331805) (xy 151.636932 -109.387209) (xy 151.606948 -109.439143)
			(xy 151.570442 -109.486719) (xy 151.528037 -109.529124) (xy 151.480461 -109.56563) (xy 151.428527 -109.595614)
			(xy 151.373123 -109.618563) (xy 151.315198 -109.634084) (xy 151.255742 -109.641912) (xy 151.195774 -109.641912)
			(xy 151.136318 -109.634084) (xy 151.078393 -109.618563) (xy 151.022989 -109.595614) (xy 150.971055 -109.56563)
			(xy 150.923479 -109.529124) (xy 150.881074 -109.486719) (xy 150.844568 -109.439143) (xy 150.814584 -109.387209)
			(xy 150.791635 -109.331805) (xy 150.776114 -109.27388) (xy 150.768286 -109.214424) (xy 150.767796 -109.18444)
			(xy 52.700295 -109.18444) (xy 52.699938 -109.20628) (xy 52.692115 -109.265702) (xy 52.676602 -109.323595)
			(xy 52.653666 -109.378968) (xy 52.623699 -109.430874) (xy 52.587212 -109.478424) (xy 52.544832 -109.520804)
			(xy 52.497282 -109.557291) (xy 52.445376 -109.587258) (xy 52.390003 -109.610194) (xy 52.33211 -109.625707)
			(xy 52.272688 -109.63353) (xy 52.212752 -109.63353) (xy 52.15333 -109.625707) (xy 52.095437 -109.610194)
			(xy 52.040064 -109.587258) (xy 51.988158 -109.557291) (xy 51.940608 -109.520804) (xy 51.898228 -109.478424)
			(xy 51.861741 -109.430874) (xy 51.831774 -109.378968) (xy 51.808838 -109.323595) (xy 51.793325 -109.265702)
			(xy 51.785502 -109.20628) (xy 51.785012 -109.176312) (xy 35.583368 -109.176312) (xy 35.583368 -109.18444)
			(xy 35.582878 -109.214408) (xy 35.575055 -109.27383) (xy 35.559542 -109.331723) (xy 35.536606 -109.387096)
			(xy 35.506639 -109.439002) (xy 35.470152 -109.486552) (xy 35.427772 -109.528932) (xy 35.380222 -109.565419)
			(xy 35.328316 -109.595386) (xy 35.272943 -109.618322) (xy 35.21505 -109.633835) (xy 35.155628 -109.641658)
			(xy 35.095692 -109.641658) (xy 35.03627 -109.633835) (xy 34.978377 -109.618322) (xy 34.923004 -109.595386)
			(xy 34.871098 -109.565419) (xy 34.823548 -109.528932) (xy 34.781168 -109.486552) (xy 34.744681 -109.439002)
			(xy 34.714714 -109.387096) (xy 34.691778 -109.331723) (xy 34.676265 -109.27383) (xy 34.668442 -109.214408)
			(xy 34.667952 -109.18444) (xy 4.30911 -109.18444) (xy 4.30911 -110.977934) (xy 37.31006 -110.977934)
			(xy 37.31006 -110.114334) (xy 37.31055 -110.084366) (xy 37.318373 -110.024944) (xy 37.333886 -109.967051)
			(xy 37.356822 -109.911678) (xy 37.386789 -109.859772) (xy 37.423276 -109.812222) (xy 37.465656 -109.769842)
			(xy 37.513206 -109.733355) (xy 37.565112 -109.703388) (xy 37.620485 -109.680452) (xy 37.678378 -109.664939)
			(xy 37.7378 -109.657116) (xy 37.797736 -109.657116) (xy 37.857158 -109.664939) (xy 37.915051 -109.680452)
			(xy 37.970424 -109.703388) (xy 38.02233 -109.733355) (xy 38.06988 -109.769842) (xy 38.11226 -109.812222)
			(xy 38.148747 -109.859772) (xy 38.178714 -109.911678) (xy 38.20165 -109.967051) (xy 38.217163 -110.024944)
			(xy 38.224986 -110.084366) (xy 38.225476 -110.114334) (xy 38.225476 -110.97641) (xy 53.639212 -110.97641)
			(xy 53.639212 -110.11281) (xy 53.639702 -110.082842) (xy 53.647525 -110.02342) (xy 53.663038 -109.965527)
			(xy 53.685974 -109.910154) (xy 53.715941 -109.858248) (xy 53.752428 -109.810698) (xy 53.794808 -109.768318)
			(xy 53.842358 -109.731831) (xy 53.894264 -109.701864) (xy 53.949637 -109.678928) (xy 54.00753 -109.663415)
			(xy 54.066952 -109.655592) (xy 54.126888 -109.655592) (xy 54.18631 -109.663415) (xy 54.244203 -109.678928)
			(xy 54.299576 -109.701864) (xy 54.351482 -109.731831) (xy 54.399032 -109.768318) (xy 54.441412 -109.810698)
			(xy 54.477899 -109.858248) (xy 54.507866 -109.910154) (xy 54.530802 -109.965527) (xy 54.546315 -110.02342)
			(xy 54.554138 -110.082842) (xy 54.554628 -110.11281) (xy 54.554628 -110.97641) (xy 54.554603 -110.977934)
			(xy 153.409904 -110.977934) (xy 153.409904 -110.114334) (xy 153.410394 -110.08435) (xy 153.418222 -110.024894)
			(xy 153.433743 -109.966969) (xy 153.456692 -109.911565) (xy 153.486676 -109.859631) (xy 153.523182 -109.812055)
			(xy 153.565587 -109.76965) (xy 153.613163 -109.733144) (xy 153.665097 -109.70316) (xy 153.720501 -109.680211)
			(xy 153.778426 -109.66469) (xy 153.837882 -109.656862) (xy 153.89785 -109.656862) (xy 153.957306 -109.66469)
			(xy 154.015231 -109.680211) (xy 154.070635 -109.70316) (xy 154.122569 -109.733144) (xy 154.170145 -109.76965)
			(xy 154.21255 -109.812055) (xy 154.249056 -109.859631) (xy 154.27904 -109.911565) (xy 154.301989 -109.966969)
			(xy 154.31751 -110.024894) (xy 154.325338 -110.08435) (xy 154.325828 -110.114334) (xy 154.325828 -110.97641)
			(xy 169.739056 -110.97641) (xy 169.739056 -110.11281) (xy 169.739546 -110.082826) (xy 169.747374 -110.02337)
			(xy 169.762895 -109.965445) (xy 169.785844 -109.910041) (xy 169.815828 -109.858107) (xy 169.852334 -109.810531)
			(xy 169.894739 -109.768126) (xy 169.942315 -109.73162) (xy 169.994249 -109.701636) (xy 170.049653 -109.678687)
			(xy 170.107578 -109.663166) (xy 170.167034 -109.655338) (xy 170.227002 -109.655338) (xy 170.286458 -109.663166)
			(xy 170.344383 -109.678687) (xy 170.399787 -109.701636) (xy 170.451721 -109.73162) (xy 170.499297 -109.768126)
			(xy 170.541702 -109.810531) (xy 170.578208 -109.858107) (xy 170.608192 -109.910041) (xy 170.631141 -109.965445)
			(xy 170.646662 -110.02337) (xy 170.65449 -110.082826) (xy 170.65498 -110.11281) (xy 170.65498 -110.97641)
			(xy 170.654955 -110.977934) (xy 269.509748 -110.977934) (xy 269.509748 -110.114334) (xy 269.510238 -110.08435)
			(xy 269.518066 -110.024894) (xy 269.533587 -109.966969) (xy 269.556536 -109.911565) (xy 269.58652 -109.859631)
			(xy 269.623026 -109.812055) (xy 269.665431 -109.76965) (xy 269.713007 -109.733144) (xy 269.764941 -109.70316)
			(xy 269.820345 -109.680211) (xy 269.87827 -109.66469) (xy 269.937726 -109.656862) (xy 269.997694 -109.656862)
			(xy 270.05715 -109.66469) (xy 270.115075 -109.680211) (xy 270.170479 -109.70316) (xy 270.222413 -109.733144)
			(xy 270.269989 -109.76965) (xy 270.312394 -109.812055) (xy 270.3489 -109.859631) (xy 270.378884 -109.911565)
			(xy 270.401833 -109.966969) (xy 270.417354 -110.024894) (xy 270.425182 -110.08435) (xy 270.425672 -110.114334)
			(xy 270.425672 -110.97641) (xy 285.8389 -110.97641) (xy 285.8389 -110.11281) (xy 285.83939 -110.082826)
			(xy 285.847218 -110.02337) (xy 285.862739 -109.965445) (xy 285.885688 -109.910041) (xy 285.915672 -109.858107)
			(xy 285.952178 -109.810531) (xy 285.994583 -109.768126) (xy 286.042159 -109.73162) (xy 286.094093 -109.701636)
			(xy 286.149497 -109.678687) (xy 286.207422 -109.663166) (xy 286.266878 -109.655338) (xy 286.326846 -109.655338)
			(xy 286.386302 -109.663166) (xy 286.444227 -109.678687) (xy 286.499631 -109.701636) (xy 286.551565 -109.73162)
			(xy 286.599141 -109.768126) (xy 286.641546 -109.810531) (xy 286.678052 -109.858107) (xy 286.708036 -109.910041)
			(xy 286.730985 -109.965445) (xy 286.746506 -110.02337) (xy 286.754334 -110.082826) (xy 286.754824 -110.11281)
			(xy 286.754824 -110.97641) (xy 286.754799 -110.977934) (xy 385.6101 -110.977934) (xy 385.6101 -110.114334)
			(xy 385.61059 -110.084366) (xy 385.618413 -110.024944) (xy 385.633926 -109.967051) (xy 385.656862 -109.911678)
			(xy 385.686829 -109.859772) (xy 385.723316 -109.812222) (xy 385.765696 -109.769842) (xy 385.813246 -109.733355)
			(xy 385.865152 -109.703388) (xy 385.920525 -109.680452) (xy 385.978418 -109.664939) (xy 386.03784 -109.657116)
			(xy 386.097776 -109.657116) (xy 386.157198 -109.664939) (xy 386.215091 -109.680452) (xy 386.270464 -109.703388)
			(xy 386.32237 -109.733355) (xy 386.36992 -109.769842) (xy 386.4123 -109.812222) (xy 386.448787 -109.859772)
			(xy 386.478754 -109.911678) (xy 386.50169 -109.967051) (xy 386.517203 -110.024944) (xy 386.525026 -110.084366)
			(xy 386.525516 -110.114334) (xy 386.525516 -110.97641) (xy 401.939252 -110.97641) (xy 401.939252 -110.11281)
			(xy 401.939742 -110.082842) (xy 401.947565 -110.02342) (xy 401.963078 -109.965527) (xy 401.986014 -109.910154)
			(xy 402.015981 -109.858248) (xy 402.052468 -109.810698) (xy 402.094848 -109.768318) (xy 402.142398 -109.731831)
			(xy 402.194304 -109.701864) (xy 402.249677 -109.678928) (xy 402.30757 -109.663415) (xy 402.366992 -109.655592)
			(xy 402.426928 -109.655592) (xy 402.48635 -109.663415) (xy 402.544243 -109.678928) (xy 402.599616 -109.701864)
			(xy 402.651522 -109.731831) (xy 402.699072 -109.768318) (xy 402.741452 -109.810698) (xy 402.777939 -109.858248)
			(xy 402.807906 -109.910154) (xy 402.830842 -109.965527) (xy 402.846355 -110.02342) (xy 402.854178 -110.082842)
			(xy 402.854668 -110.11281) (xy 402.854668 -110.97641) (xy 402.854178 -111.006378) (xy 402.846355 -111.0658)
			(xy 402.830842 -111.123693) (xy 402.807906 -111.179066) (xy 402.777939 -111.230972) (xy 402.741452 -111.278522)
			(xy 402.699072 -111.320902) (xy 402.651522 -111.357389) (xy 402.599616 -111.387356) (xy 402.544243 -111.410292)
			(xy 402.48635 -111.425805) (xy 402.426928 -111.433628) (xy 402.366992 -111.433628) (xy 402.30757 -111.425805)
			(xy 402.249677 -111.410292) (xy 402.194304 -111.387356) (xy 402.142398 -111.357389) (xy 402.094848 -111.320902)
			(xy 402.052468 -111.278522) (xy 402.015981 -111.230972) (xy 401.986014 -111.179066) (xy 401.963078 -111.123693)
			(xy 401.947565 -111.0658) (xy 401.939742 -111.006378) (xy 401.939252 -110.97641) (xy 386.525516 -110.97641)
			(xy 386.525516 -110.977934) (xy 386.525026 -111.007902) (xy 386.517203 -111.067324) (xy 386.50169 -111.125217)
			(xy 386.478754 -111.18059) (xy 386.448787 -111.232496) (xy 386.4123 -111.280046) (xy 386.36992 -111.322426)
			(xy 386.32237 -111.358913) (xy 386.270464 -111.38888) (xy 386.215091 -111.411816) (xy 386.157198 -111.427329)
			(xy 386.097776 -111.435152) (xy 386.03784 -111.435152) (xy 385.978418 -111.427329) (xy 385.920525 -111.411816)
			(xy 385.865152 -111.38888) (xy 385.813246 -111.358913) (xy 385.765696 -111.322426) (xy 385.723316 -111.280046)
			(xy 385.686829 -111.232496) (xy 385.656862 -111.18059) (xy 385.633926 -111.125217) (xy 385.618413 -111.067324)
			(xy 385.61059 -111.007902) (xy 385.6101 -110.977934) (xy 286.754799 -110.977934) (xy 286.754334 -111.006394)
			(xy 286.746506 -111.06585) (xy 286.730985 -111.123775) (xy 286.708036 -111.179179) (xy 286.678052 -111.231113)
			(xy 286.641546 -111.278689) (xy 286.599141 -111.321094) (xy 286.551565 -111.3576) (xy 286.499631 -111.387584)
			(xy 286.444227 -111.410533) (xy 286.386302 -111.426054) (xy 286.326846 -111.433882) (xy 286.266878 -111.433882)
			(xy 286.207422 -111.426054) (xy 286.149497 -111.410533) (xy 286.094093 -111.387584) (xy 286.042159 -111.3576)
			(xy 285.994583 -111.321094) (xy 285.952178 -111.278689) (xy 285.915672 -111.231113) (xy 285.885688 -111.179179)
			(xy 285.862739 -111.123775) (xy 285.847218 -111.06585) (xy 285.83939 -111.006394) (xy 285.8389 -110.97641)
			(xy 270.425672 -110.97641) (xy 270.425672 -110.977934) (xy 270.425182 -111.007918) (xy 270.417354 -111.067374)
			(xy 270.401833 -111.125299) (xy 270.378884 -111.180703) (xy 270.3489 -111.232637) (xy 270.312394 -111.280213)
			(xy 270.269989 -111.322618) (xy 270.222413 -111.359124) (xy 270.170479 -111.389108) (xy 270.115075 -111.412057)
			(xy 270.05715 -111.427578) (xy 269.997694 -111.435406) (xy 269.937726 -111.435406) (xy 269.87827 -111.427578)
			(xy 269.820345 -111.412057) (xy 269.764941 -111.389108) (xy 269.713007 -111.359124) (xy 269.665431 -111.322618)
			(xy 269.623026 -111.280213) (xy 269.58652 -111.232637) (xy 269.556536 -111.180703) (xy 269.533587 -111.125299)
			(xy 269.518066 -111.067374) (xy 269.510238 -111.007918) (xy 269.509748 -110.977934) (xy 170.654955 -110.977934)
			(xy 170.65449 -111.006394) (xy 170.646662 -111.06585) (xy 170.631141 -111.123775) (xy 170.608192 -111.179179)
			(xy 170.578208 -111.231113) (xy 170.541702 -111.278689) (xy 170.499297 -111.321094) (xy 170.451721 -111.3576)
			(xy 170.399787 -111.387584) (xy 170.344383 -111.410533) (xy 170.286458 -111.426054) (xy 170.227002 -111.433882)
			(xy 170.167034 -111.433882) (xy 170.107578 -111.426054) (xy 170.049653 -111.410533) (xy 169.994249 -111.387584)
			(xy 169.942315 -111.3576) (xy 169.894739 -111.321094) (xy 169.852334 -111.278689) (xy 169.815828 -111.231113)
			(xy 169.785844 -111.179179) (xy 169.762895 -111.123775) (xy 169.747374 -111.06585) (xy 169.739546 -111.006394)
			(xy 169.739056 -110.97641) (xy 154.325828 -110.97641) (xy 154.325828 -110.977934) (xy 154.325338 -111.007918)
			(xy 154.31751 -111.067374) (xy 154.301989 -111.125299) (xy 154.27904 -111.180703) (xy 154.249056 -111.232637)
			(xy 154.21255 -111.280213) (xy 154.170145 -111.322618) (xy 154.122569 -111.359124) (xy 154.070635 -111.389108)
			(xy 154.015231 -111.412057) (xy 153.957306 -111.427578) (xy 153.89785 -111.435406) (xy 153.837882 -111.435406)
			(xy 153.778426 -111.427578) (xy 153.720501 -111.412057) (xy 153.665097 -111.389108) (xy 153.613163 -111.359124)
			(xy 153.565587 -111.322618) (xy 153.523182 -111.280213) (xy 153.486676 -111.232637) (xy 153.456692 -111.180703)
			(xy 153.433743 -111.125299) (xy 153.418222 -111.067374) (xy 153.410394 -111.007918) (xy 153.409904 -110.977934)
			(xy 54.554603 -110.977934) (xy 54.554138 -111.006378) (xy 54.546315 -111.0658) (xy 54.530802 -111.123693)
			(xy 54.507866 -111.179066) (xy 54.477899 -111.230972) (xy 54.441412 -111.278522) (xy 54.399032 -111.320902)
			(xy 54.351482 -111.357389) (xy 54.299576 -111.387356) (xy 54.244203 -111.410292) (xy 54.18631 -111.425805)
			(xy 54.126888 -111.433628) (xy 54.066952 -111.433628) (xy 54.00753 -111.425805) (xy 53.949637 -111.410292)
			(xy 53.894264 -111.387356) (xy 53.842358 -111.357389) (xy 53.794808 -111.320902) (xy 53.752428 -111.278522)
			(xy 53.715941 -111.230972) (xy 53.685974 -111.179066) (xy 53.663038 -111.123693) (xy 53.647525 -111.0658)
			(xy 53.639702 -111.006378) (xy 53.639212 -110.97641) (xy 38.225476 -110.97641) (xy 38.225476 -110.977934)
			(xy 38.224986 -111.007902) (xy 38.217163 -111.067324) (xy 38.20165 -111.125217) (xy 38.178714 -111.18059)
			(xy 38.148747 -111.232496) (xy 38.11226 -111.280046) (xy 38.06988 -111.322426) (xy 38.02233 -111.358913)
			(xy 37.970424 -111.38888) (xy 37.915051 -111.411816) (xy 37.857158 -111.427329) (xy 37.797736 -111.435152)
			(xy 37.7378 -111.435152) (xy 37.678378 -111.427329) (xy 37.620485 -111.411816) (xy 37.565112 -111.38888)
			(xy 37.513206 -111.358913) (xy 37.465656 -111.322426) (xy 37.423276 -111.280046) (xy 37.386789 -111.232496)
			(xy 37.356822 -111.18059) (xy 37.333886 -111.125217) (xy 37.318373 -111.067324) (xy 37.31055 -111.007902)
			(xy 37.31006 -110.977934) (xy 4.30911 -110.977934) (xy 4.30911 -112.784382) (xy 34.667952 -112.784382)
			(xy 34.667952 -111.920782) (xy 34.668442 -111.890814) (xy 34.676265 -111.831392) (xy 34.691778 -111.773499)
			(xy 34.714714 -111.718126) (xy 34.744681 -111.66622) (xy 34.781168 -111.61867) (xy 34.823548 -111.57629)
			(xy 34.871098 -111.539803) (xy 34.923004 -111.509836) (xy 34.978377 -111.4869) (xy 35.03627 -111.471387)
			(xy 35.095692 -111.463564) (xy 35.155628 -111.463564) (xy 35.21505 -111.471387) (xy 35.272943 -111.4869)
			(xy 35.328316 -111.509836) (xy 35.380222 -111.539803) (xy 35.427772 -111.57629) (xy 35.470152 -111.61867)
			(xy 35.506639 -111.66622) (xy 35.536606 -111.718126) (xy 35.559542 -111.773499) (xy 35.575055 -111.831392)
			(xy 35.582878 -111.890814) (xy 35.583368 -111.920782) (xy 35.583368 -112.776508) (xy 51.785012 -112.776508)
			(xy 51.785012 -111.912908) (xy 51.785502 -111.88294) (xy 51.793325 -111.823518) (xy 51.808838 -111.765625)
			(xy 51.831774 -111.710252) (xy 51.861741 -111.658346) (xy 51.898228 -111.610796) (xy 51.940608 -111.568416)
			(xy 51.988158 -111.531929) (xy 52.040064 -111.501962) (xy 52.095437 -111.479026) (xy 52.15333 -111.463513)
			(xy 52.212752 -111.45569) (xy 52.272688 -111.45569) (xy 52.33211 -111.463513) (xy 52.390003 -111.479026)
			(xy 52.445376 -111.501962) (xy 52.497282 -111.531929) (xy 52.544832 -111.568416) (xy 52.587212 -111.610796)
			(xy 52.623699 -111.658346) (xy 52.653666 -111.710252) (xy 52.676602 -111.765625) (xy 52.692115 -111.823518)
			(xy 52.699938 -111.88294) (xy 52.700428 -111.912908) (xy 52.700428 -112.776508) (xy 52.700299 -112.784382)
			(xy 150.767796 -112.784382) (xy 150.767796 -111.920782) (xy 150.768286 -111.890798) (xy 150.776114 -111.831342)
			(xy 150.791635 -111.773417) (xy 150.814584 -111.718013) (xy 150.844568 -111.666079) (xy 150.881074 -111.618503)
			(xy 150.923479 -111.576098) (xy 150.971055 -111.539592) (xy 151.022989 -111.509608) (xy 151.078393 -111.486659)
			(xy 151.136318 -111.471138) (xy 151.195774 -111.46331) (xy 151.255742 -111.46331) (xy 151.315198 -111.471138)
			(xy 151.373123 -111.486659) (xy 151.428527 -111.509608) (xy 151.480461 -111.539592) (xy 151.528037 -111.576098)
			(xy 151.570442 -111.618503) (xy 151.606948 -111.666079) (xy 151.636932 -111.718013) (xy 151.659881 -111.773417)
			(xy 151.675402 -111.831342) (xy 151.68323 -111.890798) (xy 151.68372 -111.920782) (xy 151.68372 -112.776508)
			(xy 167.884856 -112.776508) (xy 167.884856 -111.912908) (xy 167.885346 -111.882924) (xy 167.893174 -111.823468)
			(xy 167.908695 -111.765543) (xy 167.931644 -111.710139) (xy 167.961628 -111.658205) (xy 167.998134 -111.610629)
			(xy 168.040539 -111.568224) (xy 168.088115 -111.531718) (xy 168.140049 -111.501734) (xy 168.195453 -111.478785)
			(xy 168.253378 -111.463264) (xy 168.312834 -111.455436) (xy 168.372802 -111.455436) (xy 168.432258 -111.463264)
			(xy 168.490183 -111.478785) (xy 168.545587 -111.501734) (xy 168.597521 -111.531718) (xy 168.645097 -111.568224)
			(xy 168.687502 -111.610629) (xy 168.724008 -111.658205) (xy 168.753992 -111.710139) (xy 168.776941 -111.765543)
			(xy 168.792462 -111.823468) (xy 168.80029 -111.882924) (xy 168.80078 -111.912908) (xy 168.80078 -112.776508)
			(xy 168.800651 -112.784382) (xy 266.86764 -112.784382) (xy 266.86764 -111.920782) (xy 266.86813 -111.890798)
			(xy 266.875958 -111.831342) (xy 266.891479 -111.773417) (xy 266.914428 -111.718013) (xy 266.944412 -111.666079)
			(xy 266.980918 -111.618503) (xy 267.023323 -111.576098) (xy 267.070899 -111.539592) (xy 267.122833 -111.509608)
			(xy 267.178237 -111.486659) (xy 267.236162 -111.471138) (xy 267.295618 -111.46331) (xy 267.355586 -111.46331)
			(xy 267.415042 -111.471138) (xy 267.472967 -111.486659) (xy 267.528371 -111.509608) (xy 267.580305 -111.539592)
			(xy 267.627881 -111.576098) (xy 267.670286 -111.618503) (xy 267.706792 -111.666079) (xy 267.736776 -111.718013)
			(xy 267.759725 -111.773417) (xy 267.775246 -111.831342) (xy 267.783074 -111.890798) (xy 267.783564 -111.920782)
			(xy 267.783564 -112.776508) (xy 283.9847 -112.776508) (xy 283.9847 -111.912908) (xy 283.98519 -111.882924)
			(xy 283.993018 -111.823468) (xy 284.008539 -111.765543) (xy 284.031488 -111.710139) (xy 284.061472 -111.658205)
			(xy 284.097978 -111.610629) (xy 284.140383 -111.568224) (xy 284.187959 -111.531718) (xy 284.239893 -111.501734)
			(xy 284.295297 -111.478785) (xy 284.353222 -111.463264) (xy 284.412678 -111.455436) (xy 284.472646 -111.455436)
			(xy 284.532102 -111.463264) (xy 284.590027 -111.478785) (xy 284.645431 -111.501734) (xy 284.697365 -111.531718)
			(xy 284.744941 -111.568224) (xy 284.787346 -111.610629) (xy 284.823852 -111.658205) (xy 284.853836 -111.710139)
			(xy 284.876785 -111.765543) (xy 284.892306 -111.823468) (xy 284.900134 -111.882924) (xy 284.900624 -111.912908)
			(xy 284.900624 -112.776508) (xy 284.900495 -112.784382) (xy 382.967992 -112.784382) (xy 382.967992 -111.920782)
			(xy 382.968482 -111.890814) (xy 382.976305 -111.831392) (xy 382.991818 -111.773499) (xy 383.014754 -111.718126)
			(xy 383.044721 -111.66622) (xy 383.081208 -111.61867) (xy 383.123588 -111.57629) (xy 383.171138 -111.539803)
			(xy 383.223044 -111.509836) (xy 383.278417 -111.4869) (xy 383.33631 -111.471387) (xy 383.395732 -111.463564)
			(xy 383.455668 -111.463564) (xy 383.51509 -111.471387) (xy 383.572983 -111.4869) (xy 383.628356 -111.509836)
			(xy 383.680262 -111.539803) (xy 383.727812 -111.57629) (xy 383.770192 -111.61867) (xy 383.806679 -111.66622)
			(xy 383.836646 -111.718126) (xy 383.859582 -111.773499) (xy 383.875095 -111.831392) (xy 383.882918 -111.890814)
			(xy 383.883408 -111.920782) (xy 383.883408 -112.776508) (xy 400.085052 -112.776508) (xy 400.085052 -111.912908)
			(xy 400.085542 -111.88294) (xy 400.093365 -111.823518) (xy 400.108878 -111.765625) (xy 400.131814 -111.710252)
			(xy 400.161781 -111.658346) (xy 400.198268 -111.610796) (xy 400.240648 -111.568416) (xy 400.288198 -111.531929)
			(xy 400.340104 -111.501962) (xy 400.395477 -111.479026) (xy 400.45337 -111.463513) (xy 400.512792 -111.45569)
			(xy 400.572728 -111.45569) (xy 400.63215 -111.463513) (xy 400.690043 -111.479026) (xy 400.745416 -111.501962)
			(xy 400.797322 -111.531929) (xy 400.844872 -111.568416) (xy 400.887252 -111.610796) (xy 400.923739 -111.658346)
			(xy 400.953706 -111.710252) (xy 400.976642 -111.765625) (xy 400.992155 -111.823518) (xy 400.999978 -111.88294)
			(xy 401.000468 -111.912908) (xy 401.000468 -112.776508) (xy 400.999978 -112.806476) (xy 400.992155 -112.865898)
			(xy 400.976642 -112.923791) (xy 400.953706 -112.979164) (xy 400.923739 -113.03107) (xy 400.887252 -113.07862)
			(xy 400.844872 -113.121) (xy 400.797322 -113.157487) (xy 400.745416 -113.187454) (xy 400.690043 -113.21039)
			(xy 400.63215 -113.225903) (xy 400.572728 -113.233726) (xy 400.512792 -113.233726) (xy 400.45337 -113.225903)
			(xy 400.395477 -113.21039) (xy 400.340104 -113.187454) (xy 400.288198 -113.157487) (xy 400.240648 -113.121)
			(xy 400.198268 -113.07862) (xy 400.161781 -113.03107) (xy 400.131814 -112.979164) (xy 400.108878 -112.923791)
			(xy 400.093365 -112.865898) (xy 400.085542 -112.806476) (xy 400.085052 -112.776508) (xy 383.883408 -112.776508)
			(xy 383.883408 -112.784382) (xy 383.882918 -112.81435) (xy 383.875095 -112.873772) (xy 383.859582 -112.931665)
			(xy 383.836646 -112.987038) (xy 383.806679 -113.038944) (xy 383.770192 -113.086494) (xy 383.727812 -113.128874)
			(xy 383.680262 -113.165361) (xy 383.628356 -113.195328) (xy 383.572983 -113.218264) (xy 383.51509 -113.233777)
			(xy 383.455668 -113.2416) (xy 383.395732 -113.2416) (xy 383.33631 -113.233777) (xy 383.278417 -113.218264)
			(xy 383.223044 -113.195328) (xy 383.171138 -113.165361) (xy 383.123588 -113.128874) (xy 383.081208 -113.086494)
			(xy 383.044721 -113.038944) (xy 383.014754 -112.987038) (xy 382.991818 -112.931665) (xy 382.976305 -112.873772)
			(xy 382.968482 -112.81435) (xy 382.967992 -112.784382) (xy 284.900495 -112.784382) (xy 284.900134 -112.806492)
			(xy 284.892306 -112.865948) (xy 284.876785 -112.923873) (xy 284.853836 -112.979277) (xy 284.823852 -113.031211)
			(xy 284.787346 -113.078787) (xy 284.744941 -113.121192) (xy 284.697365 -113.157698) (xy 284.645431 -113.187682)
			(xy 284.590027 -113.210631) (xy 284.532102 -113.226152) (xy 284.472646 -113.23398) (xy 284.412678 -113.23398)
			(xy 284.353222 -113.226152) (xy 284.295297 -113.210631) (xy 284.239893 -113.187682) (xy 284.187959 -113.157698)
			(xy 284.140383 -113.121192) (xy 284.097978 -113.078787) (xy 284.061472 -113.031211) (xy 284.031488 -112.979277)
			(xy 284.008539 -112.923873) (xy 283.993018 -112.865948) (xy 283.98519 -112.806492) (xy 283.9847 -112.776508)
			(xy 267.783564 -112.776508) (xy 267.783564 -112.784382) (xy 267.783074 -112.814366) (xy 267.775246 -112.873822)
			(xy 267.759725 -112.931747) (xy 267.736776 -112.987151) (xy 267.706792 -113.039085) (xy 267.670286 -113.086661)
			(xy 267.627881 -113.129066) (xy 267.580305 -113.165572) (xy 267.528371 -113.195556) (xy 267.472967 -113.218505)
			(xy 267.415042 -113.234026) (xy 267.355586 -113.241854) (xy 267.295618 -113.241854) (xy 267.236162 -113.234026)
			(xy 267.178237 -113.218505) (xy 267.122833 -113.195556) (xy 267.070899 -113.165572) (xy 267.023323 -113.129066)
			(xy 266.980918 -113.086661) (xy 266.944412 -113.039085) (xy 266.914428 -112.987151) (xy 266.891479 -112.931747)
			(xy 266.875958 -112.873822) (xy 266.86813 -112.814366) (xy 266.86764 -112.784382) (xy 168.800651 -112.784382)
			(xy 168.80029 -112.806492) (xy 168.792462 -112.865948) (xy 168.776941 -112.923873) (xy 168.753992 -112.979277)
			(xy 168.724008 -113.031211) (xy 168.687502 -113.078787) (xy 168.645097 -113.121192) (xy 168.597521 -113.157698)
			(xy 168.545587 -113.187682) (xy 168.490183 -113.210631) (xy 168.432258 -113.226152) (xy 168.372802 -113.23398)
			(xy 168.312834 -113.23398) (xy 168.253378 -113.226152) (xy 168.195453 -113.210631) (xy 168.140049 -113.187682)
			(xy 168.088115 -113.157698) (xy 168.040539 -113.121192) (xy 167.998134 -113.078787) (xy 167.961628 -113.031211)
			(xy 167.931644 -112.979277) (xy 167.908695 -112.923873) (xy 167.893174 -112.865948) (xy 167.885346 -112.806492)
			(xy 167.884856 -112.776508) (xy 151.68372 -112.776508) (xy 151.68372 -112.784382) (xy 151.68323 -112.814366)
			(xy 151.675402 -112.873822) (xy 151.659881 -112.931747) (xy 151.636932 -112.987151) (xy 151.606948 -113.039085)
			(xy 151.570442 -113.086661) (xy 151.528037 -113.129066) (xy 151.480461 -113.165572) (xy 151.428527 -113.195556)
			(xy 151.373123 -113.218505) (xy 151.315198 -113.234026) (xy 151.255742 -113.241854) (xy 151.195774 -113.241854)
			(xy 151.136318 -113.234026) (xy 151.078393 -113.218505) (xy 151.022989 -113.195556) (xy 150.971055 -113.165572)
			(xy 150.923479 -113.129066) (xy 150.881074 -113.086661) (xy 150.844568 -113.039085) (xy 150.814584 -112.987151)
			(xy 150.791635 -112.931747) (xy 150.776114 -112.873822) (xy 150.768286 -112.814366) (xy 150.767796 -112.784382)
			(xy 52.700299 -112.784382) (xy 52.699938 -112.806476) (xy 52.692115 -112.865898) (xy 52.676602 -112.923791)
			(xy 52.653666 -112.979164) (xy 52.623699 -113.03107) (xy 52.587212 -113.07862) (xy 52.544832 -113.121)
			(xy 52.497282 -113.157487) (xy 52.445376 -113.187454) (xy 52.390003 -113.21039) (xy 52.33211 -113.225903)
			(xy 52.272688 -113.233726) (xy 52.212752 -113.233726) (xy 52.15333 -113.225903) (xy 52.095437 -113.21039)
			(xy 52.040064 -113.187454) (xy 51.988158 -113.157487) (xy 51.940608 -113.121) (xy 51.898228 -113.07862)
			(xy 51.861741 -113.03107) (xy 51.831774 -112.979164) (xy 51.808838 -112.923791) (xy 51.793325 -112.865898)
			(xy 51.785502 -112.806476) (xy 51.785012 -112.776508) (xy 35.583368 -112.776508) (xy 35.583368 -112.784382)
			(xy 35.582878 -112.81435) (xy 35.575055 -112.873772) (xy 35.559542 -112.931665) (xy 35.536606 -112.987038)
			(xy 35.506639 -113.038944) (xy 35.470152 -113.086494) (xy 35.427772 -113.128874) (xy 35.380222 -113.165361)
			(xy 35.328316 -113.195328) (xy 35.272943 -113.218264) (xy 35.21505 -113.233777) (xy 35.155628 -113.2416)
			(xy 35.095692 -113.2416) (xy 35.03627 -113.233777) (xy 34.978377 -113.218264) (xy 34.923004 -113.195328)
			(xy 34.871098 -113.165361) (xy 34.823548 -113.128874) (xy 34.781168 -113.086494) (xy 34.744681 -113.038944)
			(xy 34.714714 -112.987038) (xy 34.691778 -112.931665) (xy 34.676265 -112.873772) (xy 34.668442 -112.81435)
			(xy 34.667952 -112.784382) (xy 4.30911 -112.784382) (xy 4.30911 -117.758718) (xy 74.474832 -117.758718)
			(xy 74.474832 -116.895118) (xy 74.475322 -116.865134) (xy 74.48315 -116.805678) (xy 74.498671 -116.747753)
			(xy 74.52162 -116.692349) (xy 74.551604 -116.640415) (xy 74.58811 -116.592839) (xy 74.630515 -116.550434)
			(xy 74.678091 -116.513928) (xy 74.730025 -116.483944) (xy 74.785429 -116.460995) (xy 74.843354 -116.445474)
			(xy 74.90281 -116.437646) (xy 74.962778 -116.437646) (xy 75.022234 -116.445474) (xy 75.080159 -116.460995)
			(xy 75.135563 -116.483944) (xy 75.187497 -116.513928) (xy 75.235073 -116.550434) (xy 75.277478 -116.592839)
			(xy 75.313984 -116.640415) (xy 75.343968 -116.692349) (xy 75.366917 -116.747753) (xy 75.382438 -116.805678)
			(xy 75.390266 -116.865134) (xy 75.390756 -116.895118) (xy 75.390756 -117.758718) (xy 190.574676 -117.758718)
			(xy 190.574676 -116.895118) (xy 190.575166 -116.865134) (xy 190.582994 -116.805678) (xy 190.598515 -116.747753)
			(xy 190.621464 -116.692349) (xy 190.651448 -116.640415) (xy 190.687954 -116.592839) (xy 190.730359 -116.550434)
			(xy 190.777935 -116.513928) (xy 190.829869 -116.483944) (xy 190.885273 -116.460995) (xy 190.943198 -116.445474)
			(xy 191.002654 -116.437646) (xy 191.062622 -116.437646) (xy 191.122078 -116.445474) (xy 191.180003 -116.460995)
			(xy 191.235407 -116.483944) (xy 191.287341 -116.513928) (xy 191.334917 -116.550434) (xy 191.377322 -116.592839)
			(xy 191.413828 -116.640415) (xy 191.443812 -116.692349) (xy 191.466761 -116.747753) (xy 191.482282 -116.805678)
			(xy 191.49011 -116.865134) (xy 191.4906 -116.895118) (xy 191.4906 -117.758718) (xy 306.675028 -117.758718)
			(xy 306.675028 -116.895118) (xy 306.675518 -116.86515) (xy 306.683341 -116.805728) (xy 306.698854 -116.747835)
			(xy 306.72179 -116.692462) (xy 306.751757 -116.640556) (xy 306.788244 -116.593006) (xy 306.830624 -116.550626)
			(xy 306.878174 -116.514139) (xy 306.93008 -116.484172) (xy 306.985453 -116.461236) (xy 307.043346 -116.445723)
			(xy 307.102768 -116.4379) (xy 307.162704 -116.4379) (xy 307.222126 -116.445723) (xy 307.280019 -116.461236)
			(xy 307.335392 -116.484172) (xy 307.387298 -116.514139) (xy 307.434848 -116.550626) (xy 307.477228 -116.593006)
			(xy 307.513715 -116.640556) (xy 307.543682 -116.692462) (xy 307.566618 -116.747835) (xy 307.582131 -116.805728)
			(xy 307.589954 -116.86515) (xy 307.590444 -116.895118) (xy 307.590444 -117.758718) (xy 307.590436 -117.759226)
			(xy 422.774872 -117.759226) (xy 422.774872 -116.895626) (xy 422.775362 -116.865642) (xy 422.78319 -116.806186)
			(xy 422.798711 -116.748261) (xy 422.82166 -116.692857) (xy 422.851644 -116.640923) (xy 422.88815 -116.593347)
			(xy 422.930555 -116.550942) (xy 422.978131 -116.514436) (xy 423.030065 -116.484452) (xy 423.085469 -116.461503)
			(xy 423.143394 -116.445982) (xy 423.20285 -116.438154) (xy 423.262818 -116.438154) (xy 423.322274 -116.445982)
			(xy 423.380199 -116.461503) (xy 423.435603 -116.484452) (xy 423.487537 -116.514436) (xy 423.535113 -116.550942)
			(xy 423.577518 -116.593347) (xy 423.614024 -116.640923) (xy 423.644008 -116.692857) (xy 423.666957 -116.748261)
			(xy 423.682478 -116.806186) (xy 423.690306 -116.865642) (xy 423.690796 -116.895626) (xy 423.690796 -117.759226)
			(xy 423.690306 -117.78921) (xy 423.682478 -117.848666) (xy 423.666957 -117.906591) (xy 423.644008 -117.961995)
			(xy 423.614024 -118.013929) (xy 423.577518 -118.061505) (xy 423.535113 -118.10391) (xy 423.487537 -118.140416)
			(xy 423.435603 -118.1704) (xy 423.380199 -118.193349) (xy 423.322274 -118.20887) (xy 423.262818 -118.216698)
			(xy 423.20285 -118.216698) (xy 423.143394 -118.20887) (xy 423.085469 -118.193349) (xy 423.030065 -118.1704)
			(xy 422.978131 -118.140416) (xy 422.930555 -118.10391) (xy 422.88815 -118.061505) (xy 422.851644 -118.013929)
			(xy 422.82166 -117.961995) (xy 422.798711 -117.906591) (xy 422.78319 -117.848666) (xy 422.775362 -117.78921)
			(xy 422.774872 -117.759226) (xy 307.590436 -117.759226) (xy 307.589954 -117.788686) (xy 307.582131 -117.848108)
			(xy 307.566618 -117.906001) (xy 307.543682 -117.961374) (xy 307.513715 -118.01328) (xy 307.477228 -118.06083)
			(xy 307.434848 -118.10321) (xy 307.387298 -118.139697) (xy 307.335392 -118.169664) (xy 307.280019 -118.1926)
			(xy 307.222126 -118.208113) (xy 307.162704 -118.215936) (xy 307.102768 -118.215936) (xy 307.043346 -118.208113)
			(xy 306.985453 -118.1926) (xy 306.93008 -118.169664) (xy 306.878174 -118.139697) (xy 306.830624 -118.10321)
			(xy 306.788244 -118.06083) (xy 306.751757 -118.01328) (xy 306.72179 -117.961374) (xy 306.698854 -117.906001)
			(xy 306.683341 -117.848108) (xy 306.675518 -117.788686) (xy 306.675028 -117.758718) (xy 191.4906 -117.758718)
			(xy 191.49011 -117.788702) (xy 191.482282 -117.848158) (xy 191.466761 -117.906083) (xy 191.443812 -117.961487)
			(xy 191.413828 -118.013421) (xy 191.377322 -118.060997) (xy 191.334917 -118.103402) (xy 191.287341 -118.139908)
			(xy 191.235407 -118.169892) (xy 191.180003 -118.192841) (xy 191.122078 -118.208362) (xy 191.062622 -118.21619)
			(xy 191.002654 -118.21619) (xy 190.943198 -118.208362) (xy 190.885273 -118.192841) (xy 190.829869 -118.169892)
			(xy 190.777935 -118.139908) (xy 190.730359 -118.103402) (xy 190.687954 -118.060997) (xy 190.651448 -118.013421)
			(xy 190.621464 -117.961487) (xy 190.598515 -117.906083) (xy 190.582994 -117.848158) (xy 190.575166 -117.788702)
			(xy 190.574676 -117.758718) (xy 75.390756 -117.758718) (xy 75.390266 -117.788702) (xy 75.382438 -117.848158)
			(xy 75.366917 -117.906083) (xy 75.343968 -117.961487) (xy 75.313984 -118.013421) (xy 75.277478 -118.060997)
			(xy 75.235073 -118.103402) (xy 75.187497 -118.139908) (xy 75.135563 -118.169892) (xy 75.080159 -118.192841)
			(xy 75.022234 -118.208362) (xy 74.962778 -118.21619) (xy 74.90281 -118.21619) (xy 74.843354 -118.208362)
			(xy 74.785429 -118.192841) (xy 74.730025 -118.169892) (xy 74.678091 -118.139908) (xy 74.630515 -118.103402)
			(xy 74.58811 -118.060997) (xy 74.551604 -118.013421) (xy 74.52162 -117.961487) (xy 74.498671 -117.906083)
			(xy 74.48315 -117.848158) (xy 74.475322 -117.788702) (xy 74.474832 -117.758718) (xy 4.30911 -117.758718)
			(xy 4.30911 -120.087898) (xy 34.667952 -120.087898) (xy 34.667952 -119.224298) (xy 34.668442 -119.19433)
			(xy 34.676265 -119.134908) (xy 34.691778 -119.077015) (xy 34.714714 -119.021642) (xy 34.744681 -118.969736)
			(xy 34.781168 -118.922186) (xy 34.823548 -118.879806) (xy 34.871098 -118.843319) (xy 34.923004 -118.813352)
			(xy 34.978377 -118.790416) (xy 35.03627 -118.774903) (xy 35.095692 -118.76708) (xy 35.155628 -118.76708)
			(xy 35.21505 -118.774903) (xy 35.272943 -118.790416) (xy 35.328316 -118.813352) (xy 35.380222 -118.843319)
			(xy 35.427772 -118.879806) (xy 35.470152 -118.922186) (xy 35.506639 -118.969736) (xy 35.536606 -119.021642)
			(xy 35.559542 -119.077015) (xy 35.575055 -119.134908) (xy 35.582878 -119.19433) (xy 35.583368 -119.224298)
			(xy 35.583368 -120.086374) (xy 53.639212 -120.086374) (xy 53.639212 -119.222774) (xy 53.639702 -119.192806)
			(xy 53.647525 -119.133384) (xy 53.663038 -119.075491) (xy 53.685974 -119.020118) (xy 53.715941 -118.968212)
			(xy 53.752428 -118.920662) (xy 53.794808 -118.878282) (xy 53.842358 -118.841795) (xy 53.894264 -118.811828)
			(xy 53.949637 -118.788892) (xy 54.00753 -118.773379) (xy 54.066952 -118.765556) (xy 54.126888 -118.765556)
			(xy 54.18631 -118.773379) (xy 54.244203 -118.788892) (xy 54.299576 -118.811828) (xy 54.351482 -118.841795)
			(xy 54.399032 -118.878282) (xy 54.441412 -118.920662) (xy 54.477899 -118.968212) (xy 54.507866 -119.020118)
			(xy 54.530802 -119.075491) (xy 54.546315 -119.133384) (xy 54.554138 -119.192806) (xy 54.554628 -119.222774)
			(xy 54.554628 -119.567198) (xy 66.599308 -119.567198) (xy 66.599308 -118.703598) (xy 66.599798 -118.673614)
			(xy 66.607626 -118.614158) (xy 66.623147 -118.556233) (xy 66.646096 -118.500829) (xy 66.67608 -118.448895)
			(xy 66.712586 -118.401319) (xy 66.754991 -118.358914) (xy 66.802567 -118.322408) (xy 66.854501 -118.292424)
			(xy 66.909905 -118.269475) (xy 66.96783 -118.253954) (xy 67.027286 -118.246126) (xy 67.087254 -118.246126)
			(xy 67.14671 -118.253954) (xy 67.204635 -118.269475) (xy 67.260039 -118.292424) (xy 67.311973 -118.322408)
			(xy 67.359549 -118.358914) (xy 67.401954 -118.401319) (xy 67.43846 -118.448895) (xy 67.468444 -118.500829)
			(xy 67.491393 -118.556233) (xy 67.506914 -118.614158) (xy 67.514742 -118.673614) (xy 67.515232 -118.703598)
			(xy 67.515232 -119.55907) (xy 81.07426 -119.55907) (xy 81.07426 -118.69547) (xy 81.07475 -118.665486)
			(xy 81.082578 -118.60603) (xy 81.098099 -118.548105) (xy 81.121048 -118.492701) (xy 81.151032 -118.440767)
			(xy 81.187538 -118.393191) (xy 81.229943 -118.350786) (xy 81.277519 -118.31428) (xy 81.329453 -118.284296)
			(xy 81.384857 -118.261347) (xy 81.442782 -118.245826) (xy 81.502238 -118.237998) (xy 81.562206 -118.237998)
			(xy 81.621662 -118.245826) (xy 81.679587 -118.261347) (xy 81.734991 -118.284296) (xy 81.786925 -118.31428)
			(xy 81.834501 -118.350786) (xy 81.876906 -118.393191) (xy 81.913412 -118.440767) (xy 81.943396 -118.492701)
			(xy 81.966345 -118.548105) (xy 81.981866 -118.60603) (xy 81.989694 -118.665486) (xy 81.990184 -118.69547)
			(xy 81.990184 -119.55907) (xy 81.989694 -119.589054) (xy 81.981866 -119.64851) (xy 81.966345 -119.706435)
			(xy 81.943396 -119.761839) (xy 81.913412 -119.813773) (xy 81.876906 -119.861349) (xy 81.834501 -119.903754)
			(xy 81.786925 -119.94026) (xy 81.734991 -119.970244) (xy 81.679587 -119.993193) (xy 81.621662 -120.008714)
			(xy 81.562206 -120.016542) (xy 81.502238 -120.016542) (xy 81.442782 -120.008714) (xy 81.384857 -119.993193)
			(xy 81.329453 -119.970244) (xy 81.277519 -119.94026) (xy 81.229943 -119.903754) (xy 81.187538 -119.861349)
			(xy 81.151032 -119.813773) (xy 81.121048 -119.761839) (xy 81.098099 -119.706435) (xy 81.082578 -119.64851)
			(xy 81.07475 -119.589054) (xy 81.07426 -119.55907) (xy 67.515232 -119.55907) (xy 67.515232 -119.567198)
			(xy 67.514742 -119.597182) (xy 67.506914 -119.656638) (xy 67.491393 -119.714563) (xy 67.468444 -119.769967)
			(xy 67.43846 -119.821901) (xy 67.401954 -119.869477) (xy 67.359549 -119.911882) (xy 67.311973 -119.948388)
			(xy 67.260039 -119.978372) (xy 67.204635 -120.001321) (xy 67.14671 -120.016842) (xy 67.087254 -120.02467)
			(xy 67.027286 -120.02467) (xy 66.96783 -120.016842) (xy 66.909905 -120.001321) (xy 66.854501 -119.978372)
			(xy 66.802567 -119.948388) (xy 66.754991 -119.911882) (xy 66.712586 -119.869477) (xy 66.67608 -119.821901)
			(xy 66.646096 -119.769967) (xy 66.623147 -119.714563) (xy 66.607626 -119.656638) (xy 66.599798 -119.597182)
			(xy 66.599308 -119.567198) (xy 54.554628 -119.567198) (xy 54.554628 -120.086374) (xy 54.554138 -120.116342)
			(xy 54.546315 -120.175764) (xy 54.530802 -120.233657) (xy 54.507866 -120.28903) (xy 54.477899 -120.340936)
			(xy 54.441412 -120.388486) (xy 54.399032 -120.430866) (xy 54.351482 -120.467353) (xy 54.299576 -120.49732)
			(xy 54.244203 -120.520256) (xy 54.18631 -120.535769) (xy 54.126888 -120.543592) (xy 54.066952 -120.543592)
			(xy 54.00753 -120.535769) (xy 53.949637 -120.520256) (xy 53.894264 -120.49732) (xy 53.842358 -120.467353)
			(xy 53.794808 -120.430866) (xy 53.752428 -120.388486) (xy 53.715941 -120.340936) (xy 53.685974 -120.28903)
			(xy 53.663038 -120.233657) (xy 53.647525 -120.175764) (xy 53.639702 -120.116342) (xy 53.639212 -120.086374)
			(xy 35.583368 -120.086374) (xy 35.583368 -120.087898) (xy 35.582878 -120.117866) (xy 35.575055 -120.177288)
			(xy 35.559542 -120.235181) (xy 35.536606 -120.290554) (xy 35.506639 -120.34246) (xy 35.470152 -120.39001)
			(xy 35.427772 -120.43239) (xy 35.380222 -120.468877) (xy 35.328316 -120.498844) (xy 35.272943 -120.52178)
			(xy 35.21505 -120.537293) (xy 35.155628 -120.545116) (xy 35.095692 -120.545116) (xy 35.03627 -120.537293)
			(xy 34.978377 -120.52178) (xy 34.923004 -120.498844) (xy 34.871098 -120.468877) (xy 34.823548 -120.43239)
			(xy 34.781168 -120.39001) (xy 34.744681 -120.34246) (xy 34.714714 -120.290554) (xy 34.691778 -120.235181)
			(xy 34.676265 -120.177288) (xy 34.668442 -120.117866) (xy 34.667952 -120.087898) (xy 4.30911 -120.087898)
			(xy 4.30911 -121.894346) (xy 37.31006 -121.894346) (xy 37.31006 -121.030746) (xy 37.31055 -121.000778)
			(xy 37.318373 -120.941356) (xy 37.333886 -120.883463) (xy 37.356822 -120.82809) (xy 37.386789 -120.776184)
			(xy 37.423276 -120.728634) (xy 37.465656 -120.686254) (xy 37.513206 -120.649767) (xy 37.565112 -120.6198)
			(xy 37.620485 -120.596864) (xy 37.678378 -120.581351) (xy 37.7378 -120.573528) (xy 37.797736 -120.573528)
			(xy 37.857158 -120.581351) (xy 37.915051 -120.596864) (xy 37.970424 -120.6198) (xy 38.02233 -120.649767)
			(xy 38.06988 -120.686254) (xy 38.11226 -120.728634) (xy 38.148747 -120.776184) (xy 38.178714 -120.82809)
			(xy 38.20165 -120.883463) (xy 38.217163 -120.941356) (xy 38.224986 -121.000778) (xy 38.225476 -121.030746)
			(xy 38.225476 -121.886472) (xy 51.785012 -121.886472) (xy 51.785012 -121.022872) (xy 51.785502 -120.992904)
			(xy 51.793325 -120.933482) (xy 51.808838 -120.875589) (xy 51.831774 -120.820216) (xy 51.861741 -120.76831)
			(xy 51.898228 -120.72076) (xy 51.940608 -120.67838) (xy 51.988158 -120.641893) (xy 52.040064 -120.611926)
			(xy 52.095437 -120.58899) (xy 52.15333 -120.573477) (xy 52.212752 -120.565654) (xy 52.272688 -120.565654)
			(xy 52.33211 -120.573477) (xy 52.390003 -120.58899) (xy 52.445376 -120.611926) (xy 52.497282 -120.641893)
			(xy 52.544832 -120.67838) (xy 52.587212 -120.72076) (xy 52.623699 -120.76831) (xy 52.653666 -120.820216)
			(xy 52.676602 -120.875589) (xy 52.692115 -120.933482) (xy 52.699938 -120.992904) (xy 52.700428 -121.022872)
			(xy 52.700428 -121.367296) (xy 64.745108 -121.367296) (xy 64.745108 -120.503696) (xy 64.745598 -120.473712)
			(xy 64.753426 -120.414256) (xy 64.768947 -120.356331) (xy 64.791896 -120.300927) (xy 64.82188 -120.248993)
			(xy 64.858386 -120.201417) (xy 64.900791 -120.159012) (xy 64.948367 -120.122506) (xy 65.000301 -120.092522)
			(xy 65.055705 -120.069573) (xy 65.11363 -120.054052) (xy 65.173086 -120.046224) (xy 65.233054 -120.046224)
			(xy 65.29251 -120.054052) (xy 65.350435 -120.069573) (xy 65.405839 -120.092522) (xy 65.457773 -120.122506)
			(xy 65.505349 -120.159012) (xy 65.547754 -120.201417) (xy 65.58426 -120.248993) (xy 65.614244 -120.300927)
			(xy 65.637193 -120.356331) (xy 65.652714 -120.414256) (xy 65.660542 -120.473712) (xy 65.661032 -120.503696)
			(xy 65.661032 -121.365772) (xy 83.716368 -121.365772) (xy 83.716368 -120.502172) (xy 83.716858 -120.472188)
			(xy 83.724686 -120.412732) (xy 83.740207 -120.354807) (xy 83.763156 -120.299403) (xy 83.79314 -120.247469)
			(xy 83.829646 -120.199893) (xy 83.872051 -120.157488) (xy 83.919627 -120.120982) (xy 83.971561 -120.090998)
			(xy 84.026965 -120.068049) (xy 84.08489 -120.052528) (xy 84.144346 -120.0447) (xy 84.204314 -120.0447)
			(xy 84.26377 -120.052528) (xy 84.321695 -120.068049) (xy 84.369615 -120.087898) (xy 150.767796 -120.087898)
			(xy 150.767796 -119.224298) (xy 150.768286 -119.194314) (xy 150.776114 -119.134858) (xy 150.791635 -119.076933)
			(xy 150.814584 -119.021529) (xy 150.844568 -118.969595) (xy 150.881074 -118.922019) (xy 150.923479 -118.879614)
			(xy 150.971055 -118.843108) (xy 151.022989 -118.813124) (xy 151.078393 -118.790175) (xy 151.136318 -118.774654)
			(xy 151.195774 -118.766826) (xy 151.255742 -118.766826) (xy 151.315198 -118.774654) (xy 151.373123 -118.790175)
			(xy 151.428527 -118.813124) (xy 151.480461 -118.843108) (xy 151.528037 -118.879614) (xy 151.570442 -118.922019)
			(xy 151.606948 -118.969595) (xy 151.636932 -119.021529) (xy 151.659881 -119.076933) (xy 151.675402 -119.134858)
			(xy 151.68323 -119.194314) (xy 151.68372 -119.224298) (xy 151.68372 -120.086374) (xy 169.739056 -120.086374)
			(xy 169.739056 -119.222774) (xy 169.739546 -119.19279) (xy 169.747374 -119.133334) (xy 169.762895 -119.075409)
			(xy 169.785844 -119.020005) (xy 169.815828 -118.968071) (xy 169.852334 -118.920495) (xy 169.894739 -118.87809)
			(xy 169.942315 -118.841584) (xy 169.994249 -118.8116) (xy 170.049653 -118.788651) (xy 170.107578 -118.77313)
			(xy 170.167034 -118.765302) (xy 170.227002 -118.765302) (xy 170.286458 -118.77313) (xy 170.344383 -118.788651)
			(xy 170.399787 -118.8116) (xy 170.451721 -118.841584) (xy 170.499297 -118.87809) (xy 170.541702 -118.920495)
			(xy 170.578208 -118.968071) (xy 170.608192 -119.020005) (xy 170.631141 -119.075409) (xy 170.646662 -119.133334)
			(xy 170.65449 -119.19279) (xy 170.65498 -119.222774) (xy 170.65498 -119.567198) (xy 182.69966 -119.567198)
			(xy 182.69966 -118.703598) (xy 182.70015 -118.67363) (xy 182.707973 -118.614208) (xy 182.723486 -118.556315)
			(xy 182.746422 -118.500942) (xy 182.776389 -118.449036) (xy 182.812876 -118.401486) (xy 182.855256 -118.359106)
			(xy 182.902806 -118.322619) (xy 182.954712 -118.292652) (xy 183.010085 -118.269716) (xy 183.067978 -118.254203)
			(xy 183.1274 -118.24638) (xy 183.187336 -118.24638) (xy 183.246758 -118.254203) (xy 183.304651 -118.269716)
			(xy 183.360024 -118.292652) (xy 183.41193 -118.322619) (xy 183.45948 -118.359106) (xy 183.50186 -118.401486)
			(xy 183.538347 -118.449036) (xy 183.568314 -118.500942) (xy 183.59125 -118.556315) (xy 183.606763 -118.614208)
			(xy 183.614586 -118.67363) (xy 183.615076 -118.703598) (xy 183.615076 -119.559324) (xy 197.174612 -119.559324)
			(xy 197.174612 -118.695724) (xy 197.175102 -118.665756) (xy 197.182925 -118.606334) (xy 197.198438 -118.548441)
			(xy 197.221374 -118.493068) (xy 197.251341 -118.441162) (xy 197.287828 -118.393612) (xy 197.330208 -118.351232)
			(xy 197.377758 -118.314745) (xy 197.429664 -118.284778) (xy 197.485037 -118.261842) (xy 197.54293 -118.246329)
			(xy 197.602352 -118.238506) (xy 197.662288 -118.238506) (xy 197.72171 -118.246329) (xy 197.779603 -118.261842)
			(xy 197.834976 -118.284778) (xy 197.886882 -118.314745) (xy 197.934432 -118.351232) (xy 197.976812 -118.393612)
			(xy 198.013299 -118.441162) (xy 198.043266 -118.493068) (xy 198.066202 -118.548441) (xy 198.081715 -118.606334)
			(xy 198.089538 -118.665756) (xy 198.090028 -118.695724) (xy 198.090028 -119.559324) (xy 198.089538 -119.589292)
			(xy 198.081715 -119.648714) (xy 198.066202 -119.706607) (xy 198.043266 -119.76198) (xy 198.013299 -119.813886)
			(xy 197.976812 -119.861436) (xy 197.934432 -119.903816) (xy 197.886882 -119.940303) (xy 197.834976 -119.97027)
			(xy 197.779603 -119.993206) (xy 197.72171 -120.008719) (xy 197.662288 -120.016542) (xy 197.602352 -120.016542)
			(xy 197.54293 -120.008719) (xy 197.485037 -119.993206) (xy 197.429664 -119.97027) (xy 197.377758 -119.940303)
			(xy 197.330208 -119.903816) (xy 197.287828 -119.861436) (xy 197.251341 -119.813886) (xy 197.221374 -119.76198)
			(xy 197.198438 -119.706607) (xy 197.182925 -119.648714) (xy 197.175102 -119.589292) (xy 197.174612 -119.559324)
			(xy 183.615076 -119.559324) (xy 183.615076 -119.567198) (xy 183.614586 -119.597166) (xy 183.606763 -119.656588)
			(xy 183.59125 -119.714481) (xy 183.568314 -119.769854) (xy 183.538347 -119.82176) (xy 183.50186 -119.86931)
			(xy 183.45948 -119.91169) (xy 183.41193 -119.948177) (xy 183.360024 -119.978144) (xy 183.304651 -120.00108)
			(xy 183.246758 -120.016593) (xy 183.187336 -120.024416) (xy 183.1274 -120.024416) (xy 183.067978 -120.016593)
			(xy 183.010085 -120.00108) (xy 182.954712 -119.978144) (xy 182.902806 -119.948177) (xy 182.855256 -119.91169)
			(xy 182.812876 -119.86931) (xy 182.776389 -119.82176) (xy 182.746422 -119.769854) (xy 182.723486 -119.714481)
			(xy 182.707973 -119.656588) (xy 182.70015 -119.597166) (xy 182.69966 -119.567198) (xy 170.65498 -119.567198)
			(xy 170.65498 -120.086374) (xy 170.65449 -120.116358) (xy 170.646662 -120.175814) (xy 170.631141 -120.233739)
			(xy 170.608192 -120.289143) (xy 170.578208 -120.341077) (xy 170.541702 -120.388653) (xy 170.499297 -120.431058)
			(xy 170.451721 -120.467564) (xy 170.399787 -120.497548) (xy 170.344383 -120.520497) (xy 170.286458 -120.536018)
			(xy 170.227002 -120.543846) (xy 170.167034 -120.543846) (xy 170.107578 -120.536018) (xy 170.049653 -120.520497)
			(xy 169.994249 -120.497548) (xy 169.942315 -120.467564) (xy 169.894739 -120.431058) (xy 169.852334 -120.388653)
			(xy 169.815828 -120.341077) (xy 169.785844 -120.289143) (xy 169.762895 -120.233739) (xy 169.747374 -120.175814)
			(xy 169.739546 -120.116358) (xy 169.739056 -120.086374) (xy 151.68372 -120.086374) (xy 151.68372 -120.087898)
			(xy 151.68323 -120.117882) (xy 151.675402 -120.177338) (xy 151.659881 -120.235263) (xy 151.636932 -120.290667)
			(xy 151.606948 -120.342601) (xy 151.570442 -120.390177) (xy 151.528037 -120.432582) (xy 151.480461 -120.469088)
			(xy 151.428527 -120.499072) (xy 151.373123 -120.522021) (xy 151.315198 -120.537542) (xy 151.255742 -120.54537)
			(xy 151.195774 -120.54537) (xy 151.136318 -120.537542) (xy 151.078393 -120.522021) (xy 151.022989 -120.499072)
			(xy 150.971055 -120.469088) (xy 150.923479 -120.432582) (xy 150.881074 -120.390177) (xy 150.844568 -120.342601)
			(xy 150.814584 -120.290667) (xy 150.791635 -120.235263) (xy 150.776114 -120.177338) (xy 150.768286 -120.117882)
			(xy 150.767796 -120.087898) (xy 84.369615 -120.087898) (xy 84.377099 -120.090998) (xy 84.429033 -120.120982)
			(xy 84.476609 -120.157488) (xy 84.519014 -120.199893) (xy 84.55552 -120.247469) (xy 84.585504 -120.299403)
			(xy 84.608453 -120.354807) (xy 84.623974 -120.412732) (xy 84.631802 -120.472188) (xy 84.632292 -120.502172)
			(xy 84.632292 -121.365772) (xy 84.631802 -121.395756) (xy 84.623974 -121.455212) (xy 84.608453 -121.513137)
			(xy 84.585504 -121.568541) (xy 84.55552 -121.620475) (xy 84.519014 -121.668051) (xy 84.476609 -121.710456)
			(xy 84.429033 -121.746962) (xy 84.377099 -121.776946) (xy 84.321695 -121.799895) (xy 84.26377 -121.815416)
			(xy 84.204314 -121.823244) (xy 84.144346 -121.823244) (xy 84.08489 -121.815416) (xy 84.026965 -121.799895)
			(xy 83.971561 -121.776946) (xy 83.919627 -121.746962) (xy 83.872051 -121.710456) (xy 83.829646 -121.668051)
			(xy 83.79314 -121.620475) (xy 83.763156 -121.568541) (xy 83.740207 -121.513137) (xy 83.724686 -121.455212)
			(xy 83.716858 -121.395756) (xy 83.716368 -121.365772) (xy 65.661032 -121.365772) (xy 65.661032 -121.367296)
			(xy 65.660542 -121.39728) (xy 65.652714 -121.456736) (xy 65.637193 -121.514661) (xy 65.614244 -121.570065)
			(xy 65.58426 -121.621999) (xy 65.547754 -121.669575) (xy 65.505349 -121.71198) (xy 65.457773 -121.748486)
			(xy 65.405839 -121.77847) (xy 65.350435 -121.801419) (xy 65.29251 -121.81694) (xy 65.233054 -121.824768)
			(xy 65.173086 -121.824768) (xy 65.11363 -121.81694) (xy 65.055705 -121.801419) (xy 65.000301 -121.77847)
			(xy 64.948367 -121.748486) (xy 64.900791 -121.71198) (xy 64.858386 -121.669575) (xy 64.82188 -121.621999)
			(xy 64.791896 -121.570065) (xy 64.768947 -121.514661) (xy 64.753426 -121.456736) (xy 64.745598 -121.39728)
			(xy 64.745108 -121.367296) (xy 52.700428 -121.367296) (xy 52.700428 -121.886472) (xy 52.699938 -121.91644)
			(xy 52.692115 -121.975862) (xy 52.676602 -122.033755) (xy 52.653666 -122.089128) (xy 52.623699 -122.141034)
			(xy 52.587212 -122.188584) (xy 52.544832 -122.230964) (xy 52.497282 -122.267451) (xy 52.445376 -122.297418)
			(xy 52.390003 -122.320354) (xy 52.33211 -122.335867) (xy 52.272688 -122.34369) (xy 52.212752 -122.34369)
			(xy 52.15333 -122.335867) (xy 52.095437 -122.320354) (xy 52.040064 -122.297418) (xy 51.988158 -122.267451)
			(xy 51.940608 -122.230964) (xy 51.898228 -122.188584) (xy 51.861741 -122.141034) (xy 51.831774 -122.089128)
			(xy 51.808838 -122.033755) (xy 51.793325 -121.975862) (xy 51.785502 -121.91644) (xy 51.785012 -121.886472)
			(xy 38.225476 -121.886472) (xy 38.225476 -121.894346) (xy 38.224986 -121.924314) (xy 38.217163 -121.983736)
			(xy 38.20165 -122.041629) (xy 38.178714 -122.097002) (xy 38.148747 -122.148908) (xy 38.11226 -122.196458)
			(xy 38.06988 -122.238838) (xy 38.02233 -122.275325) (xy 37.970424 -122.305292) (xy 37.915051 -122.328228)
			(xy 37.857158 -122.343741) (xy 37.797736 -122.351564) (xy 37.7378 -122.351564) (xy 37.678378 -122.343741)
			(xy 37.620485 -122.328228) (xy 37.565112 -122.305292) (xy 37.513206 -122.275325) (xy 37.465656 -122.238838)
			(xy 37.423276 -122.196458) (xy 37.386789 -122.148908) (xy 37.356822 -122.097002) (xy 37.333886 -122.041629)
			(xy 37.318373 -121.983736) (xy 37.31055 -121.924314) (xy 37.31006 -121.894346) (xy 4.30911 -121.894346)
			(xy 4.30911 -123.68784) (xy 34.667952 -123.68784) (xy 34.667952 -122.82424) (xy 34.668442 -122.794272)
			(xy 34.676265 -122.73485) (xy 34.691778 -122.676957) (xy 34.714714 -122.621584) (xy 34.744681 -122.569678)
			(xy 34.781168 -122.522128) (xy 34.823548 -122.479748) (xy 34.871098 -122.443261) (xy 34.923004 -122.413294)
			(xy 34.978377 -122.390358) (xy 35.03627 -122.374845) (xy 35.095692 -122.367022) (xy 35.155628 -122.367022)
			(xy 35.21505 -122.374845) (xy 35.272943 -122.390358) (xy 35.328316 -122.413294) (xy 35.380222 -122.443261)
			(xy 35.427772 -122.479748) (xy 35.470152 -122.522128) (xy 35.506639 -122.569678) (xy 35.536606 -122.621584)
			(xy 35.559542 -122.676957) (xy 35.575055 -122.73485) (xy 35.582878 -122.794272) (xy 35.583368 -122.82424)
			(xy 35.583368 -123.686316) (xy 53.639212 -123.686316) (xy 53.639212 -122.822716) (xy 53.639702 -122.792748)
			(xy 53.647525 -122.733326) (xy 53.663038 -122.675433) (xy 53.685974 -122.62006) (xy 53.715941 -122.568154)
			(xy 53.752428 -122.520604) (xy 53.794808 -122.478224) (xy 53.842358 -122.441737) (xy 53.894264 -122.41177)
			(xy 53.949637 -122.388834) (xy 54.00753 -122.373321) (xy 54.066952 -122.365498) (xy 54.126888 -122.365498)
			(xy 54.18631 -122.373321) (xy 54.244203 -122.388834) (xy 54.299576 -122.41177) (xy 54.351482 -122.441737)
			(xy 54.399032 -122.478224) (xy 54.441412 -122.520604) (xy 54.477899 -122.568154) (xy 54.507866 -122.62006)
			(xy 54.530802 -122.675433) (xy 54.546315 -122.733326) (xy 54.554138 -122.792748) (xy 54.554628 -122.822716)
			(xy 54.554628 -123.16714) (xy 66.599308 -123.16714) (xy 66.599308 -122.30354) (xy 66.599798 -122.273556)
			(xy 66.607626 -122.2141) (xy 66.623147 -122.156175) (xy 66.646096 -122.100771) (xy 66.67608 -122.048837)
			(xy 66.712586 -122.001261) (xy 66.754991 -121.958856) (xy 66.802567 -121.92235) (xy 66.854501 -121.892366)
			(xy 66.909905 -121.869417) (xy 66.96783 -121.853896) (xy 67.027286 -121.846068) (xy 67.087254 -121.846068)
			(xy 67.14671 -121.853896) (xy 67.204635 -121.869417) (xy 67.260039 -121.892366) (xy 67.311973 -121.92235)
			(xy 67.359549 -121.958856) (xy 67.401954 -122.001261) (xy 67.43846 -122.048837) (xy 67.468444 -122.100771)
			(xy 67.491393 -122.156175) (xy 67.506914 -122.2141) (xy 67.514742 -122.273556) (xy 67.515232 -122.30354)
			(xy 67.515232 -123.159266) (xy 81.07426 -123.159266) (xy 81.07426 -122.295666) (xy 81.07475 -122.265682)
			(xy 81.082578 -122.206226) (xy 81.098099 -122.148301) (xy 81.121048 -122.092897) (xy 81.151032 -122.040963)
			(xy 81.187538 -121.993387) (xy 81.229943 -121.950982) (xy 81.277519 -121.914476) (xy 81.329453 -121.884492)
			(xy 81.384857 -121.861543) (xy 81.442782 -121.846022) (xy 81.502238 -121.838194) (xy 81.562206 -121.838194)
			(xy 81.621662 -121.846022) (xy 81.679587 -121.861543) (xy 81.734991 -121.884492) (xy 81.752059 -121.894346)
			(xy 153.409904 -121.894346) (xy 153.409904 -121.030746) (xy 153.410394 -121.000762) (xy 153.418222 -120.941306)
			(xy 153.433743 -120.883381) (xy 153.456692 -120.827977) (xy 153.486676 -120.776043) (xy 153.523182 -120.728467)
			(xy 153.565587 -120.686062) (xy 153.613163 -120.649556) (xy 153.665097 -120.619572) (xy 153.720501 -120.596623)
			(xy 153.778426 -120.581102) (xy 153.837882 -120.573274) (xy 153.89785 -120.573274) (xy 153.957306 -120.581102)
			(xy 154.015231 -120.596623) (xy 154.070635 -120.619572) (xy 154.122569 -120.649556) (xy 154.170145 -120.686062)
			(xy 154.21255 -120.728467) (xy 154.249056 -120.776043) (xy 154.27904 -120.827977) (xy 154.301989 -120.883381)
			(xy 154.31751 -120.941306) (xy 154.325338 -121.000762) (xy 154.325828 -121.030746) (xy 154.325828 -121.886472)
			(xy 167.884856 -121.886472) (xy 167.884856 -121.022872) (xy 167.885346 -120.992888) (xy 167.893174 -120.933432)
			(xy 167.908695 -120.875507) (xy 167.931644 -120.820103) (xy 167.961628 -120.768169) (xy 167.998134 -120.720593)
			(xy 168.040539 -120.678188) (xy 168.088115 -120.641682) (xy 168.140049 -120.611698) (xy 168.195453 -120.588749)
			(xy 168.253378 -120.573228) (xy 168.312834 -120.5654) (xy 168.372802 -120.5654) (xy 168.432258 -120.573228)
			(xy 168.490183 -120.588749) (xy 168.545587 -120.611698) (xy 168.597521 -120.641682) (xy 168.645097 -120.678188)
			(xy 168.687502 -120.720593) (xy 168.724008 -120.768169) (xy 168.753992 -120.820103) (xy 168.776941 -120.875507)
			(xy 168.792462 -120.933432) (xy 168.80029 -120.992888) (xy 168.80078 -121.022872) (xy 168.80078 -121.367296)
			(xy 180.84546 -121.367296) (xy 180.84546 -120.503696) (xy 180.84595 -120.473728) (xy 180.853773 -120.414306)
			(xy 180.869286 -120.356413) (xy 180.892222 -120.30104) (xy 180.922189 -120.249134) (xy 180.958676 -120.201584)
			(xy 181.001056 -120.159204) (xy 181.048606 -120.122717) (xy 181.100512 -120.09275) (xy 181.155885 -120.069814)
			(xy 181.213778 -120.054301) (xy 181.2732 -120.046478) (xy 181.333136 -120.046478) (xy 181.392558 -120.054301)
			(xy 181.450451 -120.069814) (xy 181.505824 -120.09275) (xy 181.55773 -120.122717) (xy 181.60528 -120.159204)
			(xy 181.64766 -120.201584) (xy 181.684147 -120.249134) (xy 181.714114 -120.30104) (xy 181.73705 -120.356413)
			(xy 181.752563 -120.414306) (xy 181.760386 -120.473728) (xy 181.760876 -120.503696) (xy 181.760876 -121.365772)
			(xy 199.81672 -121.365772) (xy 199.81672 -120.502172) (xy 199.81721 -120.472204) (xy 199.825033 -120.412782)
			(xy 199.840546 -120.354889) (xy 199.863482 -120.299516) (xy 199.893449 -120.24761) (xy 199.929936 -120.20006)
			(xy 199.972316 -120.15768) (xy 200.019866 -120.121193) (xy 200.071772 -120.091226) (xy 200.127145 -120.06829)
			(xy 200.185038 -120.052777) (xy 200.24446 -120.044954) (xy 200.304396 -120.044954) (xy 200.363818 -120.052777)
			(xy 200.421711 -120.06829) (xy 200.469049 -120.087898) (xy 266.86764 -120.087898) (xy 266.86764 -119.224298)
			(xy 266.86813 -119.194314) (xy 266.875958 -119.134858) (xy 266.891479 -119.076933) (xy 266.914428 -119.021529)
			(xy 266.944412 -118.969595) (xy 266.980918 -118.922019) (xy 267.023323 -118.879614) (xy 267.070899 -118.843108)
			(xy 267.122833 -118.813124) (xy 267.178237 -118.790175) (xy 267.236162 -118.774654) (xy 267.295618 -118.766826)
			(xy 267.355586 -118.766826) (xy 267.415042 -118.774654) (xy 267.472967 -118.790175) (xy 267.528371 -118.813124)
			(xy 267.580305 -118.843108) (xy 267.627881 -118.879614) (xy 267.670286 -118.922019) (xy 267.706792 -118.969595)
			(xy 267.736776 -119.021529) (xy 267.759725 -119.076933) (xy 267.775246 -119.134858) (xy 267.783074 -119.194314)
			(xy 267.783564 -119.224298) (xy 267.783564 -120.086374) (xy 285.8389 -120.086374) (xy 285.8389 -119.222774)
			(xy 285.83939 -119.19279) (xy 285.847218 -119.133334) (xy 285.862739 -119.075409) (xy 285.885688 -119.020005)
			(xy 285.915672 -118.968071) (xy 285.952178 -118.920495) (xy 285.994583 -118.87809) (xy 286.042159 -118.841584)
			(xy 286.094093 -118.8116) (xy 286.149497 -118.788651) (xy 286.207422 -118.77313) (xy 286.266878 -118.765302)
			(xy 286.326846 -118.765302) (xy 286.386302 -118.77313) (xy 286.444227 -118.788651) (xy 286.499631 -118.8116)
			(xy 286.551565 -118.841584) (xy 286.599141 -118.87809) (xy 286.641546 -118.920495) (xy 286.678052 -118.968071)
			(xy 286.708036 -119.020005) (xy 286.730985 -119.075409) (xy 286.746506 -119.133334) (xy 286.754334 -119.19279)
			(xy 286.754824 -119.222774) (xy 286.754824 -119.567198) (xy 298.799504 -119.567198) (xy 298.799504 -118.703598)
			(xy 298.799994 -118.67363) (xy 298.807817 -118.614208) (xy 298.82333 -118.556315) (xy 298.846266 -118.500942)
			(xy 298.876233 -118.449036) (xy 298.91272 -118.401486) (xy 298.9551 -118.359106) (xy 299.00265 -118.322619)
			(xy 299.054556 -118.292652) (xy 299.109929 -118.269716) (xy 299.167822 -118.254203) (xy 299.227244 -118.24638)
			(xy 299.28718 -118.24638) (xy 299.346602 -118.254203) (xy 299.404495 -118.269716) (xy 299.459868 -118.292652)
			(xy 299.511774 -118.322619) (xy 299.559324 -118.359106) (xy 299.601704 -118.401486) (xy 299.638191 -118.449036)
			(xy 299.668158 -118.500942) (xy 299.691094 -118.556315) (xy 299.706607 -118.614208) (xy 299.71443 -118.67363)
			(xy 299.71492 -118.703598) (xy 299.71492 -119.559324) (xy 313.274456 -119.559324) (xy 313.274456 -118.695724)
			(xy 313.274946 -118.665756) (xy 313.282769 -118.606334) (xy 313.298282 -118.548441) (xy 313.321218 -118.493068)
			(xy 313.351185 -118.441162) (xy 313.387672 -118.393612) (xy 313.430052 -118.351232) (xy 313.477602 -118.314745)
			(xy 313.529508 -118.284778) (xy 313.584881 -118.261842) (xy 313.642774 -118.246329) (xy 313.702196 -118.238506)
			(xy 313.762132 -118.238506) (xy 313.821554 -118.246329) (xy 313.879447 -118.261842) (xy 313.93482 -118.284778)
			(xy 313.986726 -118.314745) (xy 314.034276 -118.351232) (xy 314.076656 -118.393612) (xy 314.113143 -118.441162)
			(xy 314.14311 -118.493068) (xy 314.166046 -118.548441) (xy 314.181559 -118.606334) (xy 314.189382 -118.665756)
			(xy 314.189872 -118.695724) (xy 314.189872 -119.559324) (xy 314.189382 -119.589292) (xy 314.181559 -119.648714)
			(xy 314.166046 -119.706607) (xy 314.14311 -119.76198) (xy 314.113143 -119.813886) (xy 314.076656 -119.861436)
			(xy 314.034276 -119.903816) (xy 313.986726 -119.940303) (xy 313.93482 -119.97027) (xy 313.879447 -119.993206)
			(xy 313.821554 -120.008719) (xy 313.762132 -120.016542) (xy 313.702196 -120.016542) (xy 313.642774 -120.008719)
			(xy 313.584881 -119.993206) (xy 313.529508 -119.97027) (xy 313.477602 -119.940303) (xy 313.430052 -119.903816)
			(xy 313.387672 -119.861436) (xy 313.351185 -119.813886) (xy 313.321218 -119.76198) (xy 313.298282 -119.706607)
			(xy 313.282769 -119.648714) (xy 313.274946 -119.589292) (xy 313.274456 -119.559324) (xy 299.71492 -119.559324)
			(xy 299.71492 -119.567198) (xy 299.71443 -119.597166) (xy 299.706607 -119.656588) (xy 299.691094 -119.714481)
			(xy 299.668158 -119.769854) (xy 299.638191 -119.82176) (xy 299.601704 -119.86931) (xy 299.559324 -119.91169)
			(xy 299.511774 -119.948177) (xy 299.459868 -119.978144) (xy 299.404495 -120.00108) (xy 299.346602 -120.016593)
			(xy 299.28718 -120.024416) (xy 299.227244 -120.024416) (xy 299.167822 -120.016593) (xy 299.109929 -120.00108)
			(xy 299.054556 -119.978144) (xy 299.00265 -119.948177) (xy 298.9551 -119.91169) (xy 298.91272 -119.86931)
			(xy 298.876233 -119.82176) (xy 298.846266 -119.769854) (xy 298.82333 -119.714481) (xy 298.807817 -119.656588)
			(xy 298.799994 -119.597166) (xy 298.799504 -119.567198) (xy 286.754824 -119.567198) (xy 286.754824 -120.086374)
			(xy 286.754334 -120.116358) (xy 286.746506 -120.175814) (xy 286.730985 -120.233739) (xy 286.708036 -120.289143)
			(xy 286.678052 -120.341077) (xy 286.641546 -120.388653) (xy 286.599141 -120.431058) (xy 286.551565 -120.467564)
			(xy 286.499631 -120.497548) (xy 286.444227 -120.520497) (xy 286.386302 -120.536018) (xy 286.326846 -120.543846)
			(xy 286.266878 -120.543846) (xy 286.207422 -120.536018) (xy 286.149497 -120.520497) (xy 286.094093 -120.497548)
			(xy 286.042159 -120.467564) (xy 285.994583 -120.431058) (xy 285.952178 -120.388653) (xy 285.915672 -120.341077)
			(xy 285.885688 -120.289143) (xy 285.862739 -120.233739) (xy 285.847218 -120.175814) (xy 285.83939 -120.116358)
			(xy 285.8389 -120.086374) (xy 267.783564 -120.086374) (xy 267.783564 -120.087898) (xy 267.783074 -120.117882)
			(xy 267.775246 -120.177338) (xy 267.759725 -120.235263) (xy 267.736776 -120.290667) (xy 267.706792 -120.342601)
			(xy 267.670286 -120.390177) (xy 267.627881 -120.432582) (xy 267.580305 -120.469088) (xy 267.528371 -120.499072)
			(xy 267.472967 -120.522021) (xy 267.415042 -120.537542) (xy 267.355586 -120.54537) (xy 267.295618 -120.54537)
			(xy 267.236162 -120.537542) (xy 267.178237 -120.522021) (xy 267.122833 -120.499072) (xy 267.070899 -120.469088)
			(xy 267.023323 -120.432582) (xy 266.980918 -120.390177) (xy 266.944412 -120.342601) (xy 266.914428 -120.290667)
			(xy 266.891479 -120.235263) (xy 266.875958 -120.177338) (xy 266.86813 -120.117882) (xy 266.86764 -120.087898)
			(xy 200.469049 -120.087898) (xy 200.477084 -120.091226) (xy 200.52899 -120.121193) (xy 200.57654 -120.15768)
			(xy 200.61892 -120.20006) (xy 200.655407 -120.24761) (xy 200.685374 -120.299516) (xy 200.70831 -120.354889)
			(xy 200.723823 -120.412782) (xy 200.731646 -120.472204) (xy 200.732136 -120.502172) (xy 200.732136 -121.365772)
			(xy 200.731646 -121.39574) (xy 200.723823 -121.455162) (xy 200.70831 -121.513055) (xy 200.685374 -121.568428)
			(xy 200.655407 -121.620334) (xy 200.61892 -121.667884) (xy 200.57654 -121.710264) (xy 200.52899 -121.746751)
			(xy 200.477084 -121.776718) (xy 200.421711 -121.799654) (xy 200.363818 -121.815167) (xy 200.304396 -121.82299)
			(xy 200.24446 -121.82299) (xy 200.185038 -121.815167) (xy 200.127145 -121.799654) (xy 200.071772 -121.776718)
			(xy 200.019866 -121.746751) (xy 199.972316 -121.710264) (xy 199.929936 -121.667884) (xy 199.893449 -121.620334)
			(xy 199.863482 -121.568428) (xy 199.840546 -121.513055) (xy 199.825033 -121.455162) (xy 199.81721 -121.39574)
			(xy 199.81672 -121.365772) (xy 181.760876 -121.365772) (xy 181.760876 -121.367296) (xy 181.760386 -121.397264)
			(xy 181.752563 -121.456686) (xy 181.73705 -121.514579) (xy 181.714114 -121.569952) (xy 181.684147 -121.621858)
			(xy 181.64766 -121.669408) (xy 181.60528 -121.711788) (xy 181.55773 -121.748275) (xy 181.505824 -121.778242)
			(xy 181.450451 -121.801178) (xy 181.392558 -121.816691) (xy 181.333136 -121.824514) (xy 181.2732 -121.824514)
			(xy 181.213778 -121.816691) (xy 181.155885 -121.801178) (xy 181.100512 -121.778242) (xy 181.048606 -121.748275)
			(xy 181.001056 -121.711788) (xy 180.958676 -121.669408) (xy 180.922189 -121.621858) (xy 180.892222 -121.569952)
			(xy 180.869286 -121.514579) (xy 180.853773 -121.456686) (xy 180.84595 -121.397264) (xy 180.84546 -121.367296)
			(xy 168.80078 -121.367296) (xy 168.80078 -121.886472) (xy 168.80029 -121.916456) (xy 168.792462 -121.975912)
			(xy 168.776941 -122.033837) (xy 168.753992 -122.089241) (xy 168.724008 -122.141175) (xy 168.687502 -122.188751)
			(xy 168.645097 -122.231156) (xy 168.597521 -122.267662) (xy 168.545587 -122.297646) (xy 168.490183 -122.320595)
			(xy 168.432258 -122.336116) (xy 168.372802 -122.343944) (xy 168.312834 -122.343944) (xy 168.253378 -122.336116)
			(xy 168.195453 -122.320595) (xy 168.140049 -122.297646) (xy 168.088115 -122.267662) (xy 168.040539 -122.231156)
			(xy 167.998134 -122.188751) (xy 167.961628 -122.141175) (xy 167.931644 -122.089241) (xy 167.908695 -122.033837)
			(xy 167.893174 -121.975912) (xy 167.885346 -121.916456) (xy 167.884856 -121.886472) (xy 154.325828 -121.886472)
			(xy 154.325828 -121.894346) (xy 154.325338 -121.92433) (xy 154.31751 -121.983786) (xy 154.301989 -122.041711)
			(xy 154.27904 -122.097115) (xy 154.249056 -122.149049) (xy 154.21255 -122.196625) (xy 154.170145 -122.23903)
			(xy 154.122569 -122.275536) (xy 154.070635 -122.30552) (xy 154.015231 -122.328469) (xy 153.957306 -122.34399)
			(xy 153.89785 -122.351818) (xy 153.837882 -122.351818) (xy 153.778426 -122.34399) (xy 153.720501 -122.328469)
			(xy 153.665097 -122.30552) (xy 153.613163 -122.275536) (xy 153.565587 -122.23903) (xy 153.523182 -122.196625)
			(xy 153.486676 -122.149049) (xy 153.456692 -122.097115) (xy 153.433743 -122.041711) (xy 153.418222 -121.983786)
			(xy 153.410394 -121.92433) (xy 153.409904 -121.894346) (xy 81.752059 -121.894346) (xy 81.786925 -121.914476)
			(xy 81.834501 -121.950982) (xy 81.876906 -121.993387) (xy 81.913412 -122.040963) (xy 81.943396 -122.092897)
			(xy 81.966345 -122.148301) (xy 81.981866 -122.206226) (xy 81.989694 -122.265682) (xy 81.990184 -122.295666)
			(xy 81.990184 -123.159266) (xy 81.989694 -123.18925) (xy 81.981866 -123.248706) (xy 81.966345 -123.306631)
			(xy 81.943396 -123.362035) (xy 81.913412 -123.413969) (xy 81.876906 -123.461545) (xy 81.834501 -123.50395)
			(xy 81.786925 -123.540456) (xy 81.734991 -123.57044) (xy 81.679587 -123.593389) (xy 81.621662 -123.60891)
			(xy 81.562206 -123.616738) (xy 81.502238 -123.616738) (xy 81.442782 -123.60891) (xy 81.384857 -123.593389)
			(xy 81.329453 -123.57044) (xy 81.277519 -123.540456) (xy 81.229943 -123.50395) (xy 81.187538 -123.461545)
			(xy 81.151032 -123.413969) (xy 81.121048 -123.362035) (xy 81.098099 -123.306631) (xy 81.082578 -123.248706)
			(xy 81.07475 -123.18925) (xy 81.07426 -123.159266) (xy 67.515232 -123.159266) (xy 67.515232 -123.16714)
			(xy 67.514742 -123.197124) (xy 67.506914 -123.25658) (xy 67.491393 -123.314505) (xy 67.468444 -123.369909)
			(xy 67.43846 -123.421843) (xy 67.401954 -123.469419) (xy 67.359549 -123.511824) (xy 67.311973 -123.54833)
			(xy 67.260039 -123.578314) (xy 67.204635 -123.601263) (xy 67.14671 -123.616784) (xy 67.087254 -123.624612)
			(xy 67.027286 -123.624612) (xy 66.96783 -123.616784) (xy 66.909905 -123.601263) (xy 66.854501 -123.578314)
			(xy 66.802567 -123.54833) (xy 66.754991 -123.511824) (xy 66.712586 -123.469419) (xy 66.67608 -123.421843)
			(xy 66.646096 -123.369909) (xy 66.623147 -123.314505) (xy 66.607626 -123.25658) (xy 66.599798 -123.197124)
			(xy 66.599308 -123.16714) (xy 54.554628 -123.16714) (xy 54.554628 -123.686316) (xy 54.554138 -123.716284)
			(xy 54.546315 -123.775706) (xy 54.530802 -123.833599) (xy 54.507866 -123.888972) (xy 54.477899 -123.940878)
			(xy 54.441412 -123.988428) (xy 54.399032 -124.030808) (xy 54.351482 -124.067295) (xy 54.299576 -124.097262)
			(xy 54.244203 -124.120198) (xy 54.18631 -124.135711) (xy 54.126888 -124.143534) (xy 54.066952 -124.143534)
			(xy 54.00753 -124.135711) (xy 53.949637 -124.120198) (xy 53.894264 -124.097262) (xy 53.842358 -124.067295)
			(xy 53.794808 -124.030808) (xy 53.752428 -123.988428) (xy 53.715941 -123.940878) (xy 53.685974 -123.888972)
			(xy 53.663038 -123.833599) (xy 53.647525 -123.775706) (xy 53.639702 -123.716284) (xy 53.639212 -123.686316)
			(xy 35.583368 -123.686316) (xy 35.583368 -123.68784) (xy 35.582878 -123.717808) (xy 35.575055 -123.77723)
			(xy 35.559542 -123.835123) (xy 35.536606 -123.890496) (xy 35.506639 -123.942402) (xy 35.470152 -123.989952)
			(xy 35.427772 -124.032332) (xy 35.380222 -124.068819) (xy 35.328316 -124.098786) (xy 35.272943 -124.121722)
			(xy 35.21505 -124.137235) (xy 35.155628 -124.145058) (xy 35.095692 -124.145058) (xy 35.03627 -124.137235)
			(xy 34.978377 -124.121722) (xy 34.923004 -124.098786) (xy 34.871098 -124.068819) (xy 34.823548 -124.032332)
			(xy 34.781168 -123.989952) (xy 34.744681 -123.942402) (xy 34.714714 -123.890496) (xy 34.691778 -123.835123)
			(xy 34.676265 -123.77723) (xy 34.668442 -123.717808) (xy 34.667952 -123.68784) (xy 4.30911 -123.68784)
			(xy 4.30911 -125.494542) (xy 37.31006 -125.494542) (xy 37.31006 -124.630942) (xy 37.31055 -124.600974)
			(xy 37.318373 -124.541552) (xy 37.333886 -124.483659) (xy 37.356822 -124.428286) (xy 37.386789 -124.37638)
			(xy 37.423276 -124.32883) (xy 37.465656 -124.28645) (xy 37.513206 -124.249963) (xy 37.565112 -124.219996)
			(xy 37.620485 -124.19706) (xy 37.678378 -124.181547) (xy 37.7378 -124.173724) (xy 37.797736 -124.173724)
			(xy 37.857158 -124.181547) (xy 37.915051 -124.19706) (xy 37.970424 -124.219996) (xy 38.02233 -124.249963)
			(xy 38.06988 -124.28645) (xy 38.11226 -124.32883) (xy 38.148747 -124.37638) (xy 38.178714 -124.428286)
			(xy 38.20165 -124.483659) (xy 38.217163 -124.541552) (xy 38.224986 -124.600974) (xy 38.225476 -124.630942)
			(xy 38.225476 -125.486414) (xy 51.785012 -125.486414) (xy 51.785012 -124.622814) (xy 51.785502 -124.592846)
			(xy 51.793325 -124.533424) (xy 51.808838 -124.475531) (xy 51.831774 -124.420158) (xy 51.861741 -124.368252)
			(xy 51.898228 -124.320702) (xy 51.940608 -124.278322) (xy 51.988158 -124.241835) (xy 52.040064 -124.211868)
			(xy 52.095437 -124.188932) (xy 52.15333 -124.173419) (xy 52.212752 -124.165596) (xy 52.272688 -124.165596)
			(xy 52.33211 -124.173419) (xy 52.390003 -124.188932) (xy 52.445376 -124.211868) (xy 52.497282 -124.241835)
			(xy 52.544832 -124.278322) (xy 52.587212 -124.320702) (xy 52.623699 -124.368252) (xy 52.653666 -124.420158)
			(xy 52.676602 -124.475531) (xy 52.692115 -124.533424) (xy 52.699938 -124.592846) (xy 52.700428 -124.622814)
			(xy 52.700428 -124.967238) (xy 64.745108 -124.967238) (xy 64.745108 -124.103638) (xy 64.745598 -124.073654)
			(xy 64.753426 -124.014198) (xy 64.768947 -123.956273) (xy 64.791896 -123.900869) (xy 64.82188 -123.848935)
			(xy 64.858386 -123.801359) (xy 64.900791 -123.758954) (xy 64.948367 -123.722448) (xy 65.000301 -123.692464)
			(xy 65.055705 -123.669515) (xy 65.11363 -123.653994) (xy 65.173086 -123.646166) (xy 65.233054 -123.646166)
			(xy 65.29251 -123.653994) (xy 65.350435 -123.669515) (xy 65.405839 -123.692464) (xy 65.457773 -123.722448)
			(xy 65.505349 -123.758954) (xy 65.547754 -123.801359) (xy 65.58426 -123.848935) (xy 65.614244 -123.900869)
			(xy 65.637193 -123.956273) (xy 65.652714 -124.014198) (xy 65.660542 -124.073654) (xy 65.661032 -124.103638)
			(xy 65.661032 -124.965714) (xy 83.716368 -124.965714) (xy 83.716368 -124.102114) (xy 83.716858 -124.07213)
			(xy 83.724686 -124.012674) (xy 83.740207 -123.954749) (xy 83.763156 -123.899345) (xy 83.79314 -123.847411)
			(xy 83.829646 -123.799835) (xy 83.872051 -123.75743) (xy 83.919627 -123.720924) (xy 83.971561 -123.69094)
			(xy 84.026965 -123.667991) (xy 84.08489 -123.65247) (xy 84.144346 -123.644642) (xy 84.204314 -123.644642)
			(xy 84.26377 -123.65247) (xy 84.321695 -123.667991) (xy 84.369615 -123.68784) (xy 150.767796 -123.68784)
			(xy 150.767796 -122.82424) (xy 150.768286 -122.794256) (xy 150.776114 -122.7348) (xy 150.791635 -122.676875)
			(xy 150.814584 -122.621471) (xy 150.844568 -122.569537) (xy 150.881074 -122.521961) (xy 150.923479 -122.479556)
			(xy 150.971055 -122.44305) (xy 151.022989 -122.413066) (xy 151.078393 -122.390117) (xy 151.136318 -122.374596)
			(xy 151.195774 -122.366768) (xy 151.255742 -122.366768) (xy 151.315198 -122.374596) (xy 151.373123 -122.390117)
			(xy 151.428527 -122.413066) (xy 151.480461 -122.44305) (xy 151.528037 -122.479556) (xy 151.570442 -122.521961)
			(xy 151.606948 -122.569537) (xy 151.636932 -122.621471) (xy 151.659881 -122.676875) (xy 151.675402 -122.7348)
			(xy 151.68323 -122.794256) (xy 151.68372 -122.82424) (xy 151.68372 -123.686316) (xy 169.739056 -123.686316)
			(xy 169.739056 -122.822716) (xy 169.739546 -122.792732) (xy 169.747374 -122.733276) (xy 169.762895 -122.675351)
			(xy 169.785844 -122.619947) (xy 169.815828 -122.568013) (xy 169.852334 -122.520437) (xy 169.894739 -122.478032)
			(xy 169.942315 -122.441526) (xy 169.994249 -122.411542) (xy 170.049653 -122.388593) (xy 170.107578 -122.373072)
			(xy 170.167034 -122.365244) (xy 170.227002 -122.365244) (xy 170.286458 -122.373072) (xy 170.344383 -122.388593)
			(xy 170.399787 -122.411542) (xy 170.451721 -122.441526) (xy 170.499297 -122.478032) (xy 170.541702 -122.520437)
			(xy 170.578208 -122.568013) (xy 170.608192 -122.619947) (xy 170.631141 -122.675351) (xy 170.646662 -122.733276)
			(xy 170.65449 -122.792732) (xy 170.65498 -122.822716) (xy 170.65498 -123.16714) (xy 182.69966 -123.16714)
			(xy 182.69966 -122.30354) (xy 182.70015 -122.273572) (xy 182.707973 -122.21415) (xy 182.723486 -122.156257)
			(xy 182.746422 -122.100884) (xy 182.776389 -122.048978) (xy 182.812876 -122.001428) (xy 182.855256 -121.959048)
			(xy 182.902806 -121.922561) (xy 182.954712 -121.892594) (xy 183.010085 -121.869658) (xy 183.067978 -121.854145)
			(xy 183.1274 -121.846322) (xy 183.187336 -121.846322) (xy 183.246758 -121.854145) (xy 183.304651 -121.869658)
			(xy 183.360024 -121.892594) (xy 183.41193 -121.922561) (xy 183.45948 -121.959048) (xy 183.50186 -122.001428)
			(xy 183.538347 -122.048978) (xy 183.568314 -122.100884) (xy 183.59125 -122.156257) (xy 183.606763 -122.21415)
			(xy 183.614586 -122.273572) (xy 183.615076 -122.30354) (xy 183.615076 -123.159266) (xy 197.174612 -123.159266)
			(xy 197.174612 -122.295666) (xy 197.175102 -122.265698) (xy 197.182925 -122.206276) (xy 197.198438 -122.148383)
			(xy 197.221374 -122.09301) (xy 197.251341 -122.041104) (xy 197.287828 -121.993554) (xy 197.330208 -121.951174)
			(xy 197.377758 -121.914687) (xy 197.429664 -121.88472) (xy 197.485037 -121.861784) (xy 197.54293 -121.846271)
			(xy 197.602352 -121.838448) (xy 197.662288 -121.838448) (xy 197.72171 -121.846271) (xy 197.779603 -121.861784)
			(xy 197.834976 -121.88472) (xy 197.851649 -121.894346) (xy 269.509748 -121.894346) (xy 269.509748 -121.030746)
			(xy 269.510238 -121.000762) (xy 269.518066 -120.941306) (xy 269.533587 -120.883381) (xy 269.556536 -120.827977)
			(xy 269.58652 -120.776043) (xy 269.623026 -120.728467) (xy 269.665431 -120.686062) (xy 269.713007 -120.649556)
			(xy 269.764941 -120.619572) (xy 269.820345 -120.596623) (xy 269.87827 -120.581102) (xy 269.937726 -120.573274)
			(xy 269.997694 -120.573274) (xy 270.05715 -120.581102) (xy 270.115075 -120.596623) (xy 270.170479 -120.619572)
			(xy 270.222413 -120.649556) (xy 270.269989 -120.686062) (xy 270.312394 -120.728467) (xy 270.3489 -120.776043)
			(xy 270.378884 -120.827977) (xy 270.401833 -120.883381) (xy 270.417354 -120.941306) (xy 270.425182 -121.000762)
			(xy 270.425672 -121.030746) (xy 270.425672 -121.886472) (xy 283.9847 -121.886472) (xy 283.9847 -121.022872)
			(xy 283.98519 -120.992888) (xy 283.993018 -120.933432) (xy 284.008539 -120.875507) (xy 284.031488 -120.820103)
			(xy 284.061472 -120.768169) (xy 284.097978 -120.720593) (xy 284.140383 -120.678188) (xy 284.187959 -120.641682)
			(xy 284.239893 -120.611698) (xy 284.295297 -120.588749) (xy 284.353222 -120.573228) (xy 284.412678 -120.5654)
			(xy 284.472646 -120.5654) (xy 284.532102 -120.573228) (xy 284.590027 -120.588749) (xy 284.645431 -120.611698)
			(xy 284.697365 -120.641682) (xy 284.744941 -120.678188) (xy 284.787346 -120.720593) (xy 284.823852 -120.768169)
			(xy 284.853836 -120.820103) (xy 284.876785 -120.875507) (xy 284.892306 -120.933432) (xy 284.900134 -120.992888)
			(xy 284.900624 -121.022872) (xy 284.900624 -121.367296) (xy 296.945304 -121.367296) (xy 296.945304 -120.503696)
			(xy 296.945794 -120.473728) (xy 296.953617 -120.414306) (xy 296.96913 -120.356413) (xy 296.992066 -120.30104)
			(xy 297.022033 -120.249134) (xy 297.05852 -120.201584) (xy 297.1009 -120.159204) (xy 297.14845 -120.122717)
			(xy 297.200356 -120.09275) (xy 297.255729 -120.069814) (xy 297.313622 -120.054301) (xy 297.373044 -120.046478)
			(xy 297.43298 -120.046478) (xy 297.492402 -120.054301) (xy 297.550295 -120.069814) (xy 297.605668 -120.09275)
			(xy 297.657574 -120.122717) (xy 297.705124 -120.159204) (xy 297.747504 -120.201584) (xy 297.783991 -120.249134)
			(xy 297.813958 -120.30104) (xy 297.836894 -120.356413) (xy 297.852407 -120.414306) (xy 297.86023 -120.473728)
			(xy 297.86072 -120.503696) (xy 297.86072 -121.365772) (xy 315.916564 -121.365772) (xy 315.916564 -120.502172)
			(xy 315.917054 -120.472204) (xy 315.924877 -120.412782) (xy 315.94039 -120.354889) (xy 315.963326 -120.299516)
			(xy 315.993293 -120.24761) (xy 316.02978 -120.20006) (xy 316.07216 -120.15768) (xy 316.11971 -120.121193)
			(xy 316.171616 -120.091226) (xy 316.226989 -120.06829) (xy 316.284882 -120.052777) (xy 316.344304 -120.044954)
			(xy 316.40424 -120.044954) (xy 316.463662 -120.052777) (xy 316.521555 -120.06829) (xy 316.568893 -120.087898)
			(xy 382.967992 -120.087898) (xy 382.967992 -119.224298) (xy 382.968482 -119.19433) (xy 382.976305 -119.134908)
			(xy 382.991818 -119.077015) (xy 383.014754 -119.021642) (xy 383.044721 -118.969736) (xy 383.081208 -118.922186)
			(xy 383.123588 -118.879806) (xy 383.171138 -118.843319) (xy 383.223044 -118.813352) (xy 383.278417 -118.790416)
			(xy 383.33631 -118.774903) (xy 383.395732 -118.76708) (xy 383.455668 -118.76708) (xy 383.51509 -118.774903)
			(xy 383.572983 -118.790416) (xy 383.628356 -118.813352) (xy 383.680262 -118.843319) (xy 383.727812 -118.879806)
			(xy 383.770192 -118.922186) (xy 383.806679 -118.969736) (xy 383.836646 -119.021642) (xy 383.859582 -119.077015)
			(xy 383.875095 -119.134908) (xy 383.882918 -119.19433) (xy 383.883408 -119.224298) (xy 383.883408 -120.086374)
			(xy 401.939252 -120.086374) (xy 401.939252 -119.222774) (xy 401.939742 -119.192806) (xy 401.947565 -119.133384)
			(xy 401.963078 -119.075491) (xy 401.986014 -119.020118) (xy 402.015981 -118.968212) (xy 402.052468 -118.920662)
			(xy 402.094848 -118.878282) (xy 402.142398 -118.841795) (xy 402.194304 -118.811828) (xy 402.249677 -118.788892)
			(xy 402.30757 -118.773379) (xy 402.366992 -118.765556) (xy 402.426928 -118.765556) (xy 402.48635 -118.773379)
			(xy 402.544243 -118.788892) (xy 402.599616 -118.811828) (xy 402.651522 -118.841795) (xy 402.699072 -118.878282)
			(xy 402.741452 -118.920662) (xy 402.777939 -118.968212) (xy 402.807906 -119.020118) (xy 402.830842 -119.075491)
			(xy 402.846355 -119.133384) (xy 402.854178 -119.192806) (xy 402.854668 -119.222774) (xy 402.854668 -119.567198)
			(xy 414.899348 -119.567198) (xy 414.899348 -118.703598) (xy 414.899838 -118.673614) (xy 414.907666 -118.614158)
			(xy 414.923187 -118.556233) (xy 414.946136 -118.500829) (xy 414.97612 -118.448895) (xy 415.012626 -118.401319)
			(xy 415.055031 -118.358914) (xy 415.102607 -118.322408) (xy 415.154541 -118.292424) (xy 415.209945 -118.269475)
			(xy 415.26787 -118.253954) (xy 415.327326 -118.246126) (xy 415.387294 -118.246126) (xy 415.44675 -118.253954)
			(xy 415.504675 -118.269475) (xy 415.560079 -118.292424) (xy 415.612013 -118.322408) (xy 415.659589 -118.358914)
			(xy 415.701994 -118.401319) (xy 415.7385 -118.448895) (xy 415.768484 -118.500829) (xy 415.791433 -118.556233)
			(xy 415.806954 -118.614158) (xy 415.814782 -118.673614) (xy 415.815272 -118.703598) (xy 415.815272 -119.559324)
			(xy 429.3743 -119.559324) (xy 429.3743 -118.695724) (xy 429.37479 -118.66574) (xy 429.382618 -118.606284)
			(xy 429.398139 -118.548359) (xy 429.421088 -118.492955) (xy 429.451072 -118.441021) (xy 429.487578 -118.393445)
			(xy 429.529983 -118.35104) (xy 429.577559 -118.314534) (xy 429.629493 -118.28455) (xy 429.684897 -118.261601)
			(xy 429.742822 -118.24608) (xy 429.802278 -118.238252) (xy 429.862246 -118.238252) (xy 429.921702 -118.24608)
			(xy 429.979627 -118.261601) (xy 430.035031 -118.28455) (xy 430.086965 -118.314534) (xy 430.134541 -118.35104)
			(xy 430.176946 -118.393445) (xy 430.213452 -118.441021) (xy 430.243436 -118.492955) (xy 430.266385 -118.548359)
			(xy 430.281906 -118.606284) (xy 430.289734 -118.66574) (xy 430.290224 -118.695724) (xy 430.290224 -119.559324)
			(xy 430.289734 -119.589308) (xy 430.281906 -119.648764) (xy 430.266385 -119.706689) (xy 430.243436 -119.762093)
			(xy 430.213452 -119.814027) (xy 430.176946 -119.861603) (xy 430.134541 -119.904008) (xy 430.086965 -119.940514)
			(xy 430.035031 -119.970498) (xy 429.979627 -119.993447) (xy 429.921702 -120.008968) (xy 429.862246 -120.016796)
			(xy 429.802278 -120.016796) (xy 429.742822 -120.008968) (xy 429.684897 -119.993447) (xy 429.629493 -119.970498)
			(xy 429.577559 -119.940514) (xy 429.529983 -119.904008) (xy 429.487578 -119.861603) (xy 429.451072 -119.814027)
			(xy 429.421088 -119.762093) (xy 429.398139 -119.706689) (xy 429.382618 -119.648764) (xy 429.37479 -119.589308)
			(xy 429.3743 -119.559324) (xy 415.815272 -119.559324) (xy 415.815272 -119.567198) (xy 415.814782 -119.597182)
			(xy 415.806954 -119.656638) (xy 415.791433 -119.714563) (xy 415.768484 -119.769967) (xy 415.7385 -119.821901)
			(xy 415.701994 -119.869477) (xy 415.659589 -119.911882) (xy 415.612013 -119.948388) (xy 415.560079 -119.978372)
			(xy 415.504675 -120.001321) (xy 415.44675 -120.016842) (xy 415.387294 -120.02467) (xy 415.327326 -120.02467)
			(xy 415.26787 -120.016842) (xy 415.209945 -120.001321) (xy 415.154541 -119.978372) (xy 415.102607 -119.948388)
			(xy 415.055031 -119.911882) (xy 415.012626 -119.869477) (xy 414.97612 -119.821901) (xy 414.946136 -119.769967)
			(xy 414.923187 -119.714563) (xy 414.907666 -119.656638) (xy 414.899838 -119.597182) (xy 414.899348 -119.567198)
			(xy 402.854668 -119.567198) (xy 402.854668 -120.086374) (xy 402.854178 -120.116342) (xy 402.846355 -120.175764)
			(xy 402.830842 -120.233657) (xy 402.807906 -120.28903) (xy 402.777939 -120.340936) (xy 402.741452 -120.388486)
			(xy 402.699072 -120.430866) (xy 402.651522 -120.467353) (xy 402.599616 -120.49732) (xy 402.544243 -120.520256)
			(xy 402.48635 -120.535769) (xy 402.426928 -120.543592) (xy 402.366992 -120.543592) (xy 402.30757 -120.535769)
			(xy 402.249677 -120.520256) (xy 402.194304 -120.49732) (xy 402.142398 -120.467353) (xy 402.094848 -120.430866)
			(xy 402.052468 -120.388486) (xy 402.015981 -120.340936) (xy 401.986014 -120.28903) (xy 401.963078 -120.233657)
			(xy 401.947565 -120.175764) (xy 401.939742 -120.116342) (xy 401.939252 -120.086374) (xy 383.883408 -120.086374)
			(xy 383.883408 -120.087898) (xy 383.882918 -120.117866) (xy 383.875095 -120.177288) (xy 383.859582 -120.235181)
			(xy 383.836646 -120.290554) (xy 383.806679 -120.34246) (xy 383.770192 -120.39001) (xy 383.727812 -120.43239)
			(xy 383.680262 -120.468877) (xy 383.628356 -120.498844) (xy 383.572983 -120.52178) (xy 383.51509 -120.537293)
			(xy 383.455668 -120.545116) (xy 383.395732 -120.545116) (xy 383.33631 -120.537293) (xy 383.278417 -120.52178)
			(xy 383.223044 -120.498844) (xy 383.171138 -120.468877) (xy 383.123588 -120.43239) (xy 383.081208 -120.39001)
			(xy 383.044721 -120.34246) (xy 383.014754 -120.290554) (xy 382.991818 -120.235181) (xy 382.976305 -120.177288)
			(xy 382.968482 -120.117866) (xy 382.967992 -120.087898) (xy 316.568893 -120.087898) (xy 316.576928 -120.091226)
			(xy 316.628834 -120.121193) (xy 316.676384 -120.15768) (xy 316.718764 -120.20006) (xy 316.755251 -120.24761)
			(xy 316.785218 -120.299516) (xy 316.808154 -120.354889) (xy 316.823667 -120.412782) (xy 316.83149 -120.472204)
			(xy 316.83198 -120.502172) (xy 316.83198 -121.365772) (xy 316.83149 -121.39574) (xy 316.823667 -121.455162)
			(xy 316.808154 -121.513055) (xy 316.785218 -121.568428) (xy 316.755251 -121.620334) (xy 316.718764 -121.667884)
			(xy 316.676384 -121.710264) (xy 316.628834 -121.746751) (xy 316.576928 -121.776718) (xy 316.521555 -121.799654)
			(xy 316.463662 -121.815167) (xy 316.40424 -121.82299) (xy 316.344304 -121.82299) (xy 316.284882 -121.815167)
			(xy 316.226989 -121.799654) (xy 316.171616 -121.776718) (xy 316.11971 -121.746751) (xy 316.07216 -121.710264)
			(xy 316.02978 -121.667884) (xy 315.993293 -121.620334) (xy 315.963326 -121.568428) (xy 315.94039 -121.513055)
			(xy 315.924877 -121.455162) (xy 315.917054 -121.39574) (xy 315.916564 -121.365772) (xy 297.86072 -121.365772)
			(xy 297.86072 -121.367296) (xy 297.86023 -121.397264) (xy 297.852407 -121.456686) (xy 297.836894 -121.514579)
			(xy 297.813958 -121.569952) (xy 297.783991 -121.621858) (xy 297.747504 -121.669408) (xy 297.705124 -121.711788)
			(xy 297.657574 -121.748275) (xy 297.605668 -121.778242) (xy 297.550295 -121.801178) (xy 297.492402 -121.816691)
			(xy 297.43298 -121.824514) (xy 297.373044 -121.824514) (xy 297.313622 -121.816691) (xy 297.255729 -121.801178)
			(xy 297.200356 -121.778242) (xy 297.14845 -121.748275) (xy 297.1009 -121.711788) (xy 297.05852 -121.669408)
			(xy 297.022033 -121.621858) (xy 296.992066 -121.569952) (xy 296.96913 -121.514579) (xy 296.953617 -121.456686)
			(xy 296.945794 -121.397264) (xy 296.945304 -121.367296) (xy 284.900624 -121.367296) (xy 284.900624 -121.886472)
			(xy 284.900134 -121.916456) (xy 284.892306 -121.975912) (xy 284.876785 -122.033837) (xy 284.853836 -122.089241)
			(xy 284.823852 -122.141175) (xy 284.787346 -122.188751) (xy 284.744941 -122.231156) (xy 284.697365 -122.267662)
			(xy 284.645431 -122.297646) (xy 284.590027 -122.320595) (xy 284.532102 -122.336116) (xy 284.472646 -122.343944)
			(xy 284.412678 -122.343944) (xy 284.353222 -122.336116) (xy 284.295297 -122.320595) (xy 284.239893 -122.297646)
			(xy 284.187959 -122.267662) (xy 284.140383 -122.231156) (xy 284.097978 -122.188751) (xy 284.061472 -122.141175)
			(xy 284.031488 -122.089241) (xy 284.008539 -122.033837) (xy 283.993018 -121.975912) (xy 283.98519 -121.916456)
			(xy 283.9847 -121.886472) (xy 270.425672 -121.886472) (xy 270.425672 -121.894346) (xy 270.425182 -121.92433)
			(xy 270.417354 -121.983786) (xy 270.401833 -122.041711) (xy 270.378884 -122.097115) (xy 270.3489 -122.149049)
			(xy 270.312394 -122.196625) (xy 270.269989 -122.23903) (xy 270.222413 -122.275536) (xy 270.170479 -122.30552)
			(xy 270.115075 -122.328469) (xy 270.05715 -122.34399) (xy 269.997694 -122.351818) (xy 269.937726 -122.351818)
			(xy 269.87827 -122.34399) (xy 269.820345 -122.328469) (xy 269.764941 -122.30552) (xy 269.713007 -122.275536)
			(xy 269.665431 -122.23903) (xy 269.623026 -122.196625) (xy 269.58652 -122.149049) (xy 269.556536 -122.097115)
			(xy 269.533587 -122.041711) (xy 269.518066 -121.983786) (xy 269.510238 -121.92433) (xy 269.509748 -121.894346)
			(xy 197.851649 -121.894346) (xy 197.886882 -121.914687) (xy 197.934432 -121.951174) (xy 197.976812 -121.993554)
			(xy 198.013299 -122.041104) (xy 198.043266 -122.09301) (xy 198.066202 -122.148383) (xy 198.081715 -122.206276)
			(xy 198.089538 -122.265698) (xy 198.090028 -122.295666) (xy 198.090028 -123.159266) (xy 198.089538 -123.189234)
			(xy 198.081715 -123.248656) (xy 198.066202 -123.306549) (xy 198.043266 -123.361922) (xy 198.013299 -123.413828)
			(xy 197.976812 -123.461378) (xy 197.934432 -123.503758) (xy 197.886882 -123.540245) (xy 197.834976 -123.570212)
			(xy 197.779603 -123.593148) (xy 197.72171 -123.608661) (xy 197.662288 -123.616484) (xy 197.602352 -123.616484)
			(xy 197.54293 -123.608661) (xy 197.485037 -123.593148) (xy 197.429664 -123.570212) (xy 197.377758 -123.540245)
			(xy 197.330208 -123.503758) (xy 197.287828 -123.461378) (xy 197.251341 -123.413828) (xy 197.221374 -123.361922)
			(xy 197.198438 -123.306549) (xy 197.182925 -123.248656) (xy 197.175102 -123.189234) (xy 197.174612 -123.159266)
			(xy 183.615076 -123.159266) (xy 183.615076 -123.16714) (xy 183.614586 -123.197108) (xy 183.606763 -123.25653)
			(xy 183.59125 -123.314423) (xy 183.568314 -123.369796) (xy 183.538347 -123.421702) (xy 183.50186 -123.469252)
			(xy 183.45948 -123.511632) (xy 183.41193 -123.548119) (xy 183.360024 -123.578086) (xy 183.304651 -123.601022)
			(xy 183.246758 -123.616535) (xy 183.187336 -123.624358) (xy 183.1274 -123.624358) (xy 183.067978 -123.616535)
			(xy 183.010085 -123.601022) (xy 182.954712 -123.578086) (xy 182.902806 -123.548119) (xy 182.855256 -123.511632)
			(xy 182.812876 -123.469252) (xy 182.776389 -123.421702) (xy 182.746422 -123.369796) (xy 182.723486 -123.314423)
			(xy 182.707973 -123.25653) (xy 182.70015 -123.197108) (xy 182.69966 -123.16714) (xy 170.65498 -123.16714)
			(xy 170.65498 -123.686316) (xy 170.65449 -123.7163) (xy 170.646662 -123.775756) (xy 170.631141 -123.833681)
			(xy 170.608192 -123.889085) (xy 170.578208 -123.941019) (xy 170.541702 -123.988595) (xy 170.499297 -124.031)
			(xy 170.451721 -124.067506) (xy 170.399787 -124.09749) (xy 170.344383 -124.120439) (xy 170.286458 -124.13596)
			(xy 170.227002 -124.143788) (xy 170.167034 -124.143788) (xy 170.107578 -124.13596) (xy 170.049653 -124.120439)
			(xy 169.994249 -124.09749) (xy 169.942315 -124.067506) (xy 169.894739 -124.031) (xy 169.852334 -123.988595)
			(xy 169.815828 -123.941019) (xy 169.785844 -123.889085) (xy 169.762895 -123.833681) (xy 169.747374 -123.775756)
			(xy 169.739546 -123.7163) (xy 169.739056 -123.686316) (xy 151.68372 -123.686316) (xy 151.68372 -123.68784)
			(xy 151.68323 -123.717824) (xy 151.675402 -123.77728) (xy 151.659881 -123.835205) (xy 151.636932 -123.890609)
			(xy 151.606948 -123.942543) (xy 151.570442 -123.990119) (xy 151.528037 -124.032524) (xy 151.480461 -124.06903)
			(xy 151.428527 -124.099014) (xy 151.373123 -124.121963) (xy 151.315198 -124.137484) (xy 151.255742 -124.145312)
			(xy 151.195774 -124.145312) (xy 151.136318 -124.137484) (xy 151.078393 -124.121963) (xy 151.022989 -124.099014)
			(xy 150.971055 -124.06903) (xy 150.923479 -124.032524) (xy 150.881074 -123.990119) (xy 150.844568 -123.942543)
			(xy 150.814584 -123.890609) (xy 150.791635 -123.835205) (xy 150.776114 -123.77728) (xy 150.768286 -123.717824)
			(xy 150.767796 -123.68784) (xy 84.369615 -123.68784) (xy 84.377099 -123.69094) (xy 84.429033 -123.720924)
			(xy 84.476609 -123.75743) (xy 84.519014 -123.799835) (xy 84.55552 -123.847411) (xy 84.585504 -123.899345)
			(xy 84.608453 -123.954749) (xy 84.623974 -124.012674) (xy 84.631802 -124.07213) (xy 84.632292 -124.102114)
			(xy 84.632292 -124.965714) (xy 84.631802 -124.995698) (xy 84.623974 -125.055154) (xy 84.608453 -125.113079)
			(xy 84.585504 -125.168483) (xy 84.55552 -125.220417) (xy 84.519014 -125.267993) (xy 84.476609 -125.310398)
			(xy 84.429033 -125.346904) (xy 84.377099 -125.376888) (xy 84.321695 -125.399837) (xy 84.26377 -125.415358)
			(xy 84.204314 -125.423186) (xy 84.144346 -125.423186) (xy 84.08489 -125.415358) (xy 84.026965 -125.399837)
			(xy 83.971561 -125.376888) (xy 83.919627 -125.346904) (xy 83.872051 -125.310398) (xy 83.829646 -125.267993)
			(xy 83.79314 -125.220417) (xy 83.763156 -125.168483) (xy 83.740207 -125.113079) (xy 83.724686 -125.055154)
			(xy 83.716858 -124.995698) (xy 83.716368 -124.965714) (xy 65.661032 -124.965714) (xy 65.661032 -124.967238)
			(xy 65.660542 -124.997222) (xy 65.652714 -125.056678) (xy 65.637193 -125.114603) (xy 65.614244 -125.170007)
			(xy 65.58426 -125.221941) (xy 65.547754 -125.269517) (xy 65.505349 -125.311922) (xy 65.457773 -125.348428)
			(xy 65.405839 -125.378412) (xy 65.350435 -125.401361) (xy 65.29251 -125.416882) (xy 65.233054 -125.42471)
			(xy 65.173086 -125.42471) (xy 65.11363 -125.416882) (xy 65.055705 -125.401361) (xy 65.000301 -125.378412)
			(xy 64.948367 -125.348428) (xy 64.900791 -125.311922) (xy 64.858386 -125.269517) (xy 64.82188 -125.221941)
			(xy 64.791896 -125.170007) (xy 64.768947 -125.114603) (xy 64.753426 -125.056678) (xy 64.745598 -124.997222)
			(xy 64.745108 -124.967238) (xy 52.700428 -124.967238) (xy 52.700428 -125.486414) (xy 52.700295 -125.494542)
			(xy 153.409904 -125.494542) (xy 153.409904 -124.630942) (xy 153.410394 -124.600958) (xy 153.418222 -124.541502)
			(xy 153.433743 -124.483577) (xy 153.456692 -124.428173) (xy 153.486676 -124.376239) (xy 153.523182 -124.328663)
			(xy 153.565587 -124.286258) (xy 153.613163 -124.249752) (xy 153.665097 -124.219768) (xy 153.720501 -124.196819)
			(xy 153.778426 -124.181298) (xy 153.837882 -124.17347) (xy 153.89785 -124.17347) (xy 153.957306 -124.181298)
			(xy 154.015231 -124.196819) (xy 154.070635 -124.219768) (xy 154.122569 -124.249752) (xy 154.170145 -124.286258)
			(xy 154.21255 -124.328663) (xy 154.249056 -124.376239) (xy 154.27904 -124.428173) (xy 154.301989 -124.483577)
			(xy 154.31751 -124.541502) (xy 154.325338 -124.600958) (xy 154.325828 -124.630942) (xy 154.325828 -125.486414)
			(xy 167.884856 -125.486414) (xy 167.884856 -124.622814) (xy 167.885346 -124.59283) (xy 167.893174 -124.533374)
			(xy 167.908695 -124.475449) (xy 167.931644 -124.420045) (xy 167.961628 -124.368111) (xy 167.998134 -124.320535)
			(xy 168.040539 -124.27813) (xy 168.088115 -124.241624) (xy 168.140049 -124.21164) (xy 168.195453 -124.188691)
			(xy 168.253378 -124.17317) (xy 168.312834 -124.165342) (xy 168.372802 -124.165342) (xy 168.432258 -124.17317)
			(xy 168.490183 -124.188691) (xy 168.545587 -124.21164) (xy 168.597521 -124.241624) (xy 168.645097 -124.27813)
			(xy 168.687502 -124.320535) (xy 168.724008 -124.368111) (xy 168.753992 -124.420045) (xy 168.776941 -124.475449)
			(xy 168.792462 -124.533374) (xy 168.80029 -124.59283) (xy 168.80078 -124.622814) (xy 168.80078 -124.967238)
			(xy 180.84546 -124.967238) (xy 180.84546 -124.103638) (xy 180.84595 -124.07367) (xy 180.853773 -124.014248)
			(xy 180.869286 -123.956355) (xy 180.892222 -123.900982) (xy 180.922189 -123.849076) (xy 180.958676 -123.801526)
			(xy 181.001056 -123.759146) (xy 181.048606 -123.722659) (xy 181.100512 -123.692692) (xy 181.155885 -123.669756)
			(xy 181.213778 -123.654243) (xy 181.2732 -123.64642) (xy 181.333136 -123.64642) (xy 181.392558 -123.654243)
			(xy 181.450451 -123.669756) (xy 181.505824 -123.692692) (xy 181.55773 -123.722659) (xy 181.60528 -123.759146)
			(xy 181.64766 -123.801526) (xy 181.684147 -123.849076) (xy 181.714114 -123.900982) (xy 181.73705 -123.956355)
			(xy 181.752563 -124.014248) (xy 181.760386 -124.07367) (xy 181.760876 -124.103638) (xy 181.760876 -124.965714)
			(xy 199.81672 -124.965714) (xy 199.81672 -124.102114) (xy 199.81721 -124.072146) (xy 199.825033 -124.012724)
			(xy 199.840546 -123.954831) (xy 199.863482 -123.899458) (xy 199.893449 -123.847552) (xy 199.929936 -123.800002)
			(xy 199.972316 -123.757622) (xy 200.019866 -123.721135) (xy 200.071772 -123.691168) (xy 200.127145 -123.668232)
			(xy 200.185038 -123.652719) (xy 200.24446 -123.644896) (xy 200.304396 -123.644896) (xy 200.363818 -123.652719)
			(xy 200.421711 -123.668232) (xy 200.469049 -123.68784) (xy 266.86764 -123.68784) (xy 266.86764 -122.82424)
			(xy 266.86813 -122.794256) (xy 266.875958 -122.7348) (xy 266.891479 -122.676875) (xy 266.914428 -122.621471)
			(xy 266.944412 -122.569537) (xy 266.980918 -122.521961) (xy 267.023323 -122.479556) (xy 267.070899 -122.44305)
			(xy 267.122833 -122.413066) (xy 267.178237 -122.390117) (xy 267.236162 -122.374596) (xy 267.295618 -122.366768)
			(xy 267.355586 -122.366768) (xy 267.415042 -122.374596) (xy 267.472967 -122.390117) (xy 267.528371 -122.413066)
			(xy 267.580305 -122.44305) (xy 267.627881 -122.479556) (xy 267.670286 -122.521961) (xy 267.706792 -122.569537)
			(xy 267.736776 -122.621471) (xy 267.759725 -122.676875) (xy 267.775246 -122.7348) (xy 267.783074 -122.794256)
			(xy 267.783564 -122.82424) (xy 267.783564 -123.686316) (xy 285.8389 -123.686316) (xy 285.8389 -122.822716)
			(xy 285.83939 -122.792732) (xy 285.847218 -122.733276) (xy 285.862739 -122.675351) (xy 285.885688 -122.619947)
			(xy 285.915672 -122.568013) (xy 285.952178 -122.520437) (xy 285.994583 -122.478032) (xy 286.042159 -122.441526)
			(xy 286.094093 -122.411542) (xy 286.149497 -122.388593) (xy 286.207422 -122.373072) (xy 286.266878 -122.365244)
			(xy 286.326846 -122.365244) (xy 286.386302 -122.373072) (xy 286.444227 -122.388593) (xy 286.499631 -122.411542)
			(xy 286.551565 -122.441526) (xy 286.599141 -122.478032) (xy 286.641546 -122.520437) (xy 286.678052 -122.568013)
			(xy 286.708036 -122.619947) (xy 286.730985 -122.675351) (xy 286.746506 -122.733276) (xy 286.754334 -122.792732)
			(xy 286.754824 -122.822716) (xy 286.754824 -123.16714) (xy 298.799504 -123.16714) (xy 298.799504 -122.30354)
			(xy 298.799994 -122.273572) (xy 298.807817 -122.21415) (xy 298.82333 -122.156257) (xy 298.846266 -122.100884)
			(xy 298.876233 -122.048978) (xy 298.91272 -122.001428) (xy 298.9551 -121.959048) (xy 299.00265 -121.922561)
			(xy 299.054556 -121.892594) (xy 299.109929 -121.869658) (xy 299.167822 -121.854145) (xy 299.227244 -121.846322)
			(xy 299.28718 -121.846322) (xy 299.346602 -121.854145) (xy 299.404495 -121.869658) (xy 299.459868 -121.892594)
			(xy 299.511774 -121.922561) (xy 299.559324 -121.959048) (xy 299.601704 -122.001428) (xy 299.638191 -122.048978)
			(xy 299.668158 -122.100884) (xy 299.691094 -122.156257) (xy 299.706607 -122.21415) (xy 299.71443 -122.273572)
			(xy 299.71492 -122.30354) (xy 299.71492 -123.159266) (xy 313.274456 -123.159266) (xy 313.274456 -122.295666)
			(xy 313.274946 -122.265698) (xy 313.282769 -122.206276) (xy 313.298282 -122.148383) (xy 313.321218 -122.09301)
			(xy 313.351185 -122.041104) (xy 313.387672 -121.993554) (xy 313.430052 -121.951174) (xy 313.477602 -121.914687)
			(xy 313.529508 -121.88472) (xy 313.584881 -121.861784) (xy 313.642774 -121.846271) (xy 313.702196 -121.838448)
			(xy 313.762132 -121.838448) (xy 313.821554 -121.846271) (xy 313.879447 -121.861784) (xy 313.93482 -121.88472)
			(xy 313.951493 -121.894346) (xy 385.6101 -121.894346) (xy 385.6101 -121.030746) (xy 385.61059 -121.000778)
			(xy 385.618413 -120.941356) (xy 385.633926 -120.883463) (xy 385.656862 -120.82809) (xy 385.686829 -120.776184)
			(xy 385.723316 -120.728634) (xy 385.765696 -120.686254) (xy 385.813246 -120.649767) (xy 385.865152 -120.6198)
			(xy 385.920525 -120.596864) (xy 385.978418 -120.581351) (xy 386.03784 -120.573528) (xy 386.097776 -120.573528)
			(xy 386.157198 -120.581351) (xy 386.215091 -120.596864) (xy 386.270464 -120.6198) (xy 386.32237 -120.649767)
			(xy 386.36992 -120.686254) (xy 386.4123 -120.728634) (xy 386.448787 -120.776184) (xy 386.478754 -120.82809)
			(xy 386.50169 -120.883463) (xy 386.517203 -120.941356) (xy 386.525026 -121.000778) (xy 386.525516 -121.030746)
			(xy 386.525516 -121.886472) (xy 400.085052 -121.886472) (xy 400.085052 -121.022872) (xy 400.085542 -120.992904)
			(xy 400.093365 -120.933482) (xy 400.108878 -120.875589) (xy 400.131814 -120.820216) (xy 400.161781 -120.76831)
			(xy 400.198268 -120.72076) (xy 400.240648 -120.67838) (xy 400.288198 -120.641893) (xy 400.340104 -120.611926)
			(xy 400.395477 -120.58899) (xy 400.45337 -120.573477) (xy 400.512792 -120.565654) (xy 400.572728 -120.565654)
			(xy 400.63215 -120.573477) (xy 400.690043 -120.58899) (xy 400.745416 -120.611926) (xy 400.797322 -120.641893)
			(xy 400.844872 -120.67838) (xy 400.887252 -120.72076) (xy 400.923739 -120.76831) (xy 400.953706 -120.820216)
			(xy 400.976642 -120.875589) (xy 400.992155 -120.933482) (xy 400.999978 -120.992904) (xy 401.000468 -121.022872)
			(xy 401.000468 -121.367296) (xy 413.045148 -121.367296) (xy 413.045148 -120.503696) (xy 413.045638 -120.473712)
			(xy 413.053466 -120.414256) (xy 413.068987 -120.356331) (xy 413.091936 -120.300927) (xy 413.12192 -120.248993)
			(xy 413.158426 -120.201417) (xy 413.200831 -120.159012) (xy 413.248407 -120.122506) (xy 413.300341 -120.092522)
			(xy 413.355745 -120.069573) (xy 413.41367 -120.054052) (xy 413.473126 -120.046224) (xy 413.533094 -120.046224)
			(xy 413.59255 -120.054052) (xy 413.650475 -120.069573) (xy 413.705879 -120.092522) (xy 413.757813 -120.122506)
			(xy 413.805389 -120.159012) (xy 413.847794 -120.201417) (xy 413.8843 -120.248993) (xy 413.914284 -120.300927)
			(xy 413.937233 -120.356331) (xy 413.952754 -120.414256) (xy 413.960582 -120.473712) (xy 413.961072 -120.503696)
			(xy 413.961072 -121.365772) (xy 432.016408 -121.365772) (xy 432.016408 -120.502172) (xy 432.016898 -120.472188)
			(xy 432.024726 -120.412732) (xy 432.040247 -120.354807) (xy 432.063196 -120.299403) (xy 432.09318 -120.247469)
			(xy 432.129686 -120.199893) (xy 432.172091 -120.157488) (xy 432.219667 -120.120982) (xy 432.271601 -120.090998)
			(xy 432.327005 -120.068049) (xy 432.38493 -120.052528) (xy 432.444386 -120.0447) (xy 432.504354 -120.0447)
			(xy 432.56381 -120.052528) (xy 432.621735 -120.068049) (xy 432.677139 -120.090998) (xy 432.729073 -120.120982)
			(xy 432.776649 -120.157488) (xy 432.819054 -120.199893) (xy 432.85556 -120.247469) (xy 432.885544 -120.299403)
			(xy 432.908493 -120.354807) (xy 432.924014 -120.412732) (xy 432.931842 -120.472188) (xy 432.932332 -120.502172)
			(xy 432.932332 -121.365772) (xy 432.931842 -121.395756) (xy 432.924014 -121.455212) (xy 432.908493 -121.513137)
			(xy 432.885544 -121.568541) (xy 432.85556 -121.620475) (xy 432.819054 -121.668051) (xy 432.776649 -121.710456)
			(xy 432.729073 -121.746962) (xy 432.677139 -121.776946) (xy 432.621735 -121.799895) (xy 432.56381 -121.815416)
			(xy 432.504354 -121.823244) (xy 432.444386 -121.823244) (xy 432.38493 -121.815416) (xy 432.327005 -121.799895)
			(xy 432.271601 -121.776946) (xy 432.219667 -121.746962) (xy 432.172091 -121.710456) (xy 432.129686 -121.668051)
			(xy 432.09318 -121.620475) (xy 432.063196 -121.568541) (xy 432.040247 -121.513137) (xy 432.024726 -121.455212)
			(xy 432.016898 -121.395756) (xy 432.016408 -121.365772) (xy 413.961072 -121.365772) (xy 413.961072 -121.367296)
			(xy 413.960582 -121.39728) (xy 413.952754 -121.456736) (xy 413.937233 -121.514661) (xy 413.914284 -121.570065)
			(xy 413.8843 -121.621999) (xy 413.847794 -121.669575) (xy 413.805389 -121.71198) (xy 413.757813 -121.748486)
			(xy 413.705879 -121.77847) (xy 413.650475 -121.801419) (xy 413.59255 -121.81694) (xy 413.533094 -121.824768)
			(xy 413.473126 -121.824768) (xy 413.41367 -121.81694) (xy 413.355745 -121.801419) (xy 413.300341 -121.77847)
			(xy 413.248407 -121.748486) (xy 413.200831 -121.71198) (xy 413.158426 -121.669575) (xy 413.12192 -121.621999)
			(xy 413.091936 -121.570065) (xy 413.068987 -121.514661) (xy 413.053466 -121.456736) (xy 413.045638 -121.39728)
			(xy 413.045148 -121.367296) (xy 401.000468 -121.367296) (xy 401.000468 -121.886472) (xy 400.999978 -121.91644)
			(xy 400.992155 -121.975862) (xy 400.976642 -122.033755) (xy 400.953706 -122.089128) (xy 400.923739 -122.141034)
			(xy 400.887252 -122.188584) (xy 400.844872 -122.230964) (xy 400.797322 -122.267451) (xy 400.745416 -122.297418)
			(xy 400.690043 -122.320354) (xy 400.63215 -122.335867) (xy 400.572728 -122.34369) (xy 400.512792 -122.34369)
			(xy 400.45337 -122.335867) (xy 400.395477 -122.320354) (xy 400.340104 -122.297418) (xy 400.288198 -122.267451)
			(xy 400.240648 -122.230964) (xy 400.198268 -122.188584) (xy 400.161781 -122.141034) (xy 400.131814 -122.089128)
			(xy 400.108878 -122.033755) (xy 400.093365 -121.975862) (xy 400.085542 -121.91644) (xy 400.085052 -121.886472)
			(xy 386.525516 -121.886472) (xy 386.525516 -121.894346) (xy 386.525026 -121.924314) (xy 386.517203 -121.983736)
			(xy 386.50169 -122.041629) (xy 386.478754 -122.097002) (xy 386.448787 -122.148908) (xy 386.4123 -122.196458)
			(xy 386.36992 -122.238838) (xy 386.32237 -122.275325) (xy 386.270464 -122.305292) (xy 386.215091 -122.328228)
			(xy 386.157198 -122.343741) (xy 386.097776 -122.351564) (xy 386.03784 -122.351564) (xy 385.978418 -122.343741)
			(xy 385.920525 -122.328228) (xy 385.865152 -122.305292) (xy 385.813246 -122.275325) (xy 385.765696 -122.238838)
			(xy 385.723316 -122.196458) (xy 385.686829 -122.148908) (xy 385.656862 -122.097002) (xy 385.633926 -122.041629)
			(xy 385.618413 -121.983736) (xy 385.61059 -121.924314) (xy 385.6101 -121.894346) (xy 313.951493 -121.894346)
			(xy 313.986726 -121.914687) (xy 314.034276 -121.951174) (xy 314.076656 -121.993554) (xy 314.113143 -122.041104)
			(xy 314.14311 -122.09301) (xy 314.166046 -122.148383) (xy 314.181559 -122.206276) (xy 314.189382 -122.265698)
			(xy 314.189872 -122.295666) (xy 314.189872 -123.159266) (xy 314.189382 -123.189234) (xy 314.181559 -123.248656)
			(xy 314.166046 -123.306549) (xy 314.14311 -123.361922) (xy 314.113143 -123.413828) (xy 314.076656 -123.461378)
			(xy 314.034276 -123.503758) (xy 313.986726 -123.540245) (xy 313.93482 -123.570212) (xy 313.879447 -123.593148)
			(xy 313.821554 -123.608661) (xy 313.762132 -123.616484) (xy 313.702196 -123.616484) (xy 313.642774 -123.608661)
			(xy 313.584881 -123.593148) (xy 313.529508 -123.570212) (xy 313.477602 -123.540245) (xy 313.430052 -123.503758)
			(xy 313.387672 -123.461378) (xy 313.351185 -123.413828) (xy 313.321218 -123.361922) (xy 313.298282 -123.306549)
			(xy 313.282769 -123.248656) (xy 313.274946 -123.189234) (xy 313.274456 -123.159266) (xy 299.71492 -123.159266)
			(xy 299.71492 -123.16714) (xy 299.71443 -123.197108) (xy 299.706607 -123.25653) (xy 299.691094 -123.314423)
			(xy 299.668158 -123.369796) (xy 299.638191 -123.421702) (xy 299.601704 -123.469252) (xy 299.559324 -123.511632)
			(xy 299.511774 -123.548119) (xy 299.459868 -123.578086) (xy 299.404495 -123.601022) (xy 299.346602 -123.616535)
			(xy 299.28718 -123.624358) (xy 299.227244 -123.624358) (xy 299.167822 -123.616535) (xy 299.109929 -123.601022)
			(xy 299.054556 -123.578086) (xy 299.00265 -123.548119) (xy 298.9551 -123.511632) (xy 298.91272 -123.469252)
			(xy 298.876233 -123.421702) (xy 298.846266 -123.369796) (xy 298.82333 -123.314423) (xy 298.807817 -123.25653)
			(xy 298.799994 -123.197108) (xy 298.799504 -123.16714) (xy 286.754824 -123.16714) (xy 286.754824 -123.686316)
			(xy 286.754334 -123.7163) (xy 286.746506 -123.775756) (xy 286.730985 -123.833681) (xy 286.708036 -123.889085)
			(xy 286.678052 -123.941019) (xy 286.641546 -123.988595) (xy 286.599141 -124.031) (xy 286.551565 -124.067506)
			(xy 286.499631 -124.09749) (xy 286.444227 -124.120439) (xy 286.386302 -124.13596) (xy 286.326846 -124.143788)
			(xy 286.266878 -124.143788) (xy 286.207422 -124.13596) (xy 286.149497 -124.120439) (xy 286.094093 -124.09749)
			(xy 286.042159 -124.067506) (xy 285.994583 -124.031) (xy 285.952178 -123.988595) (xy 285.915672 -123.941019)
			(xy 285.885688 -123.889085) (xy 285.862739 -123.833681) (xy 285.847218 -123.775756) (xy 285.83939 -123.7163)
			(xy 285.8389 -123.686316) (xy 267.783564 -123.686316) (xy 267.783564 -123.68784) (xy 267.783074 -123.717824)
			(xy 267.775246 -123.77728) (xy 267.759725 -123.835205) (xy 267.736776 -123.890609) (xy 267.706792 -123.942543)
			(xy 267.670286 -123.990119) (xy 267.627881 -124.032524) (xy 267.580305 -124.06903) (xy 267.528371 -124.099014)
			(xy 267.472967 -124.121963) (xy 267.415042 -124.137484) (xy 267.355586 -124.145312) (xy 267.295618 -124.145312)
			(xy 267.236162 -124.137484) (xy 267.178237 -124.121963) (xy 267.122833 -124.099014) (xy 267.070899 -124.06903)
			(xy 267.023323 -124.032524) (xy 266.980918 -123.990119) (xy 266.944412 -123.942543) (xy 266.914428 -123.890609)
			(xy 266.891479 -123.835205) (xy 266.875958 -123.77728) (xy 266.86813 -123.717824) (xy 266.86764 -123.68784)
			(xy 200.469049 -123.68784) (xy 200.477084 -123.691168) (xy 200.52899 -123.721135) (xy 200.57654 -123.757622)
			(xy 200.61892 -123.800002) (xy 200.655407 -123.847552) (xy 200.685374 -123.899458) (xy 200.70831 -123.954831)
			(xy 200.723823 -124.012724) (xy 200.731646 -124.072146) (xy 200.732136 -124.102114) (xy 200.732136 -124.965714)
			(xy 200.731646 -124.995682) (xy 200.723823 -125.055104) (xy 200.70831 -125.112997) (xy 200.685374 -125.16837)
			(xy 200.655407 -125.220276) (xy 200.61892 -125.267826) (xy 200.57654 -125.310206) (xy 200.52899 -125.346693)
			(xy 200.477084 -125.37666) (xy 200.421711 -125.399596) (xy 200.363818 -125.415109) (xy 200.304396 -125.422932)
			(xy 200.24446 -125.422932) (xy 200.185038 -125.415109) (xy 200.127145 -125.399596) (xy 200.071772 -125.37666)
			(xy 200.019866 -125.346693) (xy 199.972316 -125.310206) (xy 199.929936 -125.267826) (xy 199.893449 -125.220276)
			(xy 199.863482 -125.16837) (xy 199.840546 -125.112997) (xy 199.825033 -125.055104) (xy 199.81721 -124.995682)
			(xy 199.81672 -124.965714) (xy 181.760876 -124.965714) (xy 181.760876 -124.967238) (xy 181.760386 -124.997206)
			(xy 181.752563 -125.056628) (xy 181.73705 -125.114521) (xy 181.714114 -125.169894) (xy 181.684147 -125.2218)
			(xy 181.64766 -125.26935) (xy 181.60528 -125.31173) (xy 181.55773 -125.348217) (xy 181.505824 -125.378184)
			(xy 181.450451 -125.40112) (xy 181.392558 -125.416633) (xy 181.333136 -125.424456) (xy 181.2732 -125.424456)
			(xy 181.213778 -125.416633) (xy 181.155885 -125.40112) (xy 181.100512 -125.378184) (xy 181.048606 -125.348217)
			(xy 181.001056 -125.31173) (xy 180.958676 -125.26935) (xy 180.922189 -125.2218) (xy 180.892222 -125.169894)
			(xy 180.869286 -125.114521) (xy 180.853773 -125.056628) (xy 180.84595 -124.997206) (xy 180.84546 -124.967238)
			(xy 168.80078 -124.967238) (xy 168.80078 -125.486414) (xy 168.800647 -125.494542) (xy 269.509748 -125.494542)
			(xy 269.509748 -124.630942) (xy 269.510238 -124.600958) (xy 269.518066 -124.541502) (xy 269.533587 -124.483577)
			(xy 269.556536 -124.428173) (xy 269.58652 -124.376239) (xy 269.623026 -124.328663) (xy 269.665431 -124.286258)
			(xy 269.713007 -124.249752) (xy 269.764941 -124.219768) (xy 269.820345 -124.196819) (xy 269.87827 -124.181298)
			(xy 269.937726 -124.17347) (xy 269.997694 -124.17347) (xy 270.05715 -124.181298) (xy 270.115075 -124.196819)
			(xy 270.170479 -124.219768) (xy 270.222413 -124.249752) (xy 270.269989 -124.286258) (xy 270.312394 -124.328663)
			(xy 270.3489 -124.376239) (xy 270.378884 -124.428173) (xy 270.401833 -124.483577) (xy 270.417354 -124.541502)
			(xy 270.425182 -124.600958) (xy 270.425672 -124.630942) (xy 270.425672 -125.486414) (xy 283.9847 -125.486414)
			(xy 283.9847 -124.622814) (xy 283.98519 -124.59283) (xy 283.993018 -124.533374) (xy 284.008539 -124.475449)
			(xy 284.031488 -124.420045) (xy 284.061472 -124.368111) (xy 284.097978 -124.320535) (xy 284.140383 -124.27813)
			(xy 284.187959 -124.241624) (xy 284.239893 -124.21164) (xy 284.295297 -124.188691) (xy 284.353222 -124.17317)
			(xy 284.412678 -124.165342) (xy 284.472646 -124.165342) (xy 284.532102 -124.17317) (xy 284.590027 -124.188691)
			(xy 284.645431 -124.21164) (xy 284.697365 -124.241624) (xy 284.744941 -124.27813) (xy 284.787346 -124.320535)
			(xy 284.823852 -124.368111) (xy 284.853836 -124.420045) (xy 284.876785 -124.475449) (xy 284.892306 -124.533374)
			(xy 284.900134 -124.59283) (xy 284.900624 -124.622814) (xy 284.900624 -124.967238) (xy 296.945304 -124.967238)
			(xy 296.945304 -124.103638) (xy 296.945794 -124.07367) (xy 296.953617 -124.014248) (xy 296.96913 -123.956355)
			(xy 296.992066 -123.900982) (xy 297.022033 -123.849076) (xy 297.05852 -123.801526) (xy 297.1009 -123.759146)
			(xy 297.14845 -123.722659) (xy 297.200356 -123.692692) (xy 297.255729 -123.669756) (xy 297.313622 -123.654243)
			(xy 297.373044 -123.64642) (xy 297.43298 -123.64642) (xy 297.492402 -123.654243) (xy 297.550295 -123.669756)
			(xy 297.605668 -123.692692) (xy 297.657574 -123.722659) (xy 297.705124 -123.759146) (xy 297.747504 -123.801526)
			(xy 297.783991 -123.849076) (xy 297.813958 -123.900982) (xy 297.836894 -123.956355) (xy 297.852407 -124.014248)
			(xy 297.86023 -124.07367) (xy 297.86072 -124.103638) (xy 297.86072 -124.965714) (xy 315.916564 -124.965714)
			(xy 315.916564 -124.102114) (xy 315.917054 -124.072146) (xy 315.924877 -124.012724) (xy 315.94039 -123.954831)
			(xy 315.963326 -123.899458) (xy 315.993293 -123.847552) (xy 316.02978 -123.800002) (xy 316.07216 -123.757622)
			(xy 316.11971 -123.721135) (xy 316.171616 -123.691168) (xy 316.226989 -123.668232) (xy 316.284882 -123.652719)
			(xy 316.344304 -123.644896) (xy 316.40424 -123.644896) (xy 316.463662 -123.652719) (xy 316.521555 -123.668232)
			(xy 316.568893 -123.68784) (xy 382.967992 -123.68784) (xy 382.967992 -122.82424) (xy 382.968482 -122.794272)
			(xy 382.976305 -122.73485) (xy 382.991818 -122.676957) (xy 383.014754 -122.621584) (xy 383.044721 -122.569678)
			(xy 383.081208 -122.522128) (xy 383.123588 -122.479748) (xy 383.171138 -122.443261) (xy 383.223044 -122.413294)
			(xy 383.278417 -122.390358) (xy 383.33631 -122.374845) (xy 383.395732 -122.367022) (xy 383.455668 -122.367022)
			(xy 383.51509 -122.374845) (xy 383.572983 -122.390358) (xy 383.628356 -122.413294) (xy 383.680262 -122.443261)
			(xy 383.727812 -122.479748) (xy 383.770192 -122.522128) (xy 383.806679 -122.569678) (xy 383.836646 -122.621584)
			(xy 383.859582 -122.676957) (xy 383.875095 -122.73485) (xy 383.882918 -122.794272) (xy 383.883408 -122.82424)
			(xy 383.883408 -123.686316) (xy 401.939252 -123.686316) (xy 401.939252 -122.822716) (xy 401.939742 -122.792748)
			(xy 401.947565 -122.733326) (xy 401.963078 -122.675433) (xy 401.986014 -122.62006) (xy 402.015981 -122.568154)
			(xy 402.052468 -122.520604) (xy 402.094848 -122.478224) (xy 402.142398 -122.441737) (xy 402.194304 -122.41177)
			(xy 402.249677 -122.388834) (xy 402.30757 -122.373321) (xy 402.366992 -122.365498) (xy 402.426928 -122.365498)
			(xy 402.48635 -122.373321) (xy 402.544243 -122.388834) (xy 402.599616 -122.41177) (xy 402.651522 -122.441737)
			(xy 402.699072 -122.478224) (xy 402.741452 -122.520604) (xy 402.777939 -122.568154) (xy 402.807906 -122.62006)
			(xy 402.830842 -122.675433) (xy 402.846355 -122.733326) (xy 402.854178 -122.792748) (xy 402.854668 -122.822716)
			(xy 402.854668 -123.16714) (xy 414.899348 -123.16714) (xy 414.899348 -122.30354) (xy 414.899838 -122.273556)
			(xy 414.907666 -122.2141) (xy 414.923187 -122.156175) (xy 414.946136 -122.100771) (xy 414.97612 -122.048837)
			(xy 415.012626 -122.001261) (xy 415.055031 -121.958856) (xy 415.102607 -121.92235) (xy 415.154541 -121.892366)
			(xy 415.209945 -121.869417) (xy 415.26787 -121.853896) (xy 415.327326 -121.846068) (xy 415.387294 -121.846068)
			(xy 415.44675 -121.853896) (xy 415.504675 -121.869417) (xy 415.560079 -121.892366) (xy 415.612013 -121.92235)
			(xy 415.659589 -121.958856) (xy 415.701994 -122.001261) (xy 415.7385 -122.048837) (xy 415.768484 -122.100771)
			(xy 415.791433 -122.156175) (xy 415.806954 -122.2141) (xy 415.814782 -122.273556) (xy 415.815272 -122.30354)
			(xy 415.815272 -123.159266) (xy 429.3743 -123.159266) (xy 429.3743 -122.295666) (xy 429.37479 -122.265682)
			(xy 429.382618 -122.206226) (xy 429.398139 -122.148301) (xy 429.421088 -122.092897) (xy 429.451072 -122.040963)
			(xy 429.487578 -121.993387) (xy 429.529983 -121.950982) (xy 429.577559 -121.914476) (xy 429.629493 -121.884492)
			(xy 429.684897 -121.861543) (xy 429.742822 -121.846022) (xy 429.802278 -121.838194) (xy 429.862246 -121.838194)
			(xy 429.921702 -121.846022) (xy 429.979627 -121.861543) (xy 430.035031 -121.884492) (xy 430.086965 -121.914476)
			(xy 430.134541 -121.950982) (xy 430.176946 -121.993387) (xy 430.213452 -122.040963) (xy 430.243436 -122.092897)
			(xy 430.266385 -122.148301) (xy 430.281906 -122.206226) (xy 430.289734 -122.265682) (xy 430.290224 -122.295666)
			(xy 430.290224 -123.159266) (xy 430.289734 -123.18925) (xy 430.281906 -123.248706) (xy 430.266385 -123.306631)
			(xy 430.243436 -123.362035) (xy 430.213452 -123.413969) (xy 430.176946 -123.461545) (xy 430.134541 -123.50395)
			(xy 430.086965 -123.540456) (xy 430.035031 -123.57044) (xy 429.979627 -123.593389) (xy 429.921702 -123.60891)
			(xy 429.862246 -123.616738) (xy 429.802278 -123.616738) (xy 429.742822 -123.60891) (xy 429.684897 -123.593389)
			(xy 429.629493 -123.57044) (xy 429.577559 -123.540456) (xy 429.529983 -123.50395) (xy 429.487578 -123.461545)
			(xy 429.451072 -123.413969) (xy 429.421088 -123.362035) (xy 429.398139 -123.306631) (xy 429.382618 -123.248706)
			(xy 429.37479 -123.18925) (xy 429.3743 -123.159266) (xy 415.815272 -123.159266) (xy 415.815272 -123.16714)
			(xy 415.814782 -123.197124) (xy 415.806954 -123.25658) (xy 415.791433 -123.314505) (xy 415.768484 -123.369909)
			(xy 415.7385 -123.421843) (xy 415.701994 -123.469419) (xy 415.659589 -123.511824) (xy 415.612013 -123.54833)
			(xy 415.560079 -123.578314) (xy 415.504675 -123.601263) (xy 415.44675 -123.616784) (xy 415.387294 -123.624612)
			(xy 415.327326 -123.624612) (xy 415.26787 -123.616784) (xy 415.209945 -123.601263) (xy 415.154541 -123.578314)
			(xy 415.102607 -123.54833) (xy 415.055031 -123.511824) (xy 415.012626 -123.469419) (xy 414.97612 -123.421843)
			(xy 414.946136 -123.369909) (xy 414.923187 -123.314505) (xy 414.907666 -123.25658) (xy 414.899838 -123.197124)
			(xy 414.899348 -123.16714) (xy 402.854668 -123.16714) (xy 402.854668 -123.686316) (xy 402.854178 -123.716284)
			(xy 402.846355 -123.775706) (xy 402.830842 -123.833599) (xy 402.807906 -123.888972) (xy 402.777939 -123.940878)
			(xy 402.741452 -123.988428) (xy 402.699072 -124.030808) (xy 402.651522 -124.067295) (xy 402.599616 -124.097262)
			(xy 402.544243 -124.120198) (xy 402.48635 -124.135711) (xy 402.426928 -124.143534) (xy 402.366992 -124.143534)
			(xy 402.30757 -124.135711) (xy 402.249677 -124.120198) (xy 402.194304 -124.097262) (xy 402.142398 -124.067295)
			(xy 402.094848 -124.030808) (xy 402.052468 -123.988428) (xy 402.015981 -123.940878) (xy 401.986014 -123.888972)
			(xy 401.963078 -123.833599) (xy 401.947565 -123.775706) (xy 401.939742 -123.716284) (xy 401.939252 -123.686316)
			(xy 383.883408 -123.686316) (xy 383.883408 -123.68784) (xy 383.882918 -123.717808) (xy 383.875095 -123.77723)
			(xy 383.859582 -123.835123) (xy 383.836646 -123.890496) (xy 383.806679 -123.942402) (xy 383.770192 -123.989952)
			(xy 383.727812 -124.032332) (xy 383.680262 -124.068819) (xy 383.628356 -124.098786) (xy 383.572983 -124.121722)
			(xy 383.51509 -124.137235) (xy 383.455668 -124.145058) (xy 383.395732 -124.145058) (xy 383.33631 -124.137235)
			(xy 383.278417 -124.121722) (xy 383.223044 -124.098786) (xy 383.171138 -124.068819) (xy 383.123588 -124.032332)
			(xy 383.081208 -123.989952) (xy 383.044721 -123.942402) (xy 383.014754 -123.890496) (xy 382.991818 -123.835123)
			(xy 382.976305 -123.77723) (xy 382.968482 -123.717808) (xy 382.967992 -123.68784) (xy 316.568893 -123.68784)
			(xy 316.576928 -123.691168) (xy 316.628834 -123.721135) (xy 316.676384 -123.757622) (xy 316.718764 -123.800002)
			(xy 316.755251 -123.847552) (xy 316.785218 -123.899458) (xy 316.808154 -123.954831) (xy 316.823667 -124.012724)
			(xy 316.83149 -124.072146) (xy 316.83198 -124.102114) (xy 316.83198 -124.965714) (xy 316.83149 -124.995682)
			(xy 316.823667 -125.055104) (xy 316.808154 -125.112997) (xy 316.785218 -125.16837) (xy 316.755251 -125.220276)
			(xy 316.718764 -125.267826) (xy 316.676384 -125.310206) (xy 316.628834 -125.346693) (xy 316.576928 -125.37666)
			(xy 316.521555 -125.399596) (xy 316.463662 -125.415109) (xy 316.40424 -125.422932) (xy 316.344304 -125.422932)
			(xy 316.284882 -125.415109) (xy 316.226989 -125.399596) (xy 316.171616 -125.37666) (xy 316.11971 -125.346693)
			(xy 316.07216 -125.310206) (xy 316.02978 -125.267826) (xy 315.993293 -125.220276) (xy 315.963326 -125.16837)
			(xy 315.94039 -125.112997) (xy 315.924877 -125.055104) (xy 315.917054 -124.995682) (xy 315.916564 -124.965714)
			(xy 297.86072 -124.965714) (xy 297.86072 -124.967238) (xy 297.86023 -124.997206) (xy 297.852407 -125.056628)
			(xy 297.836894 -125.114521) (xy 297.813958 -125.169894) (xy 297.783991 -125.2218) (xy 297.747504 -125.26935)
			(xy 297.705124 -125.31173) (xy 297.657574 -125.348217) (xy 297.605668 -125.378184) (xy 297.550295 -125.40112)
			(xy 297.492402 -125.416633) (xy 297.43298 -125.424456) (xy 297.373044 -125.424456) (xy 297.313622 -125.416633)
			(xy 297.255729 -125.40112) (xy 297.200356 -125.378184) (xy 297.14845 -125.348217) (xy 297.1009 -125.31173)
			(xy 297.05852 -125.26935) (xy 297.022033 -125.2218) (xy 296.992066 -125.169894) (xy 296.96913 -125.114521)
			(xy 296.953617 -125.056628) (xy 296.945794 -124.997206) (xy 296.945304 -124.967238) (xy 284.900624 -124.967238)
			(xy 284.900624 -125.486414) (xy 284.900491 -125.494542) (xy 385.6101 -125.494542) (xy 385.6101 -124.630942)
			(xy 385.61059 -124.600974) (xy 385.618413 -124.541552) (xy 385.633926 -124.483659) (xy 385.656862 -124.428286)
			(xy 385.686829 -124.37638) (xy 385.723316 -124.32883) (xy 385.765696 -124.28645) (xy 385.813246 -124.249963)
			(xy 385.865152 -124.219996) (xy 385.920525 -124.19706) (xy 385.978418 -124.181547) (xy 386.03784 -124.173724)
			(xy 386.097776 -124.173724) (xy 386.157198 -124.181547) (xy 386.215091 -124.19706) (xy 386.270464 -124.219996)
			(xy 386.32237 -124.249963) (xy 386.36992 -124.28645) (xy 386.4123 -124.32883) (xy 386.448787 -124.37638)
			(xy 386.478754 -124.428286) (xy 386.50169 -124.483659) (xy 386.517203 -124.541552) (xy 386.525026 -124.600974)
			(xy 386.525516 -124.630942) (xy 386.525516 -125.486414) (xy 400.085052 -125.486414) (xy 400.085052 -124.622814)
			(xy 400.085542 -124.592846) (xy 400.093365 -124.533424) (xy 400.108878 -124.475531) (xy 400.131814 -124.420158)
			(xy 400.161781 -124.368252) (xy 400.198268 -124.320702) (xy 400.240648 -124.278322) (xy 400.288198 -124.241835)
			(xy 400.340104 -124.211868) (xy 400.395477 -124.188932) (xy 400.45337 -124.173419) (xy 400.512792 -124.165596)
			(xy 400.572728 -124.165596) (xy 400.63215 -124.173419) (xy 400.690043 -124.188932) (xy 400.745416 -124.211868)
			(xy 400.797322 -124.241835) (xy 400.844872 -124.278322) (xy 400.887252 -124.320702) (xy 400.923739 -124.368252)
			(xy 400.953706 -124.420158) (xy 400.976642 -124.475531) (xy 400.992155 -124.533424) (xy 400.999978 -124.592846)
			(xy 401.000468 -124.622814) (xy 401.000468 -124.967238) (xy 413.045148 -124.967238) (xy 413.045148 -124.103638)
			(xy 413.045638 -124.073654) (xy 413.053466 -124.014198) (xy 413.068987 -123.956273) (xy 413.091936 -123.900869)
			(xy 413.12192 -123.848935) (xy 413.158426 -123.801359) (xy 413.200831 -123.758954) (xy 413.248407 -123.722448)
			(xy 413.300341 -123.692464) (xy 413.355745 -123.669515) (xy 413.41367 -123.653994) (xy 413.473126 -123.646166)
			(xy 413.533094 -123.646166) (xy 413.59255 -123.653994) (xy 413.650475 -123.669515) (xy 413.705879 -123.692464)
			(xy 413.757813 -123.722448) (xy 413.805389 -123.758954) (xy 413.847794 -123.801359) (xy 413.8843 -123.848935)
			(xy 413.914284 -123.900869) (xy 413.937233 -123.956273) (xy 413.952754 -124.014198) (xy 413.960582 -124.073654)
			(xy 413.961072 -124.103638) (xy 413.961072 -124.965714) (xy 432.016408 -124.965714) (xy 432.016408 -124.102114)
			(xy 432.016898 -124.07213) (xy 432.024726 -124.012674) (xy 432.040247 -123.954749) (xy 432.063196 -123.899345)
			(xy 432.09318 -123.847411) (xy 432.129686 -123.799835) (xy 432.172091 -123.75743) (xy 432.219667 -123.720924)
			(xy 432.271601 -123.69094) (xy 432.327005 -123.667991) (xy 432.38493 -123.65247) (xy 432.444386 -123.644642)
			(xy 432.504354 -123.644642) (xy 432.56381 -123.65247) (xy 432.621735 -123.667991) (xy 432.677139 -123.69094)
			(xy 432.729073 -123.720924) (xy 432.776649 -123.75743) (xy 432.819054 -123.799835) (xy 432.85556 -123.847411)
			(xy 432.885544 -123.899345) (xy 432.908493 -123.954749) (xy 432.924014 -124.012674) (xy 432.931842 -124.07213)
			(xy 432.932332 -124.102114) (xy 432.932332 -124.965714) (xy 432.931842 -124.995698) (xy 432.924014 -125.055154)
			(xy 432.908493 -125.113079) (xy 432.885544 -125.168483) (xy 432.85556 -125.220417) (xy 432.819054 -125.267993)
			(xy 432.776649 -125.310398) (xy 432.729073 -125.346904) (xy 432.677139 -125.376888) (xy 432.621735 -125.399837)
			(xy 432.56381 -125.415358) (xy 432.504354 -125.423186) (xy 432.444386 -125.423186) (xy 432.38493 -125.415358)
			(xy 432.327005 -125.399837) (xy 432.271601 -125.376888) (xy 432.219667 -125.346904) (xy 432.172091 -125.310398)
			(xy 432.129686 -125.267993) (xy 432.09318 -125.220417) (xy 432.063196 -125.168483) (xy 432.040247 -125.113079)
			(xy 432.024726 -125.055154) (xy 432.016898 -124.995698) (xy 432.016408 -124.965714) (xy 413.961072 -124.965714)
			(xy 413.961072 -124.967238) (xy 413.960582 -124.997222) (xy 413.952754 -125.056678) (xy 413.937233 -125.114603)
			(xy 413.914284 -125.170007) (xy 413.8843 -125.221941) (xy 413.847794 -125.269517) (xy 413.805389 -125.311922)
			(xy 413.757813 -125.348428) (xy 413.705879 -125.378412) (xy 413.650475 -125.401361) (xy 413.59255 -125.416882)
			(xy 413.533094 -125.42471) (xy 413.473126 -125.42471) (xy 413.41367 -125.416882) (xy 413.355745 -125.401361)
			(xy 413.300341 -125.378412) (xy 413.248407 -125.348428) (xy 413.200831 -125.311922) (xy 413.158426 -125.269517)
			(xy 413.12192 -125.221941) (xy 413.091936 -125.170007) (xy 413.068987 -125.114603) (xy 413.053466 -125.056678)
			(xy 413.045638 -124.997222) (xy 413.045148 -124.967238) (xy 401.000468 -124.967238) (xy 401.000468 -125.486414)
			(xy 400.999978 -125.516382) (xy 400.992155 -125.575804) (xy 400.976642 -125.633697) (xy 400.953706 -125.68907)
			(xy 400.923739 -125.740976) (xy 400.887252 -125.788526) (xy 400.844872 -125.830906) (xy 400.797322 -125.867393)
			(xy 400.745416 -125.89736) (xy 400.690043 -125.920296) (xy 400.63215 -125.935809) (xy 400.572728 -125.943632)
			(xy 400.512792 -125.943632) (xy 400.45337 -125.935809) (xy 400.395477 -125.920296) (xy 400.340104 -125.89736)
			(xy 400.288198 -125.867393) (xy 400.240648 -125.830906) (xy 400.198268 -125.788526) (xy 400.161781 -125.740976)
			(xy 400.131814 -125.68907) (xy 400.108878 -125.633697) (xy 400.093365 -125.575804) (xy 400.085542 -125.516382)
			(xy 400.085052 -125.486414) (xy 386.525516 -125.486414) (xy 386.525516 -125.494542) (xy 386.525026 -125.52451)
			(xy 386.517203 -125.583932) (xy 386.50169 -125.641825) (xy 386.478754 -125.697198) (xy 386.448787 -125.749104)
			(xy 386.4123 -125.796654) (xy 386.36992 -125.839034) (xy 386.32237 -125.875521) (xy 386.270464 -125.905488)
			(xy 386.215091 -125.928424) (xy 386.157198 -125.943937) (xy 386.097776 -125.95176) (xy 386.03784 -125.95176)
			(xy 385.978418 -125.943937) (xy 385.920525 -125.928424) (xy 385.865152 -125.905488) (xy 385.813246 -125.875521)
			(xy 385.765696 -125.839034) (xy 385.723316 -125.796654) (xy 385.686829 -125.749104) (xy 385.656862 -125.697198)
			(xy 385.633926 -125.641825) (xy 385.618413 -125.583932) (xy 385.61059 -125.52451) (xy 385.6101 -125.494542)
			(xy 284.900491 -125.494542) (xy 284.900134 -125.516398) (xy 284.892306 -125.575854) (xy 284.876785 -125.633779)
			(xy 284.853836 -125.689183) (xy 284.823852 -125.741117) (xy 284.787346 -125.788693) (xy 284.744941 -125.831098)
			(xy 284.697365 -125.867604) (xy 284.645431 -125.897588) (xy 284.590027 -125.920537) (xy 284.532102 -125.936058)
			(xy 284.472646 -125.943886) (xy 284.412678 -125.943886) (xy 284.353222 -125.936058) (xy 284.295297 -125.920537)
			(xy 284.239893 -125.897588) (xy 284.187959 -125.867604) (xy 284.140383 -125.831098) (xy 284.097978 -125.788693)
			(xy 284.061472 -125.741117) (xy 284.031488 -125.689183) (xy 284.008539 -125.633779) (xy 283.993018 -125.575854)
			(xy 283.98519 -125.516398) (xy 283.9847 -125.486414) (xy 270.425672 -125.486414) (xy 270.425672 -125.494542)
			(xy 270.425182 -125.524526) (xy 270.417354 -125.583982) (xy 270.401833 -125.641907) (xy 270.378884 -125.697311)
			(xy 270.3489 -125.749245) (xy 270.312394 -125.796821) (xy 270.269989 -125.839226) (xy 270.222413 -125.875732)
			(xy 270.170479 -125.905716) (xy 270.115075 -125.928665) (xy 270.05715 -125.944186) (xy 269.997694 -125.952014)
			(xy 269.937726 -125.952014) (xy 269.87827 -125.944186) (xy 269.820345 -125.928665) (xy 269.764941 -125.905716)
			(xy 269.713007 -125.875732) (xy 269.665431 -125.839226) (xy 269.623026 -125.796821) (xy 269.58652 -125.749245)
			(xy 269.556536 -125.697311) (xy 269.533587 -125.641907) (xy 269.518066 -125.583982) (xy 269.510238 -125.524526)
			(xy 269.509748 -125.494542) (xy 168.800647 -125.494542) (xy 168.80029 -125.516398) (xy 168.792462 -125.575854)
			(xy 168.776941 -125.633779) (xy 168.753992 -125.689183) (xy 168.724008 -125.741117) (xy 168.687502 -125.788693)
			(xy 168.645097 -125.831098) (xy 168.597521 -125.867604) (xy 168.545587 -125.897588) (xy 168.490183 -125.920537)
			(xy 168.432258 -125.936058) (xy 168.372802 -125.943886) (xy 168.312834 -125.943886) (xy 168.253378 -125.936058)
			(xy 168.195453 -125.920537) (xy 168.140049 -125.897588) (xy 168.088115 -125.867604) (xy 168.040539 -125.831098)
			(xy 167.998134 -125.788693) (xy 167.961628 -125.741117) (xy 167.931644 -125.689183) (xy 167.908695 -125.633779)
			(xy 167.893174 -125.575854) (xy 167.885346 -125.516398) (xy 167.884856 -125.486414) (xy 154.325828 -125.486414)
			(xy 154.325828 -125.494542) (xy 154.325338 -125.524526) (xy 154.31751 -125.583982) (xy 154.301989 -125.641907)
			(xy 154.27904 -125.697311) (xy 154.249056 -125.749245) (xy 154.21255 -125.796821) (xy 154.170145 -125.839226)
			(xy 154.122569 -125.875732) (xy 154.070635 -125.905716) (xy 154.015231 -125.928665) (xy 153.957306 -125.944186)
			(xy 153.89785 -125.952014) (xy 153.837882 -125.952014) (xy 153.778426 -125.944186) (xy 153.720501 -125.928665)
			(xy 153.665097 -125.905716) (xy 153.613163 -125.875732) (xy 153.565587 -125.839226) (xy 153.523182 -125.796821)
			(xy 153.486676 -125.749245) (xy 153.456692 -125.697311) (xy 153.433743 -125.641907) (xy 153.418222 -125.583982)
			(xy 153.410394 -125.524526) (xy 153.409904 -125.494542) (xy 52.700295 -125.494542) (xy 52.699938 -125.516382)
			(xy 52.692115 -125.575804) (xy 52.676602 -125.633697) (xy 52.653666 -125.68907) (xy 52.623699 -125.740976)
			(xy 52.587212 -125.788526) (xy 52.544832 -125.830906) (xy 52.497282 -125.867393) (xy 52.445376 -125.89736)
			(xy 52.390003 -125.920296) (xy 52.33211 -125.935809) (xy 52.272688 -125.943632) (xy 52.212752 -125.943632)
			(xy 52.15333 -125.935809) (xy 52.095437 -125.920296) (xy 52.040064 -125.89736) (xy 51.988158 -125.867393)
			(xy 51.940608 -125.830906) (xy 51.898228 -125.788526) (xy 51.861741 -125.740976) (xy 51.831774 -125.68907)
			(xy 51.808838 -125.633697) (xy 51.793325 -125.575804) (xy 51.785502 -125.516382) (xy 51.785012 -125.486414)
			(xy 38.225476 -125.486414) (xy 38.225476 -125.494542) (xy 38.224986 -125.52451) (xy 38.217163 -125.583932)
			(xy 38.20165 -125.641825) (xy 38.178714 -125.697198) (xy 38.148747 -125.749104) (xy 38.11226 -125.796654)
			(xy 38.06988 -125.839034) (xy 38.02233 -125.875521) (xy 37.970424 -125.905488) (xy 37.915051 -125.928424)
			(xy 37.857158 -125.943937) (xy 37.797736 -125.95176) (xy 37.7378 -125.95176) (xy 37.678378 -125.943937)
			(xy 37.620485 -125.928424) (xy 37.565112 -125.905488) (xy 37.513206 -125.875521) (xy 37.465656 -125.839034)
			(xy 37.423276 -125.796654) (xy 37.386789 -125.749104) (xy 37.356822 -125.697198) (xy 37.333886 -125.641825)
			(xy 37.318373 -125.583932) (xy 37.31055 -125.52451) (xy 37.31006 -125.494542) (xy 4.30911 -125.494542)
			(xy 4.30911 -131.297934) (xy 34.667952 -131.297934) (xy 34.667952 -130.434334) (xy 34.668442 -130.404366)
			(xy 34.676265 -130.344944) (xy 34.691778 -130.287051) (xy 34.714714 -130.231678) (xy 34.744681 -130.179772)
			(xy 34.781168 -130.132222) (xy 34.823548 -130.089842) (xy 34.871098 -130.053355) (xy 34.923004 -130.023388)
			(xy 34.978377 -130.000452) (xy 35.03627 -129.984939) (xy 35.095692 -129.977116) (xy 35.155628 -129.977116)
			(xy 35.21505 -129.984939) (xy 35.272943 -130.000452) (xy 35.328316 -130.023388) (xy 35.380222 -130.053355)
			(xy 35.427772 -130.089842) (xy 35.470152 -130.132222) (xy 35.506639 -130.179772) (xy 35.536606 -130.231678)
			(xy 35.559542 -130.287051) (xy 35.575055 -130.344944) (xy 35.582878 -130.404366) (xy 35.583368 -130.434334)
			(xy 35.583368 -131.29641) (xy 53.639212 -131.29641) (xy 53.639212 -130.43281) (xy 53.639702 -130.402842)
			(xy 53.647525 -130.34342) (xy 53.663038 -130.285527) (xy 53.685974 -130.230154) (xy 53.715941 -130.178248)
			(xy 53.752428 -130.130698) (xy 53.794808 -130.088318) (xy 53.842358 -130.051831) (xy 53.894264 -130.021864)
			(xy 53.949637 -129.998928) (xy 54.00753 -129.983415) (xy 54.066952 -129.975592) (xy 54.126888 -129.975592)
			(xy 54.18631 -129.983415) (xy 54.244203 -129.998928) (xy 54.299576 -130.021864) (xy 54.351482 -130.051831)
			(xy 54.399032 -130.088318) (xy 54.441412 -130.130698) (xy 54.477899 -130.178248) (xy 54.507866 -130.230154)
			(xy 54.530802 -130.285527) (xy 54.546315 -130.34342) (xy 54.554138 -130.402842) (xy 54.554628 -130.43281)
			(xy 54.554628 -130.777234) (xy 66.599308 -130.777234) (xy 66.599308 -129.913634) (xy 66.599798 -129.88365)
			(xy 66.607626 -129.824194) (xy 66.623147 -129.766269) (xy 66.646096 -129.710865) (xy 66.67608 -129.658931)
			(xy 66.712586 -129.611355) (xy 66.754991 -129.56895) (xy 66.802567 -129.532444) (xy 66.854501 -129.50246)
			(xy 66.909905 -129.479511) (xy 66.96783 -129.46399) (xy 67.027286 -129.456162) (xy 67.087254 -129.456162)
			(xy 67.14671 -129.46399) (xy 67.204635 -129.479511) (xy 67.260039 -129.50246) (xy 67.311973 -129.532444)
			(xy 67.359549 -129.56895) (xy 67.401954 -129.611355) (xy 67.43846 -129.658931) (xy 67.468444 -129.710865)
			(xy 67.491393 -129.766269) (xy 67.506914 -129.824194) (xy 67.514742 -129.88365) (xy 67.515232 -129.913634)
			(xy 67.515232 -130.769106) (xy 81.07426 -130.769106) (xy 81.07426 -129.905506) (xy 81.07475 -129.875522)
			(xy 81.082578 -129.816066) (xy 81.098099 -129.758141) (xy 81.121048 -129.702737) (xy 81.151032 -129.650803)
			(xy 81.187538 -129.603227) (xy 81.229943 -129.560822) (xy 81.277519 -129.524316) (xy 81.329453 -129.494332)
			(xy 81.384857 -129.471383) (xy 81.442782 -129.455862) (xy 81.502238 -129.448034) (xy 81.562206 -129.448034)
			(xy 81.621662 -129.455862) (xy 81.679587 -129.471383) (xy 81.734991 -129.494332) (xy 81.786925 -129.524316)
			(xy 81.834501 -129.560822) (xy 81.876906 -129.603227) (xy 81.913412 -129.650803) (xy 81.943396 -129.702737)
			(xy 81.966345 -129.758141) (xy 81.981866 -129.816066) (xy 81.989694 -129.875522) (xy 81.990184 -129.905506)
			(xy 81.990184 -130.769106) (xy 81.989694 -130.79909) (xy 81.981866 -130.858546) (xy 81.966345 -130.916471)
			(xy 81.943396 -130.971875) (xy 81.913412 -131.023809) (xy 81.876906 -131.071385) (xy 81.834501 -131.11379)
			(xy 81.786925 -131.150296) (xy 81.734991 -131.18028) (xy 81.679587 -131.203229) (xy 81.621662 -131.21875)
			(xy 81.562206 -131.226578) (xy 81.502238 -131.226578) (xy 81.442782 -131.21875) (xy 81.384857 -131.203229)
			(xy 81.329453 -131.18028) (xy 81.277519 -131.150296) (xy 81.229943 -131.11379) (xy 81.187538 -131.071385)
			(xy 81.151032 -131.023809) (xy 81.121048 -130.971875) (xy 81.098099 -130.916471) (xy 81.082578 -130.858546)
			(xy 81.07475 -130.79909) (xy 81.07426 -130.769106) (xy 67.515232 -130.769106) (xy 67.515232 -130.777234)
			(xy 67.514742 -130.807218) (xy 67.506914 -130.866674) (xy 67.491393 -130.924599) (xy 67.468444 -130.980003)
			(xy 67.43846 -131.031937) (xy 67.401954 -131.079513) (xy 67.359549 -131.121918) (xy 67.311973 -131.158424)
			(xy 67.260039 -131.188408) (xy 67.204635 -131.211357) (xy 67.14671 -131.226878) (xy 67.087254 -131.234706)
			(xy 67.027286 -131.234706) (xy 66.96783 -131.226878) (xy 66.909905 -131.211357) (xy 66.854501 -131.188408)
			(xy 66.802567 -131.158424) (xy 66.754991 -131.121918) (xy 66.712586 -131.079513) (xy 66.67608 -131.031937)
			(xy 66.646096 -130.980003) (xy 66.623147 -130.924599) (xy 66.607626 -130.866674) (xy 66.599798 -130.807218)
			(xy 66.599308 -130.777234) (xy 54.554628 -130.777234) (xy 54.554628 -131.29641) (xy 54.554138 -131.326378)
			(xy 54.546315 -131.3858) (xy 54.530802 -131.443693) (xy 54.507866 -131.499066) (xy 54.477899 -131.550972)
			(xy 54.441412 -131.598522) (xy 54.399032 -131.640902) (xy 54.351482 -131.677389) (xy 54.299576 -131.707356)
			(xy 54.244203 -131.730292) (xy 54.18631 -131.745805) (xy 54.126888 -131.753628) (xy 54.066952 -131.753628)
			(xy 54.00753 -131.745805) (xy 53.949637 -131.730292) (xy 53.894264 -131.707356) (xy 53.842358 -131.677389)
			(xy 53.794808 -131.640902) (xy 53.752428 -131.598522) (xy 53.715941 -131.550972) (xy 53.685974 -131.499066)
			(xy 53.663038 -131.443693) (xy 53.647525 -131.3858) (xy 53.639702 -131.326378) (xy 53.639212 -131.29641)
			(xy 35.583368 -131.29641) (xy 35.583368 -131.297934) (xy 35.582878 -131.327902) (xy 35.575055 -131.387324)
			(xy 35.559542 -131.445217) (xy 35.536606 -131.50059) (xy 35.506639 -131.552496) (xy 35.470152 -131.600046)
			(xy 35.427772 -131.642426) (xy 35.380222 -131.678913) (xy 35.328316 -131.70888) (xy 35.272943 -131.731816)
			(xy 35.21505 -131.747329) (xy 35.155628 -131.755152) (xy 35.095692 -131.755152) (xy 35.03627 -131.747329)
			(xy 34.978377 -131.731816) (xy 34.923004 -131.70888) (xy 34.871098 -131.678913) (xy 34.823548 -131.642426)
			(xy 34.781168 -131.600046) (xy 34.744681 -131.552496) (xy 34.714714 -131.50059) (xy 34.691778 -131.445217)
			(xy 34.676265 -131.387324) (xy 34.668442 -131.327902) (xy 34.667952 -131.297934) (xy 4.30911 -131.297934)
			(xy 4.30911 -133.104382) (xy 37.31006 -133.104382) (xy 37.31006 -132.240782) (xy 37.31055 -132.210814)
			(xy 37.318373 -132.151392) (xy 37.333886 -132.093499) (xy 37.356822 -132.038126) (xy 37.386789 -131.98622)
			(xy 37.423276 -131.93867) (xy 37.465656 -131.89629) (xy 37.513206 -131.859803) (xy 37.565112 -131.829836)
			(xy 37.620485 -131.8069) (xy 37.678378 -131.791387) (xy 37.7378 -131.783564) (xy 37.797736 -131.783564)
			(xy 37.857158 -131.791387) (xy 37.915051 -131.8069) (xy 37.970424 -131.829836) (xy 38.02233 -131.859803)
			(xy 38.06988 -131.89629) (xy 38.11226 -131.93867) (xy 38.148747 -131.98622) (xy 38.178714 -132.038126)
			(xy 38.20165 -132.093499) (xy 38.217163 -132.151392) (xy 38.224986 -132.210814) (xy 38.225476 -132.240782)
			(xy 38.225476 -133.096508) (xy 51.785012 -133.096508) (xy 51.785012 -132.232908) (xy 51.785502 -132.20294)
			(xy 51.793325 -132.143518) (xy 51.808838 -132.085625) (xy 51.831774 -132.030252) (xy 51.861741 -131.978346)
			(xy 51.898228 -131.930796) (xy 51.940608 -131.888416) (xy 51.988158 -131.851929) (xy 52.040064 -131.821962)
			(xy 52.095437 -131.799026) (xy 52.15333 -131.783513) (xy 52.212752 -131.77569) (xy 52.272688 -131.77569)
			(xy 52.33211 -131.783513) (xy 52.390003 -131.799026) (xy 52.445376 -131.821962) (xy 52.497282 -131.851929)
			(xy 52.544832 -131.888416) (xy 52.587212 -131.930796) (xy 52.623699 -131.978346) (xy 52.653666 -132.030252)
			(xy 52.676602 -132.085625) (xy 52.692115 -132.143518) (xy 52.699938 -132.20294) (xy 52.700428 -132.232908)
			(xy 52.700428 -132.577332) (xy 64.745108 -132.577332) (xy 64.745108 -131.713732) (xy 64.745598 -131.683748)
			(xy 64.753426 -131.624292) (xy 64.768947 -131.566367) (xy 64.791896 -131.510963) (xy 64.82188 -131.459029)
			(xy 64.858386 -131.411453) (xy 64.900791 -131.369048) (xy 64.948367 -131.332542) (xy 65.000301 -131.302558)
			(xy 65.055705 -131.279609) (xy 65.11363 -131.264088) (xy 65.173086 -131.25626) (xy 65.233054 -131.25626)
			(xy 65.29251 -131.264088) (xy 65.350435 -131.279609) (xy 65.405839 -131.302558) (xy 65.457773 -131.332542)
			(xy 65.505349 -131.369048) (xy 65.547754 -131.411453) (xy 65.58426 -131.459029) (xy 65.614244 -131.510963)
			(xy 65.637193 -131.566367) (xy 65.652714 -131.624292) (xy 65.660542 -131.683748) (xy 65.661032 -131.713732)
			(xy 65.661032 -132.575808) (xy 83.716368 -132.575808) (xy 83.716368 -131.712208) (xy 83.716858 -131.682224)
			(xy 83.724686 -131.622768) (xy 83.740207 -131.564843) (xy 83.763156 -131.509439) (xy 83.79314 -131.457505)
			(xy 83.829646 -131.409929) (xy 83.872051 -131.367524) (xy 83.919627 -131.331018) (xy 83.971561 -131.301034)
			(xy 84.026965 -131.278085) (xy 84.08489 -131.262564) (xy 84.144346 -131.254736) (xy 84.204314 -131.254736)
			(xy 84.26377 -131.262564) (xy 84.321695 -131.278085) (xy 84.369615 -131.297934) (xy 150.767796 -131.297934)
			(xy 150.767796 -130.434334) (xy 150.768286 -130.40435) (xy 150.776114 -130.344894) (xy 150.791635 -130.286969)
			(xy 150.814584 -130.231565) (xy 150.844568 -130.179631) (xy 150.881074 -130.132055) (xy 150.923479 -130.08965)
			(xy 150.971055 -130.053144) (xy 151.022989 -130.02316) (xy 151.078393 -130.000211) (xy 151.136318 -129.98469)
			(xy 151.195774 -129.976862) (xy 151.255742 -129.976862) (xy 151.315198 -129.98469) (xy 151.373123 -130.000211)
			(xy 151.428527 -130.02316) (xy 151.480461 -130.053144) (xy 151.528037 -130.08965) (xy 151.570442 -130.132055)
			(xy 151.606948 -130.179631) (xy 151.636932 -130.231565) (xy 151.659881 -130.286969) (xy 151.675402 -130.344894)
			(xy 151.68323 -130.40435) (xy 151.68372 -130.434334) (xy 151.68372 -131.29641) (xy 169.739056 -131.29641)
			(xy 169.739056 -130.43281) (xy 169.739546 -130.402826) (xy 169.747374 -130.34337) (xy 169.762895 -130.285445)
			(xy 169.785844 -130.230041) (xy 169.815828 -130.178107) (xy 169.852334 -130.130531) (xy 169.894739 -130.088126)
			(xy 169.942315 -130.05162) (xy 169.994249 -130.021636) (xy 170.049653 -129.998687) (xy 170.107578 -129.983166)
			(xy 170.167034 -129.975338) (xy 170.227002 -129.975338) (xy 170.286458 -129.983166) (xy 170.344383 -129.998687)
			(xy 170.399787 -130.021636) (xy 170.451721 -130.05162) (xy 170.499297 -130.088126) (xy 170.541702 -130.130531)
			(xy 170.578208 -130.178107) (xy 170.608192 -130.230041) (xy 170.631141 -130.285445) (xy 170.646662 -130.34337)
			(xy 170.65449 -130.402826) (xy 170.65498 -130.43281) (xy 170.65498 -130.777234) (xy 182.69966 -130.777234)
			(xy 182.69966 -129.913634) (xy 182.70015 -129.883666) (xy 182.707973 -129.824244) (xy 182.723486 -129.766351)
			(xy 182.746422 -129.710978) (xy 182.776389 -129.659072) (xy 182.812876 -129.611522) (xy 182.855256 -129.569142)
			(xy 182.902806 -129.532655) (xy 182.954712 -129.502688) (xy 183.010085 -129.479752) (xy 183.067978 -129.464239)
			(xy 183.1274 -129.456416) (xy 183.187336 -129.456416) (xy 183.246758 -129.464239) (xy 183.304651 -129.479752)
			(xy 183.360024 -129.502688) (xy 183.41193 -129.532655) (xy 183.45948 -129.569142) (xy 183.50186 -129.611522)
			(xy 183.538347 -129.659072) (xy 183.568314 -129.710978) (xy 183.59125 -129.766351) (xy 183.606763 -129.824244)
			(xy 183.614586 -129.883666) (xy 183.615076 -129.913634) (xy 183.615076 -130.769106) (xy 197.174612 -130.769106)
			(xy 197.174612 -129.905506) (xy 197.175102 -129.875538) (xy 197.182925 -129.816116) (xy 197.198438 -129.758223)
			(xy 197.221374 -129.70285) (xy 197.251341 -129.650944) (xy 197.287828 -129.603394) (xy 197.330208 -129.561014)
			(xy 197.377758 -129.524527) (xy 197.429664 -129.49456) (xy 197.485037 -129.471624) (xy 197.54293 -129.456111)
			(xy 197.602352 -129.448288) (xy 197.662288 -129.448288) (xy 197.72171 -129.456111) (xy 197.779603 -129.471624)
			(xy 197.834976 -129.49456) (xy 197.886882 -129.524527) (xy 197.934432 -129.561014) (xy 197.976812 -129.603394)
			(xy 198.013299 -129.650944) (xy 198.043266 -129.70285) (xy 198.066202 -129.758223) (xy 198.081715 -129.816116)
			(xy 198.089538 -129.875538) (xy 198.090028 -129.905506) (xy 198.090028 -130.769106) (xy 198.089538 -130.799074)
			(xy 198.081715 -130.858496) (xy 198.066202 -130.916389) (xy 198.043266 -130.971762) (xy 198.013299 -131.023668)
			(xy 197.976812 -131.071218) (xy 197.934432 -131.113598) (xy 197.886882 -131.150085) (xy 197.834976 -131.180052)
			(xy 197.779603 -131.202988) (xy 197.72171 -131.218501) (xy 197.662288 -131.226324) (xy 197.602352 -131.226324)
			(xy 197.54293 -131.218501) (xy 197.485037 -131.202988) (xy 197.429664 -131.180052) (xy 197.377758 -131.150085)
			(xy 197.330208 -131.113598) (xy 197.287828 -131.071218) (xy 197.251341 -131.023668) (xy 197.221374 -130.971762)
			(xy 197.198438 -130.916389) (xy 197.182925 -130.858496) (xy 197.175102 -130.799074) (xy 197.174612 -130.769106)
			(xy 183.615076 -130.769106) (xy 183.615076 -130.777234) (xy 183.614586 -130.807202) (xy 183.606763 -130.866624)
			(xy 183.59125 -130.924517) (xy 183.568314 -130.97989) (xy 183.538347 -131.031796) (xy 183.50186 -131.079346)
			(xy 183.45948 -131.121726) (xy 183.41193 -131.158213) (xy 183.360024 -131.18818) (xy 183.304651 -131.211116)
			(xy 183.246758 -131.226629) (xy 183.187336 -131.234452) (xy 183.1274 -131.234452) (xy 183.067978 -131.226629)
			(xy 183.010085 -131.211116) (xy 182.954712 -131.18818) (xy 182.902806 -131.158213) (xy 182.855256 -131.121726)
			(xy 182.812876 -131.079346) (xy 182.776389 -131.031796) (xy 182.746422 -130.97989) (xy 182.723486 -130.924517)
			(xy 182.707973 -130.866624) (xy 182.70015 -130.807202) (xy 182.69966 -130.777234) (xy 170.65498 -130.777234)
			(xy 170.65498 -131.29641) (xy 170.65449 -131.326394) (xy 170.646662 -131.38585) (xy 170.631141 -131.443775)
			(xy 170.608192 -131.499179) (xy 170.578208 -131.551113) (xy 170.541702 -131.598689) (xy 170.499297 -131.641094)
			(xy 170.451721 -131.6776) (xy 170.399787 -131.707584) (xy 170.344383 -131.730533) (xy 170.286458 -131.746054)
			(xy 170.227002 -131.753882) (xy 170.167034 -131.753882) (xy 170.107578 -131.746054) (xy 170.049653 -131.730533)
			(xy 169.994249 -131.707584) (xy 169.942315 -131.6776) (xy 169.894739 -131.641094) (xy 169.852334 -131.598689)
			(xy 169.815828 -131.551113) (xy 169.785844 -131.499179) (xy 169.762895 -131.443775) (xy 169.747374 -131.38585)
			(xy 169.739546 -131.326394) (xy 169.739056 -131.29641) (xy 151.68372 -131.29641) (xy 151.68372 -131.297934)
			(xy 151.68323 -131.327918) (xy 151.675402 -131.387374) (xy 151.659881 -131.445299) (xy 151.636932 -131.500703)
			(xy 151.606948 -131.552637) (xy 151.570442 -131.600213) (xy 151.528037 -131.642618) (xy 151.480461 -131.679124)
			(xy 151.428527 -131.709108) (xy 151.373123 -131.732057) (xy 151.315198 -131.747578) (xy 151.255742 -131.755406)
			(xy 151.195774 -131.755406) (xy 151.136318 -131.747578) (xy 151.078393 -131.732057) (xy 151.022989 -131.709108)
			(xy 150.971055 -131.679124) (xy 150.923479 -131.642618) (xy 150.881074 -131.600213) (xy 150.844568 -131.552637)
			(xy 150.814584 -131.500703) (xy 150.791635 -131.445299) (xy 150.776114 -131.387374) (xy 150.768286 -131.327918)
			(xy 150.767796 -131.297934) (xy 84.369615 -131.297934) (xy 84.377099 -131.301034) (xy 84.429033 -131.331018)
			(xy 84.476609 -131.367524) (xy 84.519014 -131.409929) (xy 84.55552 -131.457505) (xy 84.585504 -131.509439)
			(xy 84.608453 -131.564843) (xy 84.623974 -131.622768) (xy 84.631802 -131.682224) (xy 84.632292 -131.712208)
			(xy 84.632292 -132.575808) (xy 84.631802 -132.605792) (xy 84.623974 -132.665248) (xy 84.608453 -132.723173)
			(xy 84.585504 -132.778577) (xy 84.55552 -132.830511) (xy 84.519014 -132.878087) (xy 84.476609 -132.920492)
			(xy 84.429033 -132.956998) (xy 84.377099 -132.986982) (xy 84.321695 -133.009931) (xy 84.26377 -133.025452)
			(xy 84.204314 -133.03328) (xy 84.144346 -133.03328) (xy 84.08489 -133.025452) (xy 84.026965 -133.009931)
			(xy 83.971561 -132.986982) (xy 83.919627 -132.956998) (xy 83.872051 -132.920492) (xy 83.829646 -132.878087)
			(xy 83.79314 -132.830511) (xy 83.763156 -132.778577) (xy 83.740207 -132.723173) (xy 83.724686 -132.665248)
			(xy 83.716858 -132.605792) (xy 83.716368 -132.575808) (xy 65.661032 -132.575808) (xy 65.661032 -132.577332)
			(xy 65.660542 -132.607316) (xy 65.652714 -132.666772) (xy 65.637193 -132.724697) (xy 65.614244 -132.780101)
			(xy 65.58426 -132.832035) (xy 65.547754 -132.879611) (xy 65.505349 -132.922016) (xy 65.457773 -132.958522)
			(xy 65.405839 -132.988506) (xy 65.350435 -133.011455) (xy 65.29251 -133.026976) (xy 65.233054 -133.034804)
			(xy 65.173086 -133.034804) (xy 65.11363 -133.026976) (xy 65.055705 -133.011455) (xy 65.000301 -132.988506)
			(xy 64.948367 -132.958522) (xy 64.900791 -132.922016) (xy 64.858386 -132.879611) (xy 64.82188 -132.832035)
			(xy 64.791896 -132.780101) (xy 64.768947 -132.724697) (xy 64.753426 -132.666772) (xy 64.745598 -132.607316)
			(xy 64.745108 -132.577332) (xy 52.700428 -132.577332) (xy 52.700428 -133.096508) (xy 52.699938 -133.126476)
			(xy 52.692115 -133.185898) (xy 52.676602 -133.243791) (xy 52.653666 -133.299164) (xy 52.623699 -133.35107)
			(xy 52.587212 -133.39862) (xy 52.544832 -133.441) (xy 52.497282 -133.477487) (xy 52.445376 -133.507454)
			(xy 52.390003 -133.53039) (xy 52.33211 -133.545903) (xy 52.272688 -133.553726) (xy 52.212752 -133.553726)
			(xy 52.15333 -133.545903) (xy 52.095437 -133.53039) (xy 52.040064 -133.507454) (xy 51.988158 -133.477487)
			(xy 51.940608 -133.441) (xy 51.898228 -133.39862) (xy 51.861741 -133.35107) (xy 51.831774 -133.299164)
			(xy 51.808838 -133.243791) (xy 51.793325 -133.185898) (xy 51.785502 -133.126476) (xy 51.785012 -133.096508)
			(xy 38.225476 -133.096508) (xy 38.225476 -133.104382) (xy 38.224986 -133.13435) (xy 38.217163 -133.193772)
			(xy 38.20165 -133.251665) (xy 38.178714 -133.307038) (xy 38.148747 -133.358944) (xy 38.11226 -133.406494)
			(xy 38.06988 -133.448874) (xy 38.02233 -133.485361) (xy 37.970424 -133.515328) (xy 37.915051 -133.538264)
			(xy 37.857158 -133.553777) (xy 37.797736 -133.5616) (xy 37.7378 -133.5616) (xy 37.678378 -133.553777)
			(xy 37.620485 -133.538264) (xy 37.565112 -133.515328) (xy 37.513206 -133.485361) (xy 37.465656 -133.448874)
			(xy 37.423276 -133.406494) (xy 37.386789 -133.358944) (xy 37.356822 -133.307038) (xy 37.333886 -133.251665)
			(xy 37.318373 -133.193772) (xy 37.31055 -133.13435) (xy 37.31006 -133.104382) (xy 4.30911 -133.104382)
			(xy 4.30911 -134.897876) (xy 34.667952 -134.897876) (xy 34.667952 -134.034276) (xy 34.668442 -134.004308)
			(xy 34.676265 -133.944886) (xy 34.691778 -133.886993) (xy 34.714714 -133.83162) (xy 34.744681 -133.779714)
			(xy 34.781168 -133.732164) (xy 34.823548 -133.689784) (xy 34.871098 -133.653297) (xy 34.923004 -133.62333)
			(xy 34.978377 -133.600394) (xy 35.03627 -133.584881) (xy 35.095692 -133.577058) (xy 35.155628 -133.577058)
			(xy 35.21505 -133.584881) (xy 35.272943 -133.600394) (xy 35.328316 -133.62333) (xy 35.380222 -133.653297)
			(xy 35.427772 -133.689784) (xy 35.470152 -133.732164) (xy 35.506639 -133.779714) (xy 35.536606 -133.83162)
			(xy 35.559542 -133.886993) (xy 35.575055 -133.944886) (xy 35.582878 -134.004308) (xy 35.583368 -134.034276)
			(xy 35.583368 -134.896352) (xy 53.639212 -134.896352) (xy 53.639212 -134.032752) (xy 53.639702 -134.002784)
			(xy 53.647525 -133.943362) (xy 53.663038 -133.885469) (xy 53.685974 -133.830096) (xy 53.715941 -133.77819)
			(xy 53.752428 -133.73064) (xy 53.794808 -133.68826) (xy 53.842358 -133.651773) (xy 53.894264 -133.621806)
			(xy 53.949637 -133.59887) (xy 54.00753 -133.583357) (xy 54.066952 -133.575534) (xy 54.126888 -133.575534)
			(xy 54.18631 -133.583357) (xy 54.244203 -133.59887) (xy 54.299576 -133.621806) (xy 54.351482 -133.651773)
			(xy 54.399032 -133.68826) (xy 54.441412 -133.73064) (xy 54.477899 -133.77819) (xy 54.507866 -133.830096)
			(xy 54.530802 -133.885469) (xy 54.546315 -133.943362) (xy 54.554138 -134.002784) (xy 54.554628 -134.032752)
			(xy 54.554628 -134.377176) (xy 66.599308 -134.377176) (xy 66.599308 -133.513576) (xy 66.599798 -133.483592)
			(xy 66.607626 -133.424136) (xy 66.623147 -133.366211) (xy 66.646096 -133.310807) (xy 66.67608 -133.258873)
			(xy 66.712586 -133.211297) (xy 66.754991 -133.168892) (xy 66.802567 -133.132386) (xy 66.854501 -133.102402)
			(xy 66.909905 -133.079453) (xy 66.96783 -133.063932) (xy 67.027286 -133.056104) (xy 67.087254 -133.056104)
			(xy 67.14671 -133.063932) (xy 67.204635 -133.079453) (xy 67.260039 -133.102402) (xy 67.311973 -133.132386)
			(xy 67.359549 -133.168892) (xy 67.401954 -133.211297) (xy 67.43846 -133.258873) (xy 67.468444 -133.310807)
			(xy 67.491393 -133.366211) (xy 67.506914 -133.424136) (xy 67.514742 -133.483592) (xy 67.515232 -133.513576)
			(xy 67.515232 -134.369302) (xy 81.07426 -134.369302) (xy 81.07426 -133.505702) (xy 81.07475 -133.475718)
			(xy 81.082578 -133.416262) (xy 81.098099 -133.358337) (xy 81.121048 -133.302933) (xy 81.151032 -133.250999)
			(xy 81.187538 -133.203423) (xy 81.229943 -133.161018) (xy 81.277519 -133.124512) (xy 81.329453 -133.094528)
			(xy 81.384857 -133.071579) (xy 81.442782 -133.056058) (xy 81.502238 -133.04823) (xy 81.562206 -133.04823)
			(xy 81.621662 -133.056058) (xy 81.679587 -133.071579) (xy 81.734991 -133.094528) (xy 81.752059 -133.104382)
			(xy 153.409904 -133.104382) (xy 153.409904 -132.240782) (xy 153.410394 -132.210798) (xy 153.418222 -132.151342)
			(xy 153.433743 -132.093417) (xy 153.456692 -132.038013) (xy 153.486676 -131.986079) (xy 153.523182 -131.938503)
			(xy 153.565587 -131.896098) (xy 153.613163 -131.859592) (xy 153.665097 -131.829608) (xy 153.720501 -131.806659)
			(xy 153.778426 -131.791138) (xy 153.837882 -131.78331) (xy 153.89785 -131.78331) (xy 153.957306 -131.791138)
			(xy 154.015231 -131.806659) (xy 154.070635 -131.829608) (xy 154.122569 -131.859592) (xy 154.170145 -131.896098)
			(xy 154.21255 -131.938503) (xy 154.249056 -131.986079) (xy 154.27904 -132.038013) (xy 154.301989 -132.093417)
			(xy 154.31751 -132.151342) (xy 154.325338 -132.210798) (xy 154.325828 -132.240782) (xy 154.325828 -133.096508)
			(xy 167.884856 -133.096508) (xy 167.884856 -132.232908) (xy 167.885346 -132.202924) (xy 167.893174 -132.143468)
			(xy 167.908695 -132.085543) (xy 167.931644 -132.030139) (xy 167.961628 -131.978205) (xy 167.998134 -131.930629)
			(xy 168.040539 -131.888224) (xy 168.088115 -131.851718) (xy 168.140049 -131.821734) (xy 168.195453 -131.798785)
			(xy 168.253378 -131.783264) (xy 168.312834 -131.775436) (xy 168.372802 -131.775436) (xy 168.432258 -131.783264)
			(xy 168.490183 -131.798785) (xy 168.545587 -131.821734) (xy 168.597521 -131.851718) (xy 168.645097 -131.888224)
			(xy 168.687502 -131.930629) (xy 168.724008 -131.978205) (xy 168.753992 -132.030139) (xy 168.776941 -132.085543)
			(xy 168.792462 -132.143468) (xy 168.80029 -132.202924) (xy 168.80078 -132.232908) (xy 168.80078 -132.577332)
			(xy 180.84546 -132.577332) (xy 180.84546 -131.713732) (xy 180.84595 -131.683764) (xy 180.853773 -131.624342)
			(xy 180.869286 -131.566449) (xy 180.892222 -131.511076) (xy 180.922189 -131.45917) (xy 180.958676 -131.41162)
			(xy 181.001056 -131.36924) (xy 181.048606 -131.332753) (xy 181.100512 -131.302786) (xy 181.155885 -131.27985)
			(xy 181.213778 -131.264337) (xy 181.2732 -131.256514) (xy 181.333136 -131.256514) (xy 181.392558 -131.264337)
			(xy 181.450451 -131.27985) (xy 181.505824 -131.302786) (xy 181.55773 -131.332753) (xy 181.60528 -131.36924)
			(xy 181.64766 -131.41162) (xy 181.684147 -131.45917) (xy 181.714114 -131.511076) (xy 181.73705 -131.566449)
			(xy 181.752563 -131.624342) (xy 181.760386 -131.683764) (xy 181.760876 -131.713732) (xy 181.760876 -132.575808)
			(xy 199.81672 -132.575808) (xy 199.81672 -131.712208) (xy 199.81721 -131.68224) (xy 199.825033 -131.622818)
			(xy 199.840546 -131.564925) (xy 199.863482 -131.509552) (xy 199.893449 -131.457646) (xy 199.929936 -131.410096)
			(xy 199.972316 -131.367716) (xy 200.019866 -131.331229) (xy 200.071772 -131.301262) (xy 200.127145 -131.278326)
			(xy 200.185038 -131.262813) (xy 200.24446 -131.25499) (xy 200.304396 -131.25499) (xy 200.363818 -131.262813)
			(xy 200.421711 -131.278326) (xy 200.469049 -131.297934) (xy 266.86764 -131.297934) (xy 266.86764 -130.434334)
			(xy 266.86813 -130.40435) (xy 266.875958 -130.344894) (xy 266.891479 -130.286969) (xy 266.914428 -130.231565)
			(xy 266.944412 -130.179631) (xy 266.980918 -130.132055) (xy 267.023323 -130.08965) (xy 267.070899 -130.053144)
			(xy 267.122833 -130.02316) (xy 267.178237 -130.000211) (xy 267.236162 -129.98469) (xy 267.295618 -129.976862)
			(xy 267.355586 -129.976862) (xy 267.415042 -129.98469) (xy 267.472967 -130.000211) (xy 267.528371 -130.02316)
			(xy 267.580305 -130.053144) (xy 267.627881 -130.08965) (xy 267.670286 -130.132055) (xy 267.706792 -130.179631)
			(xy 267.736776 -130.231565) (xy 267.759725 -130.286969) (xy 267.775246 -130.344894) (xy 267.783074 -130.40435)
			(xy 267.783564 -130.434334) (xy 267.783564 -131.29641) (xy 285.8389 -131.29641) (xy 285.8389 -130.43281)
			(xy 285.83939 -130.402826) (xy 285.847218 -130.34337) (xy 285.862739 -130.285445) (xy 285.885688 -130.230041)
			(xy 285.915672 -130.178107) (xy 285.952178 -130.130531) (xy 285.994583 -130.088126) (xy 286.042159 -130.05162)
			(xy 286.094093 -130.021636) (xy 286.149497 -129.998687) (xy 286.207422 -129.983166) (xy 286.266878 -129.975338)
			(xy 286.326846 -129.975338) (xy 286.386302 -129.983166) (xy 286.444227 -129.998687) (xy 286.499631 -130.021636)
			(xy 286.551565 -130.05162) (xy 286.599141 -130.088126) (xy 286.641546 -130.130531) (xy 286.678052 -130.178107)
			(xy 286.708036 -130.230041) (xy 286.730985 -130.285445) (xy 286.746506 -130.34337) (xy 286.754334 -130.402826)
			(xy 286.754824 -130.43281) (xy 286.754824 -130.777234) (xy 298.799504 -130.777234) (xy 298.799504 -129.913634)
			(xy 298.799994 -129.883666) (xy 298.807817 -129.824244) (xy 298.82333 -129.766351) (xy 298.846266 -129.710978)
			(xy 298.876233 -129.659072) (xy 298.91272 -129.611522) (xy 298.9551 -129.569142) (xy 299.00265 -129.532655)
			(xy 299.054556 -129.502688) (xy 299.109929 -129.479752) (xy 299.167822 -129.464239) (xy 299.227244 -129.456416)
			(xy 299.28718 -129.456416) (xy 299.346602 -129.464239) (xy 299.404495 -129.479752) (xy 299.459868 -129.502688)
			(xy 299.511774 -129.532655) (xy 299.559324 -129.569142) (xy 299.601704 -129.611522) (xy 299.638191 -129.659072)
			(xy 299.668158 -129.710978) (xy 299.691094 -129.766351) (xy 299.706607 -129.824244) (xy 299.71443 -129.883666)
			(xy 299.71492 -129.913634) (xy 299.71492 -130.769106) (xy 313.274456 -130.769106) (xy 313.274456 -129.905506)
			(xy 313.274946 -129.875538) (xy 313.282769 -129.816116) (xy 313.298282 -129.758223) (xy 313.321218 -129.70285)
			(xy 313.351185 -129.650944) (xy 313.387672 -129.603394) (xy 313.430052 -129.561014) (xy 313.477602 -129.524527)
			(xy 313.529508 -129.49456) (xy 313.584881 -129.471624) (xy 313.642774 -129.456111) (xy 313.702196 -129.448288)
			(xy 313.762132 -129.448288) (xy 313.821554 -129.456111) (xy 313.879447 -129.471624) (xy 313.93482 -129.49456)
			(xy 313.986726 -129.524527) (xy 314.034276 -129.561014) (xy 314.076656 -129.603394) (xy 314.113143 -129.650944)
			(xy 314.14311 -129.70285) (xy 314.166046 -129.758223) (xy 314.181559 -129.816116) (xy 314.189382 -129.875538)
			(xy 314.189872 -129.905506) (xy 314.189872 -130.769106) (xy 314.189382 -130.799074) (xy 314.181559 -130.858496)
			(xy 314.166046 -130.916389) (xy 314.14311 -130.971762) (xy 314.113143 -131.023668) (xy 314.076656 -131.071218)
			(xy 314.034276 -131.113598) (xy 313.986726 -131.150085) (xy 313.93482 -131.180052) (xy 313.879447 -131.202988)
			(xy 313.821554 -131.218501) (xy 313.762132 -131.226324) (xy 313.702196 -131.226324) (xy 313.642774 -131.218501)
			(xy 313.584881 -131.202988) (xy 313.529508 -131.180052) (xy 313.477602 -131.150085) (xy 313.430052 -131.113598)
			(xy 313.387672 -131.071218) (xy 313.351185 -131.023668) (xy 313.321218 -130.971762) (xy 313.298282 -130.916389)
			(xy 313.282769 -130.858496) (xy 313.274946 -130.799074) (xy 313.274456 -130.769106) (xy 299.71492 -130.769106)
			(xy 299.71492 -130.777234) (xy 299.71443 -130.807202) (xy 299.706607 -130.866624) (xy 299.691094 -130.924517)
			(xy 299.668158 -130.97989) (xy 299.638191 -131.031796) (xy 299.601704 -131.079346) (xy 299.559324 -131.121726)
			(xy 299.511774 -131.158213) (xy 299.459868 -131.18818) (xy 299.404495 -131.211116) (xy 299.346602 -131.226629)
			(xy 299.28718 -131.234452) (xy 299.227244 -131.234452) (xy 299.167822 -131.226629) (xy 299.109929 -131.211116)
			(xy 299.054556 -131.18818) (xy 299.00265 -131.158213) (xy 298.9551 -131.121726) (xy 298.91272 -131.079346)
			(xy 298.876233 -131.031796) (xy 298.846266 -130.97989) (xy 298.82333 -130.924517) (xy 298.807817 -130.866624)
			(xy 298.799994 -130.807202) (xy 298.799504 -130.777234) (xy 286.754824 -130.777234) (xy 286.754824 -131.29641)
			(xy 286.754334 -131.326394) (xy 286.746506 -131.38585) (xy 286.730985 -131.443775) (xy 286.708036 -131.499179)
			(xy 286.678052 -131.551113) (xy 286.641546 -131.598689) (xy 286.599141 -131.641094) (xy 286.551565 -131.6776)
			(xy 286.499631 -131.707584) (xy 286.444227 -131.730533) (xy 286.386302 -131.746054) (xy 286.326846 -131.753882)
			(xy 286.266878 -131.753882) (xy 286.207422 -131.746054) (xy 286.149497 -131.730533) (xy 286.094093 -131.707584)
			(xy 286.042159 -131.6776) (xy 285.994583 -131.641094) (xy 285.952178 -131.598689) (xy 285.915672 -131.551113)
			(xy 285.885688 -131.499179) (xy 285.862739 -131.443775) (xy 285.847218 -131.38585) (xy 285.83939 -131.326394)
			(xy 285.8389 -131.29641) (xy 267.783564 -131.29641) (xy 267.783564 -131.297934) (xy 267.783074 -131.327918)
			(xy 267.775246 -131.387374) (xy 267.759725 -131.445299) (xy 267.736776 -131.500703) (xy 267.706792 -131.552637)
			(xy 267.670286 -131.600213) (xy 267.627881 -131.642618) (xy 267.580305 -131.679124) (xy 267.528371 -131.709108)
			(xy 267.472967 -131.732057) (xy 267.415042 -131.747578) (xy 267.355586 -131.755406) (xy 267.295618 -131.755406)
			(xy 267.236162 -131.747578) (xy 267.178237 -131.732057) (xy 267.122833 -131.709108) (xy 267.070899 -131.679124)
			(xy 267.023323 -131.642618) (xy 266.980918 -131.600213) (xy 266.944412 -131.552637) (xy 266.914428 -131.500703)
			(xy 266.891479 -131.445299) (xy 266.875958 -131.387374) (xy 266.86813 -131.327918) (xy 266.86764 -131.297934)
			(xy 200.469049 -131.297934) (xy 200.477084 -131.301262) (xy 200.52899 -131.331229) (xy 200.57654 -131.367716)
			(xy 200.61892 -131.410096) (xy 200.655407 -131.457646) (xy 200.685374 -131.509552) (xy 200.70831 -131.564925)
			(xy 200.723823 -131.622818) (xy 200.731646 -131.68224) (xy 200.732136 -131.712208) (xy 200.732136 -132.575808)
			(xy 200.731646 -132.605776) (xy 200.723823 -132.665198) (xy 200.70831 -132.723091) (xy 200.685374 -132.778464)
			(xy 200.655407 -132.83037) (xy 200.61892 -132.87792) (xy 200.57654 -132.9203) (xy 200.52899 -132.956787)
			(xy 200.477084 -132.986754) (xy 200.421711 -133.00969) (xy 200.363818 -133.025203) (xy 200.304396 -133.033026)
			(xy 200.24446 -133.033026) (xy 200.185038 -133.025203) (xy 200.127145 -133.00969) (xy 200.071772 -132.986754)
			(xy 200.019866 -132.956787) (xy 199.972316 -132.9203) (xy 199.929936 -132.87792) (xy 199.893449 -132.83037)
			(xy 199.863482 -132.778464) (xy 199.840546 -132.723091) (xy 199.825033 -132.665198) (xy 199.81721 -132.605776)
			(xy 199.81672 -132.575808) (xy 181.760876 -132.575808) (xy 181.760876 -132.577332) (xy 181.760386 -132.6073)
			(xy 181.752563 -132.666722) (xy 181.73705 -132.724615) (xy 181.714114 -132.779988) (xy 181.684147 -132.831894)
			(xy 181.64766 -132.879444) (xy 181.60528 -132.921824) (xy 181.55773 -132.958311) (xy 181.505824 -132.988278)
			(xy 181.450451 -133.011214) (xy 181.392558 -133.026727) (xy 181.333136 -133.03455) (xy 181.2732 -133.03455)
			(xy 181.213778 -133.026727) (xy 181.155885 -133.011214) (xy 181.100512 -132.988278) (xy 181.048606 -132.958311)
			(xy 181.001056 -132.921824) (xy 180.958676 -132.879444) (xy 180.922189 -132.831894) (xy 180.892222 -132.779988)
			(xy 180.869286 -132.724615) (xy 180.853773 -132.666722) (xy 180.84595 -132.6073) (xy 180.84546 -132.577332)
			(xy 168.80078 -132.577332) (xy 168.80078 -133.096508) (xy 168.80029 -133.126492) (xy 168.792462 -133.185948)
			(xy 168.776941 -133.243873) (xy 168.753992 -133.299277) (xy 168.724008 -133.351211) (xy 168.687502 -133.398787)
			(xy 168.645097 -133.441192) (xy 168.597521 -133.477698) (xy 168.545587 -133.507682) (xy 168.490183 -133.530631)
			(xy 168.432258 -133.546152) (xy 168.372802 -133.55398) (xy 168.312834 -133.55398) (xy 168.253378 -133.546152)
			(xy 168.195453 -133.530631) (xy 168.140049 -133.507682) (xy 168.088115 -133.477698) (xy 168.040539 -133.441192)
			(xy 167.998134 -133.398787) (xy 167.961628 -133.351211) (xy 167.931644 -133.299277) (xy 167.908695 -133.243873)
			(xy 167.893174 -133.185948) (xy 167.885346 -133.126492) (xy 167.884856 -133.096508) (xy 154.325828 -133.096508)
			(xy 154.325828 -133.104382) (xy 154.325338 -133.134366) (xy 154.31751 -133.193822) (xy 154.301989 -133.251747)
			(xy 154.27904 -133.307151) (xy 154.249056 -133.359085) (xy 154.21255 -133.406661) (xy 154.170145 -133.449066)
			(xy 154.122569 -133.485572) (xy 154.070635 -133.515556) (xy 154.015231 -133.538505) (xy 153.957306 -133.554026)
			(xy 153.89785 -133.561854) (xy 153.837882 -133.561854) (xy 153.778426 -133.554026) (xy 153.720501 -133.538505)
			(xy 153.665097 -133.515556) (xy 153.613163 -133.485572) (xy 153.565587 -133.449066) (xy 153.523182 -133.406661)
			(xy 153.486676 -133.359085) (xy 153.456692 -133.307151) (xy 153.433743 -133.251747) (xy 153.418222 -133.193822)
			(xy 153.410394 -133.134366) (xy 153.409904 -133.104382) (xy 81.752059 -133.104382) (xy 81.786925 -133.124512)
			(xy 81.834501 -133.161018) (xy 81.876906 -133.203423) (xy 81.913412 -133.250999) (xy 81.943396 -133.302933)
			(xy 81.966345 -133.358337) (xy 81.981866 -133.416262) (xy 81.989694 -133.475718) (xy 81.990184 -133.505702)
			(xy 81.990184 -134.369302) (xy 81.989694 -134.399286) (xy 81.981866 -134.458742) (xy 81.966345 -134.516667)
			(xy 81.943396 -134.572071) (xy 81.913412 -134.624005) (xy 81.876906 -134.671581) (xy 81.834501 -134.713986)
			(xy 81.786925 -134.750492) (xy 81.734991 -134.780476) (xy 81.679587 -134.803425) (xy 81.621662 -134.818946)
			(xy 81.562206 -134.826774) (xy 81.502238 -134.826774) (xy 81.442782 -134.818946) (xy 81.384857 -134.803425)
			(xy 81.329453 -134.780476) (xy 81.277519 -134.750492) (xy 81.229943 -134.713986) (xy 81.187538 -134.671581)
			(xy 81.151032 -134.624005) (xy 81.121048 -134.572071) (xy 81.098099 -134.516667) (xy 81.082578 -134.458742)
			(xy 81.07475 -134.399286) (xy 81.07426 -134.369302) (xy 67.515232 -134.369302) (xy 67.515232 -134.377176)
			(xy 67.514742 -134.40716) (xy 67.506914 -134.466616) (xy 67.491393 -134.524541) (xy 67.468444 -134.579945)
			(xy 67.43846 -134.631879) (xy 67.401954 -134.679455) (xy 67.359549 -134.72186) (xy 67.311973 -134.758366)
			(xy 67.260039 -134.78835) (xy 67.204635 -134.811299) (xy 67.14671 -134.82682) (xy 67.087254 -134.834648)
			(xy 67.027286 -134.834648) (xy 66.96783 -134.82682) (xy 66.909905 -134.811299) (xy 66.854501 -134.78835)
			(xy 66.802567 -134.758366) (xy 66.754991 -134.72186) (xy 66.712586 -134.679455) (xy 66.67608 -134.631879)
			(xy 66.646096 -134.579945) (xy 66.623147 -134.524541) (xy 66.607626 -134.466616) (xy 66.599798 -134.40716)
			(xy 66.599308 -134.377176) (xy 54.554628 -134.377176) (xy 54.554628 -134.896352) (xy 54.554138 -134.92632)
			(xy 54.546315 -134.985742) (xy 54.530802 -135.043635) (xy 54.507866 -135.099008) (xy 54.477899 -135.150914)
			(xy 54.441412 -135.198464) (xy 54.399032 -135.240844) (xy 54.351482 -135.277331) (xy 54.299576 -135.307298)
			(xy 54.244203 -135.330234) (xy 54.18631 -135.345747) (xy 54.126888 -135.35357) (xy 54.066952 -135.35357)
			(xy 54.00753 -135.345747) (xy 53.949637 -135.330234) (xy 53.894264 -135.307298) (xy 53.842358 -135.277331)
			(xy 53.794808 -135.240844) (xy 53.752428 -135.198464) (xy 53.715941 -135.150914) (xy 53.685974 -135.099008)
			(xy 53.663038 -135.043635) (xy 53.647525 -134.985742) (xy 53.639702 -134.92632) (xy 53.639212 -134.896352)
			(xy 35.583368 -134.896352) (xy 35.583368 -134.897876) (xy 35.582878 -134.927844) (xy 35.575055 -134.987266)
			(xy 35.559542 -135.045159) (xy 35.536606 -135.100532) (xy 35.506639 -135.152438) (xy 35.470152 -135.199988)
			(xy 35.427772 -135.242368) (xy 35.380222 -135.278855) (xy 35.328316 -135.308822) (xy 35.272943 -135.331758)
			(xy 35.21505 -135.347271) (xy 35.155628 -135.355094) (xy 35.095692 -135.355094) (xy 35.03627 -135.347271)
			(xy 34.978377 -135.331758) (xy 34.923004 -135.308822) (xy 34.871098 -135.278855) (xy 34.823548 -135.242368)
			(xy 34.781168 -135.199988) (xy 34.744681 -135.152438) (xy 34.714714 -135.100532) (xy 34.691778 -135.045159)
			(xy 34.676265 -134.987266) (xy 34.668442 -134.927844) (xy 34.667952 -134.897876) (xy 4.30911 -134.897876)
			(xy 4.30911 -136.704324) (xy 37.31006 -136.704324) (xy 37.31006 -135.840724) (xy 37.31055 -135.810756)
			(xy 37.318373 -135.751334) (xy 37.333886 -135.693441) (xy 37.356822 -135.638068) (xy 37.386789 -135.586162)
			(xy 37.423276 -135.538612) (xy 37.465656 -135.496232) (xy 37.513206 -135.459745) (xy 37.565112 -135.429778)
			(xy 37.620485 -135.406842) (xy 37.678378 -135.391329) (xy 37.7378 -135.383506) (xy 37.797736 -135.383506)
			(xy 37.857158 -135.391329) (xy 37.915051 -135.406842) (xy 37.970424 -135.429778) (xy 38.02233 -135.459745)
			(xy 38.06988 -135.496232) (xy 38.11226 -135.538612) (xy 38.148747 -135.586162) (xy 38.178714 -135.638068)
			(xy 38.20165 -135.693441) (xy 38.217163 -135.751334) (xy 38.224986 -135.810756) (xy 38.225476 -135.840724)
			(xy 38.225476 -136.69645) (xy 51.785012 -136.69645) (xy 51.785012 -135.83285) (xy 51.785502 -135.802882)
			(xy 51.793325 -135.74346) (xy 51.808838 -135.685567) (xy 51.831774 -135.630194) (xy 51.861741 -135.578288)
			(xy 51.898228 -135.530738) (xy 51.940608 -135.488358) (xy 51.988158 -135.451871) (xy 52.040064 -135.421904)
			(xy 52.095437 -135.398968) (xy 52.15333 -135.383455) (xy 52.212752 -135.375632) (xy 52.272688 -135.375632)
			(xy 52.33211 -135.383455) (xy 52.390003 -135.398968) (xy 52.445376 -135.421904) (xy 52.497282 -135.451871)
			(xy 52.544832 -135.488358) (xy 52.587212 -135.530738) (xy 52.623699 -135.578288) (xy 52.653666 -135.630194)
			(xy 52.676602 -135.685567) (xy 52.692115 -135.74346) (xy 52.699938 -135.802882) (xy 52.700428 -135.83285)
			(xy 52.700428 -136.177274) (xy 64.745108 -136.177274) (xy 64.745108 -135.313674) (xy 64.745598 -135.28369)
			(xy 64.753426 -135.224234) (xy 64.768947 -135.166309) (xy 64.791896 -135.110905) (xy 64.82188 -135.058971)
			(xy 64.858386 -135.011395) (xy 64.900791 -134.96899) (xy 64.948367 -134.932484) (xy 65.000301 -134.9025)
			(xy 65.055705 -134.879551) (xy 65.11363 -134.86403) (xy 65.173086 -134.856202) (xy 65.233054 -134.856202)
			(xy 65.29251 -134.86403) (xy 65.350435 -134.879551) (xy 65.405839 -134.9025) (xy 65.457773 -134.932484)
			(xy 65.505349 -134.96899) (xy 65.547754 -135.011395) (xy 65.58426 -135.058971) (xy 65.614244 -135.110905)
			(xy 65.637193 -135.166309) (xy 65.652714 -135.224234) (xy 65.660542 -135.28369) (xy 65.661032 -135.313674)
			(xy 65.661032 -136.17575) (xy 83.716368 -136.17575) (xy 83.716368 -135.31215) (xy 83.716858 -135.282166)
			(xy 83.724686 -135.22271) (xy 83.740207 -135.164785) (xy 83.763156 -135.109381) (xy 83.79314 -135.057447)
			(xy 83.829646 -135.009871) (xy 83.872051 -134.967466) (xy 83.919627 -134.93096) (xy 83.971561 -134.900976)
			(xy 84.026965 -134.878027) (xy 84.08489 -134.862506) (xy 84.144346 -134.854678) (xy 84.204314 -134.854678)
			(xy 84.26377 -134.862506) (xy 84.321695 -134.878027) (xy 84.369615 -134.897876) (xy 150.767796 -134.897876)
			(xy 150.767796 -134.034276) (xy 150.768286 -134.004292) (xy 150.776114 -133.944836) (xy 150.791635 -133.886911)
			(xy 150.814584 -133.831507) (xy 150.844568 -133.779573) (xy 150.881074 -133.731997) (xy 150.923479 -133.689592)
			(xy 150.971055 -133.653086) (xy 151.022989 -133.623102) (xy 151.078393 -133.600153) (xy 151.136318 -133.584632)
			(xy 151.195774 -133.576804) (xy 151.255742 -133.576804) (xy 151.315198 -133.584632) (xy 151.373123 -133.600153)
			(xy 151.428527 -133.623102) (xy 151.480461 -133.653086) (xy 151.528037 -133.689592) (xy 151.570442 -133.731997)
			(xy 151.606948 -133.779573) (xy 151.636932 -133.831507) (xy 151.659881 -133.886911) (xy 151.675402 -133.944836)
			(xy 151.68323 -134.004292) (xy 151.68372 -134.034276) (xy 151.68372 -134.896352) (xy 169.739056 -134.896352)
			(xy 169.739056 -134.032752) (xy 169.739546 -134.002768) (xy 169.747374 -133.943312) (xy 169.762895 -133.885387)
			(xy 169.785844 -133.829983) (xy 169.815828 -133.778049) (xy 169.852334 -133.730473) (xy 169.894739 -133.688068)
			(xy 169.942315 -133.651562) (xy 169.994249 -133.621578) (xy 170.049653 -133.598629) (xy 170.107578 -133.583108)
			(xy 170.167034 -133.57528) (xy 170.227002 -133.57528) (xy 170.286458 -133.583108) (xy 170.344383 -133.598629)
			(xy 170.399787 -133.621578) (xy 170.451721 -133.651562) (xy 170.499297 -133.688068) (xy 170.541702 -133.730473)
			(xy 170.578208 -133.778049) (xy 170.608192 -133.829983) (xy 170.631141 -133.885387) (xy 170.646662 -133.943312)
			(xy 170.65449 -134.002768) (xy 170.65498 -134.032752) (xy 170.65498 -134.377176) (xy 182.69966 -134.377176)
			(xy 182.69966 -133.513576) (xy 182.70015 -133.483608) (xy 182.707973 -133.424186) (xy 182.723486 -133.366293)
			(xy 182.746422 -133.31092) (xy 182.776389 -133.259014) (xy 182.812876 -133.211464) (xy 182.855256 -133.169084)
			(xy 182.902806 -133.132597) (xy 182.954712 -133.10263) (xy 183.010085 -133.079694) (xy 183.067978 -133.064181)
			(xy 183.1274 -133.056358) (xy 183.187336 -133.056358) (xy 183.246758 -133.064181) (xy 183.304651 -133.079694)
			(xy 183.360024 -133.10263) (xy 183.41193 -133.132597) (xy 183.45948 -133.169084) (xy 183.50186 -133.211464)
			(xy 183.538347 -133.259014) (xy 183.568314 -133.31092) (xy 183.59125 -133.366293) (xy 183.606763 -133.424186)
			(xy 183.614586 -133.483608) (xy 183.615076 -133.513576) (xy 183.615076 -134.369302) (xy 197.174612 -134.369302)
			(xy 197.174612 -133.505702) (xy 197.175102 -133.475734) (xy 197.182925 -133.416312) (xy 197.198438 -133.358419)
			(xy 197.221374 -133.303046) (xy 197.251341 -133.25114) (xy 197.287828 -133.20359) (xy 197.330208 -133.16121)
			(xy 197.377758 -133.124723) (xy 197.429664 -133.094756) (xy 197.485037 -133.07182) (xy 197.54293 -133.056307)
			(xy 197.602352 -133.048484) (xy 197.662288 -133.048484) (xy 197.72171 -133.056307) (xy 197.779603 -133.07182)
			(xy 197.834976 -133.094756) (xy 197.851649 -133.104382) (xy 269.509748 -133.104382) (xy 269.509748 -132.240782)
			(xy 269.510238 -132.210798) (xy 269.518066 -132.151342) (xy 269.533587 -132.093417) (xy 269.556536 -132.038013)
			(xy 269.58652 -131.986079) (xy 269.623026 -131.938503) (xy 269.665431 -131.896098) (xy 269.713007 -131.859592)
			(xy 269.764941 -131.829608) (xy 269.820345 -131.806659) (xy 269.87827 -131.791138) (xy 269.937726 -131.78331)
			(xy 269.997694 -131.78331) (xy 270.05715 -131.791138) (xy 270.115075 -131.806659) (xy 270.170479 -131.829608)
			(xy 270.222413 -131.859592) (xy 270.269989 -131.896098) (xy 270.312394 -131.938503) (xy 270.3489 -131.986079)
			(xy 270.378884 -132.038013) (xy 270.401833 -132.093417) (xy 270.417354 -132.151342) (xy 270.425182 -132.210798)
			(xy 270.425672 -132.240782) (xy 270.425672 -133.096508) (xy 283.9847 -133.096508) (xy 283.9847 -132.232908)
			(xy 283.98519 -132.202924) (xy 283.993018 -132.143468) (xy 284.008539 -132.085543) (xy 284.031488 -132.030139)
			(xy 284.061472 -131.978205) (xy 284.097978 -131.930629) (xy 284.140383 -131.888224) (xy 284.187959 -131.851718)
			(xy 284.239893 -131.821734) (xy 284.295297 -131.798785) (xy 284.353222 -131.783264) (xy 284.412678 -131.775436)
			(xy 284.472646 -131.775436) (xy 284.532102 -131.783264) (xy 284.590027 -131.798785) (xy 284.645431 -131.821734)
			(xy 284.697365 -131.851718) (xy 284.744941 -131.888224) (xy 284.787346 -131.930629) (xy 284.823852 -131.978205)
			(xy 284.853836 -132.030139) (xy 284.876785 -132.085543) (xy 284.892306 -132.143468) (xy 284.900134 -132.202924)
			(xy 284.900624 -132.232908) (xy 284.900624 -132.577332) (xy 296.945304 -132.577332) (xy 296.945304 -131.713732)
			(xy 296.945794 -131.683764) (xy 296.953617 -131.624342) (xy 296.96913 -131.566449) (xy 296.992066 -131.511076)
			(xy 297.022033 -131.45917) (xy 297.05852 -131.41162) (xy 297.1009 -131.36924) (xy 297.14845 -131.332753)
			(xy 297.200356 -131.302786) (xy 297.255729 -131.27985) (xy 297.313622 -131.264337) (xy 297.373044 -131.256514)
			(xy 297.43298 -131.256514) (xy 297.492402 -131.264337) (xy 297.550295 -131.27985) (xy 297.605668 -131.302786)
			(xy 297.657574 -131.332753) (xy 297.705124 -131.36924) (xy 297.747504 -131.41162) (xy 297.783991 -131.45917)
			(xy 297.813958 -131.511076) (xy 297.836894 -131.566449) (xy 297.852407 -131.624342) (xy 297.86023 -131.683764)
			(xy 297.86072 -131.713732) (xy 297.86072 -132.575808) (xy 315.916564 -132.575808) (xy 315.916564 -131.712208)
			(xy 315.917054 -131.68224) (xy 315.924877 -131.622818) (xy 315.94039 -131.564925) (xy 315.963326 -131.509552)
			(xy 315.993293 -131.457646) (xy 316.02978 -131.410096) (xy 316.07216 -131.367716) (xy 316.11971 -131.331229)
			(xy 316.171616 -131.301262) (xy 316.226989 -131.278326) (xy 316.284882 -131.262813) (xy 316.344304 -131.25499)
			(xy 316.40424 -131.25499) (xy 316.463662 -131.262813) (xy 316.521555 -131.278326) (xy 316.568893 -131.297934)
			(xy 382.967992 -131.297934) (xy 382.967992 -130.434334) (xy 382.968482 -130.404366) (xy 382.976305 -130.344944)
			(xy 382.991818 -130.287051) (xy 383.014754 -130.231678) (xy 383.044721 -130.179772) (xy 383.081208 -130.132222)
			(xy 383.123588 -130.089842) (xy 383.171138 -130.053355) (xy 383.223044 -130.023388) (xy 383.278417 -130.000452)
			(xy 383.33631 -129.984939) (xy 383.395732 -129.977116) (xy 383.455668 -129.977116) (xy 383.51509 -129.984939)
			(xy 383.572983 -130.000452) (xy 383.628356 -130.023388) (xy 383.680262 -130.053355) (xy 383.727812 -130.089842)
			(xy 383.770192 -130.132222) (xy 383.806679 -130.179772) (xy 383.836646 -130.231678) (xy 383.859582 -130.287051)
			(xy 383.875095 -130.344944) (xy 383.882918 -130.404366) (xy 383.883408 -130.434334) (xy 383.883408 -131.29641)
			(xy 401.939252 -131.29641) (xy 401.939252 -130.43281) (xy 401.939742 -130.402842) (xy 401.947565 -130.34342)
			(xy 401.963078 -130.285527) (xy 401.986014 -130.230154) (xy 402.015981 -130.178248) (xy 402.052468 -130.130698)
			(xy 402.094848 -130.088318) (xy 402.142398 -130.051831) (xy 402.194304 -130.021864) (xy 402.249677 -129.998928)
			(xy 402.30757 -129.983415) (xy 402.366992 -129.975592) (xy 402.426928 -129.975592) (xy 402.48635 -129.983415)
			(xy 402.544243 -129.998928) (xy 402.599616 -130.021864) (xy 402.651522 -130.051831) (xy 402.699072 -130.088318)
			(xy 402.741452 -130.130698) (xy 402.777939 -130.178248) (xy 402.807906 -130.230154) (xy 402.830842 -130.285527)
			(xy 402.846355 -130.34342) (xy 402.854178 -130.402842) (xy 402.854668 -130.43281) (xy 402.854668 -130.777234)
			(xy 414.899348 -130.777234) (xy 414.899348 -129.913634) (xy 414.899838 -129.88365) (xy 414.907666 -129.824194)
			(xy 414.923187 -129.766269) (xy 414.946136 -129.710865) (xy 414.97612 -129.658931) (xy 415.012626 -129.611355)
			(xy 415.055031 -129.56895) (xy 415.102607 -129.532444) (xy 415.154541 -129.50246) (xy 415.209945 -129.479511)
			(xy 415.26787 -129.46399) (xy 415.327326 -129.456162) (xy 415.387294 -129.456162) (xy 415.44675 -129.46399)
			(xy 415.504675 -129.479511) (xy 415.560079 -129.50246) (xy 415.612013 -129.532444) (xy 415.659589 -129.56895)
			(xy 415.701994 -129.611355) (xy 415.7385 -129.658931) (xy 415.768484 -129.710865) (xy 415.791433 -129.766269)
			(xy 415.806954 -129.824194) (xy 415.814782 -129.88365) (xy 415.815272 -129.913634) (xy 415.815272 -130.769106)
			(xy 429.3743 -130.769106) (xy 429.3743 -129.905506) (xy 429.37479 -129.875522) (xy 429.382618 -129.816066)
			(xy 429.398139 -129.758141) (xy 429.421088 -129.702737) (xy 429.451072 -129.650803) (xy 429.487578 -129.603227)
			(xy 429.529983 -129.560822) (xy 429.577559 -129.524316) (xy 429.629493 -129.494332) (xy 429.684897 -129.471383)
			(xy 429.742822 -129.455862) (xy 429.802278 -129.448034) (xy 429.862246 -129.448034) (xy 429.921702 -129.455862)
			(xy 429.979627 -129.471383) (xy 430.035031 -129.494332) (xy 430.086965 -129.524316) (xy 430.134541 -129.560822)
			(xy 430.176946 -129.603227) (xy 430.213452 -129.650803) (xy 430.243436 -129.702737) (xy 430.266385 -129.758141)
			(xy 430.281906 -129.816066) (xy 430.289734 -129.875522) (xy 430.290224 -129.905506) (xy 430.290224 -130.769106)
			(xy 430.289734 -130.79909) (xy 430.281906 -130.858546) (xy 430.266385 -130.916471) (xy 430.243436 -130.971875)
			(xy 430.213452 -131.023809) (xy 430.176946 -131.071385) (xy 430.134541 -131.11379) (xy 430.086965 -131.150296)
			(xy 430.035031 -131.18028) (xy 429.979627 -131.203229) (xy 429.921702 -131.21875) (xy 429.862246 -131.226578)
			(xy 429.802278 -131.226578) (xy 429.742822 -131.21875) (xy 429.684897 -131.203229) (xy 429.629493 -131.18028)
			(xy 429.577559 -131.150296) (xy 429.529983 -131.11379) (xy 429.487578 -131.071385) (xy 429.451072 -131.023809)
			(xy 429.421088 -130.971875) (xy 429.398139 -130.916471) (xy 429.382618 -130.858546) (xy 429.37479 -130.79909)
			(xy 429.3743 -130.769106) (xy 415.815272 -130.769106) (xy 415.815272 -130.777234) (xy 415.814782 -130.807218)
			(xy 415.806954 -130.866674) (xy 415.791433 -130.924599) (xy 415.768484 -130.980003) (xy 415.7385 -131.031937)
			(xy 415.701994 -131.079513) (xy 415.659589 -131.121918) (xy 415.612013 -131.158424) (xy 415.560079 -131.188408)
			(xy 415.504675 -131.211357) (xy 415.44675 -131.226878) (xy 415.387294 -131.234706) (xy 415.327326 -131.234706)
			(xy 415.26787 -131.226878) (xy 415.209945 -131.211357) (xy 415.154541 -131.188408) (xy 415.102607 -131.158424)
			(xy 415.055031 -131.121918) (xy 415.012626 -131.079513) (xy 414.97612 -131.031937) (xy 414.946136 -130.980003)
			(xy 414.923187 -130.924599) (xy 414.907666 -130.866674) (xy 414.899838 -130.807218) (xy 414.899348 -130.777234)
			(xy 402.854668 -130.777234) (xy 402.854668 -131.29641) (xy 402.854178 -131.326378) (xy 402.846355 -131.3858)
			(xy 402.830842 -131.443693) (xy 402.807906 -131.499066) (xy 402.777939 -131.550972) (xy 402.741452 -131.598522)
			(xy 402.699072 -131.640902) (xy 402.651522 -131.677389) (xy 402.599616 -131.707356) (xy 402.544243 -131.730292)
			(xy 402.48635 -131.745805) (xy 402.426928 -131.753628) (xy 402.366992 -131.753628) (xy 402.30757 -131.745805)
			(xy 402.249677 -131.730292) (xy 402.194304 -131.707356) (xy 402.142398 -131.677389) (xy 402.094848 -131.640902)
			(xy 402.052468 -131.598522) (xy 402.015981 -131.550972) (xy 401.986014 -131.499066) (xy 401.963078 -131.443693)
			(xy 401.947565 -131.3858) (xy 401.939742 -131.326378) (xy 401.939252 -131.29641) (xy 383.883408 -131.29641)
			(xy 383.883408 -131.297934) (xy 383.882918 -131.327902) (xy 383.875095 -131.387324) (xy 383.859582 -131.445217)
			(xy 383.836646 -131.50059) (xy 383.806679 -131.552496) (xy 383.770192 -131.600046) (xy 383.727812 -131.642426)
			(xy 383.680262 -131.678913) (xy 383.628356 -131.70888) (xy 383.572983 -131.731816) (xy 383.51509 -131.747329)
			(xy 383.455668 -131.755152) (xy 383.395732 -131.755152) (xy 383.33631 -131.747329) (xy 383.278417 -131.731816)
			(xy 383.223044 -131.70888) (xy 383.171138 -131.678913) (xy 383.123588 -131.642426) (xy 383.081208 -131.600046)
			(xy 383.044721 -131.552496) (xy 383.014754 -131.50059) (xy 382.991818 -131.445217) (xy 382.976305 -131.387324)
			(xy 382.968482 -131.327902) (xy 382.967992 -131.297934) (xy 316.568893 -131.297934) (xy 316.576928 -131.301262)
			(xy 316.628834 -131.331229) (xy 316.676384 -131.367716) (xy 316.718764 -131.410096) (xy 316.755251 -131.457646)
			(xy 316.785218 -131.509552) (xy 316.808154 -131.564925) (xy 316.823667 -131.622818) (xy 316.83149 -131.68224)
			(xy 316.83198 -131.712208) (xy 316.83198 -132.575808) (xy 316.83149 -132.605776) (xy 316.823667 -132.665198)
			(xy 316.808154 -132.723091) (xy 316.785218 -132.778464) (xy 316.755251 -132.83037) (xy 316.718764 -132.87792)
			(xy 316.676384 -132.9203) (xy 316.628834 -132.956787) (xy 316.576928 -132.986754) (xy 316.521555 -133.00969)
			(xy 316.463662 -133.025203) (xy 316.40424 -133.033026) (xy 316.344304 -133.033026) (xy 316.284882 -133.025203)
			(xy 316.226989 -133.00969) (xy 316.171616 -132.986754) (xy 316.11971 -132.956787) (xy 316.07216 -132.9203)
			(xy 316.02978 -132.87792) (xy 315.993293 -132.83037) (xy 315.963326 -132.778464) (xy 315.94039 -132.723091)
			(xy 315.924877 -132.665198) (xy 315.917054 -132.605776) (xy 315.916564 -132.575808) (xy 297.86072 -132.575808)
			(xy 297.86072 -132.577332) (xy 297.86023 -132.6073) (xy 297.852407 -132.666722) (xy 297.836894 -132.724615)
			(xy 297.813958 -132.779988) (xy 297.783991 -132.831894) (xy 297.747504 -132.879444) (xy 297.705124 -132.921824)
			(xy 297.657574 -132.958311) (xy 297.605668 -132.988278) (xy 297.550295 -133.011214) (xy 297.492402 -133.026727)
			(xy 297.43298 -133.03455) (xy 297.373044 -133.03455) (xy 297.313622 -133.026727) (xy 297.255729 -133.011214)
			(xy 297.200356 -132.988278) (xy 297.14845 -132.958311) (xy 297.1009 -132.921824) (xy 297.05852 -132.879444)
			(xy 297.022033 -132.831894) (xy 296.992066 -132.779988) (xy 296.96913 -132.724615) (xy 296.953617 -132.666722)
			(xy 296.945794 -132.6073) (xy 296.945304 -132.577332) (xy 284.900624 -132.577332) (xy 284.900624 -133.096508)
			(xy 284.900134 -133.126492) (xy 284.892306 -133.185948) (xy 284.876785 -133.243873) (xy 284.853836 -133.299277)
			(xy 284.823852 -133.351211) (xy 284.787346 -133.398787) (xy 284.744941 -133.441192) (xy 284.697365 -133.477698)
			(xy 284.645431 -133.507682) (xy 284.590027 -133.530631) (xy 284.532102 -133.546152) (xy 284.472646 -133.55398)
			(xy 284.412678 -133.55398) (xy 284.353222 -133.546152) (xy 284.295297 -133.530631) (xy 284.239893 -133.507682)
			(xy 284.187959 -133.477698) (xy 284.140383 -133.441192) (xy 284.097978 -133.398787) (xy 284.061472 -133.351211)
			(xy 284.031488 -133.299277) (xy 284.008539 -133.243873) (xy 283.993018 -133.185948) (xy 283.98519 -133.126492)
			(xy 283.9847 -133.096508) (xy 270.425672 -133.096508) (xy 270.425672 -133.104382) (xy 270.425182 -133.134366)
			(xy 270.417354 -133.193822) (xy 270.401833 -133.251747) (xy 270.378884 -133.307151) (xy 270.3489 -133.359085)
			(xy 270.312394 -133.406661) (xy 270.269989 -133.449066) (xy 270.222413 -133.485572) (xy 270.170479 -133.515556)
			(xy 270.115075 -133.538505) (xy 270.05715 -133.554026) (xy 269.997694 -133.561854) (xy 269.937726 -133.561854)
			(xy 269.87827 -133.554026) (xy 269.820345 -133.538505) (xy 269.764941 -133.515556) (xy 269.713007 -133.485572)
			(xy 269.665431 -133.449066) (xy 269.623026 -133.406661) (xy 269.58652 -133.359085) (xy 269.556536 -133.307151)
			(xy 269.533587 -133.251747) (xy 269.518066 -133.193822) (xy 269.510238 -133.134366) (xy 269.509748 -133.104382)
			(xy 197.851649 -133.104382) (xy 197.886882 -133.124723) (xy 197.934432 -133.16121) (xy 197.976812 -133.20359)
			(xy 198.013299 -133.25114) (xy 198.043266 -133.303046) (xy 198.066202 -133.358419) (xy 198.081715 -133.416312)
			(xy 198.089538 -133.475734) (xy 198.090028 -133.505702) (xy 198.090028 -134.369302) (xy 198.089538 -134.39927)
			(xy 198.081715 -134.458692) (xy 198.066202 -134.516585) (xy 198.043266 -134.571958) (xy 198.013299 -134.623864)
			(xy 197.976812 -134.671414) (xy 197.934432 -134.713794) (xy 197.886882 -134.750281) (xy 197.834976 -134.780248)
			(xy 197.779603 -134.803184) (xy 197.72171 -134.818697) (xy 197.662288 -134.82652) (xy 197.602352 -134.82652)
			(xy 197.54293 -134.818697) (xy 197.485037 -134.803184) (xy 197.429664 -134.780248) (xy 197.377758 -134.750281)
			(xy 197.330208 -134.713794) (xy 197.287828 -134.671414) (xy 197.251341 -134.623864) (xy 197.221374 -134.571958)
			(xy 197.198438 -134.516585) (xy 197.182925 -134.458692) (xy 197.175102 -134.39927) (xy 197.174612 -134.369302)
			(xy 183.615076 -134.369302) (xy 183.615076 -134.377176) (xy 183.614586 -134.407144) (xy 183.606763 -134.466566)
			(xy 183.59125 -134.524459) (xy 183.568314 -134.579832) (xy 183.538347 -134.631738) (xy 183.50186 -134.679288)
			(xy 183.45948 -134.721668) (xy 183.41193 -134.758155) (xy 183.360024 -134.788122) (xy 183.304651 -134.811058)
			(xy 183.246758 -134.826571) (xy 183.187336 -134.834394) (xy 183.1274 -134.834394) (xy 183.067978 -134.826571)
			(xy 183.010085 -134.811058) (xy 182.954712 -134.788122) (xy 182.902806 -134.758155) (xy 182.855256 -134.721668)
			(xy 182.812876 -134.679288) (xy 182.776389 -134.631738) (xy 182.746422 -134.579832) (xy 182.723486 -134.524459)
			(xy 182.707973 -134.466566) (xy 182.70015 -134.407144) (xy 182.69966 -134.377176) (xy 170.65498 -134.377176)
			(xy 170.65498 -134.896352) (xy 170.65449 -134.926336) (xy 170.646662 -134.985792) (xy 170.631141 -135.043717)
			(xy 170.608192 -135.099121) (xy 170.578208 -135.151055) (xy 170.541702 -135.198631) (xy 170.499297 -135.241036)
			(xy 170.451721 -135.277542) (xy 170.399787 -135.307526) (xy 170.344383 -135.330475) (xy 170.286458 -135.345996)
			(xy 170.227002 -135.353824) (xy 170.167034 -135.353824) (xy 170.107578 -135.345996) (xy 170.049653 -135.330475)
			(xy 169.994249 -135.307526) (xy 169.942315 -135.277542) (xy 169.894739 -135.241036) (xy 169.852334 -135.198631)
			(xy 169.815828 -135.151055) (xy 169.785844 -135.099121) (xy 169.762895 -135.043717) (xy 169.747374 -134.985792)
			(xy 169.739546 -134.926336) (xy 169.739056 -134.896352) (xy 151.68372 -134.896352) (xy 151.68372 -134.897876)
			(xy 151.68323 -134.92786) (xy 151.675402 -134.987316) (xy 151.659881 -135.045241) (xy 151.636932 -135.100645)
			(xy 151.606948 -135.152579) (xy 151.570442 -135.200155) (xy 151.528037 -135.24256) (xy 151.480461 -135.279066)
			(xy 151.428527 -135.30905) (xy 151.373123 -135.331999) (xy 151.315198 -135.34752) (xy 151.255742 -135.355348)
			(xy 151.195774 -135.355348) (xy 151.136318 -135.34752) (xy 151.078393 -135.331999) (xy 151.022989 -135.30905)
			(xy 150.971055 -135.279066) (xy 150.923479 -135.24256) (xy 150.881074 -135.200155) (xy 150.844568 -135.152579)
			(xy 150.814584 -135.100645) (xy 150.791635 -135.045241) (xy 150.776114 -134.987316) (xy 150.768286 -134.92786)
			(xy 150.767796 -134.897876) (xy 84.369615 -134.897876) (xy 84.377099 -134.900976) (xy 84.429033 -134.93096)
			(xy 84.476609 -134.967466) (xy 84.519014 -135.009871) (xy 84.55552 -135.057447) (xy 84.585504 -135.109381)
			(xy 84.608453 -135.164785) (xy 84.623974 -135.22271) (xy 84.631802 -135.282166) (xy 84.632292 -135.31215)
			(xy 84.632292 -136.17575) (xy 84.631802 -136.205734) (xy 84.623974 -136.26519) (xy 84.608453 -136.323115)
			(xy 84.585504 -136.378519) (xy 84.55552 -136.430453) (xy 84.519014 -136.478029) (xy 84.476609 -136.520434)
			(xy 84.429033 -136.55694) (xy 84.377099 -136.586924) (xy 84.321695 -136.609873) (xy 84.26377 -136.625394)
			(xy 84.204314 -136.633222) (xy 84.144346 -136.633222) (xy 84.08489 -136.625394) (xy 84.026965 -136.609873)
			(xy 83.971561 -136.586924) (xy 83.919627 -136.55694) (xy 83.872051 -136.520434) (xy 83.829646 -136.478029)
			(xy 83.79314 -136.430453) (xy 83.763156 -136.378519) (xy 83.740207 -136.323115) (xy 83.724686 -136.26519)
			(xy 83.716858 -136.205734) (xy 83.716368 -136.17575) (xy 65.661032 -136.17575) (xy 65.661032 -136.177274)
			(xy 65.660542 -136.207258) (xy 65.652714 -136.266714) (xy 65.637193 -136.324639) (xy 65.614244 -136.380043)
			(xy 65.58426 -136.431977) (xy 65.547754 -136.479553) (xy 65.505349 -136.521958) (xy 65.457773 -136.558464)
			(xy 65.405839 -136.588448) (xy 65.350435 -136.611397) (xy 65.29251 -136.626918) (xy 65.233054 -136.634746)
			(xy 65.173086 -136.634746) (xy 65.11363 -136.626918) (xy 65.055705 -136.611397) (xy 65.000301 -136.588448)
			(xy 64.948367 -136.558464) (xy 64.900791 -136.521958) (xy 64.858386 -136.479553) (xy 64.82188 -136.431977)
			(xy 64.791896 -136.380043) (xy 64.768947 -136.324639) (xy 64.753426 -136.266714) (xy 64.745598 -136.207258)
			(xy 64.745108 -136.177274) (xy 52.700428 -136.177274) (xy 52.700428 -136.69645) (xy 52.700299 -136.704324)
			(xy 153.409904 -136.704324) (xy 153.409904 -135.840724) (xy 153.410394 -135.81074) (xy 153.418222 -135.751284)
			(xy 153.433743 -135.693359) (xy 153.456692 -135.637955) (xy 153.486676 -135.586021) (xy 153.523182 -135.538445)
			(xy 153.565587 -135.49604) (xy 153.613163 -135.459534) (xy 153.665097 -135.42955) (xy 153.720501 -135.406601)
			(xy 153.778426 -135.39108) (xy 153.837882 -135.383252) (xy 153.89785 -135.383252) (xy 153.957306 -135.39108)
			(xy 154.015231 -135.406601) (xy 154.070635 -135.42955) (xy 154.122569 -135.459534) (xy 154.170145 -135.49604)
			(xy 154.21255 -135.538445) (xy 154.249056 -135.586021) (xy 154.27904 -135.637955) (xy 154.301989 -135.693359)
			(xy 154.31751 -135.751284) (xy 154.325338 -135.81074) (xy 154.325828 -135.840724) (xy 154.325828 -136.69645)
			(xy 167.884856 -136.69645) (xy 167.884856 -135.83285) (xy 167.885346 -135.802866) (xy 167.893174 -135.74341)
			(xy 167.908695 -135.685485) (xy 167.931644 -135.630081) (xy 167.961628 -135.578147) (xy 167.998134 -135.530571)
			(xy 168.040539 -135.488166) (xy 168.088115 -135.45166) (xy 168.140049 -135.421676) (xy 168.195453 -135.398727)
			(xy 168.253378 -135.383206) (xy 168.312834 -135.375378) (xy 168.372802 -135.375378) (xy 168.432258 -135.383206)
			(xy 168.490183 -135.398727) (xy 168.545587 -135.421676) (xy 168.597521 -135.45166) (xy 168.645097 -135.488166)
			(xy 168.687502 -135.530571) (xy 168.724008 -135.578147) (xy 168.753992 -135.630081) (xy 168.776941 -135.685485)
			(xy 168.792462 -135.74341) (xy 168.80029 -135.802866) (xy 168.80078 -135.83285) (xy 168.80078 -136.177274)
			(xy 180.84546 -136.177274) (xy 180.84546 -135.313674) (xy 180.84595 -135.283706) (xy 180.853773 -135.224284)
			(xy 180.869286 -135.166391) (xy 180.892222 -135.111018) (xy 180.922189 -135.059112) (xy 180.958676 -135.011562)
			(xy 181.001056 -134.969182) (xy 181.048606 -134.932695) (xy 181.100512 -134.902728) (xy 181.155885 -134.879792)
			(xy 181.213778 -134.864279) (xy 181.2732 -134.856456) (xy 181.333136 -134.856456) (xy 181.392558 -134.864279)
			(xy 181.450451 -134.879792) (xy 181.505824 -134.902728) (xy 181.55773 -134.932695) (xy 181.60528 -134.969182)
			(xy 181.64766 -135.011562) (xy 181.684147 -135.059112) (xy 181.714114 -135.111018) (xy 181.73705 -135.166391)
			(xy 181.752563 -135.224284) (xy 181.760386 -135.283706) (xy 181.760876 -135.313674) (xy 181.760876 -136.17575)
			(xy 199.81672 -136.17575) (xy 199.81672 -135.31215) (xy 199.81721 -135.282182) (xy 199.825033 -135.22276)
			(xy 199.840546 -135.164867) (xy 199.863482 -135.109494) (xy 199.893449 -135.057588) (xy 199.929936 -135.010038)
			(xy 199.972316 -134.967658) (xy 200.019866 -134.931171) (xy 200.071772 -134.901204) (xy 200.127145 -134.878268)
			(xy 200.185038 -134.862755) (xy 200.24446 -134.854932) (xy 200.304396 -134.854932) (xy 200.363818 -134.862755)
			(xy 200.421711 -134.878268) (xy 200.469049 -134.897876) (xy 266.86764 -134.897876) (xy 266.86764 -134.034276)
			(xy 266.86813 -134.004292) (xy 266.875958 -133.944836) (xy 266.891479 -133.886911) (xy 266.914428 -133.831507)
			(xy 266.944412 -133.779573) (xy 266.980918 -133.731997) (xy 267.023323 -133.689592) (xy 267.070899 -133.653086)
			(xy 267.122833 -133.623102) (xy 267.178237 -133.600153) (xy 267.236162 -133.584632) (xy 267.295618 -133.576804)
			(xy 267.355586 -133.576804) (xy 267.415042 -133.584632) (xy 267.472967 -133.600153) (xy 267.528371 -133.623102)
			(xy 267.580305 -133.653086) (xy 267.627881 -133.689592) (xy 267.670286 -133.731997) (xy 267.706792 -133.779573)
			(xy 267.736776 -133.831507) (xy 267.759725 -133.886911) (xy 267.775246 -133.944836) (xy 267.783074 -134.004292)
			(xy 267.783564 -134.034276) (xy 267.783564 -134.896352) (xy 285.8389 -134.896352) (xy 285.8389 -134.032752)
			(xy 285.83939 -134.002768) (xy 285.847218 -133.943312) (xy 285.862739 -133.885387) (xy 285.885688 -133.829983)
			(xy 285.915672 -133.778049) (xy 285.952178 -133.730473) (xy 285.994583 -133.688068) (xy 286.042159 -133.651562)
			(xy 286.094093 -133.621578) (xy 286.149497 -133.598629) (xy 286.207422 -133.583108) (xy 286.266878 -133.57528)
			(xy 286.326846 -133.57528) (xy 286.386302 -133.583108) (xy 286.444227 -133.598629) (xy 286.499631 -133.621578)
			(xy 286.551565 -133.651562) (xy 286.599141 -133.688068) (xy 286.641546 -133.730473) (xy 286.678052 -133.778049)
			(xy 286.708036 -133.829983) (xy 286.730985 -133.885387) (xy 286.746506 -133.943312) (xy 286.754334 -134.002768)
			(xy 286.754824 -134.032752) (xy 286.754824 -134.377176) (xy 298.799504 -134.377176) (xy 298.799504 -133.513576)
			(xy 298.799994 -133.483608) (xy 298.807817 -133.424186) (xy 298.82333 -133.366293) (xy 298.846266 -133.31092)
			(xy 298.876233 -133.259014) (xy 298.91272 -133.211464) (xy 298.9551 -133.169084) (xy 299.00265 -133.132597)
			(xy 299.054556 -133.10263) (xy 299.109929 -133.079694) (xy 299.167822 -133.064181) (xy 299.227244 -133.056358)
			(xy 299.28718 -133.056358) (xy 299.346602 -133.064181) (xy 299.404495 -133.079694) (xy 299.459868 -133.10263)
			(xy 299.511774 -133.132597) (xy 299.559324 -133.169084) (xy 299.601704 -133.211464) (xy 299.638191 -133.259014)
			(xy 299.668158 -133.31092) (xy 299.691094 -133.366293) (xy 299.706607 -133.424186) (xy 299.71443 -133.483608)
			(xy 299.71492 -133.513576) (xy 299.71492 -134.369302) (xy 313.274456 -134.369302) (xy 313.274456 -133.505702)
			(xy 313.274946 -133.475734) (xy 313.282769 -133.416312) (xy 313.298282 -133.358419) (xy 313.321218 -133.303046)
			(xy 313.351185 -133.25114) (xy 313.387672 -133.20359) (xy 313.430052 -133.16121) (xy 313.477602 -133.124723)
			(xy 313.529508 -133.094756) (xy 313.584881 -133.07182) (xy 313.642774 -133.056307) (xy 313.702196 -133.048484)
			(xy 313.762132 -133.048484) (xy 313.821554 -133.056307) (xy 313.879447 -133.07182) (xy 313.93482 -133.094756)
			(xy 313.951493 -133.104382) (xy 385.6101 -133.104382) (xy 385.6101 -132.240782) (xy 385.61059 -132.210814)
			(xy 385.618413 -132.151392) (xy 385.633926 -132.093499) (xy 385.656862 -132.038126) (xy 385.686829 -131.98622)
			(xy 385.723316 -131.93867) (xy 385.765696 -131.89629) (xy 385.813246 -131.859803) (xy 385.865152 -131.829836)
			(xy 385.920525 -131.8069) (xy 385.978418 -131.791387) (xy 386.03784 -131.783564) (xy 386.097776 -131.783564)
			(xy 386.157198 -131.791387) (xy 386.215091 -131.8069) (xy 386.270464 -131.829836) (xy 386.32237 -131.859803)
			(xy 386.36992 -131.89629) (xy 386.4123 -131.93867) (xy 386.448787 -131.98622) (xy 386.478754 -132.038126)
			(xy 386.50169 -132.093499) (xy 386.517203 -132.151392) (xy 386.525026 -132.210814) (xy 386.525516 -132.240782)
			(xy 386.525516 -133.096508) (xy 400.085052 -133.096508) (xy 400.085052 -132.232908) (xy 400.085542 -132.20294)
			(xy 400.093365 -132.143518) (xy 400.108878 -132.085625) (xy 400.131814 -132.030252) (xy 400.161781 -131.978346)
			(xy 400.198268 -131.930796) (xy 400.240648 -131.888416) (xy 400.288198 -131.851929) (xy 400.340104 -131.821962)
			(xy 400.395477 -131.799026) (xy 400.45337 -131.783513) (xy 400.512792 -131.77569) (xy 400.572728 -131.77569)
			(xy 400.63215 -131.783513) (xy 400.690043 -131.799026) (xy 400.745416 -131.821962) (xy 400.797322 -131.851929)
			(xy 400.844872 -131.888416) (xy 400.887252 -131.930796) (xy 400.923739 -131.978346) (xy 400.953706 -132.030252)
			(xy 400.976642 -132.085625) (xy 400.992155 -132.143518) (xy 400.999978 -132.20294) (xy 401.000468 -132.232908)
			(xy 401.000468 -132.577332) (xy 413.045148 -132.577332) (xy 413.045148 -131.713732) (xy 413.045638 -131.683748)
			(xy 413.053466 -131.624292) (xy 413.068987 -131.566367) (xy 413.091936 -131.510963) (xy 413.12192 -131.459029)
			(xy 413.158426 -131.411453) (xy 413.200831 -131.369048) (xy 413.248407 -131.332542) (xy 413.300341 -131.302558)
			(xy 413.355745 -131.279609) (xy 413.41367 -131.264088) (xy 413.473126 -131.25626) (xy 413.533094 -131.25626)
			(xy 413.59255 -131.264088) (xy 413.650475 -131.279609) (xy 413.705879 -131.302558) (xy 413.757813 -131.332542)
			(xy 413.805389 -131.369048) (xy 413.847794 -131.411453) (xy 413.8843 -131.459029) (xy 413.914284 -131.510963)
			(xy 413.937233 -131.566367) (xy 413.952754 -131.624292) (xy 413.960582 -131.683748) (xy 413.961072 -131.713732)
			(xy 413.961072 -132.575808) (xy 432.016408 -132.575808) (xy 432.016408 -131.712208) (xy 432.016898 -131.682224)
			(xy 432.024726 -131.622768) (xy 432.040247 -131.564843) (xy 432.063196 -131.509439) (xy 432.09318 -131.457505)
			(xy 432.129686 -131.409929) (xy 432.172091 -131.367524) (xy 432.219667 -131.331018) (xy 432.271601 -131.301034)
			(xy 432.327005 -131.278085) (xy 432.38493 -131.262564) (xy 432.444386 -131.254736) (xy 432.504354 -131.254736)
			(xy 432.56381 -131.262564) (xy 432.621735 -131.278085) (xy 432.677139 -131.301034) (xy 432.729073 -131.331018)
			(xy 432.776649 -131.367524) (xy 432.819054 -131.409929) (xy 432.85556 -131.457505) (xy 432.885544 -131.509439)
			(xy 432.908493 -131.564843) (xy 432.924014 -131.622768) (xy 432.931842 -131.682224) (xy 432.932332 -131.712208)
			(xy 432.932332 -132.575808) (xy 432.931842 -132.605792) (xy 432.924014 -132.665248) (xy 432.908493 -132.723173)
			(xy 432.885544 -132.778577) (xy 432.85556 -132.830511) (xy 432.819054 -132.878087) (xy 432.776649 -132.920492)
			(xy 432.729073 -132.956998) (xy 432.677139 -132.986982) (xy 432.621735 -133.009931) (xy 432.56381 -133.025452)
			(xy 432.504354 -133.03328) (xy 432.444386 -133.03328) (xy 432.38493 -133.025452) (xy 432.327005 -133.009931)
			(xy 432.271601 -132.986982) (xy 432.219667 -132.956998) (xy 432.172091 -132.920492) (xy 432.129686 -132.878087)
			(xy 432.09318 -132.830511) (xy 432.063196 -132.778577) (xy 432.040247 -132.723173) (xy 432.024726 -132.665248)
			(xy 432.016898 -132.605792) (xy 432.016408 -132.575808) (xy 413.961072 -132.575808) (xy 413.961072 -132.577332)
			(xy 413.960582 -132.607316) (xy 413.952754 -132.666772) (xy 413.937233 -132.724697) (xy 413.914284 -132.780101)
			(xy 413.8843 -132.832035) (xy 413.847794 -132.879611) (xy 413.805389 -132.922016) (xy 413.757813 -132.958522)
			(xy 413.705879 -132.988506) (xy 413.650475 -133.011455) (xy 413.59255 -133.026976) (xy 413.533094 -133.034804)
			(xy 413.473126 -133.034804) (xy 413.41367 -133.026976) (xy 413.355745 -133.011455) (xy 413.300341 -132.988506)
			(xy 413.248407 -132.958522) (xy 413.200831 -132.922016) (xy 413.158426 -132.879611) (xy 413.12192 -132.832035)
			(xy 413.091936 -132.780101) (xy 413.068987 -132.724697) (xy 413.053466 -132.666772) (xy 413.045638 -132.607316)
			(xy 413.045148 -132.577332) (xy 401.000468 -132.577332) (xy 401.000468 -133.096508) (xy 400.999978 -133.126476)
			(xy 400.992155 -133.185898) (xy 400.976642 -133.243791) (xy 400.953706 -133.299164) (xy 400.923739 -133.35107)
			(xy 400.887252 -133.39862) (xy 400.844872 -133.441) (xy 400.797322 -133.477487) (xy 400.745416 -133.507454)
			(xy 400.690043 -133.53039) (xy 400.63215 -133.545903) (xy 400.572728 -133.553726) (xy 400.512792 -133.553726)
			(xy 400.45337 -133.545903) (xy 400.395477 -133.53039) (xy 400.340104 -133.507454) (xy 400.288198 -133.477487)
			(xy 400.240648 -133.441) (xy 400.198268 -133.39862) (xy 400.161781 -133.35107) (xy 400.131814 -133.299164)
			(xy 400.108878 -133.243791) (xy 400.093365 -133.185898) (xy 400.085542 -133.126476) (xy 400.085052 -133.096508)
			(xy 386.525516 -133.096508) (xy 386.525516 -133.104382) (xy 386.525026 -133.13435) (xy 386.517203 -133.193772)
			(xy 386.50169 -133.251665) (xy 386.478754 -133.307038) (xy 386.448787 -133.358944) (xy 386.4123 -133.406494)
			(xy 386.36992 -133.448874) (xy 386.32237 -133.485361) (xy 386.270464 -133.515328) (xy 386.215091 -133.538264)
			(xy 386.157198 -133.553777) (xy 386.097776 -133.5616) (xy 386.03784 -133.5616) (xy 385.978418 -133.553777)
			(xy 385.920525 -133.538264) (xy 385.865152 -133.515328) (xy 385.813246 -133.485361) (xy 385.765696 -133.448874)
			(xy 385.723316 -133.406494) (xy 385.686829 -133.358944) (xy 385.656862 -133.307038) (xy 385.633926 -133.251665)
			(xy 385.618413 -133.193772) (xy 385.61059 -133.13435) (xy 385.6101 -133.104382) (xy 313.951493 -133.104382)
			(xy 313.986726 -133.124723) (xy 314.034276 -133.16121) (xy 314.076656 -133.20359) (xy 314.113143 -133.25114)
			(xy 314.14311 -133.303046) (xy 314.166046 -133.358419) (xy 314.181559 -133.416312) (xy 314.189382 -133.475734)
			(xy 314.189872 -133.505702) (xy 314.189872 -134.369302) (xy 314.189382 -134.39927) (xy 314.181559 -134.458692)
			(xy 314.166046 -134.516585) (xy 314.14311 -134.571958) (xy 314.113143 -134.623864) (xy 314.076656 -134.671414)
			(xy 314.034276 -134.713794) (xy 313.986726 -134.750281) (xy 313.93482 -134.780248) (xy 313.879447 -134.803184)
			(xy 313.821554 -134.818697) (xy 313.762132 -134.82652) (xy 313.702196 -134.82652) (xy 313.642774 -134.818697)
			(xy 313.584881 -134.803184) (xy 313.529508 -134.780248) (xy 313.477602 -134.750281) (xy 313.430052 -134.713794)
			(xy 313.387672 -134.671414) (xy 313.351185 -134.623864) (xy 313.321218 -134.571958) (xy 313.298282 -134.516585)
			(xy 313.282769 -134.458692) (xy 313.274946 -134.39927) (xy 313.274456 -134.369302) (xy 299.71492 -134.369302)
			(xy 299.71492 -134.377176) (xy 299.71443 -134.407144) (xy 299.706607 -134.466566) (xy 299.691094 -134.524459)
			(xy 299.668158 -134.579832) (xy 299.638191 -134.631738) (xy 299.601704 -134.679288) (xy 299.559324 -134.721668)
			(xy 299.511774 -134.758155) (xy 299.459868 -134.788122) (xy 299.404495 -134.811058) (xy 299.346602 -134.826571)
			(xy 299.28718 -134.834394) (xy 299.227244 -134.834394) (xy 299.167822 -134.826571) (xy 299.109929 -134.811058)
			(xy 299.054556 -134.788122) (xy 299.00265 -134.758155) (xy 298.9551 -134.721668) (xy 298.91272 -134.679288)
			(xy 298.876233 -134.631738) (xy 298.846266 -134.579832) (xy 298.82333 -134.524459) (xy 298.807817 -134.466566)
			(xy 298.799994 -134.407144) (xy 298.799504 -134.377176) (xy 286.754824 -134.377176) (xy 286.754824 -134.896352)
			(xy 286.754334 -134.926336) (xy 286.746506 -134.985792) (xy 286.730985 -135.043717) (xy 286.708036 -135.099121)
			(xy 286.678052 -135.151055) (xy 286.641546 -135.198631) (xy 286.599141 -135.241036) (xy 286.551565 -135.277542)
			(xy 286.499631 -135.307526) (xy 286.444227 -135.330475) (xy 286.386302 -135.345996) (xy 286.326846 -135.353824)
			(xy 286.266878 -135.353824) (xy 286.207422 -135.345996) (xy 286.149497 -135.330475) (xy 286.094093 -135.307526)
			(xy 286.042159 -135.277542) (xy 285.994583 -135.241036) (xy 285.952178 -135.198631) (xy 285.915672 -135.151055)
			(xy 285.885688 -135.099121) (xy 285.862739 -135.043717) (xy 285.847218 -134.985792) (xy 285.83939 -134.926336)
			(xy 285.8389 -134.896352) (xy 267.783564 -134.896352) (xy 267.783564 -134.897876) (xy 267.783074 -134.92786)
			(xy 267.775246 -134.987316) (xy 267.759725 -135.045241) (xy 267.736776 -135.100645) (xy 267.706792 -135.152579)
			(xy 267.670286 -135.200155) (xy 267.627881 -135.24256) (xy 267.580305 -135.279066) (xy 267.528371 -135.30905)
			(xy 267.472967 -135.331999) (xy 267.415042 -135.34752) (xy 267.355586 -135.355348) (xy 267.295618 -135.355348)
			(xy 267.236162 -135.34752) (xy 267.178237 -135.331999) (xy 267.122833 -135.30905) (xy 267.070899 -135.279066)
			(xy 267.023323 -135.24256) (xy 266.980918 -135.200155) (xy 266.944412 -135.152579) (xy 266.914428 -135.100645)
			(xy 266.891479 -135.045241) (xy 266.875958 -134.987316) (xy 266.86813 -134.92786) (xy 266.86764 -134.897876)
			(xy 200.469049 -134.897876) (xy 200.477084 -134.901204) (xy 200.52899 -134.931171) (xy 200.57654 -134.967658)
			(xy 200.61892 -135.010038) (xy 200.655407 -135.057588) (xy 200.685374 -135.109494) (xy 200.70831 -135.164867)
			(xy 200.723823 -135.22276) (xy 200.731646 -135.282182) (xy 200.732136 -135.31215) (xy 200.732136 -136.17575)
			(xy 200.731646 -136.205718) (xy 200.723823 -136.26514) (xy 200.70831 -136.323033) (xy 200.685374 -136.378406)
			(xy 200.655407 -136.430312) (xy 200.61892 -136.477862) (xy 200.57654 -136.520242) (xy 200.52899 -136.556729)
			(xy 200.477084 -136.586696) (xy 200.421711 -136.609632) (xy 200.363818 -136.625145) (xy 200.304396 -136.632968)
			(xy 200.24446 -136.632968) (xy 200.185038 -136.625145) (xy 200.127145 -136.609632) (xy 200.071772 -136.586696)
			(xy 200.019866 -136.556729) (xy 199.972316 -136.520242) (xy 199.929936 -136.477862) (xy 199.893449 -136.430312)
			(xy 199.863482 -136.378406) (xy 199.840546 -136.323033) (xy 199.825033 -136.26514) (xy 199.81721 -136.205718)
			(xy 199.81672 -136.17575) (xy 181.760876 -136.17575) (xy 181.760876 -136.177274) (xy 181.760386 -136.207242)
			(xy 181.752563 -136.266664) (xy 181.73705 -136.324557) (xy 181.714114 -136.37993) (xy 181.684147 -136.431836)
			(xy 181.64766 -136.479386) (xy 181.60528 -136.521766) (xy 181.55773 -136.558253) (xy 181.505824 -136.58822)
			(xy 181.450451 -136.611156) (xy 181.392558 -136.626669) (xy 181.333136 -136.634492) (xy 181.2732 -136.634492)
			(xy 181.213778 -136.626669) (xy 181.155885 -136.611156) (xy 181.100512 -136.58822) (xy 181.048606 -136.558253)
			(xy 181.001056 -136.521766) (xy 180.958676 -136.479386) (xy 180.922189 -136.431836) (xy 180.892222 -136.37993)
			(xy 180.869286 -136.324557) (xy 180.853773 -136.266664) (xy 180.84595 -136.207242) (xy 180.84546 -136.177274)
			(xy 168.80078 -136.177274) (xy 168.80078 -136.69645) (xy 168.800651 -136.704324) (xy 269.509748 -136.704324)
			(xy 269.509748 -135.840724) (xy 269.510238 -135.81074) (xy 269.518066 -135.751284) (xy 269.533587 -135.693359)
			(xy 269.556536 -135.637955) (xy 269.58652 -135.586021) (xy 269.623026 -135.538445) (xy 269.665431 -135.49604)
			(xy 269.713007 -135.459534) (xy 269.764941 -135.42955) (xy 269.820345 -135.406601) (xy 269.87827 -135.39108)
			(xy 269.937726 -135.383252) (xy 269.997694 -135.383252) (xy 270.05715 -135.39108) (xy 270.115075 -135.406601)
			(xy 270.170479 -135.42955) (xy 270.222413 -135.459534) (xy 270.269989 -135.49604) (xy 270.312394 -135.538445)
			(xy 270.3489 -135.586021) (xy 270.378884 -135.637955) (xy 270.401833 -135.693359) (xy 270.417354 -135.751284)
			(xy 270.425182 -135.81074) (xy 270.425672 -135.840724) (xy 270.425672 -136.69645) (xy 283.9847 -136.69645)
			(xy 283.9847 -135.83285) (xy 283.98519 -135.802866) (xy 283.993018 -135.74341) (xy 284.008539 -135.685485)
			(xy 284.031488 -135.630081) (xy 284.061472 -135.578147) (xy 284.097978 -135.530571) (xy 284.140383 -135.488166)
			(xy 284.187959 -135.45166) (xy 284.239893 -135.421676) (xy 284.295297 -135.398727) (xy 284.353222 -135.383206)
			(xy 284.412678 -135.375378) (xy 284.472646 -135.375378) (xy 284.532102 -135.383206) (xy 284.590027 -135.398727)
			(xy 284.645431 -135.421676) (xy 284.697365 -135.45166) (xy 284.744941 -135.488166) (xy 284.787346 -135.530571)
			(xy 284.823852 -135.578147) (xy 284.853836 -135.630081) (xy 284.876785 -135.685485) (xy 284.892306 -135.74341)
			(xy 284.900134 -135.802866) (xy 284.900624 -135.83285) (xy 284.900624 -136.177274) (xy 296.945304 -136.177274)
			(xy 296.945304 -135.313674) (xy 296.945794 -135.283706) (xy 296.953617 -135.224284) (xy 296.96913 -135.166391)
			(xy 296.992066 -135.111018) (xy 297.022033 -135.059112) (xy 297.05852 -135.011562) (xy 297.1009 -134.969182)
			(xy 297.14845 -134.932695) (xy 297.200356 -134.902728) (xy 297.255729 -134.879792) (xy 297.313622 -134.864279)
			(xy 297.373044 -134.856456) (xy 297.43298 -134.856456) (xy 297.492402 -134.864279) (xy 297.550295 -134.879792)
			(xy 297.605668 -134.902728) (xy 297.657574 -134.932695) (xy 297.705124 -134.969182) (xy 297.747504 -135.011562)
			(xy 297.783991 -135.059112) (xy 297.813958 -135.111018) (xy 297.836894 -135.166391) (xy 297.852407 -135.224284)
			(xy 297.86023 -135.283706) (xy 297.86072 -135.313674) (xy 297.86072 -136.17575) (xy 315.916564 -136.17575)
			(xy 315.916564 -135.31215) (xy 315.917054 -135.282182) (xy 315.924877 -135.22276) (xy 315.94039 -135.164867)
			(xy 315.963326 -135.109494) (xy 315.993293 -135.057588) (xy 316.02978 -135.010038) (xy 316.07216 -134.967658)
			(xy 316.11971 -134.931171) (xy 316.171616 -134.901204) (xy 316.226989 -134.878268) (xy 316.284882 -134.862755)
			(xy 316.344304 -134.854932) (xy 316.40424 -134.854932) (xy 316.463662 -134.862755) (xy 316.521555 -134.878268)
			(xy 316.568893 -134.897876) (xy 382.967992 -134.897876) (xy 382.967992 -134.034276) (xy 382.968482 -134.004308)
			(xy 382.976305 -133.944886) (xy 382.991818 -133.886993) (xy 383.014754 -133.83162) (xy 383.044721 -133.779714)
			(xy 383.081208 -133.732164) (xy 383.123588 -133.689784) (xy 383.171138 -133.653297) (xy 383.223044 -133.62333)
			(xy 383.278417 -133.600394) (xy 383.33631 -133.584881) (xy 383.395732 -133.577058) (xy 383.455668 -133.577058)
			(xy 383.51509 -133.584881) (xy 383.572983 -133.600394) (xy 383.628356 -133.62333) (xy 383.680262 -133.653297)
			(xy 383.727812 -133.689784) (xy 383.770192 -133.732164) (xy 383.806679 -133.779714) (xy 383.836646 -133.83162)
			(xy 383.859582 -133.886993) (xy 383.875095 -133.944886) (xy 383.882918 -134.004308) (xy 383.883408 -134.034276)
			(xy 383.883408 -134.896352) (xy 401.939252 -134.896352) (xy 401.939252 -134.032752) (xy 401.939742 -134.002784)
			(xy 401.947565 -133.943362) (xy 401.963078 -133.885469) (xy 401.986014 -133.830096) (xy 402.015981 -133.77819)
			(xy 402.052468 -133.73064) (xy 402.094848 -133.68826) (xy 402.142398 -133.651773) (xy 402.194304 -133.621806)
			(xy 402.249677 -133.59887) (xy 402.30757 -133.583357) (xy 402.366992 -133.575534) (xy 402.426928 -133.575534)
			(xy 402.48635 -133.583357) (xy 402.544243 -133.59887) (xy 402.599616 -133.621806) (xy 402.651522 -133.651773)
			(xy 402.699072 -133.68826) (xy 402.741452 -133.73064) (xy 402.777939 -133.77819) (xy 402.807906 -133.830096)
			(xy 402.830842 -133.885469) (xy 402.846355 -133.943362) (xy 402.854178 -134.002784) (xy 402.854668 -134.032752)
			(xy 402.854668 -134.377176) (xy 414.899348 -134.377176) (xy 414.899348 -133.513576) (xy 414.899838 -133.483592)
			(xy 414.907666 -133.424136) (xy 414.923187 -133.366211) (xy 414.946136 -133.310807) (xy 414.97612 -133.258873)
			(xy 415.012626 -133.211297) (xy 415.055031 -133.168892) (xy 415.102607 -133.132386) (xy 415.154541 -133.102402)
			(xy 415.209945 -133.079453) (xy 415.26787 -133.063932) (xy 415.327326 -133.056104) (xy 415.387294 -133.056104)
			(xy 415.44675 -133.063932) (xy 415.504675 -133.079453) (xy 415.560079 -133.102402) (xy 415.612013 -133.132386)
			(xy 415.659589 -133.168892) (xy 415.701994 -133.211297) (xy 415.7385 -133.258873) (xy 415.768484 -133.310807)
			(xy 415.791433 -133.366211) (xy 415.806954 -133.424136) (xy 415.814782 -133.483592) (xy 415.815272 -133.513576)
			(xy 415.815272 -134.369302) (xy 429.3743 -134.369302) (xy 429.3743 -133.505702) (xy 429.37479 -133.475718)
			(xy 429.382618 -133.416262) (xy 429.398139 -133.358337) (xy 429.421088 -133.302933) (xy 429.451072 -133.250999)
			(xy 429.487578 -133.203423) (xy 429.529983 -133.161018) (xy 429.577559 -133.124512) (xy 429.629493 -133.094528)
			(xy 429.684897 -133.071579) (xy 429.742822 -133.056058) (xy 429.802278 -133.04823) (xy 429.862246 -133.04823)
			(xy 429.921702 -133.056058) (xy 429.979627 -133.071579) (xy 430.035031 -133.094528) (xy 430.086965 -133.124512)
			(xy 430.134541 -133.161018) (xy 430.176946 -133.203423) (xy 430.213452 -133.250999) (xy 430.243436 -133.302933)
			(xy 430.266385 -133.358337) (xy 430.281906 -133.416262) (xy 430.289734 -133.475718) (xy 430.290224 -133.505702)
			(xy 430.290224 -134.369302) (xy 430.289734 -134.399286) (xy 430.281906 -134.458742) (xy 430.266385 -134.516667)
			(xy 430.243436 -134.572071) (xy 430.213452 -134.624005) (xy 430.176946 -134.671581) (xy 430.134541 -134.713986)
			(xy 430.086965 -134.750492) (xy 430.035031 -134.780476) (xy 429.979627 -134.803425) (xy 429.921702 -134.818946)
			(xy 429.862246 -134.826774) (xy 429.802278 -134.826774) (xy 429.742822 -134.818946) (xy 429.684897 -134.803425)
			(xy 429.629493 -134.780476) (xy 429.577559 -134.750492) (xy 429.529983 -134.713986) (xy 429.487578 -134.671581)
			(xy 429.451072 -134.624005) (xy 429.421088 -134.572071) (xy 429.398139 -134.516667) (xy 429.382618 -134.458742)
			(xy 429.37479 -134.399286) (xy 429.3743 -134.369302) (xy 415.815272 -134.369302) (xy 415.815272 -134.377176)
			(xy 415.814782 -134.40716) (xy 415.806954 -134.466616) (xy 415.791433 -134.524541) (xy 415.768484 -134.579945)
			(xy 415.7385 -134.631879) (xy 415.701994 -134.679455) (xy 415.659589 -134.72186) (xy 415.612013 -134.758366)
			(xy 415.560079 -134.78835) (xy 415.504675 -134.811299) (xy 415.44675 -134.82682) (xy 415.387294 -134.834648)
			(xy 415.327326 -134.834648) (xy 415.26787 -134.82682) (xy 415.209945 -134.811299) (xy 415.154541 -134.78835)
			(xy 415.102607 -134.758366) (xy 415.055031 -134.72186) (xy 415.012626 -134.679455) (xy 414.97612 -134.631879)
			(xy 414.946136 -134.579945) (xy 414.923187 -134.524541) (xy 414.907666 -134.466616) (xy 414.899838 -134.40716)
			(xy 414.899348 -134.377176) (xy 402.854668 -134.377176) (xy 402.854668 -134.896352) (xy 402.854178 -134.92632)
			(xy 402.846355 -134.985742) (xy 402.830842 -135.043635) (xy 402.807906 -135.099008) (xy 402.777939 -135.150914)
			(xy 402.741452 -135.198464) (xy 402.699072 -135.240844) (xy 402.651522 -135.277331) (xy 402.599616 -135.307298)
			(xy 402.544243 -135.330234) (xy 402.48635 -135.345747) (xy 402.426928 -135.35357) (xy 402.366992 -135.35357)
			(xy 402.30757 -135.345747) (xy 402.249677 -135.330234) (xy 402.194304 -135.307298) (xy 402.142398 -135.277331)
			(xy 402.094848 -135.240844) (xy 402.052468 -135.198464) (xy 402.015981 -135.150914) (xy 401.986014 -135.099008)
			(xy 401.963078 -135.043635) (xy 401.947565 -134.985742) (xy 401.939742 -134.92632) (xy 401.939252 -134.896352)
			(xy 383.883408 -134.896352) (xy 383.883408 -134.897876) (xy 383.882918 -134.927844) (xy 383.875095 -134.987266)
			(xy 383.859582 -135.045159) (xy 383.836646 -135.100532) (xy 383.806679 -135.152438) (xy 383.770192 -135.199988)
			(xy 383.727812 -135.242368) (xy 383.680262 -135.278855) (xy 383.628356 -135.308822) (xy 383.572983 -135.331758)
			(xy 383.51509 -135.347271) (xy 383.455668 -135.355094) (xy 383.395732 -135.355094) (xy 383.33631 -135.347271)
			(xy 383.278417 -135.331758) (xy 383.223044 -135.308822) (xy 383.171138 -135.278855) (xy 383.123588 -135.242368)
			(xy 383.081208 -135.199988) (xy 383.044721 -135.152438) (xy 383.014754 -135.100532) (xy 382.991818 -135.045159)
			(xy 382.976305 -134.987266) (xy 382.968482 -134.927844) (xy 382.967992 -134.897876) (xy 316.568893 -134.897876)
			(xy 316.576928 -134.901204) (xy 316.628834 -134.931171) (xy 316.676384 -134.967658) (xy 316.718764 -135.010038)
			(xy 316.755251 -135.057588) (xy 316.785218 -135.109494) (xy 316.808154 -135.164867) (xy 316.823667 -135.22276)
			(xy 316.83149 -135.282182) (xy 316.83198 -135.31215) (xy 316.83198 -136.17575) (xy 316.83149 -136.205718)
			(xy 316.823667 -136.26514) (xy 316.808154 -136.323033) (xy 316.785218 -136.378406) (xy 316.755251 -136.430312)
			(xy 316.718764 -136.477862) (xy 316.676384 -136.520242) (xy 316.628834 -136.556729) (xy 316.576928 -136.586696)
			(xy 316.521555 -136.609632) (xy 316.463662 -136.625145) (xy 316.40424 -136.632968) (xy 316.344304 -136.632968)
			(xy 316.284882 -136.625145) (xy 316.226989 -136.609632) (xy 316.171616 -136.586696) (xy 316.11971 -136.556729)
			(xy 316.07216 -136.520242) (xy 316.02978 -136.477862) (xy 315.993293 -136.430312) (xy 315.963326 -136.378406)
			(xy 315.94039 -136.323033) (xy 315.924877 -136.26514) (xy 315.917054 -136.205718) (xy 315.916564 -136.17575)
			(xy 297.86072 -136.17575) (xy 297.86072 -136.177274) (xy 297.86023 -136.207242) (xy 297.852407 -136.266664)
			(xy 297.836894 -136.324557) (xy 297.813958 -136.37993) (xy 297.783991 -136.431836) (xy 297.747504 -136.479386)
			(xy 297.705124 -136.521766) (xy 297.657574 -136.558253) (xy 297.605668 -136.58822) (xy 297.550295 -136.611156)
			(xy 297.492402 -136.626669) (xy 297.43298 -136.634492) (xy 297.373044 -136.634492) (xy 297.313622 -136.626669)
			(xy 297.255729 -136.611156) (xy 297.200356 -136.58822) (xy 297.14845 -136.558253) (xy 297.1009 -136.521766)
			(xy 297.05852 -136.479386) (xy 297.022033 -136.431836) (xy 296.992066 -136.37993) (xy 296.96913 -136.324557)
			(xy 296.953617 -136.266664) (xy 296.945794 -136.207242) (xy 296.945304 -136.177274) (xy 284.900624 -136.177274)
			(xy 284.900624 -136.69645) (xy 284.900495 -136.704324) (xy 385.6101 -136.704324) (xy 385.6101 -135.840724)
			(xy 385.61059 -135.810756) (xy 385.618413 -135.751334) (xy 385.633926 -135.693441) (xy 385.656862 -135.638068)
			(xy 385.686829 -135.586162) (xy 385.723316 -135.538612) (xy 385.765696 -135.496232) (xy 385.813246 -135.459745)
			(xy 385.865152 -135.429778) (xy 385.920525 -135.406842) (xy 385.978418 -135.391329) (xy 386.03784 -135.383506)
			(xy 386.097776 -135.383506) (xy 386.157198 -135.391329) (xy 386.215091 -135.406842) (xy 386.270464 -135.429778)
			(xy 386.32237 -135.459745) (xy 386.36992 -135.496232) (xy 386.4123 -135.538612) (xy 386.448787 -135.586162)
			(xy 386.478754 -135.638068) (xy 386.50169 -135.693441) (xy 386.517203 -135.751334) (xy 386.525026 -135.810756)
			(xy 386.525516 -135.840724) (xy 386.525516 -136.69645) (xy 400.085052 -136.69645) (xy 400.085052 -135.83285)
			(xy 400.085542 -135.802882) (xy 400.093365 -135.74346) (xy 400.108878 -135.685567) (xy 400.131814 -135.630194)
			(xy 400.161781 -135.578288) (xy 400.198268 -135.530738) (xy 400.240648 -135.488358) (xy 400.288198 -135.451871)
			(xy 400.340104 -135.421904) (xy 400.395477 -135.398968) (xy 400.45337 -135.383455) (xy 400.512792 -135.375632)
			(xy 400.572728 -135.375632) (xy 400.63215 -135.383455) (xy 400.690043 -135.398968) (xy 400.745416 -135.421904)
			(xy 400.797322 -135.451871) (xy 400.844872 -135.488358) (xy 400.887252 -135.530738) (xy 400.923739 -135.578288)
			(xy 400.953706 -135.630194) (xy 400.976642 -135.685567) (xy 400.992155 -135.74346) (xy 400.999978 -135.802882)
			(xy 401.000468 -135.83285) (xy 401.000468 -136.177274) (xy 413.045148 -136.177274) (xy 413.045148 -135.313674)
			(xy 413.045638 -135.28369) (xy 413.053466 -135.224234) (xy 413.068987 -135.166309) (xy 413.091936 -135.110905)
			(xy 413.12192 -135.058971) (xy 413.158426 -135.011395) (xy 413.200831 -134.96899) (xy 413.248407 -134.932484)
			(xy 413.300341 -134.9025) (xy 413.355745 -134.879551) (xy 413.41367 -134.86403) (xy 413.473126 -134.856202)
			(xy 413.533094 -134.856202) (xy 413.59255 -134.86403) (xy 413.650475 -134.879551) (xy 413.705879 -134.9025)
			(xy 413.757813 -134.932484) (xy 413.805389 -134.96899) (xy 413.847794 -135.011395) (xy 413.8843 -135.058971)
			(xy 413.914284 -135.110905) (xy 413.937233 -135.166309) (xy 413.952754 -135.224234) (xy 413.960582 -135.28369)
			(xy 413.961072 -135.313674) (xy 413.961072 -136.17575) (xy 432.016408 -136.17575) (xy 432.016408 -135.31215)
			(xy 432.016898 -135.282166) (xy 432.024726 -135.22271) (xy 432.040247 -135.164785) (xy 432.063196 -135.109381)
			(xy 432.09318 -135.057447) (xy 432.129686 -135.009871) (xy 432.172091 -134.967466) (xy 432.219667 -134.93096)
			(xy 432.271601 -134.900976) (xy 432.327005 -134.878027) (xy 432.38493 -134.862506) (xy 432.444386 -134.854678)
			(xy 432.504354 -134.854678) (xy 432.56381 -134.862506) (xy 432.621735 -134.878027) (xy 432.677139 -134.900976)
			(xy 432.729073 -134.93096) (xy 432.776649 -134.967466) (xy 432.819054 -135.009871) (xy 432.85556 -135.057447)
			(xy 432.885544 -135.109381) (xy 432.908493 -135.164785) (xy 432.924014 -135.22271) (xy 432.931842 -135.282166)
			(xy 432.932332 -135.31215) (xy 432.932332 -136.17575) (xy 432.931842 -136.205734) (xy 432.924014 -136.26519)
			(xy 432.908493 -136.323115) (xy 432.885544 -136.378519) (xy 432.85556 -136.430453) (xy 432.819054 -136.478029)
			(xy 432.776649 -136.520434) (xy 432.729073 -136.55694) (xy 432.677139 -136.586924) (xy 432.621735 -136.609873)
			(xy 432.56381 -136.625394) (xy 432.504354 -136.633222) (xy 432.444386 -136.633222) (xy 432.38493 -136.625394)
			(xy 432.327005 -136.609873) (xy 432.271601 -136.586924) (xy 432.219667 -136.55694) (xy 432.172091 -136.520434)
			(xy 432.129686 -136.478029) (xy 432.09318 -136.430453) (xy 432.063196 -136.378519) (xy 432.040247 -136.323115)
			(xy 432.024726 -136.26519) (xy 432.016898 -136.205734) (xy 432.016408 -136.17575) (xy 413.961072 -136.17575)
			(xy 413.961072 -136.177274) (xy 413.960582 -136.207258) (xy 413.952754 -136.266714) (xy 413.937233 -136.324639)
			(xy 413.914284 -136.380043) (xy 413.8843 -136.431977) (xy 413.847794 -136.479553) (xy 413.805389 -136.521958)
			(xy 413.757813 -136.558464) (xy 413.705879 -136.588448) (xy 413.650475 -136.611397) (xy 413.59255 -136.626918)
			(xy 413.533094 -136.634746) (xy 413.473126 -136.634746) (xy 413.41367 -136.626918) (xy 413.355745 -136.611397)
			(xy 413.300341 -136.588448) (xy 413.248407 -136.558464) (xy 413.200831 -136.521958) (xy 413.158426 -136.479553)
			(xy 413.12192 -136.431977) (xy 413.091936 -136.380043) (xy 413.068987 -136.324639) (xy 413.053466 -136.266714)
			(xy 413.045638 -136.207258) (xy 413.045148 -136.177274) (xy 401.000468 -136.177274) (xy 401.000468 -136.69645)
			(xy 400.999978 -136.726418) (xy 400.992155 -136.78584) (xy 400.976642 -136.843733) (xy 400.953706 -136.899106)
			(xy 400.923739 -136.951012) (xy 400.887252 -136.998562) (xy 400.844872 -137.040942) (xy 400.797322 -137.077429)
			(xy 400.745416 -137.107396) (xy 400.690043 -137.130332) (xy 400.63215 -137.145845) (xy 400.572728 -137.153668)
			(xy 400.512792 -137.153668) (xy 400.45337 -137.145845) (xy 400.395477 -137.130332) (xy 400.340104 -137.107396)
			(xy 400.288198 -137.077429) (xy 400.240648 -137.040942) (xy 400.198268 -136.998562) (xy 400.161781 -136.951012)
			(xy 400.131814 -136.899106) (xy 400.108878 -136.843733) (xy 400.093365 -136.78584) (xy 400.085542 -136.726418)
			(xy 400.085052 -136.69645) (xy 386.525516 -136.69645) (xy 386.525516 -136.704324) (xy 386.525026 -136.734292)
			(xy 386.517203 -136.793714) (xy 386.50169 -136.851607) (xy 386.478754 -136.90698) (xy 386.448787 -136.958886)
			(xy 386.4123 -137.006436) (xy 386.36992 -137.048816) (xy 386.32237 -137.085303) (xy 386.270464 -137.11527)
			(xy 386.215091 -137.138206) (xy 386.157198 -137.153719) (xy 386.097776 -137.161542) (xy 386.03784 -137.161542)
			(xy 385.978418 -137.153719) (xy 385.920525 -137.138206) (xy 385.865152 -137.11527) (xy 385.813246 -137.085303)
			(xy 385.765696 -137.048816) (xy 385.723316 -137.006436) (xy 385.686829 -136.958886) (xy 385.656862 -136.90698)
			(xy 385.633926 -136.851607) (xy 385.618413 -136.793714) (xy 385.61059 -136.734292) (xy 385.6101 -136.704324)
			(xy 284.900495 -136.704324) (xy 284.900134 -136.726434) (xy 284.892306 -136.78589) (xy 284.876785 -136.843815)
			(xy 284.853836 -136.899219) (xy 284.823852 -136.951153) (xy 284.787346 -136.998729) (xy 284.744941 -137.041134)
			(xy 284.697365 -137.07764) (xy 284.645431 -137.107624) (xy 284.590027 -137.130573) (xy 284.532102 -137.146094)
			(xy 284.472646 -137.153922) (xy 284.412678 -137.153922) (xy 284.353222 -137.146094) (xy 284.295297 -137.130573)
			(xy 284.239893 -137.107624) (xy 284.187959 -137.07764) (xy 284.140383 -137.041134) (xy 284.097978 -136.998729)
			(xy 284.061472 -136.951153) (xy 284.031488 -136.899219) (xy 284.008539 -136.843815) (xy 283.993018 -136.78589)
			(xy 283.98519 -136.726434) (xy 283.9847 -136.69645) (xy 270.425672 -136.69645) (xy 270.425672 -136.704324)
			(xy 270.425182 -136.734308) (xy 270.417354 -136.793764) (xy 270.401833 -136.851689) (xy 270.378884 -136.907093)
			(xy 270.3489 -136.959027) (xy 270.312394 -137.006603) (xy 270.269989 -137.049008) (xy 270.222413 -137.085514)
			(xy 270.170479 -137.115498) (xy 270.115075 -137.138447) (xy 270.05715 -137.153968) (xy 269.997694 -137.161796)
			(xy 269.937726 -137.161796) (xy 269.87827 -137.153968) (xy 269.820345 -137.138447) (xy 269.764941 -137.115498)
			(xy 269.713007 -137.085514) (xy 269.665431 -137.049008) (xy 269.623026 -137.006603) (xy 269.58652 -136.959027)
			(xy 269.556536 -136.907093) (xy 269.533587 -136.851689) (xy 269.518066 -136.793764) (xy 269.510238 -136.734308)
			(xy 269.509748 -136.704324) (xy 168.800651 -136.704324) (xy 168.80029 -136.726434) (xy 168.792462 -136.78589)
			(xy 168.776941 -136.843815) (xy 168.753992 -136.899219) (xy 168.724008 -136.951153) (xy 168.687502 -136.998729)
			(xy 168.645097 -137.041134) (xy 168.597521 -137.07764) (xy 168.545587 -137.107624) (xy 168.490183 -137.130573)
			(xy 168.432258 -137.146094) (xy 168.372802 -137.153922) (xy 168.312834 -137.153922) (xy 168.253378 -137.146094)
			(xy 168.195453 -137.130573) (xy 168.140049 -137.107624) (xy 168.088115 -137.07764) (xy 168.040539 -137.041134)
			(xy 167.998134 -136.998729) (xy 167.961628 -136.951153) (xy 167.931644 -136.899219) (xy 167.908695 -136.843815)
			(xy 167.893174 -136.78589) (xy 167.885346 -136.726434) (xy 167.884856 -136.69645) (xy 154.325828 -136.69645)
			(xy 154.325828 -136.704324) (xy 154.325338 -136.734308) (xy 154.31751 -136.793764) (xy 154.301989 -136.851689)
			(xy 154.27904 -136.907093) (xy 154.249056 -136.959027) (xy 154.21255 -137.006603) (xy 154.170145 -137.049008)
			(xy 154.122569 -137.085514) (xy 154.070635 -137.115498) (xy 154.015231 -137.138447) (xy 153.957306 -137.153968)
			(xy 153.89785 -137.161796) (xy 153.837882 -137.161796) (xy 153.778426 -137.153968) (xy 153.720501 -137.138447)
			(xy 153.665097 -137.115498) (xy 153.613163 -137.085514) (xy 153.565587 -137.049008) (xy 153.523182 -137.006603)
			(xy 153.486676 -136.959027) (xy 153.456692 -136.907093) (xy 153.433743 -136.851689) (xy 153.418222 -136.793764)
			(xy 153.410394 -136.734308) (xy 153.409904 -136.704324) (xy 52.700299 -136.704324) (xy 52.699938 -136.726418)
			(xy 52.692115 -136.78584) (xy 52.676602 -136.843733) (xy 52.653666 -136.899106) (xy 52.623699 -136.951012)
			(xy 52.587212 -136.998562) (xy 52.544832 -137.040942) (xy 52.497282 -137.077429) (xy 52.445376 -137.107396)
			(xy 52.390003 -137.130332) (xy 52.33211 -137.145845) (xy 52.272688 -137.153668) (xy 52.212752 -137.153668)
			(xy 52.15333 -137.145845) (xy 52.095437 -137.130332) (xy 52.040064 -137.107396) (xy 51.988158 -137.077429)
			(xy 51.940608 -137.040942) (xy 51.898228 -136.998562) (xy 51.861741 -136.951012) (xy 51.831774 -136.899106)
			(xy 51.808838 -136.843733) (xy 51.793325 -136.78584) (xy 51.785502 -136.726418) (xy 51.785012 -136.69645)
			(xy 38.225476 -136.69645) (xy 38.225476 -136.704324) (xy 38.224986 -136.734292) (xy 38.217163 -136.793714)
			(xy 38.20165 -136.851607) (xy 38.178714 -136.90698) (xy 38.148747 -136.958886) (xy 38.11226 -137.006436)
			(xy 38.06988 -137.048816) (xy 38.02233 -137.085303) (xy 37.970424 -137.11527) (xy 37.915051 -137.138206)
			(xy 37.857158 -137.153719) (xy 37.797736 -137.161542) (xy 37.7378 -137.161542) (xy 37.678378 -137.153719)
			(xy 37.620485 -137.138206) (xy 37.565112 -137.11527) (xy 37.513206 -137.085303) (xy 37.465656 -137.048816)
			(xy 37.423276 -137.006436) (xy 37.386789 -136.958886) (xy 37.356822 -136.90698) (xy 37.333886 -136.851607)
			(xy 37.318373 -136.793714) (xy 37.31055 -136.734292) (xy 37.31006 -136.704324) (xy 4.30911 -136.704324)
			(xy 4.30911 -138.496548) (xy 43.97248 -138.496548) (xy 43.97248 -137.632948) (xy 43.97297 -137.602964)
			(xy 43.980798 -137.543508) (xy 43.996319 -137.485583) (xy 44.019268 -137.430179) (xy 44.049252 -137.378245)
			(xy 44.085758 -137.330669) (xy 44.128163 -137.288264) (xy 44.175739 -137.251758) (xy 44.227673 -137.221774)
			(xy 44.283077 -137.198825) (xy 44.341002 -137.183304) (xy 44.400458 -137.175476) (xy 44.460426 -137.175476)
			(xy 44.519882 -137.183304) (xy 44.577807 -137.198825) (xy 44.633211 -137.221774) (xy 44.685145 -137.251758)
			(xy 44.732721 -137.288264) (xy 44.775126 -137.330669) (xy 44.811632 -137.378245) (xy 44.841616 -137.430179)
			(xy 44.864565 -137.485583) (xy 44.880086 -137.543508) (xy 44.887914 -137.602964) (xy 44.888404 -137.632948)
			(xy 44.888404 -138.496548) (xy 160.072324 -138.496548) (xy 160.072324 -137.632948) (xy 160.072814 -137.602964)
			(xy 160.080642 -137.543508) (xy 160.096163 -137.485583) (xy 160.119112 -137.430179) (xy 160.149096 -137.378245)
			(xy 160.185602 -137.330669) (xy 160.228007 -137.288264) (xy 160.275583 -137.251758) (xy 160.327517 -137.221774)
			(xy 160.382921 -137.198825) (xy 160.440846 -137.183304) (xy 160.500302 -137.175476) (xy 160.56027 -137.175476)
			(xy 160.619726 -137.183304) (xy 160.677651 -137.198825) (xy 160.733055 -137.221774) (xy 160.784989 -137.251758)
			(xy 160.832565 -137.288264) (xy 160.87497 -137.330669) (xy 160.911476 -137.378245) (xy 160.94146 -137.430179)
			(xy 160.964409 -137.485583) (xy 160.97993 -137.543508) (xy 160.987758 -137.602964) (xy 160.988248 -137.632948)
			(xy 160.988248 -138.496548) (xy 276.172676 -138.496548) (xy 276.172676 -137.632948) (xy 276.173166 -137.60298)
			(xy 276.180989 -137.543558) (xy 276.196502 -137.485665) (xy 276.219438 -137.430292) (xy 276.249405 -137.378386)
			(xy 276.285892 -137.330836) (xy 276.328272 -137.288456) (xy 276.375822 -137.251969) (xy 276.427728 -137.222002)
			(xy 276.483101 -137.199066) (xy 276.540994 -137.183553) (xy 276.600416 -137.17573) (xy 276.660352 -137.17573)
			(xy 276.719774 -137.183553) (xy 276.777667 -137.199066) (xy 276.83304 -137.222002) (xy 276.884946 -137.251969)
			(xy 276.932496 -137.288456) (xy 276.974876 -137.330836) (xy 277.011363 -137.378386) (xy 277.04133 -137.430292)
			(xy 277.064266 -137.485665) (xy 277.079779 -137.543558) (xy 277.087602 -137.60298) (xy 277.088092 -137.632948)
			(xy 277.088092 -138.496548) (xy 277.088084 -138.497056) (xy 392.27252 -138.497056) (xy 392.27252 -137.633456)
			(xy 392.27301 -137.603472) (xy 392.280838 -137.544016) (xy 392.296359 -137.486091) (xy 392.319308 -137.430687)
			(xy 392.349292 -137.378753) (xy 392.385798 -137.331177) (xy 392.428203 -137.288772) (xy 392.475779 -137.252266)
			(xy 392.527713 -137.222282) (xy 392.583117 -137.199333) (xy 392.641042 -137.183812) (xy 392.700498 -137.175984)
			(xy 392.760466 -137.175984) (xy 392.819922 -137.183812) (xy 392.877847 -137.199333) (xy 392.933251 -137.222282)
			(xy 392.985185 -137.252266) (xy 393.032761 -137.288772) (xy 393.075166 -137.331177) (xy 393.111672 -137.378753)
			(xy 393.141656 -137.430687) (xy 393.164605 -137.486091) (xy 393.180126 -137.544016) (xy 393.187954 -137.603472)
			(xy 393.188444 -137.633456) (xy 393.188444 -138.497056) (xy 393.187954 -138.52704) (xy 393.180126 -138.586496)
			(xy 393.164605 -138.644421) (xy 393.141656 -138.699825) (xy 393.111672 -138.751759) (xy 393.075166 -138.799335)
			(xy 393.032761 -138.84174) (xy 392.985185 -138.878246) (xy 392.933251 -138.90823) (xy 392.877847 -138.931179)
			(xy 392.819922 -138.9467) (xy 392.760466 -138.954528) (xy 392.700498 -138.954528) (xy 392.641042 -138.9467)
			(xy 392.583117 -138.931179) (xy 392.527713 -138.90823) (xy 392.475779 -138.878246) (xy 392.428203 -138.84174)
			(xy 392.385798 -138.799335) (xy 392.349292 -138.751759) (xy 392.319308 -138.699825) (xy 392.296359 -138.644421)
			(xy 392.280838 -138.586496) (xy 392.27301 -138.52704) (xy 392.27252 -138.497056) (xy 277.088084 -138.497056)
			(xy 277.087602 -138.526516) (xy 277.079779 -138.585938) (xy 277.064266 -138.643831) (xy 277.04133 -138.699204)
			(xy 277.011363 -138.75111) (xy 276.974876 -138.79866) (xy 276.932496 -138.84104) (xy 276.884946 -138.877527)
			(xy 276.83304 -138.907494) (xy 276.777667 -138.93043) (xy 276.719774 -138.945943) (xy 276.660352 -138.953766)
			(xy 276.600416 -138.953766) (xy 276.540994 -138.945943) (xy 276.483101 -138.93043) (xy 276.427728 -138.907494)
			(xy 276.375822 -138.877527) (xy 276.328272 -138.84104) (xy 276.285892 -138.79866) (xy 276.249405 -138.75111)
			(xy 276.219438 -138.699204) (xy 276.196502 -138.643831) (xy 276.180989 -138.585938) (xy 276.173166 -138.526516)
			(xy 276.172676 -138.496548) (xy 160.988248 -138.496548) (xy 160.987758 -138.526532) (xy 160.97993 -138.585988)
			(xy 160.964409 -138.643913) (xy 160.94146 -138.699317) (xy 160.911476 -138.751251) (xy 160.87497 -138.798827)
			(xy 160.832565 -138.841232) (xy 160.784989 -138.877738) (xy 160.733055 -138.907722) (xy 160.677651 -138.930671)
			(xy 160.619726 -138.946192) (xy 160.56027 -138.95402) (xy 160.500302 -138.95402) (xy 160.440846 -138.946192)
			(xy 160.382921 -138.930671) (xy 160.327517 -138.907722) (xy 160.275583 -138.877738) (xy 160.228007 -138.841232)
			(xy 160.185602 -138.798827) (xy 160.149096 -138.751251) (xy 160.119112 -138.699317) (xy 160.096163 -138.643913)
			(xy 160.080642 -138.585988) (xy 160.072814 -138.526532) (xy 160.072324 -138.496548) (xy 44.888404 -138.496548)
			(xy 44.887914 -138.526532) (xy 44.880086 -138.585988) (xy 44.864565 -138.643913) (xy 44.841616 -138.699317)
			(xy 44.811632 -138.751251) (xy 44.775126 -138.798827) (xy 44.732721 -138.841232) (xy 44.685145 -138.877738)
			(xy 44.633211 -138.907722) (xy 44.577807 -138.930671) (xy 44.519882 -138.946192) (xy 44.460426 -138.95402)
			(xy 44.400458 -138.95402) (xy 44.341002 -138.946192) (xy 44.283077 -138.930671) (xy 44.227673 -138.907722)
			(xy 44.175739 -138.877738) (xy 44.128163 -138.841232) (xy 44.085758 -138.798827) (xy 44.049252 -138.751251)
			(xy 44.019268 -138.699317) (xy 43.996319 -138.643913) (xy 43.980798 -138.585988) (xy 43.97297 -138.526532)
			(xy 43.97248 -138.496548) (xy 4.30911 -138.496548) (xy 4.30911 -143.48714) (xy 66.599308 -143.48714)
			(xy 66.599308 -142.62354) (xy 66.599798 -142.593556) (xy 66.607626 -142.5341) (xy 66.623147 -142.476175)
			(xy 66.646096 -142.420771) (xy 66.67608 -142.368837) (xy 66.712586 -142.321261) (xy 66.754991 -142.278856)
			(xy 66.802567 -142.24235) (xy 66.854501 -142.212366) (xy 66.909905 -142.189417) (xy 66.96783 -142.173896)
			(xy 67.027286 -142.166068) (xy 67.087254 -142.166068) (xy 67.14671 -142.173896) (xy 67.204635 -142.189417)
			(xy 67.260039 -142.212366) (xy 67.311973 -142.24235) (xy 67.359549 -142.278856) (xy 67.401954 -142.321261)
			(xy 67.43846 -142.368837) (xy 67.468444 -142.420771) (xy 67.491393 -142.476175) (xy 67.506914 -142.5341)
			(xy 67.514742 -142.593556) (xy 67.515232 -142.62354) (xy 67.515232 -143.479266) (xy 81.07426 -143.479266)
			(xy 81.07426 -142.615666) (xy 81.07475 -142.585682) (xy 81.082578 -142.526226) (xy 81.098099 -142.468301)
			(xy 81.121048 -142.412897) (xy 81.151032 -142.360963) (xy 81.187538 -142.313387) (xy 81.229943 -142.270982)
			(xy 81.277519 -142.234476) (xy 81.329453 -142.204492) (xy 81.384857 -142.181543) (xy 81.442782 -142.166022)
			(xy 81.502238 -142.158194) (xy 81.562206 -142.158194) (xy 81.621662 -142.166022) (xy 81.679587 -142.181543)
			(xy 81.734991 -142.204492) (xy 81.786925 -142.234476) (xy 81.834501 -142.270982) (xy 81.876906 -142.313387)
			(xy 81.913412 -142.360963) (xy 81.943396 -142.412897) (xy 81.966345 -142.468301) (xy 81.981866 -142.526226)
			(xy 81.989694 -142.585682) (xy 81.990184 -142.615666) (xy 81.990184 -143.479266) (xy 81.990055 -143.48714)
			(xy 182.69966 -143.48714) (xy 182.69966 -142.62354) (xy 182.70015 -142.593572) (xy 182.707973 -142.53415)
			(xy 182.723486 -142.476257) (xy 182.746422 -142.420884) (xy 182.776389 -142.368978) (xy 182.812876 -142.321428)
			(xy 182.855256 -142.279048) (xy 182.902806 -142.242561) (xy 182.954712 -142.212594) (xy 183.010085 -142.189658)
			(xy 183.067978 -142.174145) (xy 183.1274 -142.166322) (xy 183.187336 -142.166322) (xy 183.246758 -142.174145)
			(xy 183.304651 -142.189658) (xy 183.360024 -142.212594) (xy 183.41193 -142.242561) (xy 183.45948 -142.279048)
			(xy 183.50186 -142.321428) (xy 183.538347 -142.368978) (xy 183.568314 -142.420884) (xy 183.59125 -142.476257)
			(xy 183.606763 -142.53415) (xy 183.614586 -142.593572) (xy 183.615076 -142.62354) (xy 183.615076 -143.479266)
			(xy 197.174612 -143.479266) (xy 197.174612 -142.615666) (xy 197.175102 -142.585698) (xy 197.182925 -142.526276)
			(xy 197.198438 -142.468383) (xy 197.221374 -142.41301) (xy 197.251341 -142.361104) (xy 197.287828 -142.313554)
			(xy 197.330208 -142.271174) (xy 197.377758 -142.234687) (xy 197.429664 -142.20472) (xy 197.485037 -142.181784)
			(xy 197.54293 -142.166271) (xy 197.602352 -142.158448) (xy 197.662288 -142.158448) (xy 197.72171 -142.166271)
			(xy 197.779603 -142.181784) (xy 197.834976 -142.20472) (xy 197.886882 -142.234687) (xy 197.934432 -142.271174)
			(xy 197.976812 -142.313554) (xy 198.013299 -142.361104) (xy 198.043266 -142.41301) (xy 198.066202 -142.468383)
			(xy 198.081715 -142.526276) (xy 198.089538 -142.585698) (xy 198.090028 -142.615666) (xy 198.090028 -143.479266)
			(xy 198.089899 -143.48714) (xy 298.799504 -143.48714) (xy 298.799504 -142.62354) (xy 298.799994 -142.593572)
			(xy 298.807817 -142.53415) (xy 298.82333 -142.476257) (xy 298.846266 -142.420884) (xy 298.876233 -142.368978)
			(xy 298.91272 -142.321428) (xy 298.9551 -142.279048) (xy 299.00265 -142.242561) (xy 299.054556 -142.212594)
			(xy 299.109929 -142.189658) (xy 299.167822 -142.174145) (xy 299.227244 -142.166322) (xy 299.28718 -142.166322)
			(xy 299.346602 -142.174145) (xy 299.404495 -142.189658) (xy 299.459868 -142.212594) (xy 299.511774 -142.242561)
			(xy 299.559324 -142.279048) (xy 299.601704 -142.321428) (xy 299.638191 -142.368978) (xy 299.668158 -142.420884)
			(xy 299.691094 -142.476257) (xy 299.706607 -142.53415) (xy 299.71443 -142.593572) (xy 299.71492 -142.62354)
			(xy 299.71492 -143.479266) (xy 313.274456 -143.479266) (xy 313.274456 -142.615666) (xy 313.274946 -142.585698)
			(xy 313.282769 -142.526276) (xy 313.298282 -142.468383) (xy 313.321218 -142.41301) (xy 313.351185 -142.361104)
			(xy 313.387672 -142.313554) (xy 313.430052 -142.271174) (xy 313.477602 -142.234687) (xy 313.529508 -142.20472)
			(xy 313.584881 -142.181784) (xy 313.642774 -142.166271) (xy 313.702196 -142.158448) (xy 313.762132 -142.158448)
			(xy 313.821554 -142.166271) (xy 313.879447 -142.181784) (xy 313.93482 -142.20472) (xy 313.986726 -142.234687)
			(xy 314.034276 -142.271174) (xy 314.076656 -142.313554) (xy 314.113143 -142.361104) (xy 314.14311 -142.41301)
			(xy 314.166046 -142.468383) (xy 314.181559 -142.526276) (xy 314.189382 -142.585698) (xy 314.189872 -142.615666)
			(xy 314.189872 -143.479266) (xy 314.189743 -143.48714) (xy 414.899348 -143.48714) (xy 414.899348 -142.62354)
			(xy 414.899838 -142.593556) (xy 414.907666 -142.5341) (xy 414.923187 -142.476175) (xy 414.946136 -142.420771)
			(xy 414.97612 -142.368837) (xy 415.012626 -142.321261) (xy 415.055031 -142.278856) (xy 415.102607 -142.24235)
			(xy 415.154541 -142.212366) (xy 415.209945 -142.189417) (xy 415.26787 -142.173896) (xy 415.327326 -142.166068)
			(xy 415.387294 -142.166068) (xy 415.44675 -142.173896) (xy 415.504675 -142.189417) (xy 415.560079 -142.212366)
			(xy 415.612013 -142.24235) (xy 415.659589 -142.278856) (xy 415.701994 -142.321261) (xy 415.7385 -142.368837)
			(xy 415.768484 -142.420771) (xy 415.791433 -142.476175) (xy 415.806954 -142.5341) (xy 415.814782 -142.593556)
			(xy 415.815272 -142.62354) (xy 415.815272 -143.479266) (xy 429.3743 -143.479266) (xy 429.3743 -142.615666)
			(xy 429.37479 -142.585682) (xy 429.382618 -142.526226) (xy 429.398139 -142.468301) (xy 429.421088 -142.412897)
			(xy 429.451072 -142.360963) (xy 429.487578 -142.313387) (xy 429.529983 -142.270982) (xy 429.577559 -142.234476)
			(xy 429.629493 -142.204492) (xy 429.684897 -142.181543) (xy 429.742822 -142.166022) (xy 429.802278 -142.158194)
			(xy 429.862246 -142.158194) (xy 429.921702 -142.166022) (xy 429.979627 -142.181543) (xy 430.035031 -142.204492)
			(xy 430.086965 -142.234476) (xy 430.134541 -142.270982) (xy 430.176946 -142.313387) (xy 430.213452 -142.360963)
			(xy 430.243436 -142.412897) (xy 430.266385 -142.468301) (xy 430.281906 -142.526226) (xy 430.289734 -142.585682)
			(xy 430.290224 -142.615666) (xy 430.290224 -143.479266) (xy 430.289734 -143.50925) (xy 430.281906 -143.568706)
			(xy 430.266385 -143.626631) (xy 430.243436 -143.682035) (xy 430.213452 -143.733969) (xy 430.176946 -143.781545)
			(xy 430.134541 -143.82395) (xy 430.086965 -143.860456) (xy 430.035031 -143.89044) (xy 429.979627 -143.913389)
			(xy 429.921702 -143.92891) (xy 429.862246 -143.936738) (xy 429.802278 -143.936738) (xy 429.742822 -143.92891)
			(xy 429.684897 -143.913389) (xy 429.629493 -143.89044) (xy 429.577559 -143.860456) (xy 429.529983 -143.82395)
			(xy 429.487578 -143.781545) (xy 429.451072 -143.733969) (xy 429.421088 -143.682035) (xy 429.398139 -143.626631)
			(xy 429.382618 -143.568706) (xy 429.37479 -143.50925) (xy 429.3743 -143.479266) (xy 415.815272 -143.479266)
			(xy 415.815272 -143.48714) (xy 415.814782 -143.517124) (xy 415.806954 -143.57658) (xy 415.791433 -143.634505)
			(xy 415.768484 -143.689909) (xy 415.7385 -143.741843) (xy 415.701994 -143.789419) (xy 415.659589 -143.831824)
			(xy 415.612013 -143.86833) (xy 415.560079 -143.898314) (xy 415.504675 -143.921263) (xy 415.44675 -143.936784)
			(xy 415.387294 -143.944612) (xy 415.327326 -143.944612) (xy 415.26787 -143.936784) (xy 415.209945 -143.921263)
			(xy 415.154541 -143.898314) (xy 415.102607 -143.86833) (xy 415.055031 -143.831824) (xy 415.012626 -143.789419)
			(xy 414.97612 -143.741843) (xy 414.946136 -143.689909) (xy 414.923187 -143.634505) (xy 414.907666 -143.57658)
			(xy 414.899838 -143.517124) (xy 414.899348 -143.48714) (xy 314.189743 -143.48714) (xy 314.189382 -143.509234)
			(xy 314.181559 -143.568656) (xy 314.166046 -143.626549) (xy 314.14311 -143.681922) (xy 314.113143 -143.733828)
			(xy 314.076656 -143.781378) (xy 314.034276 -143.823758) (xy 313.986726 -143.860245) (xy 313.93482 -143.890212)
			(xy 313.879447 -143.913148) (xy 313.821554 -143.928661) (xy 313.762132 -143.936484) (xy 313.702196 -143.936484)
			(xy 313.642774 -143.928661) (xy 313.584881 -143.913148) (xy 313.529508 -143.890212) (xy 313.477602 -143.860245)
			(xy 313.430052 -143.823758) (xy 313.387672 -143.781378) (xy 313.351185 -143.733828) (xy 313.321218 -143.681922)
			(xy 313.298282 -143.626549) (xy 313.282769 -143.568656) (xy 313.274946 -143.509234) (xy 313.274456 -143.479266)
			(xy 299.71492 -143.479266) (xy 299.71492 -143.48714) (xy 299.71443 -143.517108) (xy 299.706607 -143.57653)
			(xy 299.691094 -143.634423) (xy 299.668158 -143.689796) (xy 299.638191 -143.741702) (xy 299.601704 -143.789252)
			(xy 299.559324 -143.831632) (xy 299.511774 -143.868119) (xy 299.459868 -143.898086) (xy 299.404495 -143.921022)
			(xy 299.346602 -143.936535) (xy 299.28718 -143.944358) (xy 299.227244 -143.944358) (xy 299.167822 -143.936535)
			(xy 299.109929 -143.921022) (xy 299.054556 -143.898086) (xy 299.00265 -143.868119) (xy 298.9551 -143.831632)
			(xy 298.91272 -143.789252) (xy 298.876233 -143.741702) (xy 298.846266 -143.689796) (xy 298.82333 -143.634423)
			(xy 298.807817 -143.57653) (xy 298.799994 -143.517108) (xy 298.799504 -143.48714) (xy 198.089899 -143.48714)
			(xy 198.089538 -143.509234) (xy 198.081715 -143.568656) (xy 198.066202 -143.626549) (xy 198.043266 -143.681922)
			(xy 198.013299 -143.733828) (xy 197.976812 -143.781378) (xy 197.934432 -143.823758) (xy 197.886882 -143.860245)
			(xy 197.834976 -143.890212) (xy 197.779603 -143.913148) (xy 197.72171 -143.928661) (xy 197.662288 -143.936484)
			(xy 197.602352 -143.936484) (xy 197.54293 -143.928661) (xy 197.485037 -143.913148) (xy 197.429664 -143.890212)
			(xy 197.377758 -143.860245) (xy 197.330208 -143.823758) (xy 197.287828 -143.781378) (xy 197.251341 -143.733828)
			(xy 197.221374 -143.681922) (xy 197.198438 -143.626549) (xy 197.182925 -143.568656) (xy 197.175102 -143.509234)
			(xy 197.174612 -143.479266) (xy 183.615076 -143.479266) (xy 183.615076 -143.48714) (xy 183.614586 -143.517108)
			(xy 183.606763 -143.57653) (xy 183.59125 -143.634423) (xy 183.568314 -143.689796) (xy 183.538347 -143.741702)
			(xy 183.50186 -143.789252) (xy 183.45948 -143.831632) (xy 183.41193 -143.868119) (xy 183.360024 -143.898086)
			(xy 183.304651 -143.921022) (xy 183.246758 -143.936535) (xy 183.187336 -143.944358) (xy 183.1274 -143.944358)
			(xy 183.067978 -143.936535) (xy 183.010085 -143.921022) (xy 182.954712 -143.898086) (xy 182.902806 -143.868119)
			(xy 182.855256 -143.831632) (xy 182.812876 -143.789252) (xy 182.776389 -143.741702) (xy 182.746422 -143.689796)
			(xy 182.723486 -143.634423) (xy 182.707973 -143.57653) (xy 182.70015 -143.517108) (xy 182.69966 -143.48714)
			(xy 81.990055 -143.48714) (xy 81.989694 -143.50925) (xy 81.981866 -143.568706) (xy 81.966345 -143.626631)
			(xy 81.943396 -143.682035) (xy 81.913412 -143.733969) (xy 81.876906 -143.781545) (xy 81.834501 -143.82395)
			(xy 81.786925 -143.860456) (xy 81.734991 -143.89044) (xy 81.679587 -143.913389) (xy 81.621662 -143.92891)
			(xy 81.562206 -143.936738) (xy 81.502238 -143.936738) (xy 81.442782 -143.92891) (xy 81.384857 -143.913389)
			(xy 81.329453 -143.89044) (xy 81.277519 -143.860456) (xy 81.229943 -143.82395) (xy 81.187538 -143.781545)
			(xy 81.151032 -143.733969) (xy 81.121048 -143.682035) (xy 81.098099 -143.626631) (xy 81.082578 -143.568706)
			(xy 81.07475 -143.50925) (xy 81.07426 -143.479266) (xy 67.515232 -143.479266) (xy 67.515232 -143.48714)
			(xy 67.514742 -143.517124) (xy 67.506914 -143.57658) (xy 67.491393 -143.634505) (xy 67.468444 -143.689909)
			(xy 67.43846 -143.741843) (xy 67.401954 -143.789419) (xy 67.359549 -143.831824) (xy 67.311973 -143.86833)
			(xy 67.260039 -143.898314) (xy 67.204635 -143.921263) (xy 67.14671 -143.936784) (xy 67.087254 -143.944612)
			(xy 67.027286 -143.944612) (xy 66.96783 -143.936784) (xy 66.909905 -143.921263) (xy 66.854501 -143.898314)
			(xy 66.802567 -143.86833) (xy 66.754991 -143.831824) (xy 66.712586 -143.789419) (xy 66.67608 -143.741843)
			(xy 66.646096 -143.689909) (xy 66.623147 -143.634505) (xy 66.607626 -143.57658) (xy 66.599798 -143.517124)
			(xy 66.599308 -143.48714) (xy 4.30911 -143.48714) (xy 4.30911 -145.287238) (xy 64.745108 -145.287238)
			(xy 64.745108 -144.423638) (xy 64.745598 -144.393654) (xy 64.753426 -144.334198) (xy 64.768947 -144.276273)
			(xy 64.791896 -144.220869) (xy 64.82188 -144.168935) (xy 64.858386 -144.121359) (xy 64.900791 -144.078954)
			(xy 64.948367 -144.042448) (xy 65.000301 -144.012464) (xy 65.055705 -143.989515) (xy 65.11363 -143.973994)
			(xy 65.173086 -143.966166) (xy 65.233054 -143.966166) (xy 65.29251 -143.973994) (xy 65.350435 -143.989515)
			(xy 65.405839 -144.012464) (xy 65.457773 -144.042448) (xy 65.505349 -144.078954) (xy 65.547754 -144.121359)
			(xy 65.58426 -144.168935) (xy 65.614244 -144.220869) (xy 65.637193 -144.276273) (xy 65.652714 -144.334198)
			(xy 65.660542 -144.393654) (xy 65.661032 -144.423638) (xy 65.661032 -145.285714) (xy 83.716368 -145.285714)
			(xy 83.716368 -144.422114) (xy 83.716858 -144.39213) (xy 83.724686 -144.332674) (xy 83.740207 -144.274749)
			(xy 83.763156 -144.219345) (xy 83.79314 -144.167411) (xy 83.829646 -144.119835) (xy 83.872051 -144.07743)
			(xy 83.919627 -144.040924) (xy 83.971561 -144.01094) (xy 84.026965 -143.987991) (xy 84.08489 -143.97247)
			(xy 84.144346 -143.964642) (xy 84.204314 -143.964642) (xy 84.26377 -143.97247) (xy 84.321695 -143.987991)
			(xy 84.377099 -144.01094) (xy 84.429033 -144.040924) (xy 84.476609 -144.07743) (xy 84.519014 -144.119835)
			(xy 84.55552 -144.167411) (xy 84.585504 -144.219345) (xy 84.608453 -144.274749) (xy 84.623974 -144.332674)
			(xy 84.631802 -144.39213) (xy 84.632292 -144.422114) (xy 84.632292 -145.285714) (xy 84.632267 -145.287238)
			(xy 180.84546 -145.287238) (xy 180.84546 -144.423638) (xy 180.84595 -144.39367) (xy 180.853773 -144.334248)
			(xy 180.869286 -144.276355) (xy 180.892222 -144.220982) (xy 180.922189 -144.169076) (xy 180.958676 -144.121526)
			(xy 181.001056 -144.079146) (xy 181.048606 -144.042659) (xy 181.100512 -144.012692) (xy 181.155885 -143.989756)
			(xy 181.213778 -143.974243) (xy 181.2732 -143.96642) (xy 181.333136 -143.96642) (xy 181.392558 -143.974243)
			(xy 181.450451 -143.989756) (xy 181.505824 -144.012692) (xy 181.55773 -144.042659) (xy 181.60528 -144.079146)
			(xy 181.64766 -144.121526) (xy 181.684147 -144.169076) (xy 181.714114 -144.220982) (xy 181.73705 -144.276355)
			(xy 181.752563 -144.334248) (xy 181.760386 -144.39367) (xy 181.760876 -144.423638) (xy 181.760876 -145.285714)
			(xy 199.81672 -145.285714) (xy 199.81672 -144.422114) (xy 199.81721 -144.392146) (xy 199.825033 -144.332724)
			(xy 199.840546 -144.274831) (xy 199.863482 -144.219458) (xy 199.893449 -144.167552) (xy 199.929936 -144.120002)
			(xy 199.972316 -144.077622) (xy 200.019866 -144.041135) (xy 200.071772 -144.011168) (xy 200.127145 -143.988232)
			(xy 200.185038 -143.972719) (xy 200.24446 -143.964896) (xy 200.304396 -143.964896) (xy 200.363818 -143.972719)
			(xy 200.421711 -143.988232) (xy 200.477084 -144.011168) (xy 200.52899 -144.041135) (xy 200.57654 -144.077622)
			(xy 200.61892 -144.120002) (xy 200.655407 -144.167552) (xy 200.685374 -144.219458) (xy 200.70831 -144.274831)
			(xy 200.723823 -144.332724) (xy 200.731646 -144.392146) (xy 200.732136 -144.422114) (xy 200.732136 -145.285714)
			(xy 200.732111 -145.287238) (xy 296.945304 -145.287238) (xy 296.945304 -144.423638) (xy 296.945794 -144.39367)
			(xy 296.953617 -144.334248) (xy 296.96913 -144.276355) (xy 296.992066 -144.220982) (xy 297.022033 -144.169076)
			(xy 297.05852 -144.121526) (xy 297.1009 -144.079146) (xy 297.14845 -144.042659) (xy 297.200356 -144.012692)
			(xy 297.255729 -143.989756) (xy 297.313622 -143.974243) (xy 297.373044 -143.96642) (xy 297.43298 -143.96642)
			(xy 297.492402 -143.974243) (xy 297.550295 -143.989756) (xy 297.605668 -144.012692) (xy 297.657574 -144.042659)
			(xy 297.705124 -144.079146) (xy 297.747504 -144.121526) (xy 297.783991 -144.169076) (xy 297.813958 -144.220982)
			(xy 297.836894 -144.276355) (xy 297.852407 -144.334248) (xy 297.86023 -144.39367) (xy 297.86072 -144.423638)
			(xy 297.86072 -145.285714) (xy 315.916564 -145.285714) (xy 315.916564 -144.422114) (xy 315.917054 -144.392146)
			(xy 315.924877 -144.332724) (xy 315.94039 -144.274831) (xy 315.963326 -144.219458) (xy 315.993293 -144.167552)
			(xy 316.02978 -144.120002) (xy 316.07216 -144.077622) (xy 316.11971 -144.041135) (xy 316.171616 -144.011168)
			(xy 316.226989 -143.988232) (xy 316.284882 -143.972719) (xy 316.344304 -143.964896) (xy 316.40424 -143.964896)
			(xy 316.463662 -143.972719) (xy 316.521555 -143.988232) (xy 316.576928 -144.011168) (xy 316.628834 -144.041135)
			(xy 316.676384 -144.077622) (xy 316.718764 -144.120002) (xy 316.755251 -144.167552) (xy 316.785218 -144.219458)
			(xy 316.808154 -144.274831) (xy 316.823667 -144.332724) (xy 316.83149 -144.392146) (xy 316.83198 -144.422114)
			(xy 316.83198 -145.285714) (xy 316.831955 -145.287238) (xy 413.045148 -145.287238) (xy 413.045148 -144.423638)
			(xy 413.045638 -144.393654) (xy 413.053466 -144.334198) (xy 413.068987 -144.276273) (xy 413.091936 -144.220869)
			(xy 413.12192 -144.168935) (xy 413.158426 -144.121359) (xy 413.200831 -144.078954) (xy 413.248407 -144.042448)
			(xy 413.300341 -144.012464) (xy 413.355745 -143.989515) (xy 413.41367 -143.973994) (xy 413.473126 -143.966166)
			(xy 413.533094 -143.966166) (xy 413.59255 -143.973994) (xy 413.650475 -143.989515) (xy 413.705879 -144.012464)
			(xy 413.757813 -144.042448) (xy 413.805389 -144.078954) (xy 413.847794 -144.121359) (xy 413.8843 -144.168935)
			(xy 413.914284 -144.220869) (xy 413.937233 -144.276273) (xy 413.952754 -144.334198) (xy 413.960582 -144.393654)
			(xy 413.961072 -144.423638) (xy 413.961072 -145.285714) (xy 432.016408 -145.285714) (xy 432.016408 -144.422114)
			(xy 432.016898 -144.39213) (xy 432.024726 -144.332674) (xy 432.040247 -144.274749) (xy 432.063196 -144.219345)
			(xy 432.09318 -144.167411) (xy 432.129686 -144.119835) (xy 432.172091 -144.07743) (xy 432.219667 -144.040924)
			(xy 432.271601 -144.01094) (xy 432.327005 -143.987991) (xy 432.38493 -143.97247) (xy 432.444386 -143.964642)
			(xy 432.504354 -143.964642) (xy 432.56381 -143.97247) (xy 432.621735 -143.987991) (xy 432.677139 -144.01094)
			(xy 432.729073 -144.040924) (xy 432.776649 -144.07743) (xy 432.819054 -144.119835) (xy 432.85556 -144.167411)
			(xy 432.885544 -144.219345) (xy 432.908493 -144.274749) (xy 432.924014 -144.332674) (xy 432.931842 -144.39213)
			(xy 432.932332 -144.422114) (xy 432.932332 -145.285714) (xy 432.931842 -145.315698) (xy 432.924014 -145.375154)
			(xy 432.908493 -145.433079) (xy 432.885544 -145.488483) (xy 432.85556 -145.540417) (xy 432.819054 -145.587993)
			(xy 432.776649 -145.630398) (xy 432.729073 -145.666904) (xy 432.677139 -145.696888) (xy 432.621735 -145.719837)
			(xy 432.56381 -145.735358) (xy 432.504354 -145.743186) (xy 432.444386 -145.743186) (xy 432.38493 -145.735358)
			(xy 432.327005 -145.719837) (xy 432.271601 -145.696888) (xy 432.219667 -145.666904) (xy 432.172091 -145.630398)
			(xy 432.129686 -145.587993) (xy 432.09318 -145.540417) (xy 432.063196 -145.488483) (xy 432.040247 -145.433079)
			(xy 432.024726 -145.375154) (xy 432.016898 -145.315698) (xy 432.016408 -145.285714) (xy 413.961072 -145.285714)
			(xy 413.961072 -145.287238) (xy 413.960582 -145.317222) (xy 413.952754 -145.376678) (xy 413.937233 -145.434603)
			(xy 413.914284 -145.490007) (xy 413.8843 -145.541941) (xy 413.847794 -145.589517) (xy 413.805389 -145.631922)
			(xy 413.757813 -145.668428) (xy 413.705879 -145.698412) (xy 413.650475 -145.721361) (xy 413.59255 -145.736882)
			(xy 413.533094 -145.74471) (xy 413.473126 -145.74471) (xy 413.41367 -145.736882) (xy 413.355745 -145.721361)
			(xy 413.300341 -145.698412) (xy 413.248407 -145.668428) (xy 413.200831 -145.631922) (xy 413.158426 -145.589517)
			(xy 413.12192 -145.541941) (xy 413.091936 -145.490007) (xy 413.068987 -145.434603) (xy 413.053466 -145.376678)
			(xy 413.045638 -145.317222) (xy 413.045148 -145.287238) (xy 316.831955 -145.287238) (xy 316.83149 -145.315682)
			(xy 316.823667 -145.375104) (xy 316.808154 -145.432997) (xy 316.785218 -145.48837) (xy 316.755251 -145.540276)
			(xy 316.718764 -145.587826) (xy 316.676384 -145.630206) (xy 316.628834 -145.666693) (xy 316.576928 -145.69666)
			(xy 316.521555 -145.719596) (xy 316.463662 -145.735109) (xy 316.40424 -145.742932) (xy 316.344304 -145.742932)
			(xy 316.284882 -145.735109) (xy 316.226989 -145.719596) (xy 316.171616 -145.69666) (xy 316.11971 -145.666693)
			(xy 316.07216 -145.630206) (xy 316.02978 -145.587826) (xy 315.993293 -145.540276) (xy 315.963326 -145.48837)
			(xy 315.94039 -145.432997) (xy 315.924877 -145.375104) (xy 315.917054 -145.315682) (xy 315.916564 -145.285714)
			(xy 297.86072 -145.285714) (xy 297.86072 -145.287238) (xy 297.86023 -145.317206) (xy 297.852407 -145.376628)
			(xy 297.836894 -145.434521) (xy 297.813958 -145.489894) (xy 297.783991 -145.5418) (xy 297.747504 -145.58935)
			(xy 297.705124 -145.63173) (xy 297.657574 -145.668217) (xy 297.605668 -145.698184) (xy 297.550295 -145.72112)
			(xy 297.492402 -145.736633) (xy 297.43298 -145.744456) (xy 297.373044 -145.744456) (xy 297.313622 -145.736633)
			(xy 297.255729 -145.72112) (xy 297.200356 -145.698184) (xy 297.14845 -145.668217) (xy 297.1009 -145.63173)
			(xy 297.05852 -145.58935) (xy 297.022033 -145.5418) (xy 296.992066 -145.489894) (xy 296.96913 -145.434521)
			(xy 296.953617 -145.376628) (xy 296.945794 -145.317206) (xy 296.945304 -145.287238) (xy 200.732111 -145.287238)
			(xy 200.731646 -145.315682) (xy 200.723823 -145.375104) (xy 200.70831 -145.432997) (xy 200.685374 -145.48837)
			(xy 200.655407 -145.540276) (xy 200.61892 -145.587826) (xy 200.57654 -145.630206) (xy 200.52899 -145.666693)
			(xy 200.477084 -145.69666) (xy 200.421711 -145.719596) (xy 200.363818 -145.735109) (xy 200.304396 -145.742932)
			(xy 200.24446 -145.742932) (xy 200.185038 -145.735109) (xy 200.127145 -145.719596) (xy 200.071772 -145.69666)
			(xy 200.019866 -145.666693) (xy 199.972316 -145.630206) (xy 199.929936 -145.587826) (xy 199.893449 -145.540276)
			(xy 199.863482 -145.48837) (xy 199.840546 -145.432997) (xy 199.825033 -145.375104) (xy 199.81721 -145.315682)
			(xy 199.81672 -145.285714) (xy 181.760876 -145.285714) (xy 181.760876 -145.287238) (xy 181.760386 -145.317206)
			(xy 181.752563 -145.376628) (xy 181.73705 -145.434521) (xy 181.714114 -145.489894) (xy 181.684147 -145.5418)
			(xy 181.64766 -145.58935) (xy 181.60528 -145.63173) (xy 181.55773 -145.668217) (xy 181.505824 -145.698184)
			(xy 181.450451 -145.72112) (xy 181.392558 -145.736633) (xy 181.333136 -145.744456) (xy 181.2732 -145.744456)
			(xy 181.213778 -145.736633) (xy 181.155885 -145.72112) (xy 181.100512 -145.698184) (xy 181.048606 -145.668217)
			(xy 181.001056 -145.63173) (xy 180.958676 -145.58935) (xy 180.922189 -145.5418) (xy 180.892222 -145.489894)
			(xy 180.869286 -145.434521) (xy 180.853773 -145.376628) (xy 180.84595 -145.317206) (xy 180.84546 -145.287238)
			(xy 84.632267 -145.287238) (xy 84.631802 -145.315698) (xy 84.623974 -145.375154) (xy 84.608453 -145.433079)
			(xy 84.585504 -145.488483) (xy 84.55552 -145.540417) (xy 84.519014 -145.587993) (xy 84.476609 -145.630398)
			(xy 84.429033 -145.666904) (xy 84.377099 -145.696888) (xy 84.321695 -145.719837) (xy 84.26377 -145.735358)
			(xy 84.204314 -145.743186) (xy 84.144346 -145.743186) (xy 84.08489 -145.735358) (xy 84.026965 -145.719837)
			(xy 83.971561 -145.696888) (xy 83.919627 -145.666904) (xy 83.872051 -145.630398) (xy 83.829646 -145.587993)
			(xy 83.79314 -145.540417) (xy 83.763156 -145.488483) (xy 83.740207 -145.433079) (xy 83.724686 -145.375154)
			(xy 83.716858 -145.315698) (xy 83.716368 -145.285714) (xy 65.661032 -145.285714) (xy 65.661032 -145.287238)
			(xy 65.660542 -145.317222) (xy 65.652714 -145.376678) (xy 65.637193 -145.434603) (xy 65.614244 -145.490007)
			(xy 65.58426 -145.541941) (xy 65.547754 -145.589517) (xy 65.505349 -145.631922) (xy 65.457773 -145.668428)
			(xy 65.405839 -145.698412) (xy 65.350435 -145.721361) (xy 65.29251 -145.736882) (xy 65.233054 -145.74471)
			(xy 65.173086 -145.74471) (xy 65.11363 -145.736882) (xy 65.055705 -145.721361) (xy 65.000301 -145.698412)
			(xy 64.948367 -145.668428) (xy 64.900791 -145.631922) (xy 64.858386 -145.589517) (xy 64.82188 -145.541941)
			(xy 64.791896 -145.490007) (xy 64.768947 -145.434603) (xy 64.753426 -145.376678) (xy 64.745598 -145.317222)
			(xy 64.745108 -145.287238) (xy 4.30911 -145.287238) (xy 4.30911 -147.087336) (xy 66.599308 -147.087336)
			(xy 66.599308 -146.223736) (xy 66.599798 -146.193752) (xy 66.607626 -146.134296) (xy 66.623147 -146.076371)
			(xy 66.646096 -146.020967) (xy 66.67608 -145.969033) (xy 66.712586 -145.921457) (xy 66.754991 -145.879052)
			(xy 66.802567 -145.842546) (xy 66.854501 -145.812562) (xy 66.909905 -145.789613) (xy 66.96783 -145.774092)
			(xy 67.027286 -145.766264) (xy 67.087254 -145.766264) (xy 67.14671 -145.774092) (xy 67.204635 -145.789613)
			(xy 67.260039 -145.812562) (xy 67.311973 -145.842546) (xy 67.359549 -145.879052) (xy 67.401954 -145.921457)
			(xy 67.43846 -145.969033) (xy 67.468444 -146.020967) (xy 67.491393 -146.076371) (xy 67.506914 -146.134296)
			(xy 67.514742 -146.193752) (xy 67.515232 -146.223736) (xy 67.515232 -147.079208) (xy 81.07426 -147.079208)
			(xy 81.07426 -146.215608) (xy 81.07475 -146.185624) (xy 81.082578 -146.126168) (xy 81.098099 -146.068243)
			(xy 81.121048 -146.012839) (xy 81.151032 -145.960905) (xy 81.187538 -145.913329) (xy 81.229943 -145.870924)
			(xy 81.277519 -145.834418) (xy 81.329453 -145.804434) (xy 81.384857 -145.781485) (xy 81.442782 -145.765964)
			(xy 81.502238 -145.758136) (xy 81.562206 -145.758136) (xy 81.621662 -145.765964) (xy 81.679587 -145.781485)
			(xy 81.734991 -145.804434) (xy 81.786925 -145.834418) (xy 81.834501 -145.870924) (xy 81.876906 -145.913329)
			(xy 81.913412 -145.960905) (xy 81.943396 -146.012839) (xy 81.966345 -146.068243) (xy 81.981866 -146.126168)
			(xy 81.989694 -146.185624) (xy 81.990184 -146.215608) (xy 81.990184 -147.079208) (xy 81.990051 -147.087336)
			(xy 182.69966 -147.087336) (xy 182.69966 -146.223736) (xy 182.70015 -146.193768) (xy 182.707973 -146.134346)
			(xy 182.723486 -146.076453) (xy 182.746422 -146.02108) (xy 182.776389 -145.969174) (xy 182.812876 -145.921624)
			(xy 182.855256 -145.879244) (xy 182.902806 -145.842757) (xy 182.954712 -145.81279) (xy 183.010085 -145.789854)
			(xy 183.067978 -145.774341) (xy 183.1274 -145.766518) (xy 183.187336 -145.766518) (xy 183.246758 -145.774341)
			(xy 183.304651 -145.789854) (xy 183.360024 -145.81279) (xy 183.41193 -145.842757) (xy 183.45948 -145.879244)
			(xy 183.50186 -145.921624) (xy 183.538347 -145.969174) (xy 183.568314 -146.02108) (xy 183.59125 -146.076453)
			(xy 183.606763 -146.134346) (xy 183.614586 -146.193768) (xy 183.615076 -146.223736) (xy 183.615076 -147.079208)
			(xy 197.174612 -147.079208) (xy 197.174612 -146.215608) (xy 197.175102 -146.18564) (xy 197.182925 -146.126218)
			(xy 197.198438 -146.068325) (xy 197.221374 -146.012952) (xy 197.251341 -145.961046) (xy 197.287828 -145.913496)
			(xy 197.330208 -145.871116) (xy 197.377758 -145.834629) (xy 197.429664 -145.804662) (xy 197.485037 -145.781726)
			(xy 197.54293 -145.766213) (xy 197.602352 -145.75839) (xy 197.662288 -145.75839) (xy 197.72171 -145.766213)
			(xy 197.779603 -145.781726) (xy 197.834976 -145.804662) (xy 197.886882 -145.834629) (xy 197.934432 -145.871116)
			(xy 197.976812 -145.913496) (xy 198.013299 -145.961046) (xy 198.043266 -146.012952) (xy 198.066202 -146.068325)
			(xy 198.081715 -146.126218) (xy 198.089538 -146.18564) (xy 198.090028 -146.215608) (xy 198.090028 -147.079208)
			(xy 198.089895 -147.087336) (xy 298.799504 -147.087336) (xy 298.799504 -146.223736) (xy 298.799994 -146.193768)
			(xy 298.807817 -146.134346) (xy 298.82333 -146.076453) (xy 298.846266 -146.02108) (xy 298.876233 -145.969174)
			(xy 298.91272 -145.921624) (xy 298.9551 -145.879244) (xy 299.00265 -145.842757) (xy 299.054556 -145.81279)
			(xy 299.109929 -145.789854) (xy 299.167822 -145.774341) (xy 299.227244 -145.766518) (xy 299.28718 -145.766518)
			(xy 299.346602 -145.774341) (xy 299.404495 -145.789854) (xy 299.459868 -145.81279) (xy 299.511774 -145.842757)
			(xy 299.559324 -145.879244) (xy 299.601704 -145.921624) (xy 299.638191 -145.969174) (xy 299.668158 -146.02108)
			(xy 299.691094 -146.076453) (xy 299.706607 -146.134346) (xy 299.71443 -146.193768) (xy 299.71492 -146.223736)
			(xy 299.71492 -147.079208) (xy 313.274456 -147.079208) (xy 313.274456 -146.215608) (xy 313.274946 -146.18564)
			(xy 313.282769 -146.126218) (xy 313.298282 -146.068325) (xy 313.321218 -146.012952) (xy 313.351185 -145.961046)
			(xy 313.387672 -145.913496) (xy 313.430052 -145.871116) (xy 313.477602 -145.834629) (xy 313.529508 -145.804662)
			(xy 313.584881 -145.781726) (xy 313.642774 -145.766213) (xy 313.702196 -145.75839) (xy 313.762132 -145.75839)
			(xy 313.821554 -145.766213) (xy 313.879447 -145.781726) (xy 313.93482 -145.804662) (xy 313.986726 -145.834629)
			(xy 314.034276 -145.871116) (xy 314.076656 -145.913496) (xy 314.113143 -145.961046) (xy 314.14311 -146.012952)
			(xy 314.166046 -146.068325) (xy 314.181559 -146.126218) (xy 314.189382 -146.18564) (xy 314.189872 -146.215608)
			(xy 314.189872 -147.079208) (xy 314.189739 -147.087336) (xy 414.899348 -147.087336) (xy 414.899348 -146.223736)
			(xy 414.899838 -146.193752) (xy 414.907666 -146.134296) (xy 414.923187 -146.076371) (xy 414.946136 -146.020967)
			(xy 414.97612 -145.969033) (xy 415.012626 -145.921457) (xy 415.055031 -145.879052) (xy 415.102607 -145.842546)
			(xy 415.154541 -145.812562) (xy 415.209945 -145.789613) (xy 415.26787 -145.774092) (xy 415.327326 -145.766264)
			(xy 415.387294 -145.766264) (xy 415.44675 -145.774092) (xy 415.504675 -145.789613) (xy 415.560079 -145.812562)
			(xy 415.612013 -145.842546) (xy 415.659589 -145.879052) (xy 415.701994 -145.921457) (xy 415.7385 -145.969033)
			(xy 415.768484 -146.020967) (xy 415.791433 -146.076371) (xy 415.806954 -146.134296) (xy 415.814782 -146.193752)
			(xy 415.815272 -146.223736) (xy 415.815272 -147.079208) (xy 429.3743 -147.079208) (xy 429.3743 -146.215608)
			(xy 429.37479 -146.185624) (xy 429.382618 -146.126168) (xy 429.398139 -146.068243) (xy 429.421088 -146.012839)
			(xy 429.451072 -145.960905) (xy 429.487578 -145.913329) (xy 429.529983 -145.870924) (xy 429.577559 -145.834418)
			(xy 429.629493 -145.804434) (xy 429.684897 -145.781485) (xy 429.742822 -145.765964) (xy 429.802278 -145.758136)
			(xy 429.862246 -145.758136) (xy 429.921702 -145.765964) (xy 429.979627 -145.781485) (xy 430.035031 -145.804434)
			(xy 430.086965 -145.834418) (xy 430.134541 -145.870924) (xy 430.176946 -145.913329) (xy 430.213452 -145.960905)
			(xy 430.243436 -146.012839) (xy 430.266385 -146.068243) (xy 430.281906 -146.126168) (xy 430.289734 -146.185624)
			(xy 430.290224 -146.215608) (xy 430.290224 -147.079208) (xy 430.289734 -147.109192) (xy 430.281906 -147.168648)
			(xy 430.266385 -147.226573) (xy 430.243436 -147.281977) (xy 430.213452 -147.333911) (xy 430.176946 -147.381487)
			(xy 430.134541 -147.423892) (xy 430.086965 -147.460398) (xy 430.035031 -147.490382) (xy 429.979627 -147.513331)
			(xy 429.921702 -147.528852) (xy 429.862246 -147.53668) (xy 429.802278 -147.53668) (xy 429.742822 -147.528852)
			(xy 429.684897 -147.513331) (xy 429.629493 -147.490382) (xy 429.577559 -147.460398) (xy 429.529983 -147.423892)
			(xy 429.487578 -147.381487) (xy 429.451072 -147.333911) (xy 429.421088 -147.281977) (xy 429.398139 -147.226573)
			(xy 429.382618 -147.168648) (xy 429.37479 -147.109192) (xy 429.3743 -147.079208) (xy 415.815272 -147.079208)
			(xy 415.815272 -147.087336) (xy 415.814782 -147.11732) (xy 415.806954 -147.176776) (xy 415.791433 -147.234701)
			(xy 415.768484 -147.290105) (xy 415.7385 -147.342039) (xy 415.701994 -147.389615) (xy 415.659589 -147.43202)
			(xy 415.612013 -147.468526) (xy 415.560079 -147.49851) (xy 415.504675 -147.521459) (xy 415.44675 -147.53698)
			(xy 415.387294 -147.544808) (xy 415.327326 -147.544808) (xy 415.26787 -147.53698) (xy 415.209945 -147.521459)
			(xy 415.154541 -147.49851) (xy 415.102607 -147.468526) (xy 415.055031 -147.43202) (xy 415.012626 -147.389615)
			(xy 414.97612 -147.342039) (xy 414.946136 -147.290105) (xy 414.923187 -147.234701) (xy 414.907666 -147.176776)
			(xy 414.899838 -147.11732) (xy 414.899348 -147.087336) (xy 314.189739 -147.087336) (xy 314.189382 -147.109176)
			(xy 314.181559 -147.168598) (xy 314.166046 -147.226491) (xy 314.14311 -147.281864) (xy 314.113143 -147.33377)
			(xy 314.076656 -147.38132) (xy 314.034276 -147.4237) (xy 313.986726 -147.460187) (xy 313.93482 -147.490154)
			(xy 313.879447 -147.51309) (xy 313.821554 -147.528603) (xy 313.762132 -147.536426) (xy 313.702196 -147.536426)
			(xy 313.642774 -147.528603) (xy 313.584881 -147.51309) (xy 313.529508 -147.490154) (xy 313.477602 -147.460187)
			(xy 313.430052 -147.4237) (xy 313.387672 -147.38132) (xy 313.351185 -147.33377) (xy 313.321218 -147.281864)
			(xy 313.298282 -147.226491) (xy 313.282769 -147.168598) (xy 313.274946 -147.109176) (xy 313.274456 -147.079208)
			(xy 299.71492 -147.079208) (xy 299.71492 -147.087336) (xy 299.71443 -147.117304) (xy 299.706607 -147.176726)
			(xy 299.691094 -147.234619) (xy 299.668158 -147.289992) (xy 299.638191 -147.341898) (xy 299.601704 -147.389448)
			(xy 299.559324 -147.431828) (xy 299.511774 -147.468315) (xy 299.459868 -147.498282) (xy 299.404495 -147.521218)
			(xy 299.346602 -147.536731) (xy 299.28718 -147.544554) (xy 299.227244 -147.544554) (xy 299.167822 -147.536731)
			(xy 299.109929 -147.521218) (xy 299.054556 -147.498282) (xy 299.00265 -147.468315) (xy 298.9551 -147.431828)
			(xy 298.91272 -147.389448) (xy 298.876233 -147.341898) (xy 298.846266 -147.289992) (xy 298.82333 -147.234619)
			(xy 298.807817 -147.176726) (xy 298.799994 -147.117304) (xy 298.799504 -147.087336) (xy 198.089895 -147.087336)
			(xy 198.089538 -147.109176) (xy 198.081715 -147.168598) (xy 198.066202 -147.226491) (xy 198.043266 -147.281864)
			(xy 198.013299 -147.33377) (xy 197.976812 -147.38132) (xy 197.934432 -147.4237) (xy 197.886882 -147.460187)
			(xy 197.834976 -147.490154) (xy 197.779603 -147.51309) (xy 197.72171 -147.528603) (xy 197.662288 -147.536426)
			(xy 197.602352 -147.536426) (xy 197.54293 -147.528603) (xy 197.485037 -147.51309) (xy 197.429664 -147.490154)
			(xy 197.377758 -147.460187) (xy 197.330208 -147.4237) (xy 197.287828 -147.38132) (xy 197.251341 -147.33377)
			(xy 197.221374 -147.281864) (xy 197.198438 -147.226491) (xy 197.182925 -147.168598) (xy 197.175102 -147.109176)
			(xy 197.174612 -147.079208) (xy 183.615076 -147.079208) (xy 183.615076 -147.087336) (xy 183.614586 -147.117304)
			(xy 183.606763 -147.176726) (xy 183.59125 -147.234619) (xy 183.568314 -147.289992) (xy 183.538347 -147.341898)
			(xy 183.50186 -147.389448) (xy 183.45948 -147.431828) (xy 183.41193 -147.468315) (xy 183.360024 -147.498282)
			(xy 183.304651 -147.521218) (xy 183.246758 -147.536731) (xy 183.187336 -147.544554) (xy 183.1274 -147.544554)
			(xy 183.067978 -147.536731) (xy 183.010085 -147.521218) (xy 182.954712 -147.498282) (xy 182.902806 -147.468315)
			(xy 182.855256 -147.431828) (xy 182.812876 -147.389448) (xy 182.776389 -147.341898) (xy 182.746422 -147.289992)
			(xy 182.723486 -147.234619) (xy 182.707973 -147.176726) (xy 182.70015 -147.117304) (xy 182.69966 -147.087336)
			(xy 81.990051 -147.087336) (xy 81.989694 -147.109192) (xy 81.981866 -147.168648) (xy 81.966345 -147.226573)
			(xy 81.943396 -147.281977) (xy 81.913412 -147.333911) (xy 81.876906 -147.381487) (xy 81.834501 -147.423892)
			(xy 81.786925 -147.460398) (xy 81.734991 -147.490382) (xy 81.679587 -147.513331) (xy 81.621662 -147.528852)
			(xy 81.562206 -147.53668) (xy 81.502238 -147.53668) (xy 81.442782 -147.528852) (xy 81.384857 -147.513331)
			(xy 81.329453 -147.490382) (xy 81.277519 -147.460398) (xy 81.229943 -147.423892) (xy 81.187538 -147.381487)
			(xy 81.151032 -147.333911) (xy 81.121048 -147.281977) (xy 81.098099 -147.226573) (xy 81.082578 -147.168648)
			(xy 81.07475 -147.109192) (xy 81.07426 -147.079208) (xy 67.515232 -147.079208) (xy 67.515232 -147.087336)
			(xy 67.514742 -147.11732) (xy 67.506914 -147.176776) (xy 67.491393 -147.234701) (xy 67.468444 -147.290105)
			(xy 67.43846 -147.342039) (xy 67.401954 -147.389615) (xy 67.359549 -147.43202) (xy 67.311973 -147.468526)
			(xy 67.260039 -147.49851) (xy 67.204635 -147.521459) (xy 67.14671 -147.53698) (xy 67.087254 -147.544808)
			(xy 67.027286 -147.544808) (xy 66.96783 -147.53698) (xy 66.909905 -147.521459) (xy 66.854501 -147.49851)
			(xy 66.802567 -147.468526) (xy 66.754991 -147.43202) (xy 66.712586 -147.389615) (xy 66.67608 -147.342039)
			(xy 66.646096 -147.290105) (xy 66.623147 -147.234701) (xy 66.607626 -147.176776) (xy 66.599798 -147.11732)
			(xy 66.599308 -147.087336) (xy 4.30911 -147.087336) (xy 4.30911 -148.887434) (xy 64.745108 -148.887434)
			(xy 64.745108 -148.023834) (xy 64.745598 -147.99385) (xy 64.753426 -147.934394) (xy 64.768947 -147.876469)
			(xy 64.791896 -147.821065) (xy 64.82188 -147.769131) (xy 64.858386 -147.721555) (xy 64.900791 -147.67915)
			(xy 64.948367 -147.642644) (xy 65.000301 -147.61266) (xy 65.055705 -147.589711) (xy 65.11363 -147.57419)
			(xy 65.173086 -147.566362) (xy 65.233054 -147.566362) (xy 65.29251 -147.57419) (xy 65.350435 -147.589711)
			(xy 65.405839 -147.61266) (xy 65.457773 -147.642644) (xy 65.505349 -147.67915) (xy 65.547754 -147.721555)
			(xy 65.58426 -147.769131) (xy 65.614244 -147.821065) (xy 65.637193 -147.876469) (xy 65.652714 -147.934394)
			(xy 65.660542 -147.99385) (xy 65.661032 -148.023834) (xy 65.661032 -148.88591) (xy 83.716368 -148.88591)
			(xy 83.716368 -148.02231) (xy 83.716858 -147.992326) (xy 83.724686 -147.93287) (xy 83.740207 -147.874945)
			(xy 83.763156 -147.819541) (xy 83.79314 -147.767607) (xy 83.829646 -147.720031) (xy 83.872051 -147.677626)
			(xy 83.919627 -147.64112) (xy 83.971561 -147.611136) (xy 84.026965 -147.588187) (xy 84.08489 -147.572666)
			(xy 84.144346 -147.564838) (xy 84.204314 -147.564838) (xy 84.26377 -147.572666) (xy 84.321695 -147.588187)
			(xy 84.377099 -147.611136) (xy 84.429033 -147.64112) (xy 84.476609 -147.677626) (xy 84.519014 -147.720031)
			(xy 84.55552 -147.767607) (xy 84.585504 -147.819541) (xy 84.608453 -147.874945) (xy 84.623974 -147.93287)
			(xy 84.631802 -147.992326) (xy 84.632292 -148.02231) (xy 84.632292 -148.88591) (xy 84.632267 -148.887434)
			(xy 180.84546 -148.887434) (xy 180.84546 -148.023834) (xy 180.84595 -147.993866) (xy 180.853773 -147.934444)
			(xy 180.869286 -147.876551) (xy 180.892222 -147.821178) (xy 180.922189 -147.769272) (xy 180.958676 -147.721722)
			(xy 181.001056 -147.679342) (xy 181.048606 -147.642855) (xy 181.100512 -147.612888) (xy 181.155885 -147.589952)
			(xy 181.213778 -147.574439) (xy 181.2732 -147.566616) (xy 181.333136 -147.566616) (xy 181.392558 -147.574439)
			(xy 181.450451 -147.589952) (xy 181.505824 -147.612888) (xy 181.55773 -147.642855) (xy 181.60528 -147.679342)
			(xy 181.64766 -147.721722) (xy 181.684147 -147.769272) (xy 181.714114 -147.821178) (xy 181.73705 -147.876551)
			(xy 181.752563 -147.934444) (xy 181.760386 -147.993866) (xy 181.760876 -148.023834) (xy 181.760876 -148.88591)
			(xy 199.81672 -148.88591) (xy 199.81672 -148.02231) (xy 199.81721 -147.992342) (xy 199.825033 -147.93292)
			(xy 199.840546 -147.875027) (xy 199.863482 -147.819654) (xy 199.893449 -147.767748) (xy 199.929936 -147.720198)
			(xy 199.972316 -147.677818) (xy 200.019866 -147.641331) (xy 200.071772 -147.611364) (xy 200.127145 -147.588428)
			(xy 200.185038 -147.572915) (xy 200.24446 -147.565092) (xy 200.304396 -147.565092) (xy 200.363818 -147.572915)
			(xy 200.421711 -147.588428) (xy 200.477084 -147.611364) (xy 200.52899 -147.641331) (xy 200.57654 -147.677818)
			(xy 200.61892 -147.720198) (xy 200.655407 -147.767748) (xy 200.685374 -147.819654) (xy 200.70831 -147.875027)
			(xy 200.723823 -147.93292) (xy 200.731646 -147.992342) (xy 200.732136 -148.02231) (xy 200.732136 -148.88591)
			(xy 200.731646 -148.915878) (xy 200.723823 -148.9753) (xy 200.70831 -149.033193) (xy 200.685374 -149.088566)
			(xy 200.655407 -149.140472) (xy 200.61892 -149.188022) (xy 200.57654 -149.230402) (xy 200.52899 -149.266889)
			(xy 200.477084 -149.296856) (xy 200.421711 -149.319792) (xy 200.363818 -149.335305) (xy 200.304396 -149.343128)
			(xy 200.24446 -149.343128) (xy 200.185038 -149.335305) (xy 200.127145 -149.319792) (xy 200.071772 -149.296856)
			(xy 200.019866 -149.266889) (xy 199.972316 -149.230402) (xy 199.929936 -149.188022) (xy 199.893449 -149.140472)
			(xy 199.863482 -149.088566) (xy 199.840546 -149.033193) (xy 199.825033 -148.9753) (xy 199.81721 -148.915878)
			(xy 199.81672 -148.88591) (xy 181.760876 -148.88591) (xy 181.760876 -148.887434) (xy 181.760386 -148.917402)
			(xy 181.752563 -148.976824) (xy 181.73705 -149.034717) (xy 181.714114 -149.09009) (xy 181.684147 -149.141996)
			(xy 181.64766 -149.189546) (xy 181.60528 -149.231926) (xy 181.55773 -149.268413) (xy 181.505824 -149.29838)
			(xy 181.450451 -149.321316) (xy 181.392558 -149.336829) (xy 181.333136 -149.344652) (xy 181.2732 -149.344652)
			(xy 181.213778 -149.336829) (xy 181.155885 -149.321316) (xy 181.100512 -149.29838) (xy 181.048606 -149.268413)
			(xy 181.001056 -149.231926) (xy 180.958676 -149.189546) (xy 180.922189 -149.141996) (xy 180.892222 -149.09009)
			(xy 180.869286 -149.034717) (xy 180.853773 -148.976824) (xy 180.84595 -148.917402) (xy 180.84546 -148.887434)
			(xy 84.632267 -148.887434) (xy 84.631802 -148.915894) (xy 84.623974 -148.97535) (xy 84.608453 -149.033275)
			(xy 84.585504 -149.088679) (xy 84.55552 -149.140613) (xy 84.519014 -149.188189) (xy 84.476609 -149.230594)
			(xy 84.429033 -149.2671) (xy 84.377099 -149.297084) (xy 84.321695 -149.320033) (xy 84.26377 -149.335554)
			(xy 84.204314 -149.343382) (xy 84.144346 -149.343382) (xy 84.08489 -149.335554) (xy 84.026965 -149.320033)
			(xy 83.971561 -149.297084) (xy 83.919627 -149.2671) (xy 83.872051 -149.230594) (xy 83.829646 -149.188189)
			(xy 83.79314 -149.140613) (xy 83.763156 -149.088679) (xy 83.740207 -149.033275) (xy 83.724686 -148.97535)
			(xy 83.716858 -148.915894) (xy 83.716368 -148.88591) (xy 65.661032 -148.88591) (xy 65.661032 -148.887434)
			(xy 65.660542 -148.917418) (xy 65.652714 -148.976874) (xy 65.637193 -149.034799) (xy 65.614244 -149.090203)
			(xy 65.58426 -149.142137) (xy 65.547754 -149.189713) (xy 65.505349 -149.232118) (xy 65.457773 -149.268624)
			(xy 65.405839 -149.298608) (xy 65.350435 -149.321557) (xy 65.29251 -149.337078) (xy 65.233054 -149.344906)
			(xy 65.173086 -149.344906) (xy 65.11363 -149.337078) (xy 65.055705 -149.321557) (xy 65.000301 -149.298608)
			(xy 64.948367 -149.268624) (xy 64.900791 -149.232118) (xy 64.858386 -149.189713) (xy 64.82188 -149.142137)
			(xy 64.791896 -149.090203) (xy 64.768947 -149.034799) (xy 64.753426 -148.976874) (xy 64.745598 -148.917418)
			(xy 64.745108 -148.887434) (xy 4.30911 -148.887434) (xy 4.30911 -150.687278) (xy 66.599308 -150.687278)
			(xy 66.599308 -149.823678) (xy 66.599798 -149.793694) (xy 66.607626 -149.734238) (xy 66.623147 -149.676313)
			(xy 66.646096 -149.620909) (xy 66.67608 -149.568975) (xy 66.712586 -149.521399) (xy 66.754991 -149.478994)
			(xy 66.802567 -149.442488) (xy 66.854501 -149.412504) (xy 66.909905 -149.389555) (xy 66.96783 -149.374034)
			(xy 67.027286 -149.366206) (xy 67.087254 -149.366206) (xy 67.14671 -149.374034) (xy 67.204635 -149.389555)
			(xy 67.260039 -149.412504) (xy 67.311973 -149.442488) (xy 67.359549 -149.478994) (xy 67.401954 -149.521399)
			(xy 67.43846 -149.568975) (xy 67.468444 -149.620909) (xy 67.491393 -149.676313) (xy 67.506914 -149.734238)
			(xy 67.514742 -149.793694) (xy 67.515232 -149.823678) (xy 67.515232 -150.67915) (xy 81.07426 -150.67915)
			(xy 81.07426 -149.81555) (xy 81.07475 -149.785566) (xy 81.082578 -149.72611) (xy 81.098099 -149.668185)
			(xy 81.121048 -149.612781) (xy 81.151032 -149.560847) (xy 81.187538 -149.513271) (xy 81.229943 -149.470866)
			(xy 81.277519 -149.43436) (xy 81.329453 -149.404376) (xy 81.384857 -149.381427) (xy 81.442782 -149.365906)
			(xy 81.502238 -149.358078) (xy 81.562206 -149.358078) (xy 81.621662 -149.365906) (xy 81.679587 -149.381427)
			(xy 81.734991 -149.404376) (xy 81.786925 -149.43436) (xy 81.834501 -149.470866) (xy 81.876906 -149.513271)
			(xy 81.913412 -149.560847) (xy 81.943396 -149.612781) (xy 81.966345 -149.668185) (xy 81.981866 -149.72611)
			(xy 81.989694 -149.785566) (xy 81.990184 -149.81555) (xy 81.990184 -150.67915) (xy 81.990051 -150.687278)
			(xy 182.69966 -150.687278) (xy 182.69966 -149.823678) (xy 182.70015 -149.79371) (xy 182.707973 -149.734288)
			(xy 182.723486 -149.676395) (xy 182.746422 -149.621022) (xy 182.776389 -149.569116) (xy 182.812876 -149.521566)
			(xy 182.855256 -149.479186) (xy 182.902806 -149.442699) (xy 182.954712 -149.412732) (xy 183.010085 -149.389796)
			(xy 183.067978 -149.374283) (xy 183.1274 -149.36646) (xy 183.187336 -149.36646) (xy 183.246758 -149.374283)
			(xy 183.304651 -149.389796) (xy 183.360024 -149.412732) (xy 183.41193 -149.442699) (xy 183.45948 -149.479186)
			(xy 183.50186 -149.521566) (xy 183.538347 -149.569116) (xy 183.568314 -149.621022) (xy 183.59125 -149.676395)
			(xy 183.606763 -149.734288) (xy 183.614586 -149.79371) (xy 183.615076 -149.823678) (xy 183.615076 -150.67915)
			(xy 197.174612 -150.67915) (xy 197.174612 -149.81555) (xy 197.175102 -149.785582) (xy 197.182925 -149.72616)
			(xy 197.198438 -149.668267) (xy 197.221374 -149.612894) (xy 197.251341 -149.560988) (xy 197.287828 -149.513438)
			(xy 197.330208 -149.471058) (xy 197.377758 -149.434571) (xy 197.429664 -149.404604) (xy 197.485037 -149.381668)
			(xy 197.54293 -149.366155) (xy 197.602352 -149.358332) (xy 197.662288 -149.358332) (xy 197.72171 -149.366155)
			(xy 197.779603 -149.381668) (xy 197.834976 -149.404604) (xy 197.886882 -149.434571) (xy 197.934432 -149.471058)
			(xy 197.976812 -149.513438) (xy 198.013299 -149.560988) (xy 198.043266 -149.612894) (xy 198.066202 -149.668267)
			(xy 198.072386 -149.691344) (xy 236.708188 -149.691344) (xy 236.708188 -148.827744) (xy 236.708678 -148.79776)
			(xy 236.716506 -148.738304) (xy 236.732027 -148.680379) (xy 236.754976 -148.624975) (xy 236.78496 -148.573041)
			(xy 236.821466 -148.525465) (xy 236.863871 -148.48306) (xy 236.911447 -148.446554) (xy 236.963381 -148.41657)
			(xy 237.018785 -148.393621) (xy 237.07671 -148.3781) (xy 237.136166 -148.370272) (xy 237.196134 -148.370272)
			(xy 237.25559 -148.3781) (xy 237.313515 -148.393621) (xy 237.368919 -148.41657) (xy 237.420853 -148.446554)
			(xy 237.468429 -148.48306) (xy 237.510834 -148.525465) (xy 237.54734 -148.573041) (xy 237.577324 -148.624975)
			(xy 237.600273 -148.680379) (xy 237.615794 -148.738304) (xy 237.623622 -148.79776) (xy 237.624112 -148.827744)
			(xy 237.624112 -148.887434) (xy 296.945304 -148.887434) (xy 296.945304 -148.023834) (xy 296.945794 -147.993866)
			(xy 296.953617 -147.934444) (xy 296.96913 -147.876551) (xy 296.992066 -147.821178) (xy 297.022033 -147.769272)
			(xy 297.05852 -147.721722) (xy 297.1009 -147.679342) (xy 297.14845 -147.642855) (xy 297.200356 -147.612888)
			(xy 297.255729 -147.589952) (xy 297.313622 -147.574439) (xy 297.373044 -147.566616) (xy 297.43298 -147.566616)
			(xy 297.492402 -147.574439) (xy 297.550295 -147.589952) (xy 297.605668 -147.612888) (xy 297.657574 -147.642855)
			(xy 297.705124 -147.679342) (xy 297.747504 -147.721722) (xy 297.783991 -147.769272) (xy 297.813958 -147.821178)
			(xy 297.836894 -147.876551) (xy 297.852407 -147.934444) (xy 297.86023 -147.993866) (xy 297.86072 -148.023834)
			(xy 297.86072 -148.88591) (xy 315.916564 -148.88591) (xy 315.916564 -148.02231) (xy 315.917054 -147.992342)
			(xy 315.924877 -147.93292) (xy 315.94039 -147.875027) (xy 315.963326 -147.819654) (xy 315.993293 -147.767748)
			(xy 316.02978 -147.720198) (xy 316.07216 -147.677818) (xy 316.11971 -147.641331) (xy 316.171616 -147.611364)
			(xy 316.226989 -147.588428) (xy 316.284882 -147.572915) (xy 316.344304 -147.565092) (xy 316.40424 -147.565092)
			(xy 316.463662 -147.572915) (xy 316.521555 -147.588428) (xy 316.576928 -147.611364) (xy 316.628834 -147.641331)
			(xy 316.676384 -147.677818) (xy 316.718764 -147.720198) (xy 316.755251 -147.767748) (xy 316.785218 -147.819654)
			(xy 316.808154 -147.875027) (xy 316.823667 -147.93292) (xy 316.83149 -147.992342) (xy 316.83198 -148.02231)
			(xy 316.83198 -148.88591) (xy 316.831955 -148.887434) (xy 413.045148 -148.887434) (xy 413.045148 -148.023834)
			(xy 413.045638 -147.99385) (xy 413.053466 -147.934394) (xy 413.068987 -147.876469) (xy 413.091936 -147.821065)
			(xy 413.12192 -147.769131) (xy 413.158426 -147.721555) (xy 413.200831 -147.67915) (xy 413.248407 -147.642644)
			(xy 413.300341 -147.61266) (xy 413.355745 -147.589711) (xy 413.41367 -147.57419) (xy 413.473126 -147.566362)
			(xy 413.533094 -147.566362) (xy 413.59255 -147.57419) (xy 413.650475 -147.589711) (xy 413.705879 -147.61266)
			(xy 413.757813 -147.642644) (xy 413.805389 -147.67915) (xy 413.847794 -147.721555) (xy 413.8843 -147.769131)
			(xy 413.914284 -147.821065) (xy 413.937233 -147.876469) (xy 413.952754 -147.934394) (xy 413.960582 -147.99385)
			(xy 413.961072 -148.023834) (xy 413.961072 -148.88591) (xy 432.016408 -148.88591) (xy 432.016408 -148.02231)
			(xy 432.016898 -147.992326) (xy 432.024726 -147.93287) (xy 432.040247 -147.874945) (xy 432.063196 -147.819541)
			(xy 432.09318 -147.767607) (xy 432.129686 -147.720031) (xy 432.172091 -147.677626) (xy 432.219667 -147.64112)
			(xy 432.271601 -147.611136) (xy 432.327005 -147.588187) (xy 432.38493 -147.572666) (xy 432.444386 -147.564838)
			(xy 432.504354 -147.564838) (xy 432.56381 -147.572666) (xy 432.621735 -147.588187) (xy 432.677139 -147.611136)
			(xy 432.729073 -147.64112) (xy 432.776649 -147.677626) (xy 432.819054 -147.720031) (xy 432.85556 -147.767607)
			(xy 432.885544 -147.819541) (xy 432.908493 -147.874945) (xy 432.924014 -147.93287) (xy 432.931842 -147.992326)
			(xy 432.932332 -148.02231) (xy 432.932332 -148.88591) (xy 432.931842 -148.915894) (xy 432.924014 -148.97535)
			(xy 432.908493 -149.033275) (xy 432.885544 -149.088679) (xy 432.85556 -149.140613) (xy 432.819054 -149.188189)
			(xy 432.776649 -149.230594) (xy 432.729073 -149.2671) (xy 432.677139 -149.297084) (xy 432.621735 -149.320033)
			(xy 432.56381 -149.335554) (xy 432.504354 -149.343382) (xy 432.444386 -149.343382) (xy 432.38493 -149.335554)
			(xy 432.327005 -149.320033) (xy 432.271601 -149.297084) (xy 432.219667 -149.2671) (xy 432.172091 -149.230594)
			(xy 432.129686 -149.188189) (xy 432.09318 -149.140613) (xy 432.063196 -149.088679) (xy 432.040247 -149.033275)
			(xy 432.024726 -148.97535) (xy 432.016898 -148.915894) (xy 432.016408 -148.88591) (xy 413.961072 -148.88591)
			(xy 413.961072 -148.887434) (xy 413.960582 -148.917418) (xy 413.952754 -148.976874) (xy 413.937233 -149.034799)
			(xy 413.914284 -149.090203) (xy 413.8843 -149.142137) (xy 413.847794 -149.189713) (xy 413.805389 -149.232118)
			(xy 413.757813 -149.268624) (xy 413.705879 -149.298608) (xy 413.650475 -149.321557) (xy 413.59255 -149.337078)
			(xy 413.533094 -149.344906) (xy 413.473126 -149.344906) (xy 413.41367 -149.337078) (xy 413.355745 -149.321557)
			(xy 413.300341 -149.298608) (xy 413.248407 -149.268624) (xy 413.200831 -149.232118) (xy 413.158426 -149.189713)
			(xy 413.12192 -149.142137) (xy 413.091936 -149.090203) (xy 413.068987 -149.034799) (xy 413.053466 -148.976874)
			(xy 413.045638 -148.917418) (xy 413.045148 -148.887434) (xy 316.831955 -148.887434) (xy 316.83149 -148.915878)
			(xy 316.823667 -148.9753) (xy 316.808154 -149.033193) (xy 316.785218 -149.088566) (xy 316.755251 -149.140472)
			(xy 316.718764 -149.188022) (xy 316.676384 -149.230402) (xy 316.628834 -149.266889) (xy 316.576928 -149.296856)
			(xy 316.521555 -149.319792) (xy 316.463662 -149.335305) (xy 316.40424 -149.343128) (xy 316.344304 -149.343128)
			(xy 316.284882 -149.335305) (xy 316.226989 -149.319792) (xy 316.171616 -149.296856) (xy 316.11971 -149.266889)
			(xy 316.07216 -149.230402) (xy 316.02978 -149.188022) (xy 315.993293 -149.140472) (xy 315.963326 -149.088566)
			(xy 315.94039 -149.033193) (xy 315.924877 -148.9753) (xy 315.917054 -148.915878) (xy 315.916564 -148.88591)
			(xy 297.86072 -148.88591) (xy 297.86072 -148.887434) (xy 297.86023 -148.917402) (xy 297.852407 -148.976824)
			(xy 297.836894 -149.034717) (xy 297.813958 -149.09009) (xy 297.783991 -149.141996) (xy 297.747504 -149.189546)
			(xy 297.705124 -149.231926) (xy 297.657574 -149.268413) (xy 297.605668 -149.29838) (xy 297.550295 -149.321316)
			(xy 297.492402 -149.336829) (xy 297.43298 -149.344652) (xy 297.373044 -149.344652) (xy 297.313622 -149.336829)
			(xy 297.255729 -149.321316) (xy 297.200356 -149.29838) (xy 297.14845 -149.268413) (xy 297.1009 -149.231926)
			(xy 297.05852 -149.189546) (xy 297.022033 -149.141996) (xy 296.992066 -149.09009) (xy 296.96913 -149.034717)
			(xy 296.953617 -148.976824) (xy 296.945794 -148.917402) (xy 296.945304 -148.887434) (xy 237.624112 -148.887434)
			(xy 237.624112 -149.691344) (xy 237.623622 -149.721328) (xy 237.615794 -149.780784) (xy 237.600273 -149.838709)
			(xy 237.577324 -149.894113) (xy 237.54734 -149.946047) (xy 237.510834 -149.993623) (xy 237.468429 -150.036028)
			(xy 237.420853 -150.072534) (xy 237.368919 -150.102518) (xy 237.313515 -150.125467) (xy 237.25559 -150.140988)
			(xy 237.196134 -150.148816) (xy 237.136166 -150.148816) (xy 237.07671 -150.140988) (xy 237.018785 -150.125467)
			(xy 236.963381 -150.102518) (xy 236.911447 -150.072534) (xy 236.863871 -150.036028) (xy 236.821466 -149.993623)
			(xy 236.78496 -149.946047) (xy 236.754976 -149.894113) (xy 236.732027 -149.838709) (xy 236.716506 -149.780784)
			(xy 236.708678 -149.721328) (xy 236.708188 -149.691344) (xy 198.072386 -149.691344) (xy 198.081715 -149.72616)
			(xy 198.089538 -149.785582) (xy 198.090028 -149.81555) (xy 198.090028 -150.67915) (xy 198.089538 -150.709118)
			(xy 198.081715 -150.76854) (xy 198.066202 -150.826433) (xy 198.043266 -150.881806) (xy 198.013299 -150.933712)
			(xy 197.976812 -150.981262) (xy 197.934432 -151.023642) (xy 197.886882 -151.060129) (xy 197.834976 -151.090096)
			(xy 197.779603 -151.113032) (xy 197.72171 -151.128545) (xy 197.662288 -151.136368) (xy 197.602352 -151.136368)
			(xy 197.54293 -151.128545) (xy 197.485037 -151.113032) (xy 197.429664 -151.090096) (xy 197.377758 -151.060129)
			(xy 197.330208 -151.023642) (xy 197.287828 -150.981262) (xy 197.251341 -150.933712) (xy 197.221374 -150.881806)
			(xy 197.198438 -150.826433) (xy 197.182925 -150.76854) (xy 197.175102 -150.709118) (xy 197.174612 -150.67915)
			(xy 183.615076 -150.67915) (xy 183.615076 -150.687278) (xy 183.614586 -150.717246) (xy 183.606763 -150.776668)
			(xy 183.59125 -150.834561) (xy 183.568314 -150.889934) (xy 183.538347 -150.94184) (xy 183.50186 -150.98939)
			(xy 183.45948 -151.03177) (xy 183.41193 -151.068257) (xy 183.360024 -151.098224) (xy 183.304651 -151.12116)
			(xy 183.246758 -151.136673) (xy 183.187336 -151.144496) (xy 183.1274 -151.144496) (xy 183.067978 -151.136673)
			(xy 183.010085 -151.12116) (xy 182.954712 -151.098224) (xy 182.902806 -151.068257) (xy 182.855256 -151.03177)
			(xy 182.812876 -150.98939) (xy 182.776389 -150.94184) (xy 182.746422 -150.889934) (xy 182.723486 -150.834561)
			(xy 182.707973 -150.776668) (xy 182.70015 -150.717246) (xy 182.69966 -150.687278) (xy 81.990051 -150.687278)
			(xy 81.989694 -150.709134) (xy 81.981866 -150.76859) (xy 81.966345 -150.826515) (xy 81.943396 -150.881919)
			(xy 81.913412 -150.933853) (xy 81.876906 -150.981429) (xy 81.834501 -151.023834) (xy 81.786925 -151.06034)
			(xy 81.734991 -151.090324) (xy 81.679587 -151.113273) (xy 81.621662 -151.128794) (xy 81.562206 -151.136622)
			(xy 81.502238 -151.136622) (xy 81.442782 -151.128794) (xy 81.384857 -151.113273) (xy 81.329453 -151.090324)
			(xy 81.277519 -151.06034) (xy 81.229943 -151.023834) (xy 81.187538 -150.981429) (xy 81.151032 -150.933853)
			(xy 81.121048 -150.881919) (xy 81.098099 -150.826515) (xy 81.082578 -150.76859) (xy 81.07475 -150.709134)
			(xy 81.07426 -150.67915) (xy 67.515232 -150.67915) (xy 67.515232 -150.687278) (xy 67.514742 -150.717262)
			(xy 67.506914 -150.776718) (xy 67.491393 -150.834643) (xy 67.468444 -150.890047) (xy 67.43846 -150.941981)
			(xy 67.401954 -150.989557) (xy 67.359549 -151.031962) (xy 67.311973 -151.068468) (xy 67.260039 -151.098452)
			(xy 67.204635 -151.121401) (xy 67.14671 -151.136922) (xy 67.087254 -151.14475) (xy 67.027286 -151.14475)
			(xy 66.96783 -151.136922) (xy 66.909905 -151.121401) (xy 66.854501 -151.098452) (xy 66.802567 -151.068468)
			(xy 66.754991 -151.031962) (xy 66.712586 -150.989557) (xy 66.67608 -150.941981) (xy 66.646096 -150.890047)
			(xy 66.623147 -150.834643) (xy 66.607626 -150.776718) (xy 66.599798 -150.717262) (xy 66.599308 -150.687278)
			(xy 4.30911 -150.687278) (xy 4.30911 -152.487376) (xy 64.745108 -152.487376) (xy 64.745108 -151.623776)
			(xy 64.745598 -151.593792) (xy 64.753426 -151.534336) (xy 64.768947 -151.476411) (xy 64.791896 -151.421007)
			(xy 64.82188 -151.369073) (xy 64.858386 -151.321497) (xy 64.900791 -151.279092) (xy 64.948367 -151.242586)
			(xy 65.000301 -151.212602) (xy 65.055705 -151.189653) (xy 65.11363 -151.174132) (xy 65.173086 -151.166304)
			(xy 65.233054 -151.166304) (xy 65.29251 -151.174132) (xy 65.350435 -151.189653) (xy 65.405839 -151.212602)
			(xy 65.457773 -151.242586) (xy 65.505349 -151.279092) (xy 65.547754 -151.321497) (xy 65.58426 -151.369073)
			(xy 65.614244 -151.421007) (xy 65.637193 -151.476411) (xy 65.652714 -151.534336) (xy 65.660542 -151.593792)
			(xy 65.661032 -151.623776) (xy 65.661032 -152.485852) (xy 83.716368 -152.485852) (xy 83.716368 -151.622252)
			(xy 83.716858 -151.592268) (xy 83.724686 -151.532812) (xy 83.740207 -151.474887) (xy 83.763156 -151.419483)
			(xy 83.79314 -151.367549) (xy 83.829646 -151.319973) (xy 83.872051 -151.277568) (xy 83.919627 -151.241062)
			(xy 83.971561 -151.211078) (xy 84.026965 -151.188129) (xy 84.08489 -151.172608) (xy 84.144346 -151.16478)
			(xy 84.204314 -151.16478) (xy 84.26377 -151.172608) (xy 84.321695 -151.188129) (xy 84.377099 -151.211078)
			(xy 84.429033 -151.241062) (xy 84.476609 -151.277568) (xy 84.519014 -151.319973) (xy 84.55552 -151.367549)
			(xy 84.585504 -151.419483) (xy 84.608453 -151.474887) (xy 84.623974 -151.532812) (xy 84.631802 -151.592268)
			(xy 84.632292 -151.622252) (xy 84.632292 -152.485852) (xy 84.632267 -152.487376) (xy 180.84546 -152.487376)
			(xy 180.84546 -151.623776) (xy 180.84595 -151.593808) (xy 180.853773 -151.534386) (xy 180.869286 -151.476493)
			(xy 180.892222 -151.42112) (xy 180.922189 -151.369214) (xy 180.958676 -151.321664) (xy 181.001056 -151.279284)
			(xy 181.048606 -151.242797) (xy 181.100512 -151.21283) (xy 181.155885 -151.189894) (xy 181.213778 -151.174381)
			(xy 181.2732 -151.166558) (xy 181.333136 -151.166558) (xy 181.392558 -151.174381) (xy 181.450451 -151.189894)
			(xy 181.505824 -151.21283) (xy 181.55773 -151.242797) (xy 181.60528 -151.279284) (xy 181.64766 -151.321664)
			(xy 181.684147 -151.369214) (xy 181.714114 -151.42112) (xy 181.73705 -151.476493) (xy 181.752563 -151.534386)
			(xy 181.760386 -151.593808) (xy 181.760876 -151.623776) (xy 181.760876 -152.485852) (xy 199.81672 -152.485852)
			(xy 199.81672 -151.622252) (xy 199.81721 -151.592284) (xy 199.825033 -151.532862) (xy 199.840546 -151.474969)
			(xy 199.863482 -151.419596) (xy 199.893449 -151.36769) (xy 199.929936 -151.32014) (xy 199.972316 -151.27776)
			(xy 200.019866 -151.241273) (xy 200.071772 -151.211306) (xy 200.127145 -151.18837) (xy 200.185038 -151.172857)
			(xy 200.24446 -151.165034) (xy 200.304396 -151.165034) (xy 200.363818 -151.172857) (xy 200.421711 -151.18837)
			(xy 200.477084 -151.211306) (xy 200.52899 -151.241273) (xy 200.57654 -151.27776) (xy 200.61892 -151.32014)
			(xy 200.655407 -151.36769) (xy 200.685374 -151.419596) (xy 200.70831 -151.474969) (xy 200.723823 -151.532862)
			(xy 200.731646 -151.592284) (xy 200.732136 -151.622252) (xy 200.732136 -151.914098) (xy 236.712252 -151.914098)
			(xy 236.712252 -151.050498) (xy 236.712742 -151.020514) (xy 236.72057 -150.961058) (xy 236.736091 -150.903133)
			(xy 236.75904 -150.847729) (xy 236.789024 -150.795795) (xy 236.82553 -150.748219) (xy 236.867935 -150.705814)
			(xy 236.915511 -150.669308) (xy 236.967445 -150.639324) (xy 237.022849 -150.616375) (xy 237.080774 -150.600854)
			(xy 237.14023 -150.593026) (xy 237.200198 -150.593026) (xy 237.259654 -150.600854) (xy 237.317579 -150.616375)
			(xy 237.372983 -150.639324) (xy 237.424917 -150.669308) (xy 237.448336 -150.687278) (xy 298.799504 -150.687278)
			(xy 298.799504 -149.823678) (xy 298.799994 -149.79371) (xy 298.807817 -149.734288) (xy 298.82333 -149.676395)
			(xy 298.846266 -149.621022) (xy 298.876233 -149.569116) (xy 298.91272 -149.521566) (xy 298.9551 -149.479186)
			(xy 299.00265 -149.442699) (xy 299.054556 -149.412732) (xy 299.109929 -149.389796) (xy 299.167822 -149.374283)
			(xy 299.227244 -149.36646) (xy 299.28718 -149.36646) (xy 299.346602 -149.374283) (xy 299.404495 -149.389796)
			(xy 299.459868 -149.412732) (xy 299.511774 -149.442699) (xy 299.559324 -149.479186) (xy 299.601704 -149.521566)
			(xy 299.638191 -149.569116) (xy 299.668158 -149.621022) (xy 299.691094 -149.676395) (xy 299.706607 -149.734288)
			(xy 299.71443 -149.79371) (xy 299.71492 -149.823678) (xy 299.71492 -150.67915) (xy 313.274456 -150.67915)
			(xy 313.274456 -149.81555) (xy 313.274946 -149.785582) (xy 313.282769 -149.72616) (xy 313.298282 -149.668267)
			(xy 313.321218 -149.612894) (xy 313.351185 -149.560988) (xy 313.387672 -149.513438) (xy 313.430052 -149.471058)
			(xy 313.477602 -149.434571) (xy 313.529508 -149.404604) (xy 313.584881 -149.381668) (xy 313.642774 -149.366155)
			(xy 313.702196 -149.358332) (xy 313.762132 -149.358332) (xy 313.821554 -149.366155) (xy 313.879447 -149.381668)
			(xy 313.93482 -149.404604) (xy 313.986726 -149.434571) (xy 314.034276 -149.471058) (xy 314.076656 -149.513438)
			(xy 314.113143 -149.560988) (xy 314.14311 -149.612894) (xy 314.166046 -149.668267) (xy 314.181559 -149.72616)
			(xy 314.189382 -149.785582) (xy 314.189872 -149.81555) (xy 314.189872 -150.67915) (xy 314.189739 -150.687278)
			(xy 414.899348 -150.687278) (xy 414.899348 -149.823678) (xy 414.899838 -149.793694) (xy 414.907666 -149.734238)
			(xy 414.923187 -149.676313) (xy 414.946136 -149.620909) (xy 414.97612 -149.568975) (xy 415.012626 -149.521399)
			(xy 415.055031 -149.478994) (xy 415.102607 -149.442488) (xy 415.154541 -149.412504) (xy 415.209945 -149.389555)
			(xy 415.26787 -149.374034) (xy 415.327326 -149.366206) (xy 415.387294 -149.366206) (xy 415.44675 -149.374034)
			(xy 415.504675 -149.389555) (xy 415.560079 -149.412504) (xy 415.612013 -149.442488) (xy 415.659589 -149.478994)
			(xy 415.701994 -149.521399) (xy 415.7385 -149.568975) (xy 415.768484 -149.620909) (xy 415.791433 -149.676313)
			(xy 415.806954 -149.734238) (xy 415.814782 -149.793694) (xy 415.815272 -149.823678) (xy 415.815272 -150.67915)
			(xy 429.3743 -150.67915) (xy 429.3743 -149.81555) (xy 429.37479 -149.785566) (xy 429.382618 -149.72611)
			(xy 429.398139 -149.668185) (xy 429.421088 -149.612781) (xy 429.451072 -149.560847) (xy 429.487578 -149.513271)
			(xy 429.529983 -149.470866) (xy 429.577559 -149.43436) (xy 429.629493 -149.404376) (xy 429.684897 -149.381427)
			(xy 429.742822 -149.365906) (xy 429.802278 -149.358078) (xy 429.862246 -149.358078) (xy 429.921702 -149.365906)
			(xy 429.979627 -149.381427) (xy 430.035031 -149.404376) (xy 430.086965 -149.43436) (xy 430.134541 -149.470866)
			(xy 430.176946 -149.513271) (xy 430.213452 -149.560847) (xy 430.243436 -149.612781) (xy 430.266385 -149.668185)
			(xy 430.281906 -149.72611) (xy 430.289734 -149.785566) (xy 430.290224 -149.81555) (xy 430.290224 -150.67915)
			(xy 430.289734 -150.709134) (xy 430.281906 -150.76859) (xy 430.266385 -150.826515) (xy 430.243436 -150.881919)
			(xy 430.213452 -150.933853) (xy 430.176946 -150.981429) (xy 430.134541 -151.023834) (xy 430.086965 -151.06034)
			(xy 430.035031 -151.090324) (xy 429.979627 -151.113273) (xy 429.921702 -151.128794) (xy 429.862246 -151.136622)
			(xy 429.802278 -151.136622) (xy 429.742822 -151.128794) (xy 429.684897 -151.113273) (xy 429.629493 -151.090324)
			(xy 429.577559 -151.06034) (xy 429.529983 -151.023834) (xy 429.487578 -150.981429) (xy 429.451072 -150.933853)
			(xy 429.421088 -150.881919) (xy 429.398139 -150.826515) (xy 429.382618 -150.76859) (xy 429.37479 -150.709134)
			(xy 429.3743 -150.67915) (xy 415.815272 -150.67915) (xy 415.815272 -150.687278) (xy 415.814782 -150.717262)
			(xy 415.806954 -150.776718) (xy 415.791433 -150.834643) (xy 415.768484 -150.890047) (xy 415.7385 -150.941981)
			(xy 415.701994 -150.989557) (xy 415.659589 -151.031962) (xy 415.612013 -151.068468) (xy 415.560079 -151.098452)
			(xy 415.504675 -151.121401) (xy 415.44675 -151.136922) (xy 415.387294 -151.14475) (xy 415.327326 -151.14475)
			(xy 415.26787 -151.136922) (xy 415.209945 -151.121401) (xy 415.154541 -151.098452) (xy 415.102607 -151.068468)
			(xy 415.055031 -151.031962) (xy 415.012626 -150.989557) (xy 414.97612 -150.941981) (xy 414.946136 -150.890047)
			(xy 414.923187 -150.834643) (xy 414.907666 -150.776718) (xy 414.899838 -150.717262) (xy 414.899348 -150.687278)
			(xy 314.189739 -150.687278) (xy 314.189382 -150.709118) (xy 314.181559 -150.76854) (xy 314.166046 -150.826433)
			(xy 314.14311 -150.881806) (xy 314.113143 -150.933712) (xy 314.076656 -150.981262) (xy 314.034276 -151.023642)
			(xy 313.986726 -151.060129) (xy 313.93482 -151.090096) (xy 313.879447 -151.113032) (xy 313.821554 -151.128545)
			(xy 313.762132 -151.136368) (xy 313.702196 -151.136368) (xy 313.642774 -151.128545) (xy 313.584881 -151.113032)
			(xy 313.529508 -151.090096) (xy 313.477602 -151.060129) (xy 313.430052 -151.023642) (xy 313.387672 -150.981262)
			(xy 313.351185 -150.933712) (xy 313.321218 -150.881806) (xy 313.298282 -150.826433) (xy 313.282769 -150.76854)
			(xy 313.274946 -150.709118) (xy 313.274456 -150.67915) (xy 299.71492 -150.67915) (xy 299.71492 -150.687278)
			(xy 299.71443 -150.717246) (xy 299.706607 -150.776668) (xy 299.691094 -150.834561) (xy 299.668158 -150.889934)
			(xy 299.638191 -150.94184) (xy 299.601704 -150.98939) (xy 299.559324 -151.03177) (xy 299.511774 -151.068257)
			(xy 299.459868 -151.098224) (xy 299.404495 -151.12116) (xy 299.346602 -151.136673) (xy 299.28718 -151.144496)
			(xy 299.227244 -151.144496) (xy 299.167822 -151.136673) (xy 299.109929 -151.12116) (xy 299.054556 -151.098224)
			(xy 299.00265 -151.068257) (xy 298.9551 -151.03177) (xy 298.91272 -150.98939) (xy 298.876233 -150.94184)
			(xy 298.846266 -150.889934) (xy 298.82333 -150.834561) (xy 298.807817 -150.776668) (xy 298.799994 -150.717246)
			(xy 298.799504 -150.687278) (xy 237.448336 -150.687278) (xy 237.472493 -150.705814) (xy 237.514898 -150.748219)
			(xy 237.551404 -150.795795) (xy 237.581388 -150.847729) (xy 237.604337 -150.903133) (xy 237.619858 -150.961058)
			(xy 237.627686 -151.020514) (xy 237.628176 -151.050498) (xy 237.628176 -151.914098) (xy 237.627686 -151.944082)
			(xy 237.619858 -152.003538) (xy 237.604337 -152.061463) (xy 237.581388 -152.116867) (xy 237.551404 -152.168801)
			(xy 237.514898 -152.216377) (xy 237.472493 -152.258782) (xy 237.424917 -152.295288) (xy 237.372983 -152.325272)
			(xy 237.317579 -152.348221) (xy 237.259654 -152.363742) (xy 237.200198 -152.37157) (xy 237.14023 -152.37157)
			(xy 237.080774 -152.363742) (xy 237.022849 -152.348221) (xy 236.967445 -152.325272) (xy 236.915511 -152.295288)
			(xy 236.867935 -152.258782) (xy 236.82553 -152.216377) (xy 236.789024 -152.168801) (xy 236.75904 -152.116867)
			(xy 236.736091 -152.061463) (xy 236.72057 -152.003538) (xy 236.712742 -151.944082) (xy 236.712252 -151.914098)
			(xy 200.732136 -151.914098) (xy 200.732136 -152.485852) (xy 200.732111 -152.487376) (xy 296.945304 -152.487376)
			(xy 296.945304 -151.623776) (xy 296.945794 -151.593808) (xy 296.953617 -151.534386) (xy 296.96913 -151.476493)
			(xy 296.992066 -151.42112) (xy 297.022033 -151.369214) (xy 297.05852 -151.321664) (xy 297.1009 -151.279284)
			(xy 297.14845 -151.242797) (xy 297.200356 -151.21283) (xy 297.255729 -151.189894) (xy 297.313622 -151.174381)
			(xy 297.373044 -151.166558) (xy 297.43298 -151.166558) (xy 297.492402 -151.174381) (xy 297.550295 -151.189894)
			(xy 297.605668 -151.21283) (xy 297.657574 -151.242797) (xy 297.705124 -151.279284) (xy 297.747504 -151.321664)
			(xy 297.783991 -151.369214) (xy 297.813958 -151.42112) (xy 297.836894 -151.476493) (xy 297.852407 -151.534386)
			(xy 297.86023 -151.593808) (xy 297.86072 -151.623776) (xy 297.86072 -152.485852) (xy 315.916564 -152.485852)
			(xy 315.916564 -151.622252) (xy 315.917054 -151.592284) (xy 315.924877 -151.532862) (xy 315.94039 -151.474969)
			(xy 315.963326 -151.419596) (xy 315.993293 -151.36769) (xy 316.02978 -151.32014) (xy 316.07216 -151.27776)
			(xy 316.11971 -151.241273) (xy 316.171616 -151.211306) (xy 316.226989 -151.18837) (xy 316.284882 -151.172857)
			(xy 316.344304 -151.165034) (xy 316.40424 -151.165034) (xy 316.463662 -151.172857) (xy 316.521555 -151.18837)
			(xy 316.576928 -151.211306) (xy 316.628834 -151.241273) (xy 316.676384 -151.27776) (xy 316.718764 -151.32014)
			(xy 316.755251 -151.36769) (xy 316.785218 -151.419596) (xy 316.808154 -151.474969) (xy 316.823667 -151.532862)
			(xy 316.83149 -151.592284) (xy 316.83198 -151.622252) (xy 316.83198 -152.485852) (xy 316.831955 -152.487376)
			(xy 413.045148 -152.487376) (xy 413.045148 -151.623776) (xy 413.045638 -151.593792) (xy 413.053466 -151.534336)
			(xy 413.068987 -151.476411) (xy 413.091936 -151.421007) (xy 413.12192 -151.369073) (xy 413.158426 -151.321497)
			(xy 413.200831 -151.279092) (xy 413.248407 -151.242586) (xy 413.300341 -151.212602) (xy 413.355745 -151.189653)
			(xy 413.41367 -151.174132) (xy 413.473126 -151.166304) (xy 413.533094 -151.166304) (xy 413.59255 -151.174132)
			(xy 413.650475 -151.189653) (xy 413.705879 -151.212602) (xy 413.757813 -151.242586) (xy 413.805389 -151.279092)
			(xy 413.847794 -151.321497) (xy 413.8843 -151.369073) (xy 413.914284 -151.421007) (xy 413.937233 -151.476411)
			(xy 413.952754 -151.534336) (xy 413.960582 -151.593792) (xy 413.961072 -151.623776) (xy 413.961072 -152.485852)
			(xy 432.016408 -152.485852) (xy 432.016408 -151.622252) (xy 432.016898 -151.592268) (xy 432.024726 -151.532812)
			(xy 432.040247 -151.474887) (xy 432.063196 -151.419483) (xy 432.09318 -151.367549) (xy 432.129686 -151.319973)
			(xy 432.172091 -151.277568) (xy 432.219667 -151.241062) (xy 432.271601 -151.211078) (xy 432.327005 -151.188129)
			(xy 432.38493 -151.172608) (xy 432.444386 -151.16478) (xy 432.504354 -151.16478) (xy 432.56381 -151.172608)
			(xy 432.621735 -151.188129) (xy 432.677139 -151.211078) (xy 432.729073 -151.241062) (xy 432.776649 -151.277568)
			(xy 432.819054 -151.319973) (xy 432.85556 -151.367549) (xy 432.885544 -151.419483) (xy 432.908493 -151.474887)
			(xy 432.924014 -151.532812) (xy 432.931842 -151.592268) (xy 432.932332 -151.622252) (xy 432.932332 -152.485852)
			(xy 432.931842 -152.515836) (xy 432.924014 -152.575292) (xy 432.908493 -152.633217) (xy 432.885544 -152.688621)
			(xy 432.85556 -152.740555) (xy 432.819054 -152.788131) (xy 432.776649 -152.830536) (xy 432.729073 -152.867042)
			(xy 432.677139 -152.897026) (xy 432.621735 -152.919975) (xy 432.56381 -152.935496) (xy 432.504354 -152.943324)
			(xy 432.444386 -152.943324) (xy 432.38493 -152.935496) (xy 432.327005 -152.919975) (xy 432.271601 -152.897026)
			(xy 432.219667 -152.867042) (xy 432.172091 -152.830536) (xy 432.129686 -152.788131) (xy 432.09318 -152.740555)
			(xy 432.063196 -152.688621) (xy 432.040247 -152.633217) (xy 432.024726 -152.575292) (xy 432.016898 -152.515836)
			(xy 432.016408 -152.485852) (xy 413.961072 -152.485852) (xy 413.961072 -152.487376) (xy 413.960582 -152.51736)
			(xy 413.952754 -152.576816) (xy 413.937233 -152.634741) (xy 413.914284 -152.690145) (xy 413.8843 -152.742079)
			(xy 413.847794 -152.789655) (xy 413.805389 -152.83206) (xy 413.757813 -152.868566) (xy 413.705879 -152.89855)
			(xy 413.650475 -152.921499) (xy 413.59255 -152.93702) (xy 413.533094 -152.944848) (xy 413.473126 -152.944848)
			(xy 413.41367 -152.93702) (xy 413.355745 -152.921499) (xy 413.300341 -152.89855) (xy 413.248407 -152.868566)
			(xy 413.200831 -152.83206) (xy 413.158426 -152.789655) (xy 413.12192 -152.742079) (xy 413.091936 -152.690145)
			(xy 413.068987 -152.634741) (xy 413.053466 -152.576816) (xy 413.045638 -152.51736) (xy 413.045148 -152.487376)
			(xy 316.831955 -152.487376) (xy 316.83149 -152.51582) (xy 316.823667 -152.575242) (xy 316.808154 -152.633135)
			(xy 316.785218 -152.688508) (xy 316.755251 -152.740414) (xy 316.718764 -152.787964) (xy 316.676384 -152.830344)
			(xy 316.628834 -152.866831) (xy 316.576928 -152.896798) (xy 316.521555 -152.919734) (xy 316.463662 -152.935247)
			(xy 316.40424 -152.94307) (xy 316.344304 -152.94307) (xy 316.284882 -152.935247) (xy 316.226989 -152.919734)
			(xy 316.171616 -152.896798) (xy 316.11971 -152.866831) (xy 316.07216 -152.830344) (xy 316.02978 -152.787964)
			(xy 315.993293 -152.740414) (xy 315.963326 -152.688508) (xy 315.94039 -152.633135) (xy 315.924877 -152.575242)
			(xy 315.917054 -152.51582) (xy 315.916564 -152.485852) (xy 297.86072 -152.485852) (xy 297.86072 -152.487376)
			(xy 297.86023 -152.517344) (xy 297.852407 -152.576766) (xy 297.836894 -152.634659) (xy 297.813958 -152.690032)
			(xy 297.783991 -152.741938) (xy 297.747504 -152.789488) (xy 297.705124 -152.831868) (xy 297.657574 -152.868355)
			(xy 297.605668 -152.898322) (xy 297.550295 -152.921258) (xy 297.492402 -152.936771) (xy 297.43298 -152.944594)
			(xy 297.373044 -152.944594) (xy 297.313622 -152.936771) (xy 297.255729 -152.921258) (xy 297.200356 -152.898322)
			(xy 297.14845 -152.868355) (xy 297.1009 -152.831868) (xy 297.05852 -152.789488) (xy 297.022033 -152.741938)
			(xy 296.992066 -152.690032) (xy 296.96913 -152.634659) (xy 296.953617 -152.576766) (xy 296.945794 -152.517344)
			(xy 296.945304 -152.487376) (xy 200.732111 -152.487376) (xy 200.731646 -152.51582) (xy 200.723823 -152.575242)
			(xy 200.70831 -152.633135) (xy 200.685374 -152.688508) (xy 200.655407 -152.740414) (xy 200.61892 -152.787964)
			(xy 200.57654 -152.830344) (xy 200.52899 -152.866831) (xy 200.477084 -152.896798) (xy 200.421711 -152.919734)
			(xy 200.363818 -152.935247) (xy 200.304396 -152.94307) (xy 200.24446 -152.94307) (xy 200.185038 -152.935247)
			(xy 200.127145 -152.919734) (xy 200.071772 -152.896798) (xy 200.019866 -152.866831) (xy 199.972316 -152.830344)
			(xy 199.929936 -152.787964) (xy 199.893449 -152.740414) (xy 199.863482 -152.688508) (xy 199.840546 -152.633135)
			(xy 199.825033 -152.575242) (xy 199.81721 -152.51582) (xy 199.81672 -152.485852) (xy 181.760876 -152.485852)
			(xy 181.760876 -152.487376) (xy 181.760386 -152.517344) (xy 181.752563 -152.576766) (xy 181.73705 -152.634659)
			(xy 181.714114 -152.690032) (xy 181.684147 -152.741938) (xy 181.64766 -152.789488) (xy 181.60528 -152.831868)
			(xy 181.55773 -152.868355) (xy 181.505824 -152.898322) (xy 181.450451 -152.921258) (xy 181.392558 -152.936771)
			(xy 181.333136 -152.944594) (xy 181.2732 -152.944594) (xy 181.213778 -152.936771) (xy 181.155885 -152.921258)
			(xy 181.100512 -152.898322) (xy 181.048606 -152.868355) (xy 181.001056 -152.831868) (xy 180.958676 -152.789488)
			(xy 180.922189 -152.741938) (xy 180.892222 -152.690032) (xy 180.869286 -152.634659) (xy 180.853773 -152.576766)
			(xy 180.84595 -152.517344) (xy 180.84546 -152.487376) (xy 84.632267 -152.487376) (xy 84.631802 -152.515836)
			(xy 84.623974 -152.575292) (xy 84.608453 -152.633217) (xy 84.585504 -152.688621) (xy 84.55552 -152.740555)
			(xy 84.519014 -152.788131) (xy 84.476609 -152.830536) (xy 84.429033 -152.867042) (xy 84.377099 -152.897026)
			(xy 84.321695 -152.919975) (xy 84.26377 -152.935496) (xy 84.204314 -152.943324) (xy 84.144346 -152.943324)
			(xy 84.08489 -152.935496) (xy 84.026965 -152.919975) (xy 83.971561 -152.897026) (xy 83.919627 -152.867042)
			(xy 83.872051 -152.830536) (xy 83.829646 -152.788131) (xy 83.79314 -152.740555) (xy 83.763156 -152.688621)
			(xy 83.740207 -152.633217) (xy 83.724686 -152.575292) (xy 83.716858 -152.515836) (xy 83.716368 -152.485852)
			(xy 65.661032 -152.485852) (xy 65.661032 -152.487376) (xy 65.660542 -152.51736) (xy 65.652714 -152.576816)
			(xy 65.637193 -152.634741) (xy 65.614244 -152.690145) (xy 65.58426 -152.742079) (xy 65.547754 -152.789655)
			(xy 65.505349 -152.83206) (xy 65.457773 -152.868566) (xy 65.405839 -152.89855) (xy 65.350435 -152.921499)
			(xy 65.29251 -152.93702) (xy 65.233054 -152.944848) (xy 65.173086 -152.944848) (xy 65.11363 -152.93702)
			(xy 65.055705 -152.921499) (xy 65.000301 -152.89855) (xy 64.948367 -152.868566) (xy 64.900791 -152.83206)
			(xy 64.858386 -152.789655) (xy 64.82188 -152.742079) (xy 64.791896 -152.690145) (xy 64.768947 -152.634741)
			(xy 64.753426 -152.576816) (xy 64.745598 -152.51736) (xy 64.745108 -152.487376) (xy 4.30911 -152.487376)
			(xy 4.30911 -154.28722) (xy 66.599308 -154.28722) (xy 66.599308 -153.42362) (xy 66.599798 -153.393636)
			(xy 66.607626 -153.33418) (xy 66.623147 -153.276255) (xy 66.646096 -153.220851) (xy 66.67608 -153.168917)
			(xy 66.712586 -153.121341) (xy 66.754991 -153.078936) (xy 66.802567 -153.04243) (xy 66.854501 -153.012446)
			(xy 66.909905 -152.989497) (xy 66.96783 -152.973976) (xy 67.027286 -152.966148) (xy 67.087254 -152.966148)
			(xy 67.14671 -152.973976) (xy 67.204635 -152.989497) (xy 67.260039 -153.012446) (xy 67.311973 -153.04243)
			(xy 67.359549 -153.078936) (xy 67.401954 -153.121341) (xy 67.43846 -153.168917) (xy 67.468444 -153.220851)
			(xy 67.491393 -153.276255) (xy 67.506914 -153.33418) (xy 67.514742 -153.393636) (xy 67.515232 -153.42362)
			(xy 67.515232 -154.279346) (xy 81.07426 -154.279346) (xy 81.07426 -153.415746) (xy 81.07475 -153.385762)
			(xy 81.082578 -153.326306) (xy 81.098099 -153.268381) (xy 81.121048 -153.212977) (xy 81.151032 -153.161043)
			(xy 81.187538 -153.113467) (xy 81.229943 -153.071062) (xy 81.277519 -153.034556) (xy 81.329453 -153.004572)
			(xy 81.384857 -152.981623) (xy 81.442782 -152.966102) (xy 81.502238 -152.958274) (xy 81.562206 -152.958274)
			(xy 81.621662 -152.966102) (xy 81.679587 -152.981623) (xy 81.734991 -153.004572) (xy 81.786925 -153.034556)
			(xy 81.834501 -153.071062) (xy 81.876906 -153.113467) (xy 81.913412 -153.161043) (xy 81.943396 -153.212977)
			(xy 81.966345 -153.268381) (xy 81.981866 -153.326306) (xy 81.989694 -153.385762) (xy 81.990184 -153.415746)
			(xy 81.990184 -154.279346) (xy 81.990055 -154.28722) (xy 182.69966 -154.28722) (xy 182.69966 -153.42362)
			(xy 182.70015 -153.393652) (xy 182.707973 -153.33423) (xy 182.723486 -153.276337) (xy 182.746422 -153.220964)
			(xy 182.776389 -153.169058) (xy 182.812876 -153.121508) (xy 182.855256 -153.079128) (xy 182.902806 -153.042641)
			(xy 182.954712 -153.012674) (xy 183.010085 -152.989738) (xy 183.067978 -152.974225) (xy 183.1274 -152.966402)
			(xy 183.187336 -152.966402) (xy 183.246758 -152.974225) (xy 183.304651 -152.989738) (xy 183.360024 -153.012674)
			(xy 183.41193 -153.042641) (xy 183.45948 -153.079128) (xy 183.50186 -153.121508) (xy 183.538347 -153.169058)
			(xy 183.568314 -153.220964) (xy 183.59125 -153.276337) (xy 183.606763 -153.33423) (xy 183.614586 -153.393652)
			(xy 183.615076 -153.42362) (xy 183.615076 -154.279346) (xy 197.174612 -154.279346) (xy 197.174612 -153.415746)
			(xy 197.175102 -153.385778) (xy 197.182925 -153.326356) (xy 197.198438 -153.268463) (xy 197.221374 -153.21309)
			(xy 197.251341 -153.161184) (xy 197.287828 -153.113634) (xy 197.330208 -153.071254) (xy 197.377758 -153.034767)
			(xy 197.429664 -153.0048) (xy 197.485037 -152.981864) (xy 197.54293 -152.966351) (xy 197.602352 -152.958528)
			(xy 197.662288 -152.958528) (xy 197.72171 -152.966351) (xy 197.779603 -152.981864) (xy 197.834976 -153.0048)
			(xy 197.886882 -153.034767) (xy 197.934432 -153.071254) (xy 197.976812 -153.113634) (xy 198.013299 -153.161184)
			(xy 198.043266 -153.21309) (xy 198.066202 -153.268463) (xy 198.081715 -153.326356) (xy 198.089538 -153.385778)
			(xy 198.090028 -153.415746) (xy 198.090028 -154.279346) (xy 198.089899 -154.28722) (xy 298.799504 -154.28722)
			(xy 298.799504 -153.42362) (xy 298.799994 -153.393652) (xy 298.807817 -153.33423) (xy 298.82333 -153.276337)
			(xy 298.846266 -153.220964) (xy 298.876233 -153.169058) (xy 298.91272 -153.121508) (xy 298.9551 -153.079128)
			(xy 299.00265 -153.042641) (xy 299.054556 -153.012674) (xy 299.109929 -152.989738) (xy 299.167822 -152.974225)
			(xy 299.227244 -152.966402) (xy 299.28718 -152.966402) (xy 299.346602 -152.974225) (xy 299.404495 -152.989738)
			(xy 299.459868 -153.012674) (xy 299.511774 -153.042641) (xy 299.559324 -153.079128) (xy 299.601704 -153.121508)
			(xy 299.638191 -153.169058) (xy 299.668158 -153.220964) (xy 299.691094 -153.276337) (xy 299.706607 -153.33423)
			(xy 299.71443 -153.393652) (xy 299.71492 -153.42362) (xy 299.71492 -154.279346) (xy 313.274456 -154.279346)
			(xy 313.274456 -153.415746) (xy 313.274946 -153.385778) (xy 313.282769 -153.326356) (xy 313.298282 -153.268463)
			(xy 313.321218 -153.21309) (xy 313.351185 -153.161184) (xy 313.387672 -153.113634) (xy 313.430052 -153.071254)
			(xy 313.477602 -153.034767) (xy 313.529508 -153.0048) (xy 313.584881 -152.981864) (xy 313.642774 -152.966351)
			(xy 313.702196 -152.958528) (xy 313.762132 -152.958528) (xy 313.821554 -152.966351) (xy 313.879447 -152.981864)
			(xy 313.93482 -153.0048) (xy 313.986726 -153.034767) (xy 314.034276 -153.071254) (xy 314.076656 -153.113634)
			(xy 314.113143 -153.161184) (xy 314.14311 -153.21309) (xy 314.166046 -153.268463) (xy 314.181559 -153.326356)
			(xy 314.189382 -153.385778) (xy 314.189872 -153.415746) (xy 314.189872 -154.279346) (xy 314.189743 -154.28722)
			(xy 414.899348 -154.28722) (xy 414.899348 -153.42362) (xy 414.899838 -153.393636) (xy 414.907666 -153.33418)
			(xy 414.923187 -153.276255) (xy 414.946136 -153.220851) (xy 414.97612 -153.168917) (xy 415.012626 -153.121341)
			(xy 415.055031 -153.078936) (xy 415.102607 -153.04243) (xy 415.154541 -153.012446) (xy 415.209945 -152.989497)
			(xy 415.26787 -152.973976) (xy 415.327326 -152.966148) (xy 415.387294 -152.966148) (xy 415.44675 -152.973976)
			(xy 415.504675 -152.989497) (xy 415.560079 -153.012446) (xy 415.612013 -153.04243) (xy 415.659589 -153.078936)
			(xy 415.701994 -153.121341) (xy 415.7385 -153.168917) (xy 415.768484 -153.220851) (xy 415.791433 -153.276255)
			(xy 415.806954 -153.33418) (xy 415.814782 -153.393636) (xy 415.815272 -153.42362) (xy 415.815272 -154.279346)
			(xy 429.3743 -154.279346) (xy 429.3743 -153.415746) (xy 429.37479 -153.385762) (xy 429.382618 -153.326306)
			(xy 429.398139 -153.268381) (xy 429.421088 -153.212977) (xy 429.451072 -153.161043) (xy 429.487578 -153.113467)
			(xy 429.529983 -153.071062) (xy 429.577559 -153.034556) (xy 429.629493 -153.004572) (xy 429.684897 -152.981623)
			(xy 429.742822 -152.966102) (xy 429.802278 -152.958274) (xy 429.862246 -152.958274) (xy 429.921702 -152.966102)
			(xy 429.979627 -152.981623) (xy 430.035031 -153.004572) (xy 430.086965 -153.034556) (xy 430.134541 -153.071062)
			(xy 430.176946 -153.113467) (xy 430.213452 -153.161043) (xy 430.243436 -153.212977) (xy 430.266385 -153.268381)
			(xy 430.281906 -153.326306) (xy 430.289734 -153.385762) (xy 430.290224 -153.415746) (xy 430.290224 -154.279346)
			(xy 430.289734 -154.30933) (xy 430.281906 -154.368786) (xy 430.266385 -154.426711) (xy 430.243436 -154.482115)
			(xy 430.213452 -154.534049) (xy 430.176946 -154.581625) (xy 430.134541 -154.62403) (xy 430.086965 -154.660536)
			(xy 430.035031 -154.69052) (xy 429.979627 -154.713469) (xy 429.921702 -154.72899) (xy 429.862246 -154.736818)
			(xy 429.802278 -154.736818) (xy 429.742822 -154.72899) (xy 429.684897 -154.713469) (xy 429.629493 -154.69052)
			(xy 429.577559 -154.660536) (xy 429.529983 -154.62403) (xy 429.487578 -154.581625) (xy 429.451072 -154.534049)
			(xy 429.421088 -154.482115) (xy 429.398139 -154.426711) (xy 429.382618 -154.368786) (xy 429.37479 -154.30933)
			(xy 429.3743 -154.279346) (xy 415.815272 -154.279346) (xy 415.815272 -154.28722) (xy 415.814782 -154.317204)
			(xy 415.806954 -154.37666) (xy 415.791433 -154.434585) (xy 415.768484 -154.489989) (xy 415.7385 -154.541923)
			(xy 415.701994 -154.589499) (xy 415.659589 -154.631904) (xy 415.612013 -154.66841) (xy 415.560079 -154.698394)
			(xy 415.504675 -154.721343) (xy 415.44675 -154.736864) (xy 415.387294 -154.744692) (xy 415.327326 -154.744692)
			(xy 415.26787 -154.736864) (xy 415.209945 -154.721343) (xy 415.154541 -154.698394) (xy 415.102607 -154.66841)
			(xy 415.055031 -154.631904) (xy 415.012626 -154.589499) (xy 414.97612 -154.541923) (xy 414.946136 -154.489989)
			(xy 414.923187 -154.434585) (xy 414.907666 -154.37666) (xy 414.899838 -154.317204) (xy 414.899348 -154.28722)
			(xy 314.189743 -154.28722) (xy 314.189382 -154.309314) (xy 314.181559 -154.368736) (xy 314.166046 -154.426629)
			(xy 314.14311 -154.482002) (xy 314.113143 -154.533908) (xy 314.076656 -154.581458) (xy 314.034276 -154.623838)
			(xy 313.986726 -154.660325) (xy 313.93482 -154.690292) (xy 313.879447 -154.713228) (xy 313.821554 -154.728741)
			(xy 313.762132 -154.736564) (xy 313.702196 -154.736564) (xy 313.642774 -154.728741) (xy 313.584881 -154.713228)
			(xy 313.529508 -154.690292) (xy 313.477602 -154.660325) (xy 313.430052 -154.623838) (xy 313.387672 -154.581458)
			(xy 313.351185 -154.533908) (xy 313.321218 -154.482002) (xy 313.298282 -154.426629) (xy 313.282769 -154.368736)
			(xy 313.274946 -154.309314) (xy 313.274456 -154.279346) (xy 299.71492 -154.279346) (xy 299.71492 -154.28722)
			(xy 299.71443 -154.317188) (xy 299.706607 -154.37661) (xy 299.691094 -154.434503) (xy 299.668158 -154.489876)
			(xy 299.638191 -154.541782) (xy 299.601704 -154.589332) (xy 299.559324 -154.631712) (xy 299.511774 -154.668199)
			(xy 299.459868 -154.698166) (xy 299.404495 -154.721102) (xy 299.346602 -154.736615) (xy 299.28718 -154.744438)
			(xy 299.227244 -154.744438) (xy 299.167822 -154.736615) (xy 299.109929 -154.721102) (xy 299.054556 -154.698166)
			(xy 299.00265 -154.668199) (xy 298.9551 -154.631712) (xy 298.91272 -154.589332) (xy 298.876233 -154.541782)
			(xy 298.846266 -154.489876) (xy 298.82333 -154.434503) (xy 298.807817 -154.37661) (xy 298.799994 -154.317188)
			(xy 298.799504 -154.28722) (xy 198.089899 -154.28722) (xy 198.089538 -154.309314) (xy 198.081715 -154.368736)
			(xy 198.066202 -154.426629) (xy 198.043266 -154.482002) (xy 198.013299 -154.533908) (xy 197.976812 -154.581458)
			(xy 197.934432 -154.623838) (xy 197.886882 -154.660325) (xy 197.834976 -154.690292) (xy 197.779603 -154.713228)
			(xy 197.72171 -154.728741) (xy 197.662288 -154.736564) (xy 197.602352 -154.736564) (xy 197.54293 -154.728741)
			(xy 197.485037 -154.713228) (xy 197.429664 -154.690292) (xy 197.377758 -154.660325) (xy 197.330208 -154.623838)
			(xy 197.287828 -154.581458) (xy 197.251341 -154.533908) (xy 197.221374 -154.482002) (xy 197.198438 -154.426629)
			(xy 197.182925 -154.368736) (xy 197.175102 -154.309314) (xy 197.174612 -154.279346) (xy 183.615076 -154.279346)
			(xy 183.615076 -154.28722) (xy 183.614586 -154.317188) (xy 183.606763 -154.37661) (xy 183.59125 -154.434503)
			(xy 183.568314 -154.489876) (xy 183.538347 -154.541782) (xy 183.50186 -154.589332) (xy 183.45948 -154.631712)
			(xy 183.41193 -154.668199) (xy 183.360024 -154.698166) (xy 183.304651 -154.721102) (xy 183.246758 -154.736615)
			(xy 183.187336 -154.744438) (xy 183.1274 -154.744438) (xy 183.067978 -154.736615) (xy 183.010085 -154.721102)
			(xy 182.954712 -154.698166) (xy 182.902806 -154.668199) (xy 182.855256 -154.631712) (xy 182.812876 -154.589332)
			(xy 182.776389 -154.541782) (xy 182.746422 -154.489876) (xy 182.723486 -154.434503) (xy 182.707973 -154.37661)
			(xy 182.70015 -154.317188) (xy 182.69966 -154.28722) (xy 81.990055 -154.28722) (xy 81.989694 -154.30933)
			(xy 81.981866 -154.368786) (xy 81.966345 -154.426711) (xy 81.943396 -154.482115) (xy 81.913412 -154.534049)
			(xy 81.876906 -154.581625) (xy 81.834501 -154.62403) (xy 81.786925 -154.660536) (xy 81.734991 -154.69052)
			(xy 81.679587 -154.713469) (xy 81.621662 -154.72899) (xy 81.562206 -154.736818) (xy 81.502238 -154.736818)
			(xy 81.442782 -154.72899) (xy 81.384857 -154.713469) (xy 81.329453 -154.69052) (xy 81.277519 -154.660536)
			(xy 81.229943 -154.62403) (xy 81.187538 -154.581625) (xy 81.151032 -154.534049) (xy 81.121048 -154.482115)
			(xy 81.098099 -154.426711) (xy 81.082578 -154.368786) (xy 81.07475 -154.30933) (xy 81.07426 -154.279346)
			(xy 67.515232 -154.279346) (xy 67.515232 -154.28722) (xy 67.514742 -154.317204) (xy 67.506914 -154.37666)
			(xy 67.491393 -154.434585) (xy 67.468444 -154.489989) (xy 67.43846 -154.541923) (xy 67.401954 -154.589499)
			(xy 67.359549 -154.631904) (xy 67.311973 -154.66841) (xy 67.260039 -154.698394) (xy 67.204635 -154.721343)
			(xy 67.14671 -154.736864) (xy 67.087254 -154.744692) (xy 67.027286 -154.744692) (xy 66.96783 -154.736864)
			(xy 66.909905 -154.721343) (xy 66.854501 -154.698394) (xy 66.802567 -154.66841) (xy 66.754991 -154.631904)
			(xy 66.712586 -154.589499) (xy 66.67608 -154.541923) (xy 66.646096 -154.489989) (xy 66.623147 -154.434585)
			(xy 66.607626 -154.37666) (xy 66.599798 -154.317204) (xy 66.599308 -154.28722) (xy 4.30911 -154.28722)
			(xy 4.30911 -156.087318) (xy 64.745108 -156.087318) (xy 64.745108 -155.223718) (xy 64.745598 -155.193734)
			(xy 64.753426 -155.134278) (xy 64.768947 -155.076353) (xy 64.791896 -155.020949) (xy 64.82188 -154.969015)
			(xy 64.858386 -154.921439) (xy 64.900791 -154.879034) (xy 64.948367 -154.842528) (xy 65.000301 -154.812544)
			(xy 65.055705 -154.789595) (xy 65.11363 -154.774074) (xy 65.173086 -154.766246) (xy 65.233054 -154.766246)
			(xy 65.29251 -154.774074) (xy 65.350435 -154.789595) (xy 65.405839 -154.812544) (xy 65.457773 -154.842528)
			(xy 65.505349 -154.879034) (xy 65.547754 -154.921439) (xy 65.58426 -154.969015) (xy 65.614244 -155.020949)
			(xy 65.637193 -155.076353) (xy 65.652714 -155.134278) (xy 65.660542 -155.193734) (xy 65.661032 -155.223718)
			(xy 65.661032 -156.085794) (xy 83.716368 -156.085794) (xy 83.716368 -155.222194) (xy 83.716858 -155.19221)
			(xy 83.724686 -155.132754) (xy 83.740207 -155.074829) (xy 83.763156 -155.019425) (xy 83.79314 -154.967491)
			(xy 83.829646 -154.919915) (xy 83.872051 -154.87751) (xy 83.919627 -154.841004) (xy 83.971561 -154.81102)
			(xy 84.026965 -154.788071) (xy 84.08489 -154.77255) (xy 84.144346 -154.764722) (xy 84.204314 -154.764722)
			(xy 84.26377 -154.77255) (xy 84.321695 -154.788071) (xy 84.377099 -154.81102) (xy 84.429033 -154.841004)
			(xy 84.476609 -154.87751) (xy 84.519014 -154.919915) (xy 84.55552 -154.967491) (xy 84.585504 -155.019425)
			(xy 84.608453 -155.074829) (xy 84.623974 -155.132754) (xy 84.631802 -155.19221) (xy 84.632292 -155.222194)
			(xy 84.632292 -156.085794) (xy 84.632267 -156.087318) (xy 180.84546 -156.087318) (xy 180.84546 -155.223718)
			(xy 180.84595 -155.19375) (xy 180.853773 -155.134328) (xy 180.869286 -155.076435) (xy 180.892222 -155.021062)
			(xy 180.922189 -154.969156) (xy 180.958676 -154.921606) (xy 181.001056 -154.879226) (xy 181.048606 -154.842739)
			(xy 181.100512 -154.812772) (xy 181.155885 -154.789836) (xy 181.213778 -154.774323) (xy 181.2732 -154.7665)
			(xy 181.333136 -154.7665) (xy 181.392558 -154.774323) (xy 181.450451 -154.789836) (xy 181.505824 -154.812772)
			(xy 181.55773 -154.842739) (xy 181.60528 -154.879226) (xy 181.64766 -154.921606) (xy 181.684147 -154.969156)
			(xy 181.714114 -155.021062) (xy 181.73705 -155.076435) (xy 181.752563 -155.134328) (xy 181.760386 -155.19375)
			(xy 181.760876 -155.223718) (xy 181.760876 -156.085794) (xy 199.81672 -156.085794) (xy 199.81672 -155.222194)
			(xy 199.81721 -155.192226) (xy 199.825033 -155.132804) (xy 199.840546 -155.074911) (xy 199.863482 -155.019538)
			(xy 199.893449 -154.967632) (xy 199.929936 -154.920082) (xy 199.972316 -154.877702) (xy 200.019866 -154.841215)
			(xy 200.071772 -154.811248) (xy 200.127145 -154.788312) (xy 200.185038 -154.772799) (xy 200.24446 -154.764976)
			(xy 200.304396 -154.764976) (xy 200.363818 -154.772799) (xy 200.421711 -154.788312) (xy 200.477084 -154.811248)
			(xy 200.52899 -154.841215) (xy 200.57654 -154.877702) (xy 200.61892 -154.920082) (xy 200.655407 -154.967632)
			(xy 200.685374 -155.019538) (xy 200.70831 -155.074911) (xy 200.723823 -155.132804) (xy 200.731646 -155.192226)
			(xy 200.732136 -155.222194) (xy 200.732136 -156.085794) (xy 200.732111 -156.087318) (xy 296.945304 -156.087318)
			(xy 296.945304 -155.223718) (xy 296.945794 -155.19375) (xy 296.953617 -155.134328) (xy 296.96913 -155.076435)
			(xy 296.992066 -155.021062) (xy 297.022033 -154.969156) (xy 297.05852 -154.921606) (xy 297.1009 -154.879226)
			(xy 297.14845 -154.842739) (xy 297.200356 -154.812772) (xy 297.255729 -154.789836) (xy 297.313622 -154.774323)
			(xy 297.373044 -154.7665) (xy 297.43298 -154.7665) (xy 297.492402 -154.774323) (xy 297.550295 -154.789836)
			(xy 297.605668 -154.812772) (xy 297.657574 -154.842739) (xy 297.705124 -154.879226) (xy 297.747504 -154.921606)
			(xy 297.783991 -154.969156) (xy 297.813958 -155.021062) (xy 297.836894 -155.076435) (xy 297.852407 -155.134328)
			(xy 297.86023 -155.19375) (xy 297.86072 -155.223718) (xy 297.86072 -156.085794) (xy 315.916564 -156.085794)
			(xy 315.916564 -155.222194) (xy 315.917054 -155.192226) (xy 315.924877 -155.132804) (xy 315.94039 -155.074911)
			(xy 315.963326 -155.019538) (xy 315.993293 -154.967632) (xy 316.02978 -154.920082) (xy 316.07216 -154.877702)
			(xy 316.11971 -154.841215) (xy 316.171616 -154.811248) (xy 316.226989 -154.788312) (xy 316.284882 -154.772799)
			(xy 316.344304 -154.764976) (xy 316.40424 -154.764976) (xy 316.463662 -154.772799) (xy 316.521555 -154.788312)
			(xy 316.576928 -154.811248) (xy 316.628834 -154.841215) (xy 316.676384 -154.877702) (xy 316.718764 -154.920082)
			(xy 316.755251 -154.967632) (xy 316.785218 -155.019538) (xy 316.808154 -155.074911) (xy 316.823667 -155.132804)
			(xy 316.83149 -155.192226) (xy 316.83198 -155.222194) (xy 316.83198 -156.085794) (xy 316.831955 -156.087318)
			(xy 413.045148 -156.087318) (xy 413.045148 -155.223718) (xy 413.045638 -155.193734) (xy 413.053466 -155.134278)
			(xy 413.068987 -155.076353) (xy 413.091936 -155.020949) (xy 413.12192 -154.969015) (xy 413.158426 -154.921439)
			(xy 413.200831 -154.879034) (xy 413.248407 -154.842528) (xy 413.300341 -154.812544) (xy 413.355745 -154.789595)
			(xy 413.41367 -154.774074) (xy 413.473126 -154.766246) (xy 413.533094 -154.766246) (xy 413.59255 -154.774074)
			(xy 413.650475 -154.789595) (xy 413.705879 -154.812544) (xy 413.757813 -154.842528) (xy 413.805389 -154.879034)
			(xy 413.847794 -154.921439) (xy 413.8843 -154.969015) (xy 413.914284 -155.020949) (xy 413.937233 -155.076353)
			(xy 413.952754 -155.134278) (xy 413.960582 -155.193734) (xy 413.961072 -155.223718) (xy 413.961072 -156.085794)
			(xy 432.016408 -156.085794) (xy 432.016408 -155.222194) (xy 432.016898 -155.19221) (xy 432.024726 -155.132754)
			(xy 432.040247 -155.074829) (xy 432.063196 -155.019425) (xy 432.09318 -154.967491) (xy 432.129686 -154.919915)
			(xy 432.172091 -154.87751) (xy 432.219667 -154.841004) (xy 432.271601 -154.81102) (xy 432.327005 -154.788071)
			(xy 432.38493 -154.77255) (xy 432.444386 -154.764722) (xy 432.504354 -154.764722) (xy 432.56381 -154.77255)
			(xy 432.621735 -154.788071) (xy 432.677139 -154.81102) (xy 432.729073 -154.841004) (xy 432.776649 -154.87751)
			(xy 432.819054 -154.919915) (xy 432.85556 -154.967491) (xy 432.885544 -155.019425) (xy 432.908493 -155.074829)
			(xy 432.924014 -155.132754) (xy 432.931842 -155.19221) (xy 432.932332 -155.222194) (xy 432.932332 -156.085794)
			(xy 432.931842 -156.115778) (xy 432.924014 -156.175234) (xy 432.908493 -156.233159) (xy 432.885544 -156.288563)
			(xy 432.85556 -156.340497) (xy 432.819054 -156.388073) (xy 432.776649 -156.430478) (xy 432.729073 -156.466984)
			(xy 432.677139 -156.496968) (xy 432.621735 -156.519917) (xy 432.56381 -156.535438) (xy 432.504354 -156.543266)
			(xy 432.444386 -156.543266) (xy 432.38493 -156.535438) (xy 432.327005 -156.519917) (xy 432.271601 -156.496968)
			(xy 432.219667 -156.466984) (xy 432.172091 -156.430478) (xy 432.129686 -156.388073) (xy 432.09318 -156.340497)
			(xy 432.063196 -156.288563) (xy 432.040247 -156.233159) (xy 432.024726 -156.175234) (xy 432.016898 -156.115778)
			(xy 432.016408 -156.085794) (xy 413.961072 -156.085794) (xy 413.961072 -156.087318) (xy 413.960582 -156.117302)
			(xy 413.952754 -156.176758) (xy 413.937233 -156.234683) (xy 413.914284 -156.290087) (xy 413.8843 -156.342021)
			(xy 413.847794 -156.389597) (xy 413.805389 -156.432002) (xy 413.757813 -156.468508) (xy 413.705879 -156.498492)
			(xy 413.650475 -156.521441) (xy 413.59255 -156.536962) (xy 413.533094 -156.54479) (xy 413.473126 -156.54479)
			(xy 413.41367 -156.536962) (xy 413.355745 -156.521441) (xy 413.300341 -156.498492) (xy 413.248407 -156.468508)
			(xy 413.200831 -156.432002) (xy 413.158426 -156.389597) (xy 413.12192 -156.342021) (xy 413.091936 -156.290087)
			(xy 413.068987 -156.234683) (xy 413.053466 -156.176758) (xy 413.045638 -156.117302) (xy 413.045148 -156.087318)
			(xy 316.831955 -156.087318) (xy 316.83149 -156.115762) (xy 316.823667 -156.175184) (xy 316.808154 -156.233077)
			(xy 316.785218 -156.28845) (xy 316.755251 -156.340356) (xy 316.718764 -156.387906) (xy 316.676384 -156.430286)
			(xy 316.628834 -156.466773) (xy 316.576928 -156.49674) (xy 316.521555 -156.519676) (xy 316.463662 -156.535189)
			(xy 316.40424 -156.543012) (xy 316.344304 -156.543012) (xy 316.284882 -156.535189) (xy 316.226989 -156.519676)
			(xy 316.171616 -156.49674) (xy 316.11971 -156.466773) (xy 316.07216 -156.430286) (xy 316.02978 -156.387906)
			(xy 315.993293 -156.340356) (xy 315.963326 -156.28845) (xy 315.94039 -156.233077) (xy 315.924877 -156.175184)
			(xy 315.917054 -156.115762) (xy 315.916564 -156.085794) (xy 297.86072 -156.085794) (xy 297.86072 -156.087318)
			(xy 297.86023 -156.117286) (xy 297.852407 -156.176708) (xy 297.836894 -156.234601) (xy 297.813958 -156.289974)
			(xy 297.783991 -156.34188) (xy 297.747504 -156.38943) (xy 297.705124 -156.43181) (xy 297.657574 -156.468297)
			(xy 297.605668 -156.498264) (xy 297.550295 -156.5212) (xy 297.492402 -156.536713) (xy 297.43298 -156.544536)
			(xy 297.373044 -156.544536) (xy 297.313622 -156.536713) (xy 297.255729 -156.5212) (xy 297.200356 -156.498264)
			(xy 297.14845 -156.468297) (xy 297.1009 -156.43181) (xy 297.05852 -156.38943) (xy 297.022033 -156.34188)
			(xy 296.992066 -156.289974) (xy 296.96913 -156.234601) (xy 296.953617 -156.176708) (xy 296.945794 -156.117286)
			(xy 296.945304 -156.087318) (xy 200.732111 -156.087318) (xy 200.731646 -156.115762) (xy 200.723823 -156.175184)
			(xy 200.70831 -156.233077) (xy 200.685374 -156.28845) (xy 200.655407 -156.340356) (xy 200.61892 -156.387906)
			(xy 200.57654 -156.430286) (xy 200.52899 -156.466773) (xy 200.477084 -156.49674) (xy 200.421711 -156.519676)
			(xy 200.363818 -156.535189) (xy 200.304396 -156.543012) (xy 200.24446 -156.543012) (xy 200.185038 -156.535189)
			(xy 200.127145 -156.519676) (xy 200.071772 -156.49674) (xy 200.019866 -156.466773) (xy 199.972316 -156.430286)
			(xy 199.929936 -156.387906) (xy 199.893449 -156.340356) (xy 199.863482 -156.28845) (xy 199.840546 -156.233077)
			(xy 199.825033 -156.175184) (xy 199.81721 -156.115762) (xy 199.81672 -156.085794) (xy 181.760876 -156.085794)
			(xy 181.760876 -156.087318) (xy 181.760386 -156.117286) (xy 181.752563 -156.176708) (xy 181.73705 -156.234601)
			(xy 181.714114 -156.289974) (xy 181.684147 -156.34188) (xy 181.64766 -156.38943) (xy 181.60528 -156.43181)
			(xy 181.55773 -156.468297) (xy 181.505824 -156.498264) (xy 181.450451 -156.5212) (xy 181.392558 -156.536713)
			(xy 181.333136 -156.544536) (xy 181.2732 -156.544536) (xy 181.213778 -156.536713) (xy 181.155885 -156.5212)
			(xy 181.100512 -156.498264) (xy 181.048606 -156.468297) (xy 181.001056 -156.43181) (xy 180.958676 -156.38943)
			(xy 180.922189 -156.34188) (xy 180.892222 -156.289974) (xy 180.869286 -156.234601) (xy 180.853773 -156.176708)
			(xy 180.84595 -156.117286) (xy 180.84546 -156.087318) (xy 84.632267 -156.087318) (xy 84.631802 -156.115778)
			(xy 84.623974 -156.175234) (xy 84.608453 -156.233159) (xy 84.585504 -156.288563) (xy 84.55552 -156.340497)
			(xy 84.519014 -156.388073) (xy 84.476609 -156.430478) (xy 84.429033 -156.466984) (xy 84.377099 -156.496968)
			(xy 84.321695 -156.519917) (xy 84.26377 -156.535438) (xy 84.204314 -156.543266) (xy 84.144346 -156.543266)
			(xy 84.08489 -156.535438) (xy 84.026965 -156.519917) (xy 83.971561 -156.496968) (xy 83.919627 -156.466984)
			(xy 83.872051 -156.430478) (xy 83.829646 -156.388073) (xy 83.79314 -156.340497) (xy 83.763156 -156.288563)
			(xy 83.740207 -156.233159) (xy 83.724686 -156.175234) (xy 83.716858 -156.115778) (xy 83.716368 -156.085794)
			(xy 65.661032 -156.085794) (xy 65.661032 -156.087318) (xy 65.660542 -156.117302) (xy 65.652714 -156.176758)
			(xy 65.637193 -156.234683) (xy 65.614244 -156.290087) (xy 65.58426 -156.342021) (xy 65.547754 -156.389597)
			(xy 65.505349 -156.432002) (xy 65.457773 -156.468508) (xy 65.405839 -156.498492) (xy 65.350435 -156.521441)
			(xy 65.29251 -156.536962) (xy 65.233054 -156.54479) (xy 65.173086 -156.54479) (xy 65.11363 -156.536962)
			(xy 65.055705 -156.521441) (xy 65.000301 -156.498492) (xy 64.948367 -156.468508) (xy 64.900791 -156.432002)
			(xy 64.858386 -156.389597) (xy 64.82188 -156.342021) (xy 64.791896 -156.290087) (xy 64.768947 -156.234683)
			(xy 64.753426 -156.176758) (xy 64.745598 -156.117302) (xy 64.745108 -156.087318) (xy 4.30911 -156.087318)
			(xy 4.30911 -157.900066) (xy 228.314505 -157.900066) (xy 228.314505 -157.840134) (xy 228.322328 -157.780714)
			(xy 228.33784 -157.722823) (xy 228.360775 -157.667453) (xy 228.390741 -157.61555) (xy 228.427226 -157.568002)
			(xy 228.469605 -157.525624) (xy 228.517153 -157.489139) (xy 228.569056 -157.459173) (xy 228.624427 -157.436238)
			(xy 228.682318 -157.420727) (xy 228.741738 -157.412905) (xy 228.771704 -157.412436) (xy 229.635304 -157.412436)
			(xy 229.665274 -157.412838) (xy 229.724702 -157.420663) (xy 229.7826 -157.436177) (xy 229.837978 -157.459116)
			(xy 229.889888 -157.489086) (xy 229.937442 -157.525576) (xy 229.979827 -157.567961) (xy 230.016316 -157.615515)
			(xy 230.046286 -157.667425) (xy 230.069224 -157.722803) (xy 230.084738 -157.780702) (xy 230.092562 -157.84013)
			(xy 230.092562 -157.90007) (xy 230.089876 -157.920473) (xy 230.557725 -157.920473) (xy 230.557725 -157.860527)
			(xy 230.56555 -157.801095) (xy 230.581066 -157.743192) (xy 230.604007 -157.68781) (xy 230.633981 -157.635897)
			(xy 230.670475 -157.58834) (xy 230.712864 -157.545953) (xy 230.760423 -157.509463) (xy 230.812339 -157.479493)
			(xy 230.867722 -157.456555) (xy 230.925626 -157.441044) (xy 230.985059 -157.433223) (xy 231.015032 -157.432756)
			(xy 231.878632 -157.432756) (xy 231.908596 -157.43332) (xy 231.968011 -157.441146) (xy 232.025896 -157.45666)
			(xy 232.081261 -157.479596) (xy 232.133158 -157.509563) (xy 232.180701 -157.546046) (xy 232.223075 -157.588423)
			(xy 232.259555 -157.635968) (xy 232.289518 -157.687868) (xy 232.31245 -157.743235) (xy 232.32796 -157.801121)
			(xy 232.335782 -157.860536) (xy 232.335782 -157.920464) (xy 232.32796 -157.979879) (xy 232.31245 -158.037765)
			(xy 232.289518 -158.093132) (xy 232.259555 -158.145032) (xy 232.223075 -158.192577) (xy 232.180701 -158.234954)
			(xy 232.133158 -158.271437) (xy 232.081261 -158.301404) (xy 232.025896 -158.32434) (xy 231.968011 -158.339854)
			(xy 231.908596 -158.34768) (xy 231.878632 -158.348172) (xy 231.015032 -158.348172) (xy 230.985059 -158.347777)
			(xy 230.925626 -158.339956) (xy 230.867722 -158.324445) (xy 230.812339 -158.301507) (xy 230.760423 -158.271537)
			(xy 230.712864 -158.235047) (xy 230.670475 -158.19266) (xy 230.633981 -158.145103) (xy 230.604007 -158.09319)
			(xy 230.581066 -158.037808) (xy 230.56555 -157.979905) (xy 230.557725 -157.920473) (xy 230.089876 -157.920473)
			(xy 230.084738 -157.959498) (xy 230.069224 -158.017397) (xy 230.046286 -158.072775) (xy 230.016316 -158.124685)
			(xy 229.979827 -158.172239) (xy 229.937442 -158.214624) (xy 229.889888 -158.251114) (xy 229.837978 -158.281084)
			(xy 229.7826 -158.304023) (xy 229.724702 -158.319537) (xy 229.665274 -158.327362) (xy 229.635304 -158.327852)
			(xy 228.771704 -158.327852) (xy 228.741738 -158.327295) (xy 228.682318 -158.319473) (xy 228.624427 -158.303962)
			(xy 228.569056 -158.281027) (xy 228.517153 -158.251061) (xy 228.469605 -158.214576) (xy 228.427226 -158.172198)
			(xy 228.390741 -158.12465) (xy 228.360775 -158.072747) (xy 228.33784 -158.017377) (xy 228.322328 -157.959486)
			(xy 228.314505 -157.900066) (xy 4.30911 -157.900066) (xy 4.30911 -160.1851) (xy 45.524179 -160.1851)
			(xy 45.528134 -160.093263) (xy 45.539969 -160.002106) (xy 45.559596 -159.912303) (xy 45.58687 -159.824521)
			(xy 45.62159 -159.739407) (xy 45.663498 -159.657594) (xy 45.712284 -159.579686) (xy 45.767587 -159.506261)
			(xy 45.828997 -159.437861) (xy 45.896059 -159.374994) (xy 45.968278 -159.318124) (xy 46.045118 -159.267673)
			(xy 46.126011 -159.224014) (xy 46.210357 -159.187471) (xy 46.297533 -159.158314) (xy 46.386892 -159.13676)
			(xy 46.477773 -159.122966) (xy 46.569504 -159.117036) (xy 46.661405 -159.119014) (xy 46.752796 -159.128885)
			(xy 46.843 -159.146575) (xy 46.931349 -159.171955) (xy 47.017189 -159.204835) (xy 47.099885 -159.244973)
			(xy 47.178825 -159.292072) (xy 47.253423 -159.345782) (xy 47.323129 -159.405706) (xy 47.387424 -159.4714)
			(xy 47.445835 -159.542378) (xy 47.497927 -159.618115) (xy 47.543316 -159.69805) (xy 47.581666 -159.78159)
			(xy 47.612691 -159.868118) (xy 47.636164 -159.956993) (xy 47.65191 -160.047557) (xy 47.659812 -160.139139)
			(xy 47.660306 -160.1851) (xy 69.888875 -160.1851) (xy 69.892831 -160.093241) (xy 69.904668 -160.002062)
			(xy 69.9243 -159.912238) (xy 69.951581 -159.824435) (xy 69.986309 -159.739302) (xy 70.028227 -159.657469)
			(xy 70.077025 -159.579542) (xy 70.13234 -159.506099) (xy 70.193765 -159.437683) (xy 70.260844 -159.374801)
			(xy 70.333079 -159.317918) (xy 70.409938 -159.267455) (xy 70.49085 -159.223786) (xy 70.575216 -159.187234)
			(xy 70.662412 -159.15807) (xy 70.751793 -159.13651) (xy 70.842696 -159.122714) (xy 70.934449 -159.116782)
			(xy 71.026371 -159.118761) (xy 71.117784 -159.128634) (xy 71.208009 -159.146329) (xy 71.29638 -159.171714)
			(xy 71.38224 -159.204602) (xy 71.464956 -159.24475) (xy 71.543914 -159.291859) (xy 71.618531 -159.345582)
			(xy 71.688252 -159.40552) (xy 71.752563 -159.47123) (xy 71.810988 -159.542226) (xy 71.863093 -159.61798)
			(xy 71.908492 -159.697934) (xy 71.946851 -159.781494) (xy 71.977884 -159.868043) (xy 72.001362 -159.956939)
			(xy 72.017112 -160.047524) (xy 72.025016 -160.139128) (xy 72.02551 -160.1851) (xy 161.624277 -160.1851)
			(xy 161.628232 -160.093263) (xy 161.640067 -160.002106) (xy 161.659694 -159.912303) (xy 161.686968 -159.824521)
			(xy 161.721688 -159.739407) (xy 161.763596 -159.657594) (xy 161.812382 -159.579686) (xy 161.867685 -159.506261)
			(xy 161.929095 -159.437861) (xy 161.996157 -159.374994) (xy 162.068376 -159.318124) (xy 162.145216 -159.267673)
			(xy 162.226109 -159.224014) (xy 162.310455 -159.187471) (xy 162.397631 -159.158314) (xy 162.48699 -159.13676)
			(xy 162.577871 -159.122966) (xy 162.669602 -159.117036) (xy 162.761503 -159.119014) (xy 162.852894 -159.128885)
			(xy 162.943098 -159.146575) (xy 163.031447 -159.171955) (xy 163.117287 -159.204835) (xy 163.199983 -159.244973)
			(xy 163.278923 -159.292072) (xy 163.353521 -159.345782) (xy 163.423227 -159.405706) (xy 163.487522 -159.4714)
			(xy 163.545933 -159.542378) (xy 163.598025 -159.618115) (xy 163.643414 -159.69805) (xy 163.681764 -159.78159)
			(xy 163.712789 -159.868118) (xy 163.736262 -159.956993) (xy 163.752008 -160.047557) (xy 163.75991 -160.139139)
			(xy 163.760404 -160.1851) (xy 185.988973 -160.1851) (xy 185.992929 -160.093241) (xy 186.004766 -160.002062)
			(xy 186.024398 -159.912238) (xy 186.051679 -159.824435) (xy 186.086407 -159.739302) (xy 186.128325 -159.657469)
			(xy 186.177123 -159.579542) (xy 186.232438 -159.506099) (xy 186.293863 -159.437683) (xy 186.360942 -159.374801)
			(xy 186.433177 -159.317918) (xy 186.510036 -159.267455) (xy 186.590948 -159.223786) (xy 186.675314 -159.187234)
			(xy 186.76251 -159.15807) (xy 186.851891 -159.13651) (xy 186.942794 -159.122714) (xy 187.034547 -159.116782)
			(xy 187.126469 -159.118761) (xy 187.217882 -159.128634) (xy 187.308107 -159.146329) (xy 187.396478 -159.171714)
			(xy 187.482338 -159.204602) (xy 187.565054 -159.24475) (xy 187.644012 -159.291859) (xy 187.718629 -159.345582)
			(xy 187.78835 -159.40552) (xy 187.852661 -159.47123) (xy 187.911086 -159.542226) (xy 187.963191 -159.61798)
			(xy 188.00859 -159.697934) (xy 188.046949 -159.781494) (xy 188.077982 -159.868043) (xy 188.10146 -159.956939)
			(xy 188.11721 -160.047524) (xy 188.125114 -160.139128) (xy 188.125608 -160.1851) (xy 277.724121 -160.1851)
			(xy 277.728076 -160.093263) (xy 277.739911 -160.002106) (xy 277.759538 -159.912303) (xy 277.786812 -159.824521)
			(xy 277.821532 -159.739407) (xy 277.86344 -159.657594) (xy 277.912226 -159.579686) (xy 277.967529 -159.506261)
			(xy 278.028939 -159.437861) (xy 278.096001 -159.374994) (xy 278.16822 -159.318124) (xy 278.24506 -159.267673)
			(xy 278.325953 -159.224014) (xy 278.410299 -159.187471) (xy 278.497475 -159.158314) (xy 278.586834 -159.13676)
			(xy 278.677715 -159.122966) (xy 278.769446 -159.117036) (xy 278.861347 -159.119014) (xy 278.952738 -159.128885)
			(xy 279.042942 -159.146575) (xy 279.131291 -159.171955) (xy 279.217131 -159.204835) (xy 279.299827 -159.244973)
			(xy 279.378767 -159.292072) (xy 279.453365 -159.345782) (xy 279.523071 -159.405706) (xy 279.587366 -159.4714)
			(xy 279.645777 -159.542378) (xy 279.697869 -159.618115) (xy 279.743258 -159.69805) (xy 279.781608 -159.78159)
			(xy 279.812633 -159.868118) (xy 279.836106 -159.956993) (xy 279.851852 -160.047557) (xy 279.859754 -160.139139)
			(xy 279.860248 -160.1851) (xy 302.088817 -160.1851) (xy 302.092773 -160.093241) (xy 302.10461 -160.002062)
			(xy 302.124242 -159.912238) (xy 302.151523 -159.824435) (xy 302.186251 -159.739302) (xy 302.228169 -159.657469)
			(xy 302.276967 -159.579542) (xy 302.332282 -159.506099) (xy 302.393707 -159.437683) (xy 302.460786 -159.374801)
			(xy 302.533021 -159.317918) (xy 302.60988 -159.267455) (xy 302.690792 -159.223786) (xy 302.775158 -159.187234)
			(xy 302.862354 -159.15807) (xy 302.951735 -159.13651) (xy 303.042638 -159.122714) (xy 303.134391 -159.116782)
			(xy 303.226313 -159.118761) (xy 303.317726 -159.128634) (xy 303.407951 -159.146329) (xy 303.496322 -159.171714)
			(xy 303.582182 -159.204602) (xy 303.664898 -159.24475) (xy 303.743856 -159.291859) (xy 303.818473 -159.345582)
			(xy 303.888194 -159.40552) (xy 303.952505 -159.47123) (xy 304.01093 -159.542226) (xy 304.063035 -159.61798)
			(xy 304.108434 -159.697934) (xy 304.146793 -159.781494) (xy 304.177826 -159.868043) (xy 304.201304 -159.956939)
			(xy 304.217054 -160.047524) (xy 304.224958 -160.139128) (xy 304.225452 -160.1851) (xy 393.824219 -160.1851)
			(xy 393.828174 -160.093263) (xy 393.840009 -160.002106) (xy 393.859636 -159.912303) (xy 393.88691 -159.824521)
			(xy 393.92163 -159.739407) (xy 393.963538 -159.657594) (xy 394.012324 -159.579686) (xy 394.067627 -159.506261)
			(xy 394.129037 -159.437861) (xy 394.196099 -159.374994) (xy 394.268318 -159.318124) (xy 394.345158 -159.267673)
			(xy 394.426051 -159.224014) (xy 394.510397 -159.187471) (xy 394.597573 -159.158314) (xy 394.686932 -159.13676)
			(xy 394.777813 -159.122966) (xy 394.869544 -159.117036) (xy 394.961445 -159.119014) (xy 395.052836 -159.128885)
			(xy 395.14304 -159.146575) (xy 395.231389 -159.171955) (xy 395.317229 -159.204835) (xy 395.399925 -159.244973)
			(xy 395.478865 -159.292072) (xy 395.553463 -159.345782) (xy 395.623169 -159.405706) (xy 395.687464 -159.4714)
			(xy 395.745875 -159.542378) (xy 395.797967 -159.618115) (xy 395.843356 -159.69805) (xy 395.881706 -159.78159)
			(xy 395.912731 -159.868118) (xy 395.936204 -159.956993) (xy 395.95195 -160.047557) (xy 395.959852 -160.139139)
			(xy 395.960346 -160.1851) (xy 418.188915 -160.1851) (xy 418.192871 -160.093241) (xy 418.204708 -160.002062)
			(xy 418.22434 -159.912238) (xy 418.251621 -159.824435) (xy 418.286349 -159.739302) (xy 418.328267 -159.657469)
			(xy 418.377065 -159.579542) (xy 418.43238 -159.506099) (xy 418.493805 -159.437683) (xy 418.560884 -159.374801)
			(xy 418.633119 -159.317918) (xy 418.709978 -159.267455) (xy 418.79089 -159.223786) (xy 418.875256 -159.187234)
			(xy 418.962452 -159.15807) (xy 419.051833 -159.13651) (xy 419.142736 -159.122714) (xy 419.234489 -159.116782)
			(xy 419.326411 -159.118761) (xy 419.417824 -159.128634) (xy 419.508049 -159.146329) (xy 419.59642 -159.171714)
			(xy 419.68228 -159.204602) (xy 419.764996 -159.24475) (xy 419.843954 -159.291859) (xy 419.918571 -159.345582)
			(xy 419.988292 -159.40552) (xy 420.052603 -159.47123) (xy 420.111028 -159.542226) (xy 420.163133 -159.61798)
			(xy 420.208532 -159.697934) (xy 420.246891 -159.781494) (xy 420.277924 -159.868043) (xy 420.301402 -159.956939)
			(xy 420.317152 -160.047524) (xy 420.325056 -160.139128) (xy 420.32555 -160.1851) (xy 420.325056 -160.231072)
			(xy 420.317152 -160.322676) (xy 420.301402 -160.413261) (xy 420.277924 -160.502157) (xy 420.246891 -160.588706)
			(xy 420.208532 -160.672266) (xy 420.163133 -160.75222) (xy 420.111028 -160.827974) (xy 420.052603 -160.89897)
			(xy 419.988292 -160.96468) (xy 419.918571 -161.024618) (xy 419.843954 -161.078341) (xy 419.764996 -161.12545)
			(xy 419.68228 -161.165598) (xy 419.59642 -161.198486) (xy 419.508049 -161.223871) (xy 419.417824 -161.241566)
			(xy 419.326411 -161.251439) (xy 419.234489 -161.253418) (xy 419.142736 -161.247486) (xy 419.051833 -161.23369)
			(xy 418.962452 -161.21213) (xy 418.875256 -161.182966) (xy 418.79089 -161.146414) (xy 418.709978 -161.102745)
			(xy 418.633119 -161.052282) (xy 418.560884 -160.995399) (xy 418.493805 -160.932517) (xy 418.43238 -160.864101)
			(xy 418.377065 -160.790658) (xy 418.328267 -160.712731) (xy 418.286349 -160.630898) (xy 418.251621 -160.545765)
			(xy 418.22434 -160.457962) (xy 418.204708 -160.368138) (xy 418.192871 -160.276959) (xy 418.188915 -160.1851)
			(xy 395.960346 -160.1851) (xy 395.959852 -160.231061) (xy 395.95195 -160.322643) (xy 395.936204 -160.413207)
			(xy 395.912731 -160.502082) (xy 395.881706 -160.58861) (xy 395.843356 -160.67215) (xy 395.797967 -160.752085)
			(xy 395.745875 -160.827822) (xy 395.687464 -160.8988) (xy 395.623169 -160.964494) (xy 395.553463 -161.024418)
			(xy 395.478865 -161.078128) (xy 395.399925 -161.125227) (xy 395.317229 -161.165365) (xy 395.231389 -161.198245)
			(xy 395.14304 -161.223625) (xy 395.052836 -161.241315) (xy 394.961445 -161.251186) (xy 394.869544 -161.253164)
			(xy 394.777813 -161.247234) (xy 394.686932 -161.23344) (xy 394.597573 -161.211886) (xy 394.510397 -161.182729)
			(xy 394.426051 -161.146186) (xy 394.345158 -161.102527) (xy 394.268318 -161.052076) (xy 394.196099 -160.995206)
			(xy 394.129037 -160.932339) (xy 394.067627 -160.863939) (xy 394.012324 -160.790514) (xy 393.963538 -160.712606)
			(xy 393.92163 -160.630793) (xy 393.88691 -160.545679) (xy 393.859636 -160.457897) (xy 393.840009 -160.368094)
			(xy 393.828174 -160.276937) (xy 393.824219 -160.1851) (xy 304.225452 -160.1851) (xy 304.224958 -160.231072)
			(xy 304.217054 -160.322676) (xy 304.201304 -160.413261) (xy 304.177826 -160.502157) (xy 304.146793 -160.588706)
			(xy 304.108434 -160.672266) (xy 304.063035 -160.75222) (xy 304.01093 -160.827974) (xy 303.952505 -160.89897)
			(xy 303.888194 -160.96468) (xy 303.818473 -161.024618) (xy 303.743856 -161.078341) (xy 303.664898 -161.12545)
			(xy 303.582182 -161.165598) (xy 303.496322 -161.198486) (xy 303.407951 -161.223871) (xy 303.317726 -161.241566)
			(xy 303.226313 -161.251439) (xy 303.134391 -161.253418) (xy 303.042638 -161.247486) (xy 302.951735 -161.23369)
			(xy 302.862354 -161.21213) (xy 302.775158 -161.182966) (xy 302.690792 -161.146414) (xy 302.60988 -161.102745)
			(xy 302.533021 -161.052282) (xy 302.460786 -160.995399) (xy 302.393707 -160.932517) (xy 302.332282 -160.864101)
			(xy 302.276967 -160.790658) (xy 302.228169 -160.712731) (xy 302.186251 -160.630898) (xy 302.151523 -160.545765)
			(xy 302.124242 -160.457962) (xy 302.10461 -160.368138) (xy 302.092773 -160.276959) (xy 302.088817 -160.1851)
			(xy 279.860248 -160.1851) (xy 279.859754 -160.231061) (xy 279.851852 -160.322643) (xy 279.836106 -160.413207)
			(xy 279.812633 -160.502082) (xy 279.781608 -160.58861) (xy 279.743258 -160.67215) (xy 279.697869 -160.752085)
			(xy 279.645777 -160.827822) (xy 279.587366 -160.8988) (xy 279.523071 -160.964494) (xy 279.453365 -161.024418)
			(xy 279.378767 -161.078128) (xy 279.299827 -161.125227) (xy 279.217131 -161.165365) (xy 279.131291 -161.198245)
			(xy 279.042942 -161.223625) (xy 278.952738 -161.241315) (xy 278.861347 -161.251186) (xy 278.769446 -161.253164)
			(xy 278.677715 -161.247234) (xy 278.586834 -161.23344) (xy 278.497475 -161.211886) (xy 278.410299 -161.182729)
			(xy 278.325953 -161.146186) (xy 278.24506 -161.102527) (xy 278.16822 -161.052076) (xy 278.096001 -160.995206)
			(xy 278.028939 -160.932339) (xy 277.967529 -160.863939) (xy 277.912226 -160.790514) (xy 277.86344 -160.712606)
			(xy 277.821532 -160.630793) (xy 277.786812 -160.545679) (xy 277.759538 -160.457897) (xy 277.739911 -160.368094)
			(xy 277.728076 -160.276937) (xy 277.724121 -160.1851) (xy 188.125608 -160.1851) (xy 188.125114 -160.231072)
			(xy 188.11721 -160.322676) (xy 188.10146 -160.413261) (xy 188.077982 -160.502157) (xy 188.046949 -160.588706)
			(xy 188.00859 -160.672266) (xy 187.963191 -160.75222) (xy 187.911086 -160.827974) (xy 187.852661 -160.89897)
			(xy 187.78835 -160.96468) (xy 187.718629 -161.024618) (xy 187.644012 -161.078341) (xy 187.565054 -161.12545)
			(xy 187.482338 -161.165598) (xy 187.396478 -161.198486) (xy 187.308107 -161.223871) (xy 187.217882 -161.241566)
			(xy 187.126469 -161.251439) (xy 187.034547 -161.253418) (xy 186.942794 -161.247486) (xy 186.851891 -161.23369)
			(xy 186.76251 -161.21213) (xy 186.675314 -161.182966) (xy 186.590948 -161.146414) (xy 186.510036 -161.102745)
			(xy 186.433177 -161.052282) (xy 186.360942 -160.995399) (xy 186.293863 -160.932517) (xy 186.232438 -160.864101)
			(xy 186.177123 -160.790658) (xy 186.128325 -160.712731) (xy 186.086407 -160.630898) (xy 186.051679 -160.545765)
			(xy 186.024398 -160.457962) (xy 186.004766 -160.368138) (xy 185.992929 -160.276959) (xy 185.988973 -160.1851)
			(xy 163.760404 -160.1851) (xy 163.75991 -160.231061) (xy 163.752008 -160.322643) (xy 163.736262 -160.413207)
			(xy 163.712789 -160.502082) (xy 163.681764 -160.58861) (xy 163.643414 -160.67215) (xy 163.598025 -160.752085)
			(xy 163.545933 -160.827822) (xy 163.487522 -160.8988) (xy 163.423227 -160.964494) (xy 163.353521 -161.024418)
			(xy 163.278923 -161.078128) (xy 163.199983 -161.125227) (xy 163.117287 -161.165365) (xy 163.031447 -161.198245)
			(xy 162.943098 -161.223625) (xy 162.852894 -161.241315) (xy 162.761503 -161.251186) (xy 162.669602 -161.253164)
			(xy 162.577871 -161.247234) (xy 162.48699 -161.23344) (xy 162.397631 -161.211886) (xy 162.310455 -161.182729)
			(xy 162.226109 -161.146186) (xy 162.145216 -161.102527) (xy 162.068376 -161.052076) (xy 161.996157 -160.995206)
			(xy 161.929095 -160.932339) (xy 161.867685 -160.863939) (xy 161.812382 -160.790514) (xy 161.763596 -160.712606)
			(xy 161.721688 -160.630793) (xy 161.686968 -160.545679) (xy 161.659694 -160.457897) (xy 161.640067 -160.368094)
			(xy 161.628232 -160.276937) (xy 161.624277 -160.1851) (xy 72.02551 -160.1851) (xy 72.025016 -160.231072)
			(xy 72.017112 -160.322676) (xy 72.001362 -160.413261) (xy 71.977884 -160.502157) (xy 71.946851 -160.588706)
			(xy 71.908492 -160.672266) (xy 71.863093 -160.75222) (xy 71.810988 -160.827974) (xy 71.752563 -160.89897)
			(xy 71.688252 -160.96468) (xy 71.618531 -161.024618) (xy 71.543914 -161.078341) (xy 71.464956 -161.12545)
			(xy 71.38224 -161.165598) (xy 71.29638 -161.198486) (xy 71.208009 -161.223871) (xy 71.117784 -161.241566)
			(xy 71.026371 -161.251439) (xy 70.934449 -161.253418) (xy 70.842696 -161.247486) (xy 70.751793 -161.23369)
			(xy 70.662412 -161.21213) (xy 70.575216 -161.182966) (xy 70.49085 -161.146414) (xy 70.409938 -161.102745)
			(xy 70.333079 -161.052282) (xy 70.260844 -160.995399) (xy 70.193765 -160.932517) (xy 70.13234 -160.864101)
			(xy 70.077025 -160.790658) (xy 70.028227 -160.712731) (xy 69.986309 -160.630898) (xy 69.951581 -160.545765)
			(xy 69.9243 -160.457962) (xy 69.904668 -160.368138) (xy 69.892831 -160.276959) (xy 69.888875 -160.1851)
			(xy 47.660306 -160.1851) (xy 47.659812 -160.231061) (xy 47.65191 -160.322643) (xy 47.636164 -160.413207)
			(xy 47.612691 -160.502082) (xy 47.581666 -160.58861) (xy 47.543316 -160.67215) (xy 47.497927 -160.752085)
			(xy 47.445835 -160.827822) (xy 47.387424 -160.8988) (xy 47.323129 -160.964494) (xy 47.253423 -161.024418)
			(xy 47.178825 -161.078128) (xy 47.099885 -161.125227) (xy 47.017189 -161.165365) (xy 46.931349 -161.198245)
			(xy 46.843 -161.223625) (xy 46.752796 -161.241315) (xy 46.661405 -161.251186) (xy 46.569504 -161.253164)
			(xy 46.477773 -161.247234) (xy 46.386892 -161.23344) (xy 46.297533 -161.211886) (xy 46.210357 -161.182729)
			(xy 46.126011 -161.146186) (xy 46.045118 -161.102527) (xy 45.968278 -161.052076) (xy 45.896059 -160.995206)
			(xy 45.828997 -160.932339) (xy 45.767587 -160.863939) (xy 45.712284 -160.790514) (xy 45.663498 -160.712606)
			(xy 45.62159 -160.630793) (xy 45.58687 -160.545679) (xy 45.559596 -160.457897) (xy 45.539969 -160.368094)
			(xy 45.528134 -160.276937) (xy 45.524179 -160.1851) (xy 4.30911 -160.1851) (xy 4.30911 -168.065164)
			(xy 135.245906 -168.065164) (xy 135.245906 -168.005236) (xy 135.253728 -167.94582) (xy 135.269237 -167.887933)
			(xy 135.29217 -167.832566) (xy 135.322132 -167.780665) (xy 135.358612 -167.733119) (xy 135.400986 -167.690742)
			(xy 135.448529 -167.654257) (xy 135.500426 -167.624289) (xy 135.555791 -167.601351) (xy 135.613677 -167.585836)
			(xy 135.673092 -167.578009) (xy 135.703056 -167.577516) (xy 136.566656 -167.577516) (xy 136.596628 -167.577934)
			(xy 136.656061 -167.585754) (xy 136.713965 -167.601264) (xy 136.769348 -167.6242) (xy 136.821264 -167.654169)
			(xy 136.868823 -167.690658) (xy 136.911213 -167.733044) (xy 136.947707 -167.7806) (xy 136.977681 -167.832512)
			(xy 137.000622 -167.887894) (xy 137.016138 -167.945796) (xy 137.023963 -168.005228) (xy 137.023963 -168.065172)
			(xy 137.016138 -168.124604) (xy 137.000622 -168.182506) (xy 136.977681 -168.237888) (xy 136.947707 -168.2898)
			(xy 136.911213 -168.337356) (xy 136.868823 -168.379742) (xy 136.821264 -168.416231) (xy 136.769348 -168.4462)
			(xy 136.713965 -168.469136) (xy 136.656061 -168.484646) (xy 136.596628 -168.492466) (xy 136.566656 -168.492932)
			(xy 135.703056 -168.492932) (xy 135.673092 -168.492391) (xy 135.613677 -168.484564) (xy 135.555791 -168.469049)
			(xy 135.500426 -168.446111) (xy 135.448529 -168.416143) (xy 135.400986 -168.379658) (xy 135.358612 -168.337281)
			(xy 135.322132 -168.289735) (xy 135.29217 -168.237834) (xy 135.269237 -168.182467) (xy 135.253728 -168.12458)
			(xy 135.245906 -168.065164) (xy 4.30911 -168.065164) (xy 4.30911 -168.700164) (xy 133.213906 -168.700164)
			(xy 133.213906 -168.640236) (xy 133.221728 -168.58082) (xy 133.237237 -168.522933) (xy 133.26017 -168.467566)
			(xy 133.290132 -168.415665) (xy 133.326612 -168.368119) (xy 133.368986 -168.325742) (xy 133.416529 -168.289257)
			(xy 133.468426 -168.259289) (xy 133.523791 -168.236351) (xy 133.581677 -168.220836) (xy 133.641092 -168.213009)
			(xy 133.671056 -168.212516) (xy 134.534656 -168.212516) (xy 134.564628 -168.212934) (xy 134.624061 -168.220754)
			(xy 134.681965 -168.236264) (xy 134.737348 -168.2592) (xy 134.789264 -168.289169) (xy 134.836823 -168.325658)
			(xy 134.879213 -168.368044) (xy 134.915707 -168.4156) (xy 134.945681 -168.467512) (xy 134.968622 -168.522894)
			(xy 134.984138 -168.580796) (xy 134.991963 -168.640228) (xy 134.991963 -168.700172) (xy 134.984138 -168.759604)
			(xy 134.968622 -168.817506) (xy 134.945681 -168.872888) (xy 134.915707 -168.9248) (xy 134.879213 -168.972356)
			(xy 134.836823 -169.014742) (xy 134.789264 -169.051231) (xy 134.737348 -169.0812) (xy 134.681965 -169.104136)
			(xy 134.624061 -169.119646) (xy 134.564628 -169.127466) (xy 134.534656 -169.127932) (xy 133.671056 -169.127932)
			(xy 133.641092 -169.127391) (xy 133.581677 -169.119564) (xy 133.523791 -169.104049) (xy 133.468426 -169.081111)
			(xy 133.416529 -169.051143) (xy 133.368986 -169.014658) (xy 133.326612 -168.972281) (xy 133.290132 -168.924735)
			(xy 133.26017 -168.872834) (xy 133.237237 -168.817467) (xy 133.221728 -168.75958) (xy 133.213906 -168.700164)
			(xy 4.30911 -168.700164) (xy 4.30911 -169.61389) (xy 245.108869 -169.61389) (xy 245.108869 -169.55391)
			(xy 245.116699 -169.494444) (xy 245.132223 -169.436508) (xy 245.155178 -169.381095) (xy 245.185169 -169.329152)
			(xy 245.221684 -169.281569) (xy 245.264097 -169.239158) (xy 245.311684 -169.202648) (xy 245.363629 -169.172661)
			(xy 245.419045 -169.149711) (xy 245.476981 -169.134191) (xy 245.536448 -169.126367) (xy 245.566438 -169.1259)
			(xy 246.430038 -169.1259) (xy 246.460018 -169.126468) (xy 246.519465 -169.134299) (xy 246.577381 -169.149822)
			(xy 246.632776 -169.172772) (xy 246.684702 -169.202755) (xy 246.73227 -169.239259) (xy 246.774667 -169.281659)
			(xy 246.811166 -169.32923) (xy 246.841145 -169.381158) (xy 246.86409 -169.436555) (xy 246.879608 -169.494472)
			(xy 246.887434 -169.55392) (xy 246.887434 -169.61388) (xy 246.879608 -169.673328) (xy 246.86409 -169.731245)
			(xy 246.841145 -169.786642) (xy 246.811166 -169.83857) (xy 246.774667 -169.886141) (xy 246.73227 -169.928541)
			(xy 246.684702 -169.965045) (xy 246.632776 -169.995028) (xy 246.577381 -170.017978) (xy 246.519465 -170.033501)
			(xy 246.460018 -170.041332) (xy 246.430038 -170.041824) (xy 245.566438 -170.041824) (xy 245.536448 -170.041433)
			(xy 245.476981 -170.033609) (xy 245.419045 -170.018089) (xy 245.363629 -169.995139) (xy 245.311684 -169.965152)
			(xy 245.264097 -169.928642) (xy 245.221684 -169.886231) (xy 245.185169 -169.838648) (xy 245.155178 -169.786705)
			(xy 245.132223 -169.731292) (xy 245.116699 -169.673356) (xy 245.108869 -169.61389) (xy 4.30911 -169.61389)
			(xy 4.30911 -174.805086) (xy 141.546072 -174.805086) (xy 141.546072 -173.941486) (xy 141.546562 -173.911518)
			(xy 141.554385 -173.852096) (xy 141.569898 -173.794203) (xy 141.592834 -173.73883) (xy 141.622801 -173.686924)
			(xy 141.659288 -173.639374) (xy 141.701668 -173.596994) (xy 141.749218 -173.560507) (xy 141.801124 -173.53054)
			(xy 141.856497 -173.507604) (xy 141.91439 -173.492091) (xy 141.973812 -173.484268) (xy 142.033748 -173.484268)
			(xy 142.09317 -173.492091) (xy 142.106698 -173.495716) (xy 257.519424 -173.495716) (xy 257.519424 -172.632116)
			(xy 257.519914 -172.602132) (xy 257.527742 -172.542676) (xy 257.543263 -172.484751) (xy 257.566212 -172.429347)
			(xy 257.596196 -172.377413) (xy 257.632702 -172.329837) (xy 257.675107 -172.287432) (xy 257.722683 -172.250926)
			(xy 257.774617 -172.220942) (xy 257.830021 -172.197993) (xy 257.887946 -172.182472) (xy 257.947402 -172.174644)
			(xy 258.00737 -172.174644) (xy 258.066826 -172.182472) (xy 258.124751 -172.197993) (xy 258.180155 -172.220942)
			(xy 258.232089 -172.250926) (xy 258.279665 -172.287432) (xy 258.32207 -172.329837) (xy 258.358576 -172.377413)
			(xy 258.38856 -172.429347) (xy 258.411509 -172.484751) (xy 258.42703 -172.542676) (xy 258.434858 -172.602132)
			(xy 258.435348 -172.632116) (xy 258.435348 -173.495716) (xy 258.434858 -173.5257) (xy 258.42703 -173.585156)
			(xy 258.411509 -173.643081) (xy 258.38856 -173.698485) (xy 258.358576 -173.750419) (xy 258.32207 -173.797995)
			(xy 258.279665 -173.8404) (xy 258.232089 -173.876906) (xy 258.180155 -173.90689) (xy 258.124751 -173.929839)
			(xy 258.066826 -173.94536) (xy 258.00737 -173.953188) (xy 257.947402 -173.953188) (xy 257.887946 -173.94536)
			(xy 257.830021 -173.929839) (xy 257.774617 -173.90689) (xy 257.722683 -173.876906) (xy 257.675107 -173.8404)
			(xy 257.632702 -173.797995) (xy 257.596196 -173.750419) (xy 257.566212 -173.698485) (xy 257.543263 -173.643081)
			(xy 257.527742 -173.585156) (xy 257.519914 -173.5257) (xy 257.519424 -173.495716) (xy 142.106698 -173.495716)
			(xy 142.151063 -173.507604) (xy 142.206436 -173.53054) (xy 142.258342 -173.560507) (xy 142.305892 -173.596994)
			(xy 142.348272 -173.639374) (xy 142.384759 -173.686924) (xy 142.414726 -173.73883) (xy 142.437662 -173.794203)
			(xy 142.453175 -173.852096) (xy 142.460998 -173.911518) (xy 142.461488 -173.941486) (xy 142.461488 -174.805086)
			(xy 142.460998 -174.835054) (xy 142.453175 -174.894476) (xy 142.437662 -174.952369) (xy 142.414726 -175.007742)
			(xy 142.384759 -175.059648) (xy 142.348272 -175.107198) (xy 142.305892 -175.149578) (xy 142.258342 -175.186065)
			(xy 142.206436 -175.216032) (xy 142.151063 -175.238968) (xy 142.09317 -175.254481) (xy 142.033748 -175.262304)
			(xy 141.973812 -175.262304) (xy 141.91439 -175.254481) (xy 141.856497 -175.238968) (xy 141.801124 -175.216032)
			(xy 141.749218 -175.186065) (xy 141.701668 -175.149578) (xy 141.659288 -175.107198) (xy 141.622801 -175.059648)
			(xy 141.592834 -175.007742) (xy 141.569898 -174.952369) (xy 141.554385 -174.894476) (xy 141.546562 -174.835054)
			(xy 141.546072 -174.805086) (xy 4.30911 -174.805086) (xy 4.30911 -176.837086) (xy 142.181072 -176.837086)
			(xy 142.181072 -175.973486) (xy 142.181562 -175.943518) (xy 142.189385 -175.884096) (xy 142.204898 -175.826203)
			(xy 142.227834 -175.77083) (xy 142.257801 -175.718924) (xy 142.294288 -175.671374) (xy 142.336668 -175.628994)
			(xy 142.384218 -175.592507) (xy 142.436124 -175.56254) (xy 142.491497 -175.539604) (xy 142.54939 -175.524091)
			(xy 142.608812 -175.516268) (xy 142.668748 -175.516268) (xy 142.72817 -175.524091) (xy 142.786063 -175.539604)
			(xy 142.841436 -175.56254) (xy 142.893342 -175.592507) (xy 142.940892 -175.628994) (xy 142.983272 -175.671374)
			(xy 143.019759 -175.718924) (xy 143.049726 -175.77083) (xy 143.072662 -175.826203) (xy 143.088175 -175.884096)
			(xy 143.095998 -175.943518) (xy 143.096488 -175.973486) (xy 143.096488 -176.837086) (xy 143.095998 -176.867054)
			(xy 143.088175 -176.926476) (xy 143.072662 -176.984369) (xy 143.049726 -177.039742) (xy 143.019759 -177.091648)
			(xy 142.983272 -177.139198) (xy 142.940892 -177.181578) (xy 142.893342 -177.218065) (xy 142.841436 -177.248032)
			(xy 142.786063 -177.270968) (xy 142.72817 -177.286481) (xy 142.668748 -177.294304) (xy 142.608812 -177.294304)
			(xy 142.54939 -177.286481) (xy 142.491497 -177.270968) (xy 142.436124 -177.248032) (xy 142.384218 -177.218065)
			(xy 142.336668 -177.181578) (xy 142.294288 -177.139198) (xy 142.257801 -177.091648) (xy 142.227834 -177.039742)
			(xy 142.204898 -176.984369) (xy 142.189385 -176.926476) (xy 142.181562 -176.867054) (xy 142.181072 -176.837086)
			(xy 4.30911 -176.837086) (xy 4.30911 -178.995324) (xy 123.198636 -178.995324) (xy 123.198636 -178.131724)
			(xy 123.199126 -178.10174) (xy 123.206954 -178.042284) (xy 123.222475 -177.984359) (xy 123.245424 -177.928955)
			(xy 123.275408 -177.877021) (xy 123.311914 -177.829445) (xy 123.354319 -177.78704) (xy 123.401895 -177.750534)
			(xy 123.453829 -177.72055) (xy 123.509233 -177.697601) (xy 123.567158 -177.68208) (xy 123.626614 -177.674252)
			(xy 123.686582 -177.674252) (xy 123.746038 -177.68208) (xy 123.803963 -177.697601) (xy 123.859367 -177.72055)
			(xy 123.911301 -177.750534) (xy 123.958877 -177.78704) (xy 124.001282 -177.829445) (xy 124.037788 -177.877021)
			(xy 124.067772 -177.928955) (xy 124.090721 -177.984359) (xy 124.106242 -178.042284) (xy 124.11407 -178.10174)
			(xy 124.11456 -178.131724) (xy 124.11456 -178.869086) (xy 141.546072 -178.869086) (xy 141.546072 -178.005486)
			(xy 141.546562 -177.975518) (xy 141.554385 -177.916096) (xy 141.569898 -177.858203) (xy 141.592834 -177.80283)
			(xy 141.622801 -177.750924) (xy 141.659288 -177.703374) (xy 141.701668 -177.660994) (xy 141.749218 -177.624507)
			(xy 141.801124 -177.59454) (xy 141.856497 -177.571604) (xy 141.91439 -177.556091) (xy 141.973812 -177.548268)
			(xy 142.033748 -177.548268) (xy 142.09317 -177.556091) (xy 142.151063 -177.571604) (xy 142.206436 -177.59454)
			(xy 142.258342 -177.624507) (xy 142.305892 -177.660994) (xy 142.348272 -177.703374) (xy 142.384759 -177.750924)
			(xy 142.414726 -177.80283) (xy 142.437662 -177.858203) (xy 142.453175 -177.916096) (xy 142.460998 -177.975518)
			(xy 142.461488 -178.005486) (xy 142.461488 -178.869086) (xy 142.460998 -178.899054) (xy 142.453175 -178.958476)
			(xy 142.437662 -179.016369) (xy 142.414726 -179.071742) (xy 142.384759 -179.123648) (xy 142.348272 -179.171198)
			(xy 142.305892 -179.213578) (xy 142.258342 -179.250065) (xy 142.206436 -179.280032) (xy 142.151063 -179.302968)
			(xy 142.09317 -179.318481) (xy 142.033748 -179.326304) (xy 141.973812 -179.326304) (xy 141.91439 -179.318481)
			(xy 141.856497 -179.302968) (xy 141.801124 -179.280032) (xy 141.749218 -179.250065) (xy 141.701668 -179.213578)
			(xy 141.659288 -179.171198) (xy 141.622801 -179.123648) (xy 141.592834 -179.071742) (xy 141.569898 -179.016369)
			(xy 141.554385 -178.958476) (xy 141.546562 -178.899054) (xy 141.546072 -178.869086) (xy 124.11456 -178.869086)
			(xy 124.11456 -178.995324) (xy 124.11407 -179.025308) (xy 124.106242 -179.084764) (xy 124.090721 -179.142689)
			(xy 124.067772 -179.198093) (xy 124.037788 -179.250027) (xy 124.001282 -179.297603) (xy 123.958877 -179.340008)
			(xy 123.911301 -179.376514) (xy 123.859367 -179.406498) (xy 123.803963 -179.429447) (xy 123.746038 -179.444968)
			(xy 123.686582 -179.452796) (xy 123.626614 -179.452796) (xy 123.567158 -179.444968) (xy 123.509233 -179.429447)
			(xy 123.453829 -179.406498) (xy 123.401895 -179.376514) (xy 123.354319 -179.340008) (xy 123.311914 -179.297603)
			(xy 123.275408 -179.250027) (xy 123.245424 -179.198093) (xy 123.222475 -179.142689) (xy 123.206954 -179.084764)
			(xy 123.199126 -179.025308) (xy 123.198636 -178.995324) (xy 4.30911 -178.995324) (xy 4.30911 -180.901086)
			(xy 142.181072 -180.901086) (xy 142.181072 -180.037486) (xy 142.181562 -180.007518) (xy 142.189385 -179.948096)
			(xy 142.204898 -179.890203) (xy 142.227834 -179.83483) (xy 142.257801 -179.782924) (xy 142.294288 -179.735374)
			(xy 142.336668 -179.692994) (xy 142.384218 -179.656507) (xy 142.436124 -179.62654) (xy 142.491497 -179.603604)
			(xy 142.54939 -179.588091) (xy 142.608812 -179.580268) (xy 142.668748 -179.580268) (xy 142.72817 -179.588091)
			(xy 142.786063 -179.603604) (xy 142.841436 -179.62654) (xy 142.893342 -179.656507) (xy 142.940892 -179.692994)
			(xy 142.983272 -179.735374) (xy 143.019759 -179.782924) (xy 143.049726 -179.83483) (xy 143.072662 -179.890203)
			(xy 143.088175 -179.948096) (xy 143.095998 -180.007518) (xy 143.096488 -180.037486) (xy 143.096488 -180.901086)
			(xy 143.095998 -180.931054) (xy 143.088175 -180.990476) (xy 143.072662 -181.048369) (xy 143.049726 -181.103742)
			(xy 143.019759 -181.155648) (xy 142.983272 -181.203198) (xy 142.940892 -181.245578) (xy 142.893342 -181.282065)
			(xy 142.841436 -181.312032) (xy 142.786063 -181.334968) (xy 142.72817 -181.350481) (xy 142.668748 -181.358304)
			(xy 142.608812 -181.358304) (xy 142.54939 -181.350481) (xy 142.491497 -181.334968) (xy 142.436124 -181.312032)
			(xy 142.384218 -181.282065) (xy 142.336668 -181.245578) (xy 142.294288 -181.203198) (xy 142.257801 -181.155648)
			(xy 142.227834 -181.103742) (xy 142.204898 -181.048369) (xy 142.189385 -180.990476) (xy 142.181562 -180.931054)
			(xy 142.181072 -180.901086) (xy 4.30911 -180.901086) (xy 4.30911 -182.933086) (xy 141.546072 -182.933086)
			(xy 141.546072 -182.069486) (xy 141.546562 -182.039518) (xy 141.554385 -181.980096) (xy 141.569898 -181.922203)
			(xy 141.592834 -181.86683) (xy 141.622801 -181.814924) (xy 141.659288 -181.767374) (xy 141.701668 -181.724994)
			(xy 141.749218 -181.688507) (xy 141.801124 -181.65854) (xy 141.856497 -181.635604) (xy 141.91439 -181.620091)
			(xy 141.973812 -181.612268) (xy 142.033748 -181.612268) (xy 142.09317 -181.620091) (xy 142.151063 -181.635604)
			(xy 142.206436 -181.65854) (xy 142.258342 -181.688507) (xy 142.305892 -181.724994) (xy 142.348272 -181.767374)
			(xy 142.384759 -181.814924) (xy 142.414726 -181.86683) (xy 142.437662 -181.922203) (xy 142.453175 -181.980096)
			(xy 142.460998 -182.039518) (xy 142.461488 -182.069486) (xy 142.461488 -182.933086) (xy 142.460998 -182.963054)
			(xy 142.453175 -183.022476) (xy 142.437662 -183.080369) (xy 142.414726 -183.135742) (xy 142.384759 -183.187648)
			(xy 142.348272 -183.235198) (xy 142.305892 -183.277578) (xy 142.258342 -183.314065) (xy 142.206436 -183.344032)
			(xy 142.151063 -183.366968) (xy 142.09317 -183.382481) (xy 142.033748 -183.390304) (xy 141.973812 -183.390304)
			(xy 141.91439 -183.382481) (xy 141.856497 -183.366968) (xy 141.801124 -183.344032) (xy 141.749218 -183.314065)
			(xy 141.701668 -183.277578) (xy 141.659288 -183.235198) (xy 141.622801 -183.187648) (xy 141.592834 -183.135742)
			(xy 141.569898 -183.080369) (xy 141.554385 -183.022476) (xy 141.546562 -182.963054) (xy 141.546072 -182.933086)
			(xy 4.30911 -182.933086) (xy 4.30911 -187.124582) (xy 135.58115 -187.124582) (xy 135.58115 -187.064618)
			(xy 135.588977 -187.005166) (xy 135.604497 -186.947244) (xy 135.627444 -186.891844) (xy 135.657426 -186.839912)
			(xy 135.69393 -186.792339) (xy 135.736331 -186.749937) (xy 135.783904 -186.713432) (xy 135.835835 -186.683448)
			(xy 135.891235 -186.6605) (xy 135.949156 -186.644979) (xy 136.008608 -186.637151) (xy 136.03859 -186.63666)
			(xy 136.90219 -186.63666) (xy 136.932178 -186.637085) (xy 136.99164 -186.644912) (xy 137.049571 -186.660433)
			(xy 137.104981 -186.683384) (xy 137.156922 -186.713371) (xy 137.204504 -186.749881) (xy 137.246913 -186.792289)
			(xy 137.283424 -186.83987) (xy 137.313412 -186.89181) (xy 137.336363 -186.947219) (xy 137.351886 -187.005151)
			(xy 137.359715 -187.064612) (xy 137.359715 -187.124588) (xy 137.351886 -187.184049) (xy 137.336363 -187.241981)
			(xy 137.313412 -187.29739) (xy 137.283424 -187.34933) (xy 137.246913 -187.396911) (xy 137.204504 -187.439319)
			(xy 137.156922 -187.475829) (xy 137.104981 -187.505816) (xy 137.049571 -187.528767) (xy 136.99164 -187.544288)
			(xy 136.932178 -187.552115) (xy 136.90219 -187.552584) (xy 136.03859 -187.552584) (xy 136.008608 -187.552049)
			(xy 135.949156 -187.544221) (xy 135.891235 -187.5287) (xy 135.835835 -187.505752) (xy 135.783904 -187.475768)
			(xy 135.736331 -187.439263) (xy 135.69393 -187.396861) (xy 135.657426 -187.349288) (xy 135.627444 -187.297356)
			(xy 135.604497 -187.241956) (xy 135.588977 -187.184034) (xy 135.58115 -187.124582) (xy 4.30911 -187.124582)
			(xy 4.30911 -188.252885) (xy 128.656818 -188.252885) (xy 128.656818 -188.192915) (xy 128.664646 -188.133459)
			(xy 128.680167 -188.075533) (xy 128.703116 -188.020128) (xy 128.733101 -187.968193) (xy 128.769608 -187.920615)
			(xy 128.812012 -187.87821) (xy 128.859589 -187.841703) (xy 128.911524 -187.811718) (xy 128.966929 -187.788768)
			(xy 129.024855 -187.773246) (xy 129.084311 -187.765418) (xy 129.114296 -187.764928) (xy 129.977896 -187.764928)
			(xy 130.007881 -187.765417) (xy 130.067339 -187.773244) (xy 130.125266 -187.788765) (xy 130.180671 -187.811714)
			(xy 130.232607 -187.841699) (xy 130.280185 -187.878207) (xy 130.322591 -187.920612) (xy 130.359098 -187.96819)
			(xy 130.389084 -188.020125) (xy 130.412034 -188.075531) (xy 130.427555 -188.133458) (xy 130.435383 -188.192915)
			(xy 130.435383 -188.252885) (xy 130.434185 -188.261981) (xy 131.046262 -188.261981) (xy 131.046262 -188.202019)
			(xy 131.054088 -188.14257) (xy 131.069607 -188.084651) (xy 131.092553 -188.029253) (xy 131.122533 -187.977324)
			(xy 131.159034 -187.929752) (xy 131.201432 -187.887351) (xy 131.249002 -187.850847) (xy 131.30093 -187.820864)
			(xy 131.356326 -187.797915) (xy 131.414244 -187.782393) (xy 131.473693 -187.774564) (xy 131.503674 -187.774072)
			(xy 132.367274 -187.774072) (xy 132.397263 -187.774472) (xy 132.456728 -187.782297) (xy 132.514663 -187.797818)
			(xy 132.570077 -187.820768) (xy 132.62202 -187.850755) (xy 132.669605 -187.887266) (xy 132.712017 -187.929675)
			(xy 132.74853 -187.977258) (xy 132.77852 -188.0292) (xy 132.801474 -188.084612) (xy 132.816998 -188.142546)
			(xy 132.824827 -188.202011) (xy 132.824827 -188.261989) (xy 132.816998 -188.321454) (xy 132.801474 -188.379388)
			(xy 132.79518 -188.394582) (xy 133.54915 -188.394582) (xy 133.54915 -188.334618) (xy 133.556977 -188.275166)
			(xy 133.572497 -188.217244) (xy 133.595444 -188.161844) (xy 133.625426 -188.109912) (xy 133.66193 -188.062339)
			(xy 133.704331 -188.019937) (xy 133.751904 -187.983432) (xy 133.803835 -187.953448) (xy 133.859235 -187.9305)
			(xy 133.917156 -187.914979) (xy 133.976608 -187.907151) (xy 134.00659 -187.90666) (xy 134.87019 -187.90666)
			(xy 134.900178 -187.907085) (xy 134.95964 -187.914912) (xy 135.017571 -187.930433) (xy 135.072981 -187.953384)
			(xy 135.124922 -187.983371) (xy 135.172504 -188.019881) (xy 135.214913 -188.062289) (xy 135.251424 -188.10987)
			(xy 135.281412 -188.16181) (xy 135.304363 -188.217219) (xy 135.319886 -188.275151) (xy 135.327715 -188.334612)
			(xy 135.327715 -188.394588) (xy 135.319886 -188.454049) (xy 135.304363 -188.511981) (xy 135.281412 -188.56739)
			(xy 135.251424 -188.61933) (xy 135.214913 -188.666911) (xy 135.172504 -188.709319) (xy 135.124922 -188.745829)
			(xy 135.072981 -188.775816) (xy 135.017571 -188.798767) (xy 134.95964 -188.814288) (xy 134.900178 -188.822115)
			(xy 134.87019 -188.822584) (xy 134.00659 -188.822584) (xy 133.976608 -188.822049) (xy 133.917156 -188.814221)
			(xy 133.859235 -188.7987) (xy 133.803835 -188.775752) (xy 133.751904 -188.745768) (xy 133.704331 -188.709263)
			(xy 133.66193 -188.666861) (xy 133.625426 -188.619288) (xy 133.595444 -188.567356) (xy 133.572497 -188.511956)
			(xy 133.556977 -188.454034) (xy 133.54915 -188.394582) (xy 132.79518 -188.394582) (xy 132.77852 -188.4348)
			(xy 132.74853 -188.486742) (xy 132.712017 -188.534325) (xy 132.669605 -188.576734) (xy 132.62202 -188.613245)
			(xy 132.570077 -188.643232) (xy 132.514663 -188.666182) (xy 132.456728 -188.681703) (xy 132.397263 -188.689528)
			(xy 132.367274 -188.689996) (xy 131.503674 -188.689996) (xy 131.473693 -188.689436) (xy 131.414244 -188.681607)
			(xy 131.356326 -188.666085) (xy 131.30093 -188.643136) (xy 131.249002 -188.613153) (xy 131.201432 -188.576649)
			(xy 131.159034 -188.534248) (xy 131.122533 -188.486676) (xy 131.092553 -188.434747) (xy 131.069607 -188.379349)
			(xy 131.054088 -188.32143) (xy 131.046262 -188.261981) (xy 130.434185 -188.261981) (xy 130.427555 -188.312342)
			(xy 130.412034 -188.370269) (xy 130.389084 -188.425675) (xy 130.359098 -188.47761) (xy 130.322591 -188.525188)
			(xy 130.280185 -188.567593) (xy 130.232607 -188.604101) (xy 130.180671 -188.634086) (xy 130.125266 -188.657035)
			(xy 130.067339 -188.672556) (xy 130.007881 -188.680383) (xy 129.977896 -188.680852) (xy 129.114296 -188.680852)
			(xy 129.084311 -188.680382) (xy 129.024855 -188.672554) (xy 128.966929 -188.657032) (xy 128.911524 -188.634082)
			(xy 128.859589 -188.604097) (xy 128.812012 -188.56759) (xy 128.769608 -188.525185) (xy 128.733101 -188.477607)
			(xy 128.703116 -188.425672) (xy 128.680167 -188.370267) (xy 128.664646 -188.312341) (xy 128.656818 -188.252885)
			(xy 4.30911 -188.252885) (xy 4.30911 -195.726088) (xy 126.922185 -195.726088) (xy 126.922185 -195.666112)
			(xy 126.930014 -195.606648) (xy 126.945538 -195.548715) (xy 126.968491 -195.493304) (xy 126.99848 -195.441364)
			(xy 127.034993 -195.393782) (xy 127.077404 -195.351373) (xy 127.124989 -195.314864) (xy 127.176931 -195.284878)
			(xy 127.232344 -195.261928) (xy 127.290278 -195.246408) (xy 127.349742 -195.238583) (xy 127.37973 -195.238116)
			(xy 128.24333 -195.238116) (xy 128.273312 -195.238652) (xy 128.332761 -195.246482) (xy 128.39068 -195.262005)
			(xy 128.446078 -195.284955) (xy 128.498007 -195.314939) (xy 128.545577 -195.351444) (xy 128.587976 -195.393845)
			(xy 128.624478 -195.441418) (xy 128.654459 -195.493349) (xy 128.677405 -195.548748) (xy 128.692924 -195.606668)
			(xy 128.70075 -195.666118) (xy 128.70075 -195.726082) (xy 128.692924 -195.785532) (xy 128.677405 -195.843452)
			(xy 128.654459 -195.898851) (xy 128.624478 -195.950782) (xy 128.587976 -195.998355) (xy 128.545577 -196.040756)
			(xy 128.498007 -196.077261) (xy 128.446078 -196.107245) (xy 128.39068 -196.130195) (xy 128.332761 -196.145718)
			(xy 128.273312 -196.153548) (xy 128.24333 -196.15404) (xy 127.37973 -196.15404) (xy 127.349742 -196.153617)
			(xy 127.290278 -196.145792) (xy 127.232344 -196.130272) (xy 127.176931 -196.107322) (xy 127.124989 -196.077336)
			(xy 127.077404 -196.040827) (xy 127.034993 -195.998418) (xy 126.99848 -195.950836) (xy 126.968491 -195.898896)
			(xy 126.945538 -195.843485) (xy 126.930014 -195.785552) (xy 126.922185 -195.726088) (xy 4.30911 -195.726088)
			(xy 4.30911 -198.543743) (xy 138.243774 -198.543743) (xy 138.24519 -198.489257) (xy 138.254343 -198.435528)
			(xy 138.271047 -198.383647) (xy 138.294963 -198.33467) (xy 138.325603 -198.289594) (xy 138.362344 -198.249336)
			(xy 138.40444 -198.214715) (xy 138.451033 -198.186434) (xy 138.501175 -198.165071) (xy 138.553847 -198.151058)
			(xy 138.607977 -198.144682) (xy 138.635232 -198.144892) (xy 138.636502 -198.144892) (xy 139.488672 -198.144892)
			(xy 139.515926 -198.145353) (xy 139.56988 -198.153107) (xy 139.622181 -198.168461) (xy 139.671765 -198.191102)
			(xy 139.717622 -198.220569) (xy 139.758818 -198.256263) (xy 139.794514 -198.297456) (xy 139.823985 -198.34331)
			(xy 139.846629 -198.392892) (xy 139.861987 -198.445192) (xy 139.869745 -198.499146) (xy 139.869745 -198.553654)
			(xy 139.861987 -198.607608) (xy 139.846629 -198.659908) (xy 139.823985 -198.70949) (xy 139.794514 -198.755344)
			(xy 139.758818 -198.796537) (xy 139.717622 -198.832231) (xy 139.671765 -198.861698) (xy 139.622181 -198.884339)
			(xy 139.56988 -198.899693) (xy 139.515926 -198.907447) (xy 139.488672 -198.907908) (xy 139.477343 -198.907862)
			(xy 139.454723 -198.90659) (xy 139.44346 -198.905368) (xy 139.440412 -198.90486) (xy 138.672824 -198.90486)
			(xy 138.669776 -198.905368) (xy 138.642662 -198.908134) (xy 138.588177 -198.906693) (xy 138.534452 -198.897514)
			(xy 138.482579 -198.880785) (xy 138.433613 -198.856847) (xy 138.388552 -198.826185) (xy 138.348311 -198.789424)
			(xy 138.31371 -198.747312) (xy 138.285452 -198.700706) (xy 138.264112 -198.650554) (xy 138.250125 -198.597875)
			(xy 138.243774 -198.543743) (xy 4.30911 -198.543743) (xy 4.30911 -201.379368) (xy 98.428551 -201.379368)
			(xy 98.428551 -201.324832) (xy 98.436313 -201.270851) (xy 98.451678 -201.218525) (xy 98.474333 -201.168917)
			(xy 98.503818 -201.123039) (xy 98.539531 -201.081824) (xy 98.580747 -201.046112) (xy 98.626626 -201.016628)
			(xy 98.676234 -200.993974) (xy 98.728561 -200.978611) (xy 98.782542 -200.970851) (xy 98.80981 -200.970388)
			(xy 99.67341 -200.970388) (xy 99.700682 -200.970775) (xy 99.754672 -200.978539) (xy 99.807007 -200.993907)
			(xy 99.856623 -201.016567) (xy 99.902508 -201.046057) (xy 99.94373 -201.081777) (xy 99.979449 -201.123)
			(xy 100.008938 -201.168886) (xy 100.031596 -201.218502) (xy 100.046963 -201.270838) (xy 100.054725 -201.324828)
			(xy 100.054725 -201.379372) (xy 100.046963 -201.433362) (xy 100.031596 -201.485698) (xy 100.008938 -201.535314)
			(xy 99.979449 -201.5812) (xy 99.94373 -201.622423) (xy 99.902508 -201.658143) (xy 99.856623 -201.687633)
			(xy 99.807007 -201.710293) (xy 99.754672 -201.725661) (xy 99.700682 -201.733425) (xy 99.67341 -201.733912)
			(xy 98.80981 -201.733912) (xy 98.782542 -201.733349) (xy 98.728561 -201.725589) (xy 98.676234 -201.710226)
			(xy 98.626626 -201.687572) (xy 98.580747 -201.658088) (xy 98.539531 -201.622376) (xy 98.503818 -201.581161)
			(xy 98.474333 -201.535283) (xy 98.451678 -201.485675) (xy 98.436313 -201.433349) (xy 98.428551 -201.379368)
			(xy 4.30911 -201.379368) (xy 4.30911 -209.380836) (xy 445.288416 -209.380836) (xy 445.288416 -208.517236)
			(xy 445.288906 -208.487268) (xy 445.296729 -208.427846) (xy 445.312242 -208.369953) (xy 445.335178 -208.31458)
			(xy 445.365145 -208.262674) (xy 445.401632 -208.215124) (xy 445.444012 -208.172744) (xy 445.491562 -208.136257)
			(xy 445.543468 -208.10629) (xy 445.598841 -208.083354) (xy 445.656734 -208.067841) (xy 445.716156 -208.060018)
			(xy 445.776092 -208.060018) (xy 445.835514 -208.067841) (xy 445.893407 -208.083354) (xy 445.94878 -208.10629)
			(xy 446.000686 -208.136257) (xy 446.048236 -208.172744) (xy 446.090616 -208.215124) (xy 446.127103 -208.262674)
			(xy 446.15707 -208.31458) (xy 446.180006 -208.369953) (xy 446.195519 -208.427846) (xy 446.203342 -208.487268)
			(xy 446.203832 -208.517236) (xy 446.203832 -209.380836) (xy 446.203342 -209.410804) (xy 446.195519 -209.470226)
			(xy 446.180006 -209.528119) (xy 446.15707 -209.583492) (xy 446.127103 -209.635398) (xy 446.090616 -209.682948)
			(xy 446.048236 -209.725328) (xy 446.000686 -209.761815) (xy 445.94878 -209.791782) (xy 445.893407 -209.814718)
			(xy 445.835514 -209.830231) (xy 445.776092 -209.838054) (xy 445.716156 -209.838054) (xy 445.656734 -209.830231)
			(xy 445.598841 -209.814718) (xy 445.543468 -209.791782) (xy 445.491562 -209.761815) (xy 445.444012 -209.725328)
			(xy 445.401632 -209.682948) (xy 445.365145 -209.635398) (xy 445.335178 -209.583492) (xy 445.312242 -209.528119)
			(xy 445.296729 -209.470226) (xy 445.288906 -209.410804) (xy 445.288416 -209.380836) (xy 4.30911 -209.380836)
			(xy 4.30911 -225.261473) (xy 239.822113 -225.261473) (xy 239.822113 -225.201527) (xy 239.829938 -225.142093)
			(xy 239.845454 -225.084189) (xy 239.868395 -225.028806) (xy 239.89837 -224.976891) (xy 239.934864 -224.929333)
			(xy 239.977254 -224.886945) (xy 240.024814 -224.850454) (xy 240.076731 -224.820483) (xy 240.132115 -224.797545)
			(xy 240.19002 -224.782032) (xy 240.249455 -224.774211) (xy 240.279428 -224.773744) (xy 241.143028 -224.773744)
			(xy 241.172991 -224.774332) (xy 241.232405 -224.782157) (xy 241.290289 -224.79767) (xy 241.345653 -224.820606)
			(xy 241.39755 -224.850571) (xy 241.445091 -224.887054) (xy 241.487465 -224.92943) (xy 241.523944 -224.976974)
			(xy 241.553907 -225.028872) (xy 241.576839 -225.084238) (xy 241.592348 -225.142123) (xy 241.60017 -225.201537)
			(xy 241.60017 -225.261463) (xy 241.592348 -225.320877) (xy 241.576839 -225.378762) (xy 241.553907 -225.434128)
			(xy 241.523944 -225.486026) (xy 241.487465 -225.53357) (xy 241.445091 -225.575946) (xy 241.39755 -225.612429)
			(xy 241.345653 -225.642394) (xy 241.290289 -225.66533) (xy 241.232405 -225.680843) (xy 241.172991 -225.688668)
			(xy 241.143028 -225.68916) (xy 240.279428 -225.68916) (xy 240.249455 -225.688789) (xy 240.19002 -225.680968)
			(xy 240.132115 -225.665455) (xy 240.076731 -225.642517) (xy 240.024814 -225.612546) (xy 239.977254 -225.576055)
			(xy 239.934864 -225.533667) (xy 239.89837 -225.486109) (xy 239.868395 -225.434194) (xy 239.845454 -225.378811)
			(xy 239.829938 -225.320907) (xy 239.822113 -225.261473) (xy 4.30911 -225.261473) (xy 4.30911 -230.903589)
			(xy 383.216061 -230.903589) (xy 383.216061 -230.843611) (xy 383.22389 -230.784147) (xy 383.239413 -230.726213)
			(xy 383.262366 -230.670801) (xy 383.292355 -230.618858) (xy 383.328867 -230.571275) (xy 383.371278 -230.528865)
			(xy 383.418862 -230.492353) (xy 383.470804 -230.462364) (xy 383.526216 -230.439412) (xy 383.584151 -230.423889)
			(xy 383.643615 -230.416061) (xy 383.673604 -230.415592) (xy 384.537204 -230.415592) (xy 384.567185 -230.416174)
			(xy 384.626634 -230.424001) (xy 384.684553 -230.439521) (xy 384.739951 -230.462468) (xy 384.79188 -230.492449)
			(xy 384.839451 -230.528952) (xy 384.88185 -230.571352) (xy 384.918353 -230.618924) (xy 384.948334 -230.670853)
			(xy 384.97128 -230.726251) (xy 384.986799 -230.78417) (xy 384.994626 -230.843619) (xy 384.994626 -230.903581)
			(xy 384.986799 -230.96303) (xy 384.97128 -231.020949) (xy 384.948334 -231.076347) (xy 384.918353 -231.128276)
			(xy 384.88185 -231.175848) (xy 384.839451 -231.218248) (xy 384.79188 -231.254751) (xy 384.739951 -231.284732)
			(xy 384.684553 -231.307679) (xy 384.626634 -231.323199) (xy 384.567185 -231.331026) (xy 384.537204 -231.331516)
			(xy 383.673604 -231.331516) (xy 383.643615 -231.331139) (xy 383.584151 -231.323311) (xy 383.526216 -231.307788)
			(xy 383.470804 -231.284836) (xy 383.418862 -231.254847) (xy 383.371278 -231.218335) (xy 383.328867 -231.175925)
			(xy 383.292355 -231.128342) (xy 383.262366 -231.076399) (xy 383.239413 -231.020987) (xy 383.22389 -230.963053)
			(xy 383.216061 -230.903589) (xy 4.30911 -230.903589) (xy 4.30911 -234.655869) (xy 448.021157 -234.655869)
			(xy 448.021157 -234.595931) (xy 448.028981 -234.536505) (xy 448.044494 -234.478608) (xy 448.067432 -234.423232)
			(xy 448.097401 -234.371324) (xy 448.13389 -234.323771) (xy 448.176273 -234.281388) (xy 448.223825 -234.2449)
			(xy 448.275734 -234.214931) (xy 448.33111 -234.191993) (xy 448.389007 -234.17648) (xy 448.448433 -234.168657)
			(xy 448.478402 -234.168188) (xy 449.342002 -234.168188) (xy 449.371969 -234.168686) (xy 449.431391 -234.176509)
			(xy 449.489283 -234.192022) (xy 449.544656 -234.214958) (xy 449.596561 -234.244925) (xy 449.64411 -234.281411)
			(xy 449.68649 -234.323792) (xy 449.722976 -234.371341) (xy 449.752943 -234.423246) (xy 449.775879 -234.478618)
			(xy 449.791391 -234.536511) (xy 449.799214 -234.595933) (xy 449.799214 -234.655867) (xy 449.791391 -234.715289)
			(xy 449.775879 -234.773182) (xy 449.752943 -234.828554) (xy 449.722976 -234.880459) (xy 449.68649 -234.928008)
			(xy 449.64411 -234.970389) (xy 449.596561 -235.006875) (xy 449.544656 -235.036842) (xy 449.489283 -235.059778)
			(xy 449.431391 -235.075291) (xy 449.371969 -235.083114) (xy 449.342002 -235.083604) (xy 448.478402 -235.083604)
			(xy 448.448433 -235.083143) (xy 448.389007 -235.07532) (xy 448.33111 -235.059807) (xy 448.275734 -235.036869)
			(xy 448.223825 -235.0069) (xy 448.176273 -234.970412) (xy 448.13389 -234.928029) (xy 448.097401 -234.880476)
			(xy 448.067432 -234.828568) (xy 448.044494 -234.773192) (xy 448.028981 -234.715295) (xy 448.021157 -234.655869)
			(xy 4.30911 -234.655869) (xy 4.30911 -239.07907) (xy 153.398934 -239.07907) (xy 153.398934 -239.01913)
			(xy 153.406758 -238.959703) (xy 153.422271 -238.901805) (xy 153.445208 -238.846427) (xy 153.475178 -238.794517)
			(xy 153.511666 -238.746963) (xy 153.554049 -238.704578) (xy 153.601602 -238.668088) (xy 153.653511 -238.638116)
			(xy 153.708888 -238.615177) (xy 153.766785 -238.599661) (xy 153.826212 -238.591835) (xy 153.856182 -238.591344)
			(xy 154.719782 -238.591344) (xy 154.749749 -238.591908) (xy 154.809169 -238.599729) (xy 154.867061 -238.615239)
			(xy 154.922433 -238.638172) (xy 154.974337 -238.668138) (xy 155.021886 -238.704622) (xy 155.064267 -238.747)
			(xy 155.100752 -238.794548) (xy 155.13072 -238.846451) (xy 155.153656 -238.901822) (xy 155.169168 -238.959713)
			(xy 155.176991 -239.019133) (xy 155.176991 -239.079067) (xy 155.169168 -239.138487) (xy 155.153656 -239.196378)
			(xy 155.13072 -239.251749) (xy 155.100752 -239.303652) (xy 155.064267 -239.3512) (xy 155.021886 -239.393578)
			(xy 154.974337 -239.430062) (xy 154.922433 -239.460028) (xy 154.867061 -239.482961) (xy 154.809169 -239.498471)
			(xy 154.749749 -239.506292) (xy 154.719782 -239.50676) (xy 153.856182 -239.50676) (xy 153.826212 -239.506365)
			(xy 153.766785 -239.498539) (xy 153.708888 -239.483023) (xy 153.653511 -239.460084) (xy 153.601602 -239.430112)
			(xy 153.554049 -239.393622) (xy 153.511666 -239.351237) (xy 153.475178 -239.303683) (xy 153.445208 -239.251773)
			(xy 153.422271 -239.196395) (xy 153.406758 -239.138497) (xy 153.398934 -239.07907) (xy 4.30911 -239.07907)
			(xy 4.30911 -241.031522) (xy 4.308609 -241.101909) (xy 4.300702 -241.24246) (xy 4.284927 -241.382347)
			(xy 4.261334 -241.521129) (xy 4.229996 -241.65837) (xy 4.191013 -241.793638) (xy 4.144506 -241.926507)
			(xy 4.090623 -242.05656) (xy 4.029533 -242.183387) (xy 3.961428 -242.30659) (xy 3.886522 -242.42578)
			(xy 3.805051 -242.540582) (xy 3.717272 -242.650636) (xy 3.623459 -242.755596) (xy 3.574034 -242.805712)
			(xy 0.945642 -245.434104) (xy 0.908331 -245.472065) (xy 0.838615 -245.55251) (xy 0.774816 -245.637725)
			(xy 0.717261 -245.727274) (xy 0.666242 -245.820703) (xy 0.62202 -245.917533) (xy 0.584819 -246.017272)
			(xy 0.554831 -246.119412) (xy 0.532207 -246.22343) (xy 0.517063 -246.328799) (xy 0.509476 -246.434979)
			(xy 0.509016 -246.488204) (xy 0.509016 -270.89989) (xy 26.882353 -270.89989) (xy 26.886342 -270.75135)
			(xy 26.898299 -270.603237) (xy 26.918189 -270.45598) (xy 26.945954 -270.310004) (xy 26.981515 -270.165727)
			(xy 27.024769 -270.023568) (xy 27.075591 -269.883935) (xy 27.133835 -269.747232) (xy 27.199333 -269.613852)
			(xy 27.271896 -269.48418) (xy 27.351314 -269.35859) (xy 27.437359 -269.237443) (xy 27.529783 -269.12109)
			(xy 27.628319 -269.009866) (xy 27.732683 -268.904091) (xy 27.842575 -268.804071) (xy 27.957676 -268.710093)
			(xy 28.077656 -268.622429) (xy 28.202169 -268.541332) (xy 28.330855 -268.467035) (xy 28.463344 -268.399753)
			(xy 28.599253 -268.339679) (xy 28.738191 -268.286987) (xy 28.879757 -268.241828) (xy 29.023543 -268.204333)
			(xy 29.169134 -268.174611) (xy 29.31611 -268.152746) (xy 29.464049 -268.138802) (xy 29.612522 -268.132818)
			(xy 29.761103 -268.134813) (xy 29.909362 -268.144781) (xy 30.056873 -268.162692) (xy 30.203209 -268.188495)
			(xy 30.34795 -268.222115) (xy 30.490677 -268.263457) (xy 30.63098 -268.3124) (xy 30.768453 -268.368803)
			(xy 30.9027 -268.432504) (xy 31.033335 -268.50332) (xy 31.15998 -268.581045) (xy 31.28227 -268.665456)
			(xy 31.399853 -268.756309) (xy 31.51239 -268.853343) (xy 31.619557 -268.956278) (xy 31.721044 -269.064817)
			(xy 31.816558 -269.178646) (xy 31.905825 -269.297439) (xy 31.988586 -269.420851) (xy 32.064604 -269.548529)
			(xy 32.133659 -269.680102) (xy 32.195552 -269.815193) (xy 32.250105 -269.95341) (xy 32.29716 -270.094357)
			(xy 32.336582 -270.237627) (xy 32.368256 -270.382806) (xy 32.392092 -270.529475) (xy 32.408021 -270.677213)
			(xy 32.415997 -270.825593) (xy 32.416496 -270.89989) (xy 86.882487 -270.89989) (xy 86.886476 -270.75135)
			(xy 86.898433 -270.603237) (xy 86.918323 -270.45598) (xy 86.946088 -270.310004) (xy 86.981649 -270.165727)
			(xy 87.024903 -270.023568) (xy 87.075725 -269.883935) (xy 87.133969 -269.747232) (xy 87.199467 -269.613852)
			(xy 87.27203 -269.48418) (xy 87.351448 -269.35859) (xy 87.437493 -269.237443) (xy 87.529917 -269.12109)
			(xy 87.628453 -269.009866) (xy 87.732817 -268.904091) (xy 87.842709 -268.804071) (xy 87.95781 -268.710093)
			(xy 88.07779 -268.622429) (xy 88.202303 -268.541332) (xy 88.330989 -268.467035) (xy 88.463478 -268.399753)
			(xy 88.599387 -268.339679) (xy 88.738325 -268.286987) (xy 88.879891 -268.241828) (xy 89.023677 -268.204333)
			(xy 89.169268 -268.174611) (xy 89.316244 -268.152746) (xy 89.464183 -268.138802) (xy 89.612656 -268.132818)
			(xy 89.761237 -268.134813) (xy 89.909496 -268.144781) (xy 90.057007 -268.162692) (xy 90.203343 -268.188495)
			(xy 90.348084 -268.222115) (xy 90.490811 -268.263457) (xy 90.631114 -268.3124) (xy 90.768587 -268.368803)
			(xy 90.902834 -268.432504) (xy 91.033469 -268.50332) (xy 91.160114 -268.581045) (xy 91.282404 -268.665456)
			(xy 91.399987 -268.756309) (xy 91.512524 -268.853343) (xy 91.619691 -268.956278) (xy 91.721178 -269.064817)
			(xy 91.816692 -269.178646) (xy 91.905959 -269.297439) (xy 91.98872 -269.420851) (xy 92.064738 -269.548529)
			(xy 92.133793 -269.680102) (xy 92.195686 -269.815193) (xy 92.250239 -269.95341) (xy 92.297294 -270.094357)
			(xy 92.336716 -270.237627) (xy 92.36839 -270.382806) (xy 92.392226 -270.529475) (xy 92.408155 -270.677213)
			(xy 92.416131 -270.825593) (xy 92.41663 -270.89989) (xy 142.982451 -270.89989) (xy 142.98644 -270.75135)
			(xy 142.998397 -270.603237) (xy 143.018287 -270.45598) (xy 143.046052 -270.310004) (xy 143.081613 -270.165727)
			(xy 143.124867 -270.023568) (xy 143.175689 -269.883935) (xy 143.233933 -269.747232) (xy 143.299431 -269.613852)
			(xy 143.371994 -269.48418) (xy 143.451412 -269.35859) (xy 143.537457 -269.237443) (xy 143.629881 -269.12109)
			(xy 143.728417 -269.009866) (xy 143.832781 -268.904091) (xy 143.942673 -268.804071) (xy 144.057774 -268.710093)
			(xy 144.177754 -268.622429) (xy 144.302267 -268.541332) (xy 144.430953 -268.467035) (xy 144.563442 -268.399753)
			(xy 144.699351 -268.339679) (xy 144.838289 -268.286987) (xy 144.979855 -268.241828) (xy 145.123641 -268.204333)
			(xy 145.269232 -268.174611) (xy 145.416208 -268.152746) (xy 145.564147 -268.138802) (xy 145.71262 -268.132818)
			(xy 145.861201 -268.134813) (xy 146.00946 -268.144781) (xy 146.156971 -268.162692) (xy 146.303307 -268.188495)
			(xy 146.448048 -268.222115) (xy 146.590775 -268.263457) (xy 146.731078 -268.3124) (xy 146.868551 -268.368803)
			(xy 147.002798 -268.432504) (xy 147.133433 -268.50332) (xy 147.260078 -268.581045) (xy 147.382368 -268.665456)
			(xy 147.499951 -268.756309) (xy 147.612488 -268.853343) (xy 147.719655 -268.956278) (xy 147.821142 -269.064817)
			(xy 147.916656 -269.178646) (xy 148.005923 -269.297439) (xy 148.088684 -269.420851) (xy 148.164702 -269.548529)
			(xy 148.233757 -269.680102) (xy 148.29565 -269.815193) (xy 148.350203 -269.95341) (xy 148.397258 -270.094357)
			(xy 148.43668 -270.237627) (xy 148.468354 -270.382806) (xy 148.49219 -270.529475) (xy 148.508119 -270.677213)
			(xy 148.516095 -270.825593) (xy 148.516594 -270.89989) (xy 202.982331 -270.89989) (xy 202.98632 -270.75135)
			(xy 202.998277 -270.603237) (xy 203.018167 -270.45598) (xy 203.045932 -270.310004) (xy 203.081493 -270.165727)
			(xy 203.124747 -270.023568) (xy 203.175569 -269.883935) (xy 203.233813 -269.747232) (xy 203.299311 -269.613852)
			(xy 203.371874 -269.48418) (xy 203.451292 -269.35859) (xy 203.537337 -269.237443) (xy 203.629761 -269.12109)
			(xy 203.728297 -269.009866) (xy 203.832661 -268.904091) (xy 203.942553 -268.804071) (xy 204.057654 -268.710093)
			(xy 204.177634 -268.622429) (xy 204.302147 -268.541332) (xy 204.430833 -268.467035) (xy 204.563322 -268.399753)
			(xy 204.699231 -268.339679) (xy 204.838169 -268.286987) (xy 204.979735 -268.241828) (xy 205.123521 -268.204333)
			(xy 205.269112 -268.174611) (xy 205.416088 -268.152746) (xy 205.564027 -268.138802) (xy 205.7125 -268.132818)
			(xy 205.861081 -268.134813) (xy 206.00934 -268.144781) (xy 206.156851 -268.162692) (xy 206.303187 -268.188495)
			(xy 206.447928 -268.222115) (xy 206.590655 -268.263457) (xy 206.730958 -268.3124) (xy 206.868431 -268.368803)
			(xy 207.002678 -268.432504) (xy 207.133313 -268.50332) (xy 207.259958 -268.581045) (xy 207.382248 -268.665456)
			(xy 207.499831 -268.756309) (xy 207.612368 -268.853343) (xy 207.719535 -268.956278) (xy 207.821022 -269.064817)
			(xy 207.916536 -269.178646) (xy 208.005803 -269.297439) (xy 208.088564 -269.420851) (xy 208.164582 -269.548529)
			(xy 208.233637 -269.680102) (xy 208.29553 -269.815193) (xy 208.350083 -269.95341) (xy 208.397138 -270.094357)
			(xy 208.43656 -270.237627) (xy 208.468234 -270.382806) (xy 208.49207 -270.529475) (xy 208.507999 -270.677213)
			(xy 208.515975 -270.825593) (xy 208.516474 -270.89989) (xy 259.082549 -270.89989) (xy 259.086538 -270.75135)
			(xy 259.098495 -270.603237) (xy 259.118385 -270.45598) (xy 259.14615 -270.310004) (xy 259.181711 -270.165727)
			(xy 259.224965 -270.023568) (xy 259.275787 -269.883935) (xy 259.334031 -269.747232) (xy 259.399529 -269.613852)
			(xy 259.472092 -269.48418) (xy 259.55151 -269.35859) (xy 259.637555 -269.237443) (xy 259.729979 -269.12109)
			(xy 259.828515 -269.009866) (xy 259.932879 -268.904091) (xy 260.042771 -268.804071) (xy 260.157872 -268.710093)
			(xy 260.277852 -268.622429) (xy 260.402365 -268.541332) (xy 260.531051 -268.467035) (xy 260.66354 -268.399753)
			(xy 260.799449 -268.339679) (xy 260.938387 -268.286987) (xy 261.079953 -268.241828) (xy 261.223739 -268.204333)
			(xy 261.36933 -268.174611) (xy 261.516306 -268.152746) (xy 261.664245 -268.138802) (xy 261.812718 -268.132818)
			(xy 261.961299 -268.134813) (xy 262.109558 -268.144781) (xy 262.257069 -268.162692) (xy 262.403405 -268.188495)
			(xy 262.548146 -268.222115) (xy 262.690873 -268.263457) (xy 262.831176 -268.3124) (xy 262.968649 -268.368803)
			(xy 263.102896 -268.432504) (xy 263.233531 -268.50332) (xy 263.360176 -268.581045) (xy 263.482466 -268.665456)
			(xy 263.600049 -268.756309) (xy 263.712586 -268.853343) (xy 263.819753 -268.956278) (xy 263.92124 -269.064817)
			(xy 264.016754 -269.178646) (xy 264.106021 -269.297439) (xy 264.188782 -269.420851) (xy 264.2648 -269.548529)
			(xy 264.333855 -269.680102) (xy 264.395748 -269.815193) (xy 264.450301 -269.95341) (xy 264.497356 -270.094357)
			(xy 264.536778 -270.237627) (xy 264.568452 -270.382806) (xy 264.592288 -270.529475) (xy 264.608217 -270.677213)
			(xy 264.616193 -270.825593) (xy 264.616692 -270.89989) (xy 319.082429 -270.89989) (xy 319.086418 -270.75135)
			(xy 319.098375 -270.603237) (xy 319.118265 -270.45598) (xy 319.14603 -270.310004) (xy 319.181591 -270.165727)
			(xy 319.224845 -270.023568) (xy 319.275667 -269.883935) (xy 319.333911 -269.747232) (xy 319.399409 -269.613852)
			(xy 319.471972 -269.48418) (xy 319.55139 -269.35859) (xy 319.637435 -269.237443) (xy 319.729859 -269.12109)
			(xy 319.828395 -269.009866) (xy 319.932759 -268.904091) (xy 320.042651 -268.804071) (xy 320.157752 -268.710093)
			(xy 320.277732 -268.622429) (xy 320.402245 -268.541332) (xy 320.530931 -268.467035) (xy 320.66342 -268.399753)
			(xy 320.799329 -268.339679) (xy 320.938267 -268.286987) (xy 321.079833 -268.241828) (xy 321.223619 -268.204333)
			(xy 321.36921 -268.174611) (xy 321.516186 -268.152746) (xy 321.664125 -268.138802) (xy 321.812598 -268.132818)
			(xy 321.961179 -268.134813) (xy 322.109438 -268.144781) (xy 322.256949 -268.162692) (xy 322.403285 -268.188495)
			(xy 322.548026 -268.222115) (xy 322.690753 -268.263457) (xy 322.831056 -268.3124) (xy 322.968529 -268.368803)
			(xy 323.102776 -268.432504) (xy 323.233411 -268.50332) (xy 323.360056 -268.581045) (xy 323.482346 -268.665456)
			(xy 323.599929 -268.756309) (xy 323.712466 -268.853343) (xy 323.819633 -268.956278) (xy 323.92112 -269.064817)
			(xy 324.016634 -269.178646) (xy 324.105901 -269.297439) (xy 324.188662 -269.420851) (xy 324.26468 -269.548529)
			(xy 324.333735 -269.680102) (xy 324.395628 -269.815193) (xy 324.450181 -269.95341) (xy 324.497236 -270.094357)
			(xy 324.536658 -270.237627) (xy 324.568332 -270.382806) (xy 324.592168 -270.529475) (xy 324.608097 -270.677213)
			(xy 324.616073 -270.825593) (xy 324.616572 -270.89989) (xy 375.182393 -270.89989) (xy 375.186382 -270.75135)
			(xy 375.198339 -270.603237) (xy 375.218229 -270.45598) (xy 375.245994 -270.310004) (xy 375.281555 -270.165727)
			(xy 375.324809 -270.023568) (xy 375.375631 -269.883935) (xy 375.433875 -269.747232) (xy 375.499373 -269.613852)
			(xy 375.571936 -269.48418) (xy 375.651354 -269.35859) (xy 375.737399 -269.237443) (xy 375.829823 -269.12109)
			(xy 375.928359 -269.009866) (xy 376.032723 -268.904091) (xy 376.142615 -268.804071) (xy 376.257716 -268.710093)
			(xy 376.377696 -268.622429) (xy 376.502209 -268.541332) (xy 376.630895 -268.467035) (xy 376.763384 -268.399753)
			(xy 376.899293 -268.339679) (xy 377.038231 -268.286987) (xy 377.179797 -268.241828) (xy 377.323583 -268.204333)
			(xy 377.469174 -268.174611) (xy 377.61615 -268.152746) (xy 377.764089 -268.138802) (xy 377.912562 -268.132818)
			(xy 378.061143 -268.134813) (xy 378.209402 -268.144781) (xy 378.356913 -268.162692) (xy 378.503249 -268.188495)
			(xy 378.64799 -268.222115) (xy 378.790717 -268.263457) (xy 378.93102 -268.3124) (xy 379.068493 -268.368803)
			(xy 379.20274 -268.432504) (xy 379.333375 -268.50332) (xy 379.46002 -268.581045) (xy 379.58231 -268.665456)
			(xy 379.699893 -268.756309) (xy 379.81243 -268.853343) (xy 379.919597 -268.956278) (xy 380.021084 -269.064817)
			(xy 380.116598 -269.178646) (xy 380.205865 -269.297439) (xy 380.288626 -269.420851) (xy 380.364644 -269.548529)
			(xy 380.433699 -269.680102) (xy 380.495592 -269.815193) (xy 380.550145 -269.95341) (xy 380.5972 -270.094357)
			(xy 380.636622 -270.237627) (xy 380.668296 -270.382806) (xy 380.692132 -270.529475) (xy 380.708061 -270.677213)
			(xy 380.716037 -270.825593) (xy 380.716536 -270.89989) (xy 435.182527 -270.89989) (xy 435.186516 -270.75135)
			(xy 435.198473 -270.603237) (xy 435.218363 -270.45598) (xy 435.246128 -270.310004) (xy 435.281689 -270.165727)
			(xy 435.324943 -270.023568) (xy 435.375765 -269.883935) (xy 435.434009 -269.747232) (xy 435.499507 -269.613852)
			(xy 435.57207 -269.48418) (xy 435.651488 -269.35859) (xy 435.737533 -269.237443) (xy 435.829957 -269.12109)
			(xy 435.928493 -269.009866) (xy 436.032857 -268.904091) (xy 436.142749 -268.804071) (xy 436.25785 -268.710093)
			(xy 436.37783 -268.622429) (xy 436.502343 -268.541332) (xy 436.631029 -268.467035) (xy 436.763518 -268.399753)
			(xy 436.899427 -268.339679) (xy 437.038365 -268.286987) (xy 437.179931 -268.241828) (xy 437.323717 -268.204333)
			(xy 437.469308 -268.174611) (xy 437.616284 -268.152746) (xy 437.764223 -268.138802) (xy 437.912696 -268.132818)
			(xy 438.061277 -268.134813) (xy 438.209536 -268.144781) (xy 438.357047 -268.162692) (xy 438.503383 -268.188495)
			(xy 438.648124 -268.222115) (xy 438.790851 -268.263457) (xy 438.931154 -268.3124) (xy 439.068627 -268.368803)
			(xy 439.202874 -268.432504) (xy 439.333509 -268.50332) (xy 439.460154 -268.581045) (xy 439.582444 -268.665456)
			(xy 439.700027 -268.756309) (xy 439.812564 -268.853343) (xy 439.919731 -268.956278) (xy 440.021218 -269.064817)
			(xy 440.116732 -269.178646) (xy 440.205999 -269.297439) (xy 440.28876 -269.420851) (xy 440.364778 -269.548529)
			(xy 440.433833 -269.680102) (xy 440.495726 -269.815193) (xy 440.550279 -269.95341) (xy 440.597334 -270.094357)
			(xy 440.636756 -270.237627) (xy 440.66843 -270.382806) (xy 440.692266 -270.529475) (xy 440.708195 -270.677213)
			(xy 440.716171 -270.825593) (xy 440.71667 -270.89989) (xy 440.716171 -270.974187) (xy 440.708195 -271.122567)
			(xy 440.692266 -271.270305) (xy 440.66843 -271.416974) (xy 440.636756 -271.562153) (xy 440.597334 -271.705423)
			(xy 440.550279 -271.84637) (xy 440.495726 -271.984587) (xy 440.433833 -272.119678) (xy 440.364778 -272.251251)
			(xy 440.28876 -272.378929) (xy 440.205999 -272.502341) (xy 440.116732 -272.621134) (xy 440.021218 -272.734963)
			(xy 439.919731 -272.843502) (xy 439.812564 -272.946437) (xy 439.700027 -273.043471) (xy 439.582444 -273.134324)
			(xy 439.460154 -273.218735) (xy 439.333509 -273.29646) (xy 439.202874 -273.367276) (xy 439.068627 -273.430977)
			(xy 438.931154 -273.48738) (xy 438.790851 -273.536323) (xy 438.648124 -273.577665) (xy 438.503383 -273.611285)
			(xy 438.357047 -273.637088) (xy 438.209536 -273.654999) (xy 438.061277 -273.664967) (xy 437.912696 -273.666962)
			(xy 437.764223 -273.660978) (xy 437.616284 -273.647034) (xy 437.469308 -273.625169) (xy 437.323717 -273.595447)
			(xy 437.179931 -273.557952) (xy 437.038365 -273.512793) (xy 436.899427 -273.460101) (xy 436.763518 -273.400027)
			(xy 436.631029 -273.332745) (xy 436.502343 -273.258448) (xy 436.37783 -273.177351) (xy 436.25785 -273.089687)
			(xy 436.142749 -272.995709) (xy 436.032857 -272.895689) (xy 435.928493 -272.789914) (xy 435.829957 -272.67869)
			(xy 435.737533 -272.562337) (xy 435.651488 -272.44119) (xy 435.57207 -272.3156) (xy 435.499507 -272.185928)
			(xy 435.434009 -272.052548) (xy 435.375765 -271.915845) (xy 435.324943 -271.776212) (xy 435.281689 -271.634053)
			(xy 435.246128 -271.489776) (xy 435.218363 -271.3438) (xy 435.198473 -271.196543) (xy 435.186516 -271.04843)
			(xy 435.182527 -270.89989) (xy 380.716536 -270.89989) (xy 380.716037 -270.974187) (xy 380.708061 -271.122567)
			(xy 380.692132 -271.270305) (xy 380.668296 -271.416974) (xy 380.636622 -271.562153) (xy 380.5972 -271.705423)
			(xy 380.550145 -271.84637) (xy 380.495592 -271.984587) (xy 380.433699 -272.119678) (xy 380.364644 -272.251251)
			(xy 380.288626 -272.378929) (xy 380.205865 -272.502341) (xy 380.116598 -272.621134) (xy 380.021084 -272.734963)
			(xy 379.919597 -272.843502) (xy 379.81243 -272.946437) (xy 379.699893 -273.043471) (xy 379.58231 -273.134324)
			(xy 379.46002 -273.218735) (xy 379.333375 -273.29646) (xy 379.20274 -273.367276) (xy 379.068493 -273.430977)
			(xy 378.93102 -273.48738) (xy 378.790717 -273.536323) (xy 378.64799 -273.577665) (xy 378.503249 -273.611285)
			(xy 378.356913 -273.637088) (xy 378.209402 -273.654999) (xy 378.061143 -273.664967) (xy 377.912562 -273.666962)
			(xy 377.764089 -273.660978) (xy 377.61615 -273.647034) (xy 377.469174 -273.625169) (xy 377.323583 -273.595447)
			(xy 377.179797 -273.557952) (xy 377.038231 -273.512793) (xy 376.899293 -273.460101) (xy 376.763384 -273.400027)
			(xy 376.630895 -273.332745) (xy 376.502209 -273.258448) (xy 376.377696 -273.177351) (xy 376.257716 -273.089687)
			(xy 376.142615 -272.995709) (xy 376.032723 -272.895689) (xy 375.928359 -272.789914) (xy 375.829823 -272.67869)
			(xy 375.737399 -272.562337) (xy 375.651354 -272.44119) (xy 375.571936 -272.3156) (xy 375.499373 -272.185928)
			(xy 375.433875 -272.052548) (xy 375.375631 -271.915845) (xy 375.324809 -271.776212) (xy 375.281555 -271.634053)
			(xy 375.245994 -271.489776) (xy 375.218229 -271.3438) (xy 375.198339 -271.196543) (xy 375.186382 -271.04843)
			(xy 375.182393 -270.89989) (xy 324.616572 -270.89989) (xy 324.616073 -270.974187) (xy 324.608097 -271.122567)
			(xy 324.592168 -271.270305) (xy 324.568332 -271.416974) (xy 324.536658 -271.562153) (xy 324.497236 -271.705423)
			(xy 324.450181 -271.84637) (xy 324.395628 -271.984587) (xy 324.333735 -272.119678) (xy 324.26468 -272.251251)
			(xy 324.188662 -272.378929) (xy 324.105901 -272.502341) (xy 324.016634 -272.621134) (xy 323.92112 -272.734963)
			(xy 323.819633 -272.843502) (xy 323.712466 -272.946437) (xy 323.599929 -273.043471) (xy 323.482346 -273.134324)
			(xy 323.360056 -273.218735) (xy 323.233411 -273.29646) (xy 323.102776 -273.367276) (xy 322.968529 -273.430977)
			(xy 322.831056 -273.48738) (xy 322.690753 -273.536323) (xy 322.548026 -273.577665) (xy 322.403285 -273.611285)
			(xy 322.256949 -273.637088) (xy 322.109438 -273.654999) (xy 321.961179 -273.664967) (xy 321.812598 -273.666962)
			(xy 321.664125 -273.660978) (xy 321.516186 -273.647034) (xy 321.36921 -273.625169) (xy 321.223619 -273.595447)
			(xy 321.079833 -273.557952) (xy 320.938267 -273.512793) (xy 320.799329 -273.460101) (xy 320.66342 -273.400027)
			(xy 320.530931 -273.332745) (xy 320.402245 -273.258448) (xy 320.277732 -273.177351) (xy 320.157752 -273.089687)
			(xy 320.042651 -272.995709) (xy 319.932759 -272.895689) (xy 319.828395 -272.789914) (xy 319.729859 -272.67869)
			(xy 319.637435 -272.562337) (xy 319.55139 -272.44119) (xy 319.471972 -272.3156) (xy 319.399409 -272.185928)
			(xy 319.333911 -272.052548) (xy 319.275667 -271.915845) (xy 319.224845 -271.776212) (xy 319.181591 -271.634053)
			(xy 319.14603 -271.489776) (xy 319.118265 -271.3438) (xy 319.098375 -271.196543) (xy 319.086418 -271.04843)
			(xy 319.082429 -270.89989) (xy 264.616692 -270.89989) (xy 264.616193 -270.974187) (xy 264.608217 -271.122567)
			(xy 264.592288 -271.270305) (xy 264.568452 -271.416974) (xy 264.536778 -271.562153) (xy 264.497356 -271.705423)
			(xy 264.450301 -271.84637) (xy 264.395748 -271.984587) (xy 264.333855 -272.119678) (xy 264.2648 -272.251251)
			(xy 264.188782 -272.378929) (xy 264.106021 -272.502341) (xy 264.016754 -272.621134) (xy 263.92124 -272.734963)
			(xy 263.819753 -272.843502) (xy 263.712586 -272.946437) (xy 263.600049 -273.043471) (xy 263.482466 -273.134324)
			(xy 263.360176 -273.218735) (xy 263.233531 -273.29646) (xy 263.102896 -273.367276) (xy 262.968649 -273.430977)
			(xy 262.831176 -273.48738) (xy 262.690873 -273.536323) (xy 262.548146 -273.577665) (xy 262.403405 -273.611285)
			(xy 262.257069 -273.637088) (xy 262.109558 -273.654999) (xy 261.961299 -273.664967) (xy 261.812718 -273.666962)
			(xy 261.664245 -273.660978) (xy 261.516306 -273.647034) (xy 261.36933 -273.625169) (xy 261.223739 -273.595447)
			(xy 261.079953 -273.557952) (xy 260.938387 -273.512793) (xy 260.799449 -273.460101) (xy 260.66354 -273.400027)
			(xy 260.531051 -273.332745) (xy 260.402365 -273.258448) (xy 260.277852 -273.177351) (xy 260.157872 -273.089687)
			(xy 260.042771 -272.995709) (xy 259.932879 -272.895689) (xy 259.828515 -272.789914) (xy 259.729979 -272.67869)
			(xy 259.637555 -272.562337) (xy 259.55151 -272.44119) (xy 259.472092 -272.3156) (xy 259.399529 -272.185928)
			(xy 259.334031 -272.052548) (xy 259.275787 -271.915845) (xy 259.224965 -271.776212) (xy 259.181711 -271.634053)
			(xy 259.14615 -271.489776) (xy 259.118385 -271.3438) (xy 259.098495 -271.196543) (xy 259.086538 -271.04843)
			(xy 259.082549 -270.89989) (xy 208.516474 -270.89989) (xy 208.515975 -270.974187) (xy 208.507999 -271.122567)
			(xy 208.49207 -271.270305) (xy 208.468234 -271.416974) (xy 208.43656 -271.562153) (xy 208.397138 -271.705423)
			(xy 208.350083 -271.84637) (xy 208.29553 -271.984587) (xy 208.233637 -272.119678) (xy 208.164582 -272.251251)
			(xy 208.088564 -272.378929) (xy 208.005803 -272.502341) (xy 207.916536 -272.621134) (xy 207.821022 -272.734963)
			(xy 207.719535 -272.843502) (xy 207.612368 -272.946437) (xy 207.499831 -273.043471) (xy 207.382248 -273.134324)
			(xy 207.259958 -273.218735) (xy 207.133313 -273.29646) (xy 207.002678 -273.367276) (xy 206.868431 -273.430977)
			(xy 206.730958 -273.48738) (xy 206.590655 -273.536323) (xy 206.447928 -273.577665) (xy 206.303187 -273.611285)
			(xy 206.156851 -273.637088) (xy 206.00934 -273.654999) (xy 205.861081 -273.664967) (xy 205.7125 -273.666962)
			(xy 205.564027 -273.660978) (xy 205.416088 -273.647034) (xy 205.269112 -273.625169) (xy 205.123521 -273.595447)
			(xy 204.979735 -273.557952) (xy 204.838169 -273.512793) (xy 204.699231 -273.460101) (xy 204.563322 -273.400027)
			(xy 204.430833 -273.332745) (xy 204.302147 -273.258448) (xy 204.177634 -273.177351) (xy 204.057654 -273.089687)
			(xy 203.942553 -272.995709) (xy 203.832661 -272.895689) (xy 203.728297 -272.789914) (xy 203.629761 -272.67869)
			(xy 203.537337 -272.562337) (xy 203.451292 -272.44119) (xy 203.371874 -272.3156) (xy 203.299311 -272.185928)
			(xy 203.233813 -272.052548) (xy 203.175569 -271.915845) (xy 203.124747 -271.776212) (xy 203.081493 -271.634053)
			(xy 203.045932 -271.489776) (xy 203.018167 -271.3438) (xy 202.998277 -271.196543) (xy 202.98632 -271.04843)
			(xy 202.982331 -270.89989) (xy 148.516594 -270.89989) (xy 148.516095 -270.974187) (xy 148.508119 -271.122567)
			(xy 148.49219 -271.270305) (xy 148.468354 -271.416974) (xy 148.43668 -271.562153) (xy 148.397258 -271.705423)
			(xy 148.350203 -271.84637) (xy 148.29565 -271.984587) (xy 148.233757 -272.119678) (xy 148.164702 -272.251251)
			(xy 148.088684 -272.378929) (xy 148.005923 -272.502341) (xy 147.916656 -272.621134) (xy 147.821142 -272.734963)
			(xy 147.719655 -272.843502) (xy 147.612488 -272.946437) (xy 147.499951 -273.043471) (xy 147.382368 -273.134324)
			(xy 147.260078 -273.218735) (xy 147.133433 -273.29646) (xy 147.002798 -273.367276) (xy 146.868551 -273.430977)
			(xy 146.731078 -273.48738) (xy 146.590775 -273.536323) (xy 146.448048 -273.577665) (xy 146.303307 -273.611285)
			(xy 146.156971 -273.637088) (xy 146.00946 -273.654999) (xy 145.861201 -273.664967) (xy 145.71262 -273.666962)
			(xy 145.564147 -273.660978) (xy 145.416208 -273.647034) (xy 145.269232 -273.625169) (xy 145.123641 -273.595447)
			(xy 144.979855 -273.557952) (xy 144.838289 -273.512793) (xy 144.699351 -273.460101) (xy 144.563442 -273.400027)
			(xy 144.430953 -273.332745) (xy 144.302267 -273.258448) (xy 144.177754 -273.177351) (xy 144.057774 -273.089687)
			(xy 143.942673 -272.995709) (xy 143.832781 -272.895689) (xy 143.728417 -272.789914) (xy 143.629881 -272.67869)
			(xy 143.537457 -272.562337) (xy 143.451412 -272.44119) (xy 143.371994 -272.3156) (xy 143.299431 -272.185928)
			(xy 143.233933 -272.052548) (xy 143.175689 -271.915845) (xy 143.124867 -271.776212) (xy 143.081613 -271.634053)
			(xy 143.046052 -271.489776) (xy 143.018287 -271.3438) (xy 142.998397 -271.196543) (xy 142.98644 -271.04843)
			(xy 142.982451 -270.89989) (xy 92.41663 -270.89989) (xy 92.416131 -270.974187) (xy 92.408155 -271.122567)
			(xy 92.392226 -271.270305) (xy 92.36839 -271.416974) (xy 92.336716 -271.562153) (xy 92.297294 -271.705423)
			(xy 92.250239 -271.84637) (xy 92.195686 -271.984587) (xy 92.133793 -272.119678) (xy 92.064738 -272.251251)
			(xy 91.98872 -272.378929) (xy 91.905959 -272.502341) (xy 91.816692 -272.621134) (xy 91.721178 -272.734963)
			(xy 91.619691 -272.843502) (xy 91.512524 -272.946437) (xy 91.399987 -273.043471) (xy 91.282404 -273.134324)
			(xy 91.160114 -273.218735) (xy 91.033469 -273.29646) (xy 90.902834 -273.367276) (xy 90.768587 -273.430977)
			(xy 90.631114 -273.48738) (xy 90.490811 -273.536323) (xy 90.348084 -273.577665) (xy 90.203343 -273.611285)
			(xy 90.057007 -273.637088) (xy 89.909496 -273.654999) (xy 89.761237 -273.664967) (xy 89.612656 -273.666962)
			(xy 89.464183 -273.660978) (xy 89.316244 -273.647034) (xy 89.169268 -273.625169) (xy 89.023677 -273.595447)
			(xy 88.879891 -273.557952) (xy 88.738325 -273.512793) (xy 88.599387 -273.460101) (xy 88.463478 -273.400027)
			(xy 88.330989 -273.332745) (xy 88.202303 -273.258448) (xy 88.07779 -273.177351) (xy 87.95781 -273.089687)
			(xy 87.842709 -272.995709) (xy 87.732817 -272.895689) (xy 87.628453 -272.789914) (xy 87.529917 -272.67869)
			(xy 87.437493 -272.562337) (xy 87.351448 -272.44119) (xy 87.27203 -272.3156) (xy 87.199467 -272.185928)
			(xy 87.133969 -272.052548) (xy 87.075725 -271.915845) (xy 87.024903 -271.776212) (xy 86.981649 -271.634053)
			(xy 86.946088 -271.489776) (xy 86.918323 -271.3438) (xy 86.898433 -271.196543) (xy 86.886476 -271.04843)
			(xy 86.882487 -270.89989) (xy 32.416496 -270.89989) (xy 32.415997 -270.974187) (xy 32.408021 -271.122567)
			(xy 32.392092 -271.270305) (xy 32.368256 -271.416974) (xy 32.336582 -271.562153) (xy 32.29716 -271.705423)
			(xy 32.250105 -271.84637) (xy 32.195552 -271.984587) (xy 32.133659 -272.119678) (xy 32.064604 -272.251251)
			(xy 31.988586 -272.378929) (xy 31.905825 -272.502341) (xy 31.816558 -272.621134) (xy 31.721044 -272.734963)
			(xy 31.619557 -272.843502) (xy 31.51239 -272.946437) (xy 31.399853 -273.043471) (xy 31.28227 -273.134324)
			(xy 31.15998 -273.218735) (xy 31.033335 -273.29646) (xy 30.9027 -273.367276) (xy 30.768453 -273.430977)
			(xy 30.63098 -273.48738) (xy 30.490677 -273.536323) (xy 30.34795 -273.577665) (xy 30.203209 -273.611285)
			(xy 30.056873 -273.637088) (xy 29.909362 -273.654999) (xy 29.761103 -273.664967) (xy 29.612522 -273.666962)
			(xy 29.464049 -273.660978) (xy 29.31611 -273.647034) (xy 29.169134 -273.625169) (xy 29.023543 -273.595447)
			(xy 28.879757 -273.557952) (xy 28.738191 -273.512793) (xy 28.599253 -273.460101) (xy 28.463344 -273.400027)
			(xy 28.330855 -273.332745) (xy 28.202169 -273.258448) (xy 28.077656 -273.177351) (xy 27.957676 -273.089687)
			(xy 27.842575 -272.995709) (xy 27.732683 -272.895689) (xy 27.628319 -272.789914) (xy 27.529783 -272.67869)
			(xy 27.437359 -272.562337) (xy 27.351314 -272.44119) (xy 27.271896 -272.3156) (xy 27.199333 -272.185928)
			(xy 27.133835 -272.052548) (xy 27.075591 -271.915845) (xy 27.024769 -271.776212) (xy 26.981515 -271.634053)
			(xy 26.945954 -271.489776) (xy 26.918189 -271.3438) (xy 26.898299 -271.196543) (xy 26.886342 -271.04843)
			(xy 26.882353 -270.89989) (xy 0.509016 -270.89989) (xy 0.509016 -287.850408) (xy 37.944539 -287.850408)
			(xy 37.944539 -287.798392) (xy 37.952677 -287.747016) (xy 37.968751 -287.697546) (xy 37.992366 -287.651199)
			(xy 38.02294 -287.609117) (xy 38.059722 -287.572337) (xy 38.101804 -287.541763) (xy 38.148151 -287.518148)
			(xy 38.197622 -287.502075) (xy 38.248998 -287.493939) (xy 38.275006 -287.493456) (xy 39.224966 -287.493456)
			(xy 39.250978 -287.493901) (xy 39.302363 -287.502035) (xy 39.351843 -287.518107) (xy 39.398199 -287.541722)
			(xy 39.44029 -287.572299) (xy 39.477079 -287.609084) (xy 39.50766 -287.651172) (xy 39.53128 -287.697525)
			(xy 39.547357 -287.747004) (xy 39.555496 -287.798388) (xy 39.555496 -287.850405) (xy 40.794466 -287.850405)
			(xy 40.794466 -287.798395) (xy 40.802602 -287.747025) (xy 40.818674 -287.697561) (xy 40.842285 -287.651219)
			(xy 40.872855 -287.609142) (xy 40.909631 -287.572364) (xy 40.951707 -287.541792) (xy 40.998048 -287.518179)
			(xy 41.047512 -287.502105) (xy 41.098881 -287.493967) (xy 41.124886 -287.493456) (xy 42.074846 -287.493456)
			(xy 42.100852 -287.493934) (xy 42.152223 -287.502077) (xy 42.201688 -287.518155) (xy 42.248029 -287.541773)
			(xy 42.290106 -287.572348) (xy 42.326882 -287.609129) (xy 42.357451 -287.65121) (xy 42.381063 -287.697554)
			(xy 42.397134 -287.747022) (xy 42.40527 -287.798394) (xy 42.40527 -287.850406) (xy 42.397134 -287.901778)
			(xy 42.381063 -287.951246) (xy 42.357451 -287.99759) (xy 42.326882 -288.039671) (xy 42.290106 -288.076452)
			(xy 42.248029 -288.107027) (xy 42.201688 -288.130645) (xy 42.152223 -288.146723) (xy 42.100852 -288.154866)
			(xy 42.074846 -288.15538) (xy 41.124886 -288.15538) (xy 41.098881 -288.154833) (xy 41.047512 -288.146695)
			(xy 40.998048 -288.130621) (xy 40.951707 -288.107008) (xy 40.909631 -288.076436) (xy 40.872855 -288.039658)
			(xy 40.842285 -287.997581) (xy 40.818674 -287.951239) (xy 40.802602 -287.901775) (xy 40.794466 -287.850405)
			(xy 39.555496 -287.850405) (xy 39.555496 -287.850412) (xy 39.547357 -287.901796) (xy 39.53128 -287.951275)
			(xy 39.50766 -287.997628) (xy 39.477079 -288.039716) (xy 39.44029 -288.076501) (xy 39.398199 -288.107078)
			(xy 39.351843 -288.130693) (xy 39.302363 -288.146765) (xy 39.250978 -288.154899) (xy 39.224966 -288.15538)
			(xy 38.275006 -288.15538) (xy 38.248998 -288.154861) (xy 38.197622 -288.146725) (xy 38.148151 -288.130652)
			(xy 38.101804 -288.107037) (xy 38.059722 -288.076463) (xy 38.02294 -288.039683) (xy 37.992366 -287.997601)
			(xy 37.968751 -287.951254) (xy 37.952677 -287.901784) (xy 37.944539 -287.850408) (xy 0.509016 -287.850408)
			(xy 0.509016 -288.800413) (xy 36.0443 -288.800413) (xy 36.0443 -288.748387) (xy 36.052439 -288.697003)
			(xy 36.068516 -288.647524) (xy 36.092136 -288.60117) (xy 36.122718 -288.559082) (xy 36.159507 -288.522297)
			(xy 36.201598 -288.49172) (xy 36.247954 -288.468104) (xy 36.297434 -288.452031) (xy 36.348819 -288.443897)
			(xy 36.374832 -288.443416) (xy 37.324792 -288.443416) (xy 37.3508 -288.443943) (xy 37.402175 -288.452079)
			(xy 37.451646 -288.468151) (xy 37.497993 -288.491765) (xy 37.540075 -288.522339) (xy 37.576856 -288.559119)
			(xy 37.60743 -288.601201) (xy 37.631045 -288.647547) (xy 37.647119 -288.697017) (xy 37.655257 -288.748392)
			(xy 37.655257 -288.800408) (xy 37.655257 -288.800411) (xy 42.694299 -288.800411) (xy 42.694299 -288.748389)
			(xy 42.702438 -288.697007) (xy 42.718514 -288.64753) (xy 42.742132 -288.601178) (xy 42.77271 -288.559091)
			(xy 42.809496 -288.522306) (xy 42.851583 -288.491729) (xy 42.897936 -288.468111) (xy 42.947413 -288.452036)
			(xy 42.998795 -288.443899) (xy 43.024806 -288.443416) (xy 43.974766 -288.443416) (xy 44.000775 -288.443941)
			(xy 44.052154 -288.452074) (xy 44.101628 -288.468144) (xy 44.147978 -288.491757) (xy 44.190064 -288.52233)
			(xy 44.226848 -288.55911) (xy 44.257426 -288.601193) (xy 44.281043 -288.647541) (xy 44.297119 -288.697013)
			(xy 44.305257 -288.748391) (xy 44.305257 -288.800409) (xy 44.297119 -288.851787) (xy 44.281043 -288.901259)
			(xy 44.257426 -288.947607) (xy 44.226848 -288.98969) (xy 44.190064 -289.02647) (xy 44.147978 -289.057043)
			(xy 44.101628 -289.080656) (xy 44.052154 -289.096726) (xy 44.000775 -289.104859) (xy 43.974766 -289.10534)
			(xy 43.024806 -289.10534) (xy 42.998795 -289.104901) (xy 42.947413 -289.096764) (xy 42.897936 -289.080689)
			(xy 42.851583 -289.057071) (xy 42.809496 -289.026494) (xy 42.77271 -288.989709) (xy 42.742132 -288.947622)
			(xy 42.718514 -288.90127) (xy 42.702438 -288.851793) (xy 42.694299 -288.800411) (xy 37.655257 -288.800411)
			(xy 37.647119 -288.851783) (xy 37.631045 -288.901253) (xy 37.60743 -288.947599) (xy 37.576856 -288.989681)
			(xy 37.540075 -289.026461) (xy 37.497993 -289.057035) (xy 37.451646 -289.080649) (xy 37.402175 -289.096721)
			(xy 37.3508 -289.104857) (xy 37.324792 -289.10534) (xy 36.374832 -289.10534) (xy 36.348819 -289.104903)
			(xy 36.297434 -289.096769) (xy 36.247954 -289.080696) (xy 36.201598 -289.05708) (xy 36.159507 -289.026503)
			(xy 36.122718 -288.989718) (xy 36.092136 -288.94763) (xy 36.068516 -288.901276) (xy 36.052439 -288.851797)
			(xy 36.0443 -288.800413) (xy 0.509016 -288.800413) (xy 0.509016 -297.350788) (xy 36.044382 -297.350788)
			(xy 36.044382 -297.298812) (xy 36.052512 -297.247477) (xy 36.068572 -297.198045) (xy 36.092168 -297.151734)
			(xy 36.122717 -297.109685) (xy 36.159468 -297.072931) (xy 36.201516 -297.042379) (xy 36.247825 -297.018781)
			(xy 36.297255 -297.002717) (xy 36.34859 -296.994583) (xy 36.374578 -296.994072) (xy 37.324538 -296.994072)
			(xy 37.350522 -296.994624) (xy 37.401848 -297.002759) (xy 37.451271 -297.018822) (xy 37.497572 -297.042419)
			(xy 37.539613 -297.072968) (xy 37.576357 -297.109716) (xy 37.606901 -297.15176) (xy 37.630492 -297.198064)
			(xy 37.64655 -297.247489) (xy 37.654679 -297.298816) (xy 37.654679 -297.350784) (xy 37.654678 -297.350788)
			(xy 152.144482 -297.350788) (xy 152.144482 -297.298812) (xy 152.152612 -297.247477) (xy 152.168672 -297.198046)
			(xy 152.192268 -297.151735) (xy 152.222816 -297.109685) (xy 152.259567 -297.072932) (xy 152.301615 -297.04238)
			(xy 152.347923 -297.018782) (xy 152.397354 -297.002717) (xy 152.448688 -296.994583) (xy 152.474676 -296.994072)
			(xy 153.424636 -296.994072) (xy 153.45062 -296.994624) (xy 153.501947 -297.002759) (xy 153.55137 -297.018822)
			(xy 153.597671 -297.042418) (xy 153.639712 -297.072967) (xy 153.676457 -297.109715) (xy 153.707001 -297.151759)
			(xy 153.730592 -297.198064) (xy 153.74665 -297.247488) (xy 153.754779 -297.298816) (xy 153.754779 -297.350784)
			(xy 153.754778 -297.350792) (xy 268.244255 -297.350792) (xy 268.244255 -297.298808) (xy 268.252388 -297.247465)
			(xy 268.268452 -297.198025) (xy 268.292053 -297.151708) (xy 268.322609 -297.109653) (xy 268.359368 -297.072896)
			(xy 268.401425 -297.042342) (xy 268.447744 -297.018744) (xy 268.497184 -297.002683) (xy 268.548528 -296.994554)
			(xy 268.57452 -296.994072) (xy 269.52448 -296.994072) (xy 269.550469 -296.994594) (xy 269.601807 -297.002722)
			(xy 269.651241 -297.018781) (xy 269.697554 -297.042377) (xy 269.739606 -297.072927) (xy 269.77636 -297.109679)
			(xy 269.806913 -297.151729) (xy 269.830511 -297.198041) (xy 269.846573 -297.247474) (xy 269.854705 -297.298811)
			(xy 269.854705 -297.350789) (xy 269.854705 -297.350792) (xy 384.344355 -297.350792) (xy 384.344355 -297.298808)
			(xy 384.352488 -297.247465) (xy 384.368552 -297.198026) (xy 384.392153 -297.151709) (xy 384.422709 -297.109654)
			(xy 384.459467 -297.072897) (xy 384.501524 -297.042343) (xy 384.547842 -297.018745) (xy 384.597282 -297.002683)
			(xy 384.648626 -296.994554) (xy 384.674618 -296.994072) (xy 385.624578 -296.994072) (xy 385.650567 -296.994593)
			(xy 385.701905 -297.002721) (xy 385.751339 -297.018781) (xy 385.797653 -297.042376) (xy 385.839705 -297.072926)
			(xy 385.87646 -297.109678) (xy 385.907013 -297.151728) (xy 385.930611 -297.19804) (xy 385.946673 -297.247474)
			(xy 385.954805 -297.298811) (xy 385.954805 -297.350789) (xy 385.946673 -297.402126) (xy 385.930611 -297.45156)
			(xy 385.907013 -297.497872) (xy 385.87646 -297.539922) (xy 385.839705 -297.576674) (xy 385.797653 -297.607224)
			(xy 385.751339 -297.630819) (xy 385.701905 -297.646879) (xy 385.650567 -297.655007) (xy 385.624578 -297.655488)
			(xy 384.674618 -297.655488) (xy 384.648626 -297.655046) (xy 384.597282 -297.646917) (xy 384.547842 -297.630855)
			(xy 384.501524 -297.607257) (xy 384.459467 -297.576703) (xy 384.422709 -297.539946) (xy 384.392153 -297.497891)
			(xy 384.368552 -297.451574) (xy 384.352488 -297.402135) (xy 384.344355 -297.350792) (xy 269.854705 -297.350792)
			(xy 269.846573 -297.402126) (xy 269.830511 -297.451559) (xy 269.806913 -297.497871) (xy 269.77636 -297.539921)
			(xy 269.739606 -297.576673) (xy 269.697554 -297.607223) (xy 269.651241 -297.630819) (xy 269.601807 -297.646878)
			(xy 269.550469 -297.655006) (xy 269.52448 -297.655488) (xy 268.57452 -297.655488) (xy 268.548528 -297.655046)
			(xy 268.497184 -297.646917) (xy 268.447744 -297.630856) (xy 268.401425 -297.607258) (xy 268.359368 -297.576704)
			(xy 268.322609 -297.539947) (xy 268.292053 -297.497892) (xy 268.268452 -297.451575) (xy 268.252388 -297.402135)
			(xy 268.244255 -297.350792) (xy 153.754778 -297.350792) (xy 153.74665 -297.402112) (xy 153.730592 -297.451536)
			(xy 153.707001 -297.497841) (xy 153.676457 -297.539885) (xy 153.639712 -297.576633) (xy 153.597671 -297.607182)
			(xy 153.55137 -297.630778) (xy 153.501947 -297.646841) (xy 153.45062 -297.654976) (xy 153.424636 -297.655488)
			(xy 152.474676 -297.655488) (xy 152.448688 -297.655017) (xy 152.397354 -297.646883) (xy 152.347923 -297.630818)
			(xy 152.301615 -297.60722) (xy 152.259567 -297.576668) (xy 152.222816 -297.539915) (xy 152.192268 -297.497865)
			(xy 152.168672 -297.451554) (xy 152.152612 -297.402123) (xy 152.144482 -297.350788) (xy 37.654678 -297.350788)
			(xy 37.64655 -297.402111) (xy 37.630492 -297.451536) (xy 37.606901 -297.49784) (xy 37.576357 -297.539884)
			(xy 37.539613 -297.576632) (xy 37.497572 -297.607181) (xy 37.451271 -297.630778) (xy 37.401848 -297.646841)
			(xy 37.350522 -297.654976) (xy 37.324538 -297.655488) (xy 36.374578 -297.655488) (xy 36.34859 -297.655017)
			(xy 36.297255 -297.646883) (xy 36.247825 -297.630819) (xy 36.201516 -297.607221) (xy 36.159468 -297.576669)
			(xy 36.122717 -297.539915) (xy 36.092168 -297.497866) (xy 36.068572 -297.451555) (xy 36.052512 -297.402123)
			(xy 36.044382 -297.350788) (xy 0.509016 -297.350788) (xy 0.509016 -298.77569) (xy 39.369695 -298.77569)
			(xy 39.369695 -298.72371) (xy 39.377827 -298.67237) (xy 39.393891 -298.622935) (xy 39.417492 -298.576621)
			(xy 39.448047 -298.53457) (xy 39.484805 -298.497817) (xy 39.52686 -298.467268) (xy 39.573177 -298.443674)
			(xy 39.622615 -298.427617) (xy 39.673956 -298.419492) (xy 39.699946 -298.419012) (xy 40.649906 -298.419012)
			(xy 40.675894 -298.419482) (xy 40.727231 -298.427614) (xy 40.776664 -298.443676) (xy 40.822975 -298.467274)
			(xy 40.865025 -298.497826) (xy 40.901778 -298.534579) (xy 40.932329 -298.57663) (xy 40.955926 -298.622942)
			(xy 40.971988 -298.672375) (xy 40.980118 -298.723712) (xy 40.980118 -298.775685) (xy 387.669821 -298.775685)
			(xy 387.669821 -298.723715) (xy 387.677951 -298.672385) (xy 387.69401 -298.622959) (xy 387.717603 -298.576653)
			(xy 387.74815 -298.534608) (xy 387.784897 -298.497859) (xy 387.826941 -298.467311) (xy 387.873246 -298.443716)
			(xy 387.922671 -298.427654) (xy 387.974001 -298.419523) (xy 387.999986 -298.419012) (xy 388.949946 -298.419012)
			(xy 388.975932 -298.419485) (xy 389.027264 -298.427622) (xy 389.076692 -298.443688) (xy 389.122998 -298.467288)
			(xy 389.165042 -298.49784) (xy 389.20179 -298.534593) (xy 389.232337 -298.576642) (xy 389.25593 -298.622951)
			(xy 389.271989 -298.67238) (xy 389.280119 -298.723714) (xy 389.280119 -298.775686) (xy 389.271989 -298.82702)
			(xy 389.25593 -298.876449) (xy 389.232337 -298.922758) (xy 389.20179 -298.964807) (xy 389.165042 -299.00156)
			(xy 389.122998 -299.032112) (xy 389.076692 -299.055712) (xy 389.027264 -299.071778) (xy 388.975932 -299.079915)
			(xy 388.949946 -299.080428) (xy 387.999986 -299.080428) (xy 387.974001 -299.079877) (xy 387.922671 -299.071746)
			(xy 387.873246 -299.055684) (xy 387.826941 -299.032089) (xy 387.784897 -299.001541) (xy 387.74815 -298.964792)
			(xy 387.717603 -298.922747) (xy 387.69401 -298.876441) (xy 387.677951 -298.827015) (xy 387.669821 -298.775685)
			(xy 40.980118 -298.775685) (xy 40.980118 -298.775688) (xy 40.971988 -298.827025) (xy 40.955926 -298.876458)
			(xy 40.932329 -298.92277) (xy 40.901778 -298.964821) (xy 40.865025 -299.001574) (xy 40.822975 -299.032126)
			(xy 40.776664 -299.055724) (xy 40.727231 -299.071786) (xy 40.675894 -299.079918) (xy 40.649906 -299.080428)
			(xy 39.699946 -299.080428) (xy 39.673956 -299.079908) (xy 39.622615 -299.071783) (xy 39.573177 -299.055726)
			(xy 39.52686 -299.032132) (xy 39.484805 -299.001583) (xy 39.448047 -298.96483) (xy 39.417492 -298.922779)
			(xy 39.393891 -298.876465) (xy 39.377827 -298.82703) (xy 39.369695 -298.77569) (xy 0.509016 -298.77569)
			(xy 0.509016 -299.25101) (xy 36.044102 -299.25101) (xy 36.044102 -299.19899) (xy 36.052239 -299.147611)
			(xy 36.068313 -299.098138) (xy 36.091929 -299.051788) (xy 36.122504 -299.009703) (xy 36.159286 -298.972918)
			(xy 36.201369 -298.94234) (xy 36.247718 -298.918722) (xy 36.29719 -298.902644) (xy 36.348568 -298.894504)
			(xy 36.374578 -298.893992) (xy 37.324538 -298.893992) (xy 37.35054 -298.894597) (xy 37.401902 -298.902737)
			(xy 37.451358 -298.918812) (xy 37.497691 -298.942425) (xy 37.539761 -298.972994) (xy 37.576531 -299.009768)
			(xy 37.607095 -299.051841) (xy 37.630703 -299.098177) (xy 37.646771 -299.147635) (xy 37.654906 -299.198998)
			(xy 37.654906 -299.251002) (xy 37.654905 -299.25101) (xy 152.144202 -299.25101) (xy 152.144202 -299.19899)
			(xy 152.152339 -299.147612) (xy 152.168413 -299.098138) (xy 152.192028 -299.051788) (xy 152.222603 -299.009703)
			(xy 152.259385 -298.972919) (xy 152.301468 -298.942341) (xy 152.347816 -298.918722) (xy 152.397288 -298.902645)
			(xy 152.448666 -298.894504) (xy 152.474676 -298.893992) (xy 153.424636 -298.893992) (xy 153.450638 -298.894597)
			(xy 153.502 -298.902737) (xy 153.551457 -298.918811) (xy 153.59779 -298.942424) (xy 153.63986 -298.972993)
			(xy 153.67663 -299.009767) (xy 153.707195 -299.05184) (xy 153.730803 -299.098177) (xy 153.746871 -299.147635)
			(xy 153.755006 -299.198998) (xy 153.755006 -299.251002) (xy 153.755005 -299.251009) (xy 154.994602 -299.251009)
			(xy 154.994602 -299.198991) (xy 155.002739 -299.147613) (xy 155.018812 -299.098141) (xy 155.042426 -299.051792)
			(xy 155.073 -299.009707) (xy 155.10978 -298.972923) (xy 155.151861 -298.942345) (xy 155.198208 -298.918726)
			(xy 155.247678 -298.902647) (xy 155.299055 -298.894505) (xy 155.325064 -298.893992) (xy 156.275024 -298.893992)
			(xy 156.301026 -298.894596) (xy 156.35239 -298.902735) (xy 156.401848 -298.918808) (xy 156.448184 -298.94242)
			(xy 156.490255 -298.972989) (xy 156.527026 -299.009763) (xy 156.557593 -299.051837) (xy 156.581201 -299.098174)
			(xy 156.597271 -299.147633) (xy 156.605406 -299.198998) (xy 156.605406 -299.251002) (xy 156.605404 -299.251014)
			(xy 268.243976 -299.251014) (xy 268.243976 -299.198986) (xy 268.252115 -299.147599) (xy 268.268193 -299.098118)
			(xy 268.291814 -299.051761) (xy 268.322396 -299.009671) (xy 268.359186 -298.972883) (xy 268.401279 -298.942303)
			(xy 268.447637 -298.918685) (xy 268.497119 -298.90261) (xy 268.548506 -298.894474) (xy 268.57452 -298.893992)
			(xy 269.52448 -298.893992) (xy 269.550487 -298.894566) (xy 269.60186 -298.9027) (xy 269.651328 -298.91877)
			(xy 269.697673 -298.942382) (xy 269.739754 -298.972953) (xy 269.776534 -299.009731) (xy 269.807108 -299.05181)
			(xy 269.830722 -299.098153) (xy 269.846796 -299.147621) (xy 269.854933 -299.198993) (xy 269.854933 -299.251007)
			(xy 269.854932 -299.251013) (xy 271.094376 -299.251013) (xy 271.094376 -299.198987) (xy 271.102514 -299.147601)
			(xy 271.118592 -299.098121) (xy 271.142212 -299.051765) (xy 271.172792 -299.009675) (xy 271.209581 -298.972887)
			(xy 271.251672 -298.942307) (xy 271.298028 -298.918689) (xy 271.347509 -298.902613) (xy 271.398895 -298.894475)
			(xy 271.424908 -298.893992) (xy 272.374868 -298.893992) (xy 272.400875 -298.894565) (xy 272.45225 -298.902697)
			(xy 272.50172 -298.918767) (xy 272.548067 -298.942378) (xy 272.590149 -298.972949) (xy 272.626931 -299.009727)
			(xy 272.657506 -299.051806) (xy 272.681121 -299.09815) (xy 272.697195 -299.147619) (xy 272.705333 -299.198993)
			(xy 272.705333 -299.251007) (xy 272.705332 -299.251014) (xy 384.344076 -299.251014) (xy 384.344076 -299.198986)
			(xy 384.352215 -299.147599) (xy 384.368293 -299.098118) (xy 384.391913 -299.051762) (xy 384.422495 -299.009672)
			(xy 384.459285 -298.972884) (xy 384.501377 -298.942304) (xy 384.547735 -298.918686) (xy 384.597217 -298.902611)
			(xy 384.648604 -298.894474) (xy 384.674618 -298.893992) (xy 385.624578 -298.893992) (xy 385.650585 -298.894566)
			(xy 385.701958 -298.902699) (xy 385.751427 -298.91877) (xy 385.797772 -298.942381) (xy 385.839853 -298.972952)
			(xy 385.876634 -299.00973) (xy 385.907207 -299.051809) (xy 385.930822 -299.098153) (xy 385.946896 -299.14762)
			(xy 385.955033 -299.198993) (xy 385.955033 -299.251007) (xy 385.946896 -299.30238) (xy 385.930822 -299.351847)
			(xy 385.907207 -299.398191) (xy 385.876634 -299.44027) (xy 385.839853 -299.477048) (xy 385.797772 -299.507619)
			(xy 385.751427 -299.53123) (xy 385.701958 -299.547301) (xy 385.650585 -299.555434) (xy 385.624578 -299.555916)
			(xy 384.674618 -299.555916) (xy 384.648604 -299.555526) (xy 384.597217 -299.547389) (xy 384.547735 -299.531314)
			(xy 384.501377 -299.507696) (xy 384.459285 -299.477116) (xy 384.422495 -299.440328) (xy 384.391913 -299.398238)
			(xy 384.368293 -299.351882) (xy 384.352215 -299.302401) (xy 384.344076 -299.251014) (xy 272.705332 -299.251014)
			(xy 272.697195 -299.302381) (xy 272.681121 -299.35185) (xy 272.657506 -299.398194) (xy 272.626931 -299.440273)
			(xy 272.590149 -299.477051) (xy 272.548067 -299.507622) (xy 272.50172 -299.531233) (xy 272.45225 -299.547303)
			(xy 272.400875 -299.555435) (xy 272.374868 -299.555916) (xy 271.424908 -299.555916) (xy 271.398895 -299.555525)
			(xy 271.347509 -299.547387) (xy 271.298028 -299.531311) (xy 271.251672 -299.507693) (xy 271.209581 -299.477113)
			(xy 271.172792 -299.440325) (xy 271.142212 -299.398235) (xy 271.118592 -299.351879) (xy 271.102514 -299.302399)
			(xy 271.094376 -299.251013) (xy 269.854932 -299.251013) (xy 269.846796 -299.302379) (xy 269.830722 -299.351847)
			(xy 269.807108 -299.39819) (xy 269.776534 -299.440269) (xy 269.739754 -299.477047) (xy 269.697673 -299.507618)
			(xy 269.651328 -299.53123) (xy 269.60186 -299.5473) (xy 269.550487 -299.555434) (xy 269.52448 -299.555916)
			(xy 268.57452 -299.555916) (xy 268.548506 -299.555526) (xy 268.497119 -299.54739) (xy 268.447637 -299.531315)
			(xy 268.401279 -299.507697) (xy 268.359186 -299.477117) (xy 268.322396 -299.440329) (xy 268.291814 -299.398239)
			(xy 268.268193 -299.351882) (xy 268.252115 -299.302401) (xy 268.243976 -299.251014) (xy 156.605404 -299.251014)
			(xy 156.597271 -299.302367) (xy 156.581201 -299.351826) (xy 156.557593 -299.398163) (xy 156.527026 -299.440237)
			(xy 156.490255 -299.477011) (xy 156.448184 -299.50758) (xy 156.401848 -299.531192) (xy 156.35239 -299.547265)
			(xy 156.301026 -299.555404) (xy 156.275024 -299.555916) (xy 155.325064 -299.555916) (xy 155.299055 -299.555495)
			(xy 155.247678 -299.547353) (xy 155.198208 -299.531274) (xy 155.151861 -299.507655) (xy 155.10978 -299.477077)
			(xy 155.073 -299.440293) (xy 155.042426 -299.398208) (xy 155.018812 -299.351859) (xy 155.002739 -299.302387)
			(xy 154.994602 -299.251009) (xy 153.755005 -299.251009) (xy 153.746871 -299.302365) (xy 153.730803 -299.351823)
			(xy 153.707195 -299.39816) (xy 153.67663 -299.440233) (xy 153.63986 -299.477007) (xy 153.59779 -299.507576)
			(xy 153.551457 -299.531189) (xy 153.502 -299.547263) (xy 153.450638 -299.555403) (xy 153.424636 -299.555916)
			(xy 152.474676 -299.555916) (xy 152.448666 -299.555496) (xy 152.397288 -299.547355) (xy 152.347816 -299.531278)
			(xy 152.301468 -299.507659) (xy 152.259385 -299.477081) (xy 152.222603 -299.440297) (xy 152.192028 -299.398212)
			(xy 152.168413 -299.351862) (xy 152.152339 -299.302388) (xy 152.144202 -299.25101) (xy 37.654905 -299.25101)
			(xy 37.646771 -299.302365) (xy 37.630703 -299.351823) (xy 37.607095 -299.398159) (xy 37.576531 -299.440232)
			(xy 37.539761 -299.477006) (xy 37.497691 -299.507575) (xy 37.451358 -299.531188) (xy 37.401902 -299.547263)
			(xy 37.35054 -299.555403) (xy 37.324538 -299.555916) (xy 36.374578 -299.555916) (xy 36.348568 -299.555496)
			(xy 36.29719 -299.547356) (xy 36.247718 -299.531278) (xy 36.201369 -299.50766) (xy 36.159286 -299.477082)
			(xy 36.122504 -299.440297) (xy 36.091929 -299.398212) (xy 36.068313 -299.351862) (xy 36.052239 -299.302389)
			(xy 36.044102 -299.25101) (xy 0.509016 -299.25101) (xy 0.509016 -305.19751) (xy 17.638266 -305.19751)
			(xy 17.642339 -305.141851) (xy 17.654474 -305.087378) (xy 17.67441 -305.035252) (xy 17.701724 -304.986584)
			(xy 17.735832 -304.942412) (xy 17.776009 -304.903677) (xy 17.821397 -304.871205) (xy 17.871029 -304.845687)
			(xy 17.923849 -304.827668) (xy 17.978728 -304.817531) (xy 18.034499 -304.815493) (xy 18.089973 -304.821596)
			(xy 18.143966 -304.835712) (xy 18.195329 -304.857539) (xy 18.242967 -304.886612) (xy 18.285863 -304.922311)
			(xy 18.323105 -304.963875) (xy 18.353899 -305.010419) (xy 18.377587 -305.06095) (xy 18.393665 -305.114392)
			(xy 18.401791 -305.169606) (xy 18.4023 -305.19751) (xy 18.401791 -305.225414) (xy 18.393665 -305.280628)
			(xy 18.377587 -305.33407) (xy 18.353899 -305.384601) (xy 18.323105 -305.431145) (xy 18.285863 -305.472709)
			(xy 18.242967 -305.508408) (xy 18.195329 -305.537481) (xy 18.143966 -305.559308) (xy 18.089973 -305.573424)
			(xy 18.034499 -305.579527) (xy 17.978728 -305.577489) (xy 17.923849 -305.567352) (xy 17.871029 -305.549333)
			(xy 17.821397 -305.523815) (xy 17.776009 -305.491343) (xy 17.735832 -305.452608) (xy 17.701724 -305.408436)
			(xy 17.67441 -305.359768) (xy 17.654474 -305.307642) (xy 17.642339 -305.253169) (xy 17.638266 -305.19751)
			(xy 0.509016 -305.19751) (xy 0.509016 -306.28209) (xy 17.638266 -306.28209) (xy 17.642339 -306.226431)
			(xy 17.654474 -306.171958) (xy 17.67441 -306.119832) (xy 17.701724 -306.071164) (xy 17.735832 -306.026992)
			(xy 17.776009 -305.988257) (xy 17.821397 -305.955785) (xy 17.871029 -305.930267) (xy 17.923849 -305.912248)
			(xy 17.978728 -305.902111) (xy 18.034499 -305.900073) (xy 18.089973 -305.906176) (xy 18.143966 -305.920292)
			(xy 18.195329 -305.942119) (xy 18.242967 -305.971192) (xy 18.285863 -306.006891) (xy 18.323105 -306.048455)
			(xy 18.353899 -306.094999) (xy 18.377587 -306.14553) (xy 18.393665 -306.198972) (xy 18.401791 -306.254186)
			(xy 18.4023 -306.28209) (xy 18.401791 -306.309994) (xy 18.393665 -306.365208) (xy 18.377587 -306.41865)
			(xy 18.353899 -306.469181) (xy 18.323105 -306.515725) (xy 18.285863 -306.557289) (xy 18.242967 -306.592988)
			(xy 18.195329 -306.622061) (xy 18.143966 -306.643888) (xy 18.089973 -306.658004) (xy 18.034499 -306.664107)
			(xy 17.978728 -306.662069) (xy 17.923849 -306.651932) (xy 17.871029 -306.633913) (xy 17.821397 -306.608395)
			(xy 17.776009 -306.575923) (xy 17.735832 -306.537188) (xy 17.701724 -306.493016) (xy 17.67441 -306.444348)
			(xy 17.654474 -306.392222) (xy 17.642339 -306.337749) (xy 17.638266 -306.28209) (xy 0.509016 -306.28209)
			(xy 0.509016 -307.484272) (xy 231.935526 -307.484272) (xy 231.939599 -307.428613) (xy 231.951734 -307.37414)
			(xy 231.97167 -307.322014) (xy 231.998984 -307.273346) (xy 232.033092 -307.229174) (xy 232.073269 -307.190439)
			(xy 232.118657 -307.157967) (xy 232.168289 -307.132449) (xy 232.221109 -307.11443) (xy 232.275988 -307.104293)
			(xy 232.331759 -307.102255) (xy 232.387233 -307.108358) (xy 232.441226 -307.122474) (xy 232.492589 -307.144301)
			(xy 232.540227 -307.173374) (xy 232.583123 -307.209073) (xy 232.620365 -307.250637) (xy 232.651159 -307.297181)
			(xy 232.674847 -307.347712) (xy 232.690925 -307.401154) (xy 232.699051 -307.456368) (xy 232.69956 -307.484272)
			(xy 248.185684 -307.484272) (xy 248.189757 -307.428613) (xy 248.201892 -307.37414) (xy 248.221828 -307.322014)
			(xy 248.249142 -307.273346) (xy 248.28325 -307.229174) (xy 248.323427 -307.190439) (xy 248.368815 -307.157967)
			(xy 248.418447 -307.132449) (xy 248.471267 -307.11443) (xy 248.526146 -307.104293) (xy 248.581917 -307.102255)
			(xy 248.637391 -307.108358) (xy 248.691384 -307.122474) (xy 248.742747 -307.144301) (xy 248.790385 -307.173374)
			(xy 248.833281 -307.209073) (xy 248.870523 -307.250637) (xy 248.901317 -307.297181) (xy 248.925005 -307.347712)
			(xy 248.941083 -307.401154) (xy 248.949209 -307.456368) (xy 248.949718 -307.484272) (xy 248.949209 -307.512176)
			(xy 248.941083 -307.56739) (xy 248.928951 -307.607716) (xy 462.556604 -307.607716) (xy 462.560677 -307.552057)
			(xy 462.572812 -307.497584) (xy 462.592748 -307.445458) (xy 462.620062 -307.39679) (xy 462.65417 -307.352618)
			(xy 462.694347 -307.313883) (xy 462.739735 -307.281411) (xy 462.789367 -307.255893) (xy 462.842187 -307.237874)
			(xy 462.897066 -307.227737) (xy 462.952837 -307.225699) (xy 463.008311 -307.231802) (xy 463.062304 -307.245918)
			(xy 463.113667 -307.267745) (xy 463.161305 -307.296818) (xy 463.204201 -307.332517) (xy 463.241443 -307.374081)
			(xy 463.272237 -307.420625) (xy 463.295925 -307.471156) (xy 463.312003 -307.524598) (xy 463.320129 -307.579812)
			(xy 463.320638 -307.607716) (xy 463.320129 -307.63562) (xy 463.312003 -307.690834) (xy 463.295925 -307.744276)
			(xy 463.272237 -307.794807) (xy 463.241443 -307.841351) (xy 463.204201 -307.882915) (xy 463.161305 -307.918614)
			(xy 463.113667 -307.947687) (xy 463.062304 -307.969514) (xy 463.008311 -307.98363) (xy 462.952837 -307.989733)
			(xy 462.897066 -307.987695) (xy 462.842187 -307.977558) (xy 462.789367 -307.959539) (xy 462.739735 -307.934021)
			(xy 462.694347 -307.901549) (xy 462.65417 -307.862814) (xy 462.620062 -307.818642) (xy 462.592748 -307.769974)
			(xy 462.572812 -307.717848) (xy 462.560677 -307.663375) (xy 462.556604 -307.607716) (xy 248.928951 -307.607716)
			(xy 248.925005 -307.620832) (xy 248.901317 -307.671363) (xy 248.870523 -307.717907) (xy 248.833281 -307.759471)
			(xy 248.790385 -307.79517) (xy 248.742747 -307.824243) (xy 248.691384 -307.84607) (xy 248.637391 -307.860186)
			(xy 248.581917 -307.866289) (xy 248.526146 -307.864251) (xy 248.471267 -307.854114) (xy 248.418447 -307.836095)
			(xy 248.368815 -307.810577) (xy 248.323427 -307.778105) (xy 248.28325 -307.73937) (xy 248.249142 -307.695198)
			(xy 248.221828 -307.64653) (xy 248.201892 -307.594404) (xy 248.189757 -307.539931) (xy 248.185684 -307.484272)
			(xy 232.69956 -307.484272) (xy 232.699051 -307.512176) (xy 232.690925 -307.56739) (xy 232.674847 -307.620832)
			(xy 232.651159 -307.671363) (xy 232.620365 -307.717907) (xy 232.583123 -307.759471) (xy 232.540227 -307.79517)
			(xy 232.492589 -307.824243) (xy 232.441226 -307.84607) (xy 232.387233 -307.860186) (xy 232.331759 -307.866289)
			(xy 232.275988 -307.864251) (xy 232.221109 -307.854114) (xy 232.168289 -307.836095) (xy 232.118657 -307.810577)
			(xy 232.073269 -307.778105) (xy 232.033092 -307.73937) (xy 231.998984 -307.695198) (xy 231.97167 -307.64653)
			(xy 231.951734 -307.594404) (xy 231.939599 -307.539931) (xy 231.935526 -307.484272) (xy 0.509016 -307.484272)
			(xy 0.509016 -308.568852) (xy 231.935526 -308.568852) (xy 231.939599 -308.513193) (xy 231.951734 -308.45872)
			(xy 231.97167 -308.406594) (xy 231.998984 -308.357926) (xy 232.033092 -308.313754) (xy 232.073269 -308.275019)
			(xy 232.118657 -308.242547) (xy 232.168289 -308.217029) (xy 232.221109 -308.19901) (xy 232.275988 -308.188873)
			(xy 232.331759 -308.186835) (xy 232.387233 -308.192938) (xy 232.441226 -308.207054) (xy 232.492589 -308.228881)
			(xy 232.540227 -308.257954) (xy 232.583123 -308.293653) (xy 232.620365 -308.335217) (xy 232.651159 -308.381761)
			(xy 232.674847 -308.432292) (xy 232.690925 -308.485734) (xy 232.699051 -308.540948) (xy 232.69956 -308.568852)
			(xy 248.185684 -308.568852) (xy 248.189757 -308.513193) (xy 248.201892 -308.45872) (xy 248.221828 -308.406594)
			(xy 248.249142 -308.357926) (xy 248.28325 -308.313754) (xy 248.323427 -308.275019) (xy 248.368815 -308.242547)
			(xy 248.418447 -308.217029) (xy 248.471267 -308.19901) (xy 248.526146 -308.188873) (xy 248.581917 -308.186835)
			(xy 248.637391 -308.192938) (xy 248.691384 -308.207054) (xy 248.742747 -308.228881) (xy 248.790385 -308.257954)
			(xy 248.833281 -308.293653) (xy 248.870523 -308.335217) (xy 248.901317 -308.381761) (xy 248.925005 -308.432292)
			(xy 248.941083 -308.485734) (xy 248.949209 -308.540948) (xy 248.949718 -308.568852) (xy 248.949209 -308.596756)
			(xy 248.941083 -308.65197) (xy 248.928951 -308.692296) (xy 462.556604 -308.692296) (xy 462.560677 -308.636637)
			(xy 462.572812 -308.582164) (xy 462.592748 -308.530038) (xy 462.620062 -308.48137) (xy 462.65417 -308.437198)
			(xy 462.694347 -308.398463) (xy 462.739735 -308.365991) (xy 462.789367 -308.340473) (xy 462.842187 -308.322454)
			(xy 462.897066 -308.312317) (xy 462.952837 -308.310279) (xy 463.008311 -308.316382) (xy 463.062304 -308.330498)
			(xy 463.113667 -308.352325) (xy 463.161305 -308.381398) (xy 463.204201 -308.417097) (xy 463.241443 -308.458661)
			(xy 463.272237 -308.505205) (xy 463.295925 -308.555736) (xy 463.312003 -308.609178) (xy 463.320129 -308.664392)
			(xy 463.320638 -308.692296) (xy 463.320129 -308.7202) (xy 463.312003 -308.775414) (xy 463.295925 -308.828856)
			(xy 463.272237 -308.879387) (xy 463.241443 -308.925931) (xy 463.204201 -308.967495) (xy 463.161305 -309.003194)
			(xy 463.113667 -309.032267) (xy 463.062304 -309.054094) (xy 463.008311 -309.06821) (xy 462.952837 -309.074313)
			(xy 462.897066 -309.072275) (xy 462.842187 -309.062138) (xy 462.789367 -309.044119) (xy 462.739735 -309.018601)
			(xy 462.694347 -308.986129) (xy 462.65417 -308.947394) (xy 462.620062 -308.903222) (xy 462.592748 -308.854554)
			(xy 462.572812 -308.802428) (xy 462.560677 -308.747955) (xy 462.556604 -308.692296) (xy 248.928951 -308.692296)
			(xy 248.925005 -308.705412) (xy 248.901317 -308.755943) (xy 248.870523 -308.802487) (xy 248.833281 -308.844051)
			(xy 248.790385 -308.87975) (xy 248.742747 -308.908823) (xy 248.691384 -308.93065) (xy 248.637391 -308.944766)
			(xy 248.581917 -308.950869) (xy 248.526146 -308.948831) (xy 248.471267 -308.938694) (xy 248.418447 -308.920675)
			(xy 248.368815 -308.895157) (xy 248.323427 -308.862685) (xy 248.28325 -308.82395) (xy 248.249142 -308.779778)
			(xy 248.221828 -308.73111) (xy 248.201892 -308.678984) (xy 248.189757 -308.624511) (xy 248.185684 -308.568852)
			(xy 232.69956 -308.568852) (xy 232.699051 -308.596756) (xy 232.690925 -308.65197) (xy 232.674847 -308.705412)
			(xy 232.651159 -308.755943) (xy 232.620365 -308.802487) (xy 232.583123 -308.844051) (xy 232.540227 -308.87975)
			(xy 232.492589 -308.908823) (xy 232.441226 -308.93065) (xy 232.387233 -308.944766) (xy 232.331759 -308.950869)
			(xy 232.275988 -308.948831) (xy 232.221109 -308.938694) (xy 232.168289 -308.920675) (xy 232.118657 -308.895157)
			(xy 232.073269 -308.862685) (xy 232.033092 -308.82395) (xy 231.998984 -308.779778) (xy 231.97167 -308.73111)
			(xy 231.951734 -308.678984) (xy 231.939599 -308.624511) (xy 231.935526 -308.568852) (xy 0.509016 -308.568852)
			(xy 0.509016 -320.900044) (xy 26.882353 -320.900044) (xy 26.886342 -320.751504) (xy 26.898299 -320.603391)
			(xy 26.918189 -320.456134) (xy 26.945954 -320.310158) (xy 26.981515 -320.165881) (xy 27.024769 -320.023722)
			(xy 27.075591 -319.884089) (xy 27.133835 -319.747386) (xy 27.199333 -319.614006) (xy 27.271896 -319.484334)
			(xy 27.351314 -319.358744) (xy 27.437359 -319.237597) (xy 27.529783 -319.121244) (xy 27.628319 -319.01002)
			(xy 27.732683 -318.904245) (xy 27.842575 -318.804225) (xy 27.957676 -318.710247) (xy 28.077656 -318.622583)
			(xy 28.202169 -318.541486) (xy 28.330855 -318.467189) (xy 28.463344 -318.399907) (xy 28.599253 -318.339833)
			(xy 28.738191 -318.287141) (xy 28.879757 -318.241982) (xy 29.023543 -318.204487) (xy 29.169134 -318.174765)
			(xy 29.31611 -318.1529) (xy 29.464049 -318.138956) (xy 29.612522 -318.132972) (xy 29.761103 -318.134967)
			(xy 29.909362 -318.144935) (xy 30.056873 -318.162846) (xy 30.203209 -318.188649) (xy 30.34795 -318.222269)
			(xy 30.490677 -318.263611) (xy 30.63098 -318.312554) (xy 30.768453 -318.368957) (xy 30.9027 -318.432658)
			(xy 31.033335 -318.503474) (xy 31.15998 -318.581199) (xy 31.28227 -318.66561) (xy 31.399853 -318.756463)
			(xy 31.51239 -318.853497) (xy 31.619557 -318.956432) (xy 31.721044 -319.064971) (xy 31.816558 -319.1788)
			(xy 31.905825 -319.297593) (xy 31.988586 -319.421005) (xy 32.064604 -319.548683) (xy 32.133659 -319.680256)
			(xy 32.195552 -319.815347) (xy 32.250105 -319.953564) (xy 32.29716 -320.094511) (xy 32.336582 -320.237781)
			(xy 32.368256 -320.38296) (xy 32.392092 -320.529629) (xy 32.408021 -320.677367) (xy 32.415997 -320.825747)
			(xy 32.416496 -320.900044) (xy 86.882487 -320.900044) (xy 86.886476 -320.751504) (xy 86.898433 -320.603391)
			(xy 86.918323 -320.456134) (xy 86.946088 -320.310158) (xy 86.981649 -320.165881) (xy 87.024903 -320.023722)
			(xy 87.075725 -319.884089) (xy 87.133969 -319.747386) (xy 87.199467 -319.614006) (xy 87.27203 -319.484334)
			(xy 87.351448 -319.358744) (xy 87.437493 -319.237597) (xy 87.529917 -319.121244) (xy 87.628453 -319.01002)
			(xy 87.732817 -318.904245) (xy 87.842709 -318.804225) (xy 87.95781 -318.710247) (xy 88.07779 -318.622583)
			(xy 88.202303 -318.541486) (xy 88.330989 -318.467189) (xy 88.463478 -318.399907) (xy 88.599387 -318.339833)
			(xy 88.738325 -318.287141) (xy 88.879891 -318.241982) (xy 89.023677 -318.204487) (xy 89.169268 -318.174765)
			(xy 89.316244 -318.1529) (xy 89.464183 -318.138956) (xy 89.612656 -318.132972) (xy 89.761237 -318.134967)
			(xy 89.909496 -318.144935) (xy 90.057007 -318.162846) (xy 90.203343 -318.188649) (xy 90.348084 -318.222269)
			(xy 90.490811 -318.263611) (xy 90.631114 -318.312554) (xy 90.768587 -318.368957) (xy 90.902834 -318.432658)
			(xy 91.033469 -318.503474) (xy 91.160114 -318.581199) (xy 91.282404 -318.66561) (xy 91.399987 -318.756463)
			(xy 91.512524 -318.853497) (xy 91.619691 -318.956432) (xy 91.721178 -319.064971) (xy 91.816692 -319.1788)
			(xy 91.905959 -319.297593) (xy 91.98872 -319.421005) (xy 92.064738 -319.548683) (xy 92.133793 -319.680256)
			(xy 92.195686 -319.815347) (xy 92.250239 -319.953564) (xy 92.297294 -320.094511) (xy 92.336716 -320.237781)
			(xy 92.36839 -320.38296) (xy 92.392226 -320.529629) (xy 92.408155 -320.677367) (xy 92.416131 -320.825747)
			(xy 92.41663 -320.900044) (xy 142.982451 -320.900044) (xy 142.98644 -320.751504) (xy 142.998397 -320.603391)
			(xy 143.018287 -320.456134) (xy 143.046052 -320.310158) (xy 143.081613 -320.165881) (xy 143.124867 -320.023722)
			(xy 143.175689 -319.884089) (xy 143.233933 -319.747386) (xy 143.299431 -319.614006) (xy 143.371994 -319.484334)
			(xy 143.451412 -319.358744) (xy 143.537457 -319.237597) (xy 143.629881 -319.121244) (xy 143.728417 -319.01002)
			(xy 143.832781 -318.904245) (xy 143.942673 -318.804225) (xy 144.057774 -318.710247) (xy 144.177754 -318.622583)
			(xy 144.302267 -318.541486) (xy 144.430953 -318.467189) (xy 144.563442 -318.399907) (xy 144.699351 -318.339833)
			(xy 144.838289 -318.287141) (xy 144.979855 -318.241982) (xy 145.123641 -318.204487) (xy 145.269232 -318.174765)
			(xy 145.416208 -318.1529) (xy 145.564147 -318.138956) (xy 145.71262 -318.132972) (xy 145.861201 -318.134967)
			(xy 146.00946 -318.144935) (xy 146.156971 -318.162846) (xy 146.303307 -318.188649) (xy 146.448048 -318.222269)
			(xy 146.590775 -318.263611) (xy 146.731078 -318.312554) (xy 146.868551 -318.368957) (xy 147.002798 -318.432658)
			(xy 147.133433 -318.503474) (xy 147.260078 -318.581199) (xy 147.382368 -318.66561) (xy 147.499951 -318.756463)
			(xy 147.612488 -318.853497) (xy 147.719655 -318.956432) (xy 147.821142 -319.064971) (xy 147.916656 -319.1788)
			(xy 148.005923 -319.297593) (xy 148.088684 -319.421005) (xy 148.164702 -319.548683) (xy 148.233757 -319.680256)
			(xy 148.29565 -319.815347) (xy 148.350203 -319.953564) (xy 148.397258 -320.094511) (xy 148.43668 -320.237781)
			(xy 148.468354 -320.38296) (xy 148.49219 -320.529629) (xy 148.508119 -320.677367) (xy 148.516095 -320.825747)
			(xy 148.516594 -320.900044) (xy 202.982331 -320.900044) (xy 202.98632 -320.751504) (xy 202.998277 -320.603391)
			(xy 203.018167 -320.456134) (xy 203.045932 -320.310158) (xy 203.081493 -320.165881) (xy 203.124747 -320.023722)
			(xy 203.175569 -319.884089) (xy 203.233813 -319.747386) (xy 203.299311 -319.614006) (xy 203.371874 -319.484334)
			(xy 203.451292 -319.358744) (xy 203.537337 -319.237597) (xy 203.629761 -319.121244) (xy 203.728297 -319.01002)
			(xy 203.832661 -318.904245) (xy 203.942553 -318.804225) (xy 204.057654 -318.710247) (xy 204.177634 -318.622583)
			(xy 204.302147 -318.541486) (xy 204.430833 -318.467189) (xy 204.563322 -318.399907) (xy 204.699231 -318.339833)
			(xy 204.838169 -318.287141) (xy 204.979735 -318.241982) (xy 205.123521 -318.204487) (xy 205.269112 -318.174765)
			(xy 205.416088 -318.1529) (xy 205.564027 -318.138956) (xy 205.7125 -318.132972) (xy 205.861081 -318.134967)
			(xy 206.00934 -318.144935) (xy 206.156851 -318.162846) (xy 206.303187 -318.188649) (xy 206.447928 -318.222269)
			(xy 206.590655 -318.263611) (xy 206.730958 -318.312554) (xy 206.868431 -318.368957) (xy 207.002678 -318.432658)
			(xy 207.133313 -318.503474) (xy 207.259958 -318.581199) (xy 207.382248 -318.66561) (xy 207.499831 -318.756463)
			(xy 207.612368 -318.853497) (xy 207.719535 -318.956432) (xy 207.821022 -319.064971) (xy 207.916536 -319.1788)
			(xy 208.005803 -319.297593) (xy 208.088564 -319.421005) (xy 208.164582 -319.548683) (xy 208.233637 -319.680256)
			(xy 208.29553 -319.815347) (xy 208.350083 -319.953564) (xy 208.397138 -320.094511) (xy 208.43656 -320.237781)
			(xy 208.468234 -320.38296) (xy 208.49207 -320.529629) (xy 208.507999 -320.677367) (xy 208.515975 -320.825747)
			(xy 208.516474 -320.900044) (xy 259.082549 -320.900044) (xy 259.086538 -320.751504) (xy 259.098495 -320.603391)
			(xy 259.118385 -320.456134) (xy 259.14615 -320.310158) (xy 259.181711 -320.165881) (xy 259.224965 -320.023722)
			(xy 259.275787 -319.884089) (xy 259.334031 -319.747386) (xy 259.399529 -319.614006) (xy 259.472092 -319.484334)
			(xy 259.55151 -319.358744) (xy 259.637555 -319.237597) (xy 259.729979 -319.121244) (xy 259.828515 -319.01002)
			(xy 259.932879 -318.904245) (xy 260.042771 -318.804225) (xy 260.157872 -318.710247) (xy 260.277852 -318.622583)
			(xy 260.402365 -318.541486) (xy 260.531051 -318.467189) (xy 260.66354 -318.399907) (xy 260.799449 -318.339833)
			(xy 260.938387 -318.287141) (xy 261.079953 -318.241982) (xy 261.223739 -318.204487) (xy 261.36933 -318.174765)
			(xy 261.516306 -318.1529) (xy 261.664245 -318.138956) (xy 261.812718 -318.132972) (xy 261.961299 -318.134967)
			(xy 262.109558 -318.144935) (xy 262.257069 -318.162846) (xy 262.403405 -318.188649) (xy 262.548146 -318.222269)
			(xy 262.690873 -318.263611) (xy 262.831176 -318.312554) (xy 262.968649 -318.368957) (xy 263.102896 -318.432658)
			(xy 263.233531 -318.503474) (xy 263.360176 -318.581199) (xy 263.482466 -318.66561) (xy 263.600049 -318.756463)
			(xy 263.712586 -318.853497) (xy 263.819753 -318.956432) (xy 263.92124 -319.064971) (xy 264.016754 -319.1788)
			(xy 264.106021 -319.297593) (xy 264.188782 -319.421005) (xy 264.2648 -319.548683) (xy 264.333855 -319.680256)
			(xy 264.395748 -319.815347) (xy 264.450301 -319.953564) (xy 264.497356 -320.094511) (xy 264.536778 -320.237781)
			(xy 264.568452 -320.38296) (xy 264.592288 -320.529629) (xy 264.608217 -320.677367) (xy 264.616193 -320.825747)
			(xy 264.616692 -320.900044) (xy 319.082429 -320.900044) (xy 319.086418 -320.751504) (xy 319.098375 -320.603391)
			(xy 319.118265 -320.456134) (xy 319.14603 -320.310158) (xy 319.181591 -320.165881) (xy 319.224845 -320.023722)
			(xy 319.275667 -319.884089) (xy 319.333911 -319.747386) (xy 319.399409 -319.614006) (xy 319.471972 -319.484334)
			(xy 319.55139 -319.358744) (xy 319.637435 -319.237597) (xy 319.729859 -319.121244) (xy 319.828395 -319.01002)
			(xy 319.932759 -318.904245) (xy 320.042651 -318.804225) (xy 320.157752 -318.710247) (xy 320.277732 -318.622583)
			(xy 320.402245 -318.541486) (xy 320.530931 -318.467189) (xy 320.66342 -318.399907) (xy 320.799329 -318.339833)
			(xy 320.938267 -318.287141) (xy 321.079833 -318.241982) (xy 321.223619 -318.204487) (xy 321.36921 -318.174765)
			(xy 321.516186 -318.1529) (xy 321.664125 -318.138956) (xy 321.812598 -318.132972) (xy 321.961179 -318.134967)
			(xy 322.109438 -318.144935) (xy 322.256949 -318.162846) (xy 322.403285 -318.188649) (xy 322.548026 -318.222269)
			(xy 322.690753 -318.263611) (xy 322.831056 -318.312554) (xy 322.968529 -318.368957) (xy 323.102776 -318.432658)
			(xy 323.233411 -318.503474) (xy 323.360056 -318.581199) (xy 323.482346 -318.66561) (xy 323.599929 -318.756463)
			(xy 323.712466 -318.853497) (xy 323.819633 -318.956432) (xy 323.92112 -319.064971) (xy 324.016634 -319.1788)
			(xy 324.105901 -319.297593) (xy 324.188662 -319.421005) (xy 324.26468 -319.548683) (xy 324.333735 -319.680256)
			(xy 324.395628 -319.815347) (xy 324.450181 -319.953564) (xy 324.497236 -320.094511) (xy 324.536658 -320.237781)
			(xy 324.568332 -320.38296) (xy 324.592168 -320.529629) (xy 324.608097 -320.677367) (xy 324.616073 -320.825747)
			(xy 324.616572 -320.900044) (xy 375.182393 -320.900044) (xy 375.186382 -320.751504) (xy 375.198339 -320.603391)
			(xy 375.218229 -320.456134) (xy 375.245994 -320.310158) (xy 375.281555 -320.165881) (xy 375.324809 -320.023722)
			(xy 375.375631 -319.884089) (xy 375.433875 -319.747386) (xy 375.499373 -319.614006) (xy 375.571936 -319.484334)
			(xy 375.651354 -319.358744) (xy 375.737399 -319.237597) (xy 375.829823 -319.121244) (xy 375.928359 -319.01002)
			(xy 376.032723 -318.904245) (xy 376.142615 -318.804225) (xy 376.257716 -318.710247) (xy 376.377696 -318.622583)
			(xy 376.502209 -318.541486) (xy 376.630895 -318.467189) (xy 376.763384 -318.399907) (xy 376.899293 -318.339833)
			(xy 377.038231 -318.287141) (xy 377.179797 -318.241982) (xy 377.323583 -318.204487) (xy 377.469174 -318.174765)
			(xy 377.61615 -318.1529) (xy 377.764089 -318.138956) (xy 377.912562 -318.132972) (xy 378.061143 -318.134967)
			(xy 378.209402 -318.144935) (xy 378.356913 -318.162846) (xy 378.503249 -318.188649) (xy 378.64799 -318.222269)
			(xy 378.790717 -318.263611) (xy 378.93102 -318.312554) (xy 379.068493 -318.368957) (xy 379.20274 -318.432658)
			(xy 379.333375 -318.503474) (xy 379.46002 -318.581199) (xy 379.58231 -318.66561) (xy 379.699893 -318.756463)
			(xy 379.81243 -318.853497) (xy 379.919597 -318.956432) (xy 380.021084 -319.064971) (xy 380.116598 -319.1788)
			(xy 380.205865 -319.297593) (xy 380.288626 -319.421005) (xy 380.364644 -319.548683) (xy 380.433699 -319.680256)
			(xy 380.495592 -319.815347) (xy 380.550145 -319.953564) (xy 380.5972 -320.094511) (xy 380.636622 -320.237781)
			(xy 380.668296 -320.38296) (xy 380.692132 -320.529629) (xy 380.708061 -320.677367) (xy 380.716037 -320.825747)
			(xy 380.716536 -320.900044) (xy 435.182527 -320.900044) (xy 435.186516 -320.751504) (xy 435.198473 -320.603391)
			(xy 435.218363 -320.456134) (xy 435.246128 -320.310158) (xy 435.281689 -320.165881) (xy 435.324943 -320.023722)
			(xy 435.375765 -319.884089) (xy 435.434009 -319.747386) (xy 435.499507 -319.614006) (xy 435.57207 -319.484334)
			(xy 435.651488 -319.358744) (xy 435.737533 -319.237597) (xy 435.829957 -319.121244) (xy 435.928493 -319.01002)
			(xy 436.032857 -318.904245) (xy 436.142749 -318.804225) (xy 436.25785 -318.710247) (xy 436.37783 -318.622583)
			(xy 436.502343 -318.541486) (xy 436.631029 -318.467189) (xy 436.763518 -318.399907) (xy 436.899427 -318.339833)
			(xy 437.038365 -318.287141) (xy 437.179931 -318.241982) (xy 437.323717 -318.204487) (xy 437.469308 -318.174765)
			(xy 437.616284 -318.1529) (xy 437.764223 -318.138956) (xy 437.912696 -318.132972) (xy 438.061277 -318.134967)
			(xy 438.209536 -318.144935) (xy 438.357047 -318.162846) (xy 438.503383 -318.188649) (xy 438.648124 -318.222269)
			(xy 438.790851 -318.263611) (xy 438.931154 -318.312554) (xy 439.068627 -318.368957) (xy 439.202874 -318.432658)
			(xy 439.333509 -318.503474) (xy 439.460154 -318.581199) (xy 439.582444 -318.66561) (xy 439.700027 -318.756463)
			(xy 439.812564 -318.853497) (xy 439.919731 -318.956432) (xy 440.021218 -319.064971) (xy 440.116732 -319.1788)
			(xy 440.205999 -319.297593) (xy 440.28876 -319.421005) (xy 440.364778 -319.548683) (xy 440.433833 -319.680256)
			(xy 440.495726 -319.815347) (xy 440.550279 -319.953564) (xy 440.597334 -320.094511) (xy 440.636756 -320.237781)
			(xy 440.66843 -320.38296) (xy 440.692266 -320.529629) (xy 440.708195 -320.677367) (xy 440.716171 -320.825747)
			(xy 440.71667 -320.900044) (xy 440.716171 -320.974341) (xy 440.708195 -321.122721) (xy 440.692266 -321.270459)
			(xy 440.66843 -321.417128) (xy 440.636756 -321.562307) (xy 440.597334 -321.705577) (xy 440.550279 -321.846524)
			(xy 440.495726 -321.984741) (xy 440.433833 -322.119832) (xy 440.364778 -322.251405) (xy 440.28876 -322.379083)
			(xy 440.205999 -322.502495) (xy 440.116732 -322.621288) (xy 440.021218 -322.735117) (xy 439.919731 -322.843656)
			(xy 439.812564 -322.946591) (xy 439.700027 -323.043625) (xy 439.582444 -323.134478) (xy 439.460154 -323.218889)
			(xy 439.333509 -323.296614) (xy 439.202874 -323.36743) (xy 439.068627 -323.431131) (xy 438.931154 -323.487534)
			(xy 438.790851 -323.536477) (xy 438.648124 -323.577819) (xy 438.503383 -323.611439) (xy 438.357047 -323.637242)
			(xy 438.209536 -323.655153) (xy 438.061277 -323.665121) (xy 437.912696 -323.667116) (xy 437.764223 -323.661132)
			(xy 437.616284 -323.647188) (xy 437.469308 -323.625323) (xy 437.323717 -323.595601) (xy 437.179931 -323.558106)
			(xy 437.038365 -323.512947) (xy 436.899427 -323.460255) (xy 436.763518 -323.400181) (xy 436.631029 -323.332899)
			(xy 436.502343 -323.258602) (xy 436.37783 -323.177505) (xy 436.25785 -323.089841) (xy 436.142749 -322.995863)
			(xy 436.032857 -322.895843) (xy 435.928493 -322.790068) (xy 435.829957 -322.678844) (xy 435.737533 -322.562491)
			(xy 435.651488 -322.441344) (xy 435.57207 -322.315754) (xy 435.499507 -322.186082) (xy 435.434009 -322.052702)
			(xy 435.375765 -321.915999) (xy 435.324943 -321.776366) (xy 435.281689 -321.634207) (xy 435.246128 -321.48993)
			(xy 435.218363 -321.343954) (xy 435.198473 -321.196697) (xy 435.186516 -321.048584) (xy 435.182527 -320.900044)
			(xy 380.716536 -320.900044) (xy 380.716037 -320.974341) (xy 380.708061 -321.122721) (xy 380.692132 -321.270459)
			(xy 380.668296 -321.417128) (xy 380.636622 -321.562307) (xy 380.5972 -321.705577) (xy 380.550145 -321.846524)
			(xy 380.495592 -321.984741) (xy 380.433699 -322.119832) (xy 380.364644 -322.251405) (xy 380.288626 -322.379083)
			(xy 380.205865 -322.502495) (xy 380.116598 -322.621288) (xy 380.021084 -322.735117) (xy 379.919597 -322.843656)
			(xy 379.81243 -322.946591) (xy 379.699893 -323.043625) (xy 379.58231 -323.134478) (xy 379.46002 -323.218889)
			(xy 379.333375 -323.296614) (xy 379.20274 -323.36743) (xy 379.068493 -323.431131) (xy 378.93102 -323.487534)
			(xy 378.790717 -323.536477) (xy 378.64799 -323.577819) (xy 378.503249 -323.611439) (xy 378.356913 -323.637242)
			(xy 378.209402 -323.655153) (xy 378.061143 -323.665121) (xy 377.912562 -323.667116) (xy 377.764089 -323.661132)
			(xy 377.61615 -323.647188) (xy 377.469174 -323.625323) (xy 377.323583 -323.595601) (xy 377.179797 -323.558106)
			(xy 377.038231 -323.512947) (xy 376.899293 -323.460255) (xy 376.763384 -323.400181) (xy 376.630895 -323.332899)
			(xy 376.502209 -323.258602) (xy 376.377696 -323.177505) (xy 376.257716 -323.089841) (xy 376.142615 -322.995863)
			(xy 376.032723 -322.895843) (xy 375.928359 -322.790068) (xy 375.829823 -322.678844) (xy 375.737399 -322.562491)
			(xy 375.651354 -322.441344) (xy 375.571936 -322.315754) (xy 375.499373 -322.186082) (xy 375.433875 -322.052702)
			(xy 375.375631 -321.915999) (xy 375.324809 -321.776366) (xy 375.281555 -321.634207) (xy 375.245994 -321.48993)
			(xy 375.218229 -321.343954) (xy 375.198339 -321.196697) (xy 375.186382 -321.048584) (xy 375.182393 -320.900044)
			(xy 324.616572 -320.900044) (xy 324.616073 -320.974341) (xy 324.608097 -321.122721) (xy 324.592168 -321.270459)
			(xy 324.568332 -321.417128) (xy 324.536658 -321.562307) (xy 324.497236 -321.705577) (xy 324.450181 -321.846524)
			(xy 324.395628 -321.984741) (xy 324.333735 -322.119832) (xy 324.26468 -322.251405) (xy 324.188662 -322.379083)
			(xy 324.105901 -322.502495) (xy 324.016634 -322.621288) (xy 323.92112 -322.735117) (xy 323.819633 -322.843656)
			(xy 323.712466 -322.946591) (xy 323.599929 -323.043625) (xy 323.482346 -323.134478) (xy 323.360056 -323.218889)
			(xy 323.233411 -323.296614) (xy 323.102776 -323.36743) (xy 322.968529 -323.431131) (xy 322.831056 -323.487534)
			(xy 322.690753 -323.536477) (xy 322.548026 -323.577819) (xy 322.403285 -323.611439) (xy 322.256949 -323.637242)
			(xy 322.109438 -323.655153) (xy 321.961179 -323.665121) (xy 321.812598 -323.667116) (xy 321.664125 -323.661132)
			(xy 321.516186 -323.647188) (xy 321.36921 -323.625323) (xy 321.223619 -323.595601) (xy 321.079833 -323.558106)
			(xy 320.938267 -323.512947) (xy 320.799329 -323.460255) (xy 320.66342 -323.400181) (xy 320.530931 -323.332899)
			(xy 320.402245 -323.258602) (xy 320.277732 -323.177505) (xy 320.157752 -323.089841) (xy 320.042651 -322.995863)
			(xy 319.932759 -322.895843) (xy 319.828395 -322.790068) (xy 319.729859 -322.678844) (xy 319.637435 -322.562491)
			(xy 319.55139 -322.441344) (xy 319.471972 -322.315754) (xy 319.399409 -322.186082) (xy 319.333911 -322.052702)
			(xy 319.275667 -321.915999) (xy 319.224845 -321.776366) (xy 319.181591 -321.634207) (xy 319.14603 -321.48993)
			(xy 319.118265 -321.343954) (xy 319.098375 -321.196697) (xy 319.086418 -321.048584) (xy 319.082429 -320.900044)
			(xy 264.616692 -320.900044) (xy 264.616193 -320.974341) (xy 264.608217 -321.122721) (xy 264.592288 -321.270459)
			(xy 264.568452 -321.417128) (xy 264.536778 -321.562307) (xy 264.497356 -321.705577) (xy 264.450301 -321.846524)
			(xy 264.395748 -321.984741) (xy 264.333855 -322.119832) (xy 264.2648 -322.251405) (xy 264.188782 -322.379083)
			(xy 264.106021 -322.502495) (xy 264.016754 -322.621288) (xy 263.92124 -322.735117) (xy 263.819753 -322.843656)
			(xy 263.712586 -322.946591) (xy 263.600049 -323.043625) (xy 263.482466 -323.134478) (xy 263.360176 -323.218889)
			(xy 263.233531 -323.296614) (xy 263.102896 -323.36743) (xy 262.968649 -323.431131) (xy 262.831176 -323.487534)
			(xy 262.690873 -323.536477) (xy 262.548146 -323.577819) (xy 262.403405 -323.611439) (xy 262.257069 -323.637242)
			(xy 262.109558 -323.655153) (xy 261.961299 -323.665121) (xy 261.812718 -323.667116) (xy 261.664245 -323.661132)
			(xy 261.516306 -323.647188) (xy 261.36933 -323.625323) (xy 261.223739 -323.595601) (xy 261.079953 -323.558106)
			(xy 260.938387 -323.512947) (xy 260.799449 -323.460255) (xy 260.66354 -323.400181) (xy 260.531051 -323.332899)
			(xy 260.402365 -323.258602) (xy 260.277852 -323.177505) (xy 260.157872 -323.089841) (xy 260.042771 -322.995863)
			(xy 259.932879 -322.895843) (xy 259.828515 -322.790068) (xy 259.729979 -322.678844) (xy 259.637555 -322.562491)
			(xy 259.55151 -322.441344) (xy 259.472092 -322.315754) (xy 259.399529 -322.186082) (xy 259.334031 -322.052702)
			(xy 259.275787 -321.915999) (xy 259.224965 -321.776366) (xy 259.181711 -321.634207) (xy 259.14615 -321.48993)
			(xy 259.118385 -321.343954) (xy 259.098495 -321.196697) (xy 259.086538 -321.048584) (xy 259.082549 -320.900044)
			(xy 208.516474 -320.900044) (xy 208.515975 -320.974341) (xy 208.507999 -321.122721) (xy 208.49207 -321.270459)
			(xy 208.468234 -321.417128) (xy 208.43656 -321.562307) (xy 208.397138 -321.705577) (xy 208.350083 -321.846524)
			(xy 208.29553 -321.984741) (xy 208.233637 -322.119832) (xy 208.164582 -322.251405) (xy 208.088564 -322.379083)
			(xy 208.005803 -322.502495) (xy 207.916536 -322.621288) (xy 207.821022 -322.735117) (xy 207.719535 -322.843656)
			(xy 207.612368 -322.946591) (xy 207.499831 -323.043625) (xy 207.382248 -323.134478) (xy 207.259958 -323.218889)
			(xy 207.133313 -323.296614) (xy 207.002678 -323.36743) (xy 206.868431 -323.431131) (xy 206.730958 -323.487534)
			(xy 206.590655 -323.536477) (xy 206.447928 -323.577819) (xy 206.303187 -323.611439) (xy 206.156851 -323.637242)
			(xy 206.00934 -323.655153) (xy 205.861081 -323.665121) (xy 205.7125 -323.667116) (xy 205.564027 -323.661132)
			(xy 205.416088 -323.647188) (xy 205.269112 -323.625323) (xy 205.123521 -323.595601) (xy 204.979735 -323.558106)
			(xy 204.838169 -323.512947) (xy 204.699231 -323.460255) (xy 204.563322 -323.400181) (xy 204.430833 -323.332899)
			(xy 204.302147 -323.258602) (xy 204.177634 -323.177505) (xy 204.057654 -323.089841) (xy 203.942553 -322.995863)
			(xy 203.832661 -322.895843) (xy 203.728297 -322.790068) (xy 203.629761 -322.678844) (xy 203.537337 -322.562491)
			(xy 203.451292 -322.441344) (xy 203.371874 -322.315754) (xy 203.299311 -322.186082) (xy 203.233813 -322.052702)
			(xy 203.175569 -321.915999) (xy 203.124747 -321.776366) (xy 203.081493 -321.634207) (xy 203.045932 -321.48993)
			(xy 203.018167 -321.343954) (xy 202.998277 -321.196697) (xy 202.98632 -321.048584) (xy 202.982331 -320.900044)
			(xy 148.516594 -320.900044) (xy 148.516095 -320.974341) (xy 148.508119 -321.122721) (xy 148.49219 -321.270459)
			(xy 148.468354 -321.417128) (xy 148.43668 -321.562307) (xy 148.397258 -321.705577) (xy 148.350203 -321.846524)
			(xy 148.29565 -321.984741) (xy 148.233757 -322.119832) (xy 148.164702 -322.251405) (xy 148.088684 -322.379083)
			(xy 148.005923 -322.502495) (xy 147.916656 -322.621288) (xy 147.821142 -322.735117) (xy 147.719655 -322.843656)
			(xy 147.612488 -322.946591) (xy 147.499951 -323.043625) (xy 147.382368 -323.134478) (xy 147.260078 -323.218889)
			(xy 147.133433 -323.296614) (xy 147.002798 -323.36743) (xy 146.868551 -323.431131) (xy 146.731078 -323.487534)
			(xy 146.590775 -323.536477) (xy 146.448048 -323.577819) (xy 146.303307 -323.611439) (xy 146.156971 -323.637242)
			(xy 146.00946 -323.655153) (xy 145.861201 -323.665121) (xy 145.71262 -323.667116) (xy 145.564147 -323.661132)
			(xy 145.416208 -323.647188) (xy 145.269232 -323.625323) (xy 145.123641 -323.595601) (xy 144.979855 -323.558106)
			(xy 144.838289 -323.512947) (xy 144.699351 -323.460255) (xy 144.563442 -323.400181) (xy 144.430953 -323.332899)
			(xy 144.302267 -323.258602) (xy 144.177754 -323.177505) (xy 144.057774 -323.089841) (xy 143.942673 -322.995863)
			(xy 143.832781 -322.895843) (xy 143.728417 -322.790068) (xy 143.629881 -322.678844) (xy 143.537457 -322.562491)
			(xy 143.451412 -322.441344) (xy 143.371994 -322.315754) (xy 143.299431 -322.186082) (xy 143.233933 -322.052702)
			(xy 143.175689 -321.915999) (xy 143.124867 -321.776366) (xy 143.081613 -321.634207) (xy 143.046052 -321.48993)
			(xy 143.018287 -321.343954) (xy 142.998397 -321.196697) (xy 142.98644 -321.048584) (xy 142.982451 -320.900044)
			(xy 92.41663 -320.900044) (xy 92.416131 -320.974341) (xy 92.408155 -321.122721) (xy 92.392226 -321.270459)
			(xy 92.36839 -321.417128) (xy 92.336716 -321.562307) (xy 92.297294 -321.705577) (xy 92.250239 -321.846524)
			(xy 92.195686 -321.984741) (xy 92.133793 -322.119832) (xy 92.064738 -322.251405) (xy 91.98872 -322.379083)
			(xy 91.905959 -322.502495) (xy 91.816692 -322.621288) (xy 91.721178 -322.735117) (xy 91.619691 -322.843656)
			(xy 91.512524 -322.946591) (xy 91.399987 -323.043625) (xy 91.282404 -323.134478) (xy 91.160114 -323.218889)
			(xy 91.033469 -323.296614) (xy 90.902834 -323.36743) (xy 90.768587 -323.431131) (xy 90.631114 -323.487534)
			(xy 90.490811 -323.536477) (xy 90.348084 -323.577819) (xy 90.203343 -323.611439) (xy 90.057007 -323.637242)
			(xy 89.909496 -323.655153) (xy 89.761237 -323.665121) (xy 89.612656 -323.667116) (xy 89.464183 -323.661132)
			(xy 89.316244 -323.647188) (xy 89.169268 -323.625323) (xy 89.023677 -323.595601) (xy 88.879891 -323.558106)
			(xy 88.738325 -323.512947) (xy 88.599387 -323.460255) (xy 88.463478 -323.400181) (xy 88.330989 -323.332899)
			(xy 88.202303 -323.258602) (xy 88.07779 -323.177505) (xy 87.95781 -323.089841) (xy 87.842709 -322.995863)
			(xy 87.732817 -322.895843) (xy 87.628453 -322.790068) (xy 87.529917 -322.678844) (xy 87.437493 -322.562491)
			(xy 87.351448 -322.441344) (xy 87.27203 -322.315754) (xy 87.199467 -322.186082) (xy 87.133969 -322.052702)
			(xy 87.075725 -321.915999) (xy 87.024903 -321.776366) (xy 86.981649 -321.634207) (xy 86.946088 -321.48993)
			(xy 86.918323 -321.343954) (xy 86.898433 -321.196697) (xy 86.886476 -321.048584) (xy 86.882487 -320.900044)
			(xy 32.416496 -320.900044) (xy 32.415997 -320.974341) (xy 32.408021 -321.122721) (xy 32.392092 -321.270459)
			(xy 32.368256 -321.417128) (xy 32.336582 -321.562307) (xy 32.29716 -321.705577) (xy 32.250105 -321.846524)
			(xy 32.195552 -321.984741) (xy 32.133659 -322.119832) (xy 32.064604 -322.251405) (xy 31.988586 -322.379083)
			(xy 31.905825 -322.502495) (xy 31.816558 -322.621288) (xy 31.721044 -322.735117) (xy 31.619557 -322.843656)
			(xy 31.51239 -322.946591) (xy 31.399853 -323.043625) (xy 31.28227 -323.134478) (xy 31.15998 -323.218889)
			(xy 31.033335 -323.296614) (xy 30.9027 -323.36743) (xy 30.768453 -323.431131) (xy 30.63098 -323.487534)
			(xy 30.490677 -323.536477) (xy 30.34795 -323.577819) (xy 30.203209 -323.611439) (xy 30.056873 -323.637242)
			(xy 29.909362 -323.655153) (xy 29.761103 -323.665121) (xy 29.612522 -323.667116) (xy 29.464049 -323.661132)
			(xy 29.31611 -323.647188) (xy 29.169134 -323.625323) (xy 29.023543 -323.595601) (xy 28.879757 -323.558106)
			(xy 28.738191 -323.512947) (xy 28.599253 -323.460255) (xy 28.463344 -323.400181) (xy 28.330855 -323.332899)
			(xy 28.202169 -323.258602) (xy 28.077656 -323.177505) (xy 27.957676 -323.089841) (xy 27.842575 -322.995863)
			(xy 27.732683 -322.895843) (xy 27.628319 -322.790068) (xy 27.529783 -322.678844) (xy 27.437359 -322.562491)
			(xy 27.351314 -322.441344) (xy 27.271896 -322.315754) (xy 27.199333 -322.186082) (xy 27.133835 -322.052702)
			(xy 27.075591 -321.915999) (xy 27.024769 -321.776366) (xy 26.981515 -321.634207) (xy 26.945954 -321.48993)
			(xy 26.918189 -321.343954) (xy 26.898299 -321.196697) (xy 26.886342 -321.048584) (xy 26.882353 -320.900044)
			(xy 0.509016 -320.900044) (xy 0.509016 -330.416662) (xy 97.355152 -330.416662) (xy 97.355152 -329.553062)
			(xy 97.355642 -329.523078) (xy 97.36347 -329.463622) (xy 97.378991 -329.405697) (xy 97.40194 -329.350293)
			(xy 97.431924 -329.298359) (xy 97.46843 -329.250783) (xy 97.510835 -329.208378) (xy 97.558411 -329.171872)
			(xy 97.610345 -329.141888) (xy 97.665749 -329.118939) (xy 97.723674 -329.103418) (xy 97.78313 -329.09559)
			(xy 97.843098 -329.09559) (xy 97.902554 -329.103418) (xy 97.960479 -329.118939) (xy 98.015883 -329.141888)
			(xy 98.067817 -329.171872) (xy 98.115393 -329.208378) (xy 98.157798 -329.250783) (xy 98.194304 -329.298359)
			(xy 98.224288 -329.350293) (xy 98.247237 -329.405697) (xy 98.262758 -329.463622) (xy 98.270586 -329.523078)
			(xy 98.271076 -329.553062) (xy 98.271076 -330.416662) (xy 98.270586 -330.446646) (xy 98.262758 -330.506102)
			(xy 98.247237 -330.564027) (xy 98.224288 -330.619431) (xy 98.194304 -330.671365) (xy 98.157798 -330.718941)
			(xy 98.115393 -330.761346) (xy 98.067817 -330.797852) (xy 98.015883 -330.827836) (xy 97.960479 -330.850785)
			(xy 97.902554 -330.866306) (xy 97.843098 -330.874134) (xy 97.78313 -330.874134) (xy 97.723674 -330.866306)
			(xy 97.665749 -330.850785) (xy 97.610345 -330.827836) (xy 97.558411 -330.797852) (xy 97.510835 -330.761346)
			(xy 97.46843 -330.718941) (xy 97.431924 -330.671365) (xy 97.40194 -330.619431) (xy 97.378991 -330.564027)
			(xy 97.36347 -330.506102) (xy 97.355642 -330.446646) (xy 97.355152 -330.416662) (xy 0.509016 -330.416662)
			(xy 0.509016 -331.53223) (xy 114.955828 -331.53223) (xy 114.955828 -330.66863) (xy 114.956318 -330.638646)
			(xy 114.964146 -330.57919) (xy 114.979667 -330.521265) (xy 115.002616 -330.465861) (xy 115.0326 -330.413927)
			(xy 115.069106 -330.366351) (xy 115.111511 -330.323946) (xy 115.159087 -330.28744) (xy 115.211021 -330.257456)
			(xy 115.266425 -330.234507) (xy 115.32435 -330.218986) (xy 115.383806 -330.211158) (xy 115.443774 -330.211158)
			(xy 115.50323 -330.218986) (xy 115.561155 -330.234507) (xy 115.616559 -330.257456) (xy 115.668493 -330.28744)
			(xy 115.716069 -330.323946) (xy 115.758474 -330.366351) (xy 115.79498 -330.413927) (xy 115.824964 -330.465861)
			(xy 115.847913 -330.521265) (xy 115.863434 -330.57919) (xy 115.871262 -330.638646) (xy 115.871752 -330.66863)
			(xy 115.871752 -331.53223) (xy 115.871262 -331.562214) (xy 115.863434 -331.62167) (xy 115.847913 -331.679595)
			(xy 115.824964 -331.734999) (xy 115.79498 -331.786933) (xy 115.758474 -331.834509) (xy 115.716069 -331.876914)
			(xy 115.668493 -331.91342) (xy 115.616559 -331.943404) (xy 115.561155 -331.966353) (xy 115.50323 -331.981874)
			(xy 115.443774 -331.989702) (xy 115.383806 -331.989702) (xy 115.32435 -331.981874) (xy 115.266425 -331.966353)
			(xy 115.211021 -331.943404) (xy 115.159087 -331.91342) (xy 115.111511 -331.876914) (xy 115.069106 -331.834509)
			(xy 115.0326 -331.786933) (xy 115.002616 -331.734999) (xy 114.979667 -331.679595) (xy 114.964146 -331.62167)
			(xy 114.956318 -331.562214) (xy 114.955828 -331.53223) (xy 0.509016 -331.53223) (xy 0.509016 -333.950056)
			(xy 93.5736 -333.950056) (xy 93.5736 -333.086456) (xy 93.57409 -333.056488) (xy 93.581913 -332.997066)
			(xy 93.597426 -332.939173) (xy 93.620362 -332.8838) (xy 93.650329 -332.831894) (xy 93.686816 -332.784344)
			(xy 93.729196 -332.741964) (xy 93.776746 -332.705477) (xy 93.828652 -332.67551) (xy 93.884025 -332.652574)
			(xy 93.941918 -332.637061) (xy 94.00134 -332.629238) (xy 94.061276 -332.629238) (xy 94.120698 -332.637061)
			(xy 94.178591 -332.652574) (xy 94.233964 -332.67551) (xy 94.28587 -332.705477) (xy 94.33342 -332.741964)
			(xy 94.3758 -332.784344) (xy 94.412287 -332.831894) (xy 94.442254 -332.8838) (xy 94.46519 -332.939173)
			(xy 94.46736 -332.947271) (xy 365.368753 -332.947271) (xy 365.368753 -332.887329) (xy 365.376578 -332.827899)
			(xy 365.392093 -332.77) (xy 365.415033 -332.71462) (xy 365.445006 -332.66271) (xy 365.481498 -332.615155)
			(xy 365.523886 -332.572772) (xy 365.571443 -332.536283) (xy 365.623356 -332.506315) (xy 365.678737 -332.48338)
			(xy 365.736639 -332.46787) (xy 365.796069 -332.460051) (xy 365.82604 -332.459584) (xy 366.68964 -332.459584)
			(xy 366.719605 -332.460093) (xy 366.779023 -332.46792) (xy 366.836911 -332.483435) (xy 366.892278 -332.506374)
			(xy 366.944178 -332.536342) (xy 366.991723 -332.572828) (xy 367.034098 -332.615207) (xy 367.07058 -332.662755)
			(xy 367.100544 -332.714658) (xy 367.123478 -332.770027) (xy 367.138988 -332.827916) (xy 367.14681 -332.887335)
			(xy 367.14681 -332.947265) (xy 367.138988 -333.006684) (xy 367.123478 -333.064573) (xy 367.100544 -333.119942)
			(xy 367.07058 -333.171845) (xy 367.034098 -333.219393) (xy 366.991723 -333.261772) (xy 366.944178 -333.298258)
			(xy 366.892278 -333.328226) (xy 366.836911 -333.351165) (xy 366.779023 -333.36668) (xy 366.719605 -333.374507)
			(xy 366.68964 -333.375) (xy 365.82604 -333.375) (xy 365.796069 -333.374549) (xy 365.736639 -333.36673)
			(xy 365.678737 -333.35122) (xy 365.623356 -333.328285) (xy 365.571443 -333.298317) (xy 365.523886 -333.261828)
			(xy 365.481498 -333.219445) (xy 365.445006 -333.17189) (xy 365.415033 -333.11998) (xy 365.392093 -333.0646)
			(xy 365.376578 -333.006701) (xy 365.368753 -332.947271) (xy 94.46736 -332.947271) (xy 94.480703 -332.997066)
			(xy 94.488526 -333.056488) (xy 94.489016 -333.086456) (xy 94.489016 -333.950056) (xy 94.488526 -333.980024)
			(xy 94.480703 -334.039446) (xy 94.46519 -334.097339) (xy 94.442254 -334.152712) (xy 94.412287 -334.204618)
			(xy 94.3758 -334.252168) (xy 94.33342 -334.294548) (xy 94.28587 -334.331035) (xy 94.233964 -334.361002)
			(xy 94.178591 -334.383938) (xy 94.120698 -334.399451) (xy 94.061276 -334.407274) (xy 94.00134 -334.407274)
			(xy 93.941918 -334.399451) (xy 93.884025 -334.383938) (xy 93.828652 -334.361002) (xy 93.776746 -334.331035)
			(xy 93.729196 -334.294548) (xy 93.686816 -334.252168) (xy 93.650329 -334.204618) (xy 93.620362 -334.152712)
			(xy 93.597426 -334.097339) (xy 93.581913 -334.039446) (xy 93.57409 -333.980024) (xy 93.5736 -333.950056)
			(xy 0.509016 -333.950056) (xy 0.509016 -337.266026) (xy 234.403392 -337.266026) (xy 234.403392 -336.402426)
			(xy 234.403882 -336.372458) (xy 234.411705 -336.313036) (xy 234.427218 -336.255143) (xy 234.450154 -336.19977)
			(xy 234.480121 -336.147864) (xy 234.516608 -336.100314) (xy 234.558988 -336.057934) (xy 234.606538 -336.021447)
			(xy 234.658444 -335.99148) (xy 234.713817 -335.968544) (xy 234.77171 -335.953031) (xy 234.831132 -335.945208)
			(xy 234.891068 -335.945208) (xy 234.95049 -335.953031) (xy 235.008383 -335.968544) (xy 235.063756 -335.99148)
			(xy 235.115662 -336.021447) (xy 235.163212 -336.057934) (xy 235.205592 -336.100314) (xy 235.242079 -336.147864)
			(xy 235.272046 -336.19977) (xy 235.294982 -336.255143) (xy 235.310495 -336.313036) (xy 235.318318 -336.372458)
			(xy 235.318808 -336.402426) (xy 235.318808 -337.266026) (xy 235.318318 -337.295994) (xy 235.310495 -337.355416)
			(xy 235.294982 -337.413309) (xy 235.272046 -337.468682) (xy 235.242079 -337.520588) (xy 235.205592 -337.568138)
			(xy 235.163212 -337.610518) (xy 235.115662 -337.647005) (xy 235.063756 -337.676972) (xy 235.008383 -337.699908)
			(xy 234.95049 -337.715421) (xy 234.891068 -337.723244) (xy 234.831132 -337.723244) (xy 234.77171 -337.715421)
			(xy 234.713817 -337.699908) (xy 234.658444 -337.676972) (xy 234.606538 -337.647005) (xy 234.558988 -337.610518)
			(xy 234.516608 -337.568138) (xy 234.480121 -337.520588) (xy 234.450154 -337.468682) (xy 234.427218 -337.413309)
			(xy 234.411705 -337.355416) (xy 234.403882 -337.295994) (xy 234.403392 -337.266026) (xy 0.509016 -337.266026)
			(xy 0.509016 -342.466769) (xy 18.951172 -342.466769) (xy 18.951172 -342.412231) (xy 18.958934 -342.358247)
			(xy 18.974299 -342.305917) (xy 18.996956 -342.256307) (xy 19.026441 -342.210426) (xy 19.062157 -342.169208)
			(xy 19.103374 -342.133493) (xy 19.149255 -342.104007) (xy 19.198865 -342.08135) (xy 19.251195 -342.065985)
			(xy 19.305179 -342.058223) (xy 19.332448 -342.057736) (xy 20.196048 -342.057736) (xy 20.223319 -342.058203)
			(xy 20.277306 -342.065965) (xy 20.329638 -342.081331) (xy 20.379252 -342.103989) (xy 20.425135 -342.133476)
			(xy 20.466355 -342.169193) (xy 20.502073 -342.210413) (xy 20.53156 -342.256297) (xy 20.554218 -342.30591)
			(xy 20.569584 -342.358242) (xy 20.577347 -342.412229) (xy 20.577347 -342.466771) (xy 20.577347 -342.466772)
			(xy 22.0601 -342.466772) (xy 22.0601 -342.412228) (xy 22.067862 -342.358241) (xy 22.083229 -342.305907)
			(xy 22.105887 -342.256293) (xy 22.135375 -342.210409) (xy 22.171094 -342.169188) (xy 22.212315 -342.133471)
			(xy 22.2582 -342.103983) (xy 22.307815 -342.081326) (xy 22.360148 -342.06596) (xy 22.414136 -342.058199)
			(xy 22.441408 -342.057736) (xy 23.305008 -342.057736) (xy 23.332277 -342.058227) (xy 23.386259 -342.06599)
			(xy 23.438588 -342.081355) (xy 23.488197 -342.104012) (xy 23.534076 -342.133498) (xy 23.575293 -342.169213)
			(xy 23.611007 -342.21043) (xy 23.640492 -342.256311) (xy 23.663147 -342.30592) (xy 23.678512 -342.358249)
			(xy 23.686274 -342.412231) (xy 23.686274 -342.466768) (xy 25.169122 -342.466768) (xy 25.169122 -342.412232)
			(xy 25.176883 -342.358251) (xy 25.192247 -342.305924) (xy 25.214901 -342.256315) (xy 25.244384 -342.210436)
			(xy 25.280096 -342.169219) (xy 25.32131 -342.133503) (xy 25.367187 -342.104016) (xy 25.416794 -342.081358)
			(xy 25.46912 -342.06599) (xy 25.5231 -342.058225) (xy 25.550368 -342.057736) (xy 26.413968 -342.057736)
			(xy 26.44124 -342.058201) (xy 26.49523 -342.06596) (xy 26.547567 -342.081323) (xy 26.597184 -342.103979)
			(xy 26.643071 -342.133465) (xy 26.684295 -342.169183) (xy 26.720015 -342.210403) (xy 26.749506 -342.256288)
			(xy 26.772166 -342.305903) (xy 26.787533 -342.358238) (xy 26.795296 -342.412228) (xy 26.795296 -342.466772)
			(xy 28.278 -342.466772) (xy 28.278 -342.412228) (xy 28.285762 -342.358238) (xy 28.30113 -342.305903)
			(xy 28.32379 -342.256288) (xy 28.35328 -342.210402) (xy 28.389001 -342.169181) (xy 28.430225 -342.133464)
			(xy 28.476112 -342.103977) (xy 28.525729 -342.08132) (xy 28.578065 -342.065957) (xy 28.632056 -342.058198)
			(xy 28.659328 -342.057736) (xy 29.522928 -342.057736) (xy 29.550196 -342.058228) (xy 29.604176 -342.065993)
			(xy 29.656502 -342.081361) (xy 29.706109 -342.104019) (xy 29.751986 -342.133505) (xy 29.7932 -342.16922)
			(xy 29.828912 -342.210437) (xy 29.858395 -342.256316) (xy 29.881049 -342.305924) (xy 29.896413 -342.358251)
			(xy 29.904174 -342.412232) (xy 29.904174 -342.466768) (xy 29.904174 -342.466769) (xy 31.387022 -342.466769)
			(xy 31.387022 -342.412231) (xy 31.394784 -342.358248) (xy 31.410149 -342.305919) (xy 31.432804 -342.25631)
			(xy 31.462289 -342.210429) (xy 31.498003 -342.169212) (xy 31.53922 -342.133496) (xy 31.585099 -342.10401)
			(xy 31.634708 -342.081353) (xy 31.687036 -342.065986) (xy 31.741019 -342.058223) (xy 31.768288 -342.057736)
			(xy 32.631888 -342.057736) (xy 32.659159 -342.058203) (xy 32.713147 -342.065963) (xy 32.765481 -342.081329)
			(xy 32.815096 -342.103985) (xy 32.86098 -342.133472) (xy 32.902202 -342.16919) (xy 32.93792 -342.21041)
			(xy 32.967409 -342.256294) (xy 32.990067 -342.305908) (xy 33.005434 -342.358241) (xy 33.013196 -342.412229)
			(xy 33.013196 -342.466771) (xy 33.013196 -342.466773) (xy 34.4959 -342.466773) (xy 34.4959 -342.412227)
			(xy 34.503663 -342.358235) (xy 34.519032 -342.305899) (xy 34.541693 -342.256282) (xy 34.571185 -342.210396)
			(xy 34.606908 -342.169174) (xy 34.648134 -342.133456) (xy 34.694024 -342.10397) (xy 34.743644 -342.081315)
			(xy 34.795982 -342.065953) (xy 34.849975 -342.058196) (xy 34.877248 -342.057736) (xy 35.740848 -342.057736)
			(xy 35.768115 -342.05823) (xy 35.822093 -342.065997) (xy 35.874417 -342.081366) (xy 35.92402 -342.104025)
			(xy 35.969895 -342.133512) (xy 36.011107 -342.169227) (xy 36.046817 -342.210443) (xy 36.076298 -342.256322)
			(xy 36.098951 -342.305928) (xy 36.114313 -342.358254) (xy 36.122074 -342.412233) (xy 36.122074 -342.466767)
			(xy 36.122073 -342.466772) (xy 37.6049 -342.466772) (xy 37.6049 -342.412228) (xy 37.612662 -342.358241)
			(xy 37.628029 -342.305907) (xy 37.650687 -342.256293) (xy 37.680175 -342.210409) (xy 37.715894 -342.169188)
			(xy 37.757115 -342.133471) (xy 37.803 -342.103983) (xy 37.852615 -342.081326) (xy 37.904948 -342.06596)
			(xy 37.958936 -342.058199) (xy 37.986208 -342.057736) (xy 38.849808 -342.057736) (xy 38.877077 -342.058227)
			(xy 38.931059 -342.06599) (xy 38.983388 -342.081355) (xy 39.032997 -342.104012) (xy 39.078876 -342.133498)
			(xy 39.120093 -342.169213) (xy 39.155807 -342.21043) (xy 39.185292 -342.256311) (xy 39.207947 -342.30592)
			(xy 39.223312 -342.358249) (xy 39.231074 -342.412231) (xy 39.231074 -342.466768) (xy 40.713922 -342.466768)
			(xy 40.713922 -342.412232) (xy 40.721683 -342.358251) (xy 40.737047 -342.305924) (xy 40.759701 -342.256315)
			(xy 40.789184 -342.210436) (xy 40.824896 -342.169219) (xy 40.86611 -342.133503) (xy 40.911987 -342.104016)
			(xy 40.961594 -342.081358) (xy 41.01392 -342.06599) (xy 41.0679 -342.058225) (xy 41.095168 -342.057736)
			(xy 41.958768 -342.057736) (xy 41.98604 -342.058201) (xy 42.04003 -342.06596) (xy 42.092367 -342.081323)
			(xy 42.141984 -342.103979) (xy 42.187871 -342.133465) (xy 42.229095 -342.169183) (xy 42.264815 -342.210403)
			(xy 42.294306 -342.256288) (xy 42.316966 -342.305903) (xy 42.332333 -342.358238) (xy 42.340096 -342.412228)
			(xy 42.340096 -342.466772) (xy 43.8228 -342.466772) (xy 43.8228 -342.412228) (xy 43.830562 -342.358238)
			(xy 43.84593 -342.305903) (xy 43.86859 -342.256288) (xy 43.89808 -342.210402) (xy 43.933801 -342.169181)
			(xy 43.975025 -342.133464) (xy 44.020912 -342.103977) (xy 44.070529 -342.08132) (xy 44.122865 -342.065957)
			(xy 44.176856 -342.058198) (xy 44.204128 -342.057736) (xy 45.067728 -342.057736) (xy 45.094996 -342.058228)
			(xy 45.148976 -342.065993) (xy 45.201302 -342.081361) (xy 45.250909 -342.104019) (xy 45.296786 -342.133505)
			(xy 45.338 -342.16922) (xy 45.373712 -342.210437) (xy 45.403195 -342.256316) (xy 45.425849 -342.305924)
			(xy 45.441213 -342.358251) (xy 45.448974 -342.412232) (xy 45.448974 -342.466768) (xy 45.448974 -342.466769)
			(xy 46.931822 -342.466769) (xy 46.931822 -342.412231) (xy 46.939584 -342.358248) (xy 46.954949 -342.305919)
			(xy 46.977604 -342.25631) (xy 47.007089 -342.210429) (xy 47.042803 -342.169212) (xy 47.08402 -342.133496)
			(xy 47.129899 -342.10401) (xy 47.179508 -342.081353) (xy 47.231836 -342.065986) (xy 47.285819 -342.058223)
			(xy 47.313088 -342.057736) (xy 48.176688 -342.057736) (xy 48.203959 -342.058203) (xy 48.257947 -342.065963)
			(xy 48.310281 -342.081329) (xy 48.359896 -342.103985) (xy 48.40578 -342.133472) (xy 48.447002 -342.16919)
			(xy 48.48272 -342.21041) (xy 48.512209 -342.256294) (xy 48.534867 -342.305908) (xy 48.550234 -342.358241)
			(xy 48.557996 -342.412229) (xy 48.557996 -342.466771) (xy 48.557996 -342.466773) (xy 50.0407 -342.466773)
			(xy 50.0407 -342.412227) (xy 50.048463 -342.358235) (xy 50.063832 -342.305899) (xy 50.086493 -342.256282)
			(xy 50.115985 -342.210396) (xy 50.151708 -342.169174) (xy 50.192934 -342.133456) (xy 50.238824 -342.10397)
			(xy 50.288444 -342.081315) (xy 50.340782 -342.065953) (xy 50.394775 -342.058196) (xy 50.422048 -342.057736)
			(xy 51.285648 -342.057736) (xy 51.312915 -342.05823) (xy 51.366893 -342.065997) (xy 51.419217 -342.081366)
			(xy 51.46882 -342.104025) (xy 51.514695 -342.133512) (xy 51.555907 -342.169227) (xy 51.591617 -342.210443)
			(xy 51.621098 -342.256322) (xy 51.643751 -342.305928) (xy 51.659113 -342.358254) (xy 51.666874 -342.412233)
			(xy 51.666874 -342.466767) (xy 51.666873 -342.466773) (xy 60.9909 -342.466773) (xy 60.9909 -342.412227)
			(xy 60.998663 -342.358236) (xy 61.014031 -342.3059) (xy 61.036692 -342.256284) (xy 61.066184 -342.210398)
			(xy 61.101906 -342.169176) (xy 61.143131 -342.133459) (xy 61.18902 -342.103972) (xy 61.238639 -342.081317)
			(xy 61.290977 -342.065954) (xy 61.344969 -342.058197) (xy 61.372242 -342.057736) (xy 62.235842 -342.057736)
			(xy 62.263109 -342.058229) (xy 62.317088 -342.065996) (xy 62.369412 -342.081365) (xy 62.419017 -342.104023)
			(xy 62.464892 -342.13351) (xy 62.506105 -342.169225) (xy 62.541815 -342.210441) (xy 62.571297 -342.25632)
			(xy 62.59395 -342.305927) (xy 62.609313 -342.358253) (xy 62.617074 -342.412233) (xy 62.617074 -342.466767)
			(xy 62.617073 -342.466771) (xy 64.099899 -342.466771) (xy 64.099899 -342.412229) (xy 64.107662 -342.358241)
			(xy 64.123028 -342.305908) (xy 64.145686 -342.256295) (xy 64.175174 -342.210411) (xy 64.210892 -342.16919)
			(xy 64.252112 -342.133473) (xy 64.297997 -342.103985) (xy 64.34761 -342.081327) (xy 64.399943 -342.065961)
			(xy 64.453931 -342.058199) (xy 64.481202 -342.057736) (xy 65.344802 -342.057736) (xy 65.372071 -342.058227)
			(xy 65.426054 -342.065988) (xy 65.478383 -342.081354) (xy 65.527993 -342.10401) (xy 65.573873 -342.133496)
			(xy 65.615091 -342.169211) (xy 65.650805 -342.210428) (xy 65.680291 -342.256309) (xy 65.702947 -342.305919)
			(xy 65.718312 -342.358248) (xy 65.726074 -342.412231) (xy 65.726074 -342.466768) (xy 67.208922 -342.466768)
			(xy 67.208922 -342.412232) (xy 67.216683 -342.358252) (xy 67.232047 -342.305925) (xy 67.2547 -342.256317)
			(xy 67.284183 -342.210438) (xy 67.319894 -342.169221) (xy 67.361107 -342.133505) (xy 67.406984 -342.104018)
			(xy 67.456589 -342.08136) (xy 67.508914 -342.065991) (xy 67.562894 -342.058225) (xy 67.590162 -342.057736)
			(xy 68.453762 -342.057736) (xy 68.481035 -342.058201) (xy 68.535025 -342.065959) (xy 68.587362 -342.081321)
			(xy 68.63698 -342.103977) (xy 68.682868 -342.133463) (xy 68.724093 -342.16918) (xy 68.759814 -342.210401)
			(xy 68.789305 -342.256287) (xy 68.811965 -342.305902) (xy 68.827333 -342.358237) (xy 68.835096 -342.412227)
			(xy 68.835096 -342.466772) (xy 70.3178 -342.466772) (xy 70.3178 -342.412228) (xy 70.325562 -342.358239)
			(xy 70.34093 -342.305904) (xy 70.363589 -342.256289) (xy 70.393079 -342.210404) (xy 70.428799 -342.169183)
			(xy 70.470022 -342.133466) (xy 70.515909 -342.103979) (xy 70.565525 -342.081322) (xy 70.61786 -342.065958)
			(xy 70.67185 -342.058198) (xy 70.699122 -342.057736) (xy 71.562722 -342.057736) (xy 71.58999 -342.058228)
			(xy 71.643971 -342.065992) (xy 71.696298 -342.081359) (xy 71.745905 -342.104017) (xy 71.791783 -342.133503)
			(xy 71.832998 -342.169218) (xy 71.86871 -342.210435) (xy 71.898194 -342.256314) (xy 71.920848 -342.305923)
			(xy 71.936213 -342.35825) (xy 71.943974 -342.412232) (xy 71.943974 -342.466768) (xy 71.943974 -342.466769)
			(xy 73.426822 -342.466769) (xy 73.426822 -342.412231) (xy 73.434584 -342.358249) (xy 73.449948 -342.305921)
			(xy 73.472603 -342.256311) (xy 73.502087 -342.210431) (xy 73.537801 -342.169214) (xy 73.579017 -342.133498)
			(xy 73.624896 -342.104012) (xy 73.674504 -342.081354) (xy 73.726831 -342.065987) (xy 73.780813 -342.058224)
			(xy 73.808082 -342.057736) (xy 74.671682 -342.057736) (xy 74.698954 -342.058202) (xy 74.752942 -342.065962)
			(xy 74.805277 -342.081327) (xy 74.854892 -342.103983) (xy 74.900778 -342.13347) (xy 74.942 -342.169188)
			(xy 74.977719 -342.210408) (xy 75.007208 -342.256292) (xy 75.029867 -342.305906) (xy 75.045234 -342.35824)
			(xy 75.052996 -342.412228) (xy 75.052996 -342.466772) (xy 75.052996 -342.466773) (xy 76.5357 -342.466773)
			(xy 76.5357 -342.412227) (xy 76.543463 -342.358236) (xy 76.558831 -342.3059) (xy 76.581492 -342.256284)
			(xy 76.610984 -342.210398) (xy 76.646706 -342.169176) (xy 76.687931 -342.133459) (xy 76.73382 -342.103972)
			(xy 76.783439 -342.081317) (xy 76.835777 -342.065954) (xy 76.889769 -342.058197) (xy 76.917042 -342.057736)
			(xy 77.780642 -342.057736) (xy 77.807909 -342.058229) (xy 77.861888 -342.065996) (xy 77.914212 -342.081365)
			(xy 77.963817 -342.104023) (xy 78.009692 -342.13351) (xy 78.050905 -342.169225) (xy 78.086615 -342.210441)
			(xy 78.116097 -342.25632) (xy 78.13875 -342.305927) (xy 78.154113 -342.358253) (xy 78.161874 -342.412233)
			(xy 78.161874 -342.466767) (xy 78.161873 -342.466771) (xy 79.644699 -342.466771) (xy 79.644699 -342.412229)
			(xy 79.652462 -342.358241) (xy 79.667828 -342.305908) (xy 79.690486 -342.256295) (xy 79.719974 -342.210411)
			(xy 79.755692 -342.16919) (xy 79.796912 -342.133473) (xy 79.842797 -342.103985) (xy 79.89241 -342.081327)
			(xy 79.944743 -342.065961) (xy 79.998731 -342.058199) (xy 80.026002 -342.057736) (xy 80.889602 -342.057736)
			(xy 80.916871 -342.058227) (xy 80.970854 -342.065988) (xy 81.023183 -342.081354) (xy 81.072793 -342.10401)
			(xy 81.118673 -342.133496) (xy 81.159891 -342.169211) (xy 81.195605 -342.210428) (xy 81.225091 -342.256309)
			(xy 81.247747 -342.305919) (xy 81.263112 -342.358248) (xy 81.270874 -342.412231) (xy 81.270874 -342.466768)
			(xy 82.753722 -342.466768) (xy 82.753722 -342.412232) (xy 82.761483 -342.358252) (xy 82.776847 -342.305925)
			(xy 82.7995 -342.256317) (xy 82.828983 -342.210438) (xy 82.864694 -342.169221) (xy 82.905907 -342.133505)
			(xy 82.951784 -342.104018) (xy 83.001389 -342.08136) (xy 83.053714 -342.065991) (xy 83.107694 -342.058225)
			(xy 83.134962 -342.057736) (xy 83.998562 -342.057736) (xy 84.025835 -342.058201) (xy 84.079825 -342.065959)
			(xy 84.132162 -342.081321) (xy 84.18178 -342.103977) (xy 84.227668 -342.133463) (xy 84.268893 -342.16918)
			(xy 84.304614 -342.210401) (xy 84.334105 -342.256287) (xy 84.356765 -342.305902) (xy 84.372133 -342.358237)
			(xy 84.379896 -342.412227) (xy 84.379896 -342.466772) (xy 85.8626 -342.466772) (xy 85.8626 -342.412228)
			(xy 85.870362 -342.358239) (xy 85.88573 -342.305904) (xy 85.908389 -342.256289) (xy 85.937879 -342.210404)
			(xy 85.973599 -342.169183) (xy 86.014822 -342.133466) (xy 86.060709 -342.103979) (xy 86.110325 -342.081322)
			(xy 86.16266 -342.065958) (xy 86.21665 -342.058198) (xy 86.243922 -342.057736) (xy 87.107522 -342.057736)
			(xy 87.13479 -342.058228) (xy 87.188771 -342.065992) (xy 87.241098 -342.081359) (xy 87.290705 -342.104017)
			(xy 87.336583 -342.133503) (xy 87.377798 -342.169218) (xy 87.41351 -342.210435) (xy 87.442994 -342.256314)
			(xy 87.465648 -342.305923) (xy 87.481013 -342.35825) (xy 87.488774 -342.412232) (xy 87.488774 -342.466768)
			(xy 87.488774 -342.466769) (xy 88.971622 -342.466769) (xy 88.971622 -342.412231) (xy 88.979384 -342.358249)
			(xy 88.994748 -342.305921) (xy 89.017403 -342.256311) (xy 89.046887 -342.210431) (xy 89.082601 -342.169214)
			(xy 89.123817 -342.133498) (xy 89.169696 -342.104012) (xy 89.219304 -342.081354) (xy 89.271631 -342.065987)
			(xy 89.325613 -342.058224) (xy 89.352882 -342.057736) (xy 90.216482 -342.057736) (xy 90.243754 -342.058202)
			(xy 90.297742 -342.065962) (xy 90.350077 -342.081327) (xy 90.399692 -342.103983) (xy 90.445578 -342.13347)
			(xy 90.4868 -342.169188) (xy 90.522519 -342.210408) (xy 90.552008 -342.256292) (xy 90.574667 -342.305906)
			(xy 90.590034 -342.35824) (xy 90.597796 -342.412228) (xy 90.597796 -342.466772) (xy 90.597796 -342.466773)
			(xy 92.0805 -342.466773) (xy 92.0805 -342.412227) (xy 92.088263 -342.358236) (xy 92.103631 -342.3059)
			(xy 92.126292 -342.256284) (xy 92.155784 -342.210398) (xy 92.191506 -342.169176) (xy 92.232731 -342.133459)
			(xy 92.27862 -342.103972) (xy 92.328239 -342.081317) (xy 92.380577 -342.065954) (xy 92.434569 -342.058197)
			(xy 92.461842 -342.057736) (xy 93.325442 -342.057736) (xy 93.352709 -342.058229) (xy 93.406688 -342.065996)
			(xy 93.459012 -342.081365) (xy 93.508617 -342.104023) (xy 93.554492 -342.13351) (xy 93.595705 -342.169225)
			(xy 93.631415 -342.210441) (xy 93.660897 -342.25632) (xy 93.68355 -342.305927) (xy 93.698913 -342.358253)
			(xy 93.706674 -342.412233) (xy 93.706674 -342.466767) (xy 93.698913 -342.520747) (xy 93.68355 -342.573073)
			(xy 93.660897 -342.62268) (xy 93.631415 -342.668559) (xy 93.60914 -342.694268) (xy 102.35157 -342.694268)
			(xy 102.35157 -342.634332) (xy 102.359393 -342.574909) (xy 102.374905 -342.517016) (xy 102.397841 -342.461642)
			(xy 102.427809 -342.409736) (xy 102.464294 -342.362185) (xy 102.506675 -342.319804) (xy 102.554224 -342.283316)
			(xy 102.60613 -342.253347) (xy 102.661502 -342.23041) (xy 102.719395 -342.214896) (xy 102.778818 -342.207071)
			(xy 102.808786 -342.20658) (xy 103.672386 -342.20658) (xy 103.702355 -342.207072) (xy 103.76178 -342.214894)
			(xy 103.819676 -342.230405) (xy 103.875051 -342.253341) (xy 103.926959 -342.283309) (xy 103.974512 -342.319796)
			(xy 104.016895 -342.362178) (xy 104.053383 -342.409729) (xy 104.083352 -342.461636) (xy 104.085479 -342.466772)
			(xy 111.4808 -342.466772) (xy 111.4808 -342.412228) (xy 111.488562 -342.358241) (xy 111.503929 -342.305907)
			(xy 111.526587 -342.256293) (xy 111.556075 -342.210409) (xy 111.591794 -342.169188) (xy 111.633015 -342.133471)
			(xy 111.6789 -342.103983) (xy 111.728515 -342.081326) (xy 111.780848 -342.06596) (xy 111.834836 -342.058199)
			(xy 111.862108 -342.057736) (xy 112.725708 -342.057736) (xy 112.752977 -342.058227) (xy 112.806959 -342.06599)
			(xy 112.859288 -342.081355) (xy 112.908897 -342.104012) (xy 112.954776 -342.133498) (xy 112.995993 -342.169213)
			(xy 113.031707 -342.21043) (xy 113.061192 -342.256311) (xy 113.083847 -342.30592) (xy 113.099212 -342.358249)
			(xy 113.106974 -342.412231) (xy 113.106974 -342.466768) (xy 114.589822 -342.466768) (xy 114.589822 -342.412232)
			(xy 114.597583 -342.358251) (xy 114.612947 -342.305924) (xy 114.635601 -342.256315) (xy 114.665084 -342.210436)
			(xy 114.700796 -342.169219) (xy 114.74201 -342.133503) (xy 114.787887 -342.104016) (xy 114.837494 -342.081358)
			(xy 114.88982 -342.06599) (xy 114.9438 -342.058225) (xy 114.971068 -342.057736) (xy 115.834668 -342.057736)
			(xy 115.86194 -342.058201) (xy 115.91593 -342.06596) (xy 115.968267 -342.081323) (xy 116.017884 -342.103979)
			(xy 116.063771 -342.133465) (xy 116.104995 -342.169183) (xy 116.140715 -342.210403) (xy 116.170206 -342.256288)
			(xy 116.192866 -342.305903) (xy 116.208233 -342.358238) (xy 116.215996 -342.412228) (xy 116.215996 -342.466772)
			(xy 117.6987 -342.466772) (xy 117.6987 -342.412228) (xy 117.706462 -342.358238) (xy 117.72183 -342.305903)
			(xy 117.74449 -342.256288) (xy 117.77398 -342.210402) (xy 117.809701 -342.169181) (xy 117.850925 -342.133464)
			(xy 117.896812 -342.103977) (xy 117.946429 -342.08132) (xy 117.998765 -342.065957) (xy 118.052756 -342.058198)
			(xy 118.080028 -342.057736) (xy 118.943628 -342.057736) (xy 118.970896 -342.058228) (xy 119.024876 -342.065993)
			(xy 119.077202 -342.081361) (xy 119.126809 -342.104019) (xy 119.172686 -342.133505) (xy 119.2139 -342.16922)
			(xy 119.249612 -342.210437) (xy 119.279095 -342.256316) (xy 119.301749 -342.305924) (xy 119.317113 -342.358251)
			(xy 119.324874 -342.412232) (xy 119.324874 -342.466768) (xy 119.324874 -342.466769) (xy 120.807722 -342.466769)
			(xy 120.807722 -342.412231) (xy 120.815484 -342.358248) (xy 120.830849 -342.305919) (xy 120.853504 -342.25631)
			(xy 120.882989 -342.210429) (xy 120.918703 -342.169212) (xy 120.95992 -342.133496) (xy 121.005799 -342.10401)
			(xy 121.055408 -342.081353) (xy 121.107736 -342.065986) (xy 121.161719 -342.058223) (xy 121.188988 -342.057736)
			(xy 122.052588 -342.057736) (xy 122.079859 -342.058203) (xy 122.133847 -342.065963) (xy 122.186181 -342.081329)
			(xy 122.235796 -342.103985) (xy 122.28168 -342.133472) (xy 122.322902 -342.16919) (xy 122.35862 -342.21041)
			(xy 122.388109 -342.256294) (xy 122.410767 -342.305908) (xy 122.426134 -342.358241) (xy 122.433896 -342.412229)
			(xy 122.433896 -342.466771) (xy 122.433896 -342.466773) (xy 123.9166 -342.466773) (xy 123.9166 -342.412227)
			(xy 123.924363 -342.358235) (xy 123.939732 -342.305899) (xy 123.962393 -342.256282) (xy 123.991885 -342.210396)
			(xy 124.027608 -342.169174) (xy 124.068834 -342.133456) (xy 124.114724 -342.10397) (xy 124.164344 -342.081315)
			(xy 124.216682 -342.065953) (xy 124.270675 -342.058196) (xy 124.297948 -342.057736) (xy 125.161548 -342.057736)
			(xy 125.188815 -342.05823) (xy 125.242793 -342.065997) (xy 125.295117 -342.081366) (xy 125.34472 -342.104025)
			(xy 125.390595 -342.133512) (xy 125.431807 -342.169227) (xy 125.467517 -342.210443) (xy 125.496998 -342.256322)
			(xy 125.519651 -342.305928) (xy 125.535013 -342.358254) (xy 125.542774 -342.412233) (xy 125.542774 -342.466767)
			(xy 125.542773 -342.466772) (xy 127.0256 -342.466772) (xy 127.0256 -342.412228) (xy 127.033362 -342.358241)
			(xy 127.048729 -342.305907) (xy 127.071387 -342.256293) (xy 127.100875 -342.210409) (xy 127.136594 -342.169188)
			(xy 127.177815 -342.133471) (xy 127.2237 -342.103983) (xy 127.273315 -342.081326) (xy 127.325648 -342.06596)
			(xy 127.379636 -342.058199) (xy 127.406908 -342.057736) (xy 128.270508 -342.057736) (xy 128.297777 -342.058227)
			(xy 128.351759 -342.06599) (xy 128.404088 -342.081355) (xy 128.453697 -342.104012) (xy 128.499576 -342.133498)
			(xy 128.540793 -342.169213) (xy 128.576507 -342.21043) (xy 128.605992 -342.256311) (xy 128.628647 -342.30592)
			(xy 128.644012 -342.358249) (xy 128.651774 -342.412231) (xy 128.651774 -342.466768) (xy 130.134622 -342.466768)
			(xy 130.134622 -342.412232) (xy 130.142383 -342.358251) (xy 130.157747 -342.305924) (xy 130.180401 -342.256315)
			(xy 130.209884 -342.210436) (xy 130.245596 -342.169219) (xy 130.28681 -342.133503) (xy 130.332687 -342.104016)
			(xy 130.382294 -342.081358) (xy 130.43462 -342.06599) (xy 130.4886 -342.058225) (xy 130.515868 -342.057736)
			(xy 131.379468 -342.057736) (xy 131.40674 -342.058201) (xy 131.46073 -342.06596) (xy 131.513067 -342.081323)
			(xy 131.562684 -342.103979) (xy 131.608571 -342.133465) (xy 131.649795 -342.169183) (xy 131.685515 -342.210403)
			(xy 131.715006 -342.256288) (xy 131.737666 -342.305903) (xy 131.753033 -342.358238) (xy 131.760796 -342.412228)
			(xy 131.760796 -342.466772) (xy 133.2435 -342.466772) (xy 133.2435 -342.412228) (xy 133.251262 -342.358238)
			(xy 133.26663 -342.305903) (xy 133.28929 -342.256288) (xy 133.31878 -342.210402) (xy 133.354501 -342.169181)
			(xy 133.395725 -342.133464) (xy 133.441612 -342.103977) (xy 133.491229 -342.08132) (xy 133.543565 -342.065957)
			(xy 133.597556 -342.058198) (xy 133.624828 -342.057736) (xy 134.488428 -342.057736) (xy 134.515696 -342.058228)
			(xy 134.569676 -342.065993) (xy 134.622002 -342.081361) (xy 134.671609 -342.104019) (xy 134.717486 -342.133505)
			(xy 134.7587 -342.16922) (xy 134.794412 -342.210437) (xy 134.823895 -342.256316) (xy 134.846549 -342.305924)
			(xy 134.861913 -342.358251) (xy 134.869674 -342.412232) (xy 134.869674 -342.466768) (xy 134.869674 -342.466769)
			(xy 136.352522 -342.466769) (xy 136.352522 -342.412231) (xy 136.360284 -342.358248) (xy 136.375649 -342.305919)
			(xy 136.398304 -342.25631) (xy 136.427789 -342.210429) (xy 136.463503 -342.169212) (xy 136.50472 -342.133496)
			(xy 136.550599 -342.10401) (xy 136.600208 -342.081353) (xy 136.652536 -342.065986) (xy 136.706519 -342.058223)
			(xy 136.733788 -342.057736) (xy 137.597388 -342.057736) (xy 137.624659 -342.058203) (xy 137.678647 -342.065963)
			(xy 137.730981 -342.081329) (xy 137.780596 -342.103985) (xy 137.82648 -342.133472) (xy 137.867702 -342.16919)
			(xy 137.90342 -342.21041) (xy 137.932909 -342.256294) (xy 137.955567 -342.305908) (xy 137.970934 -342.358241)
			(xy 137.978696 -342.412229) (xy 137.978696 -342.466771) (xy 137.978696 -342.466773) (xy 139.4614 -342.466773)
			(xy 139.4614 -342.412227) (xy 139.469163 -342.358235) (xy 139.484532 -342.305899) (xy 139.507193 -342.256282)
			(xy 139.536685 -342.210396) (xy 139.572408 -342.169174) (xy 139.613634 -342.133456) (xy 139.659524 -342.10397)
			(xy 139.709144 -342.081315) (xy 139.761482 -342.065953) (xy 139.815475 -342.058196) (xy 139.842748 -342.057736)
			(xy 140.706348 -342.057736) (xy 140.733615 -342.05823) (xy 140.787593 -342.065997) (xy 140.839917 -342.081366)
			(xy 140.88952 -342.104025) (xy 140.935395 -342.133512) (xy 140.976607 -342.169227) (xy 141.012317 -342.210443)
			(xy 141.041798 -342.256322) (xy 141.064451 -342.305928) (xy 141.079813 -342.358254) (xy 141.087574 -342.412233)
			(xy 141.087574 -342.466767) (xy 141.087573 -342.466772) (xy 142.5704 -342.466772) (xy 142.5704 -342.412228)
			(xy 142.578162 -342.358241) (xy 142.593529 -342.305907) (xy 142.616187 -342.256293) (xy 142.645675 -342.210409)
			(xy 142.681394 -342.169188) (xy 142.722615 -342.133471) (xy 142.7685 -342.103983) (xy 142.818115 -342.081326)
			(xy 142.870448 -342.06596) (xy 142.924436 -342.058199) (xy 142.951708 -342.057736) (xy 143.815308 -342.057736)
			(xy 143.842577 -342.058227) (xy 143.896559 -342.06599) (xy 143.948888 -342.081355) (xy 143.998497 -342.104012)
			(xy 144.044376 -342.133498) (xy 144.085593 -342.169213) (xy 144.121307 -342.21043) (xy 144.150792 -342.256311)
			(xy 144.173447 -342.30592) (xy 144.188812 -342.358249) (xy 144.196574 -342.412231) (xy 144.196574 -342.466768)
			(xy 164.913822 -342.466768) (xy 164.913822 -342.412232) (xy 164.921583 -342.35825) (xy 164.936947 -342.305923)
			(xy 164.959602 -342.256314) (xy 164.989085 -342.210434) (xy 165.024797 -342.169217) (xy 165.066012 -342.133502)
			(xy 165.11189 -342.104015) (xy 165.161496 -342.081357) (xy 165.213823 -342.065989) (xy 165.267804 -342.058224)
			(xy 165.295072 -342.057736) (xy 166.158672 -342.057736) (xy 166.185944 -342.058202) (xy 166.239934 -342.06596)
			(xy 166.29227 -342.081324) (xy 166.341886 -342.10398) (xy 166.387773 -342.133467) (xy 166.428996 -342.169184)
			(xy 166.464716 -342.210405) (xy 166.494207 -342.256289) (xy 166.516866 -342.305904) (xy 166.532234 -342.358239)
			(xy 166.539996 -342.412228) (xy 166.539996 -342.466772) (xy 166.539996 -342.466773) (xy 168.0227 -342.466773)
			(xy 168.0227 -342.412227) (xy 168.030463 -342.358237) (xy 168.045831 -342.305902) (xy 168.068491 -342.256286)
			(xy 168.097981 -342.210401) (xy 168.133702 -342.16918) (xy 168.174927 -342.133462) (xy 168.220815 -342.103975)
			(xy 168.270432 -342.081319) (xy 168.322769 -342.065956) (xy 168.376759 -342.058197) (xy 168.404032 -342.057736)
			(xy 169.267632 -342.057736) (xy 169.2949 -342.058229) (xy 169.34888 -342.065994) (xy 169.401205 -342.081362)
			(xy 169.450811 -342.10402) (xy 169.496688 -342.133506) (xy 169.537901 -342.169222) (xy 169.573613 -342.210438)
			(xy 169.603095 -342.256317) (xy 169.625749 -342.305925) (xy 169.641113 -342.358252) (xy 169.648874 -342.412232)
			(xy 169.648874 -342.466768) (xy 169.648874 -342.466769) (xy 171.131722 -342.466769) (xy 171.131722 -342.412231)
			(xy 171.139484 -342.358248) (xy 171.154849 -342.305918) (xy 171.177505 -342.256309) (xy 171.20699 -342.210428)
			(xy 171.242705 -342.16921) (xy 171.283921 -342.133495) (xy 171.329802 -342.104009) (xy 171.379411 -342.081352)
			(xy 171.43174 -342.065986) (xy 171.485723 -342.058223) (xy 171.512992 -342.057736) (xy 172.376592 -342.057736)
			(xy 172.403863 -342.058203) (xy 172.457851 -342.065964) (xy 172.510184 -342.08133) (xy 172.559798 -342.103987)
			(xy 172.605682 -342.133474) (xy 172.646903 -342.169191) (xy 172.682621 -342.210411) (xy 172.71211 -342.256295)
			(xy 172.734768 -342.305908) (xy 172.750134 -342.358241) (xy 172.757896 -342.412229) (xy 172.757896 -342.466767)
			(xy 174.240722 -342.466767) (xy 174.240722 -342.412233) (xy 174.248483 -342.358253) (xy 174.263846 -342.305927)
			(xy 174.286499 -342.25632) (xy 174.31598 -342.210441) (xy 174.35169 -342.169224) (xy 174.392902 -342.133509)
			(xy 174.438778 -342.104022) (xy 174.488382 -342.081363) (xy 174.540706 -342.065993) (xy 174.594685 -342.058226)
			(xy 174.621952 -342.057736) (xy 175.485552 -342.057736) (xy 175.512825 -342.0582) (xy 175.566817 -342.065957)
			(xy 175.619155 -342.081319) (xy 175.668774 -342.103974) (xy 175.714663 -342.13346) (xy 175.755889 -342.169177)
			(xy 175.791612 -342.210398) (xy 175.821103 -342.256284) (xy 175.843764 -342.3059) (xy 175.859133 -342.358236)
			(xy 175.866896 -342.412227) (xy 175.866896 -342.466772) (xy 177.3496 -342.466772) (xy 177.3496 -342.412228)
			(xy 177.357362 -342.35824) (xy 177.372729 -342.305906) (xy 177.395388 -342.256292) (xy 177.424876 -342.210407)
			(xy 177.460595 -342.169187) (xy 177.501817 -342.133469) (xy 177.547703 -342.103982) (xy 177.597317 -342.081325)
			(xy 177.649652 -342.065959) (xy 177.70364 -342.058199) (xy 177.730912 -342.057736) (xy 178.594512 -342.057736)
			(xy 178.621781 -342.058227) (xy 178.675763 -342.06599) (xy 178.728091 -342.081357) (xy 178.777699 -342.104013)
			(xy 178.823578 -342.133499) (xy 178.864794 -342.169214) (xy 178.900508 -342.210432) (xy 178.929992 -342.256312)
			(xy 178.952648 -342.305921) (xy 178.968012 -342.358249) (xy 178.975774 -342.412231) (xy 178.975774 -342.466768)
			(xy 180.458622 -342.466768) (xy 180.458622 -342.412232) (xy 180.466383 -342.35825) (xy 180.481747 -342.305923)
			(xy 180.504402 -342.256314) (xy 180.533885 -342.210434) (xy 180.569597 -342.169217) (xy 180.610812 -342.133502)
			(xy 180.65669 -342.104015) (xy 180.706296 -342.081357) (xy 180.758623 -342.065989) (xy 180.812604 -342.058224)
			(xy 180.839872 -342.057736) (xy 181.703472 -342.057736) (xy 181.730744 -342.058202) (xy 181.784734 -342.06596)
			(xy 181.83707 -342.081324) (xy 181.886686 -342.10398) (xy 181.932573 -342.133467) (xy 181.973796 -342.169184)
			(xy 182.009516 -342.210405) (xy 182.039007 -342.256289) (xy 182.061666 -342.305904) (xy 182.077034 -342.358239)
			(xy 182.084796 -342.412228) (xy 182.084796 -342.466772) (xy 182.084796 -342.466773) (xy 183.5675 -342.466773)
			(xy 183.5675 -342.412227) (xy 183.575263 -342.358237) (xy 183.590631 -342.305902) (xy 183.613291 -342.256286)
			(xy 183.642781 -342.210401) (xy 183.678502 -342.16918) (xy 183.719727 -342.133462) (xy 183.765615 -342.103975)
			(xy 183.815232 -342.081319) (xy 183.867569 -342.065956) (xy 183.921559 -342.058197) (xy 183.948832 -342.057736)
			(xy 184.812432 -342.057736) (xy 184.8397 -342.058229) (xy 184.89368 -342.065994) (xy 184.946005 -342.081362)
			(xy 184.995611 -342.10402) (xy 185.041488 -342.133506) (xy 185.082701 -342.169222) (xy 185.118413 -342.210438)
			(xy 185.147895 -342.256317) (xy 185.170549 -342.305925) (xy 185.185913 -342.358252) (xy 185.193674 -342.412232)
			(xy 185.193674 -342.466768) (xy 185.193674 -342.466769) (xy 186.676522 -342.466769) (xy 186.676522 -342.412231)
			(xy 186.684284 -342.358248) (xy 186.699649 -342.305918) (xy 186.722305 -342.256309) (xy 186.75179 -342.210428)
			(xy 186.787505 -342.16921) (xy 186.828721 -342.133495) (xy 186.874602 -342.104009) (xy 186.924211 -342.081352)
			(xy 186.97654 -342.065986) (xy 187.030523 -342.058223) (xy 187.057792 -342.057736) (xy 187.921392 -342.057736)
			(xy 187.948663 -342.058203) (xy 188.002651 -342.065964) (xy 188.054984 -342.08133) (xy 188.104598 -342.103987)
			(xy 188.150482 -342.133474) (xy 188.191703 -342.169191) (xy 188.227421 -342.210411) (xy 188.25691 -342.256295)
			(xy 188.279568 -342.305908) (xy 188.294934 -342.358241) (xy 188.302696 -342.412229) (xy 188.302696 -342.466767)
			(xy 189.785522 -342.466767) (xy 189.785522 -342.412233) (xy 189.793283 -342.358253) (xy 189.808646 -342.305927)
			(xy 189.831299 -342.25632) (xy 189.86078 -342.210441) (xy 189.89649 -342.169224) (xy 189.937702 -342.133509)
			(xy 189.983578 -342.104022) (xy 190.033182 -342.081363) (xy 190.085506 -342.065993) (xy 190.139485 -342.058226)
			(xy 190.166752 -342.057736) (xy 191.030352 -342.057736) (xy 191.057625 -342.0582) (xy 191.111617 -342.065957)
			(xy 191.163955 -342.081319) (xy 191.213574 -342.103974) (xy 191.259463 -342.13346) (xy 191.300689 -342.169177)
			(xy 191.336412 -342.210398) (xy 191.365903 -342.256284) (xy 191.388564 -342.3059) (xy 191.403933 -342.358236)
			(xy 191.411696 -342.412227) (xy 191.411696 -342.466772) (xy 192.8944 -342.466772) (xy 192.8944 -342.412228)
			(xy 192.902162 -342.35824) (xy 192.917529 -342.305906) (xy 192.940188 -342.256292) (xy 192.969676 -342.210407)
			(xy 193.005395 -342.169187) (xy 193.046617 -342.133469) (xy 193.092503 -342.103982) (xy 193.142117 -342.081325)
			(xy 193.194452 -342.065959) (xy 193.24844 -342.058199) (xy 193.275712 -342.057736) (xy 194.139312 -342.057736)
			(xy 194.166581 -342.058227) (xy 194.220563 -342.06599) (xy 194.272891 -342.081357) (xy 194.322499 -342.104013)
			(xy 194.368378 -342.133499) (xy 194.409594 -342.169214) (xy 194.445308 -342.210432) (xy 194.474792 -342.256312)
			(xy 194.497448 -342.305921) (xy 194.512812 -342.358249) (xy 194.520574 -342.412231) (xy 194.520574 -342.466768)
			(xy 196.003422 -342.466768) (xy 196.003422 -342.412232) (xy 196.011183 -342.35825) (xy 196.026547 -342.305923)
			(xy 196.049202 -342.256314) (xy 196.078685 -342.210434) (xy 196.114397 -342.169217) (xy 196.155612 -342.133502)
			(xy 196.20149 -342.104015) (xy 196.251096 -342.081357) (xy 196.303423 -342.065989) (xy 196.357404 -342.058224)
			(xy 196.384672 -342.057736) (xy 197.248272 -342.057736) (xy 197.275544 -342.058202) (xy 197.28821 -342.060022)
			(xy 255.91262 -342.060022) (xy 255.91262 -341.196422) (xy 255.91311 -341.166438) (xy 255.920938 -341.106982)
			(xy 255.936459 -341.049057) (xy 255.959408 -340.993653) (xy 255.989392 -340.941719) (xy 256.025898 -340.894143)
			(xy 256.068303 -340.851738) (xy 256.115879 -340.815232) (xy 256.167813 -340.785248) (xy 256.223217 -340.762299)
			(xy 256.281142 -340.746778) (xy 256.340598 -340.73895) (xy 256.400566 -340.73895) (xy 256.460022 -340.746778)
			(xy 256.517947 -340.762299) (xy 256.573351 -340.785248) (xy 256.625285 -340.815232) (xy 256.672861 -340.851738)
			(xy 256.715266 -340.894143) (xy 256.751772 -340.941719) (xy 256.781756 -340.993653) (xy 256.804705 -341.049057)
			(xy 256.820226 -341.106982) (xy 256.828054 -341.166438) (xy 256.828544 -341.196422) (xy 256.828544 -342.060022)
			(xy 256.828054 -342.090006) (xy 256.820226 -342.149462) (xy 256.804705 -342.207387) (xy 256.781756 -342.262791)
			(xy 256.751772 -342.314725) (xy 256.715266 -342.362301) (xy 256.672861 -342.404706) (xy 256.625285 -342.441212)
			(xy 256.581015 -342.466771) (xy 267.515799 -342.466771) (xy 267.515799 -342.412229) (xy 267.523562 -342.358241)
			(xy 267.538928 -342.305908) (xy 267.561586 -342.256295) (xy 267.591074 -342.210411) (xy 267.626792 -342.16919)
			(xy 267.668012 -342.133473) (xy 267.713897 -342.103985) (xy 267.76351 -342.081327) (xy 267.815843 -342.065961)
			(xy 267.869831 -342.058199) (xy 267.897102 -342.057736) (xy 268.760702 -342.057736) (xy 268.787971 -342.058227)
			(xy 268.841954 -342.065988) (xy 268.894283 -342.081354) (xy 268.943893 -342.10401) (xy 268.989773 -342.133496)
			(xy 269.030991 -342.169211) (xy 269.066705 -342.210428) (xy 269.096191 -342.256309) (xy 269.118847 -342.305919)
			(xy 269.134212 -342.358248) (xy 269.141974 -342.412231) (xy 269.141974 -342.466768) (xy 270.624822 -342.466768)
			(xy 270.624822 -342.412232) (xy 270.632583 -342.358252) (xy 270.647947 -342.305925) (xy 270.6706 -342.256317)
			(xy 270.700083 -342.210438) (xy 270.735794 -342.169221) (xy 270.777007 -342.133505) (xy 270.822884 -342.104018)
			(xy 270.872489 -342.08136) (xy 270.924814 -342.065991) (xy 270.978794 -342.058225) (xy 271.006062 -342.057736)
			(xy 271.869662 -342.057736) (xy 271.896935 -342.058201) (xy 271.950925 -342.065959) (xy 272.003262 -342.081321)
			(xy 272.05288 -342.103977) (xy 272.098768 -342.133463) (xy 272.139993 -342.16918) (xy 272.175714 -342.210401)
			(xy 272.205205 -342.256287) (xy 272.227865 -342.305902) (xy 272.243233 -342.358237) (xy 272.250996 -342.412227)
			(xy 272.250996 -342.466772) (xy 273.7337 -342.466772) (xy 273.7337 -342.412228) (xy 273.741462 -342.358239)
			(xy 273.75683 -342.305904) (xy 273.779489 -342.256289) (xy 273.808979 -342.210404) (xy 273.844699 -342.169183)
			(xy 273.885922 -342.133466) (xy 273.931809 -342.103979) (xy 273.981425 -342.081322) (xy 274.03376 -342.065958)
			(xy 274.08775 -342.058198) (xy 274.115022 -342.057736) (xy 274.978622 -342.057736) (xy 275.00589 -342.058228)
			(xy 275.059871 -342.065992) (xy 275.112198 -342.081359) (xy 275.161805 -342.104017) (xy 275.207683 -342.133503)
			(xy 275.248898 -342.169218) (xy 275.28461 -342.210435) (xy 275.314094 -342.256314) (xy 275.336748 -342.305923)
			(xy 275.352113 -342.35825) (xy 275.359874 -342.412232) (xy 275.359874 -342.466768) (xy 275.359874 -342.466769)
			(xy 276.842722 -342.466769) (xy 276.842722 -342.412231) (xy 276.850484 -342.358249) (xy 276.865848 -342.305921)
			(xy 276.888503 -342.256311) (xy 276.917987 -342.210431) (xy 276.953701 -342.169214) (xy 276.994917 -342.133498)
			(xy 277.040796 -342.104012) (xy 277.090404 -342.081354) (xy 277.142731 -342.065987) (xy 277.196713 -342.058224)
			(xy 277.223982 -342.057736) (xy 278.087582 -342.057736) (xy 278.114854 -342.058202) (xy 278.168842 -342.065962)
			(xy 278.221177 -342.081327) (xy 278.270792 -342.103983) (xy 278.316678 -342.13347) (xy 278.3579 -342.169188)
			(xy 278.393619 -342.210408) (xy 278.423108 -342.256292) (xy 278.445767 -342.305906) (xy 278.461134 -342.35824)
			(xy 278.468896 -342.412228) (xy 278.468896 -342.466772) (xy 278.468896 -342.466773) (xy 279.9516 -342.466773)
			(xy 279.9516 -342.412227) (xy 279.959363 -342.358236) (xy 279.974731 -342.3059) (xy 279.997392 -342.256284)
			(xy 280.026884 -342.210398) (xy 280.062606 -342.169176) (xy 280.103831 -342.133459) (xy 280.14972 -342.103972)
			(xy 280.199339 -342.081317) (xy 280.251677 -342.065954) (xy 280.305669 -342.058197) (xy 280.332942 -342.057736)
			(xy 281.196542 -342.057736) (xy 281.223809 -342.058229) (xy 281.277788 -342.065996) (xy 281.330112 -342.081365)
			(xy 281.379717 -342.104023) (xy 281.425592 -342.13351) (xy 281.466805 -342.169225) (xy 281.502515 -342.210441)
			(xy 281.531997 -342.25632) (xy 281.55465 -342.305927) (xy 281.570013 -342.358253) (xy 281.577774 -342.412233)
			(xy 281.577774 -342.466767) (xy 281.577773 -342.466771) (xy 283.060599 -342.466771) (xy 283.060599 -342.412229)
			(xy 283.068362 -342.358241) (xy 283.083728 -342.305908) (xy 283.106386 -342.256295) (xy 283.135874 -342.210411)
			(xy 283.171592 -342.16919) (xy 283.212812 -342.133473) (xy 283.258697 -342.103985) (xy 283.30831 -342.081327)
			(xy 283.360643 -342.065961) (xy 283.414631 -342.058199) (xy 283.441902 -342.057736) (xy 284.305502 -342.057736)
			(xy 284.332771 -342.058227) (xy 284.386754 -342.065988) (xy 284.439083 -342.081354) (xy 284.488693 -342.10401)
			(xy 284.534573 -342.133496) (xy 284.575791 -342.169211) (xy 284.611505 -342.210428) (xy 284.640991 -342.256309)
			(xy 284.663647 -342.305919) (xy 284.679012 -342.358248) (xy 284.686774 -342.412231) (xy 284.686774 -342.466768)
			(xy 286.169622 -342.466768) (xy 286.169622 -342.412232) (xy 286.177383 -342.358252) (xy 286.192747 -342.305925)
			(xy 286.2154 -342.256317) (xy 286.244883 -342.210438) (xy 286.280594 -342.169221) (xy 286.321807 -342.133505)
			(xy 286.367684 -342.104018) (xy 286.417289 -342.08136) (xy 286.469614 -342.065991) (xy 286.523594 -342.058225)
			(xy 286.550862 -342.057736) (xy 287.414462 -342.057736) (xy 287.441735 -342.058201) (xy 287.495725 -342.065959)
			(xy 287.548062 -342.081321) (xy 287.59768 -342.103977) (xy 287.643568 -342.133463) (xy 287.684793 -342.16918)
			(xy 287.720514 -342.210401) (xy 287.750005 -342.256287) (xy 287.772665 -342.305902) (xy 287.788033 -342.358237)
			(xy 287.795796 -342.412227) (xy 287.795796 -342.466772) (xy 289.2785 -342.466772) (xy 289.2785 -342.412228)
			(xy 289.286262 -342.358239) (xy 289.30163 -342.305904) (xy 289.324289 -342.256289) (xy 289.353779 -342.210404)
			(xy 289.389499 -342.169183) (xy 289.430722 -342.133466) (xy 289.476609 -342.103979) (xy 289.526225 -342.081322)
			(xy 289.57856 -342.065958) (xy 289.63255 -342.058198) (xy 289.659822 -342.057736) (xy 290.523422 -342.057736)
			(xy 290.55069 -342.058228) (xy 290.604671 -342.065992) (xy 290.656998 -342.081359) (xy 290.706605 -342.104017)
			(xy 290.752483 -342.133503) (xy 290.793698 -342.169218) (xy 290.82941 -342.210435) (xy 290.858894 -342.256314)
			(xy 290.881548 -342.305923) (xy 290.896913 -342.35825) (xy 290.904674 -342.412232) (xy 290.904674 -342.466768)
			(xy 290.904674 -342.466769) (xy 292.387522 -342.466769) (xy 292.387522 -342.412231) (xy 292.395284 -342.358249)
			(xy 292.410648 -342.305921) (xy 292.433303 -342.256311) (xy 292.462787 -342.210431) (xy 292.498501 -342.169214)
			(xy 292.539717 -342.133498) (xy 292.585596 -342.104012) (xy 292.635204 -342.081354) (xy 292.687531 -342.065987)
			(xy 292.741513 -342.058224) (xy 292.768782 -342.057736) (xy 293.632382 -342.057736) (xy 293.659654 -342.058202)
			(xy 293.713642 -342.065962) (xy 293.765977 -342.081327) (xy 293.815592 -342.103983) (xy 293.861478 -342.13347)
			(xy 293.9027 -342.169188) (xy 293.938419 -342.210408) (xy 293.967908 -342.256292) (xy 293.990567 -342.305906)
			(xy 294.005934 -342.35824) (xy 294.013696 -342.412228) (xy 294.013696 -342.466772) (xy 294.013696 -342.466773)
			(xy 295.4964 -342.466773) (xy 295.4964 -342.412227) (xy 295.504163 -342.358236) (xy 295.519531 -342.3059)
			(xy 295.542192 -342.256284) (xy 295.571684 -342.210398) (xy 295.607406 -342.169176) (xy 295.648631 -342.133459)
			(xy 295.69452 -342.103972) (xy 295.744139 -342.081317) (xy 295.796477 -342.065954) (xy 295.850469 -342.058197)
			(xy 295.877742 -342.057736) (xy 296.741342 -342.057736) (xy 296.768609 -342.058229) (xy 296.822588 -342.065996)
			(xy 296.874912 -342.081365) (xy 296.924517 -342.104023) (xy 296.970392 -342.13351) (xy 297.011605 -342.169225)
			(xy 297.047315 -342.210441) (xy 297.076797 -342.25632) (xy 297.09945 -342.305927) (xy 297.114813 -342.358253)
			(xy 297.122574 -342.412233) (xy 297.122574 -342.466767) (xy 297.122573 -342.466771) (xy 298.605399 -342.466771)
			(xy 298.605399 -342.412229) (xy 298.613162 -342.358241) (xy 298.628528 -342.305908) (xy 298.651186 -342.256295)
			(xy 298.680674 -342.210411) (xy 298.716392 -342.16919) (xy 298.757612 -342.133473) (xy 298.803497 -342.103985)
			(xy 298.85311 -342.081327) (xy 298.905443 -342.065961) (xy 298.959431 -342.058199) (xy 298.986702 -342.057736)
			(xy 299.850302 -342.057736) (xy 299.877571 -342.058227) (xy 299.931554 -342.065988) (xy 299.983883 -342.081354)
			(xy 300.033493 -342.10401) (xy 300.079373 -342.133496) (xy 300.120591 -342.169211) (xy 300.156305 -342.210428)
			(xy 300.185791 -342.256309) (xy 300.208447 -342.305919) (xy 300.223812 -342.358248) (xy 300.231574 -342.412231)
			(xy 300.231574 -342.466769) (xy 300.231574 -342.466771) (xy 312.1215 -342.466771) (xy 312.1215 -342.412229)
			(xy 312.129262 -342.358241) (xy 312.144628 -342.305908) (xy 312.167286 -342.256294) (xy 312.196774 -342.21041)
			(xy 312.232493 -342.16919) (xy 312.273713 -342.133472) (xy 312.319598 -342.103984) (xy 312.369212 -342.081327)
			(xy 312.421545 -342.065961) (xy 312.475533 -342.058199) (xy 312.502804 -342.057736) (xy 313.366404 -342.057736)
			(xy 313.393673 -342.058227) (xy 313.447656 -342.065989) (xy 313.499985 -342.081354) (xy 313.549594 -342.104011)
			(xy 313.595474 -342.133497) (xy 313.636691 -342.169212) (xy 313.672406 -342.210429) (xy 313.701891 -342.256309)
			(xy 313.724547 -342.305919) (xy 313.739912 -342.358248) (xy 313.747674 -342.412231) (xy 313.747674 -342.466768)
			(xy 315.230522 -342.466768) (xy 315.230522 -342.412232) (xy 315.238283 -342.358251) (xy 315.253647 -342.305924)
			(xy 315.2763 -342.256316) (xy 315.305783 -342.210437) (xy 315.341495 -342.16922) (xy 315.382708 -342.133505)
			(xy 315.428585 -342.104018) (xy 315.478191 -342.081359) (xy 315.530516 -342.065991) (xy 315.584496 -342.058225)
			(xy 315.611764 -342.057736) (xy 316.475364 -342.057736) (xy 316.502637 -342.058201) (xy 316.556627 -342.065959)
			(xy 316.608964 -342.081322) (xy 316.658581 -342.103977) (xy 316.704469 -342.133464) (xy 316.745693 -342.169181)
			(xy 316.781414 -342.210402) (xy 316.810905 -342.256287) (xy 316.833565 -342.305902) (xy 316.848933 -342.358238)
			(xy 316.856696 -342.412228) (xy 316.856696 -342.466772) (xy 318.3394 -342.466772) (xy 318.3394 -342.412228)
			(xy 318.347162 -342.358239) (xy 318.36253 -342.305904) (xy 318.385189 -342.256289) (xy 318.414679 -342.210404)
			(xy 318.4504 -342.169183) (xy 318.491623 -342.133465) (xy 318.53751 -342.103978) (xy 318.587126 -342.081322)
			(xy 318.639462 -342.065957) (xy 318.693452 -342.058198) (xy 318.720724 -342.057736) (xy 319.584324 -342.057736)
			(xy 319.611592 -342.058228) (xy 319.665573 -342.065992) (xy 319.717899 -342.08136) (xy 319.767506 -342.104017)
			(xy 319.813384 -342.133504) (xy 319.854598 -342.169219) (xy 319.890311 -342.210435) (xy 319.919794 -342.256315)
			(xy 319.942449 -342.305923) (xy 319.957813 -342.358251) (xy 319.965574 -342.412232) (xy 319.965574 -342.466768)
			(xy 319.965574 -342.466769) (xy 321.448422 -342.466769) (xy 321.448422 -342.412231) (xy 321.456184 -342.358249)
			(xy 321.471548 -342.30592) (xy 321.494203 -342.256311) (xy 321.523688 -342.21043) (xy 321.559402 -342.169213)
			(xy 321.600618 -342.133498) (xy 321.646497 -342.104011) (xy 321.696105 -342.081354) (xy 321.748433 -342.065987)
			(xy 321.802415 -342.058224) (xy 321.829684 -342.057736) (xy 322.693284 -342.057736) (xy 322.720556 -342.058202)
			(xy 322.774544 -342.065963) (xy 322.826878 -342.081327) (xy 322.876493 -342.103984) (xy 322.922379 -342.133471)
			(xy 322.9636 -342.169188) (xy 322.999319 -342.210409) (xy 323.028808 -342.256293) (xy 323.051467 -342.305907)
			(xy 323.066834 -342.35824) (xy 323.074596 -342.412228) (xy 323.074596 -342.466772) (xy 323.074596 -342.466773)
			(xy 324.5573 -342.466773) (xy 324.5573 -342.412227) (xy 324.565063 -342.358236) (xy 324.580432 -342.305899)
			(xy 324.603092 -342.256283) (xy 324.632584 -342.210397) (xy 324.668307 -342.169176) (xy 324.709532 -342.133458)
			(xy 324.755422 -342.103971) (xy 324.805041 -342.081316) (xy 324.857379 -342.065954) (xy 324.911371 -342.058196)
			(xy 324.938644 -342.057736) (xy 325.802244 -342.057736) (xy 325.829511 -342.058229) (xy 325.88349 -342.065996)
			(xy 325.935814 -342.081365) (xy 325.985418 -342.104024) (xy 326.031293 -342.133511) (xy 326.072505 -342.169226)
			(xy 326.108216 -342.210442) (xy 326.137697 -342.256321) (xy 326.16035 -342.305928) (xy 326.175713 -342.358253)
			(xy 326.183474 -342.412233) (xy 326.183474 -342.466767) (xy 326.183473 -342.466771) (xy 327.6663 -342.466771)
			(xy 327.6663 -342.412229) (xy 327.674062 -342.358241) (xy 327.689428 -342.305908) (xy 327.712086 -342.256294)
			(xy 327.741574 -342.21041) (xy 327.777293 -342.16919) (xy 327.818513 -342.133472) (xy 327.864398 -342.103984)
			(xy 327.914012 -342.081327) (xy 327.966345 -342.065961) (xy 328.020333 -342.058199) (xy 328.047604 -342.057736)
			(xy 328.911204 -342.057736) (xy 328.938473 -342.058227) (xy 328.992456 -342.065989) (xy 329.044785 -342.081354)
			(xy 329.094394 -342.104011) (xy 329.140274 -342.133497) (xy 329.181491 -342.169212) (xy 329.217206 -342.210429)
			(xy 329.246691 -342.256309) (xy 329.269347 -342.305919) (xy 329.284712 -342.358248) (xy 329.292474 -342.412231)
			(xy 329.292474 -342.466768) (xy 330.775322 -342.466768) (xy 330.775322 -342.412232) (xy 330.783083 -342.358251)
			(xy 330.798447 -342.305924) (xy 330.8211 -342.256316) (xy 330.850583 -342.210437) (xy 330.886295 -342.16922)
			(xy 330.927508 -342.133505) (xy 330.973385 -342.104018) (xy 331.022991 -342.081359) (xy 331.075316 -342.065991)
			(xy 331.129296 -342.058225) (xy 331.156564 -342.057736) (xy 332.020164 -342.057736) (xy 332.047437 -342.058201)
			(xy 332.101427 -342.065959) (xy 332.153764 -342.081322) (xy 332.203381 -342.103977) (xy 332.249269 -342.133464)
			(xy 332.290493 -342.169181) (xy 332.326214 -342.210402) (xy 332.355705 -342.256287) (xy 332.378365 -342.305902)
			(xy 332.393733 -342.358238) (xy 332.401496 -342.412228) (xy 332.401496 -342.466772) (xy 333.8842 -342.466772)
			(xy 333.8842 -342.412228) (xy 333.891962 -342.358239) (xy 333.90733 -342.305904) (xy 333.929989 -342.256289)
			(xy 333.959479 -342.210404) (xy 333.9952 -342.169183) (xy 334.036423 -342.133465) (xy 334.08231 -342.103978)
			(xy 334.131926 -342.081322) (xy 334.184262 -342.065957) (xy 334.238252 -342.058198) (xy 334.265524 -342.057736)
			(xy 335.129124 -342.057736) (xy 335.156392 -342.058228) (xy 335.210373 -342.065992) (xy 335.262699 -342.08136)
			(xy 335.312306 -342.104017) (xy 335.358184 -342.133504) (xy 335.399398 -342.169219) (xy 335.435111 -342.210435)
			(xy 335.464594 -342.256315) (xy 335.487249 -342.305923) (xy 335.502613 -342.358251) (xy 335.510374 -342.412232)
			(xy 335.510374 -342.466768) (xy 335.510374 -342.466769) (xy 336.993222 -342.466769) (xy 336.993222 -342.412231)
			(xy 337.000984 -342.358249) (xy 337.016348 -342.30592) (xy 337.039003 -342.256311) (xy 337.068488 -342.21043)
			(xy 337.104202 -342.169213) (xy 337.145418 -342.133498) (xy 337.191297 -342.104011) (xy 337.240905 -342.081354)
			(xy 337.293233 -342.065987) (xy 337.347215 -342.058224) (xy 337.374484 -342.057736) (xy 338.238084 -342.057736)
			(xy 338.265356 -342.058202) (xy 338.319344 -342.065963) (xy 338.371678 -342.081327) (xy 338.421293 -342.103984)
			(xy 338.467179 -342.133471) (xy 338.5084 -342.169188) (xy 338.544119 -342.210409) (xy 338.573608 -342.256293)
			(xy 338.596267 -342.305907) (xy 338.611634 -342.35824) (xy 338.619396 -342.412228) (xy 338.619396 -342.466772)
			(xy 338.619396 -342.466773) (xy 340.1021 -342.466773) (xy 340.1021 -342.412227) (xy 340.109863 -342.358236)
			(xy 340.125232 -342.305899) (xy 340.147892 -342.256283) (xy 340.177384 -342.210397) (xy 340.213107 -342.169176)
			(xy 340.254332 -342.133458) (xy 340.300222 -342.103971) (xy 340.349841 -342.081316) (xy 340.402179 -342.065954)
			(xy 340.456171 -342.058196) (xy 340.483444 -342.057736) (xy 341.347044 -342.057736) (xy 341.374311 -342.058229)
			(xy 341.42829 -342.065996) (xy 341.480614 -342.081365) (xy 341.530218 -342.104024) (xy 341.576093 -342.133511)
			(xy 341.617305 -342.169226) (xy 341.653016 -342.210442) (xy 341.682497 -342.256321) (xy 341.70515 -342.305928)
			(xy 341.720513 -342.358253) (xy 341.728274 -342.412233) (xy 341.728274 -342.466767) (xy 341.728273 -342.466771)
			(xy 343.2111 -342.466771) (xy 343.2111 -342.412229) (xy 343.218862 -342.358241) (xy 343.234228 -342.305908)
			(xy 343.256886 -342.256294) (xy 343.286374 -342.21041) (xy 343.322093 -342.16919) (xy 343.363313 -342.133472)
			(xy 343.409198 -342.103984) (xy 343.458812 -342.081327) (xy 343.511145 -342.065961) (xy 343.565133 -342.058199)
			(xy 343.592404 -342.057736) (xy 344.456004 -342.057736) (xy 344.483273 -342.058227) (xy 344.537256 -342.065989)
			(xy 344.589585 -342.081354) (xy 344.639194 -342.104011) (xy 344.685074 -342.133497) (xy 344.726291 -342.169212)
			(xy 344.762006 -342.210429) (xy 344.791491 -342.256309) (xy 344.814147 -342.305919) (xy 344.829512 -342.358248)
			(xy 344.837274 -342.412231) (xy 344.837274 -342.466769) (xy 370.806722 -342.466769) (xy 370.806722 -342.412231)
			(xy 370.814484 -342.358249) (xy 370.829848 -342.305921) (xy 370.852503 -342.256312) (xy 370.881987 -342.210432)
			(xy 370.9177 -342.169214) (xy 370.958916 -342.133499) (xy 371.004794 -342.104012) (xy 371.054402 -342.081355)
			(xy 371.10673 -342.065988) (xy 371.160711 -342.058224) (xy 371.18798 -342.057736) (xy 372.05158 -342.057736)
			(xy 372.078852 -342.058202) (xy 372.132841 -342.065962) (xy 372.185175 -342.081326) (xy 372.234791 -342.103983)
			(xy 372.280677 -342.13347) (xy 372.321899 -342.169187) (xy 372.357618 -342.210407) (xy 372.387108 -342.256292)
			(xy 372.409767 -342.305906) (xy 372.425134 -342.35824) (xy 372.432896 -342.412228) (xy 372.432896 -342.466772)
			(xy 372.432896 -342.466773) (xy 373.9156 -342.466773) (xy 373.9156 -342.412227) (xy 373.923363 -342.358236)
			(xy 373.938731 -342.3059) (xy 373.961392 -342.256284) (xy 373.990883 -342.210398) (xy 374.026605 -342.169177)
			(xy 374.06783 -342.133459) (xy 374.113719 -342.103973) (xy 374.163338 -342.081317) (xy 374.215676 -342.065954)
			(xy 374.269667 -342.058197) (xy 374.29694 -342.057736) (xy 375.16054 -342.057736) (xy 375.187807 -342.058229)
			(xy 375.241786 -342.065995) (xy 375.294111 -342.081364) (xy 375.343716 -342.104022) (xy 375.389591 -342.133509)
			(xy 375.430804 -342.169224) (xy 375.466515 -342.210441) (xy 375.495997 -342.256319) (xy 375.51865 -342.305927)
			(xy 375.534013 -342.358253) (xy 375.541774 -342.412233) (xy 375.541774 -342.466767) (xy 375.541774 -342.46677)
			(xy 377.024622 -342.46677) (xy 377.024622 -342.41223) (xy 377.032384 -342.358247) (xy 377.04775 -342.305917)
			(xy 377.070406 -342.256306) (xy 377.099892 -342.210425) (xy 377.135607 -342.169207) (xy 377.176825 -342.133492)
			(xy 377.222706 -342.104006) (xy 377.272317 -342.08135) (xy 377.324647 -342.065984) (xy 377.37863 -342.058222)
			(xy 377.4059 -342.057736) (xy 378.2695 -342.057736) (xy 378.296769 -342.058226) (xy 378.350753 -342.065988)
			(xy 378.403082 -342.081353) (xy 378.452692 -342.104009) (xy 378.498572 -342.133495) (xy 378.53979 -342.16921)
			(xy 378.575505 -342.210428) (xy 378.604991 -342.256308) (xy 378.627647 -342.305918) (xy 378.643012 -342.358247)
			(xy 378.650774 -342.412231) (xy 378.650774 -342.466768) (xy 380.133622 -342.466768) (xy 380.133622 -342.412232)
			(xy 380.141383 -342.358252) (xy 380.156746 -342.305925) (xy 380.1794 -342.256318) (xy 380.208882 -342.210438)
			(xy 380.244593 -342.169222) (xy 380.285806 -342.133506) (xy 380.331682 -342.104019) (xy 380.381288 -342.08136)
			(xy 380.433613 -342.065991) (xy 380.487592 -342.058225) (xy 380.51486 -342.057736) (xy 381.37846 -342.057736)
			(xy 381.405733 -342.058201) (xy 381.459724 -342.065958) (xy 381.512061 -342.081321) (xy 381.561679 -342.103976)
			(xy 381.607567 -342.133463) (xy 381.648792 -342.16918) (xy 381.684513 -342.210401) (xy 381.714005 -342.256286)
			(xy 381.736665 -342.305902) (xy 381.752033 -342.358237) (xy 381.759796 -342.412227) (xy 381.759796 -342.466772)
			(xy 383.2425 -342.466772) (xy 383.2425 -342.412228) (xy 383.250262 -342.358239) (xy 383.26563 -342.305904)
			(xy 383.288289 -342.25629) (xy 383.317778 -342.210405) (xy 383.353498 -342.169184) (xy 383.394721 -342.133466)
			(xy 383.440607 -342.103979) (xy 383.490223 -342.081323) (xy 383.542559 -342.065958) (xy 383.596548 -342.058198)
			(xy 383.62382 -342.057736) (xy 384.48742 -342.057736) (xy 384.514688 -342.058228) (xy 384.568669 -342.065992)
			(xy 384.620996 -342.081359) (xy 384.670604 -342.104016) (xy 384.716482 -342.133502) (xy 384.757697 -342.169217)
			(xy 384.79341 -342.210434) (xy 384.822894 -342.256314) (xy 384.845548 -342.305922) (xy 384.860913 -342.35825)
			(xy 384.868674 -342.412232) (xy 384.868674 -342.466768) (xy 384.868674 -342.466769) (xy 386.351522 -342.466769)
			(xy 386.351522 -342.412231) (xy 386.359284 -342.358249) (xy 386.374648 -342.305921) (xy 386.397303 -342.256312)
			(xy 386.426787 -342.210432) (xy 386.4625 -342.169214) (xy 386.503716 -342.133499) (xy 386.549594 -342.104012)
			(xy 386.599202 -342.081355) (xy 386.65153 -342.065988) (xy 386.705511 -342.058224) (xy 386.73278 -342.057736)
			(xy 387.59638 -342.057736) (xy 387.623652 -342.058202) (xy 387.677641 -342.065962) (xy 387.729975 -342.081326)
			(xy 387.779591 -342.103983) (xy 387.825477 -342.13347) (xy 387.866699 -342.169187) (xy 387.902418 -342.210407)
			(xy 387.931908 -342.256292) (xy 387.954567 -342.305906) (xy 387.969934 -342.35824) (xy 387.977696 -342.412228)
			(xy 387.977696 -342.466772) (xy 387.977696 -342.466773) (xy 389.4604 -342.466773) (xy 389.4604 -342.412227)
			(xy 389.468163 -342.358236) (xy 389.483531 -342.3059) (xy 389.506192 -342.256284) (xy 389.535683 -342.210398)
			(xy 389.571405 -342.169177) (xy 389.61263 -342.133459) (xy 389.658519 -342.103973) (xy 389.708138 -342.081317)
			(xy 389.760476 -342.065954) (xy 389.814467 -342.058197) (xy 389.84174 -342.057736) (xy 390.70534 -342.057736)
			(xy 390.732607 -342.058229) (xy 390.786586 -342.065995) (xy 390.838911 -342.081364) (xy 390.888516 -342.104022)
			(xy 390.934391 -342.133509) (xy 390.975604 -342.169224) (xy 391.011315 -342.210441) (xy 391.040797 -342.256319)
			(xy 391.06345 -342.305927) (xy 391.078813 -342.358253) (xy 391.086574 -342.412233) (xy 391.086574 -342.466767)
			(xy 391.086574 -342.46677) (xy 392.569422 -342.46677) (xy 392.569422 -342.41223) (xy 392.577184 -342.358247)
			(xy 392.59255 -342.305917) (xy 392.615206 -342.256306) (xy 392.644692 -342.210425) (xy 392.680407 -342.169207)
			(xy 392.721625 -342.133492) (xy 392.767506 -342.104006) (xy 392.817117 -342.08135) (xy 392.869447 -342.065984)
			(xy 392.92343 -342.058222) (xy 392.9507 -342.057736) (xy 393.8143 -342.057736) (xy 393.841569 -342.058226)
			(xy 393.895553 -342.065988) (xy 393.947882 -342.081353) (xy 393.997492 -342.104009) (xy 394.043372 -342.133495)
			(xy 394.08459 -342.16921) (xy 394.120305 -342.210428) (xy 394.149791 -342.256308) (xy 394.172447 -342.305918)
			(xy 394.187812 -342.358247) (xy 394.195574 -342.412231) (xy 394.195574 -342.466768) (xy 395.678422 -342.466768)
			(xy 395.678422 -342.412232) (xy 395.686183 -342.358252) (xy 395.701546 -342.305925) (xy 395.7242 -342.256318)
			(xy 395.753682 -342.210438) (xy 395.789393 -342.169222) (xy 395.830606 -342.133506) (xy 395.876482 -342.104019)
			(xy 395.926088 -342.08136) (xy 395.978413 -342.065991) (xy 396.032392 -342.058225) (xy 396.05966 -342.057736)
			(xy 396.92326 -342.057736) (xy 396.950533 -342.058201) (xy 397.004524 -342.065958) (xy 397.056861 -342.081321)
			(xy 397.106479 -342.103976) (xy 397.152367 -342.133463) (xy 397.193592 -342.16918) (xy 397.229313 -342.210401)
			(xy 397.258805 -342.256286) (xy 397.281465 -342.305902) (xy 397.296833 -342.358237) (xy 397.304596 -342.412227)
			(xy 397.304596 -342.466772) (xy 398.7873 -342.466772) (xy 398.7873 -342.412228) (xy 398.795062 -342.358239)
			(xy 398.81043 -342.305904) (xy 398.833089 -342.25629) (xy 398.862578 -342.210405) (xy 398.898298 -342.169184)
			(xy 398.939521 -342.133466) (xy 398.985407 -342.103979) (xy 399.035023 -342.081323) (xy 399.087359 -342.065958)
			(xy 399.141348 -342.058198) (xy 399.16862 -342.057736) (xy 400.03222 -342.057736) (xy 400.059488 -342.058228)
			(xy 400.113469 -342.065992) (xy 400.165796 -342.081359) (xy 400.215404 -342.104016) (xy 400.261282 -342.133502)
			(xy 400.302497 -342.169217) (xy 400.33821 -342.210434) (xy 400.367694 -342.256314) (xy 400.390348 -342.305922)
			(xy 400.405713 -342.35825) (xy 400.413474 -342.412232) (xy 400.413474 -342.466768) (xy 400.413474 -342.466769)
			(xy 401.896322 -342.466769) (xy 401.896322 -342.412231) (xy 401.904084 -342.358249) (xy 401.919448 -342.305921)
			(xy 401.942103 -342.256312) (xy 401.971587 -342.210432) (xy 402.0073 -342.169214) (xy 402.048516 -342.133499)
			(xy 402.094394 -342.104012) (xy 402.144002 -342.081355) (xy 402.19633 -342.065988) (xy 402.250311 -342.058224)
			(xy 402.27758 -342.057736) (xy 403.14118 -342.057736) (xy 403.168452 -342.058202) (xy 403.222441 -342.065962)
			(xy 403.274775 -342.081326) (xy 403.324391 -342.103983) (xy 403.370277 -342.13347) (xy 403.411499 -342.169187)
			(xy 403.447218 -342.210407) (xy 403.476708 -342.256292) (xy 403.499367 -342.305906) (xy 403.514734 -342.35824)
			(xy 403.522496 -342.412228) (xy 403.522496 -342.466769) (xy 408.913822 -342.466769) (xy 408.913822 -342.412231)
			(xy 408.921584 -342.358248) (xy 408.936949 -342.305918) (xy 408.959605 -342.256309) (xy 408.98909 -342.210428)
			(xy 409.024805 -342.16921) (xy 409.066021 -342.133495) (xy 409.111902 -342.104009) (xy 409.161511 -342.081352)
			(xy 409.21384 -342.065986) (xy 409.267823 -342.058223) (xy 409.295092 -342.057736) (xy 410.158692 -342.057736)
			(xy 410.185963 -342.058203) (xy 410.239951 -342.065964) (xy 410.292284 -342.08133) (xy 410.341898 -342.103987)
			(xy 410.387782 -342.133474) (xy 410.429003 -342.169191) (xy 410.464721 -342.210411) (xy 410.49421 -342.256295)
			(xy 410.516868 -342.305908) (xy 410.532234 -342.358241) (xy 410.539996 -342.412229) (xy 410.539996 -342.466767)
			(xy 412.022822 -342.466767) (xy 412.022822 -342.412233) (xy 412.030583 -342.358253) (xy 412.045946 -342.305927)
			(xy 412.068599 -342.25632) (xy 412.09808 -342.210441) (xy 412.13379 -342.169224) (xy 412.175002 -342.133509)
			(xy 412.220878 -342.104022) (xy 412.270482 -342.081363) (xy 412.322806 -342.065993) (xy 412.376785 -342.058226)
			(xy 412.404052 -342.057736) (xy 413.267652 -342.057736) (xy 413.294925 -342.0582) (xy 413.348917 -342.065957)
			(xy 413.401255 -342.081319) (xy 413.450874 -342.103974) (xy 413.496763 -342.13346) (xy 413.537989 -342.169177)
			(xy 413.573712 -342.210398) (xy 413.603203 -342.256284) (xy 413.625864 -342.3059) (xy 413.641233 -342.358236)
			(xy 413.648996 -342.412227) (xy 413.648996 -342.466772) (xy 415.1317 -342.466772) (xy 415.1317 -342.412228)
			(xy 415.139462 -342.35824) (xy 415.154829 -342.305906) (xy 415.177488 -342.256292) (xy 415.206976 -342.210407)
			(xy 415.242695 -342.169187) (xy 415.283917 -342.133469) (xy 415.329803 -342.103982) (xy 415.379417 -342.081325)
			(xy 415.431752 -342.065959) (xy 415.48574 -342.058199) (xy 415.513012 -342.057736) (xy 416.376612 -342.057736)
			(xy 416.403881 -342.058227) (xy 416.457863 -342.06599) (xy 416.510191 -342.081357) (xy 416.559799 -342.104013)
			(xy 416.605678 -342.133499) (xy 416.646894 -342.169214) (xy 416.682608 -342.210432) (xy 416.712092 -342.256312)
			(xy 416.734748 -342.305921) (xy 416.750112 -342.358249) (xy 416.757874 -342.412231) (xy 416.757874 -342.466768)
			(xy 418.240722 -342.466768) (xy 418.240722 -342.412232) (xy 418.248483 -342.35825) (xy 418.263847 -342.305923)
			(xy 418.286502 -342.256314) (xy 418.315985 -342.210434) (xy 418.351697 -342.169217) (xy 418.392912 -342.133502)
			(xy 418.43879 -342.104015) (xy 418.488396 -342.081357) (xy 418.540723 -342.065989) (xy 418.594704 -342.058224)
			(xy 418.621972 -342.057736) (xy 419.485572 -342.057736) (xy 419.512844 -342.058202) (xy 419.566834 -342.06596)
			(xy 419.61917 -342.081324) (xy 419.668786 -342.10398) (xy 419.714673 -342.133467) (xy 419.755896 -342.169184)
			(xy 419.791616 -342.210405) (xy 419.821107 -342.256289) (xy 419.843766 -342.305904) (xy 419.859134 -342.358239)
			(xy 419.866896 -342.412228) (xy 419.866896 -342.466772) (xy 419.866896 -342.466773) (xy 421.3496 -342.466773)
			(xy 421.3496 -342.412227) (xy 421.357363 -342.358237) (xy 421.372731 -342.305902) (xy 421.395391 -342.256286)
			(xy 421.424881 -342.210401) (xy 421.460602 -342.16918) (xy 421.501827 -342.133462) (xy 421.547715 -342.103975)
			(xy 421.597332 -342.081319) (xy 421.649669 -342.065956) (xy 421.703659 -342.058197) (xy 421.730932 -342.057736)
			(xy 422.594532 -342.057736) (xy 422.6218 -342.058229) (xy 422.67578 -342.065994) (xy 422.728105 -342.081362)
			(xy 422.777711 -342.10402) (xy 422.823588 -342.133506) (xy 422.864801 -342.169222) (xy 422.900513 -342.210438)
			(xy 422.929995 -342.256317) (xy 422.952649 -342.305925) (xy 422.968013 -342.358252) (xy 422.975774 -342.412232)
			(xy 422.975774 -342.466768) (xy 422.975774 -342.466769) (xy 424.458622 -342.466769) (xy 424.458622 -342.412231)
			(xy 424.466384 -342.358248) (xy 424.481749 -342.305918) (xy 424.504405 -342.256309) (xy 424.53389 -342.210428)
			(xy 424.569605 -342.16921) (xy 424.610821 -342.133495) (xy 424.656702 -342.104009) (xy 424.706311 -342.081352)
			(xy 424.75864 -342.065986) (xy 424.812623 -342.058223) (xy 424.839892 -342.057736) (xy 425.703492 -342.057736)
			(xy 425.730763 -342.058203) (xy 425.784751 -342.065964) (xy 425.837084 -342.08133) (xy 425.886698 -342.103987)
			(xy 425.932582 -342.133474) (xy 425.973803 -342.169191) (xy 426.009521 -342.210411) (xy 426.03901 -342.256295)
			(xy 426.061668 -342.305908) (xy 426.077034 -342.358241) (xy 426.084796 -342.412229) (xy 426.084796 -342.466767)
			(xy 427.567622 -342.466767) (xy 427.567622 -342.412233) (xy 427.575383 -342.358253) (xy 427.590746 -342.305927)
			(xy 427.613399 -342.25632) (xy 427.64288 -342.210441) (xy 427.67859 -342.169224) (xy 427.719802 -342.133509)
			(xy 427.765678 -342.104022) (xy 427.815282 -342.081363) (xy 427.867606 -342.065993) (xy 427.921585 -342.058226)
			(xy 427.948852 -342.057736) (xy 428.812452 -342.057736) (xy 428.839725 -342.0582) (xy 428.893717 -342.065957)
			(xy 428.946055 -342.081319) (xy 428.995674 -342.103974) (xy 429.041563 -342.13346) (xy 429.082789 -342.169177)
			(xy 429.118512 -342.210398) (xy 429.148003 -342.256284) (xy 429.170664 -342.3059) (xy 429.186033 -342.358236)
			(xy 429.193796 -342.412227) (xy 429.193796 -342.466772) (xy 430.6765 -342.466772) (xy 430.6765 -342.412228)
			(xy 430.684262 -342.35824) (xy 430.699629 -342.305906) (xy 430.722288 -342.256292) (xy 430.751776 -342.210407)
			(xy 430.787495 -342.169187) (xy 430.828717 -342.133469) (xy 430.874603 -342.103982) (xy 430.924217 -342.081325)
			(xy 430.976552 -342.065959) (xy 431.03054 -342.058199) (xy 431.057812 -342.057736) (xy 431.921412 -342.057736)
			(xy 431.948681 -342.058227) (xy 432.002663 -342.06599) (xy 432.054991 -342.081357) (xy 432.104599 -342.104013)
			(xy 432.150478 -342.133499) (xy 432.191694 -342.169214) (xy 432.227408 -342.210432) (xy 432.256892 -342.256312)
			(xy 432.279548 -342.305921) (xy 432.294912 -342.358249) (xy 432.302674 -342.412231) (xy 432.302674 -342.466768)
			(xy 433.785522 -342.466768) (xy 433.785522 -342.412232) (xy 433.793283 -342.35825) (xy 433.808647 -342.305923)
			(xy 433.831302 -342.256314) (xy 433.860785 -342.210434) (xy 433.896497 -342.169217) (xy 433.937712 -342.133502)
			(xy 433.98359 -342.104015) (xy 434.033196 -342.081357) (xy 434.085523 -342.065989) (xy 434.139504 -342.058224)
			(xy 434.166772 -342.057736) (xy 435.030372 -342.057736) (xy 435.057644 -342.058202) (xy 435.111634 -342.06596)
			(xy 435.16397 -342.081324) (xy 435.213586 -342.10398) (xy 435.259473 -342.133467) (xy 435.300696 -342.169184)
			(xy 435.336416 -342.210405) (xy 435.365907 -342.256289) (xy 435.388566 -342.305904) (xy 435.403934 -342.358239)
			(xy 435.411696 -342.412228) (xy 435.411696 -342.466772) (xy 435.411696 -342.466773) (xy 436.8944 -342.466773)
			(xy 436.8944 -342.412227) (xy 436.902163 -342.358237) (xy 436.917531 -342.305902) (xy 436.940191 -342.256286)
			(xy 436.969681 -342.210401) (xy 437.005402 -342.16918) (xy 437.046627 -342.133462) (xy 437.092515 -342.103975)
			(xy 437.142132 -342.081319) (xy 437.194469 -342.065956) (xy 437.248459 -342.058197) (xy 437.275732 -342.057736)
			(xy 438.139332 -342.057736) (xy 438.1666 -342.058229) (xy 438.22058 -342.065994) (xy 438.272905 -342.081362)
			(xy 438.322511 -342.10402) (xy 438.368388 -342.133506) (xy 438.409601 -342.169222) (xy 438.445313 -342.210438)
			(xy 438.474795 -342.256317) (xy 438.497449 -342.305925) (xy 438.512813 -342.358252) (xy 438.520574 -342.412232)
			(xy 438.520574 -342.466768) (xy 438.520574 -342.466769) (xy 440.003422 -342.466769) (xy 440.003422 -342.412231)
			(xy 440.011184 -342.358248) (xy 440.026549 -342.305918) (xy 440.049205 -342.256309) (xy 440.07869 -342.210428)
			(xy 440.114405 -342.16921) (xy 440.155621 -342.133495) (xy 440.201502 -342.104009) (xy 440.251111 -342.081352)
			(xy 440.30344 -342.065986) (xy 440.357423 -342.058223) (xy 440.384692 -342.057736) (xy 441.248292 -342.057736)
			(xy 441.275563 -342.058203) (xy 441.329551 -342.065964) (xy 441.381884 -342.08133) (xy 441.431498 -342.103987)
			(xy 441.477382 -342.133474) (xy 441.518603 -342.169191) (xy 441.554321 -342.210411) (xy 441.58381 -342.256295)
			(xy 441.606468 -342.305908) (xy 441.621834 -342.358241) (xy 441.629596 -342.412229) (xy 441.629596 -342.466771)
			(xy 441.621834 -342.520759) (xy 441.606468 -342.573092) (xy 441.58381 -342.622705) (xy 441.554321 -342.668589)
			(xy 441.518603 -342.709809) (xy 441.477382 -342.745526) (xy 441.431498 -342.775013) (xy 441.381884 -342.79767)
			(xy 441.329551 -342.813036) (xy 441.275563 -342.820797) (xy 441.248292 -342.82126) (xy 440.384692 -342.82126)
			(xy 440.357423 -342.820777) (xy 440.30344 -342.813014) (xy 440.251111 -342.797648) (xy 440.201502 -342.774991)
			(xy 440.155621 -342.745505) (xy 440.114405 -342.70979) (xy 440.07869 -342.668572) (xy 440.049205 -342.622691)
			(xy 440.026549 -342.573082) (xy 440.011184 -342.520752) (xy 440.003422 -342.466769) (xy 438.520574 -342.466769)
			(xy 438.512813 -342.520748) (xy 438.497449 -342.573075) (xy 438.474795 -342.622683) (xy 438.445313 -342.668562)
			(xy 438.409601 -342.709778) (xy 438.368388 -342.745494) (xy 438.322511 -342.77498) (xy 438.272905 -342.797638)
			(xy 438.22058 -342.813006) (xy 438.1666 -342.820771) (xy 438.139332 -342.82126) (xy 437.275732 -342.82126)
			(xy 437.248459 -342.820803) (xy 437.194469 -342.813044) (xy 437.142132 -342.797681) (xy 437.092515 -342.775025)
			(xy 437.046627 -342.745538) (xy 437.005402 -342.70982) (xy 436.969681 -342.668599) (xy 436.940191 -342.622714)
			(xy 436.917531 -342.573098) (xy 436.902163 -342.520763) (xy 436.8944 -342.466773) (xy 435.411696 -342.466773)
			(xy 435.403934 -342.520761) (xy 435.388566 -342.573096) (xy 435.365907 -342.622711) (xy 435.336416 -342.668595)
			(xy 435.300696 -342.709816) (xy 435.259473 -342.745533) (xy 435.213586 -342.77502) (xy 435.16397 -342.797676)
			(xy 435.111634 -342.81304) (xy 435.057644 -342.820798) (xy 435.030372 -342.82126) (xy 434.166772 -342.82126)
			(xy 434.139504 -342.820776) (xy 434.085523 -342.813011) (xy 434.033196 -342.797643) (xy 433.98359 -342.774985)
			(xy 433.937712 -342.745498) (xy 433.896497 -342.709783) (xy 433.860785 -342.668566) (xy 433.831302 -342.622686)
			(xy 433.808647 -342.573077) (xy 433.793283 -342.52075) (xy 433.785522 -342.466768) (xy 432.302674 -342.466768)
			(xy 432.302674 -342.466769) (xy 432.294912 -342.520751) (xy 432.279548 -342.573079) (xy 432.256892 -342.622688)
			(xy 432.227408 -342.668568) (xy 432.191694 -342.709786) (xy 432.150478 -342.745501) (xy 432.104599 -342.774987)
			(xy 432.054991 -342.797643) (xy 432.002663 -342.81301) (xy 431.948681 -342.820773) (xy 431.921412 -342.82126)
			(xy 431.057812 -342.82126) (xy 431.03054 -342.820801) (xy 430.976552 -342.813041) (xy 430.924217 -342.797675)
			(xy 430.874603 -342.775018) (xy 430.828717 -342.745531) (xy 430.787495 -342.709813) (xy 430.751776 -342.668593)
			(xy 430.722288 -342.622708) (xy 430.699629 -342.573094) (xy 430.684262 -342.52076) (xy 430.6765 -342.466772)
			(xy 429.193796 -342.466772) (xy 429.193796 -342.466773) (xy 429.186033 -342.520764) (xy 429.170664 -342.5731)
			(xy 429.148003 -342.622716) (xy 429.118512 -342.668602) (xy 429.082789 -342.709823) (xy 429.041563 -342.74554)
			(xy 428.995674 -342.775026) (xy 428.946055 -342.797681) (xy 428.893717 -342.813043) (xy 428.839725 -342.8208)
			(xy 428.812452 -342.82126) (xy 427.948852 -342.82126) (xy 427.921585 -342.820774) (xy 427.867606 -342.813007)
			(xy 427.815282 -342.797637) (xy 427.765678 -342.774978) (xy 427.719802 -342.745491) (xy 427.67859 -342.709776)
			(xy 427.64288 -342.668559) (xy 427.613399 -342.62268) (xy 427.590746 -342.573073) (xy 427.575383 -342.520747)
			(xy 427.567622 -342.466767) (xy 426.084796 -342.466767) (xy 426.084796 -342.466771) (xy 426.077034 -342.520759)
			(xy 426.061668 -342.573092) (xy 426.03901 -342.622705) (xy 426.009521 -342.668589) (xy 425.973803 -342.709809)
			(xy 425.932582 -342.745526) (xy 425.886698 -342.775013) (xy 425.837084 -342.79767) (xy 425.784751 -342.813036)
			(xy 425.730763 -342.820797) (xy 425.703492 -342.82126) (xy 424.839892 -342.82126) (xy 424.812623 -342.820777)
			(xy 424.75864 -342.813014) (xy 424.706311 -342.797648) (xy 424.656702 -342.774991) (xy 424.610821 -342.745505)
			(xy 424.569605 -342.70979) (xy 424.53389 -342.668572) (xy 424.504405 -342.622691) (xy 424.481749 -342.573082)
			(xy 424.466384 -342.520752) (xy 424.458622 -342.466769) (xy 422.975774 -342.466769) (xy 422.968013 -342.520748)
			(xy 422.952649 -342.573075) (xy 422.929995 -342.622683) (xy 422.900513 -342.668562) (xy 422.864801 -342.709778)
			(xy 422.823588 -342.745494) (xy 422.777711 -342.77498) (xy 422.728105 -342.797638) (xy 422.67578 -342.813006)
			(xy 422.6218 -342.820771) (xy 422.594532 -342.82126) (xy 421.730932 -342.82126) (xy 421.703659 -342.820803)
			(xy 421.649669 -342.813044) (xy 421.597332 -342.797681) (xy 421.547715 -342.775025) (xy 421.501827 -342.745538)
			(xy 421.460602 -342.70982) (xy 421.424881 -342.668599) (xy 421.395391 -342.622714) (xy 421.372731 -342.573098)
			(xy 421.357363 -342.520763) (xy 421.3496 -342.466773) (xy 419.866896 -342.466773) (xy 419.859134 -342.520761)
			(xy 419.843766 -342.573096) (xy 419.821107 -342.622711) (xy 419.791616 -342.668595) (xy 419.755896 -342.709816)
			(xy 419.714673 -342.745533) (xy 419.668786 -342.77502) (xy 419.61917 -342.797676) (xy 419.566834 -342.81304)
			(xy 419.512844 -342.820798) (xy 419.485572 -342.82126) (xy 418.621972 -342.82126) (xy 418.594704 -342.820776)
			(xy 418.540723 -342.813011) (xy 418.488396 -342.797643) (xy 418.43879 -342.774985) (xy 418.392912 -342.745498)
			(xy 418.351697 -342.709783) (xy 418.315985 -342.668566) (xy 418.286502 -342.622686) (xy 418.263847 -342.573077)
			(xy 418.248483 -342.52075) (xy 418.240722 -342.466768) (xy 416.757874 -342.466768) (xy 416.757874 -342.466769)
			(xy 416.750112 -342.520751) (xy 416.734748 -342.573079) (xy 416.712092 -342.622688) (xy 416.682608 -342.668568)
			(xy 416.646894 -342.709786) (xy 416.605678 -342.745501) (xy 416.559799 -342.774987) (xy 416.510191 -342.797643)
			(xy 416.457863 -342.81301) (xy 416.403881 -342.820773) (xy 416.376612 -342.82126) (xy 415.513012 -342.82126)
			(xy 415.48574 -342.820801) (xy 415.431752 -342.813041) (xy 415.379417 -342.797675) (xy 415.329803 -342.775018)
			(xy 415.283917 -342.745531) (xy 415.242695 -342.709813) (xy 415.206976 -342.668593) (xy 415.177488 -342.622708)
			(xy 415.154829 -342.573094) (xy 415.139462 -342.52076) (xy 415.1317 -342.466772) (xy 413.648996 -342.466772)
			(xy 413.648996 -342.466773) (xy 413.641233 -342.520764) (xy 413.625864 -342.5731) (xy 413.603203 -342.622716)
			(xy 413.573712 -342.668602) (xy 413.537989 -342.709823) (xy 413.496763 -342.74554) (xy 413.450874 -342.775026)
			(xy 413.401255 -342.797681) (xy 413.348917 -342.813043) (xy 413.294925 -342.8208) (xy 413.267652 -342.82126)
			(xy 412.404052 -342.82126) (xy 412.376785 -342.820774) (xy 412.322806 -342.813007) (xy 412.270482 -342.797637)
			(xy 412.220878 -342.774978) (xy 412.175002 -342.745491) (xy 412.13379 -342.709776) (xy 412.09808 -342.668559)
			(xy 412.068599 -342.62268) (xy 412.045946 -342.573073) (xy 412.030583 -342.520747) (xy 412.022822 -342.466767)
			(xy 410.539996 -342.466767) (xy 410.539996 -342.466771) (xy 410.532234 -342.520759) (xy 410.516868 -342.573092)
			(xy 410.49421 -342.622705) (xy 410.464721 -342.668589) (xy 410.429003 -342.709809) (xy 410.387782 -342.745526)
			(xy 410.341898 -342.775013) (xy 410.292284 -342.79767) (xy 410.239951 -342.813036) (xy 410.185963 -342.820797)
			(xy 410.158692 -342.82126) (xy 409.295092 -342.82126) (xy 409.267823 -342.820777) (xy 409.21384 -342.813014)
			(xy 409.161511 -342.797648) (xy 409.111902 -342.774991) (xy 409.066021 -342.745505) (xy 409.024805 -342.70979)
			(xy 408.98909 -342.668572) (xy 408.959605 -342.622691) (xy 408.936949 -342.573082) (xy 408.921584 -342.520752)
			(xy 408.913822 -342.466769) (xy 403.522496 -342.466769) (xy 403.522496 -342.466772) (xy 403.514734 -342.52076)
			(xy 403.499367 -342.573094) (xy 403.476708 -342.622708) (xy 403.447218 -342.668593) (xy 403.411499 -342.709813)
			(xy 403.370277 -342.74553) (xy 403.324391 -342.775017) (xy 403.274775 -342.797674) (xy 403.222441 -342.813038)
			(xy 403.168452 -342.820798) (xy 403.14118 -342.82126) (xy 402.27758 -342.82126) (xy 402.250311 -342.820776)
			(xy 402.19633 -342.813012) (xy 402.144002 -342.797645) (xy 402.094394 -342.774988) (xy 402.048516 -342.745501)
			(xy 402.0073 -342.709786) (xy 401.971587 -342.668568) (xy 401.942103 -342.622688) (xy 401.919448 -342.573079)
			(xy 401.904084 -342.520751) (xy 401.896322 -342.466769) (xy 400.413474 -342.466769) (xy 400.405713 -342.52075)
			(xy 400.390348 -342.573078) (xy 400.367694 -342.622686) (xy 400.33821 -342.668566) (xy 400.302497 -342.709783)
			(xy 400.261282 -342.745498) (xy 400.215404 -342.774984) (xy 400.165796 -342.797641) (xy 400.113469 -342.813008)
			(xy 400.059488 -342.820772) (xy 400.03222 -342.82126) (xy 399.16862 -342.82126) (xy 399.141348 -342.820802)
			(xy 399.087359 -342.813042) (xy 399.035023 -342.797677) (xy 398.985407 -342.775021) (xy 398.939521 -342.745534)
			(xy 398.898298 -342.709816) (xy 398.862578 -342.668595) (xy 398.833089 -342.62271) (xy 398.81043 -342.573096)
			(xy 398.795062 -342.520761) (xy 398.7873 -342.466772) (xy 397.304596 -342.466772) (xy 397.304596 -342.466773)
			(xy 397.296833 -342.520763) (xy 397.281465 -342.573098) (xy 397.258805 -342.622714) (xy 397.229313 -342.668599)
			(xy 397.193592 -342.70982) (xy 397.152367 -342.745537) (xy 397.106479 -342.775024) (xy 397.056861 -342.797679)
			(xy 397.004524 -342.813042) (xy 396.950533 -342.820799) (xy 396.92326 -342.82126) (xy 396.05966 -342.82126)
			(xy 396.032392 -342.820775) (xy 395.978413 -342.813009) (xy 395.926088 -342.79764) (xy 395.876482 -342.774981)
			(xy 395.830606 -342.745494) (xy 395.789393 -342.709778) (xy 395.753682 -342.668562) (xy 395.7242 -342.622682)
			(xy 395.701546 -342.573075) (xy 395.686183 -342.520748) (xy 395.678422 -342.466768) (xy 394.195574 -342.466768)
			(xy 394.195574 -342.466769) (xy 394.187812 -342.520753) (xy 394.172447 -342.573082) (xy 394.149791 -342.622692)
			(xy 394.120305 -342.668572) (xy 394.08459 -342.70979) (xy 394.043372 -342.745505) (xy 393.997492 -342.774991)
			(xy 393.947882 -342.797647) (xy 393.895553 -342.813012) (xy 393.841569 -342.820774) (xy 393.8143 -342.82126)
			(xy 392.9507 -342.82126) (xy 392.92343 -342.820778) (xy 392.869447 -342.813016) (xy 392.817117 -342.79765)
			(xy 392.767506 -342.774994) (xy 392.721625 -342.745508) (xy 392.680407 -342.709793) (xy 392.644692 -342.668575)
			(xy 392.615206 -342.622694) (xy 392.59255 -342.573083) (xy 392.577184 -342.520753) (xy 392.569422 -342.46677)
			(xy 391.086574 -342.46677) (xy 391.078813 -342.520747) (xy 391.06345 -342.573073) (xy 391.040797 -342.622681)
			(xy 391.011315 -342.668559) (xy 390.975604 -342.709776) (xy 390.934391 -342.745491) (xy 390.888516 -342.774978)
			(xy 390.838911 -342.797636) (xy 390.786586 -342.813005) (xy 390.732607 -342.820771) (xy 390.70534 -342.82126)
			(xy 389.84174 -342.82126) (xy 389.814467 -342.820803) (xy 389.760476 -342.813046) (xy 389.708138 -342.797683)
			(xy 389.658519 -342.775027) (xy 389.61263 -342.745541) (xy 389.571405 -342.709823) (xy 389.535683 -342.668602)
			(xy 389.506192 -342.622716) (xy 389.483531 -342.5731) (xy 389.468163 -342.520764) (xy 389.4604 -342.466773)
			(xy 387.977696 -342.466773) (xy 387.969934 -342.52076) (xy 387.954567 -342.573094) (xy 387.931908 -342.622708)
			(xy 387.902418 -342.668593) (xy 387.866699 -342.709813) (xy 387.825477 -342.74553) (xy 387.779591 -342.775017)
			(xy 387.729975 -342.797674) (xy 387.677641 -342.813038) (xy 387.623652 -342.820798) (xy 387.59638 -342.82126)
			(xy 386.73278 -342.82126) (xy 386.705511 -342.820776) (xy 386.65153 -342.813012) (xy 386.599202 -342.797645)
			(xy 386.549594 -342.774988) (xy 386.503716 -342.745501) (xy 386.4625 -342.709786) (xy 386.426787 -342.668568)
			(xy 386.397303 -342.622688) (xy 386.374648 -342.573079) (xy 386.359284 -342.520751) (xy 386.351522 -342.466769)
			(xy 384.868674 -342.466769) (xy 384.860913 -342.52075) (xy 384.845548 -342.573078) (xy 384.822894 -342.622686)
			(xy 384.79341 -342.668566) (xy 384.757697 -342.709783) (xy 384.716482 -342.745498) (xy 384.670604 -342.774984)
			(xy 384.620996 -342.797641) (xy 384.568669 -342.813008) (xy 384.514688 -342.820772) (xy 384.48742 -342.82126)
			(xy 383.62382 -342.82126) (xy 383.596548 -342.820802) (xy 383.542559 -342.813042) (xy 383.490223 -342.797677)
			(xy 383.440607 -342.775021) (xy 383.394721 -342.745534) (xy 383.353498 -342.709816) (xy 383.317778 -342.668595)
			(xy 383.288289 -342.62271) (xy 383.26563 -342.573096) (xy 383.250262 -342.520761) (xy 383.2425 -342.466772)
			(xy 381.759796 -342.466772) (xy 381.759796 -342.466773) (xy 381.752033 -342.520763) (xy 381.736665 -342.573098)
			(xy 381.714005 -342.622714) (xy 381.684513 -342.668599) (xy 381.648792 -342.70982) (xy 381.607567 -342.745537)
			(xy 381.561679 -342.775024) (xy 381.512061 -342.797679) (xy 381.459724 -342.813042) (xy 381.405733 -342.820799)
			(xy 381.37846 -342.82126) (xy 380.51486 -342.82126) (xy 380.487592 -342.820775) (xy 380.433613 -342.813009)
			(xy 380.381288 -342.79764) (xy 380.331682 -342.774981) (xy 380.285806 -342.745494) (xy 380.244593 -342.709778)
			(xy 380.208882 -342.668562) (xy 380.1794 -342.622682) (xy 380.156746 -342.573075) (xy 380.141383 -342.520748)
			(xy 380.133622 -342.466768) (xy 378.650774 -342.466768) (xy 378.650774 -342.466769) (xy 378.643012 -342.520753)
			(xy 378.627647 -342.573082) (xy 378.604991 -342.622692) (xy 378.575505 -342.668572) (xy 378.53979 -342.70979)
			(xy 378.498572 -342.745505) (xy 378.452692 -342.774991) (xy 378.403082 -342.797647) (xy 378.350753 -342.813012)
			(xy 378.296769 -342.820774) (xy 378.2695 -342.82126) (xy 377.4059 -342.82126) (xy 377.37863 -342.820778)
			(xy 377.324647 -342.813016) (xy 377.272317 -342.79765) (xy 377.222706 -342.774994) (xy 377.176825 -342.745508)
			(xy 377.135607 -342.709793) (xy 377.099892 -342.668575) (xy 377.070406 -342.622694) (xy 377.04775 -342.573083)
			(xy 377.032384 -342.520753) (xy 377.024622 -342.46677) (xy 375.541774 -342.46677) (xy 375.534013 -342.520747)
			(xy 375.51865 -342.573073) (xy 375.495997 -342.622681) (xy 375.466515 -342.668559) (xy 375.430804 -342.709776)
			(xy 375.389591 -342.745491) (xy 375.343716 -342.774978) (xy 375.294111 -342.797636) (xy 375.241786 -342.813005)
			(xy 375.187807 -342.820771) (xy 375.16054 -342.82126) (xy 374.29694 -342.82126) (xy 374.269667 -342.820803)
			(xy 374.215676 -342.813046) (xy 374.163338 -342.797683) (xy 374.113719 -342.775027) (xy 374.06783 -342.745541)
			(xy 374.026605 -342.709823) (xy 373.990883 -342.668602) (xy 373.961392 -342.622716) (xy 373.938731 -342.5731)
			(xy 373.923363 -342.520764) (xy 373.9156 -342.466773) (xy 372.432896 -342.466773) (xy 372.425134 -342.52076)
			(xy 372.409767 -342.573094) (xy 372.387108 -342.622708) (xy 372.357618 -342.668593) (xy 372.321899 -342.709813)
			(xy 372.280677 -342.74553) (xy 372.234791 -342.775017) (xy 372.185175 -342.797674) (xy 372.132841 -342.813038)
			(xy 372.078852 -342.820798) (xy 372.05158 -342.82126) (xy 371.18798 -342.82126) (xy 371.160711 -342.820776)
			(xy 371.10673 -342.813012) (xy 371.054402 -342.797645) (xy 371.004794 -342.774988) (xy 370.958916 -342.745501)
			(xy 370.9177 -342.709786) (xy 370.881987 -342.668568) (xy 370.852503 -342.622688) (xy 370.829848 -342.573079)
			(xy 370.814484 -342.520751) (xy 370.806722 -342.466769) (xy 344.837274 -342.466769) (xy 344.829512 -342.520752)
			(xy 344.814147 -342.573081) (xy 344.791491 -342.622691) (xy 344.762006 -342.668571) (xy 344.726291 -342.709788)
			(xy 344.685074 -342.745503) (xy 344.639194 -342.774989) (xy 344.589585 -342.797646) (xy 344.537256 -342.813011)
			(xy 344.483273 -342.820773) (xy 344.456004 -342.82126) (xy 343.592404 -342.82126) (xy 343.565133 -342.820801)
			(xy 343.511145 -342.813039) (xy 343.458812 -342.797673) (xy 343.409198 -342.775016) (xy 343.363313 -342.745528)
			(xy 343.322093 -342.70981) (xy 343.286374 -342.66859) (xy 343.256886 -342.622706) (xy 343.234228 -342.573092)
			(xy 343.218862 -342.520759) (xy 343.2111 -342.466771) (xy 341.728273 -342.466771) (xy 341.720513 -342.520747)
			(xy 341.70515 -342.573072) (xy 341.682497 -342.622679) (xy 341.653016 -342.668558) (xy 341.617305 -342.709774)
			(xy 341.576093 -342.745489) (xy 341.530218 -342.774976) (xy 341.480614 -342.797635) (xy 341.42829 -342.813004)
			(xy 341.374311 -342.820771) (xy 341.347044 -342.82126) (xy 340.483444 -342.82126) (xy 340.456171 -342.820804)
			(xy 340.402179 -342.813046) (xy 340.349841 -342.797684) (xy 340.300222 -342.775029) (xy 340.254332 -342.745542)
			(xy 340.213107 -342.709824) (xy 340.177384 -342.668603) (xy 340.147892 -342.622717) (xy 340.125232 -342.573101)
			(xy 340.109863 -342.520764) (xy 340.1021 -342.466773) (xy 338.619396 -342.466773) (xy 338.611634 -342.52076)
			(xy 338.596267 -342.573093) (xy 338.573608 -342.622707) (xy 338.544119 -342.668591) (xy 338.5084 -342.709812)
			(xy 338.467179 -342.745529) (xy 338.421293 -342.775016) (xy 338.371678 -342.797673) (xy 338.319344 -342.813037)
			(xy 338.265356 -342.820798) (xy 338.238084 -342.82126) (xy 337.374484 -342.82126) (xy 337.347215 -342.820776)
			(xy 337.293233 -342.813013) (xy 337.240905 -342.797646) (xy 337.191297 -342.774989) (xy 337.145418 -342.745502)
			(xy 337.104202 -342.709787) (xy 337.068488 -342.66857) (xy 337.039003 -342.622689) (xy 337.016348 -342.57308)
			(xy 337.000984 -342.520751) (xy 336.993222 -342.466769) (xy 335.510374 -342.466769) (xy 335.502613 -342.520749)
			(xy 335.487249 -342.573077) (xy 335.464594 -342.622685) (xy 335.435111 -342.668565) (xy 335.399398 -342.709781)
			(xy 335.358184 -342.745496) (xy 335.312306 -342.774983) (xy 335.262699 -342.79764) (xy 335.210373 -342.813008)
			(xy 335.156392 -342.820772) (xy 335.129124 -342.82126) (xy 334.265524 -342.82126) (xy 334.238252 -342.820802)
			(xy 334.184262 -342.813043) (xy 334.131926 -342.797678) (xy 334.08231 -342.775022) (xy 334.036423 -342.745535)
			(xy 333.9952 -342.709817) (xy 333.959479 -342.668596) (xy 333.929989 -342.622711) (xy 333.90733 -342.573096)
			(xy 333.891962 -342.520761) (xy 333.8842 -342.466772) (xy 332.401496 -342.466772) (xy 332.393733 -342.520762)
			(xy 332.378365 -342.573098) (xy 332.355705 -342.622713) (xy 332.326214 -342.668598) (xy 332.290493 -342.709819)
			(xy 332.249269 -342.745536) (xy 332.203381 -342.775023) (xy 332.153764 -342.797678) (xy 332.101427 -342.813041)
			(xy 332.047437 -342.820799) (xy 332.020164 -342.82126) (xy 331.156564 -342.82126) (xy 331.129296 -342.820775)
			(xy 331.075316 -342.813009) (xy 331.022991 -342.797641) (xy 330.973385 -342.774982) (xy 330.927508 -342.745495)
			(xy 330.886295 -342.70978) (xy 330.850583 -342.668563) (xy 330.8211 -342.622684) (xy 330.798447 -342.573076)
			(xy 330.783083 -342.520749) (xy 330.775322 -342.466768) (xy 329.292474 -342.466768) (xy 329.292474 -342.466769)
			(xy 329.284712 -342.520752) (xy 329.269347 -342.573081) (xy 329.246691 -342.622691) (xy 329.217206 -342.668571)
			(xy 329.181491 -342.709788) (xy 329.140274 -342.745503) (xy 329.094394 -342.774989) (xy 329.044785 -342.797646)
			(xy 328.992456 -342.813011) (xy 328.938473 -342.820773) (xy 328.911204 -342.82126) (xy 328.047604 -342.82126)
			(xy 328.020333 -342.820801) (xy 327.966345 -342.813039) (xy 327.914012 -342.797673) (xy 327.864398 -342.775016)
			(xy 327.818513 -342.745528) (xy 327.777293 -342.70981) (xy 327.741574 -342.66859) (xy 327.712086 -342.622706)
			(xy 327.689428 -342.573092) (xy 327.674062 -342.520759) (xy 327.6663 -342.466771) (xy 326.183473 -342.466771)
			(xy 326.175713 -342.520747) (xy 326.16035 -342.573072) (xy 326.137697 -342.622679) (xy 326.108216 -342.668558)
			(xy 326.072505 -342.709774) (xy 326.031293 -342.745489) (xy 325.985418 -342.774976) (xy 325.935814 -342.797635)
			(xy 325.88349 -342.813004) (xy 325.829511 -342.820771) (xy 325.802244 -342.82126) (xy 324.938644 -342.82126)
			(xy 324.911371 -342.820804) (xy 324.857379 -342.813046) (xy 324.805041 -342.797684) (xy 324.755422 -342.775029)
			(xy 324.709532 -342.745542) (xy 324.668307 -342.709824) (xy 324.632584 -342.668603) (xy 324.603092 -342.622717)
			(xy 324.580432 -342.573101) (xy 324.565063 -342.520764) (xy 324.5573 -342.466773) (xy 323.074596 -342.466773)
			(xy 323.066834 -342.52076) (xy 323.051467 -342.573093) (xy 323.028808 -342.622707) (xy 322.999319 -342.668591)
			(xy 322.9636 -342.709812) (xy 322.922379 -342.745529) (xy 322.876493 -342.775016) (xy 322.826878 -342.797673)
			(xy 322.774544 -342.813037) (xy 322.720556 -342.820798) (xy 322.693284 -342.82126) (xy 321.829684 -342.82126)
			(xy 321.802415 -342.820776) (xy 321.748433 -342.813013) (xy 321.696105 -342.797646) (xy 321.646497 -342.774989)
			(xy 321.600618 -342.745502) (xy 321.559402 -342.709787) (xy 321.523688 -342.66857) (xy 321.494203 -342.622689)
			(xy 321.471548 -342.57308) (xy 321.456184 -342.520751) (xy 321.448422 -342.466769) (xy 319.965574 -342.466769)
			(xy 319.957813 -342.520749) (xy 319.942449 -342.573077) (xy 319.919794 -342.622685) (xy 319.890311 -342.668565)
			(xy 319.854598 -342.709781) (xy 319.813384 -342.745496) (xy 319.767506 -342.774983) (xy 319.717899 -342.79764)
			(xy 319.665573 -342.813008) (xy 319.611592 -342.820772) (xy 319.584324 -342.82126) (xy 318.720724 -342.82126)
			(xy 318.693452 -342.820802) (xy 318.639462 -342.813043) (xy 318.587126 -342.797678) (xy 318.53751 -342.775022)
			(xy 318.491623 -342.745535) (xy 318.4504 -342.709817) (xy 318.414679 -342.668596) (xy 318.385189 -342.622711)
			(xy 318.36253 -342.573096) (xy 318.347162 -342.520761) (xy 318.3394 -342.466772) (xy 316.856696 -342.466772)
			(xy 316.848933 -342.520762) (xy 316.833565 -342.573098) (xy 316.810905 -342.622713) (xy 316.781414 -342.668598)
			(xy 316.745693 -342.709819) (xy 316.704469 -342.745536) (xy 316.658581 -342.775023) (xy 316.608964 -342.797678)
			(xy 316.556627 -342.813041) (xy 316.502637 -342.820799) (xy 316.475364 -342.82126) (xy 315.611764 -342.82126)
			(xy 315.584496 -342.820775) (xy 315.530516 -342.813009) (xy 315.478191 -342.797641) (xy 315.428585 -342.774982)
			(xy 315.382708 -342.745495) (xy 315.341495 -342.70978) (xy 315.305783 -342.668563) (xy 315.2763 -342.622684)
			(xy 315.253647 -342.573076) (xy 315.238283 -342.520749) (xy 315.230522 -342.466768) (xy 313.747674 -342.466768)
			(xy 313.747674 -342.466769) (xy 313.739912 -342.520752) (xy 313.724547 -342.573081) (xy 313.701891 -342.622691)
			(xy 313.672406 -342.668571) (xy 313.636691 -342.709788) (xy 313.595474 -342.745503) (xy 313.549594 -342.774989)
			(xy 313.499985 -342.797646) (xy 313.447656 -342.813011) (xy 313.393673 -342.820773) (xy 313.366404 -342.82126)
			(xy 312.502804 -342.82126) (xy 312.475533 -342.820801) (xy 312.421545 -342.813039) (xy 312.369212 -342.797673)
			(xy 312.319598 -342.775016) (xy 312.273713 -342.745528) (xy 312.232493 -342.70981) (xy 312.196774 -342.66859)
			(xy 312.167286 -342.622706) (xy 312.144628 -342.573092) (xy 312.129262 -342.520759) (xy 312.1215 -342.466771)
			(xy 300.231574 -342.466771) (xy 300.223812 -342.520752) (xy 300.208447 -342.573081) (xy 300.185791 -342.622691)
			(xy 300.156305 -342.668572) (xy 300.120591 -342.709789) (xy 300.079373 -342.745504) (xy 300.033493 -342.77499)
			(xy 299.983883 -342.797646) (xy 299.931554 -342.813012) (xy 299.877571 -342.820773) (xy 299.850302 -342.82126)
			(xy 298.986702 -342.82126) (xy 298.959431 -342.820801) (xy 298.905443 -342.813039) (xy 298.85311 -342.797673)
			(xy 298.803497 -342.775015) (xy 298.757612 -342.745527) (xy 298.716392 -342.70981) (xy 298.680674 -342.668589)
			(xy 298.651186 -342.622705) (xy 298.628528 -342.573092) (xy 298.613162 -342.520759) (xy 298.605399 -342.466771)
			(xy 297.122573 -342.466771) (xy 297.114813 -342.520747) (xy 297.09945 -342.573073) (xy 297.076797 -342.62268)
			(xy 297.047315 -342.668559) (xy 297.011605 -342.709775) (xy 296.970392 -342.74549) (xy 296.924517 -342.774977)
			(xy 296.874912 -342.797635) (xy 296.822588 -342.813004) (xy 296.768609 -342.820771) (xy 296.741342 -342.82126)
			(xy 295.877742 -342.82126) (xy 295.850469 -342.820803) (xy 295.796477 -342.813046) (xy 295.744139 -342.797683)
			(xy 295.694521 -342.775028) (xy 295.648631 -342.745541) (xy 295.607406 -342.709824) (xy 295.571684 -342.668602)
			(xy 295.542192 -342.622716) (xy 295.519531 -342.5731) (xy 295.504163 -342.520764) (xy 295.4964 -342.466773)
			(xy 294.013696 -342.466773) (xy 294.005934 -342.52076) (xy 293.990567 -342.573094) (xy 293.967908 -342.622708)
			(xy 293.938419 -342.668592) (xy 293.9027 -342.709812) (xy 293.861478 -342.74553) (xy 293.815592 -342.775017)
			(xy 293.765977 -342.797673) (xy 293.713642 -342.813038) (xy 293.659654 -342.820798) (xy 293.632382 -342.82126)
			(xy 292.768782 -342.82126) (xy 292.741513 -342.820776) (xy 292.687531 -342.813013) (xy 292.635204 -342.797646)
			(xy 292.585596 -342.774988) (xy 292.539717 -342.745502) (xy 292.498501 -342.709786) (xy 292.462787 -342.668569)
			(xy 292.433303 -342.622689) (xy 292.410648 -342.573079) (xy 292.395284 -342.520751) (xy 292.387522 -342.466769)
			(xy 290.904674 -342.466769) (xy 290.896913 -342.52075) (xy 290.881548 -342.573077) (xy 290.858894 -342.622686)
			(xy 290.82941 -342.668565) (xy 290.793698 -342.709782) (xy 290.752483 -342.745497) (xy 290.706605 -342.774983)
			(xy 290.656998 -342.797641) (xy 290.604671 -342.813008) (xy 290.55069 -342.820772) (xy 290.523422 -342.82126)
			(xy 289.659822 -342.82126) (xy 289.63255 -342.820802) (xy 289.57856 -342.813042) (xy 289.526225 -342.797678)
			(xy 289.476609 -342.775021) (xy 289.430722 -342.745534) (xy 289.389499 -342.709817) (xy 289.353779 -342.668596)
			(xy 289.324289 -342.622711) (xy 289.30163 -342.573096) (xy 289.286262 -342.520761) (xy 289.2785 -342.466772)
			(xy 287.795796 -342.466772) (xy 287.795796 -342.466773) (xy 287.788033 -342.520763) (xy 287.772665 -342.573098)
			(xy 287.750005 -342.622713) (xy 287.720514 -342.668599) (xy 287.684793 -342.70982) (xy 287.643568 -342.745537)
			(xy 287.59768 -342.775023) (xy 287.548062 -342.797679) (xy 287.495725 -342.813041) (xy 287.441735 -342.820799)
			(xy 287.414462 -342.82126) (xy 286.550862 -342.82126) (xy 286.523594 -342.820775) (xy 286.469614 -342.813009)
			(xy 286.417289 -342.79764) (xy 286.367684 -342.774982) (xy 286.321807 -342.745495) (xy 286.280594 -342.709779)
			(xy 286.244883 -342.668562) (xy 286.2154 -342.622683) (xy 286.192747 -342.573075) (xy 286.177383 -342.520748)
			(xy 286.169622 -342.466768) (xy 284.686774 -342.466768) (xy 284.686774 -342.466769) (xy 284.679012 -342.520752)
			(xy 284.663647 -342.573081) (xy 284.640991 -342.622691) (xy 284.611505 -342.668572) (xy 284.575791 -342.709789)
			(xy 284.534573 -342.745504) (xy 284.488693 -342.77499) (xy 284.439083 -342.797646) (xy 284.386754 -342.813012)
			(xy 284.332771 -342.820773) (xy 284.305502 -342.82126) (xy 283.441902 -342.82126) (xy 283.414631 -342.820801)
			(xy 283.360643 -342.813039) (xy 283.30831 -342.797673) (xy 283.258697 -342.775015) (xy 283.212812 -342.745527)
			(xy 283.171592 -342.70981) (xy 283.135874 -342.668589) (xy 283.106386 -342.622705) (xy 283.083728 -342.573092)
			(xy 283.068362 -342.520759) (xy 283.060599 -342.466771) (xy 281.577773 -342.466771) (xy 281.570013 -342.520747)
			(xy 281.55465 -342.573073) (xy 281.531997 -342.62268) (xy 281.502515 -342.668559) (xy 281.466805 -342.709775)
			(xy 281.425592 -342.74549) (xy 281.379717 -342.774977) (xy 281.330112 -342.797635) (xy 281.277788 -342.813004)
			(xy 281.223809 -342.820771) (xy 281.196542 -342.82126) (xy 280.332942 -342.82126) (xy 280.305669 -342.820803)
			(xy 280.251677 -342.813046) (xy 280.199339 -342.797683) (xy 280.149721 -342.775028) (xy 280.103831 -342.745541)
			(xy 280.062606 -342.709824) (xy 280.026884 -342.668602) (xy 279.997392 -342.622716) (xy 279.974731 -342.5731)
			(xy 279.959363 -342.520764) (xy 279.9516 -342.466773) (xy 278.468896 -342.466773) (xy 278.461134 -342.52076)
			(xy 278.445767 -342.573094) (xy 278.423108 -342.622708) (xy 278.393619 -342.668592) (xy 278.3579 -342.709812)
			(xy 278.316678 -342.74553) (xy 278.270792 -342.775017) (xy 278.221177 -342.797673) (xy 278.168842 -342.813038)
			(xy 278.114854 -342.820798) (xy 278.087582 -342.82126) (xy 277.223982 -342.82126) (xy 277.196713 -342.820776)
			(xy 277.142731 -342.813013) (xy 277.090404 -342.797646) (xy 277.040796 -342.774988) (xy 276.994917 -342.745502)
			(xy 276.953701 -342.709786) (xy 276.917987 -342.668569) (xy 276.888503 -342.622689) (xy 276.865848 -342.573079)
			(xy 276.850484 -342.520751) (xy 276.842722 -342.466769) (xy 275.359874 -342.466769) (xy 275.352113 -342.52075)
			(xy 275.336748 -342.573077) (xy 275.314094 -342.622686) (xy 275.28461 -342.668565) (xy 275.248898 -342.709782)
			(xy 275.207683 -342.745497) (xy 275.161805 -342.774983) (xy 275.112198 -342.797641) (xy 275.059871 -342.813008)
			(xy 275.00589 -342.820772) (xy 274.978622 -342.82126) (xy 274.115022 -342.82126) (xy 274.08775 -342.820802)
			(xy 274.03376 -342.813042) (xy 273.981425 -342.797678) (xy 273.931809 -342.775021) (xy 273.885922 -342.745534)
			(xy 273.844699 -342.709817) (xy 273.808979 -342.668596) (xy 273.779489 -342.622711) (xy 273.75683 -342.573096)
			(xy 273.741462 -342.520761) (xy 273.7337 -342.466772) (xy 272.250996 -342.466772) (xy 272.250996 -342.466773)
			(xy 272.243233 -342.520763) (xy 272.227865 -342.573098) (xy 272.205205 -342.622713) (xy 272.175714 -342.668599)
			(xy 272.139993 -342.70982) (xy 272.098768 -342.745537) (xy 272.05288 -342.775023) (xy 272.003262 -342.797679)
			(xy 271.950925 -342.813041) (xy 271.896935 -342.820799) (xy 271.869662 -342.82126) (xy 271.006062 -342.82126)
			(xy 270.978794 -342.820775) (xy 270.924814 -342.813009) (xy 270.872489 -342.79764) (xy 270.822884 -342.774982)
			(xy 270.777007 -342.745495) (xy 270.735794 -342.709779) (xy 270.700083 -342.668562) (xy 270.6706 -342.622683)
			(xy 270.647947 -342.573075) (xy 270.632583 -342.520748) (xy 270.624822 -342.466768) (xy 269.141974 -342.466768)
			(xy 269.141974 -342.466769) (xy 269.134212 -342.520752) (xy 269.118847 -342.573081) (xy 269.096191 -342.622691)
			(xy 269.066705 -342.668572) (xy 269.030991 -342.709789) (xy 268.989773 -342.745504) (xy 268.943893 -342.77499)
			(xy 268.894283 -342.797646) (xy 268.841954 -342.813012) (xy 268.787971 -342.820773) (xy 268.760702 -342.82126)
			(xy 267.897102 -342.82126) (xy 267.869831 -342.820801) (xy 267.815843 -342.813039) (xy 267.76351 -342.797673)
			(xy 267.713897 -342.775015) (xy 267.668012 -342.745527) (xy 267.626792 -342.70981) (xy 267.591074 -342.668589)
			(xy 267.561586 -342.622705) (xy 267.538928 -342.573092) (xy 267.523562 -342.520759) (xy 267.515799 -342.466771)
			(xy 256.581015 -342.466771) (xy 256.573351 -342.471196) (xy 256.517947 -342.494145) (xy 256.460022 -342.509666)
			(xy 256.400566 -342.517494) (xy 256.340598 -342.517494) (xy 256.281142 -342.509666) (xy 256.223217 -342.494145)
			(xy 256.167813 -342.471196) (xy 256.115879 -342.441212) (xy 256.068303 -342.404706) (xy 256.025898 -342.362301)
			(xy 255.989392 -342.314725) (xy 255.959408 -342.262791) (xy 255.936459 -342.207387) (xy 255.920938 -342.149462)
			(xy 255.91311 -342.090006) (xy 255.91262 -342.060022) (xy 197.28821 -342.060022) (xy 197.329534 -342.06596)
			(xy 197.38187 -342.081324) (xy 197.431486 -342.10398) (xy 197.477373 -342.133467) (xy 197.518596 -342.169184)
			(xy 197.554316 -342.210405) (xy 197.583807 -342.256289) (xy 197.606466 -342.305904) (xy 197.621834 -342.358239)
			(xy 197.629596 -342.412228) (xy 197.629596 -342.466772) (xy 197.621834 -342.520761) (xy 197.606466 -342.573096)
			(xy 197.583807 -342.622711) (xy 197.554316 -342.668595) (xy 197.518596 -342.709816) (xy 197.477373 -342.745533)
			(xy 197.431486 -342.77502) (xy 197.38187 -342.797676) (xy 197.329534 -342.81304) (xy 197.275544 -342.820798)
			(xy 197.248272 -342.82126) (xy 196.384672 -342.82126) (xy 196.357404 -342.820776) (xy 196.303423 -342.813011)
			(xy 196.251096 -342.797643) (xy 196.20149 -342.774985) (xy 196.155612 -342.745498) (xy 196.114397 -342.709783)
			(xy 196.078685 -342.668566) (xy 196.049202 -342.622686) (xy 196.026547 -342.573077) (xy 196.011183 -342.52075)
			(xy 196.003422 -342.466768) (xy 194.520574 -342.466768) (xy 194.520574 -342.466769) (xy 194.512812 -342.520751)
			(xy 194.497448 -342.573079) (xy 194.474792 -342.622688) (xy 194.445308 -342.668568) (xy 194.409594 -342.709786)
			(xy 194.368378 -342.745501) (xy 194.322499 -342.774987) (xy 194.272891 -342.797643) (xy 194.220563 -342.81301)
			(xy 194.166581 -342.820773) (xy 194.139312 -342.82126) (xy 193.275712 -342.82126) (xy 193.24844 -342.820801)
			(xy 193.194452 -342.813041) (xy 193.142117 -342.797675) (xy 193.092503 -342.775018) (xy 193.046617 -342.745531)
			(xy 193.005395 -342.709813) (xy 192.969676 -342.668593) (xy 192.940188 -342.622708) (xy 192.917529 -342.573094)
			(xy 192.902162 -342.52076) (xy 192.8944 -342.466772) (xy 191.411696 -342.466772) (xy 191.411696 -342.466773)
			(xy 191.403933 -342.520764) (xy 191.388564 -342.5731) (xy 191.365903 -342.622716) (xy 191.336412 -342.668602)
			(xy 191.300689 -342.709823) (xy 191.259463 -342.74554) (xy 191.213574 -342.775026) (xy 191.163955 -342.797681)
			(xy 191.111617 -342.813043) (xy 191.057625 -342.8208) (xy 191.030352 -342.82126) (xy 190.166752 -342.82126)
			(xy 190.139485 -342.820774) (xy 190.085506 -342.813007) (xy 190.033182 -342.797637) (xy 189.983578 -342.774978)
			(xy 189.937702 -342.745491) (xy 189.89649 -342.709776) (xy 189.86078 -342.668559) (xy 189.831299 -342.62268)
			(xy 189.808646 -342.573073) (xy 189.793283 -342.520747) (xy 189.785522 -342.466767) (xy 188.302696 -342.466767)
			(xy 188.302696 -342.466771) (xy 188.294934 -342.520759) (xy 188.279568 -342.573092) (xy 188.25691 -342.622705)
			(xy 188.227421 -342.668589) (xy 188.191703 -342.709809) (xy 188.150482 -342.745526) (xy 188.104598 -342.775013)
			(xy 188.054984 -342.79767) (xy 188.002651 -342.813036) (xy 187.948663 -342.820797) (xy 187.921392 -342.82126)
			(xy 187.057792 -342.82126) (xy 187.030523 -342.820777) (xy 186.97654 -342.813014) (xy 186.924211 -342.797648)
			(xy 186.874602 -342.774991) (xy 186.828721 -342.745505) (xy 186.787505 -342.70979) (xy 186.75179 -342.668572)
			(xy 186.722305 -342.622691) (xy 186.699649 -342.573082) (xy 186.684284 -342.520752) (xy 186.676522 -342.466769)
			(xy 185.193674 -342.466769) (xy 185.185913 -342.520748) (xy 185.170549 -342.573075) (xy 185.147895 -342.622683)
			(xy 185.118413 -342.668562) (xy 185.082701 -342.709778) (xy 185.041488 -342.745494) (xy 184.995611 -342.77498)
			(xy 184.946005 -342.797638) (xy 184.89368 -342.813006) (xy 184.8397 -342.820771) (xy 184.812432 -342.82126)
			(xy 183.948832 -342.82126) (xy 183.921559 -342.820803) (xy 183.867569 -342.813044) (xy 183.815232 -342.797681)
			(xy 183.765615 -342.775025) (xy 183.719727 -342.745538) (xy 183.678502 -342.70982) (xy 183.642781 -342.668599)
			(xy 183.613291 -342.622714) (xy 183.590631 -342.573098) (xy 183.575263 -342.520763) (xy 183.5675 -342.466773)
			(xy 182.084796 -342.466773) (xy 182.077034 -342.520761) (xy 182.061666 -342.573096) (xy 182.039007 -342.622711)
			(xy 182.009516 -342.668595) (xy 181.973796 -342.709816) (xy 181.932573 -342.745533) (xy 181.886686 -342.77502)
			(xy 181.83707 -342.797676) (xy 181.784734 -342.81304) (xy 181.730744 -342.820798) (xy 181.703472 -342.82126)
			(xy 180.839872 -342.82126) (xy 180.812604 -342.820776) (xy 180.758623 -342.813011) (xy 180.706296 -342.797643)
			(xy 180.65669 -342.774985) (xy 180.610812 -342.745498) (xy 180.569597 -342.709783) (xy 180.533885 -342.668566)
			(xy 180.504402 -342.622686) (xy 180.481747 -342.573077) (xy 180.466383 -342.52075) (xy 180.458622 -342.466768)
			(xy 178.975774 -342.466768) (xy 178.975774 -342.466769) (xy 178.968012 -342.520751) (xy 178.952648 -342.573079)
			(xy 178.929992 -342.622688) (xy 178.900508 -342.668568) (xy 178.864794 -342.709786) (xy 178.823578 -342.745501)
			(xy 178.777699 -342.774987) (xy 178.728091 -342.797643) (xy 178.675763 -342.81301) (xy 178.621781 -342.820773)
			(xy 178.594512 -342.82126) (xy 177.730912 -342.82126) (xy 177.70364 -342.820801) (xy 177.649652 -342.813041)
			(xy 177.597317 -342.797675) (xy 177.547703 -342.775018) (xy 177.501817 -342.745531) (xy 177.460595 -342.709813)
			(xy 177.424876 -342.668593) (xy 177.395388 -342.622708) (xy 177.372729 -342.573094) (xy 177.357362 -342.52076)
			(xy 177.3496 -342.466772) (xy 175.866896 -342.466772) (xy 175.866896 -342.466773) (xy 175.859133 -342.520764)
			(xy 175.843764 -342.5731) (xy 175.821103 -342.622716) (xy 175.791612 -342.668602) (xy 175.755889 -342.709823)
			(xy 175.714663 -342.74554) (xy 175.668774 -342.775026) (xy 175.619155 -342.797681) (xy 175.566817 -342.813043)
			(xy 175.512825 -342.8208) (xy 175.485552 -342.82126) (xy 174.621952 -342.82126) (xy 174.594685 -342.820774)
			(xy 174.540706 -342.813007) (xy 174.488382 -342.797637) (xy 174.438778 -342.774978) (xy 174.392902 -342.745491)
			(xy 174.35169 -342.709776) (xy 174.31598 -342.668559) (xy 174.286499 -342.62268) (xy 174.263846 -342.573073)
			(xy 174.248483 -342.520747) (xy 174.240722 -342.466767) (xy 172.757896 -342.466767) (xy 172.757896 -342.466771)
			(xy 172.750134 -342.520759) (xy 172.734768 -342.573092) (xy 172.71211 -342.622705) (xy 172.682621 -342.668589)
			(xy 172.646903 -342.709809) (xy 172.605682 -342.745526) (xy 172.559798 -342.775013) (xy 172.510184 -342.79767)
			(xy 172.457851 -342.813036) (xy 172.403863 -342.820797) (xy 172.376592 -342.82126) (xy 171.512992 -342.82126)
			(xy 171.485723 -342.820777) (xy 171.43174 -342.813014) (xy 171.379411 -342.797648) (xy 171.329802 -342.774991)
			(xy 171.283921 -342.745505) (xy 171.242705 -342.70979) (xy 171.20699 -342.668572) (xy 171.177505 -342.622691)
			(xy 171.154849 -342.573082) (xy 171.139484 -342.520752) (xy 171.131722 -342.466769) (xy 169.648874 -342.466769)
			(xy 169.641113 -342.520748) (xy 169.625749 -342.573075) (xy 169.603095 -342.622683) (xy 169.573613 -342.668562)
			(xy 169.537901 -342.709778) (xy 169.496688 -342.745494) (xy 169.450811 -342.77498) (xy 169.401205 -342.797638)
			(xy 169.34888 -342.813006) (xy 169.2949 -342.820771) (xy 169.267632 -342.82126) (xy 168.404032 -342.82126)
			(xy 168.376759 -342.820803) (xy 168.322769 -342.813044) (xy 168.270432 -342.797681) (xy 168.220815 -342.775025)
			(xy 168.174927 -342.745538) (xy 168.133702 -342.70982) (xy 168.097981 -342.668599) (xy 168.068491 -342.622714)
			(xy 168.045831 -342.573098) (xy 168.030463 -342.520763) (xy 168.0227 -342.466773) (xy 166.539996 -342.466773)
			(xy 166.532234 -342.520761) (xy 166.516866 -342.573096) (xy 166.494207 -342.622711) (xy 166.464716 -342.668595)
			(xy 166.428996 -342.709816) (xy 166.387773 -342.745533) (xy 166.341886 -342.77502) (xy 166.29227 -342.797676)
			(xy 166.239934 -342.81304) (xy 166.185944 -342.820798) (xy 166.158672 -342.82126) (xy 165.295072 -342.82126)
			(xy 165.267804 -342.820776) (xy 165.213823 -342.813011) (xy 165.161496 -342.797643) (xy 165.11189 -342.774985)
			(xy 165.066012 -342.745498) (xy 165.024797 -342.709783) (xy 164.989085 -342.668566) (xy 164.959602 -342.622686)
			(xy 164.936947 -342.573077) (xy 164.921583 -342.52075) (xy 164.913822 -342.466768) (xy 144.196574 -342.466768)
			(xy 144.196574 -342.466769) (xy 144.188812 -342.520751) (xy 144.173447 -342.57308) (xy 144.150792 -342.622689)
			(xy 144.121307 -342.66857) (xy 144.085593 -342.709787) (xy 144.044376 -342.745502) (xy 143.998497 -342.774988)
			(xy 143.948888 -342.797645) (xy 143.896559 -342.81301) (xy 143.842577 -342.820773) (xy 143.815308 -342.82126)
			(xy 142.951708 -342.82126) (xy 142.924436 -342.820801) (xy 142.870448 -342.81304) (xy 142.818115 -342.797674)
			(xy 142.7685 -342.775017) (xy 142.722615 -342.745529) (xy 142.681394 -342.709812) (xy 142.645675 -342.668591)
			(xy 142.616187 -342.622707) (xy 142.593529 -342.573093) (xy 142.578162 -342.520759) (xy 142.5704 -342.466772)
			(xy 141.087573 -342.466772) (xy 141.079813 -342.520746) (xy 141.064451 -342.573072) (xy 141.041798 -342.622678)
			(xy 141.012317 -342.668557) (xy 140.976607 -342.709773) (xy 140.935395 -342.745488) (xy 140.88952 -342.774975)
			(xy 140.839917 -342.797634) (xy 140.787593 -342.813003) (xy 140.733615 -342.82077) (xy 140.706348 -342.82126)
			(xy 139.842748 -342.82126) (xy 139.815475 -342.820804) (xy 139.761482 -342.813047) (xy 139.709144 -342.797685)
			(xy 139.659524 -342.77503) (xy 139.613634 -342.745544) (xy 139.572408 -342.709826) (xy 139.536685 -342.668604)
			(xy 139.507193 -342.622718) (xy 139.484532 -342.573101) (xy 139.469163 -342.520765) (xy 139.4614 -342.466773)
			(xy 137.978696 -342.466773) (xy 137.970934 -342.520759) (xy 137.955567 -342.573092) (xy 137.932909 -342.622706)
			(xy 137.90342 -342.66859) (xy 137.867702 -342.70981) (xy 137.82648 -342.745528) (xy 137.780596 -342.775015)
			(xy 137.730981 -342.797671) (xy 137.678647 -342.813037) (xy 137.624659 -342.820797) (xy 137.597388 -342.82126)
			(xy 136.733788 -342.82126) (xy 136.706519 -342.820777) (xy 136.652536 -342.813014) (xy 136.600208 -342.797647)
			(xy 136.550599 -342.77499) (xy 136.50472 -342.745504) (xy 136.463503 -342.709788) (xy 136.427789 -342.668571)
			(xy 136.398304 -342.62269) (xy 136.375649 -342.573081) (xy 136.360284 -342.520752) (xy 136.352522 -342.466769)
			(xy 134.869674 -342.466769) (xy 134.861913 -342.520749) (xy 134.846549 -342.573076) (xy 134.823895 -342.622684)
			(xy 134.794412 -342.668563) (xy 134.7587 -342.70978) (xy 134.717486 -342.745495) (xy 134.671609 -342.774981)
			(xy 134.622002 -342.797639) (xy 134.569676 -342.813007) (xy 134.515696 -342.820772) (xy 134.488428 -342.82126)
			(xy 133.624828 -342.82126) (xy 133.597556 -342.820802) (xy 133.543565 -342.813043) (xy 133.491229 -342.79768)
			(xy 133.441612 -342.775023) (xy 133.395725 -342.745536) (xy 133.354501 -342.709819) (xy 133.31878 -342.668598)
			(xy 133.28929 -342.622712) (xy 133.26663 -342.573097) (xy 133.251262 -342.520762) (xy 133.2435 -342.466772)
			(xy 131.760796 -342.466772) (xy 131.753033 -342.520762) (xy 131.737666 -342.573097) (xy 131.715006 -342.622712)
			(xy 131.685515 -342.668597) (xy 131.649795 -342.709817) (xy 131.608571 -342.745535) (xy 131.562684 -342.775021)
			(xy 131.513067 -342.797677) (xy 131.46073 -342.81304) (xy 131.40674 -342.820799) (xy 131.379468 -342.82126)
			(xy 130.515868 -342.82126) (xy 130.4886 -342.820775) (xy 130.43462 -342.81301) (xy 130.382294 -342.797642)
			(xy 130.332687 -342.774984) (xy 130.28681 -342.745497) (xy 130.245596 -342.709781) (xy 130.209884 -342.668564)
			(xy 130.180401 -342.622685) (xy 130.157747 -342.573076) (xy 130.142383 -342.520749) (xy 130.134622 -342.466768)
			(xy 128.651774 -342.466768) (xy 128.651774 -342.466769) (xy 128.644012 -342.520751) (xy 128.628647 -342.57308)
			(xy 128.605992 -342.622689) (xy 128.576507 -342.66857) (xy 128.540793 -342.709787) (xy 128.499576 -342.745502)
			(xy 128.453697 -342.774988) (xy 128.404088 -342.797645) (xy 128.351759 -342.81301) (xy 128.297777 -342.820773)
			(xy 128.270508 -342.82126) (xy 127.406908 -342.82126) (xy 127.379636 -342.820801) (xy 127.325648 -342.81304)
			(xy 127.273315 -342.797674) (xy 127.2237 -342.775017) (xy 127.177815 -342.745529) (xy 127.136594 -342.709812)
			(xy 127.100875 -342.668591) (xy 127.071387 -342.622707) (xy 127.048729 -342.573093) (xy 127.033362 -342.520759)
			(xy 127.0256 -342.466772) (xy 125.542773 -342.466772) (xy 125.535013 -342.520746) (xy 125.519651 -342.573072)
			(xy 125.496998 -342.622678) (xy 125.467517 -342.668557) (xy 125.431807 -342.709773) (xy 125.390595 -342.745488)
			(xy 125.34472 -342.774975) (xy 125.295117 -342.797634) (xy 125.242793 -342.813003) (xy 125.188815 -342.82077)
			(xy 125.161548 -342.82126) (xy 124.297948 -342.82126) (xy 124.270675 -342.820804) (xy 124.216682 -342.813047)
			(xy 124.164344 -342.797685) (xy 124.114724 -342.77503) (xy 124.068834 -342.745544) (xy 124.027608 -342.709826)
			(xy 123.991885 -342.668604) (xy 123.962393 -342.622718) (xy 123.939732 -342.573101) (xy 123.924363 -342.520765)
			(xy 123.9166 -342.466773) (xy 122.433896 -342.466773) (xy 122.426134 -342.520759) (xy 122.410767 -342.573092)
			(xy 122.388109 -342.622706) (xy 122.35862 -342.66859) (xy 122.322902 -342.70981) (xy 122.28168 -342.745528)
			(xy 122.235796 -342.775015) (xy 122.186181 -342.797671) (xy 122.133847 -342.813037) (xy 122.079859 -342.820797)
			(xy 122.052588 -342.82126) (xy 121.188988 -342.82126) (xy 121.161719 -342.820777) (xy 121.107736 -342.813014)
			(xy 121.055408 -342.797647) (xy 121.005799 -342.77499) (xy 120.95992 -342.745504) (xy 120.918703 -342.709788)
			(xy 120.882989 -342.668571) (xy 120.853504 -342.62269) (xy 120.830849 -342.573081) (xy 120.815484 -342.520752)
			(xy 120.807722 -342.466769) (xy 119.324874 -342.466769) (xy 119.317113 -342.520749) (xy 119.301749 -342.573076)
			(xy 119.279095 -342.622684) (xy 119.249612 -342.668563) (xy 119.2139 -342.70978) (xy 119.172686 -342.745495)
			(xy 119.126809 -342.774981) (xy 119.077202 -342.797639) (xy 119.024876 -342.813007) (xy 118.970896 -342.820772)
			(xy 118.943628 -342.82126) (xy 118.080028 -342.82126) (xy 118.052756 -342.820802) (xy 117.998765 -342.813043)
			(xy 117.946429 -342.79768) (xy 117.896812 -342.775023) (xy 117.850925 -342.745536) (xy 117.809701 -342.709819)
			(xy 117.77398 -342.668598) (xy 117.74449 -342.622712) (xy 117.72183 -342.573097) (xy 117.706462 -342.520762)
			(xy 117.6987 -342.466772) (xy 116.215996 -342.466772) (xy 116.208233 -342.520762) (xy 116.192866 -342.573097)
			(xy 116.170206 -342.622712) (xy 116.140715 -342.668597) (xy 116.104995 -342.709817) (xy 116.063771 -342.745535)
			(xy 116.017884 -342.775021) (xy 115.968267 -342.797677) (xy 115.91593 -342.81304) (xy 115.86194 -342.820799)
			(xy 115.834668 -342.82126) (xy 114.971068 -342.82126) (xy 114.9438 -342.820775) (xy 114.88982 -342.81301)
			(xy 114.837494 -342.797642) (xy 114.787887 -342.774984) (xy 114.74201 -342.745497) (xy 114.700796 -342.709781)
			(xy 114.665084 -342.668564) (xy 114.635601 -342.622685) (xy 114.612947 -342.573076) (xy 114.597583 -342.520749)
			(xy 114.589822 -342.466768) (xy 113.106974 -342.466768) (xy 113.106974 -342.466769) (xy 113.099212 -342.520751)
			(xy 113.083847 -342.57308) (xy 113.061192 -342.622689) (xy 113.031707 -342.66857) (xy 112.995993 -342.709787)
			(xy 112.954776 -342.745502) (xy 112.908897 -342.774988) (xy 112.859288 -342.797645) (xy 112.806959 -342.81301)
			(xy 112.752977 -342.820773) (xy 112.725708 -342.82126) (xy 111.862108 -342.82126) (xy 111.834836 -342.820801)
			(xy 111.780848 -342.81304) (xy 111.728515 -342.797674) (xy 111.6789 -342.775017) (xy 111.633015 -342.745529)
			(xy 111.591794 -342.709812) (xy 111.556075 -342.668591) (xy 111.526587 -342.622707) (xy 111.503929 -342.573093)
			(xy 111.488562 -342.520759) (xy 111.4808 -342.466772) (xy 104.085479 -342.466772) (xy 104.10629 -342.517011)
			(xy 104.121803 -342.574906) (xy 104.129627 -342.634331) (xy 104.129627 -342.694269) (xy 104.121803 -342.753694)
			(xy 104.10629 -342.811589) (xy 104.083352 -342.866964) (xy 104.053383 -342.918871) (xy 104.016895 -342.966422)
			(xy 103.974512 -343.008804) (xy 103.926959 -343.045291) (xy 103.875051 -343.075259) (xy 103.819676 -343.098195)
			(xy 103.76178 -343.113706) (xy 103.702355 -343.121528) (xy 103.672386 -343.121996) (xy 102.808786 -343.121996)
			(xy 102.778818 -343.121529) (xy 102.719395 -343.113704) (xy 102.661502 -343.09819) (xy 102.60613 -343.075253)
			(xy 102.554224 -343.045284) (xy 102.506675 -343.008796) (xy 102.464294 -342.966415) (xy 102.427809 -342.918864)
			(xy 102.397841 -342.866958) (xy 102.374905 -342.811584) (xy 102.359393 -342.753691) (xy 102.35157 -342.694268)
			(xy 93.60914 -342.694268) (xy 93.595705 -342.709775) (xy 93.554492 -342.74549) (xy 93.508617 -342.774977)
			(xy 93.459012 -342.797635) (xy 93.406688 -342.813004) (xy 93.352709 -342.820771) (xy 93.325442 -342.82126)
			(xy 92.461842 -342.82126) (xy 92.434569 -342.820803) (xy 92.380577 -342.813046) (xy 92.328239 -342.797683)
			(xy 92.278621 -342.775028) (xy 92.232731 -342.745541) (xy 92.191506 -342.709824) (xy 92.155784 -342.668602)
			(xy 92.126292 -342.622716) (xy 92.103631 -342.5731) (xy 92.088263 -342.520764) (xy 92.0805 -342.466773)
			(xy 90.597796 -342.466773) (xy 90.590034 -342.52076) (xy 90.574667 -342.573094) (xy 90.552008 -342.622708)
			(xy 90.522519 -342.668592) (xy 90.4868 -342.709812) (xy 90.445578 -342.74553) (xy 90.399692 -342.775017)
			(xy 90.350077 -342.797673) (xy 90.297742 -342.813038) (xy 90.243754 -342.820798) (xy 90.216482 -342.82126)
			(xy 89.352882 -342.82126) (xy 89.325613 -342.820776) (xy 89.271631 -342.813013) (xy 89.219304 -342.797646)
			(xy 89.169696 -342.774988) (xy 89.123817 -342.745502) (xy 89.082601 -342.709786) (xy 89.046887 -342.668569)
			(xy 89.017403 -342.622689) (xy 88.994748 -342.573079) (xy 88.979384 -342.520751) (xy 88.971622 -342.466769)
			(xy 87.488774 -342.466769) (xy 87.481013 -342.52075) (xy 87.465648 -342.573077) (xy 87.442994 -342.622686)
			(xy 87.41351 -342.668565) (xy 87.377798 -342.709782) (xy 87.336583 -342.745497) (xy 87.290705 -342.774983)
			(xy 87.241098 -342.797641) (xy 87.188771 -342.813008) (xy 87.13479 -342.820772) (xy 87.107522 -342.82126)
			(xy 86.243922 -342.82126) (xy 86.21665 -342.820802) (xy 86.16266 -342.813042) (xy 86.110325 -342.797678)
			(xy 86.060709 -342.775021) (xy 86.014822 -342.745534) (xy 85.973599 -342.709817) (xy 85.937879 -342.668596)
			(xy 85.908389 -342.622711) (xy 85.88573 -342.573096) (xy 85.870362 -342.520761) (xy 85.8626 -342.466772)
			(xy 84.379896 -342.466772) (xy 84.379896 -342.466773) (xy 84.372133 -342.520763) (xy 84.356765 -342.573098)
			(xy 84.334105 -342.622713) (xy 84.304614 -342.668599) (xy 84.268893 -342.70982) (xy 84.227668 -342.745537)
			(xy 84.18178 -342.775023) (xy 84.132162 -342.797679) (xy 84.079825 -342.813041) (xy 84.025835 -342.820799)
			(xy 83.998562 -342.82126) (xy 83.134962 -342.82126) (xy 83.107694 -342.820775) (xy 83.053714 -342.813009)
			(xy 83.001389 -342.79764) (xy 82.951784 -342.774982) (xy 82.905907 -342.745495) (xy 82.864694 -342.709779)
			(xy 82.828983 -342.668562) (xy 82.7995 -342.622683) (xy 82.776847 -342.573075) (xy 82.761483 -342.520748)
			(xy 82.753722 -342.466768) (xy 81.270874 -342.466768) (xy 81.270874 -342.466769) (xy 81.263112 -342.520752)
			(xy 81.247747 -342.573081) (xy 81.225091 -342.622691) (xy 81.195605 -342.668572) (xy 81.159891 -342.709789)
			(xy 81.118673 -342.745504) (xy 81.072793 -342.77499) (xy 81.023183 -342.797646) (xy 80.970854 -342.813012)
			(xy 80.916871 -342.820773) (xy 80.889602 -342.82126) (xy 80.026002 -342.82126) (xy 79.998731 -342.820801)
			(xy 79.944743 -342.813039) (xy 79.89241 -342.797673) (xy 79.842797 -342.775015) (xy 79.796912 -342.745527)
			(xy 79.755692 -342.70981) (xy 79.719974 -342.668589) (xy 79.690486 -342.622705) (xy 79.667828 -342.573092)
			(xy 79.652462 -342.520759) (xy 79.644699 -342.466771) (xy 78.161873 -342.466771) (xy 78.154113 -342.520747)
			(xy 78.13875 -342.573073) (xy 78.116097 -342.62268) (xy 78.086615 -342.668559) (xy 78.050905 -342.709775)
			(xy 78.009692 -342.74549) (xy 77.963817 -342.774977) (xy 77.914212 -342.797635) (xy 77.861888 -342.813004)
			(xy 77.807909 -342.820771) (xy 77.780642 -342.82126) (xy 76.917042 -342.82126) (xy 76.889769 -342.820803)
			(xy 76.835777 -342.813046) (xy 76.783439 -342.797683) (xy 76.733821 -342.775028) (xy 76.687931 -342.745541)
			(xy 76.646706 -342.709824) (xy 76.610984 -342.668602) (xy 76.581492 -342.622716) (xy 76.558831 -342.5731)
			(xy 76.543463 -342.520764) (xy 76.5357 -342.466773) (xy 75.052996 -342.466773) (xy 75.045234 -342.52076)
			(xy 75.029867 -342.573094) (xy 75.007208 -342.622708) (xy 74.977719 -342.668592) (xy 74.942 -342.709812)
			(xy 74.900778 -342.74553) (xy 74.854892 -342.775017) (xy 74.805277 -342.797673) (xy 74.752942 -342.813038)
			(xy 74.698954 -342.820798) (xy 74.671682 -342.82126) (xy 73.808082 -342.82126) (xy 73.780813 -342.820776)
			(xy 73.726831 -342.813013) (xy 73.674504 -342.797646) (xy 73.624896 -342.774988) (xy 73.579017 -342.745502)
			(xy 73.537801 -342.709786) (xy 73.502087 -342.668569) (xy 73.472603 -342.622689) (xy 73.449948 -342.573079)
			(xy 73.434584 -342.520751) (xy 73.426822 -342.466769) (xy 71.943974 -342.466769) (xy 71.936213 -342.52075)
			(xy 71.920848 -342.573077) (xy 71.898194 -342.622686) (xy 71.86871 -342.668565) (xy 71.832998 -342.709782)
			(xy 71.791783 -342.745497) (xy 71.745905 -342.774983) (xy 71.696298 -342.797641) (xy 71.643971 -342.813008)
			(xy 71.58999 -342.820772) (xy 71.562722 -342.82126) (xy 70.699122 -342.82126) (xy 70.67185 -342.820802)
			(xy 70.61786 -342.813042) (xy 70.565525 -342.797678) (xy 70.515909 -342.775021) (xy 70.470022 -342.745534)
			(xy 70.428799 -342.709817) (xy 70.393079 -342.668596) (xy 70.363589 -342.622711) (xy 70.34093 -342.573096)
			(xy 70.325562 -342.520761) (xy 70.3178 -342.466772) (xy 68.835096 -342.466772) (xy 68.835096 -342.466773)
			(xy 68.827333 -342.520763) (xy 68.811965 -342.573098) (xy 68.789305 -342.622713) (xy 68.759814 -342.668599)
			(xy 68.724093 -342.70982) (xy 68.682868 -342.745537) (xy 68.63698 -342.775023) (xy 68.587362 -342.797679)
			(xy 68.535025 -342.813041) (xy 68.481035 -342.820799) (xy 68.453762 -342.82126) (xy 67.590162 -342.82126)
			(xy 67.562894 -342.820775) (xy 67.508914 -342.813009) (xy 67.456589 -342.79764) (xy 67.406984 -342.774982)
			(xy 67.361107 -342.745495) (xy 67.319894 -342.709779) (xy 67.284183 -342.668562) (xy 67.2547 -342.622683)
			(xy 67.232047 -342.573075) (xy 67.216683 -342.520748) (xy 67.208922 -342.466768) (xy 65.726074 -342.466768)
			(xy 65.726074 -342.466769) (xy 65.718312 -342.520752) (xy 65.702947 -342.573081) (xy 65.680291 -342.622691)
			(xy 65.650805 -342.668572) (xy 65.615091 -342.709789) (xy 65.573873 -342.745504) (xy 65.527993 -342.77499)
			(xy 65.478383 -342.797646) (xy 65.426054 -342.813012) (xy 65.372071 -342.820773) (xy 65.344802 -342.82126)
			(xy 64.481202 -342.82126) (xy 64.453931 -342.820801) (xy 64.399943 -342.813039) (xy 64.34761 -342.797673)
			(xy 64.297997 -342.775015) (xy 64.252112 -342.745527) (xy 64.210892 -342.70981) (xy 64.175174 -342.668589)
			(xy 64.145686 -342.622705) (xy 64.123028 -342.573092) (xy 64.107662 -342.520759) (xy 64.099899 -342.466771)
			(xy 62.617073 -342.466771) (xy 62.609313 -342.520747) (xy 62.59395 -342.573073) (xy 62.571297 -342.62268)
			(xy 62.541815 -342.668559) (xy 62.506105 -342.709775) (xy 62.464892 -342.74549) (xy 62.419017 -342.774977)
			(xy 62.369412 -342.797635) (xy 62.317088 -342.813004) (xy 62.263109 -342.820771) (xy 62.235842 -342.82126)
			(xy 61.372242 -342.82126) (xy 61.344969 -342.820803) (xy 61.290977 -342.813046) (xy 61.238639 -342.797683)
			(xy 61.189021 -342.775028) (xy 61.143131 -342.745541) (xy 61.101906 -342.709824) (xy 61.066184 -342.668602)
			(xy 61.036692 -342.622716) (xy 61.014031 -342.5731) (xy 60.998663 -342.520764) (xy 60.9909 -342.466773)
			(xy 51.666873 -342.466773) (xy 51.659113 -342.520746) (xy 51.643751 -342.573072) (xy 51.621098 -342.622678)
			(xy 51.591617 -342.668557) (xy 51.555907 -342.709773) (xy 51.514695 -342.745488) (xy 51.46882 -342.774975)
			(xy 51.419217 -342.797634) (xy 51.366893 -342.813003) (xy 51.312915 -342.82077) (xy 51.285648 -342.82126)
			(xy 50.422048 -342.82126) (xy 50.394775 -342.820804) (xy 50.340782 -342.813047) (xy 50.288444 -342.797685)
			(xy 50.238824 -342.77503) (xy 50.192934 -342.745544) (xy 50.151708 -342.709826) (xy 50.115985 -342.668604)
			(xy 50.086493 -342.622718) (xy 50.063832 -342.573101) (xy 50.048463 -342.520765) (xy 50.0407 -342.466773)
			(xy 48.557996 -342.466773) (xy 48.550234 -342.520759) (xy 48.534867 -342.573092) (xy 48.512209 -342.622706)
			(xy 48.48272 -342.66859) (xy 48.447002 -342.70981) (xy 48.40578 -342.745528) (xy 48.359896 -342.775015)
			(xy 48.310281 -342.797671) (xy 48.257947 -342.813037) (xy 48.203959 -342.820797) (xy 48.176688 -342.82126)
			(xy 47.313088 -342.82126) (xy 47.285819 -342.820777) (xy 47.231836 -342.813014) (xy 47.179508 -342.797647)
			(xy 47.129899 -342.77499) (xy 47.08402 -342.745504) (xy 47.042803 -342.709788) (xy 47.007089 -342.668571)
			(xy 46.977604 -342.62269) (xy 46.954949 -342.573081) (xy 46.939584 -342.520752) (xy 46.931822 -342.466769)
			(xy 45.448974 -342.466769) (xy 45.441213 -342.520749) (xy 45.425849 -342.573076) (xy 45.403195 -342.622684)
			(xy 45.373712 -342.668563) (xy 45.338 -342.70978) (xy 45.296786 -342.745495) (xy 45.250909 -342.774981)
			(xy 45.201302 -342.797639) (xy 45.148976 -342.813007) (xy 45.094996 -342.820772) (xy 45.067728 -342.82126)
			(xy 44.204128 -342.82126) (xy 44.176856 -342.820802) (xy 44.122865 -342.813043) (xy 44.070529 -342.79768)
			(xy 44.020912 -342.775023) (xy 43.975025 -342.745536) (xy 43.933801 -342.709819) (xy 43.89808 -342.668598)
			(xy 43.86859 -342.622712) (xy 43.84593 -342.573097) (xy 43.830562 -342.520762) (xy 43.8228 -342.466772)
			(xy 42.340096 -342.466772) (xy 42.332333 -342.520762) (xy 42.316966 -342.573097) (xy 42.294306 -342.622712)
			(xy 42.264815 -342.668597) (xy 42.229095 -342.709817) (xy 42.187871 -342.745535) (xy 42.141984 -342.775021)
			(xy 42.092367 -342.797677) (xy 42.04003 -342.81304) (xy 41.98604 -342.820799) (xy 41.958768 -342.82126)
			(xy 41.095168 -342.82126) (xy 41.0679 -342.820775) (xy 41.01392 -342.81301) (xy 40.961594 -342.797642)
			(xy 40.911987 -342.774984) (xy 40.86611 -342.745497) (xy 40.824896 -342.709781) (xy 40.789184 -342.668564)
			(xy 40.759701 -342.622685) (xy 40.737047 -342.573076) (xy 40.721683 -342.520749) (xy 40.713922 -342.466768)
			(xy 39.231074 -342.466768) (xy 39.231074 -342.466769) (xy 39.223312 -342.520751) (xy 39.207947 -342.57308)
			(xy 39.185292 -342.622689) (xy 39.155807 -342.66857) (xy 39.120093 -342.709787) (xy 39.078876 -342.745502)
			(xy 39.032997 -342.774988) (xy 38.983388 -342.797645) (xy 38.931059 -342.81301) (xy 38.877077 -342.820773)
			(xy 38.849808 -342.82126) (xy 37.986208 -342.82126) (xy 37.958936 -342.820801) (xy 37.904948 -342.81304)
			(xy 37.852615 -342.797674) (xy 37.803 -342.775017) (xy 37.757115 -342.745529) (xy 37.715894 -342.709812)
			(xy 37.680175 -342.668591) (xy 37.650687 -342.622707) (xy 37.628029 -342.573093) (xy 37.612662 -342.520759)
			(xy 37.6049 -342.466772) (xy 36.122073 -342.466772) (xy 36.114313 -342.520746) (xy 36.098951 -342.573072)
			(xy 36.076298 -342.622678) (xy 36.046817 -342.668557) (xy 36.011107 -342.709773) (xy 35.969895 -342.745488)
			(xy 35.92402 -342.774975) (xy 35.874417 -342.797634) (xy 35.822093 -342.813003) (xy 35.768115 -342.82077)
			(xy 35.740848 -342.82126) (xy 34.877248 -342.82126) (xy 34.849975 -342.820804) (xy 34.795982 -342.813047)
			(xy 34.743644 -342.797685) (xy 34.694024 -342.77503) (xy 34.648134 -342.745544) (xy 34.606908 -342.709826)
			(xy 34.571185 -342.668604) (xy 34.541693 -342.622718) (xy 34.519032 -342.573101) (xy 34.503663 -342.520765)
			(xy 34.4959 -342.466773) (xy 33.013196 -342.466773) (xy 33.005434 -342.520759) (xy 32.990067 -342.573092)
			(xy 32.967409 -342.622706) (xy 32.93792 -342.66859) (xy 32.902202 -342.70981) (xy 32.86098 -342.745528)
			(xy 32.815096 -342.775015) (xy 32.765481 -342.797671) (xy 32.713147 -342.813037) (xy 32.659159 -342.820797)
			(xy 32.631888 -342.82126) (xy 31.768288 -342.82126) (xy 31.741019 -342.820777) (xy 31.687036 -342.813014)
			(xy 31.634708 -342.797647) (xy 31.585099 -342.77499) (xy 31.53922 -342.745504) (xy 31.498003 -342.709788)
			(xy 31.462289 -342.668571) (xy 31.432804 -342.62269) (xy 31.410149 -342.573081) (xy 31.394784 -342.520752)
			(xy 31.387022 -342.466769) (xy 29.904174 -342.466769) (xy 29.896413 -342.520749) (xy 29.881049 -342.573076)
			(xy 29.858395 -342.622684) (xy 29.828912 -342.668563) (xy 29.7932 -342.70978) (xy 29.751986 -342.745495)
			(xy 29.706109 -342.774981) (xy 29.656502 -342.797639) (xy 29.604176 -342.813007) (xy 29.550196 -342.820772)
			(xy 29.522928 -342.82126) (xy 28.659328 -342.82126) (xy 28.632056 -342.820802) (xy 28.578065 -342.813043)
			(xy 28.525729 -342.79768) (xy 28.476112 -342.775023) (xy 28.430225 -342.745536) (xy 28.389001 -342.709819)
			(xy 28.35328 -342.668598) (xy 28.32379 -342.622712) (xy 28.30113 -342.573097) (xy 28.285762 -342.520762)
			(xy 28.278 -342.466772) (xy 26.795296 -342.466772) (xy 26.787533 -342.520762) (xy 26.772166 -342.573097)
			(xy 26.749506 -342.622712) (xy 26.720015 -342.668597) (xy 26.684295 -342.709817) (xy 26.643071 -342.745535)
			(xy 26.597184 -342.775021) (xy 26.547567 -342.797677) (xy 26.49523 -342.81304) (xy 26.44124 -342.820799)
			(xy 26.413968 -342.82126) (xy 25.550368 -342.82126) (xy 25.5231 -342.820775) (xy 25.46912 -342.81301)
			(xy 25.416794 -342.797642) (xy 25.367187 -342.774984) (xy 25.32131 -342.745497) (xy 25.280096 -342.709781)
			(xy 25.244384 -342.668564) (xy 25.214901 -342.622685) (xy 25.192247 -342.573076) (xy 25.176883 -342.520749)
			(xy 25.169122 -342.466768) (xy 23.686274 -342.466768) (xy 23.686274 -342.466769) (xy 23.678512 -342.520751)
			(xy 23.663147 -342.57308) (xy 23.640492 -342.622689) (xy 23.611007 -342.66857) (xy 23.575293 -342.709787)
			(xy 23.534076 -342.745502) (xy 23.488197 -342.774988) (xy 23.438588 -342.797645) (xy 23.386259 -342.81301)
			(xy 23.332277 -342.820773) (xy 23.305008 -342.82126) (xy 22.441408 -342.82126) (xy 22.414136 -342.820801)
			(xy 22.360148 -342.81304) (xy 22.307815 -342.797674) (xy 22.2582 -342.775017) (xy 22.212315 -342.745529)
			(xy 22.171094 -342.709812) (xy 22.135375 -342.668591) (xy 22.105887 -342.622707) (xy 22.083229 -342.573093)
			(xy 22.067862 -342.520759) (xy 22.0601 -342.466772) (xy 20.577347 -342.466772) (xy 20.569584 -342.520758)
			(xy 20.554218 -342.57309) (xy 20.53156 -342.622703) (xy 20.502073 -342.668587) (xy 20.466355 -342.709807)
			(xy 20.425135 -342.745524) (xy 20.379252 -342.775011) (xy 20.329638 -342.797669) (xy 20.277306 -342.813035)
			(xy 20.223319 -342.820797) (xy 20.196048 -342.82126) (xy 19.332448 -342.82126) (xy 19.305179 -342.820777)
			(xy 19.251195 -342.813015) (xy 19.198865 -342.79765) (xy 19.149255 -342.774993) (xy 19.103374 -342.745507)
			(xy 19.062157 -342.709792) (xy 19.026441 -342.668574) (xy 18.996956 -342.622693) (xy 18.974299 -342.573083)
			(xy 18.958934 -342.520753) (xy 18.951172 -342.466769) (xy 0.509016 -342.466769) (xy 0.509016 -345.49242)
			(xy 18.95117 -345.49242) (xy 18.95117 -345.43788) (xy 18.958932 -345.383896) (xy 18.974298 -345.331567)
			(xy 18.996954 -345.281956) (xy 19.02644 -345.236075) (xy 19.062155 -345.194857) (xy 19.103373 -345.159141)
			(xy 19.149254 -345.129655) (xy 19.198865 -345.106998) (xy 19.251194 -345.091633) (xy 19.305178 -345.083871)
			(xy 19.332448 -345.083384) (xy 20.196048 -345.083384) (xy 20.223319 -345.083855) (xy 20.277305 -345.091617)
			(xy 20.329638 -345.106983) (xy 20.379251 -345.12964) (xy 20.425134 -345.159128) (xy 20.466354 -345.194845)
			(xy 20.502071 -345.236064) (xy 20.531559 -345.281948) (xy 20.554216 -345.33156) (xy 20.569582 -345.383893)
			(xy 20.577345 -345.437879) (xy 20.577345 -345.49242) (xy 22.06013 -345.49242) (xy 22.06013 -345.43788)
			(xy 22.067892 -345.383896) (xy 22.083258 -345.331567) (xy 22.105914 -345.281956) (xy 22.1354 -345.236075)
			(xy 22.171115 -345.194857) (xy 22.212333 -345.159141) (xy 22.258214 -345.129655) (xy 22.307825 -345.106998)
			(xy 22.360154 -345.091633) (xy 22.414138 -345.083871) (xy 22.441408 -345.083384) (xy 23.305008 -345.083384)
			(xy 23.332279 -345.083855) (xy 23.386265 -345.091617) (xy 23.438598 -345.106983) (xy 23.488211 -345.12964)
			(xy 23.534094 -345.159128) (xy 23.575314 -345.194845) (xy 23.611031 -345.236064) (xy 23.640519 -345.281948)
			(xy 23.663176 -345.33156) (xy 23.678542 -345.383893) (xy 23.686305 -345.437879) (xy 23.686305 -345.492365)
			(xy 25.16917 -345.492365) (xy 25.16917 -345.437835) (xy 25.17693 -345.383861) (xy 25.192292 -345.33154)
			(xy 25.214943 -345.281938) (xy 25.244422 -345.236064) (xy 25.28013 -345.194853) (xy 25.321339 -345.159142)
			(xy 25.36721 -345.129658) (xy 25.41681 -345.107003) (xy 25.46913 -345.091637) (xy 25.523103 -345.083872)
			(xy 25.550368 -345.083384) (xy 26.413968 -345.083384) (xy 26.441244 -345.083753) (xy 26.495241 -345.091513)
			(xy 26.547583 -345.106878) (xy 26.597207 -345.129537) (xy 26.6431 -345.159027) (xy 26.684329 -345.194749)
			(xy 26.720054 -345.235975) (xy 26.749548 -345.281865) (xy 26.772211 -345.331487) (xy 26.78758 -345.383828)
			(xy 26.795344 -345.437824) (xy 26.795344 -345.492369) (xy 28.278047 -345.492369) (xy 28.278047 -345.437831)
			(xy 28.285809 -345.383848) (xy 28.301175 -345.33152) (xy 28.323832 -345.281911) (xy 28.353319 -345.236031)
			(xy 28.389035 -345.194815) (xy 28.430253 -345.159102) (xy 28.476135 -345.129619) (xy 28.525746 -345.106965)
			(xy 28.578076 -345.091603) (xy 28.632059 -345.083845) (xy 28.659328 -345.083384) (xy 29.522928 -345.083384)
			(xy 29.550199 -345.08378) (xy 29.604186 -345.091546) (xy 29.656519 -345.106916) (xy 29.706132 -345.129576)
			(xy 29.752014 -345.159067) (xy 29.793234 -345.194786) (xy 29.82895 -345.236008) (xy 29.858437 -345.281893)
			(xy 29.881094 -345.331507) (xy 29.89646 -345.383841) (xy 29.904222 -345.437829) (xy 29.904222 -345.492366)
			(xy 31.38707 -345.492366) (xy 31.38707 -345.437834) (xy 31.394831 -345.383858) (xy 31.410194 -345.331536)
			(xy 31.432846 -345.281933) (xy 31.462327 -345.236058) (xy 31.498037 -345.194846) (xy 31.539248 -345.159135)
			(xy 31.585122 -345.129652) (xy 31.634725 -345.106998) (xy 31.687047 -345.091633) (xy 31.741022 -345.083871)
			(xy 31.768288 -345.083384) (xy 32.631888 -345.083384) (xy 32.659163 -345.083755) (xy 32.713157 -345.091516)
			(xy 32.765498 -345.106884) (xy 32.815119 -345.129543) (xy 32.861009 -345.159034) (xy 32.902236 -345.194756)
			(xy 32.937959 -345.235981) (xy 32.967451 -345.281871) (xy 32.990112 -345.331491) (xy 33.005481 -345.383831)
			(xy 33.013244 -345.437825) (xy 33.013244 -345.49237) (xy 34.495948 -345.49237) (xy 34.495948 -345.43783)
			(xy 34.50371 -345.383846) (xy 34.519077 -345.331515) (xy 34.541735 -345.281905) (xy 34.571224 -345.236024)
			(xy 34.606942 -345.194808) (xy 34.648163 -345.159095) (xy 34.694047 -345.129612) (xy 34.74366 -345.10696)
			(xy 34.795992 -345.0916) (xy 34.849978 -345.083844) (xy 34.877248 -345.083384) (xy 35.740848 -345.083384)
			(xy 35.768118 -345.083782) (xy 35.822103 -345.09155) (xy 35.874433 -345.106921) (xy 35.924044 -345.129583)
			(xy 35.969924 -345.159074) (xy 36.011141 -345.194793) (xy 36.046855 -345.236015) (xy 36.07634 -345.281899)
			(xy 36.098995 -345.331512) (xy 36.11436 -345.383844) (xy 36.122122 -345.43783) (xy 36.122122 -345.492368)
			(xy 37.604947 -345.492368) (xy 37.604947 -345.437832) (xy 37.612709 -345.383851) (xy 37.628074 -345.331524)
			(xy 37.650729 -345.281916) (xy 37.680214 -345.236038) (xy 37.715928 -345.194822) (xy 37.757144 -345.159109)
			(xy 37.803023 -345.129625) (xy 37.852631 -345.106971) (xy 37.904959 -345.091607) (xy 37.95894 -345.083847)
			(xy 37.986208 -345.083384) (xy 38.849808 -345.083384) (xy 38.87708 -345.083779) (xy 38.93107 -345.091543)
			(xy 38.983404 -345.106911) (xy 39.03302 -345.12957) (xy 39.078905 -345.15906) (xy 39.120127 -345.194779)
			(xy 39.155845 -345.236001) (xy 39.185334 -345.281888) (xy 39.207992 -345.331503) (xy 39.223359 -345.383838)
			(xy 39.231121 -345.437828) (xy 39.231121 -345.492365) (xy 40.71397 -345.492365) (xy 40.71397 -345.437835)
			(xy 40.72173 -345.383861) (xy 40.737092 -345.33154) (xy 40.759743 -345.281938) (xy 40.789222 -345.236064)
			(xy 40.82493 -345.194853) (xy 40.866139 -345.159142) (xy 40.91201 -345.129658) (xy 40.96161 -345.107003)
			(xy 41.01393 -345.091637) (xy 41.067903 -345.083872) (xy 41.095168 -345.083384) (xy 41.958768 -345.083384)
			(xy 41.986044 -345.083753) (xy 42.040041 -345.091513) (xy 42.092383 -345.106878) (xy 42.142007 -345.129537)
			(xy 42.1879 -345.159027) (xy 42.229129 -345.194749) (xy 42.264854 -345.235975) (xy 42.294348 -345.281865)
			(xy 42.317011 -345.331487) (xy 42.33238 -345.383828) (xy 42.340144 -345.437824) (xy 42.340144 -345.492369)
			(xy 43.822847 -345.492369) (xy 43.822847 -345.437831) (xy 43.830609 -345.383848) (xy 43.845975 -345.33152)
			(xy 43.868632 -345.281911) (xy 43.898119 -345.236031) (xy 43.933835 -345.194815) (xy 43.975053 -345.159102)
			(xy 44.020935 -345.129619) (xy 44.070546 -345.106965) (xy 44.122876 -345.091603) (xy 44.176859 -345.083845)
			(xy 44.204128 -345.083384) (xy 45.067728 -345.083384) (xy 45.094999 -345.08378) (xy 45.148986 -345.091546)
			(xy 45.201319 -345.106916) (xy 45.250932 -345.129576) (xy 45.296814 -345.159067) (xy 45.338034 -345.194786)
			(xy 45.37375 -345.236008) (xy 45.403237 -345.281893) (xy 45.425894 -345.331507) (xy 45.44126 -345.383841)
			(xy 45.449022 -345.437829) (xy 45.449022 -345.492366) (xy 46.93187 -345.492366) (xy 46.93187 -345.437834)
			(xy 46.939631 -345.383858) (xy 46.954994 -345.331536) (xy 46.977646 -345.281933) (xy 47.007127 -345.236058)
			(xy 47.042837 -345.194846) (xy 47.084048 -345.159135) (xy 47.129922 -345.129652) (xy 47.179525 -345.106998)
			(xy 47.231847 -345.091633) (xy 47.285822 -345.083871) (xy 47.313088 -345.083384) (xy 48.176688 -345.083384)
			(xy 48.203963 -345.083755) (xy 48.257957 -345.091516) (xy 48.310298 -345.106884) (xy 48.359919 -345.129543)
			(xy 48.405809 -345.159034) (xy 48.447036 -345.194756) (xy 48.482759 -345.235981) (xy 48.512251 -345.281871)
			(xy 48.534912 -345.331491) (xy 48.550281 -345.383831) (xy 48.558044 -345.437825) (xy 48.558044 -345.49237)
			(xy 50.040748 -345.49237) (xy 50.040748 -345.43783) (xy 50.04851 -345.383846) (xy 50.063877 -345.331515)
			(xy 50.086535 -345.281905) (xy 50.116024 -345.236024) (xy 50.151742 -345.194808) (xy 50.192963 -345.159095)
			(xy 50.238847 -345.129612) (xy 50.28846 -345.10696) (xy 50.340792 -345.0916) (xy 50.394778 -345.083844)
			(xy 50.422048 -345.083384) (xy 51.285648 -345.083384) (xy 51.312918 -345.083782) (xy 51.366903 -345.09155)
			(xy 51.419233 -345.106921) (xy 51.468844 -345.129583) (xy 51.514724 -345.159074) (xy 51.555941 -345.194793)
			(xy 51.591655 -345.236015) (xy 51.62114 -345.281899) (xy 51.643795 -345.331512) (xy 51.65916 -345.383844)
			(xy 51.666922 -345.43783) (xy 51.666922 -345.49237) (xy 60.990948 -345.49237) (xy 60.990948 -345.43783)
			(xy 60.99871 -345.383846) (xy 61.014076 -345.331517) (xy 61.036734 -345.281907) (xy 61.066222 -345.236026)
			(xy 61.10194 -345.19481) (xy 61.14316 -345.159097) (xy 61.189044 -345.129614) (xy 61.238656 -345.106962)
			(xy 61.290987 -345.091601) (xy 61.344972 -345.083845) (xy 61.372242 -345.083384) (xy 62.235842 -345.083384)
			(xy 62.263113 -345.083781) (xy 62.317098 -345.091549) (xy 62.369429 -345.10692) (xy 62.41904 -345.129581)
			(xy 62.464921 -345.159072) (xy 62.506139 -345.194791) (xy 62.541854 -345.236013) (xy 62.571339 -345.281897)
			(xy 62.593995 -345.33151) (xy 62.60936 -345.383843) (xy 62.617122 -345.437829) (xy 62.617122 -345.492368)
			(xy 64.099947 -345.492368) (xy 64.099947 -345.437832) (xy 64.107709 -345.383852) (xy 64.123073 -345.331525)
			(xy 64.145728 -345.281918) (xy 64.175212 -345.23604) (xy 64.210926 -345.194824) (xy 64.252141 -345.159111)
			(xy 64.29802 -345.129627) (xy 64.347627 -345.106972) (xy 64.399954 -345.091608) (xy 64.453934 -345.083847)
			(xy 64.481202 -345.083384) (xy 65.344802 -345.083384) (xy 65.372075 -345.083779) (xy 65.426064 -345.091542)
			(xy 65.4784 -345.106909) (xy 65.528016 -345.129568) (xy 65.573902 -345.159057) (xy 65.615124 -345.194777)
			(xy 65.650844 -345.236) (xy 65.680333 -345.281886) (xy 65.702992 -345.331502) (xy 65.718359 -345.383838)
			(xy 65.726121 -345.437827) (xy 65.726121 -345.492364) (xy 67.20897 -345.492364) (xy 67.20897 -345.437836)
			(xy 67.21673 -345.383862) (xy 67.232092 -345.331542) (xy 67.254742 -345.28194) (xy 67.284221 -345.236066)
			(xy 67.319928 -345.194855) (xy 67.361136 -345.159144) (xy 67.407007 -345.12966) (xy 67.456606 -345.107005)
			(xy 67.508925 -345.091638) (xy 67.562898 -345.083873) (xy 67.590162 -345.083384) (xy 68.453762 -345.083384)
			(xy 68.481038 -345.083753) (xy 68.535036 -345.091512) (xy 68.587379 -345.106877) (xy 68.637003 -345.129535)
			(xy 68.682897 -345.159025) (xy 68.724127 -345.194747) (xy 68.759852 -345.235973) (xy 68.789347 -345.281864)
			(xy 68.81201 -345.331485) (xy 68.82738 -345.383827) (xy 68.835144 -345.437824) (xy 68.835144 -345.492369)
			(xy 70.317847 -345.492369) (xy 70.317847 -345.437831) (xy 70.325609 -345.383849) (xy 70.340975 -345.331521)
			(xy 70.363631 -345.281912) (xy 70.393117 -345.236033) (xy 70.428833 -345.194817) (xy 70.470051 -345.159104)
			(xy 70.515932 -345.129621) (xy 70.565541 -345.106967) (xy 70.617871 -345.091605) (xy 70.671853 -345.083846)
			(xy 70.699122 -345.083384) (xy 71.562722 -345.083384) (xy 71.589994 -345.08378) (xy 71.643981 -345.091545)
			(xy 71.696315 -345.106914) (xy 71.745928 -345.129574) (xy 71.791812 -345.159064) (xy 71.833032 -345.194784)
			(xy 71.868749 -345.236006) (xy 71.898236 -345.281891) (xy 71.920893 -345.331506) (xy 71.936259 -345.38384)
			(xy 71.944022 -345.437828) (xy 71.944022 -345.492365) (xy 73.42687 -345.492365) (xy 73.42687 -345.437835)
			(xy 73.434631 -345.383859) (xy 73.449993 -345.331537) (xy 73.472645 -345.281934) (xy 73.502126 -345.23606)
			(xy 73.537835 -345.194848) (xy 73.579045 -345.159137) (xy 73.624919 -345.129654) (xy 73.674521 -345.106999)
			(xy 73.726842 -345.091634) (xy 73.780817 -345.083872) (xy 73.808082 -345.083384) (xy 74.671682 -345.083384)
			(xy 74.698957 -345.083754) (xy 74.752952 -345.091515) (xy 74.805294 -345.106882) (xy 74.854915 -345.129541)
			(xy 74.900806 -345.159032) (xy 74.942034 -345.194754) (xy 74.977757 -345.235979) (xy 75.00725 -345.281869)
			(xy 75.029912 -345.33149) (xy 75.045281 -345.38383) (xy 75.053044 -345.437825) (xy 75.053044 -345.49237)
			(xy 76.535748 -345.49237) (xy 76.535748 -345.43783) (xy 76.54351 -345.383846) (xy 76.558876 -345.331517)
			(xy 76.581534 -345.281907) (xy 76.611022 -345.236026) (xy 76.64674 -345.19481) (xy 76.68796 -345.159097)
			(xy 76.733844 -345.129614) (xy 76.783456 -345.106962) (xy 76.835787 -345.091601) (xy 76.889772 -345.083845)
			(xy 76.917042 -345.083384) (xy 77.780642 -345.083384) (xy 77.807913 -345.083781) (xy 77.861898 -345.091549)
			(xy 77.914229 -345.10692) (xy 77.96384 -345.129581) (xy 78.009721 -345.159072) (xy 78.050939 -345.194791)
			(xy 78.086654 -345.236013) (xy 78.116139 -345.281897) (xy 78.138795 -345.33151) (xy 78.15416 -345.383843)
			(xy 78.161922 -345.437829) (xy 78.161922 -345.492368) (xy 79.644747 -345.492368) (xy 79.644747 -345.437832)
			(xy 79.652509 -345.383852) (xy 79.667873 -345.331525) (xy 79.690528 -345.281918) (xy 79.720012 -345.23604)
			(xy 79.755726 -345.194824) (xy 79.796941 -345.159111) (xy 79.84282 -345.129627) (xy 79.892427 -345.106972)
			(xy 79.944754 -345.091608) (xy 79.998734 -345.083847) (xy 80.026002 -345.083384) (xy 80.889602 -345.083384)
			(xy 80.916875 -345.083779) (xy 80.970864 -345.091542) (xy 81.0232 -345.106909) (xy 81.072816 -345.129568)
			(xy 81.118702 -345.159057) (xy 81.159924 -345.194777) (xy 81.195644 -345.236) (xy 81.225133 -345.281886)
			(xy 81.247792 -345.331502) (xy 81.263159 -345.383838) (xy 81.270921 -345.437827) (xy 81.270921 -345.492364)
			(xy 82.75377 -345.492364) (xy 82.75377 -345.437836) (xy 82.76153 -345.383862) (xy 82.776892 -345.331542)
			(xy 82.799542 -345.28194) (xy 82.829021 -345.236066) (xy 82.864728 -345.194855) (xy 82.905936 -345.159144)
			(xy 82.951807 -345.12966) (xy 83.001406 -345.107005) (xy 83.053725 -345.091638) (xy 83.107698 -345.083873)
			(xy 83.134962 -345.083384) (xy 83.998562 -345.083384) (xy 84.025838 -345.083753) (xy 84.079836 -345.091512)
			(xy 84.132179 -345.106877) (xy 84.181803 -345.129535) (xy 84.227697 -345.159025) (xy 84.268927 -345.194747)
			(xy 84.304652 -345.235973) (xy 84.334147 -345.281864) (xy 84.35681 -345.331485) (xy 84.37218 -345.383827)
			(xy 84.379944 -345.437824) (xy 84.379944 -345.492369) (xy 85.862647 -345.492369) (xy 85.862647 -345.437831)
			(xy 85.870409 -345.383849) (xy 85.885775 -345.331521) (xy 85.908431 -345.281912) (xy 85.937917 -345.236033)
			(xy 85.973633 -345.194817) (xy 86.014851 -345.159104) (xy 86.060732 -345.129621) (xy 86.110341 -345.106967)
			(xy 86.162671 -345.091605) (xy 86.216653 -345.083846) (xy 86.243922 -345.083384) (xy 87.107522 -345.083384)
			(xy 87.134794 -345.08378) (xy 87.188781 -345.091545) (xy 87.241115 -345.106914) (xy 87.290728 -345.129574)
			(xy 87.336612 -345.159064) (xy 87.377832 -345.194784) (xy 87.413549 -345.236006) (xy 87.443036 -345.281891)
			(xy 87.465693 -345.331506) (xy 87.481059 -345.38384) (xy 87.488822 -345.437828) (xy 87.488822 -345.492365)
			(xy 88.97167 -345.492365) (xy 88.97167 -345.437835) (xy 88.979431 -345.383859) (xy 88.994793 -345.331537)
			(xy 89.017445 -345.281934) (xy 89.046926 -345.23606) (xy 89.082635 -345.194848) (xy 89.123845 -345.159137)
			(xy 89.169719 -345.129654) (xy 89.219321 -345.106999) (xy 89.271642 -345.091634) (xy 89.325617 -345.083872)
			(xy 89.352882 -345.083384) (xy 90.216482 -345.083384) (xy 90.243757 -345.083754) (xy 90.297752 -345.091515)
			(xy 90.350094 -345.106882) (xy 90.399715 -345.129541) (xy 90.445606 -345.159032) (xy 90.486834 -345.194754)
			(xy 90.522557 -345.235979) (xy 90.55205 -345.281869) (xy 90.574712 -345.33149) (xy 90.590081 -345.38383)
			(xy 90.597844 -345.437825) (xy 90.597844 -345.49237) (xy 92.080548 -345.49237) (xy 92.080548 -345.43783)
			(xy 92.08831 -345.383846) (xy 92.103676 -345.331517) (xy 92.126334 -345.281907) (xy 92.155822 -345.236026)
			(xy 92.19154 -345.19481) (xy 92.23276 -345.159097) (xy 92.278644 -345.129614) (xy 92.328256 -345.106962)
			(xy 92.380587 -345.091601) (xy 92.434572 -345.083845) (xy 92.461842 -345.083384) (xy 93.325442 -345.083384)
			(xy 93.352713 -345.083781) (xy 93.406698 -345.091549) (xy 93.459029 -345.10692) (xy 93.50864 -345.129581)
			(xy 93.554521 -345.159072) (xy 93.595739 -345.194791) (xy 93.631454 -345.236013) (xy 93.660939 -345.281897)
			(xy 93.683595 -345.33151) (xy 93.69896 -345.383843) (xy 93.706722 -345.437829) (xy 93.706722 -345.492368)
			(xy 111.480847 -345.492368) (xy 111.480847 -345.437832) (xy 111.488609 -345.383851) (xy 111.503974 -345.331524)
			(xy 111.526629 -345.281916) (xy 111.556114 -345.236038) (xy 111.591828 -345.194822) (xy 111.633044 -345.159109)
			(xy 111.678923 -345.129625) (xy 111.728531 -345.106971) (xy 111.780859 -345.091607) (xy 111.83484 -345.083847)
			(xy 111.862108 -345.083384) (xy 112.725708 -345.083384) (xy 112.75298 -345.083779) (xy 112.80697 -345.091543)
			(xy 112.859304 -345.106911) (xy 112.90892 -345.12957) (xy 112.954805 -345.15906) (xy 112.996027 -345.194779)
			(xy 113.031745 -345.236001) (xy 113.061234 -345.281888) (xy 113.083892 -345.331503) (xy 113.099259 -345.383838)
			(xy 113.107021 -345.437828) (xy 113.107021 -345.492365) (xy 114.58987 -345.492365) (xy 114.58987 -345.437835)
			(xy 114.59763 -345.383861) (xy 114.612992 -345.33154) (xy 114.635643 -345.281938) (xy 114.665122 -345.236064)
			(xy 114.70083 -345.194853) (xy 114.742039 -345.159142) (xy 114.78791 -345.129658) (xy 114.83751 -345.107003)
			(xy 114.88983 -345.091637) (xy 114.943803 -345.083872) (xy 114.971068 -345.083384) (xy 115.834668 -345.083384)
			(xy 115.861944 -345.083753) (xy 115.915941 -345.091513) (xy 115.968283 -345.106878) (xy 116.017907 -345.129537)
			(xy 116.0638 -345.159027) (xy 116.105029 -345.194749) (xy 116.140754 -345.235975) (xy 116.170248 -345.281865)
			(xy 116.192911 -345.331487) (xy 116.20828 -345.383828) (xy 116.216044 -345.437824) (xy 116.216044 -345.492369)
			(xy 117.698747 -345.492369) (xy 117.698747 -345.437831) (xy 117.706509 -345.383848) (xy 117.721875 -345.33152)
			(xy 117.744532 -345.281911) (xy 117.774019 -345.236031) (xy 117.809735 -345.194815) (xy 117.850953 -345.159102)
			(xy 117.896835 -345.129619) (xy 117.946446 -345.106965) (xy 117.998776 -345.091603) (xy 118.052759 -345.083845)
			(xy 118.080028 -345.083384) (xy 118.943628 -345.083384) (xy 118.970899 -345.08378) (xy 119.024886 -345.091546)
			(xy 119.077219 -345.106916) (xy 119.126832 -345.129576) (xy 119.172714 -345.159067) (xy 119.213934 -345.194786)
			(xy 119.24965 -345.236008) (xy 119.279137 -345.281893) (xy 119.301794 -345.331507) (xy 119.31716 -345.383841)
			(xy 119.324922 -345.437829) (xy 119.324922 -345.492366) (xy 120.80777 -345.492366) (xy 120.80777 -345.437834)
			(xy 120.815531 -345.383858) (xy 120.830894 -345.331536) (xy 120.853546 -345.281933) (xy 120.883027 -345.236058)
			(xy 120.918737 -345.194846) (xy 120.959948 -345.159135) (xy 121.005822 -345.129652) (xy 121.055425 -345.106998)
			(xy 121.107747 -345.091633) (xy 121.161722 -345.083871) (xy 121.188988 -345.083384) (xy 122.052588 -345.083384)
			(xy 122.079863 -345.083755) (xy 122.133857 -345.091516) (xy 122.186198 -345.106884) (xy 122.235819 -345.129543)
			(xy 122.281709 -345.159034) (xy 122.322936 -345.194756) (xy 122.358659 -345.235981) (xy 122.388151 -345.281871)
			(xy 122.410812 -345.331491) (xy 122.426181 -345.383831) (xy 122.433944 -345.437825) (xy 122.433944 -345.49237)
			(xy 123.916648 -345.49237) (xy 123.916648 -345.43783) (xy 123.92441 -345.383846) (xy 123.939777 -345.331515)
			(xy 123.962435 -345.281905) (xy 123.991924 -345.236024) (xy 124.027642 -345.194808) (xy 124.068863 -345.159095)
			(xy 124.114747 -345.129612) (xy 124.16436 -345.10696) (xy 124.216692 -345.0916) (xy 124.270678 -345.083844)
			(xy 124.297948 -345.083384) (xy 125.161548 -345.083384) (xy 125.188818 -345.083782) (xy 125.242803 -345.09155)
			(xy 125.295133 -345.106921) (xy 125.344744 -345.129583) (xy 125.390624 -345.159074) (xy 125.431841 -345.194793)
			(xy 125.467555 -345.236015) (xy 125.49704 -345.281899) (xy 125.519695 -345.331512) (xy 125.53506 -345.383844)
			(xy 125.542822 -345.43783) (xy 125.542822 -345.492368) (xy 127.025647 -345.492368) (xy 127.025647 -345.437832)
			(xy 127.033409 -345.383851) (xy 127.048774 -345.331524) (xy 127.071429 -345.281916) (xy 127.100914 -345.236038)
			(xy 127.136628 -345.194822) (xy 127.177844 -345.159109) (xy 127.223723 -345.129625) (xy 127.273331 -345.106971)
			(xy 127.325659 -345.091607) (xy 127.37964 -345.083847) (xy 127.406908 -345.083384) (xy 128.270508 -345.083384)
			(xy 128.29778 -345.083779) (xy 128.35177 -345.091543) (xy 128.404104 -345.106911) (xy 128.45372 -345.12957)
			(xy 128.499605 -345.15906) (xy 128.540827 -345.194779) (xy 128.576545 -345.236001) (xy 128.606034 -345.281888)
			(xy 128.628692 -345.331503) (xy 128.644059 -345.383838) (xy 128.651821 -345.437828) (xy 128.651821 -345.492365)
			(xy 130.13467 -345.492365) (xy 130.13467 -345.437835) (xy 130.14243 -345.383861) (xy 130.157792 -345.33154)
			(xy 130.180443 -345.281938) (xy 130.209922 -345.236064) (xy 130.24563 -345.194853) (xy 130.286839 -345.159142)
			(xy 130.33271 -345.129658) (xy 130.38231 -345.107003) (xy 130.43463 -345.091637) (xy 130.488603 -345.083872)
			(xy 130.515868 -345.083384) (xy 131.379468 -345.083384) (xy 131.406744 -345.083753) (xy 131.460741 -345.091513)
			(xy 131.513083 -345.106878) (xy 131.562707 -345.129537) (xy 131.6086 -345.159027) (xy 131.649829 -345.194749)
			(xy 131.685554 -345.235975) (xy 131.715048 -345.281865) (xy 131.737711 -345.331487) (xy 131.75308 -345.383828)
			(xy 131.760844 -345.437824) (xy 131.760844 -345.492369) (xy 133.243547 -345.492369) (xy 133.243547 -345.437831)
			(xy 133.251309 -345.383848) (xy 133.266675 -345.33152) (xy 133.289332 -345.281911) (xy 133.318819 -345.236031)
			(xy 133.354535 -345.194815) (xy 133.395753 -345.159102) (xy 133.441635 -345.129619) (xy 133.491246 -345.106965)
			(xy 133.543576 -345.091603) (xy 133.597559 -345.083845) (xy 133.624828 -345.083384) (xy 134.488428 -345.083384)
			(xy 134.515699 -345.08378) (xy 134.569686 -345.091546) (xy 134.622019 -345.106916) (xy 134.671632 -345.129576)
			(xy 134.717514 -345.159067) (xy 134.758734 -345.194786) (xy 134.79445 -345.236008) (xy 134.823937 -345.281893)
			(xy 134.846594 -345.331507) (xy 134.86196 -345.383841) (xy 134.869722 -345.437829) (xy 134.869722 -345.492366)
			(xy 136.35257 -345.492366) (xy 136.35257 -345.437834) (xy 136.360331 -345.383858) (xy 136.375694 -345.331536)
			(xy 136.398346 -345.281933) (xy 136.427827 -345.236058) (xy 136.463537 -345.194846) (xy 136.504748 -345.159135)
			(xy 136.550622 -345.129652) (xy 136.600225 -345.106998) (xy 136.652547 -345.091633) (xy 136.706522 -345.083871)
			(xy 136.733788 -345.083384) (xy 137.597388 -345.083384) (xy 137.624663 -345.083755) (xy 137.678657 -345.091516)
			(xy 137.730998 -345.106884) (xy 137.780619 -345.129543) (xy 137.826509 -345.159034) (xy 137.867736 -345.194756)
			(xy 137.903459 -345.235981) (xy 137.932951 -345.281871) (xy 137.955612 -345.331491) (xy 137.970981 -345.383831)
			(xy 137.978744 -345.437825) (xy 137.978744 -345.49237) (xy 139.461448 -345.49237) (xy 139.461448 -345.43783)
			(xy 139.46921 -345.383846) (xy 139.484577 -345.331515) (xy 139.507235 -345.281905) (xy 139.536724 -345.236024)
			(xy 139.572442 -345.194808) (xy 139.613663 -345.159095) (xy 139.659547 -345.129612) (xy 139.70916 -345.10696)
			(xy 139.761492 -345.0916) (xy 139.815478 -345.083844) (xy 139.842748 -345.083384) (xy 140.706348 -345.083384)
			(xy 140.733618 -345.083782) (xy 140.787603 -345.09155) (xy 140.839933 -345.106921) (xy 140.889544 -345.129583)
			(xy 140.935424 -345.159074) (xy 140.976641 -345.194793) (xy 141.012355 -345.236015) (xy 141.04184 -345.281899)
			(xy 141.064495 -345.331512) (xy 141.07986 -345.383844) (xy 141.087622 -345.43783) (xy 141.087622 -345.492368)
			(xy 142.570447 -345.492368) (xy 142.570447 -345.437832) (xy 142.578209 -345.383851) (xy 142.593574 -345.331524)
			(xy 142.616229 -345.281916) (xy 142.645714 -345.236038) (xy 142.681428 -345.194822) (xy 142.722644 -345.159109)
			(xy 142.768523 -345.129625) (xy 142.818131 -345.106971) (xy 142.870459 -345.091607) (xy 142.92444 -345.083847)
			(xy 142.951708 -345.083384) (xy 143.815308 -345.083384) (xy 143.84258 -345.083779) (xy 143.89657 -345.091543)
			(xy 143.948904 -345.106911) (xy 143.99852 -345.12957) (xy 144.044405 -345.15906) (xy 144.085627 -345.194779)
			(xy 144.121345 -345.236001) (xy 144.150834 -345.281888) (xy 144.173492 -345.331503) (xy 144.188859 -345.383838)
			(xy 144.196621 -345.437828) (xy 144.196621 -345.492365) (xy 164.91387 -345.492365) (xy 164.91387 -345.437835)
			(xy 164.92163 -345.383861) (xy 164.936992 -345.33154) (xy 164.959644 -345.281937) (xy 164.989123 -345.236063)
			(xy 165.024831 -345.194851) (xy 165.066041 -345.15914) (xy 165.111913 -345.129657) (xy 165.161513 -345.107002)
			(xy 165.213833 -345.091636) (xy 165.267807 -345.083872) (xy 165.295072 -345.083384) (xy 166.158672 -345.083384)
			(xy 166.185948 -345.083754) (xy 166.239944 -345.091514) (xy 166.292286 -345.106879) (xy 166.341909 -345.129538)
			(xy 166.387802 -345.159028) (xy 166.42903 -345.19475) (xy 166.464755 -345.235976) (xy 166.494249 -345.281866)
			(xy 166.516911 -345.331487) (xy 166.532281 -345.383829) (xy 166.540044 -345.437824) (xy 166.540044 -345.492369)
			(xy 168.022747 -345.492369) (xy 168.022747 -345.437831) (xy 168.03051 -345.383848) (xy 168.045876 -345.331519)
			(xy 168.068533 -345.281909) (xy 168.09802 -345.23603) (xy 168.133736 -345.194814) (xy 168.174955 -345.159101)
			(xy 168.220838 -345.129617) (xy 168.270449 -345.106964) (xy 168.322779 -345.091603) (xy 168.376763 -345.083845)
			(xy 168.404032 -345.083384) (xy 169.267632 -345.083384) (xy 169.294903 -345.083781) (xy 169.34889 -345.091547)
			(xy 169.401222 -345.106917) (xy 169.450834 -345.129578) (xy 169.496716 -345.159068) (xy 169.537935 -345.194788)
			(xy 169.573651 -345.236009) (xy 169.603138 -345.281894) (xy 169.625794 -345.331508) (xy 169.64116 -345.383842)
			(xy 169.648922 -345.437829) (xy 169.648922 -345.492366) (xy 171.13177 -345.492366) (xy 171.13177 -345.437834)
			(xy 171.139531 -345.383858) (xy 171.154894 -345.331535) (xy 171.177547 -345.281932) (xy 171.207028 -345.236057)
			(xy 171.242738 -345.194844) (xy 171.28395 -345.159133) (xy 171.329825 -345.129651) (xy 171.379428 -345.106997)
			(xy 171.43175 -345.091633) (xy 171.485726 -345.083871) (xy 171.512992 -345.083384) (xy 172.376592 -345.083384)
			(xy 172.403867 -345.083755) (xy 172.457861 -345.091517) (xy 172.510201 -345.106885) (xy 172.559821 -345.129544)
			(xy 172.605711 -345.159035) (xy 172.646937 -345.194757) (xy 172.68266 -345.235982) (xy 172.712152 -345.281872)
			(xy 172.734813 -345.331492) (xy 172.750181 -345.383831) (xy 172.757944 -345.437825) (xy 172.757944 -345.492364)
			(xy 174.24077 -345.492364) (xy 174.24077 -345.437836) (xy 174.24853 -345.383863) (xy 174.263891 -345.331544)
			(xy 174.286541 -345.281943) (xy 174.316019 -345.23607) (xy 174.351724 -345.194858) (xy 174.392931 -345.159147)
			(xy 174.438801 -345.129664) (xy 174.488399 -345.107008) (xy 174.540716 -345.09164) (xy 174.594688 -345.083874)
			(xy 174.621952 -345.083384) (xy 175.485552 -345.083384) (xy 175.512829 -345.083752) (xy 175.566827 -345.09151)
			(xy 175.619172 -345.106874) (xy 175.668797 -345.129531) (xy 175.714692 -345.159021) (xy 175.755923 -345.194743)
			(xy 175.79165 -345.235969) (xy 175.821146 -345.281861) (xy 175.843809 -345.331483) (xy 175.85918 -345.383826)
			(xy 175.866944 -345.437824) (xy 175.866944 -345.492368) (xy 177.349647 -345.492368) (xy 177.349647 -345.437832)
			(xy 177.357409 -345.38385) (xy 177.372774 -345.331523) (xy 177.39543 -345.281915) (xy 177.424915 -345.236036)
			(xy 177.460629 -345.194821) (xy 177.501846 -345.159108) (xy 177.547726 -345.129624) (xy 177.597334 -345.10697)
			(xy 177.649662 -345.091606) (xy 177.703644 -345.083847) (xy 177.730912 -345.083384) (xy 178.594512 -345.083384)
			(xy 178.621784 -345.083779) (xy 178.675773 -345.091543) (xy 178.728107 -345.106912) (xy 178.777722 -345.129571)
			(xy 178.823607 -345.159061) (xy 178.864828 -345.194781) (xy 178.900546 -345.236003) (xy 178.930035 -345.281889)
			(xy 178.952693 -345.331504) (xy 178.968059 -345.383839) (xy 178.975821 -345.437828) (xy 178.975821 -345.492365)
			(xy 180.45867 -345.492365) (xy 180.45867 -345.437835) (xy 180.46643 -345.383861) (xy 180.481792 -345.33154)
			(xy 180.504444 -345.281937) (xy 180.533923 -345.236063) (xy 180.569631 -345.194851) (xy 180.610841 -345.15914)
			(xy 180.656713 -345.129657) (xy 180.706313 -345.107002) (xy 180.758633 -345.091636) (xy 180.812607 -345.083872)
			(xy 180.839872 -345.083384) (xy 181.703472 -345.083384) (xy 181.730748 -345.083754) (xy 181.784744 -345.091514)
			(xy 181.837086 -345.106879) (xy 181.886709 -345.129538) (xy 181.932602 -345.159028) (xy 181.97383 -345.19475)
			(xy 182.009555 -345.235976) (xy 182.039049 -345.281866) (xy 182.061711 -345.331487) (xy 182.077081 -345.383829)
			(xy 182.084844 -345.437824) (xy 182.084844 -345.492369) (xy 183.567547 -345.492369) (xy 183.567547 -345.437831)
			(xy 183.57531 -345.383848) (xy 183.590676 -345.331519) (xy 183.613333 -345.281909) (xy 183.64282 -345.23603)
			(xy 183.678536 -345.194814) (xy 183.719755 -345.159101) (xy 183.765638 -345.129617) (xy 183.815249 -345.106964)
			(xy 183.867579 -345.091603) (xy 183.921563 -345.083845) (xy 183.948832 -345.083384) (xy 184.812432 -345.083384)
			(xy 184.839703 -345.083781) (xy 184.89369 -345.091547) (xy 184.946022 -345.106917) (xy 184.995634 -345.129578)
			(xy 185.041516 -345.159068) (xy 185.082735 -345.194788) (xy 185.118451 -345.236009) (xy 185.147938 -345.281894)
			(xy 185.170594 -345.331508) (xy 185.18596 -345.383842) (xy 185.193722 -345.437829) (xy 185.193722 -345.492366)
			(xy 186.67657 -345.492366) (xy 186.67657 -345.437834) (xy 186.684331 -345.383858) (xy 186.699694 -345.331535)
			(xy 186.722347 -345.281932) (xy 186.751828 -345.236057) (xy 186.787538 -345.194844) (xy 186.82875 -345.159133)
			(xy 186.874625 -345.129651) (xy 186.924228 -345.106997) (xy 186.97655 -345.091633) (xy 187.030526 -345.083871)
			(xy 187.057792 -345.083384) (xy 187.921392 -345.083384) (xy 187.948667 -345.083755) (xy 188.002661 -345.091517)
			(xy 188.055001 -345.106885) (xy 188.104621 -345.129544) (xy 188.150511 -345.159035) (xy 188.191737 -345.194757)
			(xy 188.22746 -345.235982) (xy 188.256952 -345.281872) (xy 188.279613 -345.331492) (xy 188.294981 -345.383831)
			(xy 188.302744 -345.437825) (xy 188.302744 -345.492364) (xy 189.78557 -345.492364) (xy 189.78557 -345.437836)
			(xy 189.79333 -345.383863) (xy 189.808691 -345.331544) (xy 189.831341 -345.281943) (xy 189.860819 -345.23607)
			(xy 189.896524 -345.194858) (xy 189.937731 -345.159147) (xy 189.983601 -345.129664) (xy 190.033199 -345.107008)
			(xy 190.085516 -345.09164) (xy 190.139488 -345.083874) (xy 190.166752 -345.083384) (xy 191.030352 -345.083384)
			(xy 191.057629 -345.083752) (xy 191.111627 -345.09151) (xy 191.163972 -345.106874) (xy 191.213597 -345.129531)
			(xy 191.259492 -345.159021) (xy 191.300723 -345.194743) (xy 191.33645 -345.235969) (xy 191.365946 -345.281861)
			(xy 191.388609 -345.331483) (xy 191.40398 -345.383826) (xy 191.411744 -345.437824) (xy 191.411744 -345.492368)
			(xy 192.894447 -345.492368) (xy 192.894447 -345.437832) (xy 192.902209 -345.38385) (xy 192.917574 -345.331523)
			(xy 192.94023 -345.281915) (xy 192.969715 -345.236036) (xy 193.005429 -345.194821) (xy 193.046646 -345.159108)
			(xy 193.092526 -345.129624) (xy 193.142134 -345.10697) (xy 193.194462 -345.091606) (xy 193.248444 -345.083847)
			(xy 193.275712 -345.083384) (xy 194.139312 -345.083384) (xy 194.166584 -345.083779) (xy 194.220573 -345.091543)
			(xy 194.272907 -345.106912) (xy 194.322522 -345.129571) (xy 194.368407 -345.159061) (xy 194.409628 -345.194781)
			(xy 194.445346 -345.236003) (xy 194.474835 -345.281889) (xy 194.497493 -345.331504) (xy 194.512859 -345.383839)
			(xy 194.520621 -345.437828) (xy 194.520621 -345.492365) (xy 196.00347 -345.492365) (xy 196.00347 -345.437835)
			(xy 196.01123 -345.383861) (xy 196.026592 -345.33154) (xy 196.049244 -345.281937) (xy 196.078723 -345.236063)
			(xy 196.114431 -345.194851) (xy 196.155641 -345.15914) (xy 196.201513 -345.129657) (xy 196.251113 -345.107002)
			(xy 196.303433 -345.091636) (xy 196.357407 -345.083872) (xy 196.384672 -345.083384) (xy 197.248272 -345.083384)
			(xy 197.275548 -345.083754) (xy 197.329544 -345.091514) (xy 197.381886 -345.106879) (xy 197.431509 -345.129538)
			(xy 197.477402 -345.159028) (xy 197.51863 -345.19475) (xy 197.554355 -345.235976) (xy 197.583849 -345.281866)
			(xy 197.606511 -345.331487) (xy 197.621881 -345.383829) (xy 197.629644 -345.437824) (xy 197.629644 -345.492368)
			(xy 267.515847 -345.492368) (xy 267.515847 -345.437832) (xy 267.523609 -345.383852) (xy 267.538973 -345.331525)
			(xy 267.561628 -345.281918) (xy 267.591112 -345.23604) (xy 267.626826 -345.194824) (xy 267.668041 -345.159111)
			(xy 267.71392 -345.129627) (xy 267.763527 -345.106972) (xy 267.815854 -345.091608) (xy 267.869834 -345.083847)
			(xy 267.897102 -345.083384) (xy 268.760702 -345.083384) (xy 268.787975 -345.083779) (xy 268.841964 -345.091542)
			(xy 268.8943 -345.106909) (xy 268.943916 -345.129568) (xy 268.989802 -345.159057) (xy 269.031024 -345.194777)
			(xy 269.066744 -345.236) (xy 269.096233 -345.281886) (xy 269.118892 -345.331502) (xy 269.134259 -345.383838)
			(xy 269.142021 -345.437827) (xy 269.142021 -345.492364) (xy 270.62487 -345.492364) (xy 270.62487 -345.437836)
			(xy 270.63263 -345.383862) (xy 270.647992 -345.331542) (xy 270.670642 -345.28194) (xy 270.700121 -345.236066)
			(xy 270.735828 -345.194855) (xy 270.777036 -345.159144) (xy 270.822907 -345.12966) (xy 270.872506 -345.107005)
			(xy 270.924825 -345.091638) (xy 270.978798 -345.083873) (xy 271.006062 -345.083384) (xy 271.869662 -345.083384)
			(xy 271.896938 -345.083753) (xy 271.950936 -345.091512) (xy 272.003279 -345.106877) (xy 272.052903 -345.129535)
			(xy 272.098797 -345.159025) (xy 272.140027 -345.194747) (xy 272.175752 -345.235973) (xy 272.205247 -345.281864)
			(xy 272.22791 -345.331485) (xy 272.24328 -345.383827) (xy 272.251044 -345.437824) (xy 272.251044 -345.492369)
			(xy 273.733747 -345.492369) (xy 273.733747 -345.437831) (xy 273.741509 -345.383849) (xy 273.756875 -345.331521)
			(xy 273.779531 -345.281912) (xy 273.809017 -345.236033) (xy 273.844733 -345.194817) (xy 273.885951 -345.159104)
			(xy 273.931832 -345.129621) (xy 273.981441 -345.106967) (xy 274.033771 -345.091605) (xy 274.087753 -345.083846)
			(xy 274.115022 -345.083384) (xy 274.978622 -345.083384) (xy 275.005894 -345.08378) (xy 275.059881 -345.091545)
			(xy 275.112215 -345.106914) (xy 275.161828 -345.129574) (xy 275.207712 -345.159064) (xy 275.248932 -345.194784)
			(xy 275.284649 -345.236006) (xy 275.314136 -345.281891) (xy 275.336793 -345.331506) (xy 275.352159 -345.38384)
			(xy 275.359922 -345.437828) (xy 275.359922 -345.492365) (xy 276.84277 -345.492365) (xy 276.84277 -345.437835)
			(xy 276.850531 -345.383859) (xy 276.865893 -345.331537) (xy 276.888545 -345.281934) (xy 276.918026 -345.23606)
			(xy 276.953735 -345.194848) (xy 276.994945 -345.159137) (xy 277.040819 -345.129654) (xy 277.090421 -345.106999)
			(xy 277.142742 -345.091634) (xy 277.196717 -345.083872) (xy 277.223982 -345.083384) (xy 278.087582 -345.083384)
			(xy 278.114857 -345.083754) (xy 278.168852 -345.091515) (xy 278.221194 -345.106882) (xy 278.270815 -345.129541)
			(xy 278.316706 -345.159032) (xy 278.357934 -345.194754) (xy 278.393657 -345.235979) (xy 278.42315 -345.281869)
			(xy 278.445812 -345.33149) (xy 278.461181 -345.38383) (xy 278.468944 -345.437825) (xy 278.468944 -345.49237)
			(xy 279.951648 -345.49237) (xy 279.951648 -345.43783) (xy 279.95941 -345.383846) (xy 279.974776 -345.331517)
			(xy 279.997434 -345.281907) (xy 280.026922 -345.236026) (xy 280.06264 -345.19481) (xy 280.10386 -345.159097)
			(xy 280.149744 -345.129614) (xy 280.199356 -345.106962) (xy 280.251687 -345.091601) (xy 280.305672 -345.083845)
			(xy 280.332942 -345.083384) (xy 281.196542 -345.083384) (xy 281.223813 -345.083781) (xy 281.277798 -345.091549)
			(xy 281.330129 -345.10692) (xy 281.37974 -345.129581) (xy 281.425621 -345.159072) (xy 281.466839 -345.194791)
			(xy 281.502554 -345.236013) (xy 281.532039 -345.281897) (xy 281.554695 -345.33151) (xy 281.57006 -345.383843)
			(xy 281.577822 -345.437829) (xy 281.577822 -345.492368) (xy 283.060647 -345.492368) (xy 283.060647 -345.437832)
			(xy 283.068409 -345.383852) (xy 283.083773 -345.331525) (xy 283.106428 -345.281918) (xy 283.135912 -345.23604)
			(xy 283.171626 -345.194824) (xy 283.212841 -345.159111) (xy 283.25872 -345.129627) (xy 283.308327 -345.106972)
			(xy 283.360654 -345.091608) (xy 283.414634 -345.083847) (xy 283.441902 -345.083384) (xy 284.305502 -345.083384)
			(xy 284.332775 -345.083779) (xy 284.386764 -345.091542) (xy 284.4391 -345.106909) (xy 284.488716 -345.129568)
			(xy 284.534602 -345.159057) (xy 284.575824 -345.194777) (xy 284.611544 -345.236) (xy 284.641033 -345.281886)
			(xy 284.663692 -345.331502) (xy 284.679059 -345.383838) (xy 284.686821 -345.437827) (xy 284.686821 -345.492364)
			(xy 286.16967 -345.492364) (xy 286.16967 -345.437836) (xy 286.17743 -345.383862) (xy 286.192792 -345.331542)
			(xy 286.215442 -345.28194) (xy 286.244921 -345.236066) (xy 286.280628 -345.194855) (xy 286.321836 -345.159144)
			(xy 286.367707 -345.12966) (xy 286.417306 -345.107005) (xy 286.469625 -345.091638) (xy 286.523598 -345.083873)
			(xy 286.550862 -345.083384) (xy 287.414462 -345.083384) (xy 287.441738 -345.083753) (xy 287.495736 -345.091512)
			(xy 287.548079 -345.106877) (xy 287.597703 -345.129535) (xy 287.643597 -345.159025) (xy 287.684827 -345.194747)
			(xy 287.720552 -345.235973) (xy 287.750047 -345.281864) (xy 287.77271 -345.331485) (xy 287.78808 -345.383827)
			(xy 287.795844 -345.437824) (xy 287.795844 -345.492369) (xy 289.278547 -345.492369) (xy 289.278547 -345.437831)
			(xy 289.286309 -345.383849) (xy 289.301675 -345.331521) (xy 289.324331 -345.281912) (xy 289.353817 -345.236033)
			(xy 289.389533 -345.194817) (xy 289.430751 -345.159104) (xy 289.476632 -345.129621) (xy 289.526241 -345.106967)
			(xy 289.578571 -345.091605) (xy 289.632553 -345.083846) (xy 289.659822 -345.083384) (xy 290.523422 -345.083384)
			(xy 290.550694 -345.08378) (xy 290.604681 -345.091545) (xy 290.657015 -345.106914) (xy 290.706628 -345.129574)
			(xy 290.752512 -345.159064) (xy 290.793732 -345.194784) (xy 290.829449 -345.236006) (xy 290.858936 -345.281891)
			(xy 290.881593 -345.331506) (xy 290.896959 -345.38384) (xy 290.904722 -345.437828) (xy 290.904722 -345.492365)
			(xy 292.38757 -345.492365) (xy 292.38757 -345.437835) (xy 292.395331 -345.383859) (xy 292.410693 -345.331537)
			(xy 292.433345 -345.281934) (xy 292.462826 -345.23606) (xy 292.498535 -345.194848) (xy 292.539745 -345.159137)
			(xy 292.585619 -345.129654) (xy 292.635221 -345.106999) (xy 292.687542 -345.091634) (xy 292.741517 -345.083872)
			(xy 292.768782 -345.083384) (xy 293.632382 -345.083384) (xy 293.659657 -345.083754) (xy 293.713652 -345.091515)
			(xy 293.765994 -345.106882) (xy 293.815615 -345.129541) (xy 293.861506 -345.159032) (xy 293.902734 -345.194754)
			(xy 293.938457 -345.235979) (xy 293.96795 -345.281869) (xy 293.990612 -345.33149) (xy 294.005981 -345.38383)
			(xy 294.013744 -345.437825) (xy 294.013744 -345.49237) (xy 295.496448 -345.49237) (xy 295.496448 -345.43783)
			(xy 295.50421 -345.383846) (xy 295.519576 -345.331517) (xy 295.542234 -345.281907) (xy 295.571722 -345.236026)
			(xy 295.60744 -345.19481) (xy 295.64866 -345.159097) (xy 295.694544 -345.129614) (xy 295.744156 -345.106962)
			(xy 295.796487 -345.091601) (xy 295.850472 -345.083845) (xy 295.877742 -345.083384) (xy 296.741342 -345.083384)
			(xy 296.768613 -345.083781) (xy 296.822598 -345.091549) (xy 296.874929 -345.10692) (xy 296.92454 -345.129581)
			(xy 296.970421 -345.159072) (xy 297.011639 -345.194791) (xy 297.047354 -345.236013) (xy 297.076839 -345.281897)
			(xy 297.099495 -345.33151) (xy 297.11486 -345.383843) (xy 297.122622 -345.437829) (xy 297.122622 -345.492368)
			(xy 298.605447 -345.492368) (xy 298.605447 -345.437832) (xy 298.613209 -345.383852) (xy 298.628573 -345.331525)
			(xy 298.651228 -345.281918) (xy 298.680712 -345.23604) (xy 298.716426 -345.194824) (xy 298.757641 -345.159111)
			(xy 298.80352 -345.129627) (xy 298.853127 -345.106972) (xy 298.905454 -345.091608) (xy 298.959434 -345.083847)
			(xy 298.986702 -345.083384) (xy 299.850302 -345.083384) (xy 299.877575 -345.083779) (xy 299.931564 -345.091542)
			(xy 299.9839 -345.106909) (xy 300.033516 -345.129568) (xy 300.079402 -345.159057) (xy 300.120624 -345.194777)
			(xy 300.156344 -345.236) (xy 300.185833 -345.281886) (xy 300.208492 -345.331502) (xy 300.223859 -345.383838)
			(xy 300.231621 -345.437827) (xy 300.231621 -345.492368) (xy 312.121547 -345.492368) (xy 312.121547 -345.437832)
			(xy 312.129309 -345.383851) (xy 312.144673 -345.331525) (xy 312.167328 -345.281917) (xy 312.196813 -345.236039)
			(xy 312.232526 -345.194824) (xy 312.273742 -345.159111) (xy 312.319621 -345.129627) (xy 312.369228 -345.106972)
			(xy 312.421555 -345.091608) (xy 312.475536 -345.083847) (xy 312.502804 -345.083384) (xy 313.366404 -345.083384)
			(xy 313.393676 -345.083779) (xy 313.447666 -345.091542) (xy 313.500001 -345.106909) (xy 313.549617 -345.129569)
			(xy 313.595503 -345.159058) (xy 313.636725 -345.194778) (xy 313.672444 -345.236) (xy 313.701933 -345.281886)
			(xy 313.724592 -345.331502) (xy 313.739959 -345.383838) (xy 313.747721 -345.437828) (xy 313.747721 -345.492364)
			(xy 315.23057 -345.492364) (xy 315.23057 -345.437836) (xy 315.23833 -345.383862) (xy 315.253692 -345.331541)
			(xy 315.276343 -345.281939) (xy 315.305821 -345.236066) (xy 315.341529 -345.194854) (xy 315.382737 -345.159143)
			(xy 315.428608 -345.12966) (xy 315.478207 -345.107004) (xy 315.530526 -345.091638) (xy 315.5845 -345.083873)
			(xy 315.611764 -345.083384) (xy 316.475364 -345.083384) (xy 316.50264 -345.083753) (xy 316.556637 -345.091512)
			(xy 316.608981 -345.106877) (xy 316.658604 -345.129535) (xy 316.704498 -345.159026) (xy 316.745727 -345.194747)
			(xy 316.781453 -345.235973) (xy 316.810947 -345.281864) (xy 316.83361 -345.331486) (xy 316.84898 -345.383828)
			(xy 316.856744 -345.437824) (xy 316.856744 -345.492369) (xy 318.339447 -345.492369) (xy 318.339447 -345.437831)
			(xy 318.347209 -345.383849) (xy 318.362575 -345.33152) (xy 318.385231 -345.281912) (xy 318.414718 -345.236032)
			(xy 318.450434 -345.194817) (xy 318.491652 -345.159103) (xy 318.537533 -345.12962) (xy 318.587143 -345.106966)
			(xy 318.639472 -345.091604) (xy 318.693455 -345.083846) (xy 318.720724 -345.083384) (xy 319.584324 -345.083384)
			(xy 319.611596 -345.08378) (xy 319.665583 -345.091546) (xy 319.717916 -345.106915) (xy 319.767529 -345.129575)
			(xy 319.813413 -345.159065) (xy 319.854632 -345.194785) (xy 319.890349 -345.236007) (xy 319.919836 -345.281892)
			(xy 319.942494 -345.331507) (xy 319.95786 -345.38384) (xy 319.965622 -345.437828) (xy 319.965622 -345.492365)
			(xy 321.44847 -345.492365) (xy 321.44847 -345.437835) (xy 321.456231 -345.383859) (xy 321.471593 -345.331537)
			(xy 321.494246 -345.281934) (xy 321.523726 -345.236059) (xy 321.559436 -345.194847) (xy 321.600646 -345.159136)
			(xy 321.64652 -345.129653) (xy 321.696122 -345.106999) (xy 321.748443 -345.091634) (xy 321.802419 -345.083871)
			(xy 321.829684 -345.083384) (xy 322.693284 -345.083384) (xy 322.720559 -345.083755) (xy 322.774554 -345.091516)
			(xy 322.826895 -345.106882) (xy 322.876516 -345.129542) (xy 322.922407 -345.159033) (xy 322.963634 -345.194754)
			(xy 322.999358 -345.23598) (xy 323.02885 -345.28187) (xy 323.051512 -345.33149) (xy 323.066881 -345.38383)
			(xy 323.074644 -345.437825) (xy 323.074644 -345.49237) (xy 324.557348 -345.49237) (xy 324.557348 -345.43783)
			(xy 324.56511 -345.383846) (xy 324.580476 -345.331516) (xy 324.603135 -345.281906) (xy 324.632623 -345.236026)
			(xy 324.668341 -345.194809) (xy 324.709561 -345.159096) (xy 324.755445 -345.129613) (xy 324.805057 -345.106961)
			(xy 324.857389 -345.0916) (xy 324.911374 -345.083844) (xy 324.938644 -345.083384) (xy 325.802244 -345.083384)
			(xy 325.829515 -345.083782) (xy 325.8835 -345.091549) (xy 325.93583 -345.10692) (xy 325.985441 -345.129582)
			(xy 326.031322 -345.159072) (xy 326.072539 -345.194792) (xy 326.108254 -345.236013) (xy 326.137739 -345.281898)
			(xy 326.160395 -345.331511) (xy 326.17576 -345.383843) (xy 326.183522 -345.437829) (xy 326.183522 -345.492368)
			(xy 327.666347 -345.492368) (xy 327.666347 -345.437832) (xy 327.674109 -345.383851) (xy 327.689473 -345.331525)
			(xy 327.712128 -345.281917) (xy 327.741613 -345.236039) (xy 327.777326 -345.194824) (xy 327.818542 -345.159111)
			(xy 327.864421 -345.129627) (xy 327.914028 -345.106972) (xy 327.966355 -345.091608) (xy 328.020336 -345.083847)
			(xy 328.047604 -345.083384) (xy 328.911204 -345.083384) (xy 328.938476 -345.083779) (xy 328.992466 -345.091542)
			(xy 329.044801 -345.106909) (xy 329.094417 -345.129569) (xy 329.140303 -345.159058) (xy 329.181525 -345.194778)
			(xy 329.217244 -345.236) (xy 329.246733 -345.281886) (xy 329.269392 -345.331502) (xy 329.284759 -345.383838)
			(xy 329.292521 -345.437828) (xy 329.292521 -345.492364) (xy 330.77537 -345.492364) (xy 330.77537 -345.437836)
			(xy 330.78313 -345.383862) (xy 330.798492 -345.331541) (xy 330.821143 -345.281939) (xy 330.850621 -345.236066)
			(xy 330.886329 -345.194854) (xy 330.927537 -345.159143) (xy 330.973408 -345.12966) (xy 331.023007 -345.107004)
			(xy 331.075326 -345.091638) (xy 331.1293 -345.083873) (xy 331.156564 -345.083384) (xy 332.020164 -345.083384)
			(xy 332.04744 -345.083753) (xy 332.101437 -345.091512) (xy 332.153781 -345.106877) (xy 332.203404 -345.129535)
			(xy 332.249298 -345.159026) (xy 332.290527 -345.194747) (xy 332.326253 -345.235973) (xy 332.355747 -345.281864)
			(xy 332.37841 -345.331486) (xy 332.39378 -345.383828) (xy 332.401544 -345.437824) (xy 332.401544 -345.492369)
			(xy 333.884247 -345.492369) (xy 333.884247 -345.437831) (xy 333.892009 -345.383849) (xy 333.907375 -345.33152)
			(xy 333.930031 -345.281912) (xy 333.959518 -345.236032) (xy 333.995234 -345.194817) (xy 334.036452 -345.159103)
			(xy 334.082333 -345.12962) (xy 334.131943 -345.106966) (xy 334.184272 -345.091604) (xy 334.238255 -345.083846)
			(xy 334.265524 -345.083384) (xy 335.129124 -345.083384) (xy 335.156396 -345.08378) (xy 335.210383 -345.091546)
			(xy 335.262716 -345.106915) (xy 335.312329 -345.129575) (xy 335.358213 -345.159065) (xy 335.399432 -345.194785)
			(xy 335.435149 -345.236007) (xy 335.464636 -345.281892) (xy 335.487294 -345.331507) (xy 335.50266 -345.38384)
			(xy 335.510422 -345.437828) (xy 335.510422 -345.492365) (xy 336.99327 -345.492365) (xy 336.99327 -345.437835)
			(xy 337.001031 -345.383859) (xy 337.016393 -345.331537) (xy 337.039046 -345.281934) (xy 337.068526 -345.236059)
			(xy 337.104236 -345.194847) (xy 337.145446 -345.159136) (xy 337.19132 -345.129653) (xy 337.240922 -345.106999)
			(xy 337.293243 -345.091634) (xy 337.347219 -345.083871) (xy 337.374484 -345.083384) (xy 338.238084 -345.083384)
			(xy 338.265359 -345.083755) (xy 338.319354 -345.091516) (xy 338.371695 -345.106882) (xy 338.421316 -345.129542)
			(xy 338.467207 -345.159033) (xy 338.508434 -345.194754) (xy 338.544158 -345.23598) (xy 338.57365 -345.28187)
			(xy 338.596312 -345.33149) (xy 338.611681 -345.38383) (xy 338.619444 -345.437825) (xy 338.619444 -345.49237)
			(xy 340.102148 -345.49237) (xy 340.102148 -345.43783) (xy 340.10991 -345.383846) (xy 340.125276 -345.331516)
			(xy 340.147935 -345.281906) (xy 340.177423 -345.236026) (xy 340.213141 -345.194809) (xy 340.254361 -345.159096)
			(xy 340.300245 -345.129613) (xy 340.349857 -345.106961) (xy 340.402189 -345.0916) (xy 340.456174 -345.083844)
			(xy 340.483444 -345.083384) (xy 341.347044 -345.083384) (xy 341.374315 -345.083782) (xy 341.4283 -345.091549)
			(xy 341.48063 -345.10692) (xy 341.530241 -345.129582) (xy 341.576122 -345.159072) (xy 341.617339 -345.194792)
			(xy 341.653054 -345.236013) (xy 341.682539 -345.281898) (xy 341.705195 -345.331511) (xy 341.72056 -345.383843)
			(xy 341.728322 -345.437829) (xy 341.728322 -345.492368) (xy 343.211147 -345.492368) (xy 343.211147 -345.437832)
			(xy 343.218909 -345.383851) (xy 343.234273 -345.331525) (xy 343.256928 -345.281917) (xy 343.286413 -345.236039)
			(xy 343.322126 -345.194824) (xy 343.363342 -345.159111) (xy 343.409221 -345.129627) (xy 343.458828 -345.106972)
			(xy 343.511155 -345.091608) (xy 343.565136 -345.083847) (xy 343.592404 -345.083384) (xy 344.456004 -345.083384)
			(xy 344.483276 -345.083779) (xy 344.537266 -345.091542) (xy 344.589601 -345.106909) (xy 344.639217 -345.129569)
			(xy 344.685103 -345.159058) (xy 344.726325 -345.194778) (xy 344.762044 -345.236) (xy 344.791533 -345.281886)
			(xy 344.814192 -345.331502) (xy 344.829559 -345.383838) (xy 344.837321 -345.437828) (xy 344.837321 -345.492365)
			(xy 370.80677 -345.492365) (xy 370.80677 -345.437835) (xy 370.81453 -345.383859) (xy 370.829893 -345.331538)
			(xy 370.852545 -345.281935) (xy 370.882025 -345.236061) (xy 370.917734 -345.194848) (xy 370.958945 -345.159137)
			(xy 371.004817 -345.129655) (xy 371.054419 -345.107) (xy 371.10674 -345.091635) (xy 371.160715 -345.083872)
			(xy 371.18798 -345.083384) (xy 372.05158 -345.083384) (xy 372.078855 -345.083754) (xy 372.132851 -345.091515)
			(xy 372.185192 -345.106881) (xy 372.234814 -345.129541) (xy 372.280705 -345.159031) (xy 372.321933 -345.194753)
			(xy 372.357657 -345.235978) (xy 372.38715 -345.281869) (xy 372.409812 -345.331489) (xy 372.425181 -345.38383)
			(xy 372.432944 -345.437825) (xy 372.432944 -345.49237) (xy 373.915647 -345.49237) (xy 373.915647 -345.43783)
			(xy 373.92341 -345.383847) (xy 373.938776 -345.331517) (xy 373.961434 -345.281907) (xy 373.990922 -345.236027)
			(xy 374.026639 -345.194811) (xy 374.067859 -345.159098) (xy 374.113742 -345.129615) (xy 374.163355 -345.106962)
			(xy 374.215686 -345.091601) (xy 374.26967 -345.083845) (xy 374.29694 -345.083384) (xy 375.16054 -345.083384)
			(xy 375.187811 -345.083781) (xy 375.241797 -345.091549) (xy 375.294128 -345.106919) (xy 375.343739 -345.12958)
			(xy 375.38962 -345.159071) (xy 375.430838 -345.19479) (xy 375.466553 -345.236012) (xy 375.496039 -345.281896)
			(xy 375.518695 -345.33151) (xy 375.53406 -345.383843) (xy 375.541822 -345.437829) (xy 375.541822 -345.492366)
			(xy 377.02467 -345.492366) (xy 377.02467 -345.437834) (xy 377.032431 -345.383857) (xy 377.047795 -345.331534)
			(xy 377.070448 -345.281929) (xy 377.09993 -345.236054) (xy 377.135641 -345.194841) (xy 377.176854 -345.15913)
			(xy 377.222729 -345.129648) (xy 377.272334 -345.106995) (xy 377.324657 -345.091631) (xy 377.378634 -345.08387)
			(xy 377.4059 -345.083384) (xy 378.2695 -345.083384) (xy 378.296773 -345.083779) (xy 378.350763 -345.091541)
			(xy 378.403099 -345.106908) (xy 378.452715 -345.129567) (xy 378.498601 -345.159057) (xy 378.539824 -345.194776)
			(xy 378.575543 -345.235999) (xy 378.605033 -345.281885) (xy 378.627692 -345.331501) (xy 378.643059 -345.383837)
			(xy 378.650821 -345.437827) (xy 378.650821 -345.492364) (xy 380.13367 -345.492364) (xy 380.13367 -345.437836)
			(xy 380.14143 -345.383862) (xy 380.156791 -345.331542) (xy 380.179442 -345.281941) (xy 380.208921 -345.236067)
			(xy 380.244627 -345.194855) (xy 380.285835 -345.159145) (xy 380.331705 -345.129661) (xy 380.381305 -345.107005)
			(xy 380.433623 -345.091638) (xy 380.487596 -345.083873) (xy 380.51486 -345.083384) (xy 381.37846 -345.083384)
			(xy 381.405736 -345.083753) (xy 381.459734 -345.091511) (xy 381.512078 -345.106876) (xy 381.561702 -345.129534)
			(xy 381.607596 -345.159024) (xy 381.648826 -345.194746) (xy 381.684552 -345.235972) (xy 381.714047 -345.281863)
			(xy 381.73671 -345.331485) (xy 381.75208 -345.383827) (xy 381.759844 -345.437824) (xy 381.759844 -345.492369)
			(xy 383.242547 -345.492369) (xy 383.242547 -345.437831) (xy 383.250309 -345.383849) (xy 383.265675 -345.331521)
			(xy 383.288331 -345.281913) (xy 383.317817 -345.236034) (xy 383.353532 -345.194818) (xy 383.39475 -345.159105)
			(xy 383.44063 -345.129621) (xy 383.49024 -345.106968) (xy 383.542569 -345.091605) (xy 383.596551 -345.083846)
			(xy 383.62382 -345.083384) (xy 384.48742 -345.083384) (xy 384.514692 -345.08378) (xy 384.56868 -345.091545)
			(xy 384.621013 -345.106914) (xy 384.670627 -345.129574) (xy 384.716511 -345.159064) (xy 384.757731 -345.194783)
			(xy 384.793448 -345.236005) (xy 384.822936 -345.281891) (xy 384.845593 -345.331506) (xy 384.860959 -345.38384)
			(xy 384.868722 -345.437828) (xy 384.868722 -345.492365) (xy 386.35157 -345.492365) (xy 386.35157 -345.437835)
			(xy 386.35933 -345.383859) (xy 386.374693 -345.331538) (xy 386.397345 -345.281935) (xy 386.426825 -345.236061)
			(xy 386.462534 -345.194848) (xy 386.503745 -345.159137) (xy 386.549617 -345.129655) (xy 386.599219 -345.107)
			(xy 386.65154 -345.091635) (xy 386.705515 -345.083872) (xy 386.73278 -345.083384) (xy 387.59638 -345.083384)
			(xy 387.623655 -345.083754) (xy 387.677651 -345.091515) (xy 387.729992 -345.106881) (xy 387.779614 -345.129541)
			(xy 387.825505 -345.159031) (xy 387.866733 -345.194753) (xy 387.902457 -345.235978) (xy 387.93195 -345.281869)
			(xy 387.954612 -345.331489) (xy 387.969981 -345.38383) (xy 387.977744 -345.437825) (xy 387.977744 -345.49237)
			(xy 389.460447 -345.49237) (xy 389.460447 -345.43783) (xy 389.46821 -345.383847) (xy 389.483576 -345.331517)
			(xy 389.506234 -345.281907) (xy 389.535722 -345.236027) (xy 389.571439 -345.194811) (xy 389.612659 -345.159098)
			(xy 389.658542 -345.129615) (xy 389.708155 -345.106962) (xy 389.760486 -345.091601) (xy 389.81447 -345.083845)
			(xy 389.84174 -345.083384) (xy 390.70534 -345.083384) (xy 390.732611 -345.083781) (xy 390.786597 -345.091549)
			(xy 390.838928 -345.106919) (xy 390.888539 -345.12958) (xy 390.93442 -345.159071) (xy 390.975638 -345.19479)
			(xy 391.011353 -345.236012) (xy 391.040839 -345.281896) (xy 391.063495 -345.33151) (xy 391.07886 -345.383843)
			(xy 391.086622 -345.437829) (xy 391.086622 -345.492366) (xy 392.56947 -345.492366) (xy 392.56947 -345.437834)
			(xy 392.577231 -345.383857) (xy 392.592595 -345.331534) (xy 392.615248 -345.281929) (xy 392.64473 -345.236054)
			(xy 392.680441 -345.194841) (xy 392.721654 -345.15913) (xy 392.767529 -345.129648) (xy 392.817134 -345.106995)
			(xy 392.869457 -345.091631) (xy 392.923434 -345.08387) (xy 392.9507 -345.083384) (xy 393.8143 -345.083384)
			(xy 393.841573 -345.083779) (xy 393.895563 -345.091541) (xy 393.947899 -345.106908) (xy 393.997515 -345.129567)
			(xy 394.043401 -345.159057) (xy 394.084624 -345.194776) (xy 394.120343 -345.235999) (xy 394.149833 -345.281885)
			(xy 394.172492 -345.331501) (xy 394.187859 -345.383837) (xy 394.195621 -345.437827) (xy 394.195621 -345.492364)
			(xy 395.67847 -345.492364) (xy 395.67847 -345.437836) (xy 395.68623 -345.383862) (xy 395.701591 -345.331542)
			(xy 395.724242 -345.281941) (xy 395.753721 -345.236067) (xy 395.789427 -345.194855) (xy 395.830635 -345.159145)
			(xy 395.876505 -345.129661) (xy 395.926105 -345.107005) (xy 395.978423 -345.091638) (xy 396.032396 -345.083873)
			(xy 396.05966 -345.083384) (xy 396.92326 -345.083384) (xy 396.950536 -345.083753) (xy 397.004534 -345.091511)
			(xy 397.056878 -345.106876) (xy 397.106502 -345.129534) (xy 397.152396 -345.159024) (xy 397.193626 -345.194746)
			(xy 397.229352 -345.235972) (xy 397.258847 -345.281863) (xy 397.28151 -345.331485) (xy 397.29688 -345.383827)
			(xy 397.304644 -345.437824) (xy 397.304644 -345.492369) (xy 398.787347 -345.492369) (xy 398.787347 -345.437831)
			(xy 398.795109 -345.383849) (xy 398.810475 -345.331521) (xy 398.833131 -345.281913) (xy 398.862617 -345.236034)
			(xy 398.898332 -345.194818) (xy 398.93955 -345.159105) (xy 398.98543 -345.129621) (xy 399.03504 -345.106968)
			(xy 399.087369 -345.091605) (xy 399.141351 -345.083846) (xy 399.16862 -345.083384) (xy 400.03222 -345.083384)
			(xy 400.059492 -345.08378) (xy 400.11348 -345.091545) (xy 400.165813 -345.106914) (xy 400.215427 -345.129574)
			(xy 400.261311 -345.159064) (xy 400.302531 -345.194783) (xy 400.338248 -345.236005) (xy 400.367736 -345.281891)
			(xy 400.390393 -345.331506) (xy 400.405759 -345.38384) (xy 400.413522 -345.437828) (xy 400.413522 -345.492365)
			(xy 401.89637 -345.492365) (xy 401.89637 -345.437835) (xy 401.90413 -345.383859) (xy 401.919493 -345.331538)
			(xy 401.942145 -345.281935) (xy 401.971625 -345.236061) (xy 402.007334 -345.194848) (xy 402.048545 -345.159137)
			(xy 402.094417 -345.129655) (xy 402.144019 -345.107) (xy 402.19634 -345.091635) (xy 402.250315 -345.083872)
			(xy 402.27758 -345.083384) (xy 403.14118 -345.083384) (xy 403.168455 -345.083754) (xy 403.222451 -345.091515)
			(xy 403.274792 -345.106881) (xy 403.324414 -345.129541) (xy 403.370305 -345.159031) (xy 403.411533 -345.194753)
			(xy 403.447257 -345.235978) (xy 403.47675 -345.281869) (xy 403.499412 -345.331489) (xy 403.514781 -345.38383)
			(xy 403.522544 -345.437825) (xy 403.522544 -345.492366) (xy 408.91387 -345.492366) (xy 408.91387 -345.437834)
			(xy 408.921631 -345.383858) (xy 408.936994 -345.331535) (xy 408.959647 -345.281932) (xy 408.989128 -345.236057)
			(xy 409.024838 -345.194844) (xy 409.06605 -345.159133) (xy 409.111925 -345.129651) (xy 409.161528 -345.106997)
			(xy 409.21385 -345.091633) (xy 409.267826 -345.083871) (xy 409.295092 -345.083384) (xy 410.158692 -345.083384)
			(xy 410.185967 -345.083755) (xy 410.239961 -345.091517) (xy 410.292301 -345.106885) (xy 410.341921 -345.129544)
			(xy 410.387811 -345.159035) (xy 410.429037 -345.194757) (xy 410.46476 -345.235982) (xy 410.494252 -345.281872)
			(xy 410.516913 -345.331492) (xy 410.532281 -345.383831) (xy 410.540044 -345.437825) (xy 410.540044 -345.492364)
			(xy 412.02287 -345.492364) (xy 412.02287 -345.437836) (xy 412.03063 -345.383863) (xy 412.045991 -345.331544)
			(xy 412.068641 -345.281943) (xy 412.098119 -345.23607) (xy 412.133824 -345.194858) (xy 412.175031 -345.159147)
			(xy 412.220901 -345.129664) (xy 412.270499 -345.107008) (xy 412.322816 -345.09164) (xy 412.376788 -345.083874)
			(xy 412.404052 -345.083384) (xy 413.267652 -345.083384) (xy 413.294929 -345.083752) (xy 413.348927 -345.09151)
			(xy 413.401272 -345.106874) (xy 413.450897 -345.129531) (xy 413.496792 -345.159021) (xy 413.538023 -345.194743)
			(xy 413.57375 -345.235969) (xy 413.603246 -345.281861) (xy 413.625909 -345.331483) (xy 413.64128 -345.383826)
			(xy 413.649044 -345.437824) (xy 413.649044 -345.492368) (xy 415.131747 -345.492368) (xy 415.131747 -345.437832)
			(xy 415.139509 -345.38385) (xy 415.154874 -345.331523) (xy 415.17753 -345.281915) (xy 415.207015 -345.236036)
			(xy 415.242729 -345.194821) (xy 415.283946 -345.159108) (xy 415.329826 -345.129624) (xy 415.379434 -345.10697)
			(xy 415.431762 -345.091606) (xy 415.485744 -345.083847) (xy 415.513012 -345.083384) (xy 416.376612 -345.083384)
			(xy 416.403884 -345.083779) (xy 416.457873 -345.091543) (xy 416.510207 -345.106912) (xy 416.559822 -345.129571)
			(xy 416.605707 -345.159061) (xy 416.646928 -345.194781) (xy 416.682646 -345.236003) (xy 416.712135 -345.281889)
			(xy 416.734793 -345.331504) (xy 416.750159 -345.383839) (xy 416.757921 -345.437828) (xy 416.757921 -345.492365)
			(xy 418.24077 -345.492365) (xy 418.24077 -345.437835) (xy 418.24853 -345.383861) (xy 418.263892 -345.33154)
			(xy 418.286544 -345.281937) (xy 418.316023 -345.236063) (xy 418.351731 -345.194851) (xy 418.392941 -345.15914)
			(xy 418.438813 -345.129657) (xy 418.488413 -345.107002) (xy 418.540733 -345.091636) (xy 418.594707 -345.083872)
			(xy 418.621972 -345.083384) (xy 419.485572 -345.083384) (xy 419.512848 -345.083754) (xy 419.566844 -345.091514)
			(xy 419.619186 -345.106879) (xy 419.668809 -345.129538) (xy 419.714702 -345.159028) (xy 419.75593 -345.19475)
			(xy 419.791655 -345.235976) (xy 419.821149 -345.281866) (xy 419.843811 -345.331487) (xy 419.859181 -345.383829)
			(xy 419.866944 -345.437824) (xy 419.866944 -345.492369) (xy 421.349647 -345.492369) (xy 421.349647 -345.437831)
			(xy 421.35741 -345.383848) (xy 421.372776 -345.331519) (xy 421.395433 -345.281909) (xy 421.42492 -345.23603)
			(xy 421.460636 -345.194814) (xy 421.501855 -345.159101) (xy 421.547738 -345.129617) (xy 421.597349 -345.106964)
			(xy 421.649679 -345.091603) (xy 421.703663 -345.083845) (xy 421.730932 -345.083384) (xy 422.594532 -345.083384)
			(xy 422.621803 -345.083781) (xy 422.67579 -345.091547) (xy 422.728122 -345.106917) (xy 422.777734 -345.129578)
			(xy 422.823616 -345.159068) (xy 422.864835 -345.194788) (xy 422.900551 -345.236009) (xy 422.930038 -345.281894)
			(xy 422.952694 -345.331508) (xy 422.96806 -345.383842) (xy 422.975822 -345.437829) (xy 422.975822 -345.492366)
			(xy 424.45867 -345.492366) (xy 424.45867 -345.437834) (xy 424.466431 -345.383858) (xy 424.481794 -345.331535)
			(xy 424.504447 -345.281932) (xy 424.533928 -345.236057) (xy 424.569638 -345.194844) (xy 424.61085 -345.159133)
			(xy 424.656725 -345.129651) (xy 424.706328 -345.106997) (xy 424.75865 -345.091633) (xy 424.812626 -345.083871)
			(xy 424.839892 -345.083384) (xy 425.703492 -345.083384) (xy 425.730767 -345.083755) (xy 425.784761 -345.091517)
			(xy 425.837101 -345.106885) (xy 425.886721 -345.129544) (xy 425.932611 -345.159035) (xy 425.973837 -345.194757)
			(xy 426.00956 -345.235982) (xy 426.039052 -345.281872) (xy 426.061713 -345.331492) (xy 426.077081 -345.383831)
			(xy 426.084844 -345.437825) (xy 426.084844 -345.492364) (xy 427.56767 -345.492364) (xy 427.56767 -345.437836)
			(xy 427.57543 -345.383863) (xy 427.590791 -345.331544) (xy 427.613441 -345.281943) (xy 427.642919 -345.23607)
			(xy 427.678624 -345.194858) (xy 427.719831 -345.159147) (xy 427.765701 -345.129664) (xy 427.815299 -345.107008)
			(xy 427.867616 -345.09164) (xy 427.921588 -345.083874) (xy 427.948852 -345.083384) (xy 428.812452 -345.083384)
			(xy 428.839729 -345.083752) (xy 428.893727 -345.09151) (xy 428.946072 -345.106874) (xy 428.995697 -345.129531)
			(xy 429.041592 -345.159021) (xy 429.082823 -345.194743) (xy 429.11855 -345.235969) (xy 429.148046 -345.281861)
			(xy 429.170709 -345.331483) (xy 429.18608 -345.383826) (xy 429.193844 -345.437824) (xy 429.193844 -345.492368)
			(xy 430.676547 -345.492368) (xy 430.676547 -345.437832) (xy 430.684309 -345.38385) (xy 430.699674 -345.331523)
			(xy 430.72233 -345.281915) (xy 430.751815 -345.236036) (xy 430.787529 -345.194821) (xy 430.828746 -345.159108)
			(xy 430.874626 -345.129624) (xy 430.924234 -345.10697) (xy 430.976562 -345.091606) (xy 431.030544 -345.083847)
			(xy 431.057812 -345.083384) (xy 431.921412 -345.083384) (xy 431.948684 -345.083779) (xy 432.002673 -345.091543)
			(xy 432.055007 -345.106912) (xy 432.104622 -345.129571) (xy 432.150507 -345.159061) (xy 432.191728 -345.194781)
			(xy 432.227446 -345.236003) (xy 432.256935 -345.281889) (xy 432.279593 -345.331504) (xy 432.294959 -345.383839)
			(xy 432.302721 -345.437828) (xy 432.302721 -345.492365) (xy 433.78557 -345.492365) (xy 433.78557 -345.437835)
			(xy 433.79333 -345.383861) (xy 433.808692 -345.33154) (xy 433.831344 -345.281937) (xy 433.860823 -345.236063)
			(xy 433.896531 -345.194851) (xy 433.937741 -345.15914) (xy 433.983613 -345.129657) (xy 434.033213 -345.107002)
			(xy 434.085533 -345.091636) (xy 434.139507 -345.083872) (xy 434.166772 -345.083384) (xy 435.030372 -345.083384)
			(xy 435.057648 -345.083754) (xy 435.111644 -345.091514) (xy 435.163986 -345.106879) (xy 435.213609 -345.129538)
			(xy 435.259502 -345.159028) (xy 435.30073 -345.19475) (xy 435.336455 -345.235976) (xy 435.365949 -345.281866)
			(xy 435.388611 -345.331487) (xy 435.403981 -345.383829) (xy 435.411744 -345.437824) (xy 435.411744 -345.492369)
			(xy 436.894447 -345.492369) (xy 436.894447 -345.437831) (xy 436.90221 -345.383848) (xy 436.917576 -345.331519)
			(xy 436.940233 -345.281909) (xy 436.96972 -345.23603) (xy 437.005436 -345.194814) (xy 437.046655 -345.159101)
			(xy 437.092538 -345.129617) (xy 437.142149 -345.106964) (xy 437.194479 -345.091603) (xy 437.248463 -345.083845)
			(xy 437.275732 -345.083384) (xy 438.139332 -345.083384) (xy 438.166603 -345.083781) (xy 438.22059 -345.091547)
			(xy 438.272922 -345.106917) (xy 438.322534 -345.129578) (xy 438.368416 -345.159068) (xy 438.409635 -345.194788)
			(xy 438.445351 -345.236009) (xy 438.474838 -345.281894) (xy 438.497494 -345.331508) (xy 438.51286 -345.383842)
			(xy 438.520622 -345.437829) (xy 438.520622 -345.492366) (xy 440.00347 -345.492366) (xy 440.00347 -345.437834)
			(xy 440.011231 -345.383858) (xy 440.026594 -345.331535) (xy 440.049247 -345.281932) (xy 440.078728 -345.236057)
			(xy 440.114438 -345.194844) (xy 440.15565 -345.159133) (xy 440.201525 -345.129651) (xy 440.251128 -345.106997)
			(xy 440.30345 -345.091633) (xy 440.357426 -345.083871) (xy 440.384692 -345.083384) (xy 441.248292 -345.083384)
			(xy 441.275567 -345.083755) (xy 441.329561 -345.091517) (xy 441.381901 -345.106885) (xy 441.431521 -345.129544)
			(xy 441.477411 -345.159035) (xy 441.518637 -345.194757) (xy 441.55436 -345.235982) (xy 441.583852 -345.281872)
			(xy 441.606513 -345.331492) (xy 441.621881 -345.383831) (xy 441.629644 -345.437825) (xy 441.629644 -345.492375)
			(xy 441.621881 -345.546369) (xy 441.606513 -345.598708) (xy 441.583852 -345.648328) (xy 441.55436 -345.694218)
			(xy 441.518637 -345.735443) (xy 441.477411 -345.771165) (xy 441.431521 -345.800656) (xy 441.381901 -345.823315)
			(xy 441.329561 -345.838683) (xy 441.275567 -345.846445) (xy 441.248292 -345.846908) (xy 440.384692 -345.846908)
			(xy 440.357426 -345.846329) (xy 440.30345 -345.838567) (xy 440.251128 -345.823203) (xy 440.201525 -345.800549)
			(xy 440.15565 -345.771067) (xy 440.114438 -345.735356) (xy 440.078728 -345.694143) (xy 440.049247 -345.648268)
			(xy 440.026594 -345.598665) (xy 440.011231 -345.546342) (xy 440.00347 -345.492366) (xy 438.520622 -345.492366)
			(xy 438.520622 -345.492371) (xy 438.51286 -345.546358) (xy 438.497494 -345.598692) (xy 438.474838 -345.648306)
			(xy 438.445351 -345.694191) (xy 438.409635 -345.735412) (xy 438.368416 -345.771132) (xy 438.322534 -345.800622)
			(xy 438.272922 -345.823283) (xy 438.22059 -345.838653) (xy 438.166603 -345.846419) (xy 438.139332 -345.846908)
			(xy 437.275732 -345.846908) (xy 437.248463 -345.846355) (xy 437.194479 -345.838597) (xy 437.142149 -345.823236)
			(xy 437.092538 -345.800583) (xy 437.046655 -345.771099) (xy 437.005436 -345.735386) (xy 436.96972 -345.69417)
			(xy 436.940233 -345.648291) (xy 436.917576 -345.598681) (xy 436.90221 -345.546352) (xy 436.894447 -345.492369)
			(xy 435.411744 -345.492369) (xy 435.411744 -345.492376) (xy 435.403981 -345.546371) (xy 435.388611 -345.598713)
			(xy 435.365949 -345.648334) (xy 435.336455 -345.694224) (xy 435.30073 -345.73545) (xy 435.259502 -345.771172)
			(xy 435.213609 -345.800662) (xy 435.163986 -345.823321) (xy 435.111644 -345.838686) (xy 435.057648 -345.846446)
			(xy 435.030372 -345.846908) (xy 434.166772 -345.846908) (xy 434.139507 -345.846328) (xy 434.085533 -345.838564)
			(xy 434.033213 -345.823198) (xy 433.983613 -345.800543) (xy 433.937741 -345.77106) (xy 433.896531 -345.735349)
			(xy 433.860823 -345.694137) (xy 433.831344 -345.648263) (xy 433.808692 -345.59866) (xy 433.79333 -345.546339)
			(xy 433.78557 -345.492365) (xy 432.302721 -345.492365) (xy 432.302721 -345.492372) (xy 432.294959 -345.546361)
			(xy 432.279593 -345.598696) (xy 432.256935 -345.648311) (xy 432.227446 -345.694197) (xy 432.191728 -345.735419)
			(xy 432.150507 -345.771139) (xy 432.104622 -345.800629) (xy 432.055007 -345.823288) (xy 432.002673 -345.838657)
			(xy 431.948684 -345.846421) (xy 431.921412 -345.846908) (xy 431.057812 -345.846908) (xy 431.030544 -345.846353)
			(xy 430.976562 -345.838594) (xy 430.924234 -345.82323) (xy 430.874626 -345.800576) (xy 430.828746 -345.771092)
			(xy 430.787529 -345.735379) (xy 430.751815 -345.694164) (xy 430.72233 -345.648285) (xy 430.699674 -345.598677)
			(xy 430.684309 -345.54635) (xy 430.676547 -345.492368) (xy 429.193844 -345.492368) (xy 429.193844 -345.492376)
			(xy 429.18608 -345.546374) (xy 429.170709 -345.598717) (xy 429.148046 -345.648339) (xy 429.11855 -345.694231)
			(xy 429.082823 -345.735457) (xy 429.041592 -345.771179) (xy 428.995697 -345.800669) (xy 428.946072 -345.823326)
			(xy 428.893727 -345.83869) (xy 428.839729 -345.846448) (xy 428.812452 -345.846908) (xy 427.948852 -345.846908)
			(xy 427.921588 -345.846326) (xy 427.867616 -345.83856) (xy 427.815299 -345.823192) (xy 427.765701 -345.800536)
			(xy 427.719831 -345.771053) (xy 427.678624 -345.735342) (xy 427.642919 -345.69413) (xy 427.613441 -345.648257)
			(xy 427.590791 -345.598656) (xy 427.57543 -345.546337) (xy 427.56767 -345.492364) (xy 426.084844 -345.492364)
			(xy 426.084844 -345.492375) (xy 426.077081 -345.546369) (xy 426.061713 -345.598708) (xy 426.039052 -345.648328)
			(xy 426.00956 -345.694218) (xy 425.973837 -345.735443) (xy 425.932611 -345.771165) (xy 425.886721 -345.800656)
			(xy 425.837101 -345.823315) (xy 425.784761 -345.838683) (xy 425.730767 -345.846445) (xy 425.703492 -345.846908)
			(xy 424.839892 -345.846908) (xy 424.812626 -345.846329) (xy 424.75865 -345.838567) (xy 424.706328 -345.823203)
			(xy 424.656725 -345.800549) (xy 424.61085 -345.771067) (xy 424.569638 -345.735356) (xy 424.533928 -345.694143)
			(xy 424.504447 -345.648268) (xy 424.481794 -345.598665) (xy 424.466431 -345.546342) (xy 424.45867 -345.492366)
			(xy 422.975822 -345.492366) (xy 422.975822 -345.492371) (xy 422.96806 -345.546358) (xy 422.952694 -345.598692)
			(xy 422.930038 -345.648306) (xy 422.900551 -345.694191) (xy 422.864835 -345.735412) (xy 422.823616 -345.771132)
			(xy 422.777734 -345.800622) (xy 422.728122 -345.823283) (xy 422.67579 -345.838653) (xy 422.621803 -345.846419)
			(xy 422.594532 -345.846908) (xy 421.730932 -345.846908) (xy 421.703663 -345.846355) (xy 421.649679 -345.838597)
			(xy 421.597349 -345.823236) (xy 421.547738 -345.800583) (xy 421.501855 -345.771099) (xy 421.460636 -345.735386)
			(xy 421.42492 -345.69417) (xy 421.395433 -345.648291) (xy 421.372776 -345.598681) (xy 421.35741 -345.546352)
			(xy 421.349647 -345.492369) (xy 419.866944 -345.492369) (xy 419.866944 -345.492376) (xy 419.859181 -345.546371)
			(xy 419.843811 -345.598713) (xy 419.821149 -345.648334) (xy 419.791655 -345.694224) (xy 419.75593 -345.73545)
			(xy 419.714702 -345.771172) (xy 419.668809 -345.800662) (xy 419.619186 -345.823321) (xy 419.566844 -345.838686)
			(xy 419.512848 -345.846446) (xy 419.485572 -345.846908) (xy 418.621972 -345.846908) (xy 418.594707 -345.846328)
			(xy 418.540733 -345.838564) (xy 418.488413 -345.823198) (xy 418.438813 -345.800543) (xy 418.392941 -345.77106)
			(xy 418.351731 -345.735349) (xy 418.316023 -345.694137) (xy 418.286544 -345.648263) (xy 418.263892 -345.59866)
			(xy 418.24853 -345.546339) (xy 418.24077 -345.492365) (xy 416.757921 -345.492365) (xy 416.757921 -345.492372)
			(xy 416.750159 -345.546361) (xy 416.734793 -345.598696) (xy 416.712135 -345.648311) (xy 416.682646 -345.694197)
			(xy 416.646928 -345.735419) (xy 416.605707 -345.771139) (xy 416.559822 -345.800629) (xy 416.510207 -345.823288)
			(xy 416.457873 -345.838657) (xy 416.403884 -345.846421) (xy 416.376612 -345.846908) (xy 415.513012 -345.846908)
			(xy 415.485744 -345.846353) (xy 415.431762 -345.838594) (xy 415.379434 -345.82323) (xy 415.329826 -345.800576)
			(xy 415.283946 -345.771092) (xy 415.242729 -345.735379) (xy 415.207015 -345.694164) (xy 415.17753 -345.648285)
			(xy 415.154874 -345.598677) (xy 415.139509 -345.54635) (xy 415.131747 -345.492368) (xy 413.649044 -345.492368)
			(xy 413.649044 -345.492376) (xy 413.64128 -345.546374) (xy 413.625909 -345.598717) (xy 413.603246 -345.648339)
			(xy 413.57375 -345.694231) (xy 413.538023 -345.735457) (xy 413.496792 -345.771179) (xy 413.450897 -345.800669)
			(xy 413.401272 -345.823326) (xy 413.348927 -345.83869) (xy 413.294929 -345.846448) (xy 413.267652 -345.846908)
			(xy 412.404052 -345.846908) (xy 412.376788 -345.846326) (xy 412.322816 -345.83856) (xy 412.270499 -345.823192)
			(xy 412.220901 -345.800536) (xy 412.175031 -345.771053) (xy 412.133824 -345.735342) (xy 412.098119 -345.69413)
			(xy 412.068641 -345.648257) (xy 412.045991 -345.598656) (xy 412.03063 -345.546337) (xy 412.02287 -345.492364)
			(xy 410.540044 -345.492364) (xy 410.540044 -345.492375) (xy 410.532281 -345.546369) (xy 410.516913 -345.598708)
			(xy 410.494252 -345.648328) (xy 410.46476 -345.694218) (xy 410.429037 -345.735443) (xy 410.387811 -345.771165)
			(xy 410.341921 -345.800656) (xy 410.292301 -345.823315) (xy 410.239961 -345.838683) (xy 410.185967 -345.846445)
			(xy 410.158692 -345.846908) (xy 409.295092 -345.846908) (xy 409.267826 -345.846329) (xy 409.21385 -345.838567)
			(xy 409.161528 -345.823203) (xy 409.111925 -345.800549) (xy 409.06605 -345.771067) (xy 409.024838 -345.735356)
			(xy 408.989128 -345.694143) (xy 408.959647 -345.648268) (xy 408.936994 -345.598665) (xy 408.921631 -345.546342)
			(xy 408.91387 -345.492366) (xy 403.522544 -345.492366) (xy 403.522544 -345.492375) (xy 403.514781 -345.54637)
			(xy 403.499412 -345.598711) (xy 403.47675 -345.648331) (xy 403.447257 -345.694221) (xy 403.411533 -345.735447)
			(xy 403.370305 -345.771169) (xy 403.324414 -345.800659) (xy 403.274792 -345.823319) (xy 403.222451 -345.838685)
			(xy 403.168455 -345.846446) (xy 403.14118 -345.846908) (xy 402.27758 -345.846908) (xy 402.250315 -345.846328)
			(xy 402.19634 -345.838565) (xy 402.144019 -345.8232) (xy 402.094417 -345.800545) (xy 402.048545 -345.771063)
			(xy 402.007334 -345.735352) (xy 401.971625 -345.694139) (xy 401.942145 -345.648265) (xy 401.919493 -345.598662)
			(xy 401.90413 -345.546341) (xy 401.89637 -345.492365) (xy 400.413522 -345.492365) (xy 400.413522 -345.492372)
			(xy 400.405759 -345.54636) (xy 400.390393 -345.598694) (xy 400.367736 -345.648309) (xy 400.338248 -345.694195)
			(xy 400.302531 -345.735417) (xy 400.261311 -345.771136) (xy 400.215427 -345.800626) (xy 400.165813 -345.823286)
			(xy 400.11348 -345.838655) (xy 400.059492 -345.84642) (xy 400.03222 -345.846908) (xy 399.16862 -345.846908)
			(xy 399.141351 -345.846354) (xy 399.087369 -345.838595) (xy 399.03504 -345.823232) (xy 398.98543 -345.800579)
			(xy 398.93955 -345.771095) (xy 398.898332 -345.735382) (xy 398.862617 -345.694166) (xy 398.833131 -345.648287)
			(xy 398.810475 -345.598679) (xy 398.795109 -345.546351) (xy 398.787347 -345.492369) (xy 397.304644 -345.492369)
			(xy 397.304644 -345.492376) (xy 397.29688 -345.546373) (xy 397.28151 -345.598715) (xy 397.258847 -345.648337)
			(xy 397.229352 -345.694228) (xy 397.193626 -345.735454) (xy 397.152396 -345.771176) (xy 397.106502 -345.800666)
			(xy 397.056878 -345.823324) (xy 397.004534 -345.838689) (xy 396.950536 -345.846447) (xy 396.92326 -345.846908)
			(xy 396.05966 -345.846908) (xy 396.032396 -345.846327) (xy 395.978423 -345.838562) (xy 395.926105 -345.823195)
			(xy 395.876505 -345.800539) (xy 395.830635 -345.771055) (xy 395.789427 -345.735345) (xy 395.753721 -345.694133)
			(xy 395.724242 -345.648259) (xy 395.701591 -345.598658) (xy 395.68623 -345.546338) (xy 395.67847 -345.492364)
			(xy 394.195621 -345.492364) (xy 394.195621 -345.492373) (xy 394.187859 -345.546363) (xy 394.172492 -345.598699)
			(xy 394.149833 -345.648315) (xy 394.120343 -345.694201) (xy 394.084624 -345.735424) (xy 394.043401 -345.771143)
			(xy 393.997515 -345.800633) (xy 393.947899 -345.823292) (xy 393.895563 -345.838659) (xy 393.841573 -345.846421)
			(xy 393.8143 -345.846908) (xy 392.9507 -345.846908) (xy 392.923434 -345.84633) (xy 392.869457 -345.838569)
			(xy 392.817134 -345.823205) (xy 392.767529 -345.800552) (xy 392.721654 -345.77107) (xy 392.680441 -345.735359)
			(xy 392.64473 -345.694146) (xy 392.615248 -345.648271) (xy 392.592595 -345.598666) (xy 392.577231 -345.546343)
			(xy 392.56947 -345.492366) (xy 391.086622 -345.492366) (xy 391.086622 -345.492371) (xy 391.07886 -345.546357)
			(xy 391.063495 -345.59869) (xy 391.040839 -345.648304) (xy 391.011353 -345.694188) (xy 390.975638 -345.73541)
			(xy 390.93442 -345.771129) (xy 390.888539 -345.80062) (xy 390.838928 -345.823281) (xy 390.786597 -345.838651)
			(xy 390.732611 -345.846419) (xy 390.70534 -345.846908) (xy 389.84174 -345.846908) (xy 389.81447 -345.846355)
			(xy 389.760486 -345.838599) (xy 389.708155 -345.823238) (xy 389.658542 -345.800585) (xy 389.612659 -345.771102)
			(xy 389.571439 -345.735389) (xy 389.535722 -345.694173) (xy 389.506234 -345.648293) (xy 389.483576 -345.598683)
			(xy 389.46821 -345.546353) (xy 389.460447 -345.49237) (xy 387.977744 -345.49237) (xy 387.977744 -345.492375)
			(xy 387.969981 -345.54637) (xy 387.954612 -345.598711) (xy 387.93195 -345.648331) (xy 387.902457 -345.694221)
			(xy 387.866733 -345.735447) (xy 387.825505 -345.771169) (xy 387.779614 -345.800659) (xy 387.729992 -345.823319)
			(xy 387.677651 -345.838685) (xy 387.623655 -345.846446) (xy 387.59638 -345.846908) (xy 386.73278 -345.846908)
			(xy 386.705515 -345.846328) (xy 386.65154 -345.838565) (xy 386.599219 -345.8232) (xy 386.549617 -345.800545)
			(xy 386.503745 -345.771063) (xy 386.462534 -345.735352) (xy 386.426825 -345.694139) (xy 386.397345 -345.648265)
			(xy 386.374693 -345.598662) (xy 386.35933 -345.546341) (xy 386.35157 -345.492365) (xy 384.868722 -345.492365)
			(xy 384.868722 -345.492372) (xy 384.860959 -345.54636) (xy 384.845593 -345.598694) (xy 384.822936 -345.648309)
			(xy 384.793448 -345.694195) (xy 384.757731 -345.735417) (xy 384.716511 -345.771136) (xy 384.670627 -345.800626)
			(xy 384.621013 -345.823286) (xy 384.56868 -345.838655) (xy 384.514692 -345.84642) (xy 384.48742 -345.846908)
			(xy 383.62382 -345.846908) (xy 383.596551 -345.846354) (xy 383.542569 -345.838595) (xy 383.49024 -345.823232)
			(xy 383.44063 -345.800579) (xy 383.39475 -345.771095) (xy 383.353532 -345.735382) (xy 383.317817 -345.694166)
			(xy 383.288331 -345.648287) (xy 383.265675 -345.598679) (xy 383.250309 -345.546351) (xy 383.242547 -345.492369)
			(xy 381.759844 -345.492369) (xy 381.759844 -345.492376) (xy 381.75208 -345.546373) (xy 381.73671 -345.598715)
			(xy 381.714047 -345.648337) (xy 381.684552 -345.694228) (xy 381.648826 -345.735454) (xy 381.607596 -345.771176)
			(xy 381.561702 -345.800666) (xy 381.512078 -345.823324) (xy 381.459734 -345.838689) (xy 381.405736 -345.846447)
			(xy 381.37846 -345.846908) (xy 380.51486 -345.846908) (xy 380.487596 -345.846327) (xy 380.433623 -345.838562)
			(xy 380.381305 -345.823195) (xy 380.331705 -345.800539) (xy 380.285835 -345.771055) (xy 380.244627 -345.735345)
			(xy 380.208921 -345.694133) (xy 380.179442 -345.648259) (xy 380.156791 -345.598658) (xy 380.14143 -345.546338)
			(xy 380.13367 -345.492364) (xy 378.650821 -345.492364) (xy 378.650821 -345.492373) (xy 378.643059 -345.546363)
			(xy 378.627692 -345.598699) (xy 378.605033 -345.648315) (xy 378.575543 -345.694201) (xy 378.539824 -345.735424)
			(xy 378.498601 -345.771143) (xy 378.452715 -345.800633) (xy 378.403099 -345.823292) (xy 378.350763 -345.838659)
			(xy 378.296773 -345.846421) (xy 378.2695 -345.846908) (xy 377.4059 -345.846908) (xy 377.378634 -345.84633)
			(xy 377.324657 -345.838569) (xy 377.272334 -345.823205) (xy 377.222729 -345.800552) (xy 377.176854 -345.77107)
			(xy 377.135641 -345.735359) (xy 377.09993 -345.694146) (xy 377.070448 -345.648271) (xy 377.047795 -345.598666)
			(xy 377.032431 -345.546343) (xy 377.02467 -345.492366) (xy 375.541822 -345.492366) (xy 375.541822 -345.492371)
			(xy 375.53406 -345.546357) (xy 375.518695 -345.59869) (xy 375.496039 -345.648304) (xy 375.466553 -345.694188)
			(xy 375.430838 -345.73541) (xy 375.38962 -345.771129) (xy 375.343739 -345.80062) (xy 375.294128 -345.823281)
			(xy 375.241797 -345.838651) (xy 375.187811 -345.846419) (xy 375.16054 -345.846908) (xy 374.29694 -345.846908)
			(xy 374.26967 -345.846355) (xy 374.215686 -345.838599) (xy 374.163355 -345.823238) (xy 374.113742 -345.800585)
			(xy 374.067859 -345.771102) (xy 374.026639 -345.735389) (xy 373.990922 -345.694173) (xy 373.961434 -345.648293)
			(xy 373.938776 -345.598683) (xy 373.92341 -345.546353) (xy 373.915647 -345.49237) (xy 372.432944 -345.49237)
			(xy 372.432944 -345.492375) (xy 372.425181 -345.54637) (xy 372.409812 -345.598711) (xy 372.38715 -345.648331)
			(xy 372.357657 -345.694221) (xy 372.321933 -345.735447) (xy 372.280705 -345.771169) (xy 372.234814 -345.800659)
			(xy 372.185192 -345.823319) (xy 372.132851 -345.838685) (xy 372.078855 -345.846446) (xy 372.05158 -345.846908)
			(xy 371.18798 -345.846908) (xy 371.160715 -345.846328) (xy 371.10674 -345.838565) (xy 371.054419 -345.8232)
			(xy 371.004817 -345.800545) (xy 370.958945 -345.771063) (xy 370.917734 -345.735352) (xy 370.882025 -345.694139)
			(xy 370.852545 -345.648265) (xy 370.829893 -345.598662) (xy 370.81453 -345.546341) (xy 370.80677 -345.492365)
			(xy 344.837321 -345.492365) (xy 344.837321 -345.492372) (xy 344.829559 -345.546362) (xy 344.814192 -345.598698)
			(xy 344.791533 -345.648314) (xy 344.762044 -345.6942) (xy 344.726325 -345.735422) (xy 344.685103 -345.771142)
			(xy 344.639217 -345.800631) (xy 344.589601 -345.823291) (xy 344.537266 -345.838658) (xy 344.483276 -345.846421)
			(xy 344.456004 -345.846908) (xy 343.592404 -345.846908) (xy 343.565136 -345.846353) (xy 343.511155 -345.838592)
			(xy 343.458828 -345.823228) (xy 343.409221 -345.800573) (xy 343.363342 -345.771089) (xy 343.322126 -345.735376)
			(xy 343.286413 -345.694161) (xy 343.256928 -345.648283) (xy 343.234273 -345.598675) (xy 343.218909 -345.546349)
			(xy 343.211147 -345.492368) (xy 341.728322 -345.492368) (xy 341.728322 -345.492371) (xy 341.72056 -345.546357)
			(xy 341.705195 -345.598689) (xy 341.682539 -345.648302) (xy 341.653054 -345.694187) (xy 341.617339 -345.735408)
			(xy 341.576122 -345.771128) (xy 341.530241 -345.800618) (xy 341.48063 -345.82328) (xy 341.4283 -345.838651)
			(xy 341.374315 -345.846418) (xy 341.347044 -345.846908) (xy 340.483444 -345.846908) (xy 340.456174 -345.846356)
			(xy 340.402189 -345.8386) (xy 340.349857 -345.823239) (xy 340.300245 -345.800587) (xy 340.254361 -345.771104)
			(xy 340.213141 -345.735391) (xy 340.177423 -345.694174) (xy 340.147935 -345.648294) (xy 340.125276 -345.598684)
			(xy 340.10991 -345.546354) (xy 340.102148 -345.49237) (xy 338.619444 -345.49237) (xy 338.619444 -345.492375)
			(xy 338.611681 -345.54637) (xy 338.596312 -345.59871) (xy 338.57365 -345.64833) (xy 338.544158 -345.69422)
			(xy 338.508434 -345.735446) (xy 338.467207 -345.771167) (xy 338.421316 -345.800658) (xy 338.371695 -345.823318)
			(xy 338.319354 -345.838684) (xy 338.265359 -345.846445) (xy 338.238084 -345.846908) (xy 337.374484 -345.846908)
			(xy 337.347219 -345.846329) (xy 337.293243 -345.838566) (xy 337.240922 -345.823201) (xy 337.19132 -345.800547)
			(xy 337.145446 -345.771064) (xy 337.104236 -345.735353) (xy 337.068526 -345.694141) (xy 337.039046 -345.648266)
			(xy 337.016393 -345.598663) (xy 337.001031 -345.546341) (xy 336.99327 -345.492365) (xy 335.510422 -345.492365)
			(xy 335.510422 -345.492372) (xy 335.50266 -345.54636) (xy 335.487294 -345.598693) (xy 335.464636 -345.648308)
			(xy 335.435149 -345.694193) (xy 335.399432 -345.735415) (xy 335.358213 -345.771135) (xy 335.312329 -345.800625)
			(xy 335.262716 -345.823285) (xy 335.210383 -345.838654) (xy 335.156396 -345.84642) (xy 335.129124 -345.846908)
			(xy 334.265524 -345.846908) (xy 334.238255 -345.846354) (xy 334.184272 -345.838596) (xy 334.131943 -345.823234)
			(xy 334.082333 -345.80058) (xy 334.036452 -345.771097) (xy 333.995234 -345.735383) (xy 333.959518 -345.694168)
			(xy 333.930031 -345.648288) (xy 333.907375 -345.59868) (xy 333.892009 -345.546351) (xy 333.884247 -345.492369)
			(xy 332.401544 -345.492369) (xy 332.401544 -345.492376) (xy 332.39378 -345.546372) (xy 332.37841 -345.598714)
			(xy 332.355747 -345.648336) (xy 332.326253 -345.694227) (xy 332.290527 -345.735453) (xy 332.249298 -345.771174)
			(xy 332.203404 -345.800665) (xy 332.153781 -345.823323) (xy 332.101437 -345.838688) (xy 332.04744 -345.846447)
			(xy 332.020164 -345.846908) (xy 331.156564 -345.846908) (xy 331.1293 -345.846327) (xy 331.075326 -345.838562)
			(xy 331.023007 -345.823196) (xy 330.973408 -345.80054) (xy 330.927537 -345.771057) (xy 330.886329 -345.735346)
			(xy 330.850622 -345.694134) (xy 330.821143 -345.648261) (xy 330.798492 -345.598659) (xy 330.78313 -345.546338)
			(xy 330.77537 -345.492364) (xy 329.292521 -345.492364) (xy 329.292521 -345.492372) (xy 329.284759 -345.546362)
			(xy 329.269392 -345.598698) (xy 329.246733 -345.648314) (xy 329.217244 -345.6942) (xy 329.181525 -345.735422)
			(xy 329.140303 -345.771142) (xy 329.094417 -345.800631) (xy 329.044801 -345.823291) (xy 328.992466 -345.838658)
			(xy 328.938476 -345.846421) (xy 328.911204 -345.846908) (xy 328.047604 -345.846908) (xy 328.020336 -345.846353)
			(xy 327.966355 -345.838592) (xy 327.914028 -345.823228) (xy 327.864421 -345.800573) (xy 327.818542 -345.771089)
			(xy 327.777326 -345.735376) (xy 327.741613 -345.694161) (xy 327.712128 -345.648283) (xy 327.689473 -345.598675)
			(xy 327.674109 -345.546349) (xy 327.666347 -345.492368) (xy 326.183522 -345.492368) (xy 326.183522 -345.492371)
			(xy 326.17576 -345.546357) (xy 326.160395 -345.598689) (xy 326.137739 -345.648302) (xy 326.108254 -345.694187)
			(xy 326.072539 -345.735408) (xy 326.031322 -345.771128) (xy 325.985441 -345.800618) (xy 325.93583 -345.82328)
			(xy 325.8835 -345.838651) (xy 325.829515 -345.846418) (xy 325.802244 -345.846908) (xy 324.938644 -345.846908)
			(xy 324.911374 -345.846356) (xy 324.857389 -345.8386) (xy 324.805057 -345.823239) (xy 324.755445 -345.800587)
			(xy 324.709561 -345.771104) (xy 324.668341 -345.735391) (xy 324.632623 -345.694174) (xy 324.603135 -345.648294)
			(xy 324.580476 -345.598684) (xy 324.56511 -345.546354) (xy 324.557348 -345.49237) (xy 323.074644 -345.49237)
			(xy 323.074644 -345.492375) (xy 323.066881 -345.54637) (xy 323.051512 -345.59871) (xy 323.02885 -345.64833)
			(xy 322.999358 -345.69422) (xy 322.963634 -345.735446) (xy 322.922407 -345.771167) (xy 322.876516 -345.800658)
			(xy 322.826895 -345.823318) (xy 322.774554 -345.838684) (xy 322.720559 -345.846445) (xy 322.693284 -345.846908)
			(xy 321.829684 -345.846908) (xy 321.802419 -345.846329) (xy 321.748443 -345.838566) (xy 321.696122 -345.823201)
			(xy 321.64652 -345.800547) (xy 321.600646 -345.771064) (xy 321.559436 -345.735353) (xy 321.523726 -345.694141)
			(xy 321.494246 -345.648266) (xy 321.471593 -345.598663) (xy 321.456231 -345.546341) (xy 321.44847 -345.492365)
			(xy 319.965622 -345.492365) (xy 319.965622 -345.492372) (xy 319.95786 -345.54636) (xy 319.942494 -345.598693)
			(xy 319.919836 -345.648308) (xy 319.890349 -345.694193) (xy 319.854632 -345.735415) (xy 319.813413 -345.771135)
			(xy 319.767529 -345.800625) (xy 319.717916 -345.823285) (xy 319.665583 -345.838654) (xy 319.611596 -345.84642)
			(xy 319.584324 -345.846908) (xy 318.720724 -345.846908) (xy 318.693455 -345.846354) (xy 318.639472 -345.838596)
			(xy 318.587143 -345.823234) (xy 318.537533 -345.80058) (xy 318.491652 -345.771097) (xy 318.450434 -345.735383)
			(xy 318.414718 -345.694168) (xy 318.385231 -345.648288) (xy 318.362575 -345.59868) (xy 318.347209 -345.546351)
			(xy 318.339447 -345.492369) (xy 316.856744 -345.492369) (xy 316.856744 -345.492376) (xy 316.84898 -345.546372)
			(xy 316.83361 -345.598714) (xy 316.810947 -345.648336) (xy 316.781453 -345.694227) (xy 316.745727 -345.735453)
			(xy 316.704498 -345.771174) (xy 316.658604 -345.800665) (xy 316.608981 -345.823323) (xy 316.556637 -345.838688)
			(xy 316.50264 -345.846447) (xy 316.475364 -345.846908) (xy 315.611764 -345.846908) (xy 315.5845 -345.846327)
			(xy 315.530526 -345.838562) (xy 315.478207 -345.823196) (xy 315.428608 -345.80054) (xy 315.382737 -345.771057)
			(xy 315.341529 -345.735346) (xy 315.305822 -345.694134) (xy 315.276343 -345.648261) (xy 315.253692 -345.598659)
			(xy 315.23833 -345.546338) (xy 315.23057 -345.492364) (xy 313.747721 -345.492364) (xy 313.747721 -345.492372)
			(xy 313.739959 -345.546362) (xy 313.724592 -345.598698) (xy 313.701933 -345.648314) (xy 313.672444 -345.6942)
			(xy 313.636725 -345.735422) (xy 313.595503 -345.771142) (xy 313.549617 -345.800631) (xy 313.500001 -345.823291)
			(xy 313.447666 -345.838658) (xy 313.393676 -345.846421) (xy 313.366404 -345.846908) (xy 312.502804 -345.846908)
			(xy 312.475536 -345.846353) (xy 312.421555 -345.838592) (xy 312.369228 -345.823228) (xy 312.319621 -345.800573)
			(xy 312.273742 -345.771089) (xy 312.232526 -345.735376) (xy 312.196813 -345.694161) (xy 312.167328 -345.648283)
			(xy 312.144673 -345.598675) (xy 312.129309 -345.546349) (xy 312.121547 -345.492368) (xy 300.231621 -345.492368)
			(xy 300.231621 -345.492373) (xy 300.223859 -345.546362) (xy 300.208492 -345.598698) (xy 300.185833 -345.648314)
			(xy 300.156344 -345.6942) (xy 300.120624 -345.735423) (xy 300.079402 -345.771143) (xy 300.033516 -345.800632)
			(xy 299.9839 -345.823291) (xy 299.931564 -345.838658) (xy 299.877575 -345.846421) (xy 299.850302 -345.846908)
			(xy 298.986702 -345.846908) (xy 298.959434 -345.846353) (xy 298.905454 -345.838592) (xy 298.853127 -345.823228)
			(xy 298.80352 -345.800573) (xy 298.757641 -345.771089) (xy 298.716426 -345.735376) (xy 298.680712 -345.69416)
			(xy 298.651228 -345.648282) (xy 298.628573 -345.598675) (xy 298.613209 -345.546348) (xy 298.605447 -345.492368)
			(xy 297.122622 -345.492368) (xy 297.122622 -345.492371) (xy 297.11486 -345.546357) (xy 297.099495 -345.59869)
			(xy 297.076839 -345.648303) (xy 297.047354 -345.694187) (xy 297.011639 -345.735409) (xy 296.970421 -345.771128)
			(xy 296.92454 -345.800619) (xy 296.874929 -345.82328) (xy 296.822598 -345.838651) (xy 296.768613 -345.846419)
			(xy 296.741342 -345.846908) (xy 295.877742 -345.846908) (xy 295.850472 -345.846355) (xy 295.796487 -345.838599)
			(xy 295.744156 -345.823238) (xy 295.694543 -345.800586) (xy 295.64866 -345.771103) (xy 295.60744 -345.73539)
			(xy 295.571722 -345.694174) (xy 295.542234 -345.648293) (xy 295.519576 -345.598683) (xy 295.50421 -345.546354)
			(xy 295.496448 -345.49237) (xy 294.013744 -345.49237) (xy 294.013744 -345.492375) (xy 294.005981 -345.54637)
			(xy 293.990612 -345.59871) (xy 293.96795 -345.648331) (xy 293.938457 -345.694221) (xy 293.902734 -345.735446)
			(xy 293.861506 -345.771168) (xy 293.815615 -345.800659) (xy 293.765994 -345.823318) (xy 293.713652 -345.838685)
			(xy 293.659657 -345.846446) (xy 293.632382 -345.846908) (xy 292.768782 -345.846908) (xy 292.741517 -345.846328)
			(xy 292.687542 -345.838566) (xy 292.635221 -345.823201) (xy 292.585619 -345.800546) (xy 292.539745 -345.771063)
			(xy 292.498535 -345.735352) (xy 292.462826 -345.69414) (xy 292.433345 -345.648266) (xy 292.410693 -345.598663)
			(xy 292.395331 -345.546341) (xy 292.38757 -345.492365) (xy 290.904722 -345.492365) (xy 290.904722 -345.492372)
			(xy 290.896959 -345.54636) (xy 290.881593 -345.598694) (xy 290.858936 -345.648309) (xy 290.829449 -345.694194)
			(xy 290.793732 -345.735416) (xy 290.752512 -345.771136) (xy 290.706628 -345.800626) (xy 290.657015 -345.823286)
			(xy 290.604681 -345.838655) (xy 290.550694 -345.84642) (xy 290.523422 -345.846908) (xy 289.659822 -345.846908)
			(xy 289.632553 -345.846354) (xy 289.57857 -345.838595) (xy 289.526241 -345.823233) (xy 289.476632 -345.800579)
			(xy 289.430751 -345.771096) (xy 289.389533 -345.735383) (xy 289.353817 -345.694167) (xy 289.324331 -345.648288)
			(xy 289.301675 -345.598679) (xy 289.286309 -345.546351) (xy 289.278547 -345.492369) (xy 287.795844 -345.492369)
			(xy 287.795844 -345.492376) (xy 287.78808 -345.546373) (xy 287.77271 -345.598715) (xy 287.750047 -345.648336)
			(xy 287.720552 -345.694227) (xy 287.684827 -345.735453) (xy 287.643597 -345.771175) (xy 287.597703 -345.800665)
			(xy 287.548079 -345.823323) (xy 287.495736 -345.838688) (xy 287.441738 -345.846447) (xy 287.414462 -345.846908)
			(xy 286.550862 -345.846908) (xy 286.523598 -345.846327) (xy 286.469625 -345.838562) (xy 286.417306 -345.823195)
			(xy 286.367707 -345.80054) (xy 286.321836 -345.771056) (xy 286.280628 -345.735345) (xy 286.244921 -345.694134)
			(xy 286.215442 -345.64826) (xy 286.192792 -345.598658) (xy 286.17743 -345.546338) (xy 286.16967 -345.492364)
			(xy 284.686821 -345.492364) (xy 284.686821 -345.492373) (xy 284.679059 -345.546362) (xy 284.663692 -345.598698)
			(xy 284.641033 -345.648314) (xy 284.611544 -345.6942) (xy 284.575824 -345.735423) (xy 284.534602 -345.771143)
			(xy 284.488716 -345.800632) (xy 284.4391 -345.823291) (xy 284.386764 -345.838658) (xy 284.332775 -345.846421)
			(xy 284.305502 -345.846908) (xy 283.441902 -345.846908) (xy 283.414634 -345.846353) (xy 283.360654 -345.838592)
			(xy 283.308327 -345.823228) (xy 283.25872 -345.800573) (xy 283.212841 -345.771089) (xy 283.171626 -345.735376)
			(xy 283.135912 -345.69416) (xy 283.106428 -345.648282) (xy 283.083773 -345.598675) (xy 283.068409 -345.546348)
			(xy 283.060647 -345.492368) (xy 281.577822 -345.492368) (xy 281.577822 -345.492371) (xy 281.57006 -345.546357)
			(xy 281.554695 -345.59869) (xy 281.532039 -345.648303) (xy 281.502554 -345.694187) (xy 281.466839 -345.735409)
			(xy 281.425621 -345.771128) (xy 281.37974 -345.800619) (xy 281.330129 -345.82328) (xy 281.277798 -345.838651)
			(xy 281.223813 -345.846419) (xy 281.196542 -345.846908) (xy 280.332942 -345.846908) (xy 280.305672 -345.846355)
			(xy 280.251687 -345.838599) (xy 280.199356 -345.823238) (xy 280.149743 -345.800586) (xy 280.10386 -345.771103)
			(xy 280.06264 -345.73539) (xy 280.026922 -345.694174) (xy 279.997434 -345.648293) (xy 279.974776 -345.598683)
			(xy 279.95941 -345.546354) (xy 279.951648 -345.49237) (xy 278.468944 -345.49237) (xy 278.468944 -345.492375)
			(xy 278.461181 -345.54637) (xy 278.445812 -345.59871) (xy 278.42315 -345.648331) (xy 278.393657 -345.694221)
			(xy 278.357934 -345.735446) (xy 278.316706 -345.771168) (xy 278.270815 -345.800659) (xy 278.221194 -345.823318)
			(xy 278.168852 -345.838685) (xy 278.114857 -345.846446) (xy 278.087582 -345.846908) (xy 277.223982 -345.846908)
			(xy 277.196717 -345.846328) (xy 277.142742 -345.838566) (xy 277.090421 -345.823201) (xy 277.040819 -345.800546)
			(xy 276.994945 -345.771063) (xy 276.953735 -345.735352) (xy 276.918026 -345.69414) (xy 276.888545 -345.648266)
			(xy 276.865893 -345.598663) (xy 276.850531 -345.546341) (xy 276.84277 -345.492365) (xy 275.359922 -345.492365)
			(xy 275.359922 -345.492372) (xy 275.352159 -345.54636) (xy 275.336793 -345.598694) (xy 275.314136 -345.648309)
			(xy 275.284649 -345.694194) (xy 275.248932 -345.735416) (xy 275.207712 -345.771136) (xy 275.161828 -345.800626)
			(xy 275.112215 -345.823286) (xy 275.059881 -345.838655) (xy 275.005894 -345.84642) (xy 274.978622 -345.846908)
			(xy 274.115022 -345.846908) (xy 274.087753 -345.846354) (xy 274.03377 -345.838595) (xy 273.981441 -345.823233)
			(xy 273.931832 -345.800579) (xy 273.885951 -345.771096) (xy 273.844733 -345.735383) (xy 273.809017 -345.694167)
			(xy 273.779531 -345.648288) (xy 273.756875 -345.598679) (xy 273.741509 -345.546351) (xy 273.733747 -345.492369)
			(xy 272.251044 -345.492369) (xy 272.251044 -345.492376) (xy 272.24328 -345.546373) (xy 272.22791 -345.598715)
			(xy 272.205247 -345.648336) (xy 272.175752 -345.694227) (xy 272.140027 -345.735453) (xy 272.098797 -345.771175)
			(xy 272.052903 -345.800665) (xy 272.003279 -345.823323) (xy 271.950936 -345.838688) (xy 271.896938 -345.846447)
			(xy 271.869662 -345.846908) (xy 271.006062 -345.846908) (xy 270.978798 -345.846327) (xy 270.924825 -345.838562)
			(xy 270.872506 -345.823195) (xy 270.822907 -345.80054) (xy 270.777036 -345.771056) (xy 270.735828 -345.735345)
			(xy 270.700121 -345.694134) (xy 270.670642 -345.64826) (xy 270.647992 -345.598658) (xy 270.63263 -345.546338)
			(xy 270.62487 -345.492364) (xy 269.142021 -345.492364) (xy 269.142021 -345.492373) (xy 269.134259 -345.546362)
			(xy 269.118892 -345.598698) (xy 269.096233 -345.648314) (xy 269.066744 -345.6942) (xy 269.031024 -345.735423)
			(xy 268.989802 -345.771143) (xy 268.943916 -345.800632) (xy 268.8943 -345.823291) (xy 268.841964 -345.838658)
			(xy 268.787975 -345.846421) (xy 268.760702 -345.846908) (xy 267.897102 -345.846908) (xy 267.869834 -345.846353)
			(xy 267.815854 -345.838592) (xy 267.763527 -345.823228) (xy 267.71392 -345.800573) (xy 267.668041 -345.771089)
			(xy 267.626826 -345.735376) (xy 267.591112 -345.69416) (xy 267.561628 -345.648282) (xy 267.538973 -345.598675)
			(xy 267.523609 -345.546348) (xy 267.515847 -345.492368) (xy 197.629644 -345.492368) (xy 197.629644 -345.492376)
			(xy 197.621881 -345.546371) (xy 197.606511 -345.598713) (xy 197.583849 -345.648334) (xy 197.554355 -345.694224)
			(xy 197.51863 -345.73545) (xy 197.477402 -345.771172) (xy 197.431509 -345.800662) (xy 197.381886 -345.823321)
			(xy 197.329544 -345.838686) (xy 197.275548 -345.846446) (xy 197.248272 -345.846908) (xy 196.384672 -345.846908)
			(xy 196.357407 -345.846328) (xy 196.303433 -345.838564) (xy 196.251113 -345.823198) (xy 196.201513 -345.800543)
			(xy 196.155641 -345.77106) (xy 196.114431 -345.735349) (xy 196.078723 -345.694137) (xy 196.049244 -345.648263)
			(xy 196.026592 -345.59866) (xy 196.01123 -345.546339) (xy 196.00347 -345.492365) (xy 194.520621 -345.492365)
			(xy 194.520621 -345.492372) (xy 194.512859 -345.546361) (xy 194.497493 -345.598696) (xy 194.474835 -345.648311)
			(xy 194.445346 -345.694197) (xy 194.409628 -345.735419) (xy 194.368407 -345.771139) (xy 194.322522 -345.800629)
			(xy 194.272907 -345.823288) (xy 194.220573 -345.838657) (xy 194.166584 -345.846421) (xy 194.139312 -345.846908)
			(xy 193.275712 -345.846908) (xy 193.248444 -345.846353) (xy 193.194462 -345.838594) (xy 193.142134 -345.82323)
			(xy 193.092526 -345.800576) (xy 193.046646 -345.771092) (xy 193.005429 -345.735379) (xy 192.969715 -345.694164)
			(xy 192.94023 -345.648285) (xy 192.917574 -345.598677) (xy 192.902209 -345.54635) (xy 192.894447 -345.492368)
			(xy 191.411744 -345.492368) (xy 191.411744 -345.492376) (xy 191.40398 -345.546374) (xy 191.388609 -345.598717)
			(xy 191.365946 -345.648339) (xy 191.33645 -345.694231) (xy 191.300723 -345.735457) (xy 191.259492 -345.771179)
			(xy 191.213597 -345.800669) (xy 191.163972 -345.823326) (xy 191.111627 -345.83869) (xy 191.057629 -345.846448)
			(xy 191.030352 -345.846908) (xy 190.166752 -345.846908) (xy 190.139488 -345.846326) (xy 190.085516 -345.83856)
			(xy 190.033199 -345.823192) (xy 189.983601 -345.800536) (xy 189.937731 -345.771053) (xy 189.896524 -345.735342)
			(xy 189.860819 -345.69413) (xy 189.831341 -345.648257) (xy 189.808691 -345.598656) (xy 189.79333 -345.546337)
			(xy 189.78557 -345.492364) (xy 188.302744 -345.492364) (xy 188.302744 -345.492375) (xy 188.294981 -345.546369)
			(xy 188.279613 -345.598708) (xy 188.256952 -345.648328) (xy 188.22746 -345.694218) (xy 188.191737 -345.735443)
			(xy 188.150511 -345.771165) (xy 188.104621 -345.800656) (xy 188.055001 -345.823315) (xy 188.002661 -345.838683)
			(xy 187.948667 -345.846445) (xy 187.921392 -345.846908) (xy 187.057792 -345.846908) (xy 187.030526 -345.846329)
			(xy 186.97655 -345.838567) (xy 186.924228 -345.823203) (xy 186.874625 -345.800549) (xy 186.82875 -345.771067)
			(xy 186.787538 -345.735356) (xy 186.751828 -345.694143) (xy 186.722347 -345.648268) (xy 186.699694 -345.598665)
			(xy 186.684331 -345.546342) (xy 186.67657 -345.492366) (xy 185.193722 -345.492366) (xy 185.193722 -345.492371)
			(xy 185.18596 -345.546358) (xy 185.170594 -345.598692) (xy 185.147938 -345.648306) (xy 185.118451 -345.694191)
			(xy 185.082735 -345.735412) (xy 185.041516 -345.771132) (xy 184.995634 -345.800622) (xy 184.946022 -345.823283)
			(xy 184.89369 -345.838653) (xy 184.839703 -345.846419) (xy 184.812432 -345.846908) (xy 183.948832 -345.846908)
			(xy 183.921563 -345.846355) (xy 183.867579 -345.838597) (xy 183.815249 -345.823236) (xy 183.765638 -345.800583)
			(xy 183.719755 -345.771099) (xy 183.678536 -345.735386) (xy 183.64282 -345.69417) (xy 183.613333 -345.648291)
			(xy 183.590676 -345.598681) (xy 183.57531 -345.546352) (xy 183.567547 -345.492369) (xy 182.084844 -345.492369)
			(xy 182.084844 -345.492376) (xy 182.077081 -345.546371) (xy 182.061711 -345.598713) (xy 182.039049 -345.648334)
			(xy 182.009555 -345.694224) (xy 181.97383 -345.73545) (xy 181.932602 -345.771172) (xy 181.886709 -345.800662)
			(xy 181.837086 -345.823321) (xy 181.784744 -345.838686) (xy 181.730748 -345.846446) (xy 181.703472 -345.846908)
			(xy 180.839872 -345.846908) (xy 180.812607 -345.846328) (xy 180.758633 -345.838564) (xy 180.706313 -345.823198)
			(xy 180.656713 -345.800543) (xy 180.610841 -345.77106) (xy 180.569631 -345.735349) (xy 180.533923 -345.694137)
			(xy 180.504444 -345.648263) (xy 180.481792 -345.59866) (xy 180.46643 -345.546339) (xy 180.45867 -345.492365)
			(xy 178.975821 -345.492365) (xy 178.975821 -345.492372) (xy 178.968059 -345.546361) (xy 178.952693 -345.598696)
			(xy 178.930035 -345.648311) (xy 178.900546 -345.694197) (xy 178.864828 -345.735419) (xy 178.823607 -345.771139)
			(xy 178.777722 -345.800629) (xy 178.728107 -345.823288) (xy 178.675773 -345.838657) (xy 178.621784 -345.846421)
			(xy 178.594512 -345.846908) (xy 177.730912 -345.846908) (xy 177.703644 -345.846353) (xy 177.649662 -345.838594)
			(xy 177.597334 -345.82323) (xy 177.547726 -345.800576) (xy 177.501846 -345.771092) (xy 177.460629 -345.735379)
			(xy 177.424915 -345.694164) (xy 177.39543 -345.648285) (xy 177.372774 -345.598677) (xy 177.357409 -345.54635)
			(xy 177.349647 -345.492368) (xy 175.866944 -345.492368) (xy 175.866944 -345.492376) (xy 175.85918 -345.546374)
			(xy 175.843809 -345.598717) (xy 175.821146 -345.648339) (xy 175.79165 -345.694231) (xy 175.755923 -345.735457)
			(xy 175.714692 -345.771179) (xy 175.668797 -345.800669) (xy 175.619172 -345.823326) (xy 175.566827 -345.83869)
			(xy 175.512829 -345.846448) (xy 175.485552 -345.846908) (xy 174.621952 -345.846908) (xy 174.594688 -345.846326)
			(xy 174.540716 -345.83856) (xy 174.488399 -345.823192) (xy 174.438801 -345.800536) (xy 174.392931 -345.771053)
			(xy 174.351724 -345.735342) (xy 174.316019 -345.69413) (xy 174.286541 -345.648257) (xy 174.263891 -345.598656)
			(xy 174.24853 -345.546337) (xy 174.24077 -345.492364) (xy 172.757944 -345.492364) (xy 172.757944 -345.492375)
			(xy 172.750181 -345.546369) (xy 172.734813 -345.598708) (xy 172.712152 -345.648328) (xy 172.68266 -345.694218)
			(xy 172.646937 -345.735443) (xy 172.605711 -345.771165) (xy 172.559821 -345.800656) (xy 172.510201 -345.823315)
			(xy 172.457861 -345.838683) (xy 172.403867 -345.846445) (xy 172.376592 -345.846908) (xy 171.512992 -345.846908)
			(xy 171.485726 -345.846329) (xy 171.43175 -345.838567) (xy 171.379428 -345.823203) (xy 171.329825 -345.800549)
			(xy 171.28395 -345.771067) (xy 171.242738 -345.735356) (xy 171.207028 -345.694143) (xy 171.177547 -345.648268)
			(xy 171.154894 -345.598665) (xy 171.139531 -345.546342) (xy 171.13177 -345.492366) (xy 169.648922 -345.492366)
			(xy 169.648922 -345.492371) (xy 169.64116 -345.546358) (xy 169.625794 -345.598692) (xy 169.603138 -345.648306)
			(xy 169.573651 -345.694191) (xy 169.537935 -345.735412) (xy 169.496716 -345.771132) (xy 169.450834 -345.800622)
			(xy 169.401222 -345.823283) (xy 169.34889 -345.838653) (xy 169.294903 -345.846419) (xy 169.267632 -345.846908)
			(xy 168.404032 -345.846908) (xy 168.376763 -345.846355) (xy 168.322779 -345.838597) (xy 168.270449 -345.823236)
			(xy 168.220838 -345.800583) (xy 168.174955 -345.771099) (xy 168.133736 -345.735386) (xy 168.09802 -345.69417)
			(xy 168.068533 -345.648291) (xy 168.045876 -345.598681) (xy 168.03051 -345.546352) (xy 168.022747 -345.492369)
			(xy 166.540044 -345.492369) (xy 166.540044 -345.492376) (xy 166.532281 -345.546371) (xy 166.516911 -345.598713)
			(xy 166.494249 -345.648334) (xy 166.464755 -345.694224) (xy 166.42903 -345.73545) (xy 166.387802 -345.771172)
			(xy 166.341909 -345.800662) (xy 166.292286 -345.823321) (xy 166.239944 -345.838686) (xy 166.185948 -345.846446)
			(xy 166.158672 -345.846908) (xy 165.295072 -345.846908) (xy 165.267807 -345.846328) (xy 165.213833 -345.838564)
			(xy 165.161513 -345.823198) (xy 165.111913 -345.800543) (xy 165.066041 -345.77106) (xy 165.024831 -345.735349)
			(xy 164.989123 -345.694137) (xy 164.959644 -345.648263) (xy 164.936992 -345.59866) (xy 164.92163 -345.546339)
			(xy 164.91387 -345.492365) (xy 144.196621 -345.492365) (xy 144.196621 -345.492372) (xy 144.188859 -345.546362)
			(xy 144.173492 -345.598697) (xy 144.150834 -345.648312) (xy 144.121345 -345.694199) (xy 144.085627 -345.735421)
			(xy 144.044405 -345.77114) (xy 143.99852 -345.80063) (xy 143.948904 -345.82329) (xy 143.89657 -345.838657)
			(xy 143.84258 -345.846421) (xy 143.815308 -345.846908) (xy 142.951708 -345.846908) (xy 142.92444 -345.846353)
			(xy 142.870459 -345.838593) (xy 142.818131 -345.823229) (xy 142.768523 -345.800575) (xy 142.722644 -345.771091)
			(xy 142.681428 -345.735378) (xy 142.645714 -345.694162) (xy 142.616229 -345.648284) (xy 142.593574 -345.598676)
			(xy 142.578209 -345.546349) (xy 142.570447 -345.492368) (xy 141.087622 -345.492368) (xy 141.087622 -345.49237)
			(xy 141.07986 -345.546356) (xy 141.064495 -345.598688) (xy 141.04184 -345.648301) (xy 141.012355 -345.694185)
			(xy 140.976641 -345.735407) (xy 140.935424 -345.771126) (xy 140.889543 -345.800617) (xy 140.839933 -345.823279)
			(xy 140.787603 -345.83865) (xy 140.733618 -345.846418) (xy 140.706348 -345.846908) (xy 139.842748 -345.846908)
			(xy 139.815478 -345.846356) (xy 139.761492 -345.8386) (xy 139.70916 -345.82324) (xy 139.659547 -345.800588)
			(xy 139.613663 -345.771105) (xy 139.572442 -345.735392) (xy 139.536724 -345.694176) (xy 139.507235 -345.648295)
			(xy 139.484577 -345.598685) (xy 139.46921 -345.546354) (xy 139.461448 -345.49237) (xy 137.978744 -345.49237)
			(xy 137.978744 -345.492375) (xy 137.970981 -345.546369) (xy 137.955612 -345.598709) (xy 137.932951 -345.648329)
			(xy 137.903459 -345.694219) (xy 137.867736 -345.735444) (xy 137.826509 -345.771166) (xy 137.780619 -345.800657)
			(xy 137.730998 -345.823316) (xy 137.678658 -345.838684) (xy 137.624663 -345.846445) (xy 137.597388 -345.846908)
			(xy 136.733788 -345.846908) (xy 136.706522 -345.846329) (xy 136.652547 -345.838567) (xy 136.600225 -345.823202)
			(xy 136.550622 -345.800548) (xy 136.504748 -345.771065) (xy 136.463537 -345.735354) (xy 136.427827 -345.694142)
			(xy 136.398346 -345.648267) (xy 136.375694 -345.598664) (xy 136.360331 -345.546342) (xy 136.35257 -345.492366)
			(xy 134.869722 -345.492366) (xy 134.869722 -345.492371) (xy 134.86196 -345.546359) (xy 134.846594 -345.598693)
			(xy 134.823937 -345.648307) (xy 134.79445 -345.694192) (xy 134.758734 -345.735414) (xy 134.717514 -345.771133)
			(xy 134.671632 -345.800624) (xy 134.622019 -345.823284) (xy 134.569686 -345.838654) (xy 134.515699 -345.84642)
			(xy 134.488428 -345.846908) (xy 133.624828 -345.846908) (xy 133.597559 -345.846355) (xy 133.543576 -345.838597)
			(xy 133.491246 -345.823235) (xy 133.441635 -345.800581) (xy 133.395753 -345.771098) (xy 133.354535 -345.735385)
			(xy 133.318819 -345.694169) (xy 133.289332 -345.648289) (xy 133.266675 -345.59868) (xy 133.251309 -345.546352)
			(xy 133.243547 -345.492369) (xy 131.760844 -345.492369) (xy 131.760844 -345.492376) (xy 131.75308 -345.546372)
			(xy 131.737711 -345.598713) (xy 131.715048 -345.648335) (xy 131.685554 -345.694225) (xy 131.649829 -345.735451)
			(xy 131.6086 -345.771173) (xy 131.562707 -345.800663) (xy 131.513083 -345.823322) (xy 131.460741 -345.838687)
			(xy 131.406744 -345.846447) (xy 131.379468 -345.846908) (xy 130.515868 -345.846908) (xy 130.488603 -345.846328)
			(xy 130.43463 -345.838563) (xy 130.38231 -345.823197) (xy 130.33271 -345.800542) (xy 130.286839 -345.771058)
			(xy 130.24563 -345.735347) (xy 130.209922 -345.694136) (xy 130.180443 -345.648262) (xy 130.157792 -345.59866)
			(xy 130.14243 -345.546339) (xy 130.13467 -345.492365) (xy 128.651821 -345.492365) (xy 128.651821 -345.492372)
			(xy 128.644059 -345.546362) (xy 128.628692 -345.598697) (xy 128.606034 -345.648312) (xy 128.576545 -345.694199)
			(xy 128.540827 -345.735421) (xy 128.499605 -345.77114) (xy 128.45372 -345.80063) (xy 128.404104 -345.82329)
			(xy 128.35177 -345.838657) (xy 128.29778 -345.846421) (xy 128.270508 -345.846908) (xy 127.406908 -345.846908)
			(xy 127.37964 -345.846353) (xy 127.325659 -345.838593) (xy 127.273331 -345.823229) (xy 127.223723 -345.800575)
			(xy 127.177844 -345.771091) (xy 127.136628 -345.735378) (xy 127.100914 -345.694162) (xy 127.071429 -345.648284)
			(xy 127.048774 -345.598676) (xy 127.033409 -345.546349) (xy 127.025647 -345.492368) (xy 125.542822 -345.492368)
			(xy 125.542822 -345.49237) (xy 125.53506 -345.546356) (xy 125.519695 -345.598688) (xy 125.49704 -345.648301)
			(xy 125.467555 -345.694185) (xy 125.431841 -345.735407) (xy 125.390624 -345.771126) (xy 125.344743 -345.800617)
			(xy 125.295133 -345.823279) (xy 125.242803 -345.83865) (xy 125.188818 -345.846418) (xy 125.161548 -345.846908)
			(xy 124.297948 -345.846908) (xy 124.270678 -345.846356) (xy 124.216692 -345.8386) (xy 124.16436 -345.82324)
			(xy 124.114747 -345.800588) (xy 124.068863 -345.771105) (xy 124.027642 -345.735392) (xy 123.991924 -345.694176)
			(xy 123.962435 -345.648295) (xy 123.939777 -345.598685) (xy 123.92441 -345.546354) (xy 123.916648 -345.49237)
			(xy 122.433944 -345.49237) (xy 122.433944 -345.492375) (xy 122.426181 -345.546369) (xy 122.410812 -345.598709)
			(xy 122.388151 -345.648329) (xy 122.358659 -345.694219) (xy 122.322936 -345.735444) (xy 122.281709 -345.771166)
			(xy 122.235819 -345.800657) (xy 122.186198 -345.823316) (xy 122.133858 -345.838684) (xy 122.079863 -345.846445)
			(xy 122.052588 -345.846908) (xy 121.188988 -345.846908) (xy 121.161722 -345.846329) (xy 121.107747 -345.838567)
			(xy 121.055425 -345.823202) (xy 121.005822 -345.800548) (xy 120.959948 -345.771065) (xy 120.918737 -345.735354)
			(xy 120.883027 -345.694142) (xy 120.853546 -345.648267) (xy 120.830894 -345.598664) (xy 120.815531 -345.546342)
			(xy 120.80777 -345.492366) (xy 119.324922 -345.492366) (xy 119.324922 -345.492371) (xy 119.31716 -345.546359)
			(xy 119.301794 -345.598693) (xy 119.279137 -345.648307) (xy 119.24965 -345.694192) (xy 119.213934 -345.735414)
			(xy 119.172714 -345.771133) (xy 119.126832 -345.800624) (xy 119.077219 -345.823284) (xy 119.024886 -345.838654)
			(xy 118.970899 -345.84642) (xy 118.943628 -345.846908) (xy 118.080028 -345.846908) (xy 118.052759 -345.846355)
			(xy 117.998776 -345.838597) (xy 117.946446 -345.823235) (xy 117.896835 -345.800581) (xy 117.850953 -345.771098)
			(xy 117.809735 -345.735385) (xy 117.774019 -345.694169) (xy 117.744532 -345.648289) (xy 117.721875 -345.59868)
			(xy 117.706509 -345.546352) (xy 117.698747 -345.492369) (xy 116.216044 -345.492369) (xy 116.216044 -345.492376)
			(xy 116.20828 -345.546372) (xy 116.192911 -345.598713) (xy 116.170248 -345.648335) (xy 116.140754 -345.694225)
			(xy 116.105029 -345.735451) (xy 116.0638 -345.771173) (xy 116.017907 -345.800663) (xy 115.968283 -345.823322)
			(xy 115.915941 -345.838687) (xy 115.861944 -345.846447) (xy 115.834668 -345.846908) (xy 114.971068 -345.846908)
			(xy 114.943803 -345.846328) (xy 114.88983 -345.838563) (xy 114.83751 -345.823197) (xy 114.78791 -345.800542)
			(xy 114.742039 -345.771058) (xy 114.70083 -345.735347) (xy 114.665122 -345.694136) (xy 114.635643 -345.648262)
			(xy 114.612992 -345.59866) (xy 114.59763 -345.546339) (xy 114.58987 -345.492365) (xy 113.107021 -345.492365)
			(xy 113.107021 -345.492372) (xy 113.099259 -345.546362) (xy 113.083892 -345.598697) (xy 113.061234 -345.648312)
			(xy 113.031745 -345.694199) (xy 112.996027 -345.735421) (xy 112.954805 -345.77114) (xy 112.90892 -345.80063)
			(xy 112.859304 -345.82329) (xy 112.80697 -345.838657) (xy 112.75298 -345.846421) (xy 112.725708 -345.846908)
			(xy 111.862108 -345.846908) (xy 111.83484 -345.846353) (xy 111.780859 -345.838593) (xy 111.728531 -345.823229)
			(xy 111.678923 -345.800575) (xy 111.633044 -345.771091) (xy 111.591828 -345.735378) (xy 111.556114 -345.694162)
			(xy 111.526629 -345.648284) (xy 111.503974 -345.598676) (xy 111.488609 -345.546349) (xy 111.480847 -345.492368)
			(xy 93.706722 -345.492368) (xy 93.706722 -345.492371) (xy 93.69896 -345.546357) (xy 93.683595 -345.59869)
			(xy 93.660939 -345.648303) (xy 93.631454 -345.694187) (xy 93.595739 -345.735409) (xy 93.554521 -345.771128)
			(xy 93.50864 -345.800619) (xy 93.459029 -345.82328) (xy 93.406698 -345.838651) (xy 93.352713 -345.846419)
			(xy 93.325442 -345.846908) (xy 92.461842 -345.846908) (xy 92.434572 -345.846355) (xy 92.380587 -345.838599)
			(xy 92.328256 -345.823238) (xy 92.278643 -345.800586) (xy 92.23276 -345.771103) (xy 92.19154 -345.73539)
			(xy 92.155822 -345.694174) (xy 92.126334 -345.648293) (xy 92.103676 -345.598683) (xy 92.08831 -345.546354)
			(xy 92.080548 -345.49237) (xy 90.597844 -345.49237) (xy 90.597844 -345.492375) (xy 90.590081 -345.54637)
			(xy 90.574712 -345.59871) (xy 90.55205 -345.648331) (xy 90.522557 -345.694221) (xy 90.486834 -345.735446)
			(xy 90.445606 -345.771168) (xy 90.399715 -345.800659) (xy 90.350094 -345.823318) (xy 90.297752 -345.838685)
			(xy 90.243757 -345.846446) (xy 90.216482 -345.846908) (xy 89.352882 -345.846908) (xy 89.325617 -345.846328)
			(xy 89.271642 -345.838566) (xy 89.219321 -345.823201) (xy 89.169719 -345.800546) (xy 89.123845 -345.771063)
			(xy 89.082635 -345.735352) (xy 89.046926 -345.69414) (xy 89.017445 -345.648266) (xy 88.994793 -345.598663)
			(xy 88.979431 -345.546341) (xy 88.97167 -345.492365) (xy 87.488822 -345.492365) (xy 87.488822 -345.492372)
			(xy 87.481059 -345.54636) (xy 87.465693 -345.598694) (xy 87.443036 -345.648309) (xy 87.413549 -345.694194)
			(xy 87.377832 -345.735416) (xy 87.336612 -345.771136) (xy 87.290728 -345.800626) (xy 87.241115 -345.823286)
			(xy 87.188781 -345.838655) (xy 87.134794 -345.84642) (xy 87.107522 -345.846908) (xy 86.243922 -345.846908)
			(xy 86.216653 -345.846354) (xy 86.16267 -345.838595) (xy 86.110341 -345.823233) (xy 86.060732 -345.800579)
			(xy 86.014851 -345.771096) (xy 85.973633 -345.735383) (xy 85.937917 -345.694167) (xy 85.908431 -345.648288)
			(xy 85.885775 -345.598679) (xy 85.870409 -345.546351) (xy 85.862647 -345.492369) (xy 84.379944 -345.492369)
			(xy 84.379944 -345.492376) (xy 84.37218 -345.546373) (xy 84.35681 -345.598715) (xy 84.334147 -345.648336)
			(xy 84.304652 -345.694227) (xy 84.268927 -345.735453) (xy 84.227697 -345.771175) (xy 84.181803 -345.800665)
			(xy 84.132179 -345.823323) (xy 84.079836 -345.838688) (xy 84.025838 -345.846447) (xy 83.998562 -345.846908)
			(xy 83.134962 -345.846908) (xy 83.107698 -345.846327) (xy 83.053725 -345.838562) (xy 83.001406 -345.823195)
			(xy 82.951807 -345.80054) (xy 82.905936 -345.771056) (xy 82.864728 -345.735345) (xy 82.829021 -345.694134)
			(xy 82.799542 -345.64826) (xy 82.776892 -345.598658) (xy 82.76153 -345.546338) (xy 82.75377 -345.492364)
			(xy 81.270921 -345.492364) (xy 81.270921 -345.492373) (xy 81.263159 -345.546362) (xy 81.247792 -345.598698)
			(xy 81.225133 -345.648314) (xy 81.195644 -345.6942) (xy 81.159924 -345.735423) (xy 81.118702 -345.771143)
			(xy 81.072816 -345.800632) (xy 81.0232 -345.823291) (xy 80.970864 -345.838658) (xy 80.916875 -345.846421)
			(xy 80.889602 -345.846908) (xy 80.026002 -345.846908) (xy 79.998734 -345.846353) (xy 79.944754 -345.838592)
			(xy 79.892427 -345.823228) (xy 79.84282 -345.800573) (xy 79.796941 -345.771089) (xy 79.755726 -345.735376)
			(xy 79.720012 -345.69416) (xy 79.690528 -345.648282) (xy 79.667873 -345.598675) (xy 79.652509 -345.546348)
			(xy 79.644747 -345.492368) (xy 78.161922 -345.492368) (xy 78.161922 -345.492371) (xy 78.15416 -345.546357)
			(xy 78.138795 -345.59869) (xy 78.116139 -345.648303) (xy 78.086654 -345.694187) (xy 78.050939 -345.735409)
			(xy 78.009721 -345.771128) (xy 77.96384 -345.800619) (xy 77.914229 -345.82328) (xy 77.861898 -345.838651)
			(xy 77.807913 -345.846419) (xy 77.780642 -345.846908) (xy 76.917042 -345.846908) (xy 76.889772 -345.846355)
			(xy 76.835787 -345.838599) (xy 76.783456 -345.823238) (xy 76.733843 -345.800586) (xy 76.68796 -345.771103)
			(xy 76.64674 -345.73539) (xy 76.611022 -345.694174) (xy 76.581534 -345.648293) (xy 76.558876 -345.598683)
			(xy 76.54351 -345.546354) (xy 76.535748 -345.49237) (xy 75.053044 -345.49237) (xy 75.053044 -345.492375)
			(xy 75.045281 -345.54637) (xy 75.029912 -345.59871) (xy 75.00725 -345.648331) (xy 74.977757 -345.694221)
			(xy 74.942034 -345.735446) (xy 74.900806 -345.771168) (xy 74.854915 -345.800659) (xy 74.805294 -345.823318)
			(xy 74.752952 -345.838685) (xy 74.698957 -345.846446) (xy 74.671682 -345.846908) (xy 73.808082 -345.846908)
			(xy 73.780817 -345.846328) (xy 73.726842 -345.838566) (xy 73.674521 -345.823201) (xy 73.624919 -345.800546)
			(xy 73.579045 -345.771063) (xy 73.537835 -345.735352) (xy 73.502126 -345.69414) (xy 73.472645 -345.648266)
			(xy 73.449993 -345.598663) (xy 73.434631 -345.546341) (xy 73.42687 -345.492365) (xy 71.944022 -345.492365)
			(xy 71.944022 -345.492372) (xy 71.936259 -345.54636) (xy 71.920893 -345.598694) (xy 71.898236 -345.648309)
			(xy 71.868749 -345.694194) (xy 71.833032 -345.735416) (xy 71.791812 -345.771136) (xy 71.745928 -345.800626)
			(xy 71.696315 -345.823286) (xy 71.643981 -345.838655) (xy 71.589994 -345.84642) (xy 71.562722 -345.846908)
			(xy 70.699122 -345.846908) (xy 70.671853 -345.846354) (xy 70.61787 -345.838595) (xy 70.565541 -345.823233)
			(xy 70.515932 -345.800579) (xy 70.470051 -345.771096) (xy 70.428833 -345.735383) (xy 70.393117 -345.694167)
			(xy 70.363631 -345.648288) (xy 70.340975 -345.598679) (xy 70.325609 -345.546351) (xy 70.317847 -345.492369)
			(xy 68.835144 -345.492369) (xy 68.835144 -345.492376) (xy 68.82738 -345.546373) (xy 68.81201 -345.598715)
			(xy 68.789347 -345.648336) (xy 68.759852 -345.694227) (xy 68.724127 -345.735453) (xy 68.682897 -345.771175)
			(xy 68.637003 -345.800665) (xy 68.587379 -345.823323) (xy 68.535036 -345.838688) (xy 68.481038 -345.846447)
			(xy 68.453762 -345.846908) (xy 67.590162 -345.846908) (xy 67.562898 -345.846327) (xy 67.508925 -345.838562)
			(xy 67.456606 -345.823195) (xy 67.407007 -345.80054) (xy 67.361136 -345.771056) (xy 67.319928 -345.735345)
			(xy 67.284221 -345.694134) (xy 67.254742 -345.64826) (xy 67.232092 -345.598658) (xy 67.21673 -345.546338)
			(xy 67.20897 -345.492364) (xy 65.726121 -345.492364) (xy 65.726121 -345.492373) (xy 65.718359 -345.546362)
			(xy 65.702992 -345.598698) (xy 65.680333 -345.648314) (xy 65.650844 -345.6942) (xy 65.615124 -345.735423)
			(xy 65.573902 -345.771143) (xy 65.528016 -345.800632) (xy 65.4784 -345.823291) (xy 65.426064 -345.838658)
			(xy 65.372075 -345.846421) (xy 65.344802 -345.846908) (xy 64.481202 -345.846908) (xy 64.453934 -345.846353)
			(xy 64.399954 -345.838592) (xy 64.347627 -345.823228) (xy 64.29802 -345.800573) (xy 64.252141 -345.771089)
			(xy 64.210926 -345.735376) (xy 64.175212 -345.69416) (xy 64.145728 -345.648282) (xy 64.123073 -345.598675)
			(xy 64.107709 -345.546348) (xy 64.099947 -345.492368) (xy 62.617122 -345.492368) (xy 62.617122 -345.492371)
			(xy 62.60936 -345.546357) (xy 62.593995 -345.59869) (xy 62.571339 -345.648303) (xy 62.541854 -345.694187)
			(xy 62.506139 -345.735409) (xy 62.464921 -345.771128) (xy 62.41904 -345.800619) (xy 62.369429 -345.82328)
			(xy 62.317098 -345.838651) (xy 62.263113 -345.846419) (xy 62.235842 -345.846908) (xy 61.372242 -345.846908)
			(xy 61.344972 -345.846355) (xy 61.290987 -345.838599) (xy 61.238656 -345.823238) (xy 61.189043 -345.800586)
			(xy 61.14316 -345.771103) (xy 61.10194 -345.73539) (xy 61.066222 -345.694174) (xy 61.036734 -345.648293)
			(xy 61.014076 -345.598683) (xy 60.99871 -345.546354) (xy 60.990948 -345.49237) (xy 51.666922 -345.49237)
			(xy 51.65916 -345.546356) (xy 51.643795 -345.598688) (xy 51.62114 -345.648301) (xy 51.591655 -345.694185)
			(xy 51.555941 -345.735407) (xy 51.514724 -345.771126) (xy 51.468843 -345.800617) (xy 51.419233 -345.823279)
			(xy 51.366903 -345.83865) (xy 51.312918 -345.846418) (xy 51.285648 -345.846908) (xy 50.422048 -345.846908)
			(xy 50.394778 -345.846356) (xy 50.340792 -345.8386) (xy 50.28846 -345.82324) (xy 50.238847 -345.800588)
			(xy 50.192963 -345.771105) (xy 50.151742 -345.735392) (xy 50.116024 -345.694176) (xy 50.086535 -345.648295)
			(xy 50.063877 -345.598685) (xy 50.04851 -345.546354) (xy 50.040748 -345.49237) (xy 48.558044 -345.49237)
			(xy 48.558044 -345.492375) (xy 48.550281 -345.546369) (xy 48.534912 -345.598709) (xy 48.512251 -345.648329)
			(xy 48.482759 -345.694219) (xy 48.447036 -345.735444) (xy 48.405809 -345.771166) (xy 48.359919 -345.800657)
			(xy 48.310298 -345.823316) (xy 48.257958 -345.838684) (xy 48.203963 -345.846445) (xy 48.176688 -345.846908)
			(xy 47.313088 -345.846908) (xy 47.285822 -345.846329) (xy 47.231847 -345.838567) (xy 47.179525 -345.823202)
			(xy 47.129922 -345.800548) (xy 47.084048 -345.771065) (xy 47.042837 -345.735354) (xy 47.007127 -345.694142)
			(xy 46.977646 -345.648267) (xy 46.954994 -345.598664) (xy 46.939631 -345.546342) (xy 46.93187 -345.492366)
			(xy 45.449022 -345.492366) (xy 45.449022 -345.492371) (xy 45.44126 -345.546359) (xy 45.425894 -345.598693)
			(xy 45.403237 -345.648307) (xy 45.37375 -345.694192) (xy 45.338034 -345.735414) (xy 45.296814 -345.771133)
			(xy 45.250932 -345.800624) (xy 45.201319 -345.823284) (xy 45.148986 -345.838654) (xy 45.094999 -345.84642)
			(xy 45.067728 -345.846908) (xy 44.204128 -345.846908) (xy 44.176859 -345.846355) (xy 44.122876 -345.838597)
			(xy 44.070546 -345.823235) (xy 44.020935 -345.800581) (xy 43.975053 -345.771098) (xy 43.933835 -345.735385)
			(xy 43.898119 -345.694169) (xy 43.868632 -345.648289) (xy 43.845975 -345.59868) (xy 43.830609 -345.546352)
			(xy 43.822847 -345.492369) (xy 42.340144 -345.492369) (xy 42.340144 -345.492376) (xy 42.33238 -345.546372)
			(xy 42.317011 -345.598713) (xy 42.294348 -345.648335) (xy 42.264854 -345.694225) (xy 42.229129 -345.735451)
			(xy 42.1879 -345.771173) (xy 42.142007 -345.800663) (xy 42.092383 -345.823322) (xy 42.040041 -345.838687)
			(xy 41.986044 -345.846447) (xy 41.958768 -345.846908) (xy 41.095168 -345.846908) (xy 41.067903 -345.846328)
			(xy 41.01393 -345.838563) (xy 40.96161 -345.823197) (xy 40.91201 -345.800542) (xy 40.866139 -345.771058)
			(xy 40.82493 -345.735347) (xy 40.789222 -345.694136) (xy 40.759743 -345.648262) (xy 40.737092 -345.59866)
			(xy 40.72173 -345.546339) (xy 40.71397 -345.492365) (xy 39.231121 -345.492365) (xy 39.231121 -345.492372)
			(xy 39.223359 -345.546362) (xy 39.207992 -345.598697) (xy 39.185334 -345.648312) (xy 39.155845 -345.694199)
			(xy 39.120127 -345.735421) (xy 39.078905 -345.77114) (xy 39.03302 -345.80063) (xy 38.983404 -345.82329)
			(xy 38.93107 -345.838657) (xy 38.87708 -345.846421) (xy 38.849808 -345.846908) (xy 37.986208 -345.846908)
			(xy 37.95894 -345.846353) (xy 37.904959 -345.838593) (xy 37.852631 -345.823229) (xy 37.803023 -345.800575)
			(xy 37.757144 -345.771091) (xy 37.715928 -345.735378) (xy 37.680214 -345.694162) (xy 37.650729 -345.648284)
			(xy 37.628074 -345.598676) (xy 37.612709 -345.546349) (xy 37.604947 -345.492368) (xy 36.122122 -345.492368)
			(xy 36.122122 -345.49237) (xy 36.11436 -345.546356) (xy 36.098995 -345.598688) (xy 36.07634 -345.648301)
			(xy 36.046855 -345.694185) (xy 36.011141 -345.735407) (xy 35.969924 -345.771126) (xy 35.924043 -345.800617)
			(xy 35.874433 -345.823279) (xy 35.822103 -345.83865) (xy 35.768118 -345.846418) (xy 35.740848 -345.846908)
			(xy 34.877248 -345.846908) (xy 34.849978 -345.846356) (xy 34.795992 -345.8386) (xy 34.74366 -345.82324)
			(xy 34.694047 -345.800588) (xy 34.648163 -345.771105) (xy 34.606942 -345.735392) (xy 34.571224 -345.694176)
			(xy 34.541735 -345.648295) (xy 34.519077 -345.598685) (xy 34.50371 -345.546354) (xy 34.495948 -345.49237)
			(xy 33.013244 -345.49237) (xy 33.013244 -345.492375) (xy 33.005481 -345.546369) (xy 32.990112 -345.598709)
			(xy 32.967451 -345.648329) (xy 32.937959 -345.694219) (xy 32.902236 -345.735444) (xy 32.861009 -345.771166)
			(xy 32.815119 -345.800657) (xy 32.765498 -345.823316) (xy 32.713158 -345.838684) (xy 32.659163 -345.846445)
			(xy 32.631888 -345.846908) (xy 31.768288 -345.846908) (xy 31.741022 -345.846329) (xy 31.687047 -345.838567)
			(xy 31.634725 -345.823202) (xy 31.585122 -345.800548) (xy 31.539248 -345.771065) (xy 31.498037 -345.735354)
			(xy 31.462327 -345.694142) (xy 31.432846 -345.648267) (xy 31.410194 -345.598664) (xy 31.394831 -345.546342)
			(xy 31.38707 -345.492366) (xy 29.904222 -345.492366) (xy 29.904222 -345.492371) (xy 29.89646 -345.546359)
			(xy 29.881094 -345.598693) (xy 29.858437 -345.648307) (xy 29.82895 -345.694192) (xy 29.793234 -345.735414)
			(xy 29.752014 -345.771133) (xy 29.706132 -345.800624) (xy 29.656519 -345.823284) (xy 29.604186 -345.838654)
			(xy 29.550199 -345.84642) (xy 29.522928 -345.846908) (xy 28.659328 -345.846908) (xy 28.632059 -345.846355)
			(xy 28.578076 -345.838597) (xy 28.525746 -345.823235) (xy 28.476135 -345.800581) (xy 28.430253 -345.771098)
			(xy 28.389035 -345.735385) (xy 28.353319 -345.694169) (xy 28.323832 -345.648289) (xy 28.301175 -345.59868)
			(xy 28.285809 -345.546352) (xy 28.278047 -345.492369) (xy 26.795344 -345.492369) (xy 26.795344 -345.492376)
			(xy 26.78758 -345.546372) (xy 26.772211 -345.598713) (xy 26.749548 -345.648335) (xy 26.720054 -345.694225)
			(xy 26.684329 -345.735451) (xy 26.6431 -345.771173) (xy 26.597207 -345.800663) (xy 26.547583 -345.823322)
			(xy 26.495241 -345.838687) (xy 26.441244 -345.846447) (xy 26.413968 -345.846908) (xy 25.550368 -345.846908)
			(xy 25.523103 -345.846328) (xy 25.46913 -345.838563) (xy 25.41681 -345.823197) (xy 25.36721 -345.800542)
			(xy 25.321339 -345.771058) (xy 25.28013 -345.735347) (xy 25.244422 -345.694136) (xy 25.214943 -345.648262)
			(xy 25.192292 -345.59866) (xy 25.17693 -345.546339) (xy 25.16917 -345.492365) (xy 23.686305 -345.492365)
			(xy 23.686305 -345.492421) (xy 23.678542 -345.546407) (xy 23.663176 -345.59874) (xy 23.640519 -345.648352)
			(xy 23.611031 -345.694236) (xy 23.575314 -345.735455) (xy 23.534094 -345.771172) (xy 23.488211 -345.80066)
			(xy 23.438598 -345.823317) (xy 23.386265 -345.838683) (xy 23.332279 -345.846445) (xy 23.305008 -345.846908)
			(xy 22.441408 -345.846908) (xy 22.414138 -345.846429) (xy 22.360154 -345.838667) (xy 22.307825 -345.823302)
			(xy 22.258214 -345.800645) (xy 22.212333 -345.771159) (xy 22.171115 -345.735443) (xy 22.1354 -345.694225)
			(xy 22.105914 -345.648344) (xy 22.083258 -345.598733) (xy 22.067892 -345.546404) (xy 22.06013 -345.49242)
			(xy 20.577345 -345.49242) (xy 20.577345 -345.492421) (xy 20.569582 -345.546407) (xy 20.554216 -345.59874)
			(xy 20.531559 -345.648352) (xy 20.502071 -345.694236) (xy 20.466354 -345.735455) (xy 20.425134 -345.771172)
			(xy 20.379251 -345.80066) (xy 20.329638 -345.823317) (xy 20.277305 -345.838683) (xy 20.223319 -345.846445)
			(xy 20.196048 -345.846908) (xy 19.332448 -345.846908) (xy 19.305178 -345.846429) (xy 19.251194 -345.838667)
			(xy 19.198865 -345.823302) (xy 19.149254 -345.800645) (xy 19.103373 -345.771159) (xy 19.062155 -345.735443)
			(xy 19.02644 -345.694225) (xy 18.996954 -345.648344) (xy 18.974298 -345.598733) (xy 18.958932 -345.546404)
			(xy 18.95117 -345.49242) (xy 0.509016 -345.49242) (xy 0.509016 -348.976496) (xy 4.708641 -348.976496)
			(xy 4.708641 -348.847356) (xy 4.716591 -348.718461) (xy 4.732461 -348.590301) (xy 4.75619 -348.46336)
			(xy 4.787689 -348.338121) (xy 4.826838 -348.215058) (xy 4.873489 -348.094639) (xy 4.927464 -347.97732)
			(xy 4.988559 -347.863546) (xy 5.056542 -347.753749) (xy 5.131156 -347.648346) (xy 5.212117 -347.547736)
			(xy 5.299117 -347.452301) (xy 5.391828 -347.362402) (xy 5.489898 -347.278381) (xy 5.592953 -347.200557)
			(xy 5.700604 -347.129225) (xy 5.812443 -347.064655) (xy 5.928044 -347.007093) (xy 6.046969 -346.956756)
			(xy 6.168768 -346.913836) (xy 6.292978 -346.878495) (xy 6.419127 -346.850868) (xy 6.546739 -346.831059)
			(xy 6.675328 -346.819143) (xy 6.804406 -346.815167) (xy 6.933484 -346.819143) (xy 7.062073 -346.831059)
			(xy 7.189685 -346.850868) (xy 7.315834 -346.878495) (xy 7.440044 -346.913836) (xy 7.451736 -346.917956)
			(xy 245.50903 -346.917956) (xy 245.50903 -346.83326) (xy 245.517081 -346.748946) (xy 245.53311 -346.66578)
			(xy 245.556971 -346.584513) (xy 245.58845 -346.505883) (xy 245.627261 -346.430602) (xy 245.673051 -346.35935)
			(xy 245.725407 -346.292774) (xy 245.783855 -346.231476) (xy 245.847865 -346.176011) (xy 245.916857 -346.126882)
			(xy 245.990207 -346.084533) (xy 246.06725 -346.049349) (xy 246.147289 -346.021647) (xy 246.229598 -346.001679)
			(xy 246.313433 -345.989626) (xy 246.398034 -345.985596) (xy 246.482635 -345.989626) (xy 246.56647 -346.001679)
			(xy 246.648779 -346.021647) (xy 246.728818 -346.049349) (xy 246.805861 -346.084533) (xy 246.879211 -346.126882)
			(xy 246.948203 -346.176011) (xy 247.012213 -346.231476) (xy 247.070661 -346.292774) (xy 247.123017 -346.35935)
			(xy 247.168807 -346.430602) (xy 247.207618 -346.505883) (xy 247.239097 -346.584513) (xy 247.262958 -346.66578)
			(xy 247.278987 -346.748946) (xy 247.287038 -346.83326) (xy 247.287542 -346.875608) (xy 247.287038 -346.917956)
			(xy 247.278987 -347.00227) (xy 247.262958 -347.085436) (xy 247.239097 -347.166703) (xy 247.207618 -347.245333)
			(xy 247.168807 -347.320614) (xy 247.123017 -347.391866) (xy 247.070661 -347.458442) (xy 247.012213 -347.51974)
			(xy 246.948203 -347.575205) (xy 246.879211 -347.624334) (xy 246.805861 -347.666683) (xy 246.728818 -347.701867)
			(xy 246.648779 -347.729569) (xy 246.56647 -347.749537) (xy 246.482635 -347.76159) (xy 246.398034 -347.765621)
			(xy 246.313433 -347.76159) (xy 246.229598 -347.749537) (xy 246.147289 -347.729569) (xy 246.06725 -347.701867)
			(xy 245.990207 -347.666683) (xy 245.916857 -347.624334) (xy 245.847865 -347.575205) (xy 245.783855 -347.51974)
			(xy 245.725407 -347.458442) (xy 245.673051 -347.391866) (xy 245.627261 -347.320614) (xy 245.58845 -347.245333)
			(xy 245.556971 -347.166703) (xy 245.53311 -347.085436) (xy 245.517081 -347.00227) (xy 245.50903 -346.917956)
			(xy 7.451736 -346.917956) (xy 7.561843 -346.956756) (xy 7.680768 -347.007093) (xy 7.796369 -347.064655)
			(xy 7.908208 -347.129225) (xy 8.015859 -347.200557) (xy 8.118914 -347.278381) (xy 8.216984 -347.362402)
			(xy 8.309695 -347.452301) (xy 8.396695 -347.547736) (xy 8.477656 -347.648346) (xy 8.55227 -347.753749)
			(xy 8.620253 -347.863546) (xy 8.681348 -347.97732) (xy 8.735323 -348.094639) (xy 8.781974 -348.215058)
			(xy 8.821123 -348.338121) (xy 8.852622 -348.46336) (xy 8.876351 -348.590301) (xy 8.879169 -348.613059)
			(xy 18.951174 -348.613059) (xy 18.951174 -348.558521) (xy 18.958936 -348.504537) (xy 18.974301 -348.452208)
			(xy 18.996957 -348.402598) (xy 19.026443 -348.356717) (xy 19.062158 -348.315499) (xy 19.103375 -348.279784)
			(xy 19.149256 -348.250298) (xy 19.198866 -348.227642) (xy 19.251195 -348.212276) (xy 19.305179 -348.204515)
			(xy 19.332448 -348.204028) (xy 20.196048 -348.204028) (xy 20.223319 -348.204491) (xy 20.277306 -348.212253)
			(xy 20.329639 -348.227619) (xy 20.379253 -348.250277) (xy 20.425136 -348.279764) (xy 20.466357 -348.315482)
			(xy 20.502074 -348.356702) (xy 20.531562 -348.402586) (xy 20.55422 -348.452199) (xy 20.569586 -348.504532)
			(xy 20.577349 -348.558519) (xy 20.577349 -348.613061) (xy 20.577347 -348.613072) (xy 22.060092 -348.613072)
			(xy 22.060092 -348.558528) (xy 22.067854 -348.504539) (xy 22.083221 -348.452204) (xy 22.10588 -348.402589)
			(xy 22.135369 -348.356704) (xy 22.171088 -348.315483) (xy 22.21231 -348.279764) (xy 22.258196 -348.250276)
			(xy 22.307812 -348.227618) (xy 22.360147 -348.212252) (xy 22.414136 -348.204491) (xy 22.441408 -348.204028)
			(xy 23.305008 -348.204028) (xy 23.332276 -348.204535) (xy 23.386258 -348.212297) (xy 23.438585 -348.227663)
			(xy 23.488193 -348.250319) (xy 23.534071 -348.279804) (xy 23.575287 -348.315519) (xy 23.611 -348.356735)
			(xy 23.640485 -348.402614) (xy 23.66314 -348.452223) (xy 23.678504 -348.50455) (xy 23.686266 -348.558532)
			(xy 23.686266 -348.613068) (xy 23.686266 -348.613069) (xy 25.169114 -348.613069) (xy 25.169114 -348.558531)
			(xy 25.176875 -348.504549) (xy 25.19224 -348.452221) (xy 25.214894 -348.402611) (xy 25.244378 -348.356731)
			(xy 25.28009 -348.315513) (xy 25.321305 -348.279797) (xy 25.367183 -348.250309) (xy 25.416791 -348.227651)
			(xy 25.469118 -348.212282) (xy 25.523099 -348.204517) (xy 25.550368 -348.204028) (xy 26.413968 -348.204028)
			(xy 26.44124 -348.204509) (xy 26.495229 -348.212268) (xy 26.547564 -348.227631) (xy 26.59718 -348.250286)
			(xy 26.643066 -348.279772) (xy 26.684289 -348.315488) (xy 26.720009 -348.356708) (xy 26.749499 -348.402592)
			(xy 26.772158 -348.452206) (xy 26.787526 -348.50454) (xy 26.795288 -348.558528) (xy 26.795288 -348.613072)
			(xy 26.795288 -348.613073) (xy 28.277992 -348.613073) (xy 28.277992 -348.558527) (xy 28.285755 -348.504536)
			(xy 28.301123 -348.4522) (xy 28.323783 -348.402584) (xy 28.353274 -348.356697) (xy 28.388995 -348.315476)
			(xy 28.43022 -348.279757) (xy 28.476108 -348.25027) (xy 28.525726 -348.227613) (xy 28.578064 -348.212249)
			(xy 28.632055 -348.20449) (xy 28.659328 -348.204028) (xy 29.522928 -348.204028) (xy 29.550195 -348.204536)
			(xy 29.604175 -348.212301) (xy 29.656499 -348.227668) (xy 29.706105 -348.250326) (xy 29.751981 -348.279811)
			(xy 29.793194 -348.315526) (xy 29.828905 -348.356742) (xy 29.858388 -348.40262) (xy 29.881041 -348.452227)
			(xy 29.896405 -348.504553) (xy 29.904166 -348.558533) (xy 29.904166 -348.613067) (xy 29.904166 -348.61307)
			(xy 31.387014 -348.61307) (xy 31.387014 -348.55853) (xy 31.394776 -348.504546) (xy 31.410141 -348.452217)
			(xy 31.432797 -348.402606) (xy 31.462283 -348.356724) (xy 31.497997 -348.315506) (xy 31.539215 -348.27979)
			(xy 31.585095 -348.250303) (xy 31.634705 -348.227645) (xy 31.687035 -348.212279) (xy 31.741018 -348.204515)
			(xy 31.768288 -348.204028) (xy 32.631888 -348.204028) (xy 32.659159 -348.204511) (xy 32.713146 -348.212271)
			(xy 32.765478 -348.227636) (xy 32.815092 -348.250292) (xy 32.860976 -348.279779) (xy 32.902196 -348.315495)
			(xy 32.937914 -348.356715) (xy 32.967402 -348.402598) (xy 32.99006 -348.45221) (xy 33.005426 -348.504543)
			(xy 33.013189 -348.558529) (xy 33.013189 -348.613071) (xy 33.013189 -348.613074) (xy 34.495892 -348.613074)
			(xy 34.495892 -348.558526) (xy 34.503655 -348.504534) (xy 34.519024 -348.452196) (xy 34.541686 -348.402578)
			(xy 34.571179 -348.356691) (xy 34.606902 -348.315468) (xy 34.648129 -348.27975) (xy 34.69402 -348.250263)
			(xy 34.743641 -348.227608) (xy 34.795981 -348.212245) (xy 34.849974 -348.204488) (xy 34.877248 -348.204028)
			(xy 35.740848 -348.204028) (xy 35.768114 -348.204538) (xy 35.822091 -348.212305) (xy 35.874414 -348.227674)
			(xy 35.924017 -348.250332) (xy 35.96989 -348.279819) (xy 36.011101 -348.315533) (xy 36.04681 -348.356748)
			(xy 36.076291 -348.402626) (xy 36.098943 -348.452231) (xy 36.114306 -348.504556) (xy 36.122066 -348.558534)
			(xy 36.122066 -348.613066) (xy 36.122065 -348.613072) (xy 37.604892 -348.613072) (xy 37.604892 -348.558528)
			(xy 37.612654 -348.504539) (xy 37.628021 -348.452204) (xy 37.65068 -348.402589) (xy 37.680169 -348.356704)
			(xy 37.715888 -348.315483) (xy 37.75711 -348.279764) (xy 37.802996 -348.250276) (xy 37.852612 -348.227618)
			(xy 37.904947 -348.212252) (xy 37.958936 -348.204491) (xy 37.986208 -348.204028) (xy 38.849808 -348.204028)
			(xy 38.877076 -348.204535) (xy 38.931058 -348.212297) (xy 38.983385 -348.227663) (xy 39.032993 -348.250319)
			(xy 39.078871 -348.279804) (xy 39.120087 -348.315519) (xy 39.1558 -348.356735) (xy 39.185285 -348.402614)
			(xy 39.20794 -348.452223) (xy 39.223304 -348.50455) (xy 39.231066 -348.558532) (xy 39.231066 -348.613068)
			(xy 39.231066 -348.613069) (xy 40.713914 -348.613069) (xy 40.713914 -348.558531) (xy 40.721675 -348.504549)
			(xy 40.73704 -348.452221) (xy 40.759694 -348.402611) (xy 40.789178 -348.356731) (xy 40.82489 -348.315513)
			(xy 40.866105 -348.279797) (xy 40.911983 -348.250309) (xy 40.961591 -348.227651) (xy 41.013918 -348.212282)
			(xy 41.067899 -348.204517) (xy 41.095168 -348.204028) (xy 41.958768 -348.204028) (xy 41.98604 -348.204509)
			(xy 42.040029 -348.212268) (xy 42.092364 -348.227631) (xy 42.14198 -348.250286) (xy 42.187866 -348.279772)
			(xy 42.229089 -348.315488) (xy 42.264809 -348.356708) (xy 42.294299 -348.402592) (xy 42.316958 -348.452206)
			(xy 42.332326 -348.50454) (xy 42.340088 -348.558528) (xy 42.340088 -348.613072) (xy 42.340088 -348.613073)
			(xy 43.822792 -348.613073) (xy 43.822792 -348.558527) (xy 43.830555 -348.504536) (xy 43.845923 -348.4522)
			(xy 43.868583 -348.402584) (xy 43.898074 -348.356697) (xy 43.933795 -348.315476) (xy 43.97502 -348.279757)
			(xy 44.020908 -348.25027) (xy 44.070526 -348.227613) (xy 44.122864 -348.212249) (xy 44.176855 -348.20449)
			(xy 44.204128 -348.204028) (xy 45.067728 -348.204028) (xy 45.094995 -348.204536) (xy 45.148975 -348.212301)
			(xy 45.201299 -348.227668) (xy 45.250905 -348.250326) (xy 45.296781 -348.279811) (xy 45.337994 -348.315526)
			(xy 45.373705 -348.356742) (xy 45.403188 -348.40262) (xy 45.425841 -348.452227) (xy 45.441205 -348.504553)
			(xy 45.448966 -348.558533) (xy 45.448966 -348.613067) (xy 45.448966 -348.61307) (xy 46.931814 -348.61307)
			(xy 46.931814 -348.55853) (xy 46.939576 -348.504546) (xy 46.954941 -348.452217) (xy 46.977597 -348.402606)
			(xy 47.007083 -348.356724) (xy 47.042797 -348.315506) (xy 47.084015 -348.27979) (xy 47.129895 -348.250303)
			(xy 47.179505 -348.227645) (xy 47.231835 -348.212279) (xy 47.285818 -348.204515) (xy 47.313088 -348.204028)
			(xy 48.176688 -348.204028) (xy 48.203959 -348.204511) (xy 48.257946 -348.212271) (xy 48.310278 -348.227636)
			(xy 48.359892 -348.250292) (xy 48.405776 -348.279779) (xy 48.446996 -348.315495) (xy 48.482714 -348.356715)
			(xy 48.512202 -348.402598) (xy 48.53486 -348.45221) (xy 48.550226 -348.504543) (xy 48.557989 -348.558529)
			(xy 48.557989 -348.613071) (xy 48.557989 -348.613074) (xy 50.040692 -348.613074) (xy 50.040692 -348.558526)
			(xy 50.048455 -348.504534) (xy 50.063824 -348.452196) (xy 50.086486 -348.402578) (xy 50.115979 -348.356691)
			(xy 50.151702 -348.315468) (xy 50.192929 -348.27975) (xy 50.23882 -348.250263) (xy 50.288441 -348.227608)
			(xy 50.340781 -348.212245) (xy 50.394774 -348.204488) (xy 50.422048 -348.204028) (xy 51.285648 -348.204028)
			(xy 51.312914 -348.204538) (xy 51.366891 -348.212305) (xy 51.419214 -348.227674) (xy 51.468817 -348.250332)
			(xy 51.51469 -348.279819) (xy 51.555901 -348.315533) (xy 51.59161 -348.356748) (xy 51.621091 -348.402626)
			(xy 51.643743 -348.452231) (xy 51.659106 -348.504556) (xy 51.666866 -348.558534) (xy 51.666866 -348.613066)
			(xy 51.666865 -348.613074) (xy 60.990892 -348.613074) (xy 60.990892 -348.558526) (xy 60.998655 -348.504534)
			(xy 61.014024 -348.452197) (xy 61.036685 -348.40258) (xy 61.066177 -348.356693) (xy 61.1019 -348.315471)
			(xy 61.143127 -348.279752) (xy 61.189017 -348.250265) (xy 61.238636 -348.227609) (xy 61.290976 -348.212246)
			(xy 61.344968 -348.204489) (xy 61.372242 -348.204028) (xy 62.235842 -348.204028) (xy 62.263109 -348.204537)
			(xy 62.317086 -348.212304) (xy 62.369409 -348.227672) (xy 62.419013 -348.25033) (xy 62.464887 -348.279816)
			(xy 62.506099 -348.315531) (xy 62.541809 -348.356746) (xy 62.57129 -348.402624) (xy 62.593943 -348.45223)
			(xy 62.609305 -348.504555) (xy 62.617066 -348.558533) (xy 62.617066 -348.613067) (xy 62.617065 -348.613072)
			(xy 64.099892 -348.613072) (xy 64.099892 -348.558528) (xy 64.107654 -348.50454) (xy 64.123021 -348.452206)
			(xy 64.145679 -348.402591) (xy 64.175168 -348.356706) (xy 64.210886 -348.315485) (xy 64.252108 -348.279766)
			(xy 64.297993 -348.250278) (xy 64.347607 -348.22762) (xy 64.399942 -348.212253) (xy 64.45393 -348.204491)
			(xy 64.481202 -348.204028) (xy 65.344802 -348.204028) (xy 65.372071 -348.204535) (xy 65.426053 -348.212296)
			(xy 65.47838 -348.227661) (xy 65.527989 -348.250317) (xy 65.573869 -348.279802) (xy 65.615085 -348.315517)
			(xy 65.650799 -348.356733) (xy 65.680284 -348.402613) (xy 65.702939 -348.452221) (xy 65.718304 -348.504549)
			(xy 65.726066 -348.558531) (xy 65.726066 -348.613068) (xy 67.208914 -348.613068) (xy 67.208914 -348.558532)
			(xy 67.216675 -348.50455) (xy 67.232039 -348.452222) (xy 67.254693 -348.402613) (xy 67.284176 -348.356733)
			(xy 67.319888 -348.315515) (xy 67.361102 -348.279799) (xy 67.40698 -348.250311) (xy 67.456586 -348.227652)
			(xy 67.508913 -348.212283) (xy 67.562894 -348.204517) (xy 67.590162 -348.204028) (xy 68.453762 -348.204028)
			(xy 68.481034 -348.204509) (xy 68.535024 -348.212266) (xy 68.58736 -348.227629) (xy 68.636976 -348.250284)
			(xy 68.682863 -348.27977) (xy 68.724087 -348.315486) (xy 68.759808 -348.356706) (xy 68.789298 -348.40259)
			(xy 68.811958 -348.452205) (xy 68.827326 -348.504539) (xy 68.835088 -348.558528) (xy 68.835088 -348.613072)
			(xy 68.835088 -348.613073) (xy 70.317792 -348.613073) (xy 70.317792 -348.558527) (xy 70.325554 -348.504537)
			(xy 70.340922 -348.452201) (xy 70.363582 -348.402585) (xy 70.393072 -348.356699) (xy 70.428793 -348.315478)
			(xy 70.470017 -348.279759) (xy 70.515905 -348.250271) (xy 70.565522 -348.227615) (xy 70.617859 -348.21225)
			(xy 70.671849 -348.20449) (xy 70.699122 -348.204028) (xy 71.562722 -348.204028) (xy 71.58999 -348.204536)
			(xy 71.643969 -348.2123) (xy 71.696295 -348.227667) (xy 71.745901 -348.250324) (xy 71.791778 -348.279809)
			(xy 71.832992 -348.315524) (xy 71.868704 -348.35674) (xy 71.898187 -348.402618) (xy 71.920841 -348.452226)
			(xy 71.936205 -348.504552) (xy 71.943966 -348.558532) (xy 71.943966 -348.613068) (xy 71.943966 -348.613069)
			(xy 73.426814 -348.613069) (xy 73.426814 -348.558531) (xy 73.434576 -348.504547) (xy 73.449941 -348.452218)
			(xy 73.472596 -348.402608) (xy 73.502081 -348.356726) (xy 73.537795 -348.315508) (xy 73.579012 -348.279792)
			(xy 73.624892 -348.250305) (xy 73.674501 -348.227647) (xy 73.72683 -348.21228) (xy 73.780813 -348.204516)
			(xy 73.808082 -348.204028) (xy 74.671682 -348.204028) (xy 74.698953 -348.20451) (xy 74.752941 -348.21227)
			(xy 74.805274 -348.227634) (xy 74.854888 -348.25029) (xy 74.900773 -348.279777) (xy 74.941994 -348.315493)
			(xy 74.977712 -348.356713) (xy 75.007201 -348.402596) (xy 75.029859 -348.452209) (xy 75.045226 -348.504542)
			(xy 75.052988 -348.558529) (xy 75.052988 -348.613071) (xy 75.052988 -348.613074) (xy 76.535692 -348.613074)
			(xy 76.535692 -348.558526) (xy 76.543455 -348.504534) (xy 76.558824 -348.452197) (xy 76.581485 -348.40258)
			(xy 76.610977 -348.356693) (xy 76.6467 -348.315471) (xy 76.687927 -348.279752) (xy 76.733817 -348.250265)
			(xy 76.783436 -348.227609) (xy 76.835776 -348.212246) (xy 76.889768 -348.204489) (xy 76.917042 -348.204028)
			(xy 77.780642 -348.204028) (xy 77.807909 -348.204537) (xy 77.861886 -348.212304) (xy 77.914209 -348.227672)
			(xy 77.963813 -348.25033) (xy 78.009687 -348.279816) (xy 78.050899 -348.315531) (xy 78.086609 -348.356746)
			(xy 78.11609 -348.402624) (xy 78.138743 -348.45223) (xy 78.154105 -348.504555) (xy 78.161866 -348.558533)
			(xy 78.161866 -348.613067) (xy 78.161865 -348.613072) (xy 79.644692 -348.613072) (xy 79.644692 -348.558528)
			(xy 79.652454 -348.50454) (xy 79.667821 -348.452206) (xy 79.690479 -348.402591) (xy 79.719968 -348.356706)
			(xy 79.755686 -348.315485) (xy 79.796908 -348.279766) (xy 79.842793 -348.250278) (xy 79.892407 -348.22762)
			(xy 79.944742 -348.212253) (xy 79.99873 -348.204491) (xy 80.026002 -348.204028) (xy 80.889602 -348.204028)
			(xy 80.916871 -348.204535) (xy 80.970853 -348.212296) (xy 81.02318 -348.227661) (xy 81.072789 -348.250317)
			(xy 81.118669 -348.279802) (xy 81.159885 -348.315517) (xy 81.195599 -348.356733) (xy 81.225084 -348.402613)
			(xy 81.247739 -348.452221) (xy 81.263104 -348.504549) (xy 81.270866 -348.558531) (xy 81.270866 -348.613068)
			(xy 82.753714 -348.613068) (xy 82.753714 -348.558532) (xy 82.761475 -348.50455) (xy 82.776839 -348.452222)
			(xy 82.799493 -348.402613) (xy 82.828976 -348.356733) (xy 82.864688 -348.315515) (xy 82.905902 -348.279799)
			(xy 82.95178 -348.250311) (xy 83.001386 -348.227652) (xy 83.053713 -348.212283) (xy 83.107694 -348.204517)
			(xy 83.134962 -348.204028) (xy 83.998562 -348.204028) (xy 84.025834 -348.204509) (xy 84.079824 -348.212266)
			(xy 84.13216 -348.227629) (xy 84.181776 -348.250284) (xy 84.227663 -348.27977) (xy 84.268887 -348.315486)
			(xy 84.304608 -348.356706) (xy 84.334098 -348.40259) (xy 84.356758 -348.452205) (xy 84.372126 -348.504539)
			(xy 84.379888 -348.558528) (xy 84.379888 -348.613072) (xy 84.379888 -348.613073) (xy 85.862592 -348.613073)
			(xy 85.862592 -348.558527) (xy 85.870354 -348.504537) (xy 85.885722 -348.452201) (xy 85.908382 -348.402585)
			(xy 85.937872 -348.356699) (xy 85.973593 -348.315478) (xy 86.014817 -348.279759) (xy 86.060705 -348.250271)
			(xy 86.110322 -348.227615) (xy 86.162659 -348.21225) (xy 86.216649 -348.20449) (xy 86.243922 -348.204028)
			(xy 87.107522 -348.204028) (xy 87.13479 -348.204536) (xy 87.188769 -348.2123) (xy 87.241095 -348.227667)
			(xy 87.290701 -348.250324) (xy 87.336578 -348.279809) (xy 87.377792 -348.315524) (xy 87.413504 -348.35674)
			(xy 87.442987 -348.402618) (xy 87.465641 -348.452226) (xy 87.481005 -348.504552) (xy 87.488766 -348.558532)
			(xy 87.488766 -348.613068) (xy 87.488766 -348.613069) (xy 88.971614 -348.613069) (xy 88.971614 -348.558531)
			(xy 88.979376 -348.504547) (xy 88.994741 -348.452218) (xy 89.017396 -348.402608) (xy 89.046881 -348.356726)
			(xy 89.082595 -348.315508) (xy 89.123812 -348.279792) (xy 89.169692 -348.250305) (xy 89.219301 -348.227647)
			(xy 89.27163 -348.21228) (xy 89.325613 -348.204516) (xy 89.352882 -348.204028) (xy 90.216482 -348.204028)
			(xy 90.243753 -348.20451) (xy 90.297741 -348.21227) (xy 90.350074 -348.227634) (xy 90.399688 -348.25029)
			(xy 90.445573 -348.279777) (xy 90.486794 -348.315493) (xy 90.522512 -348.356713) (xy 90.552001 -348.402596)
			(xy 90.574659 -348.452209) (xy 90.590026 -348.504542) (xy 90.597788 -348.558529) (xy 90.597788 -348.613071)
			(xy 90.597788 -348.613074) (xy 92.080492 -348.613074) (xy 92.080492 -348.558526) (xy 92.088255 -348.504534)
			(xy 92.103624 -348.452197) (xy 92.126285 -348.40258) (xy 92.155777 -348.356693) (xy 92.1915 -348.315471)
			(xy 92.232727 -348.279752) (xy 92.278617 -348.250265) (xy 92.328236 -348.227609) (xy 92.380576 -348.212246)
			(xy 92.434568 -348.204489) (xy 92.461842 -348.204028) (xy 93.325442 -348.204028) (xy 93.352709 -348.204537)
			(xy 93.406686 -348.212304) (xy 93.459009 -348.227672) (xy 93.508613 -348.25033) (xy 93.554487 -348.279816)
			(xy 93.595699 -348.315531) (xy 93.631409 -348.356746) (xy 93.66089 -348.402624) (xy 93.683543 -348.45223)
			(xy 93.698905 -348.504555) (xy 93.706666 -348.558533) (xy 93.706666 -348.613067) (xy 93.706665 -348.613072)
			(xy 111.480792 -348.613072) (xy 111.480792 -348.558528) (xy 111.488554 -348.504539) (xy 111.503921 -348.452204)
			(xy 111.52658 -348.402589) (xy 111.556069 -348.356704) (xy 111.591788 -348.315483) (xy 111.63301 -348.279764)
			(xy 111.678896 -348.250276) (xy 111.728512 -348.227618) (xy 111.780847 -348.212252) (xy 111.834836 -348.204491)
			(xy 111.862108 -348.204028) (xy 112.725708 -348.204028) (xy 112.752976 -348.204535) (xy 112.806958 -348.212297)
			(xy 112.859285 -348.227663) (xy 112.908893 -348.250319) (xy 112.954771 -348.279804) (xy 112.995987 -348.315519)
			(xy 113.0317 -348.356735) (xy 113.061185 -348.402614) (xy 113.08384 -348.452223) (xy 113.099204 -348.50455)
			(xy 113.106966 -348.558532) (xy 113.106966 -348.613068) (xy 113.106966 -348.613069) (xy 114.589814 -348.613069)
			(xy 114.589814 -348.558531) (xy 114.597575 -348.504549) (xy 114.61294 -348.452221) (xy 114.635594 -348.402611)
			(xy 114.665078 -348.356731) (xy 114.70079 -348.315513) (xy 114.742005 -348.279797) (xy 114.787883 -348.250309)
			(xy 114.837491 -348.227651) (xy 114.889818 -348.212282) (xy 114.943799 -348.204517) (xy 114.971068 -348.204028)
			(xy 115.834668 -348.204028) (xy 115.86194 -348.204509) (xy 115.915929 -348.212268) (xy 115.968264 -348.227631)
			(xy 116.01788 -348.250286) (xy 116.063766 -348.279772) (xy 116.104989 -348.315488) (xy 116.140709 -348.356708)
			(xy 116.170199 -348.402592) (xy 116.192858 -348.452206) (xy 116.208226 -348.50454) (xy 116.215988 -348.558528)
			(xy 116.215988 -348.613072) (xy 116.215988 -348.613073) (xy 117.698692 -348.613073) (xy 117.698692 -348.558527)
			(xy 117.706455 -348.504536) (xy 117.721823 -348.4522) (xy 117.744483 -348.402584) (xy 117.773974 -348.356697)
			(xy 117.809695 -348.315476) (xy 117.85092 -348.279757) (xy 117.896808 -348.25027) (xy 117.946426 -348.227613)
			(xy 117.998764 -348.212249) (xy 118.052755 -348.20449) (xy 118.080028 -348.204028) (xy 118.943628 -348.204028)
			(xy 118.970895 -348.204536) (xy 119.024875 -348.212301) (xy 119.077199 -348.227668) (xy 119.126805 -348.250326)
			(xy 119.172681 -348.279811) (xy 119.213894 -348.315526) (xy 119.249605 -348.356742) (xy 119.279088 -348.40262)
			(xy 119.301741 -348.452227) (xy 119.317105 -348.504553) (xy 119.324866 -348.558533) (xy 119.324866 -348.613067)
			(xy 119.324866 -348.61307) (xy 120.807714 -348.61307) (xy 120.807714 -348.55853) (xy 120.815476 -348.504546)
			(xy 120.830841 -348.452217) (xy 120.853497 -348.402606) (xy 120.882983 -348.356724) (xy 120.918697 -348.315506)
			(xy 120.959915 -348.27979) (xy 121.005795 -348.250303) (xy 121.055405 -348.227645) (xy 121.107735 -348.212279)
			(xy 121.161718 -348.204515) (xy 121.188988 -348.204028) (xy 122.052588 -348.204028) (xy 122.079859 -348.204511)
			(xy 122.133846 -348.212271) (xy 122.186178 -348.227636) (xy 122.235792 -348.250292) (xy 122.281676 -348.279779)
			(xy 122.322896 -348.315495) (xy 122.358614 -348.356715) (xy 122.388102 -348.402598) (xy 122.41076 -348.45221)
			(xy 122.426126 -348.504543) (xy 122.433889 -348.558529) (xy 122.433889 -348.613071) (xy 122.433889 -348.613074)
			(xy 123.916592 -348.613074) (xy 123.916592 -348.558526) (xy 123.924355 -348.504534) (xy 123.939724 -348.452196)
			(xy 123.962386 -348.402578) (xy 123.991879 -348.356691) (xy 124.027602 -348.315468) (xy 124.068829 -348.27975)
			(xy 124.11472 -348.250263) (xy 124.164341 -348.227608) (xy 124.216681 -348.212245) (xy 124.270674 -348.204488)
			(xy 124.297948 -348.204028) (xy 125.161548 -348.204028) (xy 125.188814 -348.204538) (xy 125.242791 -348.212305)
			(xy 125.295114 -348.227674) (xy 125.344717 -348.250332) (xy 125.39059 -348.279819) (xy 125.431801 -348.315533)
			(xy 125.46751 -348.356748) (xy 125.496991 -348.402626) (xy 125.519643 -348.452231) (xy 125.535006 -348.504556)
			(xy 125.542766 -348.558534) (xy 125.542766 -348.613066) (xy 125.542765 -348.613072) (xy 127.025592 -348.613072)
			(xy 127.025592 -348.558528) (xy 127.033354 -348.504539) (xy 127.048721 -348.452204) (xy 127.07138 -348.402589)
			(xy 127.100869 -348.356704) (xy 127.136588 -348.315483) (xy 127.17781 -348.279764) (xy 127.223696 -348.250276)
			(xy 127.273312 -348.227618) (xy 127.325647 -348.212252) (xy 127.379636 -348.204491) (xy 127.406908 -348.204028)
			(xy 128.270508 -348.204028) (xy 128.297776 -348.204535) (xy 128.351758 -348.212297) (xy 128.404085 -348.227663)
			(xy 128.453693 -348.250319) (xy 128.499571 -348.279804) (xy 128.540787 -348.315519) (xy 128.5765 -348.356735)
			(xy 128.605985 -348.402614) (xy 128.62864 -348.452223) (xy 128.644004 -348.50455) (xy 128.651766 -348.558532)
			(xy 128.651766 -348.613068) (xy 128.651766 -348.613069) (xy 130.134614 -348.613069) (xy 130.134614 -348.558531)
			(xy 130.142375 -348.504549) (xy 130.15774 -348.452221) (xy 130.180394 -348.402611) (xy 130.209878 -348.356731)
			(xy 130.24559 -348.315513) (xy 130.286805 -348.279797) (xy 130.332683 -348.250309) (xy 130.382291 -348.227651)
			(xy 130.434618 -348.212282) (xy 130.488599 -348.204517) (xy 130.515868 -348.204028) (xy 131.379468 -348.204028)
			(xy 131.40674 -348.204509) (xy 131.460729 -348.212268) (xy 131.513064 -348.227631) (xy 131.56268 -348.250286)
			(xy 131.608566 -348.279772) (xy 131.649789 -348.315488) (xy 131.685509 -348.356708) (xy 131.714999 -348.402592)
			(xy 131.737658 -348.452206) (xy 131.753026 -348.50454) (xy 131.760788 -348.558528) (xy 131.760788 -348.613072)
			(xy 131.760788 -348.613073) (xy 133.243492 -348.613073) (xy 133.243492 -348.558527) (xy 133.251255 -348.504536)
			(xy 133.266623 -348.4522) (xy 133.289283 -348.402584) (xy 133.318774 -348.356697) (xy 133.354495 -348.315476)
			(xy 133.39572 -348.279757) (xy 133.441608 -348.25027) (xy 133.491226 -348.227613) (xy 133.543564 -348.212249)
			(xy 133.597555 -348.20449) (xy 133.624828 -348.204028) (xy 134.488428 -348.204028) (xy 134.515695 -348.204536)
			(xy 134.569675 -348.212301) (xy 134.621999 -348.227668) (xy 134.671605 -348.250326) (xy 134.717481 -348.279811)
			(xy 134.758694 -348.315526) (xy 134.794405 -348.356742) (xy 134.823888 -348.40262) (xy 134.846541 -348.452227)
			(xy 134.861905 -348.504553) (xy 134.869666 -348.558533) (xy 134.869666 -348.613067) (xy 134.869666 -348.61307)
			(xy 136.352514 -348.61307) (xy 136.352514 -348.55853) (xy 136.360276 -348.504546) (xy 136.375641 -348.452217)
			(xy 136.398297 -348.402606) (xy 136.427783 -348.356724) (xy 136.463497 -348.315506) (xy 136.504715 -348.27979)
			(xy 136.550595 -348.250303) (xy 136.600205 -348.227645) (xy 136.652535 -348.212279) (xy 136.706518 -348.204515)
			(xy 136.733788 -348.204028) (xy 137.597388 -348.204028) (xy 137.624659 -348.204511) (xy 137.678646 -348.212271)
			(xy 137.730978 -348.227636) (xy 137.780592 -348.250292) (xy 137.826476 -348.279779) (xy 137.867696 -348.315495)
			(xy 137.903414 -348.356715) (xy 137.932902 -348.402598) (xy 137.95556 -348.45221) (xy 137.970926 -348.504543)
			(xy 137.978689 -348.558529) (xy 137.978689 -348.613071) (xy 137.978689 -348.613074) (xy 139.461392 -348.613074)
			(xy 139.461392 -348.558526) (xy 139.469155 -348.504534) (xy 139.484524 -348.452196) (xy 139.507186 -348.402578)
			(xy 139.536679 -348.356691) (xy 139.572402 -348.315468) (xy 139.613629 -348.27975) (xy 139.65952 -348.250263)
			(xy 139.709141 -348.227608) (xy 139.761481 -348.212245) (xy 139.815474 -348.204488) (xy 139.842748 -348.204028)
			(xy 140.706348 -348.204028) (xy 140.733614 -348.204538) (xy 140.787591 -348.212305) (xy 140.839914 -348.227674)
			(xy 140.889517 -348.250332) (xy 140.93539 -348.279819) (xy 140.976601 -348.315533) (xy 141.01231 -348.356748)
			(xy 141.041791 -348.402626) (xy 141.064443 -348.452231) (xy 141.079806 -348.504556) (xy 141.087566 -348.558534)
			(xy 141.087566 -348.613066) (xy 141.087565 -348.613072) (xy 142.570392 -348.613072) (xy 142.570392 -348.558528)
			(xy 142.578154 -348.504539) (xy 142.593521 -348.452204) (xy 142.61618 -348.402589) (xy 142.645669 -348.356704)
			(xy 142.681388 -348.315483) (xy 142.72261 -348.279764) (xy 142.768496 -348.250276) (xy 142.818112 -348.227618)
			(xy 142.870447 -348.212252) (xy 142.924436 -348.204491) (xy 142.951708 -348.204028) (xy 143.815308 -348.204028)
			(xy 143.842576 -348.204535) (xy 143.896558 -348.212297) (xy 143.948885 -348.227663) (xy 143.998493 -348.250319)
			(xy 144.044371 -348.279804) (xy 144.085587 -348.315519) (xy 144.1213 -348.356735) (xy 144.150785 -348.402614)
			(xy 144.17344 -348.452223) (xy 144.188804 -348.50455) (xy 144.196566 -348.558532) (xy 144.196566 -348.613068)
			(xy 144.196565 -348.613072) (xy 161.804792 -348.613072) (xy 161.804792 -348.558528) (xy 161.812554 -348.504538)
			(xy 161.827921 -348.452203) (xy 161.850581 -348.402588) (xy 161.88007 -348.356703) (xy 161.91579 -348.315481)
			(xy 161.957012 -348.279763) (xy 162.002899 -348.250275) (xy 162.052515 -348.227617) (xy 162.10485 -348.212252)
			(xy 162.15884 -348.204491) (xy 162.186112 -348.204028) (xy 163.049712 -348.204028) (xy 163.07698 -348.204535)
			(xy 163.130961 -348.212298) (xy 163.183288 -348.227664) (xy 163.232895 -348.25032) (xy 163.278773 -348.279806)
			(xy 163.319988 -348.31552) (xy 163.355701 -348.356736) (xy 163.385185 -348.402615) (xy 163.40784 -348.452224)
			(xy 163.423204 -348.504551) (xy 163.430966 -348.558532) (xy 163.430966 -348.613068) (xy 163.430966 -348.613069)
			(xy 164.913814 -348.613069) (xy 164.913814 -348.558531) (xy 164.921576 -348.504549) (xy 164.93694 -348.45222)
			(xy 164.959595 -348.40261) (xy 164.989079 -348.35673) (xy 165.024792 -348.315512) (xy 165.066007 -348.279795)
			(xy 165.111886 -348.250308) (xy 165.161494 -348.22765) (xy 165.213821 -348.212281) (xy 165.267803 -348.204516)
			(xy 165.295072 -348.204028) (xy 166.158672 -348.204028) (xy 166.185944 -348.20451) (xy 166.239932 -348.212268)
			(xy 166.292267 -348.227632) (xy 166.341882 -348.250287) (xy 166.387768 -348.279773) (xy 166.42899 -348.31549)
			(xy 166.46471 -348.356709) (xy 166.494199 -348.402593) (xy 166.516859 -348.452207) (xy 166.532226 -348.504541)
			(xy 166.539988 -348.558528) (xy 166.539988 -348.613072) (xy 166.539988 -348.613073) (xy 168.022692 -348.613073)
			(xy 168.022692 -348.558527) (xy 168.030455 -348.504536) (xy 168.045823 -348.452199) (xy 168.068484 -348.402583)
			(xy 168.097975 -348.356696) (xy 168.133697 -348.315474) (xy 168.174922 -348.279756) (xy 168.220811 -348.250268)
			(xy 168.270429 -348.227612) (xy 168.322767 -348.212248) (xy 168.376759 -348.204489) (xy 168.404032 -348.204028)
			(xy 169.267632 -348.204028) (xy 169.294899 -348.204537) (xy 169.348878 -348.212302) (xy 169.401202 -348.227669)
			(xy 169.450807 -348.250327) (xy 169.496683 -348.279813) (xy 169.537895 -348.315527) (xy 169.573606 -348.356743)
			(xy 169.603088 -348.402621) (xy 169.625742 -348.452228) (xy 169.641105 -348.504553) (xy 169.648866 -348.558533)
			(xy 169.648866 -348.613067) (xy 169.648866 -348.61307) (xy 171.131714 -348.61307) (xy 171.131714 -348.55853)
			(xy 171.139476 -348.504546) (xy 171.154841 -348.452216) (xy 171.177498 -348.402605) (xy 171.206984 -348.356723)
			(xy 171.242699 -348.315505) (xy 171.283917 -348.279788) (xy 171.329798 -348.250301) (xy 171.379408 -348.227644)
			(xy 171.431738 -348.212278) (xy 171.485722 -348.204515) (xy 171.512992 -348.204028) (xy 172.376592 -348.204028)
			(xy 172.403863 -348.204511) (xy 172.457849 -348.212272) (xy 172.510181 -348.227637) (xy 172.559794 -348.250294)
			(xy 172.605678 -348.27978) (xy 172.646898 -348.315497) (xy 172.682615 -348.356716) (xy 172.712103 -348.402599)
			(xy 172.73476 -348.452211) (xy 172.750126 -348.504543) (xy 172.757889 -348.558529) (xy 172.757889 -348.613068)
			(xy 174.240714 -348.613068) (xy 174.240714 -348.558532) (xy 174.248475 -348.504551) (xy 174.263838 -348.452224)
			(xy 174.286492 -348.402616) (xy 174.315974 -348.356736) (xy 174.351685 -348.315519) (xy 174.392898 -348.279803)
			(xy 174.438774 -348.250315) (xy 174.488379 -348.227655) (xy 174.540704 -348.212285) (xy 174.594684 -348.204518)
			(xy 174.621952 -348.204028) (xy 175.485552 -348.204028) (xy 175.512825 -348.204508) (xy 175.566815 -348.212265)
			(xy 175.619152 -348.227626) (xy 175.66877 -348.250281) (xy 175.714659 -348.279766) (xy 175.755883 -348.315483)
			(xy 175.791605 -348.356703) (xy 175.821096 -348.402588) (xy 175.843757 -348.452203) (xy 175.859125 -348.504538)
			(xy 175.866888 -348.558528) (xy 175.866888 -348.613072) (xy 177.349592 -348.613072) (xy 177.349592 -348.558528)
			(xy 177.357354 -348.504538) (xy 177.372721 -348.452203) (xy 177.395381 -348.402588) (xy 177.42487 -348.356703)
			(xy 177.46059 -348.315481) (xy 177.501812 -348.279763) (xy 177.547699 -348.250275) (xy 177.597315 -348.227617)
			(xy 177.64965 -348.212252) (xy 177.70364 -348.204491) (xy 177.730912 -348.204028) (xy 178.594512 -348.204028)
			(xy 178.62178 -348.204535) (xy 178.675761 -348.212298) (xy 178.728088 -348.227664) (xy 178.777695 -348.25032)
			(xy 178.823573 -348.279806) (xy 178.864788 -348.31552) (xy 178.900501 -348.356736) (xy 178.929985 -348.402615)
			(xy 178.95264 -348.452224) (xy 178.968004 -348.504551) (xy 178.975766 -348.558532) (xy 178.975766 -348.613068)
			(xy 178.975766 -348.613069) (xy 180.458614 -348.613069) (xy 180.458614 -348.558531) (xy 180.466376 -348.504549)
			(xy 180.48174 -348.45222) (xy 180.504395 -348.40261) (xy 180.533879 -348.35673) (xy 180.569592 -348.315512)
			(xy 180.610807 -348.279795) (xy 180.656686 -348.250308) (xy 180.706294 -348.22765) (xy 180.758621 -348.212281)
			(xy 180.812603 -348.204516) (xy 180.839872 -348.204028) (xy 181.703472 -348.204028) (xy 181.730744 -348.20451)
			(xy 181.784732 -348.212268) (xy 181.837067 -348.227632) (xy 181.886682 -348.250287) (xy 181.932568 -348.279773)
			(xy 181.97379 -348.31549) (xy 182.00951 -348.356709) (xy 182.038999 -348.402593) (xy 182.061659 -348.452207)
			(xy 182.077026 -348.504541) (xy 182.084788 -348.558528) (xy 182.084788 -348.613072) (xy 182.084788 -348.613073)
			(xy 183.567492 -348.613073) (xy 183.567492 -348.558527) (xy 183.575255 -348.504536) (xy 183.590623 -348.452199)
			(xy 183.613284 -348.402583) (xy 183.642775 -348.356696) (xy 183.678497 -348.315474) (xy 183.719722 -348.279756)
			(xy 183.765611 -348.250268) (xy 183.815229 -348.227612) (xy 183.867567 -348.212248) (xy 183.921559 -348.204489)
			(xy 183.948832 -348.204028) (xy 184.812432 -348.204028) (xy 184.839699 -348.204537) (xy 184.893678 -348.212302)
			(xy 184.946002 -348.227669) (xy 184.995607 -348.250327) (xy 185.041483 -348.279813) (xy 185.082695 -348.315527)
			(xy 185.118406 -348.356743) (xy 185.147888 -348.402621) (xy 185.170542 -348.452228) (xy 185.185905 -348.504553)
			(xy 185.193666 -348.558533) (xy 185.193666 -348.613067) (xy 185.193666 -348.61307) (xy 186.676514 -348.61307)
			(xy 186.676514 -348.55853) (xy 186.684276 -348.504546) (xy 186.699641 -348.452216) (xy 186.722298 -348.402605)
			(xy 186.751784 -348.356723) (xy 186.787499 -348.315505) (xy 186.828717 -348.279788) (xy 186.874598 -348.250301)
			(xy 186.924208 -348.227644) (xy 186.976538 -348.212278) (xy 187.030522 -348.204515) (xy 187.057792 -348.204028)
			(xy 187.921392 -348.204028) (xy 187.948663 -348.204511) (xy 188.002649 -348.212272) (xy 188.054981 -348.227637)
			(xy 188.104594 -348.250294) (xy 188.150478 -348.27978) (xy 188.191698 -348.315497) (xy 188.227415 -348.356716)
			(xy 188.256903 -348.402599) (xy 188.27956 -348.452211) (xy 188.294926 -348.504543) (xy 188.302689 -348.558529)
			(xy 188.302689 -348.613068) (xy 189.785514 -348.613068) (xy 189.785514 -348.558532) (xy 189.793275 -348.504551)
			(xy 189.808638 -348.452224) (xy 189.831292 -348.402616) (xy 189.860774 -348.356736) (xy 189.896485 -348.315519)
			(xy 189.937698 -348.279803) (xy 189.983574 -348.250315) (xy 190.033179 -348.227655) (xy 190.085504 -348.212285)
			(xy 190.139484 -348.204518) (xy 190.166752 -348.204028) (xy 191.030352 -348.204028) (xy 191.057625 -348.204508)
			(xy 191.111615 -348.212265) (xy 191.163952 -348.227626) (xy 191.21357 -348.250281) (xy 191.259459 -348.279766)
			(xy 191.300683 -348.315483) (xy 191.336405 -348.356703) (xy 191.365896 -348.402588) (xy 191.388557 -348.452203)
			(xy 191.403925 -348.504538) (xy 191.411688 -348.558528) (xy 191.411688 -348.613072) (xy 192.894392 -348.613072)
			(xy 192.894392 -348.558528) (xy 192.902154 -348.504538) (xy 192.917521 -348.452203) (xy 192.940181 -348.402588)
			(xy 192.96967 -348.356703) (xy 193.00539 -348.315481) (xy 193.046612 -348.279763) (xy 193.092499 -348.250275)
			(xy 193.142115 -348.227617) (xy 193.19445 -348.212252) (xy 193.24844 -348.204491) (xy 193.275712 -348.204028)
			(xy 194.139312 -348.204028) (xy 194.16658 -348.204535) (xy 194.220561 -348.212298) (xy 194.272888 -348.227664)
			(xy 194.322495 -348.25032) (xy 194.368373 -348.279806) (xy 194.409588 -348.31552) (xy 194.445301 -348.356736)
			(xy 194.474785 -348.402615) (xy 194.49744 -348.452224) (xy 194.512804 -348.504551) (xy 194.520566 -348.558532)
			(xy 194.520566 -348.613068) (xy 194.520565 -348.613072) (xy 267.515792 -348.613072) (xy 267.515792 -348.558528)
			(xy 267.523554 -348.50454) (xy 267.538921 -348.452206) (xy 267.561579 -348.402591) (xy 267.591068 -348.356706)
			(xy 267.626786 -348.315485) (xy 267.668008 -348.279766) (xy 267.713893 -348.250278) (xy 267.763507 -348.22762)
			(xy 267.815842 -348.212253) (xy 267.86983 -348.204491) (xy 267.897102 -348.204028) (xy 268.760702 -348.204028)
			(xy 268.787971 -348.204535) (xy 268.841953 -348.212296) (xy 268.89428 -348.227661) (xy 268.943889 -348.250317)
			(xy 268.989769 -348.279802) (xy 269.030985 -348.315517) (xy 269.066699 -348.356733) (xy 269.096184 -348.402613)
			(xy 269.118839 -348.452221) (xy 269.134204 -348.504549) (xy 269.141966 -348.558531) (xy 269.141966 -348.613068)
			(xy 270.624814 -348.613068) (xy 270.624814 -348.558532) (xy 270.632575 -348.50455) (xy 270.647939 -348.452222)
			(xy 270.670593 -348.402613) (xy 270.700076 -348.356733) (xy 270.735788 -348.315515) (xy 270.777002 -348.279799)
			(xy 270.82288 -348.250311) (xy 270.872486 -348.227652) (xy 270.924813 -348.212283) (xy 270.978794 -348.204517)
			(xy 271.006062 -348.204028) (xy 271.869662 -348.204028) (xy 271.896934 -348.204509) (xy 271.950924 -348.212266)
			(xy 272.00326 -348.227629) (xy 272.052876 -348.250284) (xy 272.098763 -348.27977) (xy 272.139987 -348.315486)
			(xy 272.175708 -348.356706) (xy 272.205198 -348.40259) (xy 272.227858 -348.452205) (xy 272.243226 -348.504539)
			(xy 272.250988 -348.558528) (xy 272.250988 -348.613072) (xy 272.250988 -348.613073) (xy 273.733692 -348.613073)
			(xy 273.733692 -348.558527) (xy 273.741454 -348.504537) (xy 273.756822 -348.452201) (xy 273.779482 -348.402585)
			(xy 273.808972 -348.356699) (xy 273.844693 -348.315478) (xy 273.885917 -348.279759) (xy 273.931805 -348.250271)
			(xy 273.981422 -348.227615) (xy 274.033759 -348.21225) (xy 274.087749 -348.20449) (xy 274.115022 -348.204028)
			(xy 274.978622 -348.204028) (xy 275.00589 -348.204536) (xy 275.059869 -348.2123) (xy 275.112195 -348.227667)
			(xy 275.161801 -348.250324) (xy 275.207678 -348.279809) (xy 275.248892 -348.315524) (xy 275.284604 -348.35674)
			(xy 275.314087 -348.402618) (xy 275.336741 -348.452226) (xy 275.352105 -348.504552) (xy 275.359866 -348.558532)
			(xy 275.359866 -348.613068) (xy 275.359866 -348.613069) (xy 276.842714 -348.613069) (xy 276.842714 -348.558531)
			(xy 276.850476 -348.504547) (xy 276.865841 -348.452218) (xy 276.888496 -348.402608) (xy 276.917981 -348.356726)
			(xy 276.953695 -348.315508) (xy 276.994912 -348.279792) (xy 277.040792 -348.250305) (xy 277.090401 -348.227647)
			(xy 277.14273 -348.21228) (xy 277.196713 -348.204516) (xy 277.223982 -348.204028) (xy 278.087582 -348.204028)
			(xy 278.114853 -348.20451) (xy 278.168841 -348.21227) (xy 278.221174 -348.227634) (xy 278.270788 -348.25029)
			(xy 278.316673 -348.279777) (xy 278.357894 -348.315493) (xy 278.393612 -348.356713) (xy 278.423101 -348.402596)
			(xy 278.445759 -348.452209) (xy 278.461126 -348.504542) (xy 278.468888 -348.558529) (xy 278.468888 -348.613071)
			(xy 278.468888 -348.613074) (xy 279.951592 -348.613074) (xy 279.951592 -348.558526) (xy 279.959355 -348.504534)
			(xy 279.974724 -348.452197) (xy 279.997385 -348.40258) (xy 280.026877 -348.356693) (xy 280.0626 -348.315471)
			(xy 280.103827 -348.279752) (xy 280.149717 -348.250265) (xy 280.199336 -348.227609) (xy 280.251676 -348.212246)
			(xy 280.305668 -348.204489) (xy 280.332942 -348.204028) (xy 281.196542 -348.204028) (xy 281.223809 -348.204537)
			(xy 281.277786 -348.212304) (xy 281.330109 -348.227672) (xy 281.379713 -348.25033) (xy 281.425587 -348.279816)
			(xy 281.466799 -348.315531) (xy 281.502509 -348.356746) (xy 281.53199 -348.402624) (xy 281.554643 -348.45223)
			(xy 281.570005 -348.504555) (xy 281.577766 -348.558533) (xy 281.577766 -348.613067) (xy 281.577765 -348.613072)
			(xy 283.060592 -348.613072) (xy 283.060592 -348.558528) (xy 283.068354 -348.50454) (xy 283.083721 -348.452206)
			(xy 283.106379 -348.402591) (xy 283.135868 -348.356706) (xy 283.171586 -348.315485) (xy 283.212808 -348.279766)
			(xy 283.258693 -348.250278) (xy 283.308307 -348.22762) (xy 283.360642 -348.212253) (xy 283.41463 -348.204491)
			(xy 283.441902 -348.204028) (xy 284.305502 -348.204028) (xy 284.332771 -348.204535) (xy 284.386753 -348.212296)
			(xy 284.43908 -348.227661) (xy 284.488689 -348.250317) (xy 284.534569 -348.279802) (xy 284.575785 -348.315517)
			(xy 284.611499 -348.356733) (xy 284.640984 -348.402613) (xy 284.663639 -348.452221) (xy 284.679004 -348.504549)
			(xy 284.686766 -348.558531) (xy 284.686766 -348.613068) (xy 286.169614 -348.613068) (xy 286.169614 -348.558532)
			(xy 286.177375 -348.50455) (xy 286.192739 -348.452222) (xy 286.215393 -348.402613) (xy 286.244876 -348.356733)
			(xy 286.280588 -348.315515) (xy 286.321802 -348.279799) (xy 286.36768 -348.250311) (xy 286.417286 -348.227652)
			(xy 286.469613 -348.212283) (xy 286.523594 -348.204517) (xy 286.550862 -348.204028) (xy 287.414462 -348.204028)
			(xy 287.441734 -348.204509) (xy 287.495724 -348.212266) (xy 287.54806 -348.227629) (xy 287.597676 -348.250284)
			(xy 287.643563 -348.27977) (xy 287.684787 -348.315486) (xy 287.720508 -348.356706) (xy 287.749998 -348.40259)
			(xy 287.772658 -348.452205) (xy 287.788026 -348.504539) (xy 287.795788 -348.558528) (xy 287.795788 -348.613072)
			(xy 287.795788 -348.613073) (xy 289.278492 -348.613073) (xy 289.278492 -348.558527) (xy 289.286254 -348.504537)
			(xy 289.301622 -348.452201) (xy 289.324282 -348.402585) (xy 289.353772 -348.356699) (xy 289.389493 -348.315478)
			(xy 289.430717 -348.279759) (xy 289.476605 -348.250271) (xy 289.526222 -348.227615) (xy 289.578559 -348.21225)
			(xy 289.632549 -348.20449) (xy 289.659822 -348.204028) (xy 290.523422 -348.204028) (xy 290.55069 -348.204536)
			(xy 290.604669 -348.2123) (xy 290.656995 -348.227667) (xy 290.706601 -348.250324) (xy 290.752478 -348.279809)
			(xy 290.793692 -348.315524) (xy 290.829404 -348.35674) (xy 290.858887 -348.402618) (xy 290.881541 -348.452226)
			(xy 290.896905 -348.504552) (xy 290.904666 -348.558532) (xy 290.904666 -348.613068) (xy 290.904666 -348.613069)
			(xy 292.387514 -348.613069) (xy 292.387514 -348.558531) (xy 292.395276 -348.504547) (xy 292.410641 -348.452218)
			(xy 292.433296 -348.402608) (xy 292.462781 -348.356726) (xy 292.498495 -348.315508) (xy 292.539712 -348.279792)
			(xy 292.585592 -348.250305) (xy 292.635201 -348.227647) (xy 292.68753 -348.21228) (xy 292.741513 -348.204516)
			(xy 292.768782 -348.204028) (xy 293.632382 -348.204028) (xy 293.659653 -348.20451) (xy 293.713641 -348.21227)
			(xy 293.765974 -348.227634) (xy 293.815588 -348.25029) (xy 293.861473 -348.279777) (xy 293.902694 -348.315493)
			(xy 293.938412 -348.356713) (xy 293.967901 -348.402596) (xy 293.990559 -348.452209) (xy 294.005926 -348.504542)
			(xy 294.013688 -348.558529) (xy 294.013688 -348.613071) (xy 294.013688 -348.613074) (xy 295.496392 -348.613074)
			(xy 295.496392 -348.558526) (xy 295.504155 -348.504534) (xy 295.519524 -348.452197) (xy 295.542185 -348.40258)
			(xy 295.571677 -348.356693) (xy 295.6074 -348.315471) (xy 295.648627 -348.279752) (xy 295.694517 -348.250265)
			(xy 295.744136 -348.227609) (xy 295.796476 -348.212246) (xy 295.850468 -348.204489) (xy 295.877742 -348.204028)
			(xy 296.741342 -348.204028) (xy 296.768609 -348.204537) (xy 296.822586 -348.212304) (xy 296.874909 -348.227672)
			(xy 296.924513 -348.25033) (xy 296.970387 -348.279816) (xy 297.011599 -348.315531) (xy 297.047309 -348.356746)
			(xy 297.07679 -348.402624) (xy 297.099443 -348.45223) (xy 297.114805 -348.504555) (xy 297.122566 -348.558533)
			(xy 297.122566 -348.613067) (xy 297.122565 -348.613072) (xy 298.605392 -348.613072) (xy 298.605392 -348.558528)
			(xy 298.613154 -348.50454) (xy 298.628521 -348.452206) (xy 298.651179 -348.402591) (xy 298.680668 -348.356706)
			(xy 298.716386 -348.315485) (xy 298.757608 -348.279766) (xy 298.803493 -348.250278) (xy 298.853107 -348.22762)
			(xy 298.905442 -348.212253) (xy 298.95943 -348.204491) (xy 298.986702 -348.204028) (xy 299.850302 -348.204028)
			(xy 299.877571 -348.204535) (xy 299.931553 -348.212296) (xy 299.98388 -348.227661) (xy 300.033489 -348.250317)
			(xy 300.079369 -348.279802) (xy 300.120585 -348.315517) (xy 300.156299 -348.356733) (xy 300.185784 -348.402613)
			(xy 300.208439 -348.452221) (xy 300.223804 -348.504549) (xy 300.231566 -348.558531) (xy 300.231566 -348.613069)
			(xy 300.231566 -348.613072) (xy 312.121492 -348.613072) (xy 312.121492 -348.558528) (xy 312.129254 -348.504539)
			(xy 312.144621 -348.452205) (xy 312.167279 -348.40259) (xy 312.196768 -348.356705) (xy 312.232487 -348.315484)
			(xy 312.273709 -348.279766) (xy 312.319594 -348.250277) (xy 312.369209 -348.227619) (xy 312.421543 -348.212253)
			(xy 312.475532 -348.204491) (xy 312.502804 -348.204028) (xy 313.366404 -348.204028) (xy 313.393672 -348.204535)
			(xy 313.447654 -348.212297) (xy 313.499982 -348.227662) (xy 313.54959 -348.250318) (xy 313.595469 -348.279803)
			(xy 313.636686 -348.315517) (xy 313.672399 -348.356734) (xy 313.701884 -348.402613) (xy 313.72454 -348.452222)
			(xy 313.739904 -348.50455) (xy 313.747666 -348.558532) (xy 313.747666 -348.613068) (xy 315.230514 -348.613068)
			(xy 315.230514 -348.558532) (xy 315.238275 -348.50455) (xy 315.253639 -348.452222) (xy 315.276293 -348.402613)
			(xy 315.305777 -348.356732) (xy 315.341489 -348.315514) (xy 315.382703 -348.279798) (xy 315.428581 -348.250311)
			(xy 315.478188 -348.227652) (xy 315.530514 -348.212283) (xy 315.584496 -348.204517) (xy 315.611764 -348.204028)
			(xy 316.475364 -348.204028) (xy 316.502636 -348.204509) (xy 316.556625 -348.212267) (xy 316.608961 -348.22763)
			(xy 316.658577 -348.250284) (xy 316.704464 -348.27977) (xy 316.745688 -348.315487) (xy 316.781408 -348.356707)
			(xy 316.810898 -348.402591) (xy 316.833558 -348.452205) (xy 316.848926 -348.504539) (xy 316.856688 -348.558528)
			(xy 316.856688 -348.613072) (xy 316.856688 -348.613073) (xy 318.339392 -348.613073) (xy 318.339392 -348.558527)
			(xy 318.347155 -348.504537) (xy 318.362522 -348.452201) (xy 318.385182 -348.402585) (xy 318.414673 -348.356699)
			(xy 318.450394 -348.315477) (xy 318.491618 -348.279759) (xy 318.537506 -348.250271) (xy 318.587123 -348.227614)
			(xy 318.63946 -348.212249) (xy 318.693451 -348.20449) (xy 318.720724 -348.204028) (xy 319.584324 -348.204028)
			(xy 319.611592 -348.204536) (xy 319.665571 -348.2123) (xy 319.717896 -348.227667) (xy 319.767502 -348.250324)
			(xy 319.813379 -348.27981) (xy 319.854593 -348.315524) (xy 319.890304 -348.35674) (xy 319.919787 -348.402619)
			(xy 319.942441 -348.452226) (xy 319.957805 -348.504552) (xy 319.965566 -348.558532) (xy 319.965566 -348.613068)
			(xy 319.965566 -348.613069) (xy 321.448414 -348.613069) (xy 321.448414 -348.558531) (xy 321.456176 -348.504547)
			(xy 321.471541 -348.452217) (xy 321.494196 -348.402607) (xy 321.523682 -348.356726) (xy 321.559396 -348.315507)
			(xy 321.600613 -348.279791) (xy 321.646493 -348.250304) (xy 321.696102 -348.227646) (xy 321.748431 -348.212279)
			(xy 321.802415 -348.204516) (xy 321.829684 -348.204028) (xy 322.693284 -348.204028) (xy 322.720555 -348.20451)
			(xy 322.774542 -348.21227) (xy 322.826875 -348.227635) (xy 322.876489 -348.250291) (xy 322.922374 -348.279777)
			(xy 322.963595 -348.315494) (xy 322.999313 -348.356713) (xy 323.028801 -348.402597) (xy 323.051459 -348.45221)
			(xy 323.066826 -348.504542) (xy 323.074588 -348.558529) (xy 323.074588 -348.613071) (xy 323.074588 -348.613074)
			(xy 324.557292 -348.613074) (xy 324.557292 -348.558526) (xy 324.565055 -348.504534) (xy 324.580424 -348.452197)
			(xy 324.603085 -348.402579) (xy 324.632578 -348.356692) (xy 324.668301 -348.31547) (xy 324.709527 -348.279751)
			(xy 324.755418 -348.250264) (xy 324.805038 -348.227609) (xy 324.857377 -348.212246) (xy 324.91137 -348.204489)
			(xy 324.938644 -348.204028) (xy 325.802244 -348.204028) (xy 325.829511 -348.204537) (xy 325.883488 -348.212304)
			(xy 325.935811 -348.227673) (xy 325.985414 -348.250331) (xy 326.031288 -348.279817) (xy 326.0725 -348.315531)
			(xy 326.108209 -348.356747) (xy 326.13769 -348.402624) (xy 326.160343 -348.45223) (xy 326.175705 -348.504555)
			(xy 326.183466 -348.558533) (xy 326.183466 -348.613067) (xy 326.183465 -348.613072) (xy 327.666292 -348.613072)
			(xy 327.666292 -348.558528) (xy 327.674054 -348.504539) (xy 327.689421 -348.452205) (xy 327.712079 -348.40259)
			(xy 327.741568 -348.356705) (xy 327.777287 -348.315484) (xy 327.818509 -348.279766) (xy 327.864394 -348.250277)
			(xy 327.914009 -348.227619) (xy 327.966343 -348.212253) (xy 328.020332 -348.204491) (xy 328.047604 -348.204028)
			(xy 328.911204 -348.204028) (xy 328.938472 -348.204535) (xy 328.992454 -348.212297) (xy 329.044782 -348.227662)
			(xy 329.09439 -348.250318) (xy 329.140269 -348.279803) (xy 329.181486 -348.315517) (xy 329.217199 -348.356734)
			(xy 329.246684 -348.402613) (xy 329.26934 -348.452222) (xy 329.284704 -348.50455) (xy 329.292466 -348.558532)
			(xy 329.292466 -348.613068) (xy 330.775314 -348.613068) (xy 330.775314 -348.558532) (xy 330.783075 -348.50455)
			(xy 330.798439 -348.452222) (xy 330.821093 -348.402613) (xy 330.850577 -348.356732) (xy 330.886289 -348.315514)
			(xy 330.927503 -348.279798) (xy 330.973381 -348.250311) (xy 331.022988 -348.227652) (xy 331.075314 -348.212283)
			(xy 331.129296 -348.204517) (xy 331.156564 -348.204028) (xy 332.020164 -348.204028) (xy 332.047436 -348.204509)
			(xy 332.101425 -348.212267) (xy 332.153761 -348.22763) (xy 332.203377 -348.250284) (xy 332.249264 -348.27977)
			(xy 332.290488 -348.315487) (xy 332.326208 -348.356707) (xy 332.355698 -348.402591) (xy 332.378358 -348.452205)
			(xy 332.393726 -348.504539) (xy 332.401488 -348.558528) (xy 332.401488 -348.613072) (xy 332.401488 -348.613073)
			(xy 333.884192 -348.613073) (xy 333.884192 -348.558527) (xy 333.891955 -348.504537) (xy 333.907322 -348.452201)
			(xy 333.929982 -348.402585) (xy 333.959473 -348.356699) (xy 333.995194 -348.315477) (xy 334.036418 -348.279759)
			(xy 334.082306 -348.250271) (xy 334.131923 -348.227614) (xy 334.18426 -348.212249) (xy 334.238251 -348.20449)
			(xy 334.265524 -348.204028) (xy 335.129124 -348.204028) (xy 335.156392 -348.204536) (xy 335.210371 -348.2123)
			(xy 335.262696 -348.227667) (xy 335.312302 -348.250324) (xy 335.358179 -348.27981) (xy 335.399393 -348.315524)
			(xy 335.435104 -348.35674) (xy 335.464587 -348.402619) (xy 335.487241 -348.452226) (xy 335.502605 -348.504552)
			(xy 335.510366 -348.558532) (xy 335.510366 -348.613068) (xy 335.510366 -348.613069) (xy 336.993214 -348.613069)
			(xy 336.993214 -348.558531) (xy 337.000976 -348.504547) (xy 337.016341 -348.452217) (xy 337.038996 -348.402607)
			(xy 337.068482 -348.356726) (xy 337.104196 -348.315507) (xy 337.145413 -348.279791) (xy 337.191293 -348.250304)
			(xy 337.240902 -348.227646) (xy 337.293231 -348.212279) (xy 337.347215 -348.204516) (xy 337.374484 -348.204028)
			(xy 338.238084 -348.204028) (xy 338.265355 -348.20451) (xy 338.319342 -348.21227) (xy 338.371675 -348.227635)
			(xy 338.421289 -348.250291) (xy 338.467174 -348.279777) (xy 338.508395 -348.315494) (xy 338.544113 -348.356713)
			(xy 338.573601 -348.402597) (xy 338.596259 -348.45221) (xy 338.611626 -348.504542) (xy 338.619388 -348.558529)
			(xy 338.619388 -348.613071) (xy 338.619388 -348.613074) (xy 340.102092 -348.613074) (xy 340.102092 -348.558526)
			(xy 340.109855 -348.504534) (xy 340.125224 -348.452197) (xy 340.147885 -348.402579) (xy 340.177378 -348.356692)
			(xy 340.213101 -348.31547) (xy 340.254327 -348.279751) (xy 340.300218 -348.250264) (xy 340.349838 -348.227609)
			(xy 340.402177 -348.212246) (xy 340.45617 -348.204489) (xy 340.483444 -348.204028) (xy 341.347044 -348.204028)
			(xy 341.374311 -348.204537) (xy 341.428288 -348.212304) (xy 341.480611 -348.227673) (xy 341.530214 -348.250331)
			(xy 341.576088 -348.279817) (xy 341.6173 -348.315531) (xy 341.653009 -348.356747) (xy 341.68249 -348.402624)
			(xy 341.705143 -348.45223) (xy 341.720505 -348.504555) (xy 341.728266 -348.558533) (xy 341.728266 -348.613067)
			(xy 341.728265 -348.613072) (xy 343.211092 -348.613072) (xy 343.211092 -348.558528) (xy 343.218854 -348.504539)
			(xy 343.234221 -348.452205) (xy 343.256879 -348.40259) (xy 343.286368 -348.356705) (xy 343.322087 -348.315484)
			(xy 343.363309 -348.279766) (xy 343.409194 -348.250277) (xy 343.458809 -348.227619) (xy 343.511143 -348.212253)
			(xy 343.565132 -348.204491) (xy 343.592404 -348.204028) (xy 344.456004 -348.204028) (xy 344.483272 -348.204535)
			(xy 344.537254 -348.212297) (xy 344.589582 -348.227662) (xy 344.63919 -348.250318) (xy 344.685069 -348.279803)
			(xy 344.726286 -348.315517) (xy 344.761999 -348.356734) (xy 344.791484 -348.402613) (xy 344.81414 -348.452222)
			(xy 344.829504 -348.50455) (xy 344.837266 -348.558532) (xy 344.837266 -348.613068) (xy 344.837266 -348.613069)
			(xy 370.806714 -348.613069) (xy 370.806714 -348.558531) (xy 370.814476 -348.504548) (xy 370.82984 -348.452218)
			(xy 370.852496 -348.402608) (xy 370.881981 -348.356727) (xy 370.917695 -348.315509) (xy 370.958911 -348.279793)
			(xy 371.004791 -348.250305) (xy 371.054399 -348.227647) (xy 371.106728 -348.21228) (xy 371.160711 -348.204516)
			(xy 371.18798 -348.204028) (xy 372.05158 -348.204028) (xy 372.078851 -348.20451) (xy 372.132839 -348.21227)
			(xy 372.185173 -348.227634) (xy 372.234787 -348.25029) (xy 372.280672 -348.279776) (xy 372.321893 -348.315493)
			(xy 372.357612 -348.356712) (xy 372.387101 -348.402595) (xy 372.409759 -348.452209) (xy 372.425126 -348.504542)
			(xy 372.432888 -348.558529) (xy 372.432888 -348.613071) (xy 372.432888 -348.613074) (xy 373.915592 -348.613074)
			(xy 373.915592 -348.558526) (xy 373.923355 -348.504535) (xy 373.938724 -348.452197) (xy 373.961385 -348.40258)
			(xy 373.990877 -348.356694) (xy 374.0266 -348.315471) (xy 374.067826 -348.279753) (xy 374.113715 -348.250266)
			(xy 374.163335 -348.22761) (xy 374.215674 -348.212246) (xy 374.269666 -348.204489) (xy 374.29694 -348.204028)
			(xy 375.16054 -348.204028) (xy 375.187807 -348.204537) (xy 375.241785 -348.212303) (xy 375.294108 -348.227672)
			(xy 375.343712 -348.25033) (xy 375.389587 -348.279816) (xy 375.430798 -348.31553) (xy 375.466508 -348.356746)
			(xy 375.49599 -348.402623) (xy 375.518642 -348.45223) (xy 375.534005 -348.504554) (xy 375.541766 -348.558533)
			(xy 375.541766 -348.613067) (xy 375.541766 -348.61307) (xy 377.024614 -348.61307) (xy 377.024614 -348.55853)
			(xy 377.032376 -348.504545) (xy 377.047742 -348.452214) (xy 377.070399 -348.402603) (xy 377.099886 -348.35672)
			(xy 377.135602 -348.315502) (xy 377.17682 -348.279786) (xy 377.222703 -348.250299) (xy 377.272314 -348.227642)
			(xy 377.324645 -348.212276) (xy 377.37863 -348.204514) (xy 377.4059 -348.204028) (xy 378.2695 -348.204028)
			(xy 378.296769 -348.204534) (xy 378.350751 -348.212296) (xy 378.403079 -348.227661) (xy 378.452688 -348.250316)
			(xy 378.498568 -348.279802) (xy 378.539784 -348.315516) (xy 378.575498 -348.356732) (xy 378.604984 -348.402612)
			(xy 378.627639 -348.452221) (xy 378.643004 -348.504549) (xy 378.650766 -348.558531) (xy 378.650766 -348.613068)
			(xy 380.133614 -348.613068) (xy 380.133614 -348.558532) (xy 380.141375 -348.50455) (xy 380.156739 -348.452223)
			(xy 380.179393 -348.402614) (xy 380.208876 -348.356734) (xy 380.244588 -348.315516) (xy 380.285801 -348.2798)
			(xy 380.331679 -348.250312) (xy 380.381285 -348.227653) (xy 380.433611 -348.212284) (xy 380.487592 -348.204517)
			(xy 380.51486 -348.204028) (xy 381.37846 -348.204028) (xy 381.405732 -348.204509) (xy 381.459722 -348.212266)
			(xy 381.512058 -348.227628) (xy 381.561675 -348.250283) (xy 381.607562 -348.279769) (xy 381.648786 -348.315485)
			(xy 381.684507 -348.356706) (xy 381.713998 -348.40259) (xy 381.736658 -348.452204) (xy 381.752025 -348.504539)
			(xy 381.759788 -348.558528) (xy 381.759788 -348.613072) (xy 381.759788 -348.613073) (xy 383.242492 -348.613073)
			(xy 383.242492 -348.558527) (xy 383.250254 -348.504537) (xy 383.265622 -348.452202) (xy 383.288282 -348.402586)
			(xy 383.317772 -348.3567) (xy 383.353493 -348.315478) (xy 383.394716 -348.27976) (xy 383.440603 -348.250272)
			(xy 383.49022 -348.227615) (xy 383.542557 -348.21225) (xy 383.596547 -348.20449) (xy 383.62382 -348.204028)
			(xy 384.48742 -348.204028) (xy 384.514688 -348.204536) (xy 384.568668 -348.2123) (xy 384.620994 -348.227666)
			(xy 384.6706 -348.250323) (xy 384.716477 -348.279809) (xy 384.757691 -348.315523) (xy 384.793403 -348.356739)
			(xy 384.822887 -348.402618) (xy 384.845541 -348.452225) (xy 384.860905 -348.504552) (xy 384.868666 -348.558532)
			(xy 384.868666 -348.613068) (xy 384.868666 -348.613069) (xy 386.351514 -348.613069) (xy 386.351514 -348.558531)
			(xy 386.359276 -348.504548) (xy 386.37464 -348.452218) (xy 386.397296 -348.402608) (xy 386.426781 -348.356727)
			(xy 386.462495 -348.315509) (xy 386.503711 -348.279793) (xy 386.549591 -348.250305) (xy 386.599199 -348.227647)
			(xy 386.651528 -348.21228) (xy 386.705511 -348.204516) (xy 386.73278 -348.204028) (xy 387.59638 -348.204028)
			(xy 387.623651 -348.20451) (xy 387.677639 -348.21227) (xy 387.729973 -348.227634) (xy 387.779587 -348.25029)
			(xy 387.825472 -348.279776) (xy 387.866693 -348.315493) (xy 387.902412 -348.356712) (xy 387.931901 -348.402595)
			(xy 387.954559 -348.452209) (xy 387.969926 -348.504542) (xy 387.977688 -348.558529) (xy 387.977688 -348.613071)
			(xy 387.977688 -348.613074) (xy 389.460392 -348.613074) (xy 389.460392 -348.558526) (xy 389.468155 -348.504535)
			(xy 389.483524 -348.452197) (xy 389.506185 -348.40258) (xy 389.535677 -348.356694) (xy 389.5714 -348.315471)
			(xy 389.612626 -348.279753) (xy 389.658515 -348.250266) (xy 389.708135 -348.22761) (xy 389.760474 -348.212246)
			(xy 389.814466 -348.204489) (xy 389.84174 -348.204028) (xy 390.70534 -348.204028) (xy 390.732607 -348.204537)
			(xy 390.786585 -348.212303) (xy 390.838908 -348.227672) (xy 390.888512 -348.25033) (xy 390.934387 -348.279816)
			(xy 390.975598 -348.31553) (xy 391.011308 -348.356746) (xy 391.04079 -348.402623) (xy 391.063442 -348.45223)
			(xy 391.078805 -348.504554) (xy 391.086566 -348.558533) (xy 391.086566 -348.613067) (xy 391.086566 -348.61307)
			(xy 392.569414 -348.61307) (xy 392.569414 -348.55853) (xy 392.577176 -348.504545) (xy 392.592542 -348.452214)
			(xy 392.615199 -348.402603) (xy 392.644686 -348.35672) (xy 392.680402 -348.315502) (xy 392.72162 -348.279786)
			(xy 392.767503 -348.250299) (xy 392.817114 -348.227642) (xy 392.869445 -348.212276) (xy 392.92343 -348.204514)
			(xy 392.9507 -348.204028) (xy 393.8143 -348.204028) (xy 393.841569 -348.204534) (xy 393.895551 -348.212296)
			(xy 393.947879 -348.227661) (xy 393.997488 -348.250316) (xy 394.043368 -348.279802) (xy 394.084584 -348.315516)
			(xy 394.120298 -348.356732) (xy 394.149784 -348.402612) (xy 394.172439 -348.452221) (xy 394.187804 -348.504549)
			(xy 394.195566 -348.558531) (xy 394.195566 -348.613068) (xy 395.678414 -348.613068) (xy 395.678414 -348.558532)
			(xy 395.686175 -348.50455) (xy 395.701539 -348.452223) (xy 395.724193 -348.402614) (xy 395.753676 -348.356734)
			(xy 395.789388 -348.315516) (xy 395.830601 -348.2798) (xy 395.876479 -348.250312) (xy 395.926085 -348.227653)
			(xy 395.978411 -348.212284) (xy 396.032392 -348.204517) (xy 396.05966 -348.204028) (xy 396.92326 -348.204028)
			(xy 396.950532 -348.204509) (xy 397.004522 -348.212266) (xy 397.056858 -348.227628) (xy 397.106475 -348.250283)
			(xy 397.152362 -348.279769) (xy 397.193586 -348.315485) (xy 397.229307 -348.356706) (xy 397.258798 -348.40259)
			(xy 397.281458 -348.452204) (xy 397.296825 -348.504539) (xy 397.304588 -348.558528) (xy 397.304588 -348.613072)
			(xy 397.304588 -348.613073) (xy 398.787292 -348.613073) (xy 398.787292 -348.558527) (xy 398.795054 -348.504537)
			(xy 398.810422 -348.452202) (xy 398.833082 -348.402586) (xy 398.862572 -348.3567) (xy 398.898293 -348.315478)
			(xy 398.939516 -348.27976) (xy 398.985403 -348.250272) (xy 399.03502 -348.227615) (xy 399.087357 -348.21225)
			(xy 399.141347 -348.20449) (xy 399.16862 -348.204028) (xy 400.03222 -348.204028) (xy 400.059488 -348.204536)
			(xy 400.113468 -348.2123) (xy 400.165794 -348.227666) (xy 400.2154 -348.250323) (xy 400.261277 -348.279809)
			(xy 400.302491 -348.315523) (xy 400.338203 -348.356739) (xy 400.367687 -348.402618) (xy 400.390341 -348.452225)
			(xy 400.405705 -348.504552) (xy 400.413466 -348.558532) (xy 400.413466 -348.613068) (xy 400.413466 -348.613069)
			(xy 401.896314 -348.613069) (xy 401.896314 -348.558531) (xy 401.904076 -348.504548) (xy 401.91944 -348.452218)
			(xy 401.942096 -348.402608) (xy 401.971581 -348.356727) (xy 402.007295 -348.315509) (xy 402.048511 -348.279793)
			(xy 402.094391 -348.250305) (xy 402.143999 -348.227647) (xy 402.196328 -348.21228) (xy 402.250311 -348.204516)
			(xy 402.27758 -348.204028) (xy 403.14118 -348.204028) (xy 403.168451 -348.20451) (xy 403.222439 -348.21227)
			(xy 403.274773 -348.227634) (xy 403.324387 -348.25029) (xy 403.370272 -348.279776) (xy 403.411493 -348.315493)
			(xy 403.447212 -348.356712) (xy 403.476701 -348.402595) (xy 403.499359 -348.452209) (xy 403.514726 -348.504542)
			(xy 403.522488 -348.558529) (xy 403.522488 -348.61307) (xy 408.913814 -348.61307) (xy 408.913814 -348.55853)
			(xy 408.921576 -348.504546) (xy 408.936941 -348.452216) (xy 408.959598 -348.402605) (xy 408.989084 -348.356723)
			(xy 409.024799 -348.315505) (xy 409.066017 -348.279788) (xy 409.111898 -348.250301) (xy 409.161508 -348.227644)
			(xy 409.213838 -348.212278) (xy 409.267822 -348.204515) (xy 409.295092 -348.204028) (xy 410.158692 -348.204028)
			(xy 410.185963 -348.204511) (xy 410.239949 -348.212272) (xy 410.292281 -348.227637) (xy 410.341894 -348.250294)
			(xy 410.387778 -348.27978) (xy 410.428998 -348.315497) (xy 410.464715 -348.356716) (xy 410.494203 -348.402599)
			(xy 410.51686 -348.452211) (xy 410.532226 -348.504543) (xy 410.539989 -348.558529) (xy 410.539989 -348.613068)
			(xy 412.022814 -348.613068) (xy 412.022814 -348.558532) (xy 412.030575 -348.504551) (xy 412.045938 -348.452224)
			(xy 412.068592 -348.402616) (xy 412.098074 -348.356736) (xy 412.133785 -348.315519) (xy 412.174998 -348.279803)
			(xy 412.220874 -348.250315) (xy 412.270479 -348.227655) (xy 412.322804 -348.212285) (xy 412.376784 -348.204518)
			(xy 412.404052 -348.204028) (xy 413.267652 -348.204028) (xy 413.294925 -348.204508) (xy 413.348915 -348.212265)
			(xy 413.401252 -348.227626) (xy 413.45087 -348.250281) (xy 413.496759 -348.279766) (xy 413.537983 -348.315483)
			(xy 413.573705 -348.356703) (xy 413.603196 -348.402588) (xy 413.625857 -348.452203) (xy 413.641225 -348.504538)
			(xy 413.648988 -348.558528) (xy 413.648988 -348.613072) (xy 415.131692 -348.613072) (xy 415.131692 -348.558528)
			(xy 415.139454 -348.504538) (xy 415.154821 -348.452203) (xy 415.177481 -348.402588) (xy 415.20697 -348.356703)
			(xy 415.24269 -348.315481) (xy 415.283912 -348.279763) (xy 415.329799 -348.250275) (xy 415.379415 -348.227617)
			(xy 415.43175 -348.212252) (xy 415.48574 -348.204491) (xy 415.513012 -348.204028) (xy 416.376612 -348.204028)
			(xy 416.40388 -348.204535) (xy 416.457861 -348.212298) (xy 416.510188 -348.227664) (xy 416.559795 -348.25032)
			(xy 416.605673 -348.279806) (xy 416.646888 -348.31552) (xy 416.682601 -348.356736) (xy 416.712085 -348.402615)
			(xy 416.73474 -348.452224) (xy 416.750104 -348.504551) (xy 416.757866 -348.558532) (xy 416.757866 -348.613068)
			(xy 416.757866 -348.613069) (xy 418.240714 -348.613069) (xy 418.240714 -348.558531) (xy 418.248476 -348.504549)
			(xy 418.26384 -348.45222) (xy 418.286495 -348.40261) (xy 418.315979 -348.35673) (xy 418.351692 -348.315512)
			(xy 418.392907 -348.279795) (xy 418.438786 -348.250308) (xy 418.488394 -348.22765) (xy 418.540721 -348.212281)
			(xy 418.594703 -348.204516) (xy 418.621972 -348.204028) (xy 419.485572 -348.204028) (xy 419.512844 -348.20451)
			(xy 419.566832 -348.212268) (xy 419.619167 -348.227632) (xy 419.668782 -348.250287) (xy 419.714668 -348.279773)
			(xy 419.75589 -348.31549) (xy 419.79161 -348.356709) (xy 419.821099 -348.402593) (xy 419.843759 -348.452207)
			(xy 419.859126 -348.504541) (xy 419.866888 -348.558528) (xy 419.866888 -348.613072) (xy 419.866888 -348.613073)
			(xy 421.349592 -348.613073) (xy 421.349592 -348.558527) (xy 421.357355 -348.504536) (xy 421.372723 -348.452199)
			(xy 421.395384 -348.402583) (xy 421.424875 -348.356696) (xy 421.460597 -348.315474) (xy 421.501822 -348.279756)
			(xy 421.547711 -348.250268) (xy 421.597329 -348.227612) (xy 421.649667 -348.212248) (xy 421.703659 -348.204489)
			(xy 421.730932 -348.204028) (xy 422.594532 -348.204028) (xy 422.621799 -348.204537) (xy 422.675778 -348.212302)
			(xy 422.728102 -348.227669) (xy 422.777707 -348.250327) (xy 422.823583 -348.279813) (xy 422.864795 -348.315527)
			(xy 422.900506 -348.356743) (xy 422.929988 -348.402621) (xy 422.952642 -348.452228) (xy 422.968005 -348.504553)
			(xy 422.975766 -348.558533) (xy 422.975766 -348.613067) (xy 422.975766 -348.61307) (xy 424.458614 -348.61307)
			(xy 424.458614 -348.55853) (xy 424.466376 -348.504546) (xy 424.481741 -348.452216) (xy 424.504398 -348.402605)
			(xy 424.533884 -348.356723) (xy 424.569599 -348.315505) (xy 424.610817 -348.279788) (xy 424.656698 -348.250301)
			(xy 424.706308 -348.227644) (xy 424.758638 -348.212278) (xy 424.812622 -348.204515) (xy 424.839892 -348.204028)
			(xy 425.703492 -348.204028) (xy 425.730763 -348.204511) (xy 425.784749 -348.212272) (xy 425.837081 -348.227637)
			(xy 425.886694 -348.250294) (xy 425.932578 -348.27978) (xy 425.973798 -348.315497) (xy 426.009515 -348.356716)
			(xy 426.039003 -348.402599) (xy 426.06166 -348.452211) (xy 426.077026 -348.504543) (xy 426.084789 -348.558529)
			(xy 426.084789 -348.613068) (xy 427.567614 -348.613068) (xy 427.567614 -348.558532) (xy 427.575375 -348.504551)
			(xy 427.590738 -348.452224) (xy 427.613392 -348.402616) (xy 427.642874 -348.356736) (xy 427.678585 -348.315519)
			(xy 427.719798 -348.279803) (xy 427.765674 -348.250315) (xy 427.815279 -348.227655) (xy 427.867604 -348.212285)
			(xy 427.921584 -348.204518) (xy 427.948852 -348.204028) (xy 428.812452 -348.204028) (xy 428.839725 -348.204508)
			(xy 428.893715 -348.212265) (xy 428.946052 -348.227626) (xy 428.99567 -348.250281) (xy 429.041559 -348.279766)
			(xy 429.082783 -348.315483) (xy 429.118505 -348.356703) (xy 429.147996 -348.402588) (xy 429.170657 -348.452203)
			(xy 429.186025 -348.504538) (xy 429.193788 -348.558528) (xy 429.193788 -348.613072) (xy 430.676492 -348.613072)
			(xy 430.676492 -348.558528) (xy 430.684254 -348.504538) (xy 430.699621 -348.452203) (xy 430.722281 -348.402588)
			(xy 430.75177 -348.356703) (xy 430.78749 -348.315481) (xy 430.828712 -348.279763) (xy 430.874599 -348.250275)
			(xy 430.924215 -348.227617) (xy 430.97655 -348.212252) (xy 431.03054 -348.204491) (xy 431.057812 -348.204028)
			(xy 431.921412 -348.204028) (xy 431.94868 -348.204535) (xy 432.002661 -348.212298) (xy 432.054988 -348.227664)
			(xy 432.104595 -348.25032) (xy 432.150473 -348.279806) (xy 432.191688 -348.31552) (xy 432.227401 -348.356736)
			(xy 432.256885 -348.402615) (xy 432.27954 -348.452224) (xy 432.294904 -348.504551) (xy 432.302666 -348.558532)
			(xy 432.302666 -348.613068) (xy 432.302666 -348.613069) (xy 433.785514 -348.613069) (xy 433.785514 -348.558531)
			(xy 433.793276 -348.504549) (xy 433.80864 -348.45222) (xy 433.831295 -348.40261) (xy 433.860779 -348.35673)
			(xy 433.896492 -348.315512) (xy 433.937707 -348.279795) (xy 433.983586 -348.250308) (xy 434.033194 -348.22765)
			(xy 434.085521 -348.212281) (xy 434.139503 -348.204516) (xy 434.166772 -348.204028) (xy 435.030372 -348.204028)
			(xy 435.057644 -348.20451) (xy 435.111632 -348.212268) (xy 435.163967 -348.227632) (xy 435.213582 -348.250287)
			(xy 435.259468 -348.279773) (xy 435.30069 -348.31549) (xy 435.33641 -348.356709) (xy 435.365899 -348.402593)
			(xy 435.388559 -348.452207) (xy 435.403926 -348.504541) (xy 435.411688 -348.558528) (xy 435.411688 -348.613072)
			(xy 435.411688 -348.613073) (xy 436.894392 -348.613073) (xy 436.894392 -348.558527) (xy 436.902155 -348.504536)
			(xy 436.917523 -348.452199) (xy 436.940184 -348.402583) (xy 436.969675 -348.356696) (xy 437.005397 -348.315474)
			(xy 437.046622 -348.279756) (xy 437.092511 -348.250268) (xy 437.142129 -348.227612) (xy 437.194467 -348.212248)
			(xy 437.248459 -348.204489) (xy 437.275732 -348.204028) (xy 438.139332 -348.204028) (xy 438.166599 -348.204537)
			(xy 438.220578 -348.212302) (xy 438.272902 -348.227669) (xy 438.322507 -348.250327) (xy 438.368383 -348.279813)
			(xy 438.409595 -348.315527) (xy 438.445306 -348.356743) (xy 438.474788 -348.402621) (xy 438.497442 -348.452228)
			(xy 438.512805 -348.504553) (xy 438.520566 -348.558533) (xy 438.520566 -348.613067) (xy 438.520566 -348.61307)
			(xy 440.003414 -348.61307) (xy 440.003414 -348.55853) (xy 440.011176 -348.504546) (xy 440.026541 -348.452216)
			(xy 440.049198 -348.402605) (xy 440.078684 -348.356723) (xy 440.114399 -348.315505) (xy 440.155617 -348.279788)
			(xy 440.201498 -348.250301) (xy 440.251108 -348.227644) (xy 440.303438 -348.212278) (xy 440.357422 -348.204515)
			(xy 440.384692 -348.204028) (xy 441.248292 -348.204028) (xy 441.275563 -348.204511) (xy 441.329549 -348.212272)
			(xy 441.381881 -348.227637) (xy 441.431494 -348.250294) (xy 441.477378 -348.27978) (xy 441.518598 -348.315497)
			(xy 441.554315 -348.356716) (xy 441.583803 -348.402599) (xy 441.60646 -348.452211) (xy 441.621826 -348.504543)
			(xy 441.629589 -348.558529) (xy 441.629589 -348.613071) (xy 441.621826 -348.667057) (xy 441.60646 -348.719389)
			(xy 441.583803 -348.769001) (xy 441.554315 -348.814884) (xy 441.518598 -348.856103) (xy 441.477378 -348.89182)
			(xy 441.431494 -348.921306) (xy 441.381881 -348.943963) (xy 441.329549 -348.959328) (xy 441.275563 -348.967089)
			(xy 441.248292 -348.967552) (xy 440.384692 -348.967552) (xy 440.357422 -348.967085) (xy 440.303438 -348.959322)
			(xy 440.251108 -348.943956) (xy 440.201498 -348.921299) (xy 440.155617 -348.891812) (xy 440.114399 -348.856095)
			(xy 440.078684 -348.814877) (xy 440.049198 -348.768995) (xy 440.026541 -348.719384) (xy 440.011176 -348.667054)
			(xy 440.003414 -348.61307) (xy 438.520566 -348.61307) (xy 438.512805 -348.667047) (xy 438.497442 -348.719372)
			(xy 438.474788 -348.768979) (xy 438.445306 -348.814857) (xy 438.409595 -348.856073) (xy 438.368383 -348.891787)
			(xy 438.322507 -348.921273) (xy 438.272902 -348.943931) (xy 438.220578 -348.959298) (xy 438.166599 -348.967063)
			(xy 438.139332 -348.967552) (xy 437.275732 -348.967552) (xy 437.248459 -348.967111) (xy 437.194467 -348.959352)
			(xy 437.142129 -348.943988) (xy 437.092511 -348.921332) (xy 437.046622 -348.891844) (xy 437.005397 -348.856126)
			(xy 436.969675 -348.814904) (xy 436.940184 -348.769017) (xy 436.917523 -348.719401) (xy 436.902155 -348.667064)
			(xy 436.894392 -348.613073) (xy 435.411688 -348.613073) (xy 435.403926 -348.667059) (xy 435.388559 -348.719393)
			(xy 435.365899 -348.769007) (xy 435.33641 -348.814891) (xy 435.30069 -348.85611) (xy 435.259468 -348.891827)
			(xy 435.213582 -348.921313) (xy 435.163967 -348.943968) (xy 435.111632 -348.959332) (xy 435.057644 -348.96709)
			(xy 435.030372 -348.967552) (xy 434.166772 -348.967552) (xy 434.139503 -348.967084) (xy 434.085521 -348.959319)
			(xy 434.033194 -348.94395) (xy 433.983586 -348.921292) (xy 433.937707 -348.891805) (xy 433.896492 -348.856088)
			(xy 433.860779 -348.81487) (xy 433.831295 -348.76899) (xy 433.80864 -348.71938) (xy 433.793276 -348.667051)
			(xy 433.785514 -348.613069) (xy 432.302666 -348.613069) (xy 432.294904 -348.667049) (xy 432.27954 -348.719376)
			(xy 432.256885 -348.768985) (xy 432.227401 -348.814864) (xy 432.191688 -348.85608) (xy 432.150473 -348.891794)
			(xy 432.104595 -348.92128) (xy 432.054988 -348.943936) (xy 432.002661 -348.959302) (xy 431.94868 -348.967065)
			(xy 431.921412 -348.967552) (xy 431.057812 -348.967552) (xy 431.03054 -348.967109) (xy 430.97655 -348.959348)
			(xy 430.924215 -348.943983) (xy 430.874599 -348.921325) (xy 430.828712 -348.891837) (xy 430.78749 -348.856119)
			(xy 430.75177 -348.814897) (xy 430.722281 -348.769012) (xy 430.699621 -348.719397) (xy 430.684254 -348.667062)
			(xy 430.676492 -348.613072) (xy 429.193788 -348.613072) (xy 429.186025 -348.667062) (xy 429.170657 -348.719397)
			(xy 429.147996 -348.769012) (xy 429.118505 -348.814897) (xy 429.082783 -348.856117) (xy 429.041559 -348.891834)
			(xy 428.99567 -348.921319) (xy 428.946052 -348.943974) (xy 428.893715 -348.959335) (xy 428.839725 -348.967092)
			(xy 428.812452 -348.967552) (xy 427.948852 -348.967552) (xy 427.921584 -348.967082) (xy 427.867604 -348.959315)
			(xy 427.815279 -348.943945) (xy 427.765674 -348.921285) (xy 427.719798 -348.891797) (xy 427.678585 -348.856081)
			(xy 427.642874 -348.814864) (xy 427.613392 -348.768984) (xy 427.590738 -348.719376) (xy 427.575375 -348.667049)
			(xy 427.567614 -348.613068) (xy 426.084789 -348.613068) (xy 426.084789 -348.613071) (xy 426.077026 -348.667057)
			(xy 426.06166 -348.719389) (xy 426.039003 -348.769001) (xy 426.009515 -348.814884) (xy 425.973798 -348.856103)
			(xy 425.932578 -348.89182) (xy 425.886694 -348.921306) (xy 425.837081 -348.943963) (xy 425.784749 -348.959328)
			(xy 425.730763 -348.967089) (xy 425.703492 -348.967552) (xy 424.839892 -348.967552) (xy 424.812622 -348.967085)
			(xy 424.758638 -348.959322) (xy 424.706308 -348.943956) (xy 424.656698 -348.921299) (xy 424.610817 -348.891812)
			(xy 424.569599 -348.856095) (xy 424.533884 -348.814877) (xy 424.504398 -348.768995) (xy 424.481741 -348.719384)
			(xy 424.466376 -348.667054) (xy 424.458614 -348.61307) (xy 422.975766 -348.61307) (xy 422.968005 -348.667047)
			(xy 422.952642 -348.719372) (xy 422.929988 -348.768979) (xy 422.900506 -348.814857) (xy 422.864795 -348.856073)
			(xy 422.823583 -348.891787) (xy 422.777707 -348.921273) (xy 422.728102 -348.943931) (xy 422.675778 -348.959298)
			(xy 422.621799 -348.967063) (xy 422.594532 -348.967552) (xy 421.730932 -348.967552) (xy 421.703659 -348.967111)
			(xy 421.649667 -348.959352) (xy 421.597329 -348.943988) (xy 421.547711 -348.921332) (xy 421.501822 -348.891844)
			(xy 421.460597 -348.856126) (xy 421.424875 -348.814904) (xy 421.395384 -348.769017) (xy 421.372723 -348.719401)
			(xy 421.357355 -348.667064) (xy 421.349592 -348.613073) (xy 419.866888 -348.613073) (xy 419.859126 -348.667059)
			(xy 419.843759 -348.719393) (xy 419.821099 -348.769007) (xy 419.79161 -348.814891) (xy 419.75589 -348.85611)
			(xy 419.714668 -348.891827) (xy 419.668782 -348.921313) (xy 419.619167 -348.943968) (xy 419.566832 -348.959332)
			(xy 419.512844 -348.96709) (xy 419.485572 -348.967552) (xy 418.621972 -348.967552) (xy 418.594703 -348.967084)
			(xy 418.540721 -348.959319) (xy 418.488394 -348.94395) (xy 418.438786 -348.921292) (xy 418.392907 -348.891805)
			(xy 418.351692 -348.856088) (xy 418.315979 -348.81487) (xy 418.286495 -348.76899) (xy 418.26384 -348.71938)
			(xy 418.248476 -348.667051) (xy 418.240714 -348.613069) (xy 416.757866 -348.613069) (xy 416.750104 -348.667049)
			(xy 416.73474 -348.719376) (xy 416.712085 -348.768985) (xy 416.682601 -348.814864) (xy 416.646888 -348.85608)
			(xy 416.605673 -348.891794) (xy 416.559795 -348.92128) (xy 416.510188 -348.943936) (xy 416.457861 -348.959302)
			(xy 416.40388 -348.967065) (xy 416.376612 -348.967552) (xy 415.513012 -348.967552) (xy 415.48574 -348.967109)
			(xy 415.43175 -348.959348) (xy 415.379415 -348.943983) (xy 415.329799 -348.921325) (xy 415.283912 -348.891837)
			(xy 415.24269 -348.856119) (xy 415.20697 -348.814897) (xy 415.177481 -348.769012) (xy 415.154821 -348.719397)
			(xy 415.139454 -348.667062) (xy 415.131692 -348.613072) (xy 413.648988 -348.613072) (xy 413.641225 -348.667062)
			(xy 413.625857 -348.719397) (xy 413.603196 -348.769012) (xy 413.573705 -348.814897) (xy 413.537983 -348.856117)
			(xy 413.496759 -348.891834) (xy 413.45087 -348.921319) (xy 413.401252 -348.943974) (xy 413.348915 -348.959335)
			(xy 413.294925 -348.967092) (xy 413.267652 -348.967552) (xy 412.404052 -348.967552) (xy 412.376784 -348.967082)
			(xy 412.322804 -348.959315) (xy 412.270479 -348.943945) (xy 412.220874 -348.921285) (xy 412.174998 -348.891797)
			(xy 412.133785 -348.856081) (xy 412.098074 -348.814864) (xy 412.068592 -348.768984) (xy 412.045938 -348.719376)
			(xy 412.030575 -348.667049) (xy 412.022814 -348.613068) (xy 410.539989 -348.613068) (xy 410.539989 -348.613071)
			(xy 410.532226 -348.667057) (xy 410.51686 -348.719389) (xy 410.494203 -348.769001) (xy 410.464715 -348.814884)
			(xy 410.428998 -348.856103) (xy 410.387778 -348.89182) (xy 410.341894 -348.921306) (xy 410.292281 -348.943963)
			(xy 410.239949 -348.959328) (xy 410.185963 -348.967089) (xy 410.158692 -348.967552) (xy 409.295092 -348.967552)
			(xy 409.267822 -348.967085) (xy 409.213838 -348.959322) (xy 409.161508 -348.943956) (xy 409.111898 -348.921299)
			(xy 409.066017 -348.891812) (xy 409.024799 -348.856095) (xy 408.989084 -348.814877) (xy 408.959598 -348.768995)
			(xy 408.936941 -348.719384) (xy 408.921576 -348.667054) (xy 408.913814 -348.61307) (xy 403.522488 -348.61307)
			(xy 403.522488 -348.613071) (xy 403.514726 -348.667058) (xy 403.499359 -348.719391) (xy 403.476701 -348.769005)
			(xy 403.447212 -348.814888) (xy 403.411493 -348.856107) (xy 403.370272 -348.891824) (xy 403.324387 -348.92131)
			(xy 403.274773 -348.943966) (xy 403.222439 -348.95933) (xy 403.168451 -348.96709) (xy 403.14118 -348.967552)
			(xy 402.27758 -348.967552) (xy 402.250311 -348.967084) (xy 402.196328 -348.95932) (xy 402.143999 -348.943953)
			(xy 402.094391 -348.921295) (xy 402.048511 -348.891807) (xy 402.007295 -348.856091) (xy 401.971581 -348.814873)
			(xy 401.942096 -348.768992) (xy 401.91944 -348.719382) (xy 401.904076 -348.667052) (xy 401.896314 -348.613069)
			(xy 400.413466 -348.613069) (xy 400.405705 -348.667048) (xy 400.390341 -348.719375) (xy 400.367687 -348.768982)
			(xy 400.338203 -348.814861) (xy 400.302491 -348.856077) (xy 400.261277 -348.891791) (xy 400.2154 -348.921277)
			(xy 400.165794 -348.943934) (xy 400.113468 -348.9593) (xy 400.059488 -348.967064) (xy 400.03222 -348.967552)
			(xy 399.16862 -348.967552) (xy 399.141347 -348.96711) (xy 399.087357 -348.95935) (xy 399.03502 -348.943985)
			(xy 398.985403 -348.921328) (xy 398.939516 -348.89184) (xy 398.898293 -348.856122) (xy 398.862572 -348.8149)
			(xy 398.833082 -348.769014) (xy 398.810422 -348.719398) (xy 398.795054 -348.667063) (xy 398.787292 -348.613073)
			(xy 397.304588 -348.613073) (xy 397.296825 -348.667061) (xy 397.281458 -348.719396) (xy 397.258798 -348.76901)
			(xy 397.229307 -348.814894) (xy 397.193586 -348.856115) (xy 397.152362 -348.891831) (xy 397.106475 -348.921317)
			(xy 397.056858 -348.943972) (xy 397.004522 -348.959334) (xy 396.950532 -348.967091) (xy 396.92326 -348.967552)
			(xy 396.05966 -348.967552) (xy 396.032392 -348.967083) (xy 395.978411 -348.959316) (xy 395.926085 -348.943947)
			(xy 395.876479 -348.921288) (xy 395.830601 -348.8918) (xy 395.789388 -348.856084) (xy 395.753676 -348.814866)
			(xy 395.724193 -348.768986) (xy 395.701539 -348.719377) (xy 395.686175 -348.66705) (xy 395.678414 -348.613068)
			(xy 394.195566 -348.613068) (xy 394.195566 -348.613069) (xy 394.187804 -348.667051) (xy 394.172439 -348.719379)
			(xy 394.149784 -348.768988) (xy 394.120298 -348.814868) (xy 394.084584 -348.856084) (xy 394.043368 -348.891798)
			(xy 393.997488 -348.921284) (xy 393.947879 -348.943939) (xy 393.895551 -348.959304) (xy 393.841569 -348.967066)
			(xy 393.8143 -348.967552) (xy 392.9507 -348.967552) (xy 392.92343 -348.967086) (xy 392.869445 -348.959324)
			(xy 392.817114 -348.943958) (xy 392.767503 -348.921301) (xy 392.72162 -348.891814) (xy 392.680402 -348.856098)
			(xy 392.644686 -348.81488) (xy 392.615199 -348.768997) (xy 392.592542 -348.719386) (xy 392.577176 -348.667055)
			(xy 392.569414 -348.61307) (xy 391.086566 -348.61307) (xy 391.078805 -348.667046) (xy 391.063442 -348.71937)
			(xy 391.04079 -348.768977) (xy 391.011308 -348.814854) (xy 390.975598 -348.85607) (xy 390.934387 -348.891784)
			(xy 390.888512 -348.92127) (xy 390.838908 -348.943928) (xy 390.786585 -348.959297) (xy 390.732607 -348.967063)
			(xy 390.70534 -348.967552) (xy 389.84174 -348.967552) (xy 389.814466 -348.967111) (xy 389.760474 -348.959354)
			(xy 389.708135 -348.94399) (xy 389.658515 -348.921334) (xy 389.612626 -348.891847) (xy 389.5714 -348.856129)
			(xy 389.535677 -348.814906) (xy 389.506185 -348.76902) (xy 389.483524 -348.719403) (xy 389.468155 -348.667065)
			(xy 389.460392 -348.613074) (xy 387.977688 -348.613074) (xy 387.969926 -348.667058) (xy 387.954559 -348.719391)
			(xy 387.931901 -348.769005) (xy 387.902412 -348.814888) (xy 387.866693 -348.856107) (xy 387.825472 -348.891824)
			(xy 387.779587 -348.92131) (xy 387.729973 -348.943966) (xy 387.677639 -348.95933) (xy 387.623651 -348.96709)
			(xy 387.59638 -348.967552) (xy 386.73278 -348.967552) (xy 386.705511 -348.967084) (xy 386.651528 -348.95932)
			(xy 386.599199 -348.943953) (xy 386.549591 -348.921295) (xy 386.503711 -348.891807) (xy 386.462495 -348.856091)
			(xy 386.426781 -348.814873) (xy 386.397296 -348.768992) (xy 386.37464 -348.719382) (xy 386.359276 -348.667052)
			(xy 386.351514 -348.613069) (xy 384.868666 -348.613069) (xy 384.860905 -348.667048) (xy 384.845541 -348.719375)
			(xy 384.822887 -348.768982) (xy 384.793403 -348.814861) (xy 384.757691 -348.856077) (xy 384.716477 -348.891791)
			(xy 384.6706 -348.921277) (xy 384.620994 -348.943934) (xy 384.568668 -348.9593) (xy 384.514688 -348.967064)
			(xy 384.48742 -348.967552) (xy 383.62382 -348.967552) (xy 383.596547 -348.96711) (xy 383.542557 -348.95935)
			(xy 383.49022 -348.943985) (xy 383.440603 -348.921328) (xy 383.394716 -348.89184) (xy 383.353493 -348.856122)
			(xy 383.317772 -348.8149) (xy 383.288282 -348.769014) (xy 383.265622 -348.719398) (xy 383.250254 -348.667063)
			(xy 383.242492 -348.613073) (xy 381.759788 -348.613073) (xy 381.752025 -348.667061) (xy 381.736658 -348.719396)
			(xy 381.713998 -348.76901) (xy 381.684507 -348.814894) (xy 381.648786 -348.856115) (xy 381.607562 -348.891831)
			(xy 381.561675 -348.921317) (xy 381.512058 -348.943972) (xy 381.459722 -348.959334) (xy 381.405732 -348.967091)
			(xy 381.37846 -348.967552) (xy 380.51486 -348.967552) (xy 380.487592 -348.967083) (xy 380.433611 -348.959316)
			(xy 380.381285 -348.943947) (xy 380.331679 -348.921288) (xy 380.285801 -348.8918) (xy 380.244588 -348.856084)
			(xy 380.208876 -348.814866) (xy 380.179393 -348.768986) (xy 380.156739 -348.719377) (xy 380.141375 -348.66705)
			(xy 380.133614 -348.613068) (xy 378.650766 -348.613068) (xy 378.650766 -348.613069) (xy 378.643004 -348.667051)
			(xy 378.627639 -348.719379) (xy 378.604984 -348.768988) (xy 378.575498 -348.814868) (xy 378.539784 -348.856084)
			(xy 378.498568 -348.891798) (xy 378.452688 -348.921284) (xy 378.403079 -348.943939) (xy 378.350751 -348.959304)
			(xy 378.296769 -348.967066) (xy 378.2695 -348.967552) (xy 377.4059 -348.967552) (xy 377.37863 -348.967086)
			(xy 377.324645 -348.959324) (xy 377.272314 -348.943958) (xy 377.222703 -348.921301) (xy 377.17682 -348.891814)
			(xy 377.135602 -348.856098) (xy 377.099886 -348.81488) (xy 377.070399 -348.768997) (xy 377.047742 -348.719386)
			(xy 377.032376 -348.667055) (xy 377.024614 -348.61307) (xy 375.541766 -348.61307) (xy 375.534005 -348.667046)
			(xy 375.518642 -348.71937) (xy 375.49599 -348.768977) (xy 375.466508 -348.814854) (xy 375.430798 -348.85607)
			(xy 375.389587 -348.891784) (xy 375.343712 -348.92127) (xy 375.294108 -348.943928) (xy 375.241785 -348.959297)
			(xy 375.187807 -348.967063) (xy 375.16054 -348.967552) (xy 374.29694 -348.967552) (xy 374.269666 -348.967111)
			(xy 374.215674 -348.959354) (xy 374.163335 -348.94399) (xy 374.113715 -348.921334) (xy 374.067826 -348.891847)
			(xy 374.0266 -348.856129) (xy 373.990877 -348.814906) (xy 373.961385 -348.76902) (xy 373.938724 -348.719403)
			(xy 373.923355 -348.667065) (xy 373.915592 -348.613074) (xy 372.432888 -348.613074) (xy 372.425126 -348.667058)
			(xy 372.409759 -348.719391) (xy 372.387101 -348.769005) (xy 372.357612 -348.814888) (xy 372.321893 -348.856107)
			(xy 372.280672 -348.891824) (xy 372.234787 -348.92131) (xy 372.185173 -348.943966) (xy 372.132839 -348.95933)
			(xy 372.078851 -348.96709) (xy 372.05158 -348.967552) (xy 371.18798 -348.967552) (xy 371.160711 -348.967084)
			(xy 371.106728 -348.95932) (xy 371.054399 -348.943953) (xy 371.004791 -348.921295) (xy 370.958911 -348.891807)
			(xy 370.917695 -348.856091) (xy 370.881981 -348.814873) (xy 370.852496 -348.768992) (xy 370.82984 -348.719382)
			(xy 370.814476 -348.667052) (xy 370.806714 -348.613069) (xy 344.837266 -348.613069) (xy 344.829504 -348.66705)
			(xy 344.81414 -348.719378) (xy 344.791484 -348.768987) (xy 344.761999 -348.814866) (xy 344.726286 -348.856083)
			(xy 344.685069 -348.891797) (xy 344.63919 -348.921282) (xy 344.589582 -348.943938) (xy 344.537254 -348.959303)
			(xy 344.483272 -348.967065) (xy 344.456004 -348.967552) (xy 343.592404 -348.967552) (xy 343.565132 -348.967109)
			(xy 343.511143 -348.959347) (xy 343.458809 -348.943981) (xy 343.409194 -348.921323) (xy 343.363309 -348.891834)
			(xy 343.322087 -348.856116) (xy 343.286368 -348.814895) (xy 343.256879 -348.76901) (xy 343.234221 -348.719395)
			(xy 343.218854 -348.667061) (xy 343.211092 -348.613072) (xy 341.728265 -348.613072) (xy 341.720505 -348.667045)
			(xy 341.705143 -348.71937) (xy 341.68249 -348.768976) (xy 341.653009 -348.814853) (xy 341.6173 -348.856069)
			(xy 341.576088 -348.891783) (xy 341.530214 -348.921269) (xy 341.480611 -348.943927) (xy 341.428288 -348.959296)
			(xy 341.374311 -348.967063) (xy 341.347044 -348.967552) (xy 340.483444 -348.967552) (xy 340.45617 -348.967111)
			(xy 340.402177 -348.959354) (xy 340.349838 -348.943991) (xy 340.300218 -348.921336) (xy 340.254327 -348.891849)
			(xy 340.213101 -348.85613) (xy 340.177378 -348.814908) (xy 340.147885 -348.769021) (xy 340.125224 -348.719403)
			(xy 340.109855 -348.667066) (xy 340.102092 -348.613074) (xy 338.619388 -348.613074) (xy 338.611626 -348.667058)
			(xy 338.596259 -348.71939) (xy 338.573601 -348.769003) (xy 338.544113 -348.814887) (xy 338.508395 -348.856106)
			(xy 338.467174 -348.891823) (xy 338.421289 -348.921309) (xy 338.371675 -348.943965) (xy 338.319342 -348.95933)
			(xy 338.265355 -348.96709) (xy 338.238084 -348.967552) (xy 337.374484 -348.967552) (xy 337.347215 -348.967084)
			(xy 337.293231 -348.959321) (xy 337.240902 -348.943954) (xy 337.191293 -348.921296) (xy 337.145413 -348.891809)
			(xy 337.104196 -348.856093) (xy 337.068482 -348.814874) (xy 337.038996 -348.768993) (xy 337.016341 -348.719383)
			(xy 337.000976 -348.667053) (xy 336.993214 -348.613069) (xy 335.510366 -348.613069) (xy 335.502605 -348.667048)
			(xy 335.487241 -348.719374) (xy 335.464587 -348.768981) (xy 335.435104 -348.81486) (xy 335.399393 -348.856076)
			(xy 335.358179 -348.89179) (xy 335.312302 -348.921276) (xy 335.262696 -348.943933) (xy 335.210371 -348.9593)
			(xy 335.156392 -348.967064) (xy 335.129124 -348.967552) (xy 334.265524 -348.967552) (xy 334.238251 -348.96711)
			(xy 334.18426 -348.959351) (xy 334.131923 -348.943986) (xy 334.082306 -348.921329) (xy 334.036418 -348.891841)
			(xy 333.995194 -348.856123) (xy 333.959473 -348.814901) (xy 333.929982 -348.769015) (xy 333.907322 -348.719399)
			(xy 333.891955 -348.667063) (xy 333.884192 -348.613073) (xy 332.401488 -348.613073) (xy 332.393726 -348.667061)
			(xy 332.378358 -348.719395) (xy 332.355698 -348.769009) (xy 332.326208 -348.814893) (xy 332.290488 -348.856113)
			(xy 332.249264 -348.89183) (xy 332.203377 -348.921316) (xy 332.153761 -348.94397) (xy 332.101425 -348.959333)
			(xy 332.047436 -348.967091) (xy 332.020164 -348.967552) (xy 331.156564 -348.967552) (xy 331.129296 -348.967083)
			(xy 331.075314 -348.959317) (xy 331.022988 -348.943948) (xy 330.973381 -348.921289) (xy 330.927503 -348.891802)
			(xy 330.886289 -348.856086) (xy 330.850577 -348.814868) (xy 330.821093 -348.768987) (xy 330.798439 -348.719378)
			(xy 330.783075 -348.66705) (xy 330.775314 -348.613068) (xy 329.292466 -348.613068) (xy 329.284704 -348.66705)
			(xy 329.26934 -348.719378) (xy 329.246684 -348.768987) (xy 329.217199 -348.814866) (xy 329.181486 -348.856083)
			(xy 329.140269 -348.891797) (xy 329.09439 -348.921282) (xy 329.044782 -348.943938) (xy 328.992454 -348.959303)
			(xy 328.938472 -348.967065) (xy 328.911204 -348.967552) (xy 328.047604 -348.967552) (xy 328.020332 -348.967109)
			(xy 327.966343 -348.959347) (xy 327.914009 -348.943981) (xy 327.864394 -348.921323) (xy 327.818509 -348.891834)
			(xy 327.777287 -348.856116) (xy 327.741568 -348.814895) (xy 327.712079 -348.76901) (xy 327.689421 -348.719395)
			(xy 327.674054 -348.667061) (xy 327.666292 -348.613072) (xy 326.183465 -348.613072) (xy 326.175705 -348.667045)
			(xy 326.160343 -348.71937) (xy 326.13769 -348.768976) (xy 326.108209 -348.814853) (xy 326.0725 -348.856069)
			(xy 326.031288 -348.891783) (xy 325.985414 -348.921269) (xy 325.935811 -348.943927) (xy 325.883488 -348.959296)
			(xy 325.829511 -348.967063) (xy 325.802244 -348.967552) (xy 324.938644 -348.967552) (xy 324.91137 -348.967111)
			(xy 324.857377 -348.959354) (xy 324.805038 -348.943991) (xy 324.755418 -348.921336) (xy 324.709527 -348.891849)
			(xy 324.668301 -348.85613) (xy 324.632578 -348.814908) (xy 324.603085 -348.769021) (xy 324.580424 -348.719403)
			(xy 324.565055 -348.667066) (xy 324.557292 -348.613074) (xy 323.074588 -348.613074) (xy 323.066826 -348.667058)
			(xy 323.051459 -348.71939) (xy 323.028801 -348.769003) (xy 322.999313 -348.814887) (xy 322.963595 -348.856106)
			(xy 322.922374 -348.891823) (xy 322.876489 -348.921309) (xy 322.826875 -348.943965) (xy 322.774542 -348.95933)
			(xy 322.720555 -348.96709) (xy 322.693284 -348.967552) (xy 321.829684 -348.967552) (xy 321.802415 -348.967084)
			(xy 321.748431 -348.959321) (xy 321.696102 -348.943954) (xy 321.646493 -348.921296) (xy 321.600613 -348.891809)
			(xy 321.559396 -348.856093) (xy 321.523682 -348.814874) (xy 321.494196 -348.768993) (xy 321.471541 -348.719383)
			(xy 321.456176 -348.667053) (xy 321.448414 -348.613069) (xy 319.965566 -348.613069) (xy 319.957805 -348.667048)
			(xy 319.942441 -348.719374) (xy 319.919787 -348.768981) (xy 319.890304 -348.81486) (xy 319.854593 -348.856076)
			(xy 319.813379 -348.89179) (xy 319.767502 -348.921276) (xy 319.717896 -348.943933) (xy 319.665571 -348.9593)
			(xy 319.611592 -348.967064) (xy 319.584324 -348.967552) (xy 318.720724 -348.967552) (xy 318.693451 -348.96711)
			(xy 318.63946 -348.959351) (xy 318.587123 -348.943986) (xy 318.537506 -348.921329) (xy 318.491618 -348.891841)
			(xy 318.450394 -348.856123) (xy 318.414673 -348.814901) (xy 318.385182 -348.769015) (xy 318.362522 -348.719399)
			(xy 318.347155 -348.667063) (xy 318.339392 -348.613073) (xy 316.856688 -348.613073) (xy 316.848926 -348.667061)
			(xy 316.833558 -348.719395) (xy 316.810898 -348.769009) (xy 316.781408 -348.814893) (xy 316.745688 -348.856113)
			(xy 316.704464 -348.89183) (xy 316.658577 -348.921316) (xy 316.608961 -348.94397) (xy 316.556625 -348.959333)
			(xy 316.502636 -348.967091) (xy 316.475364 -348.967552) (xy 315.611764 -348.967552) (xy 315.584496 -348.967083)
			(xy 315.530514 -348.959317) (xy 315.478188 -348.943948) (xy 315.428581 -348.921289) (xy 315.382703 -348.891802)
			(xy 315.341489 -348.856086) (xy 315.305777 -348.814868) (xy 315.276293 -348.768987) (xy 315.253639 -348.719378)
			(xy 315.238275 -348.66705) (xy 315.230514 -348.613068) (xy 313.747666 -348.613068) (xy 313.739904 -348.66705)
			(xy 313.72454 -348.719378) (xy 313.701884 -348.768987) (xy 313.672399 -348.814866) (xy 313.636686 -348.856083)
			(xy 313.595469 -348.891797) (xy 313.54959 -348.921282) (xy 313.499982 -348.943938) (xy 313.447654 -348.959303)
			(xy 313.393672 -348.967065) (xy 313.366404 -348.967552) (xy 312.502804 -348.967552) (xy 312.475532 -348.967109)
			(xy 312.421543 -348.959347) (xy 312.369209 -348.943981) (xy 312.319594 -348.921323) (xy 312.273709 -348.891834)
			(xy 312.232487 -348.856116) (xy 312.196768 -348.814895) (xy 312.167279 -348.76901) (xy 312.144621 -348.719395)
			(xy 312.129254 -348.667061) (xy 312.121492 -348.613072) (xy 300.231566 -348.613072) (xy 300.223804 -348.667051)
			(xy 300.208439 -348.719379) (xy 300.185784 -348.768987) (xy 300.156299 -348.814867) (xy 300.120585 -348.856083)
			(xy 300.079369 -348.891798) (xy 300.033489 -348.921283) (xy 299.98388 -348.943939) (xy 299.931553 -348.959304)
			(xy 299.877571 -348.967065) (xy 299.850302 -348.967552) (xy 298.986702 -348.967552) (xy 298.95943 -348.967109)
			(xy 298.905442 -348.959347) (xy 298.853107 -348.94398) (xy 298.803493 -348.921322) (xy 298.757608 -348.891834)
			(xy 298.716386 -348.856115) (xy 298.680668 -348.814894) (xy 298.651179 -348.769009) (xy 298.628521 -348.719394)
			(xy 298.613154 -348.66706) (xy 298.605392 -348.613072) (xy 297.122565 -348.613072) (xy 297.114805 -348.667045)
			(xy 297.099443 -348.71937) (xy 297.07679 -348.768976) (xy 297.047309 -348.814854) (xy 297.011599 -348.856069)
			(xy 296.970387 -348.891784) (xy 296.924513 -348.92127) (xy 296.874909 -348.943928) (xy 296.822586 -348.959296)
			(xy 296.768609 -348.967063) (xy 296.741342 -348.967552) (xy 295.877742 -348.967552) (xy 295.850468 -348.967111)
			(xy 295.796476 -348.959354) (xy 295.744136 -348.943991) (xy 295.694517 -348.921335) (xy 295.648627 -348.891848)
			(xy 295.6074 -348.856129) (xy 295.571677 -348.814907) (xy 295.542185 -348.76902) (xy 295.519524 -348.719403)
			(xy 295.504155 -348.667066) (xy 295.496392 -348.613074) (xy 294.013688 -348.613074) (xy 294.005926 -348.667058)
			(xy 293.990559 -348.719391) (xy 293.967901 -348.769004) (xy 293.938412 -348.814887) (xy 293.902694 -348.856107)
			(xy 293.861473 -348.891823) (xy 293.815588 -348.92131) (xy 293.765974 -348.943966) (xy 293.713641 -348.95933)
			(xy 293.659653 -348.96709) (xy 293.632382 -348.967552) (xy 292.768782 -348.967552) (xy 292.741513 -348.967084)
			(xy 292.68753 -348.95932) (xy 292.635201 -348.943953) (xy 292.585592 -348.921295) (xy 292.539712 -348.891808)
			(xy 292.498495 -348.856092) (xy 292.462781 -348.814874) (xy 292.433296 -348.768992) (xy 292.410641 -348.719382)
			(xy 292.395276 -348.667053) (xy 292.387514 -348.613069) (xy 290.904666 -348.613069) (xy 290.896905 -348.667048)
			(xy 290.881541 -348.719374) (xy 290.858887 -348.768982) (xy 290.829404 -348.81486) (xy 290.793692 -348.856076)
			(xy 290.752478 -348.891791) (xy 290.706601 -348.921276) (xy 290.656995 -348.943933) (xy 290.604669 -348.9593)
			(xy 290.55069 -348.967064) (xy 290.523422 -348.967552) (xy 289.659822 -348.967552) (xy 289.632549 -348.96711)
			(xy 289.578559 -348.95935) (xy 289.526222 -348.943985) (xy 289.476605 -348.921329) (xy 289.430717 -348.891841)
			(xy 289.389493 -348.856122) (xy 289.353772 -348.814901) (xy 289.324282 -348.769015) (xy 289.301622 -348.719399)
			(xy 289.286254 -348.667063) (xy 289.278492 -348.613073) (xy 287.795788 -348.613073) (xy 287.788026 -348.667061)
			(xy 287.772658 -348.719395) (xy 287.749998 -348.76901) (xy 287.720508 -348.814894) (xy 287.684787 -348.856114)
			(xy 287.643563 -348.89183) (xy 287.597676 -348.921316) (xy 287.54806 -348.943971) (xy 287.495724 -348.959334)
			(xy 287.441734 -348.967091) (xy 287.414462 -348.967552) (xy 286.550862 -348.967552) (xy 286.523594 -348.967083)
			(xy 286.469613 -348.959317) (xy 286.417286 -348.943948) (xy 286.36768 -348.921289) (xy 286.321802 -348.891801)
			(xy 286.280588 -348.856085) (xy 286.244876 -348.814867) (xy 286.215393 -348.768987) (xy 286.192739 -348.719378)
			(xy 286.177375 -348.66705) (xy 286.169614 -348.613068) (xy 284.686766 -348.613068) (xy 284.686766 -348.613069)
			(xy 284.679004 -348.667051) (xy 284.663639 -348.719379) (xy 284.640984 -348.768987) (xy 284.611499 -348.814867)
			(xy 284.575785 -348.856083) (xy 284.534569 -348.891798) (xy 284.488689 -348.921283) (xy 284.43908 -348.943939)
			(xy 284.386753 -348.959304) (xy 284.332771 -348.967065) (xy 284.305502 -348.967552) (xy 283.441902 -348.967552)
			(xy 283.41463 -348.967109) (xy 283.360642 -348.959347) (xy 283.308307 -348.94398) (xy 283.258693 -348.921322)
			(xy 283.212808 -348.891834) (xy 283.171586 -348.856115) (xy 283.135868 -348.814894) (xy 283.106379 -348.769009)
			(xy 283.083721 -348.719394) (xy 283.068354 -348.66706) (xy 283.060592 -348.613072) (xy 281.577765 -348.613072)
			(xy 281.570005 -348.667045) (xy 281.554643 -348.71937) (xy 281.53199 -348.768976) (xy 281.502509 -348.814854)
			(xy 281.466799 -348.856069) (xy 281.425587 -348.891784) (xy 281.379713 -348.92127) (xy 281.330109 -348.943928)
			(xy 281.277786 -348.959296) (xy 281.223809 -348.967063) (xy 281.196542 -348.967552) (xy 280.332942 -348.967552)
			(xy 280.305668 -348.967111) (xy 280.251676 -348.959354) (xy 280.199336 -348.943991) (xy 280.149717 -348.921335)
			(xy 280.103827 -348.891848) (xy 280.0626 -348.856129) (xy 280.026877 -348.814907) (xy 279.997385 -348.76902)
			(xy 279.974724 -348.719403) (xy 279.959355 -348.667066) (xy 279.951592 -348.613074) (xy 278.468888 -348.613074)
			(xy 278.461126 -348.667058) (xy 278.445759 -348.719391) (xy 278.423101 -348.769004) (xy 278.393612 -348.814887)
			(xy 278.357894 -348.856107) (xy 278.316673 -348.891823) (xy 278.270788 -348.92131) (xy 278.221174 -348.943966)
			(xy 278.168841 -348.95933) (xy 278.114853 -348.96709) (xy 278.087582 -348.967552) (xy 277.223982 -348.967552)
			(xy 277.196713 -348.967084) (xy 277.14273 -348.95932) (xy 277.090401 -348.943953) (xy 277.040792 -348.921295)
			(xy 276.994912 -348.891808) (xy 276.953695 -348.856092) (xy 276.917981 -348.814874) (xy 276.888496 -348.768992)
			(xy 276.865841 -348.719382) (xy 276.850476 -348.667053) (xy 276.842714 -348.613069) (xy 275.359866 -348.613069)
			(xy 275.352105 -348.667048) (xy 275.336741 -348.719374) (xy 275.314087 -348.768982) (xy 275.284604 -348.81486)
			(xy 275.248892 -348.856076) (xy 275.207678 -348.891791) (xy 275.161801 -348.921276) (xy 275.112195 -348.943933)
			(xy 275.059869 -348.9593) (xy 275.00589 -348.967064) (xy 274.978622 -348.967552) (xy 274.115022 -348.967552)
			(xy 274.087749 -348.96711) (xy 274.033759 -348.95935) (xy 273.981422 -348.943985) (xy 273.931805 -348.921329)
			(xy 273.885917 -348.891841) (xy 273.844693 -348.856122) (xy 273.808972 -348.814901) (xy 273.779482 -348.769015)
			(xy 273.756822 -348.719399) (xy 273.741454 -348.667063) (xy 273.733692 -348.613073) (xy 272.250988 -348.613073)
			(xy 272.243226 -348.667061) (xy 272.227858 -348.719395) (xy 272.205198 -348.76901) (xy 272.175708 -348.814894)
			(xy 272.139987 -348.856114) (xy 272.098763 -348.89183) (xy 272.052876 -348.921316) (xy 272.00326 -348.943971)
			(xy 271.950924 -348.959334) (xy 271.896934 -348.967091) (xy 271.869662 -348.967552) (xy 271.006062 -348.967552)
			(xy 270.978794 -348.967083) (xy 270.924813 -348.959317) (xy 270.872486 -348.943948) (xy 270.82288 -348.921289)
			(xy 270.777002 -348.891801) (xy 270.735788 -348.856085) (xy 270.700076 -348.814867) (xy 270.670593 -348.768987)
			(xy 270.647939 -348.719378) (xy 270.632575 -348.66705) (xy 270.624814 -348.613068) (xy 269.141966 -348.613068)
			(xy 269.141966 -348.613069) (xy 269.134204 -348.667051) (xy 269.118839 -348.719379) (xy 269.096184 -348.768987)
			(xy 269.066699 -348.814867) (xy 269.030985 -348.856083) (xy 268.989769 -348.891798) (xy 268.943889 -348.921283)
			(xy 268.89428 -348.943939) (xy 268.841953 -348.959304) (xy 268.787971 -348.967065) (xy 268.760702 -348.967552)
			(xy 267.897102 -348.967552) (xy 267.86983 -348.967109) (xy 267.815842 -348.959347) (xy 267.763507 -348.94398)
			(xy 267.713893 -348.921322) (xy 267.668008 -348.891834) (xy 267.626786 -348.856115) (xy 267.591068 -348.814894)
			(xy 267.561579 -348.769009) (xy 267.538921 -348.719394) (xy 267.523554 -348.66706) (xy 267.515792 -348.613072)
			(xy 194.520565 -348.613072) (xy 194.512804 -348.667049) (xy 194.49744 -348.719376) (xy 194.474785 -348.768985)
			(xy 194.445301 -348.814864) (xy 194.409588 -348.85608) (xy 194.368373 -348.891794) (xy 194.322495 -348.92128)
			(xy 194.272888 -348.943936) (xy 194.220561 -348.959302) (xy 194.16658 -348.967065) (xy 194.139312 -348.967552)
			(xy 193.275712 -348.967552) (xy 193.24844 -348.967109) (xy 193.19445 -348.959348) (xy 193.142115 -348.943983)
			(xy 193.092499 -348.921325) (xy 193.046612 -348.891837) (xy 193.00539 -348.856119) (xy 192.96967 -348.814897)
			(xy 192.940181 -348.769012) (xy 192.917521 -348.719397) (xy 192.902154 -348.667062) (xy 192.894392 -348.613072)
			(xy 191.411688 -348.613072) (xy 191.403925 -348.667062) (xy 191.388557 -348.719397) (xy 191.365896 -348.769012)
			(xy 191.336405 -348.814897) (xy 191.300683 -348.856117) (xy 191.259459 -348.891834) (xy 191.21357 -348.921319)
			(xy 191.163952 -348.943974) (xy 191.111615 -348.959335) (xy 191.057625 -348.967092) (xy 191.030352 -348.967552)
			(xy 190.166752 -348.967552) (xy 190.139484 -348.967082) (xy 190.085504 -348.959315) (xy 190.033179 -348.943945)
			(xy 189.983574 -348.921285) (xy 189.937698 -348.891797) (xy 189.896485 -348.856081) (xy 189.860774 -348.814864)
			(xy 189.831292 -348.768984) (xy 189.808638 -348.719376) (xy 189.793275 -348.667049) (xy 189.785514 -348.613068)
			(xy 188.302689 -348.613068) (xy 188.302689 -348.613071) (xy 188.294926 -348.667057) (xy 188.27956 -348.719389)
			(xy 188.256903 -348.769001) (xy 188.227415 -348.814884) (xy 188.191698 -348.856103) (xy 188.150478 -348.89182)
			(xy 188.104594 -348.921306) (xy 188.054981 -348.943963) (xy 188.002649 -348.959328) (xy 187.948663 -348.967089)
			(xy 187.921392 -348.967552) (xy 187.057792 -348.967552) (xy 187.030522 -348.967085) (xy 186.976538 -348.959322)
			(xy 186.924208 -348.943956) (xy 186.874598 -348.921299) (xy 186.828717 -348.891812) (xy 186.787499 -348.856095)
			(xy 186.751784 -348.814877) (xy 186.722298 -348.768995) (xy 186.699641 -348.719384) (xy 186.684276 -348.667054)
			(xy 186.676514 -348.61307) (xy 185.193666 -348.61307) (xy 185.185905 -348.667047) (xy 185.170542 -348.719372)
			(xy 185.147888 -348.768979) (xy 185.118406 -348.814857) (xy 185.082695 -348.856073) (xy 185.041483 -348.891787)
			(xy 184.995607 -348.921273) (xy 184.946002 -348.943931) (xy 184.893678 -348.959298) (xy 184.839699 -348.967063)
			(xy 184.812432 -348.967552) (xy 183.948832 -348.967552) (xy 183.921559 -348.967111) (xy 183.867567 -348.959352)
			(xy 183.815229 -348.943988) (xy 183.765611 -348.921332) (xy 183.719722 -348.891844) (xy 183.678497 -348.856126)
			(xy 183.642775 -348.814904) (xy 183.613284 -348.769017) (xy 183.590623 -348.719401) (xy 183.575255 -348.667064)
			(xy 183.567492 -348.613073) (xy 182.084788 -348.613073) (xy 182.077026 -348.667059) (xy 182.061659 -348.719393)
			(xy 182.038999 -348.769007) (xy 182.00951 -348.814891) (xy 181.97379 -348.85611) (xy 181.932568 -348.891827)
			(xy 181.886682 -348.921313) (xy 181.837067 -348.943968) (xy 181.784732 -348.959332) (xy 181.730744 -348.96709)
			(xy 181.703472 -348.967552) (xy 180.839872 -348.967552) (xy 180.812603 -348.967084) (xy 180.758621 -348.959319)
			(xy 180.706294 -348.94395) (xy 180.656686 -348.921292) (xy 180.610807 -348.891805) (xy 180.569592 -348.856088)
			(xy 180.533879 -348.81487) (xy 180.504395 -348.76899) (xy 180.48174 -348.71938) (xy 180.466376 -348.667051)
			(xy 180.458614 -348.613069) (xy 178.975766 -348.613069) (xy 178.968004 -348.667049) (xy 178.95264 -348.719376)
			(xy 178.929985 -348.768985) (xy 178.900501 -348.814864) (xy 178.864788 -348.85608) (xy 178.823573 -348.891794)
			(xy 178.777695 -348.92128) (xy 178.728088 -348.943936) (xy 178.675761 -348.959302) (xy 178.62178 -348.967065)
			(xy 178.594512 -348.967552) (xy 177.730912 -348.967552) (xy 177.70364 -348.967109) (xy 177.64965 -348.959348)
			(xy 177.597315 -348.943983) (xy 177.547699 -348.921325) (xy 177.501812 -348.891837) (xy 177.46059 -348.856119)
			(xy 177.42487 -348.814897) (xy 177.395381 -348.769012) (xy 177.372721 -348.719397) (xy 177.357354 -348.667062)
			(xy 177.349592 -348.613072) (xy 175.866888 -348.613072) (xy 175.859125 -348.667062) (xy 175.843757 -348.719397)
			(xy 175.821096 -348.769012) (xy 175.791605 -348.814897) (xy 175.755883 -348.856117) (xy 175.714659 -348.891834)
			(xy 175.66877 -348.921319) (xy 175.619152 -348.943974) (xy 175.566815 -348.959335) (xy 175.512825 -348.967092)
			(xy 175.485552 -348.967552) (xy 174.621952 -348.967552) (xy 174.594684 -348.967082) (xy 174.540704 -348.959315)
			(xy 174.488379 -348.943945) (xy 174.438774 -348.921285) (xy 174.392898 -348.891797) (xy 174.351685 -348.856081)
			(xy 174.315974 -348.814864) (xy 174.286492 -348.768984) (xy 174.263838 -348.719376) (xy 174.248475 -348.667049)
			(xy 174.240714 -348.613068) (xy 172.757889 -348.613068) (xy 172.757889 -348.613071) (xy 172.750126 -348.667057)
			(xy 172.73476 -348.719389) (xy 172.712103 -348.769001) (xy 172.682615 -348.814884) (xy 172.646898 -348.856103)
			(xy 172.605678 -348.89182) (xy 172.559794 -348.921306) (xy 172.510181 -348.943963) (xy 172.457849 -348.959328)
			(xy 172.403863 -348.967089) (xy 172.376592 -348.967552) (xy 171.512992 -348.967552) (xy 171.485722 -348.967085)
			(xy 171.431738 -348.959322) (xy 171.379408 -348.943956) (xy 171.329798 -348.921299) (xy 171.283917 -348.891812)
			(xy 171.242699 -348.856095) (xy 171.206984 -348.814877) (xy 171.177498 -348.768995) (xy 171.154841 -348.719384)
			(xy 171.139476 -348.667054) (xy 171.131714 -348.61307) (xy 169.648866 -348.61307) (xy 169.641105 -348.667047)
			(xy 169.625742 -348.719372) (xy 169.603088 -348.768979) (xy 169.573606 -348.814857) (xy 169.537895 -348.856073)
			(xy 169.496683 -348.891787) (xy 169.450807 -348.921273) (xy 169.401202 -348.943931) (xy 169.348878 -348.959298)
			(xy 169.294899 -348.967063) (xy 169.267632 -348.967552) (xy 168.404032 -348.967552) (xy 168.376759 -348.967111)
			(xy 168.322767 -348.959352) (xy 168.270429 -348.943988) (xy 168.220811 -348.921332) (xy 168.174922 -348.891844)
			(xy 168.133697 -348.856126) (xy 168.097975 -348.814904) (xy 168.068484 -348.769017) (xy 168.045823 -348.719401)
			(xy 168.030455 -348.667064) (xy 168.022692 -348.613073) (xy 166.539988 -348.613073) (xy 166.532226 -348.667059)
			(xy 166.516859 -348.719393) (xy 166.494199 -348.769007) (xy 166.46471 -348.814891) (xy 166.42899 -348.85611)
			(xy 166.387768 -348.891827) (xy 166.341882 -348.921313) (xy 166.292267 -348.943968) (xy 166.239932 -348.959332)
			(xy 166.185944 -348.96709) (xy 166.158672 -348.967552) (xy 165.295072 -348.967552) (xy 165.267803 -348.967084)
			(xy 165.213821 -348.959319) (xy 165.161494 -348.94395) (xy 165.111886 -348.921292) (xy 165.066007 -348.891805)
			(xy 165.024792 -348.856088) (xy 164.989079 -348.81487) (xy 164.959595 -348.76899) (xy 164.93694 -348.71938)
			(xy 164.921576 -348.667051) (xy 164.913814 -348.613069) (xy 163.430966 -348.613069) (xy 163.423204 -348.667049)
			(xy 163.40784 -348.719376) (xy 163.385185 -348.768985) (xy 163.355701 -348.814864) (xy 163.319988 -348.85608)
			(xy 163.278773 -348.891794) (xy 163.232895 -348.92128) (xy 163.183288 -348.943936) (xy 163.130961 -348.959302)
			(xy 163.07698 -348.967065) (xy 163.049712 -348.967552) (xy 162.186112 -348.967552) (xy 162.15884 -348.967109)
			(xy 162.10485 -348.959348) (xy 162.052515 -348.943983) (xy 162.002899 -348.921325) (xy 161.957012 -348.891837)
			(xy 161.91579 -348.856119) (xy 161.88007 -348.814897) (xy 161.850581 -348.769012) (xy 161.827921 -348.719397)
			(xy 161.812554 -348.667062) (xy 161.804792 -348.613072) (xy 144.196565 -348.613072) (xy 144.188804 -348.66705)
			(xy 144.17344 -348.719377) (xy 144.150785 -348.768986) (xy 144.1213 -348.814865) (xy 144.085587 -348.856081)
			(xy 144.044371 -348.891796) (xy 143.998493 -348.921281) (xy 143.948885 -348.943937) (xy 143.896558 -348.959303)
			(xy 143.842576 -348.967065) (xy 143.815308 -348.967552) (xy 142.951708 -348.967552) (xy 142.924436 -348.967109)
			(xy 142.870447 -348.959348) (xy 142.818112 -348.943982) (xy 142.768496 -348.921324) (xy 142.72261 -348.891836)
			(xy 142.681388 -348.856117) (xy 142.645669 -348.814896) (xy 142.61618 -348.769011) (xy 142.593521 -348.719396)
			(xy 142.578154 -348.667061) (xy 142.570392 -348.613072) (xy 141.087565 -348.613072) (xy 141.079806 -348.667044)
			(xy 141.064443 -348.719369) (xy 141.041791 -348.768974) (xy 141.01231 -348.814852) (xy 140.976601 -348.856067)
			(xy 140.93539 -348.891781) (xy 140.889517 -348.921268) (xy 140.839914 -348.943926) (xy 140.787591 -348.959295)
			(xy 140.733614 -348.967062) (xy 140.706348 -348.967552) (xy 139.842748 -348.967552) (xy 139.815474 -348.967112)
			(xy 139.761481 -348.959355) (xy 139.709141 -348.943992) (xy 139.65952 -348.921337) (xy 139.613629 -348.89185)
			(xy 139.572402 -348.856132) (xy 139.536679 -348.814909) (xy 139.507186 -348.769022) (xy 139.484524 -348.719404)
			(xy 139.469155 -348.667066) (xy 139.461392 -348.613074) (xy 137.978689 -348.613074) (xy 137.970926 -348.667057)
			(xy 137.95556 -348.71939) (xy 137.932902 -348.769002) (xy 137.903414 -348.814885) (xy 137.867696 -348.856105)
			(xy 137.826476 -348.891821) (xy 137.780592 -348.921308) (xy 137.730978 -348.943964) (xy 137.678646 -348.959329)
			(xy 137.624659 -348.967089) (xy 137.597388 -348.967552) (xy 136.733788 -348.967552) (xy 136.706518 -348.967085)
			(xy 136.652535 -348.959321) (xy 136.600205 -348.943955) (xy 136.550595 -348.921297) (xy 136.504715 -348.89181)
			(xy 136.463497 -348.856094) (xy 136.427783 -348.814876) (xy 136.398297 -348.768994) (xy 136.375641 -348.719383)
			(xy 136.360276 -348.667053) (xy 136.352514 -348.61307) (xy 134.869666 -348.61307) (xy 134.861905 -348.667047)
			(xy 134.846541 -348.719373) (xy 134.823888 -348.76898) (xy 134.794405 -348.814858) (xy 134.758694 -348.856074)
			(xy 134.717481 -348.891789) (xy 134.671605 -348.921274) (xy 134.621999 -348.943932) (xy 134.569675 -348.959299)
			(xy 134.515695 -348.967064) (xy 134.488428 -348.967552) (xy 133.624828 -348.967552) (xy 133.597555 -348.96711)
			(xy 133.543564 -348.959351) (xy 133.491226 -348.943987) (xy 133.441608 -348.92133) (xy 133.39572 -348.891843)
			(xy 133.354495 -348.856124) (xy 133.318774 -348.814903) (xy 133.289283 -348.769016) (xy 133.266623 -348.7194)
			(xy 133.251255 -348.667064) (xy 133.243492 -348.613073) (xy 131.760788 -348.613073) (xy 131.753026 -348.66706)
			(xy 131.737658 -348.719394) (xy 131.714999 -348.769008) (xy 131.685509 -348.814892) (xy 131.649789 -348.856112)
			(xy 131.608566 -348.891828) (xy 131.56268 -348.921314) (xy 131.513064 -348.943969) (xy 131.460729 -348.959332)
			(xy 131.40674 -348.967091) (xy 131.379468 -348.967552) (xy 130.515868 -348.967552) (xy 130.488599 -348.967083)
			(xy 130.434618 -348.959318) (xy 130.382291 -348.943949) (xy 130.332683 -348.921291) (xy 130.286805 -348.891803)
			(xy 130.24559 -348.856087) (xy 130.209878 -348.814869) (xy 130.180394 -348.768989) (xy 130.15774 -348.719379)
			(xy 130.142375 -348.667051) (xy 130.134614 -348.613069) (xy 128.651766 -348.613069) (xy 128.644004 -348.66705)
			(xy 128.62864 -348.719377) (xy 128.605985 -348.768986) (xy 128.5765 -348.814865) (xy 128.540787 -348.856081)
			(xy 128.499571 -348.891796) (xy 128.453693 -348.921281) (xy 128.404085 -348.943937) (xy 128.351758 -348.959303)
			(xy 128.297776 -348.967065) (xy 128.270508 -348.967552) (xy 127.406908 -348.967552) (xy 127.379636 -348.967109)
			(xy 127.325647 -348.959348) (xy 127.273312 -348.943982) (xy 127.223696 -348.921324) (xy 127.17781 -348.891836)
			(xy 127.136588 -348.856117) (xy 127.100869 -348.814896) (xy 127.07138 -348.769011) (xy 127.048721 -348.719396)
			(xy 127.033354 -348.667061) (xy 127.025592 -348.613072) (xy 125.542765 -348.613072) (xy 125.535006 -348.667044)
			(xy 125.519643 -348.719369) (xy 125.496991 -348.768974) (xy 125.46751 -348.814852) (xy 125.431801 -348.856067)
			(xy 125.39059 -348.891781) (xy 125.344717 -348.921268) (xy 125.295114 -348.943926) (xy 125.242791 -348.959295)
			(xy 125.188814 -348.967062) (xy 125.161548 -348.967552) (xy 124.297948 -348.967552) (xy 124.270674 -348.967112)
			(xy 124.216681 -348.959355) (xy 124.164341 -348.943992) (xy 124.11472 -348.921337) (xy 124.068829 -348.89185)
			(xy 124.027602 -348.856132) (xy 123.991879 -348.814909) (xy 123.962386 -348.769022) (xy 123.939724 -348.719404)
			(xy 123.924355 -348.667066) (xy 123.916592 -348.613074) (xy 122.433889 -348.613074) (xy 122.426126 -348.667057)
			(xy 122.41076 -348.71939) (xy 122.388102 -348.769002) (xy 122.358614 -348.814885) (xy 122.322896 -348.856105)
			(xy 122.281676 -348.891821) (xy 122.235792 -348.921308) (xy 122.186178 -348.943964) (xy 122.133846 -348.959329)
			(xy 122.079859 -348.967089) (xy 122.052588 -348.967552) (xy 121.188988 -348.967552) (xy 121.161718 -348.967085)
			(xy 121.107735 -348.959321) (xy 121.055405 -348.943955) (xy 121.005795 -348.921297) (xy 120.959915 -348.89181)
			(xy 120.918697 -348.856094) (xy 120.882983 -348.814876) (xy 120.853497 -348.768994) (xy 120.830841 -348.719383)
			(xy 120.815476 -348.667053) (xy 120.807714 -348.61307) (xy 119.324866 -348.61307) (xy 119.317105 -348.667047)
			(xy 119.301741 -348.719373) (xy 119.279088 -348.76898) (xy 119.249605 -348.814858) (xy 119.213894 -348.856074)
			(xy 119.172681 -348.891789) (xy 119.126805 -348.921274) (xy 119.077199 -348.943932) (xy 119.024875 -348.959299)
			(xy 118.970895 -348.967064) (xy 118.943628 -348.967552) (xy 118.080028 -348.967552) (xy 118.052755 -348.96711)
			(xy 117.998764 -348.959351) (xy 117.946426 -348.943987) (xy 117.896808 -348.92133) (xy 117.85092 -348.891843)
			(xy 117.809695 -348.856124) (xy 117.773974 -348.814903) (xy 117.744483 -348.769016) (xy 117.721823 -348.7194)
			(xy 117.706455 -348.667064) (xy 117.698692 -348.613073) (xy 116.215988 -348.613073) (xy 116.208226 -348.66706)
			(xy 116.192858 -348.719394) (xy 116.170199 -348.769008) (xy 116.140709 -348.814892) (xy 116.104989 -348.856112)
			(xy 116.063766 -348.891828) (xy 116.01788 -348.921314) (xy 115.968264 -348.943969) (xy 115.915929 -348.959332)
			(xy 115.86194 -348.967091) (xy 115.834668 -348.967552) (xy 114.971068 -348.967552) (xy 114.943799 -348.967083)
			(xy 114.889818 -348.959318) (xy 114.837491 -348.943949) (xy 114.787883 -348.921291) (xy 114.742005 -348.891803)
			(xy 114.70079 -348.856087) (xy 114.665078 -348.814869) (xy 114.635594 -348.768989) (xy 114.61294 -348.719379)
			(xy 114.597575 -348.667051) (xy 114.589814 -348.613069) (xy 113.106966 -348.613069) (xy 113.099204 -348.66705)
			(xy 113.08384 -348.719377) (xy 113.061185 -348.768986) (xy 113.0317 -348.814865) (xy 112.995987 -348.856081)
			(xy 112.954771 -348.891796) (xy 112.908893 -348.921281) (xy 112.859285 -348.943937) (xy 112.806958 -348.959303)
			(xy 112.752976 -348.967065) (xy 112.725708 -348.967552) (xy 111.862108 -348.967552) (xy 111.834836 -348.967109)
			(xy 111.780847 -348.959348) (xy 111.728512 -348.943982) (xy 111.678896 -348.921324) (xy 111.63301 -348.891836)
			(xy 111.591788 -348.856117) (xy 111.556069 -348.814896) (xy 111.52658 -348.769011) (xy 111.503921 -348.719396)
			(xy 111.488554 -348.667061) (xy 111.480792 -348.613072) (xy 93.706665 -348.613072) (xy 93.698905 -348.667045)
			(xy 93.683543 -348.71937) (xy 93.66089 -348.768976) (xy 93.631409 -348.814854) (xy 93.595699 -348.856069)
			(xy 93.554487 -348.891784) (xy 93.508613 -348.92127) (xy 93.459009 -348.943928) (xy 93.406686 -348.959296)
			(xy 93.352709 -348.967063) (xy 93.325442 -348.967552) (xy 92.461842 -348.967552) (xy 92.434568 -348.967111)
			(xy 92.380576 -348.959354) (xy 92.328236 -348.943991) (xy 92.278617 -348.921335) (xy 92.232727 -348.891848)
			(xy 92.1915 -348.856129) (xy 92.155777 -348.814907) (xy 92.126285 -348.76902) (xy 92.103624 -348.719403)
			(xy 92.088255 -348.667066) (xy 92.080492 -348.613074) (xy 90.597788 -348.613074) (xy 90.590026 -348.667058)
			(xy 90.574659 -348.719391) (xy 90.552001 -348.769004) (xy 90.522512 -348.814887) (xy 90.486794 -348.856107)
			(xy 90.445573 -348.891823) (xy 90.399688 -348.92131) (xy 90.350074 -348.943966) (xy 90.297741 -348.95933)
			(xy 90.243753 -348.96709) (xy 90.216482 -348.967552) (xy 89.352882 -348.967552) (xy 89.325613 -348.967084)
			(xy 89.27163 -348.95932) (xy 89.219301 -348.943953) (xy 89.169692 -348.921295) (xy 89.123812 -348.891808)
			(xy 89.082595 -348.856092) (xy 89.046881 -348.814874) (xy 89.017396 -348.768992) (xy 88.994741 -348.719382)
			(xy 88.979376 -348.667053) (xy 88.971614 -348.613069) (xy 87.488766 -348.613069) (xy 87.481005 -348.667048)
			(xy 87.465641 -348.719374) (xy 87.442987 -348.768982) (xy 87.413504 -348.81486) (xy 87.377792 -348.856076)
			(xy 87.336578 -348.891791) (xy 87.290701 -348.921276) (xy 87.241095 -348.943933) (xy 87.188769 -348.9593)
			(xy 87.13479 -348.967064) (xy 87.107522 -348.967552) (xy 86.243922 -348.967552) (xy 86.216649 -348.96711)
			(xy 86.162659 -348.95935) (xy 86.110322 -348.943985) (xy 86.060705 -348.921329) (xy 86.014817 -348.891841)
			(xy 85.973593 -348.856122) (xy 85.937872 -348.814901) (xy 85.908382 -348.769015) (xy 85.885722 -348.719399)
			(xy 85.870354 -348.667063) (xy 85.862592 -348.613073) (xy 84.379888 -348.613073) (xy 84.372126 -348.667061)
			(xy 84.356758 -348.719395) (xy 84.334098 -348.76901) (xy 84.304608 -348.814894) (xy 84.268887 -348.856114)
			(xy 84.227663 -348.89183) (xy 84.181776 -348.921316) (xy 84.13216 -348.943971) (xy 84.079824 -348.959334)
			(xy 84.025834 -348.967091) (xy 83.998562 -348.967552) (xy 83.134962 -348.967552) (xy 83.107694 -348.967083)
			(xy 83.053713 -348.959317) (xy 83.001386 -348.943948) (xy 82.95178 -348.921289) (xy 82.905902 -348.891801)
			(xy 82.864688 -348.856085) (xy 82.828976 -348.814867) (xy 82.799493 -348.768987) (xy 82.776839 -348.719378)
			(xy 82.761475 -348.66705) (xy 82.753714 -348.613068) (xy 81.270866 -348.613068) (xy 81.270866 -348.613069)
			(xy 81.263104 -348.667051) (xy 81.247739 -348.719379) (xy 81.225084 -348.768987) (xy 81.195599 -348.814867)
			(xy 81.159885 -348.856083) (xy 81.118669 -348.891798) (xy 81.072789 -348.921283) (xy 81.02318 -348.943939)
			(xy 80.970853 -348.959304) (xy 80.916871 -348.967065) (xy 80.889602 -348.967552) (xy 80.026002 -348.967552)
			(xy 79.99873 -348.967109) (xy 79.944742 -348.959347) (xy 79.892407 -348.94398) (xy 79.842793 -348.921322)
			(xy 79.796908 -348.891834) (xy 79.755686 -348.856115) (xy 79.719968 -348.814894) (xy 79.690479 -348.769009)
			(xy 79.667821 -348.719394) (xy 79.652454 -348.66706) (xy 79.644692 -348.613072) (xy 78.161865 -348.613072)
			(xy 78.154105 -348.667045) (xy 78.138743 -348.71937) (xy 78.11609 -348.768976) (xy 78.086609 -348.814854)
			(xy 78.050899 -348.856069) (xy 78.009687 -348.891784) (xy 77.963813 -348.92127) (xy 77.914209 -348.943928)
			(xy 77.861886 -348.959296) (xy 77.807909 -348.967063) (xy 77.780642 -348.967552) (xy 76.917042 -348.967552)
			(xy 76.889768 -348.967111) (xy 76.835776 -348.959354) (xy 76.783436 -348.943991) (xy 76.733817 -348.921335)
			(xy 76.687927 -348.891848) (xy 76.6467 -348.856129) (xy 76.610977 -348.814907) (xy 76.581485 -348.76902)
			(xy 76.558824 -348.719403) (xy 76.543455 -348.667066) (xy 76.535692 -348.613074) (xy 75.052988 -348.613074)
			(xy 75.045226 -348.667058) (xy 75.029859 -348.719391) (xy 75.007201 -348.769004) (xy 74.977712 -348.814887)
			(xy 74.941994 -348.856107) (xy 74.900773 -348.891823) (xy 74.854888 -348.92131) (xy 74.805274 -348.943966)
			(xy 74.752941 -348.95933) (xy 74.698953 -348.96709) (xy 74.671682 -348.967552) (xy 73.808082 -348.967552)
			(xy 73.780813 -348.967084) (xy 73.72683 -348.95932) (xy 73.674501 -348.943953) (xy 73.624892 -348.921295)
			(xy 73.579012 -348.891808) (xy 73.537795 -348.856092) (xy 73.502081 -348.814874) (xy 73.472596 -348.768992)
			(xy 73.449941 -348.719382) (xy 73.434576 -348.667053) (xy 73.426814 -348.613069) (xy 71.943966 -348.613069)
			(xy 71.936205 -348.667048) (xy 71.920841 -348.719374) (xy 71.898187 -348.768982) (xy 71.868704 -348.81486)
			(xy 71.832992 -348.856076) (xy 71.791778 -348.891791) (xy 71.745901 -348.921276) (xy 71.696295 -348.943933)
			(xy 71.643969 -348.9593) (xy 71.58999 -348.967064) (xy 71.562722 -348.967552) (xy 70.699122 -348.967552)
			(xy 70.671849 -348.96711) (xy 70.617859 -348.95935) (xy 70.565522 -348.943985) (xy 70.515905 -348.921329)
			(xy 70.470017 -348.891841) (xy 70.428793 -348.856122) (xy 70.393072 -348.814901) (xy 70.363582 -348.769015)
			(xy 70.340922 -348.719399) (xy 70.325554 -348.667063) (xy 70.317792 -348.613073) (xy 68.835088 -348.613073)
			(xy 68.827326 -348.667061) (xy 68.811958 -348.719395) (xy 68.789298 -348.76901) (xy 68.759808 -348.814894)
			(xy 68.724087 -348.856114) (xy 68.682863 -348.89183) (xy 68.636976 -348.921316) (xy 68.58736 -348.943971)
			(xy 68.535024 -348.959334) (xy 68.481034 -348.967091) (xy 68.453762 -348.967552) (xy 67.590162 -348.967552)
			(xy 67.562894 -348.967083) (xy 67.508913 -348.959317) (xy 67.456586 -348.943948) (xy 67.40698 -348.921289)
			(xy 67.361102 -348.891801) (xy 67.319888 -348.856085) (xy 67.284176 -348.814867) (xy 67.254693 -348.768987)
			(xy 67.232039 -348.719378) (xy 67.216675 -348.66705) (xy 67.208914 -348.613068) (xy 65.726066 -348.613068)
			(xy 65.726066 -348.613069) (xy 65.718304 -348.667051) (xy 65.702939 -348.719379) (xy 65.680284 -348.768987)
			(xy 65.650799 -348.814867) (xy 65.615085 -348.856083) (xy 65.573869 -348.891798) (xy 65.527989 -348.921283)
			(xy 65.47838 -348.943939) (xy 65.426053 -348.959304) (xy 65.372071 -348.967065) (xy 65.344802 -348.967552)
			(xy 64.481202 -348.967552) (xy 64.45393 -348.967109) (xy 64.399942 -348.959347) (xy 64.347607 -348.94398)
			(xy 64.297993 -348.921322) (xy 64.252108 -348.891834) (xy 64.210886 -348.856115) (xy 64.175168 -348.814894)
			(xy 64.145679 -348.769009) (xy 64.123021 -348.719394) (xy 64.107654 -348.66706) (xy 64.099892 -348.613072)
			(xy 62.617065 -348.613072) (xy 62.609305 -348.667045) (xy 62.593943 -348.71937) (xy 62.57129 -348.768976)
			(xy 62.541809 -348.814854) (xy 62.506099 -348.856069) (xy 62.464887 -348.891784) (xy 62.419013 -348.92127)
			(xy 62.369409 -348.943928) (xy 62.317086 -348.959296) (xy 62.263109 -348.967063) (xy 62.235842 -348.967552)
			(xy 61.372242 -348.967552) (xy 61.344968 -348.967111) (xy 61.290976 -348.959354) (xy 61.238636 -348.943991)
			(xy 61.189017 -348.921335) (xy 61.143127 -348.891848) (xy 61.1019 -348.856129) (xy 61.066177 -348.814907)
			(xy 61.036685 -348.76902) (xy 61.014024 -348.719403) (xy 60.998655 -348.667066) (xy 60.990892 -348.613074)
			(xy 51.666865 -348.613074) (xy 51.659106 -348.667044) (xy 51.643743 -348.719369) (xy 51.621091 -348.768974)
			(xy 51.59161 -348.814852) (xy 51.555901 -348.856067) (xy 51.51469 -348.891781) (xy 51.468817 -348.921268)
			(xy 51.419214 -348.943926) (xy 51.366891 -348.959295) (xy 51.312914 -348.967062) (xy 51.285648 -348.967552)
			(xy 50.422048 -348.967552) (xy 50.394774 -348.967112) (xy 50.340781 -348.959355) (xy 50.288441 -348.943992)
			(xy 50.23882 -348.921337) (xy 50.192929 -348.89185) (xy 50.151702 -348.856132) (xy 50.115979 -348.814909)
			(xy 50.086486 -348.769022) (xy 50.063824 -348.719404) (xy 50.048455 -348.667066) (xy 50.040692 -348.613074)
			(xy 48.557989 -348.613074) (xy 48.550226 -348.667057) (xy 48.53486 -348.71939) (xy 48.512202 -348.769002)
			(xy 48.482714 -348.814885) (xy 48.446996 -348.856105) (xy 48.405776 -348.891821) (xy 48.359892 -348.921308)
			(xy 48.310278 -348.943964) (xy 48.257946 -348.959329) (xy 48.203959 -348.967089) (xy 48.176688 -348.967552)
			(xy 47.313088 -348.967552) (xy 47.285818 -348.967085) (xy 47.231835 -348.959321) (xy 47.179505 -348.943955)
			(xy 47.129895 -348.921297) (xy 47.084015 -348.89181) (xy 47.042797 -348.856094) (xy 47.007083 -348.814876)
			(xy 46.977597 -348.768994) (xy 46.954941 -348.719383) (xy 46.939576 -348.667053) (xy 46.931814 -348.61307)
			(xy 45.448966 -348.61307) (xy 45.441205 -348.667047) (xy 45.425841 -348.719373) (xy 45.403188 -348.76898)
			(xy 45.373705 -348.814858) (xy 45.337994 -348.856074) (xy 45.296781 -348.891789) (xy 45.250905 -348.921274)
			(xy 45.201299 -348.943932) (xy 45.148975 -348.959299) (xy 45.094995 -348.967064) (xy 45.067728 -348.967552)
			(xy 44.204128 -348.967552) (xy 44.176855 -348.96711) (xy 44.122864 -348.959351) (xy 44.070526 -348.943987)
			(xy 44.020908 -348.92133) (xy 43.97502 -348.891843) (xy 43.933795 -348.856124) (xy 43.898074 -348.814903)
			(xy 43.868583 -348.769016) (xy 43.845923 -348.7194) (xy 43.830555 -348.667064) (xy 43.822792 -348.613073)
			(xy 42.340088 -348.613073) (xy 42.332326 -348.66706) (xy 42.316958 -348.719394) (xy 42.294299 -348.769008)
			(xy 42.264809 -348.814892) (xy 42.229089 -348.856112) (xy 42.187866 -348.891828) (xy 42.14198 -348.921314)
			(xy 42.092364 -348.943969) (xy 42.040029 -348.959332) (xy 41.98604 -348.967091) (xy 41.958768 -348.967552)
			(xy 41.095168 -348.967552) (xy 41.067899 -348.967083) (xy 41.013918 -348.959318) (xy 40.961591 -348.943949)
			(xy 40.911983 -348.921291) (xy 40.866105 -348.891803) (xy 40.82489 -348.856087) (xy 40.789178 -348.814869)
			(xy 40.759694 -348.768989) (xy 40.73704 -348.719379) (xy 40.721675 -348.667051) (xy 40.713914 -348.613069)
			(xy 39.231066 -348.613069) (xy 39.223304 -348.66705) (xy 39.20794 -348.719377) (xy 39.185285 -348.768986)
			(xy 39.1558 -348.814865) (xy 39.120087 -348.856081) (xy 39.078871 -348.891796) (xy 39.032993 -348.921281)
			(xy 38.983385 -348.943937) (xy 38.931058 -348.959303) (xy 38.877076 -348.967065) (xy 38.849808 -348.967552)
			(xy 37.986208 -348.967552) (xy 37.958936 -348.967109) (xy 37.904947 -348.959348) (xy 37.852612 -348.943982)
			(xy 37.802996 -348.921324) (xy 37.75711 -348.891836) (xy 37.715888 -348.856117) (xy 37.680169 -348.814896)
			(xy 37.65068 -348.769011) (xy 37.628021 -348.719396) (xy 37.612654 -348.667061) (xy 37.604892 -348.613072)
			(xy 36.122065 -348.613072) (xy 36.114306 -348.667044) (xy 36.098943 -348.719369) (xy 36.076291 -348.768974)
			(xy 36.04681 -348.814852) (xy 36.011101 -348.856067) (xy 35.96989 -348.891781) (xy 35.924017 -348.921268)
			(xy 35.874414 -348.943926) (xy 35.822091 -348.959295) (xy 35.768114 -348.967062) (xy 35.740848 -348.967552)
			(xy 34.877248 -348.967552) (xy 34.849974 -348.967112) (xy 34.795981 -348.959355) (xy 34.743641 -348.943992)
			(xy 34.69402 -348.921337) (xy 34.648129 -348.89185) (xy 34.606902 -348.856132) (xy 34.571179 -348.814909)
			(xy 34.541686 -348.769022) (xy 34.519024 -348.719404) (xy 34.503655 -348.667066) (xy 34.495892 -348.613074)
			(xy 33.013189 -348.613074) (xy 33.005426 -348.667057) (xy 32.99006 -348.71939) (xy 32.967402 -348.769002)
			(xy 32.937914 -348.814885) (xy 32.902196 -348.856105) (xy 32.860976 -348.891821) (xy 32.815092 -348.921308)
			(xy 32.765478 -348.943964) (xy 32.713146 -348.959329) (xy 32.659159 -348.967089) (xy 32.631888 -348.967552)
			(xy 31.768288 -348.967552) (xy 31.741018 -348.967085) (xy 31.687035 -348.959321) (xy 31.634705 -348.943955)
			(xy 31.585095 -348.921297) (xy 31.539215 -348.89181) (xy 31.497997 -348.856094) (xy 31.462283 -348.814876)
			(xy 31.432797 -348.768994) (xy 31.410141 -348.719383) (xy 31.394776 -348.667053) (xy 31.387014 -348.61307)
			(xy 29.904166 -348.61307) (xy 29.896405 -348.667047) (xy 29.881041 -348.719373) (xy 29.858388 -348.76898)
			(xy 29.828905 -348.814858) (xy 29.793194 -348.856074) (xy 29.751981 -348.891789) (xy 29.706105 -348.921274)
			(xy 29.656499 -348.943932) (xy 29.604175 -348.959299) (xy 29.550195 -348.967064) (xy 29.522928 -348.967552)
			(xy 28.659328 -348.967552) (xy 28.632055 -348.96711) (xy 28.578064 -348.959351) (xy 28.525726 -348.943987)
			(xy 28.476108 -348.92133) (xy 28.43022 -348.891843) (xy 28.388995 -348.856124) (xy 28.353274 -348.814903)
			(xy 28.323783 -348.769016) (xy 28.301123 -348.7194) (xy 28.285755 -348.667064) (xy 28.277992 -348.613073)
			(xy 26.795288 -348.613073) (xy 26.787526 -348.66706) (xy 26.772158 -348.719394) (xy 26.749499 -348.769008)
			(xy 26.720009 -348.814892) (xy 26.684289 -348.856112) (xy 26.643066 -348.891828) (xy 26.59718 -348.921314)
			(xy 26.547564 -348.943969) (xy 26.495229 -348.959332) (xy 26.44124 -348.967091) (xy 26.413968 -348.967552)
			(xy 25.550368 -348.967552) (xy 25.523099 -348.967083) (xy 25.469118 -348.959318) (xy 25.416791 -348.943949)
			(xy 25.367183 -348.921291) (xy 25.321305 -348.891803) (xy 25.28009 -348.856087) (xy 25.244378 -348.814869)
			(xy 25.214894 -348.768989) (xy 25.19224 -348.719379) (xy 25.176875 -348.667051) (xy 25.169114 -348.613069)
			(xy 23.686266 -348.613069) (xy 23.678504 -348.66705) (xy 23.66314 -348.719377) (xy 23.640485 -348.768986)
			(xy 23.611 -348.814865) (xy 23.575287 -348.856081) (xy 23.534071 -348.891796) (xy 23.488193 -348.921281)
			(xy 23.438585 -348.943937) (xy 23.386258 -348.959303) (xy 23.332276 -348.967065) (xy 23.305008 -348.967552)
			(xy 22.441408 -348.967552) (xy 22.414136 -348.967109) (xy 22.360147 -348.959348) (xy 22.307812 -348.943982)
			(xy 22.258196 -348.921324) (xy 22.21231 -348.891836) (xy 22.171088 -348.856117) (xy 22.135369 -348.814896)
			(xy 22.10588 -348.769011) (xy 22.083221 -348.719396) (xy 22.067854 -348.667061) (xy 22.060092 -348.613072)
			(xy 20.577347 -348.613072) (xy 20.569586 -348.667048) (xy 20.55422 -348.719381) (xy 20.531562 -348.768994)
			(xy 20.502074 -348.814878) (xy 20.466357 -348.856098) (xy 20.425136 -348.891816) (xy 20.379253 -348.921303)
			(xy 20.329639 -348.943961) (xy 20.277306 -348.959327) (xy 20.223319 -348.967089) (xy 20.196048 -348.967552)
			(xy 19.332448 -348.967552) (xy 19.305179 -348.967065) (xy 19.251195 -348.959304) (xy 19.198866 -348.943938)
			(xy 19.149256 -348.921282) (xy 19.103375 -348.891796) (xy 19.062158 -348.856081) (xy 19.026443 -348.814863)
			(xy 18.996957 -348.768982) (xy 18.974301 -348.719372) (xy 18.958936 -348.667043) (xy 18.951174 -348.613059)
			(xy 8.879169 -348.613059) (xy 8.892221 -348.718461) (xy 8.900171 -348.847356) (xy 8.900668 -348.911926)
			(xy 8.900171 -348.976496) (xy 8.892221 -349.105391) (xy 8.876351 -349.233551) (xy 8.852622 -349.360492)
			(xy 8.821123 -349.485731) (xy 8.781974 -349.608794) (xy 8.735323 -349.729213) (xy 8.681348 -349.846532)
			(xy 8.620253 -349.960306) (xy 8.55227 -350.070103) (xy 8.477656 -350.175506) (xy 8.396695 -350.276116)
			(xy 8.309695 -350.371551) (xy 8.216984 -350.46145) (xy 8.118914 -350.545471) (xy 8.015859 -350.623295)
			(xy 7.908208 -350.694627) (xy 7.796369 -350.759197) (xy 7.680768 -350.816759) (xy 7.561843 -350.867096)
			(xy 7.440044 -350.910016) (xy 7.315834 -350.945357) (xy 7.189685 -350.972984) (xy 7.062073 -350.992793)
			(xy 6.933484 -351.004709) (xy 6.804406 -351.008686) (xy 6.675328 -351.004709) (xy 6.546739 -350.992793)
			(xy 6.419127 -350.972984) (xy 6.292978 -350.945357) (xy 6.168768 -350.910016) (xy 6.046969 -350.867096)
			(xy 5.928044 -350.816759) (xy 5.812443 -350.759197) (xy 5.700604 -350.694627) (xy 5.592953 -350.623295)
			(xy 5.489898 -350.545471) (xy 5.391828 -350.46145) (xy 5.299117 -350.371551) (xy 5.212117 -350.276116)
			(xy 5.131156 -350.175506) (xy 5.056542 -350.070103) (xy 4.988559 -349.960306) (xy 4.927464 -349.846532)
			(xy 4.873489 -349.729213) (xy 4.826838 -349.608794) (xy 4.787689 -349.485731) (xy 4.75619 -349.360492)
			(xy 4.732461 -349.233551) (xy 4.716591 -349.105391) (xy 4.708641 -348.976496) (xy 0.509016 -348.976496)
			(xy 0.509016 -351.638709) (xy 18.951172 -351.638709) (xy 18.951172 -351.584171) (xy 18.958934 -351.530187)
			(xy 18.974299 -351.477857) (xy 18.996956 -351.428247) (xy 19.026441 -351.382366) (xy 19.062157 -351.341148)
			(xy 19.103374 -351.305433) (xy 19.149255 -351.275947) (xy 19.198865 -351.25329) (xy 19.251195 -351.237925)
			(xy 19.305179 -351.230163) (xy 19.332448 -351.229676) (xy 20.196048 -351.229676) (xy 20.223319 -351.230143)
			(xy 20.277306 -351.237905) (xy 20.329638 -351.253271) (xy 20.379252 -351.275929) (xy 20.425135 -351.305416)
			(xy 20.466355 -351.341133) (xy 20.502073 -351.382353) (xy 20.53156 -351.428237) (xy 20.554218 -351.47785)
			(xy 20.569584 -351.530182) (xy 20.577347 -351.584169) (xy 20.577347 -351.638669) (xy 22.060139 -351.638669)
			(xy 22.060139 -351.584131) (xy 22.067901 -351.530149) (xy 22.083266 -351.477821) (xy 22.105922 -351.428212)
			(xy 22.135407 -351.382333) (xy 22.171122 -351.341117) (xy 22.212339 -351.305403) (xy 22.258219 -351.275918)
			(xy 22.307829 -351.253263) (xy 22.360157 -351.237899) (xy 22.414139 -351.230139) (xy 22.441408 -351.229676)
			(xy 23.305008 -351.229676) (xy 23.33228 -351.230087) (xy 23.386268 -351.23785) (xy 23.438602 -351.253218)
			(xy 23.488216 -351.275877) (xy 23.5341 -351.305366) (xy 23.575321 -351.341085) (xy 23.611039 -351.382306)
			(xy 23.640527 -351.428191) (xy 23.663185 -351.477806) (xy 23.678551 -351.53014) (xy 23.686314 -351.584128)
			(xy 23.686314 -351.638665) (xy 25.169162 -351.638665) (xy 25.169162 -351.584135) (xy 25.176922 -351.530159)
			(xy 25.192284 -351.477838) (xy 25.214936 -351.428234) (xy 25.244416 -351.38236) (xy 25.280124 -351.341147)
			(xy 25.321334 -351.305435) (xy 25.367206 -351.275951) (xy 25.416808 -351.253296) (xy 25.469128 -351.237929)
			(xy 25.523103 -351.230165) (xy 25.550368 -351.229676) (xy 26.413968 -351.229676) (xy 26.441243 -351.230061)
			(xy 26.495239 -351.237821) (xy 26.547581 -351.253186) (xy 26.597203 -351.275844) (xy 26.643095 -351.305333)
			(xy 26.684323 -351.341054) (xy 26.720047 -351.382279) (xy 26.749541 -351.428169) (xy 26.772203 -351.477789)
			(xy 26.787573 -351.53013) (xy 26.795336 -351.584125) (xy 26.795336 -351.63867) (xy 28.278039 -351.63867)
			(xy 28.278039 -351.58413) (xy 28.285802 -351.530146) (xy 28.301168 -351.477817) (xy 28.323825 -351.428207)
			(xy 28.353312 -351.382326) (xy 28.389029 -351.341109) (xy 28.430249 -351.305396) (xy 28.476131 -351.275912)
			(xy 28.525743 -351.253258) (xy 28.578074 -351.237896) (xy 28.632058 -351.230137) (xy 28.659328 -351.229676)
			(xy 29.522928 -351.229676) (xy 29.550199 -351.230088) (xy 29.604185 -351.237854) (xy 29.656516 -351.253223)
			(xy 29.706128 -351.275883) (xy 29.75201 -351.305373) (xy 29.793228 -351.341092) (xy 29.828944 -351.382313)
			(xy 29.85843 -351.428197) (xy 29.881086 -351.47781) (xy 29.896452 -351.530143) (xy 29.904214 -351.584129)
			(xy 29.904214 -351.638666) (xy 31.387062 -351.638666) (xy 31.387062 -351.584134) (xy 31.394823 -351.530157)
			(xy 31.410186 -351.477833) (xy 31.432839 -351.428229) (xy 31.462321 -351.382353) (xy 31.498031 -351.34114)
			(xy 31.539243 -351.305428) (xy 31.585118 -351.275945) (xy 31.634722 -351.25329) (xy 31.687045 -351.237925)
			(xy 31.741022 -351.230163) (xy 31.768288 -351.229676) (xy 32.631888 -351.229676) (xy 32.659162 -351.230063)
			(xy 32.713156 -351.237824) (xy 32.765495 -351.253191) (xy 32.815115 -351.27585) (xy 32.861004 -351.30534)
			(xy 32.90223 -351.341061) (xy 32.937952 -351.382286) (xy 32.967444 -351.428175) (xy 32.990105 -351.477794)
			(xy 33.005473 -351.530132) (xy 33.013236 -351.584126) (xy 33.013236 -351.63867) (xy 34.49594 -351.63867)
			(xy 34.49594 -351.58413) (xy 34.503702 -351.530144) (xy 34.519069 -351.477812) (xy 34.541728 -351.428201)
			(xy 34.571217 -351.38232) (xy 34.606936 -351.341102) (xy 34.648158 -351.305388) (xy 34.694043 -351.275905)
			(xy 34.743658 -351.253253) (xy 34.795991 -351.237892) (xy 34.849977 -351.230136) (xy 34.877248 -351.229676)
			(xy 35.740848 -351.229676) (xy 35.768118 -351.23009) (xy 35.822102 -351.237858) (xy 35.874431 -351.253229)
			(xy 35.92404 -351.27589) (xy 35.969919 -351.30538) (xy 36.011135 -351.341099) (xy 36.046849 -351.382319)
			(xy 36.076333 -351.428203) (xy 36.098988 -351.477814) (xy 36.114352 -351.530145) (xy 36.122114 -351.58413)
			(xy 36.122114 -351.638669) (xy 37.604939 -351.638669) (xy 37.604939 -351.584131) (xy 37.612701 -351.530149)
			(xy 37.628066 -351.477821) (xy 37.650722 -351.428212) (xy 37.680207 -351.382333) (xy 37.715922 -351.341117)
			(xy 37.757139 -351.305403) (xy 37.803019 -351.275918) (xy 37.852629 -351.253263) (xy 37.904957 -351.237899)
			(xy 37.958939 -351.230139) (xy 37.986208 -351.229676) (xy 38.849808 -351.229676) (xy 38.87708 -351.230087)
			(xy 38.931068 -351.23785) (xy 38.983402 -351.253218) (xy 39.033016 -351.275877) (xy 39.0789 -351.305366)
			(xy 39.120121 -351.341085) (xy 39.155839 -351.382306) (xy 39.185327 -351.428191) (xy 39.207985 -351.477806)
			(xy 39.223351 -351.53014) (xy 39.231114 -351.584128) (xy 39.231114 -351.638665) (xy 40.713962 -351.638665)
			(xy 40.713962 -351.584135) (xy 40.721722 -351.530159) (xy 40.737084 -351.477838) (xy 40.759736 -351.428234)
			(xy 40.789216 -351.38236) (xy 40.824924 -351.341147) (xy 40.866134 -351.305435) (xy 40.912006 -351.275951)
			(xy 40.961608 -351.253296) (xy 41.013928 -351.237929) (xy 41.067903 -351.230165) (xy 41.095168 -351.229676)
			(xy 41.958768 -351.229676) (xy 41.986043 -351.230061) (xy 42.040039 -351.237821) (xy 42.092381 -351.253186)
			(xy 42.142003 -351.275844) (xy 42.187895 -351.305333) (xy 42.229123 -351.341054) (xy 42.264847 -351.382279)
			(xy 42.294341 -351.428169) (xy 42.317003 -351.477789) (xy 42.332373 -351.53013) (xy 42.340136 -351.584125)
			(xy 42.340136 -351.63867) (xy 43.822839 -351.63867) (xy 43.822839 -351.58413) (xy 43.830602 -351.530146)
			(xy 43.845968 -351.477817) (xy 43.868625 -351.428207) (xy 43.898112 -351.382326) (xy 43.933829 -351.341109)
			(xy 43.975049 -351.305396) (xy 44.020931 -351.275912) (xy 44.070543 -351.253258) (xy 44.122874 -351.237896)
			(xy 44.176858 -351.230137) (xy 44.204128 -351.229676) (xy 45.067728 -351.229676) (xy 45.094999 -351.230088)
			(xy 45.148985 -351.237854) (xy 45.201316 -351.253223) (xy 45.250928 -351.275883) (xy 45.29681 -351.305373)
			(xy 45.338028 -351.341092) (xy 45.373744 -351.382313) (xy 45.40323 -351.428197) (xy 45.425886 -351.47781)
			(xy 45.441252 -351.530143) (xy 45.449014 -351.584129) (xy 45.449014 -351.638666) (xy 46.931862 -351.638666)
			(xy 46.931862 -351.584134) (xy 46.939623 -351.530157) (xy 46.954986 -351.477833) (xy 46.977639 -351.428229)
			(xy 47.007121 -351.382353) (xy 47.042831 -351.34114) (xy 47.084043 -351.305428) (xy 47.129918 -351.275945)
			(xy 47.179522 -351.25329) (xy 47.231845 -351.237925) (xy 47.285822 -351.230163) (xy 47.313088 -351.229676)
			(xy 48.176688 -351.229676) (xy 48.203962 -351.230063) (xy 48.257956 -351.237824) (xy 48.310295 -351.253191)
			(xy 48.359915 -351.27585) (xy 48.405804 -351.30534) (xy 48.44703 -351.341061) (xy 48.482752 -351.382286)
			(xy 48.512244 -351.428175) (xy 48.534905 -351.477794) (xy 48.550273 -351.530132) (xy 48.558036 -351.584126)
			(xy 48.558036 -351.63867) (xy 50.04074 -351.63867) (xy 50.04074 -351.58413) (xy 50.048502 -351.530144)
			(xy 50.063869 -351.477812) (xy 50.086528 -351.428201) (xy 50.116017 -351.38232) (xy 50.151736 -351.341102)
			(xy 50.192958 -351.305388) (xy 50.238843 -351.275905) (xy 50.288458 -351.253253) (xy 50.340791 -351.237892)
			(xy 50.394777 -351.230136) (xy 50.422048 -351.229676) (xy 51.285648 -351.229676) (xy 51.312918 -351.23009)
			(xy 51.366902 -351.237858) (xy 51.419231 -351.253229) (xy 51.46884 -351.27589) (xy 51.514719 -351.30538)
			(xy 51.555935 -351.341099) (xy 51.591649 -351.382319) (xy 51.621133 -351.428203) (xy 51.643788 -351.477814)
			(xy 51.659152 -351.530145) (xy 51.666914 -351.58413) (xy 51.666914 -351.63867) (xy 60.99094 -351.63867)
			(xy 60.99094 -351.58413) (xy 60.998702 -351.530145) (xy 61.014069 -351.477814) (xy 61.036727 -351.428203)
			(xy 61.066216 -351.382322) (xy 61.101934 -351.341105) (xy 61.143155 -351.305391) (xy 61.18904 -351.275907)
			(xy 61.238653 -351.253254) (xy 61.290986 -351.237893) (xy 61.344972 -351.230137) (xy 61.372242 -351.229676)
			(xy 62.235842 -351.229676) (xy 62.263112 -351.230089) (xy 62.317097 -351.237857) (xy 62.369426 -351.253227)
			(xy 62.419036 -351.275888) (xy 62.464916 -351.305378) (xy 62.506133 -351.341097) (xy 62.541847 -351.382317)
			(xy 62.571332 -351.428201) (xy 62.593988 -351.477813) (xy 62.609352 -351.530145) (xy 62.617114 -351.58413)
			(xy 62.617114 -351.638668) (xy 64.099939 -351.638668) (xy 64.099939 -351.584132) (xy 64.107701 -351.53015)
			(xy 64.123066 -351.477822) (xy 64.145721 -351.428214) (xy 64.175206 -351.382335) (xy 64.21092 -351.341119)
			(xy 64.252136 -351.305405) (xy 64.298016 -351.27592) (xy 64.347624 -351.253265) (xy 64.399952 -351.2379)
			(xy 64.453934 -351.230139) (xy 64.481202 -351.229676) (xy 65.344802 -351.229676) (xy 65.372074 -351.230087)
			(xy 65.426063 -351.237849) (xy 65.478397 -351.253216) (xy 65.528012 -351.275875) (xy 65.573897 -351.305364)
			(xy 65.615119 -351.341083) (xy 65.650837 -351.382304) (xy 65.680326 -351.42819) (xy 65.702984 -351.477805)
			(xy 65.718351 -351.530139) (xy 65.726113 -351.584128) (xy 65.726113 -351.638665) (xy 67.208962 -351.638665)
			(xy 67.208962 -351.584135) (xy 67.216722 -351.53016) (xy 67.232084 -351.477839) (xy 67.254735 -351.428236)
			(xy 67.284215 -351.382362) (xy 67.319922 -351.341149) (xy 67.361131 -351.305437) (xy 67.407003 -351.275953)
			(xy 67.456603 -351.253297) (xy 67.508923 -351.23793) (xy 67.562897 -351.230165) (xy 67.590162 -351.229676)
			(xy 68.453762 -351.229676) (xy 68.481037 -351.230061) (xy 68.535034 -351.23782) (xy 68.587376 -351.253184)
			(xy 68.636999 -351.275842) (xy 68.682892 -351.305331) (xy 68.724121 -351.341052) (xy 68.759846 -351.382277)
			(xy 68.78934 -351.428167) (xy 68.812003 -351.477788) (xy 68.827372 -351.530129) (xy 68.835136 -351.584125)
			(xy 68.835136 -351.638669) (xy 70.317839 -351.638669) (xy 70.317839 -351.584131) (xy 70.325601 -351.530147)
			(xy 70.340967 -351.477818) (xy 70.363624 -351.428208) (xy 70.393111 -351.382328) (xy 70.428827 -351.341112)
			(xy 70.470046 -351.305398) (xy 70.515928 -351.275914) (xy 70.565539 -351.25326) (xy 70.617869 -351.237897)
			(xy 70.671853 -351.230138) (xy 70.699122 -351.229676) (xy 71.562722 -351.229676) (xy 71.589993 -351.230088)
			(xy 71.64398 -351.237853) (xy 71.696312 -351.253222) (xy 71.745924 -351.275881) (xy 71.791807 -351.305371)
			(xy 71.833026 -351.34109) (xy 71.868742 -351.382311) (xy 71.898229 -351.428195) (xy 71.920886 -351.477809)
			(xy 71.936252 -351.530142) (xy 71.944014 -351.584129) (xy 71.944014 -351.638666) (xy 73.426862 -351.638666)
			(xy 73.426862 -351.584134) (xy 73.434623 -351.530158) (xy 73.449986 -351.477835) (xy 73.472638 -351.428231)
			(xy 73.50212 -351.382355) (xy 73.537829 -351.341142) (xy 73.579041 -351.30543) (xy 73.624915 -351.275947)
			(xy 73.674518 -351.253292) (xy 73.72684 -351.237927) (xy 73.780816 -351.230164) (xy 73.808082 -351.229676)
			(xy 74.671682 -351.229676) (xy 74.698957 -351.230062) (xy 74.752951 -351.237823) (xy 74.805291 -351.253189)
			(xy 74.854911 -351.275848) (xy 74.900802 -351.305338) (xy 74.942028 -351.341059) (xy 74.977751 -351.382284)
			(xy 75.007243 -351.428173) (xy 75.029904 -351.477792) (xy 75.045273 -351.530132) (xy 75.053036 -351.584125)
			(xy 75.053036 -351.63867) (xy 76.53574 -351.63867) (xy 76.53574 -351.58413) (xy 76.543502 -351.530145)
			(xy 76.558869 -351.477814) (xy 76.581527 -351.428203) (xy 76.611016 -351.382322) (xy 76.646734 -351.341105)
			(xy 76.687955 -351.305391) (xy 76.73384 -351.275907) (xy 76.783453 -351.253254) (xy 76.835786 -351.237893)
			(xy 76.889772 -351.230137) (xy 76.917042 -351.229676) (xy 77.780642 -351.229676) (xy 77.807912 -351.230089)
			(xy 77.861897 -351.237857) (xy 77.914226 -351.253227) (xy 77.963836 -351.275888) (xy 78.009716 -351.305378)
			(xy 78.050933 -351.341097) (xy 78.086647 -351.382317) (xy 78.116132 -351.428201) (xy 78.138788 -351.477813)
			(xy 78.154152 -351.530145) (xy 78.161914 -351.58413) (xy 78.161914 -351.638668) (xy 79.644739 -351.638668)
			(xy 79.644739 -351.584132) (xy 79.652501 -351.53015) (xy 79.667866 -351.477822) (xy 79.690521 -351.428214)
			(xy 79.720006 -351.382335) (xy 79.75572 -351.341119) (xy 79.796936 -351.305405) (xy 79.842816 -351.27592)
			(xy 79.892424 -351.253265) (xy 79.944752 -351.2379) (xy 79.998734 -351.230139) (xy 80.026002 -351.229676)
			(xy 80.889602 -351.229676) (xy 80.916874 -351.230087) (xy 80.970863 -351.237849) (xy 81.023197 -351.253216)
			(xy 81.072812 -351.275875) (xy 81.118697 -351.305364) (xy 81.159919 -351.341083) (xy 81.195637 -351.382304)
			(xy 81.225126 -351.42819) (xy 81.247784 -351.477805) (xy 81.263151 -351.530139) (xy 81.270913 -351.584128)
			(xy 81.270913 -351.638665) (xy 82.753762 -351.638665) (xy 82.753762 -351.584135) (xy 82.761522 -351.53016)
			(xy 82.776884 -351.477839) (xy 82.799535 -351.428236) (xy 82.829015 -351.382362) (xy 82.864722 -351.341149)
			(xy 82.905931 -351.305437) (xy 82.951803 -351.275953) (xy 83.001403 -351.253297) (xy 83.053723 -351.23793)
			(xy 83.107697 -351.230165) (xy 83.134962 -351.229676) (xy 83.998562 -351.229676) (xy 84.025837 -351.230061)
			(xy 84.079834 -351.23782) (xy 84.132176 -351.253184) (xy 84.181799 -351.275842) (xy 84.227692 -351.305331)
			(xy 84.268921 -351.341052) (xy 84.304646 -351.382277) (xy 84.33414 -351.428167) (xy 84.356803 -351.477788)
			(xy 84.372172 -351.530129) (xy 84.379936 -351.584125) (xy 84.379936 -351.638669) (xy 85.862639 -351.638669)
			(xy 85.862639 -351.584131) (xy 85.870401 -351.530147) (xy 85.885767 -351.477818) (xy 85.908424 -351.428208)
			(xy 85.937911 -351.382328) (xy 85.973627 -351.341112) (xy 86.014846 -351.305398) (xy 86.060728 -351.275914)
			(xy 86.110339 -351.25326) (xy 86.162669 -351.237897) (xy 86.216653 -351.230138) (xy 86.243922 -351.229676)
			(xy 87.107522 -351.229676) (xy 87.134793 -351.230088) (xy 87.18878 -351.237853) (xy 87.241112 -351.253222)
			(xy 87.290724 -351.275881) (xy 87.336607 -351.305371) (xy 87.377826 -351.34109) (xy 87.413542 -351.382311)
			(xy 87.443029 -351.428195) (xy 87.465686 -351.477809) (xy 87.481052 -351.530142) (xy 87.488814 -351.584129)
			(xy 87.488814 -351.638666) (xy 88.971662 -351.638666) (xy 88.971662 -351.584134) (xy 88.979423 -351.530158)
			(xy 88.994786 -351.477835) (xy 89.017438 -351.428231) (xy 89.04692 -351.382355) (xy 89.082629 -351.341142)
			(xy 89.123841 -351.30543) (xy 89.169715 -351.275947) (xy 89.219318 -351.253292) (xy 89.27164 -351.237927)
			(xy 89.325616 -351.230164) (xy 89.352882 -351.229676) (xy 90.216482 -351.229676) (xy 90.243757 -351.230062)
			(xy 90.297751 -351.237823) (xy 90.350091 -351.253189) (xy 90.399711 -351.275848) (xy 90.445602 -351.305338)
			(xy 90.486828 -351.341059) (xy 90.522551 -351.382284) (xy 90.552043 -351.428173) (xy 90.574704 -351.477792)
			(xy 90.590073 -351.530132) (xy 90.597836 -351.584125) (xy 90.597836 -351.63867) (xy 92.08054 -351.63867)
			(xy 92.08054 -351.58413) (xy 92.088302 -351.530145) (xy 92.103669 -351.477814) (xy 92.126327 -351.428203)
			(xy 92.155816 -351.382322) (xy 92.191534 -351.341105) (xy 92.232755 -351.305391) (xy 92.27864 -351.275907)
			(xy 92.328253 -351.253254) (xy 92.380586 -351.237893) (xy 92.434572 -351.230137) (xy 92.461842 -351.229676)
			(xy 93.325442 -351.229676) (xy 93.352712 -351.230089) (xy 93.406697 -351.237857) (xy 93.459026 -351.253227)
			(xy 93.508636 -351.275888) (xy 93.554516 -351.305378) (xy 93.595733 -351.341097) (xy 93.631447 -351.382317)
			(xy 93.660932 -351.428201) (xy 93.683588 -351.477813) (xy 93.698952 -351.530145) (xy 93.706714 -351.58413)
			(xy 93.706714 -351.638669) (xy 111.480839 -351.638669) (xy 111.480839 -351.584131) (xy 111.488601 -351.530149)
			(xy 111.503966 -351.477821) (xy 111.526622 -351.428212) (xy 111.556107 -351.382333) (xy 111.591822 -351.341117)
			(xy 111.633039 -351.305403) (xy 111.678919 -351.275918) (xy 111.728529 -351.253263) (xy 111.780857 -351.237899)
			(xy 111.834839 -351.230139) (xy 111.862108 -351.229676) (xy 112.725708 -351.229676) (xy 112.75298 -351.230087)
			(xy 112.806968 -351.23785) (xy 112.859302 -351.253218) (xy 112.908916 -351.275877) (xy 112.9548 -351.305366)
			(xy 112.996021 -351.341085) (xy 113.031739 -351.382306) (xy 113.061227 -351.428191) (xy 113.083885 -351.477806)
			(xy 113.099251 -351.53014) (xy 113.107014 -351.584128) (xy 113.107014 -351.638665) (xy 114.589862 -351.638665)
			(xy 114.589862 -351.584135) (xy 114.597622 -351.530159) (xy 114.612984 -351.477838) (xy 114.635636 -351.428234)
			(xy 114.665116 -351.38236) (xy 114.700824 -351.341147) (xy 114.742034 -351.305435) (xy 114.787906 -351.275951)
			(xy 114.837508 -351.253296) (xy 114.889828 -351.237929) (xy 114.943803 -351.230165) (xy 114.971068 -351.229676)
			(xy 115.834668 -351.229676) (xy 115.861943 -351.230061) (xy 115.915939 -351.237821) (xy 115.968281 -351.253186)
			(xy 116.017903 -351.275844) (xy 116.063795 -351.305333) (xy 116.105023 -351.341054) (xy 116.140747 -351.382279)
			(xy 116.170241 -351.428169) (xy 116.192903 -351.477789) (xy 116.208273 -351.53013) (xy 116.216036 -351.584125)
			(xy 116.216036 -351.63867) (xy 117.698739 -351.63867) (xy 117.698739 -351.58413) (xy 117.706502 -351.530146)
			(xy 117.721868 -351.477817) (xy 117.744525 -351.428207) (xy 117.774012 -351.382326) (xy 117.809729 -351.341109)
			(xy 117.850949 -351.305396) (xy 117.896831 -351.275912) (xy 117.946443 -351.253258) (xy 117.998774 -351.237896)
			(xy 118.052758 -351.230137) (xy 118.080028 -351.229676) (xy 118.943628 -351.229676) (xy 118.970899 -351.230088)
			(xy 119.024885 -351.237854) (xy 119.077216 -351.253223) (xy 119.126828 -351.275883) (xy 119.17271 -351.305373)
			(xy 119.213928 -351.341092) (xy 119.249644 -351.382313) (xy 119.27913 -351.428197) (xy 119.301786 -351.47781)
			(xy 119.317152 -351.530143) (xy 119.324914 -351.584129) (xy 119.324914 -351.638666) (xy 120.807762 -351.638666)
			(xy 120.807762 -351.584134) (xy 120.815523 -351.530157) (xy 120.830886 -351.477833) (xy 120.853539 -351.428229)
			(xy 120.883021 -351.382353) (xy 120.918731 -351.34114) (xy 120.959943 -351.305428) (xy 121.005818 -351.275945)
			(xy 121.055422 -351.25329) (xy 121.107745 -351.237925) (xy 121.161722 -351.230163) (xy 121.188988 -351.229676)
			(xy 122.052588 -351.229676) (xy 122.079862 -351.230063) (xy 122.133856 -351.237824) (xy 122.186195 -351.253191)
			(xy 122.235815 -351.27585) (xy 122.281704 -351.30534) (xy 122.32293 -351.341061) (xy 122.358652 -351.382286)
			(xy 122.388144 -351.428175) (xy 122.410805 -351.477794) (xy 122.426173 -351.530132) (xy 122.433936 -351.584126)
			(xy 122.433936 -351.63867) (xy 123.91664 -351.63867) (xy 123.91664 -351.58413) (xy 123.924402 -351.530144)
			(xy 123.939769 -351.477812) (xy 123.962428 -351.428201) (xy 123.991917 -351.38232) (xy 124.027636 -351.341102)
			(xy 124.068858 -351.305388) (xy 124.114743 -351.275905) (xy 124.164358 -351.253253) (xy 124.216691 -351.237892)
			(xy 124.270677 -351.230136) (xy 124.297948 -351.229676) (xy 125.161548 -351.229676) (xy 125.188818 -351.23009)
			(xy 125.242802 -351.237858) (xy 125.295131 -351.253229) (xy 125.34474 -351.27589) (xy 125.390619 -351.30538)
			(xy 125.431835 -351.341099) (xy 125.467549 -351.382319) (xy 125.497033 -351.428203) (xy 125.519688 -351.477814)
			(xy 125.535052 -351.530145) (xy 125.542814 -351.58413) (xy 125.542814 -351.638669) (xy 127.025639 -351.638669)
			(xy 127.025639 -351.584131) (xy 127.033401 -351.530149) (xy 127.048766 -351.477821) (xy 127.071422 -351.428212)
			(xy 127.100907 -351.382333) (xy 127.136622 -351.341117) (xy 127.177839 -351.305403) (xy 127.223719 -351.275918)
			(xy 127.273329 -351.253263) (xy 127.325657 -351.237899) (xy 127.379639 -351.230139) (xy 127.406908 -351.229676)
			(xy 128.270508 -351.229676) (xy 128.29778 -351.230087) (xy 128.351768 -351.23785) (xy 128.404102 -351.253218)
			(xy 128.453716 -351.275877) (xy 128.4996 -351.305366) (xy 128.540821 -351.341085) (xy 128.576539 -351.382306)
			(xy 128.606027 -351.428191) (xy 128.628685 -351.477806) (xy 128.644051 -351.53014) (xy 128.651814 -351.584128)
			(xy 128.651814 -351.638665) (xy 130.134662 -351.638665) (xy 130.134662 -351.584135) (xy 130.142422 -351.530159)
			(xy 130.157784 -351.477838) (xy 130.180436 -351.428234) (xy 130.209916 -351.38236) (xy 130.245624 -351.341147)
			(xy 130.286834 -351.305435) (xy 130.332706 -351.275951) (xy 130.382308 -351.253296) (xy 130.434628 -351.237929)
			(xy 130.488603 -351.230165) (xy 130.515868 -351.229676) (xy 131.379468 -351.229676) (xy 131.406743 -351.230061)
			(xy 131.460739 -351.237821) (xy 131.513081 -351.253186) (xy 131.562703 -351.275844) (xy 131.608595 -351.305333)
			(xy 131.649823 -351.341054) (xy 131.685547 -351.382279) (xy 131.715041 -351.428169) (xy 131.737703 -351.477789)
			(xy 131.753073 -351.53013) (xy 131.760836 -351.584125) (xy 131.760836 -351.63867) (xy 133.243539 -351.63867)
			(xy 133.243539 -351.58413) (xy 133.251302 -351.530146) (xy 133.266668 -351.477817) (xy 133.289325 -351.428207)
			(xy 133.318812 -351.382326) (xy 133.354529 -351.341109) (xy 133.395749 -351.305396) (xy 133.441631 -351.275912)
			(xy 133.491243 -351.253258) (xy 133.543574 -351.237896) (xy 133.597558 -351.230137) (xy 133.624828 -351.229676)
			(xy 134.488428 -351.229676) (xy 134.515699 -351.230088) (xy 134.569685 -351.237854) (xy 134.622016 -351.253223)
			(xy 134.671628 -351.275883) (xy 134.71751 -351.305373) (xy 134.758728 -351.341092) (xy 134.794444 -351.382313)
			(xy 134.82393 -351.428197) (xy 134.846586 -351.47781) (xy 134.861952 -351.530143) (xy 134.869714 -351.584129)
			(xy 134.869714 -351.638666) (xy 136.352562 -351.638666) (xy 136.352562 -351.584134) (xy 136.360323 -351.530157)
			(xy 136.375686 -351.477833) (xy 136.398339 -351.428229) (xy 136.427821 -351.382353) (xy 136.463531 -351.34114)
			(xy 136.504743 -351.305428) (xy 136.550618 -351.275945) (xy 136.600222 -351.25329) (xy 136.652545 -351.237925)
			(xy 136.706522 -351.230163) (xy 136.733788 -351.229676) (xy 137.597388 -351.229676) (xy 137.624662 -351.230063)
			(xy 137.678656 -351.237824) (xy 137.730995 -351.253191) (xy 137.780615 -351.27585) (xy 137.826504 -351.30534)
			(xy 137.86773 -351.341061) (xy 137.903452 -351.382286) (xy 137.932944 -351.428175) (xy 137.955605 -351.477794)
			(xy 137.970973 -351.530132) (xy 137.978736 -351.584126) (xy 137.978736 -351.63867) (xy 139.46144 -351.63867)
			(xy 139.46144 -351.58413) (xy 139.469202 -351.530144) (xy 139.484569 -351.477812) (xy 139.507228 -351.428201)
			(xy 139.536717 -351.38232) (xy 139.572436 -351.341102) (xy 139.613658 -351.305388) (xy 139.659543 -351.275905)
			(xy 139.709158 -351.253253) (xy 139.761491 -351.237892) (xy 139.815477 -351.230136) (xy 139.842748 -351.229676)
			(xy 140.706348 -351.229676) (xy 140.733618 -351.23009) (xy 140.787602 -351.237858) (xy 140.839931 -351.253229)
			(xy 140.88954 -351.27589) (xy 140.935419 -351.30538) (xy 140.976635 -351.341099) (xy 141.012349 -351.382319)
			(xy 141.041833 -351.428203) (xy 141.064488 -351.477814) (xy 141.079852 -351.530145) (xy 141.087614 -351.58413)
			(xy 141.087614 -351.638669) (xy 142.570439 -351.638669) (xy 142.570439 -351.584131) (xy 142.578201 -351.530149)
			(xy 142.593566 -351.477821) (xy 142.616222 -351.428212) (xy 142.645707 -351.382333) (xy 142.681422 -351.341117)
			(xy 142.722639 -351.305403) (xy 142.768519 -351.275918) (xy 142.818129 -351.253263) (xy 142.870457 -351.237899)
			(xy 142.924439 -351.230139) (xy 142.951708 -351.229676) (xy 143.815308 -351.229676) (xy 143.84258 -351.230087)
			(xy 143.896568 -351.23785) (xy 143.948902 -351.253218) (xy 143.998516 -351.275877) (xy 144.0444 -351.305366)
			(xy 144.085621 -351.341085) (xy 144.121339 -351.382306) (xy 144.150827 -351.428191) (xy 144.173485 -351.477806)
			(xy 144.188851 -351.53014) (xy 144.196614 -351.584128) (xy 144.196614 -351.638669) (xy 161.804839 -351.638669)
			(xy 161.804839 -351.584131) (xy 161.812601 -351.530149) (xy 161.827966 -351.47782) (xy 161.850623 -351.428211)
			(xy 161.880108 -351.382331) (xy 161.915824 -351.341115) (xy 161.957041 -351.305401) (xy 162.002922 -351.275917)
			(xy 162.052531 -351.253262) (xy 162.10486 -351.237899) (xy 162.158843 -351.230139) (xy 162.186112 -351.229676)
			(xy 163.049712 -351.229676) (xy 163.076984 -351.230087) (xy 163.130971 -351.237851) (xy 163.183304 -351.253219)
			(xy 163.232918 -351.275878) (xy 163.278802 -351.305367) (xy 163.320022 -351.341086) (xy 163.35574 -351.382308)
			(xy 163.385228 -351.428192) (xy 163.407885 -351.477807) (xy 163.423251 -351.530141) (xy 163.431014 -351.584128)
			(xy 163.431014 -351.638665) (xy 164.913862 -351.638665) (xy 164.913862 -351.584135) (xy 164.921622 -351.530159)
			(xy 164.936985 -351.477837) (xy 164.959637 -351.428233) (xy 164.989117 -351.382358) (xy 165.024826 -351.341146)
			(xy 165.066036 -351.305434) (xy 165.111909 -351.27595) (xy 165.16151 -351.253295) (xy 165.213831 -351.237928)
			(xy 165.267807 -351.230164) (xy 165.295072 -351.229676) (xy 166.158672 -351.229676) (xy 166.185947 -351.230062)
			(xy 166.239942 -351.237821) (xy 166.292284 -351.253187) (xy 166.341905 -351.275845) (xy 166.387797 -351.305335)
			(xy 166.429024 -351.341056) (xy 166.464748 -351.382281) (xy 166.494242 -351.42817) (xy 166.516903 -351.47779)
			(xy 166.532273 -351.53013) (xy 166.540036 -351.584125) (xy 166.540036 -351.63867) (xy 168.022739 -351.63867)
			(xy 168.022739 -351.58413) (xy 168.030502 -351.530146) (xy 168.045868 -351.477816) (xy 168.068526 -351.428206)
			(xy 168.098013 -351.382325) (xy 168.133731 -351.341108) (xy 168.174951 -351.305394) (xy 168.220834 -351.27591)
			(xy 168.270446 -351.253257) (xy 168.322777 -351.237895) (xy 168.376762 -351.230137) (xy 168.404032 -351.229676)
			(xy 169.267632 -351.229676) (xy 169.294903 -351.230089) (xy 169.348888 -351.237855) (xy 169.401219 -351.253224)
			(xy 169.45083 -351.275885) (xy 169.496712 -351.305374) (xy 169.537929 -351.341093) (xy 169.573645 -351.382314)
			(xy 169.603131 -351.428198) (xy 169.625787 -351.477811) (xy 169.641152 -351.530143) (xy 169.648914 -351.584129)
			(xy 169.648914 -351.638666) (xy 171.131762 -351.638666) (xy 171.131762 -351.584134) (xy 171.139523 -351.530156)
			(xy 171.154886 -351.477832) (xy 171.17754 -351.428228) (xy 171.207022 -351.382352) (xy 171.242733 -351.341138)
			(xy 171.283945 -351.305427) (xy 171.329821 -351.275944) (xy 171.379425 -351.253289) (xy 171.431748 -351.237925)
			(xy 171.485726 -351.230163) (xy 171.512992 -351.229676) (xy 172.376592 -351.229676) (xy 172.403866 -351.230063)
			(xy 172.457859 -351.237825) (xy 172.510198 -351.253192) (xy 172.559817 -351.275851) (xy 172.605706 -351.305342)
			(xy 172.646932 -351.341063) (xy 172.682653 -351.382287) (xy 172.712145 -351.428176) (xy 172.734805 -351.477794)
			(xy 172.750173 -351.530133) (xy 172.757936 -351.584126) (xy 172.757936 -351.638664) (xy 174.240762 -351.638664)
			(xy 174.240762 -351.584136) (xy 174.248522 -351.530162) (xy 174.263883 -351.477841) (xy 174.286534 -351.428239)
			(xy 174.316012 -351.382365) (xy 174.351719 -351.341153) (xy 174.392926 -351.305441) (xy 174.438797 -351.275957)
			(xy 174.488396 -351.2533) (xy 174.540715 -351.237932) (xy 174.594688 -351.230166) (xy 174.621952 -351.229676)
			(xy 175.485552 -351.229676) (xy 175.512828 -351.23006) (xy 175.566825 -351.237818) (xy 175.619169 -351.253181)
			(xy 175.668793 -351.275838) (xy 175.714687 -351.305328) (xy 175.755917 -351.341049) (xy 175.791644 -351.382274)
			(xy 175.821139 -351.428165) (xy 175.843802 -351.477786) (xy 175.859172 -351.530128) (xy 175.866936 -351.584124)
			(xy 175.866936 -351.638669) (xy 177.349639 -351.638669) (xy 177.349639 -351.584131) (xy 177.357401 -351.530149)
			(xy 177.372766 -351.47782) (xy 177.395423 -351.428211) (xy 177.424908 -351.382331) (xy 177.460624 -351.341115)
			(xy 177.501841 -351.305401) (xy 177.547722 -351.275917) (xy 177.597331 -351.253262) (xy 177.64966 -351.237899)
			(xy 177.703643 -351.230139) (xy 177.730912 -351.229676) (xy 178.594512 -351.229676) (xy 178.621784 -351.230087)
			(xy 178.675771 -351.237851) (xy 178.728104 -351.253219) (xy 178.777718 -351.275878) (xy 178.823602 -351.305367)
			(xy 178.864822 -351.341086) (xy 178.90054 -351.382308) (xy 178.930028 -351.428192) (xy 178.952685 -351.477807)
			(xy 178.968051 -351.530141) (xy 178.975814 -351.584128) (xy 178.975814 -351.638665) (xy 180.458662 -351.638665)
			(xy 180.458662 -351.584135) (xy 180.466422 -351.530159) (xy 180.481785 -351.477837) (xy 180.504437 -351.428233)
			(xy 180.533917 -351.382358) (xy 180.569626 -351.341146) (xy 180.610836 -351.305434) (xy 180.656709 -351.27595)
			(xy 180.70631 -351.253295) (xy 180.758631 -351.237928) (xy 180.812607 -351.230164) (xy 180.839872 -351.229676)
			(xy 181.703472 -351.229676) (xy 181.730747 -351.230062) (xy 181.784742 -351.237821) (xy 181.837084 -351.253187)
			(xy 181.886705 -351.275845) (xy 181.932597 -351.305335) (xy 181.973824 -351.341056) (xy 182.009548 -351.382281)
			(xy 182.039042 -351.42817) (xy 182.061703 -351.47779) (xy 182.077073 -351.53013) (xy 182.084836 -351.584125)
			(xy 182.084836 -351.63867) (xy 183.567539 -351.63867) (xy 183.567539 -351.58413) (xy 183.575302 -351.530146)
			(xy 183.590668 -351.477816) (xy 183.613326 -351.428206) (xy 183.642813 -351.382325) (xy 183.678531 -351.341108)
			(xy 183.719751 -351.305394) (xy 183.765634 -351.27591) (xy 183.815246 -351.253257) (xy 183.867577 -351.237895)
			(xy 183.921562 -351.230137) (xy 183.948832 -351.229676) (xy 184.812432 -351.229676) (xy 184.839703 -351.230089)
			(xy 184.893688 -351.237855) (xy 184.946019 -351.253224) (xy 184.99563 -351.275885) (xy 185.041512 -351.305374)
			(xy 185.082729 -351.341093) (xy 185.118445 -351.382314) (xy 185.147931 -351.428198) (xy 185.170587 -351.477811)
			(xy 185.185952 -351.530143) (xy 185.193714 -351.584129) (xy 185.193714 -351.638666) (xy 186.676562 -351.638666)
			(xy 186.676562 -351.584134) (xy 186.684323 -351.530156) (xy 186.699686 -351.477832) (xy 186.72234 -351.428228)
			(xy 186.751822 -351.382352) (xy 186.787533 -351.341138) (xy 186.828745 -351.305427) (xy 186.874621 -351.275944)
			(xy 186.924225 -351.253289) (xy 186.976548 -351.237925) (xy 187.030526 -351.230163) (xy 187.057792 -351.229676)
			(xy 187.921392 -351.229676) (xy 187.948666 -351.230063) (xy 188.002659 -351.237825) (xy 188.054998 -351.253192)
			(xy 188.104617 -351.275851) (xy 188.150506 -351.305342) (xy 188.191732 -351.341063) (xy 188.227453 -351.382287)
			(xy 188.256945 -351.428176) (xy 188.279605 -351.477794) (xy 188.294973 -351.530133) (xy 188.302736 -351.584126)
			(xy 188.302736 -351.638664) (xy 189.785562 -351.638664) (xy 189.785562 -351.584136) (xy 189.793322 -351.530162)
			(xy 189.808683 -351.477841) (xy 189.831334 -351.428239) (xy 189.860812 -351.382365) (xy 189.896519 -351.341153)
			(xy 189.937726 -351.305441) (xy 189.983597 -351.275957) (xy 190.033196 -351.2533) (xy 190.085515 -351.237932)
			(xy 190.139488 -351.230166) (xy 190.166752 -351.229676) (xy 191.030352 -351.229676) (xy 191.057628 -351.23006)
			(xy 191.111625 -351.237818) (xy 191.163969 -351.253181) (xy 191.213593 -351.275838) (xy 191.259487 -351.305328)
			(xy 191.300717 -351.341049) (xy 191.336444 -351.382274) (xy 191.365939 -351.428165) (xy 191.388602 -351.477786)
			(xy 191.403972 -351.530128) (xy 191.411736 -351.584124) (xy 191.411736 -351.638669) (xy 192.894439 -351.638669)
			(xy 192.894439 -351.584131) (xy 192.902201 -351.530149) (xy 192.917566 -351.47782) (xy 192.940223 -351.428211)
			(xy 192.969708 -351.382331) (xy 193.005424 -351.341115) (xy 193.046641 -351.305401) (xy 193.092522 -351.275917)
			(xy 193.142131 -351.253262) (xy 193.19446 -351.237899) (xy 193.248443 -351.230139) (xy 193.275712 -351.229676)
			(xy 194.139312 -351.229676) (xy 194.166584 -351.230087) (xy 194.220571 -351.237851) (xy 194.272904 -351.253219)
			(xy 194.322518 -351.275878) (xy 194.368402 -351.305367) (xy 194.409622 -351.341086) (xy 194.44534 -351.382308)
			(xy 194.474828 -351.428192) (xy 194.497485 -351.477807) (xy 194.512851 -351.530141) (xy 194.520614 -351.584128)
			(xy 194.520614 -351.638668) (xy 267.515839 -351.638668) (xy 267.515839 -351.584132) (xy 267.523601 -351.53015)
			(xy 267.538966 -351.477822) (xy 267.561621 -351.428214) (xy 267.591106 -351.382335) (xy 267.62682 -351.341119)
			(xy 267.668036 -351.305405) (xy 267.713916 -351.27592) (xy 267.763524 -351.253265) (xy 267.815852 -351.2379)
			(xy 267.869834 -351.230139) (xy 267.897102 -351.229676) (xy 268.760702 -351.229676) (xy 268.787974 -351.230087)
			(xy 268.841963 -351.237849) (xy 268.894297 -351.253216) (xy 268.943912 -351.275875) (xy 268.989797 -351.305364)
			(xy 269.031019 -351.341083) (xy 269.066737 -351.382304) (xy 269.096226 -351.42819) (xy 269.118884 -351.477805)
			(xy 269.134251 -351.530139) (xy 269.142013 -351.584128) (xy 269.142013 -351.638665) (xy 270.624862 -351.638665)
			(xy 270.624862 -351.584135) (xy 270.632622 -351.53016) (xy 270.647984 -351.477839) (xy 270.670635 -351.428236)
			(xy 270.700115 -351.382362) (xy 270.735822 -351.341149) (xy 270.777031 -351.305437) (xy 270.822903 -351.275953)
			(xy 270.872503 -351.253297) (xy 270.924823 -351.23793) (xy 270.978797 -351.230165) (xy 271.006062 -351.229676)
			(xy 271.869662 -351.229676) (xy 271.896937 -351.230061) (xy 271.950934 -351.23782) (xy 272.003276 -351.253184)
			(xy 272.052899 -351.275842) (xy 272.098792 -351.305331) (xy 272.140021 -351.341052) (xy 272.175746 -351.382277)
			(xy 272.20524 -351.428167) (xy 272.227903 -351.477788) (xy 272.243272 -351.530129) (xy 272.251036 -351.584125)
			(xy 272.251036 -351.638669) (xy 273.733739 -351.638669) (xy 273.733739 -351.584131) (xy 273.741501 -351.530147)
			(xy 273.756867 -351.477818) (xy 273.779524 -351.428208) (xy 273.809011 -351.382328) (xy 273.844727 -351.341112)
			(xy 273.885946 -351.305398) (xy 273.931828 -351.275914) (xy 273.981439 -351.25326) (xy 274.033769 -351.237897)
			(xy 274.087753 -351.230138) (xy 274.115022 -351.229676) (xy 274.978622 -351.229676) (xy 275.005893 -351.230088)
			(xy 275.05988 -351.237853) (xy 275.112212 -351.253222) (xy 275.161824 -351.275881) (xy 275.207707 -351.305371)
			(xy 275.248926 -351.34109) (xy 275.284642 -351.382311) (xy 275.314129 -351.428195) (xy 275.336786 -351.477809)
			(xy 275.352152 -351.530142) (xy 275.359914 -351.584129) (xy 275.359914 -351.638666) (xy 276.842762 -351.638666)
			(xy 276.842762 -351.584134) (xy 276.850523 -351.530158) (xy 276.865886 -351.477835) (xy 276.888538 -351.428231)
			(xy 276.91802 -351.382355) (xy 276.953729 -351.341142) (xy 276.994941 -351.30543) (xy 277.040815 -351.275947)
			(xy 277.090418 -351.253292) (xy 277.14274 -351.237927) (xy 277.196716 -351.230164) (xy 277.223982 -351.229676)
			(xy 278.087582 -351.229676) (xy 278.114857 -351.230062) (xy 278.168851 -351.237823) (xy 278.221191 -351.253189)
			(xy 278.270811 -351.275848) (xy 278.316702 -351.305338) (xy 278.357928 -351.341059) (xy 278.393651 -351.382284)
			(xy 278.423143 -351.428173) (xy 278.445804 -351.477792) (xy 278.461173 -351.530132) (xy 278.468936 -351.584125)
			(xy 278.468936 -351.63867) (xy 279.95164 -351.63867) (xy 279.95164 -351.58413) (xy 279.959402 -351.530145)
			(xy 279.974769 -351.477814) (xy 279.997427 -351.428203) (xy 280.026916 -351.382322) (xy 280.062634 -351.341105)
			(xy 280.103855 -351.305391) (xy 280.14974 -351.275907) (xy 280.199353 -351.253254) (xy 280.251686 -351.237893)
			(xy 280.305672 -351.230137) (xy 280.332942 -351.229676) (xy 281.196542 -351.229676) (xy 281.223812 -351.230089)
			(xy 281.277797 -351.237857) (xy 281.330126 -351.253227) (xy 281.379736 -351.275888) (xy 281.425616 -351.305378)
			(xy 281.466833 -351.341097) (xy 281.502547 -351.382317) (xy 281.532032 -351.428201) (xy 281.554688 -351.477813)
			(xy 281.570052 -351.530145) (xy 281.577814 -351.58413) (xy 281.577814 -351.638668) (xy 283.060639 -351.638668)
			(xy 283.060639 -351.584132) (xy 283.068401 -351.53015) (xy 283.083766 -351.477822) (xy 283.106421 -351.428214)
			(xy 283.135906 -351.382335) (xy 283.17162 -351.341119) (xy 283.212836 -351.305405) (xy 283.258716 -351.27592)
			(xy 283.308324 -351.253265) (xy 283.360652 -351.2379) (xy 283.414634 -351.230139) (xy 283.441902 -351.229676)
			(xy 284.305502 -351.229676) (xy 284.332774 -351.230087) (xy 284.386763 -351.237849) (xy 284.439097 -351.253216)
			(xy 284.488712 -351.275875) (xy 284.534597 -351.305364) (xy 284.575819 -351.341083) (xy 284.611537 -351.382304)
			(xy 284.641026 -351.42819) (xy 284.663684 -351.477805) (xy 284.679051 -351.530139) (xy 284.686813 -351.584128)
			(xy 284.686813 -351.638665) (xy 286.169662 -351.638665) (xy 286.169662 -351.584135) (xy 286.177422 -351.53016)
			(xy 286.192784 -351.477839) (xy 286.215435 -351.428236) (xy 286.244915 -351.382362) (xy 286.280622 -351.341149)
			(xy 286.321831 -351.305437) (xy 286.367703 -351.275953) (xy 286.417303 -351.253297) (xy 286.469623 -351.23793)
			(xy 286.523597 -351.230165) (xy 286.550862 -351.229676) (xy 287.414462 -351.229676) (xy 287.441737 -351.230061)
			(xy 287.495734 -351.23782) (xy 287.548076 -351.253184) (xy 287.597699 -351.275842) (xy 287.643592 -351.305331)
			(xy 287.684821 -351.341052) (xy 287.720546 -351.382277) (xy 287.75004 -351.428167) (xy 287.772703 -351.477788)
			(xy 287.788072 -351.530129) (xy 287.795836 -351.584125) (xy 287.795836 -351.638669) (xy 289.278539 -351.638669)
			(xy 289.278539 -351.584131) (xy 289.286301 -351.530147) (xy 289.301667 -351.477818) (xy 289.324324 -351.428208)
			(xy 289.353811 -351.382328) (xy 289.389527 -351.341112) (xy 289.430746 -351.305398) (xy 289.476628 -351.275914)
			(xy 289.526239 -351.25326) (xy 289.578569 -351.237897) (xy 289.632553 -351.230138) (xy 289.659822 -351.229676)
			(xy 290.523422 -351.229676) (xy 290.550693 -351.230088) (xy 290.60468 -351.237853) (xy 290.657012 -351.253222)
			(xy 290.706624 -351.275881) (xy 290.752507 -351.305371) (xy 290.793726 -351.34109) (xy 290.829442 -351.382311)
			(xy 290.858929 -351.428195) (xy 290.881586 -351.477809) (xy 290.896952 -351.530142) (xy 290.904714 -351.584129)
			(xy 290.904714 -351.638666) (xy 292.387562 -351.638666) (xy 292.387562 -351.584134) (xy 292.395323 -351.530158)
			(xy 292.410686 -351.477835) (xy 292.433338 -351.428231) (xy 292.46282 -351.382355) (xy 292.498529 -351.341142)
			(xy 292.539741 -351.30543) (xy 292.585615 -351.275947) (xy 292.635218 -351.253292) (xy 292.68754 -351.237927)
			(xy 292.741516 -351.230164) (xy 292.768782 -351.229676) (xy 293.632382 -351.229676) (xy 293.659657 -351.230062)
			(xy 293.713651 -351.237823) (xy 293.765991 -351.253189) (xy 293.815611 -351.275848) (xy 293.861502 -351.305338)
			(xy 293.902728 -351.341059) (xy 293.938451 -351.382284) (xy 293.967943 -351.428173) (xy 293.990604 -351.477792)
			(xy 294.005973 -351.530132) (xy 294.013736 -351.584125) (xy 294.013736 -351.63867) (xy 295.49644 -351.63867)
			(xy 295.49644 -351.58413) (xy 295.504202 -351.530145) (xy 295.519569 -351.477814) (xy 295.542227 -351.428203)
			(xy 295.571716 -351.382322) (xy 295.607434 -351.341105) (xy 295.648655 -351.305391) (xy 295.69454 -351.275907)
			(xy 295.744153 -351.253254) (xy 295.796486 -351.237893) (xy 295.850472 -351.230137) (xy 295.877742 -351.229676)
			(xy 296.741342 -351.229676) (xy 296.768612 -351.230089) (xy 296.822597 -351.237857) (xy 296.874926 -351.253227)
			(xy 296.924536 -351.275888) (xy 296.970416 -351.305378) (xy 297.011633 -351.341097) (xy 297.047347 -351.382317)
			(xy 297.076832 -351.428201) (xy 297.099488 -351.477813) (xy 297.114852 -351.530145) (xy 297.122614 -351.58413)
			(xy 297.122614 -351.638668) (xy 298.605439 -351.638668) (xy 298.605439 -351.584132) (xy 298.613201 -351.53015)
			(xy 298.628566 -351.477822) (xy 298.651221 -351.428214) (xy 298.680706 -351.382335) (xy 298.71642 -351.341119)
			(xy 298.757636 -351.305405) (xy 298.803516 -351.27592) (xy 298.853124 -351.253265) (xy 298.905452 -351.2379)
			(xy 298.959434 -351.230139) (xy 298.986702 -351.229676) (xy 299.850302 -351.229676) (xy 299.877574 -351.230087)
			(xy 299.931563 -351.237849) (xy 299.983897 -351.253216) (xy 300.033512 -351.275875) (xy 300.079397 -351.305364)
			(xy 300.120619 -351.341083) (xy 300.156337 -351.382304) (xy 300.185826 -351.42819) (xy 300.208484 -351.477805)
			(xy 300.223851 -351.530139) (xy 300.231613 -351.584128) (xy 300.231613 -351.638668) (xy 312.121539 -351.638668)
			(xy 312.121539 -351.584132) (xy 312.129301 -351.53015) (xy 312.144666 -351.477822) (xy 312.167321 -351.428213)
			(xy 312.196807 -351.382334) (xy 312.232521 -351.341118) (xy 312.273737 -351.305404) (xy 312.319617 -351.27592)
			(xy 312.369226 -351.253264) (xy 312.421554 -351.2379) (xy 312.475536 -351.230139) (xy 312.502804 -351.229676)
			(xy 313.366404 -351.229676) (xy 313.393676 -351.230087) (xy 313.447664 -351.23785) (xy 313.499999 -351.253217)
			(xy 313.549613 -351.275876) (xy 313.595498 -351.305365) (xy 313.63672 -351.341083) (xy 313.672438 -351.382305)
			(xy 313.701926 -351.42819) (xy 313.724584 -351.477805) (xy 313.739951 -351.530139) (xy 313.747713 -351.584128)
			(xy 313.747713 -351.638665) (xy 315.230562 -351.638665) (xy 315.230562 -351.584135) (xy 315.238322 -351.53016)
			(xy 315.253684 -351.477838) (xy 315.276335 -351.428236) (xy 315.305815 -351.382361) (xy 315.341523 -351.341148)
			(xy 315.382732 -351.305437) (xy 315.428604 -351.275953) (xy 315.478205 -351.253297) (xy 315.530525 -351.23793)
			(xy 315.584499 -351.230165) (xy 315.611764 -351.229676) (xy 316.475364 -351.229676) (xy 316.502639 -351.230061)
			(xy 316.556636 -351.23782) (xy 316.608978 -351.253185) (xy 316.6586 -351.275842) (xy 316.704493 -351.305332)
			(xy 316.745722 -351.341053) (xy 316.781446 -351.382278) (xy 316.81094 -351.428168) (xy 316.833603 -351.477788)
			(xy 316.848972 -351.530129) (xy 316.856736 -351.584125) (xy 316.856736 -351.638669) (xy 318.339439 -351.638669)
			(xy 318.339439 -351.584131) (xy 318.347201 -351.530147) (xy 318.362567 -351.477818) (xy 318.385224 -351.428208)
			(xy 318.414711 -351.382328) (xy 318.450428 -351.341111) (xy 318.491647 -351.305397) (xy 318.537529 -351.275913)
			(xy 318.58714 -351.253259) (xy 318.63947 -351.237896) (xy 318.693455 -351.230138) (xy 318.720724 -351.229676)
			(xy 319.584324 -351.229676) (xy 319.611595 -351.230088) (xy 319.665581 -351.237853) (xy 319.717913 -351.253222)
			(xy 319.767525 -351.275882) (xy 319.813408 -351.305372) (xy 319.854627 -351.34109) (xy 319.890343 -351.382312)
			(xy 319.919829 -351.428196) (xy 319.942486 -351.477809) (xy 319.957852 -351.530142) (xy 319.965614 -351.584129)
			(xy 319.965614 -351.638666) (xy 321.448462 -351.638666) (xy 321.448462 -351.584134) (xy 321.456223 -351.530157)
			(xy 321.471586 -351.477834) (xy 321.494239 -351.42823) (xy 321.52372 -351.382354) (xy 321.55943 -351.341141)
			(xy 321.600642 -351.30543) (xy 321.646516 -351.275946) (xy 321.696119 -351.253291) (xy 321.748442 -351.237926)
			(xy 321.802418 -351.230163) (xy 321.829684 -351.229676) (xy 322.693284 -351.229676) (xy 322.720558 -351.230062)
			(xy 322.774552 -351.237824) (xy 322.826892 -351.25319) (xy 322.876512 -351.275849) (xy 322.922403 -351.305339)
			(xy 322.963629 -351.34106) (xy 322.999351 -351.382285) (xy 323.028843 -351.428174) (xy 323.051504 -351.477793)
			(xy 323.066873 -351.530132) (xy 323.074636 -351.584126) (xy 323.074636 -351.63867) (xy 324.55734 -351.63867)
			(xy 324.55734 -351.58413) (xy 324.565102 -351.530144) (xy 324.580469 -351.477813) (xy 324.603128 -351.428202)
			(xy 324.632616 -351.382321) (xy 324.668335 -351.341104) (xy 324.709556 -351.30539) (xy 324.755441 -351.275906)
			(xy 324.805055 -351.253254) (xy 324.857387 -351.237893) (xy 324.911374 -351.230136) (xy 324.938644 -351.229676)
			(xy 325.802244 -351.229676) (xy 325.829514 -351.23009) (xy 325.883498 -351.237857) (xy 325.935828 -351.253228)
			(xy 325.985437 -351.275889) (xy 326.031317 -351.305379) (xy 326.072534 -351.341097) (xy 326.108248 -351.382318)
			(xy 326.137732 -351.428201) (xy 326.160388 -351.477814) (xy 326.175752 -351.530145) (xy 326.183514 -351.58413)
			(xy 326.183514 -351.638668) (xy 327.666339 -351.638668) (xy 327.666339 -351.584132) (xy 327.674101 -351.53015)
			(xy 327.689466 -351.477822) (xy 327.712121 -351.428213) (xy 327.741607 -351.382334) (xy 327.777321 -351.341118)
			(xy 327.818537 -351.305404) (xy 327.864417 -351.27592) (xy 327.914026 -351.253264) (xy 327.966354 -351.2379)
			(xy 328.020336 -351.230139) (xy 328.047604 -351.229676) (xy 328.911204 -351.229676) (xy 328.938476 -351.230087)
			(xy 328.992464 -351.23785) (xy 329.044799 -351.253217) (xy 329.094413 -351.275876) (xy 329.140298 -351.305365)
			(xy 329.18152 -351.341083) (xy 329.217238 -351.382305) (xy 329.246726 -351.42819) (xy 329.269384 -351.477805)
			(xy 329.284751 -351.530139) (xy 329.292513 -351.584128) (xy 329.292513 -351.638665) (xy 330.775362 -351.638665)
			(xy 330.775362 -351.584135) (xy 330.783122 -351.53016) (xy 330.798484 -351.477838) (xy 330.821135 -351.428236)
			(xy 330.850615 -351.382361) (xy 330.886323 -351.341148) (xy 330.927532 -351.305437) (xy 330.973404 -351.275953)
			(xy 331.023005 -351.253297) (xy 331.075325 -351.23793) (xy 331.129299 -351.230165) (xy 331.156564 -351.229676)
			(xy 332.020164 -351.229676) (xy 332.047439 -351.230061) (xy 332.101436 -351.23782) (xy 332.153778 -351.253185)
			(xy 332.2034 -351.275842) (xy 332.249293 -351.305332) (xy 332.290522 -351.341053) (xy 332.326246 -351.382278)
			(xy 332.35574 -351.428168) (xy 332.378403 -351.477788) (xy 332.393772 -351.530129) (xy 332.401536 -351.584125)
			(xy 332.401536 -351.638669) (xy 333.884239 -351.638669) (xy 333.884239 -351.584131) (xy 333.892001 -351.530147)
			(xy 333.907367 -351.477818) (xy 333.930024 -351.428208) (xy 333.959511 -351.382328) (xy 333.995228 -351.341111)
			(xy 334.036447 -351.305397) (xy 334.082329 -351.275913) (xy 334.13194 -351.253259) (xy 334.18427 -351.237896)
			(xy 334.238255 -351.230138) (xy 334.265524 -351.229676) (xy 335.129124 -351.229676) (xy 335.156395 -351.230088)
			(xy 335.210381 -351.237853) (xy 335.262713 -351.253222) (xy 335.312325 -351.275882) (xy 335.358208 -351.305372)
			(xy 335.399427 -351.34109) (xy 335.435143 -351.382312) (xy 335.464629 -351.428196) (xy 335.487286 -351.477809)
			(xy 335.502652 -351.530142) (xy 335.510414 -351.584129) (xy 335.510414 -351.638666) (xy 336.993262 -351.638666)
			(xy 336.993262 -351.584134) (xy 337.001023 -351.530157) (xy 337.016386 -351.477834) (xy 337.039039 -351.42823)
			(xy 337.06852 -351.382354) (xy 337.10423 -351.341141) (xy 337.145442 -351.30543) (xy 337.191316 -351.275946)
			(xy 337.240919 -351.253291) (xy 337.293242 -351.237926) (xy 337.347218 -351.230163) (xy 337.374484 -351.229676)
			(xy 338.238084 -351.229676) (xy 338.265358 -351.230062) (xy 338.319352 -351.237824) (xy 338.371692 -351.25319)
			(xy 338.421312 -351.275849) (xy 338.467203 -351.305339) (xy 338.508429 -351.34106) (xy 338.544151 -351.382285)
			(xy 338.573643 -351.428174) (xy 338.596304 -351.477793) (xy 338.611673 -351.530132) (xy 338.619436 -351.584126)
			(xy 338.619436 -351.63867) (xy 340.10214 -351.63867) (xy 340.10214 -351.58413) (xy 340.109902 -351.530144)
			(xy 340.125269 -351.477813) (xy 340.147928 -351.428202) (xy 340.177416 -351.382321) (xy 340.213135 -351.341104)
			(xy 340.254356 -351.30539) (xy 340.300241 -351.275906) (xy 340.349855 -351.253254) (xy 340.402187 -351.237893)
			(xy 340.456174 -351.230136) (xy 340.483444 -351.229676) (xy 341.347044 -351.229676) (xy 341.374314 -351.23009)
			(xy 341.428298 -351.237857) (xy 341.480628 -351.253228) (xy 341.530237 -351.275889) (xy 341.576117 -351.305379)
			(xy 341.617334 -351.341097) (xy 341.653048 -351.382318) (xy 341.682532 -351.428201) (xy 341.705188 -351.477814)
			(xy 341.720552 -351.530145) (xy 341.728314 -351.58413) (xy 341.728314 -351.638668) (xy 343.211139 -351.638668)
			(xy 343.211139 -351.584132) (xy 343.218901 -351.53015) (xy 343.234266 -351.477822) (xy 343.256921 -351.428213)
			(xy 343.286407 -351.382334) (xy 343.322121 -351.341118) (xy 343.363337 -351.305404) (xy 343.409217 -351.27592)
			(xy 343.458826 -351.253264) (xy 343.511154 -351.2379) (xy 343.565136 -351.230139) (xy 343.592404 -351.229676)
			(xy 344.456004 -351.229676) (xy 344.483276 -351.230087) (xy 344.537264 -351.23785) (xy 344.589599 -351.253217)
			(xy 344.639213 -351.275876) (xy 344.685098 -351.305365) (xy 344.72632 -351.341083) (xy 344.762038 -351.382305)
			(xy 344.791526 -351.42819) (xy 344.814184 -351.477805) (xy 344.829551 -351.530139) (xy 344.837313 -351.584128)
			(xy 344.837313 -351.638666) (xy 370.806762 -351.638666) (xy 370.806762 -351.584134) (xy 370.814523 -351.530158)
			(xy 370.829885 -351.477835) (xy 370.852538 -351.428231) (xy 370.882019 -351.382356) (xy 370.917729 -351.341143)
			(xy 370.95894 -351.305431) (xy 371.004814 -351.275948) (xy 371.054416 -351.253292) (xy 371.106738 -351.237927)
			(xy 371.160714 -351.230164) (xy 371.18798 -351.229676) (xy 372.05158 -351.229676) (xy 372.078855 -351.230062)
			(xy 372.132849 -351.237823) (xy 372.185189 -351.253189) (xy 372.23481 -351.275848) (xy 372.280701 -351.305338)
			(xy 372.321927 -351.341059) (xy 372.35765 -351.382283) (xy 372.387143 -351.428172) (xy 372.409804 -351.477792)
			(xy 372.425173 -351.530131) (xy 372.432936 -351.584125) (xy 372.432936 -351.63867) (xy 373.91564 -351.63867)
			(xy 373.91564 -351.58413) (xy 373.923402 -351.530145) (xy 373.938769 -351.477814) (xy 373.961427 -351.428203)
			(xy 373.990915 -351.382322) (xy 374.026634 -351.341105) (xy 374.067854 -351.305391) (xy 374.113738 -351.275908)
			(xy 374.163352 -351.253255) (xy 374.215684 -351.237893) (xy 374.26967 -351.230137) (xy 374.29694 -351.229676)
			(xy 375.16054 -351.229676) (xy 375.18781 -351.230089) (xy 375.241795 -351.237856) (xy 375.294125 -351.253227)
			(xy 375.343735 -351.275887) (xy 375.389615 -351.305377) (xy 375.430832 -351.341096) (xy 375.466547 -351.382317)
			(xy 375.496032 -351.4282) (xy 375.518687 -351.477813) (xy 375.534052 -351.530144) (xy 375.541814 -351.58413)
			(xy 375.541814 -351.638667) (xy 377.024662 -351.638667) (xy 377.024662 -351.584133) (xy 377.032423 -351.530155)
			(xy 377.047787 -351.477831) (xy 377.070441 -351.428226) (xy 377.099924 -351.382349) (xy 377.135636 -351.341136)
			(xy 377.176849 -351.305424) (xy 377.222726 -351.275941) (xy 377.272331 -351.253287) (xy 377.324655 -351.237923)
			(xy 377.378633 -351.230162) (xy 377.4059 -351.229676) (xy 378.2695 -351.229676) (xy 378.296772 -351.230087)
			(xy 378.350761 -351.237849) (xy 378.403096 -351.253216) (xy 378.452711 -351.275874) (xy 378.498596 -351.305363)
			(xy 378.539818 -351.341082) (xy 378.575537 -351.382304) (xy 378.605026 -351.428189) (xy 378.627684 -351.477804)
			(xy 378.643051 -351.530139) (xy 378.650813 -351.584128) (xy 378.650813 -351.638665) (xy 380.133662 -351.638665)
			(xy 380.133662 -351.584135) (xy 380.141422 -351.53016) (xy 380.156784 -351.477839) (xy 380.179435 -351.428237)
			(xy 380.208914 -351.382362) (xy 380.244621 -351.34115) (xy 380.28583 -351.305438) (xy 380.331702 -351.275954)
			(xy 380.381302 -351.253298) (xy 380.433621 -351.237931) (xy 380.487595 -351.230165) (xy 380.51486 -351.229676)
			(xy 381.37846 -351.229676) (xy 381.405736 -351.230061) (xy 381.459732 -351.237819) (xy 381.512075 -351.253183)
			(xy 381.561698 -351.275841) (xy 381.607591 -351.30533) (xy 381.64882 -351.341051) (xy 381.684546 -351.382277)
			(xy 381.71404 -351.428167) (xy 381.736703 -351.477788) (xy 381.752072 -351.530129) (xy 381.759836 -351.584124)
			(xy 381.759836 -351.638669) (xy 383.242539 -351.638669) (xy 383.242539 -351.584131) (xy 383.250301 -351.530148)
			(xy 383.265667 -351.477818) (xy 383.288324 -351.428209) (xy 383.31781 -351.382329) (xy 383.353526 -351.341112)
			(xy 383.394745 -351.305398) (xy 383.440626 -351.275914) (xy 383.490237 -351.25326) (xy 383.542567 -351.237897)
			(xy 383.596551 -351.230138) (xy 383.62382 -351.229676) (xy 384.48742 -351.229676) (xy 384.514691 -351.230088)
			(xy 384.568678 -351.237853) (xy 384.62101 -351.253221) (xy 384.670623 -351.275881) (xy 384.716506 -351.30537)
			(xy 384.757725 -351.341089) (xy 384.793442 -351.38231) (xy 384.822929 -351.428195) (xy 384.845586 -351.477808)
			(xy 384.860952 -351.530142) (xy 384.868714 -351.584129) (xy 384.868714 -351.638666) (xy 386.351562 -351.638666)
			(xy 386.351562 -351.584134) (xy 386.359323 -351.530158) (xy 386.374685 -351.477835) (xy 386.397338 -351.428231)
			(xy 386.426819 -351.382356) (xy 386.462529 -351.341143) (xy 386.50374 -351.305431) (xy 386.549614 -351.275948)
			(xy 386.599216 -351.253292) (xy 386.651538 -351.237927) (xy 386.705514 -351.230164) (xy 386.73278 -351.229676)
			(xy 387.59638 -351.229676) (xy 387.623655 -351.230062) (xy 387.677649 -351.237823) (xy 387.729989 -351.253189)
			(xy 387.77961 -351.275848) (xy 387.825501 -351.305338) (xy 387.866727 -351.341059) (xy 387.90245 -351.382283)
			(xy 387.931943 -351.428172) (xy 387.954604 -351.477792) (xy 387.969973 -351.530131) (xy 387.977736 -351.584125)
			(xy 387.977736 -351.63867) (xy 389.46044 -351.63867) (xy 389.46044 -351.58413) (xy 389.468202 -351.530145)
			(xy 389.483569 -351.477814) (xy 389.506227 -351.428203) (xy 389.535715 -351.382322) (xy 389.571434 -351.341105)
			(xy 389.612654 -351.305391) (xy 389.658538 -351.275908) (xy 389.708152 -351.253255) (xy 389.760484 -351.237893)
			(xy 389.81447 -351.230137) (xy 389.84174 -351.229676) (xy 390.70534 -351.229676) (xy 390.73261 -351.230089)
			(xy 390.786595 -351.237856) (xy 390.838925 -351.253227) (xy 390.888535 -351.275887) (xy 390.934415 -351.305377)
			(xy 390.975632 -351.341096) (xy 391.011347 -351.382317) (xy 391.040832 -351.4282) (xy 391.063487 -351.477813)
			(xy 391.078852 -351.530144) (xy 391.086614 -351.58413) (xy 391.086614 -351.638667) (xy 392.569462 -351.638667)
			(xy 392.569462 -351.584133) (xy 392.577223 -351.530155) (xy 392.592587 -351.477831) (xy 392.615241 -351.428226)
			(xy 392.644724 -351.382349) (xy 392.680436 -351.341136) (xy 392.721649 -351.305424) (xy 392.767526 -351.275941)
			(xy 392.817131 -351.253287) (xy 392.869455 -351.237923) (xy 392.923433 -351.230162) (xy 392.9507 -351.229676)
			(xy 393.8143 -351.229676) (xy 393.841572 -351.230087) (xy 393.895561 -351.237849) (xy 393.947896 -351.253216)
			(xy 393.997511 -351.275874) (xy 394.043396 -351.305363) (xy 394.084618 -351.341082) (xy 394.120337 -351.382304)
			(xy 394.149826 -351.428189) (xy 394.172484 -351.477804) (xy 394.187851 -351.530139) (xy 394.195613 -351.584128)
			(xy 394.195613 -351.638665) (xy 395.678462 -351.638665) (xy 395.678462 -351.584135) (xy 395.686222 -351.53016)
			(xy 395.701584 -351.477839) (xy 395.724235 -351.428237) (xy 395.753714 -351.382362) (xy 395.789421 -351.34115)
			(xy 395.83063 -351.305438) (xy 395.876502 -351.275954) (xy 395.926102 -351.253298) (xy 395.978421 -351.237931)
			(xy 396.032395 -351.230165) (xy 396.05966 -351.229676) (xy 396.92326 -351.229676) (xy 396.950536 -351.230061)
			(xy 397.004532 -351.237819) (xy 397.056875 -351.253183) (xy 397.106498 -351.275841) (xy 397.152391 -351.30533)
			(xy 397.19362 -351.341051) (xy 397.229346 -351.382277) (xy 397.25884 -351.428167) (xy 397.281503 -351.477788)
			(xy 397.296872 -351.530129) (xy 397.304636 -351.584124) (xy 397.304636 -351.638669) (xy 398.787339 -351.638669)
			(xy 398.787339 -351.584131) (xy 398.795101 -351.530148) (xy 398.810467 -351.477818) (xy 398.833124 -351.428209)
			(xy 398.86261 -351.382329) (xy 398.898326 -351.341112) (xy 398.939545 -351.305398) (xy 398.985426 -351.275914)
			(xy 399.035037 -351.25326) (xy 399.087367 -351.237897) (xy 399.141351 -351.230138) (xy 399.16862 -351.229676)
			(xy 400.03222 -351.229676) (xy 400.059491 -351.230088) (xy 400.113478 -351.237853) (xy 400.16581 -351.253221)
			(xy 400.215423 -351.275881) (xy 400.261306 -351.30537) (xy 400.302525 -351.341089) (xy 400.338242 -351.38231)
			(xy 400.367729 -351.428195) (xy 400.390386 -351.477808) (xy 400.405752 -351.530142) (xy 400.413514 -351.584129)
			(xy 400.413514 -351.638666) (xy 401.896362 -351.638666) (xy 401.896362 -351.584134) (xy 401.904123 -351.530158)
			(xy 401.919485 -351.477835) (xy 401.942138 -351.428231) (xy 401.971619 -351.382356) (xy 402.007329 -351.341143)
			(xy 402.04854 -351.305431) (xy 402.094414 -351.275948) (xy 402.144016 -351.253292) (xy 402.196338 -351.237927)
			(xy 402.250314 -351.230164) (xy 402.27758 -351.229676) (xy 403.14118 -351.229676) (xy 403.168455 -351.230062)
			(xy 403.222449 -351.237823) (xy 403.274789 -351.253189) (xy 403.32441 -351.275848) (xy 403.370301 -351.305338)
			(xy 403.411527 -351.341059) (xy 403.44725 -351.382283) (xy 403.476743 -351.428172) (xy 403.499404 -351.477792)
			(xy 403.514773 -351.530131) (xy 403.522536 -351.584125) (xy 403.522536 -351.638666) (xy 408.913862 -351.638666)
			(xy 408.913862 -351.584134) (xy 408.921623 -351.530156) (xy 408.936986 -351.477832) (xy 408.95964 -351.428228)
			(xy 408.989122 -351.382352) (xy 409.024833 -351.341138) (xy 409.066045 -351.305427) (xy 409.111921 -351.275944)
			(xy 409.161525 -351.253289) (xy 409.213848 -351.237925) (xy 409.267826 -351.230163) (xy 409.295092 -351.229676)
			(xy 410.158692 -351.229676) (xy 410.185966 -351.230063) (xy 410.239959 -351.237825) (xy 410.292298 -351.253192)
			(xy 410.341917 -351.275851) (xy 410.387806 -351.305342) (xy 410.429032 -351.341063) (xy 410.464753 -351.382287)
			(xy 410.494245 -351.428176) (xy 410.516905 -351.477794) (xy 410.532273 -351.530133) (xy 410.540036 -351.584126)
			(xy 410.540036 -351.638664) (xy 412.022862 -351.638664) (xy 412.022862 -351.584136) (xy 412.030622 -351.530162)
			(xy 412.045983 -351.477841) (xy 412.068634 -351.428239) (xy 412.098112 -351.382365) (xy 412.133819 -351.341153)
			(xy 412.175026 -351.305441) (xy 412.220897 -351.275957) (xy 412.270496 -351.2533) (xy 412.322815 -351.237932)
			(xy 412.376788 -351.230166) (xy 412.404052 -351.229676) (xy 413.267652 -351.229676) (xy 413.294928 -351.23006)
			(xy 413.348925 -351.237818) (xy 413.401269 -351.253181) (xy 413.450893 -351.275838) (xy 413.496787 -351.305328)
			(xy 413.538017 -351.341049) (xy 413.573744 -351.382274) (xy 413.603239 -351.428165) (xy 413.625902 -351.477786)
			(xy 413.641272 -351.530128) (xy 413.649036 -351.584124) (xy 413.649036 -351.638669) (xy 415.131739 -351.638669)
			(xy 415.131739 -351.584131) (xy 415.139501 -351.530149) (xy 415.154866 -351.47782) (xy 415.177523 -351.428211)
			(xy 415.207008 -351.382331) (xy 415.242724 -351.341115) (xy 415.283941 -351.305401) (xy 415.329822 -351.275917)
			(xy 415.379431 -351.253262) (xy 415.43176 -351.237899) (xy 415.485743 -351.230139) (xy 415.513012 -351.229676)
			(xy 416.376612 -351.229676) (xy 416.403884 -351.230087) (xy 416.457871 -351.237851) (xy 416.510204 -351.253219)
			(xy 416.559818 -351.275878) (xy 416.605702 -351.305367) (xy 416.646922 -351.341086) (xy 416.68264 -351.382308)
			(xy 416.712128 -351.428192) (xy 416.734785 -351.477807) (xy 416.750151 -351.530141) (xy 416.757914 -351.584128)
			(xy 416.757914 -351.638665) (xy 418.240762 -351.638665) (xy 418.240762 -351.584135) (xy 418.248522 -351.530159)
			(xy 418.263885 -351.477837) (xy 418.286537 -351.428233) (xy 418.316017 -351.382358) (xy 418.351726 -351.341146)
			(xy 418.392936 -351.305434) (xy 418.438809 -351.27595) (xy 418.48841 -351.253295) (xy 418.540731 -351.237928)
			(xy 418.594707 -351.230164) (xy 418.621972 -351.229676) (xy 419.485572 -351.229676) (xy 419.512847 -351.230062)
			(xy 419.566842 -351.237821) (xy 419.619184 -351.253187) (xy 419.668805 -351.275845) (xy 419.714697 -351.305335)
			(xy 419.755924 -351.341056) (xy 419.791648 -351.382281) (xy 419.821142 -351.42817) (xy 419.843803 -351.47779)
			(xy 419.859173 -351.53013) (xy 419.866936 -351.584125) (xy 419.866936 -351.63867) (xy 421.349639 -351.63867)
			(xy 421.349639 -351.58413) (xy 421.357402 -351.530146) (xy 421.372768 -351.477816) (xy 421.395426 -351.428206)
			(xy 421.424913 -351.382325) (xy 421.460631 -351.341108) (xy 421.501851 -351.305394) (xy 421.547734 -351.27591)
			(xy 421.597346 -351.253257) (xy 421.649677 -351.237895) (xy 421.703662 -351.230137) (xy 421.730932 -351.229676)
			(xy 422.594532 -351.229676) (xy 422.621803 -351.230089) (xy 422.675788 -351.237855) (xy 422.728119 -351.253224)
			(xy 422.77773 -351.275885) (xy 422.823612 -351.305374) (xy 422.864829 -351.341093) (xy 422.900545 -351.382314)
			(xy 422.930031 -351.428198) (xy 422.952687 -351.477811) (xy 422.968052 -351.530143) (xy 422.975814 -351.584129)
			(xy 422.975814 -351.638666) (xy 424.458662 -351.638666) (xy 424.458662 -351.584134) (xy 424.466423 -351.530156)
			(xy 424.481786 -351.477832) (xy 424.50444 -351.428228) (xy 424.533922 -351.382352) (xy 424.569633 -351.341138)
			(xy 424.610845 -351.305427) (xy 424.656721 -351.275944) (xy 424.706325 -351.253289) (xy 424.758648 -351.237925)
			(xy 424.812626 -351.230163) (xy 424.839892 -351.229676) (xy 425.703492 -351.229676) (xy 425.730766 -351.230063)
			(xy 425.784759 -351.237825) (xy 425.837098 -351.253192) (xy 425.886717 -351.275851) (xy 425.932606 -351.305342)
			(xy 425.973832 -351.341063) (xy 426.009553 -351.382287) (xy 426.039045 -351.428176) (xy 426.061705 -351.477794)
			(xy 426.077073 -351.530133) (xy 426.084836 -351.584126) (xy 426.084836 -351.638664) (xy 427.567662 -351.638664)
			(xy 427.567662 -351.584136) (xy 427.575422 -351.530162) (xy 427.590783 -351.477841) (xy 427.613434 -351.428239)
			(xy 427.642912 -351.382365) (xy 427.678619 -351.341153) (xy 427.719826 -351.305441) (xy 427.765697 -351.275957)
			(xy 427.815296 -351.2533) (xy 427.867615 -351.237932) (xy 427.921588 -351.230166) (xy 427.948852 -351.229676)
			(xy 428.812452 -351.229676) (xy 428.839728 -351.23006) (xy 428.893725 -351.237818) (xy 428.946069 -351.253181)
			(xy 428.995693 -351.275838) (xy 429.041587 -351.305328) (xy 429.082817 -351.341049) (xy 429.118544 -351.382274)
			(xy 429.148039 -351.428165) (xy 429.170702 -351.477786) (xy 429.186072 -351.530128) (xy 429.193836 -351.584124)
			(xy 429.193836 -351.638669) (xy 430.676539 -351.638669) (xy 430.676539 -351.584131) (xy 430.684301 -351.530149)
			(xy 430.699666 -351.47782) (xy 430.722323 -351.428211) (xy 430.751808 -351.382331) (xy 430.787524 -351.341115)
			(xy 430.828741 -351.305401) (xy 430.874622 -351.275917) (xy 430.924231 -351.253262) (xy 430.97656 -351.237899)
			(xy 431.030543 -351.230139) (xy 431.057812 -351.229676) (xy 431.921412 -351.229676) (xy 431.948684 -351.230087)
			(xy 432.002671 -351.237851) (xy 432.055004 -351.253219) (xy 432.104618 -351.275878) (xy 432.150502 -351.305367)
			(xy 432.191722 -351.341086) (xy 432.22744 -351.382308) (xy 432.256928 -351.428192) (xy 432.279585 -351.477807)
			(xy 432.294951 -351.530141) (xy 432.302714 -351.584128) (xy 432.302714 -351.638665) (xy 433.785562 -351.638665)
			(xy 433.785562 -351.584135) (xy 433.793322 -351.530159) (xy 433.808685 -351.477837) (xy 433.831337 -351.428233)
			(xy 433.860817 -351.382358) (xy 433.896526 -351.341146) (xy 433.937736 -351.305434) (xy 433.983609 -351.27595)
			(xy 434.03321 -351.253295) (xy 434.085531 -351.237928) (xy 434.139507 -351.230164) (xy 434.166772 -351.229676)
			(xy 435.030372 -351.229676) (xy 435.057647 -351.230062) (xy 435.111642 -351.237821) (xy 435.163984 -351.253187)
			(xy 435.213605 -351.275845) (xy 435.259497 -351.305335) (xy 435.300724 -351.341056) (xy 435.336448 -351.382281)
			(xy 435.365942 -351.42817) (xy 435.388603 -351.47779) (xy 435.403973 -351.53013) (xy 435.411736 -351.584125)
			(xy 435.411736 -351.63867) (xy 436.894439 -351.63867) (xy 436.894439 -351.58413) (xy 436.902202 -351.530146)
			(xy 436.917568 -351.477816) (xy 436.940226 -351.428206) (xy 436.969713 -351.382325) (xy 437.005431 -351.341108)
			(xy 437.046651 -351.305394) (xy 437.092534 -351.27591) (xy 437.142146 -351.253257) (xy 437.194477 -351.237895)
			(xy 437.248462 -351.230137) (xy 437.275732 -351.229676) (xy 438.139332 -351.229676) (xy 438.166603 -351.230089)
			(xy 438.220588 -351.237855) (xy 438.272919 -351.253224) (xy 438.32253 -351.275885) (xy 438.368412 -351.305374)
			(xy 438.409629 -351.341093) (xy 438.445345 -351.382314) (xy 438.474831 -351.428198) (xy 438.497487 -351.477811)
			(xy 438.512852 -351.530143) (xy 438.520614 -351.584129) (xy 438.520614 -351.638666) (xy 440.003462 -351.638666)
			(xy 440.003462 -351.584134) (xy 440.011223 -351.530156) (xy 440.026586 -351.477832) (xy 440.04924 -351.428228)
			(xy 440.078722 -351.382352) (xy 440.114433 -351.341138) (xy 440.155645 -351.305427) (xy 440.201521 -351.275944)
			(xy 440.251125 -351.253289) (xy 440.303448 -351.237925) (xy 440.357426 -351.230163) (xy 440.384692 -351.229676)
			(xy 441.248292 -351.229676) (xy 441.275566 -351.230063) (xy 441.329559 -351.237825) (xy 441.381898 -351.253192)
			(xy 441.431517 -351.275851) (xy 441.477406 -351.305342) (xy 441.518632 -351.341063) (xy 441.554353 -351.382287)
			(xy 441.583845 -351.428176) (xy 441.606505 -351.477794) (xy 441.621873 -351.530133) (xy 441.629636 -351.584126)
			(xy 441.629636 -351.638674) (xy 441.621873 -351.692667) (xy 441.606505 -351.745006) (xy 441.583845 -351.794624)
			(xy 441.554353 -351.840513) (xy 441.518632 -351.881737) (xy 441.477406 -351.917458) (xy 441.431517 -351.946949)
			(xy 441.381898 -351.969608) (xy 441.329559 -351.984975) (xy 441.275566 -351.992737) (xy 441.248292 -351.9932)
			(xy 440.384692 -351.9932) (xy 440.357426 -351.992637) (xy 440.303448 -351.984875) (xy 440.251125 -351.969511)
			(xy 440.201521 -351.946856) (xy 440.155645 -351.917373) (xy 440.114433 -351.881662) (xy 440.078722 -351.840448)
			(xy 440.04924 -351.794572) (xy 440.026586 -351.744968) (xy 440.011223 -351.692644) (xy 440.003462 -351.638666)
			(xy 438.520614 -351.638666) (xy 438.520614 -351.638671) (xy 438.512852 -351.692657) (xy 438.497487 -351.744989)
			(xy 438.474831 -351.794602) (xy 438.445345 -351.840486) (xy 438.409629 -351.881707) (xy 438.368412 -351.917426)
			(xy 438.32253 -351.946915) (xy 438.272919 -351.969576) (xy 438.220588 -351.984945) (xy 438.166603 -351.992711)
			(xy 438.139332 -351.9932) (xy 437.275732 -351.9932) (xy 437.248462 -351.992663) (xy 437.194477 -351.984905)
			(xy 437.142146 -351.969543) (xy 437.092534 -351.94689) (xy 437.046651 -351.917406) (xy 437.005431 -351.881692)
			(xy 436.969713 -351.840475) (xy 436.940226 -351.794594) (xy 436.917568 -351.744984) (xy 436.902202 -351.692654)
			(xy 436.894439 -351.63867) (xy 435.411736 -351.63867) (xy 435.411736 -351.638675) (xy 435.403973 -351.69267)
			(xy 435.388603 -351.74501) (xy 435.365942 -351.79463) (xy 435.336448 -351.840519) (xy 435.300724 -351.881744)
			(xy 435.259497 -351.917465) (xy 435.213605 -351.946955) (xy 435.163984 -351.969613) (xy 435.111642 -351.984979)
			(xy 435.057647 -351.992738) (xy 435.030372 -351.9932) (xy 434.166772 -351.9932) (xy 434.139507 -351.992636)
			(xy 434.085531 -351.984872) (xy 434.03321 -351.969505) (xy 433.983609 -351.94685) (xy 433.937736 -351.917366)
			(xy 433.896526 -351.881654) (xy 433.860817 -351.840442) (xy 433.831337 -351.794567) (xy 433.808685 -351.744963)
			(xy 433.793322 -351.692641) (xy 433.785562 -351.638665) (xy 432.302714 -351.638665) (xy 432.302714 -351.638672)
			(xy 432.294951 -351.692659) (xy 432.279585 -351.744993) (xy 432.256928 -351.794608) (xy 432.22744 -351.840492)
			(xy 432.191722 -351.881714) (xy 432.150502 -351.917433) (xy 432.104618 -351.946922) (xy 432.055004 -351.969581)
			(xy 432.002671 -351.984949) (xy 431.948684 -351.992713) (xy 431.921412 -351.9932) (xy 431.057812 -351.9932)
			(xy 431.030543 -351.992661) (xy 430.97656 -351.984901) (xy 430.924231 -351.969538) (xy 430.874622 -351.946883)
			(xy 430.828741 -351.917399) (xy 430.787524 -351.881685) (xy 430.751808 -351.840469) (xy 430.722323 -351.794589)
			(xy 430.699666 -351.74498) (xy 430.684301 -351.692651) (xy 430.676539 -351.638669) (xy 429.193836 -351.638669)
			(xy 429.193836 -351.638676) (xy 429.186072 -351.692672) (xy 429.170702 -351.745014) (xy 429.148039 -351.794635)
			(xy 429.118544 -351.840526) (xy 429.082817 -351.881751) (xy 429.041587 -351.917472) (xy 428.995693 -351.946962)
			(xy 428.946069 -351.969619) (xy 428.893725 -351.984982) (xy 428.839728 -351.99274) (xy 428.812452 -351.9932)
			(xy 427.948852 -351.9932) (xy 427.921588 -351.992634) (xy 427.867615 -351.984868) (xy 427.815296 -351.9695)
			(xy 427.765697 -351.946843) (xy 427.719826 -351.917359) (xy 427.678619 -351.881647) (xy 427.642912 -351.840435)
			(xy 427.613434 -351.794561) (xy 427.590783 -351.744959) (xy 427.575422 -351.692639) (xy 427.567662 -351.638664)
			(xy 426.084836 -351.638664) (xy 426.084836 -351.638674) (xy 426.077073 -351.692667) (xy 426.061705 -351.745006)
			(xy 426.039045 -351.794624) (xy 426.009553 -351.840513) (xy 425.973832 -351.881737) (xy 425.932606 -351.917458)
			(xy 425.886717 -351.946949) (xy 425.837098 -351.969608) (xy 425.784759 -351.984975) (xy 425.730766 -351.992737)
			(xy 425.703492 -351.9932) (xy 424.839892 -351.9932) (xy 424.812626 -351.992637) (xy 424.758648 -351.984875)
			(xy 424.706325 -351.969511) (xy 424.656721 -351.946856) (xy 424.610845 -351.917373) (xy 424.569633 -351.881662)
			(xy 424.533922 -351.840448) (xy 424.50444 -351.794572) (xy 424.481786 -351.744968) (xy 424.466423 -351.692644)
			(xy 424.458662 -351.638666) (xy 422.975814 -351.638666) (xy 422.975814 -351.638671) (xy 422.968052 -351.692657)
			(xy 422.952687 -351.744989) (xy 422.930031 -351.794602) (xy 422.900545 -351.840486) (xy 422.864829 -351.881707)
			(xy 422.823612 -351.917426) (xy 422.77773 -351.946915) (xy 422.728119 -351.969576) (xy 422.675788 -351.984945)
			(xy 422.621803 -351.992711) (xy 422.594532 -351.9932) (xy 421.730932 -351.9932) (xy 421.703662 -351.992663)
			(xy 421.649677 -351.984905) (xy 421.597346 -351.969543) (xy 421.547734 -351.94689) (xy 421.501851 -351.917406)
			(xy 421.460631 -351.881692) (xy 421.424913 -351.840475) (xy 421.395426 -351.794594) (xy 421.372768 -351.744984)
			(xy 421.357402 -351.692654) (xy 421.349639 -351.63867) (xy 419.866936 -351.63867) (xy 419.866936 -351.638675)
			(xy 419.859173 -351.69267) (xy 419.843803 -351.74501) (xy 419.821142 -351.79463) (xy 419.791648 -351.840519)
			(xy 419.755924 -351.881744) (xy 419.714697 -351.917465) (xy 419.668805 -351.946955) (xy 419.619184 -351.969613)
			(xy 419.566842 -351.984979) (xy 419.512847 -351.992738) (xy 419.485572 -351.9932) (xy 418.621972 -351.9932)
			(xy 418.594707 -351.992636) (xy 418.540731 -351.984872) (xy 418.48841 -351.969505) (xy 418.438809 -351.94685)
			(xy 418.392936 -351.917366) (xy 418.351726 -351.881654) (xy 418.316017 -351.840442) (xy 418.286537 -351.794567)
			(xy 418.263885 -351.744963) (xy 418.248522 -351.692641) (xy 418.240762 -351.638665) (xy 416.757914 -351.638665)
			(xy 416.757914 -351.638672) (xy 416.750151 -351.692659) (xy 416.734785 -351.744993) (xy 416.712128 -351.794608)
			(xy 416.68264 -351.840492) (xy 416.646922 -351.881714) (xy 416.605702 -351.917433) (xy 416.559818 -351.946922)
			(xy 416.510204 -351.969581) (xy 416.457871 -351.984949) (xy 416.403884 -351.992713) (xy 416.376612 -351.9932)
			(xy 415.513012 -351.9932) (xy 415.485743 -351.992661) (xy 415.43176 -351.984901) (xy 415.379431 -351.969538)
			(xy 415.329822 -351.946883) (xy 415.283941 -351.917399) (xy 415.242724 -351.881685) (xy 415.207008 -351.840469)
			(xy 415.177523 -351.794589) (xy 415.154866 -351.74498) (xy 415.139501 -351.692651) (xy 415.131739 -351.638669)
			(xy 413.649036 -351.638669) (xy 413.649036 -351.638676) (xy 413.641272 -351.692672) (xy 413.625902 -351.745014)
			(xy 413.603239 -351.794635) (xy 413.573744 -351.840526) (xy 413.538017 -351.881751) (xy 413.496787 -351.917472)
			(xy 413.450893 -351.946962) (xy 413.401269 -351.969619) (xy 413.348925 -351.984982) (xy 413.294928 -351.99274)
			(xy 413.267652 -351.9932) (xy 412.404052 -351.9932) (xy 412.376788 -351.992634) (xy 412.322815 -351.984868)
			(xy 412.270496 -351.9695) (xy 412.220897 -351.946843) (xy 412.175026 -351.917359) (xy 412.133819 -351.881647)
			(xy 412.098112 -351.840435) (xy 412.068634 -351.794561) (xy 412.045983 -351.744959) (xy 412.030622 -351.692639)
			(xy 412.022862 -351.638664) (xy 410.540036 -351.638664) (xy 410.540036 -351.638674) (xy 410.532273 -351.692667)
			(xy 410.516905 -351.745006) (xy 410.494245 -351.794624) (xy 410.464753 -351.840513) (xy 410.429032 -351.881737)
			(xy 410.387806 -351.917458) (xy 410.341917 -351.946949) (xy 410.292298 -351.969608) (xy 410.239959 -351.984975)
			(xy 410.185966 -351.992737) (xy 410.158692 -351.9932) (xy 409.295092 -351.9932) (xy 409.267826 -351.992637)
			(xy 409.213848 -351.984875) (xy 409.161525 -351.969511) (xy 409.111921 -351.946856) (xy 409.066045 -351.917373)
			(xy 409.024833 -351.881662) (xy 408.989122 -351.840448) (xy 408.95964 -351.794572) (xy 408.936986 -351.744968)
			(xy 408.921623 -351.692644) (xy 408.913862 -351.638666) (xy 403.522536 -351.638666) (xy 403.522536 -351.638675)
			(xy 403.514773 -351.692669) (xy 403.499404 -351.745008) (xy 403.476743 -351.794628) (xy 403.44725 -351.840517)
			(xy 403.411527 -351.881741) (xy 403.370301 -351.917462) (xy 403.32441 -351.946952) (xy 403.274789 -351.969611)
			(xy 403.222449 -351.984977) (xy 403.168455 -351.992738) (xy 403.14118 -351.9932) (xy 402.27758 -351.9932)
			(xy 402.250314 -351.992636) (xy 402.196338 -351.984873) (xy 402.144016 -351.969508) (xy 402.094414 -351.946852)
			(xy 402.04854 -351.917369) (xy 402.007329 -351.881657) (xy 401.971619 -351.840444) (xy 401.942138 -351.794569)
			(xy 401.919485 -351.744965) (xy 401.904123 -351.692642) (xy 401.896362 -351.638666) (xy 400.413514 -351.638666)
			(xy 400.413514 -351.638671) (xy 400.405752 -351.692658) (xy 400.390386 -351.744992) (xy 400.367729 -351.794605)
			(xy 400.338242 -351.84049) (xy 400.302525 -351.881711) (xy 400.261306 -351.91743) (xy 400.215423 -351.946919)
			(xy 400.16581 -351.969579) (xy 400.113478 -351.984947) (xy 400.059491 -351.992712) (xy 400.03222 -351.9932)
			(xy 399.16862 -351.9932) (xy 399.141351 -351.992662) (xy 399.087367 -351.984903) (xy 399.035037 -351.96954)
			(xy 398.985426 -351.946886) (xy 398.939545 -351.917402) (xy 398.898326 -351.881688) (xy 398.86261 -351.840471)
			(xy 398.833124 -351.794591) (xy 398.810467 -351.744982) (xy 398.795101 -351.692652) (xy 398.787339 -351.638669)
			(xy 397.304636 -351.638669) (xy 397.304636 -351.638676) (xy 397.296872 -351.692671) (xy 397.281503 -351.745012)
			(xy 397.25884 -351.794633) (xy 397.229346 -351.840523) (xy 397.19362 -351.881749) (xy 397.152391 -351.91747)
			(xy 397.106498 -351.946959) (xy 397.056875 -351.969617) (xy 397.004532 -351.984981) (xy 396.950536 -351.992739)
			(xy 396.92326 -351.9932) (xy 396.05966 -351.9932) (xy 396.032395 -351.992635) (xy 395.978421 -351.984869)
			(xy 395.926102 -351.969502) (xy 395.876502 -351.946846) (xy 395.83063 -351.917362) (xy 395.789421 -351.88165)
			(xy 395.753714 -351.840438) (xy 395.724235 -351.794563) (xy 395.701584 -351.744961) (xy 395.686222 -351.69264)
			(xy 395.678462 -351.638665) (xy 394.195613 -351.638665) (xy 394.195613 -351.638672) (xy 394.187851 -351.692661)
			(xy 394.172484 -351.744996) (xy 394.149826 -351.794611) (xy 394.120337 -351.840496) (xy 394.084618 -351.881718)
			(xy 394.043396 -351.917437) (xy 393.997511 -351.946926) (xy 393.947896 -351.969584) (xy 393.895561 -351.984951)
			(xy 393.841572 -351.992713) (xy 393.8143 -351.9932) (xy 392.9507 -351.9932) (xy 392.923433 -351.992638)
			(xy 392.869455 -351.984877) (xy 392.817131 -351.969513) (xy 392.767526 -351.946859) (xy 392.721649 -351.917376)
			(xy 392.680436 -351.881664) (xy 392.644724 -351.840451) (xy 392.615241 -351.794574) (xy 392.592587 -351.744969)
			(xy 392.577223 -351.692645) (xy 392.569462 -351.638667) (xy 391.086614 -351.638667) (xy 391.086614 -351.63867)
			(xy 391.078852 -351.692656) (xy 391.063487 -351.744987) (xy 391.040832 -351.7946) (xy 391.011347 -351.840483)
			(xy 390.975632 -351.881704) (xy 390.934415 -351.917423) (xy 390.888535 -351.946913) (xy 390.838925 -351.969573)
			(xy 390.786595 -351.984944) (xy 390.73261 -351.992711) (xy 390.70534 -351.9932) (xy 389.84174 -351.9932)
			(xy 389.81447 -351.992663) (xy 389.760484 -351.984907) (xy 389.708152 -351.969545) (xy 389.658538 -351.946892)
			(xy 389.612654 -351.917409) (xy 389.571434 -351.881695) (xy 389.535715 -351.840478) (xy 389.506227 -351.794597)
			(xy 389.483569 -351.744986) (xy 389.468202 -351.692655) (xy 389.46044 -351.63867) (xy 387.977736 -351.63867)
			(xy 387.977736 -351.638675) (xy 387.969973 -351.692669) (xy 387.954604 -351.745008) (xy 387.931943 -351.794628)
			(xy 387.90245 -351.840517) (xy 387.866727 -351.881741) (xy 387.825501 -351.917462) (xy 387.77961 -351.946952)
			(xy 387.729989 -351.969611) (xy 387.677649 -351.984977) (xy 387.623655 -351.992738) (xy 387.59638 -351.9932)
			(xy 386.73278 -351.9932) (xy 386.705514 -351.992636) (xy 386.651538 -351.984873) (xy 386.599216 -351.969508)
			(xy 386.549614 -351.946852) (xy 386.50374 -351.917369) (xy 386.462529 -351.881657) (xy 386.426819 -351.840444)
			(xy 386.397338 -351.794569) (xy 386.374685 -351.744965) (xy 386.359323 -351.692642) (xy 386.351562 -351.638666)
			(xy 384.868714 -351.638666) (xy 384.868714 -351.638671) (xy 384.860952 -351.692658) (xy 384.845586 -351.744992)
			(xy 384.822929 -351.794605) (xy 384.793442 -351.84049) (xy 384.757725 -351.881711) (xy 384.716506 -351.91743)
			(xy 384.670623 -351.946919) (xy 384.62101 -351.969579) (xy 384.568678 -351.984947) (xy 384.514691 -351.992712)
			(xy 384.48742 -351.9932) (xy 383.62382 -351.9932) (xy 383.596551 -351.992662) (xy 383.542567 -351.984903)
			(xy 383.490237 -351.96954) (xy 383.440626 -351.946886) (xy 383.394745 -351.917402) (xy 383.353526 -351.881688)
			(xy 383.31781 -351.840471) (xy 383.288324 -351.794591) (xy 383.265667 -351.744982) (xy 383.250301 -351.692652)
			(xy 383.242539 -351.638669) (xy 381.759836 -351.638669) (xy 381.759836 -351.638676) (xy 381.752072 -351.692671)
			(xy 381.736703 -351.745012) (xy 381.71404 -351.794633) (xy 381.684546 -351.840523) (xy 381.64882 -351.881749)
			(xy 381.607591 -351.91747) (xy 381.561698 -351.946959) (xy 381.512075 -351.969617) (xy 381.459732 -351.984981)
			(xy 381.405736 -351.992739) (xy 381.37846 -351.9932) (xy 380.51486 -351.9932) (xy 380.487595 -351.992635)
			(xy 380.433621 -351.984869) (xy 380.381302 -351.969502) (xy 380.331702 -351.946846) (xy 380.28583 -351.917362)
			(xy 380.244621 -351.88165) (xy 380.208914 -351.840438) (xy 380.179435 -351.794563) (xy 380.156784 -351.744961)
			(xy 380.141422 -351.69264) (xy 380.133662 -351.638665) (xy 378.650813 -351.638665) (xy 378.650813 -351.638672)
			(xy 378.643051 -351.692661) (xy 378.627684 -351.744996) (xy 378.605026 -351.794611) (xy 378.575537 -351.840496)
			(xy 378.539818 -351.881718) (xy 378.498596 -351.917437) (xy 378.452711 -351.946926) (xy 378.403096 -351.969584)
			(xy 378.350761 -351.984951) (xy 378.296772 -351.992713) (xy 378.2695 -351.9932) (xy 377.4059 -351.9932)
			(xy 377.378633 -351.992638) (xy 377.324655 -351.984877) (xy 377.272331 -351.969513) (xy 377.222726 -351.946859)
			(xy 377.176849 -351.917376) (xy 377.135636 -351.881664) (xy 377.099924 -351.840451) (xy 377.070441 -351.794574)
			(xy 377.047787 -351.744969) (xy 377.032423 -351.692645) (xy 377.024662 -351.638667) (xy 375.541814 -351.638667)
			(xy 375.541814 -351.63867) (xy 375.534052 -351.692656) (xy 375.518687 -351.744987) (xy 375.496032 -351.7946)
			(xy 375.466547 -351.840483) (xy 375.430832 -351.881704) (xy 375.389615 -351.917423) (xy 375.343735 -351.946913)
			(xy 375.294125 -351.969573) (xy 375.241795 -351.984944) (xy 375.18781 -351.992711) (xy 375.16054 -351.9932)
			(xy 374.29694 -351.9932) (xy 374.26967 -351.992663) (xy 374.215684 -351.984907) (xy 374.163352 -351.969545)
			(xy 374.113738 -351.946892) (xy 374.067854 -351.917409) (xy 374.026634 -351.881695) (xy 373.990915 -351.840478)
			(xy 373.961427 -351.794597) (xy 373.938769 -351.744986) (xy 373.923402 -351.692655) (xy 373.91564 -351.63867)
			(xy 372.432936 -351.63867) (xy 372.432936 -351.638675) (xy 372.425173 -351.692669) (xy 372.409804 -351.745008)
			(xy 372.387143 -351.794628) (xy 372.35765 -351.840517) (xy 372.321927 -351.881741) (xy 372.280701 -351.917462)
			(xy 372.23481 -351.946952) (xy 372.185189 -351.969611) (xy 372.132849 -351.984977) (xy 372.078855 -351.992738)
			(xy 372.05158 -351.9932) (xy 371.18798 -351.9932) (xy 371.160714 -351.992636) (xy 371.106738 -351.984873)
			(xy 371.054416 -351.969508) (xy 371.004814 -351.946852) (xy 370.95894 -351.917369) (xy 370.917729 -351.881657)
			(xy 370.882019 -351.840444) (xy 370.852538 -351.794569) (xy 370.829885 -351.744965) (xy 370.814523 -351.692642)
			(xy 370.806762 -351.638666) (xy 344.837313 -351.638666) (xy 344.837313 -351.638672) (xy 344.829551 -351.692661)
			(xy 344.814184 -351.744995) (xy 344.791526 -351.79461) (xy 344.762038 -351.840495) (xy 344.726319 -351.881717)
			(xy 344.685098 -351.917435) (xy 344.639213 -351.946924) (xy 344.589599 -351.969583) (xy 344.537264 -351.98495)
			(xy 344.483276 -351.992713) (xy 344.456004 -351.9932) (xy 343.592404 -351.9932) (xy 343.565136 -351.992661)
			(xy 343.511154 -351.9849) (xy 343.458826 -351.969536) (xy 343.409217 -351.94688) (xy 343.363337 -351.917396)
			(xy 343.322121 -351.881682) (xy 343.286407 -351.840466) (xy 343.256921 -351.794587) (xy 343.234266 -351.744978)
			(xy 343.218901 -351.69265) (xy 343.211139 -351.638668) (xy 341.728314 -351.638668) (xy 341.728314 -351.63867)
			(xy 341.720552 -351.692655) (xy 341.705188 -351.744986) (xy 341.682532 -351.794599) (xy 341.653048 -351.840482)
			(xy 341.617334 -351.881703) (xy 341.576117 -351.917421) (xy 341.530237 -351.946911) (xy 341.480628 -351.969572)
			(xy 341.428298 -351.984943) (xy 341.374314 -351.99271) (xy 341.347044 -351.9932) (xy 340.483444 -351.9932)
			(xy 340.456174 -351.992664) (xy 340.402187 -351.984907) (xy 340.349855 -351.969546) (xy 340.300241 -351.946894)
			(xy 340.254356 -351.91741) (xy 340.213135 -351.881696) (xy 340.177416 -351.840479) (xy 340.147928 -351.794598)
			(xy 340.125269 -351.744987) (xy 340.109902 -351.692656) (xy 340.10214 -351.63867) (xy 338.619436 -351.63867)
			(xy 338.619436 -351.638674) (xy 338.611673 -351.692668) (xy 338.596304 -351.745007) (xy 338.573643 -351.794626)
			(xy 338.544151 -351.840515) (xy 338.508429 -351.88174) (xy 338.467203 -351.917461) (xy 338.421312 -351.946951)
			(xy 338.371692 -351.96961) (xy 338.319352 -351.984976) (xy 338.265358 -351.992738) (xy 338.238084 -351.9932)
			(xy 337.374484 -351.9932) (xy 337.347218 -351.992637) (xy 337.293242 -351.984874) (xy 337.240919 -351.969509)
			(xy 337.191316 -351.946854) (xy 337.145442 -351.91737) (xy 337.10423 -351.881659) (xy 337.06852 -351.840446)
			(xy 337.039039 -351.79457) (xy 337.016386 -351.744966) (xy 337.001023 -351.692643) (xy 336.993262 -351.638666)
			(xy 335.510414 -351.638666) (xy 335.510414 -351.638671) (xy 335.502652 -351.692658) (xy 335.487286 -351.744991)
			(xy 335.464629 -351.794604) (xy 335.435143 -351.840488) (xy 335.399427 -351.88171) (xy 335.358208 -351.917428)
			(xy 335.312325 -351.946918) (xy 335.262713 -351.969578) (xy 335.210381 -351.984947) (xy 335.156395 -351.992712)
			(xy 335.129124 -351.9932) (xy 334.265524 -351.9932) (xy 334.238255 -351.992662) (xy 334.18427 -351.984904)
			(xy 334.13194 -351.969541) (xy 334.082329 -351.946887) (xy 334.036447 -351.917403) (xy 333.995228 -351.881689)
			(xy 333.959511 -351.840472) (xy 333.930024 -351.794592) (xy 333.907367 -351.744982) (xy 333.892001 -351.692653)
			(xy 333.884239 -351.638669) (xy 332.401536 -351.638669) (xy 332.401536 -351.638675) (xy 332.393772 -351.692671)
			(xy 332.378403 -351.745011) (xy 332.35574 -351.794632) (xy 332.326246 -351.840522) (xy 332.290522 -351.881747)
			(xy 332.249293 -351.917468) (xy 332.2034 -351.946958) (xy 332.153778 -351.969615) (xy 332.101436 -351.98498)
			(xy 332.047439 -351.992739) (xy 332.020164 -351.9932) (xy 331.156564 -351.9932) (xy 331.129299 -351.992635)
			(xy 331.075325 -351.98487) (xy 331.023005 -351.969503) (xy 330.973404 -351.946847) (xy 330.927532 -351.917363)
			(xy 330.886323 -351.881652) (xy 330.850615 -351.840439) (xy 330.821136 -351.794564) (xy 330.798484 -351.744962)
			(xy 330.783122 -351.69264) (xy 330.775362 -351.638665) (xy 329.292513 -351.638665) (xy 329.292513 -351.638672)
			(xy 329.284751 -351.692661) (xy 329.269384 -351.744995) (xy 329.246726 -351.79461) (xy 329.217238 -351.840495)
			(xy 329.181519 -351.881717) (xy 329.140298 -351.917435) (xy 329.094413 -351.946924) (xy 329.044799 -351.969583)
			(xy 328.992464 -351.98495) (xy 328.938476 -351.992713) (xy 328.911204 -351.9932) (xy 328.047604 -351.9932)
			(xy 328.020336 -351.992661) (xy 327.966354 -351.9849) (xy 327.914026 -351.969536) (xy 327.864417 -351.94688)
			(xy 327.818537 -351.917396) (xy 327.777321 -351.881682) (xy 327.741607 -351.840466) (xy 327.712121 -351.794587)
			(xy 327.689466 -351.744978) (xy 327.674101 -351.69265) (xy 327.666339 -351.638668) (xy 326.183514 -351.638668)
			(xy 326.183514 -351.63867) (xy 326.175752 -351.692655) (xy 326.160388 -351.744986) (xy 326.137732 -351.794599)
			(xy 326.108248 -351.840482) (xy 326.072534 -351.881703) (xy 326.031317 -351.917421) (xy 325.985437 -351.946911)
			(xy 325.935828 -351.969572) (xy 325.883498 -351.984943) (xy 325.829514 -351.99271) (xy 325.802244 -351.9932)
			(xy 324.938644 -351.9932) (xy 324.911374 -351.992664) (xy 324.857387 -351.984907) (xy 324.805055 -351.969546)
			(xy 324.755441 -351.946894) (xy 324.709556 -351.91741) (xy 324.668335 -351.881696) (xy 324.632616 -351.840479)
			(xy 324.603128 -351.794598) (xy 324.580469 -351.744987) (xy 324.565102 -351.692656) (xy 324.55734 -351.63867)
			(xy 323.074636 -351.63867) (xy 323.074636 -351.638674) (xy 323.066873 -351.692668) (xy 323.051504 -351.745007)
			(xy 323.028843 -351.794626) (xy 322.999351 -351.840515) (xy 322.963629 -351.88174) (xy 322.922403 -351.917461)
			(xy 322.876512 -351.946951) (xy 322.826892 -351.96961) (xy 322.774552 -351.984976) (xy 322.720558 -351.992738)
			(xy 322.693284 -351.9932) (xy 321.829684 -351.9932) (xy 321.802418 -351.992637) (xy 321.748442 -351.984874)
			(xy 321.696119 -351.969509) (xy 321.646516 -351.946854) (xy 321.600642 -351.91737) (xy 321.55943 -351.881659)
			(xy 321.52372 -351.840446) (xy 321.494239 -351.79457) (xy 321.471586 -351.744966) (xy 321.456223 -351.692643)
			(xy 321.448462 -351.638666) (xy 319.965614 -351.638666) (xy 319.965614 -351.638671) (xy 319.957852 -351.692658)
			(xy 319.942486 -351.744991) (xy 319.919829 -351.794604) (xy 319.890343 -351.840488) (xy 319.854627 -351.88171)
			(xy 319.813408 -351.917428) (xy 319.767525 -351.946918) (xy 319.717913 -351.969578) (xy 319.665581 -351.984947)
			(xy 319.611595 -351.992712) (xy 319.584324 -351.9932) (xy 318.720724 -351.9932) (xy 318.693455 -351.992662)
			(xy 318.63947 -351.984904) (xy 318.58714 -351.969541) (xy 318.537529 -351.946887) (xy 318.491647 -351.917403)
			(xy 318.450428 -351.881689) (xy 318.414711 -351.840472) (xy 318.385224 -351.794592) (xy 318.362567 -351.744982)
			(xy 318.347201 -351.692653) (xy 318.339439 -351.638669) (xy 316.856736 -351.638669) (xy 316.856736 -351.638675)
			(xy 316.848972 -351.692671) (xy 316.833603 -351.745011) (xy 316.81094 -351.794632) (xy 316.781446 -351.840522)
			(xy 316.745722 -351.881747) (xy 316.704493 -351.917468) (xy 316.6586 -351.946958) (xy 316.608978 -351.969615)
			(xy 316.556636 -351.98498) (xy 316.502639 -351.992739) (xy 316.475364 -351.9932) (xy 315.611764 -351.9932)
			(xy 315.584499 -351.992635) (xy 315.530525 -351.98487) (xy 315.478205 -351.969503) (xy 315.428604 -351.946847)
			(xy 315.382732 -351.917363) (xy 315.341523 -351.881652) (xy 315.305815 -351.840439) (xy 315.276336 -351.794564)
			(xy 315.253684 -351.744962) (xy 315.238322 -351.69264) (xy 315.230562 -351.638665) (xy 313.747713 -351.638665)
			(xy 313.747713 -351.638672) (xy 313.739951 -351.692661) (xy 313.724584 -351.744995) (xy 313.701926 -351.79461)
			(xy 313.672438 -351.840495) (xy 313.636719 -351.881717) (xy 313.595498 -351.917435) (xy 313.549613 -351.946924)
			(xy 313.499999 -351.969583) (xy 313.447664 -351.98495) (xy 313.393676 -351.992713) (xy 313.366404 -351.9932)
			(xy 312.502804 -351.9932) (xy 312.475536 -351.992661) (xy 312.421554 -351.9849) (xy 312.369226 -351.969536)
			(xy 312.319617 -351.94688) (xy 312.273737 -351.917396) (xy 312.232521 -351.881682) (xy 312.196807 -351.840466)
			(xy 312.167321 -351.794587) (xy 312.144666 -351.744978) (xy 312.129301 -351.69265) (xy 312.121539 -351.638668)
			(xy 300.231613 -351.638668) (xy 300.231613 -351.638672) (xy 300.223851 -351.692661) (xy 300.208484 -351.744995)
			(xy 300.185826 -351.79461) (xy 300.156337 -351.840496) (xy 300.120619 -351.881717) (xy 300.079397 -351.917436)
			(xy 300.033512 -351.946925) (xy 299.983897 -351.969584) (xy 299.931563 -351.984951) (xy 299.877574 -351.992713)
			(xy 299.850302 -351.9932) (xy 298.986702 -351.9932) (xy 298.959434 -351.992661) (xy 298.905452 -351.9849)
			(xy 298.853124 -351.969535) (xy 298.803516 -351.94688) (xy 298.757636 -351.917395) (xy 298.71642 -351.881681)
			(xy 298.680706 -351.840465) (xy 298.651221 -351.794586) (xy 298.628566 -351.744978) (xy 298.613201 -351.69265)
			(xy 298.605439 -351.638668) (xy 297.122614 -351.638668) (xy 297.122614 -351.63867) (xy 297.114852 -351.692655)
			(xy 297.099488 -351.744987) (xy 297.076832 -351.794599) (xy 297.047347 -351.840483) (xy 297.011633 -351.881703)
			(xy 296.970416 -351.917422) (xy 296.924536 -351.946912) (xy 296.874926 -351.969573) (xy 296.822597 -351.984943)
			(xy 296.768612 -351.992711) (xy 296.741342 -351.9932) (xy 295.877742 -351.9932) (xy 295.850472 -351.992663)
			(xy 295.796486 -351.984907) (xy 295.744153 -351.969546) (xy 295.69454 -351.946893) (xy 295.648655 -351.917409)
			(xy 295.607434 -351.881695) (xy 295.571716 -351.840478) (xy 295.542227 -351.794597) (xy 295.519569 -351.744986)
			(xy 295.504202 -351.692655) (xy 295.49644 -351.63867) (xy 294.013736 -351.63867) (xy 294.013736 -351.638675)
			(xy 294.005973 -351.692668) (xy 293.990604 -351.745008) (xy 293.967943 -351.794627) (xy 293.938451 -351.840516)
			(xy 293.902728 -351.881741) (xy 293.861502 -351.917462) (xy 293.815611 -351.946952) (xy 293.765991 -351.969611)
			(xy 293.713651 -351.984977) (xy 293.659657 -351.992738) (xy 293.632382 -351.9932) (xy 292.768782 -351.9932)
			(xy 292.741516 -351.992636) (xy 292.68754 -351.984873) (xy 292.635218 -351.969508) (xy 292.585615 -351.946853)
			(xy 292.539741 -351.91737) (xy 292.498529 -351.881658) (xy 292.46282 -351.840445) (xy 292.433338 -351.794569)
			(xy 292.410686 -351.744965) (xy 292.395323 -351.692642) (xy 292.387562 -351.638666) (xy 290.904714 -351.638666)
			(xy 290.904714 -351.638671) (xy 290.896952 -351.692658) (xy 290.881586 -351.744991) (xy 290.858929 -351.794605)
			(xy 290.829442 -351.840489) (xy 290.793726 -351.88171) (xy 290.752507 -351.917429) (xy 290.706624 -351.946919)
			(xy 290.657012 -351.969578) (xy 290.60468 -351.984947) (xy 290.550693 -351.992712) (xy 290.523422 -351.9932)
			(xy 289.659822 -351.9932) (xy 289.632553 -351.992662) (xy 289.578569 -351.984903) (xy 289.526239 -351.96954)
			(xy 289.476628 -351.946886) (xy 289.430746 -351.917402) (xy 289.389527 -351.881688) (xy 289.353811 -351.840472)
			(xy 289.324324 -351.794592) (xy 289.301667 -351.744982) (xy 289.286301 -351.692653) (xy 289.278539 -351.638669)
			(xy 287.795836 -351.638669) (xy 287.795836 -351.638675) (xy 287.788072 -351.692671) (xy 287.772703 -351.745012)
			(xy 287.75004 -351.794633) (xy 287.720546 -351.840523) (xy 287.684821 -351.881748) (xy 287.643592 -351.917469)
			(xy 287.597699 -351.946958) (xy 287.548076 -351.969616) (xy 287.495734 -351.98498) (xy 287.441737 -351.992739)
			(xy 287.414462 -351.9932) (xy 286.550862 -351.9932) (xy 286.523597 -351.992635) (xy 286.469623 -351.98487)
			(xy 286.417303 -351.969503) (xy 286.367703 -351.946847) (xy 286.321831 -351.917363) (xy 286.280622 -351.881651)
			(xy 286.244915 -351.840438) (xy 286.215435 -351.794564) (xy 286.192784 -351.744961) (xy 286.177422 -351.69264)
			(xy 286.169662 -351.638665) (xy 284.686813 -351.638665) (xy 284.686813 -351.638672) (xy 284.679051 -351.692661)
			(xy 284.663684 -351.744995) (xy 284.641026 -351.79461) (xy 284.611537 -351.840496) (xy 284.575819 -351.881717)
			(xy 284.534597 -351.917436) (xy 284.488712 -351.946925) (xy 284.439097 -351.969584) (xy 284.386763 -351.984951)
			(xy 284.332774 -351.992713) (xy 284.305502 -351.9932) (xy 283.441902 -351.9932) (xy 283.414634 -351.992661)
			(xy 283.360652 -351.9849) (xy 283.308324 -351.969535) (xy 283.258716 -351.94688) (xy 283.212836 -351.917395)
			(xy 283.17162 -351.881681) (xy 283.135906 -351.840465) (xy 283.106421 -351.794586) (xy 283.083766 -351.744978)
			(xy 283.068401 -351.69265) (xy 283.060639 -351.638668) (xy 281.577814 -351.638668) (xy 281.577814 -351.63867)
			(xy 281.570052 -351.692655) (xy 281.554688 -351.744987) (xy 281.532032 -351.794599) (xy 281.502547 -351.840483)
			(xy 281.466833 -351.881703) (xy 281.425616 -351.917422) (xy 281.379736 -351.946912) (xy 281.330126 -351.969573)
			(xy 281.277797 -351.984943) (xy 281.223812 -351.992711) (xy 281.196542 -351.9932) (xy 280.332942 -351.9932)
			(xy 280.305672 -351.992663) (xy 280.251686 -351.984907) (xy 280.199353 -351.969546) (xy 280.14974 -351.946893)
			(xy 280.103855 -351.917409) (xy 280.062634 -351.881695) (xy 280.026916 -351.840478) (xy 279.997427 -351.794597)
			(xy 279.974769 -351.744986) (xy 279.959402 -351.692655) (xy 279.95164 -351.63867) (xy 278.468936 -351.63867)
			(xy 278.468936 -351.638675) (xy 278.461173 -351.692668) (xy 278.445804 -351.745008) (xy 278.423143 -351.794627)
			(xy 278.393651 -351.840516) (xy 278.357928 -351.881741) (xy 278.316702 -351.917462) (xy 278.270811 -351.946952)
			(xy 278.221191 -351.969611) (xy 278.168851 -351.984977) (xy 278.114857 -351.992738) (xy 278.087582 -351.9932)
			(xy 277.223982 -351.9932) (xy 277.196716 -351.992636) (xy 277.14274 -351.984873) (xy 277.090418 -351.969508)
			(xy 277.040815 -351.946853) (xy 276.994941 -351.91737) (xy 276.953729 -351.881658) (xy 276.91802 -351.840445)
			(xy 276.888538 -351.794569) (xy 276.865886 -351.744965) (xy 276.850523 -351.692642) (xy 276.842762 -351.638666)
			(xy 275.359914 -351.638666) (xy 275.359914 -351.638671) (xy 275.352152 -351.692658) (xy 275.336786 -351.744991)
			(xy 275.314129 -351.794605) (xy 275.284642 -351.840489) (xy 275.248926 -351.88171) (xy 275.207707 -351.917429)
			(xy 275.161824 -351.946919) (xy 275.112212 -351.969578) (xy 275.05988 -351.984947) (xy 275.005893 -351.992712)
			(xy 274.978622 -351.9932) (xy 274.115022 -351.9932) (xy 274.087753 -351.992662) (xy 274.033769 -351.984903)
			(xy 273.981439 -351.96954) (xy 273.931828 -351.946886) (xy 273.885946 -351.917402) (xy 273.844727 -351.881688)
			(xy 273.809011 -351.840472) (xy 273.779524 -351.794592) (xy 273.756867 -351.744982) (xy 273.741501 -351.692653)
			(xy 273.733739 -351.638669) (xy 272.251036 -351.638669) (xy 272.251036 -351.638675) (xy 272.243272 -351.692671)
			(xy 272.227903 -351.745012) (xy 272.20524 -351.794633) (xy 272.175746 -351.840523) (xy 272.140021 -351.881748)
			(xy 272.098792 -351.917469) (xy 272.052899 -351.946958) (xy 272.003276 -351.969616) (xy 271.950934 -351.98498)
			(xy 271.896937 -351.992739) (xy 271.869662 -351.9932) (xy 271.006062 -351.9932) (xy 270.978797 -351.992635)
			(xy 270.924823 -351.98487) (xy 270.872503 -351.969503) (xy 270.822903 -351.946847) (xy 270.777031 -351.917363)
			(xy 270.735822 -351.881651) (xy 270.700115 -351.840438) (xy 270.670635 -351.794564) (xy 270.647984 -351.744961)
			(xy 270.632622 -351.69264) (xy 270.624862 -351.638665) (xy 269.142013 -351.638665) (xy 269.142013 -351.638672)
			(xy 269.134251 -351.692661) (xy 269.118884 -351.744995) (xy 269.096226 -351.79461) (xy 269.066737 -351.840496)
			(xy 269.031019 -351.881717) (xy 268.989797 -351.917436) (xy 268.943912 -351.946925) (xy 268.894297 -351.969584)
			(xy 268.841963 -351.984951) (xy 268.787974 -351.992713) (xy 268.760702 -351.9932) (xy 267.897102 -351.9932)
			(xy 267.869834 -351.992661) (xy 267.815852 -351.9849) (xy 267.763524 -351.969535) (xy 267.713916 -351.94688)
			(xy 267.668036 -351.917395) (xy 267.62682 -351.881681) (xy 267.591106 -351.840465) (xy 267.561621 -351.794586)
			(xy 267.538966 -351.744978) (xy 267.523601 -351.69265) (xy 267.515839 -351.638668) (xy 194.520614 -351.638668)
			(xy 194.520614 -351.638672) (xy 194.512851 -351.692659) (xy 194.497485 -351.744993) (xy 194.474828 -351.794608)
			(xy 194.44534 -351.840492) (xy 194.409622 -351.881714) (xy 194.368402 -351.917433) (xy 194.322518 -351.946922)
			(xy 194.272904 -351.969581) (xy 194.220571 -351.984949) (xy 194.166584 -351.992713) (xy 194.139312 -351.9932)
			(xy 193.275712 -351.9932) (xy 193.248443 -351.992661) (xy 193.19446 -351.984901) (xy 193.142131 -351.969538)
			(xy 193.092522 -351.946883) (xy 193.046641 -351.917399) (xy 193.005424 -351.881685) (xy 192.969708 -351.840469)
			(xy 192.940223 -351.794589) (xy 192.917566 -351.74498) (xy 192.902201 -351.692651) (xy 192.894439 -351.638669)
			(xy 191.411736 -351.638669) (xy 191.411736 -351.638676) (xy 191.403972 -351.692672) (xy 191.388602 -351.745014)
			(xy 191.365939 -351.794635) (xy 191.336444 -351.840526) (xy 191.300717 -351.881751) (xy 191.259487 -351.917472)
			(xy 191.213593 -351.946962) (xy 191.163969 -351.969619) (xy 191.111625 -351.984982) (xy 191.057628 -351.99274)
			(xy 191.030352 -351.9932) (xy 190.166752 -351.9932) (xy 190.139488 -351.992634) (xy 190.085515 -351.984868)
			(xy 190.033196 -351.9695) (xy 189.983597 -351.946843) (xy 189.937726 -351.917359) (xy 189.896519 -351.881647)
			(xy 189.860812 -351.840435) (xy 189.831334 -351.794561) (xy 189.808683 -351.744959) (xy 189.793322 -351.692639)
			(xy 189.785562 -351.638664) (xy 188.302736 -351.638664) (xy 188.302736 -351.638674) (xy 188.294973 -351.692667)
			(xy 188.279605 -351.745006) (xy 188.256945 -351.794624) (xy 188.227453 -351.840513) (xy 188.191732 -351.881737)
			(xy 188.150506 -351.917458) (xy 188.104617 -351.946949) (xy 188.054998 -351.969608) (xy 188.002659 -351.984975)
			(xy 187.948666 -351.992737) (xy 187.921392 -351.9932) (xy 187.057792 -351.9932) (xy 187.030526 -351.992637)
			(xy 186.976548 -351.984875) (xy 186.924225 -351.969511) (xy 186.874621 -351.946856) (xy 186.828745 -351.917373)
			(xy 186.787533 -351.881662) (xy 186.751822 -351.840448) (xy 186.72234 -351.794572) (xy 186.699686 -351.744968)
			(xy 186.684323 -351.692644) (xy 186.676562 -351.638666) (xy 185.193714 -351.638666) (xy 185.193714 -351.638671)
			(xy 185.185952 -351.692657) (xy 185.170587 -351.744989) (xy 185.147931 -351.794602) (xy 185.118445 -351.840486)
			(xy 185.082729 -351.881707) (xy 185.041512 -351.917426) (xy 184.99563 -351.946915) (xy 184.946019 -351.969576)
			(xy 184.893688 -351.984945) (xy 184.839703 -351.992711) (xy 184.812432 -351.9932) (xy 183.948832 -351.9932)
			(xy 183.921562 -351.992663) (xy 183.867577 -351.984905) (xy 183.815246 -351.969543) (xy 183.765634 -351.94689)
			(xy 183.719751 -351.917406) (xy 183.678531 -351.881692) (xy 183.642813 -351.840475) (xy 183.613326 -351.794594)
			(xy 183.590668 -351.744984) (xy 183.575302 -351.692654) (xy 183.567539 -351.63867) (xy 182.084836 -351.63867)
			(xy 182.084836 -351.638675) (xy 182.077073 -351.69267) (xy 182.061703 -351.74501) (xy 182.039042 -351.79463)
			(xy 182.009548 -351.840519) (xy 181.973824 -351.881744) (xy 181.932597 -351.917465) (xy 181.886705 -351.946955)
			(xy 181.837084 -351.969613) (xy 181.784742 -351.984979) (xy 181.730747 -351.992738) (xy 181.703472 -351.9932)
			(xy 180.839872 -351.9932) (xy 180.812607 -351.992636) (xy 180.758631 -351.984872) (xy 180.70631 -351.969505)
			(xy 180.656709 -351.94685) (xy 180.610836 -351.917366) (xy 180.569626 -351.881654) (xy 180.533917 -351.840442)
			(xy 180.504437 -351.794567) (xy 180.481785 -351.744963) (xy 180.466422 -351.692641) (xy 180.458662 -351.638665)
			(xy 178.975814 -351.638665) (xy 178.975814 -351.638672) (xy 178.968051 -351.692659) (xy 178.952685 -351.744993)
			(xy 178.930028 -351.794608) (xy 178.90054 -351.840492) (xy 178.864822 -351.881714) (xy 178.823602 -351.917433)
			(xy 178.777718 -351.946922) (xy 178.728104 -351.969581) (xy 178.675771 -351.984949) (xy 178.621784 -351.992713)
			(xy 178.594512 -351.9932) (xy 177.730912 -351.9932) (xy 177.703643 -351.992661) (xy 177.64966 -351.984901)
			(xy 177.597331 -351.969538) (xy 177.547722 -351.946883) (xy 177.501841 -351.917399) (xy 177.460624 -351.881685)
			(xy 177.424908 -351.840469) (xy 177.395423 -351.794589) (xy 177.372766 -351.74498) (xy 177.357401 -351.692651)
			(xy 177.349639 -351.638669) (xy 175.866936 -351.638669) (xy 175.866936 -351.638676) (xy 175.859172 -351.692672)
			(xy 175.843802 -351.745014) (xy 175.821139 -351.794635) (xy 175.791644 -351.840526) (xy 175.755917 -351.881751)
			(xy 175.714687 -351.917472) (xy 175.668793 -351.946962) (xy 175.619169 -351.969619) (xy 175.566825 -351.984982)
			(xy 175.512828 -351.99274) (xy 175.485552 -351.9932) (xy 174.621952 -351.9932) (xy 174.594688 -351.992634)
			(xy 174.540715 -351.984868) (xy 174.488396 -351.9695) (xy 174.438797 -351.946843) (xy 174.392926 -351.917359)
			(xy 174.351719 -351.881647) (xy 174.316012 -351.840435) (xy 174.286534 -351.794561) (xy 174.263883 -351.744959)
			(xy 174.248522 -351.692639) (xy 174.240762 -351.638664) (xy 172.757936 -351.638664) (xy 172.757936 -351.638674)
			(xy 172.750173 -351.692667) (xy 172.734805 -351.745006) (xy 172.712145 -351.794624) (xy 172.682653 -351.840513)
			(xy 172.646932 -351.881737) (xy 172.605706 -351.917458) (xy 172.559817 -351.946949) (xy 172.510198 -351.969608)
			(xy 172.457859 -351.984975) (xy 172.403866 -351.992737) (xy 172.376592 -351.9932) (xy 171.512992 -351.9932)
			(xy 171.485726 -351.992637) (xy 171.431748 -351.984875) (xy 171.379425 -351.969511) (xy 171.329821 -351.946856)
			(xy 171.283945 -351.917373) (xy 171.242733 -351.881662) (xy 171.207022 -351.840448) (xy 171.17754 -351.794572)
			(xy 171.154886 -351.744968) (xy 171.139523 -351.692644) (xy 171.131762 -351.638666) (xy 169.648914 -351.638666)
			(xy 169.648914 -351.638671) (xy 169.641152 -351.692657) (xy 169.625787 -351.744989) (xy 169.603131 -351.794602)
			(xy 169.573645 -351.840486) (xy 169.537929 -351.881707) (xy 169.496712 -351.917426) (xy 169.45083 -351.946915)
			(xy 169.401219 -351.969576) (xy 169.348888 -351.984945) (xy 169.294903 -351.992711) (xy 169.267632 -351.9932)
			(xy 168.404032 -351.9932) (xy 168.376762 -351.992663) (xy 168.322777 -351.984905) (xy 168.270446 -351.969543)
			(xy 168.220834 -351.94689) (xy 168.174951 -351.917406) (xy 168.133731 -351.881692) (xy 168.098013 -351.840475)
			(xy 168.068526 -351.794594) (xy 168.045868 -351.744984) (xy 168.030502 -351.692654) (xy 168.022739 -351.63867)
			(xy 166.540036 -351.63867) (xy 166.540036 -351.638675) (xy 166.532273 -351.69267) (xy 166.516903 -351.74501)
			(xy 166.494242 -351.79463) (xy 166.464748 -351.840519) (xy 166.429024 -351.881744) (xy 166.387797 -351.917465)
			(xy 166.341905 -351.946955) (xy 166.292284 -351.969613) (xy 166.239942 -351.984979) (xy 166.185947 -351.992738)
			(xy 166.158672 -351.9932) (xy 165.295072 -351.9932) (xy 165.267807 -351.992636) (xy 165.213831 -351.984872)
			(xy 165.16151 -351.969505) (xy 165.111909 -351.94685) (xy 165.066036 -351.917366) (xy 165.024826 -351.881654)
			(xy 164.989117 -351.840442) (xy 164.959637 -351.794567) (xy 164.936985 -351.744963) (xy 164.921622 -351.692641)
			(xy 164.913862 -351.638665) (xy 163.431014 -351.638665) (xy 163.431014 -351.638672) (xy 163.423251 -351.692659)
			(xy 163.407885 -351.744993) (xy 163.385228 -351.794608) (xy 163.35574 -351.840492) (xy 163.320022 -351.881714)
			(xy 163.278802 -351.917433) (xy 163.232918 -351.946922) (xy 163.183304 -351.969581) (xy 163.130971 -351.984949)
			(xy 163.076984 -351.992713) (xy 163.049712 -351.9932) (xy 162.186112 -351.9932) (xy 162.158843 -351.992661)
			(xy 162.10486 -351.984901) (xy 162.052531 -351.969538) (xy 162.002922 -351.946883) (xy 161.957041 -351.917399)
			(xy 161.915824 -351.881685) (xy 161.880108 -351.840469) (xy 161.850623 -351.794589) (xy 161.827966 -351.74498)
			(xy 161.812601 -351.692651) (xy 161.804839 -351.638669) (xy 144.196614 -351.638669) (xy 144.196614 -351.638672)
			(xy 144.188851 -351.69266) (xy 144.173485 -351.744994) (xy 144.150827 -351.794609) (xy 144.121339 -351.840494)
			(xy 144.085621 -351.881715) (xy 144.0444 -351.917434) (xy 143.998516 -351.946923) (xy 143.948902 -351.969582)
			(xy 143.896568 -351.98495) (xy 143.84258 -351.992713) (xy 143.815308 -351.9932) (xy 142.951708 -351.9932)
			(xy 142.924439 -351.992661) (xy 142.870457 -351.984901) (xy 142.818129 -351.969537) (xy 142.768519 -351.946882)
			(xy 142.722639 -351.917397) (xy 142.681422 -351.881683) (xy 142.645707 -351.840467) (xy 142.616222 -351.794588)
			(xy 142.593566 -351.744979) (xy 142.578201 -351.692651) (xy 142.570439 -351.638669) (xy 141.087614 -351.638669)
			(xy 141.087614 -351.63867) (xy 141.079852 -351.692655) (xy 141.064488 -351.744986) (xy 141.041833 -351.794597)
			(xy 141.012349 -351.840481) (xy 140.976635 -351.881701) (xy 140.935419 -351.91742) (xy 140.88954 -351.94691)
			(xy 140.839931 -351.969571) (xy 140.787602 -351.984942) (xy 140.733618 -351.99271) (xy 140.706348 -351.9932)
			(xy 139.842748 -351.9932) (xy 139.815477 -351.992664) (xy 139.761491 -351.984908) (xy 139.709158 -351.969547)
			(xy 139.659543 -351.946895) (xy 139.613658 -351.917411) (xy 139.572436 -351.881698) (xy 139.536717 -351.84048)
			(xy 139.507228 -351.794599) (xy 139.484569 -351.744987) (xy 139.469202 -351.692656) (xy 139.46144 -351.63867)
			(xy 137.978736 -351.63867) (xy 137.978736 -351.638674) (xy 137.970973 -351.692668) (xy 137.955605 -351.745006)
			(xy 137.932944 -351.794625) (xy 137.903452 -351.840514) (xy 137.86773 -351.881739) (xy 137.826504 -351.91746)
			(xy 137.780615 -351.94695) (xy 137.730995 -351.969609) (xy 137.678656 -351.984976) (xy 137.624662 -351.992737)
			(xy 137.597388 -351.9932) (xy 136.733788 -351.9932) (xy 136.706522 -351.992637) (xy 136.652545 -351.984875)
			(xy 136.600222 -351.96951) (xy 136.550618 -351.946855) (xy 136.504744 -351.917372) (xy 136.463531 -351.88166)
			(xy 136.427821 -351.840447) (xy 136.398339 -351.794571) (xy 136.375686 -351.744967) (xy 136.360323 -351.692643)
			(xy 136.352562 -351.638666) (xy 134.869714 -351.638666) (xy 134.869714 -351.638671) (xy 134.861952 -351.692657)
			(xy 134.846586 -351.74499) (xy 134.82393 -351.794603) (xy 134.794444 -351.840487) (xy 134.758728 -351.881708)
			(xy 134.71751 -351.917427) (xy 134.671628 -351.946917) (xy 134.622016 -351.969577) (xy 134.569685 -351.984946)
			(xy 134.515699 -351.992712) (xy 134.488428 -351.9932) (xy 133.624828 -351.9932) (xy 133.597558 -351.992663)
			(xy 133.543574 -351.984904) (xy 133.491243 -351.969542) (xy 133.441631 -351.946888) (xy 133.395749 -351.917404)
			(xy 133.354529 -351.881691) (xy 133.318812 -351.840474) (xy 133.289325 -351.794593) (xy 133.266668 -351.744983)
			(xy 133.251302 -351.692654) (xy 133.243539 -351.63867) (xy 131.760836 -351.63867) (xy 131.760836 -351.638675)
			(xy 131.753073 -351.69267) (xy 131.737703 -351.745011) (xy 131.715041 -351.794631) (xy 131.685547 -351.840521)
			(xy 131.649823 -351.881746) (xy 131.608595 -351.917467) (xy 131.562703 -351.946956) (xy 131.513081 -351.969614)
			(xy 131.460739 -351.984979) (xy 131.406743 -351.992739) (xy 131.379468 -351.9932) (xy 130.515868 -351.9932)
			(xy 130.488603 -351.992635) (xy 130.434628 -351.984871) (xy 130.382308 -351.969504) (xy 130.332706 -351.946849)
			(xy 130.286834 -351.917365) (xy 130.245624 -351.881653) (xy 130.209916 -351.84044) (xy 130.180436 -351.794566)
			(xy 130.157784 -351.744962) (xy 130.142422 -351.692641) (xy 130.134662 -351.638665) (xy 128.651814 -351.638665)
			(xy 128.651814 -351.638672) (xy 128.644051 -351.69266) (xy 128.628685 -351.744994) (xy 128.606027 -351.794609)
			(xy 128.576539 -351.840494) (xy 128.540821 -351.881715) (xy 128.4996 -351.917434) (xy 128.453716 -351.946923)
			(xy 128.404102 -351.969582) (xy 128.351768 -351.98495) (xy 128.29778 -351.992713) (xy 128.270508 -351.9932)
			(xy 127.406908 -351.9932) (xy 127.379639 -351.992661) (xy 127.325657 -351.984901) (xy 127.273329 -351.969537)
			(xy 127.223719 -351.946882) (xy 127.177839 -351.917397) (xy 127.136622 -351.881683) (xy 127.100907 -351.840467)
			(xy 127.071422 -351.794588) (xy 127.048766 -351.744979) (xy 127.033401 -351.692651) (xy 127.025639 -351.638669)
			(xy 125.542814 -351.638669) (xy 125.542814 -351.63867) (xy 125.535052 -351.692655) (xy 125.519688 -351.744986)
			(xy 125.497033 -351.794597) (xy 125.467549 -351.840481) (xy 125.431835 -351.881701) (xy 125.390619 -351.91742)
			(xy 125.34474 -351.94691) (xy 125.295131 -351.969571) (xy 125.242802 -351.984942) (xy 125.188818 -351.99271)
			(xy 125.161548 -351.9932) (xy 124.297948 -351.9932) (xy 124.270677 -351.992664) (xy 124.216691 -351.984908)
			(xy 124.164358 -351.969547) (xy 124.114743 -351.946895) (xy 124.068858 -351.917411) (xy 124.027636 -351.881698)
			(xy 123.991917 -351.84048) (xy 123.962428 -351.794599) (xy 123.939769 -351.744987) (xy 123.924402 -351.692656)
			(xy 123.91664 -351.63867) (xy 122.433936 -351.63867) (xy 122.433936 -351.638674) (xy 122.426173 -351.692668)
			(xy 122.410805 -351.745006) (xy 122.388144 -351.794625) (xy 122.358652 -351.840514) (xy 122.32293 -351.881739)
			(xy 122.281704 -351.91746) (xy 122.235815 -351.94695) (xy 122.186195 -351.969609) (xy 122.133856 -351.984976)
			(xy 122.079862 -351.992737) (xy 122.052588 -351.9932) (xy 121.188988 -351.9932) (xy 121.161722 -351.992637)
			(xy 121.107745 -351.984875) (xy 121.055422 -351.96951) (xy 121.005818 -351.946855) (xy 120.959944 -351.917372)
			(xy 120.918731 -351.88166) (xy 120.883021 -351.840447) (xy 120.853539 -351.794571) (xy 120.830886 -351.744967)
			(xy 120.815523 -351.692643) (xy 120.807762 -351.638666) (xy 119.324914 -351.638666) (xy 119.324914 -351.638671)
			(xy 119.317152 -351.692657) (xy 119.301786 -351.74499) (xy 119.27913 -351.794603) (xy 119.249644 -351.840487)
			(xy 119.213928 -351.881708) (xy 119.17271 -351.917427) (xy 119.126828 -351.946917) (xy 119.077216 -351.969577)
			(xy 119.024885 -351.984946) (xy 118.970899 -351.992712) (xy 118.943628 -351.9932) (xy 118.080028 -351.9932)
			(xy 118.052758 -351.992663) (xy 117.998774 -351.984904) (xy 117.946443 -351.969542) (xy 117.896831 -351.946888)
			(xy 117.850949 -351.917404) (xy 117.809729 -351.881691) (xy 117.774012 -351.840474) (xy 117.744525 -351.794593)
			(xy 117.721868 -351.744983) (xy 117.706502 -351.692654) (xy 117.698739 -351.63867) (xy 116.216036 -351.63867)
			(xy 116.216036 -351.638675) (xy 116.208273 -351.69267) (xy 116.192903 -351.745011) (xy 116.170241 -351.794631)
			(xy 116.140747 -351.840521) (xy 116.105023 -351.881746) (xy 116.063795 -351.917467) (xy 116.017903 -351.946956)
			(xy 115.968281 -351.969614) (xy 115.915939 -351.984979) (xy 115.861943 -351.992739) (xy 115.834668 -351.9932)
			(xy 114.971068 -351.9932) (xy 114.943803 -351.992635) (xy 114.889828 -351.984871) (xy 114.837508 -351.969504)
			(xy 114.787906 -351.946849) (xy 114.742034 -351.917365) (xy 114.700824 -351.881653) (xy 114.665116 -351.84044)
			(xy 114.635636 -351.794566) (xy 114.612984 -351.744962) (xy 114.597622 -351.692641) (xy 114.589862 -351.638665)
			(xy 113.107014 -351.638665) (xy 113.107014 -351.638672) (xy 113.099251 -351.69266) (xy 113.083885 -351.744994)
			(xy 113.061227 -351.794609) (xy 113.031739 -351.840494) (xy 112.996021 -351.881715) (xy 112.9548 -351.917434)
			(xy 112.908916 -351.946923) (xy 112.859302 -351.969582) (xy 112.806968 -351.98495) (xy 112.75298 -351.992713)
			(xy 112.725708 -351.9932) (xy 111.862108 -351.9932) (xy 111.834839 -351.992661) (xy 111.780857 -351.984901)
			(xy 111.728529 -351.969537) (xy 111.678919 -351.946882) (xy 111.633039 -351.917397) (xy 111.591822 -351.881683)
			(xy 111.556107 -351.840467) (xy 111.526622 -351.794588) (xy 111.503966 -351.744979) (xy 111.488601 -351.692651)
			(xy 111.480839 -351.638669) (xy 93.706714 -351.638669) (xy 93.706714 -351.63867) (xy 93.698952 -351.692655)
			(xy 93.683588 -351.744987) (xy 93.660932 -351.794599) (xy 93.631447 -351.840483) (xy 93.595733 -351.881703)
			(xy 93.554516 -351.917422) (xy 93.508636 -351.946912) (xy 93.459026 -351.969573) (xy 93.406697 -351.984943)
			(xy 93.352712 -351.992711) (xy 93.325442 -351.9932) (xy 92.461842 -351.9932) (xy 92.434572 -351.992663)
			(xy 92.380586 -351.984907) (xy 92.328253 -351.969546) (xy 92.27864 -351.946893) (xy 92.232755 -351.917409)
			(xy 92.191534 -351.881695) (xy 92.155816 -351.840478) (xy 92.126327 -351.794597) (xy 92.103669 -351.744986)
			(xy 92.088302 -351.692655) (xy 92.08054 -351.63867) (xy 90.597836 -351.63867) (xy 90.597836 -351.638675)
			(xy 90.590073 -351.692668) (xy 90.574704 -351.745008) (xy 90.552043 -351.794627) (xy 90.522551 -351.840516)
			(xy 90.486828 -351.881741) (xy 90.445602 -351.917462) (xy 90.399711 -351.946952) (xy 90.350091 -351.969611)
			(xy 90.297751 -351.984977) (xy 90.243757 -351.992738) (xy 90.216482 -351.9932) (xy 89.352882 -351.9932)
			(xy 89.325616 -351.992636) (xy 89.27164 -351.984873) (xy 89.219318 -351.969508) (xy 89.169715 -351.946853)
			(xy 89.123841 -351.91737) (xy 89.082629 -351.881658) (xy 89.04692 -351.840445) (xy 89.017438 -351.794569)
			(xy 88.994786 -351.744965) (xy 88.979423 -351.692642) (xy 88.971662 -351.638666) (xy 87.488814 -351.638666)
			(xy 87.488814 -351.638671) (xy 87.481052 -351.692658) (xy 87.465686 -351.744991) (xy 87.443029 -351.794605)
			(xy 87.413542 -351.840489) (xy 87.377826 -351.88171) (xy 87.336607 -351.917429) (xy 87.290724 -351.946919)
			(xy 87.241112 -351.969578) (xy 87.18878 -351.984947) (xy 87.134793 -351.992712) (xy 87.107522 -351.9932)
			(xy 86.243922 -351.9932) (xy 86.216653 -351.992662) (xy 86.162669 -351.984903) (xy 86.110339 -351.96954)
			(xy 86.060728 -351.946886) (xy 86.014846 -351.917402) (xy 85.973627 -351.881688) (xy 85.937911 -351.840472)
			(xy 85.908424 -351.794592) (xy 85.885767 -351.744982) (xy 85.870401 -351.692653) (xy 85.862639 -351.638669)
			(xy 84.379936 -351.638669) (xy 84.379936 -351.638675) (xy 84.372172 -351.692671) (xy 84.356803 -351.745012)
			(xy 84.33414 -351.794633) (xy 84.304646 -351.840523) (xy 84.268921 -351.881748) (xy 84.227692 -351.917469)
			(xy 84.181799 -351.946958) (xy 84.132176 -351.969616) (xy 84.079834 -351.98498) (xy 84.025837 -351.992739)
			(xy 83.998562 -351.9932) (xy 83.134962 -351.9932) (xy 83.107697 -351.992635) (xy 83.053723 -351.98487)
			(xy 83.001403 -351.969503) (xy 82.951803 -351.946847) (xy 82.905931 -351.917363) (xy 82.864722 -351.881651)
			(xy 82.829015 -351.840438) (xy 82.799535 -351.794564) (xy 82.776884 -351.744961) (xy 82.761522 -351.69264)
			(xy 82.753762 -351.638665) (xy 81.270913 -351.638665) (xy 81.270913 -351.638672) (xy 81.263151 -351.692661)
			(xy 81.247784 -351.744995) (xy 81.225126 -351.79461) (xy 81.195637 -351.840496) (xy 81.159919 -351.881717)
			(xy 81.118697 -351.917436) (xy 81.072812 -351.946925) (xy 81.023197 -351.969584) (xy 80.970863 -351.984951)
			(xy 80.916874 -351.992713) (xy 80.889602 -351.9932) (xy 80.026002 -351.9932) (xy 79.998734 -351.992661)
			(xy 79.944752 -351.9849) (xy 79.892424 -351.969535) (xy 79.842816 -351.94688) (xy 79.796936 -351.917395)
			(xy 79.75572 -351.881681) (xy 79.720006 -351.840465) (xy 79.690521 -351.794586) (xy 79.667866 -351.744978)
			(xy 79.652501 -351.69265) (xy 79.644739 -351.638668) (xy 78.161914 -351.638668) (xy 78.161914 -351.63867)
			(xy 78.154152 -351.692655) (xy 78.138788 -351.744987) (xy 78.116132 -351.794599) (xy 78.086647 -351.840483)
			(xy 78.050933 -351.881703) (xy 78.009716 -351.917422) (xy 77.963836 -351.946912) (xy 77.914226 -351.969573)
			(xy 77.861897 -351.984943) (xy 77.807912 -351.992711) (xy 77.780642 -351.9932) (xy 76.917042 -351.9932)
			(xy 76.889772 -351.992663) (xy 76.835786 -351.984907) (xy 76.783453 -351.969546) (xy 76.73384 -351.946893)
			(xy 76.687955 -351.917409) (xy 76.646734 -351.881695) (xy 76.611016 -351.840478) (xy 76.581527 -351.794597)
			(xy 76.558869 -351.744986) (xy 76.543502 -351.692655) (xy 76.53574 -351.63867) (xy 75.053036 -351.63867)
			(xy 75.053036 -351.638675) (xy 75.045273 -351.692668) (xy 75.029904 -351.745008) (xy 75.007243 -351.794627)
			(xy 74.977751 -351.840516) (xy 74.942028 -351.881741) (xy 74.900802 -351.917462) (xy 74.854911 -351.946952)
			(xy 74.805291 -351.969611) (xy 74.752951 -351.984977) (xy 74.698957 -351.992738) (xy 74.671682 -351.9932)
			(xy 73.808082 -351.9932) (xy 73.780816 -351.992636) (xy 73.72684 -351.984873) (xy 73.674518 -351.969508)
			(xy 73.624915 -351.946853) (xy 73.579041 -351.91737) (xy 73.537829 -351.881658) (xy 73.50212 -351.840445)
			(xy 73.472638 -351.794569) (xy 73.449986 -351.744965) (xy 73.434623 -351.692642) (xy 73.426862 -351.638666)
			(xy 71.944014 -351.638666) (xy 71.944014 -351.638671) (xy 71.936252 -351.692658) (xy 71.920886 -351.744991)
			(xy 71.898229 -351.794605) (xy 71.868742 -351.840489) (xy 71.833026 -351.88171) (xy 71.791807 -351.917429)
			(xy 71.745924 -351.946919) (xy 71.696312 -351.969578) (xy 71.64398 -351.984947) (xy 71.589993 -351.992712)
			(xy 71.562722 -351.9932) (xy 70.699122 -351.9932) (xy 70.671853 -351.992662) (xy 70.617869 -351.984903)
			(xy 70.565539 -351.96954) (xy 70.515928 -351.946886) (xy 70.470046 -351.917402) (xy 70.428827 -351.881688)
			(xy 70.393111 -351.840472) (xy 70.363624 -351.794592) (xy 70.340967 -351.744982) (xy 70.325601 -351.692653)
			(xy 70.317839 -351.638669) (xy 68.835136 -351.638669) (xy 68.835136 -351.638675) (xy 68.827372 -351.692671)
			(xy 68.812003 -351.745012) (xy 68.78934 -351.794633) (xy 68.759846 -351.840523) (xy 68.724121 -351.881748)
			(xy 68.682892 -351.917469) (xy 68.636999 -351.946958) (xy 68.587376 -351.969616) (xy 68.535034 -351.98498)
			(xy 68.481037 -351.992739) (xy 68.453762 -351.9932) (xy 67.590162 -351.9932) (xy 67.562897 -351.992635)
			(xy 67.508923 -351.98487) (xy 67.456603 -351.969503) (xy 67.407003 -351.946847) (xy 67.361131 -351.917363)
			(xy 67.319922 -351.881651) (xy 67.284215 -351.840438) (xy 67.254735 -351.794564) (xy 67.232084 -351.744961)
			(xy 67.216722 -351.69264) (xy 67.208962 -351.638665) (xy 65.726113 -351.638665) (xy 65.726113 -351.638672)
			(xy 65.718351 -351.692661) (xy 65.702984 -351.744995) (xy 65.680326 -351.79461) (xy 65.650837 -351.840496)
			(xy 65.615119 -351.881717) (xy 65.573897 -351.917436) (xy 65.528012 -351.946925) (xy 65.478397 -351.969584)
			(xy 65.426063 -351.984951) (xy 65.372074 -351.992713) (xy 65.344802 -351.9932) (xy 64.481202 -351.9932)
			(xy 64.453934 -351.992661) (xy 64.399952 -351.9849) (xy 64.347624 -351.969535) (xy 64.298016 -351.94688)
			(xy 64.252136 -351.917395) (xy 64.21092 -351.881681) (xy 64.175206 -351.840465) (xy 64.145721 -351.794586)
			(xy 64.123066 -351.744978) (xy 64.107701 -351.69265) (xy 64.099939 -351.638668) (xy 62.617114 -351.638668)
			(xy 62.617114 -351.63867) (xy 62.609352 -351.692655) (xy 62.593988 -351.744987) (xy 62.571332 -351.794599)
			(xy 62.541847 -351.840483) (xy 62.506133 -351.881703) (xy 62.464916 -351.917422) (xy 62.419036 -351.946912)
			(xy 62.369426 -351.969573) (xy 62.317097 -351.984943) (xy 62.263112 -351.992711) (xy 62.235842 -351.9932)
			(xy 61.372242 -351.9932) (xy 61.344972 -351.992663) (xy 61.290986 -351.984907) (xy 61.238653 -351.969546)
			(xy 61.18904 -351.946893) (xy 61.143155 -351.917409) (xy 61.101934 -351.881695) (xy 61.066216 -351.840478)
			(xy 61.036727 -351.794597) (xy 61.014069 -351.744986) (xy 60.998702 -351.692655) (xy 60.99094 -351.63867)
			(xy 51.666914 -351.63867) (xy 51.659152 -351.692655) (xy 51.643788 -351.744986) (xy 51.621133 -351.794597)
			(xy 51.591649 -351.840481) (xy 51.555935 -351.881701) (xy 51.514719 -351.91742) (xy 51.46884 -351.94691)
			(xy 51.419231 -351.969571) (xy 51.366902 -351.984942) (xy 51.312918 -351.99271) (xy 51.285648 -351.9932)
			(xy 50.422048 -351.9932) (xy 50.394777 -351.992664) (xy 50.340791 -351.984908) (xy 50.288458 -351.969547)
			(xy 50.238843 -351.946895) (xy 50.192958 -351.917411) (xy 50.151736 -351.881698) (xy 50.116017 -351.84048)
			(xy 50.086528 -351.794599) (xy 50.063869 -351.744987) (xy 50.048502 -351.692656) (xy 50.04074 -351.63867)
			(xy 48.558036 -351.63867) (xy 48.558036 -351.638674) (xy 48.550273 -351.692668) (xy 48.534905 -351.745006)
			(xy 48.512244 -351.794625) (xy 48.482752 -351.840514) (xy 48.44703 -351.881739) (xy 48.405804 -351.91746)
			(xy 48.359915 -351.94695) (xy 48.310295 -351.969609) (xy 48.257956 -351.984976) (xy 48.203962 -351.992737)
			(xy 48.176688 -351.9932) (xy 47.313088 -351.9932) (xy 47.285822 -351.992637) (xy 47.231845 -351.984875)
			(xy 47.179522 -351.96951) (xy 47.129918 -351.946855) (xy 47.084044 -351.917372) (xy 47.042831 -351.88166)
			(xy 47.007121 -351.840447) (xy 46.977639 -351.794571) (xy 46.954986 -351.744967) (xy 46.939623 -351.692643)
			(xy 46.931862 -351.638666) (xy 45.449014 -351.638666) (xy 45.449014 -351.638671) (xy 45.441252 -351.692657)
			(xy 45.425886 -351.74499) (xy 45.40323 -351.794603) (xy 45.373744 -351.840487) (xy 45.338028 -351.881708)
			(xy 45.29681 -351.917427) (xy 45.250928 -351.946917) (xy 45.201316 -351.969577) (xy 45.148985 -351.984946)
			(xy 45.094999 -351.992712) (xy 45.067728 -351.9932) (xy 44.204128 -351.9932) (xy 44.176858 -351.992663)
			(xy 44.122874 -351.984904) (xy 44.070543 -351.969542) (xy 44.020931 -351.946888) (xy 43.975049 -351.917404)
			(xy 43.933829 -351.881691) (xy 43.898112 -351.840474) (xy 43.868625 -351.794593) (xy 43.845968 -351.744983)
			(xy 43.830602 -351.692654) (xy 43.822839 -351.63867) (xy 42.340136 -351.63867) (xy 42.340136 -351.638675)
			(xy 42.332373 -351.69267) (xy 42.317003 -351.745011) (xy 42.294341 -351.794631) (xy 42.264847 -351.840521)
			(xy 42.229123 -351.881746) (xy 42.187895 -351.917467) (xy 42.142003 -351.946956) (xy 42.092381 -351.969614)
			(xy 42.040039 -351.984979) (xy 41.986043 -351.992739) (xy 41.958768 -351.9932) (xy 41.095168 -351.9932)
			(xy 41.067903 -351.992635) (xy 41.013928 -351.984871) (xy 40.961608 -351.969504) (xy 40.912006 -351.946849)
			(xy 40.866134 -351.917365) (xy 40.824924 -351.881653) (xy 40.789216 -351.84044) (xy 40.759736 -351.794566)
			(xy 40.737084 -351.744962) (xy 40.721722 -351.692641) (xy 40.713962 -351.638665) (xy 39.231114 -351.638665)
			(xy 39.231114 -351.638672) (xy 39.223351 -351.69266) (xy 39.207985 -351.744994) (xy 39.185327 -351.794609)
			(xy 39.155839 -351.840494) (xy 39.120121 -351.881715) (xy 39.0789 -351.917434) (xy 39.033016 -351.946923)
			(xy 38.983402 -351.969582) (xy 38.931068 -351.98495) (xy 38.87708 -351.992713) (xy 38.849808 -351.9932)
			(xy 37.986208 -351.9932) (xy 37.958939 -351.992661) (xy 37.904957 -351.984901) (xy 37.852629 -351.969537)
			(xy 37.803019 -351.946882) (xy 37.757139 -351.917397) (xy 37.715922 -351.881683) (xy 37.680207 -351.840467)
			(xy 37.650722 -351.794588) (xy 37.628066 -351.744979) (xy 37.612701 -351.692651) (xy 37.604939 -351.638669)
			(xy 36.122114 -351.638669) (xy 36.122114 -351.63867) (xy 36.114352 -351.692655) (xy 36.098988 -351.744986)
			(xy 36.076333 -351.794597) (xy 36.046849 -351.840481) (xy 36.011135 -351.881701) (xy 35.969919 -351.91742)
			(xy 35.92404 -351.94691) (xy 35.874431 -351.969571) (xy 35.822102 -351.984942) (xy 35.768118 -351.99271)
			(xy 35.740848 -351.9932) (xy 34.877248 -351.9932) (xy 34.849977 -351.992664) (xy 34.795991 -351.984908)
			(xy 34.743658 -351.969547) (xy 34.694043 -351.946895) (xy 34.648158 -351.917411) (xy 34.606936 -351.881698)
			(xy 34.571217 -351.84048) (xy 34.541728 -351.794599) (xy 34.519069 -351.744987) (xy 34.503702 -351.692656)
			(xy 34.49594 -351.63867) (xy 33.013236 -351.63867) (xy 33.013236 -351.638674) (xy 33.005473 -351.692668)
			(xy 32.990105 -351.745006) (xy 32.967444 -351.794625) (xy 32.937952 -351.840514) (xy 32.90223 -351.881739)
			(xy 32.861004 -351.91746) (xy 32.815115 -351.94695) (xy 32.765495 -351.969609) (xy 32.713156 -351.984976)
			(xy 32.659162 -351.992737) (xy 32.631888 -351.9932) (xy 31.768288 -351.9932) (xy 31.741022 -351.992637)
			(xy 31.687045 -351.984875) (xy 31.634722 -351.96951) (xy 31.585118 -351.946855) (xy 31.539244 -351.917372)
			(xy 31.498031 -351.88166) (xy 31.462321 -351.840447) (xy 31.432839 -351.794571) (xy 31.410186 -351.744967)
			(xy 31.394823 -351.692643) (xy 31.387062 -351.638666) (xy 29.904214 -351.638666) (xy 29.904214 -351.638671)
			(xy 29.896452 -351.692657) (xy 29.881086 -351.74499) (xy 29.85843 -351.794603) (xy 29.828944 -351.840487)
			(xy 29.793228 -351.881708) (xy 29.75201 -351.917427) (xy 29.706128 -351.946917) (xy 29.656516 -351.969577)
			(xy 29.604185 -351.984946) (xy 29.550199 -351.992712) (xy 29.522928 -351.9932) (xy 28.659328 -351.9932)
			(xy 28.632058 -351.992663) (xy 28.578074 -351.984904) (xy 28.525743 -351.969542) (xy 28.476131 -351.946888)
			(xy 28.430249 -351.917404) (xy 28.389029 -351.881691) (xy 28.353312 -351.840474) (xy 28.323825 -351.794593)
			(xy 28.301168 -351.744983) (xy 28.285802 -351.692654) (xy 28.278039 -351.63867) (xy 26.795336 -351.63867)
			(xy 26.795336 -351.638675) (xy 26.787573 -351.69267) (xy 26.772203 -351.745011) (xy 26.749541 -351.794631)
			(xy 26.720047 -351.840521) (xy 26.684323 -351.881746) (xy 26.643095 -351.917467) (xy 26.597203 -351.946956)
			(xy 26.547581 -351.969614) (xy 26.495239 -351.984979) (xy 26.441243 -351.992739) (xy 26.413968 -351.9932)
			(xy 25.550368 -351.9932) (xy 25.523103 -351.992635) (xy 25.469128 -351.984871) (xy 25.416808 -351.969504)
			(xy 25.367206 -351.946849) (xy 25.321334 -351.917365) (xy 25.280124 -351.881653) (xy 25.244416 -351.84044)
			(xy 25.214936 -351.794566) (xy 25.192284 -351.744962) (xy 25.176922 -351.692641) (xy 25.169162 -351.638665)
			(xy 23.686314 -351.638665) (xy 23.686314 -351.638672) (xy 23.678551 -351.69266) (xy 23.663185 -351.744994)
			(xy 23.640527 -351.794609) (xy 23.611039 -351.840494) (xy 23.575321 -351.881715) (xy 23.5341 -351.917434)
			(xy 23.488216 -351.946923) (xy 23.438602 -351.969582) (xy 23.386268 -351.98495) (xy 23.33228 -351.992713)
			(xy 23.305008 -351.9932) (xy 22.441408 -351.9932) (xy 22.414139 -351.992661) (xy 22.360157 -351.984901)
			(xy 22.307829 -351.969537) (xy 22.258219 -351.946882) (xy 22.212339 -351.917397) (xy 22.171122 -351.881683)
			(xy 22.135407 -351.840467) (xy 22.105922 -351.794588) (xy 22.083266 -351.744979) (xy 22.067901 -351.692651)
			(xy 22.060139 -351.638669) (xy 20.577347 -351.638669) (xy 20.577347 -351.638711) (xy 20.569584 -351.692698)
			(xy 20.554218 -351.74503) (xy 20.53156 -351.794643) (xy 20.502073 -351.840527) (xy 20.466355 -351.881747)
			(xy 20.425135 -351.917464) (xy 20.379252 -351.946951) (xy 20.329638 -351.969609) (xy 20.277306 -351.984975)
			(xy 20.223319 -351.992737) (xy 20.196048 -351.9932) (xy 19.332448 -351.9932) (xy 19.305179 -351.992717)
			(xy 19.251195 -351.984955) (xy 19.198865 -351.96959) (xy 19.149255 -351.946933) (xy 19.103374 -351.917447)
			(xy 19.062157 -351.881732) (xy 19.026441 -351.840514) (xy 18.996956 -351.794633) (xy 18.974299 -351.745023)
			(xy 18.958934 -351.692693) (xy 18.951172 -351.638709) (xy 0.509016 -351.638709) (xy 0.509016 -354.759373)
			(xy 22.060084 -354.759373) (xy 22.060084 -354.704827) (xy 22.067846 -354.650837) (xy 22.083214 -354.598501)
			(xy 22.105873 -354.548885) (xy 22.135363 -354.502999) (xy 22.171083 -354.461777) (xy 22.212306 -354.426058)
			(xy 22.258192 -354.396569) (xy 22.307809 -354.373911) (xy 22.360145 -354.358545) (xy 22.414135 -354.350783)
			(xy 22.441408 -354.35032) (xy 23.305008 -354.35032) (xy 23.332276 -354.350843) (xy 23.386256 -354.358605)
			(xy 23.438582 -354.37397) (xy 23.488189 -354.396626) (xy 23.534067 -354.426111) (xy 23.575281 -354.461824)
			(xy 23.610994 -354.50304) (xy 23.640478 -354.548918) (xy 23.663132 -354.598525) (xy 23.678497 -354.650852)
			(xy 23.686258 -354.704832) (xy 23.686258 -354.759368) (xy 23.686258 -354.759369) (xy 25.169106 -354.759369)
			(xy 25.169106 -354.704831) (xy 25.176868 -354.650847) (xy 25.192232 -354.598518) (xy 25.214887 -354.548908)
			(xy 25.244371 -354.503026) (xy 25.280085 -354.461807) (xy 25.3213 -354.42609) (xy 25.36718 -354.396602)
			(xy 25.416788 -354.373943) (xy 25.469116 -354.358574) (xy 25.523099 -354.350809) (xy 25.550368 -354.35032)
			(xy 26.413968 -354.35032) (xy 26.441239 -354.350817) (xy 26.495227 -354.358575) (xy 26.547561 -354.373938)
			(xy 26.597176 -354.396593) (xy 26.643061 -354.426078) (xy 26.684283 -354.461794) (xy 26.720003 -354.503013)
			(xy 26.749492 -354.548896) (xy 26.772151 -354.598509) (xy 26.787518 -354.650842) (xy 26.79528 -354.704829)
			(xy 26.79528 -354.759371) (xy 26.79528 -354.759374) (xy 28.277984 -354.759374) (xy 28.277984 -354.704826)
			(xy 28.285747 -354.650835) (xy 28.301115 -354.598497) (xy 28.323776 -354.54888) (xy 28.353268 -354.502993)
			(xy 28.38899 -354.46177) (xy 28.430215 -354.426051) (xy 28.476104 -354.396562) (xy 28.525723 -354.373905)
			(xy 28.578062 -354.358541) (xy 28.632054 -354.350782) (xy 28.659328 -354.35032) (xy 29.522928 -354.35032)
			(xy 29.550195 -354.350844) (xy 29.604173 -354.358609) (xy 29.656497 -354.373976) (xy 29.706101 -354.396633)
			(xy 29.751976 -354.426118) (xy 29.793188 -354.461831) (xy 29.828899 -354.503046) (xy 29.858381 -354.548924)
			(xy 29.881034 -354.59853) (xy 29.896397 -354.650855) (xy 29.904158 -354.704833) (xy 29.904158 -354.759367)
			(xy 29.904158 -354.75937) (xy 31.387006 -354.75937) (xy 31.387006 -354.70483) (xy 31.394768 -354.650845)
			(xy 31.410134 -354.598514) (xy 31.43279 -354.548902) (xy 31.462276 -354.50302) (xy 31.497992 -354.4618)
			(xy 31.53921 -354.426083) (xy 31.585091 -354.396596) (xy 31.634703 -354.373938) (xy 31.687033 -354.358571)
			(xy 31.741018 -354.350807) (xy 31.768288 -354.35032) (xy 32.631888 -354.35032) (xy 32.659158 -354.350819)
			(xy 32.713144 -354.358579) (xy 32.765476 -354.373944) (xy 32.815088 -354.396599) (xy 32.860971 -354.426085)
			(xy 32.902191 -354.461801) (xy 32.937908 -354.503019) (xy 32.967395 -354.548902) (xy 32.990052 -354.598513)
			(xy 33.005418 -354.650844) (xy 33.013181 -354.70483) (xy 33.013181 -354.75937) (xy 33.01318 -354.759374)
			(xy 34.495884 -354.759374) (xy 34.495884 -354.704826) (xy 34.503647 -354.650832) (xy 34.519017 -354.598493)
			(xy 34.541679 -354.548874) (xy 34.571172 -354.502986) (xy 34.606897 -354.461763) (xy 34.648125 -354.426044)
			(xy 34.694016 -354.396556) (xy 34.743638 -354.3739) (xy 34.795979 -354.358537) (xy 34.849973 -354.35078)
			(xy 34.877248 -354.35032) (xy 35.740848 -354.35032) (xy 35.768114 -354.350846) (xy 35.82209 -354.358613)
			(xy 35.874411 -354.373981) (xy 35.924013 -354.396639) (xy 35.969886 -354.426125) (xy 36.011095 -354.461839)
			(xy 36.046804 -354.503053) (xy 36.076284 -354.548929) (xy 36.098936 -354.598534) (xy 36.114298 -354.650857)
			(xy 36.122058 -354.704834) (xy 36.122058 -354.759366) (xy 36.122057 -354.759373) (xy 37.604884 -354.759373)
			(xy 37.604884 -354.704827) (xy 37.612646 -354.650837) (xy 37.628014 -354.598501) (xy 37.650673 -354.548885)
			(xy 37.680163 -354.502999) (xy 37.715883 -354.461777) (xy 37.757106 -354.426058) (xy 37.802992 -354.396569)
			(xy 37.852609 -354.373911) (xy 37.904945 -354.358545) (xy 37.958935 -354.350783) (xy 37.986208 -354.35032)
			(xy 38.849808 -354.35032) (xy 38.877076 -354.350843) (xy 38.931056 -354.358605) (xy 38.983382 -354.37397)
			(xy 39.032989 -354.396626) (xy 39.078867 -354.426111) (xy 39.120081 -354.461824) (xy 39.155794 -354.50304)
			(xy 39.185278 -354.548918) (xy 39.207932 -354.598525) (xy 39.223297 -354.650852) (xy 39.231058 -354.704832)
			(xy 39.231058 -354.759368) (xy 39.231058 -354.759369) (xy 40.713906 -354.759369) (xy 40.713906 -354.704831)
			(xy 40.721668 -354.650847) (xy 40.737032 -354.598518) (xy 40.759687 -354.548908) (xy 40.789171 -354.503026)
			(xy 40.824885 -354.461807) (xy 40.8661 -354.42609) (xy 40.91198 -354.396602) (xy 40.961588 -354.373943)
			(xy 41.013916 -354.358574) (xy 41.067899 -354.350809) (xy 41.095168 -354.35032) (xy 41.958768 -354.35032)
			(xy 41.986039 -354.350817) (xy 42.040027 -354.358575) (xy 42.092361 -354.373938) (xy 42.141976 -354.396593)
			(xy 42.187861 -354.426078) (xy 42.229083 -354.461794) (xy 42.264803 -354.503013) (xy 42.294292 -354.548896)
			(xy 42.316951 -354.598509) (xy 42.332318 -354.650842) (xy 42.34008 -354.704829) (xy 42.34008 -354.759371)
			(xy 42.34008 -354.759374) (xy 43.822784 -354.759374) (xy 43.822784 -354.704826) (xy 43.830547 -354.650835)
			(xy 43.845915 -354.598497) (xy 43.868576 -354.54888) (xy 43.898068 -354.502993) (xy 43.93379 -354.46177)
			(xy 43.975015 -354.426051) (xy 44.020904 -354.396562) (xy 44.070523 -354.373905) (xy 44.122862 -354.358541)
			(xy 44.176854 -354.350782) (xy 44.204128 -354.35032) (xy 45.067728 -354.35032) (xy 45.094995 -354.350844)
			(xy 45.148973 -354.358609) (xy 45.201297 -354.373976) (xy 45.250901 -354.396633) (xy 45.296776 -354.426118)
			(xy 45.337988 -354.461831) (xy 45.373699 -354.503046) (xy 45.403181 -354.548924) (xy 45.425834 -354.59853)
			(xy 45.441197 -354.650855) (xy 45.448958 -354.704833) (xy 45.448958 -354.759367) (xy 45.448958 -354.75937)
			(xy 46.931806 -354.75937) (xy 46.931806 -354.70483) (xy 46.939568 -354.650845) (xy 46.954934 -354.598514)
			(xy 46.97759 -354.548902) (xy 47.007076 -354.50302) (xy 47.042792 -354.4618) (xy 47.08401 -354.426083)
			(xy 47.129891 -354.396596) (xy 47.179503 -354.373938) (xy 47.231833 -354.358571) (xy 47.285818 -354.350807)
			(xy 47.313088 -354.35032) (xy 48.176688 -354.35032) (xy 48.203958 -354.350819) (xy 48.257944 -354.358579)
			(xy 48.310276 -354.373944) (xy 48.359888 -354.396599) (xy 48.405771 -354.426085) (xy 48.446991 -354.461801)
			(xy 48.482708 -354.503019) (xy 48.512195 -354.548902) (xy 48.534852 -354.598513) (xy 48.550218 -354.650844)
			(xy 48.557981 -354.70483) (xy 48.557981 -354.75937) (xy 48.55798 -354.759374) (xy 50.040684 -354.759374)
			(xy 50.040684 -354.704826) (xy 50.048447 -354.650832) (xy 50.063817 -354.598493) (xy 50.086479 -354.548874)
			(xy 50.115972 -354.502986) (xy 50.151697 -354.461763) (xy 50.192925 -354.426044) (xy 50.238816 -354.396556)
			(xy 50.288438 -354.3739) (xy 50.340779 -354.358537) (xy 50.394773 -354.35078) (xy 50.422048 -354.35032)
			(xy 51.285648 -354.35032) (xy 51.312914 -354.350846) (xy 51.36689 -354.358613) (xy 51.419211 -354.373981)
			(xy 51.468813 -354.396639) (xy 51.514686 -354.426125) (xy 51.555895 -354.461839) (xy 51.591604 -354.503053)
			(xy 51.621084 -354.548929) (xy 51.643736 -354.598534) (xy 51.659098 -354.650857) (xy 51.666858 -354.704834)
			(xy 51.666858 -354.759366) (xy 51.666857 -354.759372) (xy 64.099884 -354.759372) (xy 64.099884 -354.704828)
			(xy 64.107646 -354.650838) (xy 64.123013 -354.598503) (xy 64.145672 -354.548887) (xy 64.175161 -354.503001)
			(xy 64.210881 -354.461779) (xy 64.252103 -354.42606) (xy 64.297989 -354.396571) (xy 64.347605 -354.373912)
			(xy 64.39994 -354.358546) (xy 64.45393 -354.350783) (xy 64.481202 -354.35032) (xy 65.344802 -354.35032)
			(xy 65.37207 -354.350843) (xy 65.426051 -354.358604) (xy 65.478378 -354.373969) (xy 65.527985 -354.396624)
			(xy 65.573864 -354.426109) (xy 65.615079 -354.461822) (xy 65.650793 -354.503038) (xy 65.680277 -354.548917)
			(xy 65.702932 -354.598524) (xy 65.718296 -354.650851) (xy 65.726058 -354.704832) (xy 65.726058 -354.759368)
			(xy 65.726058 -354.759369) (xy 67.208906 -354.759369) (xy 67.208906 -354.704831) (xy 67.216667 -354.650848)
			(xy 67.232032 -354.598519) (xy 67.254686 -354.548909) (xy 67.28417 -354.503028) (xy 67.319883 -354.46181)
			(xy 67.361098 -354.426093) (xy 67.406976 -354.396604) (xy 67.456584 -354.373945) (xy 67.508911 -354.358575)
			(xy 67.562893 -354.350809) (xy 67.590162 -354.35032) (xy 68.453762 -354.35032) (xy 68.481033 -354.350817)
			(xy 68.535022 -354.358574) (xy 68.587357 -354.373936) (xy 68.636972 -354.396591) (xy 68.682859 -354.426076)
			(xy 68.724081 -354.461792) (xy 68.759801 -354.503011) (xy 68.789291 -354.548894) (xy 68.81195 -354.598508)
			(xy 68.827318 -354.650841) (xy 68.83508 -354.704829) (xy 68.83508 -354.759371) (xy 68.83508 -354.759373)
			(xy 70.317784 -354.759373) (xy 70.317784 -354.704827) (xy 70.325547 -354.650835) (xy 70.340915 -354.598498)
			(xy 70.363575 -354.548882) (xy 70.393066 -354.502995) (xy 70.428788 -354.461772) (xy 70.470012 -354.426053)
			(xy 70.515901 -354.396564) (xy 70.565519 -354.373907) (xy 70.617857 -354.358542) (xy 70.671849 -354.350782)
			(xy 70.699122 -354.35032) (xy 71.562722 -354.35032) (xy 71.589989 -354.350844) (xy 71.643968 -354.358608)
			(xy 71.696292 -354.373974) (xy 71.745897 -354.396631) (xy 71.791773 -354.426116) (xy 71.832986 -354.461829)
			(xy 71.868697 -354.503044) (xy 71.89818 -354.548922) (xy 71.920833 -354.598528) (xy 71.936197 -354.650854)
			(xy 71.943958 -354.704833) (xy 71.943958 -354.759367) (xy 71.943958 -354.75937) (xy 73.426806 -354.75937)
			(xy 73.426806 -354.70483) (xy 73.434568 -354.650846) (xy 73.449933 -354.598515) (xy 73.472589 -354.548904)
			(xy 73.502075 -354.503022) (xy 73.53779 -354.461802) (xy 73.579007 -354.426085) (xy 73.624888 -354.396598)
			(xy 73.674498 -354.373939) (xy 73.726828 -354.358572) (xy 73.780812 -354.350808) (xy 73.808082 -354.35032)
			(xy 74.671682 -354.35032) (xy 74.698953 -354.350818) (xy 74.752939 -354.358578) (xy 74.805271 -354.373942)
			(xy 74.854884 -354.396597) (xy 74.900768 -354.426083) (xy 74.941988 -354.461799) (xy 74.977706 -354.503018)
			(xy 75.007194 -354.5489) (xy 75.029852 -354.598512) (xy 75.045218 -354.650844) (xy 75.052981 -354.704829)
			(xy 75.052981 -354.759371) (xy 75.052981 -354.759374) (xy 76.535684 -354.759374) (xy 76.535684 -354.704826)
			(xy 76.543447 -354.650833) (xy 76.558816 -354.598494) (xy 76.581478 -354.548876) (xy 76.610971 -354.502988)
			(xy 76.646695 -354.461765) (xy 76.687922 -354.426046) (xy 76.733813 -354.396558) (xy 76.783434 -354.373902)
			(xy 76.835774 -354.358538) (xy 76.889768 -354.350781) (xy 76.917042 -354.35032) (xy 77.780642 -354.35032)
			(xy 77.807908 -354.350845) (xy 77.861885 -354.358611) (xy 77.914207 -354.37398) (xy 77.963809 -354.396637)
			(xy 78.009683 -354.426123) (xy 78.050893 -354.461836) (xy 78.086602 -354.503051) (xy 78.116083 -354.548928)
			(xy 78.138735 -354.598533) (xy 78.154098 -354.650856) (xy 78.161858 -354.704834) (xy 78.161858 -354.759366)
			(xy 78.161857 -354.759372) (xy 79.644684 -354.759372) (xy 79.644684 -354.704828) (xy 79.652446 -354.650838)
			(xy 79.667813 -354.598503) (xy 79.690472 -354.548887) (xy 79.719961 -354.503001) (xy 79.755681 -354.461779)
			(xy 79.796903 -354.42606) (xy 79.842789 -354.396571) (xy 79.892405 -354.373912) (xy 79.94474 -354.358546)
			(xy 79.99873 -354.350783) (xy 80.026002 -354.35032) (xy 80.889602 -354.35032) (xy 80.91687 -354.350843)
			(xy 80.970851 -354.358604) (xy 81.023178 -354.373969) (xy 81.072785 -354.396624) (xy 81.118664 -354.426109)
			(xy 81.159879 -354.461822) (xy 81.195593 -354.503038) (xy 81.225077 -354.548917) (xy 81.247732 -354.598524)
			(xy 81.263096 -354.650851) (xy 81.270858 -354.704832) (xy 81.270858 -354.759368) (xy 81.270858 -354.759369)
			(xy 82.753706 -354.759369) (xy 82.753706 -354.704831) (xy 82.761467 -354.650848) (xy 82.776832 -354.598519)
			(xy 82.799486 -354.548909) (xy 82.82897 -354.503028) (xy 82.864683 -354.46181) (xy 82.905898 -354.426093)
			(xy 82.951776 -354.396604) (xy 83.001384 -354.373945) (xy 83.053711 -354.358575) (xy 83.107693 -354.350809)
			(xy 83.134962 -354.35032) (xy 83.998562 -354.35032) (xy 84.025833 -354.350817) (xy 84.079822 -354.358574)
			(xy 84.132157 -354.373936) (xy 84.181772 -354.396591) (xy 84.227659 -354.426076) (xy 84.268881 -354.461792)
			(xy 84.304601 -354.503011) (xy 84.334091 -354.548894) (xy 84.35675 -354.598508) (xy 84.372118 -354.650841)
			(xy 84.37988 -354.704829) (xy 84.37988 -354.759371) (xy 84.37988 -354.759373) (xy 85.862584 -354.759373)
			(xy 85.862584 -354.704827) (xy 85.870347 -354.650835) (xy 85.885715 -354.598498) (xy 85.908375 -354.548882)
			(xy 85.937866 -354.502995) (xy 85.973588 -354.461772) (xy 86.014812 -354.426053) (xy 86.060701 -354.396564)
			(xy 86.110319 -354.373907) (xy 86.162657 -354.358542) (xy 86.216649 -354.350782) (xy 86.243922 -354.35032)
			(xy 87.107522 -354.35032) (xy 87.134789 -354.350844) (xy 87.188768 -354.358608) (xy 87.241092 -354.373974)
			(xy 87.290697 -354.396631) (xy 87.336573 -354.426116) (xy 87.377786 -354.461829) (xy 87.413497 -354.503044)
			(xy 87.44298 -354.548922) (xy 87.465633 -354.598528) (xy 87.480997 -354.650854) (xy 87.488758 -354.704833)
			(xy 87.488758 -354.759367) (xy 87.488758 -354.75937) (xy 88.971606 -354.75937) (xy 88.971606 -354.70483)
			(xy 88.979368 -354.650846) (xy 88.994733 -354.598515) (xy 89.017389 -354.548904) (xy 89.046875 -354.503022)
			(xy 89.08259 -354.461802) (xy 89.123807 -354.426085) (xy 89.169688 -354.396598) (xy 89.219298 -354.373939)
			(xy 89.271628 -354.358572) (xy 89.325612 -354.350808) (xy 89.352882 -354.35032) (xy 90.216482 -354.35032)
			(xy 90.243753 -354.350818) (xy 90.297739 -354.358578) (xy 90.350071 -354.373942) (xy 90.399684 -354.396597)
			(xy 90.445568 -354.426083) (xy 90.486788 -354.461799) (xy 90.522506 -354.503018) (xy 90.551994 -354.5489)
			(xy 90.574652 -354.598512) (xy 90.590018 -354.650844) (xy 90.597781 -354.704829) (xy 90.597781 -354.759371)
			(xy 90.597781 -354.759374) (xy 92.080484 -354.759374) (xy 92.080484 -354.704826) (xy 92.088247 -354.650833)
			(xy 92.103616 -354.598494) (xy 92.126278 -354.548876) (xy 92.155771 -354.502988) (xy 92.191495 -354.461765)
			(xy 92.232722 -354.426046) (xy 92.278613 -354.396558) (xy 92.328234 -354.373902) (xy 92.380574 -354.358538)
			(xy 92.434568 -354.350781) (xy 92.461842 -354.35032) (xy 93.325442 -354.35032) (xy 93.352708 -354.350845)
			(xy 93.406685 -354.358611) (xy 93.459007 -354.37398) (xy 93.508609 -354.396637) (xy 93.554483 -354.426123)
			(xy 93.595693 -354.461836) (xy 93.631402 -354.503051) (xy 93.660883 -354.548928) (xy 93.683535 -354.598533)
			(xy 93.698898 -354.650856) (xy 93.706658 -354.704834) (xy 93.706658 -354.759366) (xy 93.706658 -354.759369)
			(xy 114.589806 -354.759369) (xy 114.589806 -354.704831) (xy 114.597568 -354.650847) (xy 114.612932 -354.598518)
			(xy 114.635587 -354.548908) (xy 114.665071 -354.503026) (xy 114.700785 -354.461807) (xy 114.742 -354.42609)
			(xy 114.78788 -354.396602) (xy 114.837488 -354.373943) (xy 114.889816 -354.358574) (xy 114.943799 -354.350809)
			(xy 114.971068 -354.35032) (xy 115.834668 -354.35032) (xy 115.861939 -354.350817) (xy 115.915927 -354.358575)
			(xy 115.968261 -354.373938) (xy 116.017876 -354.396593) (xy 116.063761 -354.426078) (xy 116.104983 -354.461794)
			(xy 116.140703 -354.503013) (xy 116.170192 -354.548896) (xy 116.192851 -354.598509) (xy 116.208218 -354.650842)
			(xy 116.21598 -354.704829) (xy 116.21598 -354.759371) (xy 116.21598 -354.759374) (xy 117.698684 -354.759374)
			(xy 117.698684 -354.704826) (xy 117.706447 -354.650835) (xy 117.721815 -354.598497) (xy 117.744476 -354.54888)
			(xy 117.773968 -354.502993) (xy 117.80969 -354.46177) (xy 117.850915 -354.426051) (xy 117.896804 -354.396562)
			(xy 117.946423 -354.373905) (xy 117.998762 -354.358541) (xy 118.052754 -354.350782) (xy 118.080028 -354.35032)
			(xy 118.943628 -354.35032) (xy 118.970895 -354.350844) (xy 119.024873 -354.358609) (xy 119.077197 -354.373976)
			(xy 119.126801 -354.396633) (xy 119.172676 -354.426118) (xy 119.213888 -354.461831) (xy 119.249599 -354.503046)
			(xy 119.279081 -354.548924) (xy 119.301734 -354.59853) (xy 119.317097 -354.650855) (xy 119.324858 -354.704833)
			(xy 119.324858 -354.759367) (xy 119.324858 -354.75937) (xy 120.807706 -354.75937) (xy 120.807706 -354.70483)
			(xy 120.815468 -354.650845) (xy 120.830834 -354.598514) (xy 120.85349 -354.548902) (xy 120.882976 -354.50302)
			(xy 120.918692 -354.4618) (xy 120.95991 -354.426083) (xy 121.005791 -354.396596) (xy 121.055403 -354.373938)
			(xy 121.107733 -354.358571) (xy 121.161718 -354.350807) (xy 121.188988 -354.35032) (xy 122.052588 -354.35032)
			(xy 122.079858 -354.350819) (xy 122.133844 -354.358579) (xy 122.186176 -354.373944) (xy 122.235788 -354.396599)
			(xy 122.281671 -354.426085) (xy 122.322891 -354.461801) (xy 122.358608 -354.503019) (xy 122.388095 -354.548902)
			(xy 122.410752 -354.598513) (xy 122.426118 -354.650844) (xy 122.433881 -354.70483) (xy 122.433881 -354.75937)
			(xy 122.43388 -354.759374) (xy 123.916584 -354.759374) (xy 123.916584 -354.704826) (xy 123.924347 -354.650832)
			(xy 123.939717 -354.598493) (xy 123.962379 -354.548874) (xy 123.991872 -354.502986) (xy 124.027597 -354.461763)
			(xy 124.068825 -354.426044) (xy 124.114716 -354.396556) (xy 124.164338 -354.3739) (xy 124.216679 -354.358537)
			(xy 124.270673 -354.35078) (xy 124.297948 -354.35032) (xy 125.161548 -354.35032) (xy 125.188814 -354.350846)
			(xy 125.24279 -354.358613) (xy 125.295111 -354.373981) (xy 125.344713 -354.396639) (xy 125.390586 -354.426125)
			(xy 125.431795 -354.461839) (xy 125.467504 -354.503053) (xy 125.496984 -354.548929) (xy 125.519636 -354.598534)
			(xy 125.534998 -354.650857) (xy 125.542758 -354.704834) (xy 125.542758 -354.759366) (xy 125.542757 -354.759373)
			(xy 127.025584 -354.759373) (xy 127.025584 -354.704827) (xy 127.033346 -354.650837) (xy 127.048714 -354.598501)
			(xy 127.071373 -354.548885) (xy 127.100863 -354.502999) (xy 127.136583 -354.461777) (xy 127.177806 -354.426058)
			(xy 127.223692 -354.396569) (xy 127.273309 -354.373911) (xy 127.325645 -354.358545) (xy 127.379635 -354.350783)
			(xy 127.406908 -354.35032) (xy 128.270508 -354.35032) (xy 128.297776 -354.350843) (xy 128.351756 -354.358605)
			(xy 128.404082 -354.37397) (xy 128.453689 -354.396626) (xy 128.499567 -354.426111) (xy 128.540781 -354.461824)
			(xy 128.576494 -354.50304) (xy 128.605978 -354.548918) (xy 128.628632 -354.598525) (xy 128.643997 -354.650852)
			(xy 128.651758 -354.704832) (xy 128.651758 -354.759368) (xy 128.651758 -354.759369) (xy 130.134606 -354.759369)
			(xy 130.134606 -354.704831) (xy 130.142368 -354.650847) (xy 130.157732 -354.598518) (xy 130.180387 -354.548908)
			(xy 130.209871 -354.503026) (xy 130.245585 -354.461807) (xy 130.2868 -354.42609) (xy 130.33268 -354.396602)
			(xy 130.382288 -354.373943) (xy 130.434616 -354.358574) (xy 130.488599 -354.350809) (xy 130.515868 -354.35032)
			(xy 131.379468 -354.35032) (xy 131.406739 -354.350817) (xy 131.460727 -354.358575) (xy 131.513061 -354.373938)
			(xy 131.562676 -354.396593) (xy 131.608561 -354.426078) (xy 131.649783 -354.461794) (xy 131.685503 -354.503013)
			(xy 131.714992 -354.548896) (xy 131.737651 -354.598509) (xy 131.753018 -354.650842) (xy 131.76078 -354.704829)
			(xy 131.76078 -354.759371) (xy 131.76078 -354.759374) (xy 133.243484 -354.759374) (xy 133.243484 -354.704826)
			(xy 133.251247 -354.650835) (xy 133.266615 -354.598497) (xy 133.289276 -354.54888) (xy 133.318768 -354.502993)
			(xy 133.35449 -354.46177) (xy 133.395715 -354.426051) (xy 133.441604 -354.396562) (xy 133.491223 -354.373905)
			(xy 133.543562 -354.358541) (xy 133.597554 -354.350782) (xy 133.624828 -354.35032) (xy 134.488428 -354.35032)
			(xy 134.515695 -354.350844) (xy 134.569673 -354.358609) (xy 134.621997 -354.373976) (xy 134.671601 -354.396633)
			(xy 134.717476 -354.426118) (xy 134.758688 -354.461831) (xy 134.794399 -354.503046) (xy 134.823881 -354.548924)
			(xy 134.846534 -354.59853) (xy 134.861897 -354.650855) (xy 134.869658 -354.704833) (xy 134.869658 -354.759367)
			(xy 134.869658 -354.75937) (xy 136.352506 -354.75937) (xy 136.352506 -354.70483) (xy 136.360268 -354.650845)
			(xy 136.375634 -354.598514) (xy 136.39829 -354.548902) (xy 136.427776 -354.50302) (xy 136.463492 -354.4618)
			(xy 136.50471 -354.426083) (xy 136.550591 -354.396596) (xy 136.600203 -354.373938) (xy 136.652533 -354.358571)
			(xy 136.706518 -354.350807) (xy 136.733788 -354.35032) (xy 137.597388 -354.35032) (xy 137.624658 -354.350819)
			(xy 137.678644 -354.358579) (xy 137.730976 -354.373944) (xy 137.780588 -354.396599) (xy 137.826471 -354.426085)
			(xy 137.867691 -354.461801) (xy 137.903408 -354.503019) (xy 137.932895 -354.548902) (xy 137.955552 -354.598513)
			(xy 137.970918 -354.650844) (xy 137.978681 -354.70483) (xy 137.978681 -354.75937) (xy 137.97868 -354.759374)
			(xy 139.461384 -354.759374) (xy 139.461384 -354.704826) (xy 139.469147 -354.650832) (xy 139.484517 -354.598493)
			(xy 139.507179 -354.548874) (xy 139.536672 -354.502986) (xy 139.572397 -354.461763) (xy 139.613625 -354.426044)
			(xy 139.659516 -354.396556) (xy 139.709138 -354.3739) (xy 139.761479 -354.358537) (xy 139.815473 -354.35078)
			(xy 139.842748 -354.35032) (xy 140.706348 -354.35032) (xy 140.733614 -354.350846) (xy 140.78759 -354.358613)
			(xy 140.839911 -354.373981) (xy 140.889513 -354.396639) (xy 140.935386 -354.426125) (xy 140.976595 -354.461839)
			(xy 141.012304 -354.503053) (xy 141.041784 -354.548929) (xy 141.064436 -354.598534) (xy 141.079798 -354.650857)
			(xy 141.087558 -354.704834) (xy 141.087558 -354.759366) (xy 141.087557 -354.759373) (xy 142.570384 -354.759373)
			(xy 142.570384 -354.704827) (xy 142.578146 -354.650837) (xy 142.593514 -354.598501) (xy 142.616173 -354.548885)
			(xy 142.645663 -354.502999) (xy 142.681383 -354.461777) (xy 142.722606 -354.426058) (xy 142.768492 -354.396569)
			(xy 142.818109 -354.373911) (xy 142.870445 -354.358545) (xy 142.924435 -354.350783) (xy 142.951708 -354.35032)
			(xy 143.815308 -354.35032) (xy 143.842576 -354.350843) (xy 143.896556 -354.358605) (xy 143.948882 -354.37397)
			(xy 143.998489 -354.396626) (xy 144.044367 -354.426111) (xy 144.085581 -354.461824) (xy 144.121294 -354.50304)
			(xy 144.150778 -354.548918) (xy 144.173432 -354.598525) (xy 144.188797 -354.650852) (xy 144.196558 -354.704832)
			(xy 144.196558 -354.759368) (xy 158.695906 -354.759368) (xy 158.695906 -354.704832) (xy 158.703667 -354.65085)
			(xy 158.719031 -354.598521) (xy 158.741685 -354.548912) (xy 158.771167 -354.503031) (xy 158.806879 -354.461813)
			(xy 158.848093 -354.426096) (xy 158.89397 -354.396608) (xy 158.943576 -354.373948) (xy 158.995903 -354.358577)
			(xy 159.049884 -354.35081) (xy 159.077152 -354.35032) (xy 159.940752 -354.35032) (xy 159.968024 -354.350816)
			(xy 160.022013 -354.358572) (xy 160.074349 -354.373934) (xy 160.123966 -354.396588) (xy 160.169854 -354.426072)
			(xy 160.211078 -354.461788) (xy 160.246799 -354.503008) (xy 160.276289 -354.548891) (xy 160.298949 -354.598506)
			(xy 160.314317 -354.65084) (xy 160.32208 -354.704828) (xy 160.32208 -354.759372) (xy 160.32208 -354.759373)
			(xy 161.804784 -354.759373) (xy 161.804784 -354.704827) (xy 161.812546 -354.650837) (xy 161.827914 -354.598501)
			(xy 161.850573 -354.548884) (xy 161.880064 -354.502998) (xy 161.915784 -354.461776) (xy 161.957008 -354.426056)
			(xy 162.002895 -354.396568) (xy 162.052512 -354.37391) (xy 162.104848 -354.358544) (xy 162.158839 -354.350783)
			(xy 162.186112 -354.35032) (xy 163.049712 -354.35032) (xy 163.07698 -354.350843) (xy 163.130959 -354.358606)
			(xy 163.183285 -354.373972) (xy 163.232891 -354.396627) (xy 163.278768 -354.426112) (xy 163.319983 -354.461826)
			(xy 163.355695 -354.503041) (xy 163.385178 -354.548919) (xy 163.407833 -354.598526) (xy 163.423197 -354.650852)
			(xy 163.430958 -354.704832) (xy 163.430958 -354.759368) (xy 163.430958 -354.759369) (xy 164.913806 -354.759369)
			(xy 164.913806 -354.704831) (xy 164.921568 -354.650847) (xy 164.936932 -354.598517) (xy 164.959588 -354.548907)
			(xy 164.989072 -354.503025) (xy 165.024786 -354.461806) (xy 165.066002 -354.426089) (xy 165.111882 -354.396601)
			(xy 165.161491 -354.373942) (xy 165.21382 -354.358574) (xy 165.267803 -354.350808) (xy 165.295072 -354.35032)
			(xy 166.158672 -354.35032) (xy 166.185943 -354.350818) (xy 166.23993 -354.358576) (xy 166.292264 -354.373939)
			(xy 166.341878 -354.396594) (xy 166.387763 -354.42608) (xy 166.428985 -354.461795) (xy 166.464704 -354.503014)
			(xy 166.494192 -354.548897) (xy 166.516851 -354.59851) (xy 166.532218 -354.650842) (xy 166.53998 -354.704829)
			(xy 166.53998 -354.759371) (xy 166.53998 -354.759374) (xy 168.022684 -354.759374) (xy 168.022684 -354.704826)
			(xy 168.030447 -354.650834) (xy 168.045816 -354.598496) (xy 168.068477 -354.548879) (xy 168.097969 -354.502991)
			(xy 168.133691 -354.461768) (xy 168.174917 -354.426049) (xy 168.220807 -354.396561) (xy 168.270426 -354.373904)
			(xy 168.322765 -354.35854) (xy 168.376758 -354.350781) (xy 168.404032 -354.35032) (xy 169.267632 -354.35032)
			(xy 169.294899 -354.350845) (xy 169.348876 -354.35861) (xy 169.401199 -354.373977) (xy 169.450803 -354.396634)
			(xy 169.496678 -354.426119) (xy 169.53789 -354.461833) (xy 169.5736 -354.503048) (xy 169.603081 -354.548925)
			(xy 169.625734 -354.598531) (xy 169.641097 -354.650855) (xy 169.648858 -354.704833) (xy 169.648858 -354.759367)
			(xy 169.648858 -354.75937) (xy 171.131706 -354.75937) (xy 171.131706 -354.70483) (xy 171.139468 -354.650844)
			(xy 171.154834 -354.598513) (xy 171.177491 -354.548901) (xy 171.206977 -354.503018) (xy 171.242693 -354.461799)
			(xy 171.283912 -354.426082) (xy 171.329794 -354.396594) (xy 171.379405 -354.373937) (xy 171.431736 -354.35857)
			(xy 171.485722 -354.350807) (xy 171.512992 -354.35032) (xy 172.376592 -354.35032) (xy 172.403862 -354.350819)
			(xy 172.457847 -354.35858) (xy 172.510178 -354.373945) (xy 172.55979 -354.396601) (xy 172.605673 -354.426087)
			(xy 172.646892 -354.461802) (xy 172.682609 -354.503021) (xy 172.712096 -354.548903) (xy 172.734753 -354.598514)
			(xy 172.750119 -354.650845) (xy 172.757881 -354.70483) (xy 172.757881 -354.759368) (xy 174.240706 -354.759368)
			(xy 174.240706 -354.704832) (xy 174.248467 -354.65085) (xy 174.263831 -354.598521) (xy 174.286485 -354.548912)
			(xy 174.315967 -354.503031) (xy 174.351679 -354.461813) (xy 174.392893 -354.426096) (xy 174.43877 -354.396608)
			(xy 174.488376 -354.373948) (xy 174.540703 -354.358577) (xy 174.594684 -354.35081) (xy 174.621952 -354.35032)
			(xy 175.485552 -354.35032) (xy 175.512824 -354.350816) (xy 175.566813 -354.358572) (xy 175.619149 -354.373934)
			(xy 175.668766 -354.396588) (xy 175.714654 -354.426072) (xy 175.755878 -354.461788) (xy 175.791599 -354.503008)
			(xy 175.821089 -354.548891) (xy 175.843749 -354.598506) (xy 175.859117 -354.65084) (xy 175.86688 -354.704828)
			(xy 175.86688 -354.759372) (xy 175.86688 -354.759373) (xy 177.349584 -354.759373) (xy 177.349584 -354.704827)
			(xy 177.357346 -354.650837) (xy 177.372714 -354.598501) (xy 177.395373 -354.548884) (xy 177.424864 -354.502998)
			(xy 177.460584 -354.461776) (xy 177.501808 -354.426056) (xy 177.547695 -354.396568) (xy 177.597312 -354.37391)
			(xy 177.649648 -354.358544) (xy 177.703639 -354.350783) (xy 177.730912 -354.35032) (xy 178.594512 -354.35032)
			(xy 178.62178 -354.350843) (xy 178.675759 -354.358606) (xy 178.728085 -354.373972) (xy 178.777691 -354.396627)
			(xy 178.823568 -354.426112) (xy 178.864783 -354.461826) (xy 178.900495 -354.503041) (xy 178.929978 -354.548919)
			(xy 178.952633 -354.598526) (xy 178.967997 -354.650852) (xy 178.975758 -354.704832) (xy 178.975758 -354.759368)
			(xy 178.975758 -354.759369) (xy 180.458606 -354.759369) (xy 180.458606 -354.704831) (xy 180.466368 -354.650847)
			(xy 180.481732 -354.598517) (xy 180.504388 -354.548907) (xy 180.533872 -354.503025) (xy 180.569586 -354.461806)
			(xy 180.610802 -354.426089) (xy 180.656682 -354.396601) (xy 180.706291 -354.373942) (xy 180.75862 -354.358574)
			(xy 180.812603 -354.350808) (xy 180.839872 -354.35032) (xy 181.703472 -354.35032) (xy 181.730743 -354.350818)
			(xy 181.78473 -354.358576) (xy 181.837064 -354.373939) (xy 181.886678 -354.396594) (xy 181.932563 -354.42608)
			(xy 181.973785 -354.461795) (xy 182.009504 -354.503014) (xy 182.038992 -354.548897) (xy 182.061651 -354.59851)
			(xy 182.077018 -354.650842) (xy 182.08478 -354.704829) (xy 182.08478 -354.735472) (xy 183.567508 -354.735472)
			(xy 183.567508 -354.680928) (xy 183.57527 -354.626939) (xy 183.590638 -354.574605) (xy 183.613298 -354.52499)
			(xy 183.642788 -354.479106) (xy 183.678508 -354.437885) (xy 183.719731 -354.402169) (xy 183.765618 -354.372682)
			(xy 183.815235 -354.350027) (xy 183.86757 -354.334664) (xy 183.92156 -354.326905) (xy 183.948832 -354.326444)
			(xy 184.812432 -354.326444) (xy 184.8397 -354.326921) (xy 184.893681 -354.334686) (xy 184.946008 -354.350054)
			(xy 184.995615 -354.372713) (xy 185.041492 -354.4022) (xy 185.082707 -354.437916) (xy 185.118419 -354.479133)
			(xy 185.147903 -354.525013) (xy 185.170557 -354.574622) (xy 185.185921 -354.62695) (xy 185.193682 -354.680932)
			(xy 185.193682 -354.735468) (xy 185.193682 -354.735469) (xy 186.67653 -354.735469) (xy 186.67653 -354.680931)
			(xy 186.684292 -354.626949) (xy 186.699656 -354.574621) (xy 186.722312 -354.525012) (xy 186.751796 -354.479133)
			(xy 186.78751 -354.437916) (xy 186.828726 -354.402201) (xy 186.874605 -354.372716) (xy 186.924214 -354.350059)
			(xy 186.976542 -354.334693) (xy 187.030523 -354.326931) (xy 187.057792 -354.326444) (xy 187.921392 -354.326444)
			(xy 187.948664 -354.326895) (xy 188.002652 -354.334656) (xy 188.054987 -354.350022) (xy 188.104602 -354.37268)
			(xy 188.150487 -354.402167) (xy 188.191709 -354.437885) (xy 188.227428 -354.479106) (xy 188.256917 -354.524991)
			(xy 188.279575 -354.574606) (xy 188.294942 -354.62694) (xy 188.302704 -354.680928) (xy 188.302704 -354.735472)
			(xy 188.299268 -354.759369) (xy 270.624806 -354.759369) (xy 270.624806 -354.704831) (xy 270.632567 -354.650848)
			(xy 270.647932 -354.598519) (xy 270.670586 -354.548909) (xy 270.70007 -354.503028) (xy 270.735783 -354.46181)
			(xy 270.776998 -354.426093) (xy 270.822876 -354.396604) (xy 270.872484 -354.373945) (xy 270.924811 -354.358575)
			(xy 270.978793 -354.350809) (xy 271.006062 -354.35032) (xy 271.869662 -354.35032) (xy 271.896933 -354.350817)
			(xy 271.950922 -354.358574) (xy 272.003257 -354.373936) (xy 272.052872 -354.396591) (xy 272.098759 -354.426076)
			(xy 272.139981 -354.461792) (xy 272.175701 -354.503011) (xy 272.205191 -354.548894) (xy 272.22785 -354.598508)
			(xy 272.243218 -354.650841) (xy 272.25098 -354.704829) (xy 272.25098 -354.759371) (xy 272.25098 -354.759373)
			(xy 273.733684 -354.759373) (xy 273.733684 -354.704827) (xy 273.741447 -354.650835) (xy 273.756815 -354.598498)
			(xy 273.779475 -354.548882) (xy 273.808966 -354.502995) (xy 273.844688 -354.461772) (xy 273.885912 -354.426053)
			(xy 273.931801 -354.396564) (xy 273.981419 -354.373907) (xy 274.033757 -354.358542) (xy 274.087749 -354.350782)
			(xy 274.115022 -354.35032) (xy 274.978622 -354.35032) (xy 275.005889 -354.350844) (xy 275.059868 -354.358608)
			(xy 275.112192 -354.373974) (xy 275.161797 -354.396631) (xy 275.207673 -354.426116) (xy 275.248886 -354.461829)
			(xy 275.284597 -354.503044) (xy 275.31408 -354.548922) (xy 275.336733 -354.598528) (xy 275.352097 -354.650854)
			(xy 275.359858 -354.704833) (xy 275.359858 -354.759367) (xy 275.359858 -354.75937) (xy 276.842706 -354.75937)
			(xy 276.842706 -354.70483) (xy 276.850468 -354.650846) (xy 276.865833 -354.598515) (xy 276.888489 -354.548904)
			(xy 276.917975 -354.503022) (xy 276.95369 -354.461802) (xy 276.994907 -354.426085) (xy 277.040788 -354.396598)
			(xy 277.090398 -354.373939) (xy 277.142728 -354.358572) (xy 277.196712 -354.350808) (xy 277.223982 -354.35032)
			(xy 278.087582 -354.35032) (xy 278.114853 -354.350818) (xy 278.168839 -354.358578) (xy 278.221171 -354.373942)
			(xy 278.270784 -354.396597) (xy 278.316668 -354.426083) (xy 278.357888 -354.461799) (xy 278.393606 -354.503018)
			(xy 278.423094 -354.5489) (xy 278.445752 -354.598512) (xy 278.461118 -354.650844) (xy 278.468881 -354.704829)
			(xy 278.468881 -354.759371) (xy 278.468881 -354.759374) (xy 279.951584 -354.759374) (xy 279.951584 -354.704826)
			(xy 279.959347 -354.650833) (xy 279.974716 -354.598494) (xy 279.997378 -354.548876) (xy 280.026871 -354.502988)
			(xy 280.062595 -354.461765) (xy 280.103822 -354.426046) (xy 280.149713 -354.396558) (xy 280.199334 -354.373902)
			(xy 280.251674 -354.358538) (xy 280.305668 -354.350781) (xy 280.332942 -354.35032) (xy 281.196542 -354.35032)
			(xy 281.223808 -354.350845) (xy 281.277785 -354.358611) (xy 281.330107 -354.37398) (xy 281.379709 -354.396637)
			(xy 281.425583 -354.426123) (xy 281.466793 -354.461836) (xy 281.502502 -354.503051) (xy 281.531983 -354.548928)
			(xy 281.554635 -354.598533) (xy 281.569998 -354.650856) (xy 281.577758 -354.704834) (xy 281.577758 -354.759366)
			(xy 281.577757 -354.759372) (xy 283.060584 -354.759372) (xy 283.060584 -354.704828) (xy 283.068346 -354.650838)
			(xy 283.083713 -354.598503) (xy 283.106372 -354.548887) (xy 283.135861 -354.503001) (xy 283.171581 -354.461779)
			(xy 283.212803 -354.42606) (xy 283.258689 -354.396571) (xy 283.308305 -354.373912) (xy 283.36064 -354.358546)
			(xy 283.41463 -354.350783) (xy 283.441902 -354.35032) (xy 284.305502 -354.35032) (xy 284.33277 -354.350843)
			(xy 284.386751 -354.358604) (xy 284.439078 -354.373969) (xy 284.488685 -354.396624) (xy 284.534564 -354.426109)
			(xy 284.575779 -354.461822) (xy 284.611493 -354.503038) (xy 284.640977 -354.548917) (xy 284.663632 -354.598524)
			(xy 284.678996 -354.650851) (xy 284.686758 -354.704832) (xy 284.686758 -354.759368) (xy 284.686758 -354.759369)
			(xy 286.169606 -354.759369) (xy 286.169606 -354.704831) (xy 286.177367 -354.650848) (xy 286.192732 -354.598519)
			(xy 286.215386 -354.548909) (xy 286.24487 -354.503028) (xy 286.280583 -354.46181) (xy 286.321798 -354.426093)
			(xy 286.367676 -354.396604) (xy 286.417284 -354.373945) (xy 286.469611 -354.358575) (xy 286.523593 -354.350809)
			(xy 286.550862 -354.35032) (xy 287.414462 -354.35032) (xy 287.441733 -354.350817) (xy 287.495722 -354.358574)
			(xy 287.548057 -354.373936) (xy 287.597672 -354.396591) (xy 287.643559 -354.426076) (xy 287.684781 -354.461792)
			(xy 287.720501 -354.503011) (xy 287.749991 -354.548894) (xy 287.77265 -354.598508) (xy 287.788018 -354.650841)
			(xy 287.79578 -354.704829) (xy 287.79578 -354.759371) (xy 287.79578 -354.759373) (xy 289.278484 -354.759373)
			(xy 289.278484 -354.704827) (xy 289.286247 -354.650835) (xy 289.301615 -354.598498) (xy 289.324275 -354.548882)
			(xy 289.353766 -354.502995) (xy 289.389488 -354.461772) (xy 289.430712 -354.426053) (xy 289.476601 -354.396564)
			(xy 289.526219 -354.373907) (xy 289.578557 -354.358542) (xy 289.632549 -354.350782) (xy 289.659822 -354.35032)
			(xy 290.523422 -354.35032) (xy 290.550689 -354.350844) (xy 290.604668 -354.358608) (xy 290.656992 -354.373974)
			(xy 290.706597 -354.396631) (xy 290.752473 -354.426116) (xy 290.793686 -354.461829) (xy 290.829397 -354.503044)
			(xy 290.85888 -354.548922) (xy 290.881533 -354.598528) (xy 290.896897 -354.650854) (xy 290.904658 -354.704833)
			(xy 290.904658 -354.759367) (xy 290.904658 -354.75937) (xy 292.387506 -354.75937) (xy 292.387506 -354.70483)
			(xy 292.395268 -354.650846) (xy 292.410633 -354.598515) (xy 292.433289 -354.548904) (xy 292.462775 -354.503022)
			(xy 292.49849 -354.461802) (xy 292.539707 -354.426085) (xy 292.585588 -354.396598) (xy 292.635198 -354.373939)
			(xy 292.687528 -354.358572) (xy 292.741512 -354.350808) (xy 292.768782 -354.35032) (xy 293.632382 -354.35032)
			(xy 293.659653 -354.350818) (xy 293.713639 -354.358578) (xy 293.765971 -354.373942) (xy 293.815584 -354.396597)
			(xy 293.861468 -354.426083) (xy 293.902688 -354.461799) (xy 293.938406 -354.503018) (xy 293.967894 -354.5489)
			(xy 293.990552 -354.598512) (xy 294.005918 -354.650844) (xy 294.013681 -354.704829) (xy 294.013681 -354.759371)
			(xy 294.013681 -354.759374) (xy 295.496384 -354.759374) (xy 295.496384 -354.704826) (xy 295.504147 -354.650833)
			(xy 295.519516 -354.598494) (xy 295.542178 -354.548876) (xy 295.571671 -354.502988) (xy 295.607395 -354.461765)
			(xy 295.648622 -354.426046) (xy 295.694513 -354.396558) (xy 295.744134 -354.373902) (xy 295.796474 -354.358538)
			(xy 295.850468 -354.350781) (xy 295.877742 -354.35032) (xy 296.741342 -354.35032) (xy 296.768608 -354.350845)
			(xy 296.822585 -354.358611) (xy 296.874907 -354.37398) (xy 296.924509 -354.396637) (xy 296.970383 -354.426123)
			(xy 297.011593 -354.461836) (xy 297.047302 -354.503051) (xy 297.076783 -354.548928) (xy 297.099435 -354.598533)
			(xy 297.114798 -354.650856) (xy 297.122558 -354.704834) (xy 297.122558 -354.759366) (xy 297.122557 -354.759372)
			(xy 298.605384 -354.759372) (xy 298.605384 -354.704828) (xy 298.613146 -354.650838) (xy 298.628513 -354.598503)
			(xy 298.651172 -354.548887) (xy 298.680661 -354.503001) (xy 298.716381 -354.461779) (xy 298.757603 -354.42606)
			(xy 298.803489 -354.396571) (xy 298.853105 -354.373912) (xy 298.90544 -354.358546) (xy 298.95943 -354.350783)
			(xy 298.986702 -354.35032) (xy 299.850302 -354.35032) (xy 299.87757 -354.350843) (xy 299.931551 -354.358604)
			(xy 299.983878 -354.373969) (xy 300.033485 -354.396624) (xy 300.079364 -354.426109) (xy 300.120579 -354.461822)
			(xy 300.156293 -354.503038) (xy 300.185777 -354.548917) (xy 300.208432 -354.598524) (xy 300.223796 -354.650851)
			(xy 300.231558 -354.704832) (xy 300.231558 -354.759368) (xy 300.231558 -354.759369) (xy 315.230506 -354.759369)
			(xy 315.230506 -354.704831) (xy 315.238267 -354.650848) (xy 315.253632 -354.598519) (xy 315.276286 -354.548909)
			(xy 315.30577 -354.503027) (xy 315.341483 -354.461809) (xy 315.382699 -354.426092) (xy 315.428577 -354.396604)
			(xy 315.478185 -354.373944) (xy 315.530513 -354.358575) (xy 315.584495 -354.350809) (xy 315.611764 -354.35032)
			(xy 316.475364 -354.35032) (xy 316.502635 -354.350817) (xy 316.556624 -354.358575) (xy 316.608958 -354.373937)
			(xy 316.658574 -354.396591) (xy 316.70446 -354.426077) (xy 316.745682 -354.461793) (xy 316.781402 -354.503012)
			(xy 316.810891 -354.548895) (xy 316.83355 -354.598508) (xy 316.848918 -354.650841) (xy 316.85668 -354.704829)
			(xy 316.85668 -354.759371) (xy 316.85668 -354.759373) (xy 318.339384 -354.759373) (xy 318.339384 -354.704827)
			(xy 318.347147 -354.650835) (xy 318.362515 -354.598498) (xy 318.385175 -354.548881) (xy 318.414667 -354.502994)
			(xy 318.450388 -354.461771) (xy 318.491613 -354.426052) (xy 318.537502 -354.396564) (xy 318.587121 -354.373907)
			(xy 318.639459 -354.358542) (xy 318.693451 -354.350782) (xy 318.720724 -354.35032) (xy 319.584324 -354.35032)
			(xy 319.611591 -354.350844) (xy 319.665569 -354.358608) (xy 319.717894 -354.373975) (xy 319.767498 -354.396631)
			(xy 319.813374 -354.426116) (xy 319.854587 -354.46183) (xy 319.890298 -354.503045) (xy 319.91978 -354.548923)
			(xy 319.942434 -354.598529) (xy 319.957797 -354.650854) (xy 319.965558 -354.704833) (xy 319.965558 -354.759367)
			(xy 319.965558 -354.75937) (xy 321.448406 -354.75937) (xy 321.448406 -354.70483) (xy 321.456168 -354.650845)
			(xy 321.471533 -354.598515) (xy 321.494189 -354.548903) (xy 321.523675 -354.503021) (xy 321.55939 -354.461802)
			(xy 321.600608 -354.426085) (xy 321.646489 -354.396597) (xy 321.6961 -354.373939) (xy 321.74843 -354.358571)
			(xy 321.802414 -354.350808) (xy 321.829684 -354.35032) (xy 322.693284 -354.35032) (xy 322.720554 -354.350818)
			(xy 322.774541 -354.358578) (xy 322.826873 -354.373942) (xy 322.876485 -354.396598) (xy 322.922369 -354.426084)
			(xy 322.963589 -354.4618) (xy 322.999307 -354.503018) (xy 323.028794 -354.5489) (xy 323.051452 -354.598512)
			(xy 323.066818 -354.650844) (xy 323.074581 -354.70483) (xy 323.074581 -354.75937) (xy 323.07458 -354.759374)
			(xy 324.557284 -354.759374) (xy 324.557284 -354.704826) (xy 324.565047 -354.650832) (xy 324.580417 -354.598494)
			(xy 324.603078 -354.548875) (xy 324.632571 -354.502987) (xy 324.668295 -354.461764) (xy 324.709523 -354.426045)
			(xy 324.755414 -354.396557) (xy 324.805035 -354.373901) (xy 324.857375 -354.358538) (xy 324.91137 -354.350781)
			(xy 324.938644 -354.35032) (xy 325.802244 -354.35032) (xy 325.82951 -354.350845) (xy 325.883486 -354.358612)
			(xy 325.935808 -354.37398) (xy 325.98541 -354.396638) (xy 326.031284 -354.426124) (xy 326.072494 -354.461837)
			(xy 326.108203 -354.503052) (xy 326.137683 -354.548928) (xy 326.160335 -354.598533) (xy 326.175698 -354.650857)
			(xy 326.183458 -354.704834) (xy 326.183458 -354.759366) (xy 326.183457 -354.759372) (xy 327.666284 -354.759372)
			(xy 327.666284 -354.704828) (xy 327.674046 -354.650838) (xy 327.689413 -354.598502) (xy 327.712072 -354.548887)
			(xy 327.741562 -354.503001) (xy 327.777281 -354.461778) (xy 327.818504 -354.426059) (xy 327.86439 -354.39657)
			(xy 327.914006 -354.373912) (xy 327.966342 -354.358545) (xy 328.020332 -354.350783) (xy 328.047604 -354.35032)
			(xy 328.911204 -354.35032) (xy 328.938472 -354.350843) (xy 328.992453 -354.358604) (xy 329.044779 -354.373969)
			(xy 329.094386 -354.396625) (xy 329.140265 -354.426109) (xy 329.18148 -354.461823) (xy 329.217193 -354.503039)
			(xy 329.246677 -354.548917) (xy 329.269332 -354.598525) (xy 329.284696 -354.650851) (xy 329.292458 -354.704832)
			(xy 329.292458 -354.759368) (xy 329.292458 -354.759369) (xy 330.775306 -354.759369) (xy 330.775306 -354.704831)
			(xy 330.783067 -354.650848) (xy 330.798432 -354.598519) (xy 330.821086 -354.548909) (xy 330.85057 -354.503027)
			(xy 330.886283 -354.461809) (xy 330.927499 -354.426092) (xy 330.973377 -354.396604) (xy 331.022985 -354.373944)
			(xy 331.075313 -354.358575) (xy 331.129295 -354.350809) (xy 331.156564 -354.35032) (xy 332.020164 -354.35032)
			(xy 332.047435 -354.350817) (xy 332.101424 -354.358575) (xy 332.153758 -354.373937) (xy 332.203374 -354.396591)
			(xy 332.24926 -354.426077) (xy 332.290482 -354.461793) (xy 332.326202 -354.503012) (xy 332.355691 -354.548895)
			(xy 332.37835 -354.598508) (xy 332.393718 -354.650841) (xy 332.40148 -354.704829) (xy 332.40148 -354.759371)
			(xy 332.40148 -354.759373) (xy 333.884184 -354.759373) (xy 333.884184 -354.704827) (xy 333.891947 -354.650835)
			(xy 333.907315 -354.598498) (xy 333.929975 -354.548881) (xy 333.959467 -354.502994) (xy 333.995188 -354.461771)
			(xy 334.036413 -354.426052) (xy 334.082302 -354.396564) (xy 334.131921 -354.373907) (xy 334.184259 -354.358542)
			(xy 334.238251 -354.350782) (xy 334.265524 -354.35032) (xy 335.129124 -354.35032) (xy 335.156391 -354.350844)
			(xy 335.210369 -354.358608) (xy 335.262694 -354.373975) (xy 335.312298 -354.396631) (xy 335.358174 -354.426116)
			(xy 335.399387 -354.46183) (xy 335.435098 -354.503045) (xy 335.46458 -354.548923) (xy 335.487234 -354.598529)
			(xy 335.502597 -354.650854) (xy 335.510358 -354.704833) (xy 335.510358 -354.759367) (xy 335.510358 -354.75937)
			(xy 336.993206 -354.75937) (xy 336.993206 -354.70483) (xy 337.000968 -354.650845) (xy 337.016333 -354.598515)
			(xy 337.038989 -354.548903) (xy 337.068475 -354.503021) (xy 337.10419 -354.461802) (xy 337.145408 -354.426085)
			(xy 337.191289 -354.396597) (xy 337.2409 -354.373939) (xy 337.29323 -354.358571) (xy 337.347214 -354.350808)
			(xy 337.374484 -354.35032) (xy 338.238084 -354.35032) (xy 338.265354 -354.350818) (xy 338.319341 -354.358578)
			(xy 338.371673 -354.373942) (xy 338.421285 -354.396598) (xy 338.467169 -354.426084) (xy 338.508389 -354.4618)
			(xy 338.544107 -354.503018) (xy 338.573594 -354.5489) (xy 338.596252 -354.598512) (xy 338.611618 -354.650844)
			(xy 338.619381 -354.70483) (xy 338.619381 -354.75937) (xy 338.61938 -354.759374) (xy 340.102084 -354.759374)
			(xy 340.102084 -354.704826) (xy 340.109847 -354.650832) (xy 340.125217 -354.598494) (xy 340.147878 -354.548875)
			(xy 340.177371 -354.502987) (xy 340.213095 -354.461764) (xy 340.254323 -354.426045) (xy 340.300214 -354.396557)
			(xy 340.349835 -354.373901) (xy 340.402175 -354.358538) (xy 340.45617 -354.350781) (xy 340.483444 -354.35032)
			(xy 341.347044 -354.35032) (xy 341.37431 -354.350845) (xy 341.428286 -354.358612) (xy 341.480608 -354.37398)
			(xy 341.53021 -354.396638) (xy 341.576084 -354.426124) (xy 341.617294 -354.461837) (xy 341.653003 -354.503052)
			(xy 341.682483 -354.548928) (xy 341.705135 -354.598533) (xy 341.720498 -354.650857) (xy 341.728258 -354.704834)
			(xy 341.728258 -354.759366) (xy 341.728257 -354.759372) (xy 343.211084 -354.759372) (xy 343.211084 -354.704828)
			(xy 343.218846 -354.650838) (xy 343.234213 -354.598502) (xy 343.256872 -354.548887) (xy 343.286362 -354.503001)
			(xy 343.322081 -354.461778) (xy 343.363304 -354.426059) (xy 343.40919 -354.39657) (xy 343.458806 -354.373912)
			(xy 343.511142 -354.358545) (xy 343.565132 -354.350783) (xy 343.592404 -354.35032) (xy 344.456004 -354.35032)
			(xy 344.483272 -354.350843) (xy 344.537253 -354.358604) (xy 344.589579 -354.373969) (xy 344.639186 -354.396625)
			(xy 344.685065 -354.426109) (xy 344.72628 -354.461823) (xy 344.761993 -354.503039) (xy 344.791477 -354.548917)
			(xy 344.814132 -354.598525) (xy 344.829496 -354.650851) (xy 344.837258 -354.704832) (xy 344.837258 -354.759368)
			(xy 344.837257 -354.759374) (xy 373.915584 -354.759374) (xy 373.915584 -354.704826) (xy 373.923347 -354.650833)
			(xy 373.938716 -354.598495) (xy 373.961378 -354.548876) (xy 373.990871 -354.502989) (xy 374.026594 -354.461766)
			(xy 374.067821 -354.426047) (xy 374.113712 -354.396559) (xy 374.163332 -354.373902) (xy 374.215672 -354.358539)
			(xy 374.269666 -354.350781) (xy 374.29694 -354.35032) (xy 375.16054 -354.35032) (xy 375.187806 -354.350845)
			(xy 375.241783 -354.358611) (xy 375.294105 -354.373979) (xy 375.343708 -354.396637) (xy 375.389582 -354.426122)
			(xy 375.430793 -354.461836) (xy 375.466502 -354.50305) (xy 375.495983 -354.548927) (xy 375.518635 -354.598532)
			(xy 375.533997 -354.650856) (xy 375.541758 -354.704834) (xy 375.541758 -354.759366) (xy 375.541757 -354.759371)
			(xy 377.024606 -354.759371) (xy 377.024606 -354.704829) (xy 377.032369 -354.650843) (xy 377.047735 -354.598511)
			(xy 377.070392 -354.548899) (xy 377.099879 -354.503016) (xy 377.135596 -354.461796) (xy 377.176816 -354.426079)
			(xy 377.222699 -354.396592) (xy 377.272311 -354.373935) (xy 377.324643 -354.358569) (xy 377.378629 -354.350806)
			(xy 377.4059 -354.35032) (xy 378.2695 -354.35032) (xy 378.296768 -354.350842) (xy 378.350749 -354.358604)
			(xy 378.403076 -354.373968) (xy 378.452684 -354.396623) (xy 378.498563 -354.426108) (xy 378.539778 -354.461822)
			(xy 378.575492 -354.503037) (xy 378.604977 -354.548916) (xy 378.627632 -354.598524) (xy 378.642996 -354.650851)
			(xy 378.650758 -354.704832) (xy 378.650758 -354.759368) (xy 378.650758 -354.759369) (xy 380.133606 -354.759369)
			(xy 380.133606 -354.704831) (xy 380.141367 -354.650849) (xy 380.156731 -354.59852) (xy 380.179386 -354.54891)
			(xy 380.208869 -354.503029) (xy 380.244582 -354.46181) (xy 380.285797 -354.426093) (xy 380.331675 -354.396605)
			(xy 380.381282 -354.373945) (xy 380.433609 -354.358576) (xy 380.487591 -354.350809) (xy 380.51486 -354.35032)
			(xy 381.37846 -354.35032) (xy 381.405732 -354.350817) (xy 381.45972 -354.358574) (xy 381.512055 -354.373936)
			(xy 381.561671 -354.39659) (xy 381.607558 -354.426075) (xy 381.648781 -354.461791) (xy 381.684501 -354.50301)
			(xy 381.713991 -354.548894) (xy 381.73665 -354.598507) (xy 381.752018 -354.650841) (xy 381.75978 -354.704828)
			(xy 381.75978 -354.759372) (xy 381.75978 -354.759373) (xy 383.242484 -354.759373) (xy 383.242484 -354.704827)
			(xy 383.250247 -354.650836) (xy 383.265615 -354.598499) (xy 383.288275 -354.548882) (xy 383.317766 -354.502995)
			(xy 383.353487 -354.461773) (xy 383.394711 -354.426054) (xy 383.4406 -354.396565) (xy 383.490218 -354.373908)
			(xy 383.542555 -354.358542) (xy 383.596547 -354.350782) (xy 383.62382 -354.35032) (xy 384.48742 -354.35032)
			(xy 384.514687 -354.350844) (xy 384.568666 -354.358607) (xy 384.620991 -354.373974) (xy 384.670596 -354.39663)
			(xy 384.716472 -354.426115) (xy 384.757686 -354.461829) (xy 384.793397 -354.503044) (xy 384.82288 -354.548922)
			(xy 384.845533 -354.598528) (xy 384.860897 -354.650854) (xy 384.868658 -354.704833) (xy 384.868658 -354.759367)
			(xy 384.868658 -354.75937) (xy 386.351506 -354.75937) (xy 386.351506 -354.70483) (xy 386.359268 -354.650846)
			(xy 386.374633 -354.598515) (xy 386.397289 -354.548904) (xy 386.426774 -354.503022) (xy 386.462489 -354.461803)
			(xy 386.503706 -354.426086) (xy 386.549587 -354.396598) (xy 386.599197 -354.37394) (xy 386.651526 -354.358572)
			(xy 386.70551 -354.350808) (xy 386.73278 -354.35032) (xy 387.59638 -354.35032) (xy 387.623651 -354.350818)
			(xy 387.677637 -354.358578) (xy 387.72997 -354.373941) (xy 387.779583 -354.396597) (xy 387.825467 -354.426082)
			(xy 387.866688 -354.461798) (xy 387.902406 -354.503017) (xy 387.931894 -354.548899) (xy 387.954552 -354.598511)
			(xy 387.969918 -354.650843) (xy 387.97768 -354.704829) (xy 387.97768 -354.759371) (xy 387.97768 -354.759374)
			(xy 389.460384 -354.759374) (xy 389.460384 -354.704826) (xy 389.468147 -354.650833) (xy 389.483516 -354.598495)
			(xy 389.506178 -354.548876) (xy 389.535671 -354.502989) (xy 389.571394 -354.461766) (xy 389.612621 -354.426047)
			(xy 389.658512 -354.396559) (xy 389.708132 -354.373902) (xy 389.760472 -354.358539) (xy 389.814466 -354.350781)
			(xy 389.84174 -354.35032) (xy 390.70534 -354.35032) (xy 390.732606 -354.350845) (xy 390.786583 -354.358611)
			(xy 390.838905 -354.373979) (xy 390.888508 -354.396637) (xy 390.934382 -354.426122) (xy 390.975593 -354.461836)
			(xy 391.011302 -354.50305) (xy 391.040783 -354.548927) (xy 391.063435 -354.598532) (xy 391.078797 -354.650856)
			(xy 391.086558 -354.704834) (xy 391.086558 -354.759366) (xy 391.086557 -354.759371) (xy 392.569406 -354.759371)
			(xy 392.569406 -354.704829) (xy 392.577169 -354.650843) (xy 392.592535 -354.598511) (xy 392.615192 -354.548899)
			(xy 392.644679 -354.503016) (xy 392.680396 -354.461796) (xy 392.721616 -354.426079) (xy 392.767499 -354.396592)
			(xy 392.817111 -354.373935) (xy 392.869443 -354.358569) (xy 392.923429 -354.350806) (xy 392.9507 -354.35032)
			(xy 393.8143 -354.35032) (xy 393.841568 -354.350842) (xy 393.895549 -354.358604) (xy 393.947876 -354.373968)
			(xy 393.997484 -354.396623) (xy 394.043363 -354.426108) (xy 394.084578 -354.461822) (xy 394.120292 -354.503037)
			(xy 394.149777 -354.548916) (xy 394.172432 -354.598524) (xy 394.187796 -354.650851) (xy 394.195558 -354.704832)
			(xy 394.195558 -354.759368) (xy 394.195558 -354.759369) (xy 395.678406 -354.759369) (xy 395.678406 -354.704831)
			(xy 395.686167 -354.650849) (xy 395.701531 -354.59852) (xy 395.724186 -354.54891) (xy 395.753669 -354.503029)
			(xy 395.789382 -354.46181) (xy 395.830597 -354.426093) (xy 395.876475 -354.396605) (xy 395.926082 -354.373945)
			(xy 395.978409 -354.358576) (xy 396.032391 -354.350809) (xy 396.05966 -354.35032) (xy 396.92326 -354.35032)
			(xy 396.950532 -354.350817) (xy 397.00452 -354.358574) (xy 397.056855 -354.373936) (xy 397.106471 -354.39659)
			(xy 397.152358 -354.426075) (xy 397.193581 -354.461791) (xy 397.229301 -354.50301) (xy 397.258791 -354.548894)
			(xy 397.28145 -354.598507) (xy 397.296818 -354.650841) (xy 397.30458 -354.704828) (xy 397.30458 -354.759372)
			(xy 397.30458 -354.759373) (xy 398.787284 -354.759373) (xy 398.787284 -354.704827) (xy 398.795047 -354.650836)
			(xy 398.810415 -354.598499) (xy 398.833075 -354.548882) (xy 398.862566 -354.502995) (xy 398.898287 -354.461773)
			(xy 398.939511 -354.426054) (xy 398.9854 -354.396565) (xy 399.035018 -354.373908) (xy 399.087355 -354.358542)
			(xy 399.141347 -354.350782) (xy 399.16862 -354.35032) (xy 400.03222 -354.35032) (xy 400.059487 -354.350844)
			(xy 400.113466 -354.358607) (xy 400.165791 -354.373974) (xy 400.215396 -354.39663) (xy 400.261272 -354.426115)
			(xy 400.302486 -354.461829) (xy 400.338197 -354.503044) (xy 400.36768 -354.548922) (xy 400.390333 -354.598528)
			(xy 400.405697 -354.650854) (xy 400.413458 -354.704833) (xy 400.413458 -354.759367) (xy 400.413458 -354.75937)
			(xy 401.896306 -354.75937) (xy 401.896306 -354.70483) (xy 401.904068 -354.650846) (xy 401.919433 -354.598515)
			(xy 401.942089 -354.548904) (xy 401.971574 -354.503022) (xy 402.007289 -354.461803) (xy 402.048506 -354.426086)
			(xy 402.094387 -354.396598) (xy 402.143997 -354.37394) (xy 402.196326 -354.358572) (xy 402.25031 -354.350808)
			(xy 402.27758 -354.35032) (xy 403.14118 -354.35032) (xy 403.168451 -354.350818) (xy 403.222437 -354.358578)
			(xy 403.27477 -354.373941) (xy 403.324383 -354.396597) (xy 403.370267 -354.426082) (xy 403.411488 -354.461798)
			(xy 403.447206 -354.503017) (xy 403.476694 -354.548899) (xy 403.499352 -354.598511) (xy 403.514718 -354.650843)
			(xy 403.52248 -354.704829) (xy 403.52248 -354.759368) (xy 412.022806 -354.759368) (xy 412.022806 -354.704832)
			(xy 412.030567 -354.65085) (xy 412.045931 -354.598521) (xy 412.068585 -354.548912) (xy 412.098067 -354.503031)
			(xy 412.133779 -354.461813) (xy 412.174993 -354.426096) (xy 412.22087 -354.396608) (xy 412.270476 -354.373948)
			(xy 412.322803 -354.358577) (xy 412.376784 -354.35081) (xy 412.404052 -354.35032) (xy 413.267652 -354.35032)
			(xy 413.294924 -354.350816) (xy 413.348913 -354.358572) (xy 413.401249 -354.373934) (xy 413.450866 -354.396588)
			(xy 413.496754 -354.426072) (xy 413.537978 -354.461788) (xy 413.573699 -354.503008) (xy 413.603189 -354.548891)
			(xy 413.625849 -354.598506) (xy 413.641217 -354.65084) (xy 413.64898 -354.704828) (xy 413.64898 -354.759372)
			(xy 413.64898 -354.759373) (xy 415.131684 -354.759373) (xy 415.131684 -354.704827) (xy 415.139446 -354.650837)
			(xy 415.154814 -354.598501) (xy 415.177473 -354.548884) (xy 415.206964 -354.502998) (xy 415.242684 -354.461776)
			(xy 415.283908 -354.426056) (xy 415.329795 -354.396568) (xy 415.379412 -354.37391) (xy 415.431748 -354.358544)
			(xy 415.485739 -354.350783) (xy 415.513012 -354.35032) (xy 416.376612 -354.35032) (xy 416.40388 -354.350843)
			(xy 416.457859 -354.358606) (xy 416.510185 -354.373972) (xy 416.559791 -354.396627) (xy 416.605668 -354.426112)
			(xy 416.646883 -354.461826) (xy 416.682595 -354.503041) (xy 416.712078 -354.548919) (xy 416.734733 -354.598526)
			(xy 416.750097 -354.650852) (xy 416.757858 -354.704832) (xy 416.757858 -354.759368) (xy 416.757858 -354.759369)
			(xy 418.240706 -354.759369) (xy 418.240706 -354.704831) (xy 418.248468 -354.650847) (xy 418.263832 -354.598517)
			(xy 418.286488 -354.548907) (xy 418.315972 -354.503025) (xy 418.351686 -354.461806) (xy 418.392902 -354.426089)
			(xy 418.438782 -354.396601) (xy 418.488391 -354.373942) (xy 418.54072 -354.358574) (xy 418.594703 -354.350808)
			(xy 418.621972 -354.35032) (xy 419.485572 -354.35032) (xy 419.512843 -354.350818) (xy 419.56683 -354.358576)
			(xy 419.619164 -354.373939) (xy 419.668778 -354.396594) (xy 419.714663 -354.42608) (xy 419.755885 -354.461795)
			(xy 419.791604 -354.503014) (xy 419.821092 -354.548897) (xy 419.843751 -354.59851) (xy 419.859118 -354.650842)
			(xy 419.86688 -354.704829) (xy 419.86688 -354.759371) (xy 419.86688 -354.759374) (xy 421.349584 -354.759374)
			(xy 421.349584 -354.704826) (xy 421.357347 -354.650834) (xy 421.372716 -354.598496) (xy 421.395377 -354.548879)
			(xy 421.424869 -354.502991) (xy 421.460591 -354.461768) (xy 421.501817 -354.426049) (xy 421.547707 -354.396561)
			(xy 421.597326 -354.373904) (xy 421.649665 -354.35854) (xy 421.703658 -354.350781) (xy 421.730932 -354.35032)
			(xy 422.594532 -354.35032) (xy 422.621799 -354.350845) (xy 422.675776 -354.35861) (xy 422.728099 -354.373977)
			(xy 422.777703 -354.396634) (xy 422.823578 -354.426119) (xy 422.86479 -354.461833) (xy 422.9005 -354.503048)
			(xy 422.929981 -354.548925) (xy 422.952634 -354.598531) (xy 422.967997 -354.650855) (xy 422.975758 -354.704833)
			(xy 422.975758 -354.759367) (xy 422.975758 -354.75937) (xy 424.458606 -354.75937) (xy 424.458606 -354.70483)
			(xy 424.466368 -354.650844) (xy 424.481734 -354.598513) (xy 424.504391 -354.548901) (xy 424.533877 -354.503018)
			(xy 424.569593 -354.461799) (xy 424.610812 -354.426082) (xy 424.656694 -354.396594) (xy 424.706305 -354.373937)
			(xy 424.758636 -354.35857) (xy 424.812622 -354.350807) (xy 424.839892 -354.35032) (xy 425.703492 -354.35032)
			(xy 425.730762 -354.350819) (xy 425.784747 -354.35858) (xy 425.837078 -354.373945) (xy 425.88669 -354.396601)
			(xy 425.932573 -354.426087) (xy 425.973792 -354.461802) (xy 426.009509 -354.503021) (xy 426.038996 -354.548903)
			(xy 426.061653 -354.598514) (xy 426.077019 -354.650845) (xy 426.084781 -354.70483) (xy 426.084781 -354.759368)
			(xy 427.567606 -354.759368) (xy 427.567606 -354.704832) (xy 427.575367 -354.65085) (xy 427.590731 -354.598521)
			(xy 427.613385 -354.548912) (xy 427.642867 -354.503031) (xy 427.678579 -354.461813) (xy 427.719793 -354.426096)
			(xy 427.76567 -354.396608) (xy 427.815276 -354.373948) (xy 427.867603 -354.358577) (xy 427.921584 -354.35081)
			(xy 427.948852 -354.35032) (xy 428.812452 -354.35032) (xy 428.839724 -354.350816) (xy 428.893713 -354.358572)
			(xy 428.946049 -354.373934) (xy 428.995666 -354.396588) (xy 429.041554 -354.426072) (xy 429.082778 -354.461788)
			(xy 429.118499 -354.503008) (xy 429.147989 -354.548891) (xy 429.170649 -354.598506) (xy 429.186017 -354.65084)
			(xy 429.19378 -354.704828) (xy 429.19378 -354.759372) (xy 429.19378 -354.759373) (xy 430.676484 -354.759373)
			(xy 430.676484 -354.704827) (xy 430.684246 -354.650837) (xy 430.699614 -354.598501) (xy 430.722273 -354.548884)
			(xy 430.751764 -354.502998) (xy 430.787484 -354.461776) (xy 430.828708 -354.426056) (xy 430.874595 -354.396568)
			(xy 430.924212 -354.37391) (xy 430.976548 -354.358544) (xy 431.030539 -354.350783) (xy 431.057812 -354.35032)
			(xy 431.921412 -354.35032) (xy 431.94868 -354.350843) (xy 432.002659 -354.358606) (xy 432.054985 -354.373972)
			(xy 432.104591 -354.396627) (xy 432.150468 -354.426112) (xy 432.191683 -354.461826) (xy 432.227395 -354.503041)
			(xy 432.256878 -354.548919) (xy 432.279533 -354.598526) (xy 432.294897 -354.650852) (xy 432.302658 -354.704832)
			(xy 432.302658 -354.759368) (xy 432.302658 -354.759369) (xy 433.785506 -354.759369) (xy 433.785506 -354.704831)
			(xy 433.793268 -354.650847) (xy 433.808632 -354.598517) (xy 433.831288 -354.548907) (xy 433.860772 -354.503025)
			(xy 433.896486 -354.461806) (xy 433.937702 -354.426089) (xy 433.983582 -354.396601) (xy 434.033191 -354.373942)
			(xy 434.08552 -354.358574) (xy 434.139503 -354.350808) (xy 434.166772 -354.35032) (xy 435.030372 -354.35032)
			(xy 435.057643 -354.350818) (xy 435.11163 -354.358576) (xy 435.163964 -354.373939) (xy 435.213578 -354.396594)
			(xy 435.259463 -354.42608) (xy 435.300685 -354.461795) (xy 435.336404 -354.503014) (xy 435.365892 -354.548897)
			(xy 435.388551 -354.59851) (xy 435.403918 -354.650842) (xy 435.41168 -354.704829) (xy 435.41168 -354.759371)
			(xy 435.41168 -354.759374) (xy 436.894384 -354.759374) (xy 436.894384 -354.704826) (xy 436.902147 -354.650834)
			(xy 436.917516 -354.598496) (xy 436.940177 -354.548879) (xy 436.969669 -354.502991) (xy 437.005391 -354.461768)
			(xy 437.046617 -354.426049) (xy 437.092507 -354.396561) (xy 437.142126 -354.373904) (xy 437.194465 -354.35854)
			(xy 437.248458 -354.350781) (xy 437.275732 -354.35032) (xy 438.139332 -354.35032) (xy 438.166599 -354.350845)
			(xy 438.220576 -354.35861) (xy 438.272899 -354.373977) (xy 438.322503 -354.396634) (xy 438.368378 -354.426119)
			(xy 438.40959 -354.461833) (xy 438.4453 -354.503048) (xy 438.474781 -354.548925) (xy 438.497434 -354.598531)
			(xy 438.512797 -354.650855) (xy 438.520558 -354.704833) (xy 438.520558 -354.759367) (xy 438.520558 -354.75937)
			(xy 440.003406 -354.75937) (xy 440.003406 -354.70483) (xy 440.011168 -354.650844) (xy 440.026534 -354.598513)
			(xy 440.049191 -354.548901) (xy 440.078677 -354.503018) (xy 440.114393 -354.461799) (xy 440.155612 -354.426082)
			(xy 440.201494 -354.396594) (xy 440.251105 -354.373937) (xy 440.303436 -354.35857) (xy 440.357422 -354.350807)
			(xy 440.384692 -354.35032) (xy 441.248292 -354.35032) (xy 441.275562 -354.350819) (xy 441.329547 -354.35858)
			(xy 441.381878 -354.373945) (xy 441.43149 -354.396601) (xy 441.477373 -354.426087) (xy 441.518592 -354.461802)
			(xy 441.554309 -354.503021) (xy 441.583796 -354.548903) (xy 441.606453 -354.598514) (xy 441.621819 -354.650845)
			(xy 441.629581 -354.70483) (xy 441.629581 -354.75937) (xy 441.621819 -354.813355) (xy 441.606453 -354.865686)
			(xy 441.583796 -354.915297) (xy 441.554309 -354.961179) (xy 441.518592 -355.002398) (xy 441.477373 -355.038113)
			(xy 441.43149 -355.067599) (xy 441.381878 -355.090255) (xy 441.329547 -355.10562) (xy 441.275562 -355.113381)
			(xy 441.248292 -355.113844) (xy 440.384692 -355.113844) (xy 440.357422 -355.113393) (xy 440.303436 -355.10563)
			(xy 440.251105 -355.090263) (xy 440.201494 -355.067606) (xy 440.155612 -355.038118) (xy 440.114393 -355.002401)
			(xy 440.078677 -354.961182) (xy 440.049191 -354.915299) (xy 440.026534 -354.865687) (xy 440.011168 -354.813356)
			(xy 440.003406 -354.75937) (xy 438.520558 -354.75937) (xy 438.512797 -354.813345) (xy 438.497434 -354.865669)
			(xy 438.474781 -354.915275) (xy 438.4453 -354.961152) (xy 438.40959 -355.002367) (xy 438.368378 -355.038081)
			(xy 438.322503 -355.067566) (xy 438.272899 -355.090223) (xy 438.220576 -355.10559) (xy 438.166599 -355.113355)
			(xy 438.139332 -355.113844) (xy 437.275732 -355.113844) (xy 437.248458 -355.113419) (xy 437.194465 -355.10566)
			(xy 437.142126 -355.090296) (xy 437.092507 -355.067639) (xy 437.046617 -355.038151) (xy 437.005391 -355.002432)
			(xy 436.969669 -354.961209) (xy 436.940177 -354.915321) (xy 436.917516 -354.865704) (xy 436.902147 -354.813366)
			(xy 436.894384 -354.759374) (xy 435.41168 -354.759374) (xy 435.403918 -354.813358) (xy 435.388551 -354.86569)
			(xy 435.365892 -354.915303) (xy 435.336404 -354.961186) (xy 435.300685 -355.002405) (xy 435.259463 -355.03812)
			(xy 435.213578 -355.067606) (xy 435.163964 -355.090261) (xy 435.11163 -355.105624) (xy 435.057643 -355.113382)
			(xy 435.030372 -355.113844) (xy 434.166772 -355.113844) (xy 434.139503 -355.113392) (xy 434.08552 -355.105626)
			(xy 434.033191 -355.090258) (xy 433.983582 -355.067599) (xy 433.937702 -355.038111) (xy 433.896486 -355.002394)
			(xy 433.860772 -354.961175) (xy 433.831288 -354.915293) (xy 433.808632 -354.865683) (xy 433.793268 -354.813353)
			(xy 433.785506 -354.759369) (xy 432.302658 -354.759369) (xy 432.294897 -354.813348) (xy 432.279533 -354.865674)
			(xy 432.256878 -354.915281) (xy 432.227395 -354.961159) (xy 432.191683 -355.002374) (xy 432.150468 -355.038088)
			(xy 432.104591 -355.067573) (xy 432.054985 -355.090228) (xy 432.002659 -355.105594) (xy 431.94868 -355.113357)
			(xy 431.921412 -355.113844) (xy 431.057812 -355.113844) (xy 431.030539 -355.113417) (xy 430.976548 -355.105656)
			(xy 430.924212 -355.09029) (xy 430.874595 -355.067632) (xy 430.828708 -355.038144) (xy 430.787484 -355.002424)
			(xy 430.751764 -354.961202) (xy 430.722273 -354.915316) (xy 430.699614 -354.865699) (xy 430.684246 -354.813363)
			(xy 430.676484 -354.759373) (xy 429.19378 -354.759373) (xy 429.186017 -354.81336) (xy 429.170649 -354.865694)
			(xy 429.147989 -354.915309) (xy 429.118499 -354.961192) (xy 429.082778 -355.002412) (xy 429.041554 -355.038128)
			(xy 428.995666 -355.067612) (xy 428.946049 -355.090266) (xy 428.893713 -355.105628) (xy 428.839724 -355.113384)
			(xy 428.812452 -355.113844) (xy 427.948852 -355.113844) (xy 427.921584 -355.11339) (xy 427.867603 -355.105623)
			(xy 427.815276 -355.090252) (xy 427.76567 -355.067592) (xy 427.719793 -355.038104) (xy 427.678579 -355.002387)
			(xy 427.642867 -354.961169) (xy 427.613385 -354.915288) (xy 427.590731 -354.865679) (xy 427.575367 -354.81335)
			(xy 427.567606 -354.759368) (xy 426.084781 -354.759368) (xy 426.084781 -354.75937) (xy 426.077019 -354.813355)
			(xy 426.061653 -354.865686) (xy 426.038996 -354.915297) (xy 426.009509 -354.961179) (xy 425.973792 -355.002398)
			(xy 425.932573 -355.038113) (xy 425.88669 -355.067599) (xy 425.837078 -355.090255) (xy 425.784747 -355.10562)
			(xy 425.730762 -355.113381) (xy 425.703492 -355.113844) (xy 424.839892 -355.113844) (xy 424.812622 -355.113393)
			(xy 424.758636 -355.10563) (xy 424.706305 -355.090263) (xy 424.656694 -355.067606) (xy 424.610812 -355.038118)
			(xy 424.569593 -355.002401) (xy 424.533877 -354.961182) (xy 424.504391 -354.915299) (xy 424.481734 -354.865687)
			(xy 424.466368 -354.813356) (xy 424.458606 -354.75937) (xy 422.975758 -354.75937) (xy 422.967997 -354.813345)
			(xy 422.952634 -354.865669) (xy 422.929981 -354.915275) (xy 422.9005 -354.961152) (xy 422.86479 -355.002367)
			(xy 422.823578 -355.038081) (xy 422.777703 -355.067566) (xy 422.728099 -355.090223) (xy 422.675776 -355.10559)
			(xy 422.621799 -355.113355) (xy 422.594532 -355.113844) (xy 421.730932 -355.113844) (xy 421.703658 -355.113419)
			(xy 421.649665 -355.10566) (xy 421.597326 -355.090296) (xy 421.547707 -355.067639) (xy 421.501817 -355.038151)
			(xy 421.460591 -355.002432) (xy 421.424869 -354.961209) (xy 421.395377 -354.915321) (xy 421.372716 -354.865704)
			(xy 421.357347 -354.813366) (xy 421.349584 -354.759374) (xy 419.86688 -354.759374) (xy 419.859118 -354.813358)
			(xy 419.843751 -354.86569) (xy 419.821092 -354.915303) (xy 419.791604 -354.961186) (xy 419.755885 -355.002405)
			(xy 419.714663 -355.03812) (xy 419.668778 -355.067606) (xy 419.619164 -355.090261) (xy 419.56683 -355.105624)
			(xy 419.512843 -355.113382) (xy 419.485572 -355.113844) (xy 418.621972 -355.113844) (xy 418.594703 -355.113392)
			(xy 418.54072 -355.105626) (xy 418.488391 -355.090258) (xy 418.438782 -355.067599) (xy 418.392902 -355.038111)
			(xy 418.351686 -355.002394) (xy 418.315972 -354.961175) (xy 418.286488 -354.915293) (xy 418.263832 -354.865683)
			(xy 418.248468 -354.813353) (xy 418.240706 -354.759369) (xy 416.757858 -354.759369) (xy 416.750097 -354.813348)
			(xy 416.734733 -354.865674) (xy 416.712078 -354.915281) (xy 416.682595 -354.961159) (xy 416.646883 -355.002374)
			(xy 416.605668 -355.038088) (xy 416.559791 -355.067573) (xy 416.510185 -355.090228) (xy 416.457859 -355.105594)
			(xy 416.40388 -355.113357) (xy 416.376612 -355.113844) (xy 415.513012 -355.113844) (xy 415.485739 -355.113417)
			(xy 415.431748 -355.105656) (xy 415.379412 -355.09029) (xy 415.329795 -355.067632) (xy 415.283908 -355.038144)
			(xy 415.242684 -355.002424) (xy 415.206964 -354.961202) (xy 415.177473 -354.915316) (xy 415.154814 -354.865699)
			(xy 415.139446 -354.813363) (xy 415.131684 -354.759373) (xy 413.64898 -354.759373) (xy 413.641217 -354.81336)
			(xy 413.625849 -354.865694) (xy 413.603189 -354.915309) (xy 413.573699 -354.961192) (xy 413.537978 -355.002412)
			(xy 413.496754 -355.038128) (xy 413.450866 -355.067612) (xy 413.401249 -355.090266) (xy 413.348913 -355.105628)
			(xy 413.294924 -355.113384) (xy 413.267652 -355.113844) (xy 412.404052 -355.113844) (xy 412.376784 -355.11339)
			(xy 412.322803 -355.105623) (xy 412.270476 -355.090252) (xy 412.22087 -355.067592) (xy 412.174993 -355.038104)
			(xy 412.133779 -355.002387) (xy 412.098067 -354.961169) (xy 412.068585 -354.915288) (xy 412.045931 -354.865679)
			(xy 412.030567 -354.81335) (xy 412.022806 -354.759368) (xy 403.52248 -354.759368) (xy 403.52248 -354.759371)
			(xy 403.514718 -354.813357) (xy 403.499352 -354.865689) (xy 403.476694 -354.915301) (xy 403.447206 -354.961183)
			(xy 403.411488 -355.002402) (xy 403.370267 -355.038118) (xy 403.324383 -355.067603) (xy 403.27477 -355.090259)
			(xy 403.222437 -355.105622) (xy 403.168451 -355.113382) (xy 403.14118 -355.113844) (xy 402.27758 -355.113844)
			(xy 402.25031 -355.113392) (xy 402.196326 -355.105628) (xy 402.143997 -355.09026) (xy 402.094387 -355.067602)
			(xy 402.048506 -355.038114) (xy 402.007289 -355.002397) (xy 401.971574 -354.961178) (xy 401.942089 -354.915296)
			(xy 401.919433 -354.865685) (xy 401.904068 -354.813354) (xy 401.896306 -354.75937) (xy 400.413458 -354.75937)
			(xy 400.405697 -354.813346) (xy 400.390333 -354.865672) (xy 400.36768 -354.915278) (xy 400.338197 -354.961156)
			(xy 400.302486 -355.002371) (xy 400.261272 -355.038085) (xy 400.215396 -355.06757) (xy 400.165791 -355.090226)
			(xy 400.113466 -355.105593) (xy 400.059487 -355.113356) (xy 400.03222 -355.113844) (xy 399.16862 -355.113844)
			(xy 399.141347 -355.113418) (xy 399.087355 -355.105658) (xy 399.035018 -355.090292) (xy 398.9854 -355.067635)
			(xy 398.939511 -355.038146) (xy 398.898287 -355.002427) (xy 398.862566 -354.961205) (xy 398.833075 -354.915318)
			(xy 398.810415 -354.865701) (xy 398.795047 -354.813364) (xy 398.787284 -354.759373) (xy 397.30458 -354.759373)
			(xy 397.296818 -354.813359) (xy 397.28145 -354.865693) (xy 397.258791 -354.915306) (xy 397.229301 -354.96119)
			(xy 397.193581 -355.002409) (xy 397.152358 -355.038125) (xy 397.106471 -355.06761) (xy 397.056855 -355.090264)
			(xy 397.00452 -355.105626) (xy 396.950532 -355.113383) (xy 396.92326 -355.113844) (xy 396.05966 -355.113844)
			(xy 396.032391 -355.113391) (xy 395.978409 -355.105624) (xy 395.926082 -355.090255) (xy 395.876475 -355.067595)
			(xy 395.830597 -355.038107) (xy 395.789382 -355.00239) (xy 395.753669 -354.961171) (xy 395.724186 -354.91529)
			(xy 395.701531 -354.86568) (xy 395.686167 -354.813351) (xy 395.678406 -354.759369) (xy 394.195558 -354.759369)
			(xy 394.187796 -354.813349) (xy 394.172432 -354.865676) (xy 394.149777 -354.915284) (xy 394.120292 -354.961163)
			(xy 394.084578 -355.002378) (xy 394.043363 -355.038092) (xy 393.997484 -355.067577) (xy 393.947876 -355.090232)
			(xy 393.895549 -355.105596) (xy 393.841568 -355.113358) (xy 393.8143 -355.113844) (xy 392.9507 -355.113844)
			(xy 392.923429 -355.113394) (xy 392.869443 -355.105631) (xy 392.817111 -355.090265) (xy 392.767499 -355.067608)
			(xy 392.721616 -355.038121) (xy 392.680396 -355.002404) (xy 392.644679 -354.961184) (xy 392.615192 -354.915301)
			(xy 392.592535 -354.865689) (xy 392.577169 -354.813357) (xy 392.569406 -354.759371) (xy 391.086557 -354.759371)
			(xy 391.078797 -354.813344) (xy 391.063435 -354.865668) (xy 391.040783 -354.915273) (xy 391.011302 -354.96115)
			(xy 390.975593 -355.002364) (xy 390.934382 -355.038078) (xy 390.888508 -355.067563) (xy 390.838905 -355.090221)
			(xy 390.786583 -355.105589) (xy 390.732606 -355.113355) (xy 390.70534 -355.113844) (xy 389.84174 -355.113844)
			(xy 389.814466 -355.113419) (xy 389.760472 -355.105661) (xy 389.708132 -355.090298) (xy 389.658512 -355.067641)
			(xy 389.612621 -355.038153) (xy 389.571394 -355.002434) (xy 389.535671 -354.961211) (xy 389.506178 -354.915324)
			(xy 389.483516 -354.865705) (xy 389.468147 -354.813367) (xy 389.460384 -354.759374) (xy 387.97768 -354.759374)
			(xy 387.969918 -354.813357) (xy 387.954552 -354.865689) (xy 387.931894 -354.915301) (xy 387.902406 -354.961183)
			(xy 387.866688 -355.002402) (xy 387.825467 -355.038118) (xy 387.779583 -355.067603) (xy 387.72997 -355.090259)
			(xy 387.677637 -355.105622) (xy 387.623651 -355.113382) (xy 387.59638 -355.113844) (xy 386.73278 -355.113844)
			(xy 386.70551 -355.113392) (xy 386.651526 -355.105628) (xy 386.599197 -355.09026) (xy 386.549587 -355.067602)
			(xy 386.503706 -355.038114) (xy 386.462489 -355.002397) (xy 386.426774 -354.961178) (xy 386.397289 -354.915296)
			(xy 386.374633 -354.865685) (xy 386.359268 -354.813354) (xy 386.351506 -354.75937) (xy 384.868658 -354.75937)
			(xy 384.860897 -354.813346) (xy 384.845533 -354.865672) (xy 384.82288 -354.915278) (xy 384.793397 -354.961156)
			(xy 384.757686 -355.002371) (xy 384.716472 -355.038085) (xy 384.670596 -355.06757) (xy 384.620991 -355.090226)
			(xy 384.568666 -355.105593) (xy 384.514687 -355.113356) (xy 384.48742 -355.113844) (xy 383.62382 -355.113844)
			(xy 383.596547 -355.113418) (xy 383.542555 -355.105658) (xy 383.490218 -355.090292) (xy 383.4406 -355.067635)
			(xy 383.394711 -355.038146) (xy 383.353487 -355.002427) (xy 383.317766 -354.961205) (xy 383.288275 -354.915318)
			(xy 383.265615 -354.865701) (xy 383.250247 -354.813364) (xy 383.242484 -354.759373) (xy 381.75978 -354.759373)
			(xy 381.752018 -354.813359) (xy 381.73665 -354.865693) (xy 381.713991 -354.915306) (xy 381.684501 -354.96119)
			(xy 381.648781 -355.002409) (xy 381.607558 -355.038125) (xy 381.561671 -355.06761) (xy 381.512055 -355.090264)
			(xy 381.45972 -355.105626) (xy 381.405732 -355.113383) (xy 381.37846 -355.113844) (xy 380.51486 -355.113844)
			(xy 380.487591 -355.113391) (xy 380.433609 -355.105624) (xy 380.381282 -355.090255) (xy 380.331675 -355.067595)
			(xy 380.285797 -355.038107) (xy 380.244582 -355.00239) (xy 380.208869 -354.961171) (xy 380.179386 -354.91529)
			(xy 380.156731 -354.86568) (xy 380.141367 -354.813351) (xy 380.133606 -354.759369) (xy 378.650758 -354.759369)
			(xy 378.642996 -354.813349) (xy 378.627632 -354.865676) (xy 378.604977 -354.915284) (xy 378.575492 -354.961163)
			(xy 378.539778 -355.002378) (xy 378.498563 -355.038092) (xy 378.452684 -355.067577) (xy 378.403076 -355.090232)
			(xy 378.350749 -355.105596) (xy 378.296768 -355.113358) (xy 378.2695 -355.113844) (xy 377.4059 -355.113844)
			(xy 377.378629 -355.113394) (xy 377.324643 -355.105631) (xy 377.272311 -355.090265) (xy 377.222699 -355.067608)
			(xy 377.176816 -355.038121) (xy 377.135596 -355.002404) (xy 377.099879 -354.961184) (xy 377.070392 -354.915301)
			(xy 377.047735 -354.865689) (xy 377.032369 -354.813357) (xy 377.024606 -354.759371) (xy 375.541757 -354.759371)
			(xy 375.533997 -354.813344) (xy 375.518635 -354.865668) (xy 375.495983 -354.915273) (xy 375.466502 -354.96115)
			(xy 375.430793 -355.002364) (xy 375.389582 -355.038078) (xy 375.343708 -355.067563) (xy 375.294105 -355.090221)
			(xy 375.241783 -355.105589) (xy 375.187806 -355.113355) (xy 375.16054 -355.113844) (xy 374.29694 -355.113844)
			(xy 374.269666 -355.113419) (xy 374.215672 -355.105661) (xy 374.163332 -355.090298) (xy 374.113712 -355.067641)
			(xy 374.067821 -355.038153) (xy 374.026594 -355.002434) (xy 373.990871 -354.961211) (xy 373.961378 -354.915324)
			(xy 373.938716 -354.865705) (xy 373.923347 -354.813367) (xy 373.915584 -354.759374) (xy 344.837257 -354.759374)
			(xy 344.829496 -354.813349) (xy 344.814132 -354.865675) (xy 344.791477 -354.915283) (xy 344.761993 -354.961161)
			(xy 344.72628 -355.002377) (xy 344.685065 -355.038091) (xy 344.639186 -355.067575) (xy 344.589579 -355.090231)
			(xy 344.537253 -355.105596) (xy 344.483272 -355.113357) (xy 344.456004 -355.113844) (xy 343.592404 -355.113844)
			(xy 343.565132 -355.113417) (xy 343.511142 -355.105655) (xy 343.458806 -355.090288) (xy 343.40919 -355.06763)
			(xy 343.363304 -355.038141) (xy 343.322081 -355.002422) (xy 343.286362 -354.961199) (xy 343.256872 -354.915313)
			(xy 343.234213 -354.865698) (xy 343.218846 -354.813362) (xy 343.211084 -354.759372) (xy 341.728257 -354.759372)
			(xy 341.720498 -354.813343) (xy 341.705135 -354.865667) (xy 341.682483 -354.915272) (xy 341.653003 -354.961148)
			(xy 341.617294 -355.002363) (xy 341.576084 -355.038076) (xy 341.53021 -355.067562) (xy 341.480608 -355.09022)
			(xy 341.428286 -355.105588) (xy 341.37431 -355.113355) (xy 341.347044 -355.113844) (xy 340.483444 -355.113844)
			(xy 340.45617 -355.113419) (xy 340.402175 -355.105662) (xy 340.349835 -355.090299) (xy 340.300214 -355.067643)
			(xy 340.254323 -355.038155) (xy 340.213095 -355.002436) (xy 340.177371 -354.961213) (xy 340.147878 -354.915325)
			(xy 340.125217 -354.865706) (xy 340.109847 -354.813368) (xy 340.102084 -354.759374) (xy 338.61938 -354.759374)
			(xy 338.611618 -354.813356) (xy 338.596252 -354.865688) (xy 338.573594 -354.9153) (xy 338.544107 -354.961182)
			(xy 338.508389 -355.0024) (xy 338.467169 -355.038116) (xy 338.421285 -355.067602) (xy 338.371673 -355.090258)
			(xy 338.319341 -355.105622) (xy 338.265354 -355.113382) (xy 338.238084 -355.113844) (xy 337.374484 -355.113844)
			(xy 337.347214 -355.113392) (xy 337.29323 -355.105629) (xy 337.2409 -355.090261) (xy 337.191289 -355.067603)
			(xy 337.145408 -355.038115) (xy 337.10419 -355.002398) (xy 337.068475 -354.961179) (xy 337.038989 -354.915297)
			(xy 337.016333 -354.865685) (xy 337.000968 -354.813355) (xy 336.993206 -354.75937) (xy 335.510358 -354.75937)
			(xy 335.502597 -354.813346) (xy 335.487234 -354.865671) (xy 335.46458 -354.915277) (xy 335.435098 -354.961155)
			(xy 335.399387 -355.00237) (xy 335.358174 -355.038084) (xy 335.312298 -355.067569) (xy 335.262694 -355.090225)
			(xy 335.210369 -355.105592) (xy 335.156391 -355.113356) (xy 335.129124 -355.113844) (xy 334.265524 -355.113844)
			(xy 334.238251 -355.113418) (xy 334.184259 -355.105658) (xy 334.131921 -355.090293) (xy 334.082302 -355.067636)
			(xy 334.036413 -355.038148) (xy 333.995188 -355.002429) (xy 333.959467 -354.961206) (xy 333.929975 -354.915319)
			(xy 333.907315 -354.865702) (xy 333.891947 -354.813365) (xy 333.884184 -354.759373) (xy 332.40148 -354.759373)
			(xy 332.393718 -354.813359) (xy 332.37835 -354.865692) (xy 332.355691 -354.915305) (xy 332.326202 -354.961188)
			(xy 332.290482 -355.002407) (xy 332.24926 -355.038123) (xy 332.203374 -355.067609) (xy 332.153758 -355.090263)
			(xy 332.101424 -355.105625) (xy 332.047435 -355.113383) (xy 332.020164 -355.113844) (xy 331.156564 -355.113844)
			(xy 331.129295 -355.113391) (xy 331.075313 -355.105625) (xy 331.022985 -355.090256) (xy 330.973377 -355.067596)
			(xy 330.927499 -355.038108) (xy 330.886283 -355.002391) (xy 330.85057 -354.961173) (xy 330.821086 -354.915291)
			(xy 330.798432 -354.865681) (xy 330.783067 -354.813352) (xy 330.775306 -354.759369) (xy 329.292458 -354.759369)
			(xy 329.284696 -354.813349) (xy 329.269332 -354.865675) (xy 329.246677 -354.915283) (xy 329.217193 -354.961161)
			(xy 329.18148 -355.002377) (xy 329.140265 -355.038091) (xy 329.094386 -355.067575) (xy 329.044779 -355.090231)
			(xy 328.992453 -355.105596) (xy 328.938472 -355.113357) (xy 328.911204 -355.113844) (xy 328.047604 -355.113844)
			(xy 328.020332 -355.113417) (xy 327.966342 -355.105655) (xy 327.914006 -355.090288) (xy 327.86439 -355.06763)
			(xy 327.818504 -355.038141) (xy 327.777281 -355.002422) (xy 327.741562 -354.961199) (xy 327.712072 -354.915313)
			(xy 327.689413 -354.865698) (xy 327.674046 -354.813362) (xy 327.666284 -354.759372) (xy 326.183457 -354.759372)
			(xy 326.175698 -354.813343) (xy 326.160335 -354.865667) (xy 326.137683 -354.915272) (xy 326.108203 -354.961148)
			(xy 326.072494 -355.002363) (xy 326.031284 -355.038076) (xy 325.98541 -355.067562) (xy 325.935808 -355.09022)
			(xy 325.883486 -355.105588) (xy 325.82951 -355.113355) (xy 325.802244 -355.113844) (xy 324.938644 -355.113844)
			(xy 324.91137 -355.113419) (xy 324.857375 -355.105662) (xy 324.805035 -355.090299) (xy 324.755414 -355.067643)
			(xy 324.709523 -355.038155) (xy 324.668295 -355.002436) (xy 324.632571 -354.961213) (xy 324.603078 -354.915325)
			(xy 324.580417 -354.865706) (xy 324.565047 -354.813368) (xy 324.557284 -354.759374) (xy 323.07458 -354.759374)
			(xy 323.066818 -354.813356) (xy 323.051452 -354.865688) (xy 323.028794 -354.9153) (xy 322.999307 -354.961182)
			(xy 322.963589 -355.0024) (xy 322.922369 -355.038116) (xy 322.876485 -355.067602) (xy 322.826873 -355.090258)
			(xy 322.774541 -355.105622) (xy 322.720554 -355.113382) (xy 322.693284 -355.113844) (xy 321.829684 -355.113844)
			(xy 321.802414 -355.113392) (xy 321.74843 -355.105629) (xy 321.6961 -355.090261) (xy 321.646489 -355.067603)
			(xy 321.600608 -355.038115) (xy 321.55939 -355.002398) (xy 321.523675 -354.961179) (xy 321.494189 -354.915297)
			(xy 321.471533 -354.865685) (xy 321.456168 -354.813355) (xy 321.448406 -354.75937) (xy 319.965558 -354.75937)
			(xy 319.957797 -354.813346) (xy 319.942434 -354.865671) (xy 319.91978 -354.915277) (xy 319.890298 -354.961155)
			(xy 319.854587 -355.00237) (xy 319.813374 -355.038084) (xy 319.767498 -355.067569) (xy 319.717894 -355.090225)
			(xy 319.665569 -355.105592) (xy 319.611591 -355.113356) (xy 319.584324 -355.113844) (xy 318.720724 -355.113844)
			(xy 318.693451 -355.113418) (xy 318.639459 -355.105658) (xy 318.587121 -355.090293) (xy 318.537502 -355.067636)
			(xy 318.491613 -355.038148) (xy 318.450388 -355.002429) (xy 318.414667 -354.961206) (xy 318.385175 -354.915319)
			(xy 318.362515 -354.865702) (xy 318.347147 -354.813365) (xy 318.339384 -354.759373) (xy 316.85668 -354.759373)
			(xy 316.848918 -354.813359) (xy 316.83355 -354.865692) (xy 316.810891 -354.915305) (xy 316.781402 -354.961188)
			(xy 316.745682 -355.002407) (xy 316.70446 -355.038123) (xy 316.658574 -355.067609) (xy 316.608958 -355.090263)
			(xy 316.556624 -355.105625) (xy 316.502635 -355.113383) (xy 316.475364 -355.113844) (xy 315.611764 -355.113844)
			(xy 315.584495 -355.113391) (xy 315.530513 -355.105625) (xy 315.478185 -355.090256) (xy 315.428577 -355.067596)
			(xy 315.382699 -355.038108) (xy 315.341483 -355.002391) (xy 315.30577 -354.961173) (xy 315.276286 -354.915291)
			(xy 315.253632 -354.865681) (xy 315.238267 -354.813352) (xy 315.230506 -354.759369) (xy 300.231558 -354.759369)
			(xy 300.223796 -354.813349) (xy 300.208432 -354.865676) (xy 300.185777 -354.915283) (xy 300.156293 -354.961162)
			(xy 300.120579 -355.002378) (xy 300.079364 -355.038091) (xy 300.033485 -355.067576) (xy 299.983878 -355.090231)
			(xy 299.931551 -355.105596) (xy 299.87757 -355.113357) (xy 299.850302 -355.113844) (xy 298.986702 -355.113844)
			(xy 298.95943 -355.113417) (xy 298.90544 -355.105654) (xy 298.853105 -355.090288) (xy 298.803489 -355.067629)
			(xy 298.757603 -355.03814) (xy 298.716381 -355.002421) (xy 298.680661 -354.961199) (xy 298.651172 -354.915313)
			(xy 298.628513 -354.865697) (xy 298.613146 -354.813362) (xy 298.605384 -354.759372) (xy 297.122557 -354.759372)
			(xy 297.114798 -354.813344) (xy 297.099435 -354.865667) (xy 297.076783 -354.915272) (xy 297.047302 -354.961149)
			(xy 297.011593 -355.002364) (xy 296.970383 -355.038077) (xy 296.924509 -355.067563) (xy 296.874907 -355.09022)
			(xy 296.822585 -355.105589) (xy 296.768608 -355.113355) (xy 296.741342 -355.113844) (xy 295.877742 -355.113844)
			(xy 295.850468 -355.113419) (xy 295.796474 -355.105662) (xy 295.744134 -355.090298) (xy 295.694513 -355.067642)
			(xy 295.648622 -355.038154) (xy 295.607395 -355.002435) (xy 295.571671 -354.961212) (xy 295.542178 -354.915324)
			(xy 295.519516 -354.865706) (xy 295.504147 -354.813367) (xy 295.496384 -354.759374) (xy 294.013681 -354.759374)
			(xy 294.005918 -354.813356) (xy 293.990552 -354.865688) (xy 293.967894 -354.9153) (xy 293.938406 -354.961182)
			(xy 293.902688 -355.002401) (xy 293.861468 -355.038117) (xy 293.815584 -355.067603) (xy 293.765971 -355.090258)
			(xy 293.713639 -355.105622) (xy 293.659653 -355.113382) (xy 293.632382 -355.113844) (xy 292.768782 -355.113844)
			(xy 292.741512 -355.113392) (xy 292.687528 -355.105628) (xy 292.635198 -355.090261) (xy 292.585588 -355.067602)
			(xy 292.539707 -355.038115) (xy 292.49849 -355.002398) (xy 292.462775 -354.961178) (xy 292.433289 -354.915296)
			(xy 292.410633 -354.865685) (xy 292.395268 -354.813354) (xy 292.387506 -354.75937) (xy 290.904658 -354.75937)
			(xy 290.896897 -354.813346) (xy 290.881533 -354.865672) (xy 290.85888 -354.915278) (xy 290.829397 -354.961156)
			(xy 290.793686 -355.002371) (xy 290.752473 -355.038084) (xy 290.706597 -355.067569) (xy 290.656992 -355.090226)
			(xy 290.604668 -355.105592) (xy 290.550689 -355.113356) (xy 290.523422 -355.113844) (xy 289.659822 -355.113844)
			(xy 289.632549 -355.113418) (xy 289.578557 -355.105658) (xy 289.526219 -355.090293) (xy 289.476601 -355.067636)
			(xy 289.430712 -355.038147) (xy 289.389488 -355.002428) (xy 289.353766 -354.961205) (xy 289.324275 -354.915318)
			(xy 289.301615 -354.865702) (xy 289.286247 -354.813365) (xy 289.278484 -354.759373) (xy 287.79578 -354.759373)
			(xy 287.788018 -354.813359) (xy 287.77265 -354.865692) (xy 287.749991 -354.915306) (xy 287.720501 -354.961189)
			(xy 287.684781 -355.002408) (xy 287.643559 -355.038124) (xy 287.597672 -355.067609) (xy 287.548057 -355.090264)
			(xy 287.495722 -355.105626) (xy 287.441733 -355.113383) (xy 287.414462 -355.113844) (xy 286.550862 -355.113844)
			(xy 286.523593 -355.113391) (xy 286.469611 -355.105625) (xy 286.417284 -355.090255) (xy 286.367676 -355.067596)
			(xy 286.321798 -355.038107) (xy 286.280583 -355.00239) (xy 286.24487 -354.961172) (xy 286.215386 -354.915291)
			(xy 286.192732 -354.865681) (xy 286.177367 -354.813352) (xy 286.169606 -354.759369) (xy 284.686758 -354.759369)
			(xy 284.678996 -354.813349) (xy 284.663632 -354.865676) (xy 284.640977 -354.915283) (xy 284.611493 -354.961162)
			(xy 284.575779 -355.002378) (xy 284.534564 -355.038091) (xy 284.488685 -355.067576) (xy 284.439078 -355.090231)
			(xy 284.386751 -355.105596) (xy 284.33277 -355.113357) (xy 284.305502 -355.113844) (xy 283.441902 -355.113844)
			(xy 283.41463 -355.113417) (xy 283.36064 -355.105654) (xy 283.308305 -355.090288) (xy 283.258689 -355.067629)
			(xy 283.212803 -355.03814) (xy 283.171581 -355.002421) (xy 283.135861 -354.961199) (xy 283.106372 -354.915313)
			(xy 283.083713 -354.865697) (xy 283.068346 -354.813362) (xy 283.060584 -354.759372) (xy 281.577757 -354.759372)
			(xy 281.569998 -354.813344) (xy 281.554635 -354.865667) (xy 281.531983 -354.915272) (xy 281.502502 -354.961149)
			(xy 281.466793 -355.002364) (xy 281.425583 -355.038077) (xy 281.379709 -355.067563) (xy 281.330107 -355.09022)
			(xy 281.277785 -355.105589) (xy 281.223808 -355.113355) (xy 281.196542 -355.113844) (xy 280.332942 -355.113844)
			(xy 280.305668 -355.113419) (xy 280.251674 -355.105662) (xy 280.199334 -355.090298) (xy 280.149713 -355.067642)
			(xy 280.103822 -355.038154) (xy 280.062595 -355.002435) (xy 280.026871 -354.961212) (xy 279.997378 -354.915324)
			(xy 279.974716 -354.865706) (xy 279.959347 -354.813367) (xy 279.951584 -354.759374) (xy 278.468881 -354.759374)
			(xy 278.461118 -354.813356) (xy 278.445752 -354.865688) (xy 278.423094 -354.9153) (xy 278.393606 -354.961182)
			(xy 278.357888 -355.002401) (xy 278.316668 -355.038117) (xy 278.270784 -355.067603) (xy 278.221171 -355.090258)
			(xy 278.168839 -355.105622) (xy 278.114853 -355.113382) (xy 278.087582 -355.113844) (xy 277.223982 -355.113844)
			(xy 277.196712 -355.113392) (xy 277.142728 -355.105628) (xy 277.090398 -355.090261) (xy 277.040788 -355.067602)
			(xy 276.994907 -355.038115) (xy 276.95369 -355.002398) (xy 276.917975 -354.961178) (xy 276.888489 -354.915296)
			(xy 276.865833 -354.865685) (xy 276.850468 -354.813354) (xy 276.842706 -354.75937) (xy 275.359858 -354.75937)
			(xy 275.352097 -354.813346) (xy 275.336733 -354.865672) (xy 275.31408 -354.915278) (xy 275.284597 -354.961156)
			(xy 275.248886 -355.002371) (xy 275.207673 -355.038084) (xy 275.161797 -355.067569) (xy 275.112192 -355.090226)
			(xy 275.059868 -355.105592) (xy 275.005889 -355.113356) (xy 274.978622 -355.113844) (xy 274.115022 -355.113844)
			(xy 274.087749 -355.113418) (xy 274.033757 -355.105658) (xy 273.981419 -355.090293) (xy 273.931801 -355.067636)
			(xy 273.885912 -355.038147) (xy 273.844688 -355.002428) (xy 273.808966 -354.961205) (xy 273.779475 -354.915318)
			(xy 273.756815 -354.865702) (xy 273.741447 -354.813365) (xy 273.733684 -354.759373) (xy 272.25098 -354.759373)
			(xy 272.243218 -354.813359) (xy 272.22785 -354.865692) (xy 272.205191 -354.915306) (xy 272.175701 -354.961189)
			(xy 272.139981 -355.002408) (xy 272.098759 -355.038124) (xy 272.052872 -355.067609) (xy 272.003257 -355.090264)
			(xy 271.950922 -355.105626) (xy 271.896933 -355.113383) (xy 271.869662 -355.113844) (xy 271.006062 -355.113844)
			(xy 270.978793 -355.113391) (xy 270.924811 -355.105625) (xy 270.872484 -355.090255) (xy 270.822876 -355.067596)
			(xy 270.776998 -355.038107) (xy 270.735783 -355.00239) (xy 270.70007 -354.961172) (xy 270.670586 -354.915291)
			(xy 270.647932 -354.865681) (xy 270.632567 -354.813352) (xy 270.624806 -354.759369) (xy 188.299268 -354.759369)
			(xy 188.294942 -354.78946) (xy 188.279575 -354.841794) (xy 188.256917 -354.891409) (xy 188.227428 -354.937294)
			(xy 188.191709 -354.978515) (xy 188.150487 -355.014233) (xy 188.104602 -355.04372) (xy 188.054987 -355.066378)
			(xy 188.002652 -355.081744) (xy 187.948664 -355.089505) (xy 187.921392 -355.089968) (xy 187.057792 -355.089968)
			(xy 187.030523 -355.089469) (xy 186.976542 -355.081707) (xy 186.924214 -355.066341) (xy 186.874605 -355.043684)
			(xy 186.828726 -355.014199) (xy 186.78751 -354.978484) (xy 186.751796 -354.937267) (xy 186.722312 -354.891388)
			(xy 186.699656 -354.841779) (xy 186.684292 -354.789451) (xy 186.67653 -354.735469) (xy 185.193682 -354.735469)
			(xy 185.185921 -354.78945) (xy 185.170557 -354.841778) (xy 185.147903 -354.891387) (xy 185.118419 -354.937267)
			(xy 185.082707 -354.978484) (xy 185.041492 -355.0142) (xy 184.995615 -355.043687) (xy 184.946008 -355.066346)
			(xy 184.893681 -355.081714) (xy 184.8397 -355.089479) (xy 184.812432 -355.089968) (xy 183.948832 -355.089968)
			(xy 183.92156 -355.089495) (xy 183.86757 -355.081736) (xy 183.815235 -355.066373) (xy 183.765618 -355.043718)
			(xy 183.719731 -355.014231) (xy 183.678508 -354.978515) (xy 183.642788 -354.937294) (xy 183.613298 -354.89141)
			(xy 183.590638 -354.841795) (xy 183.57527 -354.789461) (xy 183.567508 -354.735472) (xy 182.08478 -354.735472)
			(xy 182.08478 -354.759371) (xy 182.077018 -354.813358) (xy 182.061651 -354.86569) (xy 182.038992 -354.915303)
			(xy 182.009504 -354.961186) (xy 181.973785 -355.002405) (xy 181.932563 -355.03812) (xy 181.886678 -355.067606)
			(xy 181.837064 -355.090261) (xy 181.78473 -355.105624) (xy 181.730743 -355.113382) (xy 181.703472 -355.113844)
			(xy 180.839872 -355.113844) (xy 180.812603 -355.113392) (xy 180.75862 -355.105626) (xy 180.706291 -355.090258)
			(xy 180.656682 -355.067599) (xy 180.610802 -355.038111) (xy 180.569586 -355.002394) (xy 180.533872 -354.961175)
			(xy 180.504388 -354.915293) (xy 180.481732 -354.865683) (xy 180.466368 -354.813353) (xy 180.458606 -354.759369)
			(xy 178.975758 -354.759369) (xy 178.967997 -354.813348) (xy 178.952633 -354.865674) (xy 178.929978 -354.915281)
			(xy 178.900495 -354.961159) (xy 178.864783 -355.002374) (xy 178.823568 -355.038088) (xy 178.777691 -355.067573)
			(xy 178.728085 -355.090228) (xy 178.675759 -355.105594) (xy 178.62178 -355.113357) (xy 178.594512 -355.113844)
			(xy 177.730912 -355.113844) (xy 177.703639 -355.113417) (xy 177.649648 -355.105656) (xy 177.597312 -355.09029)
			(xy 177.547695 -355.067632) (xy 177.501808 -355.038144) (xy 177.460584 -355.002424) (xy 177.424864 -354.961202)
			(xy 177.395373 -354.915316) (xy 177.372714 -354.865699) (xy 177.357346 -354.813363) (xy 177.349584 -354.759373)
			(xy 175.86688 -354.759373) (xy 175.859117 -354.81336) (xy 175.843749 -354.865694) (xy 175.821089 -354.915309)
			(xy 175.791599 -354.961192) (xy 175.755878 -355.002412) (xy 175.714654 -355.038128) (xy 175.668766 -355.067612)
			(xy 175.619149 -355.090266) (xy 175.566813 -355.105628) (xy 175.512824 -355.113384) (xy 175.485552 -355.113844)
			(xy 174.621952 -355.113844) (xy 174.594684 -355.11339) (xy 174.540703 -355.105623) (xy 174.488376 -355.090252)
			(xy 174.43877 -355.067592) (xy 174.392893 -355.038104) (xy 174.351679 -355.002387) (xy 174.315967 -354.961169)
			(xy 174.286485 -354.915288) (xy 174.263831 -354.865679) (xy 174.248467 -354.81335) (xy 174.240706 -354.759368)
			(xy 172.757881 -354.759368) (xy 172.757881 -354.75937) (xy 172.750119 -354.813355) (xy 172.734753 -354.865686)
			(xy 172.712096 -354.915297) (xy 172.682609 -354.961179) (xy 172.646892 -355.002398) (xy 172.605673 -355.038113)
			(xy 172.55979 -355.067599) (xy 172.510178 -355.090255) (xy 172.457847 -355.10562) (xy 172.403862 -355.113381)
			(xy 172.376592 -355.113844) (xy 171.512992 -355.113844) (xy 171.485722 -355.113393) (xy 171.431736 -355.10563)
			(xy 171.379405 -355.090263) (xy 171.329794 -355.067606) (xy 171.283912 -355.038118) (xy 171.242693 -355.002401)
			(xy 171.206977 -354.961182) (xy 171.177491 -354.915299) (xy 171.154834 -354.865687) (xy 171.139468 -354.813356)
			(xy 171.131706 -354.75937) (xy 169.648858 -354.75937) (xy 169.641097 -354.813345) (xy 169.625734 -354.865669)
			(xy 169.603081 -354.915275) (xy 169.5736 -354.961152) (xy 169.53789 -355.002367) (xy 169.496678 -355.038081)
			(xy 169.450803 -355.067566) (xy 169.401199 -355.090223) (xy 169.348876 -355.10559) (xy 169.294899 -355.113355)
			(xy 169.267632 -355.113844) (xy 168.404032 -355.113844) (xy 168.376758 -355.113419) (xy 168.322765 -355.10566)
			(xy 168.270426 -355.090296) (xy 168.220807 -355.067639) (xy 168.174917 -355.038151) (xy 168.133691 -355.002432)
			(xy 168.097969 -354.961209) (xy 168.068477 -354.915321) (xy 168.045816 -354.865704) (xy 168.030447 -354.813366)
			(xy 168.022684 -354.759374) (xy 166.53998 -354.759374) (xy 166.532218 -354.813358) (xy 166.516851 -354.86569)
			(xy 166.494192 -354.915303) (xy 166.464704 -354.961186) (xy 166.428985 -355.002405) (xy 166.387763 -355.03812)
			(xy 166.341878 -355.067606) (xy 166.292264 -355.090261) (xy 166.23993 -355.105624) (xy 166.185943 -355.113382)
			(xy 166.158672 -355.113844) (xy 165.295072 -355.113844) (xy 165.267803 -355.113392) (xy 165.21382 -355.105626)
			(xy 165.161491 -355.090258) (xy 165.111882 -355.067599) (xy 165.066002 -355.038111) (xy 165.024786 -355.002394)
			(xy 164.989072 -354.961175) (xy 164.959588 -354.915293) (xy 164.936932 -354.865683) (xy 164.921568 -354.813353)
			(xy 164.913806 -354.759369) (xy 163.430958 -354.759369) (xy 163.423197 -354.813348) (xy 163.407833 -354.865674)
			(xy 163.385178 -354.915281) (xy 163.355695 -354.961159) (xy 163.319983 -355.002374) (xy 163.278768 -355.038088)
			(xy 163.232891 -355.067573) (xy 163.183285 -355.090228) (xy 163.130959 -355.105594) (xy 163.07698 -355.113357)
			(xy 163.049712 -355.113844) (xy 162.186112 -355.113844) (xy 162.158839 -355.113417) (xy 162.104848 -355.105656)
			(xy 162.052512 -355.09029) (xy 162.002895 -355.067632) (xy 161.957008 -355.038144) (xy 161.915784 -355.002424)
			(xy 161.880064 -354.961202) (xy 161.850573 -354.915316) (xy 161.827914 -354.865699) (xy 161.812546 -354.813363)
			(xy 161.804784 -354.759373) (xy 160.32208 -354.759373) (xy 160.314317 -354.81336) (xy 160.298949 -354.865694)
			(xy 160.276289 -354.915309) (xy 160.246799 -354.961192) (xy 160.211078 -355.002412) (xy 160.169854 -355.038128)
			(xy 160.123966 -355.067612) (xy 160.074349 -355.090266) (xy 160.022013 -355.105628) (xy 159.968024 -355.113384)
			(xy 159.940752 -355.113844) (xy 159.077152 -355.113844) (xy 159.049884 -355.11339) (xy 158.995903 -355.105623)
			(xy 158.943576 -355.090252) (xy 158.89397 -355.067592) (xy 158.848093 -355.038104) (xy 158.806879 -355.002387)
			(xy 158.771167 -354.961169) (xy 158.741685 -354.915288) (xy 158.719031 -354.865679) (xy 158.703667 -354.81335)
			(xy 158.695906 -354.759368) (xy 144.196558 -354.759368) (xy 144.188797 -354.813348) (xy 144.173432 -354.865675)
			(xy 144.150778 -354.915282) (xy 144.121294 -354.96116) (xy 144.085581 -355.002376) (xy 144.044367 -355.038089)
			(xy 143.998489 -355.067574) (xy 143.948882 -355.09023) (xy 143.896556 -355.105595) (xy 143.842576 -355.113357)
			(xy 143.815308 -355.113844) (xy 142.951708 -355.113844) (xy 142.924435 -355.113417) (xy 142.870445 -355.105655)
			(xy 142.818109 -355.090289) (xy 142.768492 -355.067631) (xy 142.722606 -355.038142) (xy 142.681383 -355.002423)
			(xy 142.645663 -354.961201) (xy 142.616173 -354.915315) (xy 142.593514 -354.865699) (xy 142.578146 -354.813363)
			(xy 142.570384 -354.759373) (xy 141.087557 -354.759373) (xy 141.079798 -354.813343) (xy 141.064436 -354.865666)
			(xy 141.041784 -354.915271) (xy 141.012304 -354.961147) (xy 140.976595 -355.002361) (xy 140.935386 -355.038075)
			(xy 140.889513 -355.067561) (xy 140.839911 -355.090219) (xy 140.78759 -355.105587) (xy 140.733614 -355.113354)
			(xy 140.706348 -355.113844) (xy 139.842748 -355.113844) (xy 139.815473 -355.11342) (xy 139.761479 -355.105663)
			(xy 139.709138 -355.0903) (xy 139.659516 -355.067644) (xy 139.613625 -355.038156) (xy 139.572397 -355.002437)
			(xy 139.536672 -354.961214) (xy 139.507179 -354.915326) (xy 139.484517 -354.865707) (xy 139.469147 -354.813368)
			(xy 139.461384 -354.759374) (xy 137.97868 -354.759374) (xy 137.970918 -354.813356) (xy 137.955552 -354.865687)
			(xy 137.932895 -354.915298) (xy 137.903408 -354.961181) (xy 137.867691 -355.002399) (xy 137.826471 -355.038115)
			(xy 137.780588 -355.067601) (xy 137.730976 -355.090256) (xy 137.678644 -355.105621) (xy 137.624658 -355.113381)
			(xy 137.597388 -355.113844) (xy 136.733788 -355.113844) (xy 136.706518 -355.113393) (xy 136.652533 -355.105629)
			(xy 136.600203 -355.090262) (xy 136.550591 -355.067604) (xy 136.50471 -355.038117) (xy 136.463492 -355.0024)
			(xy 136.427776 -354.96118) (xy 136.39829 -354.915298) (xy 136.375634 -354.865686) (xy 136.360268 -354.813355)
			(xy 136.352506 -354.75937) (xy 134.869658 -354.75937) (xy 134.861897 -354.813345) (xy 134.846534 -354.86567)
			(xy 134.823881 -354.915276) (xy 134.794399 -354.961154) (xy 134.758688 -355.002369) (xy 134.717476 -355.038082)
			(xy 134.671601 -355.067567) (xy 134.621997 -355.090224) (xy 134.569673 -355.105591) (xy 134.515695 -355.113356)
			(xy 134.488428 -355.113844) (xy 133.624828 -355.113844) (xy 133.597554 -355.113418) (xy 133.543562 -355.105659)
			(xy 133.491223 -355.090295) (xy 133.441604 -355.067638) (xy 133.395715 -355.038149) (xy 133.35449 -355.00243)
			(xy 133.318768 -354.961207) (xy 133.289276 -354.91532) (xy 133.266615 -354.865703) (xy 133.251247 -354.813365)
			(xy 133.243484 -354.759374) (xy 131.76078 -354.759374) (xy 131.753018 -354.813358) (xy 131.737651 -354.865691)
			(xy 131.714992 -354.915304) (xy 131.685503 -354.961187) (xy 131.649783 -355.002406) (xy 131.608561 -355.038122)
			(xy 131.562676 -355.067607) (xy 131.513061 -355.090262) (xy 131.460727 -355.105625) (xy 131.406739 -355.113383)
			(xy 131.379468 -355.113844) (xy 130.515868 -355.113844) (xy 130.488599 -355.113391) (xy 130.434616 -355.105626)
			(xy 130.382288 -355.090257) (xy 130.33268 -355.067598) (xy 130.2868 -355.03811) (xy 130.245585 -355.002393)
			(xy 130.209871 -354.961174) (xy 130.180387 -354.915292) (xy 130.157732 -354.865682) (xy 130.142368 -354.813353)
			(xy 130.134606 -354.759369) (xy 128.651758 -354.759369) (xy 128.643997 -354.813348) (xy 128.628632 -354.865675)
			(xy 128.605978 -354.915282) (xy 128.576494 -354.96116) (xy 128.540781 -355.002376) (xy 128.499567 -355.038089)
			(xy 128.453689 -355.067574) (xy 128.404082 -355.09023) (xy 128.351756 -355.105595) (xy 128.297776 -355.113357)
			(xy 128.270508 -355.113844) (xy 127.406908 -355.113844) (xy 127.379635 -355.113417) (xy 127.325645 -355.105655)
			(xy 127.273309 -355.090289) (xy 127.223692 -355.067631) (xy 127.177806 -355.038142) (xy 127.136583 -355.002423)
			(xy 127.100863 -354.961201) (xy 127.071373 -354.915315) (xy 127.048714 -354.865699) (xy 127.033346 -354.813363)
			(xy 127.025584 -354.759373) (xy 125.542757 -354.759373) (xy 125.534998 -354.813343) (xy 125.519636 -354.865666)
			(xy 125.496984 -354.915271) (xy 125.467504 -354.961147) (xy 125.431795 -355.002361) (xy 125.390586 -355.038075)
			(xy 125.344713 -355.067561) (xy 125.295111 -355.090219) (xy 125.24279 -355.105587) (xy 125.188814 -355.113354)
			(xy 125.161548 -355.113844) (xy 124.297948 -355.113844) (xy 124.270673 -355.11342) (xy 124.216679 -355.105663)
			(xy 124.164338 -355.0903) (xy 124.114716 -355.067644) (xy 124.068825 -355.038156) (xy 124.027597 -355.002437)
			(xy 123.991872 -354.961214) (xy 123.962379 -354.915326) (xy 123.939717 -354.865707) (xy 123.924347 -354.813368)
			(xy 123.916584 -354.759374) (xy 122.43388 -354.759374) (xy 122.426118 -354.813356) (xy 122.410752 -354.865687)
			(xy 122.388095 -354.915298) (xy 122.358608 -354.961181) (xy 122.322891 -355.002399) (xy 122.281671 -355.038115)
			(xy 122.235788 -355.067601) (xy 122.186176 -355.090256) (xy 122.133844 -355.105621) (xy 122.079858 -355.113381)
			(xy 122.052588 -355.113844) (xy 121.188988 -355.113844) (xy 121.161718 -355.113393) (xy 121.107733 -355.105629)
			(xy 121.055403 -355.090262) (xy 121.005791 -355.067604) (xy 120.95991 -355.038117) (xy 120.918692 -355.0024)
			(xy 120.882976 -354.96118) (xy 120.85349 -354.915298) (xy 120.830834 -354.865686) (xy 120.815468 -354.813355)
			(xy 120.807706 -354.75937) (xy 119.324858 -354.75937) (xy 119.317097 -354.813345) (xy 119.301734 -354.86567)
			(xy 119.279081 -354.915276) (xy 119.249599 -354.961154) (xy 119.213888 -355.002369) (xy 119.172676 -355.038082)
			(xy 119.126801 -355.067567) (xy 119.077197 -355.090224) (xy 119.024873 -355.105591) (xy 118.970895 -355.113356)
			(xy 118.943628 -355.113844) (xy 118.080028 -355.113844) (xy 118.052754 -355.113418) (xy 117.998762 -355.105659)
			(xy 117.946423 -355.090295) (xy 117.896804 -355.067638) (xy 117.850915 -355.038149) (xy 117.80969 -355.00243)
			(xy 117.773968 -354.961207) (xy 117.744476 -354.91532) (xy 117.721815 -354.865703) (xy 117.706447 -354.813365)
			(xy 117.698684 -354.759374) (xy 116.21598 -354.759374) (xy 116.208218 -354.813358) (xy 116.192851 -354.865691)
			(xy 116.170192 -354.915304) (xy 116.140703 -354.961187) (xy 116.104983 -355.002406) (xy 116.063761 -355.038122)
			(xy 116.017876 -355.067607) (xy 115.968261 -355.090262) (xy 115.915927 -355.105625) (xy 115.861939 -355.113383)
			(xy 115.834668 -355.113844) (xy 114.971068 -355.113844) (xy 114.943799 -355.113391) (xy 114.889816 -355.105626)
			(xy 114.837488 -355.090257) (xy 114.78788 -355.067598) (xy 114.742 -355.03811) (xy 114.700785 -355.002393)
			(xy 114.665071 -354.961174) (xy 114.635587 -354.915292) (xy 114.612932 -354.865682) (xy 114.597568 -354.813353)
			(xy 114.589806 -354.759369) (xy 93.706658 -354.759369) (xy 93.698898 -354.813344) (xy 93.683535 -354.865667)
			(xy 93.660883 -354.915272) (xy 93.631402 -354.961149) (xy 93.595693 -355.002364) (xy 93.554483 -355.038077)
			(xy 93.508609 -355.067563) (xy 93.459007 -355.09022) (xy 93.406685 -355.105589) (xy 93.352708 -355.113355)
			(xy 93.325442 -355.113844) (xy 92.461842 -355.113844) (xy 92.434568 -355.113419) (xy 92.380574 -355.105662)
			(xy 92.328234 -355.090298) (xy 92.278613 -355.067642) (xy 92.232722 -355.038154) (xy 92.191495 -355.002435)
			(xy 92.155771 -354.961212) (xy 92.126278 -354.915324) (xy 92.103616 -354.865706) (xy 92.088247 -354.813367)
			(xy 92.080484 -354.759374) (xy 90.597781 -354.759374) (xy 90.590018 -354.813356) (xy 90.574652 -354.865688)
			(xy 90.551994 -354.9153) (xy 90.522506 -354.961182) (xy 90.486788 -355.002401) (xy 90.445568 -355.038117)
			(xy 90.399684 -355.067603) (xy 90.350071 -355.090258) (xy 90.297739 -355.105622) (xy 90.243753 -355.113382)
			(xy 90.216482 -355.113844) (xy 89.352882 -355.113844) (xy 89.325612 -355.113392) (xy 89.271628 -355.105628)
			(xy 89.219298 -355.090261) (xy 89.169688 -355.067602) (xy 89.123807 -355.038115) (xy 89.08259 -355.002398)
			(xy 89.046875 -354.961178) (xy 89.017389 -354.915296) (xy 88.994733 -354.865685) (xy 88.979368 -354.813354)
			(xy 88.971606 -354.75937) (xy 87.488758 -354.75937) (xy 87.480997 -354.813346) (xy 87.465633 -354.865672)
			(xy 87.44298 -354.915278) (xy 87.413497 -354.961156) (xy 87.377786 -355.002371) (xy 87.336573 -355.038084)
			(xy 87.290697 -355.067569) (xy 87.241092 -355.090226) (xy 87.188768 -355.105592) (xy 87.134789 -355.113356)
			(xy 87.107522 -355.113844) (xy 86.243922 -355.113844) (xy 86.216649 -355.113418) (xy 86.162657 -355.105658)
			(xy 86.110319 -355.090293) (xy 86.060701 -355.067636) (xy 86.014812 -355.038147) (xy 85.973588 -355.002428)
			(xy 85.937866 -354.961205) (xy 85.908375 -354.915318) (xy 85.885715 -354.865702) (xy 85.870347 -354.813365)
			(xy 85.862584 -354.759373) (xy 84.37988 -354.759373) (xy 84.372118 -354.813359) (xy 84.35675 -354.865692)
			(xy 84.334091 -354.915306) (xy 84.304601 -354.961189) (xy 84.268881 -355.002408) (xy 84.227659 -355.038124)
			(xy 84.181772 -355.067609) (xy 84.132157 -355.090264) (xy 84.079822 -355.105626) (xy 84.025833 -355.113383)
			(xy 83.998562 -355.113844) (xy 83.134962 -355.113844) (xy 83.107693 -355.113391) (xy 83.053711 -355.105625)
			(xy 83.001384 -355.090255) (xy 82.951776 -355.067596) (xy 82.905898 -355.038107) (xy 82.864683 -355.00239)
			(xy 82.82897 -354.961172) (xy 82.799486 -354.915291) (xy 82.776832 -354.865681) (xy 82.761467 -354.813352)
			(xy 82.753706 -354.759369) (xy 81.270858 -354.759369) (xy 81.263096 -354.813349) (xy 81.247732 -354.865676)
			(xy 81.225077 -354.915283) (xy 81.195593 -354.961162) (xy 81.159879 -355.002378) (xy 81.118664 -355.038091)
			(xy 81.072785 -355.067576) (xy 81.023178 -355.090231) (xy 80.970851 -355.105596) (xy 80.91687 -355.113357)
			(xy 80.889602 -355.113844) (xy 80.026002 -355.113844) (xy 79.99873 -355.113417) (xy 79.94474 -355.105654)
			(xy 79.892405 -355.090288) (xy 79.842789 -355.067629) (xy 79.796903 -355.03814) (xy 79.755681 -355.002421)
			(xy 79.719961 -354.961199) (xy 79.690472 -354.915313) (xy 79.667813 -354.865697) (xy 79.652446 -354.813362)
			(xy 79.644684 -354.759372) (xy 78.161857 -354.759372) (xy 78.154098 -354.813344) (xy 78.138735 -354.865667)
			(xy 78.116083 -354.915272) (xy 78.086602 -354.961149) (xy 78.050893 -355.002364) (xy 78.009683 -355.038077)
			(xy 77.963809 -355.067563) (xy 77.914207 -355.09022) (xy 77.861885 -355.105589) (xy 77.807908 -355.113355)
			(xy 77.780642 -355.113844) (xy 76.917042 -355.113844) (xy 76.889768 -355.113419) (xy 76.835774 -355.105662)
			(xy 76.783434 -355.090298) (xy 76.733813 -355.067642) (xy 76.687922 -355.038154) (xy 76.646695 -355.002435)
			(xy 76.610971 -354.961212) (xy 76.581478 -354.915324) (xy 76.558816 -354.865706) (xy 76.543447 -354.813367)
			(xy 76.535684 -354.759374) (xy 75.052981 -354.759374) (xy 75.045218 -354.813356) (xy 75.029852 -354.865688)
			(xy 75.007194 -354.9153) (xy 74.977706 -354.961182) (xy 74.941988 -355.002401) (xy 74.900768 -355.038117)
			(xy 74.854884 -355.067603) (xy 74.805271 -355.090258) (xy 74.752939 -355.105622) (xy 74.698953 -355.113382)
			(xy 74.671682 -355.113844) (xy 73.808082 -355.113844) (xy 73.780812 -355.113392) (xy 73.726828 -355.105628)
			(xy 73.674498 -355.090261) (xy 73.624888 -355.067602) (xy 73.579007 -355.038115) (xy 73.53779 -355.002398)
			(xy 73.502075 -354.961178) (xy 73.472589 -354.915296) (xy 73.449933 -354.865685) (xy 73.434568 -354.813354)
			(xy 73.426806 -354.75937) (xy 71.943958 -354.75937) (xy 71.936197 -354.813346) (xy 71.920833 -354.865672)
			(xy 71.89818 -354.915278) (xy 71.868697 -354.961156) (xy 71.832986 -355.002371) (xy 71.791773 -355.038084)
			(xy 71.745897 -355.067569) (xy 71.696292 -355.090226) (xy 71.643968 -355.105592) (xy 71.589989 -355.113356)
			(xy 71.562722 -355.113844) (xy 70.699122 -355.113844) (xy 70.671849 -355.113418) (xy 70.617857 -355.105658)
			(xy 70.565519 -355.090293) (xy 70.515901 -355.067636) (xy 70.470012 -355.038147) (xy 70.428788 -355.002428)
			(xy 70.393066 -354.961205) (xy 70.363575 -354.915318) (xy 70.340915 -354.865702) (xy 70.325547 -354.813365)
			(xy 70.317784 -354.759373) (xy 68.83508 -354.759373) (xy 68.827318 -354.813359) (xy 68.81195 -354.865692)
			(xy 68.789291 -354.915306) (xy 68.759801 -354.961189) (xy 68.724081 -355.002408) (xy 68.682859 -355.038124)
			(xy 68.636972 -355.067609) (xy 68.587357 -355.090264) (xy 68.535022 -355.105626) (xy 68.481033 -355.113383)
			(xy 68.453762 -355.113844) (xy 67.590162 -355.113844) (xy 67.562893 -355.113391) (xy 67.508911 -355.105625)
			(xy 67.456584 -355.090255) (xy 67.406976 -355.067596) (xy 67.361098 -355.038107) (xy 67.319883 -355.00239)
			(xy 67.28417 -354.961172) (xy 67.254686 -354.915291) (xy 67.232032 -354.865681) (xy 67.216667 -354.813352)
			(xy 67.208906 -354.759369) (xy 65.726058 -354.759369) (xy 65.718296 -354.813349) (xy 65.702932 -354.865676)
			(xy 65.680277 -354.915283) (xy 65.650793 -354.961162) (xy 65.615079 -355.002378) (xy 65.573864 -355.038091)
			(xy 65.527985 -355.067576) (xy 65.478378 -355.090231) (xy 65.426051 -355.105596) (xy 65.37207 -355.113357)
			(xy 65.344802 -355.113844) (xy 64.481202 -355.113844) (xy 64.45393 -355.113417) (xy 64.39994 -355.105654)
			(xy 64.347605 -355.090288) (xy 64.297989 -355.067629) (xy 64.252103 -355.03814) (xy 64.210881 -355.002421)
			(xy 64.175161 -354.961199) (xy 64.145672 -354.915313) (xy 64.123013 -354.865697) (xy 64.107646 -354.813362)
			(xy 64.099884 -354.759372) (xy 51.666857 -354.759372) (xy 51.659098 -354.813343) (xy 51.643736 -354.865666)
			(xy 51.621084 -354.915271) (xy 51.591604 -354.961147) (xy 51.555895 -355.002361) (xy 51.514686 -355.038075)
			(xy 51.468813 -355.067561) (xy 51.419211 -355.090219) (xy 51.36689 -355.105587) (xy 51.312914 -355.113354)
			(xy 51.285648 -355.113844) (xy 50.422048 -355.113844) (xy 50.394773 -355.11342) (xy 50.340779 -355.105663)
			(xy 50.288438 -355.0903) (xy 50.238816 -355.067644) (xy 50.192925 -355.038156) (xy 50.151697 -355.002437)
			(xy 50.115972 -354.961214) (xy 50.086479 -354.915326) (xy 50.063817 -354.865707) (xy 50.048447 -354.813368)
			(xy 50.040684 -354.759374) (xy 48.55798 -354.759374) (xy 48.550218 -354.813356) (xy 48.534852 -354.865687)
			(xy 48.512195 -354.915298) (xy 48.482708 -354.961181) (xy 48.446991 -355.002399) (xy 48.405771 -355.038115)
			(xy 48.359888 -355.067601) (xy 48.310276 -355.090256) (xy 48.257944 -355.105621) (xy 48.203958 -355.113381)
			(xy 48.176688 -355.113844) (xy 47.313088 -355.113844) (xy 47.285818 -355.113393) (xy 47.231833 -355.105629)
			(xy 47.179503 -355.090262) (xy 47.129891 -355.067604) (xy 47.08401 -355.038117) (xy 47.042792 -355.0024)
			(xy 47.007076 -354.96118) (xy 46.97759 -354.915298) (xy 46.954934 -354.865686) (xy 46.939568 -354.813355)
			(xy 46.931806 -354.75937) (xy 45.448958 -354.75937) (xy 45.441197 -354.813345) (xy 45.425834 -354.86567)
			(xy 45.403181 -354.915276) (xy 45.373699 -354.961154) (xy 45.337988 -355.002369) (xy 45.296776 -355.038082)
			(xy 45.250901 -355.067567) (xy 45.201297 -355.090224) (xy 45.148973 -355.105591) (xy 45.094995 -355.113356)
			(xy 45.067728 -355.113844) (xy 44.204128 -355.113844) (xy 44.176854 -355.113418) (xy 44.122862 -355.105659)
			(xy 44.070523 -355.090295) (xy 44.020904 -355.067638) (xy 43.975015 -355.038149) (xy 43.93379 -355.00243)
			(xy 43.898068 -354.961207) (xy 43.868576 -354.91532) (xy 43.845915 -354.865703) (xy 43.830547 -354.813365)
			(xy 43.822784 -354.759374) (xy 42.34008 -354.759374) (xy 42.332318 -354.813358) (xy 42.316951 -354.865691)
			(xy 42.294292 -354.915304) (xy 42.264803 -354.961187) (xy 42.229083 -355.002406) (xy 42.187861 -355.038122)
			(xy 42.141976 -355.067607) (xy 42.092361 -355.090262) (xy 42.040027 -355.105625) (xy 41.986039 -355.113383)
			(xy 41.958768 -355.113844) (xy 41.095168 -355.113844) (xy 41.067899 -355.113391) (xy 41.013916 -355.105626)
			(xy 40.961588 -355.090257) (xy 40.91198 -355.067598) (xy 40.8661 -355.03811) (xy 40.824885 -355.002393)
			(xy 40.789171 -354.961174) (xy 40.759687 -354.915292) (xy 40.737032 -354.865682) (xy 40.721668 -354.813353)
			(xy 40.713906 -354.759369) (xy 39.231058 -354.759369) (xy 39.223297 -354.813348) (xy 39.207932 -354.865675)
			(xy 39.185278 -354.915282) (xy 39.155794 -354.96116) (xy 39.120081 -355.002376) (xy 39.078867 -355.038089)
			(xy 39.032989 -355.067574) (xy 38.983382 -355.09023) (xy 38.931056 -355.105595) (xy 38.877076 -355.113357)
			(xy 38.849808 -355.113844) (xy 37.986208 -355.113844) (xy 37.958935 -355.113417) (xy 37.904945 -355.105655)
			(xy 37.852609 -355.090289) (xy 37.802992 -355.067631) (xy 37.757106 -355.038142) (xy 37.715883 -355.002423)
			(xy 37.680163 -354.961201) (xy 37.650673 -354.915315) (xy 37.628014 -354.865699) (xy 37.612646 -354.813363)
			(xy 37.604884 -354.759373) (xy 36.122057 -354.759373) (xy 36.114298 -354.813343) (xy 36.098936 -354.865666)
			(xy 36.076284 -354.915271) (xy 36.046804 -354.961147) (xy 36.011095 -355.002361) (xy 35.969886 -355.038075)
			(xy 35.924013 -355.067561) (xy 35.874411 -355.090219) (xy 35.82209 -355.105587) (xy 35.768114 -355.113354)
			(xy 35.740848 -355.113844) (xy 34.877248 -355.113844) (xy 34.849973 -355.11342) (xy 34.795979 -355.105663)
			(xy 34.743638 -355.0903) (xy 34.694016 -355.067644) (xy 34.648125 -355.038156) (xy 34.606897 -355.002437)
			(xy 34.571172 -354.961214) (xy 34.541679 -354.915326) (xy 34.519017 -354.865707) (xy 34.503647 -354.813368)
			(xy 34.495884 -354.759374) (xy 33.01318 -354.759374) (xy 33.005418 -354.813356) (xy 32.990052 -354.865687)
			(xy 32.967395 -354.915298) (xy 32.937908 -354.961181) (xy 32.902191 -355.002399) (xy 32.860971 -355.038115)
			(xy 32.815088 -355.067601) (xy 32.765476 -355.090256) (xy 32.713144 -355.105621) (xy 32.659158 -355.113381)
			(xy 32.631888 -355.113844) (xy 31.768288 -355.113844) (xy 31.741018 -355.113393) (xy 31.687033 -355.105629)
			(xy 31.634703 -355.090262) (xy 31.585091 -355.067604) (xy 31.53921 -355.038117) (xy 31.497992 -355.0024)
			(xy 31.462276 -354.96118) (xy 31.43279 -354.915298) (xy 31.410134 -354.865686) (xy 31.394768 -354.813355)
			(xy 31.387006 -354.75937) (xy 29.904158 -354.75937) (xy 29.896397 -354.813345) (xy 29.881034 -354.86567)
			(xy 29.858381 -354.915276) (xy 29.828899 -354.961154) (xy 29.793188 -355.002369) (xy 29.751976 -355.038082)
			(xy 29.706101 -355.067567) (xy 29.656497 -355.090224) (xy 29.604173 -355.105591) (xy 29.550195 -355.113356)
			(xy 29.522928 -355.113844) (xy 28.659328 -355.113844) (xy 28.632054 -355.113418) (xy 28.578062 -355.105659)
			(xy 28.525723 -355.090295) (xy 28.476104 -355.067638) (xy 28.430215 -355.038149) (xy 28.38899 -355.00243)
			(xy 28.353268 -354.961207) (xy 28.323776 -354.91532) (xy 28.301115 -354.865703) (xy 28.285747 -354.813365)
			(xy 28.277984 -354.759374) (xy 26.79528 -354.759374) (xy 26.787518 -354.813358) (xy 26.772151 -354.865691)
			(xy 26.749492 -354.915304) (xy 26.720003 -354.961187) (xy 26.684283 -355.002406) (xy 26.643061 -355.038122)
			(xy 26.597176 -355.067607) (xy 26.547561 -355.090262) (xy 26.495227 -355.105625) (xy 26.441239 -355.113383)
			(xy 26.413968 -355.113844) (xy 25.550368 -355.113844) (xy 25.523099 -355.113391) (xy 25.469116 -355.105626)
			(xy 25.416788 -355.090257) (xy 25.36718 -355.067598) (xy 25.3213 -355.03811) (xy 25.280085 -355.002393)
			(xy 25.244371 -354.961174) (xy 25.214887 -354.915292) (xy 25.192232 -354.865682) (xy 25.176868 -354.813353)
			(xy 25.169106 -354.759369) (xy 23.686258 -354.759369) (xy 23.678497 -354.813348) (xy 23.663132 -354.865675)
			(xy 23.640478 -354.915282) (xy 23.610994 -354.96116) (xy 23.575281 -355.002376) (xy 23.534067 -355.038089)
			(xy 23.488189 -355.067574) (xy 23.438582 -355.09023) (xy 23.386256 -355.105595) (xy 23.332276 -355.113357)
			(xy 23.305008 -355.113844) (xy 22.441408 -355.113844) (xy 22.414135 -355.113417) (xy 22.360145 -355.105655)
			(xy 22.307809 -355.090289) (xy 22.258192 -355.067631) (xy 22.212306 -355.038142) (xy 22.171083 -355.002423)
			(xy 22.135363 -354.961201) (xy 22.105873 -354.915315) (xy 22.083214 -354.865699) (xy 22.067846 -354.813363)
			(xy 22.060084 -354.759373) (xy 0.509016 -354.759373) (xy 0.509016 -357.784969) (xy 22.060131 -357.784969)
			(xy 22.060131 -357.730431) (xy 22.067893 -357.676447) (xy 22.083259 -357.624118) (xy 22.105915 -357.574508)
			(xy 22.135401 -357.528628) (xy 22.171117 -357.487411) (xy 22.212334 -357.451696) (xy 22.258215 -357.422211)
			(xy 22.307826 -357.399556) (xy 22.360155 -357.384191) (xy 22.414139 -357.376431) (xy 22.441408 -357.375968)
			(xy 23.305008 -357.375968) (xy 23.332279 -357.376395) (xy 23.386266 -357.384158) (xy 23.438599 -357.399525)
			(xy 23.488212 -357.422184) (xy 23.534095 -357.451672) (xy 23.575315 -357.48739) (xy 23.611032 -357.528611)
			(xy 23.64052 -357.574495) (xy 23.663177 -357.624109) (xy 23.678543 -357.676442) (xy 23.686306 -357.730429)
			(xy 23.686306 -357.784966) (xy 25.169154 -357.784966) (xy 25.169154 -357.730434) (xy 25.176914 -357.676458)
			(xy 25.192277 -357.624135) (xy 25.214929 -357.574531) (xy 25.24441 -357.528655) (xy 25.280119 -357.487441)
			(xy 25.321329 -357.451729) (xy 25.367203 -357.422244) (xy 25.416805 -357.399588) (xy 25.469126 -357.384221)
			(xy 25.523102 -357.376457) (xy 25.550368 -357.375968) (xy 26.413968 -357.375968) (xy 26.441243 -357.376369)
			(xy 26.495237 -357.384128) (xy 26.547578 -357.399493) (xy 26.597199 -357.422151) (xy 26.64309 -357.45164)
			(xy 26.684317 -357.48736) (xy 26.720041 -357.528584) (xy 26.749534 -357.574473) (xy 26.772196 -357.624092)
			(xy 26.787565 -357.676431) (xy 26.795328 -357.730425) (xy 26.795328 -357.78497) (xy 28.278031 -357.78497)
			(xy 28.278032 -357.73043) (xy 28.285794 -357.676445) (xy 28.30116 -357.624114) (xy 28.323818 -357.574503)
			(xy 28.353306 -357.528621) (xy 28.389024 -357.487404) (xy 28.430244 -357.451689) (xy 28.476127 -357.422205)
			(xy 28.52574 -357.39955) (xy 28.578072 -357.384188) (xy 28.632058 -357.37643) (xy 28.659328 -357.375968)
			(xy 29.522928 -357.375968) (xy 29.550198 -357.376396) (xy 29.604183 -357.384162) (xy 29.656513 -357.399531)
			(xy 29.706124 -357.42219) (xy 29.752005 -357.451679) (xy 29.793222 -357.487397) (xy 29.828937 -357.528618)
			(xy 29.858423 -357.574501) (xy 29.881079 -357.624113) (xy 29.896444 -357.676444) (xy 29.904206 -357.73043)
			(xy 29.904206 -357.784967) (xy 31.387054 -357.784967) (xy 31.387054 -357.730433) (xy 31.394815 -357.676455)
			(xy 31.410179 -357.624131) (xy 31.432832 -357.574525) (xy 31.462315 -357.528648) (xy 31.498026 -357.487434)
			(xy 31.539239 -357.451722) (xy 31.585115 -357.422238) (xy 31.634719 -357.399583) (xy 31.687043 -357.384218)
			(xy 31.741021 -357.376455) (xy 31.768288 -357.375968) (xy 32.631888 -357.375968) (xy 32.659162 -357.376371)
			(xy 32.713154 -357.384132) (xy 32.765492 -357.399499) (xy 32.815111 -357.422157) (xy 32.861 -357.451647)
			(xy 32.902224 -357.487367) (xy 32.937946 -357.528591) (xy 32.967437 -357.574479) (xy 32.990097 -357.624096)
			(xy 33.005465 -357.676434) (xy 33.013228 -357.730426) (xy 33.013228 -357.784971) (xy 34.495932 -357.784971)
			(xy 34.495932 -357.730429) (xy 34.503694 -357.676442) (xy 34.519062 -357.62411) (xy 34.541721 -357.574497)
			(xy 34.571211 -357.528615) (xy 34.606931 -357.487397) (xy 34.648153 -357.451682) (xy 34.694039 -357.422198)
			(xy 34.743655 -357.399545) (xy 34.795989 -357.384184) (xy 34.849977 -357.376428) (xy 34.877248 -357.375968)
			(xy 35.740848 -357.375968) (xy 35.768117 -357.376398) (xy 35.8221 -357.384166) (xy 35.874428 -357.399536)
			(xy 35.924036 -357.422197) (xy 35.969914 -357.451687) (xy 36.011129 -357.487405) (xy 36.046842 -357.528624)
			(xy 36.076326 -357.574506) (xy 36.09898 -357.624117) (xy 36.114345 -357.676447) (xy 36.122106 -357.730431)
			(xy 36.122106 -357.784969) (xy 37.604931 -357.784969) (xy 37.604931 -357.730431) (xy 37.612693 -357.676447)
			(xy 37.628059 -357.624118) (xy 37.650715 -357.574508) (xy 37.680201 -357.528628) (xy 37.715917 -357.487411)
			(xy 37.757134 -357.451696) (xy 37.803015 -357.422211) (xy 37.852626 -357.399556) (xy 37.904955 -357.384191)
			(xy 37.958939 -357.376431) (xy 37.986208 -357.375968) (xy 38.849808 -357.375968) (xy 38.877079 -357.376395)
			(xy 38.931066 -357.384158) (xy 38.983399 -357.399525) (xy 39.033012 -357.422184) (xy 39.078895 -357.451672)
			(xy 39.120115 -357.48739) (xy 39.155832 -357.528611) (xy 39.18532 -357.574495) (xy 39.207977 -357.624109)
			(xy 39.223343 -357.676442) (xy 39.231106 -357.730429) (xy 39.231106 -357.784966) (xy 40.713954 -357.784966)
			(xy 40.713954 -357.730434) (xy 40.721714 -357.676458) (xy 40.737077 -357.624135) (xy 40.759729 -357.574531)
			(xy 40.78921 -357.528655) (xy 40.824919 -357.487441) (xy 40.866129 -357.451729) (xy 40.912003 -357.422244)
			(xy 40.961605 -357.399588) (xy 41.013926 -357.384221) (xy 41.067902 -357.376457) (xy 41.095168 -357.375968)
			(xy 41.958768 -357.375968) (xy 41.986043 -357.376369) (xy 42.040037 -357.384128) (xy 42.092378 -357.399493)
			(xy 42.141999 -357.422151) (xy 42.18789 -357.45164) (xy 42.229117 -357.48736) (xy 42.264841 -357.528584)
			(xy 42.294334 -357.574473) (xy 42.316996 -357.624092) (xy 42.332365 -357.676431) (xy 42.340128 -357.730425)
			(xy 42.340128 -357.78497) (xy 43.822831 -357.78497) (xy 43.822832 -357.73043) (xy 43.830594 -357.676445)
			(xy 43.84596 -357.624114) (xy 43.868618 -357.574503) (xy 43.898106 -357.528621) (xy 43.933824 -357.487404)
			(xy 43.975044 -357.451689) (xy 44.020927 -357.422205) (xy 44.07054 -357.39955) (xy 44.122872 -357.384188)
			(xy 44.176858 -357.37643) (xy 44.204128 -357.375968) (xy 45.067728 -357.375968) (xy 45.094998 -357.376396)
			(xy 45.148983 -357.384162) (xy 45.201313 -357.399531) (xy 45.250924 -357.42219) (xy 45.296805 -357.451679)
			(xy 45.338022 -357.487397) (xy 45.373737 -357.528618) (xy 45.403223 -357.574501) (xy 45.425879 -357.624113)
			(xy 45.441244 -357.676444) (xy 45.449006 -357.73043) (xy 45.449006 -357.784967) (xy 46.931854 -357.784967)
			(xy 46.931854 -357.730433) (xy 46.939615 -357.676455) (xy 46.954979 -357.624131) (xy 46.977632 -357.574525)
			(xy 47.007115 -357.528648) (xy 47.042826 -357.487434) (xy 47.084039 -357.451722) (xy 47.129915 -357.422238)
			(xy 47.179519 -357.399583) (xy 47.231843 -357.384218) (xy 47.285821 -357.376455) (xy 47.313088 -357.375968)
			(xy 48.176688 -357.375968) (xy 48.203962 -357.376371) (xy 48.257954 -357.384132) (xy 48.310292 -357.399499)
			(xy 48.359911 -357.422157) (xy 48.4058 -357.451647) (xy 48.447024 -357.487367) (xy 48.482746 -357.528591)
			(xy 48.512237 -357.574479) (xy 48.534897 -357.624096) (xy 48.550265 -357.676434) (xy 48.558028 -357.730426)
			(xy 48.558028 -357.784971) (xy 50.040732 -357.784971) (xy 50.040732 -357.730429) (xy 50.048494 -357.676442)
			(xy 50.063862 -357.62411) (xy 50.086521 -357.574497) (xy 50.116011 -357.528615) (xy 50.151731 -357.487397)
			(xy 50.192953 -357.451682) (xy 50.238839 -357.422198) (xy 50.288455 -357.399545) (xy 50.340789 -357.384184)
			(xy 50.394777 -357.376428) (xy 50.422048 -357.375968) (xy 51.285648 -357.375968) (xy 51.312917 -357.376398)
			(xy 51.3669 -357.384166) (xy 51.419228 -357.399536) (xy 51.468836 -357.422197) (xy 51.514714 -357.451687)
			(xy 51.555929 -357.487405) (xy 51.591642 -357.528624) (xy 51.621126 -357.574506) (xy 51.64378 -357.624117)
			(xy 51.659145 -357.676447) (xy 51.666906 -357.730431) (xy 51.666906 -357.784969) (xy 64.099931 -357.784969)
			(xy 64.099931 -357.730431) (xy 64.107693 -357.676448) (xy 64.123058 -357.62412) (xy 64.145714 -357.57451)
			(xy 64.1752 -357.52863) (xy 64.210914 -357.487413) (xy 64.252132 -357.451698) (xy 64.298012 -357.422213)
			(xy 64.347621 -357.399557) (xy 64.39995 -357.384193) (xy 64.453933 -357.376431) (xy 64.481202 -357.375968)
			(xy 65.344802 -357.375968) (xy 65.372073 -357.376395) (xy 65.426061 -357.384157) (xy 65.478394 -357.399524)
			(xy 65.528008 -357.422182) (xy 65.573893 -357.45167) (xy 65.615113 -357.487388) (xy 65.650831 -357.528609)
			(xy 65.680319 -357.574493) (xy 65.702977 -357.624107) (xy 65.718343 -357.676441) (xy 65.726106 -357.730429)
			(xy 65.726106 -357.784966) (xy 67.208954 -357.784966) (xy 67.208954 -357.730435) (xy 67.216714 -357.676458)
			(xy 67.232077 -357.624136) (xy 67.254728 -357.574532) (xy 67.284208 -357.528657) (xy 67.319917 -357.487443)
			(xy 67.361126 -357.451731) (xy 67.406999 -357.422246) (xy 67.4566 -357.39959) (xy 67.508921 -357.384222)
			(xy 67.562897 -357.376457) (xy 67.590162 -357.375968) (xy 68.453762 -357.375968) (xy 68.481037 -357.376369)
			(xy 68.535032 -357.384127) (xy 68.587373 -357.399491) (xy 68.636995 -357.422149) (xy 68.682887 -357.451638)
			(xy 68.724115 -357.487358) (xy 68.75984 -357.528582) (xy 68.789333 -357.574471) (xy 68.811995 -357.624091)
			(xy 68.827365 -357.676431) (xy 68.835128 -357.730425) (xy 68.835128 -357.78497) (xy 70.317831 -357.78497)
			(xy 70.317831 -357.73043) (xy 70.325594 -357.676446) (xy 70.34096 -357.624115) (xy 70.363617 -357.574505)
			(xy 70.393105 -357.528623) (xy 70.428822 -357.487406) (xy 70.470041 -357.451691) (xy 70.515924 -357.422207)
			(xy 70.565536 -357.399552) (xy 70.617867 -357.384189) (xy 70.671852 -357.37643) (xy 70.699122 -357.375968)
			(xy 71.562722 -357.375968) (xy 71.589992 -357.376396) (xy 71.643978 -357.384161) (xy 71.696309 -357.399529)
			(xy 71.74592 -357.422189) (xy 71.791802 -357.451677) (xy 71.83302 -357.487395) (xy 71.868736 -357.528616)
			(xy 71.898222 -357.574499) (xy 71.920878 -357.624112) (xy 71.936244 -357.676444) (xy 71.944006 -357.730429)
			(xy 71.944006 -357.784966) (xy 73.426854 -357.784966) (xy 73.426854 -357.730434) (xy 73.434615 -357.676456)
			(xy 73.449978 -357.624132) (xy 73.472631 -357.574527) (xy 73.502113 -357.52865) (xy 73.537824 -357.487436)
			(xy 73.579036 -357.451724) (xy 73.624911 -357.42224) (xy 73.674515 -357.399584) (xy 73.726838 -357.384219)
			(xy 73.780816 -357.376456) (xy 73.808082 -357.375968) (xy 74.671682 -357.375968) (xy 74.698956 -357.37637)
			(xy 74.752949 -357.384131) (xy 74.805288 -357.399497) (xy 74.854907 -357.422155) (xy 74.900797 -357.451645)
			(xy 74.942022 -357.487365) (xy 74.977744 -357.528589) (xy 75.007236 -357.574477) (xy 75.029897 -357.624095)
			(xy 75.045265 -357.676433) (xy 75.053028 -357.730426) (xy 75.053028 -357.784971) (xy 76.535732 -357.784971)
			(xy 76.535732 -357.730429) (xy 76.543494 -357.676443) (xy 76.558861 -357.624111) (xy 76.58152 -357.574499)
			(xy 76.611009 -357.528617) (xy 76.646729 -357.487399) (xy 76.687951 -357.451684) (xy 76.733836 -357.4222)
			(xy 76.78345 -357.399547) (xy 76.835784 -357.384185) (xy 76.889771 -357.376429) (xy 76.917042 -357.375968)
			(xy 77.780642 -357.375968) (xy 77.807912 -357.376397) (xy 77.861895 -357.384165) (xy 77.914223 -357.399535)
			(xy 77.963832 -357.422195) (xy 78.009711 -357.451684) (xy 78.050927 -357.487402) (xy 78.086641 -357.528622)
			(xy 78.116125 -357.574505) (xy 78.13878 -357.624116) (xy 78.154144 -357.676446) (xy 78.161906 -357.73043)
			(xy 78.161906 -357.784969) (xy 79.644731 -357.784969) (xy 79.644731 -357.730431) (xy 79.652493 -357.676448)
			(xy 79.667858 -357.62412) (xy 79.690514 -357.57451) (xy 79.72 -357.52863) (xy 79.755714 -357.487413)
			(xy 79.796932 -357.451698) (xy 79.842812 -357.422213) (xy 79.892421 -357.399557) (xy 79.94475 -357.384193)
			(xy 79.998733 -357.376431) (xy 80.026002 -357.375968) (xy 80.889602 -357.375968) (xy 80.916873 -357.376395)
			(xy 80.970861 -357.384157) (xy 81.023194 -357.399524) (xy 81.072808 -357.422182) (xy 81.118693 -357.45167)
			(xy 81.159913 -357.487388) (xy 81.195631 -357.528609) (xy 81.225119 -357.574493) (xy 81.247777 -357.624107)
			(xy 81.263143 -357.676441) (xy 81.270906 -357.730429) (xy 81.270906 -357.784966) (xy 82.753754 -357.784966)
			(xy 82.753754 -357.730435) (xy 82.761514 -357.676458) (xy 82.776877 -357.624136) (xy 82.799528 -357.574532)
			(xy 82.829008 -357.528657) (xy 82.864717 -357.487443) (xy 82.905926 -357.451731) (xy 82.951799 -357.422246)
			(xy 83.0014 -357.39959) (xy 83.053721 -357.384222) (xy 83.107697 -357.376457) (xy 83.134962 -357.375968)
			(xy 83.998562 -357.375968) (xy 84.025837 -357.376369) (xy 84.079832 -357.384127) (xy 84.132173 -357.399491)
			(xy 84.181795 -357.422149) (xy 84.227687 -357.451638) (xy 84.268915 -357.487358) (xy 84.30464 -357.528582)
			(xy 84.334133 -357.574471) (xy 84.356795 -357.624091) (xy 84.372165 -357.676431) (xy 84.379928 -357.730425)
			(xy 84.379928 -357.78497) (xy 85.862631 -357.78497) (xy 85.862631 -357.73043) (xy 85.870394 -357.676446)
			(xy 85.88576 -357.624115) (xy 85.908417 -357.574505) (xy 85.937905 -357.528623) (xy 85.973622 -357.487406)
			(xy 86.014841 -357.451691) (xy 86.060724 -357.422207) (xy 86.110336 -357.399552) (xy 86.162667 -357.384189)
			(xy 86.216652 -357.37643) (xy 86.243922 -357.375968) (xy 87.107522 -357.375968) (xy 87.134792 -357.376396)
			(xy 87.188778 -357.384161) (xy 87.241109 -357.399529) (xy 87.29072 -357.422189) (xy 87.336602 -357.451677)
			(xy 87.37782 -357.487395) (xy 87.413536 -357.528616) (xy 87.443022 -357.574499) (xy 87.465678 -357.624112)
			(xy 87.481044 -357.676444) (xy 87.488806 -357.730429) (xy 87.488806 -357.784966) (xy 88.971654 -357.784966)
			(xy 88.971654 -357.730434) (xy 88.979415 -357.676456) (xy 88.994778 -357.624132) (xy 89.017431 -357.574527)
			(xy 89.046913 -357.52865) (xy 89.082624 -357.487436) (xy 89.123836 -357.451724) (xy 89.169711 -357.42224)
			(xy 89.219315 -357.399584) (xy 89.271638 -357.384219) (xy 89.325616 -357.376456) (xy 89.352882 -357.375968)
			(xy 90.216482 -357.375968) (xy 90.243756 -357.37637) (xy 90.297749 -357.384131) (xy 90.350088 -357.399497)
			(xy 90.399707 -357.422155) (xy 90.445597 -357.451645) (xy 90.486822 -357.487365) (xy 90.522544 -357.528589)
			(xy 90.552036 -357.574477) (xy 90.574697 -357.624095) (xy 90.590065 -357.676433) (xy 90.597828 -357.730426)
			(xy 90.597828 -357.784971) (xy 92.080532 -357.784971) (xy 92.080532 -357.730429) (xy 92.088294 -357.676443)
			(xy 92.103661 -357.624111) (xy 92.12632 -357.574499) (xy 92.155809 -357.528617) (xy 92.191529 -357.487399)
			(xy 92.232751 -357.451684) (xy 92.278636 -357.4222) (xy 92.32825 -357.399547) (xy 92.380584 -357.384185)
			(xy 92.434571 -357.376429) (xy 92.461842 -357.375968) (xy 93.325442 -357.375968) (xy 93.352712 -357.376397)
			(xy 93.406695 -357.384165) (xy 93.459023 -357.399535) (xy 93.508632 -357.422195) (xy 93.554511 -357.451684)
			(xy 93.595727 -357.487402) (xy 93.631441 -357.528622) (xy 93.660925 -357.574505) (xy 93.68358 -357.624116)
			(xy 93.698944 -357.676446) (xy 93.706706 -357.73043) (xy 93.706706 -357.784966) (xy 114.589854 -357.784966)
			(xy 114.589854 -357.730434) (xy 114.597614 -357.676458) (xy 114.612977 -357.624135) (xy 114.635629 -357.574531)
			(xy 114.66511 -357.528655) (xy 114.700819 -357.487441) (xy 114.742029 -357.451729) (xy 114.787903 -357.422244)
			(xy 114.837505 -357.399588) (xy 114.889826 -357.384221) (xy 114.943802 -357.376457) (xy 114.971068 -357.375968)
			(xy 115.834668 -357.375968) (xy 115.861943 -357.376369) (xy 115.915937 -357.384128) (xy 115.968278 -357.399493)
			(xy 116.017899 -357.422151) (xy 116.06379 -357.45164) (xy 116.105017 -357.48736) (xy 116.140741 -357.528584)
			(xy 116.170234 -357.574473) (xy 116.192896 -357.624092) (xy 116.208265 -357.676431) (xy 116.216028 -357.730425)
			(xy 116.216028 -357.78497) (xy 117.698731 -357.78497) (xy 117.698732 -357.73043) (xy 117.706494 -357.676445)
			(xy 117.72186 -357.624114) (xy 117.744518 -357.574503) (xy 117.774006 -357.528621) (xy 117.809724 -357.487404)
			(xy 117.850944 -357.451689) (xy 117.896827 -357.422205) (xy 117.94644 -357.39955) (xy 117.998772 -357.384188)
			(xy 118.052758 -357.37643) (xy 118.080028 -357.375968) (xy 118.943628 -357.375968) (xy 118.970898 -357.376396)
			(xy 119.024883 -357.384162) (xy 119.077213 -357.399531) (xy 119.126824 -357.42219) (xy 119.172705 -357.451679)
			(xy 119.213922 -357.487397) (xy 119.249637 -357.528618) (xy 119.279123 -357.574501) (xy 119.301779 -357.624113)
			(xy 119.317144 -357.676444) (xy 119.324906 -357.73043) (xy 119.324906 -357.784967) (xy 120.807754 -357.784967)
			(xy 120.807754 -357.730433) (xy 120.815515 -357.676455) (xy 120.830879 -357.624131) (xy 120.853532 -357.574525)
			(xy 120.883015 -357.528648) (xy 120.918726 -357.487434) (xy 120.959939 -357.451722) (xy 121.005815 -357.422238)
			(xy 121.055419 -357.399583) (xy 121.107743 -357.384218) (xy 121.161721 -357.376455) (xy 121.188988 -357.375968)
			(xy 122.052588 -357.375968) (xy 122.079862 -357.376371) (xy 122.133854 -357.384132) (xy 122.186192 -357.399499)
			(xy 122.235811 -357.422157) (xy 122.2817 -357.451647) (xy 122.322924 -357.487367) (xy 122.358646 -357.528591)
			(xy 122.388137 -357.574479) (xy 122.410797 -357.624096) (xy 122.426165 -357.676434) (xy 122.433928 -357.730426)
			(xy 122.433928 -357.784971) (xy 123.916632 -357.784971) (xy 123.916632 -357.730429) (xy 123.924394 -357.676442)
			(xy 123.939762 -357.62411) (xy 123.962421 -357.574497) (xy 123.991911 -357.528615) (xy 124.027631 -357.487397)
			(xy 124.068853 -357.451682) (xy 124.114739 -357.422198) (xy 124.164355 -357.399545) (xy 124.216689 -357.384184)
			(xy 124.270677 -357.376428) (xy 124.297948 -357.375968) (xy 125.161548 -357.375968) (xy 125.188817 -357.376398)
			(xy 125.2428 -357.384166) (xy 125.295128 -357.399536) (xy 125.344736 -357.422197) (xy 125.390614 -357.451687)
			(xy 125.431829 -357.487405) (xy 125.467542 -357.528624) (xy 125.497026 -357.574506) (xy 125.51968 -357.624117)
			(xy 125.535045 -357.676447) (xy 125.542806 -357.730431) (xy 125.542806 -357.784969) (xy 127.025631 -357.784969)
			(xy 127.025631 -357.730431) (xy 127.033393 -357.676447) (xy 127.048759 -357.624118) (xy 127.071415 -357.574508)
			(xy 127.100901 -357.528628) (xy 127.136617 -357.487411) (xy 127.177834 -357.451696) (xy 127.223715 -357.422211)
			(xy 127.273326 -357.399556) (xy 127.325655 -357.384191) (xy 127.379639 -357.376431) (xy 127.406908 -357.375968)
			(xy 128.270508 -357.375968) (xy 128.297779 -357.376395) (xy 128.351766 -357.384158) (xy 128.404099 -357.399525)
			(xy 128.453712 -357.422184) (xy 128.499595 -357.451672) (xy 128.540815 -357.48739) (xy 128.576532 -357.528611)
			(xy 128.60602 -357.574495) (xy 128.628677 -357.624109) (xy 128.644043 -357.676442) (xy 128.651806 -357.730429)
			(xy 128.651806 -357.784966) (xy 130.134654 -357.784966) (xy 130.134654 -357.730434) (xy 130.142414 -357.676458)
			(xy 130.157777 -357.624135) (xy 130.180429 -357.574531) (xy 130.20991 -357.528655) (xy 130.245619 -357.487441)
			(xy 130.286829 -357.451729) (xy 130.332703 -357.422244) (xy 130.382305 -357.399588) (xy 130.434626 -357.384221)
			(xy 130.488602 -357.376457) (xy 130.515868 -357.375968) (xy 131.379468 -357.375968) (xy 131.406743 -357.376369)
			(xy 131.460737 -357.384128) (xy 131.513078 -357.399493) (xy 131.562699 -357.422151) (xy 131.60859 -357.45164)
			(xy 131.649817 -357.48736) (xy 131.685541 -357.528584) (xy 131.715034 -357.574473) (xy 131.737696 -357.624092)
			(xy 131.753065 -357.676431) (xy 131.760828 -357.730425) (xy 131.760828 -357.78497) (xy 133.243531 -357.78497)
			(xy 133.243532 -357.73043) (xy 133.251294 -357.676445) (xy 133.26666 -357.624114) (xy 133.289318 -357.574503)
			(xy 133.318806 -357.528621) (xy 133.354524 -357.487404) (xy 133.395744 -357.451689) (xy 133.441627 -357.422205)
			(xy 133.49124 -357.39955) (xy 133.543572 -357.384188) (xy 133.597558 -357.37643) (xy 133.624828 -357.375968)
			(xy 134.488428 -357.375968) (xy 134.515698 -357.376396) (xy 134.569683 -357.384162) (xy 134.622013 -357.399531)
			(xy 134.671624 -357.42219) (xy 134.717505 -357.451679) (xy 134.758722 -357.487397) (xy 134.794437 -357.528618)
			(xy 134.823923 -357.574501) (xy 134.846579 -357.624113) (xy 134.861944 -357.676444) (xy 134.869706 -357.73043)
			(xy 134.869706 -357.784967) (xy 136.352554 -357.784967) (xy 136.352554 -357.730433) (xy 136.360315 -357.676455)
			(xy 136.375679 -357.624131) (xy 136.398332 -357.574525) (xy 136.427815 -357.528648) (xy 136.463526 -357.487434)
			(xy 136.504739 -357.451722) (xy 136.550615 -357.422238) (xy 136.600219 -357.399583) (xy 136.652543 -357.384218)
			(xy 136.706521 -357.376455) (xy 136.733788 -357.375968) (xy 137.597388 -357.375968) (xy 137.624662 -357.376371)
			(xy 137.678654 -357.384132) (xy 137.730992 -357.399499) (xy 137.780611 -357.422157) (xy 137.8265 -357.451647)
			(xy 137.867724 -357.487367) (xy 137.903446 -357.528591) (xy 137.932937 -357.574479) (xy 137.955597 -357.624096)
			(xy 137.970965 -357.676434) (xy 137.978728 -357.730426) (xy 137.978728 -357.784971) (xy 139.461432 -357.784971)
			(xy 139.461432 -357.730429) (xy 139.469194 -357.676442) (xy 139.484562 -357.62411) (xy 139.507221 -357.574497)
			(xy 139.536711 -357.528615) (xy 139.572431 -357.487397) (xy 139.613653 -357.451682) (xy 139.659539 -357.422198)
			(xy 139.709155 -357.399545) (xy 139.761489 -357.384184) (xy 139.815477 -357.376428) (xy 139.842748 -357.375968)
			(xy 140.706348 -357.375968) (xy 140.733617 -357.376398) (xy 140.7876 -357.384166) (xy 140.839928 -357.399536)
			(xy 140.889536 -357.422197) (xy 140.935414 -357.451687) (xy 140.976629 -357.487405) (xy 141.012342 -357.528624)
			(xy 141.041826 -357.574506) (xy 141.06448 -357.624117) (xy 141.079845 -357.676447) (xy 141.087606 -357.730431)
			(xy 141.087606 -357.784969) (xy 142.570431 -357.784969) (xy 142.570431 -357.730431) (xy 142.578193 -357.676447)
			(xy 142.593559 -357.624118) (xy 142.616215 -357.574508) (xy 142.645701 -357.528628) (xy 142.681417 -357.487411)
			(xy 142.722634 -357.451696) (xy 142.768515 -357.422211) (xy 142.818126 -357.399556) (xy 142.870455 -357.384191)
			(xy 142.924439 -357.376431) (xy 142.951708 -357.375968) (xy 143.815308 -357.375968) (xy 143.842579 -357.376395)
			(xy 143.896566 -357.384158) (xy 143.948899 -357.399525) (xy 143.998512 -357.422184) (xy 144.044395 -357.451672)
			(xy 144.085615 -357.48739) (xy 144.121332 -357.528611) (xy 144.15082 -357.574495) (xy 144.173477 -357.624109)
			(xy 144.188843 -357.676442) (xy 144.196606 -357.730429) (xy 144.196606 -357.784965) (xy 158.695954 -357.784965)
			(xy 158.695954 -357.730435) (xy 158.703714 -357.67646) (xy 158.719076 -357.624138) (xy 158.741727 -357.574535)
			(xy 158.771206 -357.52866) (xy 158.806913 -357.487447) (xy 158.848122 -357.451735) (xy 158.893993 -357.42225)
			(xy 158.943593 -357.399593) (xy 158.995913 -357.384224) (xy 159.049887 -357.376458) (xy 159.077152 -357.375968)
			(xy 159.940752 -357.375968) (xy 159.968027 -357.376368) (xy 160.022024 -357.384125) (xy 160.074366 -357.399489)
			(xy 160.123989 -357.422145) (xy 160.169883 -357.451634) (xy 160.211112 -357.487354) (xy 160.246837 -357.528579)
			(xy 160.276332 -357.574468) (xy 160.298994 -357.624089) (xy 160.314364 -357.676429) (xy 160.322128 -357.730425)
			(xy 160.322128 -357.784969) (xy 161.804831 -357.784969) (xy 161.804831 -357.730431) (xy 161.812593 -357.676447)
			(xy 161.827959 -357.624117) (xy 161.850616 -357.574507) (xy 161.880102 -357.528627) (xy 161.915818 -357.487409)
			(xy 161.957036 -357.451695) (xy 162.002918 -357.42221) (xy 162.052529 -357.399555) (xy 162.104859 -357.384191)
			(xy 162.158843 -357.376431) (xy 162.186112 -357.375968) (xy 163.049712 -357.375968) (xy 163.076983 -357.376395)
			(xy 163.130969 -357.384159) (xy 163.183302 -357.399527) (xy 163.232914 -357.422185) (xy 163.278797 -357.451674)
			(xy 163.320017 -357.487392) (xy 163.355733 -357.528612) (xy 163.385221 -357.574496) (xy 163.407878 -357.62411)
			(xy 163.423244 -357.676442) (xy 163.431006 -357.730429) (xy 163.431006 -357.784966) (xy 164.913854 -357.784966)
			(xy 164.913854 -357.730434) (xy 164.921615 -357.676457) (xy 164.936977 -357.624134) (xy 164.95963 -357.57453)
			(xy 164.989111 -357.528654) (xy 165.02482 -357.48744) (xy 165.066031 -357.451727) (xy 165.111905 -357.422243)
			(xy 165.161508 -357.399587) (xy 165.21383 -357.384221) (xy 165.267806 -357.376456) (xy 165.295072 -357.375968)
			(xy 166.158672 -357.375968) (xy 166.185946 -357.37637) (xy 166.239941 -357.384129) (xy 166.292281 -357.399494)
			(xy 166.341901 -357.422152) (xy 166.387792 -357.451641) (xy 166.429019 -357.487361) (xy 166.464742 -357.528585)
			(xy 166.494235 -357.574474) (xy 166.516896 -357.624093) (xy 166.532265 -357.676432) (xy 166.540028 -357.730426)
			(xy 166.540028 -357.78497) (xy 168.022732 -357.78497) (xy 168.022732 -357.73043) (xy 168.030494 -357.676444)
			(xy 168.045861 -357.624113) (xy 168.068519 -357.574502) (xy 168.098007 -357.52862) (xy 168.133725 -357.487402)
			(xy 168.174946 -357.451688) (xy 168.22083 -357.422203) (xy 168.270443 -357.399549) (xy 168.322776 -357.384187)
			(xy 168.376762 -357.376429) (xy 168.404032 -357.375968) (xy 169.267632 -357.375968) (xy 169.294902 -357.376397)
			(xy 169.348886 -357.384163) (xy 169.401216 -357.399532) (xy 169.450826 -357.422192) (xy 169.496707 -357.451681)
			(xy 169.537924 -357.487399) (xy 169.573638 -357.528619) (xy 169.603124 -357.574502) (xy 169.625779 -357.624114)
			(xy 169.641144 -357.676445) (xy 169.648906 -357.73043) (xy 169.648906 -357.784967) (xy 171.131754 -357.784967)
			(xy 171.131754 -357.730433) (xy 171.139515 -357.676454) (xy 171.154879 -357.62413) (xy 171.177533 -357.574524)
			(xy 171.207016 -357.528647) (xy 171.242727 -357.487433) (xy 171.283941 -357.45172) (xy 171.329817 -357.422237)
			(xy 171.379422 -357.399582) (xy 171.431747 -357.384217) (xy 171.485725 -357.376455) (xy 171.512992 -357.375968)
			(xy 172.376592 -357.375968) (xy 172.403866 -357.376371) (xy 172.457857 -357.384133) (xy 172.510195 -357.3995)
			(xy 172.559813 -357.422159) (xy 172.605702 -357.451648) (xy 172.646926 -357.487368) (xy 172.682647 -357.528592)
			(xy 172.712138 -357.57448) (xy 172.734798 -357.624097) (xy 172.750165 -357.676435) (xy 172.757928 -357.730426)
			(xy 172.757928 -357.784965) (xy 174.240754 -357.784965) (xy 174.240754 -357.730435) (xy 174.248514 -357.67646)
			(xy 174.263876 -357.624138) (xy 174.286527 -357.574535) (xy 174.316006 -357.52866) (xy 174.351713 -357.487447)
			(xy 174.392922 -357.451735) (xy 174.438793 -357.42225) (xy 174.488393 -357.399593) (xy 174.540713 -357.384224)
			(xy 174.594687 -357.376458) (xy 174.621952 -357.375968) (xy 175.485552 -357.375968) (xy 175.512827 -357.376368)
			(xy 175.566824 -357.384125) (xy 175.619166 -357.399489) (xy 175.668789 -357.422145) (xy 175.714683 -357.451634)
			(xy 175.755912 -357.487354) (xy 175.791637 -357.528579) (xy 175.821132 -357.574468) (xy 175.843794 -357.624089)
			(xy 175.859164 -357.676429) (xy 175.866928 -357.730425) (xy 175.866928 -357.784969) (xy 177.349631 -357.784969)
			(xy 177.349631 -357.730431) (xy 177.357393 -357.676447) (xy 177.372759 -357.624117) (xy 177.395416 -357.574507)
			(xy 177.424902 -357.528627) (xy 177.460618 -357.487409) (xy 177.501836 -357.451695) (xy 177.547718 -357.42221)
			(xy 177.597329 -357.399555) (xy 177.649659 -357.384191) (xy 177.703643 -357.376431) (xy 177.730912 -357.375968)
			(xy 178.594512 -357.375968) (xy 178.621783 -357.376395) (xy 178.675769 -357.384159) (xy 178.728102 -357.399527)
			(xy 178.777714 -357.422185) (xy 178.823597 -357.451674) (xy 178.864817 -357.487392) (xy 178.900533 -357.528612)
			(xy 178.930021 -357.574496) (xy 178.952678 -357.62411) (xy 178.968044 -357.676442) (xy 178.975806 -357.730429)
			(xy 178.975806 -357.784966) (xy 180.458654 -357.784966) (xy 180.458654 -357.730434) (xy 180.466415 -357.676457)
			(xy 180.481777 -357.624134) (xy 180.50443 -357.57453) (xy 180.533911 -357.528654) (xy 180.56962 -357.48744)
			(xy 180.610831 -357.451727) (xy 180.656705 -357.422243) (xy 180.706308 -357.399587) (xy 180.75863 -357.384221)
			(xy 180.812606 -357.376456) (xy 180.839872 -357.375968) (xy 181.703472 -357.375968) (xy 181.730746 -357.37637)
			(xy 181.784741 -357.384129) (xy 181.837081 -357.399494) (xy 181.886701 -357.422152) (xy 181.932592 -357.451641)
			(xy 181.973819 -357.487361) (xy 182.009542 -357.528585) (xy 182.039035 -357.574474) (xy 182.061696 -357.624093)
			(xy 182.077065 -357.676432) (xy 182.084828 -357.730426) (xy 182.084828 -357.761176) (xy 183.567456 -357.761176)
			(xy 183.567456 -357.706624) (xy 183.57522 -357.652628) (xy 183.590589 -357.600287) (xy 183.613252 -357.550665)
			(xy 183.642746 -357.504775) (xy 183.678471 -357.463549) (xy 183.7197 -357.427827) (xy 183.765593 -357.398337)
			(xy 183.815217 -357.375678) (xy 183.867559 -357.360313) (xy 183.921556 -357.352553) (xy 183.948832 -357.352092)
			(xy 184.812432 -357.352092) (xy 184.839697 -357.352672) (xy 184.89367 -357.360437) (xy 184.94599 -357.375803)
			(xy 184.99559 -357.398458) (xy 185.041461 -357.427942) (xy 185.08267 -357.463653) (xy 185.118378 -357.504864)
			(xy 185.147857 -357.550738) (xy 185.170508 -357.60034) (xy 185.18587 -357.652661) (xy 185.19363 -357.706635)
			(xy 185.19363 -357.761165) (xy 185.193629 -357.761172) (xy 186.676479 -357.761172) (xy 186.676479 -357.706628)
			(xy 186.684241 -357.652638) (xy 186.699608 -357.600303) (xy 186.722266 -357.550688) (xy 186.751755 -357.504801)
			(xy 186.787473 -357.463579) (xy 186.828695 -357.42786) (xy 186.87458 -357.39837) (xy 186.924196 -357.37571)
			(xy 186.97653 -357.360343) (xy 187.03052 -357.352579) (xy 187.057792 -357.352092) (xy 187.921392 -357.352092)
			(xy 187.94866 -357.352647) (xy 188.002641 -357.360407) (xy 188.054969 -357.375771) (xy 188.104577 -357.398425)
			(xy 188.150456 -357.427909) (xy 188.191672 -357.463622) (xy 188.227386 -357.504838) (xy 188.256871 -357.550716)
			(xy 188.279526 -357.600324) (xy 188.294891 -357.652651) (xy 188.302653 -357.706632) (xy 188.302653 -357.761168)
			(xy 188.294891 -357.815149) (xy 188.279526 -357.867476) (xy 188.256871 -357.917084) (xy 188.227386 -357.962962)
			(xy 188.223925 -357.966956) (xy 245.50903 -357.966956) (xy 245.50903 -357.88226) (xy 245.517081 -357.797946)
			(xy 245.53311 -357.71478) (xy 245.556971 -357.633513) (xy 245.58845 -357.554883) (xy 245.627261 -357.479602)
			(xy 245.673051 -357.40835) (xy 245.725407 -357.341774) (xy 245.783855 -357.280476) (xy 245.847865 -357.225011)
			(xy 245.916857 -357.175882) (xy 245.990207 -357.133533) (xy 246.06725 -357.098349) (xy 246.147289 -357.070647)
			(xy 246.229598 -357.050679) (xy 246.313433 -357.038626) (xy 246.398034 -357.034596) (xy 246.482635 -357.038626)
			(xy 246.56647 -357.050679) (xy 246.648779 -357.070647) (xy 246.728818 -357.098349) (xy 246.805861 -357.133533)
			(xy 246.879211 -357.175882) (xy 246.948203 -357.225011) (xy 247.012213 -357.280476) (xy 247.070661 -357.341774)
			(xy 247.123017 -357.40835) (xy 247.168807 -357.479602) (xy 247.207618 -357.554883) (xy 247.239097 -357.633513)
			(xy 247.262958 -357.71478) (xy 247.276485 -357.784966) (xy 270.624854 -357.784966) (xy 270.624854 -357.730435)
			(xy 270.632614 -357.676458) (xy 270.647977 -357.624136) (xy 270.670628 -357.574532) (xy 270.700108 -357.528657)
			(xy 270.735817 -357.487443) (xy 270.777026 -357.451731) (xy 270.822899 -357.422246) (xy 270.8725 -357.39959)
			(xy 270.924821 -357.384222) (xy 270.978797 -357.376457) (xy 271.006062 -357.375968) (xy 271.869662 -357.375968)
			(xy 271.896937 -357.376369) (xy 271.950932 -357.384127) (xy 272.003273 -357.399491) (xy 272.052895 -357.422149)
			(xy 272.098787 -357.451638) (xy 272.140015 -357.487358) (xy 272.17574 -357.528582) (xy 272.205233 -357.574471)
			(xy 272.227895 -357.624091) (xy 272.243265 -357.676431) (xy 272.251028 -357.730425) (xy 272.251028 -357.78497)
			(xy 273.733731 -357.78497) (xy 273.733731 -357.73043) (xy 273.741494 -357.676446) (xy 273.75686 -357.624115)
			(xy 273.779517 -357.574505) (xy 273.809005 -357.528623) (xy 273.844722 -357.487406) (xy 273.885941 -357.451691)
			(xy 273.931824 -357.422207) (xy 273.981436 -357.399552) (xy 274.033767 -357.384189) (xy 274.087752 -357.37643)
			(xy 274.115022 -357.375968) (xy 274.978622 -357.375968) (xy 275.005892 -357.376396) (xy 275.059878 -357.384161)
			(xy 275.112209 -357.399529) (xy 275.16182 -357.422189) (xy 275.207702 -357.451677) (xy 275.24892 -357.487395)
			(xy 275.284636 -357.528616) (xy 275.314122 -357.574499) (xy 275.336778 -357.624112) (xy 275.352144 -357.676444)
			(xy 275.359906 -357.730429) (xy 275.359906 -357.784966) (xy 276.842754 -357.784966) (xy 276.842754 -357.730434)
			(xy 276.850515 -357.676456) (xy 276.865878 -357.624132) (xy 276.888531 -357.574527) (xy 276.918013 -357.52865)
			(xy 276.953724 -357.487436) (xy 276.994936 -357.451724) (xy 277.040811 -357.42224) (xy 277.090415 -357.399584)
			(xy 277.142738 -357.384219) (xy 277.196716 -357.376456) (xy 277.223982 -357.375968) (xy 278.087582 -357.375968)
			(xy 278.114856 -357.37637) (xy 278.168849 -357.384131) (xy 278.221188 -357.399497) (xy 278.270807 -357.422155)
			(xy 278.316697 -357.451645) (xy 278.357922 -357.487365) (xy 278.393644 -357.528589) (xy 278.423136 -357.574477)
			(xy 278.445797 -357.624095) (xy 278.461165 -357.676433) (xy 278.468928 -357.730426) (xy 278.468928 -357.784971)
			(xy 279.951632 -357.784971) (xy 279.951632 -357.730429) (xy 279.959394 -357.676443) (xy 279.974761 -357.624111)
			(xy 279.99742 -357.574499) (xy 280.026909 -357.528617) (xy 280.062629 -357.487399) (xy 280.103851 -357.451684)
			(xy 280.149736 -357.4222) (xy 280.19935 -357.399547) (xy 280.251684 -357.384185) (xy 280.305671 -357.376429)
			(xy 280.332942 -357.375968) (xy 281.196542 -357.375968) (xy 281.223812 -357.376397) (xy 281.277795 -357.384165)
			(xy 281.330123 -357.399535) (xy 281.379732 -357.422195) (xy 281.425611 -357.451684) (xy 281.466827 -357.487402)
			(xy 281.502541 -357.528622) (xy 281.532025 -357.574505) (xy 281.55468 -357.624116) (xy 281.570044 -357.676446)
			(xy 281.577806 -357.73043) (xy 281.577806 -357.784969) (xy 283.060631 -357.784969) (xy 283.060631 -357.730431)
			(xy 283.068393 -357.676448) (xy 283.083758 -357.62412) (xy 283.106414 -357.57451) (xy 283.1359 -357.52863)
			(xy 283.171614 -357.487413) (xy 283.212832 -357.451698) (xy 283.258712 -357.422213) (xy 283.308321 -357.399557)
			(xy 283.36065 -357.384193) (xy 283.414633 -357.376431) (xy 283.441902 -357.375968) (xy 284.305502 -357.375968)
			(xy 284.332773 -357.376395) (xy 284.386761 -357.384157) (xy 284.439094 -357.399524) (xy 284.488708 -357.422182)
			(xy 284.534593 -357.45167) (xy 284.575813 -357.487388) (xy 284.611531 -357.528609) (xy 284.641019 -357.574493)
			(xy 284.663677 -357.624107) (xy 284.679043 -357.676441) (xy 284.686806 -357.730429) (xy 284.686806 -357.784966)
			(xy 286.169654 -357.784966) (xy 286.169654 -357.730435) (xy 286.177414 -357.676458) (xy 286.192777 -357.624136)
			(xy 286.215428 -357.574532) (xy 286.244908 -357.528657) (xy 286.280617 -357.487443) (xy 286.321826 -357.451731)
			(xy 286.367699 -357.422246) (xy 286.4173 -357.39959) (xy 286.469621 -357.384222) (xy 286.523597 -357.376457)
			(xy 286.550862 -357.375968) (xy 287.414462 -357.375968) (xy 287.441737 -357.376369) (xy 287.495732 -357.384127)
			(xy 287.548073 -357.399491) (xy 287.597695 -357.422149) (xy 287.643587 -357.451638) (xy 287.684815 -357.487358)
			(xy 287.72054 -357.528582) (xy 287.750033 -357.574471) (xy 287.772695 -357.624091) (xy 287.788065 -357.676431)
			(xy 287.795828 -357.730425) (xy 287.795828 -357.78497) (xy 289.278531 -357.78497) (xy 289.278531 -357.73043)
			(xy 289.286294 -357.676446) (xy 289.30166 -357.624115) (xy 289.324317 -357.574505) (xy 289.353805 -357.528623)
			(xy 289.389522 -357.487406) (xy 289.430741 -357.451691) (xy 289.476624 -357.422207) (xy 289.526236 -357.399552)
			(xy 289.578567 -357.384189) (xy 289.632552 -357.37643) (xy 289.659822 -357.375968) (xy 290.523422 -357.375968)
			(xy 290.550692 -357.376396) (xy 290.604678 -357.384161) (xy 290.657009 -357.399529) (xy 290.70662 -357.422189)
			(xy 290.752502 -357.451677) (xy 290.79372 -357.487395) (xy 290.829436 -357.528616) (xy 290.858922 -357.574499)
			(xy 290.881578 -357.624112) (xy 290.896944 -357.676444) (xy 290.904706 -357.730429) (xy 290.904706 -357.784966)
			(xy 292.387554 -357.784966) (xy 292.387554 -357.730434) (xy 292.395315 -357.676456) (xy 292.410678 -357.624132)
			(xy 292.433331 -357.574527) (xy 292.462813 -357.52865) (xy 292.498524 -357.487436) (xy 292.539736 -357.451724)
			(xy 292.585611 -357.42224) (xy 292.635215 -357.399584) (xy 292.687538 -357.384219) (xy 292.741516 -357.376456)
			(xy 292.768782 -357.375968) (xy 293.632382 -357.375968) (xy 293.659656 -357.37637) (xy 293.713649 -357.384131)
			(xy 293.765988 -357.399497) (xy 293.815607 -357.422155) (xy 293.861497 -357.451645) (xy 293.902722 -357.487365)
			(xy 293.938444 -357.528589) (xy 293.967936 -357.574477) (xy 293.990597 -357.624095) (xy 294.005965 -357.676433)
			(xy 294.013728 -357.730426) (xy 294.013728 -357.784971) (xy 295.496432 -357.784971) (xy 295.496432 -357.730429)
			(xy 295.504194 -357.676443) (xy 295.519561 -357.624111) (xy 295.54222 -357.574499) (xy 295.571709 -357.528617)
			(xy 295.607429 -357.487399) (xy 295.648651 -357.451684) (xy 295.694536 -357.4222) (xy 295.74415 -357.399547)
			(xy 295.796484 -357.384185) (xy 295.850471 -357.376429) (xy 295.877742 -357.375968) (xy 296.741342 -357.375968)
			(xy 296.768612 -357.376397) (xy 296.822595 -357.384165) (xy 296.874923 -357.399535) (xy 296.924532 -357.422195)
			(xy 296.970411 -357.451684) (xy 297.011627 -357.487402) (xy 297.047341 -357.528622) (xy 297.076825 -357.574505)
			(xy 297.09948 -357.624116) (xy 297.114844 -357.676446) (xy 297.122606 -357.73043) (xy 297.122606 -357.784969)
			(xy 298.605431 -357.784969) (xy 298.605431 -357.730431) (xy 298.613193 -357.676448) (xy 298.628558 -357.62412)
			(xy 298.651214 -357.57451) (xy 298.6807 -357.52863) (xy 298.716414 -357.487413) (xy 298.757632 -357.451698)
			(xy 298.803512 -357.422213) (xy 298.853121 -357.399557) (xy 298.90545 -357.384193) (xy 298.959433 -357.376431)
			(xy 298.986702 -357.375968) (xy 299.850302 -357.375968) (xy 299.877573 -357.376395) (xy 299.931561 -357.384157)
			(xy 299.983894 -357.399524) (xy 300.033508 -357.422182) (xy 300.079393 -357.45167) (xy 300.120613 -357.487388)
			(xy 300.156331 -357.528609) (xy 300.185819 -357.574493) (xy 300.208477 -357.624107) (xy 300.223843 -357.676441)
			(xy 300.231606 -357.730429) (xy 300.231606 -357.784966) (xy 315.230554 -357.784966) (xy 315.230554 -357.730434)
			(xy 315.238314 -357.676458) (xy 315.253677 -357.624136) (xy 315.276328 -357.574532) (xy 315.305809 -357.528656)
			(xy 315.341517 -357.487443) (xy 315.382727 -357.45173) (xy 315.4286 -357.422246) (xy 315.478202 -357.399589)
			(xy 315.530523 -357.384222) (xy 315.584498 -357.376457) (xy 315.611764 -357.375968) (xy 316.475364 -357.375968)
			(xy 316.502639 -357.376369) (xy 316.556634 -357.384128) (xy 316.608975 -357.399492) (xy 316.658597 -357.422149)
			(xy 316.704488 -357.451638) (xy 316.745716 -357.487359) (xy 316.78144 -357.528583) (xy 316.810933 -357.574472)
			(xy 316.833595 -357.624091) (xy 316.848965 -357.676431) (xy 316.856728 -357.730425) (xy 316.856728 -357.78497)
			(xy 318.339431 -357.78497) (xy 318.339431 -357.73043) (xy 318.347194 -357.676445) (xy 318.36256 -357.624115)
			(xy 318.385217 -357.574504) (xy 318.414705 -357.528623) (xy 318.450422 -357.487405) (xy 318.491642 -357.451691)
			(xy 318.537525 -357.422206) (xy 318.587137 -357.399552) (xy 318.639469 -357.384189) (xy 318.693454 -357.37643)
			(xy 318.720724 -357.375968) (xy 319.584324 -357.375968) (xy 319.611594 -357.376396) (xy 319.66558 -357.384161)
			(xy 319.71791 -357.39953) (xy 319.767521 -357.422189) (xy 319.813403 -357.451678) (xy 319.854621 -357.487396)
			(xy 319.890336 -357.528616) (xy 319.919822 -357.5745) (xy 319.942479 -357.624112) (xy 319.957844 -357.676444)
			(xy 319.965606 -357.73043) (xy 319.965606 -357.784967) (xy 321.448454 -357.784967) (xy 321.448454 -357.730434)
			(xy 321.456215 -357.676456) (xy 321.471578 -357.624131) (xy 321.494232 -357.574526) (xy 321.523714 -357.52865)
			(xy 321.559424 -357.487436) (xy 321.600637 -357.451723) (xy 321.646512 -357.422239) (xy 321.696116 -357.399584)
			(xy 321.74844 -357.384218) (xy 321.802418 -357.376455) (xy 321.829684 -357.375968) (xy 322.693284 -357.375968)
			(xy 322.720558 -357.37637) (xy 322.774551 -357.384131) (xy 322.826889 -357.399497) (xy 322.876508 -357.422156)
			(xy 322.922398 -357.451645) (xy 322.963623 -357.487366) (xy 322.999345 -357.528589) (xy 323.028836 -357.574477)
			(xy 323.051497 -357.624096) (xy 323.066865 -357.676434) (xy 323.074628 -357.730426) (xy 323.074628 -357.784971)
			(xy 324.557332 -357.784971) (xy 324.557332 -357.730429) (xy 324.565094 -357.676443) (xy 324.580461 -357.624111)
			(xy 324.603121 -357.574498) (xy 324.63261 -357.528616) (xy 324.668329 -357.487398) (xy 324.709551 -357.451684)
			(xy 324.755437 -357.422199) (xy 324.805052 -357.399546) (xy 324.857386 -357.384185) (xy 324.911373 -357.376428)
			(xy 324.938644 -357.375968) (xy 325.802244 -357.375968) (xy 325.829513 -357.376398) (xy 325.883497 -357.384165)
			(xy 325.935825 -357.399535) (xy 325.985433 -357.422196) (xy 326.031312 -357.451685) (xy 326.072528 -357.487403)
			(xy 326.108241 -357.528623) (xy 326.137725 -357.574505) (xy 326.16038 -357.624116) (xy 326.175744 -357.676447)
			(xy 326.183506 -357.73043) (xy 326.183506 -357.784969) (xy 327.666331 -357.784969) (xy 327.666331 -357.730431)
			(xy 327.674093 -357.676448) (xy 327.689458 -357.624119) (xy 327.712114 -357.57451) (xy 327.7416 -357.528629)
			(xy 327.777315 -357.487412) (xy 327.818533 -357.451698) (xy 327.864413 -357.422212) (xy 327.914023 -357.399557)
			(xy 327.966352 -357.384192) (xy 328.020335 -357.376431) (xy 328.047604 -357.375968) (xy 328.911204 -357.375968)
			(xy 328.938475 -357.376395) (xy 328.992463 -357.384158) (xy 329.044796 -357.399524) (xy 329.094409 -357.422183)
			(xy 329.140293 -357.451671) (xy 329.181514 -357.487389) (xy 329.217231 -357.52861) (xy 329.246719 -357.574494)
			(xy 329.269377 -357.624108) (xy 329.284743 -357.676441) (xy 329.292506 -357.730429) (xy 329.292506 -357.784966)
			(xy 330.775354 -357.784966) (xy 330.775354 -357.730434) (xy 330.783114 -357.676458) (xy 330.798477 -357.624136)
			(xy 330.821128 -357.574532) (xy 330.850609 -357.528656) (xy 330.886317 -357.487443) (xy 330.927527 -357.45173)
			(xy 330.9734 -357.422246) (xy 331.023002 -357.399589) (xy 331.075323 -357.384222) (xy 331.129298 -357.376457)
			(xy 331.156564 -357.375968) (xy 332.020164 -357.375968) (xy 332.047439 -357.376369) (xy 332.101434 -357.384128)
			(xy 332.153775 -357.399492) (xy 332.203397 -357.422149) (xy 332.249288 -357.451638) (xy 332.290516 -357.487359)
			(xy 332.32624 -357.528583) (xy 332.355733 -357.574472) (xy 332.378395 -357.624091) (xy 332.393765 -357.676431)
			(xy 332.401528 -357.730425) (xy 332.401528 -357.78497) (xy 333.884231 -357.78497) (xy 333.884231 -357.73043)
			(xy 333.891994 -357.676445) (xy 333.90736 -357.624115) (xy 333.930017 -357.574504) (xy 333.959505 -357.528623)
			(xy 333.995222 -357.487405) (xy 334.036442 -357.451691) (xy 334.082325 -357.422206) (xy 334.131937 -357.399552)
			(xy 334.184269 -357.384189) (xy 334.238254 -357.37643) (xy 334.265524 -357.375968) (xy 335.129124 -357.375968)
			(xy 335.156394 -357.376396) (xy 335.21038 -357.384161) (xy 335.26271 -357.39953) (xy 335.312321 -357.422189)
			(xy 335.358203 -357.451678) (xy 335.399421 -357.487396) (xy 335.435136 -357.528616) (xy 335.464622 -357.5745)
			(xy 335.487279 -357.624112) (xy 335.502644 -357.676444) (xy 335.510406 -357.73043) (xy 335.510406 -357.784967)
			(xy 336.993254 -357.784967) (xy 336.993254 -357.730434) (xy 337.001015 -357.676456) (xy 337.016378 -357.624131)
			(xy 337.039032 -357.574526) (xy 337.068514 -357.52865) (xy 337.104224 -357.487436) (xy 337.145437 -357.451723)
			(xy 337.191312 -357.422239) (xy 337.240916 -357.399584) (xy 337.29324 -357.384218) (xy 337.347218 -357.376455)
			(xy 337.374484 -357.375968) (xy 338.238084 -357.375968) (xy 338.265358 -357.37637) (xy 338.319351 -357.384131)
			(xy 338.371689 -357.399497) (xy 338.421308 -357.422156) (xy 338.467198 -357.451645) (xy 338.508423 -357.487366)
			(xy 338.544145 -357.528589) (xy 338.573636 -357.574477) (xy 338.596297 -357.624096) (xy 338.611665 -357.676434)
			(xy 338.619428 -357.730426) (xy 338.619428 -357.784971) (xy 340.102132 -357.784971) (xy 340.102132 -357.730429)
			(xy 340.109894 -357.676443) (xy 340.125261 -357.624111) (xy 340.147921 -357.574498) (xy 340.17741 -357.528616)
			(xy 340.213129 -357.487398) (xy 340.254351 -357.451684) (xy 340.300237 -357.422199) (xy 340.349852 -357.399546)
			(xy 340.402186 -357.384185) (xy 340.456173 -357.376428) (xy 340.483444 -357.375968) (xy 341.347044 -357.375968)
			(xy 341.374313 -357.376398) (xy 341.428297 -357.384165) (xy 341.480625 -357.399535) (xy 341.530233 -357.422196)
			(xy 341.576112 -357.451685) (xy 341.617328 -357.487403) (xy 341.653041 -357.528623) (xy 341.682525 -357.574505)
			(xy 341.70518 -357.624116) (xy 341.720544 -357.676447) (xy 341.728306 -357.73043) (xy 341.728306 -357.784969)
			(xy 343.211131 -357.784969) (xy 343.211131 -357.730431) (xy 343.218893 -357.676448) (xy 343.234258 -357.624119)
			(xy 343.256914 -357.57451) (xy 343.2864 -357.528629) (xy 343.322115 -357.487412) (xy 343.363333 -357.451698)
			(xy 343.409213 -357.422212) (xy 343.458823 -357.399557) (xy 343.511152 -357.384192) (xy 343.565135 -357.376431)
			(xy 343.592404 -357.375968) (xy 344.456004 -357.375968) (xy 344.483275 -357.376395) (xy 344.537263 -357.384158)
			(xy 344.589596 -357.399524) (xy 344.639209 -357.422183) (xy 344.685093 -357.451671) (xy 344.726314 -357.487389)
			(xy 344.762031 -357.52861) (xy 344.791519 -357.574494) (xy 344.814177 -357.624108) (xy 344.829543 -357.676441)
			(xy 344.837306 -357.730429) (xy 344.837306 -357.784971) (xy 373.915632 -357.784971) (xy 373.915632 -357.730429)
			(xy 373.923394 -357.676443) (xy 373.938761 -357.624111) (xy 373.96142 -357.574499) (xy 373.990909 -357.528617)
			(xy 374.026628 -357.4874) (xy 374.06785 -357.451685) (xy 374.113735 -357.422201) (xy 374.163349 -357.399547)
			(xy 374.215682 -357.384186) (xy 374.269669 -357.376429) (xy 374.29694 -357.375968) (xy 375.16054 -357.375968)
			(xy 375.18781 -357.376397) (xy 375.241793 -357.384164) (xy 375.294122 -357.399534) (xy 375.343731 -357.422194)
			(xy 375.389611 -357.451684) (xy 375.430827 -357.487402) (xy 375.46654 -357.528622) (xy 375.496025 -357.574504)
			(xy 375.51868 -357.624116) (xy 375.534044 -357.676446) (xy 375.541806 -357.73043) (xy 375.541806 -357.784967)
			(xy 377.024654 -357.784967) (xy 377.024654 -357.730433) (xy 377.032415 -357.676453) (xy 377.04778 -357.624128)
			(xy 377.070434 -357.574522) (xy 377.099918 -357.528644) (xy 377.13563 -357.48743) (xy 377.176844 -357.451718)
			(xy 377.222722 -357.422234) (xy 377.272328 -357.39958) (xy 377.324653 -357.384215) (xy 377.378633 -357.376454)
			(xy 377.4059 -357.375968) (xy 378.2695 -357.375968) (xy 378.296772 -357.376395) (xy 378.350759 -357.384157)
			(xy 378.403093 -357.399523) (xy 378.452707 -357.422181) (xy 378.498592 -357.451669) (xy 378.539812 -357.487388)
			(xy 378.575531 -357.528608) (xy 378.605019 -357.574493) (xy 378.627677 -357.624107) (xy 378.643043 -357.676441)
			(xy 378.650805 -357.730428) (xy 378.650805 -357.784965) (xy 380.133654 -357.784965) (xy 380.133654 -357.730435)
			(xy 380.141414 -357.676459) (xy 380.156776 -357.624137) (xy 380.179428 -357.574533) (xy 380.208908 -357.528658)
			(xy 380.244616 -357.487444) (xy 380.285825 -357.451732) (xy 380.331698 -357.422247) (xy 380.381299 -357.39959)
			(xy 380.43362 -357.384223) (xy 380.487595 -357.376457) (xy 380.51486 -357.375968) (xy 381.37846 -357.375968)
			(xy 381.405735 -357.376369) (xy 381.45973 -357.384127) (xy 381.512072 -357.399491) (xy 381.561694 -357.422148)
			(xy 381.607586 -357.451637) (xy 381.648815 -357.487357) (xy 381.684539 -357.528582) (xy 381.714033 -357.574471)
			(xy 381.736695 -357.62409) (xy 381.752065 -357.67643) (xy 381.759828 -357.730425) (xy 381.759828 -357.78497)
			(xy 383.242531 -357.78497) (xy 383.242531 -357.73043) (xy 383.250294 -357.676446) (xy 383.26566 -357.624116)
			(xy 383.288317 -357.574505) (xy 383.317804 -357.528624) (xy 383.353521 -357.487407) (xy 383.39474 -357.451692)
			(xy 383.440623 -357.422207) (xy 383.490234 -357.399553) (xy 383.542565 -357.384189) (xy 383.59655 -357.37643)
			(xy 383.62382 -357.375968) (xy 384.48742 -357.375968) (xy 384.514691 -357.376396) (xy 384.568676 -357.38416)
			(xy 384.621007 -357.399529) (xy 384.670619 -357.422188) (xy 384.716501 -357.451677) (xy 384.75772 -357.487395)
			(xy 384.793435 -357.528615) (xy 384.822922 -357.574499) (xy 384.845578 -357.624111) (xy 384.860944 -357.676443)
			(xy 384.868706 -357.730429) (xy 384.868706 -357.784966) (xy 386.351554 -357.784966) (xy 386.351554 -357.730434)
			(xy 386.359315 -357.676456) (xy 386.374678 -357.624132) (xy 386.397331 -357.574527) (xy 386.426813 -357.528651)
			(xy 386.462523 -357.487437) (xy 386.503735 -357.451725) (xy 386.54961 -357.422241) (xy 386.599213 -357.399585)
			(xy 386.651537 -357.384219) (xy 386.705514 -357.376456) (xy 386.73278 -357.375968) (xy 387.59638 -357.375968)
			(xy 387.623654 -357.37637) (xy 387.677647 -357.384131) (xy 387.729987 -357.399496) (xy 387.779606 -357.422155)
			(xy 387.825496 -357.451644) (xy 387.866722 -357.487364) (xy 387.902444 -357.528588) (xy 387.931936 -357.574476)
			(xy 387.954597 -357.624095) (xy 387.969965 -357.676433) (xy 387.977728 -357.730426) (xy 387.977728 -357.784971)
			(xy 389.460432 -357.784971) (xy 389.460432 -357.730429) (xy 389.468194 -357.676443) (xy 389.483561 -357.624111)
			(xy 389.50622 -357.574499) (xy 389.535709 -357.528617) (xy 389.571428 -357.4874) (xy 389.61265 -357.451685)
			(xy 389.658535 -357.422201) (xy 389.708149 -357.399547) (xy 389.760482 -357.384186) (xy 389.814469 -357.376429)
			(xy 389.84174 -357.375968) (xy 390.70534 -357.375968) (xy 390.73261 -357.376397) (xy 390.786593 -357.384164)
			(xy 390.838922 -357.399534) (xy 390.888531 -357.422194) (xy 390.934411 -357.451684) (xy 390.975627 -357.487402)
			(xy 391.01134 -357.528622) (xy 391.040825 -357.574504) (xy 391.06348 -357.624116) (xy 391.078844 -357.676446)
			(xy 391.086606 -357.73043) (xy 391.086606 -357.784967) (xy 392.569454 -357.784967) (xy 392.569454 -357.730433)
			(xy 392.577215 -357.676453) (xy 392.59258 -357.624128) (xy 392.615234 -357.574522) (xy 392.644718 -357.528644)
			(xy 392.68043 -357.48743) (xy 392.721644 -357.451718) (xy 392.767522 -357.422234) (xy 392.817128 -357.39958)
			(xy 392.869453 -357.384215) (xy 392.923433 -357.376454) (xy 392.9507 -357.375968) (xy 393.8143 -357.375968)
			(xy 393.841572 -357.376395) (xy 393.895559 -357.384157) (xy 393.947893 -357.399523) (xy 393.997507 -357.422181)
			(xy 394.043392 -357.451669) (xy 394.084612 -357.487388) (xy 394.120331 -357.528608) (xy 394.149819 -357.574493)
			(xy 394.172477 -357.624107) (xy 394.187843 -357.676441) (xy 394.195605 -357.730428) (xy 394.195605 -357.784965)
			(xy 395.678454 -357.784965) (xy 395.678454 -357.730435) (xy 395.686214 -357.676459) (xy 395.701576 -357.624137)
			(xy 395.724228 -357.574533) (xy 395.753708 -357.528658) (xy 395.789416 -357.487444) (xy 395.830625 -357.451732)
			(xy 395.876498 -357.422247) (xy 395.926099 -357.39959) (xy 395.97842 -357.384223) (xy 396.032395 -357.376457)
			(xy 396.05966 -357.375968) (xy 396.92326 -357.375968) (xy 396.950535 -357.376369) (xy 397.00453 -357.384127)
			(xy 397.056872 -357.399491) (xy 397.106494 -357.422148) (xy 397.152386 -357.451637) (xy 397.193615 -357.487357)
			(xy 397.229339 -357.528582) (xy 397.258833 -357.574471) (xy 397.281495 -357.62409) (xy 397.296865 -357.67643)
			(xy 397.304628 -357.730425) (xy 397.304628 -357.78497) (xy 398.787331 -357.78497) (xy 398.787331 -357.73043)
			(xy 398.795094 -357.676446) (xy 398.81046 -357.624116) (xy 398.833117 -357.574505) (xy 398.862604 -357.528624)
			(xy 398.898321 -357.487407) (xy 398.93954 -357.451692) (xy 398.985423 -357.422207) (xy 399.035034 -357.399553)
			(xy 399.087365 -357.384189) (xy 399.14135 -357.37643) (xy 399.16862 -357.375968) (xy 400.03222 -357.375968)
			(xy 400.059491 -357.376396) (xy 400.113476 -357.38416) (xy 400.165807 -357.399529) (xy 400.215419 -357.422188)
			(xy 400.261301 -357.451677) (xy 400.30252 -357.487395) (xy 400.338235 -357.528615) (xy 400.367722 -357.574499)
			(xy 400.390378 -357.624111) (xy 400.405744 -357.676443) (xy 400.413506 -357.730429) (xy 400.413506 -357.784966)
			(xy 401.896354 -357.784966) (xy 401.896354 -357.730434) (xy 401.904115 -357.676456) (xy 401.919478 -357.624132)
			(xy 401.942131 -357.574527) (xy 401.971613 -357.528651) (xy 402.007323 -357.487437) (xy 402.048535 -357.451725)
			(xy 402.09441 -357.422241) (xy 402.144013 -357.399585) (xy 402.196337 -357.384219) (xy 402.250314 -357.376456)
			(xy 402.27758 -357.375968) (xy 403.14118 -357.375968) (xy 403.168454 -357.37637) (xy 403.222447 -357.384131)
			(xy 403.274787 -357.399496) (xy 403.324406 -357.422155) (xy 403.370296 -357.451644) (xy 403.411522 -357.487364)
			(xy 403.447244 -357.528588) (xy 403.476736 -357.574476) (xy 403.499397 -357.624095) (xy 403.514765 -357.676433)
			(xy 403.522528 -357.730426) (xy 403.522528 -357.784965) (xy 412.022854 -357.784965) (xy 412.022854 -357.730435)
			(xy 412.030614 -357.67646) (xy 412.045976 -357.624138) (xy 412.068627 -357.574535) (xy 412.098106 -357.52866)
			(xy 412.133813 -357.487447) (xy 412.175022 -357.451735) (xy 412.220893 -357.42225) (xy 412.270493 -357.399593)
			(xy 412.322813 -357.384224) (xy 412.376787 -357.376458) (xy 412.404052 -357.375968) (xy 413.267652 -357.375968)
			(xy 413.294927 -357.376368) (xy 413.348924 -357.384125) (xy 413.401266 -357.399489) (xy 413.450889 -357.422145)
			(xy 413.496783 -357.451634) (xy 413.538012 -357.487354) (xy 413.573737 -357.528579) (xy 413.603232 -357.574468)
			(xy 413.625894 -357.624089) (xy 413.641264 -357.676429) (xy 413.649028 -357.730425) (xy 413.649028 -357.784969)
			(xy 415.131731 -357.784969) (xy 415.131731 -357.730431) (xy 415.139493 -357.676447) (xy 415.154859 -357.624117)
			(xy 415.177516 -357.574507) (xy 415.207002 -357.528627) (xy 415.242718 -357.487409) (xy 415.283936 -357.451695)
			(xy 415.329818 -357.42221) (xy 415.379429 -357.399555) (xy 415.431759 -357.384191) (xy 415.485743 -357.376431)
			(xy 415.513012 -357.375968) (xy 416.376612 -357.375968) (xy 416.403883 -357.376395) (xy 416.457869 -357.384159)
			(xy 416.510202 -357.399527) (xy 416.559814 -357.422185) (xy 416.605697 -357.451674) (xy 416.646917 -357.487392)
			(xy 416.682633 -357.528612) (xy 416.712121 -357.574496) (xy 416.734778 -357.62411) (xy 416.750144 -357.676442)
			(xy 416.757906 -357.730429) (xy 416.757906 -357.784966) (xy 418.240754 -357.784966) (xy 418.240754 -357.730434)
			(xy 418.248515 -357.676457) (xy 418.263877 -357.624134) (xy 418.28653 -357.57453) (xy 418.316011 -357.528654)
			(xy 418.35172 -357.48744) (xy 418.392931 -357.451727) (xy 418.438805 -357.422243) (xy 418.488408 -357.399587)
			(xy 418.54073 -357.384221) (xy 418.594706 -357.376456) (xy 418.621972 -357.375968) (xy 419.485572 -357.375968)
			(xy 419.512846 -357.37637) (xy 419.566841 -357.384129) (xy 419.619181 -357.399494) (xy 419.668801 -357.422152)
			(xy 419.714692 -357.451641) (xy 419.755919 -357.487361) (xy 419.791642 -357.528585) (xy 419.821135 -357.574474)
			(xy 419.843796 -357.624093) (xy 419.859165 -357.676432) (xy 419.866928 -357.730426) (xy 419.866928 -357.78497)
			(xy 421.349632 -357.78497) (xy 421.349632 -357.73043) (xy 421.357394 -357.676444) (xy 421.372761 -357.624113)
			(xy 421.395419 -357.574502) (xy 421.424907 -357.52862) (xy 421.460625 -357.487402) (xy 421.501846 -357.451688)
			(xy 421.54773 -357.422203) (xy 421.597343 -357.399549) (xy 421.649676 -357.384187) (xy 421.703662 -357.376429)
			(xy 421.730932 -357.375968) (xy 422.594532 -357.375968) (xy 422.621802 -357.376397) (xy 422.675786 -357.384163)
			(xy 422.728116 -357.399532) (xy 422.777726 -357.422192) (xy 422.823607 -357.451681) (xy 422.864824 -357.487399)
			(xy 422.900538 -357.528619) (xy 422.930024 -357.574502) (xy 422.952679 -357.624114) (xy 422.968044 -357.676445)
			(xy 422.975806 -357.73043) (xy 422.975806 -357.784967) (xy 424.458654 -357.784967) (xy 424.458654 -357.730433)
			(xy 424.466415 -357.676454) (xy 424.481779 -357.62413) (xy 424.504433 -357.574524) (xy 424.533916 -357.528647)
			(xy 424.569627 -357.487433) (xy 424.610841 -357.45172) (xy 424.656717 -357.422237) (xy 424.706322 -357.399582)
			(xy 424.758647 -357.384217) (xy 424.812625 -357.376455) (xy 424.839892 -357.375968) (xy 425.703492 -357.375968)
			(xy 425.730766 -357.376371) (xy 425.784757 -357.384133) (xy 425.837095 -357.3995) (xy 425.886713 -357.422159)
			(xy 425.932602 -357.451648) (xy 425.973826 -357.487368) (xy 426.009547 -357.528592) (xy 426.039038 -357.57448)
			(xy 426.061698 -357.624097) (xy 426.077065 -357.676435) (xy 426.084828 -357.730426) (xy 426.084828 -357.784965)
			(xy 427.567654 -357.784965) (xy 427.567654 -357.730435) (xy 427.575414 -357.67646) (xy 427.590776 -357.624138)
			(xy 427.613427 -357.574535) (xy 427.642906 -357.52866) (xy 427.678613 -357.487447) (xy 427.719822 -357.451735)
			(xy 427.765693 -357.42225) (xy 427.815293 -357.399593) (xy 427.867613 -357.384224) (xy 427.921587 -357.376458)
			(xy 427.948852 -357.375968) (xy 428.812452 -357.375968) (xy 428.839727 -357.376368) (xy 428.893724 -357.384125)
			(xy 428.946066 -357.399489) (xy 428.995689 -357.422145) (xy 429.041583 -357.451634) (xy 429.082812 -357.487354)
			(xy 429.118537 -357.528579) (xy 429.148032 -357.574468) (xy 429.170694 -357.624089) (xy 429.186064 -357.676429)
			(xy 429.193828 -357.730425) (xy 429.193828 -357.784969) (xy 430.676531 -357.784969) (xy 430.676531 -357.730431)
			(xy 430.684293 -357.676447) (xy 430.699659 -357.624117) (xy 430.722316 -357.574507) (xy 430.751802 -357.528627)
			(xy 430.787518 -357.487409) (xy 430.828736 -357.451695) (xy 430.874618 -357.42221) (xy 430.924229 -357.399555)
			(xy 430.976559 -357.384191) (xy 431.030543 -357.376431) (xy 431.057812 -357.375968) (xy 431.921412 -357.375968)
			(xy 431.948683 -357.376395) (xy 432.002669 -357.384159) (xy 432.055002 -357.399527) (xy 432.104614 -357.422185)
			(xy 432.150497 -357.451674) (xy 432.191717 -357.487392) (xy 432.227433 -357.528612) (xy 432.256921 -357.574496)
			(xy 432.279578 -357.62411) (xy 432.294944 -357.676442) (xy 432.302706 -357.730429) (xy 432.302706 -357.784966)
			(xy 433.785554 -357.784966) (xy 433.785554 -357.730434) (xy 433.793315 -357.676457) (xy 433.808677 -357.624134)
			(xy 433.83133 -357.57453) (xy 433.860811 -357.528654) (xy 433.89652 -357.48744) (xy 433.937731 -357.451727)
			(xy 433.983605 -357.422243) (xy 434.033208 -357.399587) (xy 434.08553 -357.384221) (xy 434.139506 -357.376456)
			(xy 434.166772 -357.375968) (xy 435.030372 -357.375968) (xy 435.057646 -357.37637) (xy 435.111641 -357.384129)
			(xy 435.163981 -357.399494) (xy 435.213601 -357.422152) (xy 435.259492 -357.451641) (xy 435.300719 -357.487361)
			(xy 435.336442 -357.528585) (xy 435.365935 -357.574474) (xy 435.388596 -357.624093) (xy 435.403965 -357.676432)
			(xy 435.411728 -357.730426) (xy 435.411728 -357.78497) (xy 436.894432 -357.78497) (xy 436.894432 -357.73043)
			(xy 436.902194 -357.676444) (xy 436.917561 -357.624113) (xy 436.940219 -357.574502) (xy 436.969707 -357.52862)
			(xy 437.005425 -357.487402) (xy 437.046646 -357.451688) (xy 437.09253 -357.422203) (xy 437.142143 -357.399549)
			(xy 437.194476 -357.384187) (xy 437.248462 -357.376429) (xy 437.275732 -357.375968) (xy 438.139332 -357.375968)
			(xy 438.166602 -357.376397) (xy 438.220586 -357.384163) (xy 438.272916 -357.399532) (xy 438.322526 -357.422192)
			(xy 438.368407 -357.451681) (xy 438.409624 -357.487399) (xy 438.445338 -357.528619) (xy 438.474824 -357.574502)
			(xy 438.497479 -357.624114) (xy 438.512844 -357.676445) (xy 438.520606 -357.73043) (xy 438.520606 -357.784967)
			(xy 440.003454 -357.784967) (xy 440.003454 -357.730433) (xy 440.011215 -357.676454) (xy 440.026579 -357.62413)
			(xy 440.049233 -357.574524) (xy 440.078716 -357.528647) (xy 440.114427 -357.487433) (xy 440.155641 -357.45172)
			(xy 440.201517 -357.422237) (xy 440.251122 -357.399582) (xy 440.303447 -357.384217) (xy 440.357425 -357.376455)
			(xy 440.384692 -357.375968) (xy 441.248292 -357.375968) (xy 441.275566 -357.376371) (xy 441.329557 -357.384133)
			(xy 441.381895 -357.3995) (xy 441.431513 -357.422159) (xy 441.477402 -357.451648) (xy 441.518626 -357.487368)
			(xy 441.554347 -357.528592) (xy 441.583838 -357.57448) (xy 441.606498 -357.624097) (xy 441.621865 -357.676435)
			(xy 441.629628 -357.730426) (xy 441.629628 -357.784974) (xy 441.621865 -357.838965) (xy 441.606498 -357.891303)
			(xy 441.583838 -357.94092) (xy 441.554347 -357.986808) (xy 441.518626 -358.028032) (xy 441.477402 -358.063752)
			(xy 441.431513 -358.093241) (xy 441.381895 -358.1159) (xy 441.329557 -358.131267) (xy 441.275566 -358.139029)
			(xy 441.248292 -358.139492) (xy 440.384692 -358.139492) (xy 440.357425 -358.138945) (xy 440.303447 -358.131183)
			(xy 440.251122 -358.115818) (xy 440.201517 -358.093163) (xy 440.155641 -358.06368) (xy 440.114427 -358.027967)
			(xy 440.078716 -357.986753) (xy 440.049233 -357.940876) (xy 440.026579 -357.89127) (xy 440.011215 -357.838946)
			(xy 440.003454 -357.784967) (xy 438.520606 -357.784967) (xy 438.520606 -357.78497) (xy 438.512844 -357.838955)
			(xy 438.497479 -357.891286) (xy 438.474824 -357.940898) (xy 438.445338 -357.986781) (xy 438.409624 -358.028001)
			(xy 438.368407 -358.063719) (xy 438.322526 -358.093208) (xy 438.272916 -358.115868) (xy 438.220586 -358.131237)
			(xy 438.166602 -358.139003) (xy 438.139332 -358.139492) (xy 437.275732 -358.139492) (xy 437.248462 -358.138971)
			(xy 437.194476 -358.131213) (xy 437.142143 -358.115851) (xy 437.09253 -358.093197) (xy 437.046646 -358.063712)
			(xy 437.005425 -358.027998) (xy 436.969707 -357.98678) (xy 436.940219 -357.940898) (xy 436.917561 -357.891287)
			(xy 436.902194 -357.838956) (xy 436.894432 -357.78497) (xy 435.411728 -357.78497) (xy 435.411728 -357.784974)
			(xy 435.403965 -357.838968) (xy 435.388596 -357.891307) (xy 435.365935 -357.940926) (xy 435.336442 -357.986815)
			(xy 435.300719 -358.028039) (xy 435.259492 -358.063759) (xy 435.213601 -358.093248) (xy 435.163981 -358.115906)
			(xy 435.111641 -358.131271) (xy 435.057646 -358.13903) (xy 435.030372 -358.139492) (xy 434.166772 -358.139492)
			(xy 434.139506 -358.138944) (xy 434.08553 -358.131179) (xy 434.033208 -358.115813) (xy 433.983605 -358.093157)
			(xy 433.937731 -358.063673) (xy 433.89652 -358.02796) (xy 433.860811 -357.986746) (xy 433.83133 -357.94087)
			(xy 433.808677 -357.891266) (xy 433.793315 -357.838943) (xy 433.785554 -357.784966) (xy 432.302706 -357.784966)
			(xy 432.302706 -357.784971) (xy 432.294944 -357.838958) (xy 432.279578 -357.89129) (xy 432.256921 -357.940904)
			(xy 432.227433 -357.986788) (xy 432.191717 -358.028008) (xy 432.150497 -358.063726) (xy 432.104614 -358.093215)
			(xy 432.055002 -358.115873) (xy 432.002669 -358.131241) (xy 431.948683 -358.139005) (xy 431.921412 -358.139492)
			(xy 431.057812 -358.139492) (xy 431.030543 -358.138969) (xy 430.976559 -358.131209) (xy 430.924229 -358.115845)
			(xy 430.874618 -358.09319) (xy 430.828736 -358.063705) (xy 430.787518 -358.027991) (xy 430.751802 -357.986773)
			(xy 430.722316 -357.940893) (xy 430.699659 -357.891283) (xy 430.684293 -357.838953) (xy 430.676531 -357.784969)
			(xy 429.193828 -357.784969) (xy 429.193828 -357.784975) (xy 429.186064 -357.838971) (xy 429.170694 -357.891311)
			(xy 429.148032 -357.940932) (xy 429.118537 -357.986821) (xy 429.082812 -358.028046) (xy 429.041583 -358.063766)
			(xy 428.995689 -358.093255) (xy 428.946066 -358.115911) (xy 428.893724 -358.131275) (xy 428.839727 -358.139032)
			(xy 428.812452 -358.139492) (xy 427.948852 -358.139492) (xy 427.921587 -358.138942) (xy 427.867613 -358.131176)
			(xy 427.815293 -358.115807) (xy 427.765693 -358.09315) (xy 427.719822 -358.063665) (xy 427.678613 -358.027953)
			(xy 427.642906 -357.98674) (xy 427.613427 -357.940865) (xy 427.590776 -357.891262) (xy 427.575414 -357.83894)
			(xy 427.567654 -357.784965) (xy 426.084828 -357.784965) (xy 426.084828 -357.784974) (xy 426.077065 -357.838965)
			(xy 426.061698 -357.891303) (xy 426.039038 -357.94092) (xy 426.009547 -357.986808) (xy 425.973826 -358.028032)
			(xy 425.932602 -358.063752) (xy 425.886713 -358.093241) (xy 425.837095 -358.1159) (xy 425.784757 -358.131267)
			(xy 425.730766 -358.139029) (xy 425.703492 -358.139492) (xy 424.839892 -358.139492) (xy 424.812625 -358.138945)
			(xy 424.758647 -358.131183) (xy 424.706322 -358.115818) (xy 424.656717 -358.093163) (xy 424.610841 -358.06368)
			(xy 424.569627 -358.027967) (xy 424.533916 -357.986753) (xy 424.504433 -357.940876) (xy 424.481779 -357.89127)
			(xy 424.466415 -357.838946) (xy 424.458654 -357.784967) (xy 422.975806 -357.784967) (xy 422.975806 -357.78497)
			(xy 422.968044 -357.838955) (xy 422.952679 -357.891286) (xy 422.930024 -357.940898) (xy 422.900538 -357.986781)
			(xy 422.864824 -358.028001) (xy 422.823607 -358.063719) (xy 422.777726 -358.093208) (xy 422.728116 -358.115868)
			(xy 422.675786 -358.131237) (xy 422.621802 -358.139003) (xy 422.594532 -358.139492) (xy 421.730932 -358.139492)
			(xy 421.703662 -358.138971) (xy 421.649676 -358.131213) (xy 421.597343 -358.115851) (xy 421.54773 -358.093197)
			(xy 421.501846 -358.063712) (xy 421.460625 -358.027998) (xy 421.424907 -357.98678) (xy 421.395419 -357.940898)
			(xy 421.372761 -357.891287) (xy 421.357394 -357.838956) (xy 421.349632 -357.78497) (xy 419.866928 -357.78497)
			(xy 419.866928 -357.784974) (xy 419.859165 -357.838968) (xy 419.843796 -357.891307) (xy 419.821135 -357.940926)
			(xy 419.791642 -357.986815) (xy 419.755919 -358.028039) (xy 419.714692 -358.063759) (xy 419.668801 -358.093248)
			(xy 419.619181 -358.115906) (xy 419.566841 -358.131271) (xy 419.512846 -358.13903) (xy 419.485572 -358.139492)
			(xy 418.621972 -358.139492) (xy 418.594706 -358.138944) (xy 418.54073 -358.131179) (xy 418.488408 -358.115813)
			(xy 418.438805 -358.093157) (xy 418.392931 -358.063673) (xy 418.35172 -358.02796) (xy 418.316011 -357.986746)
			(xy 418.28653 -357.94087) (xy 418.263877 -357.891266) (xy 418.248515 -357.838943) (xy 418.240754 -357.784966)
			(xy 416.757906 -357.784966) (xy 416.757906 -357.784971) (xy 416.750144 -357.838958) (xy 416.734778 -357.89129)
			(xy 416.712121 -357.940904) (xy 416.682633 -357.986788) (xy 416.646917 -358.028008) (xy 416.605697 -358.063726)
			(xy 416.559814 -358.093215) (xy 416.510202 -358.115873) (xy 416.457869 -358.131241) (xy 416.403883 -358.139005)
			(xy 416.376612 -358.139492) (xy 415.513012 -358.139492) (xy 415.485743 -358.138969) (xy 415.431759 -358.131209)
			(xy 415.379429 -358.115845) (xy 415.329818 -358.09319) (xy 415.283936 -358.063705) (xy 415.242718 -358.027991)
			(xy 415.207002 -357.986773) (xy 415.177516 -357.940893) (xy 415.154859 -357.891283) (xy 415.139493 -357.838953)
			(xy 415.131731 -357.784969) (xy 413.649028 -357.784969) (xy 413.649028 -357.784975) (xy 413.641264 -357.838971)
			(xy 413.625894 -357.891311) (xy 413.603232 -357.940932) (xy 413.573737 -357.986821) (xy 413.538012 -358.028046)
			(xy 413.496783 -358.063766) (xy 413.450889 -358.093255) (xy 413.401266 -358.115911) (xy 413.348924 -358.131275)
			(xy 413.294927 -358.139032) (xy 413.267652 -358.139492) (xy 412.404052 -358.139492) (xy 412.376787 -358.138942)
			(xy 412.322813 -358.131176) (xy 412.270493 -358.115807) (xy 412.220893 -358.09315) (xy 412.175022 -358.063665)
			(xy 412.133813 -358.027953) (xy 412.098106 -357.98674) (xy 412.068627 -357.940865) (xy 412.045976 -357.891262)
			(xy 412.030614 -357.83894) (xy 412.022854 -357.784965) (xy 403.522528 -357.784965) (xy 403.522528 -357.784974)
			(xy 403.514765 -357.838967) (xy 403.499397 -357.891305) (xy 403.476736 -357.940924) (xy 403.447244 -357.986812)
			(xy 403.411522 -358.028036) (xy 403.370296 -358.063756) (xy 403.324406 -358.093245) (xy 403.274787 -358.115904)
			(xy 403.222447 -358.131269) (xy 403.168454 -358.13903) (xy 403.14118 -358.139492) (xy 402.27758 -358.139492)
			(xy 402.250314 -358.138944) (xy 402.196337 -358.131181) (xy 402.144013 -358.115815) (xy 402.09441 -358.093159)
			(xy 402.048535 -358.063675) (xy 402.007323 -358.027963) (xy 401.971613 -357.986749) (xy 401.942131 -357.940873)
			(xy 401.919478 -357.891268) (xy 401.904115 -357.838944) (xy 401.896354 -357.784966) (xy 400.413506 -357.784966)
			(xy 400.413506 -357.784971) (xy 400.405744 -357.838957) (xy 400.390378 -357.891289) (xy 400.367722 -357.940901)
			(xy 400.338235 -357.986785) (xy 400.30252 -358.028005) (xy 400.261301 -358.063723) (xy 400.215419 -358.093212)
			(xy 400.165807 -358.115871) (xy 400.113476 -358.13124) (xy 400.059491 -358.139004) (xy 400.03222 -358.139492)
			(xy 399.16862 -358.139492) (xy 399.14135 -358.13897) (xy 399.087365 -358.131211) (xy 399.035034 -358.115847)
			(xy 398.985423 -358.093193) (xy 398.93954 -358.063708) (xy 398.898321 -358.027993) (xy 398.862604 -357.986776)
			(xy 398.833117 -357.940895) (xy 398.81046 -357.891284) (xy 398.795094 -357.838954) (xy 398.787331 -357.78497)
			(xy 397.304628 -357.78497) (xy 397.304628 -357.784975) (xy 397.296865 -357.83897) (xy 397.281495 -357.89131)
			(xy 397.258833 -357.940929) (xy 397.229339 -357.986818) (xy 397.193615 -358.028043) (xy 397.152386 -358.063763)
			(xy 397.106494 -358.093252) (xy 397.056872 -358.115909) (xy 397.00453 -358.131273) (xy 396.950535 -358.139031)
			(xy 396.92326 -358.139492) (xy 396.05966 -358.139492) (xy 396.032395 -358.138943) (xy 395.97842 -358.131177)
			(xy 395.926099 -358.11581) (xy 395.876498 -358.093153) (xy 395.830625 -358.063668) (xy 395.789416 -358.027956)
			(xy 395.753708 -357.986742) (xy 395.724228 -357.940867) (xy 395.701576 -357.891263) (xy 395.686214 -357.838941)
			(xy 395.678454 -357.784965) (xy 394.195605 -357.784965) (xy 394.195605 -357.784972) (xy 394.187843 -357.838959)
			(xy 394.172477 -357.891293) (xy 394.149819 -357.940907) (xy 394.120331 -357.986792) (xy 394.084612 -358.028012)
			(xy 394.043392 -358.063731) (xy 393.997507 -358.093219) (xy 393.947893 -358.115877) (xy 393.895559 -358.131243)
			(xy 393.841572 -358.139005) (xy 393.8143 -358.139492) (xy 392.9507 -358.139492) (xy 392.923433 -358.138946)
			(xy 392.869453 -358.131185) (xy 392.817128 -358.11582) (xy 392.767522 -358.093166) (xy 392.721644 -358.063682)
			(xy 392.68043 -358.02797) (xy 392.644718 -357.986756) (xy 392.615234 -357.940878) (xy 392.59258 -357.891272)
			(xy 392.577215 -357.838947) (xy 392.569454 -357.784967) (xy 391.086606 -357.784967) (xy 391.086606 -357.78497)
			(xy 391.078844 -357.838954) (xy 391.06348 -357.891284) (xy 391.040825 -357.940896) (xy 391.01134 -357.986778)
			(xy 390.975627 -358.027998) (xy 390.934411 -358.063716) (xy 390.888531 -358.093206) (xy 390.838922 -358.115866)
			(xy 390.786593 -358.131236) (xy 390.73261 -358.139003) (xy 390.70534 -358.139492) (xy 389.84174 -358.139492)
			(xy 389.814469 -358.138971) (xy 389.760482 -358.131214) (xy 389.708149 -358.115853) (xy 389.658535 -358.093199)
			(xy 389.61265 -358.063715) (xy 389.571428 -358.028) (xy 389.535709 -357.986783) (xy 389.50622 -357.940901)
			(xy 389.483561 -357.891289) (xy 389.468194 -357.838957) (xy 389.460432 -357.784971) (xy 387.977728 -357.784971)
			(xy 387.977728 -357.784974) (xy 387.969965 -357.838967) (xy 387.954597 -357.891305) (xy 387.931936 -357.940924)
			(xy 387.902444 -357.986812) (xy 387.866722 -358.028036) (xy 387.825496 -358.063756) (xy 387.779606 -358.093245)
			(xy 387.729987 -358.115904) (xy 387.677647 -358.131269) (xy 387.623654 -358.13903) (xy 387.59638 -358.139492)
			(xy 386.73278 -358.139492) (xy 386.705514 -358.138944) (xy 386.651537 -358.131181) (xy 386.599213 -358.115815)
			(xy 386.54961 -358.093159) (xy 386.503735 -358.063675) (xy 386.462523 -358.027963) (xy 386.426813 -357.986749)
			(xy 386.397331 -357.940873) (xy 386.374678 -357.891268) (xy 386.359315 -357.838944) (xy 386.351554 -357.784966)
			(xy 384.868706 -357.784966) (xy 384.868706 -357.784971) (xy 384.860944 -357.838957) (xy 384.845578 -357.891289)
			(xy 384.822922 -357.940901) (xy 384.793435 -357.986785) (xy 384.75772 -358.028005) (xy 384.716501 -358.063723)
			(xy 384.670619 -358.093212) (xy 384.621007 -358.115871) (xy 384.568676 -358.13124) (xy 384.514691 -358.139004)
			(xy 384.48742 -358.139492) (xy 383.62382 -358.139492) (xy 383.59655 -358.13897) (xy 383.542565 -358.131211)
			(xy 383.490234 -358.115847) (xy 383.440623 -358.093193) (xy 383.39474 -358.063708) (xy 383.353521 -358.027993)
			(xy 383.317804 -357.986776) (xy 383.288317 -357.940895) (xy 383.26566 -357.891284) (xy 383.250294 -357.838954)
			(xy 383.242531 -357.78497) (xy 381.759828 -357.78497) (xy 381.759828 -357.784975) (xy 381.752065 -357.83897)
			(xy 381.736695 -357.89131) (xy 381.714033 -357.940929) (xy 381.684539 -357.986818) (xy 381.648815 -358.028043)
			(xy 381.607586 -358.063763) (xy 381.561694 -358.093252) (xy 381.512072 -358.115909) (xy 381.45973 -358.131273)
			(xy 381.405735 -358.139031) (xy 381.37846 -358.139492) (xy 380.51486 -358.139492) (xy 380.487595 -358.138943)
			(xy 380.43362 -358.131177) (xy 380.381299 -358.11581) (xy 380.331698 -358.093153) (xy 380.285825 -358.063668)
			(xy 380.244616 -358.027956) (xy 380.208908 -357.986742) (xy 380.179428 -357.940867) (xy 380.156776 -357.891263)
			(xy 380.141414 -357.838941) (xy 380.133654 -357.784965) (xy 378.650805 -357.784965) (xy 378.650805 -357.784972)
			(xy 378.643043 -357.838959) (xy 378.627677 -357.891293) (xy 378.605019 -357.940907) (xy 378.575531 -357.986792)
			(xy 378.539812 -358.028012) (xy 378.498592 -358.063731) (xy 378.452707 -358.093219) (xy 378.403093 -358.115877)
			(xy 378.350759 -358.131243) (xy 378.296772 -358.139005) (xy 378.2695 -358.139492) (xy 377.4059 -358.139492)
			(xy 377.378633 -358.138946) (xy 377.324653 -358.131185) (xy 377.272328 -358.11582) (xy 377.222722 -358.093166)
			(xy 377.176844 -358.063682) (xy 377.13563 -358.02797) (xy 377.099918 -357.986756) (xy 377.070434 -357.940878)
			(xy 377.04778 -357.891272) (xy 377.032415 -357.838947) (xy 377.024654 -357.784967) (xy 375.541806 -357.784967)
			(xy 375.541806 -357.78497) (xy 375.534044 -357.838954) (xy 375.51868 -357.891284) (xy 375.496025 -357.940896)
			(xy 375.46654 -357.986778) (xy 375.430827 -358.027998) (xy 375.389611 -358.063716) (xy 375.343731 -358.093206)
			(xy 375.294122 -358.115866) (xy 375.241793 -358.131236) (xy 375.18781 -358.139003) (xy 375.16054 -358.139492)
			(xy 374.29694 -358.139492) (xy 374.269669 -358.138971) (xy 374.215682 -358.131214) (xy 374.163349 -358.115853)
			(xy 374.113735 -358.093199) (xy 374.06785 -358.063715) (xy 374.026628 -358.028) (xy 373.990909 -357.986783)
			(xy 373.96142 -357.940901) (xy 373.938761 -357.891289) (xy 373.923394 -357.838957) (xy 373.915632 -357.784971)
			(xy 344.837306 -357.784971) (xy 344.829543 -357.838959) (xy 344.814177 -357.891292) (xy 344.791519 -357.940906)
			(xy 344.762031 -357.98679) (xy 344.726314 -358.028011) (xy 344.685093 -358.063729) (xy 344.639209 -358.093217)
			(xy 344.589596 -358.115876) (xy 344.537263 -358.131242) (xy 344.483275 -358.139005) (xy 344.456004 -358.139492)
			(xy 343.592404 -358.139492) (xy 343.565135 -358.138969) (xy 343.511152 -358.131208) (xy 343.458823 -358.115843)
			(xy 343.409213 -358.093188) (xy 343.363333 -358.063702) (xy 343.322115 -358.027988) (xy 343.2864 -357.986771)
			(xy 343.256914 -357.94089) (xy 343.234258 -357.891281) (xy 343.218893 -357.838952) (xy 343.211131 -357.784969)
			(xy 341.728306 -357.784969) (xy 341.728306 -357.78497) (xy 341.720544 -357.838953) (xy 341.70518 -357.891284)
			(xy 341.682525 -357.940895) (xy 341.653041 -357.986777) (xy 341.617328 -358.027997) (xy 341.576112 -358.063715)
			(xy 341.530233 -358.093204) (xy 341.480625 -358.115865) (xy 341.428297 -358.131235) (xy 341.374313 -358.139002)
			(xy 341.347044 -358.139492) (xy 340.483444 -358.139492) (xy 340.456173 -358.138972) (xy 340.402186 -358.131215)
			(xy 340.349852 -358.115854) (xy 340.300237 -358.093201) (xy 340.254351 -358.063716) (xy 340.213129 -358.028002)
			(xy 340.17741 -357.986784) (xy 340.147921 -357.940902) (xy 340.125261 -357.891289) (xy 340.109894 -357.838957)
			(xy 340.102132 -357.784971) (xy 338.619428 -357.784971) (xy 338.619428 -357.784974) (xy 338.611665 -357.838966)
			(xy 338.596297 -357.891304) (xy 338.573636 -357.940923) (xy 338.544145 -357.986811) (xy 338.508423 -358.028034)
			(xy 338.467198 -358.063755) (xy 338.421308 -358.093244) (xy 338.371689 -358.115903) (xy 338.319351 -358.131269)
			(xy 338.265358 -358.13903) (xy 338.238084 -358.139492) (xy 337.374484 -358.139492) (xy 337.347218 -358.138945)
			(xy 337.29324 -358.131182) (xy 337.240916 -358.115816) (xy 337.191312 -358.093161) (xy 337.145437 -358.063677)
			(xy 337.104224 -358.027964) (xy 337.068514 -357.98675) (xy 337.039032 -357.940874) (xy 337.016378 -357.891269)
			(xy 337.001015 -357.838944) (xy 336.993254 -357.784967) (xy 335.510406 -357.784967) (xy 335.510406 -357.78497)
			(xy 335.502644 -357.838956) (xy 335.487279 -357.891288) (xy 335.464622 -357.9409) (xy 335.435136 -357.986784)
			(xy 335.399421 -358.028004) (xy 335.358203 -358.063722) (xy 335.312321 -358.093211) (xy 335.26271 -358.11587)
			(xy 335.21038 -358.131239) (xy 335.156394 -358.139004) (xy 335.129124 -358.139492) (xy 334.265524 -358.139492)
			(xy 334.238254 -358.13897) (xy 334.184269 -358.131211) (xy 334.131937 -358.115848) (xy 334.082325 -358.093194)
			(xy 334.036442 -358.063709) (xy 333.995222 -358.027995) (xy 333.959505 -357.986777) (xy 333.930017 -357.940896)
			(xy 333.90736 -357.891285) (xy 333.891994 -357.838955) (xy 333.884231 -357.78497) (xy 332.401528 -357.78497)
			(xy 332.401528 -357.784975) (xy 332.393765 -357.838969) (xy 332.378395 -357.891309) (xy 332.355733 -357.940928)
			(xy 332.32624 -357.986817) (xy 332.290516 -358.028041) (xy 332.249288 -358.063762) (xy 332.203397 -358.093251)
			(xy 332.153775 -358.115908) (xy 332.101434 -358.131272) (xy 332.047439 -358.139031) (xy 332.020164 -358.139492)
			(xy 331.156564 -358.139492) (xy 331.129298 -358.138943) (xy 331.075323 -358.131178) (xy 331.023002 -358.115811)
			(xy 330.9734 -358.093154) (xy 330.927527 -358.06367) (xy 330.886317 -358.027957) (xy 330.850609 -357.986744)
			(xy 330.821128 -357.940868) (xy 330.798477 -357.891264) (xy 330.783114 -357.838942) (xy 330.775354 -357.784966)
			(xy 329.292506 -357.784966) (xy 329.292506 -357.784971) (xy 329.284743 -357.838959) (xy 329.269377 -357.891292)
			(xy 329.246719 -357.940906) (xy 329.217231 -357.98679) (xy 329.181514 -358.028011) (xy 329.140293 -358.063729)
			(xy 329.094409 -358.093217) (xy 329.044796 -358.115876) (xy 328.992463 -358.131242) (xy 328.938475 -358.139005)
			(xy 328.911204 -358.139492) (xy 328.047604 -358.139492) (xy 328.020335 -358.138969) (xy 327.966352 -358.131208)
			(xy 327.914023 -358.115843) (xy 327.864413 -358.093188) (xy 327.818533 -358.063702) (xy 327.777315 -358.027988)
			(xy 327.7416 -357.986771) (xy 327.712114 -357.94089) (xy 327.689458 -357.891281) (xy 327.674093 -357.838952)
			(xy 327.666331 -357.784969) (xy 326.183506 -357.784969) (xy 326.183506 -357.78497) (xy 326.175744 -357.838953)
			(xy 326.16038 -357.891284) (xy 326.137725 -357.940895) (xy 326.108241 -357.986777) (xy 326.072528 -358.027997)
			(xy 326.031312 -358.063715) (xy 325.985433 -358.093204) (xy 325.935825 -358.115865) (xy 325.883497 -358.131235)
			(xy 325.829513 -358.139002) (xy 325.802244 -358.139492) (xy 324.938644 -358.139492) (xy 324.911373 -358.138972)
			(xy 324.857386 -358.131215) (xy 324.805052 -358.115854) (xy 324.755437 -358.093201) (xy 324.709551 -358.063716)
			(xy 324.668329 -358.028002) (xy 324.63261 -357.986784) (xy 324.603121 -357.940902) (xy 324.580461 -357.891289)
			(xy 324.565094 -357.838957) (xy 324.557332 -357.784971) (xy 323.074628 -357.784971) (xy 323.074628 -357.784974)
			(xy 323.066865 -357.838966) (xy 323.051497 -357.891304) (xy 323.028836 -357.940923) (xy 322.999345 -357.986811)
			(xy 322.963623 -358.028034) (xy 322.922398 -358.063755) (xy 322.876508 -358.093244) (xy 322.826889 -358.115903)
			(xy 322.774551 -358.131269) (xy 322.720558 -358.13903) (xy 322.693284 -358.139492) (xy 321.829684 -358.139492)
			(xy 321.802418 -358.138945) (xy 321.74844 -358.131182) (xy 321.696116 -358.115816) (xy 321.646512 -358.093161)
			(xy 321.600637 -358.063677) (xy 321.559424 -358.027964) (xy 321.523714 -357.98675) (xy 321.494232 -357.940874)
			(xy 321.471578 -357.891269) (xy 321.456215 -357.838944) (xy 321.448454 -357.784967) (xy 319.965606 -357.784967)
			(xy 319.965606 -357.78497) (xy 319.957844 -357.838956) (xy 319.942479 -357.891288) (xy 319.919822 -357.9409)
			(xy 319.890336 -357.986784) (xy 319.854621 -358.028004) (xy 319.813403 -358.063722) (xy 319.767521 -358.093211)
			(xy 319.71791 -358.11587) (xy 319.66558 -358.131239) (xy 319.611594 -358.139004) (xy 319.584324 -358.139492)
			(xy 318.720724 -358.139492) (xy 318.693454 -358.13897) (xy 318.639469 -358.131211) (xy 318.587137 -358.115848)
			(xy 318.537525 -358.093194) (xy 318.491642 -358.063709) (xy 318.450422 -358.027995) (xy 318.414705 -357.986777)
			(xy 318.385217 -357.940896) (xy 318.36256 -357.891285) (xy 318.347194 -357.838955) (xy 318.339431 -357.78497)
			(xy 316.856728 -357.78497) (xy 316.856728 -357.784975) (xy 316.848965 -357.838969) (xy 316.833595 -357.891309)
			(xy 316.810933 -357.940928) (xy 316.78144 -357.986817) (xy 316.745716 -358.028041) (xy 316.704488 -358.063762)
			(xy 316.658597 -358.093251) (xy 316.608975 -358.115908) (xy 316.556634 -358.131272) (xy 316.502639 -358.139031)
			(xy 316.475364 -358.139492) (xy 315.611764 -358.139492) (xy 315.584498 -358.138943) (xy 315.530523 -358.131178)
			(xy 315.478202 -358.115811) (xy 315.4286 -358.093154) (xy 315.382727 -358.06367) (xy 315.341517 -358.027957)
			(xy 315.305809 -357.986744) (xy 315.276328 -357.940868) (xy 315.253677 -357.891264) (xy 315.238314 -357.838942)
			(xy 315.230554 -357.784966) (xy 300.231606 -357.784966) (xy 300.231606 -357.784971) (xy 300.223843 -357.838959)
			(xy 300.208477 -357.891293) (xy 300.185819 -357.940907) (xy 300.156331 -357.986791) (xy 300.120613 -358.028012)
			(xy 300.079393 -358.06373) (xy 300.033508 -358.093218) (xy 299.983894 -358.115876) (xy 299.931561 -358.131243)
			(xy 299.877573 -358.139005) (xy 299.850302 -358.139492) (xy 298.986702 -358.139492) (xy 298.959433 -358.138969)
			(xy 298.90545 -358.131207) (xy 298.853121 -358.115843) (xy 298.803512 -358.093187) (xy 298.757632 -358.063702)
			(xy 298.716414 -358.027987) (xy 298.6807 -357.98677) (xy 298.651214 -357.94089) (xy 298.628558 -357.89128)
			(xy 298.613193 -357.838952) (xy 298.605431 -357.784969) (xy 297.122606 -357.784969) (xy 297.122606 -357.78497)
			(xy 297.114844 -357.838954) (xy 297.09948 -357.891284) (xy 297.076825 -357.940895) (xy 297.047341 -357.986778)
			(xy 297.011627 -358.027998) (xy 296.970411 -358.063716) (xy 296.924532 -358.093205) (xy 296.874923 -358.115865)
			(xy 296.822595 -358.131235) (xy 296.768612 -358.139003) (xy 296.741342 -358.139492) (xy 295.877742 -358.139492)
			(xy 295.850471 -358.138971) (xy 295.796484 -358.131215) (xy 295.74415 -358.115853) (xy 295.694536 -358.0932)
			(xy 295.64865 -358.063716) (xy 295.607429 -358.028001) (xy 295.571709 -357.986783) (xy 295.54222 -357.940901)
			(xy 295.519561 -357.891289) (xy 295.504194 -357.838957) (xy 295.496432 -357.784971) (xy 294.013728 -357.784971)
			(xy 294.013728 -357.784974) (xy 294.005965 -357.838967) (xy 293.990597 -357.891305) (xy 293.967936 -357.940923)
			(xy 293.938444 -357.986811) (xy 293.902722 -358.028035) (xy 293.861497 -358.063755) (xy 293.815607 -358.093245)
			(xy 293.765988 -358.115903) (xy 293.713649 -358.131269) (xy 293.659656 -358.13903) (xy 293.632382 -358.139492)
			(xy 292.768782 -358.139492) (xy 292.741516 -358.138944) (xy 292.687538 -358.131181) (xy 292.635215 -358.115816)
			(xy 292.585611 -358.09316) (xy 292.539736 -358.063676) (xy 292.498524 -358.027964) (xy 292.462813 -357.98675)
			(xy 292.433331 -357.940873) (xy 292.410678 -357.891268) (xy 292.395315 -357.838944) (xy 292.387554 -357.784966)
			(xy 290.904706 -357.784966) (xy 290.904706 -357.784971) (xy 290.896944 -357.838956) (xy 290.881578 -357.891288)
			(xy 290.858922 -357.940901) (xy 290.829436 -357.986784) (xy 290.79372 -358.028005) (xy 290.752502 -358.063723)
			(xy 290.70662 -358.093211) (xy 290.657009 -358.115871) (xy 290.604678 -358.131239) (xy 290.550692 -358.139004)
			(xy 290.523422 -358.139492) (xy 289.659822 -358.139492) (xy 289.632552 -358.13897) (xy 289.578567 -358.131211)
			(xy 289.526236 -358.115848) (xy 289.476624 -358.093193) (xy 289.430741 -358.063709) (xy 289.389522 -358.027994)
			(xy 289.353805 -357.986777) (xy 289.324317 -357.940895) (xy 289.30166 -357.891285) (xy 289.286294 -357.838954)
			(xy 289.278531 -357.78497) (xy 287.795828 -357.78497) (xy 287.795828 -357.784975) (xy 287.788065 -357.838969)
			(xy 287.772695 -357.891309) (xy 287.750033 -357.940929) (xy 287.72054 -357.986818) (xy 287.684815 -358.028042)
			(xy 287.643587 -358.063762) (xy 287.597695 -358.093251) (xy 287.548073 -358.115908) (xy 287.495732 -358.131273)
			(xy 287.441737 -358.139031) (xy 287.414462 -358.139492) (xy 286.550862 -358.139492) (xy 286.523597 -358.138943)
			(xy 286.469621 -358.131178) (xy 286.4173 -358.11581) (xy 286.367699 -358.093154) (xy 286.321826 -358.063669)
			(xy 286.280617 -358.027957) (xy 286.244908 -357.986743) (xy 286.215428 -357.940868) (xy 286.192777 -357.891264)
			(xy 286.177414 -357.838942) (xy 286.169654 -357.784966) (xy 284.686806 -357.784966) (xy 284.686806 -357.784971)
			(xy 284.679043 -357.838959) (xy 284.663677 -357.891293) (xy 284.641019 -357.940907) (xy 284.611531 -357.986791)
			(xy 284.575813 -358.028012) (xy 284.534593 -358.06373) (xy 284.488708 -358.093218) (xy 284.439094 -358.115876)
			(xy 284.386761 -358.131243) (xy 284.332773 -358.139005) (xy 284.305502 -358.139492) (xy 283.441902 -358.139492)
			(xy 283.414633 -358.138969) (xy 283.36065 -358.131207) (xy 283.308321 -358.115843) (xy 283.258712 -358.093187)
			(xy 283.212832 -358.063702) (xy 283.171614 -358.027987) (xy 283.1359 -357.98677) (xy 283.106414 -357.94089)
			(xy 283.083758 -357.89128) (xy 283.068393 -357.838952) (xy 283.060631 -357.784969) (xy 281.577806 -357.784969)
			(xy 281.577806 -357.78497) (xy 281.570044 -357.838954) (xy 281.55468 -357.891284) (xy 281.532025 -357.940895)
			(xy 281.502541 -357.986778) (xy 281.466827 -358.027998) (xy 281.425611 -358.063716) (xy 281.379732 -358.093205)
			(xy 281.330123 -358.115865) (xy 281.277795 -358.131235) (xy 281.223812 -358.139003) (xy 281.196542 -358.139492)
			(xy 280.332942 -358.139492) (xy 280.305671 -358.138971) (xy 280.251684 -358.131215) (xy 280.19935 -358.115853)
			(xy 280.149736 -358.0932) (xy 280.10385 -358.063716) (xy 280.062629 -358.028001) (xy 280.026909 -357.986783)
			(xy 279.99742 -357.940901) (xy 279.974761 -357.891289) (xy 279.959394 -357.838957) (xy 279.951632 -357.784971)
			(xy 278.468928 -357.784971) (xy 278.468928 -357.784974) (xy 278.461165 -357.838967) (xy 278.445797 -357.891305)
			(xy 278.423136 -357.940923) (xy 278.393644 -357.986811) (xy 278.357922 -358.028035) (xy 278.316697 -358.063755)
			(xy 278.270807 -358.093245) (xy 278.221188 -358.115903) (xy 278.168849 -358.131269) (xy 278.114856 -358.13903)
			(xy 278.087582 -358.139492) (xy 277.223982 -358.139492) (xy 277.196716 -358.138944) (xy 277.142738 -358.131181)
			(xy 277.090415 -358.115816) (xy 277.040811 -358.09316) (xy 276.994936 -358.063676) (xy 276.953724 -358.027964)
			(xy 276.918013 -357.98675) (xy 276.888531 -357.940873) (xy 276.865878 -357.891268) (xy 276.850515 -357.838944)
			(xy 276.842754 -357.784966) (xy 275.359906 -357.784966) (xy 275.359906 -357.784971) (xy 275.352144 -357.838956)
			(xy 275.336778 -357.891288) (xy 275.314122 -357.940901) (xy 275.284636 -357.986784) (xy 275.24892 -358.028005)
			(xy 275.207702 -358.063723) (xy 275.16182 -358.093211) (xy 275.112209 -358.115871) (xy 275.059878 -358.131239)
			(xy 275.005892 -358.139004) (xy 274.978622 -358.139492) (xy 274.115022 -358.139492) (xy 274.087752 -358.13897)
			(xy 274.033767 -358.131211) (xy 273.981436 -358.115848) (xy 273.931824 -358.093193) (xy 273.885941 -358.063709)
			(xy 273.844722 -358.027994) (xy 273.809005 -357.986777) (xy 273.779517 -357.940895) (xy 273.75686 -357.891285)
			(xy 273.741494 -357.838954) (xy 273.733731 -357.78497) (xy 272.251028 -357.78497) (xy 272.251028 -357.784975)
			(xy 272.243265 -357.838969) (xy 272.227895 -357.891309) (xy 272.205233 -357.940929) (xy 272.17574 -357.986818)
			(xy 272.140015 -358.028042) (xy 272.098787 -358.063762) (xy 272.052895 -358.093251) (xy 272.003273 -358.115908)
			(xy 271.950932 -358.131273) (xy 271.896937 -358.139031) (xy 271.869662 -358.139492) (xy 271.006062 -358.139492)
			(xy 270.978797 -358.138943) (xy 270.924821 -358.131178) (xy 270.8725 -358.11581) (xy 270.822899 -358.093154)
			(xy 270.777026 -358.063669) (xy 270.735817 -358.027957) (xy 270.700108 -357.986743) (xy 270.670628 -357.940868)
			(xy 270.647977 -357.891264) (xy 270.632614 -357.838942) (xy 270.624854 -357.784966) (xy 247.276485 -357.784966)
			(xy 247.278987 -357.797946) (xy 247.287038 -357.88226) (xy 247.287542 -357.924608) (xy 247.287038 -357.966956)
			(xy 247.278987 -358.05127) (xy 247.262958 -358.134436) (xy 247.239097 -358.215703) (xy 247.207618 -358.294333)
			(xy 247.168807 -358.369614) (xy 247.123017 -358.440866) (xy 247.070661 -358.507442) (xy 247.012213 -358.56874)
			(xy 246.948203 -358.624205) (xy 246.879211 -358.673334) (xy 246.805861 -358.715683) (xy 246.728818 -358.750867)
			(xy 246.648779 -358.778569) (xy 246.56647 -358.798537) (xy 246.482635 -358.81059) (xy 246.398034 -358.814621)
			(xy 246.313433 -358.81059) (xy 246.229598 -358.798537) (xy 246.147289 -358.778569) (xy 246.06725 -358.750867)
			(xy 245.990207 -358.715683) (xy 245.916857 -358.673334) (xy 245.847865 -358.624205) (xy 245.783855 -358.56874)
			(xy 245.725407 -358.507442) (xy 245.673051 -358.440866) (xy 245.627261 -358.369614) (xy 245.58845 -358.294333)
			(xy 245.556971 -358.215703) (xy 245.53311 -358.134436) (xy 245.517081 -358.05127) (xy 245.50903 -357.966956)
			(xy 188.223925 -357.966956) (xy 188.191672 -358.004178) (xy 188.150456 -358.039891) (xy 188.104577 -358.069375)
			(xy 188.054969 -358.092029) (xy 188.002641 -358.107393) (xy 187.94866 -358.115153) (xy 187.921392 -358.115616)
			(xy 187.057792 -358.115616) (xy 187.03052 -358.115221) (xy 186.97653 -358.107457) (xy 186.924196 -358.092089)
			(xy 186.87458 -358.06943) (xy 186.828695 -358.03994) (xy 186.787473 -358.004221) (xy 186.751755 -357.962999)
			(xy 186.722266 -357.917112) (xy 186.699608 -357.867497) (xy 186.684241 -357.815162) (xy 186.676479 -357.761172)
			(xy 185.193629 -357.761172) (xy 185.18587 -357.815139) (xy 185.170508 -357.86746) (xy 185.147857 -357.917062)
			(xy 185.118378 -357.962936) (xy 185.08267 -358.004147) (xy 185.041461 -358.039858) (xy 184.99559 -358.069342)
			(xy 184.94599 -358.091997) (xy 184.89367 -358.107363) (xy 184.839697 -358.115128) (xy 184.812432 -358.115616)
			(xy 183.948832 -358.115616) (xy 183.921556 -358.115247) (xy 183.867559 -358.107487) (xy 183.815217 -358.092122)
			(xy 183.765593 -358.069463) (xy 183.7197 -358.039973) (xy 183.678471 -358.004251) (xy 183.642746 -357.963025)
			(xy 183.613252 -357.917135) (xy 183.590589 -357.867513) (xy 183.57522 -357.815172) (xy 183.567456 -357.761176)
			(xy 182.084828 -357.761176) (xy 182.084828 -357.784974) (xy 182.077065 -357.838968) (xy 182.061696 -357.891307)
			(xy 182.039035 -357.940926) (xy 182.009542 -357.986815) (xy 181.973819 -358.028039) (xy 181.932592 -358.063759)
			(xy 181.886701 -358.093248) (xy 181.837081 -358.115906) (xy 181.784741 -358.131271) (xy 181.730746 -358.13903)
			(xy 181.703472 -358.139492) (xy 180.839872 -358.139492) (xy 180.812606 -358.138944) (xy 180.75863 -358.131179)
			(xy 180.706308 -358.115813) (xy 180.656705 -358.093157) (xy 180.610831 -358.063673) (xy 180.56962 -358.02796)
			(xy 180.533911 -357.986746) (xy 180.50443 -357.94087) (xy 180.481777 -357.891266) (xy 180.466415 -357.838943)
			(xy 180.458654 -357.784966) (xy 178.975806 -357.784966) (xy 178.975806 -357.784971) (xy 178.968044 -357.838958)
			(xy 178.952678 -357.89129) (xy 178.930021 -357.940904) (xy 178.900533 -357.986788) (xy 178.864817 -358.028008)
			(xy 178.823597 -358.063726) (xy 178.777714 -358.093215) (xy 178.728102 -358.115873) (xy 178.675769 -358.131241)
			(xy 178.621783 -358.139005) (xy 178.594512 -358.139492) (xy 177.730912 -358.139492) (xy 177.703643 -358.138969)
			(xy 177.649659 -358.131209) (xy 177.597329 -358.115845) (xy 177.547718 -358.09319) (xy 177.501836 -358.063705)
			(xy 177.460618 -358.027991) (xy 177.424902 -357.986773) (xy 177.395416 -357.940893) (xy 177.372759 -357.891283)
			(xy 177.357393 -357.838953) (xy 177.349631 -357.784969) (xy 175.866928 -357.784969) (xy 175.866928 -357.784975)
			(xy 175.859164 -357.838971) (xy 175.843794 -357.891311) (xy 175.821132 -357.940932) (xy 175.791637 -357.986821)
			(xy 175.755912 -358.028046) (xy 175.714683 -358.063766) (xy 175.668789 -358.093255) (xy 175.619166 -358.115911)
			(xy 175.566824 -358.131275) (xy 175.512827 -358.139032) (xy 175.485552 -358.139492) (xy 174.621952 -358.139492)
			(xy 174.594687 -358.138942) (xy 174.540713 -358.131176) (xy 174.488393 -358.115807) (xy 174.438793 -358.09315)
			(xy 174.392922 -358.063665) (xy 174.351713 -358.027953) (xy 174.316006 -357.98674) (xy 174.286527 -357.940865)
			(xy 174.263876 -357.891262) (xy 174.248514 -357.83894) (xy 174.240754 -357.784965) (xy 172.757928 -357.784965)
			(xy 172.757928 -357.784974) (xy 172.750165 -357.838965) (xy 172.734798 -357.891303) (xy 172.712138 -357.94092)
			(xy 172.682647 -357.986808) (xy 172.646926 -358.028032) (xy 172.605702 -358.063752) (xy 172.559813 -358.093241)
			(xy 172.510195 -358.1159) (xy 172.457857 -358.131267) (xy 172.403866 -358.139029) (xy 172.376592 -358.139492)
			(xy 171.512992 -358.139492) (xy 171.485725 -358.138945) (xy 171.431747 -358.131183) (xy 171.379422 -358.115818)
			(xy 171.329817 -358.093163) (xy 171.283941 -358.06368) (xy 171.242727 -358.027967) (xy 171.207016 -357.986753)
			(xy 171.177533 -357.940876) (xy 171.154879 -357.89127) (xy 171.139515 -357.838946) (xy 171.131754 -357.784967)
			(xy 169.648906 -357.784967) (xy 169.648906 -357.78497) (xy 169.641144 -357.838955) (xy 169.625779 -357.891286)
			(xy 169.603124 -357.940898) (xy 169.573638 -357.986781) (xy 169.537924 -358.028001) (xy 169.496707 -358.063719)
			(xy 169.450826 -358.093208) (xy 169.401216 -358.115868) (xy 169.348886 -358.131237) (xy 169.294902 -358.139003)
			(xy 169.267632 -358.139492) (xy 168.404032 -358.139492) (xy 168.376762 -358.138971) (xy 168.322776 -358.131213)
			(xy 168.270443 -358.115851) (xy 168.22083 -358.093197) (xy 168.174946 -358.063712) (xy 168.133725 -358.027998)
			(xy 168.098007 -357.98678) (xy 168.068519 -357.940898) (xy 168.045861 -357.891287) (xy 168.030494 -357.838956)
			(xy 168.022732 -357.78497) (xy 166.540028 -357.78497) (xy 166.540028 -357.784974) (xy 166.532265 -357.838968)
			(xy 166.516896 -357.891307) (xy 166.494235 -357.940926) (xy 166.464742 -357.986815) (xy 166.429019 -358.028039)
			(xy 166.387792 -358.063759) (xy 166.341901 -358.093248) (xy 166.292281 -358.115906) (xy 166.239941 -358.131271)
			(xy 166.185946 -358.13903) (xy 166.158672 -358.139492) (xy 165.295072 -358.139492) (xy 165.267806 -358.138944)
			(xy 165.21383 -358.131179) (xy 165.161508 -358.115813) (xy 165.111905 -358.093157) (xy 165.066031 -358.063673)
			(xy 165.02482 -358.02796) (xy 164.989111 -357.986746) (xy 164.95963 -357.94087) (xy 164.936977 -357.891266)
			(xy 164.921615 -357.838943) (xy 164.913854 -357.784966) (xy 163.431006 -357.784966) (xy 163.431006 -357.784971)
			(xy 163.423244 -357.838958) (xy 163.407878 -357.89129) (xy 163.385221 -357.940904) (xy 163.355733 -357.986788)
			(xy 163.320017 -358.028008) (xy 163.278797 -358.063726) (xy 163.232914 -358.093215) (xy 163.183302 -358.115873)
			(xy 163.130969 -358.131241) (xy 163.076983 -358.139005) (xy 163.049712 -358.139492) (xy 162.186112 -358.139492)
			(xy 162.158843 -358.138969) (xy 162.104859 -358.131209) (xy 162.052529 -358.115845) (xy 162.002918 -358.09319)
			(xy 161.957036 -358.063705) (xy 161.915818 -358.027991) (xy 161.880102 -357.986773) (xy 161.850616 -357.940893)
			(xy 161.827959 -357.891283) (xy 161.812593 -357.838953) (xy 161.804831 -357.784969) (xy 160.322128 -357.784969)
			(xy 160.322128 -357.784975) (xy 160.314364 -357.838971) (xy 160.298994 -357.891311) (xy 160.276332 -357.940932)
			(xy 160.246837 -357.986821) (xy 160.211112 -358.028046) (xy 160.169883 -358.063766) (xy 160.123989 -358.093255)
			(xy 160.074366 -358.115911) (xy 160.022024 -358.131275) (xy 159.968027 -358.139032) (xy 159.940752 -358.139492)
			(xy 159.077152 -358.139492) (xy 159.049887 -358.138942) (xy 158.995913 -358.131176) (xy 158.943593 -358.115807)
			(xy 158.893993 -358.09315) (xy 158.848122 -358.063665) (xy 158.806913 -358.027953) (xy 158.771206 -357.98674)
			(xy 158.741727 -357.940865) (xy 158.719076 -357.891262) (xy 158.703714 -357.83894) (xy 158.695954 -357.784965)
			(xy 144.196606 -357.784965) (xy 144.196606 -357.784971) (xy 144.188843 -357.838958) (xy 144.173477 -357.891291)
			(xy 144.15082 -357.940905) (xy 144.121332 -357.986789) (xy 144.085615 -358.02801) (xy 144.044395 -358.063728)
			(xy 143.998512 -358.093216) (xy 143.948899 -358.115875) (xy 143.896566 -358.131242) (xy 143.842579 -358.139005)
			(xy 143.815308 -358.139492) (xy 142.951708 -358.139492) (xy 142.924439 -358.138969) (xy 142.870455 -358.131209)
			(xy 142.818126 -358.115844) (xy 142.768515 -358.093189) (xy 142.722634 -358.063704) (xy 142.681417 -358.027989)
			(xy 142.645701 -357.986772) (xy 142.616215 -357.940892) (xy 142.593559 -357.891282) (xy 142.578193 -357.838953)
			(xy 142.570431 -357.784969) (xy 141.087606 -357.784969) (xy 141.079845 -357.838953) (xy 141.06448 -357.891283)
			(xy 141.041826 -357.940894) (xy 141.012342 -357.986776) (xy 140.976629 -358.027995) (xy 140.935414 -358.063713)
			(xy 140.889536 -358.093203) (xy 140.839928 -358.115864) (xy 140.7876 -358.131234) (xy 140.733617 -358.139002)
			(xy 140.706348 -358.139492) (xy 139.842748 -358.139492) (xy 139.815477 -358.138972) (xy 139.761489 -358.131216)
			(xy 139.709155 -358.115855) (xy 139.659539 -358.093202) (xy 139.613653 -358.063718) (xy 139.572431 -358.028003)
			(xy 139.536711 -357.986785) (xy 139.507221 -357.940903) (xy 139.484562 -357.89129) (xy 139.469194 -357.838958)
			(xy 139.461432 -357.784971) (xy 137.978728 -357.784971) (xy 137.978728 -357.784974) (xy 137.970965 -357.838966)
			(xy 137.955597 -357.891304) (xy 137.932937 -357.940921) (xy 137.903446 -357.986809) (xy 137.867724 -358.028033)
			(xy 137.8265 -358.063753) (xy 137.780611 -358.093243) (xy 137.730992 -358.115901) (xy 137.678654 -358.131268)
			(xy 137.624662 -358.139029) (xy 137.597388 -358.139492) (xy 136.733788 -358.139492) (xy 136.706521 -358.138945)
			(xy 136.652543 -358.131182) (xy 136.600219 -358.115817) (xy 136.550615 -358.093162) (xy 136.504739 -358.063678)
			(xy 136.463526 -358.027966) (xy 136.427815 -357.986752) (xy 136.398332 -357.940875) (xy 136.375679 -357.891269)
			(xy 136.360315 -357.838945) (xy 136.352554 -357.784967) (xy 134.869706 -357.784967) (xy 134.869706 -357.78497)
			(xy 134.861944 -357.838956) (xy 134.846579 -357.891287) (xy 134.823923 -357.940899) (xy 134.794437 -357.986782)
			(xy 134.758722 -358.028003) (xy 134.717505 -358.063721) (xy 134.671624 -358.09321) (xy 134.622013 -358.115869)
			(xy 134.569683 -358.131238) (xy 134.515698 -358.139004) (xy 134.488428 -358.139492) (xy 133.624828 -358.139492)
			(xy 133.597558 -358.13897) (xy 133.543572 -358.131212) (xy 133.49124 -358.11585) (xy 133.441627 -358.093195)
			(xy 133.395744 -358.063711) (xy 133.354524 -358.027996) (xy 133.318806 -357.986779) (xy 133.289318 -357.940897)
			(xy 133.26666 -357.891286) (xy 133.251294 -357.838955) (xy 133.243531 -357.78497) (xy 131.760828 -357.78497)
			(xy 131.760828 -357.784975) (xy 131.753065 -357.838969) (xy 131.737696 -357.891308) (xy 131.715034 -357.940927)
			(xy 131.685541 -357.986816) (xy 131.649817 -358.02804) (xy 131.60859 -358.06376) (xy 131.562699 -358.093249)
			(xy 131.513078 -358.115907) (xy 131.460737 -358.131272) (xy 131.406743 -358.139031) (xy 131.379468 -358.139492)
			(xy 130.515868 -358.139492) (xy 130.488602 -358.138943) (xy 130.434626 -358.131179) (xy 130.382305 -358.115812)
			(xy 130.332703 -358.093156) (xy 130.286829 -358.063671) (xy 130.245619 -358.027959) (xy 130.20991 -357.986745)
			(xy 130.180429 -357.940869) (xy 130.157777 -357.891265) (xy 130.142414 -357.838942) (xy 130.134654 -357.784966)
			(xy 128.651806 -357.784966) (xy 128.651806 -357.784971) (xy 128.644043 -357.838958) (xy 128.628677 -357.891291)
			(xy 128.60602 -357.940905) (xy 128.576532 -357.986789) (xy 128.540815 -358.02801) (xy 128.499595 -358.063728)
			(xy 128.453712 -358.093216) (xy 128.404099 -358.115875) (xy 128.351766 -358.131242) (xy 128.297779 -358.139005)
			(xy 128.270508 -358.139492) (xy 127.406908 -358.139492) (xy 127.379639 -358.138969) (xy 127.325655 -358.131209)
			(xy 127.273326 -358.115844) (xy 127.223715 -358.093189) (xy 127.177834 -358.063704) (xy 127.136617 -358.027989)
			(xy 127.100901 -357.986772) (xy 127.071415 -357.940892) (xy 127.048759 -357.891282) (xy 127.033393 -357.838953)
			(xy 127.025631 -357.784969) (xy 125.542806 -357.784969) (xy 125.535045 -357.838953) (xy 125.51968 -357.891283)
			(xy 125.497026 -357.940894) (xy 125.467542 -357.986776) (xy 125.431829 -358.027995) (xy 125.390614 -358.063713)
			(xy 125.344736 -358.093203) (xy 125.295128 -358.115864) (xy 125.2428 -358.131234) (xy 125.188817 -358.139002)
			(xy 125.161548 -358.139492) (xy 124.297948 -358.139492) (xy 124.270677 -358.138972) (xy 124.216689 -358.131216)
			(xy 124.164355 -358.115855) (xy 124.114739 -358.093202) (xy 124.068853 -358.063718) (xy 124.027631 -358.028003)
			(xy 123.991911 -357.986785) (xy 123.962421 -357.940903) (xy 123.939762 -357.89129) (xy 123.924394 -357.838958)
			(xy 123.916632 -357.784971) (xy 122.433928 -357.784971) (xy 122.433928 -357.784974) (xy 122.426165 -357.838966)
			(xy 122.410797 -357.891304) (xy 122.388137 -357.940921) (xy 122.358646 -357.986809) (xy 122.322924 -358.028033)
			(xy 122.2817 -358.063753) (xy 122.235811 -358.093243) (xy 122.186192 -358.115901) (xy 122.133854 -358.131268)
			(xy 122.079862 -358.139029) (xy 122.052588 -358.139492) (xy 121.188988 -358.139492) (xy 121.161721 -358.138945)
			(xy 121.107743 -358.131182) (xy 121.055419 -358.115817) (xy 121.005815 -358.093162) (xy 120.959939 -358.063678)
			(xy 120.918726 -358.027966) (xy 120.883015 -357.986752) (xy 120.853532 -357.940875) (xy 120.830879 -357.891269)
			(xy 120.815515 -357.838945) (xy 120.807754 -357.784967) (xy 119.324906 -357.784967) (xy 119.324906 -357.78497)
			(xy 119.317144 -357.838956) (xy 119.301779 -357.891287) (xy 119.279123 -357.940899) (xy 119.249637 -357.986782)
			(xy 119.213922 -358.028003) (xy 119.172705 -358.063721) (xy 119.126824 -358.09321) (xy 119.077213 -358.115869)
			(xy 119.024883 -358.131238) (xy 118.970898 -358.139004) (xy 118.943628 -358.139492) (xy 118.080028 -358.139492)
			(xy 118.052758 -358.13897) (xy 117.998772 -358.131212) (xy 117.94644 -358.11585) (xy 117.896827 -358.093195)
			(xy 117.850944 -358.063711) (xy 117.809724 -358.027996) (xy 117.774006 -357.986779) (xy 117.744518 -357.940897)
			(xy 117.72186 -357.891286) (xy 117.706494 -357.838955) (xy 117.698731 -357.78497) (xy 116.216028 -357.78497)
			(xy 116.216028 -357.784975) (xy 116.208265 -357.838969) (xy 116.192896 -357.891308) (xy 116.170234 -357.940927)
			(xy 116.140741 -357.986816) (xy 116.105017 -358.02804) (xy 116.06379 -358.06376) (xy 116.017899 -358.093249)
			(xy 115.968278 -358.115907) (xy 115.915937 -358.131272) (xy 115.861943 -358.139031) (xy 115.834668 -358.139492)
			(xy 114.971068 -358.139492) (xy 114.943802 -358.138943) (xy 114.889826 -358.131179) (xy 114.837505 -358.115812)
			(xy 114.787903 -358.093156) (xy 114.742029 -358.063671) (xy 114.700819 -358.027959) (xy 114.66511 -357.986745)
			(xy 114.635629 -357.940869) (xy 114.612977 -357.891265) (xy 114.597614 -357.838942) (xy 114.589854 -357.784966)
			(xy 93.706706 -357.784966) (xy 93.706706 -357.78497) (xy 93.698944 -357.838954) (xy 93.68358 -357.891284)
			(xy 93.660925 -357.940895) (xy 93.631441 -357.986778) (xy 93.595727 -358.027998) (xy 93.554511 -358.063716)
			(xy 93.508632 -358.093205) (xy 93.459023 -358.115865) (xy 93.406695 -358.131235) (xy 93.352712 -358.139003)
			(xy 93.325442 -358.139492) (xy 92.461842 -358.139492) (xy 92.434571 -358.138971) (xy 92.380584 -358.131215)
			(xy 92.32825 -358.115853) (xy 92.278636 -358.0932) (xy 92.23275 -358.063716) (xy 92.191529 -358.028001)
			(xy 92.155809 -357.986783) (xy 92.12632 -357.940901) (xy 92.103661 -357.891289) (xy 92.088294 -357.838957)
			(xy 92.080532 -357.784971) (xy 90.597828 -357.784971) (xy 90.597828 -357.784974) (xy 90.590065 -357.838967)
			(xy 90.574697 -357.891305) (xy 90.552036 -357.940923) (xy 90.522544 -357.986811) (xy 90.486822 -358.028035)
			(xy 90.445597 -358.063755) (xy 90.399707 -358.093245) (xy 90.350088 -358.115903) (xy 90.297749 -358.131269)
			(xy 90.243756 -358.13903) (xy 90.216482 -358.139492) (xy 89.352882 -358.139492) (xy 89.325616 -358.138944)
			(xy 89.271638 -358.131181) (xy 89.219315 -358.115816) (xy 89.169711 -358.09316) (xy 89.123836 -358.063676)
			(xy 89.082624 -358.027964) (xy 89.046913 -357.98675) (xy 89.017431 -357.940873) (xy 88.994778 -357.891268)
			(xy 88.979415 -357.838944) (xy 88.971654 -357.784966) (xy 87.488806 -357.784966) (xy 87.488806 -357.784971)
			(xy 87.481044 -357.838956) (xy 87.465678 -357.891288) (xy 87.443022 -357.940901) (xy 87.413536 -357.986784)
			(xy 87.37782 -358.028005) (xy 87.336602 -358.063723) (xy 87.29072 -358.093211) (xy 87.241109 -358.115871)
			(xy 87.188778 -358.131239) (xy 87.134792 -358.139004) (xy 87.107522 -358.139492) (xy 86.243922 -358.139492)
			(xy 86.216652 -358.13897) (xy 86.162667 -358.131211) (xy 86.110336 -358.115848) (xy 86.060724 -358.093193)
			(xy 86.014841 -358.063709) (xy 85.973622 -358.027994) (xy 85.937905 -357.986777) (xy 85.908417 -357.940895)
			(xy 85.88576 -357.891285) (xy 85.870394 -357.838954) (xy 85.862631 -357.78497) (xy 84.379928 -357.78497)
			(xy 84.379928 -357.784975) (xy 84.372165 -357.838969) (xy 84.356795 -357.891309) (xy 84.334133 -357.940929)
			(xy 84.30464 -357.986818) (xy 84.268915 -358.028042) (xy 84.227687 -358.063762) (xy 84.181795 -358.093251)
			(xy 84.132173 -358.115908) (xy 84.079832 -358.131273) (xy 84.025837 -358.139031) (xy 83.998562 -358.139492)
			(xy 83.134962 -358.139492) (xy 83.107697 -358.138943) (xy 83.053721 -358.131178) (xy 83.0014 -358.11581)
			(xy 82.951799 -358.093154) (xy 82.905926 -358.063669) (xy 82.864717 -358.027957) (xy 82.829008 -357.986743)
			(xy 82.799528 -357.940868) (xy 82.776877 -357.891264) (xy 82.761514 -357.838942) (xy 82.753754 -357.784966)
			(xy 81.270906 -357.784966) (xy 81.270906 -357.784971) (xy 81.263143 -357.838959) (xy 81.247777 -357.891293)
			(xy 81.225119 -357.940907) (xy 81.195631 -357.986791) (xy 81.159913 -358.028012) (xy 81.118693 -358.06373)
			(xy 81.072808 -358.093218) (xy 81.023194 -358.115876) (xy 80.970861 -358.131243) (xy 80.916873 -358.139005)
			(xy 80.889602 -358.139492) (xy 80.026002 -358.139492) (xy 79.998733 -358.138969) (xy 79.94475 -358.131207)
			(xy 79.892421 -358.115843) (xy 79.842812 -358.093187) (xy 79.796932 -358.063702) (xy 79.755714 -358.027987)
			(xy 79.72 -357.98677) (xy 79.690514 -357.94089) (xy 79.667858 -357.89128) (xy 79.652493 -357.838952)
			(xy 79.644731 -357.784969) (xy 78.161906 -357.784969) (xy 78.161906 -357.78497) (xy 78.154144 -357.838954)
			(xy 78.13878 -357.891284) (xy 78.116125 -357.940895) (xy 78.086641 -357.986778) (xy 78.050927 -358.027998)
			(xy 78.009711 -358.063716) (xy 77.963832 -358.093205) (xy 77.914223 -358.115865) (xy 77.861895 -358.131235)
			(xy 77.807912 -358.139003) (xy 77.780642 -358.139492) (xy 76.917042 -358.139492) (xy 76.889771 -358.138971)
			(xy 76.835784 -358.131215) (xy 76.78345 -358.115853) (xy 76.733836 -358.0932) (xy 76.68795 -358.063716)
			(xy 76.646729 -358.028001) (xy 76.611009 -357.986783) (xy 76.58152 -357.940901) (xy 76.558861 -357.891289)
			(xy 76.543494 -357.838957) (xy 76.535732 -357.784971) (xy 75.053028 -357.784971) (xy 75.053028 -357.784974)
			(xy 75.045265 -357.838967) (xy 75.029897 -357.891305) (xy 75.007236 -357.940923) (xy 74.977744 -357.986811)
			(xy 74.942022 -358.028035) (xy 74.900797 -358.063755) (xy 74.854907 -358.093245) (xy 74.805288 -358.115903)
			(xy 74.752949 -358.131269) (xy 74.698956 -358.13903) (xy 74.671682 -358.139492) (xy 73.808082 -358.139492)
			(xy 73.780816 -358.138944) (xy 73.726838 -358.131181) (xy 73.674515 -358.115816) (xy 73.624911 -358.09316)
			(xy 73.579036 -358.063676) (xy 73.537824 -358.027964) (xy 73.502113 -357.98675) (xy 73.472631 -357.940873)
			(xy 73.449978 -357.891268) (xy 73.434615 -357.838944) (xy 73.426854 -357.784966) (xy 71.944006 -357.784966)
			(xy 71.944006 -357.784971) (xy 71.936244 -357.838956) (xy 71.920878 -357.891288) (xy 71.898222 -357.940901)
			(xy 71.868736 -357.986784) (xy 71.83302 -358.028005) (xy 71.791802 -358.063723) (xy 71.74592 -358.093211)
			(xy 71.696309 -358.115871) (xy 71.643978 -358.131239) (xy 71.589992 -358.139004) (xy 71.562722 -358.139492)
			(xy 70.699122 -358.139492) (xy 70.671852 -358.13897) (xy 70.617867 -358.131211) (xy 70.565536 -358.115848)
			(xy 70.515924 -358.093193) (xy 70.470041 -358.063709) (xy 70.428822 -358.027994) (xy 70.393105 -357.986777)
			(xy 70.363617 -357.940895) (xy 70.34096 -357.891285) (xy 70.325594 -357.838954) (xy 70.317831 -357.78497)
			(xy 68.835128 -357.78497) (xy 68.835128 -357.784975) (xy 68.827365 -357.838969) (xy 68.811995 -357.891309)
			(xy 68.789333 -357.940929) (xy 68.75984 -357.986818) (xy 68.724115 -358.028042) (xy 68.682887 -358.063762)
			(xy 68.636995 -358.093251) (xy 68.587373 -358.115908) (xy 68.535032 -358.131273) (xy 68.481037 -358.139031)
			(xy 68.453762 -358.139492) (xy 67.590162 -358.139492) (xy 67.562897 -358.138943) (xy 67.508921 -358.131178)
			(xy 67.4566 -358.11581) (xy 67.406999 -358.093154) (xy 67.361126 -358.063669) (xy 67.319917 -358.027957)
			(xy 67.284208 -357.986743) (xy 67.254728 -357.940868) (xy 67.232077 -357.891264) (xy 67.216714 -357.838942)
			(xy 67.208954 -357.784966) (xy 65.726106 -357.784966) (xy 65.726106 -357.784971) (xy 65.718343 -357.838959)
			(xy 65.702977 -357.891293) (xy 65.680319 -357.940907) (xy 65.650831 -357.986791) (xy 65.615113 -358.028012)
			(xy 65.573893 -358.06373) (xy 65.528008 -358.093218) (xy 65.478394 -358.115876) (xy 65.426061 -358.131243)
			(xy 65.372073 -358.139005) (xy 65.344802 -358.139492) (xy 64.481202 -358.139492) (xy 64.453933 -358.138969)
			(xy 64.39995 -358.131207) (xy 64.347621 -358.115843) (xy 64.298012 -358.093187) (xy 64.252132 -358.063702)
			(xy 64.210914 -358.027987) (xy 64.1752 -357.98677) (xy 64.145714 -357.94089) (xy 64.123058 -357.89128)
			(xy 64.107693 -357.838952) (xy 64.099931 -357.784969) (xy 51.666906 -357.784969) (xy 51.659145 -357.838953)
			(xy 51.64378 -357.891283) (xy 51.621126 -357.940894) (xy 51.591642 -357.986776) (xy 51.555929 -358.027995)
			(xy 51.514714 -358.063713) (xy 51.468836 -358.093203) (xy 51.419228 -358.115864) (xy 51.3669 -358.131234)
			(xy 51.312917 -358.139002) (xy 51.285648 -358.139492) (xy 50.422048 -358.139492) (xy 50.394777 -358.138972)
			(xy 50.340789 -358.131216) (xy 50.288455 -358.115855) (xy 50.238839 -358.093202) (xy 50.192953 -358.063718)
			(xy 50.151731 -358.028003) (xy 50.116011 -357.986785) (xy 50.086521 -357.940903) (xy 50.063862 -357.89129)
			(xy 50.048494 -357.838958) (xy 50.040732 -357.784971) (xy 48.558028 -357.784971) (xy 48.558028 -357.784974)
			(xy 48.550265 -357.838966) (xy 48.534897 -357.891304) (xy 48.512237 -357.940921) (xy 48.482746 -357.986809)
			(xy 48.447024 -358.028033) (xy 48.4058 -358.063753) (xy 48.359911 -358.093243) (xy 48.310292 -358.115901)
			(xy 48.257954 -358.131268) (xy 48.203962 -358.139029) (xy 48.176688 -358.139492) (xy 47.313088 -358.139492)
			(xy 47.285821 -358.138945) (xy 47.231843 -358.131182) (xy 47.179519 -358.115817) (xy 47.129915 -358.093162)
			(xy 47.084039 -358.063678) (xy 47.042826 -358.027966) (xy 47.007115 -357.986752) (xy 46.977632 -357.940875)
			(xy 46.954979 -357.891269) (xy 46.939615 -357.838945) (xy 46.931854 -357.784967) (xy 45.449006 -357.784967)
			(xy 45.449006 -357.78497) (xy 45.441244 -357.838956) (xy 45.425879 -357.891287) (xy 45.403223 -357.940899)
			(xy 45.373737 -357.986782) (xy 45.338022 -358.028003) (xy 45.296805 -358.063721) (xy 45.250924 -358.09321)
			(xy 45.201313 -358.115869) (xy 45.148983 -358.131238) (xy 45.094998 -358.139004) (xy 45.067728 -358.139492)
			(xy 44.204128 -358.139492) (xy 44.176858 -358.13897) (xy 44.122872 -358.131212) (xy 44.07054 -358.11585)
			(xy 44.020927 -358.093195) (xy 43.975044 -358.063711) (xy 43.933824 -358.027996) (xy 43.898106 -357.986779)
			(xy 43.868618 -357.940897) (xy 43.84596 -357.891286) (xy 43.830594 -357.838955) (xy 43.822831 -357.78497)
			(xy 42.340128 -357.78497) (xy 42.340128 -357.784975) (xy 42.332365 -357.838969) (xy 42.316996 -357.891308)
			(xy 42.294334 -357.940927) (xy 42.264841 -357.986816) (xy 42.229117 -358.02804) (xy 42.18789 -358.06376)
			(xy 42.141999 -358.093249) (xy 42.092378 -358.115907) (xy 42.040037 -358.131272) (xy 41.986043 -358.139031)
			(xy 41.958768 -358.139492) (xy 41.095168 -358.139492) (xy 41.067902 -358.138943) (xy 41.013926 -358.131179)
			(xy 40.961605 -358.115812) (xy 40.912003 -358.093156) (xy 40.866129 -358.063671) (xy 40.824919 -358.027959)
			(xy 40.78921 -357.986745) (xy 40.759729 -357.940869) (xy 40.737077 -357.891265) (xy 40.721714 -357.838942)
			(xy 40.713954 -357.784966) (xy 39.231106 -357.784966) (xy 39.231106 -357.784971) (xy 39.223343 -357.838958)
			(xy 39.207977 -357.891291) (xy 39.18532 -357.940905) (xy 39.155832 -357.986789) (xy 39.120115 -358.02801)
			(xy 39.078895 -358.063728) (xy 39.033012 -358.093216) (xy 38.983399 -358.115875) (xy 38.931066 -358.131242)
			(xy 38.877079 -358.139005) (xy 38.849808 -358.139492) (xy 37.986208 -358.139492) (xy 37.958939 -358.138969)
			(xy 37.904955 -358.131209) (xy 37.852626 -358.115844) (xy 37.803015 -358.093189) (xy 37.757134 -358.063704)
			(xy 37.715917 -358.027989) (xy 37.680201 -357.986772) (xy 37.650715 -357.940892) (xy 37.628059 -357.891282)
			(xy 37.612693 -357.838953) (xy 37.604931 -357.784969) (xy 36.122106 -357.784969) (xy 36.114345 -357.838953)
			(xy 36.09898 -357.891283) (xy 36.076326 -357.940894) (xy 36.046842 -357.986776) (xy 36.011129 -358.027995)
			(xy 35.969914 -358.063713) (xy 35.924036 -358.093203) (xy 35.874428 -358.115864) (xy 35.8221 -358.131234)
			(xy 35.768117 -358.139002) (xy 35.740848 -358.139492) (xy 34.877248 -358.139492) (xy 34.849977 -358.138972)
			(xy 34.795989 -358.131216) (xy 34.743655 -358.115855) (xy 34.694039 -358.093202) (xy 34.648153 -358.063718)
			(xy 34.606931 -358.028003) (xy 34.571211 -357.986785) (xy 34.541721 -357.940903) (xy 34.519062 -357.89129)
			(xy 34.503694 -357.838958) (xy 34.495932 -357.784971) (xy 33.013228 -357.784971) (xy 33.013228 -357.784974)
			(xy 33.005465 -357.838966) (xy 32.990097 -357.891304) (xy 32.967437 -357.940921) (xy 32.937946 -357.986809)
			(xy 32.902224 -358.028033) (xy 32.861 -358.063753) (xy 32.815111 -358.093243) (xy 32.765492 -358.115901)
			(xy 32.713154 -358.131268) (xy 32.659162 -358.139029) (xy 32.631888 -358.139492) (xy 31.768288 -358.139492)
			(xy 31.741021 -358.138945) (xy 31.687043 -358.131182) (xy 31.634719 -358.115817) (xy 31.585115 -358.093162)
			(xy 31.539239 -358.063678) (xy 31.498026 -358.027966) (xy 31.462315 -357.986752) (xy 31.432832 -357.940875)
			(xy 31.410179 -357.891269) (xy 31.394815 -357.838945) (xy 31.387054 -357.784967) (xy 29.904206 -357.784967)
			(xy 29.904206 -357.78497) (xy 29.896444 -357.838956) (xy 29.881079 -357.891287) (xy 29.858423 -357.940899)
			(xy 29.828937 -357.986782) (xy 29.793222 -358.028003) (xy 29.752005 -358.063721) (xy 29.706124 -358.09321)
			(xy 29.656513 -358.115869) (xy 29.604183 -358.131238) (xy 29.550198 -358.139004) (xy 29.522928 -358.139492)
			(xy 28.659328 -358.139492) (xy 28.632058 -358.13897) (xy 28.578072 -358.131212) (xy 28.52574 -358.11585)
			(xy 28.476127 -358.093195) (xy 28.430244 -358.063711) (xy 28.389024 -358.027996) (xy 28.353306 -357.986779)
			(xy 28.323818 -357.940897) (xy 28.30116 -357.891286) (xy 28.285794 -357.838955) (xy 28.278031 -357.78497)
			(xy 26.795328 -357.78497) (xy 26.795328 -357.784975) (xy 26.787565 -357.838969) (xy 26.772196 -357.891308)
			(xy 26.749534 -357.940927) (xy 26.720041 -357.986816) (xy 26.684317 -358.02804) (xy 26.64309 -358.06376)
			(xy 26.597199 -358.093249) (xy 26.547578 -358.115907) (xy 26.495237 -358.131272) (xy 26.441243 -358.139031)
			(xy 26.413968 -358.139492) (xy 25.550368 -358.139492) (xy 25.523102 -358.138943) (xy 25.469126 -358.131179)
			(xy 25.416805 -358.115812) (xy 25.367203 -358.093156) (xy 25.321329 -358.063671) (xy 25.280119 -358.027959)
			(xy 25.24441 -357.986745) (xy 25.214929 -357.940869) (xy 25.192277 -357.891265) (xy 25.176914 -357.838942)
			(xy 25.169154 -357.784966) (xy 23.686306 -357.784966) (xy 23.686306 -357.784971) (xy 23.678543 -357.838958)
			(xy 23.663177 -357.891291) (xy 23.64052 -357.940905) (xy 23.611032 -357.986789) (xy 23.575315 -358.02801)
			(xy 23.534095 -358.063728) (xy 23.488212 -358.093216) (xy 23.438599 -358.115875) (xy 23.386266 -358.131242)
			(xy 23.332279 -358.139005) (xy 23.305008 -358.139492) (xy 22.441408 -358.139492) (xy 22.414139 -358.138969)
			(xy 22.360155 -358.131209) (xy 22.307826 -358.115844) (xy 22.258215 -358.093189) (xy 22.212334 -358.063704)
			(xy 22.171117 -358.027989) (xy 22.135401 -357.986772) (xy 22.105915 -357.940892) (xy 22.083259 -357.891282)
			(xy 22.067893 -357.838953) (xy 22.060131 -357.784969) (xy 0.509016 -357.784969) (xy 0.509016 -360.017783)
			(xy 101.774757 -360.017783) (xy 101.774757 -359.957817) (xy 101.782584 -359.898365) (xy 101.798104 -359.840443)
			(xy 101.821052 -359.785042) (xy 101.851035 -359.733111) (xy 101.88754 -359.685538) (xy 101.929942 -359.643136)
			(xy 101.977516 -359.606632) (xy 102.029448 -359.57665) (xy 102.084849 -359.553703) (xy 102.142771 -359.538183)
			(xy 102.202223 -359.530357) (xy 102.232206 -359.529888) (xy 103.095806 -359.529888) (xy 103.125793 -359.530279)
			(xy 103.185255 -359.538108) (xy 103.243186 -359.553631) (xy 103.298595 -359.576583) (xy 103.350534 -359.60657)
			(xy 103.398115 -359.643081) (xy 103.440523 -359.68549) (xy 103.477033 -359.733071) (xy 103.50702 -359.785011)
			(xy 103.529971 -359.84042) (xy 103.545494 -359.898351) (xy 103.553322 -359.957813) (xy 103.553322 -360.017787)
			(xy 103.545494 -360.077249) (xy 103.529971 -360.13518) (xy 103.50702 -360.190589) (xy 103.477033 -360.242529)
			(xy 103.440523 -360.29011) (xy 103.398115 -360.332519) (xy 103.350534 -360.36903) (xy 103.298595 -360.399017)
			(xy 103.243186 -360.421969) (xy 103.185255 -360.437492) (xy 103.125793 -360.445321) (xy 103.095806 -360.445812)
			(xy 102.232206 -360.445812) (xy 102.202223 -360.445243) (xy 102.142771 -360.437417) (xy 102.084849 -360.421897)
			(xy 102.029448 -360.39895) (xy 101.977516 -360.368968) (xy 101.929942 -360.332464) (xy 101.88754 -360.290062)
			(xy 101.851035 -360.242489) (xy 101.821052 -360.190558) (xy 101.798104 -360.135157) (xy 101.782584 -360.077235)
			(xy 101.774757 -360.017783) (xy 0.509016 -360.017783) (xy 0.509016 -363.334808) (xy 54.890416 -363.334808)
			(xy 54.890416 -362.471208) (xy 54.890906 -362.441224) (xy 54.898734 -362.381768) (xy 54.914255 -362.323843)
			(xy 54.937204 -362.268439) (xy 54.967188 -362.216505) (xy 55.003694 -362.168929) (xy 55.046099 -362.126524)
			(xy 55.093675 -362.090018) (xy 55.145609 -362.060034) (xy 55.201013 -362.037085) (xy 55.258938 -362.021564)
			(xy 55.318394 -362.013736) (xy 55.378362 -362.013736) (xy 55.437818 -362.021564) (xy 55.495743 -362.037085)
			(xy 55.551147 -362.060034) (xy 55.603081 -362.090018) (xy 55.650657 -362.126524) (xy 55.693062 -362.168929)
			(xy 55.729568 -362.216505) (xy 55.759552 -362.268439) (xy 55.782501 -362.323843) (xy 55.798022 -362.381768)
			(xy 55.80585 -362.441224) (xy 55.80634 -362.471208) (xy 55.80634 -363.334808) (xy 55.80585 -363.364792)
			(xy 55.798022 -363.424248) (xy 55.782501 -363.482173) (xy 55.759552 -363.537577) (xy 55.729568 -363.589511)
			(xy 55.693062 -363.637087) (xy 55.650657 -363.679492) (xy 55.603081 -363.715998) (xy 55.551147 -363.745982)
			(xy 55.495743 -363.768931) (xy 55.437818 -363.784452) (xy 55.378362 -363.79228) (xy 55.318394 -363.79228)
			(xy 55.258938 -363.784452) (xy 55.201013 -363.768931) (xy 55.145609 -363.745982) (xy 55.093675 -363.715998)
			(xy 55.046099 -363.679492) (xy 55.003694 -363.637087) (xy 54.967188 -363.589511) (xy 54.937204 -363.537577)
			(xy 54.914255 -363.482173) (xy 54.898734 -363.424248) (xy 54.890906 -363.364792) (xy 54.890416 -363.334808)
			(xy 0.509016 -363.334808) (xy 0.509016 -365.797384) (xy 54.438294 -365.797384) (xy 54.438294 -365.737416)
			(xy 54.446121 -365.67796) (xy 54.461641 -365.620034) (xy 54.484589 -365.564629) (xy 54.514571 -365.512694)
			(xy 54.551076 -365.465115) (xy 54.593478 -365.422709) (xy 54.641052 -365.386199) (xy 54.692984 -365.356211)
			(xy 54.748387 -365.333257) (xy 54.806311 -365.317731) (xy 54.865766 -365.309897) (xy 54.89575 -365.309404)
			(xy 55.75935 -365.309404) (xy 55.789336 -365.309938) (xy 55.848794 -365.31776) (xy 55.906723 -365.333276)
			(xy 55.962131 -365.356222) (xy 56.01407 -365.386203) (xy 56.06165 -365.422708) (xy 56.104059 -365.465112)
			(xy 56.140569 -365.512689) (xy 56.170556 -365.564624) (xy 56.193508 -365.620029) (xy 56.20903 -365.677957)
			(xy 56.216859 -365.737414) (xy 56.216859 -365.797386) (xy 56.20903 -365.856843) (xy 56.193508 -365.914771)
			(xy 56.170556 -365.970176) (xy 56.140569 -366.022112) (xy 56.104059 -366.069688) (xy 56.06165 -366.112092)
			(xy 56.01407 -366.148597) (xy 55.962131 -366.178578) (xy 55.906723 -366.201524) (xy 55.848794 -366.21704)
			(xy 55.789336 -366.224862) (xy 55.75935 -366.225328) (xy 54.89575 -366.225328) (xy 54.865766 -366.224903)
			(xy 54.806311 -366.217069) (xy 54.748386 -366.201543) (xy 54.692984 -366.178589) (xy 54.641052 -366.148601)
			(xy 54.593478 -366.112091) (xy 54.551076 -366.069685) (xy 54.514571 -366.022106) (xy 54.484589 -365.970171)
			(xy 54.461641 -365.914766) (xy 54.446121 -365.85684) (xy 54.438294 -365.797384) (xy 0.509016 -365.797384)
			(xy 0.509016 -368.516662) (xy 53.966364 -368.516662) (xy 53.966364 -367.653062) (xy 53.96685 -367.625793)
			(xy 53.974612 -367.571809) (xy 53.989977 -367.519479) (xy 54.012634 -367.469869) (xy 54.04212 -367.423988)
			(xy 54.077835 -367.382771) (xy 54.119052 -367.347056) (xy 54.164933 -367.31757) (xy 54.214543 -367.294913)
			(xy 54.266873 -367.279548) (xy 54.320857 -367.271786) (xy 54.375395 -367.271786) (xy 54.429379 -367.279548)
			(xy 54.481709 -367.294913) (xy 54.531319 -367.31757) (xy 54.5772 -367.347056) (xy 54.618417 -367.382771)
			(xy 54.654132 -367.423988) (xy 54.683618 -367.469869) (xy 54.706275 -367.519479) (xy 54.72164 -367.571809)
			(xy 54.729402 -367.625793) (xy 54.729888 -367.653062) (xy 54.729888 -368.516662) (xy 57.339484 -368.516662)
			(xy 57.339484 -367.653062) (xy 57.33997 -367.625793) (xy 57.347732 -367.571809) (xy 57.363097 -367.519479)
			(xy 57.385754 -367.469869) (xy 57.41524 -367.423988) (xy 57.450955 -367.382771) (xy 57.492172 -367.347056)
			(xy 57.538053 -367.31757) (xy 57.587663 -367.294913) (xy 57.639993 -367.279548) (xy 57.693977 -367.271786)
			(xy 57.748515 -367.271786) (xy 57.802499 -367.279548) (xy 57.854829 -367.294913) (xy 57.904439 -367.31757)
			(xy 57.95032 -367.347056) (xy 57.991537 -367.382771) (xy 58.027252 -367.423988) (xy 58.056738 -367.469869)
			(xy 58.079395 -367.519479) (xy 58.09476 -367.571809) (xy 58.102522 -367.625793) (xy 58.103008 -367.653062)
			(xy 58.103008 -368.516662) (xy 58.102522 -368.543931) (xy 58.09476 -368.597915) (xy 58.079395 -368.650245)
			(xy 58.056738 -368.699855) (xy 58.027252 -368.745736) (xy 57.991537 -368.786953) (xy 57.95032 -368.822668)
			(xy 57.904439 -368.852154) (xy 57.854829 -368.874811) (xy 57.802499 -368.890176) (xy 57.748515 -368.897938)
			(xy 57.693977 -368.897938) (xy 57.639993 -368.890176) (xy 57.587663 -368.874811) (xy 57.538053 -368.852154)
			(xy 57.492172 -368.822668) (xy 57.450955 -368.786953) (xy 57.41524 -368.745736) (xy 57.385754 -368.699855)
			(xy 57.363097 -368.650245) (xy 57.347732 -368.597915) (xy 57.33997 -368.543931) (xy 57.339484 -368.516662)
			(xy 54.729888 -368.516662) (xy 54.729402 -368.543931) (xy 54.72164 -368.597915) (xy 54.706275 -368.650245)
			(xy 54.683618 -368.699855) (xy 54.654132 -368.745736) (xy 54.618417 -368.786953) (xy 54.5772 -368.822668)
			(xy 54.531319 -368.852154) (xy 54.481709 -368.874811) (xy 54.429379 -368.890176) (xy 54.375395 -368.897938)
			(xy 54.320857 -368.897938) (xy 54.266873 -368.890176) (xy 54.214543 -368.874811) (xy 54.164933 -368.852154)
			(xy 54.119052 -368.822668) (xy 54.077835 -368.786953) (xy 54.04212 -368.745736) (xy 54.012634 -368.699855)
			(xy 53.989977 -368.650245) (xy 53.974612 -368.597915) (xy 53.96685 -368.543931) (xy 53.966364 -368.516662)
			(xy 0.509016 -368.516662) (xy 0.509016 -370.523703) (xy 27.348898 -370.523703) (xy 27.348899 -370.456279)
			(xy 27.356975 -370.38934) (xy 27.373012 -370.323851) (xy 27.396776 -370.260753) (xy 27.427927 -370.200957)
			(xy 27.466016 -370.145322) (xy 27.48788 -370.119656) (xy 27.493675 -370.11251) (xy 27.500191 -370.09532)
			(xy 27.50058 -370.086128) (xy 27.50058 -369.928902) (xy 27.501029 -369.918771) (xy 27.508764 -369.900042)
			(xy 27.523062 -369.885684) (xy 27.541759 -369.877872) (xy 27.551888 -369.87734) (xy 28.268168 -369.87734)
			(xy 28.278293 -369.877743) (xy 28.297004 -369.885488) (xy 28.311321 -369.899809) (xy 28.31906 -369.918522)
			(xy 28.319476 -369.928648) (xy 28.319476 -370.086128) (xy 28.319878 -370.095316) (xy 28.326398 -370.1125)
			(xy 28.332176 -370.119656) (xy 28.354029 -370.145331) (xy 28.39212 -370.200963) (xy 28.423272 -370.260758)
			(xy 28.447038 -370.323854) (xy 28.463075 -370.389342) (xy 28.471152 -370.456279) (xy 28.471153 -370.523644)
			(xy 31.749193 -370.523644) (xy 31.749194 -370.456338) (xy 31.75724 -370.389514) (xy 31.773215 -370.324131)
			(xy 31.79689 -370.261126) (xy 31.827927 -370.201402) (xy 31.865879 -370.145816) (xy 31.887668 -370.120164)
			(xy 31.893471 -370.113023) (xy 31.89998 -370.095829) (xy 31.900368 -370.086636) (xy 31.900368 -369.928902)
			(xy 31.900766 -369.918727) (xy 31.908556 -369.899926) (xy 31.92295 -369.88554) (xy 31.941755 -369.877761)
			(xy 31.95193 -369.87734) (xy 32.66821 -369.87734) (xy 32.678369 -369.877825) (xy 32.697138 -369.885603)
			(xy 32.711503 -369.899972) (xy 32.719277 -369.918743) (xy 32.719772 -369.928902) (xy 32.719772 -370.086636)
			(xy 32.720171 -370.095824) (xy 32.726693 -370.113008) (xy 32.732472 -370.120164) (xy 32.754248 -370.145826)
			(xy 32.792196 -370.201411) (xy 32.823229 -370.261134) (xy 32.846902 -370.324137) (xy 32.862876 -370.389518)
			(xy 32.870921 -370.456339) (xy 32.870922 -370.523643) (xy 32.870915 -370.523703) (xy 36.148986 -370.523703)
			(xy 36.148987 -370.456279) (xy 36.157063 -370.389341) (xy 36.173099 -370.323851) (xy 36.196863 -370.260754)
			(xy 36.228013 -370.200957) (xy 36.266101 -370.145322) (xy 36.287964 -370.119656) (xy 36.29377 -370.112518)
			(xy 36.300277 -370.095322) (xy 36.300664 -370.086128) (xy 36.300664 -369.928902) (xy 36.301129 -369.918772)
			(xy 36.308861 -369.900047) (xy 36.323154 -369.88569) (xy 36.341845 -369.877875) (xy 36.351972 -369.87734)
			(xy 37.068252 -369.87734) (xy 37.078408 -369.877762) (xy 37.097167 -369.885549) (xy 37.111494 -369.899947)
			(xy 37.119188 -369.918744) (xy 37.11956 -369.928902) (xy 37.11956 -370.086128) (xy 37.119966 -370.095315)
			(xy 37.126483 -370.112499) (xy 37.13226 -370.119656) (xy 37.154114 -370.14533) (xy 37.192205 -370.200963)
			(xy 37.223359 -370.260757) (xy 37.247125 -370.323853) (xy 37.263163 -370.389341) (xy 37.27124 -370.456279)
			(xy 37.271241 -370.523703) (xy 37.271241 -370.523704) (xy 40.548752 -370.523704) (xy 40.548753 -370.456278)
			(xy 40.556831 -370.389338) (xy 40.572869 -370.323848) (xy 40.596637 -370.26075) (xy 40.627792 -370.200954)
			(xy 40.665885 -370.14532) (xy 40.687752 -370.119656) (xy 40.693556 -370.112516) (xy 40.700065 -370.095321)
			(xy 40.700452 -370.086128) (xy 40.700452 -369.928902) (xy 40.700929 -369.918774) (xy 40.708658 -369.900051)
			(xy 40.722947 -369.885694) (xy 40.741634 -369.877877) (xy 40.75176 -369.87734) (xy 41.46804 -369.87734)
			(xy 41.478202 -369.87769) (xy 41.496963 -369.885506) (xy 41.511286 -369.899925) (xy 41.518977 -369.918738)
			(xy 41.519348 -369.928902) (xy 41.519348 -370.086128) (xy 41.519756 -370.095315) (xy 41.526273 -370.112499)
			(xy 41.532048 -370.119656) (xy 41.553902 -370.14533) (xy 41.591994 -370.200962) (xy 41.623149 -370.260757)
			(xy 41.646916 -370.323852) (xy 41.662954 -370.389341) (xy 41.671031 -370.456279) (xy 41.671032 -370.523644)
			(xy 44.949071 -370.523644) (xy 44.949073 -370.456338) (xy 44.957118 -370.389515) (xy 44.973092 -370.324132)
			(xy 44.996766 -370.261127) (xy 45.027801 -370.201403) (xy 45.065751 -370.145816) (xy 45.08754 -370.120164)
			(xy 45.093339 -370.113021) (xy 45.099851 -370.095829) (xy 45.10024 -370.086636) (xy 45.10024 -369.928902)
			(xy 45.100665 -369.91873) (xy 45.10845 -369.899935) (xy 45.122835 -369.88555) (xy 45.14163 -369.877765)
			(xy 45.151802 -369.87734) (xy 45.868082 -369.87734) (xy 45.878253 -369.877778) (xy 45.897047 -369.885558)
			(xy 45.911433 -369.899939) (xy 45.919218 -369.918731) (xy 45.919644 -369.928902) (xy 45.919644 -370.086636)
			(xy 45.92005 -370.095823) (xy 45.926568 -370.113007) (xy 45.932344 -370.120164) (xy 45.95412 -370.145826)
			(xy 45.992071 -370.20141) (xy 46.023105 -370.261132) (xy 46.046779 -370.324136) (xy 46.062754 -370.389517)
			(xy 46.070799 -370.456339) (xy 46.0708 -370.523643) (xy 46.062757 -370.590465) (xy 46.046785 -370.655847)
			(xy 46.023113 -370.718851) (xy 45.99208 -370.778574) (xy 45.954131 -370.83416) (xy 45.932344 -370.859812)
			(xy 45.926553 -370.866961) (xy 45.920036 -370.884149) (xy 45.919644 -370.89334) (xy 45.919644 -371.386862)
			(xy 45.920085 -371.396046) (xy 45.926578 -371.41323) (xy 45.932344 -371.42039) (xy 45.954146 -371.44603)
			(xy 45.992096 -371.501618) (xy 46.023129 -371.561343) (xy 46.046568 -371.623726) (xy 47.14919 -371.623726)
			(xy 47.149193 -371.556417) (xy 47.157242 -371.489591) (xy 47.17322 -371.424206) (xy 47.1969 -371.3612)
			(xy 47.22794 -371.301475) (xy 47.265897 -371.24589) (xy 47.287688 -371.220238) (xy 47.293492 -371.213098)
			(xy 47.300003 -371.195904) (xy 47.300388 -371.18671) (xy 47.300388 -371.028722) (xy 47.300783 -371.018546)
			(xy 47.30857 -370.999742) (xy 47.322966 -370.985355) (xy 47.341773 -370.977578) (xy 47.35195 -370.97716)
			(xy 48.06823 -370.97716) (xy 48.078392 -370.977609) (xy 48.097167 -370.985398) (xy 48.111532 -370.999777)
			(xy 48.119301 -371.018559) (xy 48.119792 -371.028722) (xy 48.119792 -371.18671) (xy 48.120199 -371.195898)
			(xy 48.126715 -371.213082) (xy 48.132492 -371.220238) (xy 48.154241 -371.245921) (xy 48.192189 -371.301504)
			(xy 48.196948 -371.310662) (xy 53.966364 -371.310662) (xy 53.966364 -370.447062) (xy 53.96685 -370.419793)
			(xy 53.974612 -370.365809) (xy 53.989977 -370.313479) (xy 54.012634 -370.263869) (xy 54.04212 -370.217988)
			(xy 54.077835 -370.176771) (xy 54.119052 -370.141056) (xy 54.164933 -370.11157) (xy 54.214543 -370.088913)
			(xy 54.266873 -370.073548) (xy 54.320857 -370.065786) (xy 54.375395 -370.065786) (xy 54.429379 -370.073548)
			(xy 54.481709 -370.088913) (xy 54.531319 -370.11157) (xy 54.5772 -370.141056) (xy 54.618417 -370.176771)
			(xy 54.654132 -370.217988) (xy 54.683618 -370.263869) (xy 54.706275 -370.313479) (xy 54.72164 -370.365809)
			(xy 54.729402 -370.419793) (xy 54.729888 -370.447062) (xy 54.729888 -371.310662) (xy 57.339484 -371.310662)
			(xy 57.339484 -370.447062) (xy 57.33997 -370.419793) (xy 57.347732 -370.365809) (xy 57.363097 -370.313479)
			(xy 57.385754 -370.263869) (xy 57.41524 -370.217988) (xy 57.450955 -370.176771) (xy 57.492172 -370.141056)
			(xy 57.538053 -370.11157) (xy 57.587663 -370.088913) (xy 57.639993 -370.073548) (xy 57.693977 -370.065786)
			(xy 57.748515 -370.065786) (xy 57.802499 -370.073548) (xy 57.854829 -370.088913) (xy 57.904439 -370.11157)
			(xy 57.95032 -370.141056) (xy 57.991537 -370.176771) (xy 58.027252 -370.217988) (xy 58.056738 -370.263869)
			(xy 58.079395 -370.313479) (xy 58.09476 -370.365809) (xy 58.102522 -370.419793) (xy 58.103008 -370.447062)
			(xy 58.103008 -370.523703) (xy 71.348807 -370.523703) (xy 71.348808 -370.456279) (xy 71.356885 -370.38934)
			(xy 71.372921 -370.32385) (xy 71.396686 -370.260753) (xy 71.427838 -370.200956) (xy 71.465928 -370.145321)
			(xy 71.487792 -370.119656) (xy 71.493589 -370.112511) (xy 71.500104 -370.09532) (xy 71.500492 -370.086128)
			(xy 71.500492 -369.928902) (xy 71.501027 -369.918781) (xy 71.508745 -369.900069) (xy 71.523016 -369.885715)
			(xy 71.541682 -369.877887) (xy 71.5518 -369.87734) (xy 72.26808 -369.87734) (xy 72.278238 -369.877739)
			(xy 72.296998 -369.885535) (xy 72.311323 -369.89994) (xy 72.319016 -369.918742) (xy 72.319388 -369.928902)
			(xy 72.319388 -370.086128) (xy 72.319787 -370.095316) (xy 72.326309 -370.1125) (xy 72.332088 -370.119656)
			(xy 72.353941 -370.145331) (xy 72.39203 -370.200964) (xy 72.423182 -370.260758) (xy 72.446948 -370.323854)
			(xy 72.462984 -370.389342) (xy 72.471061 -370.45628) (xy 72.471063 -370.523644) (xy 75.749102 -370.523644)
			(xy 75.749103 -370.456338) (xy 75.757149 -370.389513) (xy 75.773125 -370.32413) (xy 75.796801 -370.261125)
			(xy 75.827837 -370.201401) (xy 75.86579 -370.145816) (xy 75.88758 -370.120164) (xy 75.893372 -370.113015)
			(xy 75.89989 -370.095828) (xy 75.90028 -370.086636) (xy 75.90028 -369.928902) (xy 75.900666 -369.918725)
			(xy 75.908459 -369.899923) (xy 75.922856 -369.885536) (xy 75.941665 -369.877759) (xy 75.951842 -369.87734)
			(xy 76.668122 -369.87734) (xy 76.678281 -369.877815) (xy 76.697052 -369.885597) (xy 76.711416 -369.899969)
			(xy 76.71919 -369.918742) (xy 76.719684 -369.928902) (xy 76.719684 -370.086636) (xy 76.72008 -370.095825)
			(xy 76.726604 -370.113009) (xy 76.732384 -370.120164) (xy 76.754159 -370.145826) (xy 76.792107 -370.201412)
			(xy 76.82314 -370.261134) (xy 76.846812 -370.324137) (xy 76.862785 -370.389518) (xy 76.87083 -370.456339)
			(xy 76.870831 -370.523643) (xy 76.870824 -370.523703) (xy 80.148895 -370.523703) (xy 80.148896 -370.456279)
			(xy 80.156972 -370.38934) (xy 80.173008 -370.323851) (xy 80.196773 -370.260754) (xy 80.227924 -370.200957)
			(xy 80.266012 -370.145322) (xy 80.287876 -370.119656) (xy 80.293671 -370.112509) (xy 80.300187 -370.09532)
			(xy 80.300576 -370.086128) (xy 80.300576 -369.928902) (xy 80.301029 -369.918771) (xy 80.308763 -369.900043)
			(xy 80.32306 -369.885685) (xy 80.341755 -369.877873) (xy 80.351884 -369.87734) (xy 81.068164 -369.87734)
			(xy 81.078289 -369.877747) (xy 81.096999 -369.88549) (xy 81.111316 -369.899811) (xy 81.119056 -369.918523)
			(xy 81.119472 -369.928648) (xy 81.119472 -370.086128) (xy 81.119875 -370.095316) (xy 81.126394 -370.1125)
			(xy 81.132172 -370.119656) (xy 81.154025 -370.14533) (xy 81.192116 -370.200963) (xy 81.223269 -370.260758)
			(xy 81.247035 -370.323853) (xy 81.263072 -370.389342) (xy 81.271149 -370.456279) (xy 81.27115 -370.523703)
			(xy 84.548686 -370.523703) (xy 84.548687 -370.456279) (xy 84.556763 -370.389341) (xy 84.572799 -370.323851)
			(xy 84.596563 -370.260754) (xy 84.627713 -370.200957) (xy 84.665801 -370.145322) (xy 84.687664 -370.119656)
			(xy 84.69347 -370.112518) (xy 84.699977 -370.095322) (xy 84.700364 -370.086128) (xy 84.700364 -369.928902)
			(xy 84.700829 -369.918772) (xy 84.708561 -369.900047) (xy 84.722854 -369.88569) (xy 84.741545 -369.877875)
			(xy 84.751672 -369.87734) (xy 85.467952 -369.87734) (xy 85.478076 -369.877756) (xy 85.496787 -369.885496)
			(xy 85.511104 -369.899813) (xy 85.518844 -369.918524) (xy 85.51926 -369.928648) (xy 85.51926 -370.086128)
			(xy 85.519666 -370.095315) (xy 85.526183 -370.112499) (xy 85.53196 -370.119656) (xy 85.553814 -370.14533)
			(xy 85.591905 -370.200963) (xy 85.623059 -370.260757) (xy 85.646825 -370.323853) (xy 85.662863 -370.389341)
			(xy 85.67094 -370.456279) (xy 85.670941 -370.523644) (xy 115.349244 -370.523644) (xy 115.349245 -370.456338)
			(xy 115.35729 -370.389516) (xy 115.373263 -370.324133) (xy 115.396936 -370.261128) (xy 115.427969 -370.201404)
			(xy 115.465917 -370.145817) (xy 115.487704 -370.120164) (xy 115.493499 -370.113018) (xy 115.500014 -370.095828)
			(xy 115.500404 -370.086636) (xy 115.500404 -369.928902) (xy 115.500934 -369.918749) (xy 115.508702 -369.899986)
			(xy 115.523056 -369.885622) (xy 115.541813 -369.877841) (xy 115.551966 -369.87734) (xy 116.268246 -369.87734)
			(xy 116.278407 -369.877796) (xy 116.297177 -369.885586) (xy 116.311541 -369.899963) (xy 116.319314 -369.918741)
			(xy 116.319808 -369.928902) (xy 116.319808 -370.086636) (xy 116.320199 -370.095825) (xy 116.326726 -370.11301)
			(xy 116.332508 -370.120164) (xy 116.354286 -370.145825) (xy 116.392238 -370.201409) (xy 116.423275 -370.261131)
			(xy 116.446951 -370.324134) (xy 116.462926 -370.389516) (xy 116.470972 -370.456338) (xy 116.470973 -370.523644)
			(xy 116.470966 -370.523703) (xy 119.749013 -370.523703) (xy 119.749014 -370.456279) (xy 119.757091 -370.38934)
			(xy 119.773128 -370.32385) (xy 119.796893 -370.260752) (xy 119.828045 -370.200956) (xy 119.866135 -370.145321)
			(xy 119.888 -370.119656) (xy 119.893798 -370.112512) (xy 119.900312 -370.09532) (xy 119.9007 -370.086128)
			(xy 119.9007 -369.928902) (xy 119.901227 -369.91878) (xy 119.908947 -369.900067) (xy 119.92322 -369.885712)
			(xy 119.941889 -369.877886) (xy 119.952008 -369.87734) (xy 120.668288 -369.87734) (xy 120.678446 -369.877732)
			(xy 120.697206 -369.885531) (xy 120.711531 -369.899938) (xy 120.719224 -369.918741) (xy 120.719596 -369.928902)
			(xy 120.719596 -370.086128) (xy 120.719993 -370.095317) (xy 120.726516 -370.112501) (xy 120.732296 -370.119656)
			(xy 120.754148 -370.145331) (xy 120.792238 -370.200964) (xy 120.823389 -370.260759) (xy 120.847154 -370.323854)
			(xy 120.863191 -370.389342) (xy 120.871267 -370.45628) (xy 120.871269 -370.523644) (xy 124.149308 -370.523644)
			(xy 124.149309 -370.456338) (xy 124.157355 -370.389513) (xy 124.173331 -370.32413) (xy 124.197007 -370.261125)
			(xy 124.228045 -370.201401) (xy 124.265998 -370.145816) (xy 124.287788 -370.120164) (xy 124.293581 -370.113016)
			(xy 124.300098 -370.095828) (xy 124.300488 -370.086636) (xy 124.300488 -369.928902) (xy 124.300867 -369.918724)
			(xy 124.30866 -369.89992) (xy 124.32306 -369.885533) (xy 124.341872 -369.877757) (xy 124.35205 -369.87734)
			(xy 125.06833 -369.87734) (xy 125.07849 -369.877809) (xy 125.09726 -369.885593) (xy 125.111625 -369.899967)
			(xy 125.119398 -369.918742) (xy 125.119892 -369.928902) (xy 125.119892 -370.086636) (xy 125.120286 -370.095825)
			(xy 125.126811 -370.113009) (xy 125.132592 -370.120164) (xy 125.154367 -370.145826) (xy 125.192314 -370.201412)
			(xy 125.223346 -370.261134) (xy 125.247018 -370.324138) (xy 125.262991 -370.389518) (xy 125.271036 -370.456339)
			(xy 125.271037 -370.523643) (xy 125.271037 -370.523644) (xy 128.549099 -370.523644) (xy 128.5491 -370.456338)
			(xy 128.557146 -370.389514) (xy 128.573121 -370.32413) (xy 128.596797 -370.261125) (xy 128.627834 -370.201402)
			(xy 128.665787 -370.145816) (xy 128.687576 -370.120164) (xy 128.693368 -370.113015) (xy 128.699886 -370.095828)
			(xy 128.700276 -370.086636) (xy 128.700276 -369.928902) (xy 128.700666 -369.918726) (xy 128.708458 -369.899924)
			(xy 128.722854 -369.885538) (xy 128.741661 -369.877759) (xy 128.751838 -369.87734) (xy 129.468118 -369.87734)
			(xy 129.478277 -369.877818) (xy 129.497047 -369.885599) (xy 129.511412 -369.89997) (xy 129.519185 -369.918743)
			(xy 129.51968 -369.928902) (xy 129.51968 -370.086636) (xy 129.520077 -370.095824) (xy 129.5266 -370.113008)
			(xy 129.53238 -370.120164) (xy 129.554155 -370.145826) (xy 129.592103 -370.201412) (xy 129.623136 -370.261134)
			(xy 129.646809 -370.324137) (xy 129.662782 -370.389518) (xy 129.670827 -370.456339) (xy 129.670828 -370.523643)
			(xy 129.670828 -370.523644) (xy 159.349153 -370.523644) (xy 159.349154 -370.456338) (xy 159.357199 -370.389515)
			(xy 159.373173 -370.324133) (xy 159.396846 -370.261128) (xy 159.427879 -370.201404) (xy 159.465828 -370.145816)
			(xy 159.487616 -370.120164) (xy 159.493412 -370.113019) (xy 159.499927 -370.095828) (xy 159.500316 -370.086636)
			(xy 159.500316 -369.928902) (xy 159.500835 -369.918747) (xy 159.508604 -369.899982) (xy 159.522962 -369.885618)
			(xy 159.541723 -369.877839) (xy 159.551878 -369.87734) (xy 160.268158 -369.87734) (xy 160.278327 -369.877798)
			(xy 160.297121 -369.88557) (xy 160.311508 -369.899945) (xy 160.319294 -369.918733) (xy 160.31972 -369.928902)
			(xy 160.31972 -370.086636) (xy 160.320109 -370.095826) (xy 160.326637 -370.11301) (xy 160.33242 -370.120164)
			(xy 160.354197 -370.145825) (xy 160.392149 -370.20141) (xy 160.423185 -370.261131) (xy 160.44686 -370.324135)
			(xy 160.462835 -370.389516) (xy 160.470881 -370.456339) (xy 160.470882 -370.523643) (xy 160.470875 -370.523703)
			(xy 163.748922 -370.523703) (xy 163.748923 -370.456279) (xy 163.757 -370.389339) (xy 163.773037 -370.323849)
			(xy 163.796803 -370.260752) (xy 163.827956 -370.200955) (xy 163.866047 -370.145321) (xy 163.887912 -370.119656)
			(xy 163.893711 -370.112513) (xy 163.900224 -370.095321) (xy 163.900612 -370.086128) (xy 163.900612 -369.928902)
			(xy 163.901127 -369.918779) (xy 163.908849 -369.900063) (xy 163.923126 -369.885708) (xy 163.9418 -369.877884)
			(xy 163.95192 -369.87734) (xy 164.6682 -369.87734) (xy 164.678359 -369.877722) (xy 164.697119 -369.885526)
			(xy 164.711444 -369.899935) (xy 164.719136 -369.918741) (xy 164.719508 -369.928902) (xy 164.719508 -370.086128)
			(xy 164.719903 -370.095317) (xy 164.726427 -370.112501) (xy 164.732208 -370.119656) (xy 164.75406 -370.145331)
			(xy 164.792148 -370.200964) (xy 164.823299 -370.260759) (xy 164.847064 -370.323855) (xy 164.8631 -370.389343)
			(xy 164.871176 -370.45628) (xy 164.871178 -370.523644) (xy 168.149241 -370.523644) (xy 168.149242 -370.456338)
			(xy 168.157287 -370.389516) (xy 168.17326 -370.324133) (xy 168.196933 -370.261128) (xy 168.227965 -370.201404)
			(xy 168.265913 -370.145817) (xy 168.2877 -370.120164) (xy 168.293494 -370.113017) (xy 168.30001 -370.095828)
			(xy 168.3004 -370.086636) (xy 168.3004 -369.928902) (xy 168.300934 -369.918749) (xy 168.308701 -369.899987)
			(xy 168.323054 -369.885623) (xy 168.341809 -369.877842) (xy 168.351962 -369.87734) (xy 169.068242 -369.87734)
			(xy 169.078403 -369.877799) (xy 169.097173 -369.885588) (xy 169.111537 -369.899964) (xy 169.11931 -369.918741)
			(xy 169.119804 -369.928902) (xy 169.119804 -370.086636) (xy 169.120196 -370.095825) (xy 169.126722 -370.113009)
			(xy 169.132504 -370.120164) (xy 169.154279 -370.145826) (xy 169.192225 -370.201412) (xy 169.223256 -370.261135)
			(xy 169.246928 -370.324138) (xy 169.2629 -370.389519) (xy 169.270945 -370.456339) (xy 169.270946 -370.523643)
			(xy 169.270946 -370.523644) (xy 172.549008 -370.523644) (xy 172.549009 -370.456338) (xy 172.557055 -370.389513)
			(xy 172.573031 -370.32413) (xy 172.596707 -370.261125) (xy 172.627745 -370.201401) (xy 172.665698 -370.145816)
			(xy 172.687488 -370.120164) (xy 172.693281 -370.113016) (xy 172.699798 -370.095828) (xy 172.700188 -370.086636)
			(xy 172.700188 -369.928902) (xy 172.700567 -369.918724) (xy 172.70836 -369.89992) (xy 172.72276 -369.885533)
			(xy 172.741572 -369.877757) (xy 172.75175 -369.87734) (xy 173.46803 -369.87734) (xy 173.47819 -369.877809)
			(xy 173.49696 -369.885593) (xy 173.511325 -369.899967) (xy 173.519098 -369.918742) (xy 173.519592 -369.928902)
			(xy 173.519592 -370.086636) (xy 173.519986 -370.095825) (xy 173.526511 -370.113009) (xy 173.532292 -370.120164)
			(xy 173.554067 -370.145826) (xy 173.592014 -370.201412) (xy 173.623046 -370.261134) (xy 173.646718 -370.324138)
			(xy 173.662691 -370.389518) (xy 173.670736 -370.456339) (xy 173.670737 -370.523643) (xy 173.662694 -370.590464)
			(xy 173.646724 -370.655845) (xy 173.623054 -370.718849) (xy 173.592023 -370.778573) (xy 173.554078 -370.834159)
			(xy 173.532292 -370.859812) (xy 173.526507 -370.866965) (xy 173.519986 -370.88415) (xy 173.519592 -370.89334)
			(xy 173.519592 -371.386862) (xy 173.520022 -371.396047) (xy 173.526522 -371.413231) (xy 173.532292 -371.42039)
			(xy 173.554093 -371.446031) (xy 173.592039 -371.50162) (xy 173.62307 -371.561345) (xy 173.646506 -371.623725)
			(xy 174.74915 -371.623725) (xy 174.749154 -371.556417) (xy 174.757201 -371.489592) (xy 174.773178 -371.424208)
			(xy 174.796855 -371.361202) (xy 174.827893 -371.301477) (xy 174.865846 -371.24589) (xy 174.887636 -371.220238)
			(xy 174.893446 -371.213102) (xy 174.899952 -371.195904) (xy 174.900336 -371.18671) (xy 174.900336 -371.028722)
			(xy 174.900782 -371.018552) (xy 174.908559 -370.999758) (xy 174.922938 -370.985373) (xy 174.941728 -370.977587)
			(xy 174.951898 -370.97716) (xy 175.668178 -370.97716) (xy 175.678351 -370.977583) (xy 175.697149 -370.985364)
			(xy 175.711536 -370.999751) (xy 175.719317 -371.018549) (xy 175.71974 -371.028722) (xy 175.71974 -371.18671)
			(xy 175.720159 -371.195896) (xy 175.726668 -371.21308) (xy 175.73244 -371.220238) (xy 175.754191 -371.245921)
			(xy 175.792142 -371.301502) (xy 175.823178 -371.361221) (xy 175.846854 -371.424222) (xy 175.86283 -371.489601)
			(xy 175.870878 -371.55642) (xy 175.870881 -371.623723) (xy 175.862841 -371.690543) (xy 175.846871 -371.755923)
			(xy 175.823202 -371.818926) (xy 175.792172 -371.878649) (xy 175.754226 -371.934234) (xy 175.73244 -371.959886)
			(xy 175.726617 -371.967012) (xy 175.72012 -371.984218) (xy 175.71974 -371.993414) (xy 175.71974 -372.486682)
			(xy 175.720172 -372.495867) (xy 175.726672 -372.51305) (xy 175.73244 -372.52021) (xy 175.754262 -372.545834)
			(xy 175.792211 -372.601424) (xy 175.823244 -372.661151) (xy 175.846916 -372.72416) (xy 175.862887 -372.789545)
			(xy 175.870929 -372.856371) (xy 175.870926 -372.92368) (xy 175.862878 -372.990505) (xy 175.846901 -373.055889)
			(xy 175.823223 -373.118895) (xy 175.792185 -373.17862) (xy 175.754231 -373.234206) (xy 175.73244 -373.259858)
			(xy 175.726629 -373.266993) (xy 175.720125 -373.284191) (xy 175.71974 -373.293386) (xy 175.71974 -373.451374)
			(xy 175.719314 -373.461547) (xy 175.711534 -373.480345) (xy 175.697148 -373.494731) (xy 175.678351 -373.502513)
			(xy 175.668178 -373.502936) (xy 174.951898 -373.502936) (xy 174.941723 -373.502537) (xy 174.922923 -373.494747)
			(xy 174.908538 -373.480353) (xy 174.900757 -373.461549) (xy 174.900336 -373.451374) (xy 174.900336 -373.293386)
			(xy 174.899925 -373.284199) (xy 174.893411 -373.267015) (xy 174.887636 -373.259858) (xy 174.865882 -373.234178)
			(xy 174.827932 -373.178596) (xy 174.796898 -373.118876) (xy 174.773223 -373.055875) (xy 174.757248 -372.990496)
			(xy 174.749201 -372.923677) (xy 174.749198 -372.856374) (xy 174.757239 -372.789554) (xy 174.773208 -372.724174)
			(xy 174.796877 -372.661171) (xy 174.827906 -372.601448) (xy 174.865851 -372.545862) (xy 174.887636 -372.52021)
			(xy 174.893458 -372.513083) (xy 174.899957 -372.495878) (xy 174.900336 -372.486682) (xy 174.900336 -371.993414)
			(xy 174.899911 -371.984229) (xy 174.893407 -371.967044) (xy 174.887636 -371.959886) (xy 174.865811 -371.934265)
			(xy 174.827863 -371.878674) (xy 174.796832 -371.818946) (xy 174.773161 -371.755937) (xy 174.757191 -371.690551)
			(xy 174.74915 -371.623725) (xy 173.646506 -371.623725) (xy 173.646741 -371.624351) (xy 173.662712 -371.689734)
			(xy 173.670754 -371.756558) (xy 173.670753 -371.823863) (xy 173.662708 -371.890686) (xy 173.646734 -371.956069)
			(xy 173.623061 -372.019074) (xy 173.592028 -372.078798) (xy 173.55408 -372.134385) (xy 173.532292 -372.160038)
			(xy 173.526496 -372.167183) (xy 173.519981 -372.184374) (xy 173.519592 -372.193566) (xy 173.519592 -372.351554)
			(xy 173.519099 -372.361719) (xy 173.511335 -372.380507) (xy 173.496971 -372.394892) (xy 173.478194 -372.402684)
			(xy 173.46803 -372.403116) (xy 172.75175 -372.403116) (xy 172.741576 -372.402694) (xy 172.722773 -372.394917)
			(xy 172.708385 -372.38053) (xy 172.700607 -372.361728) (xy 172.700188 -372.351554) (xy 172.700188 -372.193566)
			(xy 172.699797 -372.184377) (xy 172.69327 -372.167192) (xy 172.687488 -372.160038) (xy 172.665713 -372.134375)
			(xy 172.62776 -372.078791) (xy 172.596724 -372.01907) (xy 172.573048 -371.956067) (xy 172.557072 -371.890685)
			(xy 172.549026 -371.823863) (xy 172.549025 -371.756558) (xy 172.557069 -371.689736) (xy 172.573042 -371.624354)
			(xy 172.596715 -371.561349) (xy 172.627749 -371.501627) (xy 172.6657 -371.446041) (xy 172.687488 -371.42039)
			(xy 172.69327 -371.413234) (xy 172.699794 -371.396052) (xy 172.700188 -371.386862) (xy 172.700188 -370.89334)
			(xy 172.699761 -370.884154) (xy 172.69326 -370.86697) (xy 172.687488 -370.859812) (xy 172.665687 -370.83417)
			(xy 172.627735 -370.778583) (xy 172.5967 -370.718859) (xy 172.573026 -370.655853) (xy 172.557052 -370.590469)
			(xy 172.549008 -370.523644) (xy 169.270946 -370.523644) (xy 169.262904 -370.590464) (xy 169.246933 -370.655845)
			(xy 169.223264 -370.718849) (xy 169.192234 -370.778572) (xy 169.15429 -370.834159) (xy 169.132504 -370.859812)
			(xy 169.12672 -370.866966) (xy 169.120198 -370.88415) (xy 169.119804 -370.89334) (xy 169.119804 -371.386862)
			(xy 169.120231 -371.396047) (xy 169.126733 -371.413232) (xy 169.132504 -371.42039) (xy 169.154304 -371.446031)
			(xy 169.19225 -371.50162) (xy 169.22328 -371.561346) (xy 169.246737 -371.623785) (xy 170.348831 -371.623785)
			(xy 170.348834 -371.556358) (xy 170.356914 -371.489416) (xy 170.372955 -371.423924) (xy 170.396726 -371.360825)
			(xy 170.427884 -371.301029) (xy 170.46598 -371.245394) (xy 170.487848 -371.21973) (xy 170.493663 -371.212598)
			(xy 170.500165 -371.195397) (xy 170.500548 -371.186202) (xy 170.500548 -371.028722) (xy 170.501045 -371.018596)
			(xy 170.508767 -370.999873) (xy 170.52305 -370.985516) (xy 170.541732 -370.977698) (xy 170.551856 -370.97716)
			(xy 171.268136 -370.97716) (xy 171.278287 -370.977591) (xy 171.297033 -370.985391) (xy 171.311354 -370.999784)
			(xy 171.319059 -371.018568) (xy 171.319444 -371.028722) (xy 171.319444 -371.186202) (xy 171.319866 -371.195388)
			(xy 171.326373 -371.212571) (xy 171.332144 -371.21973) (xy 171.353973 -371.245425) (xy 171.392066 -371.301054)
			(xy 171.423222 -371.360846) (xy 171.44699 -371.423939) (xy 171.46303 -371.489425) (xy 171.47111 -371.556361)
			(xy 171.471113 -371.623782) (xy 171.46304 -371.690719) (xy 171.447007 -371.756207) (xy 171.423245 -371.819302)
			(xy 171.392096 -371.879097) (xy 171.354008 -371.93473) (xy 171.332144 -371.960394) (xy 171.326361 -371.967548)
			(xy 171.31984 -371.984732) (xy 171.319444 -371.993922) (xy 171.319444 -372.486174) (xy 171.319879 -372.495358)
			(xy 171.326377 -372.512542) (xy 171.332144 -372.519702) (xy 171.354043 -372.545339) (xy 171.392135 -372.600976)
			(xy 171.423287 -372.660776) (xy 171.447052 -372.723876) (xy 171.463087 -372.789369) (xy 171.471161 -372.856312)
			(xy 171.471158 -372.923739) (xy 171.463077 -372.990681) (xy 171.447037 -373.056172) (xy 171.423266 -373.119271)
			(xy 171.392108 -373.179068) (xy 171.354012 -373.234702) (xy 171.332144 -373.260366) (xy 171.32633 -373.267499)
			(xy 171.319827 -373.284699) (xy 171.319444 -373.293894) (xy 171.319444 -373.451374) (xy 171.318952 -373.461501)
			(xy 171.31123 -373.480225) (xy 171.296945 -373.494583) (xy 171.27826 -373.5024) (xy 171.268136 -373.502936)
			(xy 170.551856 -373.502936) (xy 170.541704 -373.502515) (xy 170.522957 -373.494712) (xy 170.508637 -373.480316)
			(xy 170.500932 -373.461529) (xy 170.500548 -373.451374) (xy 170.500548 -373.293894) (xy 170.50013 -373.284708)
			(xy 170.493621 -373.267524) (xy 170.487848 -373.260366) (xy 170.466016 -373.234674) (xy 170.427923 -373.179044)
			(xy 170.396768 -373.119252) (xy 170.373 -373.056159) (xy 170.356961 -372.990673) (xy 170.348881 -372.923736)
			(xy 170.348878 -372.856315) (xy 170.356951 -372.789378) (xy 170.372985 -372.72389) (xy 170.396747 -372.660794)
			(xy 170.427897 -372.600999) (xy 170.465984 -372.545366) (xy 170.487848 -372.519702) (xy 170.493632 -372.512548)
			(xy 170.500153 -372.495364) (xy 170.500548 -372.486174) (xy 170.500548 -371.993922) (xy 170.500117 -371.984737)
			(xy 170.493617 -371.967553) (xy 170.487848 -371.960394) (xy 170.465945 -371.93476) (xy 170.427854 -371.879122)
			(xy 170.396703 -371.819322) (xy 170.372938 -371.756221) (xy 170.356904 -371.690728) (xy 170.348831 -371.623785)
			(xy 169.246737 -371.623785) (xy 169.24695 -371.624352) (xy 169.262921 -371.689735) (xy 169.270963 -371.756558)
			(xy 169.270962 -371.823863) (xy 169.262917 -371.890686) (xy 169.246944 -371.956068) (xy 169.223271 -372.019073)
			(xy 169.192239 -372.078798) (xy 169.154291 -372.134385) (xy 169.132504 -372.160038) (xy 169.126709 -372.167185)
			(xy 169.120193 -372.184374) (xy 169.119804 -372.193566) (xy 169.119804 -372.351554) (xy 169.1193 -372.361717)
			(xy 169.111537 -372.380503) (xy 169.097177 -372.394888) (xy 169.078405 -372.402682) (xy 169.068242 -372.403116)
			(xy 168.351962 -372.403116) (xy 168.341782 -372.402766) (xy 168.322978 -372.39496) (xy 168.308593 -372.380552)
			(xy 168.300817 -372.361734) (xy 168.3004 -372.351554) (xy 168.3004 -372.193566) (xy 168.300006 -372.184377)
			(xy 168.293481 -372.167193) (xy 168.2877 -372.160038) (xy 168.265927 -372.134374) (xy 168.227981 -372.078788)
			(xy 168.196949 -372.019066) (xy 168.173277 -371.956063) (xy 168.157304 -371.890683) (xy 168.14926 -371.823862)
			(xy 168.149258 -371.756559) (xy 168.1573 -371.689738) (xy 168.173271 -371.624357) (xy 168.19694 -371.561353)
			(xy 168.22797 -371.50163) (xy 168.265914 -371.446043) (xy 168.2877 -371.42039) (xy 168.293483 -371.413235)
			(xy 168.300006 -371.396052) (xy 168.3004 -371.386862) (xy 168.3004 -370.89334) (xy 168.299971 -370.884155)
			(xy 168.29347 -370.86697) (xy 168.2877 -370.859812) (xy 168.265902 -370.834169) (xy 168.227956 -370.77858)
			(xy 168.196925 -370.718855) (xy 168.173255 -370.65585) (xy 168.157284 -370.590467) (xy 168.149241 -370.523644)
			(xy 164.871178 -370.523644) (xy 164.871178 -370.523702) (xy 164.863103 -370.59064) (xy 164.847069 -370.656128)
			(xy 164.823307 -370.719224) (xy 164.792158 -370.77902) (xy 164.754071 -370.834655) (xy 164.732208 -370.86032)
			(xy 164.726421 -370.867472) (xy 164.7199 -370.884657) (xy 164.719508 -370.893848) (xy 164.719508 -371.386354)
			(xy 164.719938 -371.395539) (xy 164.726438 -371.412724) (xy 164.732208 -371.419882) (xy 164.754085 -371.445536)
			(xy 164.792173 -371.501172) (xy 164.823323 -371.56097) (xy 164.846957 -371.623726) (xy 165.949062 -371.623726)
			(xy 165.949066 -371.556417) (xy 165.957114 -371.489592) (xy 165.973091 -371.424207) (xy 165.996769 -371.361201)
			(xy 166.027807 -371.301477) (xy 166.065761 -371.24589) (xy 166.087552 -371.220238) (xy 166.093364 -371.213104)
			(xy 166.099868 -371.195905) (xy 166.100252 -371.18671) (xy 166.100252 -371.028722) (xy 166.100682 -371.01855)
			(xy 166.108463 -370.999753) (xy 166.122847 -370.985367) (xy 166.141642 -370.977584) (xy 166.151814 -370.97716)
			(xy 166.868094 -370.97716) (xy 166.878268 -370.977569) (xy 166.897067 -370.985356) (xy 166.911453 -370.999747)
			(xy 166.919234 -371.018548) (xy 166.919656 -371.028722) (xy 166.919656 -371.18671) (xy 166.920071 -371.195896)
			(xy 166.926582 -371.21308) (xy 166.932356 -371.220238) (xy 166.954106 -371.245921) (xy 166.992057 -371.301503)
			(xy 167.023092 -371.361222) (xy 167.046767 -371.424223) (xy 167.062743 -371.489601) (xy 167.07079 -371.55642)
			(xy 167.070793 -371.623722) (xy 167.062753 -371.690543) (xy 167.046784 -371.755923) (xy 167.023115 -371.818926)
			(xy 166.992086 -371.878648) (xy 166.954141 -371.934234) (xy 166.932356 -371.959886) (xy 166.926535 -371.967014)
			(xy 166.920036 -371.984218) (xy 166.919656 -371.993414) (xy 166.919656 -372.486682) (xy 166.920085 -372.495867)
			(xy 166.926586 -372.513051) (xy 166.932356 -372.52021) (xy 166.954177 -372.545834) (xy 166.992126 -372.601425)
			(xy 167.023158 -372.661152) (xy 167.046829 -372.72416) (xy 167.0628 -372.789546) (xy 167.070841 -372.856372)
			(xy 167.070838 -372.923679) (xy 167.06279 -372.990504) (xy 167.046814 -373.055889) (xy 167.023137 -373.118895)
			(xy 166.992099 -373.178619) (xy 166.954146 -373.234206) (xy 166.932356 -373.259858) (xy 166.926547 -373.266994)
			(xy 166.920041 -373.284192) (xy 166.919656 -373.293386) (xy 166.919656 -373.451374) (xy 166.919215 -373.461545)
			(xy 166.911437 -373.48034) (xy 166.897057 -373.494726) (xy 166.878264 -373.502511) (xy 166.868094 -373.502936)
			(xy 166.151814 -373.502936) (xy 166.14164 -373.502524) (xy 166.122841 -373.494739) (xy 166.108454 -373.480349)
			(xy 166.100673 -373.461548) (xy 166.100252 -373.451374) (xy 166.100252 -373.293386) (xy 166.099837 -373.2842)
			(xy 166.093325 -373.267016) (xy 166.087552 -373.259858) (xy 166.065797 -373.234178) (xy 166.027847 -373.178596)
			(xy 165.996811 -373.118877) (xy 165.973136 -373.055876) (xy 165.95716 -372.990497) (xy 165.949113 -372.923677)
			(xy 165.94911 -372.856374) (xy 165.957151 -372.789554) (xy 165.973121 -372.724173) (xy 165.99679 -372.66117)
			(xy 166.02782 -372.601448) (xy 166.065766 -372.545862) (xy 166.087552 -372.52021) (xy 166.093376 -372.513084)
			(xy 166.099873 -372.495879) (xy 166.100252 -372.486682) (xy 166.100252 -371.993414) (xy 166.099824 -371.984229)
			(xy 166.093321 -371.967045) (xy 166.087552 -371.959886) (xy 166.065726 -371.934265) (xy 166.027778 -371.878674)
			(xy 165.996745 -371.818947) (xy 165.973074 -371.755938) (xy 165.957104 -371.690552) (xy 165.949062 -371.623726)
			(xy 164.846957 -371.623726) (xy 164.847086 -371.624068) (xy 164.86312 -371.689559) (xy 164.871195 -371.756498)
			(xy 164.871194 -371.823923) (xy 164.863116 -371.890862) (xy 164.84708 -371.956352) (xy 164.823314 -372.019449)
			(xy 164.792162 -372.079246) (xy 164.754073 -372.134881) (xy 164.732208 -372.160546) (xy 164.72641 -372.16769)
			(xy 164.719896 -372.184881) (xy 164.719508 -372.194074) (xy 164.719508 -372.351554) (xy 164.718937 -372.361672)
			(xy 164.711233 -372.380383) (xy 164.696973 -372.394739) (xy 164.678314 -372.402568) (xy 164.6682 -372.403116)
			(xy 163.95192 -372.403116) (xy 163.941769 -372.402662) (xy 163.92302 -372.394876) (xy 163.908697 -372.38049)
			(xy 163.900993 -372.361707) (xy 163.900612 -372.351554) (xy 163.900612 -372.194074) (xy 163.900212 -372.184886)
			(xy 163.893691 -372.167702) (xy 163.887912 -372.160546) (xy 163.866061 -372.13487) (xy 163.827971 -372.079237)
			(xy 163.796819 -372.019442) (xy 163.773054 -371.956347) (xy 163.757017 -371.890859) (xy 163.74894 -371.823922)
			(xy 163.748939 -371.756499) (xy 163.757013 -371.689562) (xy 163.773048 -371.624073) (xy 163.796811 -371.560977)
			(xy 163.827961 -371.501181) (xy 163.866048 -371.445547) (xy 163.887912 -371.419882) (xy 163.8937 -371.412731)
			(xy 163.900219 -371.395545) (xy 163.900612 -371.386354) (xy 163.900612 -370.893848) (xy 163.900176 -370.884664)
			(xy 163.89368 -370.867479) (xy 163.887912 -370.86032) (xy 163.866036 -370.834665) (xy 163.827947 -370.779029)
			(xy 163.796796 -370.719232) (xy 163.773032 -370.656133) (xy 163.756997 -370.590643) (xy 163.748922 -370.523703)
			(xy 160.470875 -370.523703) (xy 160.462839 -370.590466) (xy 160.446866 -370.655848) (xy 160.423192 -370.718852)
			(xy 160.392158 -370.778575) (xy 160.354208 -370.83416) (xy 160.33242 -370.859812) (xy 160.326638 -370.866968)
			(xy 160.320114 -370.88415) (xy 160.31972 -370.89334) (xy 160.31972 -371.386862) (xy 160.320144 -371.396048)
			(xy 160.326647 -371.413233) (xy 160.33242 -371.42039) (xy 160.354223 -371.44603) (xy 160.392174 -371.501618)
			(xy 160.423209 -371.561342) (xy 160.44667 -371.623784) (xy 161.548767 -371.623784) (xy 161.548771 -371.556358)
			(xy 161.55685 -371.489418) (xy 161.572888 -371.423928) (xy 161.596655 -371.360829) (xy 161.627808 -371.301032)
			(xy 161.665899 -371.245396) (xy 161.687764 -371.21973) (xy 161.693581 -371.212599) (xy 161.700082 -371.195397)
			(xy 161.700464 -371.186202) (xy 161.700464 -371.028722) (xy 161.700945 -371.018594) (xy 161.70867 -370.999868)
			(xy 161.722959 -370.985511) (xy 161.741646 -370.977695) (xy 161.751772 -370.97716) (xy 162.468052 -370.97716)
			(xy 162.478166 -370.977654) (xy 162.496861 -370.985379) (xy 162.511176 -370.999671) (xy 162.51893 -371.018354)
			(xy 162.51936 -371.028468) (xy 162.51936 -371.186202) (xy 162.519778 -371.195388) (xy 162.526287 -371.212572)
			(xy 162.53206 -371.21973) (xy 162.553888 -371.245425) (xy 162.591981 -371.301055) (xy 162.623135 -371.360846)
			(xy 162.646903 -371.423939) (xy 162.662942 -371.489425) (xy 162.671022 -371.556361) (xy 162.671025 -371.623782)
			(xy 162.662953 -371.690719) (xy 162.64692 -371.756206) (xy 162.623158 -371.819302) (xy 162.59201 -371.879096)
			(xy 162.553923 -371.934729) (xy 162.53206 -371.960394) (xy 162.526278 -371.96755) (xy 162.519756 -371.984732)
			(xy 162.51936 -371.993922) (xy 162.51936 -372.486174) (xy 162.519791 -372.495359) (xy 162.526291 -372.512543)
			(xy 162.53206 -372.519702) (xy 162.553959 -372.545339) (xy 162.592049 -372.600977) (xy 162.623201 -372.660776)
			(xy 162.646965 -372.723877) (xy 162.662999 -372.78937) (xy 162.671073 -372.856312) (xy 162.67107 -372.923739)
			(xy 162.66299 -372.99068) (xy 162.646949 -373.056172) (xy 162.62318 -373.11927) (xy 162.592023 -373.179067)
			(xy 162.553927 -373.234701) (xy 162.53206 -373.260366) (xy 162.526248 -373.2675) (xy 162.519743 -373.284699)
			(xy 162.51936 -373.293894) (xy 162.51936 -373.451374) (xy 162.518852 -373.461499) (xy 162.511133 -373.48022)
			(xy 162.496853 -373.494577) (xy 162.478174 -373.502397) (xy 162.468052 -373.502936) (xy 161.751772 -373.502936)
			(xy 161.741666 -373.502439) (xy 161.722994 -373.494699) (xy 161.708701 -373.480406) (xy 161.700961 -373.461734)
			(xy 161.700464 -373.451628) (xy 161.700464 -373.293894) (xy 161.700042 -373.284708) (xy 161.693535 -373.267525)
			(xy 161.687764 -373.260366) (xy 161.665935 -373.234673) (xy 161.627847 -373.179041) (xy 161.596697 -373.119249)
			(xy 161.572933 -373.056155) (xy 161.556896 -372.99067) (xy 161.548818 -372.923736) (xy 161.548815 -372.856315)
			(xy 161.556887 -372.78938) (xy 161.572918 -372.723893) (xy 161.596676 -372.660798) (xy 161.627821 -372.601003)
			(xy 161.665903 -372.545368) (xy 161.687764 -372.519702) (xy 161.69355 -372.51255) (xy 161.700069 -372.495364)
			(xy 161.700464 -372.486174) (xy 161.700464 -371.993922) (xy 161.700029 -371.984738) (xy 161.693531 -371.967554)
			(xy 161.687764 -371.960394) (xy 161.665864 -371.934759) (xy 161.627779 -371.879119) (xy 161.596632 -371.819319)
			(xy 161.572871 -371.756218) (xy 161.55684 -371.690725) (xy 161.548767 -371.623784) (xy 160.44667 -371.623784)
			(xy 160.446882 -371.624348) (xy 160.462856 -371.689733) (xy 160.470899 -371.756557) (xy 160.470898 -371.823864)
			(xy 160.462852 -371.890688) (xy 160.446876 -371.956072) (xy 160.4232 -372.019077) (xy 160.392163 -372.078801)
			(xy 160.35421 -372.134386) (xy 160.33242 -372.160038) (xy 160.326627 -372.167186) (xy 160.32011 -372.184374)
			(xy 160.31972 -372.193566) (xy 160.31972 -372.351554) (xy 160.319297 -372.361728) (xy 160.31152 -372.38053)
			(xy 160.297133 -372.394918) (xy 160.278332 -372.402697) (xy 160.268158 -372.403116) (xy 159.551878 -372.403116)
			(xy 159.541699 -372.402753) (xy 159.522895 -372.394952) (xy 159.50851 -372.380547) (xy 159.500734 -372.361733)
			(xy 159.500316 -372.351554) (xy 159.500316 -372.193566) (xy 159.499919 -372.184378) (xy 159.493396 -372.167193)
			(xy 159.487616 -372.160038) (xy 159.465843 -372.134374) (xy 159.427895 -372.078789) (xy 159.396862 -372.019067)
			(xy 159.37319 -371.956064) (xy 159.357216 -371.890683) (xy 159.349172 -371.823862) (xy 159.34917 -371.756559)
			(xy 159.357213 -371.689738) (xy 159.373184 -371.624356) (xy 159.396854 -371.561353) (xy 159.427884 -371.501629)
			(xy 159.46583 -371.446042) (xy 159.487616 -371.42039) (xy 159.493401 -371.413237) (xy 159.499922 -371.396052)
			(xy 159.500316 -371.386862) (xy 159.500316 -370.89334) (xy 159.499883 -370.884155) (xy 159.493385 -370.866971)
			(xy 159.487616 -370.859812) (xy 159.465817 -370.834169) (xy 159.42787 -370.778581) (xy 159.396839 -370.718856)
			(xy 159.373168 -370.65585) (xy 159.357196 -370.590467) (xy 159.349153 -370.523644) (xy 129.670828 -370.523644)
			(xy 129.662785 -370.590464) (xy 129.646814 -370.655846) (xy 129.623143 -370.71885) (xy 129.592113 -370.778573)
			(xy 129.554166 -370.83416) (xy 129.53238 -370.859812) (xy 129.526594 -370.866964) (xy 129.520073 -370.884149)
			(xy 129.51968 -370.89334) (xy 129.51968 -371.386862) (xy 129.520113 -371.396047) (xy 129.526611 -371.413231)
			(xy 129.53238 -371.42039) (xy 129.554181 -371.446031) (xy 129.592128 -371.50162) (xy 129.62316 -371.561345)
			(xy 129.646596 -371.623725) (xy 130.749241 -371.623725) (xy 130.749245 -371.556418) (xy 130.757292 -371.489593)
			(xy 130.773269 -371.424208) (xy 130.796945 -371.361202) (xy 130.827982 -371.301478) (xy 130.865934 -371.24589)
			(xy 130.887724 -371.220238) (xy 130.893532 -371.213101) (xy 130.900039 -371.195904) (xy 130.900424 -371.18671)
			(xy 130.900424 -371.028722) (xy 130.900882 -371.018554) (xy 130.908657 -370.999762) (xy 130.923032 -370.985377)
			(xy 130.941818 -370.977589) (xy 130.951986 -370.97716) (xy 131.668266 -370.97716) (xy 131.678438 -370.977592)
			(xy 131.697236 -370.98537) (xy 131.711623 -370.999754) (xy 131.719405 -371.01855) (xy 131.719828 -371.028722)
			(xy 131.719828 -371.18671) (xy 131.720227 -371.195898) (xy 131.726748 -371.213083) (xy 131.732528 -371.220238)
			(xy 131.754279 -371.24592) (xy 131.792231 -371.301502) (xy 131.823268 -371.361221) (xy 131.846945 -371.424221)
			(xy 131.862921 -371.4896) (xy 131.870969 -371.55642) (xy 131.870972 -371.623723) (xy 131.862931 -371.690543)
			(xy 131.846961 -371.755924) (xy 131.823291 -371.818927) (xy 131.792261 -371.878649) (xy 131.754314 -371.934234)
			(xy 131.732528 -371.959886) (xy 131.726704 -371.967011) (xy 131.720208 -371.984217) (xy 131.719828 -371.993414)
			(xy 131.719828 -372.486682) (xy 131.72024 -372.495869) (xy 131.726752 -372.513054) (xy 131.732528 -372.52021)
			(xy 131.75435 -372.545834) (xy 131.7923 -372.601424) (xy 131.823334 -372.661151) (xy 131.847006 -372.724159)
			(xy 131.862978 -372.789545) (xy 131.87102 -372.856371) (xy 131.871017 -372.92368) (xy 131.862969 -372.990505)
			(xy 131.846991 -373.05589) (xy 131.823313 -373.118896) (xy 131.792274 -373.17862) (xy 131.754319 -373.234206)
			(xy 131.732528 -373.259858) (xy 131.726716 -373.266992) (xy 131.720212 -373.284191) (xy 131.719828 -373.293386)
			(xy 131.719828 -373.451374) (xy 131.719414 -373.461548) (xy 131.711631 -373.480349) (xy 131.697242 -373.494736)
			(xy 131.67844 -373.502515) (xy 131.668266 -373.502936) (xy 130.951986 -373.502936) (xy 130.94181 -373.502547)
			(xy 130.92301 -373.494752) (xy 130.908625 -373.480356) (xy 130.900845 -373.46155) (xy 130.900424 -373.451374)
			(xy 130.900424 -373.293386) (xy 130.900015 -373.284199) (xy 130.8935 -373.267015) (xy 130.887724 -373.259858)
			(xy 130.86597 -373.234178) (xy 130.828022 -373.178595) (xy 130.796988 -373.118875) (xy 130.773314 -373.055874)
			(xy 130.757339 -372.990496) (xy 130.749292 -372.923677) (xy 130.749289 -372.856375) (xy 130.75733 -372.789555)
			(xy 130.773299 -372.724174) (xy 130.796967 -372.661171) (xy 130.827995 -372.601449) (xy 130.865939 -372.545863)
			(xy 130.887724 -372.52021) (xy 130.893544 -372.513082) (xy 130.900044 -372.495878) (xy 130.900424 -372.486682)
			(xy 130.900424 -371.993414) (xy 130.900002 -371.984228) (xy 130.893496 -371.967044) (xy 130.887724 -371.959886)
			(xy 130.865899 -371.934264) (xy 130.827953 -371.878673) (xy 130.796922 -371.818945) (xy 130.773252 -371.755937)
			(xy 130.757282 -371.690551) (xy 130.749241 -371.623725) (xy 129.646596 -371.623725) (xy 129.646831 -371.624351)
			(xy 129.662802 -371.689734) (xy 129.670845 -371.756558) (xy 129.670844 -371.823863) (xy 129.662799 -371.890687)
			(xy 129.646825 -371.956069) (xy 129.623151 -372.019074) (xy 129.592117 -372.078799) (xy 129.554168 -372.134386)
			(xy 129.53238 -372.160038) (xy 129.526582 -372.167182) (xy 129.520069 -372.184374) (xy 129.51968 -372.193566)
			(xy 129.51968 -372.351554) (xy 129.519199 -372.36172) (xy 129.511432 -372.380511) (xy 129.497064 -372.394896)
			(xy 129.478284 -372.402686) (xy 129.468118 -372.403116) (xy 128.751838 -372.403116) (xy 128.741663 -372.402704)
			(xy 128.722861 -372.394923) (xy 128.708473 -372.380533) (xy 128.700695 -372.361729) (xy 128.700276 -372.351554)
			(xy 128.700276 -372.193566) (xy 128.699887 -372.184376) (xy 128.693359 -372.167192) (xy 128.687576 -372.160038)
			(xy 128.665801 -372.134375) (xy 128.627849 -372.078791) (xy 128.596813 -372.019069) (xy 128.573138 -371.956066)
			(xy 128.557163 -371.890685) (xy 128.549117 -371.823863) (xy 128.549116 -371.756558) (xy 128.557159 -371.689736)
			(xy 128.573132 -371.624354) (xy 128.596805 -371.56135) (xy 128.627838 -371.501627) (xy 128.665788 -371.446042)
			(xy 128.687576 -371.42039) (xy 128.693357 -371.413233) (xy 128.699882 -371.396052) (xy 128.700276 -371.386862)
			(xy 128.700276 -370.89334) (xy 128.699852 -370.884154) (xy 128.693349 -370.866969) (xy 128.687576 -370.859812)
			(xy 128.665775 -370.83417) (xy 128.627825 -370.778583) (xy 128.59679 -370.718858) (xy 128.573116 -370.655852)
			(xy 128.557143 -370.590469) (xy 128.549099 -370.523644) (xy 125.271037 -370.523644) (xy 125.262994 -370.590464)
			(xy 125.247024 -370.655845) (xy 125.223354 -370.718849) (xy 125.192323 -370.778573) (xy 125.154378 -370.834159)
			(xy 125.132592 -370.859812) (xy 125.126807 -370.866965) (xy 125.120286 -370.88415) (xy 125.119892 -370.89334)
			(xy 125.119892 -371.386862) (xy 125.120322 -371.396047) (xy 125.126822 -371.413231) (xy 125.132592 -371.42039)
			(xy 125.154393 -371.446031) (xy 125.192339 -371.50162) (xy 125.22337 -371.561345) (xy 125.246828 -371.623785)
			(xy 126.348921 -371.623785) (xy 126.348925 -371.556358) (xy 126.357005 -371.489416) (xy 126.373046 -371.423925)
			(xy 126.396816 -371.360826) (xy 126.427973 -371.301029) (xy 126.466069 -371.245395) (xy 126.487936 -371.21973)
			(xy 126.493749 -371.212597) (xy 126.500253 -371.195397) (xy 126.500636 -371.186202) (xy 126.500636 -371.028722)
			(xy 126.501144 -371.018597) (xy 126.508864 -370.999877) (xy 126.523144 -370.98552) (xy 126.541822 -370.9777)
			(xy 126.551944 -370.97716) (xy 127.268224 -370.97716) (xy 127.278375 -370.977601) (xy 127.29712 -370.985397)
			(xy 127.311441 -370.999787) (xy 127.319147 -371.018569) (xy 127.319532 -371.028722) (xy 127.319532 -371.186202)
			(xy 127.319956 -371.195387) (xy 127.326462 -371.212571) (xy 127.332232 -371.21973) (xy 127.354058 -371.245427)
			(xy 127.392145 -371.301057) (xy 127.423296 -371.36085) (xy 127.447061 -371.423942) (xy 127.463098 -371.489427)
			(xy 127.471176 -371.556361) (xy 127.47118 -371.623781) (xy 127.463108 -371.690717) (xy 127.447078 -371.756203)
			(xy 127.423319 -371.819298) (xy 127.392175 -371.879094) (xy 127.354093 -371.934728) (xy 127.332232 -371.960394)
			(xy 127.326447 -371.967547) (xy 127.319927 -371.984732) (xy 127.319532 -371.993922) (xy 127.319532 -372.486174)
			(xy 127.31997 -372.495358) (xy 127.326466 -372.512542) (xy 127.332232 -372.519702) (xy 127.354128 -372.54534)
			(xy 127.392214 -372.600979) (xy 127.423361 -372.66078) (xy 127.447122 -372.72388) (xy 127.463154 -372.789372)
			(xy 127.471227 -372.856313) (xy 127.471224 -372.923738) (xy 127.463145 -372.990678) (xy 127.447107 -373.056169)
			(xy 127.42334 -373.119267) (xy 127.392188 -373.179064) (xy 127.354097 -373.2347) (xy 127.332232 -373.260366)
			(xy 127.326417 -373.267498) (xy 127.319915 -373.284699) (xy 127.319532 -373.293894) (xy 127.319532 -373.451374)
			(xy 127.319051 -373.461503) (xy 127.311327 -373.480228) (xy 127.297038 -373.494587) (xy 127.27835 -373.502402)
			(xy 127.268224 -373.502936) (xy 126.551944 -373.502936) (xy 126.541797 -373.502443) (xy 126.523053 -373.494669)
			(xy 126.508729 -373.480294) (xy 126.501021 -373.461522) (xy 126.500636 -373.451374) (xy 126.500636 -373.293894)
			(xy 126.500221 -373.284708) (xy 126.49371 -373.267524) (xy 126.487936 -373.260366) (xy 126.466104 -373.234674)
			(xy 126.428012 -373.179044) (xy 126.396858 -373.119252) (xy 126.37309 -373.056158) (xy 126.357051 -372.990672)
			(xy 126.348972 -372.923736) (xy 126.348969 -372.856315) (xy 126.357042 -372.789378) (xy 126.373075 -372.72389)
			(xy 126.396837 -372.660795) (xy 126.427986 -372.601) (xy 126.466073 -372.545367) (xy 126.487936 -372.519702)
			(xy 126.493719 -372.512547) (xy 126.500241 -372.495364) (xy 126.500636 -372.486174) (xy 126.500636 -371.993922)
			(xy 126.500207 -371.984737) (xy 126.493706 -371.967553) (xy 126.487936 -371.960394) (xy 126.466033 -371.93476)
			(xy 126.427943 -371.879122) (xy 126.396792 -371.819322) (xy 126.373029 -371.756221) (xy 126.356995 -371.690727)
			(xy 126.348921 -371.623785) (xy 125.246828 -371.623785) (xy 125.247041 -371.624351) (xy 125.263012 -371.689734)
			(xy 125.271054 -371.756558) (xy 125.271053 -371.823863) (xy 125.263008 -371.890686) (xy 125.247034 -371.956069)
			(xy 125.223361 -372.019074) (xy 125.192328 -372.078798) (xy 125.15438 -372.134385) (xy 125.132592 -372.160038)
			(xy 125.126796 -372.167183) (xy 125.120281 -372.184374) (xy 125.119892 -372.193566) (xy 125.119892 -372.351554)
			(xy 125.119399 -372.361719) (xy 125.111635 -372.380507) (xy 125.097271 -372.394892) (xy 125.078494 -372.402684)
			(xy 125.06833 -372.403116) (xy 124.35205 -372.403116) (xy 124.341876 -372.402694) (xy 124.323073 -372.394917)
			(xy 124.308685 -372.38053) (xy 124.300907 -372.361728) (xy 124.300488 -372.351554) (xy 124.300488 -372.193566)
			(xy 124.300097 -372.184377) (xy 124.29357 -372.167192) (xy 124.287788 -372.160038) (xy 124.266013 -372.134375)
			(xy 124.22806 -372.078791) (xy 124.197024 -372.01907) (xy 124.173348 -371.956067) (xy 124.157372 -371.890685)
			(xy 124.149326 -371.823863) (xy 124.149325 -371.756558) (xy 124.157369 -371.689736) (xy 124.173342 -371.624354)
			(xy 124.197015 -371.561349) (xy 124.228049 -371.501627) (xy 124.266 -371.446041) (xy 124.287788 -371.42039)
			(xy 124.29357 -371.413234) (xy 124.300094 -371.396052) (xy 124.300488 -371.386862) (xy 124.300488 -370.89334)
			(xy 124.300061 -370.884154) (xy 124.29356 -370.86697) (xy 124.287788 -370.859812) (xy 124.265987 -370.83417)
			(xy 124.228035 -370.778583) (xy 124.197 -370.718859) (xy 124.173326 -370.655853) (xy 124.157352 -370.590469)
			(xy 124.149308 -370.523644) (xy 120.871269 -370.523644) (xy 120.871269 -370.523702) (xy 120.863194 -370.59064)
			(xy 120.847159 -370.656128) (xy 120.823396 -370.719225) (xy 120.792247 -370.779021) (xy 120.754159 -370.834655)
			(xy 120.732296 -370.86032) (xy 120.726508 -370.867471) (xy 120.719988 -370.884657) (xy 120.719596 -370.893848)
			(xy 120.719596 -371.386354) (xy 120.720029 -371.395539) (xy 120.726527 -371.412723) (xy 120.732296 -371.419882)
			(xy 120.754174 -371.445536) (xy 120.792262 -371.501172) (xy 120.823413 -371.56097) (xy 120.847047 -371.623725)
			(xy 121.949153 -371.623725) (xy 121.949157 -371.556417) (xy 121.957205 -371.489592) (xy 121.973182 -371.424208)
			(xy 121.996859 -371.361202) (xy 122.027896 -371.301477) (xy 122.06585 -371.24589) (xy 122.08764 -371.220238)
			(xy 122.09345 -371.213103) (xy 122.099956 -371.195904) (xy 122.10034 -371.18671) (xy 122.10034 -371.028722)
			(xy 122.100782 -371.018552) (xy 122.10856 -370.999757) (xy 122.12294 -370.985371) (xy 122.141732 -370.977586)
			(xy 122.151902 -370.97716) (xy 122.868182 -370.97716) (xy 122.878355 -370.977579) (xy 122.897154 -370.985362)
			(xy 122.91154 -370.99975) (xy 122.919322 -371.018549) (xy 122.919744 -371.028722) (xy 122.919744 -371.18671)
			(xy 122.920162 -371.195896) (xy 122.926672 -371.21308) (xy 122.932444 -371.220238) (xy 122.954195 -371.245921)
			(xy 122.992146 -371.301502) (xy 123.023182 -371.361222) (xy 123.046857 -371.424222) (xy 123.062833 -371.489601)
			(xy 123.070881 -371.55642) (xy 123.070884 -371.623723) (xy 123.062844 -371.690543) (xy 123.046874 -371.755923)
			(xy 123.023205 -371.818926) (xy 122.992175 -371.878648) (xy 122.95423 -371.934234) (xy 122.932444 -371.959886)
			(xy 122.926622 -371.967013) (xy 122.920124 -371.984218) (xy 122.919744 -371.993414) (xy 122.919744 -372.486682)
			(xy 122.920175 -372.495867) (xy 122.926676 -372.513051) (xy 122.932444 -372.52021) (xy 122.954266 -372.545834)
			(xy 122.992215 -372.601424) (xy 123.023248 -372.661152) (xy 123.046919 -372.72416) (xy 123.06289 -372.789546)
			(xy 123.070932 -372.856372) (xy 123.070929 -372.92368) (xy 123.062881 -372.990505) (xy 123.046904 -373.055889)
			(xy 123.023227 -373.118895) (xy 122.992188 -373.17862) (xy 122.954234 -373.234206) (xy 122.932444 -373.259858)
			(xy 122.926633 -373.266993) (xy 122.920129 -373.284192) (xy 122.919744 -373.293386) (xy 122.919744 -373.451374)
			(xy 122.919314 -373.461546) (xy 122.911534 -373.480344) (xy 122.89715 -373.49473) (xy 122.878354 -373.502513)
			(xy 122.868182 -373.502936) (xy 122.151902 -373.502936) (xy 122.141727 -373.502534) (xy 122.122928 -373.494745)
			(xy 122.108542 -373.480352) (xy 122.100761 -373.461549) (xy 122.10034 -373.451374) (xy 122.10034 -373.293386)
			(xy 122.099928 -373.284199) (xy 122.093415 -373.267015) (xy 122.08764 -373.259858) (xy 122.065886 -373.234178)
			(xy 122.027936 -373.178596) (xy 121.996901 -373.118876) (xy 121.973226 -373.055875) (xy 121.957251 -372.990496)
			(xy 121.949204 -372.923677) (xy 121.949201 -372.856374) (xy 121.957242 -372.789554) (xy 121.973211 -372.724174)
			(xy 121.99688 -372.661171) (xy 122.02791 -372.601448) (xy 122.065855 -372.545862) (xy 122.08764 -372.52021)
			(xy 122.093462 -372.513083) (xy 122.099961 -372.495878) (xy 122.10034 -372.486682) (xy 122.10034 -371.993414)
			(xy 122.099914 -371.984229) (xy 122.093411 -371.967045) (xy 122.08764 -371.959886) (xy 122.065815 -371.934265)
			(xy 122.027867 -371.878674) (xy 121.996835 -371.818946) (xy 121.973165 -371.755937) (xy 121.957194 -371.690551)
			(xy 121.949153 -371.623725) (xy 120.847047 -371.623725) (xy 120.847176 -371.624068) (xy 120.863211 -371.689558)
			(xy 120.871286 -371.756498) (xy 120.871284 -371.823923) (xy 120.863207 -371.890862) (xy 120.84717 -371.956352)
			(xy 120.823404 -372.01945) (xy 120.792252 -372.079246) (xy 120.754161 -372.134881) (xy 120.732296 -372.160546)
			(xy 120.726497 -372.167689) (xy 120.719984 -372.184881) (xy 120.719596 -372.194074) (xy 120.719596 -372.351554)
			(xy 120.719037 -372.361673) (xy 120.711331 -372.380387) (xy 120.697067 -372.394743) (xy 120.678404 -372.40257)
			(xy 120.668288 -372.403116) (xy 119.952008 -372.403116) (xy 119.941856 -372.402672) (xy 119.923107 -372.394882)
			(xy 119.908784 -372.380493) (xy 119.901081 -372.361707) (xy 119.9007 -372.351554) (xy 119.9007 -372.194074)
			(xy 119.900303 -372.184885) (xy 119.89378 -372.167701) (xy 119.888 -372.160546) (xy 119.86615 -372.134869)
			(xy 119.828061 -372.079237) (xy 119.796909 -372.019442) (xy 119.773144 -371.956346) (xy 119.757108 -371.890859)
			(xy 119.749031 -371.823922) (xy 119.74903 -371.756499) (xy 119.757104 -371.689562) (xy 119.773138 -371.624074)
			(xy 119.796901 -371.560977) (xy 119.82805 -371.501182) (xy 119.866137 -371.445547) (xy 119.888 -371.419882)
			(xy 119.893787 -371.41273) (xy 119.900307 -371.395545) (xy 119.9007 -371.386354) (xy 119.9007 -370.893848)
			(xy 119.900267 -370.884663) (xy 119.893769 -370.867479) (xy 119.888 -370.86032) (xy 119.866124 -370.834664)
			(xy 119.828036 -370.779029) (xy 119.796886 -370.719231) (xy 119.773122 -370.656133) (xy 119.757088 -370.590643)
			(xy 119.749013 -370.523703) (xy 116.470966 -370.523703) (xy 116.462929 -370.590466) (xy 116.446956 -370.655848)
			(xy 116.423282 -370.718853) (xy 116.392247 -370.778575) (xy 116.354297 -370.834161) (xy 116.332508 -370.859812)
			(xy 116.326725 -370.866967) (xy 116.320202 -370.88415) (xy 116.319808 -370.89334) (xy 116.319808 -371.386862)
			(xy 116.320235 -371.396047) (xy 116.326737 -371.413232) (xy 116.332508 -371.42039) (xy 116.354311 -371.44603)
			(xy 116.392263 -371.501617) (xy 116.423299 -371.561342) (xy 116.446761 -371.623785) (xy 117.548834 -371.623785)
			(xy 117.548837 -371.556358) (xy 117.556917 -371.489416) (xy 117.572959 -371.423924) (xy 117.596729 -371.360825)
			(xy 117.627887 -371.301028) (xy 117.665984 -371.245394) (xy 117.687852 -371.21973) (xy 117.693667 -371.212598)
			(xy 117.700169 -371.195397) (xy 117.700552 -371.186202) (xy 117.700552 -371.028722) (xy 117.701045 -371.018595)
			(xy 117.708768 -370.999872) (xy 117.723052 -370.985515) (xy 117.741736 -370.977697) (xy 117.75186 -370.97716)
			(xy 118.46814 -370.97716) (xy 118.478292 -370.977588) (xy 118.497037 -370.985389) (xy 118.511358 -370.999783)
			(xy 118.519063 -371.018568) (xy 118.519448 -371.028722) (xy 118.519448 -371.186202) (xy 118.519869 -371.195388)
			(xy 118.526376 -371.212572) (xy 118.532148 -371.21973) (xy 118.553976 -371.245425) (xy 118.59207 -371.301054)
			(xy 118.623225 -371.360846) (xy 118.646994 -371.423939) (xy 118.663033 -371.489425) (xy 118.671113 -371.556361)
			(xy 118.671116 -371.623782) (xy 118.663044 -371.690719) (xy 118.647011 -371.756207) (xy 118.623248 -371.819302)
			(xy 118.592099 -371.879097) (xy 118.554012 -371.93473) (xy 118.532148 -371.960394) (xy 118.526365 -371.967549)
			(xy 118.519844 -371.984732) (xy 118.519448 -371.993922) (xy 118.519448 -372.486174) (xy 118.519882 -372.495358)
			(xy 118.52638 -372.512542) (xy 118.532148 -372.519702) (xy 118.554047 -372.545339) (xy 118.592138 -372.600976)
			(xy 118.62329 -372.660776) (xy 118.647055 -372.723877) (xy 118.66309 -372.78937) (xy 118.671164 -372.856312)
			(xy 118.671161 -372.923739) (xy 118.663081 -372.990681) (xy 118.64704 -373.056172) (xy 118.62327 -373.119271)
			(xy 118.592112 -373.179068) (xy 118.554016 -373.234702) (xy 118.532148 -373.260366) (xy 118.526334 -373.267499)
			(xy 118.519831 -373.284699) (xy 118.519448 -373.293894) (xy 118.519448 -373.451374) (xy 118.518952 -373.461501)
			(xy 118.51123 -373.480223) (xy 118.496947 -373.494581) (xy 118.478264 -373.502399) (xy 118.46814 -373.502936)
			(xy 117.75186 -373.502936) (xy 117.741708 -373.502512) (xy 117.722961 -373.49471) (xy 117.708641 -373.480315)
			(xy 117.700936 -373.461528) (xy 117.700552 -373.451374) (xy 117.700552 -373.293894) (xy 117.700133 -373.284708)
			(xy 117.693624 -373.267524) (xy 117.687852 -373.260366) (xy 117.66602 -373.234674) (xy 117.627926 -373.179045)
			(xy 117.596771 -373.119253) (xy 117.573003 -373.056159) (xy 117.556964 -372.990673) (xy 117.548884 -372.923737)
			(xy 117.548881 -372.856315) (xy 117.556954 -372.789378) (xy 117.572988 -372.72389) (xy 117.596751 -372.660794)
			(xy 117.6279 -372.600999) (xy 117.665988 -372.545366) (xy 117.687852 -372.519702) (xy 117.693637 -372.512549)
			(xy 117.700157 -372.495364) (xy 117.700552 -372.486174) (xy 117.700552 -371.993922) (xy 117.70012 -371.984737)
			(xy 117.69362 -371.967553) (xy 117.687852 -371.960394) (xy 117.665949 -371.93476) (xy 117.627858 -371.879123)
			(xy 117.596706 -371.819323) (xy 117.572942 -371.756221) (xy 117.556907 -371.690728) (xy 117.548834 -371.623785)
			(xy 116.446761 -371.623785) (xy 116.446973 -371.624348) (xy 116.462946 -371.689732) (xy 116.47099 -371.756557)
			(xy 116.470989 -371.823864) (xy 116.462943 -371.890689) (xy 116.446967 -371.956072) (xy 116.42329 -372.019077)
			(xy 116.392252 -372.078801) (xy 116.354298 -372.134387) (xy 116.332508 -372.160038) (xy 116.326714 -372.167185)
			(xy 116.320197 -372.184374) (xy 116.319808 -372.193566) (xy 116.319808 -372.351554) (xy 116.31923 -372.361703)
			(xy 116.311479 -372.380462) (xy 116.29714 -372.394828) (xy 116.278394 -372.402612) (xy 116.268246 -372.403116)
			(xy 115.551966 -372.403116) (xy 115.541786 -372.402763) (xy 115.522982 -372.394958) (xy 115.508597 -372.380551)
			(xy 115.500821 -372.361734) (xy 115.500404 -372.351554) (xy 115.500404 -372.193566) (xy 115.500009 -372.184377)
			(xy 115.493485 -372.167193) (xy 115.487704 -372.160038) (xy 115.465931 -372.134374) (xy 115.427984 -372.078788)
			(xy 115.396952 -372.019066) (xy 115.37328 -371.956063) (xy 115.357307 -371.890683) (xy 115.349263 -371.823862)
			(xy 115.349261 -371.756559) (xy 115.357303 -371.689738) (xy 115.373274 -371.624357) (xy 115.396944 -371.561353)
			(xy 115.427973 -371.50163) (xy 115.465918 -371.446043) (xy 115.487704 -371.42039) (xy 115.493488 -371.413236)
			(xy 115.50001 -371.396052) (xy 115.500404 -371.386862) (xy 115.500404 -370.89334) (xy 115.499974 -370.884155)
			(xy 115.493474 -370.86697) (xy 115.487704 -370.859812) (xy 115.465906 -370.834169) (xy 115.427959 -370.77858)
			(xy 115.396929 -370.718855) (xy 115.373258 -370.65585) (xy 115.357287 -370.590467) (xy 115.349244 -370.523644)
			(xy 85.670941 -370.523644) (xy 85.670941 -370.523703) (xy 85.662866 -370.590641) (xy 85.646831 -370.65613)
			(xy 85.623066 -370.719226) (xy 85.591915 -370.779022) (xy 85.553825 -370.834655) (xy 85.53196 -370.86032)
			(xy 85.526167 -370.867468) (xy 85.519651 -370.884656) (xy 85.51926 -370.893848) (xy 85.51926 -371.386354)
			(xy 85.519701 -371.395538) (xy 85.526194 -371.412722) (xy 85.53196 -371.419882) (xy 85.553839 -371.445535)
			(xy 85.59193 -371.501171) (xy 85.623082 -371.560968) (xy 85.646742 -371.623785) (xy 86.748803 -371.623785)
			(xy 86.748807 -371.556358) (xy 86.756887 -371.489417) (xy 86.772927 -371.423926) (xy 86.796696 -371.360827)
			(xy 86.827851 -371.30103) (xy 86.865945 -371.245395) (xy 86.887812 -371.21973) (xy 86.893622 -371.212594)
			(xy 86.900128 -371.195397) (xy 86.900512 -371.186202) (xy 86.900512 -371.028722) (xy 86.901044 -371.0186)
			(xy 86.908759 -370.999885) (xy 86.923031 -370.985529) (xy 86.941701 -370.977704) (xy 86.95182 -370.97716)
			(xy 87.6681 -370.97716) (xy 87.678204 -370.977684) (xy 87.696874 -370.985414) (xy 87.711168 -370.999699)
			(xy 87.718909 -371.018365) (xy 87.719408 -371.028468) (xy 87.719408 -371.186202) (xy 87.719815 -371.195389)
			(xy 87.726331 -371.212574) (xy 87.732108 -371.21973) (xy 87.753934 -371.245426) (xy 87.792024 -371.301056)
			(xy 87.823176 -371.360848) (xy 87.846942 -371.423941) (xy 87.862979 -371.489426) (xy 87.871058 -371.556361)
			(xy 87.871062 -371.623782) (xy 87.86299 -371.690717) (xy 87.846958 -371.756204) (xy 87.823199 -371.819299)
			(xy 87.792053 -371.879095) (xy 87.753969 -371.934729) (xy 87.732108 -371.960394) (xy 87.726332 -371.967554)
			(xy 87.719805 -371.984733) (xy 87.719408 -371.993922) (xy 87.719408 -372.486174) (xy 87.719829 -372.49536)
			(xy 87.726335 -372.512545) (xy 87.732108 -372.519702) (xy 87.754005 -372.54534) (xy 87.792092 -372.600978)
			(xy 87.823241 -372.660779) (xy 87.847003 -372.723879) (xy 87.863036 -372.789371) (xy 87.871109 -372.856312)
			(xy 87.871106 -372.923739) (xy 87.863027 -372.990679) (xy 87.846988 -373.05617) (xy 87.82322 -373.119268)
			(xy 87.792066 -373.179065) (xy 87.753974 -373.234701) (xy 87.732108 -373.260366) (xy 87.726302 -373.267504)
			(xy 87.719793 -373.2847) (xy 87.719408 -373.293894) (xy 87.719408 -373.451374) (xy 87.718854 -373.461493)
			(xy 87.711143 -373.480205) (xy 87.696878 -373.49456) (xy 87.678216 -373.502389) (xy 87.6681 -373.502936)
			(xy 86.95182 -373.502936) (xy 86.941717 -373.502399) (xy 86.923046 -373.494675) (xy 86.908752 -373.480394)
			(xy 86.90101 -373.461731) (xy 86.900512 -373.451628) (xy 86.900512 -373.293894) (xy 86.900102 -373.284707)
			(xy 86.893588 -373.267523) (xy 86.887812 -373.260366) (xy 86.865981 -373.234673) (xy 86.82789 -373.179043)
			(xy 86.796738 -373.119251) (xy 86.772971 -373.056157) (xy 86.756933 -372.990672) (xy 86.748854 -372.923736)
			(xy 86.748851 -372.856315) (xy 86.756924 -372.789379) (xy 86.772956 -372.723891) (xy 86.796717 -372.660796)
			(xy 86.827864 -372.601001) (xy 86.86595 -372.545367) (xy 86.887812 -372.519702) (xy 86.893592 -372.512545)
			(xy 86.900116 -372.495363) (xy 86.900512 -372.486174) (xy 86.900512 -371.993922) (xy 86.900088 -371.984736)
			(xy 86.893584 -371.967552) (xy 86.887812 -371.960394) (xy 86.86591 -371.93476) (xy 86.827822 -371.879121)
			(xy 86.796672 -371.819321) (xy 86.77291 -371.75622) (xy 86.756876 -371.690727) (xy 86.748803 -371.623785)
			(xy 85.646742 -371.623785) (xy 85.646848 -371.624067) (xy 85.662883 -371.689557) (xy 85.670959 -371.756498)
			(xy 85.670957 -371.823923) (xy 85.662879 -371.890863) (xy 85.646841 -371.956354) (xy 85.623074 -372.019451)
			(xy 85.591919 -372.079248) (xy 85.553826 -372.134881) (xy 85.53196 -372.160546) (xy 85.526156 -372.167686)
			(xy 85.519647 -372.184881) (xy 85.51926 -372.194074) (xy 85.51926 -372.351554) (xy 85.518736 -372.361678)
			(xy 85.511023 -372.380398) (xy 85.496748 -372.394756) (xy 85.478073 -372.402576) (xy 85.467952 -372.403116)
			(xy 84.751672 -372.403116) (xy 84.741563 -372.402638) (xy 84.722888 -372.394894) (xy 84.708594 -372.380596)
			(xy 84.700858 -372.361917) (xy 84.700364 -372.351808) (xy 84.700364 -372.194074) (xy 84.699952 -372.184887)
			(xy 84.693438 -372.167704) (xy 84.687664 -372.160546) (xy 84.665815 -372.134869) (xy 84.627728 -372.079235)
			(xy 84.596579 -372.01944) (xy 84.572816 -371.956345) (xy 84.55678 -371.890858) (xy 84.548704 -371.823921)
			(xy 84.548703 -371.7565) (xy 84.556776 -371.689563) (xy 84.572809 -371.624075) (xy 84.59657 -371.560979)
			(xy 84.627717 -371.501183) (xy 84.665802 -371.445548) (xy 84.687664 -371.419882) (xy 84.693459 -371.412736)
			(xy 84.699973 -371.395546) (xy 84.700364 -371.386354) (xy 84.700364 -370.893848) (xy 84.699917 -370.884665)
			(xy 84.693427 -370.867481) (xy 84.687664 -370.86032) (xy 84.66579 -370.834664) (xy 84.627704 -370.779027)
			(xy 84.596555 -370.719229) (xy 84.572793 -370.656131) (xy 84.55676 -370.590642) (xy 84.548686 -370.523703)
			(xy 81.27115 -370.523703) (xy 81.263075 -370.590641) (xy 81.24704 -370.656129) (xy 81.223276 -370.719226)
			(xy 81.192125 -370.779021) (xy 81.154036 -370.834655) (xy 81.132172 -370.86032) (xy 81.126381 -370.867469)
			(xy 81.119864 -370.884657) (xy 81.119472 -370.893848) (xy 81.119472 -371.386354) (xy 81.119911 -371.395538)
			(xy 81.126405 -371.412722) (xy 81.132172 -371.419882) (xy 81.154051 -371.445535) (xy 81.192141 -371.501171)
			(xy 81.223293 -371.560969) (xy 81.246928 -371.623725) (xy 82.349035 -371.623725) (xy 82.349038 -371.556418)
			(xy 82.357086 -371.489593) (xy 82.373062 -371.424209) (xy 82.396738 -371.361203) (xy 82.427775 -371.301478)
			(xy 82.465727 -371.24589) (xy 82.487516 -371.220238) (xy 82.493323 -371.2131) (xy 82.499831 -371.195904)
			(xy 82.500216 -371.18671) (xy 82.500216 -371.028722) (xy 82.500751 -371.018568) (xy 82.508514 -370.999804)
			(xy 82.522867 -370.985439) (xy 82.541625 -370.977659) (xy 82.551778 -370.97716) (xy 83.268058 -370.97716)
			(xy 83.27823 -370.977599) (xy 83.297028 -370.985374) (xy 83.311415 -370.999756) (xy 83.319197 -371.018551)
			(xy 83.31962 -371.028722) (xy 83.31962 -371.18671) (xy 83.320021 -371.195898) (xy 83.326541 -371.213083)
			(xy 83.33232 -371.220238) (xy 83.354072 -371.24592) (xy 83.392024 -371.301501) (xy 83.423061 -371.361221)
			(xy 83.446738 -371.424221) (xy 83.462715 -371.4896) (xy 83.470763 -371.55642) (xy 83.470766 -371.623723)
			(xy 83.462725 -371.690544) (xy 83.446755 -371.755924) (xy 83.423085 -371.818927) (xy 83.392054 -371.878649)
			(xy 83.354107 -371.934234) (xy 83.33232 -371.959886) (xy 83.326507 -371.96702) (xy 83.320001 -371.984219)
			(xy 83.31962 -371.993414) (xy 83.31962 -372.486682) (xy 83.320034 -372.495869) (xy 83.326545 -372.513054)
			(xy 83.33232 -372.52021) (xy 83.354142 -372.545834) (xy 83.392093 -372.601424) (xy 83.423127 -372.661151)
			(xy 83.446799 -372.724159) (xy 83.462771 -372.789545) (xy 83.470813 -372.856371) (xy 83.47081 -372.92368)
			(xy 83.462762 -372.990505) (xy 83.446784 -373.05589) (xy 83.423106 -373.118896) (xy 83.392066 -373.17862)
			(xy 83.354111 -373.234206) (xy 83.33232 -373.259858) (xy 83.326519 -373.267) (xy 83.320006 -373.284193)
			(xy 83.31962 -373.293386) (xy 83.31962 -373.451374) (xy 83.319214 -373.461549) (xy 83.311429 -373.480351)
			(xy 83.297038 -373.494738) (xy 83.278233 -373.502517) (xy 83.268058 -373.502936) (xy 82.551778 -373.502936)
			(xy 82.541602 -373.502553) (xy 82.522802 -373.494756) (xy 82.508417 -373.480358) (xy 82.500637 -373.461551)
			(xy 82.500216 -373.451374) (xy 82.500216 -373.293386) (xy 82.499809 -373.284199) (xy 82.493293 -373.267014)
			(xy 82.487516 -373.259858) (xy 82.465763 -373.234178) (xy 82.427814 -373.178595) (xy 82.396781 -373.118875)
			(xy 82.373107 -373.055874) (xy 82.357133 -372.990496) (xy 82.349086 -372.923677) (xy 82.349083 -372.856375)
			(xy 82.357123 -372.789555) (xy 82.373092 -372.724175) (xy 82.39676 -372.661172) (xy 82.427788 -372.601449)
			(xy 82.465731 -372.545863) (xy 82.487516 -372.52021) (xy 82.493335 -372.513081) (xy 82.499836 -372.495878)
			(xy 82.500216 -372.486682) (xy 82.500216 -371.993414) (xy 82.499795 -371.984228) (xy 82.493288 -371.967044)
			(xy 82.487516 -371.959886) (xy 82.465692 -371.934264) (xy 82.427745 -371.878673) (xy 82.396715 -371.818945)
			(xy 82.373045 -371.755936) (xy 82.357076 -371.690551) (xy 82.349035 -371.623725) (xy 81.246928 -371.623725)
			(xy 81.247057 -371.624067) (xy 81.263092 -371.689558) (xy 81.271168 -371.756498) (xy 81.271166 -371.823923)
			(xy 81.263089 -371.890863) (xy 81.247051 -371.956353) (xy 81.223284 -372.019451) (xy 81.19213 -372.079247)
			(xy 81.154038 -372.134881) (xy 81.132172 -372.160546) (xy 81.12637 -372.167687) (xy 81.119859 -372.184881)
			(xy 81.119472 -372.194074) (xy 81.119472 -372.351554) (xy 81.118936 -372.361676) (xy 81.111226 -372.380394)
			(xy 81.096954 -372.394752) (xy 81.078283 -372.402574) (xy 81.068164 -372.403116) (xy 80.351884 -372.403116)
			(xy 80.341776 -372.402628) (xy 80.323101 -372.394888) (xy 80.308807 -372.380592) (xy 80.30107 -372.361916)
			(xy 80.300576 -372.351808) (xy 80.300576 -372.194074) (xy 80.300184 -372.184885) (xy 80.293658 -372.1677)
			(xy 80.287876 -372.160546) (xy 80.266027 -372.134869) (xy 80.227939 -372.079236) (xy 80.196789 -372.019441)
			(xy 80.173025 -371.956346) (xy 80.156989 -371.890858) (xy 80.148913 -371.823922) (xy 80.148912 -371.756499)
			(xy 80.156986 -371.689563) (xy 80.173019 -371.624075) (xy 80.196781 -371.560978) (xy 80.227928 -371.501182)
			(xy 80.266014 -371.445548) (xy 80.287876 -371.419882) (xy 80.29366 -371.412728) (xy 80.300183 -371.395544)
			(xy 80.300576 -371.386354) (xy 80.300576 -370.893848) (xy 80.300148 -370.884663) (xy 80.293647 -370.867478)
			(xy 80.287876 -370.86032) (xy 80.266001 -370.834664) (xy 80.227914 -370.779028) (xy 80.196765 -370.71923)
			(xy 80.173003 -370.656132) (xy 80.156969 -370.590642) (xy 80.148895 -370.523703) (xy 76.870824 -370.523703)
			(xy 76.862788 -370.590464) (xy 76.846817 -370.655845) (xy 76.823147 -370.718849) (xy 76.792116 -370.778573)
			(xy 76.75417 -370.83416) (xy 76.732384 -370.859812) (xy 76.726598 -370.866965) (xy 76.720078 -370.88415)
			(xy 76.719684 -370.89334) (xy 76.719684 -371.386862) (xy 76.720116 -371.396047) (xy 76.726615 -371.413231)
			(xy 76.732384 -371.42039) (xy 76.754185 -371.446031) (xy 76.792132 -371.50162) (xy 76.823163 -371.561345)
			(xy 76.846621 -371.623785) (xy 77.948715 -371.623785) (xy 77.948719 -371.556358) (xy 77.956799 -371.489417)
			(xy 77.972839 -371.423925) (xy 77.996609 -371.360826) (xy 78.027766 -371.301029) (xy 78.065861 -371.245395)
			(xy 78.087728 -371.21973) (xy 78.09354 -371.212596) (xy 78.100045 -371.195397) (xy 78.100428 -371.186202)
			(xy 78.100428 -371.028722) (xy 78.100944 -371.018598) (xy 78.108662 -370.99988) (xy 78.12294 -370.985523)
			(xy 78.141615 -370.977701) (xy 78.151736 -370.97716) (xy 78.868016 -370.97716) (xy 78.878121 -370.977671)
			(xy 78.896792 -370.985407) (xy 78.911084 -370.999695) (xy 78.918826 -371.018363) (xy 78.919324 -371.028468)
			(xy 78.919324 -371.186202) (xy 78.919728 -371.19539) (xy 78.926245 -371.212575) (xy 78.932024 -371.21973)
			(xy 78.95385 -371.245426) (xy 78.991938 -371.301057) (xy 79.023089 -371.360849) (xy 79.046854 -371.423942)
			(xy 79.062892 -371.489427) (xy 79.07097 -371.556361) (xy 79.070974 -371.623782) (xy 79.062902 -371.690717)
			(xy 79.046871 -371.756203) (xy 79.023112 -371.819299) (xy 78.991967 -371.879094) (xy 78.953885 -371.934728)
			(xy 78.932024 -371.960394) (xy 78.92625 -371.967556) (xy 78.919721 -371.984733) (xy 78.919324 -371.993922)
			(xy 78.919324 -372.486174) (xy 78.919741 -372.495361) (xy 78.926249 -372.512545) (xy 78.932024 -372.519702)
			(xy 78.953921 -372.54534) (xy 78.992007 -372.600979) (xy 79.023155 -372.660779) (xy 79.046916 -372.72388)
			(xy 79.062948 -372.789372) (xy 79.071021 -372.856313) (xy 79.071018 -372.923738) (xy 79.062939 -372.990679)
			(xy 79.046901 -373.056169) (xy 79.023134 -373.119267) (xy 78.99198 -373.179065) (xy 78.953889 -373.2347)
			(xy 78.932024 -373.260366) (xy 78.92622 -373.267506) (xy 78.919709 -373.2847) (xy 78.919324 -373.293894)
			(xy 78.919324 -373.451374) (xy 78.918851 -373.461504) (xy 78.911125 -373.480231) (xy 78.896834 -373.49459)
			(xy 78.878143 -373.502403) (xy 78.868016 -373.502936) (xy 78.151736 -373.502936) (xy 78.14162 -373.502455)
			(xy 78.122924 -373.494726) (xy 78.10861 -373.480429) (xy 78.100857 -373.461743) (xy 78.100428 -373.451628)
			(xy 78.100428 -373.293894) (xy 78.100015 -373.284707) (xy 78.093503 -373.267523) (xy 78.087728 -373.260366)
			(xy 78.065896 -373.234674) (xy 78.027805 -373.179044) (xy 77.996651 -373.119251) (xy 77.972884 -373.056158)
			(xy 77.956845 -372.990672) (xy 77.948766 -372.923736) (xy 77.948763 -372.856315) (xy 77.956836 -372.789378)
			(xy 77.972869 -372.723891) (xy 77.99663 -372.660795) (xy 78.027779 -372.601) (xy 78.065865 -372.545367)
			(xy 78.087728 -372.519702) (xy 78.09351 -372.512547) (xy 78.100033 -372.495364) (xy 78.100428 -372.486174)
			(xy 78.100428 -371.993922) (xy 78.100001 -371.984737) (xy 78.093498 -371.967553) (xy 78.087728 -371.960394)
			(xy 78.065826 -371.93476) (xy 78.027736 -371.879122) (xy 77.996586 -371.819321) (xy 77.972822 -371.75622)
			(xy 77.956789 -371.690727) (xy 77.948715 -371.623785) (xy 76.846621 -371.623785) (xy 76.846834 -371.624351)
			(xy 76.862805 -371.689734) (xy 76.870848 -371.756558) (xy 76.870847 -371.823863) (xy 76.862802 -371.890687)
			(xy 76.846828 -371.956069) (xy 76.823155 -372.019074) (xy 76.792121 -372.078798) (xy 76.754172 -372.134386)
			(xy 76.732384 -372.160038) (xy 76.726587 -372.167183) (xy 76.720073 -372.184374) (xy 76.719684 -372.193566)
			(xy 76.719684 -372.351554) (xy 76.719199 -372.36172) (xy 76.711433 -372.380509) (xy 76.697067 -372.394895)
			(xy 76.678287 -372.402686) (xy 76.668122 -372.403116) (xy 75.951842 -372.403116) (xy 75.941667 -372.402701)
			(xy 75.922865 -372.394921) (xy 75.908477 -372.380532) (xy 75.900699 -372.361729) (xy 75.90028 -372.351554)
			(xy 75.90028 -372.193566) (xy 75.899891 -372.184377) (xy 75.893363 -372.167192) (xy 75.88758 -372.160038)
			(xy 75.865805 -372.134375) (xy 75.827853 -372.078791) (xy 75.796817 -372.019069) (xy 75.773141 -371.956066)
			(xy 75.757166 -371.890685) (xy 75.74912 -371.823863) (xy 75.749119 -371.756558) (xy 75.757162 -371.689736)
			(xy 75.773135 -371.624354) (xy 75.796808 -371.56135) (xy 75.827842 -371.501627) (xy 75.865792 -371.446042)
			(xy 75.88758 -371.42039) (xy 75.893361 -371.413234) (xy 75.899886 -371.396052) (xy 75.90028 -371.386862)
			(xy 75.90028 -370.89334) (xy 75.899855 -370.884154) (xy 75.893352 -370.866969) (xy 75.88758 -370.859812)
			(xy 75.865779 -370.83417) (xy 75.827828 -370.778583) (xy 75.796793 -370.718859) (xy 75.773119 -370.655853)
			(xy 75.757146 -370.590469) (xy 75.749102 -370.523644) (xy 72.471063 -370.523644) (xy 72.471063 -370.523702)
			(xy 72.462988 -370.59064) (xy 72.446953 -370.656129) (xy 72.42319 -370.719225) (xy 72.39204 -370.779021)
			(xy 72.353952 -370.834655) (xy 72.332088 -370.86032) (xy 72.326299 -370.867471) (xy 72.31978 -370.884657)
			(xy 72.319388 -370.893848) (xy 72.319388 -371.386354) (xy 72.319823 -371.395539) (xy 72.32632 -371.412723)
			(xy 72.332088 -371.419882) (xy 72.353966 -371.445536) (xy 72.392055 -371.501172) (xy 72.423206 -371.560969)
			(xy 72.446841 -371.623725) (xy 73.548947 -371.623725) (xy 73.548951 -371.556417) (xy 73.556998 -371.489592)
			(xy 73.572975 -371.424208) (xy 73.596652 -371.361202) (xy 73.627689 -371.301477) (xy 73.665642 -371.24589)
			(xy 73.687432 -371.220238) (xy 73.693242 -371.213102) (xy 73.699748 -371.195904) (xy 73.700132 -371.18671)
			(xy 73.700132 -371.028722) (xy 73.700582 -371.018553) (xy 73.708359 -370.99976) (xy 73.722736 -370.985374)
			(xy 73.741525 -370.977587) (xy 73.751694 -370.97716) (xy 74.467974 -370.97716) (xy 74.478147 -370.977586)
			(xy 74.496945 -370.985366) (xy 74.511331 -370.999752) (xy 74.519113 -371.018549) (xy 74.519536 -371.028722)
			(xy 74.519536 -371.18671) (xy 74.519956 -371.195896) (xy 74.526464 -371.21308) (xy 74.532236 -371.220238)
			(xy 74.553987 -371.245921) (xy 74.591939 -371.301502) (xy 74.622975 -371.361221) (xy 74.646651 -371.424222)
			(xy 74.662627 -371.489601) (xy 74.670675 -371.55642) (xy 74.670678 -371.623723) (xy 74.662638 -371.690543)
			(xy 74.646668 -371.755924) (xy 74.622998 -371.818926) (xy 74.591968 -371.878649) (xy 74.554022 -371.934234)
			(xy 74.532236 -371.959886) (xy 74.526413 -371.967012) (xy 74.519916 -371.984217) (xy 74.519536 -371.993414)
			(xy 74.519536 -372.486682) (xy 74.519969 -372.495866) (xy 74.526468 -372.51305) (xy 74.532236 -372.52021)
			(xy 74.554058 -372.545834) (xy 74.592008 -372.601424) (xy 74.623041 -372.661151) (xy 74.646713 -372.724159)
			(xy 74.662684 -372.789545) (xy 74.670726 -372.856371) (xy 74.670723 -372.92368) (xy 74.662675 -372.990505)
			(xy 74.646698 -373.055889) (xy 74.62302 -373.118896) (xy 74.591981 -373.17862) (xy 74.554027 -373.234206)
			(xy 74.532236 -373.259858) (xy 74.526425 -373.266992) (xy 74.519921 -373.284191) (xy 74.519536 -373.293386)
			(xy 74.519536 -373.451374) (xy 74.519114 -373.461547) (xy 74.511333 -373.480346) (xy 74.496946 -373.494733)
			(xy 74.478147 -373.502514) (xy 74.467974 -373.502936) (xy 73.751694 -373.502936) (xy 73.741519 -373.50254)
			(xy 73.722719 -373.494749) (xy 73.708333 -373.480354) (xy 73.700553 -373.461549) (xy 73.700132 -373.451374)
			(xy 73.700132 -373.293386) (xy 73.699722 -373.284199) (xy 73.693207 -373.267015) (xy 73.687432 -373.259858)
			(xy 73.665678 -373.234178) (xy 73.627729 -373.178595) (xy 73.596694 -373.118876) (xy 73.57302 -373.055875)
			(xy 73.557045 -372.990496) (xy 73.548998 -372.923677) (xy 73.548995 -372.856374) (xy 73.557036 -372.789554)
			(xy 73.573005 -372.724174) (xy 73.596674 -372.661171) (xy 73.627702 -372.601448) (xy 73.665647 -372.545862)
			(xy 73.687432 -372.52021) (xy 73.693253 -372.513083) (xy 73.699753 -372.495878) (xy 73.700132 -372.486682)
			(xy 73.700132 -371.993414) (xy 73.699708 -371.984228) (xy 73.693203 -371.967044) (xy 73.687432 -371.959886)
			(xy 73.665607 -371.934265) (xy 73.62766 -371.878674) (xy 73.596629 -371.818946) (xy 73.572958 -371.755937)
			(xy 73.556988 -371.690551) (xy 73.548947 -371.623725) (xy 72.446841 -371.623725) (xy 72.44697 -371.624068)
			(xy 72.463005 -371.689558) (xy 72.47108 -371.756498) (xy 72.471078 -371.823923) (xy 72.463001 -371.890862)
			(xy 72.446964 -371.956352) (xy 72.423197 -372.01945) (xy 72.392044 -372.079246) (xy 72.353953 -372.134881)
			(xy 72.332088 -372.160546) (xy 72.326288 -372.167689) (xy 72.319776 -372.184881) (xy 72.319388 -372.194074)
			(xy 72.319388 -372.351554) (xy 72.318836 -372.361674) (xy 72.311129 -372.380389) (xy 72.296863 -372.394746)
			(xy 72.278197 -372.402572) (xy 72.26808 -372.403116) (xy 71.5518 -372.403116) (xy 71.541648 -372.402679)
			(xy 71.522899 -372.394886) (xy 71.508576 -372.380494) (xy 71.500873 -372.361708) (xy 71.500492 -372.351554)
			(xy 71.500492 -372.194074) (xy 71.500096 -372.184885) (xy 71.493573 -372.167701) (xy 71.487792 -372.160546)
			(xy 71.465942 -372.134869) (xy 71.427853 -372.079236) (xy 71.396703 -372.019442) (xy 71.372938 -371.956346)
			(xy 71.356902 -371.890859) (xy 71.348825 -371.823922) (xy 71.348824 -371.756499) (xy 71.356898 -371.689562)
			(xy 71.372932 -371.624074) (xy 71.396694 -371.560978) (xy 71.427843 -371.501182) (xy 71.465929 -371.445547)
			(xy 71.487792 -371.419882) (xy 71.493578 -371.412729) (xy 71.500099 -371.395545) (xy 71.500492 -371.386354)
			(xy 71.500492 -370.893848) (xy 71.500061 -370.884663) (xy 71.493562 -370.867478) (xy 71.487792 -370.86032)
			(xy 71.465917 -370.834664) (xy 71.427829 -370.779028) (xy 71.396679 -370.719231) (xy 71.372916 -370.656133)
			(xy 71.356881 -370.590642) (xy 71.348807 -370.523703) (xy 58.103008 -370.523703) (xy 58.103008 -371.310662)
			(xy 58.102522 -371.337931) (xy 58.09476 -371.391915) (xy 58.079395 -371.444245) (xy 58.056738 -371.493855)
			(xy 58.027252 -371.539736) (xy 57.991537 -371.580953) (xy 57.95032 -371.616668) (xy 57.904439 -371.646154)
			(xy 57.854829 -371.668811) (xy 57.802499 -371.684176) (xy 57.748515 -371.691938) (xy 57.693977 -371.691938)
			(xy 57.639993 -371.684176) (xy 57.587663 -371.668811) (xy 57.538053 -371.646154) (xy 57.492172 -371.616668)
			(xy 57.450955 -371.580953) (xy 57.41524 -371.539736) (xy 57.385754 -371.493855) (xy 57.363097 -371.444245)
			(xy 57.347732 -371.391915) (xy 57.33997 -371.337931) (xy 57.339484 -371.310662) (xy 54.729888 -371.310662)
			(xy 54.729402 -371.337931) (xy 54.72164 -371.391915) (xy 54.706275 -371.444245) (xy 54.683618 -371.493855)
			(xy 54.654132 -371.539736) (xy 54.618417 -371.580953) (xy 54.5772 -371.616668) (xy 54.531319 -371.646154)
			(xy 54.481709 -371.668811) (xy 54.429379 -371.684176) (xy 54.375395 -371.691938) (xy 54.320857 -371.691938)
			(xy 54.266873 -371.684176) (xy 54.214543 -371.668811) (xy 54.164933 -371.646154) (xy 54.119052 -371.616668)
			(xy 54.077835 -371.580953) (xy 54.04212 -371.539736) (xy 54.012634 -371.493855) (xy 53.989977 -371.444245)
			(xy 53.974612 -371.391915) (xy 53.96685 -371.337931) (xy 53.966364 -371.310662) (xy 48.196948 -371.310662)
			(xy 48.223223 -371.361224) (xy 48.246896 -371.424224) (xy 48.262871 -371.489602) (xy 48.270918 -371.556421)
			(xy 48.270921 -371.623722) (xy 48.262881 -371.690542) (xy 48.246913 -371.755921) (xy 48.223246 -371.818924)
			(xy 48.192219 -371.878647) (xy 48.154277 -371.934234) (xy 48.132492 -371.959886) (xy 48.126675 -371.967017)
			(xy 48.120173 -371.984218) (xy 48.119792 -371.993414) (xy 48.119792 -372.486682) (xy 48.120213 -372.495868)
			(xy 48.126719 -372.513052) (xy 48.132492 -372.52021) (xy 48.154312 -372.545835) (xy 48.192258 -372.601426)
			(xy 48.223288 -372.661154) (xy 48.246958 -372.724162) (xy 48.262927 -372.789547) (xy 48.270968 -372.856372)
			(xy 48.270965 -372.923679) (xy 48.262918 -372.990504) (xy 48.246942 -373.055887) (xy 48.223267 -373.118893)
			(xy 48.192232 -373.178618) (xy 48.154281 -373.234205) (xy 48.132492 -373.259858) (xy 48.126687 -373.266997)
			(xy 48.120178 -373.284192) (xy 48.119792 -373.293386) (xy 48.119792 -373.451374) (xy 48.119246 -373.461526)
			(xy 48.111486 -373.480289) (xy 48.097136 -373.494655) (xy 48.078382 -373.502435) (xy 48.06823 -373.502936)
			(xy 47.35195 -373.502936) (xy 47.341778 -373.502495) (xy 47.32298 -373.494721) (xy 47.308592 -373.48034)
			(xy 47.30081 -373.461545) (xy 47.300388 -373.451374) (xy 47.300388 -373.293386) (xy 47.299987 -373.284198)
			(xy 47.293467 -373.267013) (xy 47.287688 -373.259858) (xy 47.265932 -373.234179) (xy 47.227979 -373.178598)
			(xy 47.196942 -373.118878) (xy 47.173265 -373.055877) (xy 47.157288 -372.990498) (xy 47.14924 -372.923677)
			(xy 47.149237 -372.856374) (xy 47.157279 -372.789553) (xy 47.17325 -372.724172) (xy 47.196921 -372.661169)
			(xy 47.227953 -372.601446) (xy 47.265901 -372.545861) (xy 47.287688 -372.52021) (xy 47.293504 -372.513078)
			(xy 47.300007 -372.495878) (xy 47.300388 -372.486682) (xy 47.300388 -371.993414) (xy 47.299974 -371.984227)
			(xy 47.293463 -371.967043) (xy 47.287688 -371.959886) (xy 47.265861 -371.934265) (xy 47.227911 -371.878675)
			(xy 47.196876 -371.818948) (xy 47.173204 -371.755939) (xy 47.157232 -371.690553) (xy 47.14919 -371.623726)
			(xy 46.046568 -371.623726) (xy 46.046802 -371.624349) (xy 46.062775 -371.689733) (xy 46.070818 -371.756557)
			(xy 46.070817 -371.823864) (xy 46.062771 -371.890688) (xy 46.046796 -371.956071) (xy 46.023121 -372.019076)
			(xy 45.992085 -372.0788) (xy 45.954133 -372.134386) (xy 45.932344 -372.160038) (xy 45.926542 -372.167179)
			(xy 45.920032 -372.184373) (xy 45.919644 -372.193566) (xy 45.919644 -372.351554) (xy 45.919198 -372.361725)
			(xy 45.911425 -372.380522) (xy 45.897046 -372.394909) (xy 45.878253 -372.402693) (xy 45.868082 -372.403116)
			(xy 45.151802 -372.403116) (xy 45.141625 -372.402733) (xy 45.122821 -372.394941) (xy 45.108435 -372.380542)
			(xy 45.100658 -372.361732) (xy 45.10024 -372.351554) (xy 45.10024 -372.193566) (xy 45.099837 -372.184378)
			(xy 45.093317 -372.167194) (xy 45.08754 -372.160038) (xy 45.065766 -372.134374) (xy 45.027817 -372.07879)
			(xy 44.996783 -372.019068) (xy 44.973109 -371.956065) (xy 44.957135 -371.890684) (xy 44.94909 -371.823862)
			(xy 44.949089 -371.756559) (xy 44.957132 -371.689737) (xy 44.973103 -371.624356) (xy 44.996774 -371.561352)
			(xy 45.027806 -371.501628) (xy 45.065753 -371.446042) (xy 45.08754 -371.42039) (xy 45.093328 -371.413239)
			(xy 45.099847 -371.396053) (xy 45.10024 -371.386862) (xy 45.10024 -370.89334) (xy 45.099801 -370.884156)
			(xy 45.093306 -370.866972) (xy 45.08754 -370.859812) (xy 45.06574 -370.83417) (xy 45.027792 -370.778582)
			(xy 44.996759 -370.718857) (xy 44.973087 -370.655851) (xy 44.957115 -370.590468) (xy 44.949071 -370.523644)
			(xy 41.671032 -370.523644) (xy 41.671032 -370.523703) (xy 41.662957 -370.590641) (xy 41.646921 -370.65613)
			(xy 41.623156 -370.719227) (xy 41.592004 -370.779022) (xy 41.553913 -370.834656) (xy 41.532048 -370.86032)
			(xy 41.526254 -370.867467) (xy 41.519739 -370.884656) (xy 41.519348 -370.893848) (xy 41.519348 -371.386354)
			(xy 41.519792 -371.395537) (xy 41.526284 -371.412721) (xy 41.532048 -371.419882) (xy 41.553928 -371.445535)
			(xy 41.592019 -371.50117) (xy 41.623172 -371.560967) (xy 41.646832 -371.623785) (xy 42.748894 -371.623785)
			(xy 42.748898 -371.556358) (xy 42.756977 -371.489417) (xy 42.773017 -371.423926) (xy 42.796785 -371.360828)
			(xy 42.827941 -371.30103) (xy 42.866034 -371.245395) (xy 42.8879 -371.21973) (xy 42.893709 -371.212593)
			(xy 42.900216 -371.195396) (xy 42.9006 -371.186202) (xy 42.9006 -371.028722) (xy 42.901143 -371.018602)
			(xy 42.908856 -370.999888) (xy 42.923125 -370.985533) (xy 42.941791 -370.977706) (xy 42.951908 -370.97716)
			(xy 43.668188 -370.97716) (xy 43.678336 -370.977631) (xy 43.697081 -370.985415) (xy 43.711403 -370.999796)
			(xy 43.71911 -371.018572) (xy 43.719496 -371.028722) (xy 43.719496 -371.186202) (xy 43.719906 -371.195389)
			(xy 43.72642 -371.212573) (xy 43.732196 -371.21973) (xy 43.754023 -371.245426) (xy 43.792113 -371.301056)
			(xy 43.823265 -371.360848) (xy 43.847032 -371.423941) (xy 43.86307 -371.489426) (xy 43.871149 -371.556361)
			(xy 43.871153 -371.623782) (xy 43.86308 -371.690718) (xy 43.847049 -371.756205) (xy 43.823289 -371.8193)
			(xy 43.792142 -371.879095) (xy 43.754058 -371.934729) (xy 43.732196 -371.960394) (xy 43.726419 -371.967553)
			(xy 43.719893 -371.984733) (xy 43.719496 -371.993922) (xy 43.719496 -372.486174) (xy 43.71992 -372.49536)
			(xy 43.726424 -372.512544) (xy 43.732196 -372.519702) (xy 43.754094 -372.54534) (xy 43.792181 -372.600978)
			(xy 43.823331 -372.660778) (xy 43.847093 -372.723878) (xy 43.863127 -372.789371) (xy 43.8712 -372.856312)
			(xy 43.871197 -372.923739) (xy 43.863117 -372.990679) (xy 43.847078 -373.05617) (xy 43.82331 -373.119269)
			(xy 43.792155 -373.179066) (xy 43.754062 -373.234701) (xy 43.732196 -373.260366) (xy 43.726388 -373.267503)
			(xy 43.71988 -373.2847) (xy 43.719496 -373.293894) (xy 43.719496 -373.451374) (xy 43.718953 -373.461495)
			(xy 43.711241 -373.480208) (xy 43.696972 -373.494564) (xy 43.678306 -373.502391) (xy 43.668188 -373.502936)
			(xy 42.951908 -373.502936) (xy 42.941759 -373.502473) (xy 42.923014 -373.494686) (xy 42.908691 -373.480303)
			(xy 42.900985 -373.461525) (xy 42.9006 -373.451374) (xy 42.9006 -373.293894) (xy 42.900193 -373.284707)
			(xy 42.893677 -373.267522) (xy 42.8879 -373.260366) (xy 42.866069 -373.234673) (xy 42.82798 -373.179043)
			(xy 42.796828 -373.11925) (xy 42.773061 -373.056157) (xy 42.757024 -372.990671) (xy 42.748945 -372.923736)
			(xy 42.748942 -372.856315) (xy 42.757014 -372.789379) (xy 42.773046 -372.723892) (xy 42.796807 -372.660796)
			(xy 42.827953 -372.601001) (xy 42.866038 -372.545367) (xy 42.8879 -372.519702) (xy 42.893678 -372.512544)
			(xy 42.900204 -372.495363) (xy 42.9006 -372.486174) (xy 42.9006 -371.993922) (xy 42.900179 -371.984736)
			(xy 42.893673 -371.967551) (xy 42.8879 -371.960394) (xy 42.865999 -371.93476) (xy 42.827911 -371.879121)
			(xy 42.796762 -371.81932) (xy 42.773 -371.756219) (xy 42.756967 -371.690726) (xy 42.748894 -371.623785)
			(xy 41.646832 -371.623785) (xy 41.646938 -371.624066) (xy 41.662974 -371.689557) (xy 41.67105 -371.756498)
			(xy 41.671048 -371.823923) (xy 41.66297 -371.890864) (xy 41.646932 -371.956354) (xy 41.623164 -372.019452)
			(xy 41.592008 -372.079248) (xy 41.553915 -372.134882) (xy 41.532048 -372.160546) (xy 41.526243 -372.167685)
			(xy 41.519735 -372.18488) (xy 41.519348 -372.194074) (xy 41.519348 -372.351554) (xy 41.518835 -372.361679)
			(xy 41.51112 -372.380402) (xy 41.496842 -372.39476) (xy 41.478162 -372.402579) (xy 41.46804 -372.403116)
			(xy 40.75176 -372.403116) (xy 40.741605 -372.402711) (xy 40.722855 -372.394906) (xy 40.708534 -372.380504)
			(xy 40.700833 -372.361711) (xy 40.700452 -372.351554) (xy 40.700452 -372.194074) (xy 40.700043 -372.184887)
			(xy 40.693527 -372.167703) (xy 40.687752 -372.160546) (xy 40.6659 -372.13487) (xy 40.627807 -372.079238)
			(xy 40.596653 -372.019444) (xy 40.572886 -371.956349) (xy 40.556848 -371.89086) (xy 40.54877 -371.823922)
			(xy 40.548769 -371.756499) (xy 40.556844 -371.68956) (xy 40.57288 -371.624072) (xy 40.596645 -371.560975)
			(xy 40.627797 -371.50118) (xy 40.665887 -371.445546) (xy 40.687752 -371.419882) (xy 40.693545 -371.412735)
			(xy 40.70006 -371.395546) (xy 40.700452 -371.386354) (xy 40.700452 -370.893848) (xy 40.700007 -370.884665)
			(xy 40.693516 -370.867481) (xy 40.687752 -370.86032) (xy 40.665874 -370.834665) (xy 40.627783 -370.779031)
			(xy 40.59663 -370.719233) (xy 40.572864 -370.656135) (xy 40.556828 -370.590644) (xy 40.548752 -370.523704)
			(xy 37.271241 -370.523704) (xy 37.263166 -370.590641) (xy 37.247131 -370.65613) (xy 37.223366 -370.719226)
			(xy 37.192215 -370.779022) (xy 37.154125 -370.834655) (xy 37.13226 -370.86032) (xy 37.126467 -370.867468)
			(xy 37.119951 -370.884656) (xy 37.11956 -370.893848) (xy 37.11956 -371.386354) (xy 37.120001 -371.395538)
			(xy 37.126494 -371.412722) (xy 37.13226 -371.419882) (xy 37.154139 -371.445535) (xy 37.19223 -371.501171)
			(xy 37.223382 -371.560968) (xy 37.247019 -371.623725) (xy 38.349126 -371.623725) (xy 38.349129 -371.556418)
			(xy 38.357177 -371.489593) (xy 38.373153 -371.424209) (xy 38.396828 -371.361203) (xy 38.427864 -371.301478)
			(xy 38.465815 -371.245891) (xy 38.487604 -371.220238) (xy 38.49341 -371.213099) (xy 38.499919 -371.195904)
			(xy 38.500304 -371.18671) (xy 38.500304 -371.028722) (xy 38.50085 -371.01857) (xy 38.508611 -370.999808)
			(xy 38.522961 -370.985443) (xy 38.541714 -370.977661) (xy 38.551866 -370.97716) (xy 39.268146 -370.97716)
			(xy 39.278309 -370.977596) (xy 39.297084 -370.98539) (xy 39.311448 -370.999773) (xy 39.319217 -371.018558)
			(xy 39.319708 -371.028722) (xy 39.319708 -371.18671) (xy 39.320112 -371.195898) (xy 39.32663 -371.213082)
			(xy 39.332408 -371.220238) (xy 39.35416 -371.24592) (xy 39.392113 -371.301501) (xy 39.423151 -371.36122)
			(xy 39.446829 -371.424221) (xy 39.462806 -371.4896) (xy 39.470854 -371.55642) (xy 39.470857 -371.623723)
			(xy 39.462816 -371.690544) (xy 39.446845 -371.755925) (xy 39.423175 -371.818928) (xy 39.392143 -371.87865)
			(xy 39.354195 -371.934235) (xy 39.332408 -371.959886) (xy 39.326593 -371.967018) (xy 39.320089 -371.984219)
			(xy 39.319708 -371.993414) (xy 39.319708 -372.486682) (xy 39.320125 -372.495868) (xy 39.326634 -372.513053)
			(xy 39.332408 -372.52021) (xy 39.354231 -372.545834) (xy 39.392182 -372.601423) (xy 39.423217 -372.66115)
			(xy 39.44689 -372.724158) (xy 39.462862 -372.789545) (xy 39.470904 -372.856371) (xy 39.470901 -372.92368)
			(xy 39.462853 -372.990506) (xy 39.446875 -373.05589) (xy 39.423196 -373.118897) (xy 39.392156 -373.178621)
			(xy 39.354199 -373.234207) (xy 39.332408 -373.259858) (xy 39.326605 -373.266999) (xy 39.320094 -373.284193)
			(xy 39.319708 -373.293386) (xy 39.319708 -373.451374) (xy 39.319147 -373.461525) (xy 39.311389 -373.480284)
			(xy 39.297045 -373.494649) (xy 39.278296 -373.502432) (xy 39.268146 -373.502936) (xy 38.551866 -373.502936)
			(xy 38.541703 -373.502494) (xy 38.522928 -373.494703) (xy 38.508563 -373.480322) (xy 38.500794 -373.461538)
			(xy 38.500304 -373.451374) (xy 38.500304 -373.293386) (xy 38.4999 -373.284198) (xy 38.493382 -373.267014)
			(xy 38.487604 -373.259858) (xy 38.465851 -373.234178) (xy 38.427903 -373.178595) (xy 38.39687 -373.118875)
			(xy 38.373197 -373.055874) (xy 38.357223 -372.990495) (xy 38.349177 -372.923676) (xy 38.349174 -372.856375)
			(xy 38.357214 -372.789555) (xy 38.373182 -372.724175) (xy 38.396849 -372.661172) (xy 38.427877 -372.601449)
			(xy 38.465819 -372.545863) (xy 38.487604 -372.52021) (xy 38.493422 -372.51308) (xy 38.499924 -372.495878)
			(xy 38.500304 -372.486682) (xy 38.500304 -371.993414) (xy 38.499886 -371.984228) (xy 38.493378 -371.967043)
			(xy 38.487604 -371.959886) (xy 38.46578 -371.934264) (xy 38.427835 -371.878672) (xy 38.396805 -371.818944)
			(xy 38.373136 -371.755936) (xy 38.357167 -371.69055) (xy 38.349126 -371.623725) (xy 37.247019 -371.623725)
			(xy 37.247148 -371.624067) (xy 37.263183 -371.689557) (xy 37.271259 -371.756498) (xy 37.271257 -371.823923)
			(xy 37.263179 -371.890863) (xy 37.247141 -371.956354) (xy 37.223374 -372.019451) (xy 37.192219 -372.079248)
			(xy 37.154126 -372.134881) (xy 37.13226 -372.160546) (xy 37.126456 -372.167686) (xy 37.119947 -372.184881)
			(xy 37.11956 -372.194074) (xy 37.11956 -372.351554) (xy 37.119036 -372.361678) (xy 37.111323 -372.380398)
			(xy 37.097048 -372.394756) (xy 37.078373 -372.402576) (xy 37.068252 -372.403116) (xy 36.351972 -372.403116)
			(xy 36.341818 -372.402702) (xy 36.323068 -372.3949) (xy 36.308746 -372.380501) (xy 36.301045 -372.36171)
			(xy 36.300664 -372.351554) (xy 36.300664 -372.194074) (xy 36.300252 -372.184887) (xy 36.293738 -372.167704)
			(xy 36.287964 -372.160546) (xy 36.266115 -372.134869) (xy 36.228028 -372.079235) (xy 36.196879 -372.01944)
			(xy 36.173116 -371.956345) (xy 36.15708 -371.890858) (xy 36.149004 -371.823921) (xy 36.149003 -371.7565)
			(xy 36.157076 -371.689563) (xy 36.173109 -371.624075) (xy 36.19687 -371.560979) (xy 36.228017 -371.501183)
			(xy 36.266102 -371.445548) (xy 36.287964 -371.419882) (xy 36.293759 -371.412736) (xy 36.300273 -371.395546)
			(xy 36.300664 -371.386354) (xy 36.300664 -370.893848) (xy 36.300217 -370.884665) (xy 36.293727 -370.867481)
			(xy 36.287964 -370.86032) (xy 36.26609 -370.834664) (xy 36.228004 -370.779027) (xy 36.196855 -370.719229)
			(xy 36.173093 -370.656131) (xy 36.15706 -370.590642) (xy 36.148986 -370.523703) (xy 32.870915 -370.523703)
			(xy 32.862879 -370.590465) (xy 32.846908 -370.655846) (xy 32.823237 -370.71885) (xy 32.792205 -370.778573)
			(xy 32.754259 -370.83416) (xy 32.732472 -370.859812) (xy 32.726684 -370.866963) (xy 32.720165 -370.884149)
			(xy 32.719772 -370.89334) (xy 32.719772 -371.386862) (xy 32.720207 -371.396046) (xy 32.726704 -371.413231)
			(xy 32.732472 -371.42039) (xy 32.754273 -371.446031) (xy 32.792221 -371.501619) (xy 32.823253 -371.561344)
			(xy 32.846713 -371.623785) (xy 33.948806 -371.623785) (xy 33.94881 -371.556358) (xy 33.95689 -371.489417)
			(xy 33.97293 -371.423925) (xy 33.996699 -371.360827) (xy 34.027855 -371.30103) (xy 34.065949 -371.245395)
			(xy 34.087816 -371.21973) (xy 34.093627 -371.212595) (xy 34.100132 -371.195397) (xy 34.100516 -371.186202)
			(xy 34.100516 -371.028722) (xy 34.101044 -371.0186) (xy 34.10876 -370.999883) (xy 34.123033 -370.985527)
			(xy 34.141705 -370.977703) (xy 34.151824 -370.97716) (xy 34.868104 -370.97716) (xy 34.878253 -370.977618)
			(xy 34.896998 -370.985407) (xy 34.91132 -370.999792) (xy 34.919027 -371.018571) (xy 34.919412 -371.028722)
			(xy 34.919412 -371.186202) (xy 34.919819 -371.19539) (xy 34.926334 -371.212574) (xy 34.932112 -371.21973)
			(xy 34.953938 -371.245426) (xy 34.992027 -371.301057) (xy 35.023179 -371.360849) (xy 35.046945 -371.423941)
			(xy 35.062982 -371.489427) (xy 35.071061 -371.556361) (xy 35.071065 -371.623782) (xy 35.062993 -371.690717)
			(xy 35.046962 -371.756204) (xy 35.023202 -371.819299) (xy 34.992057 -371.879094) (xy 34.953973 -371.934729)
			(xy 34.932112 -371.960394) (xy 34.926337 -371.967555) (xy 34.919809 -371.984733) (xy 34.919412 -371.993922)
			(xy 34.919412 -372.486174) (xy 34.919832 -372.49536) (xy 34.926338 -372.512545) (xy 34.932112 -372.519702)
			(xy 34.954009 -372.54534) (xy 34.992096 -372.600979) (xy 35.023244 -372.660779) (xy 35.047006 -372.723879)
			(xy 35.063039 -372.789371) (xy 35.071112 -372.856312) (xy 35.071109 -372.923739) (xy 35.06303 -372.990679)
			(xy 35.046991 -373.05617) (xy 35.023224 -373.119268) (xy 34.99207 -373.179065) (xy 34.953978 -373.234701)
			(xy 34.932112 -373.260366) (xy 34.926306 -373.267505) (xy 34.919797 -373.2847) (xy 34.919412 -373.293894)
			(xy 34.919412 -373.451374) (xy 34.918854 -373.461493) (xy 34.911144 -373.480203) (xy 34.89688 -373.494559)
			(xy 34.878219 -373.502388) (xy 34.868104 -373.502936) (xy 34.151824 -373.502936) (xy 34.141676 -373.50246)
			(xy 34.122931 -373.494679) (xy 34.108608 -373.480299) (xy 34.100901 -373.461524) (xy 34.100516 -373.451374)
			(xy 34.100516 -373.293894) (xy 34.100105 -373.284707) (xy 34.093592 -373.267523) (xy 34.087816 -373.260366)
			(xy 34.065985 -373.234673) (xy 34.027894 -373.179043) (xy 33.996741 -373.119251) (xy 33.972974 -373.056158)
			(xy 33.956936 -372.990672) (xy 33.948857 -372.923736) (xy 33.948854 -372.856315) (xy 33.956927 -372.789379)
			(xy 33.972959 -372.723891) (xy 33.99672 -372.660796) (xy 34.027868 -372.601001) (xy 34.065953 -372.545367)
			(xy 34.087816 -372.519702) (xy 34.093596 -372.512545) (xy 34.10012 -372.495364) (xy 34.100516 -372.486174)
			(xy 34.100516 -371.993922) (xy 34.100092 -371.984736) (xy 34.093587 -371.967552) (xy 34.087816 -371.960394)
			(xy 34.065914 -371.93476) (xy 34.027826 -371.879121) (xy 33.996676 -371.819321) (xy 33.972913 -371.75622)
			(xy 33.956879 -371.690727) (xy 33.948806 -371.623785) (xy 32.846713 -371.623785) (xy 32.846925 -371.62435)
			(xy 32.862896 -371.689734) (xy 32.870939 -371.756558) (xy 32.870938 -371.823864) (xy 32.862892 -371.890687)
			(xy 32.846918 -371.95607) (xy 32.823244 -372.019075) (xy 32.79221 -372.078799) (xy 32.75426 -372.134386)
			(xy 32.732472 -372.160038) (xy 32.726673 -372.167181) (xy 32.72016 -372.184373) (xy 32.719772 -372.193566)
			(xy 32.719772 -372.351554) (xy 32.719299 -372.361721) (xy 32.711531 -372.380513) (xy 32.69716 -372.394899)
			(xy 32.678377 -372.402688) (xy 32.66821 -372.403116) (xy 31.95193 -372.403116) (xy 31.941755 -372.40271)
			(xy 31.922952 -372.394927) (xy 31.908564 -372.380535) (xy 31.900787 -372.361729) (xy 31.900368 -372.351554)
			(xy 31.900368 -372.193566) (xy 31.899959 -372.184379) (xy 31.893443 -372.167195) (xy 31.887668 -372.160038)
			(xy 31.865893 -372.134375) (xy 31.827942 -372.078791) (xy 31.796907 -372.019069) (xy 31.773232 -371.956066)
			(xy 31.757257 -371.890685) (xy 31.749211 -371.823863) (xy 31.74921 -371.756558) (xy 31.757253 -371.689736)
			(xy 31.773226 -371.624354) (xy 31.796898 -371.56135) (xy 31.827931 -371.501627) (xy 31.86588 -371.446042)
			(xy 31.887668 -371.42039) (xy 31.89346 -371.413242) (xy 31.899975 -371.396053) (xy 31.900368 -371.386862)
			(xy 31.900368 -370.89334) (xy 31.899923 -370.884157) (xy 31.893432 -370.866973) (xy 31.887668 -370.859812)
			(xy 31.865868 -370.83417) (xy 31.827917 -370.778583) (xy 31.796883 -370.718858) (xy 31.77321 -370.655852)
			(xy 31.757237 -370.590468) (xy 31.749193 -370.523644) (xy 28.471153 -370.523644) (xy 28.471153 -370.523703)
			(xy 28.463078 -370.59064) (xy 28.447043 -370.656129) (xy 28.42328 -370.719226) (xy 28.392129 -370.779021)
			(xy 28.35404 -370.834655) (xy 28.332176 -370.86032) (xy 28.326386 -370.867469) (xy 28.319868 -370.884657)
			(xy 28.319476 -370.893848) (xy 28.319476 -371.386354) (xy 28.319914 -371.395538) (xy 28.326409 -371.412722)
			(xy 28.332176 -371.419882) (xy 28.354055 -371.445535) (xy 28.392144 -371.501171) (xy 28.423296 -371.560969)
			(xy 28.446931 -371.623725) (xy 29.549038 -371.623725) (xy 29.549042 -371.556418) (xy 29.557089 -371.489593)
			(xy 29.573066 -371.424209) (xy 29.596742 -371.361203) (xy 29.627778 -371.301478) (xy 29.665731 -371.24589)
			(xy 29.68752 -371.220238) (xy 29.693328 -371.213101) (xy 29.699835 -371.195904) (xy 29.70022 -371.18671)
			(xy 29.70022 -371.028722) (xy 29.700682 -371.018554) (xy 29.708456 -370.999763) (xy 29.72283 -370.985378)
			(xy 29.741614 -370.97759) (xy 29.751782 -370.97716) (xy 30.468062 -370.97716) (xy 30.478234 -370.977596)
			(xy 30.497032 -370.985372) (xy 30.511419 -370.999755) (xy 30.519201 -371.01855) (xy 30.519624 -371.028722)
			(xy 30.519624 -371.18671) (xy 30.520024 -371.195898) (xy 30.526544 -371.213083) (xy 30.532324 -371.220238)
			(xy 30.554075 -371.24592) (xy 30.592028 -371.301502) (xy 30.623065 -371.361221) (xy 30.646741 -371.424221)
			(xy 30.662718 -371.4896) (xy 30.670766 -371.55642) (xy 30.670769 -371.623723) (xy 30.662728 -371.690543)
			(xy 30.646758 -371.755924) (xy 30.623088 -371.818927) (xy 30.592057 -371.878649) (xy 30.554111 -371.934234)
			(xy 30.532324 -371.959886) (xy 30.526511 -371.96702) (xy 30.520005 -371.984219) (xy 30.519624 -371.993414)
			(xy 30.519624 -372.486682) (xy 30.520037 -372.495869) (xy 30.526548 -372.513054) (xy 30.532324 -372.52021)
			(xy 30.554146 -372.545834) (xy 30.592096 -372.601424) (xy 30.62313 -372.661151) (xy 30.646803 -372.724159)
			(xy 30.662774 -372.789545) (xy 30.670816 -372.856371) (xy 30.670813 -372.92368) (xy 30.662765 -372.990505)
			(xy 30.646788 -373.05589) (xy 30.623109 -373.118896) (xy 30.59207 -373.17862) (xy 30.554115 -373.234206)
			(xy 30.532324 -373.259858) (xy 30.526523 -373.267) (xy 30.52001 -373.284193) (xy 30.519624 -373.293386)
			(xy 30.519624 -373.451374) (xy 30.519214 -373.461549) (xy 30.51143 -373.48035) (xy 30.49704 -373.494737)
			(xy 30.478237 -373.502516) (xy 30.468062 -373.502936) (xy 29.751782 -373.502936) (xy 29.741606 -373.50255)
			(xy 29.722806 -373.494754) (xy 29.708421 -373.480357) (xy 29.700641 -373.46155) (xy 29.70022 -373.451374)
			(xy 29.70022 -373.293386) (xy 29.699812 -373.284199) (xy 29.693297 -373.267015) (xy 29.68752 -373.259858)
			(xy 29.665767 -373.234178) (xy 29.627818 -373.178595) (xy 29.596784 -373.118875) (xy 29.57311 -373.055874)
			(xy 29.557136 -372.990496) (xy 29.549089 -372.923677) (xy 29.549086 -372.856375) (xy 29.557127 -372.789555)
			(xy 29.573095 -372.724175) (xy 29.596763 -372.661172) (xy 29.627792 -372.601449) (xy 29.665735 -372.545863)
			(xy 29.68752 -372.52021) (xy 29.69334 -372.513081) (xy 29.69984 -372.495878) (xy 29.70022 -372.486682)
			(xy 29.70022 -371.993414) (xy 29.699798 -371.984228) (xy 29.693292 -371.967044) (xy 29.68752 -371.959886)
			(xy 29.665695 -371.934264) (xy 29.627749 -371.878673) (xy 29.596718 -371.818945) (xy 29.573049 -371.755937)
			(xy 29.557079 -371.690551) (xy 29.549038 -371.623725) (xy 28.446931 -371.623725) (xy 28.44706 -371.624067)
			(xy 28.463096 -371.689558) (xy 28.471171 -371.756498) (xy 28.471169 -371.823923) (xy 28.463092 -371.890863)
			(xy 28.447054 -371.956353) (xy 28.423287 -372.01945) (xy 28.392134 -372.079247) (xy 28.354042 -372.134881)
			(xy 28.332176 -372.160546) (xy 28.326375 -372.167688) (xy 28.319864 -372.184881) (xy 28.319476 -372.194074)
			(xy 28.319476 -372.351554) (xy 28.318936 -372.361676) (xy 28.311226 -372.380393) (xy 28.296956 -372.39475)
			(xy 28.278287 -372.402574) (xy 28.268168 -372.403116) (xy 27.551888 -372.403116) (xy 27.541781 -372.402625)
			(xy 27.523105 -372.394886) (xy 27.508811 -372.380591) (xy 27.501074 -372.361916) (xy 27.50058 -372.351808)
			(xy 27.50058 -372.194074) (xy 27.500187 -372.184885) (xy 27.493662 -372.167701) (xy 27.48788 -372.160546)
			(xy 27.46603 -372.134869) (xy 27.427943 -372.079236) (xy 27.396792 -372.019441) (xy 27.373028 -371.956346)
			(xy 27.356993 -371.890858) (xy 27.348916 -371.823922) (xy 27.348915 -371.756499) (xy 27.356989 -371.689562)
			(xy 27.373022 -371.624074) (xy 27.396784 -371.560978) (xy 27.427932 -371.501182) (xy 27.466018 -371.445548)
			(xy 27.48788 -371.419882) (xy 27.493664 -371.412728) (xy 27.500187 -371.395544) (xy 27.50058 -371.386354)
			(xy 27.50058 -370.893848) (xy 27.500151 -370.884663) (xy 27.493651 -370.867478) (xy 27.48788 -370.86032)
			(xy 27.466005 -370.834664) (xy 27.427918 -370.779028) (xy 27.396769 -370.71923) (xy 27.373006 -370.656132)
			(xy 27.356972 -370.590642) (xy 27.348898 -370.523703) (xy 0.509016 -370.523703) (xy 0.509016 -372.100847)
			(xy 8.642336 -372.100847) (xy 8.642336 -372.040913) (xy 8.650159 -371.981491) (xy 8.665671 -371.923598)
			(xy 8.688607 -371.868226) (xy 8.718575 -371.81632) (xy 8.755061 -371.768771) (xy 8.797441 -371.726391)
			(xy 8.84499 -371.689905) (xy 8.896896 -371.659937) (xy 8.952268 -371.637001) (xy 9.010161 -371.621489)
			(xy 9.069583 -371.613666) (xy 9.09955 -371.613176) (xy 9.96315 -371.613176) (xy 9.993118 -371.613658)
			(xy 10.052541 -371.621481) (xy 10.110435 -371.636994) (xy 10.165808 -371.65993) (xy 10.217714 -371.689898)
			(xy 10.265264 -371.726385) (xy 10.307645 -371.768766) (xy 10.344132 -371.816316) (xy 10.3741 -371.868222)
			(xy 10.397036 -371.923595) (xy 10.412549 -371.981489) (xy 10.420372 -372.040912) (xy 10.420372 -372.100848)
			(xy 10.412549 -372.160271) (xy 10.397036 -372.218165) (xy 10.3741 -372.273538) (xy 10.344132 -372.325444)
			(xy 10.307645 -372.372994) (xy 10.265264 -372.415375) (xy 10.217714 -372.451862) (xy 10.165808 -372.48183)
			(xy 10.110435 -372.504766) (xy 10.052541 -372.520279) (xy 9.993118 -372.528102) (xy 9.96315 -372.528592)
			(xy 9.09955 -372.528592) (xy 9.069583 -372.528094) (xy 9.010161 -372.520271) (xy 8.952268 -372.504759)
			(xy 8.896896 -372.481823) (xy 8.84499 -372.451855) (xy 8.797441 -372.415369) (xy 8.755061 -372.372989)
			(xy 8.718575 -372.32544) (xy 8.688607 -372.273534) (xy 8.665671 -372.218162) (xy 8.650159 -372.160269)
			(xy 8.642336 -372.100847) (xy 0.509016 -372.100847) (xy 0.509016 -374.423871) (xy 27.348897 -374.423871)
			(xy 27.348897 -374.356446) (xy 27.356974 -374.289508) (xy 27.37301 -374.224019) (xy 27.396774 -374.160922)
			(xy 27.427926 -374.101125) (xy 27.466016 -374.045491) (xy 27.48788 -374.019826) (xy 27.493688 -374.012689)
			(xy 27.500197 -373.995492) (xy 27.50058 -373.986298) (xy 27.50058 -373.828818) (xy 27.501042 -373.818688)
			(xy 27.508772 -373.799959) (xy 27.523066 -373.785601) (xy 27.54176 -373.777788) (xy 27.551888 -373.777256)
			(xy 28.268168 -373.777256) (xy 28.278269 -373.77781) (xy 28.296938 -373.785529) (xy 28.311233 -373.799804)
			(xy 28.318977 -373.818463) (xy 28.319476 -373.828564) (xy 28.319476 -373.986298) (xy 28.319892 -373.995484)
			(xy 28.326402 -374.012669) (xy 28.332176 -374.019826) (xy 28.354038 -374.045493) (xy 28.392127 -374.101127)
			(xy 28.423278 -374.160923) (xy 28.447043 -374.22402) (xy 28.463078 -374.289509) (xy 28.471154 -374.356447)
			(xy 28.471155 -374.423823) (xy 31.749171 -374.423823) (xy 31.749175 -374.356514) (xy 31.757224 -374.289688)
			(xy 31.773202 -374.224303) (xy 31.796881 -374.161297) (xy 31.827921 -374.101572) (xy 31.865877 -374.045986)
			(xy 31.887668 -374.020334) (xy 31.893483 -374.013202) (xy 31.899985 -373.996001) (xy 31.900368 -373.986806)
			(xy 31.900368 -373.828818) (xy 31.900779 -373.818644) (xy 31.908564 -373.799844) (xy 31.922954 -373.785457)
			(xy 31.941756 -373.777677) (xy 31.95193 -373.777256) (xy 32.66821 -373.777256) (xy 32.678384 -373.777656)
			(xy 32.697183 -373.785448) (xy 32.711568 -373.799841) (xy 32.719349 -373.818643) (xy 32.719772 -373.828818)
			(xy 32.719772 -373.986806) (xy 32.720185 -373.995993) (xy 32.726697 -374.013177) (xy 32.732472 -374.020334)
			(xy 32.754218 -374.04602) (xy 32.792167 -374.101602) (xy 32.823202 -374.161321) (xy 32.846876 -374.224321)
			(xy 32.862852 -374.289699) (xy 32.870899 -374.356518) (xy 32.870903 -374.423819) (xy 32.870895 -374.423882)
			(xy 36.148964 -374.423882) (xy 36.148968 -374.356455) (xy 36.157048 -374.289515) (xy 36.173087 -374.224024)
			(xy 36.196854 -374.160925) (xy 36.228007 -374.101128) (xy 36.266099 -374.045492) (xy 36.287964 -374.019826)
			(xy 36.293782 -374.012697) (xy 36.300282 -373.995494) (xy 36.300664 -373.986298) (xy 36.300664 -373.828818)
			(xy 36.301142 -373.818689) (xy 36.308868 -373.799964) (xy 36.323158 -373.785606) (xy 36.341846 -373.777791)
			(xy 36.351972 -373.777256) (xy 37.068252 -373.777256) (xy 37.078398 -373.77776) (xy 37.09714 -373.785532)
			(xy 37.111464 -373.799903) (xy 37.119173 -373.818671) (xy 37.11956 -373.828818) (xy 37.11956 -373.986298)
			(xy 37.11998 -373.995484) (xy 37.126488 -374.012668) (xy 37.13226 -374.019826) (xy 37.154084 -374.045525)
			(xy 37.192177 -374.101153) (xy 37.223331 -374.160945) (xy 37.2471 -374.224037) (xy 37.263139 -374.289523)
			(xy 37.271219 -374.356458) (xy 37.271223 -374.423879) (xy 37.271223 -374.423882) (xy 40.548731 -374.423882)
			(xy 40.548735 -374.356454) (xy 40.556815 -374.289512) (xy 40.572857 -374.22402) (xy 40.596628 -374.160921)
			(xy 40.627787 -374.101124) (xy 40.665884 -374.04549) (xy 40.687752 -374.019826) (xy 40.693569 -374.012695)
			(xy 40.70007 -373.995494) (xy 40.700452 -373.986298) (xy 40.700452 -373.828818) (xy 40.700942 -373.818691)
			(xy 40.708666 -373.799968) (xy 40.722951 -373.785611) (xy 40.741636 -373.777793) (xy 40.75176 -373.777256)
			(xy 41.46804 -373.777256) (xy 41.478191 -373.777688) (xy 41.496936 -373.785489) (xy 41.511256 -373.799881)
			(xy 41.518963 -373.818665) (xy 41.519348 -373.828818) (xy 41.519348 -373.986298) (xy 41.519771 -373.995484)
			(xy 41.526277 -374.012667) (xy 41.532048 -374.019826) (xy 41.553873 -374.045524) (xy 41.591966 -374.101153)
			(xy 41.623121 -374.160944) (xy 41.64689 -374.224037) (xy 41.66293 -374.289522) (xy 41.67101 -374.356458)
			(xy 41.671014 -374.423823) (xy 44.94905 -374.423823) (xy 44.949054 -374.356514) (xy 44.957102 -374.289689)
			(xy 44.97308 -374.224304) (xy 44.996757 -374.161298) (xy 45.027796 -374.101573) (xy 45.06575 -374.045986)
			(xy 45.08754 -374.020334) (xy 45.093352 -374.0132) (xy 45.099857 -373.996001) (xy 45.10024 -373.986806)
			(xy 45.10024 -373.828818) (xy 45.100678 -373.818647) (xy 45.108458 -373.799853) (xy 45.122839 -373.785467)
			(xy 45.141631 -373.777682) (xy 45.151802 -373.777256) (xy 45.868082 -373.777256) (xy 45.878255 -373.777679)
			(xy 45.897053 -373.785461) (xy 45.911439 -373.799847) (xy 45.919221 -373.818645) (xy 45.919644 -373.828818)
			(xy 45.919644 -373.986806) (xy 45.920064 -373.995992) (xy 45.926572 -374.013176) (xy 45.932344 -374.020334)
			(xy 45.954091 -374.04602) (xy 45.992042 -374.101601) (xy 46.023078 -374.16132) (xy 46.046754 -374.22432)
			(xy 46.06273 -374.289698) (xy 46.070778 -374.356517) (xy 46.070782 -374.423819) (xy 46.070774 -374.423882)
			(xy 71.348786 -374.423882) (xy 71.348789 -374.356455) (xy 71.356869 -374.289514) (xy 71.372909 -374.224023)
			(xy 71.396677 -374.160924) (xy 71.427833 -374.101127) (xy 71.465926 -374.045491) (xy 71.487792 -374.019826)
			(xy 71.493602 -374.01269) (xy 71.500109 -373.995492) (xy 71.500492 -373.986298) (xy 71.500492 -373.828818)
			(xy 71.50104 -373.818698) (xy 71.508753 -373.799987) (xy 71.52302 -373.785631) (xy 71.541684 -373.777803)
			(xy 71.5518 -373.777256) (xy 72.26808 -373.777256) (xy 72.278227 -373.777737) (xy 72.296971 -373.785518)
			(xy 72.311293 -373.799896) (xy 72.319002 -373.818669) (xy 72.319388 -373.828818) (xy 72.319388 -373.986298)
			(xy 72.319802 -373.995485) (xy 72.326313 -374.012669) (xy 72.332088 -374.019826) (xy 72.353911 -374.045525)
			(xy 72.392002 -374.101154) (xy 72.423155 -374.160946) (xy 72.446922 -374.224038) (xy 72.462961 -374.289523)
			(xy 72.47104 -374.356458) (xy 72.471044 -374.423823) (xy 75.749081 -374.423823) (xy 75.749084 -374.356514)
			(xy 75.757133 -374.289688) (xy 75.773112 -374.224303) (xy 75.796791 -374.161296) (xy 75.827832 -374.101572)
			(xy 75.865788 -374.045985) (xy 75.88758 -374.020334) (xy 75.893385 -374.013194) (xy 75.899895 -373.996)
			(xy 75.90028 -373.986806) (xy 75.90028 -373.828818) (xy 75.900679 -373.818642) (xy 75.908466 -373.79984)
			(xy 75.92286 -373.785453) (xy 75.941666 -373.777675) (xy 75.951842 -373.777256) (xy 76.668122 -373.777256)
			(xy 76.678283 -373.777716) (xy 76.697057 -373.785501) (xy 76.711422 -373.799877) (xy 76.719192 -373.818656)
			(xy 76.719684 -373.828818) (xy 76.719684 -373.986806) (xy 76.720095 -373.995993) (xy 76.726608 -374.013177)
			(xy 76.732384 -374.020334) (xy 76.754129 -374.046021) (xy 76.792078 -374.101603) (xy 76.823112 -374.161322)
			(xy 76.846786 -374.224322) (xy 76.862761 -374.289699) (xy 76.870808 -374.356518) (xy 76.870812 -374.423819)
			(xy 76.870804 -374.423882) (xy 80.148873 -374.423882) (xy 80.148877 -374.356455) (xy 80.156957 -374.289515)
			(xy 80.172996 -374.224023) (xy 80.196764 -374.160925) (xy 80.227918 -374.101127) (xy 80.26601 -374.045492)
			(xy 80.287876 -374.019826) (xy 80.293684 -374.012689) (xy 80.300193 -373.995492) (xy 80.300576 -373.986298)
			(xy 80.300576 -373.828818) (xy 80.301042 -373.818688) (xy 80.308771 -373.79996) (xy 80.323064 -373.785602)
			(xy 80.341756 -373.777789) (xy 80.351884 -373.777256) (xy 81.068164 -373.777256) (xy 81.078265 -373.777814)
			(xy 81.096934 -373.785531) (xy 81.111228 -373.799806) (xy 81.118972 -373.818464) (xy 81.119472 -373.828564)
			(xy 81.119472 -373.986298) (xy 81.119889 -373.995484) (xy 81.126399 -374.012668) (xy 81.132172 -374.019826)
			(xy 81.153996 -374.045525) (xy 81.192087 -374.101154) (xy 81.223242 -374.160945) (xy 81.247009 -374.224038)
			(xy 81.263049 -374.289523) (xy 81.271128 -374.356458) (xy 81.271132 -374.423879) (xy 81.271132 -374.423882)
			(xy 84.548664 -374.423882) (xy 84.548668 -374.356455) (xy 84.556748 -374.289515) (xy 84.572787 -374.224024)
			(xy 84.596554 -374.160925) (xy 84.627707 -374.101128) (xy 84.665799 -374.045492) (xy 84.687664 -374.019826)
			(xy 84.693482 -374.012697) (xy 84.699982 -373.995494) (xy 84.700364 -373.986298) (xy 84.700364 -373.828818)
			(xy 84.700842 -373.818689) (xy 84.708568 -373.799964) (xy 84.722858 -373.785606) (xy 84.741546 -373.777791)
			(xy 84.751672 -373.777256) (xy 85.467952 -373.777256) (xy 85.478066 -373.777754) (xy 85.49676 -373.785478)
			(xy 85.511074 -373.799769) (xy 85.518829 -373.818451) (xy 85.51926 -373.828564) (xy 85.51926 -373.986298)
			(xy 85.51968 -373.995484) (xy 85.526188 -374.012668) (xy 85.53196 -374.019826) (xy 85.553784 -374.045525)
			(xy 85.591877 -374.101153) (xy 85.623031 -374.160945) (xy 85.6468 -374.224037) (xy 85.662839 -374.289523)
			(xy 85.670919 -374.356458) (xy 85.670923 -374.423822) (xy 115.349223 -374.423822) (xy 115.349227 -374.356515)
			(xy 115.357275 -374.28969) (xy 115.373251 -374.224306) (xy 115.396927 -374.1613) (xy 115.427963 -374.101574)
			(xy 115.465915 -374.045987) (xy 115.487704 -374.020334) (xy 115.493512 -374.013197) (xy 115.50002 -373.996)
			(xy 115.500404 -373.986806) (xy 115.500404 -373.828818) (xy 115.500947 -373.818666) (xy 115.508709 -373.799903)
			(xy 115.52306 -373.785539) (xy 115.541814 -373.777757) (xy 115.551966 -373.777256) (xy 116.268246 -373.777256)
			(xy 116.278409 -373.777696) (xy 116.297183 -373.785489) (xy 116.311547 -373.799871) (xy 116.319316 -373.818654)
			(xy 116.319808 -373.828818) (xy 116.319808 -373.986806) (xy 116.320214 -373.995994) (xy 116.32673 -374.013178)
			(xy 116.332508 -374.020334) (xy 116.354256 -374.046019) (xy 116.39221 -374.1016) (xy 116.423248 -374.161318)
			(xy 116.446925 -374.224319) (xy 116.462903 -374.289697) (xy 116.470951 -374.356517) (xy 116.470955 -374.42382)
			(xy 116.470948 -374.423882) (xy 119.748992 -374.423882) (xy 119.748995 -374.356455) (xy 119.757075 -374.289514)
			(xy 119.773115 -374.224022) (xy 119.796884 -374.160924) (xy 119.82804 -374.101126) (xy 119.866134 -374.045491)
			(xy 119.888 -374.019826) (xy 119.89381 -374.012691) (xy 119.900317 -373.995493) (xy 119.9007 -373.986298)
			(xy 119.9007 -373.828818) (xy 119.90124 -373.818697) (xy 119.908955 -373.799984) (xy 119.923224 -373.785629)
			(xy 119.94189 -373.777802) (xy 119.952008 -373.777256) (xy 120.668288 -373.777256) (xy 120.678436 -373.777731)
			(xy 120.69718 -373.785514) (xy 120.711502 -373.799894) (xy 120.71921 -373.818669) (xy 120.719596 -373.828818)
			(xy 120.719596 -373.986298) (xy 120.720008 -373.995485) (xy 120.726521 -374.012669) (xy 120.732296 -374.019826)
			(xy 120.754119 -374.045525) (xy 120.792209 -374.101155) (xy 120.823362 -374.160946) (xy 120.847129 -374.224039)
			(xy 120.863167 -374.289524) (xy 120.871246 -374.356458) (xy 120.87125 -374.423823) (xy 124.149287 -374.423823)
			(xy 124.149291 -374.356514) (xy 124.15734 -374.289688) (xy 124.173319 -374.224302) (xy 124.196998 -374.161296)
			(xy 124.228039 -374.101572) (xy 124.265996 -374.045986) (xy 124.287788 -374.020334) (xy 124.293594 -374.013195)
			(xy 124.300103 -373.996) (xy 124.300488 -373.986806) (xy 124.300488 -373.828818) (xy 124.30088 -373.818641)
			(xy 124.308668 -373.799837) (xy 124.323064 -373.78545) (xy 124.341873 -373.777673) (xy 124.35205 -373.777256)
			(xy 125.06833 -373.777256) (xy 125.078492 -373.777709) (xy 125.097265 -373.785497) (xy 125.11163 -373.799875)
			(xy 125.1194 -373.818656) (xy 125.119892 -373.828818) (xy 125.119892 -373.986806) (xy 125.120301 -373.995993)
			(xy 125.126816 -374.013177) (xy 125.132592 -374.020334) (xy 125.154338 -374.04602) (xy 125.192286 -374.101603)
			(xy 125.223319 -374.161322) (xy 125.246993 -374.224322) (xy 125.262968 -374.2897) (xy 125.271015 -374.356518)
			(xy 125.271019 -374.423819) (xy 125.271019 -374.423823) (xy 128.549078 -374.423823) (xy 128.549081 -374.356514)
			(xy 128.55713 -374.289688) (xy 128.573109 -374.224303) (xy 128.596788 -374.161296) (xy 128.627828 -374.101572)
			(xy 128.665784 -374.045985) (xy 128.687576 -374.020334) (xy 128.69338 -374.013194) (xy 128.699891 -373.996)
			(xy 128.700276 -373.986806) (xy 128.700276 -373.828818) (xy 128.700679 -373.818643) (xy 128.708465 -373.799841)
			(xy 128.722858 -373.785454) (xy 128.741663 -373.777675) (xy 128.751838 -373.777256) (xy 129.468118 -373.777256)
			(xy 129.478279 -373.777719) (xy 129.497052 -373.785503) (xy 129.511418 -373.799878) (xy 129.519188 -373.818656)
			(xy 129.51968 -373.828818) (xy 129.51968 -373.986806) (xy 129.520092 -373.995993) (xy 129.526605 -374.013177)
			(xy 129.53238 -374.020334) (xy 129.554126 -374.046021) (xy 129.592074 -374.101603) (xy 129.623108 -374.161322)
			(xy 129.646783 -374.224321) (xy 129.662758 -374.289699) (xy 129.670805 -374.356518) (xy 129.670809 -374.423819)
			(xy 129.670809 -374.423822) (xy 159.349132 -374.423822) (xy 159.349136 -374.356514) (xy 159.357184 -374.289689)
			(xy 159.373161 -374.224305) (xy 159.396837 -374.161299) (xy 159.427874 -374.101574) (xy 159.465826 -374.045986)
			(xy 159.487616 -374.020334) (xy 159.493425 -374.013198) (xy 159.499932 -373.996) (xy 159.500316 -373.986806)
			(xy 159.500316 -373.828818) (xy 159.500847 -373.818664) (xy 159.508612 -373.799899) (xy 159.522966 -373.785534)
			(xy 159.541724 -373.777755) (xy 159.551878 -373.777256) (xy 160.268158 -373.777256) (xy 160.278329 -373.777699)
			(xy 160.297126 -373.785473) (xy 160.311513 -373.799854) (xy 160.319297 -373.818647) (xy 160.31972 -373.828818)
			(xy 160.31972 -373.986806) (xy 160.320123 -373.995994) (xy 160.326641 -374.013179) (xy 160.33242 -374.020334)
			(xy 160.354168 -374.04602) (xy 160.39212 -374.1016) (xy 160.423158 -374.161319) (xy 160.446835 -374.224319)
			(xy 160.462812 -374.289698) (xy 160.47086 -374.356517) (xy 160.470864 -374.42382) (xy 160.470857 -374.423882)
			(xy 163.748901 -374.423882) (xy 163.748904 -374.356455) (xy 163.756985 -374.289514) (xy 163.773025 -374.224022)
			(xy 163.796794 -374.160923) (xy 163.827951 -374.101126) (xy 163.866045 -374.045491) (xy 163.887912 -374.019826)
			(xy 163.893724 -374.012692) (xy 163.900229 -373.995493) (xy 163.900612 -373.986298) (xy 163.900612 -373.828818)
			(xy 163.90114 -373.818696) (xy 163.908857 -373.79998) (xy 163.92313 -373.785624) (xy 163.941801 -373.7778)
			(xy 163.95192 -373.777256) (xy 164.6682 -373.777256) (xy 164.678349 -373.777721) (xy 164.697092 -373.785508)
			(xy 164.711414 -373.799891) (xy 164.719122 -373.818668) (xy 164.719508 -373.828818) (xy 164.719508 -373.986298)
			(xy 164.719917 -373.995485) (xy 164.726431 -374.01267) (xy 164.732208 -374.019826) (xy 164.75403 -374.045525)
			(xy 164.79212 -374.101155) (xy 164.823272 -374.160947) (xy 164.847038 -374.224039) (xy 164.863076 -374.289524)
			(xy 164.871155 -374.356458) (xy 164.871159 -374.423822) (xy 168.14922 -374.423822) (xy 168.149224 -374.356515)
			(xy 168.157272 -374.28969) (xy 168.173248 -374.224306) (xy 168.196924 -374.1613) (xy 168.22796 -374.101575)
			(xy 168.265911 -374.045987) (xy 168.2877 -374.020334) (xy 168.293507 -374.013196) (xy 168.300015 -373.996)
			(xy 168.3004 -373.986806) (xy 168.3004 -373.828818) (xy 168.300947 -373.818666) (xy 168.308709 -373.799905)
			(xy 168.323058 -373.78554) (xy 168.341811 -373.777758) (xy 168.351962 -373.777256) (xy 169.068242 -373.777256)
			(xy 169.078405 -373.777699) (xy 169.097178 -373.785491) (xy 169.111543 -373.799872) (xy 169.119312 -373.818655)
			(xy 169.119804 -373.828818) (xy 169.119804 -373.986806) (xy 169.120211 -373.995994) (xy 169.126727 -374.013178)
			(xy 169.132504 -374.020334) (xy 169.154249 -374.046021) (xy 169.192196 -374.101603) (xy 169.223229 -374.161322)
			(xy 169.246902 -374.224322) (xy 169.262877 -374.2897) (xy 169.270924 -374.356518) (xy 169.270928 -374.423819)
			(xy 169.270928 -374.423823) (xy 172.548987 -374.423823) (xy 172.548991 -374.356514) (xy 172.55704 -374.289688)
			(xy 172.573019 -374.224302) (xy 172.596698 -374.161296) (xy 172.627739 -374.101572) (xy 172.665696 -374.045986)
			(xy 172.687488 -374.020334) (xy 172.693294 -374.013195) (xy 172.699803 -373.996) (xy 172.700188 -373.986806)
			(xy 172.700188 -373.828818) (xy 172.70058 -373.818641) (xy 172.708368 -373.799837) (xy 172.722764 -373.78545)
			(xy 172.741573 -373.777673) (xy 172.75175 -373.777256) (xy 173.46803 -373.777256) (xy 173.478192 -373.777709)
			(xy 173.496965 -373.785497) (xy 173.51133 -373.799875) (xy 173.5191 -373.818656) (xy 173.519592 -373.828818)
			(xy 173.519592 -373.986806) (xy 173.520001 -373.995993) (xy 173.526516 -374.013177) (xy 173.532292 -374.020334)
			(xy 173.554038 -374.04602) (xy 173.591986 -374.101603) (xy 173.623019 -374.161322) (xy 173.646693 -374.224322)
			(xy 173.662668 -374.2897) (xy 173.670715 -374.356518) (xy 173.670719 -374.423819) (xy 173.662679 -374.490638)
			(xy 173.646712 -374.556018) (xy 173.623045 -374.61902) (xy 173.592018 -374.678743) (xy 173.554076 -374.73433)
			(xy 173.532292 -374.759982) (xy 173.526477 -374.767114) (xy 173.519974 -374.784315) (xy 173.519592 -374.79351)
			(xy 173.519592 -375.286778) (xy 173.520015 -375.295964) (xy 173.52652 -375.313148) (xy 173.532292 -375.320306)
			(xy 173.554108 -375.345934) (xy 173.592054 -375.401525) (xy 173.623084 -375.461252) (xy 173.646754 -375.52426)
			(xy 173.662724 -375.589644) (xy 173.670765 -375.656469) (xy 173.670763 -375.723776) (xy 173.662716 -375.7906)
			(xy 173.646741 -375.855984) (xy 173.623066 -375.918989) (xy 173.592031 -375.978714) (xy 173.554081 -376.034301)
			(xy 173.532292 -376.059954) (xy 173.526489 -376.067095) (xy 173.519978 -376.084289) (xy 173.519592 -376.093482)
			(xy 173.519592 -376.25147) (xy 173.519043 -376.261622) (xy 173.511284 -376.280385) (xy 173.496935 -376.29475)
			(xy 173.478182 -376.302531) (xy 173.46803 -376.303032) (xy 172.75175 -376.303032) (xy 172.741578 -376.302595)
			(xy 172.722779 -376.29482) (xy 172.708391 -376.280438) (xy 172.700609 -376.261642) (xy 172.700188 -376.25147)
			(xy 172.700188 -376.093482) (xy 172.699789 -376.084294) (xy 172.693268 -376.067109) (xy 172.687488 -376.059954)
			(xy 172.665728 -376.034278) (xy 172.627775 -375.978696) (xy 172.596738 -375.918976) (xy 172.573061 -375.855975)
			(xy 172.557085 -375.790595) (xy 172.549038 -375.723774) (xy 172.549035 -375.656471) (xy 172.557077 -375.589649)
			(xy 172.573048 -375.524268) (xy 172.59672 -375.461265) (xy 172.627752 -375.401542) (xy 172.665701 -375.345957)
			(xy 172.687488 -375.320306) (xy 172.693263 -375.313145) (xy 172.699791 -375.295967) (xy 172.700188 -375.286778)
			(xy 172.700188 -374.79351) (xy 172.699776 -374.784323) (xy 172.693264 -374.767138) (xy 172.687488 -374.759982)
			(xy 172.665658 -374.734364) (xy 172.627707 -374.678774) (xy 172.596673 -374.619046) (xy 172.573 -374.556037)
			(xy 172.557029 -374.49065) (xy 172.548987 -374.423823) (xy 169.270928 -374.423823) (xy 169.262888 -374.490638)
			(xy 169.246921 -374.556017) (xy 169.223255 -374.61902) (xy 169.192229 -374.678743) (xy 169.154288 -374.734329)
			(xy 169.132504 -374.759982) (xy 169.126691 -374.767115) (xy 169.120186 -374.784315) (xy 169.119804 -374.79351)
			(xy 169.119804 -375.286778) (xy 169.120224 -375.295964) (xy 169.126731 -375.313149) (xy 169.132504 -375.320306)
			(xy 169.15432 -375.345935) (xy 169.192265 -375.401525) (xy 169.223295 -375.461253) (xy 169.246964 -375.52426)
			(xy 169.262933 -375.589645) (xy 169.270974 -375.656469) (xy 169.270972 -375.723776) (xy 169.262925 -375.7906)
			(xy 169.24695 -375.855983) (xy 169.223276 -375.918989) (xy 169.192242 -375.978713) (xy 169.154292 -376.034301)
			(xy 169.132504 -376.059954) (xy 169.126702 -376.067096) (xy 169.120191 -376.084289) (xy 169.119804 -376.093482)
			(xy 169.119804 -376.25147) (xy 169.119243 -376.261621) (xy 169.111487 -376.280381) (xy 169.097142 -376.294746)
			(xy 169.078392 -376.302529) (xy 169.068242 -376.303032) (xy 168.351962 -376.303032) (xy 168.341798 -376.302597)
			(xy 168.323022 -376.294804) (xy 168.308657 -376.280421) (xy 168.30089 -376.261635) (xy 168.3004 -376.25147)
			(xy 168.3004 -376.093482) (xy 168.299998 -376.084294) (xy 168.293479 -376.06711) (xy 168.2877 -376.059954)
			(xy 168.265943 -376.034277) (xy 168.227996 -375.978693) (xy 168.196963 -375.918973) (xy 168.173291 -375.855972)
			(xy 168.157317 -375.790593) (xy 168.149271 -375.723774) (xy 168.149268 -375.656472) (xy 168.157309 -375.589652)
			(xy 168.173277 -375.524272) (xy 168.196945 -375.461269) (xy 168.227973 -375.401546) (xy 168.265915 -375.345959)
			(xy 168.2877 -375.320306) (xy 168.293477 -375.313147) (xy 168.300003 -375.295967) (xy 168.3004 -375.286778)
			(xy 168.3004 -374.79351) (xy 168.299985 -374.784323) (xy 168.293475 -374.767139) (xy 168.2877 -374.759982)
			(xy 168.265872 -374.734363) (xy 168.227927 -374.678771) (xy 168.196898 -374.619043) (xy 168.173229 -374.556034)
			(xy 168.15726 -374.490648) (xy 168.14922 -374.423822) (xy 164.871159 -374.423822) (xy 164.871159 -374.423879)
			(xy 164.863088 -374.490814) (xy 164.847057 -374.5563) (xy 164.823298 -374.619396) (xy 164.792152 -374.679191)
			(xy 164.754069 -374.734825) (xy 164.732208 -374.76049) (xy 164.726392 -374.767621) (xy 164.719889 -374.784822)
			(xy 164.719508 -374.794018) (xy 164.719508 -375.28627) (xy 164.719931 -375.295456) (xy 164.726435 -375.31264)
			(xy 164.732208 -375.319798) (xy 164.754101 -375.345439) (xy 164.792188 -375.401077) (xy 164.823337 -375.460877)
			(xy 164.8471 -375.523977) (xy 164.863133 -375.589469) (xy 164.871206 -375.65641) (xy 164.871203 -375.723835)
			(xy 164.863125 -375.790776) (xy 164.847086 -375.856266) (xy 164.823319 -375.919364) (xy 164.792165 -375.979161)
			(xy 164.754073 -376.034797) (xy 164.732208 -376.060462) (xy 164.726404 -376.067602) (xy 164.719893 -376.084796)
			(xy 164.719508 -376.09399) (xy 164.719508 -376.25147) (xy 164.71895 -376.261589) (xy 164.711241 -376.2803)
			(xy 164.696977 -376.294656) (xy 164.678316 -376.302485) (xy 164.6682 -376.303032) (xy 163.95192 -376.303032)
			(xy 163.941771 -376.302563) (xy 163.923025 -376.29478) (xy 163.908702 -376.280398) (xy 163.900996 -376.26162)
			(xy 163.900612 -376.25147) (xy 163.900612 -376.09399) (xy 163.900204 -376.084803) (xy 163.893689 -376.067618)
			(xy 163.887912 -376.060462) (xy 163.866077 -376.034773) (xy 163.827987 -375.979142) (xy 163.796834 -375.919349)
			(xy 163.773068 -375.856255) (xy 163.75703 -375.790769) (xy 163.748951 -375.723833) (xy 163.748949 -375.656412)
			(xy 163.757022 -375.589475) (xy 163.773054 -375.523988) (xy 163.796816 -375.460892) (xy 163.827963 -375.401097)
			(xy 163.866049 -375.345463) (xy 163.887912 -375.319798) (xy 163.893693 -375.312642) (xy 163.900217 -375.29546)
			(xy 163.900612 -375.28627) (xy 163.900612 -374.794018) (xy 163.90019 -374.784832) (xy 163.893684 -374.767648)
			(xy 163.887912 -374.76049) (xy 163.866006 -374.734859) (xy 163.827918 -374.67922) (xy 163.796769 -374.619419)
			(xy 163.773006 -374.556318) (xy 163.756973 -374.490824) (xy 163.748901 -374.423882) (xy 160.470857 -374.423882)
			(xy 160.462823 -374.49064) (xy 160.446853 -374.556021) (xy 160.423184 -374.619023) (xy 160.392153 -374.678745)
			(xy 160.354206 -374.73433) (xy 160.33242 -374.759982) (xy 160.326608 -374.767117) (xy 160.320102 -374.784315)
			(xy 160.31972 -374.79351) (xy 160.31972 -375.286778) (xy 160.320136 -375.295965) (xy 160.326645 -375.313149)
			(xy 160.33242 -375.320306) (xy 160.354238 -375.345933) (xy 160.392189 -375.401522) (xy 160.423223 -375.461249)
			(xy 160.446896 -375.524257) (xy 160.462868 -375.589643) (xy 160.470911 -375.656468) (xy 160.470908 -375.723777)
			(xy 160.46286 -375.790602) (xy 160.446883 -375.855986) (xy 160.423205 -375.918992) (xy 160.392166 -375.978716)
			(xy 160.354211 -376.034302) (xy 160.33242 -376.059954) (xy 160.32662 -376.067097) (xy 160.320107 -376.084289)
			(xy 160.31972 -376.093482) (xy 160.31972 -376.25147) (xy 160.31931 -376.261645) (xy 160.311528 -376.280447)
			(xy 160.297137 -376.294834) (xy 160.278333 -376.302613) (xy 160.268158 -376.303032) (xy 159.551878 -376.303032)
			(xy 159.541701 -376.302653) (xy 159.5229 -376.294855) (xy 159.508515 -376.280456) (xy 159.500737 -376.261647)
			(xy 159.500316 -376.25147) (xy 159.500316 -376.093482) (xy 159.499911 -376.084294) (xy 159.493393 -376.06711)
			(xy 159.487616 -376.059954) (xy 159.465858 -376.034277) (xy 159.42791 -375.978694) (xy 159.396877 -375.918973)
			(xy 159.373203 -375.855972) (xy 159.357229 -375.790593) (xy 159.349183 -375.723774) (xy 159.34918 -375.656471)
			(xy 159.357221 -375.589651) (xy 159.37319 -375.524271) (xy 159.396858 -375.461268) (xy 159.427887 -375.401545)
			(xy 159.465831 -375.345958) (xy 159.487616 -375.320306) (xy 159.493394 -375.313148) (xy 159.499919 -375.295967)
			(xy 159.500316 -375.286778) (xy 159.500316 -374.79351) (xy 159.499897 -374.784324) (xy 159.493389 -374.76714)
			(xy 159.487616 -374.759982) (xy 159.465788 -374.734364) (xy 159.427842 -374.678772) (xy 159.396811 -374.619043)
			(xy 159.373142 -374.556034) (xy 159.357173 -374.490648) (xy 159.349132 -374.423822) (xy 129.670809 -374.423822)
			(xy 129.662769 -374.490638) (xy 129.646801 -374.556018) (xy 129.623134 -374.619021) (xy 129.592107 -374.678743)
			(xy 129.554164 -374.734329) (xy 129.53238 -374.759982) (xy 129.526564 -374.767113) (xy 129.520062 -374.784315)
			(xy 129.51968 -374.79351) (xy 129.51968 -375.286778) (xy 129.520105 -375.295963) (xy 129.526609 -375.313148)
			(xy 129.53238 -375.320306) (xy 129.554197 -375.345934) (xy 129.592143 -375.401524) (xy 129.623174 -375.461252)
			(xy 129.646845 -375.524259) (xy 129.662815 -375.589644) (xy 129.670856 -375.656469) (xy 129.670854 -375.723776)
			(xy 129.662807 -375.7906) (xy 129.646831 -375.855984) (xy 129.623156 -375.91899) (xy 129.59212 -375.978714)
			(xy 129.554169 -376.034302) (xy 129.53238 -376.059954) (xy 129.526576 -376.067094) (xy 129.520066 -376.084288)
			(xy 129.51968 -376.093482) (xy 129.51968 -376.25147) (xy 129.519212 -376.261637) (xy 129.51144 -376.280428)
			(xy 129.497068 -376.294813) (xy 129.478285 -376.302602) (xy 129.468118 -376.303032) (xy 128.751838 -376.303032)
			(xy 128.741665 -376.302604) (xy 128.722866 -376.294826) (xy 128.708478 -376.280441) (xy 128.700697 -376.261643)
			(xy 128.700276 -376.25147) (xy 128.700276 -376.093482) (xy 128.69988 -376.084293) (xy 128.693357 -376.067109)
			(xy 128.687576 -376.059954) (xy 128.665817 -376.034278) (xy 128.627865 -375.978696) (xy 128.596828 -375.918976)
			(xy 128.573152 -375.855974) (xy 128.557176 -375.790595) (xy 128.549129 -375.723774) (xy 128.549126 -375.656471)
			(xy 128.557168 -375.58965) (xy 128.573138 -375.524269) (xy 128.59681 -375.461265) (xy 128.627841 -375.401543)
			(xy 128.665789 -375.345958) (xy 128.687576 -375.320306) (xy 128.69335 -375.313144) (xy 128.699879 -375.295967)
			(xy 128.700276 -375.286778) (xy 128.700276 -374.79351) (xy 128.699866 -374.784323) (xy 128.693353 -374.767138)
			(xy 128.687576 -374.759982) (xy 128.665746 -374.734365) (xy 128.627796 -374.678774) (xy 128.596762 -374.619046)
			(xy 128.57309 -374.556037) (xy 128.557119 -374.49065) (xy 128.549078 -374.423823) (xy 125.271019 -374.423823)
			(xy 125.262979 -374.490638) (xy 125.247012 -374.556018) (xy 125.223345 -374.61902) (xy 125.192318 -374.678743)
			(xy 125.154376 -374.73433) (xy 125.132592 -374.759982) (xy 125.126777 -374.767114) (xy 125.120274 -374.784315)
			(xy 125.119892 -374.79351) (xy 125.119892 -375.286778) (xy 125.120315 -375.295964) (xy 125.12682 -375.313148)
			(xy 125.132592 -375.320306) (xy 125.154408 -375.345934) (xy 125.192354 -375.401525) (xy 125.223384 -375.461252)
			(xy 125.247054 -375.52426) (xy 125.263024 -375.589644) (xy 125.271065 -375.656469) (xy 125.271063 -375.723776)
			(xy 125.263016 -375.7906) (xy 125.247041 -375.855984) (xy 125.223366 -375.918989) (xy 125.192331 -375.978714)
			(xy 125.154381 -376.034301) (xy 125.132592 -376.059954) (xy 125.126789 -376.067095) (xy 125.120278 -376.084289)
			(xy 125.119892 -376.093482) (xy 125.119892 -376.25147) (xy 125.119343 -376.261622) (xy 125.111584 -376.280385)
			(xy 125.097235 -376.29475) (xy 125.078482 -376.302531) (xy 125.06833 -376.303032) (xy 124.35205 -376.303032)
			(xy 124.341878 -376.302595) (xy 124.323079 -376.29482) (xy 124.308691 -376.280438) (xy 124.300909 -376.261642)
			(xy 124.300488 -376.25147) (xy 124.300488 -376.093482) (xy 124.300089 -376.084294) (xy 124.293568 -376.067109)
			(xy 124.287788 -376.059954) (xy 124.266028 -376.034278) (xy 124.228075 -375.978696) (xy 124.197038 -375.918976)
			(xy 124.173361 -375.855975) (xy 124.157385 -375.790595) (xy 124.149338 -375.723774) (xy 124.149335 -375.656471)
			(xy 124.157377 -375.589649) (xy 124.173348 -375.524268) (xy 124.19702 -375.461265) (xy 124.228052 -375.401542)
			(xy 124.266001 -375.345957) (xy 124.287788 -375.320306) (xy 124.293563 -375.313145) (xy 124.300091 -375.295967)
			(xy 124.300488 -375.286778) (xy 124.300488 -374.79351) (xy 124.300076 -374.784323) (xy 124.293564 -374.767138)
			(xy 124.287788 -374.759982) (xy 124.265958 -374.734364) (xy 124.228007 -374.678774) (xy 124.196973 -374.619046)
			(xy 124.1733 -374.556037) (xy 124.157329 -374.49065) (xy 124.149287 -374.423823) (xy 120.87125 -374.423823)
			(xy 120.87125 -374.423879) (xy 120.863178 -374.490814) (xy 120.847147 -374.556301) (xy 120.823388 -374.619396)
			(xy 120.792242 -374.679191) (xy 120.754158 -374.734825) (xy 120.732296 -374.76049) (xy 120.726478 -374.76762)
			(xy 120.719976 -374.784822) (xy 120.719596 -374.794018) (xy 120.719596 -375.28627) (xy 120.720022 -375.295456)
			(xy 120.726525 -375.31264) (xy 120.732296 -375.319798) (xy 120.75419 -375.345439) (xy 120.792278 -375.401077)
			(xy 120.823427 -375.460876) (xy 120.84719 -375.523976) (xy 120.863223 -375.589468) (xy 120.871297 -375.656409)
			(xy 120.871294 -375.723836) (xy 120.863215 -375.790776) (xy 120.847177 -375.856267) (xy 120.823409 -375.919365)
			(xy 120.792254 -375.979162) (xy 120.754162 -376.034797) (xy 120.732296 -376.060462) (xy 120.72649 -376.067601)
			(xy 120.719981 -376.084796) (xy 120.719596 -376.09399) (xy 120.719596 -376.25147) (xy 120.71905 -376.26159)
			(xy 120.711339 -376.280304) (xy 120.697071 -376.29466) (xy 120.678405 -376.302487) (xy 120.668288 -376.303032)
			(xy 119.952008 -376.303032) (xy 119.941858 -376.302572) (xy 119.923112 -376.294786) (xy 119.90879 -376.280401)
			(xy 119.901084 -376.261621) (xy 119.9007 -376.25147) (xy 119.9007 -376.09399) (xy 119.900294 -376.084802)
			(xy 119.893777 -376.067618) (xy 119.888 -376.060462) (xy 119.866166 -376.034772) (xy 119.828076 -375.979141)
			(xy 119.796924 -375.919349) (xy 119.773158 -375.856255) (xy 119.75712 -375.790769) (xy 119.749042 -375.723833)
			(xy 119.749039 -375.656412) (xy 119.757112 -375.589476) (xy 119.773145 -375.523988) (xy 119.796905 -375.460893)
			(xy 119.828053 -375.401097) (xy 119.866138 -375.345463) (xy 119.888 -375.319798) (xy 119.89378 -375.312641)
			(xy 119.900305 -375.29546) (xy 119.9007 -375.28627) (xy 119.9007 -374.794018) (xy 119.900281 -374.784832)
			(xy 119.893773 -374.767647) (xy 119.888 -374.76049) (xy 119.866095 -374.734859) (xy 119.828007 -374.679219)
			(xy 119.796858 -374.619418) (xy 119.773097 -374.556317) (xy 119.757064 -374.490824) (xy 119.748992 -374.423882)
			(xy 116.470948 -374.423882) (xy 116.462914 -374.49064) (xy 116.446944 -374.556021) (xy 116.423273 -374.619024)
			(xy 116.392242 -374.678746) (xy 116.354295 -374.734331) (xy 116.332508 -374.759982) (xy 116.326695 -374.767116)
			(xy 116.32019 -374.784315) (xy 116.319808 -374.79351) (xy 116.319808 -375.286778) (xy 116.320227 -375.295964)
			(xy 116.326734 -375.313149) (xy 116.332508 -375.320306) (xy 116.354327 -375.345933) (xy 116.392278 -375.401522)
			(xy 116.423313 -375.461249) (xy 116.446986 -375.524256) (xy 116.462959 -375.589642) (xy 116.471001 -375.656468)
			(xy 116.470999 -375.723777) (xy 116.462951 -375.790602) (xy 116.446973 -375.855987) (xy 116.423295 -375.918993)
			(xy 116.392255 -375.978717) (xy 116.354299 -376.034303) (xy 116.332508 -376.059954) (xy 116.326707 -376.067096)
			(xy 116.320195 -376.084289) (xy 116.319808 -376.093482) (xy 116.319808 -376.25147) (xy 116.319243 -376.26162)
			(xy 116.311487 -376.28038) (xy 116.297144 -376.294745) (xy 116.278395 -376.302528) (xy 116.268246 -376.303032)
			(xy 115.551966 -376.303032) (xy 115.541802 -376.302594) (xy 115.523027 -376.294803) (xy 115.508662 -376.28042)
			(xy 115.500894 -376.261634) (xy 115.500404 -376.25147) (xy 115.500404 -376.093482) (xy 115.500002 -376.084294)
			(xy 115.493483 -376.06711) (xy 115.487704 -376.059954) (xy 115.465947 -376.034277) (xy 115.427999 -375.978693)
			(xy 115.396967 -375.918973) (xy 115.373294 -375.855972) (xy 115.35732 -375.790593) (xy 115.349274 -375.723774)
			(xy 115.349271 -375.656472) (xy 115.357312 -375.589652) (xy 115.37328 -375.524271) (xy 115.396948 -375.461268)
			(xy 115.427976 -375.401545) (xy 115.465919 -375.345959) (xy 115.487704 -375.320306) (xy 115.493481 -375.313147)
			(xy 115.500007 -375.295967) (xy 115.500404 -375.286778) (xy 115.500404 -374.79351) (xy 115.499988 -374.784323)
			(xy 115.493478 -374.767139) (xy 115.487704 -374.759982) (xy 115.465876 -374.734363) (xy 115.427931 -374.678771)
			(xy 115.396901 -374.619043) (xy 115.373232 -374.556034) (xy 115.357263 -374.490648) (xy 115.349223 -374.423822)
			(xy 85.670923 -374.423822) (xy 85.670923 -374.423879) (xy 85.662851 -374.490815) (xy 85.646818 -374.556302)
			(xy 85.623057 -374.619398) (xy 85.591909 -374.679192) (xy 85.553823 -374.734826) (xy 85.53196 -374.76049)
			(xy 85.526138 -374.767617) (xy 85.519639 -374.784822) (xy 85.51926 -374.794018) (xy 85.51926 -375.28627)
			(xy 85.519694 -375.295454) (xy 85.526192 -375.312639) (xy 85.53196 -375.319798) (xy 85.553855 -375.345438)
			(xy 85.591945 -375.401075) (xy 85.623097 -375.460875) (xy 85.646861 -375.523975) (xy 85.662896 -375.589467)
			(xy 85.67097 -375.656409) (xy 85.670967 -375.723836) (xy 85.662888 -375.790777) (xy 85.646848 -375.856268)
			(xy 85.623079 -375.919367) (xy 85.591922 -375.979163) (xy 85.553827 -376.034797) (xy 85.53196 -376.060462)
			(xy 85.52615 -376.067597) (xy 85.519644 -376.084796) (xy 85.51926 -376.09399) (xy 85.51926 -376.25147)
			(xy 85.518749 -376.261595) (xy 85.511031 -376.280315) (xy 85.496752 -376.294673) (xy 85.478074 -376.302493)
			(xy 85.467952 -376.303032) (xy 84.751672 -376.303032) (xy 84.741565 -376.302539) (xy 84.722893 -376.294798)
			(xy 84.7086 -376.280504) (xy 84.700861 -376.261831) (xy 84.700364 -376.251724) (xy 84.700364 -376.09399)
			(xy 84.699944 -376.084804) (xy 84.693436 -376.06762) (xy 84.687664 -376.060462) (xy 84.665831 -376.034772)
			(xy 84.627744 -375.97914) (xy 84.596594 -375.919347) (xy 84.572829 -375.856253) (xy 84.556793 -375.790768)
			(xy 84.548715 -375.723833) (xy 84.548712 -375.656412) (xy 84.556785 -375.589477) (xy 84.572816 -375.52399)
			(xy 84.596575 -375.460894) (xy 84.62772 -375.401099) (xy 84.665803 -375.345464) (xy 84.687664 -375.319798)
			(xy 84.693452 -375.312647) (xy 84.69997 -375.295461) (xy 84.700364 -375.28627) (xy 84.700364 -374.794018)
			(xy 84.699931 -374.784834) (xy 84.693432 -374.76765) (xy 84.687664 -374.76049) (xy 84.66576 -374.734858)
			(xy 84.627675 -374.679218) (xy 84.596528 -374.619417) (xy 84.572768 -374.556316) (xy 84.556736 -374.490823)
			(xy 84.548664 -374.423882) (xy 81.271132 -374.423882) (xy 81.26306 -374.490815) (xy 81.247028 -374.556302)
			(xy 81.223267 -374.619397) (xy 81.19212 -374.679192) (xy 81.154034 -374.734825) (xy 81.132172 -374.76049)
			(xy 81.126351 -374.767618) (xy 81.119852 -374.784822) (xy 81.119472 -374.794018) (xy 81.119472 -375.28627)
			(xy 81.119903 -375.295455) (xy 81.126403 -375.312639) (xy 81.132172 -375.319798) (xy 81.154066 -375.345438)
			(xy 81.192156 -375.401076) (xy 81.223307 -375.460875) (xy 81.247071 -375.523975) (xy 81.263105 -375.589468)
			(xy 81.271179 -375.656409) (xy 81.271176 -375.723836) (xy 81.263097 -375.790777) (xy 81.247057 -375.856268)
			(xy 81.223289 -375.919366) (xy 81.192133 -375.979163) (xy 81.154039 -376.034797) (xy 81.132172 -376.060462)
			(xy 81.126363 -376.067598) (xy 81.119856 -376.084796) (xy 81.119472 -376.09399) (xy 81.119472 -376.25147)
			(xy 81.118949 -376.261593) (xy 81.111234 -376.280312) (xy 81.096958 -376.294669) (xy 81.078284 -376.302491)
			(xy 81.068164 -376.303032) (xy 80.351884 -376.303032) (xy 80.341778 -376.302529) (xy 80.323106 -376.294792)
			(xy 80.308813 -376.280501) (xy 80.301073 -376.26183) (xy 80.300576 -376.251724) (xy 80.300576 -376.09399)
			(xy 80.300176 -376.084802) (xy 80.293656 -376.067617) (xy 80.287876 -376.060462) (xy 80.266042 -376.034772)
			(xy 80.227954 -375.97914) (xy 80.196804 -375.919347) (xy 80.173039 -375.856254) (xy 80.157002 -375.790768)
			(xy 80.148924 -375.723833) (xy 80.148921 -375.656412) (xy 80.156994 -375.589476) (xy 80.173025 -375.523989)
			(xy 80.196785 -375.460894) (xy 80.227931 -375.401098) (xy 80.266015 -375.345464) (xy 80.287876 -375.319798)
			(xy 80.293653 -375.312639) (xy 80.30018 -375.295459) (xy 80.300576 -375.28627) (xy 80.300576 -374.794018)
			(xy 80.300163 -374.784831) (xy 80.293652 -374.767646) (xy 80.287876 -374.76049) (xy 80.265972 -374.734858)
			(xy 80.227886 -374.679218) (xy 80.196738 -374.619417) (xy 80.172977 -374.556316) (xy 80.156946 -374.490823)
			(xy 80.148873 -374.423882) (xy 76.870804 -374.423882) (xy 76.862772 -374.490638) (xy 76.846805 -374.556018)
			(xy 76.823138 -374.619021) (xy 76.79211 -374.678743) (xy 76.754168 -374.734329) (xy 76.732384 -374.759982)
			(xy 76.726568 -374.767114) (xy 76.720066 -374.784315) (xy 76.719684 -374.79351) (xy 76.719684 -375.286778)
			(xy 76.720108 -375.295964) (xy 76.726613 -375.313148) (xy 76.732384 -375.320306) (xy 76.754201 -375.345934)
			(xy 76.792147 -375.401525) (xy 76.823178 -375.461252) (xy 76.846848 -375.524259) (xy 76.862818 -375.589644)
			(xy 76.870859 -375.656469) (xy 76.870857 -375.723776) (xy 76.86281 -375.7906) (xy 76.846834 -375.855984)
			(xy 76.823159 -375.91899) (xy 76.792124 -375.978714) (xy 76.754173 -376.034302) (xy 76.732384 -376.059954)
			(xy 76.72658 -376.067094) (xy 76.72007 -376.084289) (xy 76.719684 -376.093482) (xy 76.719684 -376.25147)
			(xy 76.719212 -376.261637) (xy 76.711441 -376.280427) (xy 76.69707 -376.294812) (xy 76.678288 -376.302602)
			(xy 76.668122 -376.303032) (xy 75.951842 -376.303032) (xy 75.941669 -376.302601) (xy 75.92287 -376.294824)
			(xy 75.908482 -376.28044) (xy 75.900701 -376.261643) (xy 75.90028 -376.25147) (xy 75.90028 -376.093482)
			(xy 75.899883 -376.084293) (xy 75.893361 -376.067109) (xy 75.88758 -376.059954) (xy 75.865821 -376.034278)
			(xy 75.827868 -375.978696) (xy 75.796831 -375.918976) (xy 75.773155 -375.855975) (xy 75.757179 -375.790595)
			(xy 75.749132 -375.723774) (xy 75.749129 -375.656471) (xy 75.757171 -375.58965) (xy 75.773142 -375.524269)
			(xy 75.796813 -375.461265) (xy 75.827845 -375.401543) (xy 75.865793 -375.345958) (xy 75.88758 -375.320306)
			(xy 75.893354 -375.313145) (xy 75.899883 -375.295967) (xy 75.90028 -375.286778) (xy 75.90028 -374.79351)
			(xy 75.89987 -374.784323) (xy 75.893357 -374.767138) (xy 75.88758 -374.759982) (xy 75.865749 -374.734365)
			(xy 75.827799 -374.678774) (xy 75.796765 -374.619046) (xy 75.773093 -374.556037) (xy 75.757122 -374.49065)
			(xy 75.749081 -374.423823) (xy 72.471044 -374.423823) (xy 72.471044 -374.423879) (xy 72.462972 -374.490814)
			(xy 72.446941 -374.556301) (xy 72.423181 -374.619396) (xy 72.392034 -374.679191) (xy 72.35395 -374.734825)
			(xy 72.332088 -374.76049) (xy 72.326269 -374.76762) (xy 72.319768 -374.784822) (xy 72.319388 -374.794018)
			(xy 72.319388 -375.28627) (xy 72.319815 -375.295455) (xy 72.326317 -375.31264) (xy 72.332088 -375.319798)
			(xy 72.353982 -375.345439) (xy 72.39207 -375.401076) (xy 72.423221 -375.460876) (xy 72.446984 -375.523976)
			(xy 72.463017 -375.589468) (xy 72.471091 -375.656409) (xy 72.471088 -375.723836) (xy 72.463009 -375.790776)
			(xy 72.44697 -375.856267) (xy 72.423202 -375.919365) (xy 72.392047 -375.979162) (xy 72.353954 -376.034797)
			(xy 72.332088 -376.060462) (xy 72.326281 -376.0676) (xy 72.319773 -376.084796) (xy 72.319388 -376.09399)
			(xy 72.319388 -376.25147) (xy 72.31885 -376.261591) (xy 72.311137 -376.280307) (xy 72.296867 -376.294663)
			(xy 72.278198 -376.302488) (xy 72.26808 -376.303032) (xy 71.5518 -376.303032) (xy 71.54165 -376.302579)
			(xy 71.522904 -376.294789) (xy 71.508582 -376.280403) (xy 71.500876 -376.261622) (xy 71.500492 -376.25147)
			(xy 71.500492 -376.09399) (xy 71.500088 -376.084802) (xy 71.49357 -376.067618) (xy 71.487792 -376.060462)
			(xy 71.465958 -376.034772) (xy 71.427869 -375.979141) (xy 71.396717 -375.919348) (xy 71.372952 -375.856255)
			(xy 71.356914 -375.790769) (xy 71.348836 -375.723833) (xy 71.348833 -375.656412) (xy 71.356906 -375.589476)
			(xy 71.372938 -375.523989) (xy 71.396699 -375.460893) (xy 71.427845 -375.401098) (xy 71.46593 -375.345463)
			(xy 71.487792 -375.319798) (xy 71.493571 -375.31264) (xy 71.500096 -375.295459) (xy 71.500492 -375.28627)
			(xy 71.500492 -374.794018) (xy 71.500075 -374.784832) (xy 71.493566 -374.767647) (xy 71.487792 -374.76049)
			(xy 71.465887 -374.734859) (xy 71.4278 -374.679219) (xy 71.396652 -374.619418) (xy 71.37289 -374.556317)
			(xy 71.356858 -374.490824) (xy 71.348786 -374.423882) (xy 46.070774 -374.423882) (xy 46.062742 -374.490639)
			(xy 46.046773 -374.55602) (xy 46.023104 -374.619022) (xy 45.992075 -374.678745) (xy 45.95413 -374.73433)
			(xy 45.932344 -374.759982) (xy 45.926523 -374.76711) (xy 45.920025 -374.784314) (xy 45.919644 -374.79351)
			(xy 45.919644 -375.286778) (xy 45.920077 -375.295962) (xy 45.926576 -375.313146) (xy 45.932344 -375.320306)
			(xy 45.954162 -375.345934) (xy 45.992111 -375.401523) (xy 46.023144 -375.46125) (xy 46.046816 -375.524258)
			(xy 46.062787 -375.589643) (xy 46.070829 -375.656469) (xy 46.070826 -375.723776) (xy 46.062779 -375.790601)
			(xy 46.046802 -375.855985) (xy 46.023125 -375.918991) (xy 45.992088 -375.978716) (xy 45.954134 -376.034302)
			(xy 45.932344 -376.059954) (xy 45.926535 -376.06709) (xy 45.920029 -376.084288) (xy 45.919644 -376.093482)
			(xy 45.919644 -376.25147) (xy 45.919211 -376.261642) (xy 45.911433 -376.280439) (xy 45.897049 -376.294826)
			(xy 45.878254 -376.302609) (xy 45.868082 -376.303032) (xy 45.151802 -376.303032) (xy 45.141627 -376.302634)
			(xy 45.122826 -376.294844) (xy 45.10844 -376.28045) (xy 45.100661 -376.261645) (xy 45.10024 -376.25147)
			(xy 45.10024 -376.093482) (xy 45.09983 -376.084295) (xy 45.093315 -376.067111) (xy 45.08754 -376.059954)
			(xy 45.065782 -376.034277) (xy 45.027832 -375.978695) (xy 44.996798 -375.918974) (xy 44.973123 -375.855973)
			(xy 44.957148 -375.790594) (xy 44.949101 -375.723774) (xy 44.949099 -375.656471) (xy 44.95714 -375.589651)
			(xy 44.97311 -375.52427) (xy 44.996779 -375.461267) (xy 45.027809 -375.401544) (xy 45.065754 -375.345958)
			(xy 45.08754 -375.320306) (xy 45.093322 -375.31315) (xy 45.099844 -375.295968) (xy 45.10024 -375.286778)
			(xy 45.10024 -374.79351) (xy 45.099816 -374.784324) (xy 45.093311 -374.76714) (xy 45.08754 -374.759982)
			(xy 45.065711 -374.734364) (xy 45.027763 -374.678773) (xy 44.996732 -374.619044) (xy 44.973061 -374.556035)
			(xy 44.957091 -374.490649) (xy 44.94905 -374.423823) (xy 41.671014 -374.423823) (xy 41.671014 -374.423879)
			(xy 41.662941 -374.490816) (xy 41.646909 -374.556303) (xy 41.623147 -374.619398) (xy 41.591998 -374.679193)
			(xy 41.553911 -374.734826) (xy 41.532048 -374.76049) (xy 41.526224 -374.767616) (xy 41.519727 -374.784821)
			(xy 41.519348 -374.794018) (xy 41.519348 -375.28627) (xy 41.519784 -375.295454) (xy 41.526281 -375.312638)
			(xy 41.532048 -375.319798) (xy 41.553943 -375.345438) (xy 41.592035 -375.401075) (xy 41.623187 -375.460874)
			(xy 41.646952 -375.523974) (xy 41.662987 -375.589467) (xy 41.671061 -375.656409) (xy 41.671058 -375.723836)
			(xy 41.662978 -375.790777) (xy 41.646938 -375.856269) (xy 41.623168 -375.919367) (xy 41.592011 -375.979164)
			(xy 41.553916 -376.034798) (xy 41.532048 -376.060462) (xy 41.526236 -376.067596) (xy 41.519732 -376.084795)
			(xy 41.519348 -376.09399) (xy 41.519348 -376.25147) (xy 41.518849 -376.261596) (xy 41.511129 -376.280319)
			(xy 41.496846 -376.294677) (xy 41.478164 -376.302495) (xy 41.46804 -376.303032) (xy 40.75176 -376.303032)
			(xy 40.741607 -376.302612) (xy 40.72286 -376.294809) (xy 40.708539 -376.280413) (xy 40.700835 -376.261625)
			(xy 40.700452 -376.25147) (xy 40.700452 -376.09399) (xy 40.700035 -376.084804) (xy 40.693525 -376.06762)
			(xy 40.687752 -376.060462) (xy 40.665916 -376.034773) (xy 40.627823 -375.979143) (xy 40.596668 -375.919351)
			(xy 40.5729 -375.856257) (xy 40.55686 -375.79077) (xy 40.548781 -375.723834) (xy 40.548779 -375.656411)
			(xy 40.556852 -375.589474) (xy 40.572886 -375.523986) (xy 40.596649 -375.46089) (xy 40.627799 -375.401095)
			(xy 40.665888 -375.345462) (xy 40.687752 -375.319798) (xy 40.693538 -375.312646) (xy 40.700058 -375.29546)
			(xy 40.700452 -375.28627) (xy 40.700452 -374.794018) (xy 40.700022 -374.784833) (xy 40.693521 -374.767649)
			(xy 40.687752 -374.76049) (xy 40.665845 -374.73486) (xy 40.627754 -374.679221) (xy 40.596602 -374.619421)
			(xy 40.572838 -374.556319) (xy 40.556804 -374.490825) (xy 40.548731 -374.423882) (xy 37.271223 -374.423882)
			(xy 37.263151 -374.490815) (xy 37.247118 -374.556302) (xy 37.223357 -374.619398) (xy 37.192209 -374.679192)
			(xy 37.154123 -374.734826) (xy 37.13226 -374.76049) (xy 37.126438 -374.767617) (xy 37.119939 -374.784822)
			(xy 37.11956 -374.794018) (xy 37.11956 -375.28627) (xy 37.119994 -375.295454) (xy 37.126492 -375.312639)
			(xy 37.13226 -375.319798) (xy 37.154155 -375.345438) (xy 37.192245 -375.401075) (xy 37.223397 -375.460875)
			(xy 37.247161 -375.523975) (xy 37.263196 -375.589467) (xy 37.27127 -375.656409) (xy 37.271267 -375.723836)
			(xy 37.263188 -375.790777) (xy 37.247148 -375.856268) (xy 37.223379 -375.919367) (xy 37.192222 -375.979163)
			(xy 37.154127 -376.034797) (xy 37.13226 -376.060462) (xy 37.12645 -376.067597) (xy 37.119944 -376.084796)
			(xy 37.11956 -376.09399) (xy 37.11956 -376.25147) (xy 37.119049 -376.261595) (xy 37.111331 -376.280315)
			(xy 37.097052 -376.294673) (xy 37.078374 -376.302493) (xy 37.068252 -376.303032) (xy 36.351972 -376.303032)
			(xy 36.34182 -376.302602) (xy 36.323073 -376.294803) (xy 36.308752 -376.28041) (xy 36.301047 -376.261624)
			(xy 36.300664 -376.25147) (xy 36.300664 -376.09399) (xy 36.300244 -376.084804) (xy 36.293736 -376.06762)
			(xy 36.287964 -376.060462) (xy 36.266131 -376.034772) (xy 36.228044 -375.97914) (xy 36.196894 -375.919347)
			(xy 36.173129 -375.856253) (xy 36.157093 -375.790768) (xy 36.149015 -375.723833) (xy 36.149012 -375.656412)
			(xy 36.157085 -375.589477) (xy 36.173116 -375.52399) (xy 36.196875 -375.460894) (xy 36.22802 -375.401099)
			(xy 36.266103 -375.345464) (xy 36.287964 -375.319798) (xy 36.293752 -375.312647) (xy 36.30027 -375.295461)
			(xy 36.300664 -375.28627) (xy 36.300664 -374.794018) (xy 36.300231 -374.784834) (xy 36.293732 -374.76765)
			(xy 36.287964 -374.76049) (xy 36.26606 -374.734858) (xy 36.227975 -374.679218) (xy 36.196828 -374.619417)
			(xy 36.173068 -374.556316) (xy 36.157036 -374.490823) (xy 36.148964 -374.423882) (xy 32.870895 -374.423882)
			(xy 32.862863 -374.490639) (xy 32.846895 -374.556018) (xy 32.823227 -374.619021) (xy 32.7922 -374.678743)
			(xy 32.754257 -374.73433) (xy 32.732472 -374.759982) (xy 32.726654 -374.767112) (xy 32.720153 -374.784314)
			(xy 32.719772 -374.79351) (xy 32.719772 -375.286778) (xy 32.720199 -375.295963) (xy 32.726702 -375.313147)
			(xy 32.732472 -375.320306) (xy 32.754289 -375.345934) (xy 32.792236 -375.401524) (xy 32.823268 -375.461251)
			(xy 32.846938 -375.524259) (xy 32.862909 -375.589644) (xy 32.87095 -375.656469) (xy 32.870948 -375.723776)
			(xy 32.862901 -375.790601) (xy 32.846925 -375.855984) (xy 32.823249 -375.91899) (xy 32.792213 -375.978715)
			(xy 32.754261 -376.034302) (xy 32.732472 -376.059954) (xy 32.726666 -376.067093) (xy 32.720158 -376.084288)
			(xy 32.719772 -376.093482) (xy 32.719772 -376.25147) (xy 32.719312 -376.261638) (xy 32.711538 -376.28043)
			(xy 32.697164 -376.294816) (xy 32.678378 -376.302604) (xy 32.66821 -376.303032) (xy 31.95193 -376.303032)
			(xy 31.941757 -376.302611) (xy 31.922957 -376.29483) (xy 31.90857 -376.280443) (xy 31.900789 -376.261643)
			(xy 31.900368 -376.25147) (xy 31.900368 -376.093482) (xy 31.899951 -376.084296) (xy 31.89344 -376.067112)
			(xy 31.887668 -376.059954) (xy 31.865909 -376.034278) (xy 31.827957 -375.978696) (xy 31.796921 -375.918976)
			(xy 31.773245 -375.855974) (xy 31.75727 -375.790595) (xy 31.749223 -375.723774) (xy 31.74922 -375.656471)
			(xy 31.757261 -375.58965) (xy 31.773232 -375.524269) (xy 31.796903 -375.461266) (xy 31.827934 -375.401543)
			(xy 31.865881 -375.345958) (xy 31.887668 -375.320306) (xy 31.893453 -375.313153) (xy 31.899973 -375.295968)
			(xy 31.900368 -375.286778) (xy 31.900368 -374.79351) (xy 31.899938 -374.784325) (xy 31.893436 -374.767142)
			(xy 31.887668 -374.759982) (xy 31.865838 -374.734364) (xy 31.827888 -374.678774) (xy 31.796855 -374.619046)
			(xy 31.773184 -374.556036) (xy 31.757213 -374.49065) (xy 31.749171 -374.423823) (xy 28.471155 -374.423823)
			(xy 28.471155 -374.42387) (xy 28.463079 -374.490809) (xy 28.447044 -374.556297) (xy 28.423279 -374.619394)
			(xy 28.392129 -374.67919) (xy 28.35404 -374.734825) (xy 28.332176 -374.76049) (xy 28.326356 -374.767618)
			(xy 28.319856 -374.784822) (xy 28.319476 -374.794018) (xy 28.319476 -375.28627) (xy 28.319906 -375.295455)
			(xy 28.326407 -375.312639) (xy 28.332176 -375.319798) (xy 28.35407 -375.345439) (xy 28.39216 -375.401076)
			(xy 28.42331 -375.460875) (xy 28.447074 -375.523976) (xy 28.463108 -375.589468) (xy 28.471182 -375.656409)
			(xy 28.471179 -375.723836) (xy 28.4631 -375.790777) (xy 28.447061 -375.856268) (xy 28.423292 -375.919366)
			(xy 28.392136 -375.979163) (xy 28.354043 -376.034797) (xy 28.332176 -376.060462) (xy 28.326368 -376.067599)
			(xy 28.319861 -376.084796) (xy 28.319476 -376.09399) (xy 28.319476 -376.25147) (xy 28.31895 -376.261593)
			(xy 28.311235 -376.28031) (xy 28.29696 -376.294667) (xy 28.278288 -376.30249) (xy 28.268168 -376.303032)
			(xy 27.551888 -376.303032) (xy 27.541783 -376.302525) (xy 27.52311 -376.29479) (xy 27.508817 -376.2805)
			(xy 27.501077 -376.261829) (xy 27.50058 -376.251724) (xy 27.50058 -376.09399) (xy 27.500179 -376.084802)
			(xy 27.493659 -376.067617) (xy 27.48788 -376.060462) (xy 27.466046 -376.034772) (xy 27.427958 -375.979141)
			(xy 27.396807 -375.919348) (xy 27.373042 -375.856254) (xy 27.357005 -375.790768) (xy 27.348927 -375.723833)
			(xy 27.348924 -375.656412) (xy 27.356997 -375.589476) (xy 27.373029 -375.523989) (xy 27.396789 -375.460894)
			(xy 27.427935 -375.401098) (xy 27.466019 -375.345464) (xy 27.48788 -375.319798) (xy 27.493658 -375.312639)
			(xy 27.500184 -375.295459) (xy 27.50058 -375.28627) (xy 27.50058 -374.794018) (xy 27.500166 -374.784831)
			(xy 27.493655 -374.767646) (xy 27.48788 -374.76049) (xy 27.466014 -374.734827) (xy 27.427924 -374.679192)
			(xy 27.396773 -374.619396) (xy 27.373009 -374.556299) (xy 27.356973 -374.490809) (xy 27.348897 -374.423871)
			(xy 0.509016 -374.423871) (xy 0.509016 -376.756551) (xy 29.549067 -376.756551) (xy 29.557111 -376.689729)
			(xy 29.573083 -376.624347) (xy 29.596754 -376.561343) (xy 29.627786 -376.501619) (xy 29.665733 -376.446032)
			(xy 29.68752 -376.42038) (xy 29.69331 -376.41323) (xy 29.699828 -376.396043) (xy 29.70022 -376.386852)
			(xy 29.70022 -375.893584) (xy 29.699813 -375.884397) (xy 29.693297 -375.867212) (xy 29.68752 -375.860056)
			(xy 29.665765 -375.834378) (xy 29.627816 -375.778794) (xy 29.596782 -375.719074) (xy 29.573109 -375.656073)
			(xy 29.557134 -375.590694) (xy 29.549088 -375.523875) (xy 29.549085 -375.456573) (xy 29.557126 -375.389753)
			(xy 29.573095 -375.324373) (xy 29.596763 -375.26137) (xy 29.627791 -375.201647) (xy 29.665735 -375.146061)
			(xy 29.68752 -375.120408) (xy 29.693298 -375.11325) (xy 29.699823 -375.096069) (xy 29.70022 -375.08688)
			(xy 29.70022 -374.928638) (xy 29.700695 -374.918471) (xy 29.708464 -374.899681) (xy 29.722834 -374.885295)
			(xy 29.741616 -374.877506) (xy 29.751782 -374.877076) (xy 30.468062 -374.877076) (xy 30.478236 -374.877496)
			(xy 30.497037 -374.885276) (xy 30.511424 -374.899663) (xy 30.519204 -374.918464) (xy 30.519624 -374.928638)
			(xy 30.519624 -375.08688) (xy 30.520038 -375.096067) (xy 30.526548 -375.113252) (xy 30.532324 -375.120408)
			(xy 30.554144 -375.146034) (xy 30.592094 -375.201623) (xy 30.623128 -375.26135) (xy 30.646801 -375.324358)
			(xy 30.662773 -375.389744) (xy 30.670815 -375.45657) (xy 30.670812 -375.523878) (xy 30.662764 -375.590704)
			(xy 30.646787 -375.656088) (xy 30.623109 -375.719094) (xy 30.59207 -375.778818) (xy 30.554115 -375.834404)
			(xy 30.532324 -375.860056) (xy 30.526524 -375.867199) (xy 30.520011 -375.884391) (xy 30.519624 -375.893584)
			(xy 30.519624 -376.386852) (xy 30.520052 -376.396037) (xy 30.526553 -376.413222) (xy 30.532324 -376.42038)
			(xy 30.554117 -376.446028) (xy 30.592068 -376.501615) (xy 30.623103 -376.561338) (xy 30.646777 -376.624343)
			(xy 30.662751 -376.689726) (xy 30.670795 -376.75655) (xy 30.670795 -376.823856) (xy 30.670788 -376.823915)
			(xy 33.948836 -376.823915) (xy 33.948836 -376.756491) (xy 33.956911 -376.689553) (xy 33.972947 -376.624064)
			(xy 33.996711 -376.560967) (xy 34.027862 -376.501171) (xy 34.065952 -376.445537) (xy 34.087816 -376.419872)
			(xy 34.093609 -376.412724) (xy 34.100125 -376.395536) (xy 34.100516 -376.386344) (xy 34.100516 -375.894092)
			(xy 34.100106 -375.884905) (xy 34.093592 -375.867721) (xy 34.087816 -375.860564) (xy 34.065983 -375.834873)
			(xy 34.027892 -375.779243) (xy 33.996739 -375.71945) (xy 33.972973 -375.656357) (xy 33.956934 -375.59087)
			(xy 33.948856 -375.523935) (xy 33.948853 -375.456513) (xy 33.956926 -375.389577) (xy 33.972958 -375.324089)
			(xy 33.99672 -375.260994) (xy 34.027867 -375.201199) (xy 34.065953 -375.145565) (xy 34.087816 -375.1199)
			(xy 34.093597 -375.112744) (xy 34.10012 -375.095562) (xy 34.100516 -375.086372) (xy 34.100516 -374.928638)
			(xy 34.101057 -374.918517) (xy 34.108768 -374.899801) (xy 34.123038 -374.885444) (xy 34.141706 -374.87762)
			(xy 34.151824 -374.877076) (xy 34.868104 -374.877076) (xy 34.878255 -374.877518) (xy 34.897003 -374.88531)
			(xy 34.911325 -374.8997) (xy 34.919029 -374.918485) (xy 34.919412 -374.928638) (xy 34.919412 -375.086372)
			(xy 34.919833 -375.095558) (xy 34.926339 -375.112743) (xy 34.932112 -375.1199) (xy 34.954007 -375.14554)
			(xy 34.992094 -375.201178) (xy 35.023243 -375.260978) (xy 35.047004 -375.324078) (xy 35.063037 -375.38957)
			(xy 35.07111 -375.456511) (xy 35.071108 -375.523937) (xy 35.063029 -375.590877) (xy 35.04699 -375.656368)
			(xy 35.023223 -375.719466) (xy 34.992069 -375.779263) (xy 34.953977 -375.834899) (xy 34.932112 -375.860564)
			(xy 34.926307 -375.867703) (xy 34.919797 -375.884898) (xy 34.919412 -375.894092) (xy 34.919412 -376.386344)
			(xy 34.919798 -376.395534) (xy 34.926328 -376.412718) (xy 34.932112 -376.419872) (xy 34.953979 -376.445534)
			(xy 34.992067 -376.501169) (xy 35.023217 -376.560966) (xy 35.046981 -376.624063) (xy 35.063015 -376.689553)
			(xy 35.071091 -376.756491) (xy 35.071091 -376.756551) (xy 38.349155 -376.756551) (xy 38.357198 -376.689729)
			(xy 38.37317 -376.624348) (xy 38.396841 -376.561343) (xy 38.427872 -376.50162) (xy 38.465818 -376.446033)
			(xy 38.487604 -376.42038) (xy 38.493392 -376.413229) (xy 38.499912 -376.396043) (xy 38.500304 -376.386852)
			(xy 38.500304 -375.893584) (xy 38.499901 -375.884396) (xy 38.493382 -375.867212) (xy 38.487604 -375.860056)
			(xy 38.465849 -375.834378) (xy 38.427901 -375.778794) (xy 38.396869 -375.719074) (xy 38.373195 -375.656073)
			(xy 38.357221 -375.590694) (xy 38.349175 -375.523875) (xy 38.349172 -375.456573) (xy 38.357213 -375.389753)
			(xy 38.373181 -375.324373) (xy 38.396849 -375.26137) (xy 38.427876 -375.201647) (xy 38.465819 -375.146061)
			(xy 38.487604 -375.120408) (xy 38.49338 -375.113248) (xy 38.499907 -375.096069) (xy 38.500304 -375.08688)
			(xy 38.500304 -374.928638) (xy 38.500794 -374.918473) (xy 38.50856 -374.899686) (xy 38.522925 -374.885301)
			(xy 38.541702 -374.877508) (xy 38.551866 -374.877076) (xy 39.268146 -374.877076) (xy 39.278311 -374.877497)
			(xy 39.297089 -374.885293) (xy 39.311454 -374.899682) (xy 39.31922 -374.918472) (xy 39.319708 -374.928638)
			(xy 39.319708 -375.08688) (xy 39.320126 -375.096066) (xy 39.326634 -375.113251) (xy 39.332408 -375.120408)
			(xy 39.354229 -375.146034) (xy 39.39218 -375.201623) (xy 39.423215 -375.261349) (xy 39.446888 -375.324357)
			(xy 39.462861 -375.389743) (xy 39.470903 -375.45657) (xy 39.4709 -375.523878) (xy 39.462852 -375.590704)
			(xy 39.446874 -375.656089) (xy 39.423195 -375.719095) (xy 39.392155 -375.778819) (xy 39.354199 -375.834405)
			(xy 39.332408 -375.860056) (xy 39.326606 -375.867197) (xy 39.320094 -375.884391) (xy 39.319708 -375.893584)
			(xy 39.319708 -376.386852) (xy 39.320139 -376.396037) (xy 39.326638 -376.413222) (xy 39.332408 -376.42038)
			(xy 39.354201 -376.446028) (xy 39.392153 -376.501614) (xy 39.423189 -376.561338) (xy 39.446864 -376.624343)
			(xy 39.462839 -376.689726) (xy 39.470883 -376.75655) (xy 39.470883 -376.823856) (xy 39.470876 -376.823915)
			(xy 42.748924 -376.823915) (xy 42.748924 -376.756491) (xy 42.756999 -376.689553) (xy 42.773034 -376.624064)
			(xy 42.796798 -376.560968) (xy 42.827948 -376.501172) (xy 42.866036 -376.445537) (xy 42.8879 -376.419872)
			(xy 42.893691 -376.412723) (xy 42.900209 -376.395535) (xy 42.9006 -376.386344) (xy 42.9006 -375.894092)
			(xy 42.900194 -375.884904) (xy 42.893677 -375.86772) (xy 42.8879 -375.860564) (xy 42.866067 -375.834873)
			(xy 42.827978 -375.779242) (xy 42.796826 -375.719449) (xy 42.77306 -375.656356) (xy 42.757022 -375.59087)
			(xy 42.748944 -375.523935) (xy 42.748941 -375.456513) (xy 42.757013 -375.389577) (xy 42.773045 -375.32409)
			(xy 42.796806 -375.260995) (xy 42.827953 -375.201199) (xy 42.866038 -375.145565) (xy 42.8879 -375.1199)
			(xy 42.893679 -375.112742) (xy 42.900204 -375.095561) (xy 42.9006 -375.086372) (xy 42.9006 -374.928638)
			(xy 42.901157 -374.918519) (xy 42.908865 -374.899806) (xy 42.923129 -374.88545) (xy 42.941792 -374.877622)
			(xy 42.951908 -374.877076) (xy 43.668188 -374.877076) (xy 43.678338 -374.877531) (xy 43.697086 -374.885318)
			(xy 43.711409 -374.899704) (xy 43.719113 -374.918486) (xy 43.719496 -374.928638) (xy 43.719496 -375.086372)
			(xy 43.719921 -375.095558) (xy 43.726424 -375.112742) (xy 43.732196 -375.1199) (xy 43.754092 -375.145539)
			(xy 43.79218 -375.201177) (xy 43.823329 -375.260977) (xy 43.847092 -375.324077) (xy 43.863125 -375.38957)
			(xy 43.871198 -375.456511) (xy 43.871196 -375.523937) (xy 43.863116 -375.590878) (xy 43.847077 -375.656369)
			(xy 43.823309 -375.719467) (xy 43.792155 -375.779264) (xy 43.754062 -375.834899) (xy 43.732196 -375.860564)
			(xy 43.726389 -375.867702) (xy 43.719881 -375.884898) (xy 43.719496 -375.894092) (xy 43.719496 -376.386344)
			(xy 43.719886 -376.395533) (xy 43.726414 -376.412717) (xy 43.732196 -376.419872) (xy 43.754064 -376.445534)
			(xy 43.792153 -376.501169) (xy 43.823304 -376.560965) (xy 43.847068 -376.624063) (xy 43.863103 -376.689552)
			(xy 43.871179 -376.756491) (xy 43.871178 -376.823856) (xy 47.149219 -376.823856) (xy 47.149219 -376.75655)
			(xy 47.157264 -376.689727) (xy 47.173238 -376.624344) (xy 47.196912 -376.56134) (xy 47.227948 -376.501617)
			(xy 47.265899 -376.446031) (xy 47.287688 -376.42038) (xy 47.293474 -376.413227) (xy 47.299995 -376.396043)
			(xy 47.300388 -376.386852) (xy 47.300388 -375.893584) (xy 47.299988 -375.884396) (xy 47.293468 -375.867211)
			(xy 47.287688 -375.860056) (xy 47.26593 -375.834379) (xy 47.227977 -375.778797) (xy 47.19694 -375.719077)
			(xy 47.173263 -375.656076) (xy 47.157287 -375.590696) (xy 47.149239 -375.523876) (xy 47.149236 -375.456572)
			(xy 47.157278 -375.389751) (xy 47.173249 -375.32437) (xy 47.19692 -375.261367) (xy 47.227952 -375.201644)
			(xy 47.265901 -375.146059) (xy 47.287688 -375.120408) (xy 47.293462 -375.113247) (xy 47.299991 -375.096069)
			(xy 47.300388 -375.08688) (xy 47.300388 -374.928892) (xy 47.300815 -374.918739) (xy 47.308611 -374.899989)
			(xy 47.323006 -374.885666) (xy 47.341795 -374.877965) (xy 47.35195 -374.877584) (xy 48.06823 -374.877584)
			(xy 48.078364 -374.878003) (xy 48.097094 -374.885749) (xy 48.111451 -374.900056) (xy 48.119261 -374.91876)
			(xy 48.119792 -374.928892) (xy 48.119792 -375.08688) (xy 48.120214 -375.096066) (xy 48.12672 -375.11325)
			(xy 48.132492 -375.120408) (xy 48.15431 -375.146035) (xy 48.192256 -375.201626) (xy 48.223286 -375.261353)
			(xy 48.246956 -375.324361) (xy 48.262926 -375.389746) (xy 48.270967 -375.456571) (xy 48.270964 -375.523878)
			(xy 48.262917 -375.590702) (xy 48.246942 -375.656085) (xy 48.223267 -375.719091) (xy 48.192231 -375.778816)
			(xy 48.154281 -375.834403) (xy 48.132492 -375.860056) (xy 48.126688 -375.867196) (xy 48.120178 -375.884391)
			(xy 48.119792 -375.893584) (xy 48.119792 -376.386852) (xy 48.120227 -376.396037) (xy 48.126724 -376.413221)
			(xy 48.132492 -376.42038) (xy 48.154283 -376.446029) (xy 48.192229 -376.501617) (xy 48.223261 -376.561341)
			(xy 48.246932 -376.624346) (xy 48.262904 -376.689728) (xy 48.270947 -376.756551) (xy 73.548976 -376.756551)
			(xy 73.55702 -376.689728) (xy 73.572992 -376.624347) (xy 73.596664 -376.561342) (xy 73.627697 -376.501619)
			(xy 73.665645 -376.446032) (xy 73.687432 -376.42038) (xy 73.693224 -376.413231) (xy 73.699741 -376.396043)
			(xy 73.700132 -376.386852) (xy 73.700132 -375.893584) (xy 73.699722 -375.884397) (xy 73.693208 -375.867213)
			(xy 73.687432 -375.860056) (xy 73.665676 -375.834378) (xy 73.627727 -375.778795) (xy 73.596693 -375.719075)
			(xy 73.573018 -375.656074) (xy 73.557043 -375.590695) (xy 73.548997 -375.523875) (xy 73.548994 -375.456573)
			(xy 73.557035 -375.389753) (xy 73.573004 -375.324372) (xy 73.596673 -375.261369) (xy 73.627702 -375.201647)
			(xy 73.665647 -375.14606) (xy 73.687432 -375.120408) (xy 73.693212 -375.113251) (xy 73.699736 -375.096069)
			(xy 73.700132 -375.08688) (xy 73.700132 -374.928638) (xy 73.700595 -374.91847) (xy 73.708366 -374.899677)
			(xy 73.72274 -374.885291) (xy 73.741526 -374.877504) (xy 73.751694 -374.877076) (xy 74.467974 -374.877076)
			(xy 74.478149 -374.877486) (xy 74.49695 -374.88527) (xy 74.511337 -374.89966) (xy 74.519116 -374.918463)
			(xy 74.519536 -374.928638) (xy 74.519536 -375.08688) (xy 74.51997 -375.096064) (xy 74.526469 -375.113248)
			(xy 74.532236 -375.120408) (xy 74.554056 -375.146034) (xy 74.592006 -375.201623) (xy 74.623039 -375.26135)
			(xy 74.646711 -375.324358) (xy 74.662683 -375.389744) (xy 74.670725 -375.45657) (xy 74.670722 -375.523878)
			(xy 74.662674 -375.590703) (xy 74.646697 -375.656088) (xy 74.623019 -375.719094) (xy 74.591981 -375.778818)
			(xy 74.554027 -375.834404) (xy 74.532236 -375.860056) (xy 74.526425 -375.867191) (xy 74.519921 -375.88439)
			(xy 74.519536 -375.893584) (xy 74.519536 -376.386852) (xy 74.519983 -376.396035) (xy 74.526473 -376.413219)
			(xy 74.532236 -376.42038) (xy 74.554028 -376.446029) (xy 74.591979 -376.501615) (xy 74.623013 -376.561339)
			(xy 74.646687 -376.624344) (xy 74.66266 -376.689727) (xy 74.670704 -376.75655) (xy 74.670704 -376.823856)
			(xy 74.670697 -376.823915) (xy 77.948745 -376.823915) (xy 77.948745 -376.756491) (xy 77.956821 -376.689553)
			(xy 77.972856 -376.624063) (xy 77.996621 -376.560967) (xy 78.027773 -376.501171) (xy 78.065863 -376.445537)
			(xy 78.087728 -376.419872) (xy 78.093523 -376.412726) (xy 78.100038 -376.395536) (xy 78.100428 -376.386344)
			(xy 78.100428 -375.894092) (xy 78.100016 -375.884905) (xy 78.093503 -375.867721) (xy 78.087728 -375.860564)
			(xy 78.065894 -375.834873) (xy 78.027803 -375.779243) (xy 77.996649 -375.719451) (xy 77.972882 -375.656357)
			(xy 77.956844 -375.590871) (xy 77.948765 -375.523935) (xy 77.948762 -375.456513) (xy 77.956835 -375.389577)
			(xy 77.972868 -375.324089) (xy 77.99663 -375.260993) (xy 78.027778 -375.201198) (xy 78.065865 -375.145565)
			(xy 78.087728 -375.1199) (xy 78.093511 -375.112745) (xy 78.100033 -375.095562) (xy 78.100428 -375.086372)
			(xy 78.100428 -374.928638) (xy 78.100958 -374.918515) (xy 78.108671 -374.899797) (xy 78.122944 -374.88544)
			(xy 78.141616 -374.877618) (xy 78.151736 -374.877076) (xy 78.868016 -374.877076) (xy 78.878123 -374.877572)
			(xy 78.896797 -374.88531) (xy 78.91109 -374.899603) (xy 78.918828 -374.918277) (xy 78.919324 -374.928384)
			(xy 78.919324 -375.086372) (xy 78.919742 -375.095558) (xy 78.92625 -375.112743) (xy 78.932024 -375.1199)
			(xy 78.953919 -375.14554) (xy 78.992005 -375.201178) (xy 79.023153 -375.260978) (xy 79.046914 -375.324079)
			(xy 79.062947 -375.38957) (xy 79.07102 -375.456511) (xy 79.071017 -375.523937) (xy 79.062938 -375.590877)
			(xy 79.0469 -375.656367) (xy 79.023133 -375.719466) (xy 78.99198 -375.779263) (xy 78.953889 -375.834898)
			(xy 78.932024 -375.860564) (xy 78.926221 -375.867704) (xy 78.919709 -375.884898) (xy 78.919324 -375.894092)
			(xy 78.919324 -376.386344) (xy 78.919708 -376.395534) (xy 78.926239 -376.412718) (xy 78.932024 -376.419872)
			(xy 78.953891 -376.445534) (xy 78.991978 -376.50117) (xy 79.023127 -376.560967) (xy 79.04689 -376.624064)
			(xy 79.062925 -376.689553) (xy 79.071 -376.756491) (xy 79.071 -376.756551) (xy 82.349064 -376.756551)
			(xy 82.357108 -376.689729) (xy 82.373079 -376.624347) (xy 82.396751 -376.561343) (xy 82.427782 -376.501619)
			(xy 82.465729 -376.446032) (xy 82.487516 -376.42038) (xy 82.493305 -376.41323) (xy 82.499824 -376.396043)
			(xy 82.500216 -376.386852) (xy 82.500216 -375.893584) (xy 82.49981 -375.884396) (xy 82.493293 -375.867212)
			(xy 82.487516 -375.860056) (xy 82.46576 -375.834378) (xy 82.427812 -375.778795) (xy 82.396779 -375.719074)
			(xy 82.373105 -375.656073) (xy 82.357131 -375.590694) (xy 82.349084 -375.523875) (xy 82.349081 -375.456573)
			(xy 82.357122 -375.389753) (xy 82.373091 -375.324373) (xy 82.396759 -375.26137) (xy 82.427787 -375.201647)
			(xy 82.465731 -375.14606) (xy 82.487516 -375.120408) (xy 82.493294 -375.113249) (xy 82.499819 -375.096069)
			(xy 82.500216 -375.08688) (xy 82.500216 -374.928638) (xy 82.500694 -374.918472) (xy 82.508463 -374.899682)
			(xy 82.522832 -374.885297) (xy 82.541612 -374.877506) (xy 82.551778 -374.877076) (xy 83.268058 -374.877076)
			(xy 83.278232 -374.877499) (xy 83.297033 -374.885277) (xy 83.31142 -374.899664) (xy 83.3192 -374.918464)
			(xy 83.31962 -374.928638) (xy 83.31962 -375.08688) (xy 83.320035 -375.096067) (xy 83.326545 -375.113251)
			(xy 83.33232 -375.120408) (xy 83.35414 -375.146034) (xy 83.392091 -375.201623) (xy 83.423125 -375.26135)
			(xy 83.446798 -375.324358) (xy 83.46277 -375.389744) (xy 83.470812 -375.45657) (xy 83.470809 -375.523878)
			(xy 83.462761 -375.590704) (xy 83.446784 -375.656088) (xy 83.423105 -375.719094) (xy 83.392066 -375.778818)
			(xy 83.354111 -375.834404) (xy 83.33232 -375.860056) (xy 83.326519 -375.867199) (xy 83.320007 -375.884391)
			(xy 83.31962 -375.893584) (xy 83.31962 -376.386852) (xy 83.320049 -376.396037) (xy 83.326549 -376.413222)
			(xy 83.33232 -376.42038) (xy 83.354113 -376.446028) (xy 83.392064 -376.501614) (xy 83.4231 -376.561338)
			(xy 83.446774 -376.624343) (xy 83.462748 -376.689726) (xy 83.470792 -376.75655) (xy 83.470792 -376.823856)
			(xy 83.470785 -376.823915) (xy 86.748833 -376.823915) (xy 86.748833 -376.756491) (xy 86.756908 -376.689553)
			(xy 86.772944 -376.624064) (xy 86.796708 -376.560967) (xy 86.827859 -376.501171) (xy 86.865948 -376.445537)
			(xy 86.887812 -376.419872) (xy 86.893604 -376.412724) (xy 86.900121 -376.395536) (xy 86.900512 -376.386344)
			(xy 86.900512 -375.894092) (xy 86.900103 -375.884905) (xy 86.893588 -375.86772) (xy 86.887812 -375.860564)
			(xy 86.865979 -375.834873) (xy 86.827889 -375.779242) (xy 86.796736 -375.71945) (xy 86.772969 -375.656356)
			(xy 86.756931 -375.59087) (xy 86.748853 -375.523935) (xy 86.74885 -375.456513) (xy 86.756923 -375.389577)
			(xy 86.772955 -375.32409) (xy 86.796716 -375.260994) (xy 86.827864 -375.201199) (xy 86.86595 -375.145565)
			(xy 86.887812 -375.1199) (xy 86.893592 -375.112743) (xy 86.900116 -375.095562) (xy 86.900512 -375.086372)
			(xy 86.900512 -374.928638) (xy 86.901057 -374.918517) (xy 86.908767 -374.899802) (xy 86.923035 -374.885446)
			(xy 86.941702 -374.87762) (xy 86.95182 -374.877076) (xy 87.6681 -374.877076) (xy 87.678206 -374.877585)
			(xy 87.696879 -374.885318) (xy 87.711173 -374.899607) (xy 87.718912 -374.918278) (xy 87.719408 -374.928384)
			(xy 87.719408 -375.086372) (xy 87.71983 -375.095558) (xy 87.726335 -375.112743) (xy 87.732108 -375.1199)
			(xy 87.754003 -375.145539) (xy 87.79209 -375.201178) (xy 87.798441 -375.213371) (xy 104.681961 -375.213371)
			(xy 104.681961 -375.153429) (xy 104.689785 -375.094001) (xy 104.7053 -375.036103) (xy 104.72824 -374.980725)
			(xy 104.758212 -374.928815) (xy 104.794703 -374.881262) (xy 104.837089 -374.838879) (xy 104.884645 -374.802391)
			(xy 104.936557 -374.772424) (xy 104.991937 -374.749489) (xy 105.049837 -374.733978) (xy 105.109265 -374.726159)
			(xy 105.139236 -374.725692) (xy 106.002836 -374.725692) (xy 106.032802 -374.726184) (xy 106.092221 -374.734011)
			(xy 106.15011 -374.749527) (xy 106.205479 -374.772465) (xy 106.25738 -374.802434) (xy 106.304926 -374.838921)
			(xy 106.347303 -374.881301) (xy 106.383786 -374.92885) (xy 106.413751 -374.980753) (xy 106.436685 -375.036124)
			(xy 106.452196 -375.094014) (xy 106.460018 -375.153434) (xy 106.460018 -375.213366) (xy 106.452196 -375.272786)
			(xy 106.436685 -375.330676) (xy 106.413751 -375.386047) (xy 106.383786 -375.43795) (xy 106.347303 -375.485499)
			(xy 106.304926 -375.527879) (xy 106.25738 -375.564366) (xy 106.205479 -375.594335) (xy 106.15011 -375.617273)
			(xy 106.092221 -375.632789) (xy 106.032802 -375.640616) (xy 106.002836 -375.641108) (xy 105.139236 -375.641108)
			(xy 105.109265 -375.640641) (xy 105.049837 -375.632822) (xy 104.991937 -375.617311) (xy 104.936557 -375.594376)
			(xy 104.884645 -375.564409) (xy 104.837089 -375.527921) (xy 104.794703 -375.485538) (xy 104.758212 -375.437985)
			(xy 104.72824 -375.386075) (xy 104.7053 -375.330697) (xy 104.689785 -375.272799) (xy 104.681961 -375.213371)
			(xy 87.798441 -375.213371) (xy 87.823239 -375.260978) (xy 87.847001 -375.324078) (xy 87.863034 -375.38957)
			(xy 87.871107 -375.456511) (xy 87.871105 -375.523937) (xy 87.863026 -375.590877) (xy 87.846987 -375.656368)
			(xy 87.82322 -375.719466) (xy 87.792066 -375.779263) (xy 87.753974 -375.834899) (xy 87.732108 -375.860564)
			(xy 87.726303 -375.867703) (xy 87.719793 -375.884898) (xy 87.719408 -375.894092) (xy 87.719408 -376.386344)
			(xy 87.719795 -376.395534) (xy 87.726324 -376.412718) (xy 87.732108 -376.419872) (xy 87.753976 -376.445534)
			(xy 87.792064 -376.501169) (xy 87.823214 -376.560966) (xy 87.846977 -376.624063) (xy 87.863012 -376.689553)
			(xy 87.871088 -376.756491) (xy 87.871087 -376.823915) (xy 117.548863 -376.823915) (xy 117.548863 -376.756491)
			(xy 117.556939 -376.689552) (xy 117.572976 -376.624062) (xy 117.596742 -376.560965) (xy 117.627895 -376.50117)
			(xy 117.665986 -376.445536) (xy 117.687852 -376.419872) (xy 117.693649 -376.412728) (xy 117.700162 -376.395536)
			(xy 117.700552 -376.386344) (xy 117.700552 -375.894092) (xy 117.700134 -375.884906) (xy 117.693625 -375.867722)
			(xy 117.687852 -375.860564) (xy 117.666018 -375.834874) (xy 117.627925 -375.779244) (xy 117.59677 -375.719452)
			(xy 117.573001 -375.656358) (xy 117.556962 -375.590871) (xy 117.548883 -375.523935) (xy 117.54888 -375.456513)
			(xy 117.556953 -375.389576) (xy 117.572987 -375.324088) (xy 117.59675 -375.260992) (xy 117.6279 -375.201197)
			(xy 117.665988 -375.145564) (xy 117.687852 -375.1199) (xy 117.693638 -375.112747) (xy 117.700157 -375.095562)
			(xy 117.700552 -375.086372) (xy 117.700552 -374.928638) (xy 117.701058 -374.918512) (xy 117.708776 -374.89979)
			(xy 117.723056 -374.885432) (xy 117.741737 -374.877613) (xy 117.75186 -374.877076) (xy 118.46814 -374.877076)
			(xy 118.478294 -374.877488) (xy 118.497042 -374.885293) (xy 118.511363 -374.899691) (xy 118.519066 -374.918482)
			(xy 118.519448 -374.928638) (xy 118.519448 -375.086372) (xy 118.519883 -375.095556) (xy 118.526381 -375.11274)
			(xy 118.532148 -375.1199) (xy 118.554045 -375.145538) (xy 118.592136 -375.201176) (xy 118.623289 -375.260975)
			(xy 118.647053 -375.324075) (xy 118.663088 -375.389568) (xy 118.671162 -375.45651) (xy 118.671159 -375.523938)
			(xy 118.66308 -375.590879) (xy 118.647039 -375.656371) (xy 118.623269 -375.719469) (xy 118.592112 -375.779266)
			(xy 118.554016 -375.8349) (xy 118.532148 -375.860564) (xy 118.526335 -375.867698) (xy 118.519832 -375.884897)
			(xy 118.519448 -375.894092) (xy 118.519448 -376.386344) (xy 118.519849 -376.395532) (xy 118.52637 -376.412715)
			(xy 118.532148 -376.419872) (xy 118.554018 -376.445533) (xy 118.59211 -376.501167) (xy 118.623263 -376.560963)
			(xy 118.647029 -376.624061) (xy 118.663066 -376.689551) (xy 118.671143 -376.75649) (xy 118.671143 -376.756551)
			(xy 121.949182 -376.756551) (xy 121.957226 -376.689728) (xy 121.973199 -376.624346) (xy 121.996871 -376.561342)
			(xy 122.027904 -376.501618) (xy 122.065852 -376.446032) (xy 122.08764 -376.42038) (xy 122.093433 -376.413232)
			(xy 122.099949 -376.396044) (xy 122.10034 -376.386852) (xy 122.10034 -375.893584) (xy 122.099929 -375.884397)
			(xy 122.093415 -375.867213) (xy 122.08764 -375.860056) (xy 122.065884 -375.834378) (xy 122.027934 -375.778795)
			(xy 121.996899 -375.719075) (xy 121.973225 -375.656074) (xy 121.95725 -375.590695) (xy 121.949203 -375.523875)
			(xy 121.9492 -375.456573) (xy 121.957241 -375.389752) (xy 121.973211 -375.324372) (xy 121.99688 -375.261369)
			(xy 122.027909 -375.201646) (xy 122.065854 -375.14606) (xy 122.08764 -375.120408) (xy 122.093421 -375.113252)
			(xy 122.099944 -375.09607) (xy 122.10034 -375.08688) (xy 122.10034 -374.928638) (xy 122.100795 -374.918469)
			(xy 122.108568 -374.899674) (xy 122.122944 -374.885288) (xy 122.141733 -374.877502) (xy 122.151902 -374.877076)
			(xy 122.868182 -374.877076) (xy 122.878357 -374.877479) (xy 122.897159 -374.885265) (xy 122.911546 -374.899658)
			(xy 122.919325 -374.918463) (xy 122.919744 -374.928638) (xy 122.919744 -375.08688) (xy 122.920176 -375.096065)
			(xy 122.926676 -375.113249) (xy 122.932444 -375.120408) (xy 122.954264 -375.146034) (xy 122.992213 -375.201624)
			(xy 123.023246 -375.261351) (xy 123.046917 -375.324359) (xy 123.062889 -375.389744) (xy 123.070931 -375.45657)
			(xy 123.070928 -375.523878) (xy 123.06288 -375.590703) (xy 123.046903 -375.656087) (xy 123.023226 -375.719093)
			(xy 122.992188 -375.778818) (xy 122.954234 -375.834404) (xy 122.932444 -375.860056) (xy 122.926634 -375.867192)
			(xy 122.920129 -375.88439) (xy 122.919744 -375.893584) (xy 122.919744 -376.386852) (xy 122.92019 -376.396035)
			(xy 122.92668 -376.413219) (xy 122.932444 -376.42038) (xy 122.954236 -376.446029) (xy 122.992186 -376.501615)
			(xy 123.02322 -376.561339) (xy 123.046893 -376.624344) (xy 123.062866 -376.689727) (xy 123.07091 -376.75655)
			(xy 123.07091 -376.823856) (xy 123.070903 -376.823915) (xy 126.348951 -376.823915) (xy 126.348951 -376.756491)
			(xy 126.357027 -376.689552) (xy 126.373063 -376.624063) (xy 126.396828 -376.560966) (xy 126.42798 -376.50117)
			(xy 126.466071 -376.445537) (xy 126.487936 -376.419872) (xy 126.493732 -376.412726) (xy 126.500246 -376.395536)
			(xy 126.500636 -376.386344) (xy 126.500636 -375.894092) (xy 126.500222 -375.884905) (xy 126.49371 -375.867721)
			(xy 126.487936 -375.860564) (xy 126.466102 -375.834873) (xy 126.42801 -375.779243) (xy 126.396856 -375.719451)
			(xy 126.373088 -375.656357) (xy 126.35705 -375.590871) (xy 126.348971 -375.523935) (xy 126.348968 -375.456513)
			(xy 126.357041 -375.389576) (xy 126.373074 -375.324089) (xy 126.396836 -375.260993) (xy 126.427985 -375.201198)
			(xy 126.466073 -375.145565) (xy 126.487936 -375.1199) (xy 126.49372 -375.112746) (xy 126.500241 -375.095562)
			(xy 126.500636 -375.086372) (xy 126.500636 -374.928638) (xy 126.501158 -374.918514) (xy 126.508872 -374.899795)
			(xy 126.523148 -374.885437) (xy 126.541823 -374.877616) (xy 126.551944 -374.877076) (xy 127.268224 -374.877076)
			(xy 127.278377 -374.877501) (xy 127.297125 -374.8853) (xy 127.311447 -374.899695) (xy 127.31915 -374.918483)
			(xy 127.319532 -374.928638) (xy 127.319532 -375.086372) (xy 127.319971 -375.095556) (xy 127.326466 -375.11274)
			(xy 127.332232 -375.1199) (xy 127.354126 -375.14554) (xy 127.392212 -375.201179) (xy 127.423359 -375.260979)
			(xy 127.44712 -375.324079) (xy 127.463153 -375.389571) (xy 127.471226 -375.456511) (xy 127.471223 -375.523937)
			(xy 127.463144 -375.590877) (xy 127.447106 -375.656367) (xy 127.42334 -375.719465) (xy 127.392187 -375.779263)
			(xy 127.354097 -375.834898) (xy 127.332232 -375.860564) (xy 127.326417 -375.867696) (xy 127.319915 -375.884897)
			(xy 127.319532 -375.894092) (xy 127.319532 -376.386344) (xy 127.319936 -376.395532) (xy 127.326456 -376.412715)
			(xy 127.332232 -376.419872) (xy 127.354099 -376.445535) (xy 127.392185 -376.50117) (xy 127.423334 -376.560967)
			(xy 127.447097 -376.624064) (xy 127.463131 -376.689553) (xy 127.471206 -376.756491) (xy 127.471206 -376.756551)
			(xy 130.74927 -376.756551) (xy 130.757314 -376.689729) (xy 130.773286 -376.624347) (xy 130.796958 -376.561343)
			(xy 130.827989 -376.501619) (xy 130.865937 -376.446032) (xy 130.887724 -376.42038) (xy 130.893514 -376.413231)
			(xy 130.900032 -376.396043) (xy 130.900424 -376.386852) (xy 130.900424 -375.893584) (xy 130.900016 -375.884397)
			(xy 130.8935 -375.867213) (xy 130.887724 -375.860056) (xy 130.865968 -375.834378) (xy 130.82802 -375.778795)
			(xy 130.796986 -375.719074) (xy 130.773312 -375.656073) (xy 130.757337 -375.590695) (xy 130.749291 -375.523875)
			(xy 130.749288 -375.456573) (xy 130.757329 -375.389753) (xy 130.773298 -375.324373) (xy 130.796966 -375.26137)
			(xy 130.827995 -375.201647) (xy 130.865939 -375.146061) (xy 130.887724 -375.120408) (xy 130.893502 -375.11325)
			(xy 130.900027 -375.096069) (xy 130.900424 -375.08688) (xy 130.900424 -374.928638) (xy 130.900895 -374.918471)
			(xy 130.908665 -374.899679) (xy 130.923036 -374.885294) (xy 130.941819 -374.877505) (xy 130.951986 -374.877076)
			(xy 131.668266 -374.877076) (xy 131.67844 -374.877493) (xy 131.697241 -374.885274) (xy 131.711629 -374.899662)
			(xy 131.719408 -374.918464) (xy 131.719828 -374.928638) (xy 131.719828 -375.08688) (xy 131.720241 -375.096067)
			(xy 131.726752 -375.113252) (xy 131.732528 -375.120408) (xy 131.754348 -375.146034) (xy 131.792298 -375.201623)
			(xy 131.823332 -375.26135) (xy 131.847005 -375.324358) (xy 131.862976 -375.389744) (xy 131.871018 -375.45657)
			(xy 131.871016 -375.523878) (xy 131.862968 -375.590704) (xy 131.84699 -375.656088) (xy 131.823313 -375.719094)
			(xy 131.792274 -375.778818) (xy 131.754319 -375.834404) (xy 131.732528 -375.860056) (xy 131.726716 -375.86719)
			(xy 131.720213 -375.884389) (xy 131.719828 -375.893584) (xy 131.719828 -376.386852) (xy 131.720255 -376.396037)
			(xy 131.726756 -376.413222) (xy 131.732528 -376.42038) (xy 131.754321 -376.446029) (xy 131.792271 -376.501615)
			(xy 131.823306 -376.561338) (xy 131.84698 -376.624344) (xy 131.862954 -376.689727) (xy 131.870991 -376.756492)
			(xy 161.548796 -376.756492) (xy 161.556871 -376.689554) (xy 161.572905 -376.624066) (xy 161.596667 -376.560969)
			(xy 161.627816 -376.501173) (xy 161.665902 -376.445538) (xy 161.687764 -376.419872) (xy 161.693563 -376.412729)
			(xy 161.700074 -376.395536) (xy 161.700464 -376.386344) (xy 161.700464 -375.894092) (xy 161.700043 -375.884906)
			(xy 161.693535 -375.867723) (xy 161.687764 -375.860564) (xy 161.665933 -375.834872) (xy 161.627845 -375.779241)
			(xy 161.596695 -375.719448) (xy 161.572931 -375.656354) (xy 161.556894 -375.590869) (xy 161.548816 -375.523934)
			(xy 161.548814 -375.456514) (xy 161.556886 -375.389578) (xy 161.572917 -375.324092) (xy 161.596676 -375.260996)
			(xy 161.627821 -375.201201) (xy 161.665903 -375.145566) (xy 161.687764 -375.1199) (xy 161.693551 -375.112748)
			(xy 161.70007 -375.095562) (xy 161.700464 -375.086372) (xy 161.700464 -374.928638) (xy 161.700959 -374.918511)
			(xy 161.708678 -374.899786) (xy 161.722963 -374.885428) (xy 161.741647 -374.877611) (xy 161.751772 -374.877076)
			(xy 162.468052 -374.877076) (xy 162.478168 -374.877555) (xy 162.496866 -374.885283) (xy 162.511181 -374.89958)
			(xy 162.518933 -374.918268) (xy 162.51936 -374.928384) (xy 162.51936 -375.086372) (xy 162.519793 -375.095557)
			(xy 162.526292 -375.112741) (xy 162.53206 -375.1199) (xy 162.553957 -375.145539) (xy 162.592047 -375.201176)
			(xy 162.623199 -375.260976) (xy 162.646963 -375.324076) (xy 162.662997 -375.389569) (xy 162.671071 -375.456511)
			(xy 162.671068 -375.523938) (xy 162.662989 -375.590879) (xy 162.646949 -375.65637) (xy 162.623179 -375.719468)
			(xy 162.592022 -375.779265) (xy 162.553927 -375.834899) (xy 162.53206 -375.860564) (xy 162.526249 -375.867699)
			(xy 162.519744 -375.884897) (xy 162.51936 -375.894092) (xy 162.51936 -376.386344) (xy 162.519758 -376.395532)
			(xy 162.526281 -376.412716) (xy 162.53206 -376.419872) (xy 162.553929 -376.445533) (xy 162.592021 -376.501167)
			(xy 162.623173 -376.560964) (xy 162.646939 -376.624061) (xy 162.662975 -376.689551) (xy 162.671052 -376.756491)
			(xy 162.671051 -376.823855) (xy 165.949092 -376.823855) (xy 165.949092 -376.756551) (xy 165.957136 -376.689728)
			(xy 165.973109 -376.624346) (xy 165.996782 -376.561342) (xy 166.027815 -376.501618) (xy 166.065764 -376.446032)
			(xy 166.087552 -376.42038) (xy 166.093346 -376.413233) (xy 166.099861 -376.396044) (xy 166.100252 -376.386852)
			(xy 166.100252 -375.893584) (xy 166.099838 -375.884397) (xy 166.093326 -375.867214) (xy 166.087552 -375.860056)
			(xy 166.065795 -375.834378) (xy 166.027845 -375.778796) (xy 165.996809 -375.719076) (xy 165.973134 -375.656075)
			(xy 165.957159 -375.590695) (xy 165.949112 -375.523875) (xy 165.949109 -375.456573) (xy 165.95715 -375.389752)
			(xy 165.97312 -375.324371) (xy 165.99679 -375.261368) (xy 166.02782 -375.201646) (xy 166.065766 -375.14606)
			(xy 166.087552 -375.120408) (xy 166.093334 -375.113253) (xy 166.099856 -375.09607) (xy 166.100252 -375.08688)
			(xy 166.100252 -374.928638) (xy 166.100695 -374.918467) (xy 166.10847 -374.899671) (xy 166.12285 -374.885284)
			(xy 166.141643 -374.8775) (xy 166.151814 -374.877076) (xy 166.868094 -374.877076) (xy 166.87827 -374.87747)
			(xy 166.897072 -374.88526) (xy 166.911458 -374.899655) (xy 166.919237 -374.918462) (xy 166.919656 -374.928638)
			(xy 166.919656 -375.08688) (xy 166.920085 -375.096065) (xy 166.926587 -375.113249) (xy 166.932356 -375.120408)
			(xy 166.954175 -375.146034) (xy 166.992124 -375.201624) (xy 167.023156 -375.261351) (xy 167.046827 -375.324359)
			(xy 167.062798 -375.389745) (xy 167.07084 -375.45657) (xy 167.070837 -375.523878) (xy 167.062789 -375.590703)
			(xy 167.046813 -375.656087) (xy 167.023136 -375.719093) (xy 166.992099 -375.778817) (xy 166.954146 -375.834404)
			(xy 166.932356 -375.860056) (xy 166.926548 -375.867193) (xy 166.920041 -375.88439) (xy 166.919656 -375.893584)
			(xy 166.919656 -376.386852) (xy 166.920099 -376.396035) (xy 166.926591 -376.41322) (xy 166.932356 -376.42038)
			(xy 166.954148 -376.446029) (xy 166.992097 -376.501616) (xy 167.02313 -376.56134) (xy 167.046803 -376.624345)
			(xy 167.062776 -376.689727) (xy 167.07082 -376.75655) (xy 167.07082 -376.823856) (xy 167.070813 -376.823915)
			(xy 170.34886 -376.823915) (xy 170.34886 -376.756491) (xy 170.356936 -376.689552) (xy 170.372972 -376.624063)
			(xy 170.396738 -376.560966) (xy 170.427891 -376.50117) (xy 170.465983 -376.445536) (xy 170.487848 -376.419872)
			(xy 170.493645 -376.412727) (xy 170.500158 -376.395536) (xy 170.500548 -376.386344) (xy 170.500548 -375.894092)
			(xy 170.500131 -375.884906) (xy 170.493621 -375.867722) (xy 170.487848 -375.860564) (xy 170.466014 -375.834874)
			(xy 170.427921 -375.779244) (xy 170.396766 -375.719452) (xy 170.372998 -375.656358) (xy 170.356959 -375.590871)
			(xy 170.34888 -375.523935) (xy 170.348877 -375.456513) (xy 170.35695 -375.389576) (xy 170.372984 -375.324088)
			(xy 170.396747 -375.260992) (xy 170.427896 -375.201197) (xy 170.465984 -375.145564) (xy 170.487848 -375.1199)
			(xy 170.493633 -375.112747) (xy 170.500153 -375.095562) (xy 170.500548 -375.086372) (xy 170.500548 -374.928638)
			(xy 170.501058 -374.918513) (xy 170.508775 -374.899791) (xy 170.523054 -374.885433) (xy 170.541734 -374.877614)
			(xy 170.551856 -374.877076) (xy 171.268136 -374.877076) (xy 171.278289 -374.877492) (xy 171.297038 -374.885295)
			(xy 171.311359 -374.899692) (xy 171.319062 -374.918482) (xy 171.319444 -374.928638) (xy 171.319444 -375.086372)
			(xy 171.31988 -375.095556) (xy 171.326377 -375.11274) (xy 171.332144 -375.1199) (xy 171.354041 -375.145538)
			(xy 171.392133 -375.201175) (xy 171.423285 -375.260975) (xy 171.44705 -375.324075) (xy 171.463085 -375.389568)
			(xy 171.471159 -375.45651) (xy 171.471156 -375.523938) (xy 171.463076 -375.590879) (xy 171.447036 -375.656371)
			(xy 171.423266 -375.719469) (xy 171.392108 -375.779266) (xy 171.354012 -375.8349) (xy 171.332144 -375.860564)
			(xy 171.326331 -375.867697) (xy 171.319828 -375.884897) (xy 171.319444 -375.894092) (xy 171.319444 -376.386344)
			(xy 171.319845 -376.395532) (xy 171.326366 -376.412716) (xy 171.332144 -376.419872) (xy 171.354014 -376.445533)
			(xy 171.392106 -376.501167) (xy 171.42326 -376.560963) (xy 171.447026 -376.624061) (xy 171.463063 -376.689551)
			(xy 171.47114 -376.75649) (xy 171.47114 -376.756551) (xy 174.749179 -376.756551) (xy 174.757223 -376.689728)
			(xy 174.773195 -376.624346) (xy 174.796868 -376.561342) (xy 174.8279 -376.501619) (xy 174.865848 -376.446032)
			(xy 174.887636 -376.42038) (xy 174.893428 -376.413232) (xy 174.899945 -376.396043) (xy 174.900336 -376.386852)
			(xy 174.900336 -375.893584) (xy 174.899926 -375.884397) (xy 174.893411 -375.867213) (xy 174.887636 -375.860056)
			(xy 174.86588 -375.834378) (xy 174.82793 -375.778795) (xy 174.796896 -375.719075) (xy 174.773222 -375.656074)
			(xy 174.757246 -375.590695) (xy 174.7492 -375.523875) (xy 174.749197 -375.456573) (xy 174.757238 -375.389752)
			(xy 174.773207 -375.324372) (xy 174.796876 -375.261369) (xy 174.827906 -375.201646) (xy 174.865851 -375.14606)
			(xy 174.887636 -375.120408) (xy 174.893416 -375.113251) (xy 174.89994 -375.096069) (xy 174.900336 -375.08688)
			(xy 174.900336 -374.928638) (xy 174.900795 -374.918469) (xy 174.908567 -374.899676) (xy 174.922942 -374.88529)
			(xy 174.941729 -374.877503) (xy 174.951898 -374.877076) (xy 175.668178 -374.877076) (xy 175.678353 -374.877483)
			(xy 175.697154 -374.885268) (xy 175.711541 -374.899659) (xy 175.71932 -374.918463) (xy 175.71974 -374.928638)
			(xy 175.71974 -375.08688) (xy 175.720173 -375.096064) (xy 175.726672 -375.113248) (xy 175.73244 -375.120408)
			(xy 175.75426 -375.146034) (xy 175.792209 -375.201624) (xy 175.823242 -375.261351) (xy 175.846914 -375.324359)
			(xy 175.862886 -375.389744) (xy 175.870928 -375.45657) (xy 175.870925 -375.523878) (xy 175.862877 -375.590703)
			(xy 175.8469 -375.656087) (xy 175.823223 -375.719093) (xy 175.792185 -375.778818) (xy 175.754231 -375.834404)
			(xy 175.73244 -375.860056) (xy 175.72663 -375.867191) (xy 175.720125 -375.88439) (xy 175.71974 -375.893584)
			(xy 175.71974 -376.386852) (xy 175.720186 -376.396035) (xy 175.726676 -376.413219) (xy 175.73244 -376.42038)
			(xy 175.754232 -376.446029) (xy 175.792182 -376.501615) (xy 175.823216 -376.561339) (xy 175.84689 -376.624344)
			(xy 175.862863 -376.689727) (xy 175.870907 -376.75655) (xy 175.870907 -376.823856) (xy 175.862862 -376.890679)
			(xy 175.846888 -376.956062) (xy 175.823214 -377.019066) (xy 175.792179 -377.07879) (xy 175.754228 -377.134376)
			(xy 175.73244 -377.160028) (xy 175.726642 -377.167172) (xy 175.72013 -377.184364) (xy 175.71974 -377.193556)
			(xy 175.71974 -377.35129) (xy 175.719328 -377.361464) (xy 175.711542 -377.380262) (xy 175.697152 -377.394648)
			(xy 175.678352 -377.40243) (xy 175.668178 -377.402852) (xy 174.951898 -377.402852) (xy 174.941725 -377.402438)
			(xy 174.922928 -377.39465) (xy 174.908543 -377.380262) (xy 174.90076 -377.361463) (xy 174.900336 -377.35129)
			(xy 174.900336 -377.193556) (xy 174.899939 -377.184368) (xy 174.893415 -377.167184) (xy 174.887636 -377.160028)
			(xy 174.865852 -377.134373) (xy 174.827903 -377.078787) (xy 174.79687 -377.019063) (xy 174.773197 -376.956059)
			(xy 174.757224 -376.890678) (xy 174.74918 -376.823855) (xy 174.749179 -376.756551) (xy 171.47114 -376.756551)
			(xy 171.471139 -376.823916) (xy 171.463062 -376.890855) (xy 171.447024 -376.956345) (xy 171.423257 -377.019442)
			(xy 171.392103 -377.079238) (xy 171.35401 -377.134872) (xy 171.332144 -377.160536) (xy 171.326343 -377.167678)
			(xy 171.319832 -377.184871) (xy 171.319444 -377.194064) (xy 171.319444 -377.35129) (xy 171.318965 -377.361418)
			(xy 171.311237 -377.380142) (xy 171.296948 -377.394499) (xy 171.278262 -377.402316) (xy 171.268136 -377.402852)
			(xy 170.551856 -377.402852) (xy 170.541706 -377.402415) (xy 170.522962 -377.394615) (xy 170.508642 -377.380224)
			(xy 170.500935 -377.361442) (xy 170.500548 -377.35129) (xy 170.500548 -377.194064) (xy 170.500144 -377.184876)
			(xy 170.493625 -377.167693) (xy 170.487848 -377.160536) (xy 170.465986 -377.134868) (xy 170.427894 -377.079235)
			(xy 170.396741 -377.01944) (xy 170.372974 -376.956343) (xy 170.356937 -376.890854) (xy 170.34886 -376.823915)
			(xy 167.070813 -376.823915) (xy 167.062775 -376.890679) (xy 167.046801 -376.956061) (xy 167.023128 -377.019066)
			(xy 166.992094 -377.07879) (xy 166.954144 -377.134376) (xy 166.932356 -377.160028) (xy 166.92656 -377.167173)
			(xy 166.920046 -377.184364) (xy 166.919656 -377.193556) (xy 166.919656 -377.35129) (xy 166.919228 -377.361462)
			(xy 166.911445 -377.380257) (xy 166.897061 -377.394643) (xy 166.878266 -377.402427) (xy 166.868094 -377.402852)
			(xy 166.151814 -377.402852) (xy 166.141642 -377.402425) (xy 166.122846 -377.394642) (xy 166.10846 -377.380258)
			(xy 166.100676 -377.361462) (xy 166.100252 -377.35129) (xy 166.100252 -377.193556) (xy 166.099851 -377.184368)
			(xy 166.09333 -377.167185) (xy 166.087552 -377.160028) (xy 166.065768 -377.134373) (xy 166.027818 -377.078787)
			(xy 165.996784 -377.019064) (xy 165.97311 -376.95606) (xy 165.957137 -376.890678) (xy 165.949092 -376.823855)
			(xy 162.671051 -376.823855) (xy 162.671051 -376.823915) (xy 162.662974 -376.890855) (xy 162.646937 -376.956344)
			(xy 162.623171 -377.019442) (xy 162.592017 -377.079238) (xy 162.553926 -377.134871) (xy 162.53206 -377.160536)
			(xy 162.526261 -377.167679) (xy 162.519749 -377.184871) (xy 162.51936 -377.194064) (xy 162.51936 -377.35129)
			(xy 162.518865 -377.361416) (xy 162.511141 -377.380137) (xy 162.496857 -377.394494) (xy 162.478175 -377.402313)
			(xy 162.468052 -377.402852) (xy 161.751772 -377.402852) (xy 161.741668 -377.402339) (xy 161.722999 -377.394602)
			(xy 161.708707 -377.380314) (xy 161.700964 -377.361648) (xy 161.700464 -377.351544) (xy 161.700464 -377.194064)
			(xy 161.700057 -377.184877) (xy 161.69354 -377.167693) (xy 161.687764 -377.160536) (xy 161.665905 -377.134867)
			(xy 161.627819 -377.079232) (xy 161.59667 -377.019436) (xy 161.572907 -376.95634) (xy 161.556872 -376.890852)
			(xy 161.548797 -376.823914) (xy 161.548796 -376.756492) (xy 131.870991 -376.756492) (xy 131.870998 -376.75655)
			(xy 131.870998 -376.823856) (xy 131.862953 -376.890679) (xy 131.846979 -376.956062) (xy 131.823304 -377.019067)
			(xy 131.792268 -377.07879) (xy 131.754317 -377.134376) (xy 131.732528 -377.160028) (xy 131.726728 -377.167171)
			(xy 131.720218 -377.184363) (xy 131.719828 -377.193556) (xy 131.719828 -377.35129) (xy 131.719427 -377.361465)
			(xy 131.711639 -377.380266) (xy 131.697246 -377.394653) (xy 131.678441 -377.402432) (xy 131.668266 -377.402852)
			(xy 130.951986 -377.402852) (xy 130.941826 -377.402378) (xy 130.923055 -377.394597) (xy 130.90869 -377.380225)
			(xy 130.900918 -377.36145) (xy 130.900424 -377.35129) (xy 130.900424 -377.193556) (xy 130.90003 -377.184367)
			(xy 130.893504 -377.167183) (xy 130.887724 -377.160028) (xy 130.865941 -377.134372) (xy 130.827993 -377.078786)
			(xy 130.79696 -377.019063) (xy 130.773288 -376.956059) (xy 130.757315 -376.890677) (xy 130.749271 -376.823855)
			(xy 130.74927 -376.756551) (xy 127.471206 -376.756551) (xy 127.471205 -376.823915) (xy 127.46313 -376.890853)
			(xy 127.447095 -376.956342) (xy 127.423332 -377.019438) (xy 127.392182 -377.079235) (xy 127.354095 -377.13487)
			(xy 127.332232 -377.160536) (xy 127.326429 -377.167677) (xy 127.31992 -377.184871) (xy 127.319532 -377.194064)
			(xy 127.319532 -377.35129) (xy 127.319064 -377.36142) (xy 127.311335 -377.380146) (xy 127.297042 -377.394503)
			(xy 127.278351 -377.402318) (xy 127.268224 -377.402852) (xy 126.551944 -377.402852) (xy 126.541799 -377.402343)
			(xy 126.523058 -377.394572) (xy 126.508735 -377.380202) (xy 126.501024 -377.361436) (xy 126.500636 -377.35129)
			(xy 126.500636 -377.194064) (xy 126.500235 -377.184876) (xy 126.493714 -377.167692) (xy 126.487936 -377.160536)
			(xy 126.466075 -377.134868) (xy 126.427984 -377.079235) (xy 126.396831 -377.019439) (xy 126.373065 -376.956343)
			(xy 126.357028 -376.890854) (xy 126.348951 -376.823915) (xy 123.070903 -376.823915) (xy 123.062865 -376.890679)
			(xy 123.046891 -376.956062) (xy 123.023217 -377.019066) (xy 122.992183 -377.07879) (xy 122.954232 -377.134376)
			(xy 122.932444 -377.160028) (xy 122.926646 -377.167172) (xy 122.920134 -377.184364) (xy 122.919744 -377.193556)
			(xy 122.919744 -377.35129) (xy 122.919328 -377.361463) (xy 122.911543 -377.380261) (xy 122.897154 -377.394647)
			(xy 122.878355 -377.402429) (xy 122.868182 -377.402852) (xy 122.151902 -377.402852) (xy 122.141729 -377.402434)
			(xy 122.122933 -377.394648) (xy 122.108547 -377.380261) (xy 122.100764 -377.361463) (xy 122.10034 -377.35129)
			(xy 122.10034 -377.193556) (xy 122.099942 -377.184368) (xy 122.093419 -377.167184) (xy 122.08764 -377.160028)
			(xy 122.065856 -377.134373) (xy 122.027907 -377.078787) (xy 121.996873 -377.019064) (xy 121.9732 -376.95606)
			(xy 121.957227 -376.890678) (xy 121.949183 -376.823855) (xy 121.949182 -376.756551) (xy 118.671143 -376.756551)
			(xy 118.671142 -376.823916) (xy 118.663065 -376.890855) (xy 118.647028 -376.956345) (xy 118.623261 -377.019442)
			(xy 118.592107 -377.079238) (xy 118.554014 -377.134872) (xy 118.532148 -377.160536) (xy 118.526347 -377.167678)
			(xy 118.519836 -377.184871) (xy 118.519448 -377.194064) (xy 118.519448 -377.35129) (xy 118.518965 -377.361418)
			(xy 118.511238 -377.380141) (xy 118.496951 -377.394498) (xy 118.478265 -377.402315) (xy 118.46814 -377.402852)
			(xy 117.75186 -377.402852) (xy 117.74171 -377.402412) (xy 117.722967 -377.394613) (xy 117.708647 -377.380223)
			(xy 117.700939 -377.361442) (xy 117.700552 -377.35129) (xy 117.700552 -377.194064) (xy 117.700147 -377.184876)
			(xy 117.693628 -377.167693) (xy 117.687852 -377.160536) (xy 117.66599 -377.134868) (xy 117.627898 -377.079235)
			(xy 117.596744 -377.01944) (xy 117.572977 -376.956343) (xy 117.55694 -376.890854) (xy 117.548863 -376.823915)
			(xy 87.871087 -376.823915) (xy 87.863011 -376.890853) (xy 87.846976 -376.956342) (xy 87.823211 -377.019439)
			(xy 87.792061 -377.079236) (xy 87.753972 -377.134871) (xy 87.732108 -377.160536) (xy 87.726315 -377.167684)
			(xy 87.719798 -377.184872) (xy 87.719408 -377.194064) (xy 87.719408 -377.35129) (xy 87.718867 -377.36141)
			(xy 87.711151 -377.380122) (xy 87.696882 -377.394477) (xy 87.678217 -377.402305) (xy 87.6681 -377.402852)
			(xy 86.95182 -377.402852) (xy 86.941719 -377.4023) (xy 86.923051 -377.394578) (xy 86.908757 -377.380303)
			(xy 86.901013 -377.361644) (xy 86.900512 -377.351544) (xy 86.900512 -377.194064) (xy 86.900117 -377.184875)
			(xy 86.893592 -377.167691) (xy 86.887812 -377.160536) (xy 86.865952 -377.134868) (xy 86.827862 -377.079234)
			(xy 86.79671 -377.019438) (xy 86.772945 -376.956342) (xy 86.756909 -376.890853) (xy 86.748833 -376.823915)
			(xy 83.470785 -376.823915) (xy 83.462747 -376.89068) (xy 83.446772 -376.956063) (xy 83.423097 -377.019067)
			(xy 83.392061 -377.078791) (xy 83.354109 -377.134376) (xy 83.33232 -377.160028) (xy 83.326531 -377.167179)
			(xy 83.320011 -377.184365) (xy 83.31962 -377.193556) (xy 83.31962 -377.35129) (xy 83.319227 -377.361466)
			(xy 83.311438 -377.380269) (xy 83.297042 -377.394655) (xy 83.278234 -377.402433) (xy 83.268058 -377.402852)
			(xy 82.551778 -377.402852) (xy 82.541618 -377.402385) (xy 82.522846 -377.394601) (xy 82.508481 -377.380227)
			(xy 82.500709 -377.361451) (xy 82.500216 -377.35129) (xy 82.500216 -377.193556) (xy 82.499823 -377.184367)
			(xy 82.493297 -377.167183) (xy 82.487516 -377.160028) (xy 82.465733 -377.134372) (xy 82.427785 -377.078786)
			(xy 82.396753 -377.019063) (xy 82.373081 -376.956059) (xy 82.357109 -376.890677) (xy 82.349065 -376.823855)
			(xy 82.349064 -376.756551) (xy 79.071 -376.756551) (xy 79.070999 -376.823915) (xy 79.062924 -376.890853)
			(xy 79.046888 -376.956342) (xy 79.023125 -377.019439) (xy 78.991975 -377.079235) (xy 78.953887 -377.13487)
			(xy 78.932024 -377.160536) (xy 78.926232 -377.167685) (xy 78.919714 -377.184872) (xy 78.919324 -377.194064)
			(xy 78.919324 -377.35129) (xy 78.918864 -377.36142) (xy 78.911133 -377.380148) (xy 78.896838 -377.394506)
			(xy 78.878144 -377.402319) (xy 78.868016 -377.402852) (xy 78.151736 -377.402852) (xy 78.141636 -377.402286)
			(xy 78.122969 -377.39457) (xy 78.108674 -377.380299) (xy 78.100929 -377.361643) (xy 78.100428 -377.351544)
			(xy 78.100428 -377.194064) (xy 78.100029 -377.184876) (xy 78.093507 -377.167692) (xy 78.087728 -377.160536)
			(xy 78.065867 -377.134868) (xy 78.027776 -377.079235) (xy 77.996624 -377.019439) (xy 77.972858 -376.956342)
			(xy 77.956822 -376.890853) (xy 77.948745 -376.823915) (xy 74.670697 -376.823915) (xy 74.662659 -376.890679)
			(xy 74.646685 -376.956062) (xy 74.623011 -377.019067) (xy 74.591976 -377.07879) (xy 74.554025 -377.134376)
			(xy 74.532236 -377.160028) (xy 74.526437 -377.167171) (xy 74.519926 -377.184364) (xy 74.519536 -377.193556)
			(xy 74.519536 -377.35129) (xy 74.519127 -377.361464) (xy 74.511341 -377.380264) (xy 74.49695 -377.39465)
			(xy 74.478148 -377.402431) (xy 74.467974 -377.402852) (xy 73.751694 -377.402852) (xy 73.741521 -377.402441)
			(xy 73.722724 -377.394652) (xy 73.708339 -377.380263) (xy 73.700556 -377.361463) (xy 73.700132 -377.35129)
			(xy 73.700132 -377.193556) (xy 73.699736 -377.184367) (xy 73.693212 -377.167184) (xy 73.687432 -377.160028)
			(xy 73.665648 -377.134373) (xy 73.6277 -377.078786) (xy 73.596667 -377.019063) (xy 73.572994 -376.956059)
			(xy 73.557021 -376.890677) (xy 73.548977 -376.823855) (xy 73.548976 -376.756551) (xy 48.270947 -376.756551)
			(xy 48.270947 -376.823855) (xy 48.262903 -376.890678) (xy 48.24693 -376.95606) (xy 48.223258 -377.019064)
			(xy 48.192226 -377.078788) (xy 48.154279 -377.134375) (xy 48.132492 -377.160028) (xy 48.1267 -377.167176)
			(xy 48.120183 -377.184365) (xy 48.119792 -377.193556) (xy 48.119792 -377.351544) (xy 48.119414 -377.361702)
			(xy 48.111603 -377.380457) (xy 48.097193 -377.394779) (xy 48.07839 -377.402476) (xy 48.06823 -377.402852)
			(xy 47.35195 -377.402852) (xy 47.341825 -377.402332) (xy 47.323104 -377.394619) (xy 47.308746 -377.380343)
			(xy 47.300926 -377.361666) (xy 47.300388 -377.351544) (xy 47.300388 -377.193556) (xy 47.300002 -377.184366)
			(xy 47.293472 -377.167182) (xy 47.287688 -377.160028) (xy 47.265903 -377.134373) (xy 47.227951 -377.078788)
			(xy 47.196914 -377.019066) (xy 47.173239 -376.956061) (xy 47.157265 -376.890679) (xy 47.149219 -376.823856)
			(xy 43.871178 -376.823856) (xy 43.871178 -376.823915) (xy 43.863102 -376.890854) (xy 43.847066 -376.956343)
			(xy 43.823301 -377.01944) (xy 43.79215 -377.079236) (xy 43.75406 -377.134871) (xy 43.732196 -377.160536)
			(xy 43.726401 -377.167682) (xy 43.719886 -377.184872) (xy 43.719496 -377.194064) (xy 43.719496 -377.35129)
			(xy 43.718966 -377.361412) (xy 43.711248 -377.380126) (xy 43.696976 -377.394481) (xy 43.678307 -377.402307)
			(xy 43.668188 -377.402852) (xy 42.951908 -377.402852) (xy 42.941761 -377.402373) (xy 42.923019 -377.39459)
			(xy 42.908697 -377.380211) (xy 42.900988 -377.361439) (xy 42.9006 -377.35129) (xy 42.9006 -377.194064)
			(xy 42.900207 -377.184875) (xy 42.893682 -377.167691) (xy 42.8879 -377.160536) (xy 42.86604 -377.134868)
			(xy 42.827951 -377.079233) (xy 42.7968 -377.019438) (xy 42.773036 -376.956341) (xy 42.757 -376.890853)
			(xy 42.748924 -376.823915) (xy 39.470876 -376.823915) (xy 39.462838 -376.89068) (xy 39.446863 -376.956063)
			(xy 39.423187 -377.019068) (xy 39.39215 -377.078791) (xy 39.354198 -377.134377) (xy 39.332408 -377.160028)
			(xy 39.326618 -377.167178) (xy 39.320099 -377.184365) (xy 39.319708 -377.193556) (xy 39.319708 -377.35129)
			(xy 39.31916 -377.361441) (xy 39.311397 -377.380202) (xy 39.297049 -377.394566) (xy 39.278297 -377.402349)
			(xy 39.268146 -377.402852) (xy 38.551866 -377.402852) (xy 38.541705 -377.402394) (xy 38.522933 -377.394607)
			(xy 38.508569 -377.38023) (xy 38.500797 -377.361452) (xy 38.500304 -377.35129) (xy 38.500304 -377.193556)
			(xy 38.499914 -377.184367) (xy 38.493386 -377.167183) (xy 38.487604 -377.160028) (xy 38.465821 -377.134372)
			(xy 38.427875 -377.078785) (xy 38.396843 -377.019062) (xy 38.373172 -376.956058) (xy 38.357199 -376.890677)
			(xy 38.349156 -376.823855) (xy 38.349155 -376.756551) (xy 35.071091 -376.756551) (xy 35.07109 -376.823915)
			(xy 35.063014 -376.890853) (xy 35.046979 -376.956342) (xy 35.023215 -377.019439) (xy 34.992064 -377.079236)
			(xy 34.953976 -377.134871) (xy 34.932112 -377.160536) (xy 34.926319 -377.167684) (xy 34.919802 -377.184872)
			(xy 34.919412 -377.194064) (xy 34.919412 -377.35129) (xy 34.918867 -377.36141) (xy 34.911152 -377.380121)
			(xy 34.896884 -377.394476) (xy 34.878221 -377.402304) (xy 34.868104 -377.402852) (xy 34.151824 -377.402852)
			(xy 34.141678 -377.40236) (xy 34.122936 -377.394582) (xy 34.108614 -377.380208) (xy 34.100904 -377.361438)
			(xy 34.100516 -377.35129) (xy 34.100516 -377.194064) (xy 34.10012 -377.184875) (xy 34.093596 -377.167691)
			(xy 34.087816 -377.160536) (xy 34.065955 -377.134868) (xy 34.027866 -377.079234) (xy 33.996714 -377.019438)
			(xy 33.972949 -376.956342) (xy 33.956912 -376.890853) (xy 33.948836 -376.823915) (xy 30.670788 -376.823915)
			(xy 30.66275 -376.89068) (xy 30.646775 -376.956062) (xy 30.6231 -377.019067) (xy 30.592065 -377.078791)
			(xy 30.554113 -377.134376) (xy 30.532324 -377.160028) (xy 30.526536 -377.167179) (xy 30.520015 -377.184365)
			(xy 30.519624 -377.193556) (xy 30.519624 -377.35129) (xy 30.519227 -377.361466) (xy 30.511438 -377.380267)
			(xy 30.497044 -377.394654) (xy 30.478238 -377.402433) (xy 30.468062 -377.402852) (xy 29.751782 -377.402852)
			(xy 29.741622 -377.402381) (xy 29.72285 -377.394599) (xy 29.708485 -377.380226) (xy 29.700713 -377.36145)
			(xy 29.70022 -377.35129) (xy 29.70022 -377.193556) (xy 29.699827 -377.184367) (xy 29.693301 -377.167183)
			(xy 29.68752 -377.160028) (xy 29.665737 -377.134372) (xy 29.627789 -377.078786) (xy 29.596757 -377.019063)
			(xy 29.573084 -376.956059) (xy 29.557112 -376.890677) (xy 29.549068 -376.823855) (xy 29.549067 -376.756551)
			(xy 0.509016 -376.756551) (xy 0.509016 -378.323793) (xy 27.348888 -378.323793) (xy 27.34889 -378.256368)
			(xy 27.356968 -378.189428) (xy 27.373006 -378.123938) (xy 27.396772 -378.06084) (xy 27.427925 -378.001043)
			(xy 27.466015 -377.945408) (xy 27.48788 -377.919742) (xy 27.493681 -377.9126) (xy 27.500194 -377.895407)
			(xy 27.50058 -377.886214) (xy 27.50058 -377.728734) (xy 27.501056 -377.718605) (xy 27.50878 -377.699877)
			(xy 27.52307 -377.685518) (xy 27.541761 -377.677705) (xy 27.551888 -377.677172) (xy 28.268168 -377.677172)
			(xy 28.278285 -377.677641) (xy 28.296983 -377.685374) (xy 28.311297 -377.699674) (xy 28.319048 -377.718363)
			(xy 28.319476 -377.72848) (xy 28.319476 -377.886214) (xy 28.319885 -377.895401) (xy 28.3264 -377.912585)
			(xy 28.332176 -377.919742) (xy 28.354015 -377.945428) (xy 28.392106 -378.001059) (xy 28.42326 -378.060852)
			(xy 28.447026 -378.123946) (xy 28.463064 -378.189433) (xy 28.471143 -378.256369) (xy 28.471145 -378.323734)
			(xy 31.749183 -378.323734) (xy 31.749186 -378.256427) (xy 31.757233 -378.189602) (xy 31.773209 -378.124218)
			(xy 31.796886 -378.061212) (xy 31.827924 -378.001488) (xy 31.865878 -377.945902) (xy 31.887668 -377.92025)
			(xy 31.893477 -377.913114) (xy 31.899982 -377.895916) (xy 31.900368 -377.886722) (xy 31.900368 -377.728734)
			(xy 31.900793 -377.718561) (xy 31.908572 -377.699761) (xy 31.922958 -377.685374) (xy 31.941757 -377.677593)
			(xy 31.95193 -377.677172) (xy 32.66821 -377.677172) (xy 32.678386 -377.677557) (xy 32.697188 -377.685351)
			(xy 32.711574 -377.699749) (xy 32.719352 -377.718557) (xy 32.719772 -377.728734) (xy 32.719772 -377.886722)
			(xy 32.720178 -377.89591) (xy 32.726695 -377.913094) (xy 32.732472 -377.92025) (xy 32.754234 -377.945924)
			(xy 32.792182 -378.001507) (xy 32.823216 -378.061228) (xy 32.84689 -378.12423) (xy 32.862864 -378.189609)
			(xy 32.87091 -378.256429) (xy 32.870913 -378.323732) (xy 32.870906 -378.323793) (xy 36.148976 -378.323793)
			(xy 36.148978 -378.256368) (xy 36.157056 -378.189429) (xy 36.173093 -378.123939) (xy 36.196859 -378.060841)
			(xy 36.22801 -378.001044) (xy 36.2661 -377.945408) (xy 36.287964 -377.919742) (xy 36.293775 -377.912608)
			(xy 36.300279 -377.895409) (xy 36.300664 -377.886214) (xy 36.300664 -377.728734) (xy 36.301155 -377.718607)
			(xy 36.308876 -377.699882) (xy 36.323162 -377.685523) (xy 36.341847 -377.677707) (xy 36.351972 -377.677172)
			(xy 37.068252 -377.677172) (xy 37.0784 -377.67766) (xy 37.097145 -377.685435) (xy 37.11147 -377.699811)
			(xy 37.119176 -377.718585) (xy 37.11956 -377.728734) (xy 37.11956 -377.886214) (xy 37.119972 -377.895401)
			(xy 37.126485 -377.912585) (xy 37.13226 -377.919742) (xy 37.1541 -377.945428) (xy 37.192192 -378.001058)
			(xy 37.223346 -378.060851) (xy 37.247113 -378.123946) (xy 37.263152 -378.189433) (xy 37.27123 -378.256369)
			(xy 37.271233 -378.323792) (xy 37.271233 -378.323794) (xy 40.548742 -378.323794) (xy 40.548744 -378.256367)
			(xy 40.556824 -378.189426) (xy 40.572863 -378.123935) (xy 40.596633 -378.060837) (xy 40.627789 -378.00104)
			(xy 40.665885 -377.945406) (xy 40.687752 -377.919742) (xy 40.693562 -377.912607) (xy 40.700067 -377.895408)
			(xy 40.700452 -377.886214) (xy 40.700452 -377.728734) (xy 40.700955 -377.718608) (xy 40.708674 -377.699885)
			(xy 40.722955 -377.685528) (xy 40.741637 -377.677709) (xy 40.75176 -377.677172) (xy 41.46804 -377.677172)
			(xy 41.478193 -377.677588) (xy 41.496941 -377.685392) (xy 41.511262 -377.699789) (xy 41.518965 -377.718579)
			(xy 41.519348 -377.728734) (xy 41.519348 -377.886214) (xy 41.519763 -377.8954) (xy 41.526275 -377.912584)
			(xy 41.532048 -377.919742) (xy 41.553888 -377.945427) (xy 41.591981 -378.001058) (xy 41.623136 -378.060851)
			(xy 41.646904 -378.123945) (xy 41.662943 -378.189432) (xy 41.671021 -378.256369) (xy 41.671024 -378.323792)
			(xy 41.671024 -378.323793) (xy 71.348797 -378.323793) (xy 71.348799 -378.256368) (xy 71.356877 -378.189428)
			(xy 71.372915 -378.123937) (xy 71.396682 -378.060839) (xy 71.427835 -378.001042) (xy 71.465927 -377.945407)
			(xy 71.487792 -377.919742) (xy 71.493595 -377.912601) (xy 71.500106 -377.895407) (xy 71.500492 -377.886214)
			(xy 71.500492 -377.728734) (xy 71.501053 -377.718615) (xy 71.508761 -377.699904) (xy 71.523024 -377.685548)
			(xy 71.541685 -377.67772) (xy 71.5518 -377.677172) (xy 72.26808 -377.677172) (xy 72.278229 -377.677637)
			(xy 72.296976 -377.685421) (xy 72.311299 -377.699804) (xy 72.319005 -377.718583) (xy 72.319388 -377.728734)
			(xy 72.319388 -377.886214) (xy 72.319794 -377.895402) (xy 72.326311 -377.912586) (xy 72.332088 -377.919742)
			(xy 72.353927 -377.945428) (xy 72.392017 -378.001059) (xy 72.42317 -378.060853) (xy 72.446936 -378.123947)
			(xy 72.462973 -378.189433) (xy 72.471052 -378.25637) (xy 72.471054 -378.323734) (xy 75.749092 -378.323734)
			(xy 75.749095 -378.256427) (xy 75.757142 -378.189601) (xy 75.773119 -378.124217) (xy 75.796796 -378.061212)
			(xy 75.827835 -378.001488) (xy 75.86579 -377.945902) (xy 75.88758 -377.92025) (xy 75.893378 -377.913106)
			(xy 75.899892 -377.895915) (xy 75.90028 -377.886722) (xy 75.90028 -377.728734) (xy 75.900693 -377.718559)
			(xy 75.908474 -377.699757) (xy 75.922864 -377.68537) (xy 75.941667 -377.677591) (xy 75.951842 -377.677172)
			(xy 76.668122 -377.677172) (xy 76.678299 -377.677547) (xy 76.697101 -377.685345) (xy 76.711486 -377.699746)
			(xy 76.719264 -377.718556) (xy 76.719684 -377.728734) (xy 76.719684 -377.886722) (xy 76.720087 -377.89591)
			(xy 76.726606 -377.913094) (xy 76.732384 -377.92025) (xy 76.754146 -377.945923) (xy 76.792094 -378.001507)
			(xy 76.823127 -378.061228) (xy 76.8468 -378.12423) (xy 76.862774 -378.189609) (xy 76.87082 -378.256429)
			(xy 76.870822 -378.323732) (xy 76.870815 -378.323793) (xy 80.148885 -378.323793) (xy 80.148887 -378.256368)
			(xy 80.156965 -378.189428) (xy 80.173003 -378.123938) (xy 80.196769 -378.06084) (xy 80.227921 -378.001043)
			(xy 80.266011 -377.945408) (xy 80.287876 -377.919742) (xy 80.293677 -377.9126) (xy 80.30019 -377.895407)
			(xy 80.300576 -377.886214) (xy 80.300576 -377.728734) (xy 80.301056 -377.718605) (xy 80.308779 -377.699878)
			(xy 80.323068 -377.685519) (xy 80.341758 -377.677705) (xy 80.351884 -377.677172) (xy 81.068164 -377.677172)
			(xy 81.078281 -377.677645) (xy 81.096978 -377.685376) (xy 81.111293 -377.699675) (xy 81.119044 -377.718364)
			(xy 81.119472 -377.72848) (xy 81.119472 -377.886214) (xy 81.119882 -377.895401) (xy 81.126396 -377.912585)
			(xy 81.132172 -377.919742) (xy 81.154011 -377.945428) (xy 81.192103 -378.001059) (xy 81.223256 -378.060852)
			(xy 81.247023 -378.123946) (xy 81.263061 -378.189433) (xy 81.27114 -378.256369) (xy 81.271142 -378.323792)
			(xy 81.271142 -378.323793) (xy 84.548676 -378.323793) (xy 84.548678 -378.256368) (xy 84.556756 -378.189429)
			(xy 84.572793 -378.123939) (xy 84.596559 -378.060841) (xy 84.62771 -378.001044) (xy 84.6658 -377.945408)
			(xy 84.687664 -377.919742) (xy 84.693475 -377.912608) (xy 84.699979 -377.895409) (xy 84.700364 -377.886214)
			(xy 84.700364 -377.728734) (xy 84.700855 -377.718607) (xy 84.708576 -377.699882) (xy 84.722862 -377.685523)
			(xy 84.741547 -377.677707) (xy 84.751672 -377.677172) (xy 85.467952 -377.677172) (xy 85.478068 -377.677655)
			(xy 85.496765 -377.685382) (xy 85.51108 -377.699678) (xy 85.518832 -377.718365) (xy 85.51926 -377.72848)
			(xy 85.51926 -377.886214) (xy 85.519672 -377.895401) (xy 85.526185 -377.912585) (xy 85.53196 -377.919742)
			(xy 85.5538 -377.945428) (xy 85.591892 -378.001058) (xy 85.623046 -378.060851) (xy 85.646813 -378.123946)
			(xy 85.662852 -378.189433) (xy 85.67093 -378.256369) (xy 85.670933 -378.323734) (xy 115.349234 -378.323734)
			(xy 115.349237 -378.256427) (xy 115.357283 -378.189603) (xy 115.373258 -378.12422) (xy 115.396932 -378.061215)
			(xy 115.427966 -378.00149) (xy 115.465916 -377.945903) (xy 115.487704 -377.92025) (xy 115.493505 -377.913108)
			(xy 115.500017 -377.895915) (xy 115.500404 -377.886722) (xy 115.500404 -377.728734) (xy 115.500961 -377.718583)
			(xy 115.508717 -377.699821) (xy 115.523064 -377.685456) (xy 115.541815 -377.677674) (xy 115.551966 -377.677172)
			(xy 116.268246 -377.677172) (xy 116.278411 -377.677597) (xy 116.297188 -377.685393) (xy 116.311552 -377.69978)
			(xy 116.319319 -377.718568) (xy 116.319808 -377.728734) (xy 116.319808 -377.886722) (xy 116.320206 -377.895911)
			(xy 116.326728 -377.913095) (xy 116.332508 -377.92025) (xy 116.354272 -377.945922) (xy 116.392225 -378.001505)
			(xy 116.423262 -378.061225) (xy 116.446939 -378.124227) (xy 116.462915 -378.189607) (xy 116.470962 -378.256428)
			(xy 116.470964 -378.323732) (xy 116.470957 -378.323793) (xy 119.749003 -378.323793) (xy 119.749005 -378.256368)
			(xy 119.757084 -378.189428) (xy 119.773122 -378.123937) (xy 119.796889 -378.060839) (xy 119.828043 -378.001042)
			(xy 119.866134 -377.945407) (xy 119.888 -377.919742) (xy 119.893804 -377.912602) (xy 119.900314 -377.895407)
			(xy 119.9007 -377.886214) (xy 119.9007 -377.728734) (xy 119.901253 -377.718614) (xy 119.908963 -377.699902)
			(xy 119.923228 -377.685546) (xy 119.941892 -377.677718) (xy 119.952008 -377.677172) (xy 120.668288 -377.677172)
			(xy 120.678438 -377.677631) (xy 120.697185 -377.685417) (xy 120.711507 -377.699802) (xy 120.719213 -377.718582)
			(xy 120.719596 -377.728734) (xy 120.719596 -377.886214) (xy 120.72 -377.895402) (xy 120.726518 -377.912586)
			(xy 120.732296 -377.919742) (xy 120.754135 -377.945428) (xy 120.792224 -378.00106) (xy 120.823376 -378.060853)
			(xy 120.847142 -378.123947) (xy 120.86318 -378.189434) (xy 120.871258 -378.25637) (xy 120.87126 -378.323734)
			(xy 124.149298 -378.323734) (xy 124.149301 -378.256426) (xy 124.157348 -378.189601) (xy 124.173325 -378.124217)
			(xy 124.197003 -378.061211) (xy 124.228042 -378.001487) (xy 124.265997 -377.945902) (xy 124.287788 -377.92025)
			(xy 124.293587 -377.913106) (xy 124.300101 -377.895915) (xy 124.300488 -377.886722) (xy 124.300488 -377.728734)
			(xy 124.300893 -377.718558) (xy 124.308676 -377.699755) (xy 124.323068 -377.685367) (xy 124.341874 -377.67759)
			(xy 124.35205 -377.677172) (xy 125.06833 -377.677172) (xy 125.078508 -377.67754) (xy 125.09731 -377.685341)
			(xy 125.111695 -377.699744) (xy 125.119473 -377.718556) (xy 125.119892 -377.728734) (xy 125.119892 -377.886722)
			(xy 125.120293 -377.89591) (xy 125.126813 -377.913094) (xy 125.132592 -377.92025) (xy 125.154353 -377.945924)
			(xy 125.192301 -378.001508) (xy 125.223334 -378.061229) (xy 125.247006 -378.12423) (xy 125.26298 -378.189609)
			(xy 125.271026 -378.256429) (xy 125.271028 -378.323732) (xy 125.271028 -378.323734) (xy 128.549089 -378.323734)
			(xy 128.549092 -378.256427) (xy 128.557139 -378.189602) (xy 128.573116 -378.124218) (xy 128.596793 -378.061212)
			(xy 128.627831 -378.001488) (xy 128.665786 -377.945902) (xy 128.687576 -377.92025) (xy 128.693374 -377.913105)
			(xy 128.699888 -377.895915) (xy 128.700276 -377.886722) (xy 128.700276 -377.728734) (xy 128.700693 -377.71856)
			(xy 128.708474 -377.699759) (xy 128.722862 -377.685371) (xy 128.741664 -377.677592) (xy 128.751838 -377.677172)
			(xy 129.468118 -377.677172) (xy 129.478295 -377.67755) (xy 129.497097 -377.685347) (xy 129.511482 -377.699747)
			(xy 129.51926 -377.718557) (xy 129.51968 -377.728734) (xy 129.51968 -377.886722) (xy 129.520084 -377.89591)
			(xy 129.526602 -377.913094) (xy 129.53238 -377.92025) (xy 129.554142 -377.945923) (xy 129.59209 -378.001507)
			(xy 129.623123 -378.061228) (xy 129.646797 -378.12423) (xy 129.662771 -378.189609) (xy 129.670817 -378.256429)
			(xy 129.670819 -378.323732) (xy 129.670819 -378.323734) (xy 159.349143 -378.323734) (xy 159.349146 -378.256427)
			(xy 159.357192 -378.189603) (xy 159.373167 -378.12422) (xy 159.396842 -378.061214) (xy 159.427877 -378.00149)
			(xy 159.465827 -377.945902) (xy 159.487616 -377.92025) (xy 159.493418 -377.913109) (xy 159.499929 -377.895915)
			(xy 159.500316 -377.886722) (xy 159.500316 -377.728734) (xy 159.500791 -377.718567) (xy 159.508561 -377.699778)
			(xy 159.522931 -377.685392) (xy 159.541712 -377.677602) (xy 159.551878 -377.677172) (xy 160.268158 -377.677172)
			(xy 160.278331 -377.677599) (xy 160.297131 -377.685377) (xy 160.311519 -377.699762) (xy 160.319299 -377.718561)
			(xy 160.31972 -377.728734) (xy 160.31972 -377.886722) (xy 160.320115 -377.895911) (xy 160.326639 -377.913095)
			(xy 160.33242 -377.92025) (xy 160.354183 -377.945923) (xy 160.392136 -378.001505) (xy 160.423172 -378.061226)
			(xy 160.446848 -378.124227) (xy 160.462824 -378.189608) (xy 160.470871 -378.256429) (xy 160.470874 -378.323732)
			(xy 160.470867 -378.323793) (xy 163.748912 -378.323793) (xy 163.748914 -378.256367) (xy 163.756993 -378.189427)
			(xy 163.773031 -378.123937) (xy 163.796799 -378.060839) (xy 163.827953 -378.001042) (xy 163.866046 -377.945407)
			(xy 163.887912 -377.919742) (xy 163.893717 -377.912603) (xy 163.900226 -377.895408) (xy 163.900612 -377.886214)
			(xy 163.900612 -377.728734) (xy 163.901154 -377.718613) (xy 163.908865 -377.699898) (xy 163.923134 -377.685542)
			(xy 163.941802 -377.677716) (xy 163.95192 -377.677172) (xy 164.6682 -377.677172) (xy 164.678351 -377.677621)
			(xy 164.697098 -377.685411) (xy 164.71142 -377.699799) (xy 164.719125 -377.718582) (xy 164.719508 -377.728734)
			(xy 164.719508 -377.886214) (xy 164.71991 -377.895402) (xy 164.726429 -377.912586) (xy 164.732208 -377.919742)
			(xy 164.754046 -377.945428) (xy 164.792135 -378.00106) (xy 164.823286 -378.060853) (xy 164.847052 -378.123948)
			(xy 164.863089 -378.189434) (xy 164.871167 -378.25637) (xy 164.871169 -378.323734) (xy 168.149231 -378.323734)
			(xy 168.149234 -378.256427) (xy 168.15728 -378.189604) (xy 168.173254 -378.12422) (xy 168.196928 -378.061215)
			(xy 168.227963 -378.00149) (xy 168.265912 -377.945903) (xy 168.2877 -377.92025) (xy 168.2935 -377.913107)
			(xy 168.300013 -377.895915) (xy 168.3004 -377.886722) (xy 168.3004 -377.728734) (xy 168.30096 -377.718583)
			(xy 168.308717 -377.699822) (xy 168.323062 -377.685457) (xy 168.341812 -377.677675) (xy 168.351962 -377.677172)
			(xy 169.068242 -377.677172) (xy 169.078407 -377.6776) (xy 169.097183 -377.685394) (xy 169.111548 -377.699781)
			(xy 169.119315 -377.718569) (xy 169.119804 -377.728734) (xy 169.119804 -377.886722) (xy 169.120203 -377.89591)
			(xy 169.126724 -377.913095) (xy 169.132504 -377.92025) (xy 169.154265 -377.945924) (xy 169.192212 -378.001508)
			(xy 169.223244 -378.061229) (xy 169.246916 -378.124231) (xy 169.26289 -378.18961) (xy 169.270935 -378.256429)
			(xy 169.270937 -378.323732) (xy 169.270937 -378.323734) (xy 172.548998 -378.323734) (xy 172.549001 -378.256426)
			(xy 172.557048 -378.189601) (xy 172.573025 -378.124217) (xy 172.596703 -378.061211) (xy 172.627742 -378.001487)
			(xy 172.665697 -377.945902) (xy 172.687488 -377.92025) (xy 172.693287 -377.913106) (xy 172.699801 -377.895915)
			(xy 172.700188 -377.886722) (xy 172.700188 -377.728734) (xy 172.700593 -377.718558) (xy 172.708376 -377.699755)
			(xy 172.722768 -377.685367) (xy 172.741574 -377.67759) (xy 172.75175 -377.677172) (xy 173.46803 -377.677172)
			(xy 173.478208 -377.67754) (xy 173.49701 -377.685341) (xy 173.511395 -377.699744) (xy 173.519173 -377.718556)
			(xy 173.519592 -377.728734) (xy 173.519592 -377.886722) (xy 173.519993 -377.89591) (xy 173.526513 -377.913094)
			(xy 173.532292 -377.92025) (xy 173.554053 -377.945924) (xy 173.592001 -378.001508) (xy 173.623034 -378.061229)
			(xy 173.646706 -378.12423) (xy 173.66268 -378.189609) (xy 173.670726 -378.256429) (xy 173.670728 -378.323732)
			(xy 173.662687 -378.390552) (xy 173.646718 -378.455932) (xy 173.623049 -378.518936) (xy 173.592021 -378.578659)
			(xy 173.554077 -378.634245) (xy 173.532292 -378.659898) (xy 173.526513 -378.667056) (xy 173.519988 -378.684237)
			(xy 173.519592 -378.693426) (xy 173.519592 -378.766811) (xy 193.48983 -378.766811) (xy 193.48983 -378.633249)
			(xy 193.497894 -378.499931) (xy 193.513994 -378.367343) (xy 193.538069 -378.235969) (xy 193.570032 -378.106288)
			(xy 193.609767 -377.978774) (xy 193.657129 -377.853891) (xy 193.711944 -377.732096) (xy 193.774014 -377.613833)
			(xy 193.84311 -377.499534) (xy 193.918982 -377.389614) (xy 194.001352 -377.284477) (xy 194.08992 -377.184504)
			(xy 194.184362 -377.090062) (xy 194.284335 -377.001494) (xy 194.389472 -376.919124) (xy 194.499392 -376.843252)
			(xy 194.613691 -376.774156) (xy 194.731954 -376.712086) (xy 194.853749 -376.657271) (xy 194.978632 -376.609909)
			(xy 195.106146 -376.570174) (xy 195.235827 -376.538211) (xy 195.367201 -376.514136) (xy 195.499789 -376.498036)
			(xy 195.633107 -376.489972) (xy 195.766669 -376.489972) (xy 195.899987 -376.498036) (xy 196.032575 -376.514136)
			(xy 196.163949 -376.538211) (xy 196.29363 -376.570174) (xy 196.421144 -376.609909) (xy 196.546027 -376.657271)
			(xy 196.667822 -376.712086) (xy 196.786085 -376.774156) (xy 196.900384 -376.843252) (xy 197.010304 -376.919124)
			(xy 197.115441 -377.001494) (xy 197.215414 -377.090062) (xy 197.309856 -377.184504) (xy 197.398424 -377.284477)
			(xy 197.480794 -377.389614) (xy 197.556666 -377.499534) (xy 197.625762 -377.613833) (xy 197.687832 -377.732096)
			(xy 197.742647 -377.853891) (xy 197.790009 -377.978774) (xy 197.829744 -378.106288) (xy 197.861707 -378.235969)
			(xy 197.862607 -378.240882) (xy 204.068504 -378.240882) (xy 204.076595 -378.185806) (xy 204.092605 -378.132491)
			(xy 204.116196 -378.082071) (xy 204.146866 -378.035615) (xy 204.183964 -377.994111) (xy 204.226701 -377.958442)
			(xy 204.274169 -377.929363) (xy 204.299566 -377.917964) (xy 204.31379 -377.911868) (xy 204.3303 -377.886722)
			(xy 204.3303 -374.878092) (xy 204.329857 -374.868543) (xy 204.322824 -374.850787) (xy 204.316584 -374.843548)
			(xy 204.300697 -374.825797) (xy 204.273817 -374.786469) (xy 204.25311 -374.743569) (xy 204.23904 -374.698059)
			(xy 204.231922 -374.650958) (xy 204.231494 -374.62714) (xy 204.231494 -371.243098) (xy 204.231071 -371.233029)
			(xy 204.223349 -371.214431) (xy 204.216508 -371.20703) (xy 204.18298 -371.173502) (xy 204.165683 -371.155513)
			(xy 204.136361 -371.115135) (xy 204.113715 -371.070668) (xy 204.098302 -371.023206) (xy 204.090502 -370.973917)
			(xy 204.090016 -370.948966) (xy 204.090016 -367.26876) (xy 204.090486 -367.24381) (xy 204.098304 -367.194525)
			(xy 204.113727 -367.147067) (xy 204.136375 -367.102602) (xy 204.165692 -367.062221) (xy 204.18298 -367.044224)
			(xy 204.446632 -366.780572) (xy 204.464604 -366.763255) (xy 204.504984 -366.733927) (xy 204.549455 -366.711277)
			(xy 204.596921 -366.695864) (xy 204.646215 -366.688067) (xy 204.671168 -366.687608) (xy 208.09839 -366.687608)
			(xy 208.123339 -366.688112) (xy 208.172622 -366.695922) (xy 208.220079 -366.711337) (xy 208.264545 -366.733977)
			(xy 208.304928 -366.763287) (xy 208.322926 -366.780572) (xy 208.566512 -367.024158) (xy 208.583789 -367.042165)
			(xy 208.613114 -367.082538) (xy 208.635764 -367.127001) (xy 208.651181 -367.174459) (xy 208.658986 -367.223744)
			(xy 208.659476 -367.248694) (xy 208.659476 -369.788186) (xy 208.659999 -369.79819) (xy 208.667649 -369.816677)
			(xy 208.681791 -369.830829) (xy 208.700273 -369.838494) (xy 208.710276 -369.838986) (xy 208.785968 -369.838986)
			(xy 208.810919 -369.839447) (xy 208.860203 -369.847269) (xy 208.907661 -369.862694) (xy 208.952126 -369.885344)
			(xy 208.992507 -369.914662) (xy 209.010504 -369.93195) (xy 209.67573 -370.597176) (xy 209.683128 -370.604019)
			(xy 209.701729 -370.611738) (xy 209.711798 -370.612162) (xy 210.06562 -370.612162) (xy 210.090569 -370.61266)
			(xy 210.139852 -370.620474) (xy 210.187309 -370.635891) (xy 210.231774 -370.658532) (xy 210.272157 -370.687842)
			(xy 210.290156 -370.705126) (xy 210.516978 -370.931948) (xy 210.534292 -370.949922) (xy 210.563614 -370.990303)
			(xy 210.586257 -371.034774) (xy 210.601666 -371.08224) (xy 210.609459 -371.131532) (xy 210.609942 -371.156484)
			(xy 210.609942 -371.380512) (xy 210.610311 -371.390539) (xy 210.617993 -371.409064) (xy 210.632181 -371.423238)
			(xy 210.650714 -371.4309) (xy 210.660742 -371.431312) (xy 216.45245 -371.431312) (xy 216.462519 -371.430884)
			(xy 216.481119 -371.423168) (xy 216.488518 -371.416326) (xy 217.302334 -370.60251) (xy 217.309167 -370.595105)
			(xy 217.31689 -370.576509) (xy 217.31732 -370.566442) (xy 217.31732 -367.318036) (xy 217.317803 -367.293087)
			(xy 217.325622 -367.243804) (xy 217.341043 -367.196347) (xy 217.363688 -367.151882) (xy 217.392999 -367.111499)
			(xy 217.410284 -367.0935) (xy 217.733118 -366.770666) (xy 217.751095 -366.753355) (xy 217.791474 -366.724026)
			(xy 217.835943 -366.701376) (xy 217.883409 -366.685961) (xy 217.932701 -366.678162) (xy 217.957654 -366.677702)
			(xy 221.342458 -366.677702) (xy 221.367409 -366.678165) (xy 221.416693 -366.685986) (xy 221.464151 -366.70141)
			(xy 221.508616 -366.724059) (xy 221.548997 -366.753378) (xy 221.566994 -366.770666) (xy 221.81058 -367.014252)
			(xy 221.827896 -367.032223) (xy 221.857217 -367.072606) (xy 221.879861 -367.117077) (xy 221.895269 -367.164543)
			(xy 221.903062 -367.213836) (xy 221.903544 -367.238788) (xy 221.903544 -370.592604) (xy 221.903956 -370.602675)
			(xy 221.911685 -370.621273) (xy 221.91853 -370.628672) (xy 222.004382 -370.714524) (xy 222.021685 -370.732507)
			(xy 222.051008 -370.772886) (xy 222.073654 -370.817355) (xy 222.089065 -370.864819) (xy 222.096861 -370.914109)
			(xy 222.097346 -370.93906) (xy 222.097346 -373.42191) (xy 222.097754 -373.431981) (xy 222.105485 -373.45058)
			(xy 222.112332 -373.457978) (xy 223.764602 -375.110248) (xy 223.772013 -375.117074) (xy 223.790604 -375.124804)
			(xy 223.80067 -375.125234) (xy 225.416872 -375.125234) (xy 225.426942 -375.124811) (xy 225.445541 -375.117091)
			(xy 225.45294 -375.110248) (xy 226.51339 -374.049798) (xy 226.520222 -374.042392) (xy 226.527947 -374.023797)
			(xy 226.528376 -374.01373) (xy 226.528376 -372.656862) (xy 226.528859 -372.631912) (xy 226.536676 -372.582629)
			(xy 226.552096 -372.535172) (xy 226.574741 -372.490706) (xy 226.604054 -372.450324) (xy 226.62134 -372.432326)
			(xy 227.816156 -371.23751) (xy 227.822978 -371.230095) (xy 227.83071 -371.211508) (xy 227.831142 -371.201442)
			(xy 227.831142 -370.936012) (xy 227.831666 -370.911064) (xy 227.839474 -370.861783) (xy 227.854885 -370.814326)
			(xy 227.877521 -370.76986) (xy 227.906825 -370.729476) (xy 227.924106 -370.711476) (xy 228.003608 -370.631974)
			(xy 228.010453 -370.624578) (xy 228.01817 -370.605976) (xy 228.018594 -370.595906) (xy 228.018594 -367.245138)
			(xy 228.019057 -367.220188) (xy 228.026878 -367.170903) (xy 228.042302 -367.123445) (xy 228.064952 -367.07898)
			(xy 228.09427 -367.038599) (xy 228.111558 -367.020602) (xy 228.364796 -366.767364) (xy 228.382783 -366.750063)
			(xy 228.423159 -366.720733) (xy 228.467626 -366.698081) (xy 228.515089 -366.682663) (xy 228.56438 -366.674861)
			(xy 228.589332 -366.6744) (xy 232.007156 -366.6744) (xy 232.032106 -366.674865) (xy 232.081391 -366.682685)
			(xy 232.128849 -366.698109) (xy 232.173314 -366.720758) (xy 232.213695 -366.750076) (xy 232.231692 -366.767364)
			(xy 232.48493 -367.020602) (xy 232.502233 -367.038587) (xy 232.531563 -367.078963) (xy 232.554215 -367.123431)
			(xy 232.569632 -367.170894) (xy 232.577433 -367.220186) (xy 232.577894 -367.245138) (xy 232.577894 -370.60251)
			(xy 232.578289 -370.612583) (xy 232.586028 -370.631182) (xy 232.59288 -370.638578) (xy 232.652824 -370.698522)
			(xy 232.670133 -370.716499) (xy 232.699454 -370.756881) (xy 232.722098 -370.801351) (xy 232.737507 -370.848816)
			(xy 232.745303 -370.898106) (xy 232.745788 -370.923058) (xy 232.745788 -371.05971) (xy 232.746185 -371.069783)
			(xy 232.753923 -371.088382) (xy 232.760774 -371.095778) (xy 233.402886 -371.73789) (xy 233.420173 -371.755888)
			(xy 233.449498 -371.796263) (xy 233.472147 -371.840728) (xy 233.487562 -371.888188) (xy 233.495363 -371.937476)
			(xy 233.49585 -371.962426) (xy 233.49585 -375.346214) (xy 233.496255 -375.356286) (xy 233.503988 -375.374884)
			(xy 233.510836 -375.382282) (xy 234.427522 -376.298968) (xy 235.473748 -376.298968) (xy 235.473748 -368.60607)
			(xy 235.474244 -368.581121) (xy 235.482059 -368.531838) (xy 235.497476 -368.484382) (xy 235.520118 -368.439916)
			(xy 235.549428 -368.399533) (xy 235.566712 -368.381534) (xy 235.993178 -367.955068) (xy 236.011173 -367.937776)
			(xy 236.051547 -367.908445) (xy 236.096012 -367.885791) (xy 236.143473 -367.870371) (xy 236.192762 -367.862567)
			(xy 236.217714 -367.862104) (xy 265.631168 -367.862104) (xy 265.656119 -367.86256) (xy 265.705404 -367.870382)
			(xy 265.752862 -367.885808) (xy 265.797327 -367.908459) (xy 265.837707 -367.937779) (xy 265.855704 -367.955068)
			(xy 266.408408 -368.507772) (xy 266.425691 -368.525774) (xy 266.455015 -368.566148) (xy 266.477664 -368.610612)
			(xy 266.49308 -368.658072) (xy 266.500884 -368.707358) (xy 266.501372 -368.732308) (xy 266.501372 -370.523704)
			(xy 286.928752 -370.523704) (xy 286.928753 -370.456278) (xy 286.936831 -370.389338) (xy 286.952869 -370.323848)
			(xy 286.976637 -370.26075) (xy 287.007792 -370.200954) (xy 287.045885 -370.14532) (xy 287.067752 -370.119656)
			(xy 287.073556 -370.112516) (xy 287.080065 -370.095321) (xy 287.080452 -370.086128) (xy 287.080452 -369.928902)
			(xy 287.080929 -369.918774) (xy 287.088658 -369.900051) (xy 287.102947 -369.885694) (xy 287.121634 -369.877877)
			(xy 287.13176 -369.87734) (xy 287.84804 -369.87734) (xy 287.85817 -369.877684) (xy 287.876882 -369.885453)
			(xy 287.891196 -369.899792) (xy 287.898933 -369.918517) (xy 287.899348 -369.928648) (xy 287.899348 -370.086128)
			(xy 287.899756 -370.095315) (xy 287.906273 -370.112499) (xy 287.912048 -370.119656) (xy 287.933902 -370.14533)
			(xy 287.971994 -370.200962) (xy 288.003149 -370.260757) (xy 288.026916 -370.323852) (xy 288.042954 -370.389341)
			(xy 288.051031 -370.456279) (xy 288.051032 -370.523644) (xy 291.329071 -370.523644) (xy 291.329073 -370.456338)
			(xy 291.337118 -370.389515) (xy 291.353092 -370.324132) (xy 291.376766 -370.261127) (xy 291.407801 -370.201403)
			(xy 291.445751 -370.145816) (xy 291.46754 -370.120164) (xy 291.473339 -370.113021) (xy 291.479851 -370.095829)
			(xy 291.48024 -370.086636) (xy 291.48024 -369.928902) (xy 291.480665 -369.91873) (xy 291.48845 -369.899935)
			(xy 291.502835 -369.88555) (xy 291.52163 -369.877765) (xy 291.531802 -369.87734) (xy 292.248082 -369.87734)
			(xy 292.258253 -369.877778) (xy 292.277047 -369.885558) (xy 292.291433 -369.899939) (xy 292.299218 -369.918731)
			(xy 292.299644 -369.928902) (xy 292.299644 -370.086636) (xy 292.30005 -370.095823) (xy 292.306568 -370.113007)
			(xy 292.312344 -370.120164) (xy 292.33412 -370.145826) (xy 292.372071 -370.20141) (xy 292.403105 -370.261132)
			(xy 292.426779 -370.324136) (xy 292.442754 -370.389517) (xy 292.450799 -370.456339) (xy 292.4508 -370.523643)
			(xy 292.450793 -370.523704) (xy 295.72884 -370.523704) (xy 295.728841 -370.456278) (xy 295.736918 -370.389339)
			(xy 295.752956 -370.323848) (xy 295.776723 -370.260751) (xy 295.807878 -370.200955) (xy 295.84597 -370.145321)
			(xy 295.867836 -370.119656) (xy 295.873638 -370.112515) (xy 295.880149 -370.095321) (xy 295.880536 -370.086128)
			(xy 295.880536 -369.928902) (xy 295.881028 -369.918776) (xy 295.888755 -369.900056) (xy 295.903039 -369.885699)
			(xy 295.92172 -369.877879) (xy 295.931844 -369.87734) (xy 296.648124 -369.87734) (xy 296.658285 -369.877703)
			(xy 296.677045 -369.885514) (xy 296.691369 -369.899929) (xy 296.699061 -369.918739) (xy 296.699432 -369.928902)
			(xy 296.699432 -370.086128) (xy 296.699844 -370.095315) (xy 296.706358 -370.112498) (xy 296.712132 -370.119656)
			(xy 296.733983 -370.145332) (xy 296.77207 -370.200965) (xy 296.803219 -370.26076) (xy 296.826983 -370.323856)
			(xy 296.843018 -370.389343) (xy 296.851095 -370.45628) (xy 296.851096 -370.523702) (xy 296.851096 -370.523704)
			(xy 300.128631 -370.523704) (xy 300.128632 -370.456278) (xy 300.136709 -370.389339) (xy 300.152747 -370.323849)
			(xy 300.176513 -370.260751) (xy 300.207667 -370.200955) (xy 300.245758 -370.145321) (xy 300.267624 -370.119656)
			(xy 300.273425 -370.112514) (xy 300.279936 -370.095321) (xy 300.280324 -370.086128) (xy 300.280324 -369.928902)
			(xy 300.280828 -369.918777) (xy 300.288552 -369.900059) (xy 300.302833 -369.885704) (xy 300.32151 -369.877882)
			(xy 300.331632 -369.87734) (xy 301.047912 -369.87734) (xy 301.058072 -369.877712) (xy 301.076832 -369.885519)
			(xy 301.091157 -369.899932) (xy 301.098849 -369.91874) (xy 301.09922 -369.928902) (xy 301.09922 -370.086128)
			(xy 301.099612 -370.095317) (xy 301.106138 -370.112502) (xy 301.11192 -370.119656) (xy 301.133771 -370.145331)
			(xy 301.171859 -370.200965) (xy 301.203009 -370.26076) (xy 301.226773 -370.323855) (xy 301.242809 -370.389343)
			(xy 301.250886 -370.45628) (xy 301.250887 -370.523644) (xy 330.92919 -370.523644) (xy 330.929191 -370.456338)
			(xy 330.937237 -370.389514) (xy 330.953212 -370.324131) (xy 330.976887 -370.261126) (xy 331.007923 -370.201402)
			(xy 331.045875 -370.145816) (xy 331.067664 -370.120164) (xy 331.073466 -370.113023) (xy 331.079976 -370.095829)
			(xy 331.080364 -370.086636) (xy 331.080364 -369.928902) (xy 331.080766 -369.918727) (xy 331.088555 -369.899928)
			(xy 331.102948 -369.885542) (xy 331.121751 -369.877761) (xy 331.131926 -369.87734) (xy 331.848206 -369.87734)
			(xy 331.858364 -369.877829) (xy 331.877134 -369.885605) (xy 331.891499 -369.899973) (xy 331.899273 -369.918744)
			(xy 331.899768 -369.928902) (xy 331.899768 -370.086636) (xy 331.900168 -370.095824) (xy 331.90669 -370.113008)
			(xy 331.912468 -370.120164) (xy 331.934244 -370.145826) (xy 331.972193 -370.201411) (xy 332.003226 -370.261133)
			(xy 332.026899 -370.324137) (xy 332.042873 -370.389518) (xy 332.050918 -370.456339) (xy 332.050919 -370.523643)
			(xy 332.050912 -370.523703) (xy 335.328983 -370.523703) (xy 335.328984 -370.456279) (xy 335.33706 -370.389341)
			(xy 335.353096 -370.323852) (xy 335.376859 -370.260754) (xy 335.408009 -370.200957) (xy 335.446097 -370.145322)
			(xy 335.46796 -370.119656) (xy 335.473765 -370.112517) (xy 335.480273 -370.095322) (xy 335.48066 -370.086128)
			(xy 335.48066 -369.928902) (xy 335.481129 -369.918773) (xy 335.48886 -369.900048) (xy 335.503152 -369.885691)
			(xy 335.521841 -369.877875) (xy 335.531968 -369.87734) (xy 336.248248 -369.87734) (xy 336.25841 -369.877683)
			(xy 336.277171 -369.885502) (xy 336.291494 -369.899923) (xy 336.299185 -369.918737) (xy 336.299556 -369.928902)
			(xy 336.299556 -370.086128) (xy 336.299963 -370.095315) (xy 336.30648 -370.112499) (xy 336.312256 -370.119656)
			(xy 336.33411 -370.14533) (xy 336.372202 -370.200962) (xy 336.403355 -370.260757) (xy 336.427122 -370.323853)
			(xy 336.44316 -370.389341) (xy 336.451237 -370.456279) (xy 336.451238 -370.523644) (xy 339.729277 -370.523644)
			(xy 339.729279 -370.456338) (xy 339.737324 -370.389514) (xy 339.753299 -370.324131) (xy 339.776973 -370.261126)
			(xy 339.808008 -370.201402) (xy 339.845959 -370.145816) (xy 339.867748 -370.120164) (xy 339.873548 -370.113022)
			(xy 339.880059 -370.095829) (xy 339.880448 -370.086636) (xy 339.880448 -369.928902) (xy 339.880866 -369.918729)
			(xy 339.888652 -369.899933) (xy 339.903039 -369.885547) (xy 339.921837 -369.877764) (xy 339.93201 -369.87734)
			(xy 340.64829 -369.87734) (xy 340.658461 -369.877772) (xy 340.677256 -369.885554) (xy 340.691641 -369.899937)
			(xy 340.699426 -369.918731) (xy 340.699852 -369.928902) (xy 340.699852 -370.086636) (xy 340.700256 -370.095824)
			(xy 340.706775 -370.113007) (xy 340.712552 -370.120164) (xy 340.734328 -370.145826) (xy 340.772278 -370.201411)
			(xy 340.803312 -370.261133) (xy 340.826986 -370.324136) (xy 340.84296 -370.389517) (xy 340.851005 -370.456339)
			(xy 340.851006 -370.523643) (xy 340.851006 -370.523644) (xy 344.129068 -370.523644) (xy 344.129069 -370.456338)
			(xy 344.137115 -370.389515) (xy 344.153089 -370.324132) (xy 344.176763 -370.261127) (xy 344.207797 -370.201403)
			(xy 344.245748 -370.145816) (xy 344.267536 -370.120164) (xy 344.273335 -370.113021) (xy 344.279847 -370.095829)
			(xy 344.280236 -370.086636) (xy 344.280236 -369.928902) (xy 344.280735 -369.918745) (xy 344.288508 -369.899976)
			(xy 344.302873 -369.885611) (xy 344.321641 -369.877836) (xy 344.331798 -369.87734) (xy 345.048078 -369.87734)
			(xy 345.058248 -369.877782) (xy 345.077043 -369.88556) (xy 345.091429 -369.89994) (xy 345.099214 -369.918732)
			(xy 345.09964 -369.928902) (xy 345.09964 -370.086636) (xy 345.100046 -370.095823) (xy 345.106564 -370.113007)
			(xy 345.11234 -370.120164) (xy 345.134116 -370.145826) (xy 345.172067 -370.20141) (xy 345.203102 -370.261132)
			(xy 345.226776 -370.324136) (xy 345.242751 -370.389517) (xy 345.250796 -370.456339) (xy 345.250797 -370.523643)
			(xy 345.250797 -370.523644) (xy 374.929099 -370.523644) (xy 374.9291 -370.456338) (xy 374.937146 -370.389514)
			(xy 374.953121 -370.32413) (xy 374.976797 -370.261125) (xy 375.007834 -370.201402) (xy 375.045787 -370.145816)
			(xy 375.067576 -370.120164) (xy 375.073368 -370.113015) (xy 375.079886 -370.095828) (xy 375.080276 -370.086636)
			(xy 375.080276 -369.928902) (xy 375.080666 -369.918726) (xy 375.088458 -369.899924) (xy 375.102854 -369.885538)
			(xy 375.121661 -369.877759) (xy 375.131838 -369.87734) (xy 375.848118 -369.87734) (xy 375.858277 -369.877818)
			(xy 375.877047 -369.885599) (xy 375.891412 -369.89997) (xy 375.899185 -369.918743) (xy 375.89968 -369.928902)
			(xy 375.89968 -370.086636) (xy 375.900077 -370.095824) (xy 375.9066 -370.113008) (xy 375.91238 -370.120164)
			(xy 375.934155 -370.145826) (xy 375.972103 -370.201412) (xy 376.003136 -370.261134) (xy 376.026809 -370.324137)
			(xy 376.042782 -370.389518) (xy 376.050827 -370.456339) (xy 376.050828 -370.523643) (xy 376.050821 -370.523703)
			(xy 379.328892 -370.523703) (xy 379.328893 -370.456279) (xy 379.336969 -370.38934) (xy 379.353005 -370.323851)
			(xy 379.376769 -370.260754) (xy 379.40792 -370.200957) (xy 379.446008 -370.145322) (xy 379.467872 -370.119656)
			(xy 379.473678 -370.112518) (xy 379.480185 -370.095322) (xy 379.480572 -370.086128) (xy 379.480572 -369.928902)
			(xy 379.481029 -369.918772) (xy 379.488762 -369.900044) (xy 379.503058 -369.885687) (xy 379.521752 -369.877873)
			(xy 379.53188 -369.87734) (xy 380.24816 -369.87734) (xy 380.258316 -369.877755) (xy 380.277076 -369.885545)
			(xy 380.291402 -369.899945) (xy 380.299096 -369.918743) (xy 380.299468 -369.928902) (xy 380.299468 -370.086128)
			(xy 380.299872 -370.095316) (xy 380.306391 -370.1125) (xy 380.312168 -370.119656) (xy 380.334021 -370.14533)
			(xy 380.372112 -370.200963) (xy 380.403265 -370.260758) (xy 380.427032 -370.323853) (xy 380.443069 -370.389342)
			(xy 380.451146 -370.456279) (xy 380.451147 -370.523644) (xy 383.729187 -370.523644) (xy 383.729188 -370.456338)
			(xy 383.737234 -370.389514) (xy 383.753209 -370.324131) (xy 383.776884 -370.261126) (xy 383.807919 -370.201402)
			(xy 383.845871 -370.145816) (xy 383.86766 -370.120164) (xy 383.873462 -370.113023) (xy 383.879972 -370.095829)
			(xy 383.88036 -370.086636) (xy 383.88036 -369.928902) (xy 383.880766 -369.918728) (xy 383.888554 -369.899929)
			(xy 383.902946 -369.885543) (xy 383.921748 -369.877762) (xy 383.931922 -369.87734) (xy 384.648202 -369.87734)
			(xy 384.65836 -369.877832) (xy 384.67713 -369.885607) (xy 384.691495 -369.899974) (xy 384.699269 -369.918744)
			(xy 384.699764 -369.928902) (xy 384.699764 -370.086636) (xy 384.700165 -370.095824) (xy 384.706686 -370.113008)
			(xy 384.712464 -370.120164) (xy 384.73424 -370.145826) (xy 384.772189 -370.201411) (xy 384.803222 -370.261133)
			(xy 384.826895 -370.324137) (xy 384.842869 -370.389518) (xy 384.850914 -370.456339) (xy 384.850915 -370.523643)
			(xy 384.850915 -370.523644) (xy 388.128977 -370.523644) (xy 388.128979 -370.456338) (xy 388.137024 -370.389514)
			(xy 388.152999 -370.324131) (xy 388.176673 -370.261126) (xy 388.207708 -370.201402) (xy 388.245659 -370.145816)
			(xy 388.267448 -370.120164) (xy 388.273248 -370.113022) (xy 388.279759 -370.095829) (xy 388.280148 -370.086636)
			(xy 388.280148 -369.928902) (xy 388.280566 -369.918729) (xy 388.288352 -369.899933) (xy 388.302739 -369.885547)
			(xy 388.321537 -369.877764) (xy 388.33171 -369.87734) (xy 389.04799 -369.87734) (xy 389.058161 -369.877772)
			(xy 389.076956 -369.885554) (xy 389.091341 -369.899937) (xy 389.099126 -369.918731) (xy 389.099552 -369.928902)
			(xy 389.099552 -370.086636) (xy 389.099956 -370.095824) (xy 389.106475 -370.113007) (xy 389.112252 -370.120164)
			(xy 389.134028 -370.145826) (xy 389.171978 -370.201411) (xy 389.203012 -370.261133) (xy 389.226686 -370.324136)
			(xy 389.24266 -370.389517) (xy 389.250705 -370.456339) (xy 389.250706 -370.523643) (xy 389.250706 -370.523644)
			(xy 418.929008 -370.523644) (xy 418.929009 -370.456338) (xy 418.937055 -370.389513) (xy 418.953031 -370.32413)
			(xy 418.976707 -370.261125) (xy 419.007745 -370.201401) (xy 419.045698 -370.145816) (xy 419.067488 -370.120164)
			(xy 419.073281 -370.113016) (xy 419.079798 -370.095828) (xy 419.080188 -370.086636) (xy 419.080188 -369.928902)
			(xy 419.080567 -369.918724) (xy 419.08836 -369.89992) (xy 419.10276 -369.885533) (xy 419.121572 -369.877757)
			(xy 419.13175 -369.87734) (xy 419.84803 -369.87734) (xy 419.85819 -369.877809) (xy 419.87696 -369.885593)
			(xy 419.891325 -369.899967) (xy 419.899098 -369.918742) (xy 419.899592 -369.928902) (xy 419.899592 -370.086636)
			(xy 419.899986 -370.095825) (xy 419.906511 -370.113009) (xy 419.912292 -370.120164) (xy 419.934067 -370.145826)
			(xy 419.972014 -370.201412) (xy 420.003046 -370.261134) (xy 420.026718 -370.324138) (xy 420.042691 -370.389518)
			(xy 420.050736 -370.456339) (xy 420.050737 -370.523643) (xy 420.05073 -370.523703) (xy 423.328801 -370.523703)
			(xy 423.328802 -370.456279) (xy 423.336878 -370.38934) (xy 423.352915 -370.323851) (xy 423.37668 -370.260753)
			(xy 423.407831 -370.200957) (xy 423.44592 -370.145322) (xy 423.467784 -370.119656) (xy 423.47358 -370.11251)
			(xy 423.480095 -370.09532) (xy 423.480484 -370.086128) (xy 423.480484 -369.928902) (xy 423.48093 -369.91877)
			(xy 423.488665 -369.900041) (xy 423.502964 -369.885683) (xy 423.521662 -369.877871) (xy 423.531792 -369.87734)
			(xy 424.248072 -369.87734) (xy 424.258198 -369.87774) (xy 424.276908 -369.885486) (xy 424.291225 -369.899808)
			(xy 424.298964 -369.918522) (xy 424.29938 -369.928648) (xy 424.29938 -370.086128) (xy 424.299781 -370.095316)
			(xy 424.306302 -370.1125) (xy 424.31208 -370.119656) (xy 424.333933 -370.145331) (xy 424.372023 -370.200963)
			(xy 424.403176 -370.260758) (xy 424.426941 -370.323854) (xy 424.442978 -370.389342) (xy 424.451055 -370.456279)
			(xy 424.451056 -370.523644) (xy 427.729096 -370.523644) (xy 427.729097 -370.456338) (xy 427.737143 -370.389514)
			(xy 427.753118 -370.32413) (xy 427.776794 -370.261125) (xy 427.80783 -370.201402) (xy 427.845783 -370.145816)
			(xy 427.867572 -370.120164) (xy 427.873375 -370.113024) (xy 427.879884 -370.095829) (xy 427.880272 -370.086636)
			(xy 427.880272 -369.928902) (xy 427.880666 -369.918726) (xy 427.888457 -369.899925) (xy 427.902852 -369.885539)
			(xy 427.921658 -369.87776) (xy 427.931834 -369.87734) (xy 428.648114 -369.87734) (xy 428.658273 -369.877822)
			(xy 428.677043 -369.885602) (xy 428.691407 -369.899971) (xy 428.699181 -369.918743) (xy 428.699676 -369.928902)
			(xy 428.699676 -370.086636) (xy 428.700074 -370.095824) (xy 428.706597 -370.113008) (xy 428.712376 -370.120164)
			(xy 428.734152 -370.145826) (xy 428.7721 -370.201411) (xy 428.803133 -370.261134) (xy 428.826806 -370.324137)
			(xy 428.842779 -370.389518) (xy 428.850824 -370.456339) (xy 428.850825 -370.523643) (xy 428.850825 -370.523644)
			(xy 432.128887 -370.523644) (xy 432.128888 -370.456338) (xy 432.136934 -370.389514) (xy 432.152909 -370.324131)
			(xy 432.176584 -370.261126) (xy 432.207619 -370.201402) (xy 432.245571 -370.145816) (xy 432.26736 -370.120164)
			(xy 432.273162 -370.113023) (xy 432.279672 -370.095829) (xy 432.28006 -370.086636) (xy 432.28006 -369.928902)
			(xy 432.280466 -369.918728) (xy 432.288254 -369.899929) (xy 432.302646 -369.885543) (xy 432.321448 -369.877762)
			(xy 432.331622 -369.87734) (xy 433.047902 -369.87734) (xy 433.05806 -369.877832) (xy 433.07683 -369.885607)
			(xy 433.091195 -369.899974) (xy 433.098969 -369.918744) (xy 433.099464 -369.928902) (xy 433.099464 -370.086636)
			(xy 433.099865 -370.095824) (xy 433.106386 -370.113008) (xy 433.112164 -370.120164) (xy 433.13394 -370.145826)
			(xy 433.171889 -370.201411) (xy 433.202922 -370.261133) (xy 433.226595 -370.324137) (xy 433.242569 -370.389518)
			(xy 433.250614 -370.456339) (xy 433.250615 -370.523643) (xy 433.242572 -370.590465) (xy 433.226601 -370.655846)
			(xy 433.20293 -370.71885) (xy 433.171898 -370.778573) (xy 433.133951 -370.83416) (xy 433.112164 -370.859812)
			(xy 433.106375 -370.866963) (xy 433.099857 -370.884149) (xy 433.099464 -370.89334) (xy 433.099464 -371.386862)
			(xy 433.099901 -371.396046) (xy 433.106397 -371.41323) (xy 433.112164 -371.42039) (xy 433.133966 -371.446031)
			(xy 433.171914 -371.501619) (xy 433.202946 -371.561344) (xy 433.226383 -371.623725) (xy 434.329029 -371.623725)
			(xy 434.329032 -371.556418) (xy 434.33708 -371.489593) (xy 434.353056 -371.424209) (xy 434.376732 -371.361203)
			(xy 434.407768 -371.301478) (xy 434.445719 -371.245891) (xy 434.467508 -371.220238) (xy 434.473314 -371.2131)
			(xy 434.479823 -371.195904) (xy 434.480208 -371.18671) (xy 434.480208 -371.028722) (xy 434.48075 -371.018569)
			(xy 434.488512 -370.999806) (xy 434.502863 -370.985441) (xy 434.521618 -370.977661) (xy 434.53177 -370.97716)
			(xy 435.24805 -370.97716) (xy 435.258221 -370.977605) (xy 435.277019 -370.985378) (xy 435.291406 -370.999758)
			(xy 435.299189 -371.018551) (xy 435.299612 -371.028722) (xy 435.299612 -371.18671) (xy 435.300015 -371.195898)
			(xy 435.306533 -371.213082) (xy 435.312312 -371.220238) (xy 435.334064 -371.24592) (xy 435.372017 -371.301501)
			(xy 435.403055 -371.36122) (xy 435.426732 -371.424221) (xy 435.442709 -371.4896) (xy 435.450757 -371.55642)
			(xy 435.45076 -371.623723) (xy 435.442719 -371.690544) (xy 435.426749 -371.755924) (xy 435.403078 -371.818928)
			(xy 435.372046 -371.87865) (xy 435.334099 -371.934235) (xy 435.312312 -371.959886) (xy 435.306498 -371.967019)
			(xy 435.299993 -371.984219) (xy 435.299612 -371.993414) (xy 435.299612 -372.486682) (xy 435.300028 -372.495869)
			(xy 435.306537 -372.513053) (xy 435.312312 -372.52021) (xy 435.334135 -372.545834) (xy 435.372086 -372.601423)
			(xy 435.40312 -372.66115) (xy 435.426793 -372.724159) (xy 435.442765 -372.789545) (xy 435.450807 -372.856371)
			(xy 435.450804 -372.92368) (xy 435.442756 -372.990506) (xy 435.426778 -373.05589) (xy 435.403099 -373.118896)
			(xy 435.372059 -373.178621) (xy 435.334103 -373.234206) (xy 435.312312 -373.259858) (xy 435.30651 -373.266999)
			(xy 435.299998 -373.284193) (xy 435.299612 -373.293386) (xy 435.299612 -373.451374) (xy 435.299213 -373.46155)
			(xy 435.291428 -373.480354) (xy 435.277034 -373.494741) (xy 435.258226 -373.502518) (xy 435.24805 -373.502936)
			(xy 434.53177 -373.502936) (xy 434.521607 -373.502491) (xy 434.502832 -373.494701) (xy 434.488467 -373.480321)
			(xy 434.480698 -373.461537) (xy 434.480208 -373.451374) (xy 434.480208 -373.293386) (xy 434.479803 -373.284198)
			(xy 434.473286 -373.267014) (xy 434.467508 -373.259858) (xy 434.445755 -373.234178) (xy 434.407807 -373.178595)
			(xy 434.376774 -373.118875) (xy 434.3531 -373.055874) (xy 434.337126 -372.990495) (xy 434.32908 -372.923676)
			(xy 434.329077 -372.856375) (xy 434.337117 -372.789555) (xy 434.353085 -372.724175) (xy 434.376753 -372.661172)
			(xy 434.40778 -372.601449) (xy 434.445723 -372.545863) (xy 434.467508 -372.52021) (xy 434.473326 -372.51308)
			(xy 434.479828 -372.495878) (xy 434.480208 -372.486682) (xy 434.480208 -371.993414) (xy 434.479789 -371.984228)
			(xy 434.473281 -371.967043) (xy 434.467508 -371.959886) (xy 434.445684 -371.934264) (xy 434.407738 -371.878673)
			(xy 434.376708 -371.818945) (xy 434.353039 -371.755936) (xy 434.33707 -371.690551) (xy 434.329029 -371.623725)
			(xy 433.226383 -371.623725) (xy 433.226618 -371.62435) (xy 433.24259 -371.689734) (xy 433.250633 -371.756557)
			(xy 433.250632 -371.823864) (xy 433.242586 -371.890687) (xy 433.226612 -371.95607) (xy 433.202938 -372.019075)
			(xy 433.171903 -372.078799) (xy 433.133953 -372.134386) (xy 433.112164 -372.160038) (xy 433.106364 -372.167181)
			(xy 433.099852 -372.184373) (xy 433.099464 -372.193566) (xy 433.099464 -372.351554) (xy 433.098999 -372.361722)
			(xy 433.091229 -372.380516) (xy 433.076856 -372.394902) (xy 433.05807 -372.402689) (xy 433.047902 -372.403116)
			(xy 432.331622 -372.403116) (xy 432.321446 -372.402717) (xy 432.302643 -372.394931) (xy 432.288256 -372.380537)
			(xy 432.280478 -372.36173) (xy 432.28006 -372.351554) (xy 432.28006 -372.193566) (xy 432.279653 -372.184379)
			(xy 432.273135 -372.167195) (xy 432.26736 -372.160038) (xy 432.245586 -372.134375) (xy 432.207635 -372.07879)
			(xy 432.1766 -372.019069) (xy 432.152925 -371.956065) (xy 432.136951 -371.890684) (xy 432.128905 -371.823863)
			(xy 432.128904 -371.756558) (xy 432.136947 -371.689736) (xy 432.152919 -371.624355) (xy 432.176591 -371.561351)
			(xy 432.207624 -371.501628) (xy 432.245573 -371.446042) (xy 432.26736 -371.42039) (xy 432.273151 -371.413241)
			(xy 432.279667 -371.396053) (xy 432.28006 -371.386862) (xy 432.28006 -370.89334) (xy 432.279617 -370.884157)
			(xy 432.273125 -370.866972) (xy 432.26736 -370.859812) (xy 432.24556 -370.83417) (xy 432.20761 -370.778582)
			(xy 432.176576 -370.718858) (xy 432.152903 -370.655852) (xy 432.136931 -370.590468) (xy 432.128887 -370.523644)
			(xy 428.850825 -370.523644) (xy 428.842782 -370.590464) (xy 428.826811 -370.655846) (xy 428.80314 -370.71885)
			(xy 428.772109 -370.778573) (xy 428.734163 -370.83416) (xy 428.712376 -370.859812) (xy 428.706589 -370.866964)
			(xy 428.700069 -370.884149) (xy 428.699676 -370.89334) (xy 428.699676 -371.386862) (xy 428.70011 -371.396047)
			(xy 428.706608 -371.413231) (xy 428.712376 -371.42039) (xy 428.734177 -371.446031) (xy 428.772125 -371.501619)
			(xy 428.803156 -371.561345) (xy 428.826615 -371.623785) (xy 429.928709 -371.623785) (xy 429.928713 -371.556358)
			(xy 429.936793 -371.489417) (xy 429.952833 -371.423925) (xy 429.976602 -371.360827) (xy 430.007759 -371.30103)
			(xy 430.045853 -371.245395) (xy 430.06772 -371.21973) (xy 430.073531 -371.212595) (xy 430.080036 -371.195397)
			(xy 430.08042 -371.186202) (xy 430.08042 -371.028722) (xy 430.080944 -371.018599) (xy 430.088661 -370.999882)
			(xy 430.102935 -370.985526) (xy 430.121608 -370.977702) (xy 430.131728 -370.97716) (xy 430.848008 -370.97716)
			(xy 430.858158 -370.977614) (xy 430.876902 -370.985405) (xy 430.891224 -370.999791) (xy 430.898931 -371.018571)
			(xy 430.899316 -371.028722) (xy 430.899316 -371.186202) (xy 430.899722 -371.19539) (xy 430.906238 -371.212574)
			(xy 430.912016 -371.21973) (xy 430.933842 -371.245426) (xy 430.971931 -371.301057) (xy 431.003082 -371.360849)
			(xy 431.026848 -371.423942) (xy 431.042886 -371.489427) (xy 431.050964 -371.556361) (xy 431.050968 -371.623782)
			(xy 431.042896 -371.690717) (xy 431.026865 -371.756204) (xy 431.003106 -371.819299) (xy 430.97196 -371.879094)
			(xy 430.933877 -371.934729) (xy 430.912016 -371.960394) (xy 430.906241 -371.967555) (xy 430.899713 -371.984733)
			(xy 430.899316 -371.993922) (xy 430.899316 -372.486174) (xy 430.899735 -372.49536) (xy 430.906242 -372.512545)
			(xy 430.912016 -372.519702) (xy 430.933913 -372.54534) (xy 430.971999 -372.600979) (xy 431.003148 -372.660779)
			(xy 431.026909 -372.723879) (xy 431.042942 -372.789371) (xy 431.051015 -372.856313) (xy 431.051012 -372.923739)
			(xy 431.042933 -372.990679) (xy 431.026894 -373.05617) (xy 431.003127 -373.119268) (xy 430.971973 -373.179065)
			(xy 430.933881 -373.2347) (xy 430.912016 -373.260366) (xy 430.906211 -373.267505) (xy 430.899701 -373.2847)
			(xy 430.899316 -373.293894) (xy 430.899316 -373.451374) (xy 430.898851 -373.461504) (xy 430.891124 -373.480233)
			(xy 430.87683 -373.494592) (xy 430.858136 -373.502405) (xy 430.848008 -373.502936) (xy 430.131728 -373.502936)
			(xy 430.12158 -373.502456) (xy 430.102835 -373.494677) (xy 430.088512 -373.480298) (xy 430.080805 -373.461523)
			(xy 430.08042 -373.451374) (xy 430.08042 -373.293894) (xy 430.080008 -373.284707) (xy 430.073495 -373.267523)
			(xy 430.06772 -373.260366) (xy 430.045889 -373.234674) (xy 430.007798 -373.179043) (xy 429.976644 -373.119251)
			(xy 429.952877 -373.056158) (xy 429.936839 -372.990672) (xy 429.92876 -372.923736) (xy 429.928757 -372.856315)
			(xy 429.93683 -372.789379) (xy 429.952862 -372.723891) (xy 429.976624 -372.660796) (xy 430.007771 -372.601)
			(xy 430.045857 -372.545367) (xy 430.06772 -372.519702) (xy 430.073501 -372.512546) (xy 430.080024 -372.495364)
			(xy 430.08042 -372.486174) (xy 430.08042 -371.993922) (xy 430.079995 -371.984737) (xy 430.073491 -371.967552)
			(xy 430.06772 -371.960394) (xy 430.045818 -371.93476) (xy 430.007729 -371.879121) (xy 429.976579 -371.819321)
			(xy 429.952816 -371.75622) (xy 429.936783 -371.690727) (xy 429.928709 -371.623785) (xy 428.826615 -371.623785)
			(xy 428.826828 -371.624351) (xy 428.842799 -371.689734) (xy 428.850842 -371.756558) (xy 428.850841 -371.823863)
			(xy 428.842795 -371.890687) (xy 428.826821 -371.95607) (xy 428.803148 -372.019075) (xy 428.772114 -372.078799)
			(xy 428.734164 -372.134386) (xy 428.712376 -372.160038) (xy 428.706578 -372.167182) (xy 428.700065 -372.184374)
			(xy 428.699676 -372.193566) (xy 428.699676 -372.351554) (xy 428.699199 -372.361721) (xy 428.691432 -372.380512)
			(xy 428.677062 -372.394898) (xy 428.65828 -372.402687) (xy 428.648114 -372.403116) (xy 427.931834 -372.403116)
			(xy 427.921659 -372.402707) (xy 427.902856 -372.394925) (xy 427.888469 -372.380534) (xy 427.880691 -372.361729)
			(xy 427.880272 -372.351554) (xy 427.880272 -372.193566) (xy 427.879884 -372.184376) (xy 427.873356 -372.167192)
			(xy 427.867572 -372.160038) (xy 427.845797 -372.134375) (xy 427.807846 -372.078791) (xy 427.77681 -372.019069)
			(xy 427.753135 -371.956066) (xy 427.73716 -371.890685) (xy 427.729114 -371.823863) (xy 427.729113 -371.756558)
			(xy 427.737156 -371.689736) (xy 427.753129 -371.624354) (xy 427.776801 -371.56135) (xy 427.807835 -371.501627)
			(xy 427.845784 -371.446042) (xy 427.867572 -371.42039) (xy 427.873364 -371.413242) (xy 427.879879 -371.396053)
			(xy 427.880272 -371.386862) (xy 427.880272 -370.89334) (xy 427.879849 -370.884154) (xy 427.873345 -370.866969)
			(xy 427.867572 -370.859812) (xy 427.845772 -370.83417) (xy 427.807821 -370.778583) (xy 427.776786 -370.718858)
			(xy 427.753113 -370.655852) (xy 427.73714 -370.590468) (xy 427.729096 -370.523644) (xy 424.451056 -370.523644)
			(xy 424.451056 -370.523703) (xy 424.442981 -370.59064) (xy 424.426947 -370.656129) (xy 424.403183 -370.719225)
			(xy 424.372033 -370.779021) (xy 424.333944 -370.834655) (xy 424.31208 -370.86032) (xy 424.30629 -370.86747)
			(xy 424.299772 -370.884657) (xy 424.29938 -370.893848) (xy 424.29938 -371.386354) (xy 424.299817 -371.395538)
			(xy 424.306312 -371.412723) (xy 424.31208 -371.419882) (xy 424.333958 -371.445536) (xy 424.372048 -371.501171)
			(xy 424.403199 -371.560969) (xy 424.426835 -371.623725) (xy 425.528941 -371.623725) (xy 425.528945 -371.556418)
			(xy 425.536992 -371.489593) (xy 425.552969 -371.424208) (xy 425.576645 -371.361202) (xy 425.607682 -371.301478)
			(xy 425.645634 -371.24589) (xy 425.667424 -371.220238) (xy 425.673232 -371.213101) (xy 425.679739 -371.195904)
			(xy 425.680124 -371.18671) (xy 425.680124 -371.028722) (xy 425.680582 -371.018554) (xy 425.688357 -370.999762)
			(xy 425.702732 -370.985377) (xy 425.721518 -370.977589) (xy 425.731686 -370.97716) (xy 426.447966 -370.97716)
			(xy 426.458138 -370.977592) (xy 426.476936 -370.98537) (xy 426.491323 -370.999754) (xy 426.499105 -371.01855)
			(xy 426.499528 -371.028722) (xy 426.499528 -371.18671) (xy 426.499927 -371.195898) (xy 426.506448 -371.213083)
			(xy 426.512228 -371.220238) (xy 426.533979 -371.24592) (xy 426.571931 -371.301502) (xy 426.602968 -371.361221)
			(xy 426.626645 -371.424221) (xy 426.642621 -371.4896) (xy 426.650669 -371.55642) (xy 426.650672 -371.623723)
			(xy 426.642631 -371.690543) (xy 426.626661 -371.755924) (xy 426.602991 -371.818927) (xy 426.571961 -371.878649)
			(xy 426.534014 -371.934234) (xy 426.512228 -371.959886) (xy 426.506404 -371.967011) (xy 426.499908 -371.984217)
			(xy 426.499528 -371.993414) (xy 426.499528 -372.486682) (xy 426.49994 -372.495869) (xy 426.506452 -372.513054)
			(xy 426.512228 -372.52021) (xy 426.53405 -372.545834) (xy 426.572 -372.601424) (xy 426.603034 -372.661151)
			(xy 426.626706 -372.724159) (xy 426.642678 -372.789545) (xy 426.65072 -372.856371) (xy 426.650717 -372.92368)
			(xy 426.642669 -372.990505) (xy 426.626691 -373.05589) (xy 426.603013 -373.118896) (xy 426.571974 -373.17862)
			(xy 426.534019 -373.234206) (xy 426.512228 -373.259858) (xy 426.506416 -373.266992) (xy 426.499912 -373.284191)
			(xy 426.499528 -373.293386) (xy 426.499528 -373.451374) (xy 426.499114 -373.461548) (xy 426.491331 -373.480349)
			(xy 426.476942 -373.494736) (xy 426.45814 -373.502515) (xy 426.447966 -373.502936) (xy 425.731686 -373.502936)
			(xy 425.72151 -373.502547) (xy 425.70271 -373.494752) (xy 425.688325 -373.480356) (xy 425.680545 -373.46155)
			(xy 425.680124 -373.451374) (xy 425.680124 -373.293386) (xy 425.679715 -373.284199) (xy 425.6732 -373.267015)
			(xy 425.667424 -373.259858) (xy 425.64567 -373.234178) (xy 425.607722 -373.178595) (xy 425.576688 -373.118875)
			(xy 425.553014 -373.055874) (xy 425.537039 -372.990496) (xy 425.528992 -372.923677) (xy 425.528989 -372.856375)
			(xy 425.53703 -372.789555) (xy 425.552999 -372.724174) (xy 425.576667 -372.661171) (xy 425.607695 -372.601449)
			(xy 425.645639 -372.545863) (xy 425.667424 -372.52021) (xy 425.673244 -372.513082) (xy 425.679744 -372.495878)
			(xy 425.680124 -372.486682) (xy 425.680124 -371.993414) (xy 425.679702 -371.984228) (xy 425.673196 -371.967044)
			(xy 425.667424 -371.959886) (xy 425.645599 -371.934264) (xy 425.607653 -371.878673) (xy 425.576622 -371.818945)
			(xy 425.552952 -371.755937) (xy 425.536982 -371.690551) (xy 425.528941 -371.623725) (xy 424.426835 -371.623725)
			(xy 424.426964 -371.624067) (xy 424.442999 -371.689558) (xy 424.451074 -371.756498) (xy 424.451072 -371.823923)
			(xy 424.442995 -371.890863) (xy 424.426957 -371.956353) (xy 424.403191 -372.01945) (xy 424.372037 -372.079247)
			(xy 424.333946 -372.134881) (xy 424.31208 -372.160546) (xy 424.306279 -372.167688) (xy 424.299768 -372.184881)
			(xy 424.29938 -372.194074) (xy 424.29938 -372.351554) (xy 424.298836 -372.361675) (xy 424.291127 -372.380392)
			(xy 424.276858 -372.394749) (xy 424.25819 -372.402573) (xy 424.248072 -372.403116) (xy 423.531792 -372.403116)
			(xy 423.521685 -372.402622) (xy 423.50301 -372.394884) (xy 423.488716 -372.38059) (xy 423.480978 -372.361915)
			(xy 423.480484 -372.351808) (xy 423.480484 -372.194074) (xy 423.48009 -372.184885) (xy 423.473565 -372.167701)
			(xy 423.467784 -372.160546) (xy 423.445934 -372.134869) (xy 423.407846 -372.079236) (xy 423.376696 -372.019441)
			(xy 423.352932 -371.956346) (xy 423.336896 -371.890858) (xy 423.328819 -371.823922) (xy 423.328818 -371.756499)
			(xy 423.336892 -371.689562) (xy 423.352925 -371.624074) (xy 423.376687 -371.560978) (xy 423.407835 -371.501182)
			(xy 423.445921 -371.445547) (xy 423.467784 -371.419882) (xy 423.473569 -371.412728) (xy 423.480091 -371.395544)
			(xy 423.480484 -371.386354) (xy 423.480484 -370.893848) (xy 423.480055 -370.884663) (xy 423.473555 -370.867478)
			(xy 423.467784 -370.86032) (xy 423.445909 -370.834664) (xy 423.407821 -370.779028) (xy 423.376672 -370.71923)
			(xy 423.352909 -370.656132) (xy 423.336875 -370.590642) (xy 423.328801 -370.523703) (xy 420.05073 -370.523703)
			(xy 420.042694 -370.590464) (xy 420.026724 -370.655845) (xy 420.003054 -370.718849) (xy 419.972023 -370.778573)
			(xy 419.934078 -370.834159) (xy 419.912292 -370.859812) (xy 419.906507 -370.866965) (xy 419.899986 -370.88415)
			(xy 419.899592 -370.89334) (xy 419.899592 -371.386862) (xy 419.900022 -371.396047) (xy 419.906522 -371.413231)
			(xy 419.912292 -371.42039) (xy 419.934093 -371.446031) (xy 419.972039 -371.50162) (xy 420.00307 -371.561345)
			(xy 420.026528 -371.623785) (xy 421.128621 -371.623785) (xy 421.128625 -371.556358) (xy 421.136705 -371.489416)
			(xy 421.152746 -371.423925) (xy 421.176516 -371.360826) (xy 421.207673 -371.301029) (xy 421.245769 -371.245395)
			(xy 421.267636 -371.21973) (xy 421.273449 -371.212597) (xy 421.279953 -371.195397) (xy 421.280336 -371.186202)
			(xy 421.280336 -371.028722) (xy 421.280844 -371.018597) (xy 421.288564 -370.999877) (xy 421.302844 -370.98552)
			(xy 421.321522 -370.9777) (xy 421.331644 -370.97716) (xy 422.047924 -370.97716) (xy 422.058029 -370.977664)
			(xy 422.076701 -370.985402) (xy 422.090993 -370.999693) (xy 422.098734 -371.018363) (xy 422.099232 -371.028468)
			(xy 422.099232 -371.186202) (xy 422.099656 -371.195387) (xy 422.106162 -371.212571) (xy 422.111932 -371.21973)
			(xy 422.133758 -371.245427) (xy 422.171845 -371.301057) (xy 422.202996 -371.36085) (xy 422.226761 -371.423942)
			(xy 422.242798 -371.489427) (xy 422.250876 -371.556361) (xy 422.25088 -371.623781) (xy 422.242808 -371.690717)
			(xy 422.226778 -371.756203) (xy 422.203019 -371.819298) (xy 422.171875 -371.879094) (xy 422.133793 -371.934728)
			(xy 422.111932 -371.960394) (xy 422.106147 -371.967547) (xy 422.099627 -371.984732) (xy 422.099232 -371.993922)
			(xy 422.099232 -372.486174) (xy 422.09967 -372.495358) (xy 422.106166 -372.512542) (xy 422.111932 -372.519702)
			(xy 422.133828 -372.54534) (xy 422.171914 -372.600979) (xy 422.203061 -372.66078) (xy 422.226822 -372.72388)
			(xy 422.242854 -372.789372) (xy 422.250927 -372.856313) (xy 422.250924 -372.923738) (xy 422.242845 -372.990678)
			(xy 422.226807 -373.056169) (xy 422.20304 -373.119267) (xy 422.171888 -373.179064) (xy 422.133797 -373.2347)
			(xy 422.111932 -373.260366) (xy 422.106117 -373.267498) (xy 422.099615 -373.284699) (xy 422.099232 -373.293894)
			(xy 422.099232 -373.451374) (xy 422.098751 -373.461503) (xy 422.091027 -373.480228) (xy 422.076738 -373.494587)
			(xy 422.05805 -373.502402) (xy 422.047924 -373.502936) (xy 421.331644 -373.502936) (xy 421.321529 -373.502449)
			(xy 421.302833 -373.494722) (xy 421.288519 -373.480427) (xy 421.280765 -373.461743) (xy 421.280336 -373.451628)
			(xy 421.280336 -373.293894) (xy 421.279921 -373.284708) (xy 421.27341 -373.267524) (xy 421.267636 -373.260366)
			(xy 421.245804 -373.234674) (xy 421.207712 -373.179044) (xy 421.176558 -373.119252) (xy 421.15279 -373.056158)
			(xy 421.136751 -372.990672) (xy 421.128672 -372.923736) (xy 421.128669 -372.856315) (xy 421.136742 -372.789378)
			(xy 421.152775 -372.72389) (xy 421.176537 -372.660795) (xy 421.207686 -372.601) (xy 421.245773 -372.545367)
			(xy 421.267636 -372.519702) (xy 421.273419 -372.512547) (xy 421.279941 -372.495364) (xy 421.280336 -372.486174)
			(xy 421.280336 -371.993922) (xy 421.279907 -371.984737) (xy 421.273406 -371.967553) (xy 421.267636 -371.960394)
			(xy 421.245733 -371.93476) (xy 421.207643 -371.879122) (xy 421.176492 -371.819322) (xy 421.152729 -371.756221)
			(xy 421.136695 -371.690727) (xy 421.128621 -371.623785) (xy 420.026528 -371.623785) (xy 420.026741 -371.624351)
			(xy 420.042712 -371.689734) (xy 420.050754 -371.756558) (xy 420.050753 -371.823863) (xy 420.042708 -371.890686)
			(xy 420.026734 -371.956069) (xy 420.003061 -372.019074) (xy 419.972028 -372.078798) (xy 419.93408 -372.134385)
			(xy 419.912292 -372.160038) (xy 419.906496 -372.167183) (xy 419.899981 -372.184374) (xy 419.899592 -372.193566)
			(xy 419.899592 -372.351554) (xy 419.899099 -372.361719) (xy 419.891335 -372.380507) (xy 419.876971 -372.394892)
			(xy 419.858194 -372.402684) (xy 419.84803 -372.403116) (xy 419.13175 -372.403116) (xy 419.121576 -372.402694)
			(xy 419.102773 -372.394917) (xy 419.088385 -372.38053) (xy 419.080607 -372.361728) (xy 419.080188 -372.351554)
			(xy 419.080188 -372.193566) (xy 419.079797 -372.184377) (xy 419.07327 -372.167192) (xy 419.067488 -372.160038)
			(xy 419.045713 -372.134375) (xy 419.00776 -372.078791) (xy 418.976724 -372.01907) (xy 418.953048 -371.956067)
			(xy 418.937072 -371.890685) (xy 418.929026 -371.823863) (xy 418.929025 -371.756558) (xy 418.937069 -371.689736)
			(xy 418.953042 -371.624354) (xy 418.976715 -371.561349) (xy 419.007749 -371.501627) (xy 419.0457 -371.446041)
			(xy 419.067488 -371.42039) (xy 419.07327 -371.413234) (xy 419.079794 -371.396052) (xy 419.080188 -371.386862)
			(xy 419.080188 -370.89334) (xy 419.079761 -370.884154) (xy 419.07326 -370.86697) (xy 419.067488 -370.859812)
			(xy 419.045687 -370.83417) (xy 419.007735 -370.778583) (xy 418.9767 -370.718859) (xy 418.953026 -370.655853)
			(xy 418.937052 -370.590469) (xy 418.929008 -370.523644) (xy 389.250706 -370.523644) (xy 389.242663 -370.590465)
			(xy 389.226691 -370.655847) (xy 389.203019 -370.718851) (xy 389.171987 -370.778574) (xy 389.134039 -370.83416)
			(xy 389.112252 -370.859812) (xy 389.106462 -370.866962) (xy 389.099945 -370.884149) (xy 389.099552 -370.89334)
			(xy 389.099552 -371.386862) (xy 389.099991 -371.396046) (xy 389.106486 -371.41323) (xy 389.112252 -371.42039)
			(xy 389.134054 -371.446031) (xy 389.172003 -371.501618) (xy 389.203036 -371.561344) (xy 389.226474 -371.623725)
			(xy 390.32912 -371.623725) (xy 390.329123 -371.556418) (xy 390.337171 -371.489593) (xy 390.353146 -371.42421)
			(xy 390.376822 -371.361204) (xy 390.407857 -371.301479) (xy 390.445807 -371.245891) (xy 390.467596 -371.220238)
			(xy 390.473401 -371.213099) (xy 390.479911 -371.195904) (xy 390.480296 -371.18671) (xy 390.480296 -371.028722)
			(xy 390.48085 -371.018571) (xy 390.48861 -370.99981) (xy 390.502956 -370.985446) (xy 390.521707 -370.977663)
			(xy 390.531858 -370.97716) (xy 391.248138 -370.97716) (xy 391.258301 -370.977603) (xy 391.277075 -370.985394)
			(xy 391.29144 -370.999775) (xy 391.299209 -371.018558) (xy 391.2997 -371.028722) (xy 391.2997 -371.18671)
			(xy 391.300106 -371.195898) (xy 391.306623 -371.213082) (xy 391.3124 -371.220238) (xy 391.334149 -371.245921)
			(xy 391.372097 -371.301504) (xy 391.403129 -371.361224) (xy 391.426803 -371.424224) (xy 391.442777 -371.489602)
			(xy 391.450824 -371.556421) (xy 391.450827 -371.623722) (xy 391.442787 -371.690541) (xy 391.42682 -371.755921)
			(xy 391.403153 -371.818924) (xy 391.372126 -371.878647) (xy 391.334184 -371.934233) (xy 391.3124 -371.959886)
			(xy 391.306584 -371.967018) (xy 391.300081 -371.984219) (xy 391.2997 -371.993414) (xy 391.2997 -372.486682)
			(xy 391.300119 -372.495868) (xy 391.306627 -372.513053) (xy 391.3124 -372.52021) (xy 391.33422 -372.545835)
			(xy 391.372165 -372.601426) (xy 391.403195 -372.661154) (xy 391.426864 -372.724162) (xy 391.442833 -372.789547)
			(xy 391.450874 -372.856372) (xy 391.450871 -372.923679) (xy 391.442824 -372.990503) (xy 391.426849 -373.055887)
			(xy 391.403174 -373.118893) (xy 391.372139 -373.178617) (xy 391.334189 -373.234205) (xy 391.3124 -373.259858)
			(xy 391.306596 -373.266998) (xy 391.300086 -373.284193) (xy 391.2997 -373.293386) (xy 391.2997 -373.451374)
			(xy 391.299146 -373.461525) (xy 391.291388 -373.480287) (xy 391.277041 -373.494652) (xy 391.258289 -373.502434)
			(xy 391.248138 -373.502936) (xy 390.531858 -373.502936) (xy 390.521694 -373.5025) (xy 390.502919 -373.494707)
			(xy 390.488555 -373.480324) (xy 390.480786 -373.461538) (xy 390.480296 -373.451374) (xy 390.480296 -373.293386)
			(xy 390.479893 -373.284198) (xy 390.473374 -373.267014) (xy 390.467596 -373.259858) (xy 390.445843 -373.234178)
			(xy 390.407896 -373.178594) (xy 390.376864 -373.118874) (xy 390.353191 -373.055874) (xy 390.337217 -372.990495)
			(xy 390.329171 -372.923676) (xy 390.329167 -372.856375) (xy 390.337208 -372.789555) (xy 390.353176 -372.724175)
			(xy 390.376843 -372.661173) (xy 390.40787 -372.60145) (xy 390.445812 -372.545863) (xy 390.467596 -372.52021)
			(xy 390.473413 -372.513079) (xy 390.479916 -372.495878) (xy 390.480296 -372.486682) (xy 390.480296 -371.993414)
			(xy 390.47988 -371.984227) (xy 390.47337 -371.967043) (xy 390.467596 -371.959886) (xy 390.445772 -371.934264)
			(xy 390.407827 -371.878672) (xy 390.376798 -371.818944) (xy 390.353129 -371.755936) (xy 390.33716 -371.69055)
			(xy 390.32912 -371.623725) (xy 389.226474 -371.623725) (xy 389.226709 -371.62435) (xy 389.242681 -371.689733)
			(xy 389.250724 -371.756557) (xy 389.250723 -371.823864) (xy 389.242677 -371.890687) (xy 389.226702 -371.956071)
			(xy 389.203028 -372.019076) (xy 389.171992 -372.0788) (xy 389.134041 -372.134386) (xy 389.112252 -372.160038)
			(xy 389.106451 -372.16718) (xy 389.09994 -372.184373) (xy 389.099552 -372.193566) (xy 389.099552 -372.351554)
			(xy 389.099098 -372.361724) (xy 389.091327 -372.380519) (xy 389.07695 -372.394906) (xy 389.05816 -372.402691)
			(xy 389.04799 -372.403116) (xy 388.33171 -372.403116) (xy 388.321533 -372.402727) (xy 388.30273 -372.394937)
			(xy 388.288343 -372.38054) (xy 388.280566 -372.361731) (xy 388.280148 -372.351554) (xy 388.280148 -372.193566)
			(xy 388.279743 -372.184378) (xy 388.273225 -372.167195) (xy 388.267448 -372.160038) (xy 388.245674 -372.134375)
			(xy 388.207724 -372.07879) (xy 388.17669 -372.019068) (xy 388.153016 -371.956065) (xy 388.137042 -371.890684)
			(xy 388.128996 -371.823863) (xy 388.128995 -371.756558) (xy 388.137038 -371.689737) (xy 388.15301 -371.624355)
			(xy 388.176681 -371.561351) (xy 388.207713 -371.501628) (xy 388.245661 -371.446042) (xy 388.267448 -371.42039)
			(xy 388.273237 -371.41324) (xy 388.279755 -371.396053) (xy 388.280148 -371.386862) (xy 388.280148 -370.89334)
			(xy 388.279708 -370.884156) (xy 388.273214 -370.866972) (xy 388.267448 -370.859812) (xy 388.245648 -370.83417)
			(xy 388.207699 -370.778582) (xy 388.176666 -370.718857) (xy 388.152993 -370.655851) (xy 388.137021 -370.590468)
			(xy 388.128977 -370.523644) (xy 384.850915 -370.523644) (xy 384.842872 -370.590465) (xy 384.826901 -370.655846)
			(xy 384.80323 -370.71885) (xy 384.772198 -370.778573) (xy 384.734251 -370.83416) (xy 384.712464 -370.859812)
			(xy 384.706675 -370.866963) (xy 384.700157 -370.884149) (xy 384.699764 -370.89334) (xy 384.699764 -371.386862)
			(xy 384.700201 -371.396046) (xy 384.706697 -371.41323) (xy 384.712464 -371.42039) (xy 384.734266 -371.446031)
			(xy 384.772214 -371.501619) (xy 384.803246 -371.561344) (xy 384.826706 -371.623785) (xy 385.9288 -371.623785)
			(xy 385.928804 -371.556358) (xy 385.936884 -371.489417) (xy 385.952923 -371.423926) (xy 385.976692 -371.360827)
			(xy 386.007848 -371.30103) (xy 386.045941 -371.245395) (xy 386.067808 -371.21973) (xy 386.073618 -371.212594)
			(xy 386.080124 -371.195396) (xy 386.080508 -371.186202) (xy 386.080508 -371.028722) (xy 386.081044 -371.018601)
			(xy 386.088758 -370.999886) (xy 386.103029 -370.98553) (xy 386.121698 -370.977704) (xy 386.131816 -370.97716)
			(xy 386.848096 -370.97716) (xy 386.858245 -370.977624) (xy 386.876989 -370.985411) (xy 386.891311 -370.999794)
			(xy 386.899019 -371.018571) (xy 386.899404 -371.028722) (xy 386.899404 -371.186202) (xy 386.899812 -371.195389)
			(xy 386.906327 -371.212574) (xy 386.912104 -371.21973) (xy 386.93393 -371.245426) (xy 386.97202 -371.301056)
			(xy 387.003172 -371.360848) (xy 387.026938 -371.423941) (xy 387.042976 -371.489426) (xy 387.051055 -371.556361)
			(xy 387.051059 -371.623782) (xy 387.042987 -371.690717) (xy 387.026955 -371.756204) (xy 387.003196 -371.8193)
			(xy 386.972049 -371.879095) (xy 386.933966 -371.934729) (xy 386.912104 -371.960394) (xy 386.906328 -371.967554)
			(xy 386.899801 -371.984733) (xy 386.899404 -371.993922) (xy 386.899404 -372.486174) (xy 386.899826 -372.49536)
			(xy 386.906331 -372.512545) (xy 386.912104 -372.519702) (xy 386.934001 -372.54534) (xy 386.972089 -372.600978)
			(xy 387.003238 -372.660778) (xy 387.027 -372.723879) (xy 387.043033 -372.789371) (xy 387.051106 -372.856312)
			(xy 387.051103 -372.923739) (xy 387.043024 -372.990679) (xy 387.026985 -373.05617) (xy 387.003217 -373.119268)
			(xy 386.972062 -373.179066) (xy 386.93397 -373.234701) (xy 386.912104 -373.260366) (xy 386.906297 -373.267504)
			(xy 386.899789 -373.2847) (xy 386.899404 -373.293894) (xy 386.899404 -373.451374) (xy 386.898854 -373.461494)
			(xy 386.891142 -373.480206) (xy 386.876876 -373.494562) (xy 386.858212 -373.50239) (xy 386.848096 -373.502936)
			(xy 386.131816 -373.502936) (xy 386.121667 -373.502466) (xy 386.102922 -373.494683) (xy 386.0886 -373.480301)
			(xy 386.080893 -373.461524) (xy 386.080508 -373.451374) (xy 386.080508 -373.293894) (xy 386.080099 -373.284707)
			(xy 386.073584 -373.267523) (xy 386.067808 -373.260366) (xy 386.045977 -373.234673) (xy 386.007887 -373.179043)
			(xy 385.976734 -373.119251) (xy 385.952968 -373.056157) (xy 385.93693 -372.990671) (xy 385.928851 -372.923736)
			(xy 385.928848 -372.856315) (xy 385.936921 -372.789379) (xy 385.952953 -372.723892) (xy 385.976713 -372.660796)
			(xy 386.007861 -372.601001) (xy 386.045946 -372.545367) (xy 386.067808 -372.519702) (xy 386.073587 -372.512544)
			(xy 386.080112 -372.495363) (xy 386.080508 -372.486174) (xy 386.080508 -371.993922) (xy 386.080085 -371.984736)
			(xy 386.07358 -371.967552) (xy 386.067808 -371.960394) (xy 386.045906 -371.93476) (xy 386.007818 -371.879121)
			(xy 385.976669 -371.819321) (xy 385.952906 -371.75622) (xy 385.936873 -371.690727) (xy 385.9288 -371.623785)
			(xy 384.826706 -371.623785) (xy 384.826918 -371.62435) (xy 384.84289 -371.689734) (xy 384.850933 -371.756557)
			(xy 384.850932 -371.823864) (xy 384.842886 -371.890687) (xy 384.826912 -371.95607) (xy 384.803238 -372.019075)
			(xy 384.772203 -372.078799) (xy 384.734253 -372.134386) (xy 384.712464 -372.160038) (xy 384.706664 -372.167181)
			(xy 384.700152 -372.184373) (xy 384.699764 -372.193566) (xy 384.699764 -372.351554) (xy 384.699299 -372.361722)
			(xy 384.691529 -372.380516) (xy 384.677156 -372.394902) (xy 384.65837 -372.402689) (xy 384.648202 -372.403116)
			(xy 383.931922 -372.403116) (xy 383.921746 -372.402717) (xy 383.902943 -372.394931) (xy 383.888556 -372.380537)
			(xy 383.880778 -372.36173) (xy 383.88036 -372.351554) (xy 383.88036 -372.193566) (xy 383.879953 -372.184379)
			(xy 383.873435 -372.167195) (xy 383.86766 -372.160038) (xy 383.845886 -372.134375) (xy 383.807935 -372.07879)
			(xy 383.7769 -372.019069) (xy 383.753225 -371.956065) (xy 383.737251 -371.890684) (xy 383.729205 -371.823863)
			(xy 383.729204 -371.756558) (xy 383.737247 -371.689736) (xy 383.753219 -371.624355) (xy 383.776891 -371.561351)
			(xy 383.807924 -371.501628) (xy 383.845873 -371.446042) (xy 383.86766 -371.42039) (xy 383.873451 -371.413241)
			(xy 383.879967 -371.396053) (xy 383.88036 -371.386862) (xy 383.88036 -370.89334) (xy 383.879917 -370.884157)
			(xy 383.873425 -370.866972) (xy 383.86766 -370.859812) (xy 383.84586 -370.83417) (xy 383.80791 -370.778582)
			(xy 383.776876 -370.718858) (xy 383.753203 -370.655852) (xy 383.737231 -370.590468) (xy 383.729187 -370.523644)
			(xy 380.451147 -370.523644) (xy 380.451147 -370.523703) (xy 380.443072 -370.590641) (xy 380.427037 -370.656129)
			(xy 380.403273 -370.719226) (xy 380.372122 -370.779022) (xy 380.334032 -370.834655) (xy 380.312168 -370.86032)
			(xy 380.306376 -370.867469) (xy 380.299859 -370.884657) (xy 380.299468 -370.893848) (xy 380.299468 -371.386354)
			(xy 380.299908 -371.395538) (xy 380.306402 -371.412722) (xy 380.312168 -371.419882) (xy 380.334047 -371.445535)
			(xy 380.372137 -371.501171) (xy 380.403289 -371.560968) (xy 380.426925 -371.623725) (xy 381.529032 -371.623725)
			(xy 381.529035 -371.556418) (xy 381.537083 -371.489593) (xy 381.553059 -371.424209) (xy 381.576735 -371.361203)
			(xy 381.607771 -371.301478) (xy 381.645723 -371.245891) (xy 381.667512 -371.220238) (xy 381.673319 -371.2131)
			(xy 381.679827 -371.195904) (xy 381.680212 -371.18671) (xy 381.680212 -371.028722) (xy 381.680751 -371.018569)
			(xy 381.688513 -370.999805) (xy 381.702865 -370.98544) (xy 381.721621 -370.97766) (xy 381.731774 -370.97716)
			(xy 382.448054 -370.97716) (xy 382.458225 -370.977602) (xy 382.477023 -370.985376) (xy 382.491411 -370.999757)
			(xy 382.499193 -371.018551) (xy 382.499616 -371.028722) (xy 382.499616 -371.18671) (xy 382.500018 -371.195898)
			(xy 382.506537 -371.213083) (xy 382.512316 -371.220238) (xy 382.534068 -371.24592) (xy 382.572021 -371.301501)
			(xy 382.603058 -371.36122) (xy 382.626735 -371.424221) (xy 382.642712 -371.4896) (xy 382.65076 -371.55642)
			(xy 382.650763 -371.623723) (xy 382.642722 -371.690544) (xy 382.626752 -371.755924) (xy 382.603081 -371.818927)
			(xy 382.57205 -371.87865) (xy 382.534103 -371.934234) (xy 382.512316 -371.959886) (xy 382.506502 -371.967019)
			(xy 382.499997 -371.984219) (xy 382.499616 -371.993414) (xy 382.499616 -372.486682) (xy 382.500031 -372.495869)
			(xy 382.506541 -372.513053) (xy 382.512316 -372.52021) (xy 382.534138 -372.545834) (xy 382.572089 -372.601424)
			(xy 382.603123 -372.661151) (xy 382.626796 -372.724159) (xy 382.642768 -372.789545) (xy 382.65081 -372.856371)
			(xy 382.650807 -372.92368) (xy 382.642759 -372.990506) (xy 382.626781 -373.05589) (xy 382.603103 -373.118896)
			(xy 382.572063 -373.17862) (xy 382.534107 -373.234206) (xy 382.512316 -373.259858) (xy 382.506514 -373.267)
			(xy 382.500002 -373.284193) (xy 382.499616 -373.293386) (xy 382.499616 -373.451374) (xy 382.499214 -373.46155)
			(xy 382.491429 -373.480352) (xy 382.477036 -373.49474) (xy 382.45823 -373.502517) (xy 382.448054 -373.502936)
			(xy 381.731774 -373.502936) (xy 381.721611 -373.502487) (xy 381.702837 -373.4947) (xy 381.688471 -373.48032)
			(xy 381.680702 -373.461537) (xy 381.680212 -373.451374) (xy 381.680212 -373.293386) (xy 381.679806 -373.284198)
			(xy 381.673289 -373.267014) (xy 381.667512 -373.259858) (xy 381.645758 -373.234178) (xy 381.60781 -373.178595)
			(xy 381.576777 -373.118875) (xy 381.553104 -373.055874) (xy 381.537129 -372.990496) (xy 381.529083 -372.923676)
			(xy 381.52908 -372.856375) (xy 381.53712 -372.789555) (xy 381.553088 -372.724175) (xy 381.576756 -372.661172)
			(xy 381.607784 -372.601449) (xy 381.645727 -372.545862) (xy 381.667512 -372.52021) (xy 381.673331 -372.51308)
			(xy 381.679832 -372.495878) (xy 381.680212 -372.486682) (xy 381.680212 -371.993414) (xy 381.679792 -371.984228)
			(xy 381.673285 -371.967044) (xy 381.667512 -371.959886) (xy 381.645688 -371.934264) (xy 381.607742 -371.878673)
			(xy 381.576712 -371.818945) (xy 381.553042 -371.755936) (xy 381.537073 -371.690551) (xy 381.529032 -371.623725)
			(xy 380.426925 -371.623725) (xy 380.427054 -371.624067) (xy 380.443089 -371.689558) (xy 380.451165 -371.756498)
			(xy 380.451163 -371.823923) (xy 380.443086 -371.890863) (xy 380.427048 -371.956353) (xy 380.403281 -372.019451)
			(xy 380.372126 -372.079247) (xy 380.334034 -372.134881) (xy 380.312168 -372.160546) (xy 380.306365 -372.167687)
			(xy 380.299855 -372.184881) (xy 380.299468 -372.194074) (xy 380.299468 -372.351554) (xy 380.298936 -372.361677)
			(xy 380.291225 -372.380395) (xy 380.276952 -372.394753) (xy 380.25828 -372.402575) (xy 380.24816 -372.403116)
			(xy 379.53188 -372.403116) (xy 379.521727 -372.402695) (xy 379.502977 -372.394896) (xy 379.488655 -372.3805)
			(xy 379.480953 -372.36171) (xy 379.480572 -372.351554) (xy 379.480572 -372.194074) (xy 379.480181 -372.184885)
			(xy 379.473655 -372.1677) (xy 379.467872 -372.160546) (xy 379.446023 -372.134869) (xy 379.407935 -372.079235)
			(xy 379.376786 -372.019441) (xy 379.353022 -371.956345) (xy 379.336986 -371.890858) (xy 379.32891 -371.823922)
			(xy 379.328909 -371.7565) (xy 379.336983 -371.689563) (xy 379.353016 -371.624075) (xy 379.376777 -371.560979)
			(xy 379.407925 -371.501183) (xy 379.44601 -371.445548) (xy 379.467872 -371.419882) (xy 379.473667 -371.412736)
			(xy 379.480181 -371.395546) (xy 379.480572 -371.386354) (xy 379.480572 -370.893848) (xy 379.480145 -370.884663)
			(xy 379.473644 -370.867478) (xy 379.467872 -370.86032) (xy 379.445997 -370.834664) (xy 379.407911 -370.779027)
			(xy 379.376762 -370.71923) (xy 379.353 -370.656132) (xy 379.336966 -370.590642) (xy 379.328892 -370.523703)
			(xy 376.050821 -370.523703) (xy 376.042785 -370.590464) (xy 376.026814 -370.655846) (xy 376.003143 -370.71885)
			(xy 375.972113 -370.778573) (xy 375.934166 -370.83416) (xy 375.91238 -370.859812) (xy 375.906594 -370.866964)
			(xy 375.900073 -370.884149) (xy 375.89968 -370.89334) (xy 375.89968 -371.386862) (xy 375.900113 -371.396047)
			(xy 375.906611 -371.413231) (xy 375.91238 -371.42039) (xy 375.934181 -371.446031) (xy 375.972128 -371.50162)
			(xy 376.00316 -371.561345) (xy 376.026618 -371.623785) (xy 377.128712 -371.623785) (xy 377.128716 -371.556358)
			(xy 377.136796 -371.489417) (xy 377.152836 -371.423925) (xy 377.176606 -371.360827) (xy 377.207762 -371.301029)
			(xy 377.245857 -371.245395) (xy 377.267724 -371.21973) (xy 377.273536 -371.212596) (xy 377.28004 -371.195397)
			(xy 377.280424 -371.186202) (xy 377.280424 -371.028722) (xy 377.280944 -371.018599) (xy 377.288662 -370.999881)
			(xy 377.302938 -370.985524) (xy 377.321612 -370.977702) (xy 377.331732 -370.97716) (xy 378.048012 -370.97716)
			(xy 378.058162 -370.977611) (xy 378.076907 -370.985403) (xy 378.091229 -370.99979) (xy 378.098935 -371.01857)
			(xy 378.09932 -371.028722) (xy 378.09932 -371.186202) (xy 378.099725 -371.19539) (xy 378.106242 -371.212574)
			(xy 378.11202 -371.21973) (xy 378.133846 -371.245426) (xy 378.171934 -371.301057) (xy 378.203086 -371.360849)
			(xy 378.226851 -371.423942) (xy 378.242889 -371.489427) (xy 378.250967 -371.556361) (xy 378.250971 -371.623782)
			(xy 378.242899 -371.690717) (xy 378.226868 -371.756204) (xy 378.203109 -371.819299) (xy 378.171964 -371.879094)
			(xy 378.133881 -371.934728) (xy 378.11202 -371.960394) (xy 378.106246 -371.967555) (xy 378.099717 -371.984733)
			(xy 378.09932 -371.993922) (xy 378.09932 -372.486174) (xy 378.099738 -372.49536) (xy 378.106246 -372.512545)
			(xy 378.11202 -372.519702) (xy 378.133917 -372.54534) (xy 378.172003 -372.600979) (xy 378.203151 -372.660779)
			(xy 378.226913 -372.723879) (xy 378.242945 -372.789372) (xy 378.251018 -372.856313) (xy 378.251015 -372.923739)
			(xy 378.242936 -372.990679) (xy 378.226897 -373.056169) (xy 378.20313 -373.119268) (xy 378.171977 -373.179065)
			(xy 378.133885 -373.2347) (xy 378.11202 -373.260366) (xy 378.106215 -373.267506) (xy 378.099705 -373.2847)
			(xy 378.09932 -373.293894) (xy 378.09932 -373.451374) (xy 378.098851 -373.461504) (xy 378.091125 -373.480232)
			(xy 378.076832 -373.494591) (xy 378.05814 -373.502404) (xy 378.048012 -373.502936) (xy 377.331732 -373.502936)
			(xy 377.321584 -373.502453) (xy 377.30284 -373.494675) (xy 377.288516 -373.480297) (xy 377.280809 -373.461523)
			(xy 377.280424 -373.451374) (xy 377.280424 -373.293894) (xy 377.280012 -373.284707) (xy 377.273499 -373.267523)
			(xy 377.267724 -373.260366) (xy 377.245893 -373.234674) (xy 377.207801 -373.179044) (xy 377.176648 -373.119251)
			(xy 377.152881 -373.056158) (xy 377.136842 -372.990672) (xy 377.128763 -372.923736) (xy 377.12876 -372.856315)
			(xy 377.136833 -372.789378) (xy 377.152865 -372.723891) (xy 377.176627 -372.660795) (xy 377.207775 -372.601)
			(xy 377.245861 -372.545367) (xy 377.267724 -372.519702) (xy 377.273505 -372.512546) (xy 377.280028 -372.495364)
			(xy 377.280424 -372.486174) (xy 377.280424 -371.993922) (xy 377.279998 -371.984737) (xy 377.273495 -371.967552)
			(xy 377.267724 -371.960394) (xy 377.245822 -371.93476) (xy 377.207733 -371.879122) (xy 377.176582 -371.819321)
			(xy 377.152819 -371.75622) (xy 377.136786 -371.690727) (xy 377.128712 -371.623785) (xy 376.026618 -371.623785)
			(xy 376.026831 -371.624351) (xy 376.042802 -371.689734) (xy 376.050845 -371.756558) (xy 376.050844 -371.823863)
			(xy 376.042799 -371.890687) (xy 376.026825 -371.956069) (xy 376.003151 -372.019074) (xy 375.972117 -372.078799)
			(xy 375.934168 -372.134386) (xy 375.91238 -372.160038) (xy 375.906582 -372.167182) (xy 375.900069 -372.184374)
			(xy 375.89968 -372.193566) (xy 375.89968 -372.351554) (xy 375.899199 -372.36172) (xy 375.891432 -372.380511)
			(xy 375.877064 -372.394896) (xy 375.858284 -372.402686) (xy 375.848118 -372.403116) (xy 375.131838 -372.403116)
			(xy 375.121663 -372.402704) (xy 375.102861 -372.394923) (xy 375.088473 -372.380533) (xy 375.080695 -372.361729)
			(xy 375.080276 -372.351554) (xy 375.080276 -372.193566) (xy 375.079887 -372.184376) (xy 375.073359 -372.167192)
			(xy 375.067576 -372.160038) (xy 375.045801 -372.134375) (xy 375.007849 -372.078791) (xy 374.976813 -372.019069)
			(xy 374.953138 -371.956066) (xy 374.937163 -371.890685) (xy 374.929117 -371.823863) (xy 374.929116 -371.756558)
			(xy 374.937159 -371.689736) (xy 374.953132 -371.624354) (xy 374.976805 -371.56135) (xy 375.007838 -371.501627)
			(xy 375.045788 -371.446042) (xy 375.067576 -371.42039) (xy 375.073357 -371.413233) (xy 375.079882 -371.396052)
			(xy 375.080276 -371.386862) (xy 375.080276 -370.89334) (xy 375.079852 -370.884154) (xy 375.073349 -370.866969)
			(xy 375.067576 -370.859812) (xy 375.045775 -370.83417) (xy 375.007825 -370.778583) (xy 374.97679 -370.718858)
			(xy 374.953116 -370.655852) (xy 374.937143 -370.590469) (xy 374.929099 -370.523644) (xy 345.250797 -370.523644)
			(xy 345.242754 -370.590465) (xy 345.226782 -370.655847) (xy 345.203109 -370.718851) (xy 345.172076 -370.778574)
			(xy 345.134128 -370.83416) (xy 345.11234 -370.859812) (xy 345.106548 -370.86696) (xy 345.100032 -370.884149)
			(xy 345.09964 -370.89334) (xy 345.09964 -371.386862) (xy 345.100082 -371.396046) (xy 345.106575 -371.41323)
			(xy 345.11234 -371.42039) (xy 345.134142 -371.446031) (xy 345.172092 -371.501618) (xy 345.203126 -371.561343)
			(xy 345.226564 -371.623726) (xy 346.329187 -371.623726) (xy 346.32919 -371.556417) (xy 346.337239 -371.489591)
			(xy 346.353217 -371.424206) (xy 346.376896 -371.3612) (xy 346.407936 -371.301476) (xy 346.445893 -371.24589)
			(xy 346.467684 -371.220238) (xy 346.473488 -371.213098) (xy 346.479999 -371.195904) (xy 346.480384 -371.18671)
			(xy 346.480384 -371.028722) (xy 346.480783 -371.018546) (xy 346.488569 -370.999743) (xy 346.502963 -370.985356)
			(xy 346.52177 -370.977578) (xy 346.531946 -370.97716) (xy 347.248226 -370.97716) (xy 347.258388 -370.977612)
			(xy 347.277162 -370.9854) (xy 347.291527 -370.999778) (xy 347.299297 -371.018559) (xy 347.299788 -371.028722)
			(xy 347.299788 -371.18671) (xy 347.300196 -371.195897) (xy 347.306711 -371.213082) (xy 347.312488 -371.220238)
			(xy 347.334237 -371.245921) (xy 347.372185 -371.301504) (xy 347.403219 -371.361224) (xy 347.426893 -371.424224)
			(xy 347.442867 -371.489602) (xy 347.450914 -371.556421) (xy 347.450918 -371.623722) (xy 347.442878 -371.690542)
			(xy 347.426909 -371.755921) (xy 347.403242 -371.818924) (xy 347.372215 -371.878647) (xy 347.334272 -371.934233)
			(xy 347.312488 -371.959886) (xy 347.306671 -371.967017) (xy 347.300169 -371.984218) (xy 347.299788 -371.993414)
			(xy 347.299788 -372.486682) (xy 347.30021 -372.495868) (xy 347.306716 -372.513052) (xy 347.312488 -372.52021)
			(xy 347.334308 -372.545835) (xy 347.372254 -372.601426) (xy 347.403285 -372.661154) (xy 347.426954 -372.724162)
			(xy 347.442924 -372.789547) (xy 347.450965 -372.856372) (xy 347.450962 -372.923679) (xy 347.442915 -372.990504)
			(xy 347.426939 -373.055887) (xy 347.403264 -373.118893) (xy 347.372228 -373.178618) (xy 347.334277 -373.234205)
			(xy 347.312488 -373.259858) (xy 347.306683 -373.266997) (xy 347.300174 -373.284192) (xy 347.299788 -373.293386)
			(xy 347.299788 -373.451374) (xy 347.299246 -373.461527) (xy 347.291485 -373.480291) (xy 347.277134 -373.494656)
			(xy 347.258378 -373.502436) (xy 347.248226 -373.502936) (xy 346.531946 -373.502936) (xy 346.521774 -373.502498)
			(xy 346.502975 -373.494723) (xy 346.488588 -373.480341) (xy 346.480806 -373.461546) (xy 346.480384 -373.451374)
			(xy 346.480384 -373.293386) (xy 346.479984 -373.284198) (xy 346.473464 -373.267013) (xy 346.467684 -373.259858)
			(xy 346.445928 -373.234179) (xy 346.407976 -373.178597) (xy 346.376938 -373.118878) (xy 346.353262 -373.055877)
			(xy 346.337285 -372.990498) (xy 346.329237 -372.923677) (xy 346.329234 -372.856374) (xy 346.337276 -372.789553)
			(xy 346.353247 -372.724172) (xy 346.376917 -372.661169) (xy 346.407949 -372.601447) (xy 346.445897 -372.545862)
			(xy 346.467684 -372.52021) (xy 346.473499 -372.513078) (xy 346.480003 -372.495877) (xy 346.480384 -372.486682)
			(xy 346.480384 -371.993414) (xy 346.479971 -371.984227) (xy 346.47346 -371.967042) (xy 346.467684 -371.959886)
			(xy 346.445858 -371.934265) (xy 346.407907 -371.878675) (xy 346.376873 -371.818948) (xy 346.3532 -371.755939)
			(xy 346.337229 -371.690553) (xy 346.329187 -371.623726) (xy 345.226564 -371.623726) (xy 345.226798 -371.624349)
			(xy 345.242771 -371.689733) (xy 345.250814 -371.756557) (xy 345.250813 -371.823864) (xy 345.242767 -371.890688)
			(xy 345.226792 -371.956071) (xy 345.203117 -372.019076) (xy 345.172081 -372.0788) (xy 345.134129 -372.134386)
			(xy 345.11234 -372.160038) (xy 345.106537 -372.167179) (xy 345.100028 -372.184373) (xy 345.09964 -372.193566)
			(xy 345.09964 -372.351554) (xy 345.099198 -372.361725) (xy 345.091424 -372.380523) (xy 345.077043 -372.394911)
			(xy 345.058249 -372.402693) (xy 345.048078 -372.403116) (xy 344.331798 -372.403116) (xy 344.321621 -372.402737)
			(xy 344.302817 -372.394942) (xy 344.288431 -372.380543) (xy 344.280654 -372.361732) (xy 344.280236 -372.351554)
			(xy 344.280236 -372.193566) (xy 344.279834 -372.184378) (xy 344.273314 -372.167194) (xy 344.267536 -372.160038)
			(xy 344.245762 -372.134374) (xy 344.207813 -372.078789) (xy 344.17678 -372.019067) (xy 344.153106 -371.956064)
			(xy 344.137132 -371.890684) (xy 344.129087 -371.823862) (xy 344.129086 -371.756559) (xy 344.137129 -371.689737)
			(xy 344.1531 -371.624356) (xy 344.176771 -371.561352) (xy 344.207803 -371.501629) (xy 344.245749 -371.446042)
			(xy 344.267536 -371.42039) (xy 344.273324 -371.413239) (xy 344.279843 -371.396053) (xy 344.280236 -371.386862)
			(xy 344.280236 -370.89334) (xy 344.279798 -370.884156) (xy 344.273303 -370.866972) (xy 344.267536 -370.859812)
			(xy 344.245736 -370.83417) (xy 344.207788 -370.778582) (xy 344.176756 -370.718857) (xy 344.153084 -370.655851)
			(xy 344.137112 -370.590468) (xy 344.129068 -370.523644) (xy 340.851006 -370.523644) (xy 340.842963 -370.590465)
			(xy 340.826991 -370.655847) (xy 340.803319 -370.718851) (xy 340.772287 -370.778574) (xy 340.734339 -370.83416)
			(xy 340.712552 -370.859812) (xy 340.706762 -370.866962) (xy 340.700245 -370.884149) (xy 340.699852 -370.89334)
			(xy 340.699852 -371.386862) (xy 340.700291 -371.396046) (xy 340.706786 -371.41323) (xy 340.712552 -371.42039)
			(xy 340.734354 -371.446031) (xy 340.772303 -371.501618) (xy 340.803336 -371.561344) (xy 340.826797 -371.623785)
			(xy 341.928891 -371.623785) (xy 341.928895 -371.556358) (xy 341.936974 -371.489417) (xy 341.953014 -371.423926)
			(xy 341.976782 -371.360828) (xy 342.007937 -371.301031) (xy 342.04603 -371.245395) (xy 342.067896 -371.21973)
			(xy 342.073704 -371.212593) (xy 342.080212 -371.195396) (xy 342.080596 -371.186202) (xy 342.080596 -371.028722)
			(xy 342.081143 -371.018602) (xy 342.088856 -370.99989) (xy 342.103123 -370.985534) (xy 342.121787 -370.977706)
			(xy 342.131904 -370.97716) (xy 342.848184 -370.97716) (xy 342.858332 -370.977634) (xy 342.877076 -370.985417)
			(xy 342.891399 -370.999797) (xy 342.899106 -371.018572) (xy 342.899492 -371.028722) (xy 342.899492 -371.186202)
			(xy 342.899903 -371.195389) (xy 342.906416 -371.212573) (xy 342.912192 -371.21973) (xy 342.934019 -371.245426)
			(xy 342.972109 -371.301056) (xy 343.003262 -371.360848) (xy 343.027029 -371.423941) (xy 343.043067 -371.489426)
			(xy 343.051146 -371.556361) (xy 343.05115 -371.623782) (xy 343.043077 -371.690718) (xy 343.027046 -371.756205)
			(xy 343.003285 -371.8193) (xy 342.972139 -371.879095) (xy 342.934054 -371.934729) (xy 342.912192 -371.960394)
			(xy 342.906415 -371.967553) (xy 342.899889 -371.984733) (xy 342.899492 -371.993922) (xy 342.899492 -372.486174)
			(xy 342.899917 -372.49536) (xy 342.90642 -372.512544) (xy 342.912192 -372.519702) (xy 342.93409 -372.54534)
			(xy 342.972178 -372.600978) (xy 343.003328 -372.660778) (xy 343.02709 -372.723878) (xy 343.043124 -372.789371)
			(xy 343.051197 -372.856312) (xy 343.051194 -372.923739) (xy 343.043114 -372.99068) (xy 343.027075 -373.056171)
			(xy 343.003307 -373.119269) (xy 342.972152 -373.179066) (xy 342.934058 -373.234701) (xy 342.912192 -373.260366)
			(xy 342.906384 -373.267503) (xy 342.899876 -373.2847) (xy 342.899492 -373.293894) (xy 342.899492 -373.451374)
			(xy 342.898953 -373.461495) (xy 342.89124 -373.48021) (xy 342.87697 -373.494566) (xy 342.858302 -373.502392)
			(xy 342.848184 -373.502936) (xy 342.131904 -373.502936) (xy 342.121755 -373.502476) (xy 342.103009 -373.494688)
			(xy 342.088687 -373.480304) (xy 342.080981 -373.461525) (xy 342.080596 -373.451374) (xy 342.080596 -373.293894)
			(xy 342.080189 -373.284706) (xy 342.073673 -373.267522) (xy 342.067896 -373.260366) (xy 342.046066 -373.234673)
			(xy 342.007976 -373.179042) (xy 341.976824 -373.11925) (xy 341.953058 -373.056157) (xy 341.937021 -372.990671)
			(xy 341.928942 -372.923736) (xy 341.928939 -372.856315) (xy 341.937011 -372.789379) (xy 341.953043 -372.723892)
			(xy 341.976803 -372.660797) (xy 342.00795 -372.601001) (xy 342.046034 -372.545367) (xy 342.067896 -372.519702)
			(xy 342.073674 -372.512543) (xy 342.0802 -372.495363) (xy 342.080596 -372.486174) (xy 342.080596 -371.993922)
			(xy 342.080176 -371.984736) (xy 342.073669 -371.967551) (xy 342.067896 -371.960394) (xy 342.045995 -371.934759)
			(xy 342.007908 -371.87912) (xy 341.976759 -371.81932) (xy 341.952997 -371.756219) (xy 341.936964 -371.690726)
			(xy 341.928891 -371.623785) (xy 340.826797 -371.623785) (xy 340.827009 -371.62435) (xy 340.842981 -371.689733)
			(xy 340.851024 -371.756557) (xy 340.851023 -371.823864) (xy 340.842977 -371.890687) (xy 340.827002 -371.956071)
			(xy 340.803328 -372.019076) (xy 340.772292 -372.0788) (xy 340.734341 -372.134386) (xy 340.712552 -372.160038)
			(xy 340.706751 -372.16718) (xy 340.70024 -372.184373) (xy 340.699852 -372.193566) (xy 340.699852 -372.351554)
			(xy 340.699398 -372.361724) (xy 340.691627 -372.380519) (xy 340.67725 -372.394906) (xy 340.65846 -372.402691)
			(xy 340.64829 -372.403116) (xy 339.93201 -372.403116) (xy 339.921833 -372.402727) (xy 339.90303 -372.394937)
			(xy 339.888643 -372.38054) (xy 339.880866 -372.361731) (xy 339.880448 -372.351554) (xy 339.880448 -372.193566)
			(xy 339.880043 -372.184378) (xy 339.873525 -372.167195) (xy 339.867748 -372.160038) (xy 339.845974 -372.134375)
			(xy 339.808024 -372.07879) (xy 339.77699 -372.019068) (xy 339.753316 -371.956065) (xy 339.737342 -371.890684)
			(xy 339.729296 -371.823863) (xy 339.729295 -371.756558) (xy 339.737338 -371.689737) (xy 339.75331 -371.624355)
			(xy 339.776981 -371.561351) (xy 339.808013 -371.501628) (xy 339.845961 -371.446042) (xy 339.867748 -371.42039)
			(xy 339.873537 -371.41324) (xy 339.880055 -371.396053) (xy 339.880448 -371.386862) (xy 339.880448 -370.89334)
			(xy 339.880008 -370.884156) (xy 339.873514 -370.866972) (xy 339.867748 -370.859812) (xy 339.845948 -370.83417)
			(xy 339.807999 -370.778582) (xy 339.776966 -370.718857) (xy 339.753293 -370.655851) (xy 339.737321 -370.590468)
			(xy 339.729277 -370.523644) (xy 336.451238 -370.523644) (xy 336.451238 -370.523703) (xy 336.443163 -370.590641)
			(xy 336.427128 -370.65613) (xy 336.403363 -370.719227) (xy 336.372211 -370.779022) (xy 336.334121 -370.834656)
			(xy 336.312256 -370.86032) (xy 336.306463 -370.867467) (xy 336.299947 -370.884656) (xy 336.299556 -370.893848)
			(xy 336.299556 -371.386354) (xy 336.299998 -371.395538) (xy 336.306491 -371.412722) (xy 336.312256 -371.419882)
			(xy 336.334135 -371.445535) (xy 336.372226 -371.50117) (xy 336.403379 -371.560968) (xy 336.427016 -371.623725)
			(xy 337.529123 -371.623725) (xy 337.529126 -371.556418) (xy 337.537174 -371.489593) (xy 337.55315 -371.424209)
			(xy 337.576825 -371.361204) (xy 337.60786 -371.301479) (xy 337.645811 -371.245891) (xy 337.6676 -371.220238)
			(xy 337.673405 -371.213099) (xy 337.679915 -371.195904) (xy 337.6803 -371.18671) (xy 337.6803 -371.028722)
			(xy 337.68085 -371.01857) (xy 337.68861 -370.999809) (xy 337.702958 -370.985444) (xy 337.721711 -370.977662)
			(xy 337.731862 -370.97716) (xy 338.448142 -370.97716) (xy 338.458305 -370.9776) (xy 338.477079 -370.985392)
			(xy 338.491444 -370.999774) (xy 338.499213 -371.018558) (xy 338.499704 -371.028722) (xy 338.499704 -371.18671)
			(xy 338.500109 -371.195898) (xy 338.506626 -371.213082) (xy 338.512404 -371.220238) (xy 338.534153 -371.245921)
			(xy 338.5721 -371.301504) (xy 338.603133 -371.361224) (xy 338.626806 -371.424224) (xy 338.64278 -371.489602)
			(xy 338.650827 -371.556421) (xy 338.65083 -371.623722) (xy 338.64279 -371.690541) (xy 338.626823 -371.755921)
			(xy 338.603156 -371.818924) (xy 338.57213 -371.878646) (xy 338.534188 -371.934233) (xy 338.512404 -371.959886)
			(xy 338.506589 -371.967018) (xy 338.500085 -371.984219) (xy 338.499704 -371.993414) (xy 338.499704 -372.486682)
			(xy 338.500122 -372.495868) (xy 338.50663 -372.513053) (xy 338.512404 -372.52021) (xy 338.534224 -372.545835)
			(xy 338.572169 -372.601427) (xy 338.603198 -372.661154) (xy 338.626867 -372.724162) (xy 338.642836 -372.789547)
			(xy 338.650877 -372.856372) (xy 338.650874 -372.923679) (xy 338.642827 -372.990503) (xy 338.626852 -373.055887)
			(xy 338.603177 -373.118892) (xy 338.572142 -373.178617) (xy 338.534192 -373.234205) (xy 338.512404 -373.259858)
			(xy 338.506601 -373.266999) (xy 338.50009 -373.284193) (xy 338.499704 -373.293386) (xy 338.499704 -373.451374)
			(xy 338.499147 -373.461525) (xy 338.491388 -373.480286) (xy 338.477043 -373.49465) (xy 338.458292 -373.502433)
			(xy 338.448142 -373.502936) (xy 337.731862 -373.502936) (xy 337.721699 -373.502497) (xy 337.702924 -373.494705)
			(xy 337.688559 -373.480323) (xy 337.68079 -373.461538) (xy 337.6803 -373.451374) (xy 337.6803 -373.293386)
			(xy 337.679896 -373.284198) (xy 337.673378 -373.267014) (xy 337.6676 -373.259858) (xy 337.645847 -373.234178)
			(xy 337.6079 -373.178595) (xy 337.576867 -373.118874) (xy 337.553194 -373.055874) (xy 337.53722 -372.990495)
			(xy 337.529174 -372.923676) (xy 337.52917 -372.856375) (xy 337.537211 -372.789555) (xy 337.553179 -372.724175)
			(xy 337.576846 -372.661172) (xy 337.607873 -372.601449) (xy 337.645816 -372.545863) (xy 337.6676 -372.52021)
			(xy 337.673417 -372.513079) (xy 337.67992 -372.495878) (xy 337.6803 -372.486682) (xy 337.6803 -371.993414)
			(xy 337.679883 -371.984228) (xy 337.673374 -371.967043) (xy 337.6676 -371.959886) (xy 337.645776 -371.934264)
			(xy 337.607831 -371.878672) (xy 337.576802 -371.818944) (xy 337.553133 -371.755936) (xy 337.537163 -371.69055)
			(xy 337.529123 -371.623725) (xy 336.427016 -371.623725) (xy 336.427144 -371.624066) (xy 336.44318 -371.689557)
			(xy 336.451256 -371.756498) (xy 336.451254 -371.823923) (xy 336.443176 -371.890863) (xy 336.427138 -371.956354)
			(xy 336.40337 -372.019451) (xy 336.372216 -372.079248) (xy 336.334122 -372.134881) (xy 336.312256 -372.160546)
			(xy 336.306452 -372.167686) (xy 336.299943 -372.184881) (xy 336.299556 -372.194074) (xy 336.299556 -372.351554)
			(xy 336.299036 -372.361678) (xy 336.291322 -372.380399) (xy 336.277046 -372.394757) (xy 336.258369 -372.402577)
			(xy 336.248248 -372.403116) (xy 335.531968 -372.403116) (xy 335.521814 -372.402705) (xy 335.503064 -372.394902)
			(xy 335.488742 -372.380502) (xy 335.481041 -372.36171) (xy 335.48066 -372.351554) (xy 335.48066 -372.194074)
			(xy 335.480249 -372.184887) (xy 335.473734 -372.167704) (xy 335.46796 -372.160546) (xy 335.446111 -372.134869)
			(xy 335.408025 -372.079235) (xy 335.376876 -372.01944) (xy 335.353112 -371.956345) (xy 335.337077 -371.890858)
			(xy 335.329001 -371.823921) (xy 335.329 -371.7565) (xy 335.337073 -371.689563) (xy 335.353106 -371.624075)
			(xy 335.376867 -371.560979) (xy 335.408014 -371.501183) (xy 335.446098 -371.445548) (xy 335.46796 -371.419882)
			(xy 335.473754 -371.412735) (xy 335.480269 -371.395546) (xy 335.48066 -371.386354) (xy 335.48066 -370.893848)
			(xy 335.480214 -370.884665) (xy 335.473724 -370.867481) (xy 335.46796 -370.86032) (xy 335.446086 -370.834664)
			(xy 335.408 -370.779027) (xy 335.376852 -370.719229) (xy 335.35309 -370.656131) (xy 335.337057 -370.590642)
			(xy 335.328983 -370.523703) (xy 332.050912 -370.523703) (xy 332.042876 -370.590465) (xy 332.026905 -370.655846)
			(xy 332.003233 -370.71885) (xy 331.972202 -370.778573) (xy 331.934255 -370.83416) (xy 331.912468 -370.859812)
			(xy 331.90668 -370.866963) (xy 331.900161 -370.884149) (xy 331.899768 -370.89334) (xy 331.899768 -371.386862)
			(xy 331.900204 -371.396046) (xy 331.906701 -371.41323) (xy 331.912468 -371.42039) (xy 331.934269 -371.446031)
			(xy 331.972217 -371.501619) (xy 332.00325 -371.561344) (xy 332.026709 -371.623785) (xy 333.128803 -371.623785)
			(xy 333.128807 -371.556358) (xy 333.136887 -371.489417) (xy 333.152927 -371.423926) (xy 333.176696 -371.360827)
			(xy 333.207851 -371.30103) (xy 333.245945 -371.245395) (xy 333.267812 -371.21973) (xy 333.273622 -371.212594)
			(xy 333.280128 -371.195397) (xy 333.280512 -371.186202) (xy 333.280512 -371.028722) (xy 333.281044 -371.0186)
			(xy 333.288759 -370.999885) (xy 333.303031 -370.985529) (xy 333.321701 -370.977704) (xy 333.33182 -370.97716)
			(xy 334.0481 -370.97716) (xy 334.058249 -370.977621) (xy 334.076994 -370.985409) (xy 334.091316 -370.999793)
			(xy 334.099023 -371.018571) (xy 334.099408 -371.028722) (xy 334.099408 -371.186202) (xy 334.099815 -371.195389)
			(xy 334.106331 -371.212574) (xy 334.112108 -371.21973) (xy 334.133934 -371.245426) (xy 334.172024 -371.301056)
			(xy 334.203176 -371.360848) (xy 334.226942 -371.423941) (xy 334.242979 -371.489426) (xy 334.251058 -371.556361)
			(xy 334.251062 -371.623782) (xy 334.24299 -371.690717) (xy 334.226958 -371.756204) (xy 334.203199 -371.819299)
			(xy 334.172053 -371.879095) (xy 334.133969 -371.934729) (xy 334.112108 -371.960394) (xy 334.106332 -371.967554)
			(xy 334.099805 -371.984733) (xy 334.099408 -371.993922) (xy 334.099408 -372.486174) (xy 334.099829 -372.49536)
			(xy 334.106335 -372.512545) (xy 334.112108 -372.519702) (xy 334.134005 -372.54534) (xy 334.172092 -372.600978)
			(xy 334.203241 -372.660779) (xy 334.227003 -372.723879) (xy 334.243036 -372.789371) (xy 334.251109 -372.856312)
			(xy 334.251106 -372.923739) (xy 334.243027 -372.990679) (xy 334.226988 -373.05617) (xy 334.20322 -373.119268)
			(xy 334.172066 -373.179065) (xy 334.133974 -373.234701) (xy 334.112108 -373.260366) (xy 334.106302 -373.267504)
			(xy 334.099793 -373.2847) (xy 334.099408 -373.293894) (xy 334.099408 -373.451374) (xy 334.098854 -373.461493)
			(xy 334.091143 -373.480205) (xy 334.076878 -373.49456) (xy 334.058216 -373.502389) (xy 334.0481 -373.502936)
			(xy 333.33182 -373.502936) (xy 333.321672 -373.502463) (xy 333.302927 -373.494681) (xy 333.288604 -373.4803)
			(xy 333.280897 -373.461524) (xy 333.280512 -373.451374) (xy 333.280512 -373.293894) (xy 333.280102 -373.284707)
			(xy 333.273588 -373.267523) (xy 333.267812 -373.260366) (xy 333.245981 -373.234673) (xy 333.20789 -373.179043)
			(xy 333.176738 -373.119251) (xy 333.152971 -373.056157) (xy 333.136933 -372.990672) (xy 333.128854 -372.923736)
			(xy 333.128851 -372.856315) (xy 333.136924 -372.789379) (xy 333.152956 -372.723891) (xy 333.176717 -372.660796)
			(xy 333.207864 -372.601001) (xy 333.24595 -372.545367) (xy 333.267812 -372.519702) (xy 333.273592 -372.512545)
			(xy 333.280116 -372.495363) (xy 333.280512 -372.486174) (xy 333.280512 -371.993922) (xy 333.280088 -371.984736)
			(xy 333.273584 -371.967552) (xy 333.267812 -371.960394) (xy 333.24591 -371.93476) (xy 333.207822 -371.879121)
			(xy 333.176672 -371.819321) (xy 333.15291 -371.75622) (xy 333.136876 -371.690727) (xy 333.128803 -371.623785)
			(xy 332.026709 -371.623785) (xy 332.026921 -371.62435) (xy 332.042893 -371.689734) (xy 332.050936 -371.756558)
			(xy 332.050935 -371.823864) (xy 332.042889 -371.890687) (xy 332.026915 -371.95607) (xy 332.003241 -372.019075)
			(xy 331.972207 -372.078799) (xy 331.934256 -372.134386) (xy 331.912468 -372.160038) (xy 331.906669 -372.167181)
			(xy 331.900156 -372.184373) (xy 331.899768 -372.193566) (xy 331.899768 -372.351554) (xy 331.899299 -372.361722)
			(xy 331.89153 -372.380514) (xy 331.877158 -372.394901) (xy 331.858373 -372.402688) (xy 331.848206 -372.403116)
			(xy 331.131926 -372.403116) (xy 331.12175 -372.402714) (xy 331.102948 -372.394929) (xy 331.08856 -372.380536)
			(xy 331.080783 -372.36173) (xy 331.080364 -372.351554) (xy 331.080364 -372.193566) (xy 331.079956 -372.184379)
			(xy 331.073439 -372.167195) (xy 331.067664 -372.160038) (xy 331.045889 -372.134375) (xy 331.007939 -372.078791)
			(xy 330.976903 -372.019069) (xy 330.953229 -371.956066) (xy 330.937254 -371.890684) (xy 330.929208 -371.823863)
			(xy 330.929207 -371.756558) (xy 330.93725 -371.689736) (xy 330.953222 -371.624355) (xy 330.976895 -371.561351)
			(xy 331.007928 -371.501628) (xy 331.045876 -371.446042) (xy 331.067664 -371.42039) (xy 331.073455 -371.413241)
			(xy 331.079971 -371.396053) (xy 331.080364 -371.386862) (xy 331.080364 -370.89334) (xy 331.07992 -370.884157)
			(xy 331.073428 -370.866973) (xy 331.067664 -370.859812) (xy 331.045864 -370.83417) (xy 331.007914 -370.778582)
			(xy 330.97688 -370.718858) (xy 330.953206 -370.655852) (xy 330.937234 -370.590468) (xy 330.92919 -370.523644)
			(xy 301.250887 -370.523644) (xy 301.250887 -370.523702) (xy 301.242812 -370.590639) (xy 301.226779 -370.656127)
			(xy 301.203017 -370.719224) (xy 301.171869 -370.77902) (xy 301.133783 -370.834654) (xy 301.11192 -370.86032)
			(xy 301.106135 -370.867473) (xy 301.099613 -370.884658) (xy 301.09922 -370.893848) (xy 301.09922 -371.386354)
			(xy 301.099648 -371.395539) (xy 301.106149 -371.412724) (xy 301.11192 -371.419882) (xy 301.133797 -371.445536)
			(xy 301.171884 -371.501173) (xy 301.203033 -371.560971) (xy 301.226688 -371.623785) (xy 302.328773 -371.623785)
			(xy 302.328777 -371.556358) (xy 302.336856 -371.489418) (xy 302.352895 -371.423927) (xy 302.376662 -371.360829)
			(xy 302.407815 -371.301031) (xy 302.445907 -371.245396) (xy 302.467772 -371.21973) (xy 302.47359 -371.2126)
			(xy 302.48009 -371.195398) (xy 302.480472 -371.186202) (xy 302.480472 -371.028722) (xy 302.480945 -371.018593)
			(xy 302.488672 -370.999866) (xy 302.502963 -370.985508) (xy 302.521653 -370.977693) (xy 302.53178 -370.97716)
			(xy 303.24806 -370.97716) (xy 303.258207 -370.977654) (xy 303.27695 -370.985429) (xy 303.291274 -370.999803)
			(xy 303.298982 -371.018574) (xy 303.299368 -371.028722) (xy 303.299368 -371.186202) (xy 303.299784 -371.195388)
			(xy 303.306294 -371.212572) (xy 303.312068 -371.21973) (xy 303.333896 -371.245425) (xy 303.371988 -371.301055)
			(xy 303.403142 -371.360847) (xy 303.42691 -371.42394) (xy 303.442949 -371.489425) (xy 303.451028 -371.556361)
			(xy 303.451031 -371.623782) (xy 303.442959 -371.690718) (xy 303.426926 -371.756206) (xy 303.403165 -371.819301)
			(xy 303.372017 -371.879096) (xy 303.333931 -371.934729) (xy 303.312068 -371.960394) (xy 303.306287 -371.96755)
			(xy 303.299764 -371.984732) (xy 303.299368 -371.993922) (xy 303.299368 -372.486174) (xy 303.299798 -372.495359)
			(xy 303.306299 -372.512543) (xy 303.312068 -372.519702) (xy 303.333966 -372.545339) (xy 303.372056 -372.600977)
			(xy 303.403207 -372.660777) (xy 303.426971 -372.723877) (xy 303.443005 -372.78937) (xy 303.451079 -372.856312)
			(xy 303.451076 -372.923739) (xy 303.442996 -372.99068) (xy 303.426956 -373.056172) (xy 303.403186 -373.11927)
			(xy 303.37203 -373.179067) (xy 303.333935 -373.234701) (xy 303.312068 -373.260366) (xy 303.306257 -373.267501)
			(xy 303.299752 -373.284699) (xy 303.299368 -373.293894) (xy 303.299368 -373.451374) (xy 303.298853 -373.461498)
			(xy 303.291135 -373.480217) (xy 303.276857 -373.494574) (xy 303.258181 -373.502396) (xy 303.24806 -373.502936)
			(xy 302.53178 -373.502936) (xy 302.521629 -373.502496) (xy 302.502883 -373.4947) (xy 302.488562 -373.48031)
			(xy 302.480856 -373.461527) (xy 302.480472 -373.451374) (xy 302.480472 -373.293894) (xy 302.480071 -373.284706)
			(xy 302.473552 -373.267521) (xy 302.467772 -373.260366) (xy 302.445942 -373.234673) (xy 302.407855 -373.179042)
			(xy 302.376704 -373.119249) (xy 302.352939 -373.056156) (xy 302.336902 -372.99067) (xy 302.328824 -372.923736)
			(xy 302.328821 -372.856315) (xy 302.336893 -372.78938) (xy 302.352924 -372.723893) (xy 302.376683 -372.660798)
			(xy 302.407828 -372.601002) (xy 302.445911 -372.545368) (xy 302.467772 -372.519702) (xy 302.473559 -372.51255)
			(xy 302.480077 -372.495364) (xy 302.480472 -372.486174) (xy 302.480472 -371.993922) (xy 302.480058 -371.984735)
			(xy 302.473548 -371.96755) (xy 302.467772 -371.960394) (xy 302.445872 -371.934759) (xy 302.407786 -371.87912)
			(xy 302.376638 -371.819319) (xy 302.352878 -371.756218) (xy 302.336846 -371.690726) (xy 302.328773 -371.623785)
			(xy 301.226688 -371.623785) (xy 301.226795 -371.624069) (xy 301.242829 -371.689559) (xy 301.250904 -371.756498)
			(xy 301.250903 -371.823923) (xy 301.242826 -371.890862) (xy 301.226789 -371.956351) (xy 301.203024 -372.019449)
			(xy 301.171873 -372.079245) (xy 301.133784 -372.13488) (xy 301.11192 -372.160546) (xy 301.106124 -372.167692)
			(xy 301.099608 -372.184882) (xy 301.09922 -372.194074) (xy 301.09922 -372.351554) (xy 301.098734 -372.361683)
			(xy 301.091014 -372.38041) (xy 301.076727 -372.39477) (xy 301.058038 -372.402583) (xy 301.047912 -372.403116)
			(xy 300.331632 -372.403116) (xy 300.321482 -372.402653) (xy 300.302733 -372.394871) (xy 300.288409 -372.380487)
			(xy 300.280705 -372.361706) (xy 300.280324 -372.351554) (xy 300.280324 -372.194074) (xy 300.279921 -372.184886)
			(xy 300.273402 -372.167702) (xy 300.267624 -372.160546) (xy 300.245773 -372.13487) (xy 300.207682 -372.079237)
			(xy 300.17653 -372.019443) (xy 300.152764 -371.956347) (xy 300.136726 -371.890859) (xy 300.128649 -371.823922)
			(xy 300.128648 -371.756499) (xy 300.136723 -371.689561) (xy 300.152757 -371.624073) (xy 300.176521 -371.560976)
			(xy 300.207671 -371.501181) (xy 300.24576 -371.445547) (xy 300.267624 -371.419882) (xy 300.273413 -371.412732)
			(xy 300.279932 -371.395545) (xy 300.280324 -371.386354) (xy 300.280324 -370.893848) (xy 300.279885 -370.884664)
			(xy 300.273391 -370.86748) (xy 300.267624 -370.86032) (xy 300.245747 -370.834665) (xy 300.207657 -370.779029)
			(xy 300.176506 -370.719232) (xy 300.152741 -370.656134) (xy 300.136706 -370.590643) (xy 300.128631 -370.523704)
			(xy 296.851096 -370.523704) (xy 296.843021 -370.590639) (xy 296.826988 -370.656127) (xy 296.803227 -370.719223)
			(xy 296.772079 -370.779019) (xy 296.733994 -370.834654) (xy 296.712132 -370.86032) (xy 296.706336 -370.867465)
			(xy 296.699823 -370.884656) (xy 296.699432 -370.893848) (xy 296.699432 -371.386354) (xy 296.699879 -371.395537)
			(xy 296.706369 -371.412721) (xy 296.712132 -371.419882) (xy 296.734009 -371.445536) (xy 296.772095 -371.501173)
			(xy 296.803243 -371.560971) (xy 296.826876 -371.623726) (xy 297.92898 -371.623726) (xy 297.928984 -371.556417)
			(xy 297.937032 -371.489591) (xy 297.95301 -371.424206) (xy 297.976689 -371.3612) (xy 298.007729 -371.301476)
			(xy 298.045685 -371.245889) (xy 298.067476 -371.220238) (xy 298.073279 -371.213097) (xy 298.07979 -371.195903)
			(xy 298.080176 -371.18671) (xy 298.080176 -371.028722) (xy 298.080583 -371.018547) (xy 298.088368 -370.999746)
			(xy 298.102759 -370.985359) (xy 298.121563 -370.97758) (xy 298.131738 -370.97716) (xy 298.848018 -370.97716)
			(xy 298.858193 -370.97755) (xy 298.876993 -370.985345) (xy 298.891378 -370.999741) (xy 298.899158 -371.018546)
			(xy 298.89958 -371.028722) (xy 298.89958 -371.18671) (xy 298.89999 -371.195897) (xy 298.906504 -371.213081)
			(xy 298.91228 -371.220238) (xy 298.93403 -371.245921) (xy 298.971978 -371.301504) (xy 299.003012 -371.361223)
			(xy 299.026686 -371.424224) (xy 299.042661 -371.489602) (xy 299.050708 -371.556421) (xy 299.050711 -371.623722)
			(xy 299.042671 -371.690542) (xy 299.026703 -371.755922) (xy 299.003035 -371.818925) (xy 298.972008 -371.878647)
			(xy 298.934065 -371.934233) (xy 298.91228 -371.959886) (xy 298.906462 -371.967016) (xy 298.899961 -371.984218)
			(xy 298.89958 -371.993414) (xy 298.89958 -372.486682) (xy 298.900003 -372.495868) (xy 298.906508 -372.513052)
			(xy 298.91228 -372.52021) (xy 298.934101 -372.545835) (xy 298.972047 -372.601426) (xy 299.003078 -372.661153)
			(xy 299.026748 -372.724161) (xy 299.042718 -372.789547) (xy 299.050759 -372.856372) (xy 299.050756 -372.923679)
			(xy 299.042709 -372.990504) (xy 299.026733 -373.055888) (xy 299.003057 -373.118894) (xy 298.972021 -373.178618)
			(xy 298.934069 -373.234206) (xy 298.91228 -373.259858) (xy 298.906474 -373.266996) (xy 298.899966 -373.284192)
			(xy 298.89958 -373.293386) (xy 298.89958 -373.451374) (xy 298.899115 -373.461542) (xy 298.891342 -373.480332)
			(xy 298.876969 -373.494717) (xy 298.858185 -373.502506) (xy 298.848018 -373.502936) (xy 298.131738 -373.502936)
			(xy 298.121566 -373.502504) (xy 298.102767 -373.494727) (xy 298.08838 -373.480343) (xy 298.080598 -373.461546)
			(xy 298.080176 -373.451374) (xy 298.080176 -373.293386) (xy 298.079778 -373.284197) (xy 298.073256 -373.267013)
			(xy 298.067476 -373.259858) (xy 298.045721 -373.234179) (xy 298.007768 -373.178597) (xy 297.976732 -373.118878)
			(xy 297.953055 -373.055877) (xy 297.937079 -372.990497) (xy 297.929031 -372.923677) (xy 297.929028 -372.856374)
			(xy 297.93707 -372.789553) (xy 297.95304 -372.724172) (xy 297.976711 -372.661169) (xy 298.007742 -372.601447)
			(xy 298.045689 -372.545862) (xy 298.067476 -372.52021) (xy 298.073291 -372.513077) (xy 298.079795 -372.495877)
			(xy 298.080176 -372.486682) (xy 298.080176 -371.993414) (xy 298.079765 -371.984227) (xy 298.073252 -371.967042)
			(xy 298.067476 -371.959886) (xy 298.04565 -371.934265) (xy 298.007699 -371.878675) (xy 297.976666 -371.818948)
			(xy 297.952993 -371.755939) (xy 297.937022 -371.690552) (xy 297.92898 -371.623726) (xy 296.826876 -371.623726)
			(xy 296.827005 -371.624069) (xy 296.843039 -371.689559) (xy 296.851113 -371.756498) (xy 296.851112 -371.823923)
			(xy 296.843035 -371.890861) (xy 296.826999 -371.956351) (xy 296.803235 -372.019448) (xy 296.772084 -372.079245)
			(xy 296.733996 -372.13488) (xy 296.712132 -372.160546) (xy 296.706325 -372.167684) (xy 296.699819 -372.18488)
			(xy 296.699432 -372.194074) (xy 296.699432 -372.351554) (xy 296.698935 -372.361681) (xy 296.691217 -372.380407)
			(xy 296.676933 -372.394765) (xy 296.658249 -372.402581) (xy 296.648124 -372.403116) (xy 295.931844 -372.403116)
			(xy 295.921695 -372.402643) (xy 295.902946 -372.394865) (xy 295.888622 -372.380484) (xy 295.880918 -372.361705)
			(xy 295.880536 -372.351554) (xy 295.880536 -372.194074) (xy 295.88013 -372.184887) (xy 295.873613 -372.167703)
			(xy 295.867836 -372.160546) (xy 295.845985 -372.13487) (xy 295.807893 -372.079238) (xy 295.77674 -372.019444)
			(xy 295.752973 -371.956348) (xy 295.736936 -371.89086) (xy 295.728858 -371.823922) (xy 295.728857 -371.756499)
			(xy 295.736932 -371.689561) (xy 295.752967 -371.624072) (xy 295.776731 -371.560976) (xy 295.807882 -371.50118)
			(xy 295.845972 -371.445547) (xy 295.867836 -371.419882) (xy 295.873627 -371.412733) (xy 295.880144 -371.395545)
			(xy 295.880536 -371.386354) (xy 295.880536 -370.893848) (xy 295.880095 -370.884664) (xy 295.873602 -370.86748)
			(xy 295.867836 -370.86032) (xy 295.845959 -370.834665) (xy 295.807868 -370.77903) (xy 295.776716 -370.719233)
			(xy 295.752951 -370.656134) (xy 295.736915 -370.590644) (xy 295.72884 -370.523704) (xy 292.450793 -370.523704)
			(xy 292.442757 -370.590465) (xy 292.426785 -370.655847) (xy 292.403113 -370.718851) (xy 292.37208 -370.778574)
			(xy 292.334131 -370.83416) (xy 292.312344 -370.859812) (xy 292.306553 -370.866961) (xy 292.300036 -370.884149)
			(xy 292.299644 -370.89334) (xy 292.299644 -371.386862) (xy 292.300085 -371.396046) (xy 292.306578 -371.41323)
			(xy 292.312344 -371.42039) (xy 292.334146 -371.44603) (xy 292.372096 -371.501618) (xy 292.403129 -371.561343)
			(xy 292.42659 -371.623785) (xy 293.528685 -371.623785) (xy 293.528689 -371.556358) (xy 293.536768 -371.489418)
			(xy 293.552807 -371.423927) (xy 293.576575 -371.360828) (xy 293.60773 -371.301031) (xy 293.645822 -371.245395)
			(xy 293.667688 -371.21973) (xy 293.673495 -371.212592) (xy 293.680004 -371.195396) (xy 293.680388 -371.186202)
			(xy 293.680388 -371.028722) (xy 293.680943 -371.018603) (xy 293.688654 -370.999892) (xy 293.702919 -370.985537)
			(xy 293.72158 -370.977708) (xy 293.731696 -370.97716) (xy 294.447976 -370.97716) (xy 294.458078 -370.977704)
			(xy 294.476748 -370.985426) (xy 294.491043 -370.999705) (xy 294.498785 -371.018366) (xy 294.499284 -371.028468)
			(xy 294.499284 -371.186202) (xy 294.499697 -371.195389) (xy 294.506209 -371.212573) (xy 294.511984 -371.21973)
			(xy 294.533811 -371.245426) (xy 294.571902 -371.301056) (xy 294.603055 -371.360847) (xy 294.626822 -371.42394)
			(xy 294.642861 -371.489426) (xy 294.65094 -371.556361) (xy 294.650944 -371.623782) (xy 294.642871 -371.690718)
			(xy 294.626839 -371.756205) (xy 294.603079 -371.8193) (xy 294.571932 -371.879095) (xy 294.533846 -371.934729)
			(xy 294.511984 -371.960394) (xy 294.506206 -371.967552) (xy 294.499681 -371.984733) (xy 294.499284 -371.993922)
			(xy 294.499284 -372.486174) (xy 294.49971 -372.495359) (xy 294.506213 -372.512544) (xy 294.511984 -372.519702)
			(xy 294.533882 -372.545339) (xy 294.571971 -372.600978) (xy 294.603121 -372.660777) (xy 294.626884 -372.723878)
			(xy 294.642917 -372.789371) (xy 294.650991 -372.856312) (xy 294.650988 -372.923739) (xy 294.642908 -372.99068)
			(xy 294.626869 -373.056171) (xy 294.6031 -373.119269) (xy 294.571944 -373.179066) (xy 294.533851 -373.234701)
			(xy 294.511984 -373.260366) (xy 294.506175 -373.267502) (xy 294.499668 -373.2847) (xy 294.499284 -373.293894)
			(xy 294.499284 -373.451374) (xy 294.498753 -373.461496) (xy 294.491038 -373.480212) (xy 294.476766 -373.494569)
			(xy 294.458095 -373.502393) (xy 294.447976 -373.502936) (xy 293.731696 -373.502936) (xy 293.721591 -373.502419)
			(xy 293.70292 -373.494687) (xy 293.688627 -373.4804) (xy 293.680886 -373.461732) (xy 293.680388 -373.451628)
			(xy 293.680388 -373.293894) (xy 293.679983 -373.284706) (xy 293.673466 -373.267522) (xy 293.667688 -373.260366)
			(xy 293.645858 -373.234673) (xy 293.607769 -373.179042) (xy 293.576617 -373.11925) (xy 293.552852 -373.056156)
			(xy 293.536814 -372.990671) (xy 293.528736 -372.923736) (xy 293.528733 -372.856315) (xy 293.536805 -372.789379)
			(xy 293.552837 -372.723892) (xy 293.576597 -372.660797) (xy 293.607743 -372.601002) (xy 293.645826 -372.545367)
			(xy 293.667688 -372.519702) (xy 293.673465 -372.512543) (xy 293.679992 -372.495363) (xy 293.680388 -372.486174)
			(xy 293.680388 -371.993922) (xy 293.67997 -371.984736) (xy 293.673462 -371.967551) (xy 293.667688 -371.960394)
			(xy 293.645787 -371.934759) (xy 293.6077 -371.87912) (xy 293.576552 -371.81932) (xy 293.55279 -371.756219)
			(xy 293.536758 -371.690726) (xy 293.528685 -371.623785) (xy 292.42659 -371.623785) (xy 292.426802 -371.624349)
			(xy 292.442775 -371.689733) (xy 292.450818 -371.756557) (xy 292.450817 -371.823864) (xy 292.442771 -371.890688)
			(xy 292.426796 -371.956071) (xy 292.403121 -372.019076) (xy 292.372085 -372.0788) (xy 292.334133 -372.134386)
			(xy 292.312344 -372.160038) (xy 292.306542 -372.167179) (xy 292.300032 -372.184373) (xy 292.299644 -372.193566)
			(xy 292.299644 -372.351554) (xy 292.299198 -372.361725) (xy 292.291425 -372.380522) (xy 292.277046 -372.394909)
			(xy 292.258253 -372.402693) (xy 292.248082 -372.403116) (xy 291.531802 -372.403116) (xy 291.521625 -372.402733)
			(xy 291.502821 -372.394941) (xy 291.488435 -372.380542) (xy 291.480658 -372.361732) (xy 291.48024 -372.351554)
			(xy 291.48024 -372.193566) (xy 291.479837 -372.184378) (xy 291.473317 -372.167194) (xy 291.46754 -372.160038)
			(xy 291.445766 -372.134374) (xy 291.407817 -372.07879) (xy 291.376783 -372.019068) (xy 291.353109 -371.956065)
			(xy 291.337135 -371.890684) (xy 291.32909 -371.823862) (xy 291.329089 -371.756559) (xy 291.337132 -371.689737)
			(xy 291.353103 -371.624356) (xy 291.376774 -371.561352) (xy 291.407806 -371.501628) (xy 291.445753 -371.446042)
			(xy 291.46754 -371.42039) (xy 291.473328 -371.413239) (xy 291.479847 -371.396053) (xy 291.48024 -371.386862)
			(xy 291.48024 -370.89334) (xy 291.479801 -370.884156) (xy 291.473306 -370.866972) (xy 291.46754 -370.859812)
			(xy 291.44574 -370.83417) (xy 291.407792 -370.778582) (xy 291.376759 -370.718857) (xy 291.353087 -370.655851)
			(xy 291.337115 -370.590468) (xy 291.329071 -370.523644) (xy 288.051032 -370.523644) (xy 288.051032 -370.523703)
			(xy 288.042957 -370.590641) (xy 288.026921 -370.65613) (xy 288.003156 -370.719227) (xy 287.972004 -370.779022)
			(xy 287.933913 -370.834656) (xy 287.912048 -370.86032) (xy 287.906254 -370.867467) (xy 287.899739 -370.884656)
			(xy 287.899348 -370.893848) (xy 287.899348 -371.386354) (xy 287.899792 -371.395537) (xy 287.906284 -371.412721)
			(xy 287.912048 -371.419882) (xy 287.933928 -371.445535) (xy 287.972019 -371.50117) (xy 288.003172 -371.560967)
			(xy 288.02681 -371.623726) (xy 289.128893 -371.623726) (xy 289.128896 -371.556417) (xy 289.136945 -371.489591)
			(xy 289.152924 -371.424206) (xy 289.176603 -371.3612) (xy 289.207644 -371.301475) (xy 289.2456 -371.245889)
			(xy 289.267392 -371.220238) (xy 289.273196 -371.213098) (xy 289.279707 -371.195904) (xy 289.280092 -371.18671)
			(xy 289.280092 -371.028722) (xy 289.28065 -371.018571) (xy 289.288409 -370.999811) (xy 289.302754 -370.985447)
			(xy 289.321504 -370.977663) (xy 289.331654 -370.97716) (xy 290.047934 -370.97716) (xy 290.058097 -370.977606)
			(xy 290.076871 -370.985396) (xy 290.091236 -370.999776) (xy 290.099005 -371.018559) (xy 290.099496 -371.028722)
			(xy 290.099496 -371.18671) (xy 290.099902 -371.195898) (xy 290.106419 -371.213082) (xy 290.112196 -371.220238)
			(xy 290.133945 -371.245921) (xy 290.171893 -371.301504) (xy 290.202926 -371.361224) (xy 290.226599 -371.424224)
			(xy 290.242574 -371.489602) (xy 290.250621 -371.556421) (xy 290.250624 -371.623722) (xy 290.242584 -371.690542)
			(xy 290.226616 -371.755921) (xy 290.202949 -371.818924) (xy 290.171922 -371.878647) (xy 290.13398 -371.934233)
			(xy 290.112196 -371.959886) (xy 290.10638 -371.967017) (xy 290.099877 -371.984218) (xy 290.099496 -371.993414)
			(xy 290.099496 -372.486682) (xy 290.099916 -372.495868) (xy 290.106423 -372.513053) (xy 290.112196 -372.52021)
			(xy 290.134016 -372.545835) (xy 290.171962 -372.601426) (xy 290.202991 -372.661154) (xy 290.226661 -372.724162)
			(xy 290.24263 -372.789547) (xy 290.250671 -372.856372) (xy 290.250668 -372.923679) (xy 290.242621 -372.990503)
			(xy 290.226646 -373.055887) (xy 290.202971 -373.118893) (xy 290.171935 -373.178618) (xy 290.133985 -373.234205)
			(xy 290.112196 -373.259858) (xy 290.106392 -373.266998) (xy 290.099882 -373.284192) (xy 290.099496 -373.293386)
			(xy 290.099496 -373.451374) (xy 290.098946 -373.461526) (xy 290.091187 -373.480288) (xy 290.076838 -373.494653)
			(xy 290.058085 -373.502435) (xy 290.047934 -373.502936) (xy 289.331654 -373.502936) (xy 289.32149 -373.502504)
			(xy 289.302715 -373.494709) (xy 289.28835 -373.480325) (xy 289.280582 -373.461539) (xy 289.280092 -373.451374)
			(xy 289.280092 -373.293386) (xy 289.27969 -373.284198) (xy 289.273171 -373.267014) (xy 289.267392 -373.259858)
			(xy 289.245636 -373.234179) (xy 289.207683 -373.178598) (xy 289.176645 -373.118878) (xy 289.152968 -373.055877)
			(xy 289.136991 -372.990498) (xy 289.128943 -372.923677) (xy 289.12894 -372.856374) (xy 289.136982 -372.789553)
			(xy 289.152953 -372.724172) (xy 289.176624 -372.661168) (xy 289.207656 -372.601446) (xy 289.245605 -372.545861)
			(xy 289.267392 -372.52021) (xy 289.273208 -372.513079) (xy 289.279711 -372.495878) (xy 289.280092 -372.486682)
			(xy 289.280092 -371.993414) (xy 289.279677 -371.984227) (xy 289.273167 -371.967043) (xy 289.267392 -371.959886)
			(xy 289.245565 -371.934265) (xy 289.207614 -371.878676) (xy 289.17658 -371.818948) (xy 289.152907 -371.755939)
			(xy 289.136935 -371.690553) (xy 289.128893 -371.623726) (xy 288.02681 -371.623726) (xy 288.026938 -371.624066)
			(xy 288.042974 -371.689557) (xy 288.05105 -371.756498) (xy 288.051048 -371.823923) (xy 288.04297 -371.890864)
			(xy 288.026932 -371.956354) (xy 288.003164 -372.019452) (xy 287.972008 -372.079248) (xy 287.933915 -372.134882)
			(xy 287.912048 -372.160546) (xy 287.906243 -372.167685) (xy 287.899735 -372.18488) (xy 287.899348 -372.194074)
			(xy 287.899348 -372.351554) (xy 287.898835 -372.361679) (xy 287.89112 -372.380402) (xy 287.876842 -372.39476)
			(xy 287.858162 -372.402579) (xy 287.84804 -372.403116) (xy 287.13176 -372.403116) (xy 287.121651 -372.402648)
			(xy 287.102975 -372.3949) (xy 287.088682 -372.380598) (xy 287.080946 -372.361918) (xy 287.080452 -372.351808)
			(xy 287.080452 -372.194074) (xy 287.080043 -372.184887) (xy 287.073527 -372.167703) (xy 287.067752 -372.160546)
			(xy 287.0459 -372.13487) (xy 287.007807 -372.079238) (xy 286.976653 -372.019444) (xy 286.952886 -371.956349)
			(xy 286.936848 -371.89086) (xy 286.92877 -371.823922) (xy 286.928769 -371.756499) (xy 286.936844 -371.68956)
			(xy 286.95288 -371.624072) (xy 286.976645 -371.560975) (xy 287.007797 -371.50118) (xy 287.045887 -371.445546)
			(xy 287.067752 -371.419882) (xy 287.073545 -371.412735) (xy 287.08006 -371.395546) (xy 287.080452 -371.386354)
			(xy 287.080452 -370.893848) (xy 287.080007 -370.884665) (xy 287.073516 -370.867481) (xy 287.067752 -370.86032)
			(xy 287.045874 -370.834665) (xy 287.007783 -370.779031) (xy 286.97663 -370.719233) (xy 286.952864 -370.656135)
			(xy 286.936828 -370.590644) (xy 286.928752 -370.523704) (xy 266.501372 -370.523704) (xy 266.501372 -374.423882)
			(xy 286.928731 -374.423882) (xy 286.928735 -374.356454) (xy 286.936815 -374.289512) (xy 286.952857 -374.22402)
			(xy 286.976628 -374.160921) (xy 287.007787 -374.101124) (xy 287.045884 -374.04549) (xy 287.067752 -374.019826)
			(xy 287.073569 -374.012695) (xy 287.08007 -373.995494) (xy 287.080452 -373.986298) (xy 287.080452 -373.828818)
			(xy 287.080942 -373.818691) (xy 287.088666 -373.799968) (xy 287.102951 -373.785611) (xy 287.121636 -373.777793)
			(xy 287.13176 -373.777256) (xy 287.84804 -373.777256) (xy 287.858146 -373.777751) (xy 287.876817 -373.785494)
			(xy 287.891108 -373.799787) (xy 287.898849 -373.818458) (xy 287.899348 -373.828564) (xy 287.899348 -373.986298)
			(xy 287.899771 -373.995484) (xy 287.906277 -374.012667) (xy 287.912048 -374.019826) (xy 287.933873 -374.045524)
			(xy 287.971966 -374.101153) (xy 288.003121 -374.160944) (xy 288.02689 -374.224037) (xy 288.04293 -374.289522)
			(xy 288.05101 -374.356458) (xy 288.051014 -374.423823) (xy 291.32905 -374.423823) (xy 291.329054 -374.356514)
			(xy 291.337102 -374.289689) (xy 291.35308 -374.224304) (xy 291.376757 -374.161298) (xy 291.407796 -374.101573)
			(xy 291.44575 -374.045986) (xy 291.46754 -374.020334) (xy 291.473352 -374.0132) (xy 291.479857 -373.996001)
			(xy 291.48024 -373.986806) (xy 291.48024 -373.828818) (xy 291.480678 -373.818647) (xy 291.488458 -373.799853)
			(xy 291.502839 -373.785467) (xy 291.521631 -373.777682) (xy 291.531802 -373.777256) (xy 292.248082 -373.777256)
			(xy 292.258255 -373.777679) (xy 292.277053 -373.785461) (xy 292.291439 -373.799847) (xy 292.299221 -373.818645)
			(xy 292.299644 -373.828818) (xy 292.299644 -373.986806) (xy 292.300064 -373.995992) (xy 292.306572 -374.013176)
			(xy 292.312344 -374.020334) (xy 292.334091 -374.04602) (xy 292.372042 -374.101601) (xy 292.403078 -374.16132)
			(xy 292.426754 -374.22432) (xy 292.44273 -374.289698) (xy 292.450778 -374.356517) (xy 292.450782 -374.423819)
			(xy 292.450774 -374.423882) (xy 295.728819 -374.423882) (xy 295.728822 -374.356455) (xy 295.736903 -374.289513)
			(xy 295.752944 -374.224021) (xy 295.776715 -374.160922) (xy 295.807872 -374.101125) (xy 295.845968 -374.045491)
			(xy 295.867836 -374.019826) (xy 295.873651 -374.012694) (xy 295.880154 -373.995493) (xy 295.880536 -373.986298)
			(xy 295.880536 -373.828818) (xy 295.881041 -373.818693) (xy 295.888762 -373.799973) (xy 295.903043 -373.785616)
			(xy 295.921722 -373.777796) (xy 295.931844 -373.777256) (xy 296.648124 -373.777256) (xy 296.658274 -373.777701)
			(xy 296.677019 -373.785496) (xy 296.69134 -373.799885) (xy 296.699046 -373.818666) (xy 296.699432 -373.828818)
			(xy 296.699432 -373.986298) (xy 296.699858 -373.995483) (xy 296.706362 -374.012667) (xy 296.712132 -374.019826)
			(xy 296.733954 -374.045526) (xy 296.772041 -374.101156) (xy 296.803192 -374.160948) (xy 296.826957 -374.22404)
			(xy 296.842995 -374.289525) (xy 296.851073 -374.356459) (xy 296.851077 -374.423878) (xy 296.851077 -374.423882)
			(xy 300.12861 -374.423882) (xy 300.128613 -374.356455) (xy 300.136694 -374.289513) (xy 300.152734 -374.224021)
			(xy 300.176504 -374.160923) (xy 300.207661 -374.101126) (xy 300.245757 -374.045491) (xy 300.267624 -374.019826)
			(xy 300.273437 -374.012693) (xy 300.279941 -373.995493) (xy 300.280324 -373.986298) (xy 300.280324 -373.828818)
			(xy 300.280841 -373.818694) (xy 300.28856 -373.799977) (xy 300.302837 -373.78562) (xy 300.321511 -373.777798)
			(xy 300.331632 -373.777256) (xy 301.047912 -373.777256) (xy 301.058061 -373.777711) (xy 301.076806 -373.785502)
			(xy 301.091127 -373.799888) (xy 301.098834 -373.818667) (xy 301.09922 -373.828818) (xy 301.09922 -373.986298)
			(xy 301.099627 -373.995486) (xy 301.106142 -374.01267) (xy 301.11192 -374.019826) (xy 301.133742 -374.045526)
			(xy 301.171831 -374.101156) (xy 301.202982 -374.160947) (xy 301.226748 -374.22404) (xy 301.242785 -374.289524)
			(xy 301.250864 -374.356458) (xy 301.250868 -374.423823) (xy 330.929168 -374.423823) (xy 330.929172 -374.356514)
			(xy 330.937221 -374.289688) (xy 330.953199 -374.224303) (xy 330.976878 -374.161297) (xy 331.007917 -374.101572)
			(xy 331.045873 -374.045986) (xy 331.067664 -374.020334) (xy 331.073479 -374.013202) (xy 331.079981 -373.996001)
			(xy 331.080364 -373.986806) (xy 331.080364 -373.828818) (xy 331.080779 -373.818644) (xy 331.088563 -373.799845)
			(xy 331.102952 -373.785458) (xy 331.121752 -373.777677) (xy 331.131926 -373.777256) (xy 331.848206 -373.777256)
			(xy 331.85838 -373.777659) (xy 331.877178 -373.78545) (xy 331.891564 -373.799842) (xy 331.899345 -373.818644)
			(xy 331.899768 -373.828818) (xy 331.899768 -373.986806) (xy 331.900182 -373.995993) (xy 331.906694 -374.013177)
			(xy 331.912468 -374.020334) (xy 331.934214 -374.04602) (xy 331.972164 -374.101602) (xy 332.003198 -374.161321)
			(xy 332.026873 -374.224321) (xy 332.042849 -374.289699) (xy 332.050896 -374.356518) (xy 332.0509 -374.423819)
			(xy 332.050892 -374.423882) (xy 335.328961 -374.423882) (xy 335.328965 -374.356455) (xy 335.337045 -374.289515)
			(xy 335.353083 -374.224024) (xy 335.37685 -374.160926) (xy 335.408004 -374.101128) (xy 335.446095 -374.045492)
			(xy 335.46796 -374.019826) (xy 335.473778 -374.012696) (xy 335.480278 -373.995494) (xy 335.48066 -373.986298)
			(xy 335.48066 -373.828818) (xy 335.481142 -373.81869) (xy 335.488867 -373.799965) (xy 335.503156 -373.785608)
			(xy 335.521842 -373.777791) (xy 335.531968 -373.777256) (xy 336.248248 -373.777256) (xy 336.2584 -373.777682)
			(xy 336.277145 -373.785485) (xy 336.291465 -373.799879) (xy 336.299171 -373.818664) (xy 336.299556 -373.828818)
			(xy 336.299556 -373.986298) (xy 336.299977 -373.995484) (xy 336.306484 -374.012668) (xy 336.312256 -374.019826)
			(xy 336.33408 -374.045525) (xy 336.372173 -374.101153) (xy 336.403328 -374.160944) (xy 336.427097 -374.224037)
			(xy 336.443136 -374.289523) (xy 336.451216 -374.356458) (xy 336.45122 -374.423823) (xy 339.729256 -374.423823)
			(xy 339.72926 -374.356514) (xy 339.737309 -374.289689) (xy 339.753286 -374.224304) (xy 339.776964 -374.161298)
			(xy 339.808003 -374.101573) (xy 339.845957 -374.045986) (xy 339.867748 -374.020334) (xy 339.873561 -374.013201)
			(xy 339.880065 -373.996001) (xy 339.880448 -373.986806) (xy 339.880448 -373.828818) (xy 339.880879 -373.818646)
			(xy 339.88866 -373.79985) (xy 339.903043 -373.785464) (xy 339.921838 -373.77768) (xy 339.93201 -373.777256)
			(xy 340.64829 -373.777256) (xy 340.658463 -373.777672) (xy 340.677261 -373.785457) (xy 340.691647 -373.799846)
			(xy 340.699429 -373.818645) (xy 340.699852 -373.828818) (xy 340.699852 -373.986806) (xy 340.70027 -373.995992)
			(xy 340.706779 -374.013176) (xy 340.712552 -374.020334) (xy 340.734299 -374.04602) (xy 340.772249 -374.101601)
			(xy 340.803285 -374.16132) (xy 340.82696 -374.22432) (xy 340.842936 -374.289699) (xy 340.850984 -374.356517)
			(xy 340.850988 -374.423819) (xy 340.850988 -374.423823) (xy 344.129047 -374.423823) (xy 344.129051 -374.356514)
			(xy 344.137099 -374.289689) (xy 344.153077 -374.224304) (xy 344.176754 -374.161298) (xy 344.207792 -374.101573)
			(xy 344.245746 -374.045986) (xy 344.267536 -374.020334) (xy 344.273348 -374.0132) (xy 344.279852 -373.996001)
			(xy 344.280236 -373.986806) (xy 344.280236 -373.828818) (xy 344.280678 -373.818648) (xy 344.288457 -373.799854)
			(xy 344.302837 -373.785468) (xy 344.321628 -373.777682) (xy 344.331798 -373.777256) (xy 345.048078 -373.777256)
			(xy 345.05825 -373.777683) (xy 345.077048 -373.785464) (xy 345.091434 -373.799849) (xy 345.099217 -373.818646)
			(xy 345.09964 -373.828818) (xy 345.09964 -373.986806) (xy 345.100061 -373.995992) (xy 345.106569 -374.013175)
			(xy 345.11234 -374.020334) (xy 345.134087 -374.04602) (xy 345.172038 -374.101601) (xy 345.203075 -374.16132)
			(xy 345.226751 -374.22432) (xy 345.242727 -374.289698) (xy 345.250775 -374.356517) (xy 345.250779 -374.423819)
			(xy 345.250779 -374.423823) (xy 374.929078 -374.423823) (xy 374.929081 -374.356514) (xy 374.93713 -374.289688)
			(xy 374.953109 -374.224303) (xy 374.976788 -374.161296) (xy 375.007828 -374.101572) (xy 375.045784 -374.045985)
			(xy 375.067576 -374.020334) (xy 375.07338 -374.013194) (xy 375.079891 -373.996) (xy 375.080276 -373.986806)
			(xy 375.080276 -373.828818) (xy 375.080679 -373.818643) (xy 375.088465 -373.799841) (xy 375.102858 -373.785454)
			(xy 375.121663 -373.777675) (xy 375.131838 -373.777256) (xy 375.848118 -373.777256) (xy 375.858279 -373.777719)
			(xy 375.877052 -373.785503) (xy 375.891418 -373.799878) (xy 375.899188 -373.818656) (xy 375.89968 -373.828818)
			(xy 375.89968 -373.986806) (xy 375.900092 -373.995993) (xy 375.906605 -374.013177) (xy 375.91238 -374.020334)
			(xy 375.934126 -374.046021) (xy 375.972074 -374.101603) (xy 376.003108 -374.161322) (xy 376.026783 -374.224321)
			(xy 376.042758 -374.289699) (xy 376.050805 -374.356518) (xy 376.050809 -374.423819) (xy 376.050801 -374.423882)
			(xy 379.32887 -374.423882) (xy 379.328874 -374.356455) (xy 379.336954 -374.289515) (xy 379.352993 -374.224024)
			(xy 379.376761 -374.160925) (xy 379.407915 -374.101127) (xy 379.446007 -374.045492) (xy 379.467872 -374.019826)
			(xy 379.473691 -374.012697) (xy 379.48019 -373.995494) (xy 379.480572 -373.986298) (xy 379.480572 -373.828818)
			(xy 379.481042 -373.818688) (xy 379.48877 -373.799962) (xy 379.503062 -373.785604) (xy 379.521753 -373.777789)
			(xy 379.53188 -373.777256) (xy 380.24816 -373.777256) (xy 380.258306 -373.777754) (xy 380.277049 -373.785528)
			(xy 380.291372 -373.799901) (xy 380.299081 -373.818671) (xy 380.299468 -373.828818) (xy 380.299468 -373.986298)
			(xy 380.299886 -373.995484) (xy 380.306395 -374.012668) (xy 380.312168 -374.019826) (xy 380.333992 -374.045525)
			(xy 380.372084 -374.101154) (xy 380.403238 -374.160945) (xy 380.427006 -374.224038) (xy 380.443046 -374.289523)
			(xy 380.451125 -374.356458) (xy 380.451129 -374.423823) (xy 383.729165 -374.423823) (xy 383.729169 -374.356514)
			(xy 383.737218 -374.289688) (xy 383.753196 -374.224303) (xy 383.776874 -374.161297) (xy 383.807914 -374.101572)
			(xy 383.845869 -374.045986) (xy 383.86766 -374.020334) (xy 383.873474 -374.013202) (xy 383.879977 -373.996001)
			(xy 383.88036 -373.986806) (xy 383.88036 -373.828818) (xy 383.880779 -373.818645) (xy 383.888562 -373.799846)
			(xy 383.90295 -373.78546) (xy 383.921749 -373.777678) (xy 383.931922 -373.777256) (xy 384.648202 -373.777256)
			(xy 384.658376 -373.777663) (xy 384.677174 -373.785452) (xy 384.69156 -373.799843) (xy 384.699341 -373.818644)
			(xy 384.699764 -373.828818) (xy 384.699764 -373.986806) (xy 384.700179 -373.995992) (xy 384.70669 -374.013176)
			(xy 384.712464 -374.020334) (xy 384.73421 -374.04602) (xy 384.77216 -374.101602) (xy 384.803195 -374.161321)
			(xy 384.82687 -374.224321) (xy 384.842846 -374.289699) (xy 384.850893 -374.356518) (xy 384.850897 -374.423819)
			(xy 384.850897 -374.423823) (xy 388.128956 -374.423823) (xy 388.12896 -374.356514) (xy 388.137009 -374.289689)
			(xy 388.152986 -374.224304) (xy 388.176664 -374.161298) (xy 388.207703 -374.101573) (xy 388.245657 -374.045986)
			(xy 388.267448 -374.020334) (xy 388.273261 -374.013201) (xy 388.279765 -373.996001) (xy 388.280148 -373.986806)
			(xy 388.280148 -373.828818) (xy 388.280579 -373.818646) (xy 388.28836 -373.79985) (xy 388.302743 -373.785464)
			(xy 388.321538 -373.77768) (xy 388.33171 -373.777256) (xy 389.04799 -373.777256) (xy 389.058163 -373.777672)
			(xy 389.076961 -373.785457) (xy 389.091347 -373.799846) (xy 389.099129 -373.818645) (xy 389.099552 -373.828818)
			(xy 389.099552 -373.986806) (xy 389.09997 -373.995992) (xy 389.106479 -374.013176) (xy 389.112252 -374.020334)
			(xy 389.133999 -374.04602) (xy 389.171949 -374.101601) (xy 389.202985 -374.16132) (xy 389.22666 -374.22432)
			(xy 389.242636 -374.289699) (xy 389.250684 -374.356517) (xy 389.250688 -374.423819) (xy 389.250688 -374.423823)
			(xy 418.928987 -374.423823) (xy 418.928991 -374.356514) (xy 418.93704 -374.289688) (xy 418.953019 -374.224302)
			(xy 418.976698 -374.161296) (xy 419.007739 -374.101572) (xy 419.045696 -374.045986) (xy 419.067488 -374.020334)
			(xy 419.073294 -374.013195) (xy 419.079803 -373.996) (xy 419.080188 -373.986806) (xy 419.080188 -373.828818)
			(xy 419.08058 -373.818641) (xy 419.088368 -373.799837) (xy 419.102764 -373.78545) (xy 419.121573 -373.777673)
			(xy 419.13175 -373.777256) (xy 419.84803 -373.777256) (xy 419.858192 -373.777709) (xy 419.876965 -373.785497)
			(xy 419.89133 -373.799875) (xy 419.8991 -373.818656) (xy 419.899592 -373.828818) (xy 419.899592 -373.986806)
			(xy 419.900001 -373.995993) (xy 419.906516 -374.013177) (xy 419.912292 -374.020334) (xy 419.934038 -374.04602)
			(xy 419.971986 -374.101603) (xy 420.003019 -374.161322) (xy 420.026693 -374.224322) (xy 420.042668 -374.2897)
			(xy 420.050715 -374.356518) (xy 420.050719 -374.423819) (xy 420.050711 -374.423882) (xy 423.328779 -374.423882)
			(xy 423.328783 -374.356455) (xy 423.336863 -374.289514) (xy 423.352903 -374.224023) (xy 423.376671 -374.160925)
			(xy 423.407825 -374.101127) (xy 423.445918 -374.045492) (xy 423.467784 -374.019826) (xy 423.473593 -374.012689)
			(xy 423.480101 -373.995492) (xy 423.480484 -373.986298) (xy 423.480484 -373.828818) (xy 423.480942 -373.818687)
			(xy 423.488672 -373.799958) (xy 423.502968 -373.785599) (xy 423.521663 -373.777787) (xy 423.531792 -373.777256)
			(xy 424.248072 -373.777256) (xy 424.258174 -373.777807) (xy 424.276843 -373.785527) (xy 424.291137 -373.799803)
			(xy 424.298881 -373.818463) (xy 424.29938 -373.828564) (xy 424.29938 -373.986298) (xy 424.299795 -373.995485)
			(xy 424.306306 -374.012669) (xy 424.31208 -374.019826) (xy 424.333903 -374.045525) (xy 424.371995 -374.101154)
			(xy 424.403148 -374.160946) (xy 424.426916 -374.224038) (xy 424.442955 -374.289523) (xy 424.451034 -374.356458)
			(xy 424.451038 -374.423823) (xy 427.729074 -374.423823) (xy 427.729078 -374.356514) (xy 427.737127 -374.289688)
			(xy 427.753106 -374.224303) (xy 427.776784 -374.161296) (xy 427.807824 -374.101572) (xy 427.84578 -374.045986)
			(xy 427.867572 -374.020334) (xy 427.873388 -374.013203) (xy 427.879889 -373.996001) (xy 427.880272 -373.986806)
			(xy 427.880272 -373.828818) (xy 427.880679 -373.818643) (xy 427.888465 -373.799842) (xy 427.902856 -373.785456)
			(xy 427.921659 -373.777676) (xy 427.931834 -373.777256) (xy 428.648114 -373.777256) (xy 428.658289 -373.777653)
			(xy 428.677087 -373.785446) (xy 428.691472 -373.79984) (xy 428.699253 -373.818643) (xy 428.699676 -373.828818)
			(xy 428.699676 -373.986806) (xy 428.700088 -373.995993) (xy 428.706601 -374.013177) (xy 428.712376 -374.020334)
			(xy 428.734122 -374.04602) (xy 428.772071 -374.101602) (xy 428.803105 -374.161321) (xy 428.82678 -374.224321)
			(xy 428.842755 -374.289699) (xy 428.850802 -374.356518) (xy 428.850806 -374.423819) (xy 428.850806 -374.423823)
			(xy 432.128865 -374.423823) (xy 432.128869 -374.356514) (xy 432.136918 -374.289688) (xy 432.152896 -374.224303)
			(xy 432.176574 -374.161297) (xy 432.207614 -374.101572) (xy 432.245569 -374.045986) (xy 432.26736 -374.020334)
			(xy 432.273174 -374.013202) (xy 432.279677 -373.996001) (xy 432.28006 -373.986806) (xy 432.28006 -373.828818)
			(xy 432.280479 -373.818645) (xy 432.288262 -373.799846) (xy 432.30265 -373.78546) (xy 432.321449 -373.777678)
			(xy 432.331622 -373.777256) (xy 433.047902 -373.777256) (xy 433.058076 -373.777663) (xy 433.076874 -373.785452)
			(xy 433.09126 -373.799843) (xy 433.099041 -373.818644) (xy 433.099464 -373.828818) (xy 433.099464 -373.986806)
			(xy 433.099879 -373.995992) (xy 433.10639 -374.013176) (xy 433.112164 -374.020334) (xy 433.13391 -374.04602)
			(xy 433.17186 -374.101602) (xy 433.202895 -374.161321) (xy 433.22657 -374.224321) (xy 433.242546 -374.289699)
			(xy 433.250593 -374.356518) (xy 433.250597 -374.423819) (xy 433.242557 -374.490639) (xy 433.226589 -374.556019)
			(xy 433.202921 -374.619021) (xy 433.171892 -374.678744) (xy 433.133949 -374.73433) (xy 433.112164 -374.759982)
			(xy 433.106346 -374.767112) (xy 433.099845 -374.784314) (xy 433.099464 -374.79351) (xy 433.099464 -375.286778)
			(xy 433.099893 -375.295963) (xy 433.106394 -375.313147) (xy 433.112164 -375.320306) (xy 433.133981 -375.345934)
			(xy 433.171929 -375.401524) (xy 433.202961 -375.461251) (xy 433.226632 -375.524259) (xy 433.242603 -375.589644)
			(xy 433.250644 -375.656469) (xy 433.250642 -375.723776) (xy 433.242594 -375.790601) (xy 433.226618 -375.855985)
			(xy 433.202942 -375.91899) (xy 433.171906 -375.978715) (xy 433.133954 -376.034302) (xy 433.112164 -376.059954)
			(xy 433.106357 -376.067092) (xy 433.09985 -376.084288) (xy 433.099464 -376.093482) (xy 433.099464 -376.25147)
			(xy 433.099011 -376.261639) (xy 433.091237 -376.280433) (xy 433.07686 -376.294819) (xy 433.058071 -376.302605)
			(xy 433.047902 -376.303032) (xy 432.331622 -376.303032) (xy 432.321448 -376.302617) (xy 432.302648 -376.294834)
			(xy 432.288262 -376.280445) (xy 432.280481 -376.261644) (xy 432.28006 -376.25147) (xy 432.28006 -376.093482)
			(xy 432.279645 -376.084296) (xy 432.273133 -376.067112) (xy 432.26736 -376.059954) (xy 432.245601 -376.034278)
			(xy 432.20765 -375.978695) (xy 432.176614 -375.918975) (xy 432.152939 -375.855974) (xy 432.136963 -375.790594)
			(xy 432.128917 -375.723774) (xy 432.128914 -375.656471) (xy 432.136955 -375.58965) (xy 432.152926 -375.524269)
			(xy 432.176596 -375.461266) (xy 432.207627 -375.401543) (xy 432.245574 -375.345958) (xy 432.26736 -375.320306)
			(xy 432.273144 -375.313152) (xy 432.279664 -375.295968) (xy 432.28006 -375.286778) (xy 432.28006 -374.79351)
			(xy 432.279632 -374.784325) (xy 432.273129 -374.767141) (xy 432.26736 -374.759982) (xy 432.24553 -374.734364)
			(xy 432.207581 -374.678773) (xy 432.176549 -374.619045) (xy 432.152877 -374.556036) (xy 432.136907 -374.49065)
			(xy 432.128865 -374.423823) (xy 428.850806 -374.423823) (xy 428.842766 -374.490639) (xy 428.826798 -374.556018)
			(xy 428.803131 -374.619021) (xy 428.772103 -374.678743) (xy 428.73416 -374.734329) (xy 428.712376 -374.759982)
			(xy 428.706559 -374.767113) (xy 428.700057 -374.784314) (xy 428.699676 -374.79351) (xy 428.699676 -375.286778)
			(xy 428.700102 -375.295963) (xy 428.706605 -375.313148) (xy 428.712376 -375.320306) (xy 428.734193 -375.345934)
			(xy 428.77214 -375.401524) (xy 428.803171 -375.461251) (xy 428.826841 -375.524259) (xy 428.842812 -375.589644)
			(xy 428.850853 -375.656469) (xy 428.850851 -375.723776) (xy 428.842804 -375.790601) (xy 428.826828 -375.855984)
			(xy 428.803152 -375.91899) (xy 428.772117 -375.978714) (xy 428.734165 -376.034302) (xy 428.712376 -376.059954)
			(xy 428.706571 -376.067093) (xy 428.700062 -376.084288) (xy 428.699676 -376.093482) (xy 428.699676 -376.25147)
			(xy 428.699212 -376.261638) (xy 428.691439 -376.280429) (xy 428.677066 -376.294815) (xy 428.658282 -376.302603)
			(xy 428.648114 -376.303032) (xy 427.931834 -376.303032) (xy 427.921661 -376.302607) (xy 427.902861 -376.294828)
			(xy 427.888474 -376.280442) (xy 427.880693 -376.261643) (xy 427.880272 -376.25147) (xy 427.880272 -376.093482)
			(xy 427.879877 -376.084293) (xy 427.873353 -376.067109) (xy 427.867572 -376.059954) (xy 427.845813 -376.034278)
			(xy 427.807861 -375.978696) (xy 427.776825 -375.918976) (xy 427.753149 -375.855974) (xy 427.737173 -375.790595)
			(xy 427.729126 -375.723774) (xy 427.729123 -375.656471) (xy 427.737165 -375.58965) (xy 427.753135 -375.524269)
			(xy 427.776806 -375.461266) (xy 427.807838 -375.401543) (xy 427.845785 -375.345958) (xy 427.867572 -375.320306)
			(xy 427.873357 -375.313153) (xy 427.879877 -375.295968) (xy 427.880272 -375.286778) (xy 427.880272 -374.79351)
			(xy 427.879863 -374.784323) (xy 427.873349 -374.767138) (xy 427.867572 -374.759982) (xy 427.845742 -374.734364)
			(xy 427.807792 -374.678774) (xy 427.776759 -374.619046) (xy 427.753087 -374.556037) (xy 427.737116 -374.49065)
			(xy 427.729074 -374.423823) (xy 424.451038 -374.423823) (xy 424.451038 -374.423879) (xy 424.442966 -374.490815)
			(xy 424.426934 -374.556302) (xy 424.403174 -374.619397) (xy 424.372027 -374.679192) (xy 424.333942 -374.734825)
			(xy 424.31208 -374.76049) (xy 424.30626 -374.767619) (xy 424.29976 -374.784822) (xy 424.29938 -374.794018)
			(xy 424.29938 -375.28627) (xy 424.299809 -375.295455) (xy 424.30631 -375.312639) (xy 424.31208 -375.319798)
			(xy 424.333974 -375.345439) (xy 424.372063 -375.401076) (xy 424.403214 -375.460876) (xy 424.426977 -375.523976)
			(xy 424.443011 -375.589468) (xy 424.451085 -375.656409) (xy 424.451082 -375.723836) (xy 424.443003 -375.790776)
			(xy 424.426964 -375.856267) (xy 424.403195 -375.919366) (xy 424.37204 -375.979163) (xy 424.333946 -376.034797)
			(xy 424.31208 -376.060462) (xy 424.306272 -376.067599) (xy 424.299765 -376.084796) (xy 424.29938 -376.09399)
			(xy 424.29938 -376.25147) (xy 424.29885 -376.261592) (xy 424.291135 -376.280309) (xy 424.276863 -376.294666)
			(xy 424.258191 -376.30249) (xy 424.248072 -376.303032) (xy 423.531792 -376.303032) (xy 423.521687 -376.302522)
			(xy 423.503015 -376.294788) (xy 423.488721 -376.280499) (xy 423.480981 -376.261829) (xy 423.480484 -376.251724)
			(xy 423.480484 -376.09399) (xy 423.480082 -376.084802) (xy 423.473563 -376.067617) (xy 423.467784 -376.060462)
			(xy 423.44595 -376.034772) (xy 423.407862 -375.979141) (xy 423.37671 -375.919348) (xy 423.352945 -375.856254)
			(xy 423.336908 -375.790768) (xy 423.32883 -375.723833) (xy 423.328827 -375.656412) (xy 423.3369 -375.589476)
			(xy 423.352932 -375.523989) (xy 423.376692 -375.460893) (xy 423.407838 -375.401098) (xy 423.445922 -375.345463)
			(xy 423.467784 -375.319798) (xy 423.473562 -375.31264) (xy 423.480088 -375.295459) (xy 423.480484 -375.28627)
			(xy 423.480484 -374.794018) (xy 423.480069 -374.784831) (xy 423.473559 -374.767647) (xy 423.467784 -374.76049)
			(xy 423.445879 -374.734859) (xy 423.407793 -374.679219) (xy 423.376645 -374.619418) (xy 423.352884 -374.556317)
			(xy 423.336852 -374.490824) (xy 423.328779 -374.423882) (xy 420.050711 -374.423882) (xy 420.042679 -374.490638)
			(xy 420.026712 -374.556018) (xy 420.003045 -374.61902) (xy 419.972018 -374.678743) (xy 419.934076 -374.73433)
			(xy 419.912292 -374.759982) (xy 419.906477 -374.767114) (xy 419.899974 -374.784315) (xy 419.899592 -374.79351)
			(xy 419.899592 -375.286778) (xy 419.900015 -375.295964) (xy 419.90652 -375.313148) (xy 419.912292 -375.320306)
			(xy 419.934108 -375.345934) (xy 419.972054 -375.401525) (xy 420.003084 -375.461252) (xy 420.026754 -375.52426)
			(xy 420.042724 -375.589644) (xy 420.050765 -375.656469) (xy 420.050763 -375.723776) (xy 420.042716 -375.7906)
			(xy 420.026741 -375.855984) (xy 420.003066 -375.918989) (xy 419.972031 -375.978714) (xy 419.934081 -376.034301)
			(xy 419.912292 -376.059954) (xy 419.906489 -376.067095) (xy 419.899978 -376.084289) (xy 419.899592 -376.093482)
			(xy 419.899592 -376.25147) (xy 419.899043 -376.261622) (xy 419.891284 -376.280385) (xy 419.876935 -376.29475)
			(xy 419.858182 -376.302531) (xy 419.84803 -376.303032) (xy 419.13175 -376.303032) (xy 419.121578 -376.302595)
			(xy 419.102779 -376.29482) (xy 419.088391 -376.280438) (xy 419.080609 -376.261642) (xy 419.080188 -376.25147)
			(xy 419.080188 -376.093482) (xy 419.079789 -376.084294) (xy 419.073268 -376.067109) (xy 419.067488 -376.059954)
			(xy 419.045728 -376.034278) (xy 419.007775 -375.978696) (xy 418.976738 -375.918976) (xy 418.953061 -375.855975)
			(xy 418.937085 -375.790595) (xy 418.929038 -375.723774) (xy 418.929035 -375.656471) (xy 418.937077 -375.589649)
			(xy 418.953048 -375.524268) (xy 418.97672 -375.461265) (xy 419.007752 -375.401542) (xy 419.045701 -375.345957)
			(xy 419.067488 -375.320306) (xy 419.073263 -375.313145) (xy 419.079791 -375.295967) (xy 419.080188 -375.286778)
			(xy 419.080188 -374.79351) (xy 419.079776 -374.784323) (xy 419.073264 -374.767138) (xy 419.067488 -374.759982)
			(xy 419.045658 -374.734364) (xy 419.007707 -374.678774) (xy 418.976673 -374.619046) (xy 418.953 -374.556037)
			(xy 418.937029 -374.49065) (xy 418.928987 -374.423823) (xy 389.250688 -374.423823) (xy 389.242648 -374.490639)
			(xy 389.226679 -374.556019) (xy 389.203011 -374.619022) (xy 389.171982 -374.678744) (xy 389.134037 -374.73433)
			(xy 389.112252 -374.759982) (xy 389.106432 -374.76711) (xy 389.099933 -374.784314) (xy 389.099552 -374.79351)
			(xy 389.099552 -375.286778) (xy 389.099983 -375.295963) (xy 389.106483 -375.313147) (xy 389.112252 -375.320306)
			(xy 389.13407 -375.345934) (xy 389.172018 -375.401523) (xy 389.203051 -375.46125) (xy 389.226722 -375.524258)
			(xy 389.242693 -375.589643) (xy 389.250735 -375.656469) (xy 389.250732 -375.723776) (xy 389.242685 -375.790601)
			(xy 389.226709 -375.855985) (xy 389.203032 -375.918991) (xy 389.171995 -375.978715) (xy 389.134042 -376.034302)
			(xy 389.112252 -376.059954) (xy 389.106444 -376.067091) (xy 389.099937 -376.084288) (xy 389.099552 -376.093482)
			(xy 389.099552 -376.25147) (xy 389.099111 -376.261641) (xy 389.091334 -376.280437) (xy 389.076954 -376.294823)
			(xy 389.058161 -376.302607) (xy 389.04799 -376.303032) (xy 388.33171 -376.303032) (xy 388.321535 -376.302627)
			(xy 388.302735 -376.29484) (xy 388.288349 -376.280448) (xy 388.280569 -376.261645) (xy 388.280148 -376.25147)
			(xy 388.280148 -376.093482) (xy 388.279736 -376.084295) (xy 388.273222 -376.067111) (xy 388.267448 -376.059954)
			(xy 388.24569 -376.034278) (xy 388.207739 -375.978695) (xy 388.176704 -375.918975) (xy 388.153029 -375.855973)
			(xy 388.137054 -375.790594) (xy 388.129007 -375.723774) (xy 388.129005 -375.656471) (xy 388.137046 -375.58965)
			(xy 388.153016 -375.52427) (xy 388.176686 -375.461267) (xy 388.207716 -375.401544) (xy 388.245662 -375.345958)
			(xy 388.267448 -375.320306) (xy 388.273231 -375.313151) (xy 388.279752 -375.295968) (xy 388.280148 -375.286778)
			(xy 388.280148 -374.79351) (xy 388.279722 -374.784325) (xy 388.273218 -374.767141) (xy 388.267448 -374.759982)
			(xy 388.245619 -374.734364) (xy 388.20767 -374.678773) (xy 388.176638 -374.619045) (xy 388.152968 -374.556036)
			(xy 388.136997 -374.490649) (xy 388.128956 -374.423823) (xy 384.850897 -374.423823) (xy 384.842857 -374.490639)
			(xy 384.826889 -374.556019) (xy 384.803221 -374.619021) (xy 384.772192 -374.678744) (xy 384.734249 -374.73433)
			(xy 384.712464 -374.759982) (xy 384.706646 -374.767112) (xy 384.700145 -374.784314) (xy 384.699764 -374.79351)
			(xy 384.699764 -375.286778) (xy 384.700193 -375.295963) (xy 384.706694 -375.313147) (xy 384.712464 -375.320306)
			(xy 384.734281 -375.345934) (xy 384.772229 -375.401524) (xy 384.803261 -375.461251) (xy 384.826932 -375.524259)
			(xy 384.842903 -375.589644) (xy 384.850944 -375.656469) (xy 384.850942 -375.723776) (xy 384.842894 -375.790601)
			(xy 384.826918 -375.855985) (xy 384.803242 -375.91899) (xy 384.772206 -375.978715) (xy 384.734254 -376.034302)
			(xy 384.712464 -376.059954) (xy 384.706657 -376.067092) (xy 384.70015 -376.084288) (xy 384.699764 -376.093482)
			(xy 384.699764 -376.25147) (xy 384.699311 -376.261639) (xy 384.691537 -376.280433) (xy 384.67716 -376.294819)
			(xy 384.658371 -376.302605) (xy 384.648202 -376.303032) (xy 383.931922 -376.303032) (xy 383.921748 -376.302617)
			(xy 383.902948 -376.294834) (xy 383.888562 -376.280445) (xy 383.880781 -376.261644) (xy 383.88036 -376.25147)
			(xy 383.88036 -376.093482) (xy 383.879945 -376.084296) (xy 383.873433 -376.067112) (xy 383.86766 -376.059954)
			(xy 383.845901 -376.034278) (xy 383.80795 -375.978695) (xy 383.776914 -375.918975) (xy 383.753239 -375.855974)
			(xy 383.737263 -375.790594) (xy 383.729217 -375.723774) (xy 383.729214 -375.656471) (xy 383.737255 -375.58965)
			(xy 383.753226 -375.524269) (xy 383.776896 -375.461266) (xy 383.807927 -375.401543) (xy 383.845874 -375.345958)
			(xy 383.86766 -375.320306) (xy 383.873444 -375.313152) (xy 383.879964 -375.295968) (xy 383.88036 -375.286778)
			(xy 383.88036 -374.79351) (xy 383.879932 -374.784325) (xy 383.873429 -374.767141) (xy 383.86766 -374.759982)
			(xy 383.84583 -374.734364) (xy 383.807881 -374.678773) (xy 383.776849 -374.619045) (xy 383.753177 -374.556036)
			(xy 383.737207 -374.49065) (xy 383.729165 -374.423823) (xy 380.451129 -374.423823) (xy 380.451129 -374.423879)
			(xy 380.443057 -374.490815) (xy 380.427025 -374.556302) (xy 380.403264 -374.619397) (xy 380.372116 -374.679192)
			(xy 380.334031 -374.734825) (xy 380.312168 -374.76049) (xy 380.306347 -374.767617) (xy 380.299847 -374.784822)
			(xy 380.299468 -374.794018) (xy 380.299468 -375.28627) (xy 380.2999 -375.295455) (xy 380.306399 -375.312639)
			(xy 380.312168 -375.319798) (xy 380.334063 -375.345438) (xy 380.372152 -375.401076) (xy 380.403304 -375.460875)
			(xy 380.427068 -375.523975) (xy 380.443102 -375.589468) (xy 380.451176 -375.656409) (xy 380.451173 -375.723836)
			(xy 380.443094 -375.790777) (xy 380.427054 -375.856268) (xy 380.403285 -375.919366) (xy 380.372129 -375.979163)
			(xy 380.334035 -376.034797) (xy 380.312168 -376.060462) (xy 380.306358 -376.067598) (xy 380.299852 -376.084796)
			(xy 380.299468 -376.09399) (xy 380.299468 -376.25147) (xy 380.298949 -376.261594) (xy 380.291233 -376.280313)
			(xy 380.276956 -376.29467) (xy 380.258281 -376.302492) (xy 380.24816 -376.303032) (xy 379.53188 -376.303032)
			(xy 379.521729 -376.302596) (xy 379.502982 -376.294799) (xy 379.48866 -376.280408) (xy 379.480955 -376.261623)
			(xy 379.480572 -376.25147) (xy 379.480572 -376.09399) (xy 379.480173 -376.084802) (xy 379.473652 -376.067617)
			(xy 379.467872 -376.060462) (xy 379.446038 -376.034772) (xy 379.407951 -375.97914) (xy 379.3768 -375.919347)
			(xy 379.353036 -375.856254) (xy 379.336999 -375.790768) (xy 379.328921 -375.723833) (xy 379.328918 -375.656412)
			(xy 379.336991 -375.589476) (xy 379.353022 -375.523989) (xy 379.376782 -375.460894) (xy 379.407928 -375.401098)
			(xy 379.446011 -375.345464) (xy 379.467872 -375.319798) (xy 379.473661 -375.312648) (xy 379.480178 -375.295461)
			(xy 379.480572 -375.28627) (xy 379.480572 -374.794018) (xy 379.48016 -374.784831) (xy 379.473648 -374.767646)
			(xy 379.467872 -374.76049) (xy 379.445968 -374.734858) (xy 379.407882 -374.679218) (xy 379.376735 -374.619417)
			(xy 379.352974 -374.556316) (xy 379.336943 -374.490823) (xy 379.32887 -374.423882) (xy 376.050801 -374.423882)
			(xy 376.042769 -374.490638) (xy 376.026801 -374.556018) (xy 376.003134 -374.619021) (xy 375.972107 -374.678743)
			(xy 375.934164 -374.734329) (xy 375.91238 -374.759982) (xy 375.906564 -374.767113) (xy 375.900062 -374.784315)
			(xy 375.89968 -374.79351) (xy 375.89968 -375.286778) (xy 375.900105 -375.295963) (xy 375.906609 -375.313148)
			(xy 375.91238 -375.320306) (xy 375.934197 -375.345934) (xy 375.972143 -375.401524) (xy 376.003174 -375.461252)
			(xy 376.026845 -375.524259) (xy 376.042815 -375.589644) (xy 376.050856 -375.656469) (xy 376.050854 -375.723776)
			(xy 376.042807 -375.7906) (xy 376.026831 -375.855984) (xy 376.003156 -375.91899) (xy 375.97212 -375.978714)
			(xy 375.934169 -376.034302) (xy 375.91238 -376.059954) (xy 375.906576 -376.067094) (xy 375.900066 -376.084288)
			(xy 375.89968 -376.093482) (xy 375.89968 -376.25147) (xy 375.899212 -376.261637) (xy 375.89144 -376.280428)
			(xy 375.877068 -376.294813) (xy 375.858285 -376.302602) (xy 375.848118 -376.303032) (xy 375.131838 -376.303032)
			(xy 375.121665 -376.302604) (xy 375.102866 -376.294826) (xy 375.088478 -376.280441) (xy 375.080697 -376.261643)
			(xy 375.080276 -376.25147) (xy 375.080276 -376.093482) (xy 375.07988 -376.084293) (xy 375.073357 -376.067109)
			(xy 375.067576 -376.059954) (xy 375.045817 -376.034278) (xy 375.007865 -375.978696) (xy 374.976828 -375.918976)
			(xy 374.953152 -375.855974) (xy 374.937176 -375.790595) (xy 374.929129 -375.723774) (xy 374.929126 -375.656471)
			(xy 374.937168 -375.58965) (xy 374.953138 -375.524269) (xy 374.97681 -375.461265) (xy 375.007841 -375.401543)
			(xy 375.045789 -375.345958) (xy 375.067576 -375.320306) (xy 375.07335 -375.313144) (xy 375.079879 -375.295967)
			(xy 375.080276 -375.286778) (xy 375.080276 -374.79351) (xy 375.079866 -374.784323) (xy 375.073353 -374.767138)
			(xy 375.067576 -374.759982) (xy 375.045746 -374.734365) (xy 375.007796 -374.678774) (xy 374.976762 -374.619046)
			(xy 374.95309 -374.556037) (xy 374.937119 -374.49065) (xy 374.929078 -374.423823) (xy 345.250779 -374.423823)
			(xy 345.242739 -374.49064) (xy 345.226769 -374.55602) (xy 345.2031 -374.619022) (xy 345.172071 -374.678745)
			(xy 345.134126 -374.73433) (xy 345.11234 -374.759982) (xy 345.106519 -374.767109) (xy 345.10002 -374.784314)
			(xy 345.09964 -374.79351) (xy 345.09964 -375.286778) (xy 345.100074 -375.295962) (xy 345.106573 -375.313146)
			(xy 345.11234 -375.320306) (xy 345.134158 -375.345933) (xy 345.172107 -375.401523) (xy 345.203141 -375.46125)
			(xy 345.226813 -375.524258) (xy 345.242784 -375.589643) (xy 345.250826 -375.656469) (xy 345.250823 -375.723776)
			(xy 345.242776 -375.790602) (xy 345.226799 -375.855986) (xy 345.203122 -375.918992) (xy 345.172084 -375.978716)
			(xy 345.13413 -376.034302) (xy 345.11234 -376.059954) (xy 345.106531 -376.06709) (xy 345.100025 -376.084288)
			(xy 345.09964 -376.093482) (xy 345.09964 -376.25147) (xy 345.099211 -376.261642) (xy 345.091432 -376.280441)
			(xy 345.077047 -376.294827) (xy 345.05825 -376.302609) (xy 345.048078 -376.303032) (xy 344.331798 -376.303032)
			(xy 344.321623 -376.302637) (xy 344.302822 -376.294846) (xy 344.288436 -376.280451) (xy 344.280657 -376.261646)
			(xy 344.280236 -376.25147) (xy 344.280236 -376.093482) (xy 344.279826 -376.084295) (xy 344.273311 -376.067111)
			(xy 344.267536 -376.059954) (xy 344.245778 -376.034277) (xy 344.207829 -375.978694) (xy 344.176794 -375.918974)
			(xy 344.15312 -375.855973) (xy 344.137145 -375.790594) (xy 344.129098 -375.723774) (xy 344.129096 -375.656471)
			(xy 344.137137 -375.589651) (xy 344.153106 -375.52427) (xy 344.176776 -375.461267) (xy 344.207805 -375.401544)
			(xy 344.24575 -375.345958) (xy 344.267536 -375.320306) (xy 344.273317 -375.31315) (xy 344.27984 -375.295968)
			(xy 344.280236 -375.286778) (xy 344.280236 -374.79351) (xy 344.279813 -374.784324) (xy 344.273308 -374.76714)
			(xy 344.267536 -374.759982) (xy 344.245707 -374.734364) (xy 344.20776 -374.678772) (xy 344.176728 -374.619044)
			(xy 344.153058 -374.556035) (xy 344.137088 -374.490649) (xy 344.129047 -374.423823) (xy 340.850988 -374.423823)
			(xy 340.842948 -374.490639) (xy 340.826979 -374.556019) (xy 340.803311 -374.619022) (xy 340.772282 -374.678744)
			(xy 340.734337 -374.73433) (xy 340.712552 -374.759982) (xy 340.706732 -374.76711) (xy 340.700233 -374.784314)
			(xy 340.699852 -374.79351) (xy 340.699852 -375.286778) (xy 340.700283 -375.295963) (xy 340.706783 -375.313147)
			(xy 340.712552 -375.320306) (xy 340.73437 -375.345934) (xy 340.772318 -375.401523) (xy 340.803351 -375.46125)
			(xy 340.827022 -375.524258) (xy 340.842993 -375.589643) (xy 340.851035 -375.656469) (xy 340.851032 -375.723776)
			(xy 340.842985 -375.790601) (xy 340.827009 -375.855985) (xy 340.803332 -375.918991) (xy 340.772295 -375.978715)
			(xy 340.734342 -376.034302) (xy 340.712552 -376.059954) (xy 340.706744 -376.067091) (xy 340.700237 -376.084288)
			(xy 340.699852 -376.093482) (xy 340.699852 -376.25147) (xy 340.699411 -376.261641) (xy 340.691634 -376.280437)
			(xy 340.677254 -376.294823) (xy 340.658461 -376.302607) (xy 340.64829 -376.303032) (xy 339.93201 -376.303032)
			(xy 339.921835 -376.302627) (xy 339.903035 -376.29484) (xy 339.888649 -376.280448) (xy 339.880869 -376.261645)
			(xy 339.880448 -376.25147) (xy 339.880448 -376.093482) (xy 339.880036 -376.084295) (xy 339.873522 -376.067111)
			(xy 339.867748 -376.059954) (xy 339.84599 -376.034278) (xy 339.808039 -375.978695) (xy 339.777004 -375.918975)
			(xy 339.753329 -375.855973) (xy 339.737354 -375.790594) (xy 339.729307 -375.723774) (xy 339.729305 -375.656471)
			(xy 339.737346 -375.58965) (xy 339.753316 -375.52427) (xy 339.776986 -375.461267) (xy 339.808016 -375.401544)
			(xy 339.845962 -375.345958) (xy 339.867748 -375.320306) (xy 339.873531 -375.313151) (xy 339.880052 -375.295968)
			(xy 339.880448 -375.286778) (xy 339.880448 -374.79351) (xy 339.880022 -374.784325) (xy 339.873518 -374.767141)
			(xy 339.867748 -374.759982) (xy 339.845919 -374.734364) (xy 339.80797 -374.678773) (xy 339.776938 -374.619045)
			(xy 339.753268 -374.556036) (xy 339.737297 -374.490649) (xy 339.729256 -374.423823) (xy 336.45122 -374.423823)
			(xy 336.45122 -374.423879) (xy 336.443148 -374.490815) (xy 336.427115 -374.556303) (xy 336.403354 -374.619398)
			(xy 336.372206 -374.679193) (xy 336.334119 -374.734826) (xy 336.312256 -374.76049) (xy 336.306433 -374.767616)
			(xy 336.299935 -374.784821) (xy 336.299556 -374.794018) (xy 336.299556 -375.28627) (xy 336.29999 -375.295454)
			(xy 336.306488 -375.312639) (xy 336.312256 -375.319798) (xy 336.334151 -375.345438) (xy 336.372242 -375.401075)
			(xy 336.403394 -375.460875) (xy 336.427158 -375.523975) (xy 336.443193 -375.589467) (xy 336.451267 -375.656409)
			(xy 336.451264 -375.723836) (xy 336.443185 -375.790777) (xy 336.427145 -375.856268) (xy 336.403375 -375.919367)
			(xy 336.372218 -375.979163) (xy 336.334123 -376.034797) (xy 336.312256 -376.060462) (xy 336.306445 -376.067597)
			(xy 336.29994 -376.084795) (xy 336.299556 -376.09399) (xy 336.299556 -376.25147) (xy 336.299049 -376.261595)
			(xy 336.29133 -376.280317) (xy 336.27705 -376.294674) (xy 336.258371 -376.302494) (xy 336.248248 -376.303032)
			(xy 335.531968 -376.303032) (xy 335.521816 -376.302605) (xy 335.503069 -376.294805) (xy 335.488748 -376.280411)
			(xy 335.481043 -376.261624) (xy 335.48066 -376.25147) (xy 335.48066 -376.09399) (xy 335.480241 -376.084804)
			(xy 335.473732 -376.06762) (xy 335.46796 -376.060462) (xy 335.446127 -376.034772) (xy 335.40804 -375.97914)
			(xy 335.37689 -375.919347) (xy 335.353126 -375.856253) (xy 335.33709 -375.790768) (xy 335.329012 -375.723833)
			(xy 335.329009 -375.656412) (xy 335.337082 -375.589477) (xy 335.353113 -375.52399) (xy 335.376872 -375.460894)
			(xy 335.408017 -375.401099) (xy 335.446099 -375.345464) (xy 335.46796 -375.319798) (xy 335.473747 -375.312647)
			(xy 335.480266 -375.295461) (xy 335.48066 -375.28627) (xy 335.48066 -374.794018) (xy 335.480228 -374.784833)
			(xy 335.473728 -374.76765) (xy 335.46796 -374.76049) (xy 335.446056 -374.734858) (xy 335.407971 -374.679218)
			(xy 335.376825 -374.619417) (xy 335.353065 -374.556316) (xy 335.337033 -374.490823) (xy 335.328961 -374.423882)
			(xy 332.050892 -374.423882) (xy 332.04286 -374.490639) (xy 332.026892 -374.556019) (xy 332.003224 -374.619021)
			(xy 331.972196 -374.678744) (xy 331.934253 -374.73433) (xy 331.912468 -374.759982) (xy 331.90665 -374.767112)
			(xy 331.900149 -374.784314) (xy 331.899768 -374.79351) (xy 331.899768 -375.286778) (xy 331.900196 -375.295963)
			(xy 331.906698 -375.313147) (xy 331.912468 -375.320306) (xy 331.934285 -375.345934) (xy 331.972233 -375.401524)
			(xy 332.003264 -375.461251) (xy 332.026935 -375.524259) (xy 332.042906 -375.589644) (xy 332.050947 -375.656469)
			(xy 332.050945 -375.723776) (xy 332.042898 -375.790601) (xy 332.026922 -375.855985) (xy 332.003246 -375.91899)
			(xy 331.972209 -375.978715) (xy 331.934257 -376.034302) (xy 331.912468 -376.059954) (xy 331.906662 -376.067092)
			(xy 331.900154 -376.084288) (xy 331.899768 -376.093482) (xy 331.899768 -376.25147) (xy 331.899312 -376.261639)
			(xy 331.891538 -376.280432) (xy 331.877162 -376.294817) (xy 331.858375 -376.302604) (xy 331.848206 -376.303032)
			(xy 331.131926 -376.303032) (xy 331.121752 -376.302614) (xy 331.102953 -376.294832) (xy 331.088566 -376.280444)
			(xy 331.080785 -376.261644) (xy 331.080364 -376.25147) (xy 331.080364 -376.093482) (xy 331.079948 -376.084296)
			(xy 331.073437 -376.067112) (xy 331.067664 -376.059954) (xy 331.045905 -376.034278) (xy 331.007954 -375.978695)
			(xy 330.976918 -375.918975) (xy 330.953242 -375.855974) (xy 330.937266 -375.790594) (xy 330.92922 -375.723774)
			(xy 330.929217 -375.656471) (xy 330.937258 -375.58965) (xy 330.953229 -375.524269) (xy 330.976899 -375.461266)
			(xy 331.007931 -375.401543) (xy 331.045877 -375.345958) (xy 331.067664 -375.320306) (xy 331.073448 -375.313152)
			(xy 331.079969 -375.295968) (xy 331.080364 -375.286778) (xy 331.080364 -374.79351) (xy 331.079935 -374.784325)
			(xy 331.073433 -374.767141) (xy 331.067664 -374.759982) (xy 331.045834 -374.734364) (xy 331.007885 -374.678773)
			(xy 330.976852 -374.619045) (xy 330.95318 -374.556036) (xy 330.93721 -374.49065) (xy 330.929168 -374.423823)
			(xy 301.250868 -374.423823) (xy 301.250868 -374.423878) (xy 301.242797 -374.490814) (xy 301.226766 -374.5563)
			(xy 301.203008 -374.619395) (xy 301.171863 -374.67919) (xy 301.133781 -374.734824) (xy 301.11192 -374.76049)
			(xy 301.106105 -374.767622) (xy 301.099601 -374.784823) (xy 301.09922 -374.794018) (xy 301.09922 -375.28627)
			(xy 301.09964 -375.295456) (xy 301.106146 -375.312641) (xy 301.11192 -375.319798) (xy 301.133813 -375.345439)
			(xy 301.171899 -375.401078) (xy 301.203048 -375.460877) (xy 301.226809 -375.523977) (xy 301.242842 -375.589469)
			(xy 301.250915 -375.65641) (xy 301.250912 -375.723835) (xy 301.242834 -375.790775) (xy 301.226796 -375.856266)
			(xy 301.203029 -375.919364) (xy 301.171876 -375.979161) (xy 301.133785 -376.034796) (xy 301.11192 -376.060462)
			(xy 301.106117 -376.067603) (xy 301.099605 -376.084797) (xy 301.09922 -376.09399) (xy 301.09922 -376.25147)
			(xy 301.098748 -376.2616) (xy 301.091023 -376.280328) (xy 301.076731 -376.294687) (xy 301.058039 -376.3025)
			(xy 301.047912 -376.303032) (xy 300.331632 -376.303032) (xy 300.321484 -376.302553) (xy 300.302738 -376.294774)
			(xy 300.288415 -376.280395) (xy 300.280708 -376.26162) (xy 300.280324 -376.25147) (xy 300.280324 -376.09399)
			(xy 300.279913 -376.084803) (xy 300.2734 -376.067619) (xy 300.267624 -376.060462) (xy 300.245789 -376.034773)
			(xy 300.207697 -375.979142) (xy 300.176544 -375.91935) (xy 300.152777 -375.856256) (xy 300.136739 -375.790769)
			(xy 300.12866 -375.723833) (xy 300.128658 -375.656412) (xy 300.136731 -375.589475) (xy 300.152764 -375.523987)
			(xy 300.176526 -375.460892) (xy 300.207674 -375.401096) (xy 300.245761 -375.345463) (xy 300.267624 -375.319798)
			(xy 300.273407 -375.312643) (xy 300.279929 -375.29546) (xy 300.280324 -375.28627) (xy 300.280324 -374.794018)
			(xy 300.2799 -374.784832) (xy 300.273395 -374.767648) (xy 300.267624 -374.76049) (xy 300.245718 -374.734859)
			(xy 300.207629 -374.67922) (xy 300.176479 -374.61942) (xy 300.152716 -374.556318) (xy 300.136683 -374.490825)
			(xy 300.12861 -374.423882) (xy 296.851077 -374.423882) (xy 296.843006 -374.490813) (xy 296.826976 -374.556299)
			(xy 296.803218 -374.619394) (xy 296.772074 -374.67919) (xy 296.733992 -374.734824) (xy 296.712132 -374.76049)
			(xy 296.706306 -374.767614) (xy 296.699811 -374.784821) (xy 296.699432 -374.794018) (xy 296.699432 -375.28627)
			(xy 296.699872 -375.295454) (xy 296.706366 -375.312638) (xy 296.712132 -375.319798) (xy 296.734024 -375.345439)
			(xy 296.77211 -375.401078) (xy 296.803258 -375.460878) (xy 296.827019 -375.523978) (xy 296.843051 -375.589469)
			(xy 296.851124 -375.65641) (xy 296.851121 -375.723835) (xy 296.843043 -375.790775) (xy 296.827005 -375.856265)
			(xy 296.803239 -375.919363) (xy 296.772087 -375.979161) (xy 296.733997 -376.034796) (xy 296.712132 -376.060462)
			(xy 296.706318 -376.067595) (xy 296.699816 -376.084795) (xy 296.699432 -376.09399) (xy 296.699432 -376.25147)
			(xy 296.698948 -376.261598) (xy 296.691225 -376.280324) (xy 296.676937 -376.294683) (xy 296.65825 -376.302498)
			(xy 296.648124 -376.303032) (xy 295.931844 -376.303032) (xy 295.921697 -376.302543) (xy 295.902951 -376.294768)
			(xy 295.888628 -376.280392) (xy 295.880921 -376.261619) (xy 295.880536 -376.25147) (xy 295.880536 -376.09399)
			(xy 295.880123 -376.084803) (xy 295.87361 -376.067619) (xy 295.867836 -376.060462) (xy 295.846 -376.034773)
			(xy 295.807908 -375.979143) (xy 295.776754 -375.91935) (xy 295.752987 -375.856256) (xy 295.736948 -375.79077)
			(xy 295.728869 -375.723834) (xy 295.728867 -375.656412) (xy 295.73694 -375.589475) (xy 295.752973 -375.523987)
			(xy 295.776736 -375.460891) (xy 295.807885 -375.401096) (xy 295.845973 -375.345463) (xy 295.867836 -375.319798)
			(xy 295.873621 -375.312644) (xy 295.880142 -375.29546) (xy 295.880536 -375.28627) (xy 295.880536 -374.794018)
			(xy 295.880109 -374.784833) (xy 295.873606 -374.767649) (xy 295.867836 -374.76049) (xy 295.84593 -374.734859)
			(xy 295.80784 -374.679221) (xy 295.776689 -374.61942) (xy 295.752925 -374.556319) (xy 295.736892 -374.490825)
			(xy 295.728819 -374.423882) (xy 292.450774 -374.423882) (xy 292.442742 -374.490639) (xy 292.426773 -374.55602)
			(xy 292.403104 -374.619022) (xy 292.372075 -374.678745) (xy 292.33413 -374.73433) (xy 292.312344 -374.759982)
			(xy 292.306523 -374.76711) (xy 292.300025 -374.784314) (xy 292.299644 -374.79351) (xy 292.299644 -375.286778)
			(xy 292.300077 -375.295962) (xy 292.306576 -375.313146) (xy 292.312344 -375.320306) (xy 292.334162 -375.345934)
			(xy 292.372111 -375.401523) (xy 292.403144 -375.46125) (xy 292.426816 -375.524258) (xy 292.442787 -375.589643)
			(xy 292.450829 -375.656469) (xy 292.450826 -375.723776) (xy 292.442779 -375.790601) (xy 292.426802 -375.855985)
			(xy 292.403125 -375.918991) (xy 292.372088 -375.978716) (xy 292.334134 -376.034302) (xy 292.312344 -376.059954)
			(xy 292.306535 -376.06709) (xy 292.300029 -376.084288) (xy 292.299644 -376.093482) (xy 292.299644 -376.25147)
			(xy 292.299211 -376.261642) (xy 292.291433 -376.280439) (xy 292.277049 -376.294826) (xy 292.258254 -376.302609)
			(xy 292.248082 -376.303032) (xy 291.531802 -376.303032) (xy 291.521627 -376.302634) (xy 291.502826 -376.294844)
			(xy 291.48844 -376.28045) (xy 291.480661 -376.261645) (xy 291.48024 -376.25147) (xy 291.48024 -376.093482)
			(xy 291.47983 -376.084295) (xy 291.473315 -376.067111) (xy 291.46754 -376.059954) (xy 291.445782 -376.034277)
			(xy 291.407832 -375.978695) (xy 291.376798 -375.918974) (xy 291.353123 -375.855973) (xy 291.337148 -375.790594)
			(xy 291.329101 -375.723774) (xy 291.329099 -375.656471) (xy 291.33714 -375.589651) (xy 291.35311 -375.52427)
			(xy 291.376779 -375.461267) (xy 291.407809 -375.401544) (xy 291.445754 -375.345958) (xy 291.46754 -375.320306)
			(xy 291.473322 -375.31315) (xy 291.479844 -375.295968) (xy 291.48024 -375.286778) (xy 291.48024 -374.79351)
			(xy 291.479816 -374.784324) (xy 291.473311 -374.76714) (xy 291.46754 -374.759982) (xy 291.445711 -374.734364)
			(xy 291.407763 -374.678773) (xy 291.376732 -374.619044) (xy 291.353061 -374.556035) (xy 291.337091 -374.490649)
			(xy 291.32905 -374.423823) (xy 288.051014 -374.423823) (xy 288.051014 -374.423879) (xy 288.042941 -374.490816)
			(xy 288.026909 -374.556303) (xy 288.003147 -374.619398) (xy 287.971998 -374.679193) (xy 287.933911 -374.734826)
			(xy 287.912048 -374.76049) (xy 287.906224 -374.767616) (xy 287.899727 -374.784821) (xy 287.899348 -374.794018)
			(xy 287.899348 -375.28627) (xy 287.899784 -375.295454) (xy 287.906281 -375.312638) (xy 287.912048 -375.319798)
			(xy 287.933943 -375.345438) (xy 287.972035 -375.401075) (xy 288.003187 -375.460874) (xy 288.026952 -375.523974)
			(xy 288.042987 -375.589467) (xy 288.051061 -375.656409) (xy 288.051058 -375.723836) (xy 288.042978 -375.790777)
			(xy 288.026938 -375.856269) (xy 288.003168 -375.919367) (xy 287.972011 -375.979164) (xy 287.933916 -376.034798)
			(xy 287.912048 -376.060462) (xy 287.906236 -376.067596) (xy 287.899732 -376.084795) (xy 287.899348 -376.09399)
			(xy 287.899348 -376.25147) (xy 287.898849 -376.261596) (xy 287.891129 -376.280319) (xy 287.876846 -376.294677)
			(xy 287.858164 -376.302495) (xy 287.84804 -376.303032) (xy 287.13176 -376.303032) (xy 287.121653 -376.302548)
			(xy 287.10298 -376.294804) (xy 287.088687 -376.280507) (xy 287.080948 -376.261831) (xy 287.080452 -376.251724)
			(xy 287.080452 -376.09399) (xy 287.080035 -376.084804) (xy 287.073525 -376.06762) (xy 287.067752 -376.060462)
			(xy 287.045916 -376.034773) (xy 287.007823 -375.979143) (xy 286.976668 -375.919351) (xy 286.9529 -375.856257)
			(xy 286.93686 -375.79077) (xy 286.928781 -375.723834) (xy 286.928779 -375.656411) (xy 286.936852 -375.589474)
			(xy 286.952886 -375.523986) (xy 286.976649 -375.46089) (xy 287.007799 -375.401095) (xy 287.045888 -375.345462)
			(xy 287.067752 -375.319798) (xy 287.073538 -375.312646) (xy 287.080058 -375.29546) (xy 287.080452 -375.28627)
			(xy 287.080452 -374.794018) (xy 287.080022 -374.784833) (xy 287.073521 -374.767649) (xy 287.067752 -374.76049)
			(xy 287.045845 -374.73486) (xy 287.007754 -374.679221) (xy 286.976602 -374.619421) (xy 286.952838 -374.556319)
			(xy 286.936804 -374.490825) (xy 286.928731 -374.423882) (xy 266.501372 -374.423882) (xy 266.501372 -377.582176)
			(xy 266.500836 -377.607123) (xy 266.49303 -377.656404) (xy 266.477622 -377.70386) (xy 266.454989 -377.748327)
			(xy 266.425688 -377.788712) (xy 266.408408 -377.806712) (xy 265.993118 -378.222002) (xy 265.975119 -378.239288)
			(xy 265.934744 -378.268613) (xy 265.890279 -378.291261) (xy 265.842819 -378.306676) (xy 265.793532 -378.314478)
			(xy 265.768582 -378.314966) (xy 243.004086 -378.314966) (xy 242.979138 -378.314456) (xy 242.929856 -378.306644)
			(xy 242.882399 -378.291229) (xy 242.837933 -378.268591) (xy 242.797549 -378.239285) (xy 242.77955 -378.222002)
			(xy 242.203732 -377.646184) (xy 242.186435 -377.628195) (xy 242.157111 -377.587818) (xy 242.134464 -377.543351)
			(xy 242.119051 -377.495888) (xy 242.111253 -377.446599) (xy 242.110768 -377.421648) (xy 242.110768 -377.180602)
			(xy 242.11035 -377.170532) (xy 242.102625 -377.151933) (xy 242.095782 -377.144534) (xy 242.00104 -377.049792)
			(xy 241.993621 -377.042976) (xy 241.975036 -377.035243) (xy 241.964972 -377.034806) (xy 236.209586 -377.034806)
			(xy 236.184637 -377.034313) (xy 236.135353 -377.026499) (xy 236.087896 -377.011082) (xy 236.04343 -376.988439)
			(xy 236.003048 -376.959128) (xy 235.98505 -376.941842) (xy 235.566712 -376.523504) (xy 235.549421 -376.505509)
			(xy 235.520097 -376.465133) (xy 235.497449 -376.420668) (xy 235.482035 -376.373206) (xy 235.474235 -376.323919)
			(xy 235.473748 -376.298968) (xy 234.427522 -376.298968) (xy 237.245652 -379.117098) (xy 237.253075 -379.123909)
			(xy 237.271657 -379.131646) (xy 237.28172 -379.132084) (xy 239.621314 -379.132084) (xy 239.631385 -379.13167)
			(xy 239.649982 -379.123942) (xy 239.657382 -379.117098) (xy 240.207292 -378.567188) (xy 240.225285 -378.549895)
			(xy 240.265662 -378.520572) (xy 240.310128 -378.497925) (xy 240.357589 -378.482511) (xy 240.406877 -378.474711)
			(xy 240.431828 -378.474224) (xy 262.084058 -378.474224) (xy 262.109007 -378.474709) (xy 262.15829 -378.482528)
			(xy 262.205747 -378.497948) (xy 262.250212 -378.520592) (xy 262.290595 -378.549903) (xy 262.308594 -378.567188)
			(xy 262.508217 -378.766811) (xy 269.68983 -378.766811) (xy 269.68983 -378.633249) (xy 269.697894 -378.499931)
			(xy 269.713994 -378.367343) (xy 269.738069 -378.235969) (xy 269.770032 -378.106288) (xy 269.809767 -377.978774)
			(xy 269.857129 -377.853891) (xy 269.911944 -377.732096) (xy 269.974014 -377.613833) (xy 270.04311 -377.499534)
			(xy 270.118982 -377.389614) (xy 270.201352 -377.284477) (xy 270.28992 -377.184504) (xy 270.384362 -377.090062)
			(xy 270.484335 -377.001494) (xy 270.589472 -376.919124) (xy 270.699392 -376.843252) (xy 270.813691 -376.774156)
			(xy 270.931954 -376.712086) (xy 271.053749 -376.657271) (xy 271.178632 -376.609909) (xy 271.306146 -376.570174)
			(xy 271.435827 -376.538211) (xy 271.567201 -376.514136) (xy 271.699789 -376.498036) (xy 271.833107 -376.489972)
			(xy 271.966669 -376.489972) (xy 272.099987 -376.498036) (xy 272.232575 -376.514136) (xy 272.363949 -376.538211)
			(xy 272.49363 -376.570174) (xy 272.621144 -376.609909) (xy 272.746027 -376.657271) (xy 272.867822 -376.712086)
			(xy 272.986085 -376.774156) (xy 273.068299 -376.823856) (xy 289.128922 -376.823856) (xy 289.128922 -376.75655)
			(xy 289.136967 -376.689727) (xy 289.152941 -376.624344) (xy 289.176615 -376.56134) (xy 289.207651 -376.501617)
			(xy 289.245603 -376.446031) (xy 289.267392 -376.42038) (xy 289.273179 -376.413228) (xy 289.2797 -376.396043)
			(xy 289.280092 -376.386852) (xy 289.280092 -375.893584) (xy 289.279691 -375.884396) (xy 289.273171 -375.867212)
			(xy 289.267392 -375.860056) (xy 289.245634 -375.834379) (xy 289.207681 -375.778797) (xy 289.176643 -375.719078)
			(xy 289.152966 -375.656076) (xy 289.13699 -375.590696) (xy 289.128942 -375.523876) (xy 289.128939 -375.456572)
			(xy 289.136981 -375.389751) (xy 289.152952 -375.32437) (xy 289.176624 -375.261367) (xy 289.207656 -375.201644)
			(xy 289.245605 -375.146059) (xy 289.267392 -375.120408) (xy 289.273167 -375.113247) (xy 289.279695 -375.096069)
			(xy 289.280092 -375.08688) (xy 289.280092 -374.928638) (xy 289.280664 -374.918488) (xy 289.288417 -374.899729)
			(xy 289.302758 -374.885364) (xy 289.321505 -374.87758) (xy 289.331654 -374.877076) (xy 290.047934 -374.877076)
			(xy 290.058113 -374.877437) (xy 290.076915 -374.88524) (xy 290.0913 -374.899645) (xy 290.099077 -374.918459)
			(xy 290.099496 -374.928638) (xy 290.099496 -375.08688) (xy 290.099917 -375.096066) (xy 290.106423 -375.11325)
			(xy 290.112196 -375.120408) (xy 290.134014 -375.146035) (xy 290.17196 -375.201626) (xy 290.20299 -375.261353)
			(xy 290.226659 -375.324361) (xy 290.242629 -375.389746) (xy 290.25067 -375.456571) (xy 290.250667 -375.523878)
			(xy 290.24262 -375.590702) (xy 290.226645 -375.656085) (xy 290.20297 -375.719091) (xy 290.171935 -375.778816)
			(xy 290.133985 -375.834403) (xy 290.112196 -375.860056) (xy 290.106393 -375.867196) (xy 290.099882 -375.884391)
			(xy 290.099496 -375.893584) (xy 290.099496 -376.386852) (xy 290.09993 -376.396037) (xy 290.106427 -376.413221)
			(xy 290.112196 -376.42038) (xy 290.133987 -376.446029) (xy 290.171933 -376.501617) (xy 290.202964 -376.561341)
			(xy 290.226635 -376.624346) (xy 290.242607 -376.689728) (xy 290.25065 -376.756551) (xy 290.25065 -376.823855)
			(xy 290.250643 -376.823915) (xy 293.528715 -376.823915) (xy 293.528715 -376.756491) (xy 293.53679 -376.689554)
			(xy 293.552824 -376.624065) (xy 293.576588 -376.560968) (xy 293.607737 -376.501172) (xy 293.645825 -376.445537)
			(xy 293.667688 -376.419872) (xy 293.673478 -376.412722) (xy 293.679997 -376.395535) (xy 293.680388 -376.386344)
			(xy 293.680388 -375.894092) (xy 293.679984 -375.884904) (xy 293.673466 -375.86772) (xy 293.667688 -375.860564)
			(xy 293.645856 -375.834873) (xy 293.607767 -375.779242) (xy 293.576616 -375.719449) (xy 293.55285 -375.656355)
			(xy 293.536813 -375.59087) (xy 293.528735 -375.523934) (xy 293.528732 -375.456514) (xy 293.536804 -375.389578)
			(xy 293.552836 -375.324091) (xy 293.576596 -375.260995) (xy 293.607742 -375.2012) (xy 293.645826 -375.145565)
			(xy 293.667688 -375.1199) (xy 293.673466 -375.112741) (xy 293.679992 -375.095561) (xy 293.680388 -375.086372)
			(xy 293.680388 -374.928638) (xy 293.680956 -374.91852) (xy 293.688662 -374.89981) (xy 293.702923 -374.885454)
			(xy 293.721582 -374.877624) (xy 293.731696 -374.877076) (xy 294.447976 -374.877076) (xy 294.458094 -374.877535)
			(xy 294.476793 -374.885271) (xy 294.491107 -374.899574) (xy 294.498857 -374.918266) (xy 294.499284 -374.928384)
			(xy 294.499284 -375.086372) (xy 294.499711 -375.095557) (xy 294.506214 -375.112742) (xy 294.511984 -375.1199)
			(xy 294.53388 -375.145539) (xy 294.571969 -375.201177) (xy 294.603119 -375.260977) (xy 294.626882 -375.324077)
			(xy 294.642916 -375.389569) (xy 294.650989 -375.456511) (xy 294.650986 -375.523937) (xy 294.642907 -375.590878)
			(xy 294.626868 -375.656369) (xy 294.603099 -375.719467) (xy 294.571944 -375.779264) (xy 294.53385 -375.834899)
			(xy 294.511984 -375.860564) (xy 294.506176 -375.867701) (xy 294.499669 -375.884898) (xy 294.499284 -375.894092)
			(xy 294.499284 -376.386344) (xy 294.499677 -376.395533) (xy 294.506203 -376.412717) (xy 294.511984 -376.419872)
			(xy 294.533852 -376.445534) (xy 294.571942 -376.501168) (xy 294.603094 -376.560965) (xy 294.626858 -376.624062)
			(xy 294.642894 -376.689552) (xy 294.65097 -376.756491) (xy 294.650969 -376.823856) (xy 297.92901 -376.823856)
			(xy 297.92901 -376.75655) (xy 297.937054 -376.689727) (xy 297.953028 -376.624345) (xy 297.976702 -376.56134)
			(xy 298.007737 -376.501617) (xy 298.045687 -376.446032) (xy 298.067476 -376.42038) (xy 298.073261 -376.413226)
			(xy 298.079783 -376.396042) (xy 298.080176 -376.386852) (xy 298.080176 -375.893584) (xy 298.079779 -375.884395)
			(xy 298.073257 -375.867211) (xy 298.067476 -375.860056) (xy 298.045719 -375.834378) (xy 298.007766 -375.778797)
			(xy 297.97673 -375.719077) (xy 297.953054 -375.656076) (xy 297.937077 -375.590696) (xy 297.92903 -375.523876)
			(xy 297.929027 -375.456572) (xy 297.937069 -375.389751) (xy 297.953039 -375.324371) (xy 297.97671 -375.261367)
			(xy 298.007742 -375.201645) (xy 298.045689 -375.14606) (xy 298.067476 -375.120408) (xy 298.073249 -375.113246)
			(xy 298.079778 -375.096068) (xy 298.080176 -375.08688) (xy 298.080176 -374.928638) (xy 298.080596 -374.918464)
			(xy 298.088376 -374.899663) (xy 298.102763 -374.885276) (xy 298.121564 -374.877496) (xy 298.131738 -374.877076)
			(xy 298.848018 -374.877076) (xy 298.858195 -374.87745) (xy 298.876998 -374.885248) (xy 298.891383 -374.899649)
			(xy 298.899161 -374.91846) (xy 298.89958 -374.928638) (xy 298.89958 -375.08688) (xy 298.900004 -375.096066)
			(xy 298.906509 -375.11325) (xy 298.91228 -375.120408) (xy 298.934099 -375.146035) (xy 298.972045 -375.201625)
			(xy 299.003076 -375.261352) (xy 299.026746 -375.32436) (xy 299.042716 -375.389745) (xy 299.050758 -375.45657)
			(xy 299.050755 -375.523878) (xy 299.042708 -375.590702) (xy 299.026732 -375.656086) (xy 299.003056 -375.719092)
			(xy 298.972021 -375.778816) (xy 298.934069 -375.834404) (xy 298.91228 -375.860056) (xy 298.906475 -375.867195)
			(xy 298.899966 -375.88439) (xy 298.89958 -375.893584) (xy 298.89958 -376.386852) (xy 298.900018 -376.396036)
			(xy 298.906513 -376.413221) (xy 298.91228 -376.42038) (xy 298.934071 -376.446029) (xy 298.972019 -376.501616)
			(xy 299.003051 -376.561341) (xy 299.026722 -376.624345) (xy 299.042695 -376.689728) (xy 299.050731 -376.756492)
			(xy 302.328802 -376.756492) (xy 302.336877 -376.689554) (xy 302.352912 -376.624066) (xy 302.376674 -376.560969)
			(xy 302.407823 -376.501173) (xy 302.445909 -376.445538) (xy 302.467772 -376.419872) (xy 302.473572 -376.412729)
			(xy 302.480082 -376.395537) (xy 302.480472 -376.386344) (xy 302.480472 -375.894092) (xy 302.480072 -375.884904)
			(xy 302.473552 -375.867719) (xy 302.467772 -375.860564) (xy 302.44594 -375.834872) (xy 302.407853 -375.779241)
			(xy 302.376702 -375.719448) (xy 302.352937 -375.656355) (xy 302.336901 -375.590869) (xy 302.328823 -375.523934)
			(xy 302.32882 -375.456514) (xy 302.336892 -375.389578) (xy 302.352923 -375.324091) (xy 302.376682 -375.260996)
			(xy 302.407828 -375.2012) (xy 302.445911 -375.145566) (xy 302.467772 -375.1199) (xy 302.47356 -375.112749)
			(xy 302.480078 -375.095563) (xy 302.480472 -375.086372) (xy 302.480472 -374.928638) (xy 302.480959 -374.91851)
			(xy 302.48868 -374.899784) (xy 302.502967 -374.885425) (xy 302.521654 -374.87761) (xy 302.53178 -374.877076)
			(xy 303.24806 -374.877076) (xy 303.258209 -374.877554) (xy 303.276955 -374.885332) (xy 303.291279 -374.899711)
			(xy 303.298985 -374.918488) (xy 303.299368 -374.928638) (xy 303.299368 -375.086372) (xy 303.299799 -375.095557)
			(xy 303.306299 -375.112741) (xy 303.312068 -375.1199) (xy 303.333965 -375.145539) (xy 303.372054 -375.201176)
			(xy 303.403205 -375.260976) (xy 303.426969 -375.324076) (xy 303.443004 -375.389569) (xy 303.451077 -375.456511)
			(xy 303.451074 -375.523937) (xy 303.442995 -375.590878) (xy 303.426955 -375.65637) (xy 303.403186 -375.719468)
			(xy 303.37203 -375.779265) (xy 303.333935 -375.834899) (xy 303.312068 -375.860564) (xy 303.306258 -375.867699)
			(xy 303.299752 -375.884898) (xy 303.299368 -375.894092) (xy 303.299368 -376.386344) (xy 303.299764 -376.395533)
			(xy 303.306288 -376.412716) (xy 303.312068 -376.419872) (xy 303.333937 -376.445533) (xy 303.372028 -376.501168)
			(xy 303.40318 -376.560964) (xy 303.426945 -376.624062) (xy 303.442982 -376.689551) (xy 303.451058 -376.756491)
			(xy 303.451057 -376.823915) (xy 333.128833 -376.823915) (xy 333.128833 -376.756491) (xy 333.136908 -376.689553)
			(xy 333.152944 -376.624064) (xy 333.176708 -376.560967) (xy 333.207859 -376.501171) (xy 333.245948 -376.445537)
			(xy 333.267812 -376.419872) (xy 333.273604 -376.412724) (xy 333.280121 -376.395536) (xy 333.280512 -376.386344)
			(xy 333.280512 -375.894092) (xy 333.280103 -375.884905) (xy 333.273588 -375.86772) (xy 333.267812 -375.860564)
			(xy 333.245979 -375.834873) (xy 333.207889 -375.779242) (xy 333.176736 -375.71945) (xy 333.152969 -375.656356)
			(xy 333.136931 -375.59087) (xy 333.128853 -375.523935) (xy 333.12885 -375.456513) (xy 333.136923 -375.389577)
			(xy 333.152955 -375.32409) (xy 333.176716 -375.260994) (xy 333.207864 -375.201199) (xy 333.24595 -375.145565)
			(xy 333.267812 -375.1199) (xy 333.273592 -375.112743) (xy 333.280116 -375.095562) (xy 333.280512 -375.086372)
			(xy 333.280512 -374.928638) (xy 333.281057 -374.918517) (xy 333.288767 -374.899802) (xy 333.303035 -374.885446)
			(xy 333.321702 -374.87762) (xy 333.33182 -374.877076) (xy 334.0481 -374.877076) (xy 334.058251 -374.877521)
			(xy 334.076999 -374.885312) (xy 334.091321 -374.899701) (xy 334.099025 -374.918485) (xy 334.099408 -374.928638)
			(xy 334.099408 -375.086372) (xy 334.09983 -375.095558) (xy 334.106335 -375.112743) (xy 334.112108 -375.1199)
			(xy 334.134003 -375.145539) (xy 334.17209 -375.201178) (xy 334.203239 -375.260978) (xy 334.227001 -375.324078)
			(xy 334.243034 -375.38957) (xy 334.251107 -375.456511) (xy 334.251105 -375.523937) (xy 334.243026 -375.590877)
			(xy 334.226987 -375.656368) (xy 334.20322 -375.719466) (xy 334.172066 -375.779263) (xy 334.133974 -375.834899)
			(xy 334.112108 -375.860564) (xy 334.106303 -375.867703) (xy 334.099793 -375.884898) (xy 334.099408 -375.894092)
			(xy 334.099408 -376.386344) (xy 334.099795 -376.395534) (xy 334.106324 -376.412718) (xy 334.112108 -376.419872)
			(xy 334.133976 -376.445534) (xy 334.172064 -376.501169) (xy 334.203214 -376.560966) (xy 334.226977 -376.624063)
			(xy 334.243012 -376.689553) (xy 334.251088 -376.756491) (xy 334.251087 -376.823855) (xy 337.529152 -376.823855)
			(xy 337.529152 -376.756551) (xy 337.537195 -376.689729) (xy 337.553167 -376.624348) (xy 337.576837 -376.561344)
			(xy 337.607868 -376.50162) (xy 337.645814 -376.446033) (xy 337.6676 -376.42038) (xy 337.673388 -376.413228)
			(xy 337.679908 -376.396043) (xy 337.6803 -376.386852) (xy 337.6803 -375.893584) (xy 337.679897 -375.884396)
			(xy 337.673378 -375.867212) (xy 337.6676 -375.860056) (xy 337.645845 -375.834377) (xy 337.607898 -375.778794)
			(xy 337.576865 -375.719074) (xy 337.553192 -375.656073) (xy 337.537218 -375.590694) (xy 337.529172 -375.523875)
			(xy 337.529169 -375.456573) (xy 337.53721 -375.389753) (xy 337.553178 -375.324373) (xy 337.576846 -375.26137)
			(xy 337.607873 -375.201647) (xy 337.645815 -375.146061) (xy 337.6676 -375.120408) (xy 337.673376 -375.113248)
			(xy 337.679903 -375.096069) (xy 337.6803 -375.08688) (xy 337.6803 -374.928638) (xy 337.680864 -374.918487)
			(xy 337.688619 -374.899726) (xy 337.702963 -374.885361) (xy 337.721712 -374.877579) (xy 337.731862 -374.877076)
			(xy 338.448142 -374.877076) (xy 338.458307 -374.8775) (xy 338.477085 -374.885295) (xy 338.49145 -374.899683)
			(xy 338.499216 -374.918472) (xy 338.499704 -374.928638) (xy 338.499704 -375.08688) (xy 338.500123 -375.096066)
			(xy 338.50663 -375.113251) (xy 338.512404 -375.120408) (xy 338.534222 -375.146035) (xy 338.572167 -375.201626)
			(xy 338.603196 -375.261353) (xy 338.626865 -375.324361) (xy 338.642835 -375.389746) (xy 338.650876 -375.456571)
			(xy 338.650873 -375.523877) (xy 338.642826 -375.590701) (xy 338.626851 -375.656085) (xy 338.603177 -375.719091)
			(xy 338.572142 -375.778815) (xy 338.534192 -375.834403) (xy 338.512404 -375.860056) (xy 338.506602 -375.867197)
			(xy 338.50009 -375.884391) (xy 338.499704 -375.893584) (xy 338.499704 -376.386852) (xy 338.500136 -376.396037)
			(xy 338.506634 -376.413222) (xy 338.512404 -376.42038) (xy 338.534194 -376.44603) (xy 338.57214 -376.501617)
			(xy 338.603171 -376.561342) (xy 338.626842 -376.624346) (xy 338.642813 -376.689729) (xy 338.650856 -376.756551)
			(xy 338.650856 -376.823855) (xy 338.650849 -376.823915) (xy 341.928921 -376.823915) (xy 341.928921 -376.756491)
			(xy 341.936996 -376.689553) (xy 341.953031 -376.624065) (xy 341.976794 -376.560968) (xy 342.007944 -376.501172)
			(xy 342.046032 -376.445537) (xy 342.067896 -376.419872) (xy 342.073686 -376.412722) (xy 342.080205 -376.395535)
			(xy 342.080596 -376.386344) (xy 342.080596 -375.894092) (xy 342.08019 -375.884904) (xy 342.073674 -375.86772)
			(xy 342.067896 -375.860564) (xy 342.046064 -375.834873) (xy 342.007974 -375.779242) (xy 341.976822 -375.719449)
			(xy 341.953057 -375.656356) (xy 341.937019 -375.59087) (xy 341.928941 -375.523935) (xy 341.928938 -375.456513)
			(xy 341.93701 -375.389577) (xy 341.953042 -375.32409) (xy 341.976803 -375.260995) (xy 342.007949 -375.201199)
			(xy 342.046034 -375.145565) (xy 342.067896 -375.1199) (xy 342.073675 -375.112742) (xy 342.0802 -375.095561)
			(xy 342.080596 -375.086372) (xy 342.080596 -374.928638) (xy 342.081157 -374.918519) (xy 342.088864 -374.899807)
			(xy 342.103127 -374.885451) (xy 342.121789 -374.877623) (xy 342.131904 -374.877076) (xy 342.848184 -374.877076)
			(xy 342.858334 -374.877534) (xy 342.877082 -374.88532) (xy 342.891405 -374.899705) (xy 342.899109 -374.918486)
			(xy 342.899492 -374.928638) (xy 342.899492 -375.086372) (xy 342.899917 -375.095558) (xy 342.906421 -375.112742)
			(xy 342.912192 -375.1199) (xy 342.934088 -375.145539) (xy 342.972176 -375.201177) (xy 343.003326 -375.260977)
			(xy 343.027088 -375.324077) (xy 343.043122 -375.38957) (xy 343.051195 -375.456511) (xy 343.051193 -375.523937)
			(xy 343.043113 -375.590878) (xy 343.027074 -375.656369) (xy 343.003306 -375.719467) (xy 342.972151 -375.779264)
			(xy 342.934058 -375.834899) (xy 342.912192 -375.860564) (xy 342.906385 -375.867702) (xy 342.899877 -375.884898)
			(xy 342.899492 -375.894092) (xy 342.899492 -376.386344) (xy 342.899883 -376.395533) (xy 342.90641 -376.412717)
			(xy 342.912192 -376.419872) (xy 342.93406 -376.445534) (xy 342.972149 -376.501169) (xy 343.0033 -376.560965)
			(xy 343.027065 -376.624063) (xy 343.0431 -376.689552) (xy 343.051176 -376.756491) (xy 343.051175 -376.823856)
			(xy 346.329216 -376.823856) (xy 346.329216 -376.75655) (xy 346.33726 -376.689727) (xy 346.353234 -376.624345)
			(xy 346.376909 -376.56134) (xy 346.407944 -376.501617) (xy 346.445895 -376.446032) (xy 346.467684 -376.42038)
			(xy 346.47347 -376.413227) (xy 346.479991 -376.396043) (xy 346.480384 -376.386852) (xy 346.480384 -375.893584)
			(xy 346.479985 -375.884396) (xy 346.473464 -375.867211) (xy 346.467684 -375.860056) (xy 346.445926 -375.834379)
			(xy 346.407974 -375.778797) (xy 346.376937 -375.719077) (xy 346.35326 -375.656076) (xy 346.337283 -375.590696)
			(xy 346.329236 -375.523876) (xy 346.329233 -375.456572) (xy 346.337275 -375.389751) (xy 346.353246 -375.32437)
			(xy 346.376917 -375.261367) (xy 346.407949 -375.201645) (xy 346.445897 -375.14606) (xy 346.467684 -375.120408)
			(xy 346.473458 -375.113247) (xy 346.479987 -375.096069) (xy 346.480384 -375.08688) (xy 346.480384 -374.928638)
			(xy 346.480796 -374.918463) (xy 346.488577 -374.899661) (xy 346.502967 -374.885273) (xy 346.521771 -374.877495)
			(xy 346.531946 -374.877076) (xy 347.248226 -374.877076) (xy 347.258404 -374.877443) (xy 347.277207 -374.885244)
			(xy 347.291592 -374.899647) (xy 347.299369 -374.918459) (xy 347.299788 -374.928638) (xy 347.299788 -375.08688)
			(xy 347.300211 -375.096066) (xy 347.306716 -375.11325) (xy 347.312488 -375.120408) (xy 347.334306 -375.146035)
			(xy 347.372252 -375.201625) (xy 347.403283 -375.261353) (xy 347.426953 -375.324361) (xy 347.442923 -375.389746)
			(xy 347.450964 -375.456571) (xy 347.450961 -375.523878) (xy 347.442914 -375.590702) (xy 347.426938 -375.656086)
			(xy 347.403263 -375.719091) (xy 347.372228 -375.778816) (xy 347.334277 -375.834403) (xy 347.312488 -375.860056)
			(xy 347.306684 -375.867196) (xy 347.300174 -375.88439) (xy 347.299788 -375.893584) (xy 347.299788 -376.386852)
			(xy 347.300224 -376.396036) (xy 347.30672 -376.413221) (xy 347.312488 -376.42038) (xy 347.334279 -376.446029)
			(xy 347.372226 -376.501617) (xy 347.403257 -376.561341) (xy 347.426929 -376.624346) (xy 347.442901 -376.689728)
			(xy 347.450944 -376.756551) (xy 347.450944 -376.823855) (xy 347.450937 -376.823915) (xy 377.128742 -376.823915)
			(xy 377.128742 -376.756491) (xy 377.136817 -376.689553) (xy 377.152853 -376.624064) (xy 377.176618 -376.560967)
			(xy 377.20777 -376.501171) (xy 377.245859 -376.445537) (xy 377.267724 -376.419872) (xy 377.273518 -376.412725)
			(xy 377.280033 -376.395536) (xy 377.280424 -376.386344) (xy 377.280424 -375.894092) (xy 377.280012 -375.884905)
			(xy 377.273499 -375.867721) (xy 377.267724 -375.860564) (xy 377.245891 -375.834873) (xy 377.207799 -375.779243)
			(xy 377.176646 -375.71945) (xy 377.152879 -375.656357) (xy 377.136841 -375.590871) (xy 377.128762 -375.523935)
			(xy 377.128759 -375.456513) (xy 377.136832 -375.389577) (xy 377.152865 -375.324089) (xy 377.176626 -375.260993)
			(xy 377.207775 -375.201198) (xy 377.245861 -375.145565) (xy 377.267724 -375.1199) (xy 377.273506 -375.112744)
			(xy 377.280029 -375.095562) (xy 377.280424 -375.086372) (xy 377.280424 -374.928638) (xy 377.280957 -374.918516)
			(xy 377.28867 -374.899799) (xy 377.302942 -374.885442) (xy 377.321613 -374.877618) (xy 377.331732 -374.877076)
			(xy 378.048012 -374.877076) (xy 378.058164 -374.877511) (xy 378.076912 -374.885306) (xy 378.091234 -374.899698)
			(xy 378.098938 -374.918484) (xy 378.09932 -374.928638) (xy 378.09932 -375.086372) (xy 378.099739 -375.095558)
			(xy 378.106246 -375.112743) (xy 378.11202 -375.1199) (xy 378.133915 -375.14554) (xy 378.172001 -375.201178)
			(xy 378.203149 -375.260978) (xy 378.226911 -375.324078) (xy 378.242943 -375.38957) (xy 378.251016 -375.456511)
			(xy 378.251014 -375.523937) (xy 378.242935 -375.590877) (xy 378.226897 -375.656368) (xy 378.20313 -375.719466)
			(xy 378.171976 -375.779263) (xy 378.133885 -375.834898) (xy 378.11202 -375.860564) (xy 378.106216 -375.867704)
			(xy 378.099705 -375.884898) (xy 378.09932 -375.894092) (xy 378.09932 -376.386344) (xy 378.099704 -376.395534)
			(xy 378.106235 -376.412718) (xy 378.11202 -376.419872) (xy 378.133887 -376.445534) (xy 378.171974 -376.50117)
			(xy 378.203124 -376.560967) (xy 378.226887 -376.624064) (xy 378.242922 -376.689553) (xy 378.250997 -376.756491)
			(xy 378.250997 -376.756551) (xy 381.529061 -376.756551) (xy 381.537105 -376.689729) (xy 381.553076 -376.624347)
			(xy 381.576747 -376.561343) (xy 381.607779 -376.501619) (xy 381.645725 -376.446032) (xy 381.667512 -376.42038)
			(xy 381.673301 -376.413229) (xy 381.67982 -376.396043) (xy 381.680212 -376.386852) (xy 381.680212 -375.893584)
			(xy 381.679807 -375.884396) (xy 381.67329 -375.867212) (xy 381.667512 -375.860056) (xy 381.645756 -375.834378)
			(xy 381.607808 -375.778794) (xy 381.576775 -375.719074) (xy 381.553102 -375.656073) (xy 381.537127 -375.590694)
			(xy 381.529081 -375.523875) (xy 381.529078 -375.456573) (xy 381.537119 -375.389753) (xy 381.553088 -375.324373)
			(xy 381.576756 -375.26137) (xy 381.607784 -375.201647) (xy 381.645727 -375.14606) (xy 381.667512 -375.120408)
			(xy 381.673289 -375.113249) (xy 381.679815 -375.096069) (xy 381.680212 -375.08688) (xy 381.680212 -374.928638)
			(xy 381.680694 -374.918472) (xy 381.688462 -374.899683) (xy 381.702829 -374.885298) (xy 381.721609 -374.877507)
			(xy 381.731774 -374.877076) (xy 382.448054 -374.877076) (xy 382.458227 -374.877502) (xy 382.477028 -374.885279)
			(xy 382.491416 -374.899665) (xy 382.499196 -374.918465) (xy 382.499616 -374.928638) (xy 382.499616 -375.08688)
			(xy 382.500032 -375.096067) (xy 382.506541 -375.113251) (xy 382.512316 -375.120408) (xy 382.534136 -375.146034)
			(xy 382.572087 -375.201623) (xy 382.603122 -375.26135) (xy 382.626795 -375.324358) (xy 382.642767 -375.389744)
			(xy 382.650809 -375.45657) (xy 382.650806 -375.523878) (xy 382.642758 -375.590704) (xy 382.62678 -375.656088)
			(xy 382.603102 -375.719094) (xy 382.572063 -375.778818) (xy 382.534107 -375.834404) (xy 382.512316 -375.860056)
			(xy 382.506515 -375.867198) (xy 382.500002 -375.884391) (xy 382.499616 -375.893584) (xy 382.499616 -376.386852)
			(xy 382.500045 -376.396037) (xy 382.506545 -376.413222) (xy 382.512316 -376.42038) (xy 382.534109 -376.446028)
			(xy 382.572061 -376.501614) (xy 382.603096 -376.561338) (xy 382.626771 -376.624343) (xy 382.642745 -376.689726)
			(xy 382.650789 -376.75655) (xy 382.650789 -376.823856) (xy 382.650782 -376.823915) (xy 385.92883 -376.823915)
			(xy 385.92883 -376.756491) (xy 385.936905 -376.689553) (xy 385.95294 -376.624064) (xy 385.976705 -376.560967)
			(xy 386.007855 -376.501171) (xy 386.045944 -376.445537) (xy 386.067808 -376.419872) (xy 386.0736 -376.412724)
			(xy 386.080117 -376.395535) (xy 386.080508 -376.386344) (xy 386.080508 -375.894092) (xy 386.0801 -375.884905)
			(xy 386.073584 -375.867721) (xy 386.067808 -375.860564) (xy 386.045975 -375.834873) (xy 386.007885 -375.779242)
			(xy 385.976732 -375.71945) (xy 385.952966 -375.656356) (xy 385.936928 -375.59087) (xy 385.92885 -375.523935)
			(xy 385.928847 -375.456513) (xy 385.93692 -375.389577) (xy 385.952952 -375.32409) (xy 385.976713 -375.260994)
			(xy 386.00786 -375.201199) (xy 386.045946 -375.145565) (xy 386.067808 -375.1199) (xy 386.073588 -375.112743)
			(xy 386.080112 -375.095562) (xy 386.080508 -375.086372) (xy 386.080508 -374.928638) (xy 386.081057 -374.918518)
			(xy 386.088766 -374.899804) (xy 386.103033 -374.885447) (xy 386.121699 -374.877621) (xy 386.131816 -374.877076)
			(xy 386.848096 -374.877076) (xy 386.858247 -374.877524) (xy 386.876995 -374.885314) (xy 386.891317 -374.899702)
			(xy 386.899021 -374.918485) (xy 386.899404 -374.928638) (xy 386.899404 -375.086372) (xy 386.899827 -375.095558)
			(xy 386.906332 -375.112742) (xy 386.912104 -375.1199) (xy 386.933999 -375.145539) (xy 386.972087 -375.201178)
			(xy 387.003236 -375.260978) (xy 387.026998 -375.324078) (xy 387.043031 -375.38957) (xy 387.051104 -375.456511)
			(xy 387.051102 -375.523937) (xy 387.043023 -375.590877) (xy 387.026984 -375.656368) (xy 387.003216 -375.719466)
			(xy 386.972062 -375.779264) (xy 386.93397 -375.834899) (xy 386.912104 -375.860564) (xy 386.906298 -375.867703)
			(xy 386.899789 -375.884898) (xy 386.899404 -375.894092) (xy 386.899404 -376.386344) (xy 386.899792 -376.395534)
			(xy 386.906321 -376.412718) (xy 386.912104 -376.419872) (xy 386.933972 -376.445534) (xy 386.97206 -376.501169)
			(xy 387.00321 -376.560966) (xy 387.026974 -376.624063) (xy 387.043009 -376.689552) (xy 387.051085 -376.756491)
			(xy 387.051084 -376.823855) (xy 390.329149 -376.823855) (xy 390.329149 -376.756551) (xy 390.337192 -376.689729)
			(xy 390.353163 -376.624348) (xy 390.376834 -376.561344) (xy 390.407864 -376.50162) (xy 390.44581 -376.446033)
			(xy 390.467596 -376.42038) (xy 390.473383 -376.413228) (xy 390.479904 -376.396043) (xy 390.480296 -376.386852)
			(xy 390.480296 -375.893584) (xy 390.479894 -375.884396) (xy 390.473375 -375.867212) (xy 390.467596 -375.860056)
			(xy 390.445841 -375.834377) (xy 390.407894 -375.778794) (xy 390.376862 -375.719073) (xy 390.353189 -375.656072)
			(xy 390.337215 -375.590694) (xy 390.329169 -375.523875) (xy 390.329166 -375.456573) (xy 390.337207 -375.389754)
			(xy 390.353175 -375.324374) (xy 390.376842 -375.261371) (xy 390.407869 -375.201648) (xy 390.445812 -375.146061)
			(xy 390.467596 -375.120408) (xy 390.473371 -375.113248) (xy 390.479899 -375.096069) (xy 390.480296 -375.08688)
			(xy 390.480296 -374.928638) (xy 390.480864 -374.918488) (xy 390.488618 -374.899728) (xy 390.502961 -374.885363)
			(xy 390.521709 -374.877579) (xy 390.531858 -374.877076) (xy 391.248138 -374.877076) (xy 391.258303 -374.877503)
			(xy 391.27708 -374.885297) (xy 391.291445 -374.899684) (xy 391.299212 -374.918472) (xy 391.2997 -374.928638)
			(xy 391.2997 -375.08688) (xy 391.30012 -375.096066) (xy 391.306627 -375.113251) (xy 391.3124 -375.120408)
			(xy 391.334218 -375.146035) (xy 391.372163 -375.201626) (xy 391.403193 -375.261353) (xy 391.426862 -375.324361)
			(xy 391.442832 -375.389746) (xy 391.450873 -375.456571) (xy 391.45087 -375.523877) (xy 391.442823 -375.590702)
			(xy 391.426848 -375.656085) (xy 391.403173 -375.719091) (xy 391.372139 -375.778816) (xy 391.334188 -375.834403)
			(xy 391.3124 -375.860056) (xy 391.306597 -375.867197) (xy 391.300086 -375.884391) (xy 391.2997 -375.893584)
			(xy 391.2997 -376.386852) (xy 391.300133 -376.396037) (xy 391.306631 -376.413221) (xy 391.3124 -376.42038)
			(xy 391.33419 -376.446029) (xy 391.372137 -376.501617) (xy 391.403168 -376.561342) (xy 391.426838 -376.624346)
			(xy 391.44281 -376.689728) (xy 391.450853 -376.756551) (xy 391.450853 -376.823855) (xy 391.450846 -376.823915)
			(xy 421.128651 -376.823915) (xy 421.128651 -376.756491) (xy 421.136727 -376.689552) (xy 421.152763 -376.624063)
			(xy 421.176528 -376.560966) (xy 421.20768 -376.50117) (xy 421.245771 -376.445537) (xy 421.267636 -376.419872)
			(xy 421.273432 -376.412726) (xy 421.279946 -376.395536) (xy 421.280336 -376.386344) (xy 421.280336 -375.894092)
			(xy 421.279922 -375.884905) (xy 421.27341 -375.867721) (xy 421.267636 -375.860564) (xy 421.245802 -375.834873)
			(xy 421.20771 -375.779243) (xy 421.176556 -375.719451) (xy 421.152788 -375.656357) (xy 421.13675 -375.590871)
			(xy 421.128671 -375.523935) (xy 421.128668 -375.456513) (xy 421.136741 -375.389576) (xy 421.152774 -375.324089)
			(xy 421.176536 -375.260993) (xy 421.207685 -375.201198) (xy 421.245773 -375.145565) (xy 421.267636 -375.1199)
			(xy 421.27342 -375.112746) (xy 421.279941 -375.095562) (xy 421.280336 -375.086372) (xy 421.280336 -374.928638)
			(xy 421.280858 -374.918514) (xy 421.288572 -374.899795) (xy 421.302848 -374.885437) (xy 421.321523 -374.877616)
			(xy 421.331644 -374.877076) (xy 422.047924 -374.877076) (xy 422.058031 -374.877565) (xy 422.076706 -374.885306)
			(xy 422.090999 -374.899601) (xy 422.098737 -374.918277) (xy 422.099232 -374.928384) (xy 422.099232 -375.086372)
			(xy 422.099671 -375.095556) (xy 422.106166 -375.11274) (xy 422.111932 -375.1199) (xy 422.133826 -375.14554)
			(xy 422.171912 -375.201179) (xy 422.203059 -375.260979) (xy 422.22682 -375.324079) (xy 422.242853 -375.389571)
			(xy 422.250926 -375.456511) (xy 422.250923 -375.523937) (xy 422.242844 -375.590877) (xy 422.226806 -375.656367)
			(xy 422.20304 -375.719465) (xy 422.171887 -375.779263) (xy 422.133797 -375.834898) (xy 422.111932 -375.860564)
			(xy 422.106117 -375.867696) (xy 422.099615 -375.884897) (xy 422.099232 -375.894092) (xy 422.099232 -376.386344)
			(xy 422.099636 -376.395532) (xy 422.106156 -376.412715) (xy 422.111932 -376.419872) (xy 422.133799 -376.445535)
			(xy 422.171885 -376.50117) (xy 422.203034 -376.560967) (xy 422.226797 -376.624064) (xy 422.242831 -376.689553)
			(xy 422.250906 -376.756491) (xy 422.250906 -376.756551) (xy 425.52897 -376.756551) (xy 425.537014 -376.689729)
			(xy 425.552986 -376.624347) (xy 425.576658 -376.561343) (xy 425.607689 -376.501619) (xy 425.645637 -376.446032)
			(xy 425.667424 -376.42038) (xy 425.673214 -376.413231) (xy 425.679732 -376.396043) (xy 425.680124 -376.386852)
			(xy 425.680124 -375.893584) (xy 425.679716 -375.884397) (xy 425.6732 -375.867213) (xy 425.667424 -375.860056)
			(xy 425.645668 -375.834378) (xy 425.60772 -375.778795) (xy 425.576686 -375.719074) (xy 425.553012 -375.656073)
			(xy 425.537037 -375.590695) (xy 425.528991 -375.523875) (xy 425.528988 -375.456573) (xy 425.537029 -375.389753)
			(xy 425.552998 -375.324373) (xy 425.576666 -375.26137) (xy 425.607695 -375.201647) (xy 425.645639 -375.146061)
			(xy 425.667424 -375.120408) (xy 425.673202 -375.11325) (xy 425.679727 -375.096069) (xy 425.680124 -375.08688)
			(xy 425.680124 -374.928638) (xy 425.680595 -374.918471) (xy 425.688365 -374.899679) (xy 425.702736 -374.885294)
			(xy 425.721519 -374.877505) (xy 425.731686 -374.877076) (xy 426.447966 -374.877076) (xy 426.45814 -374.877493)
			(xy 426.476941 -374.885274) (xy 426.491329 -374.899662) (xy 426.499108 -374.918464) (xy 426.499528 -374.928638)
			(xy 426.499528 -375.08688) (xy 426.499941 -375.096067) (xy 426.506452 -375.113252) (xy 426.512228 -375.120408)
			(xy 426.534048 -375.146034) (xy 426.571998 -375.201623) (xy 426.603032 -375.26135) (xy 426.626705 -375.324358)
			(xy 426.642676 -375.389744) (xy 426.650718 -375.45657) (xy 426.650716 -375.523878) (xy 426.642668 -375.590704)
			(xy 426.62669 -375.656088) (xy 426.603013 -375.719094) (xy 426.571974 -375.778818) (xy 426.534019 -375.834404)
			(xy 426.512228 -375.860056) (xy 426.506416 -375.86719) (xy 426.499913 -375.884389) (xy 426.499528 -375.893584)
			(xy 426.499528 -376.386852) (xy 426.499955 -376.396037) (xy 426.506456 -376.413222) (xy 426.512228 -376.42038)
			(xy 426.534021 -376.446029) (xy 426.571971 -376.501615) (xy 426.603006 -376.561338) (xy 426.62668 -376.624344)
			(xy 426.642654 -376.689727) (xy 426.650698 -376.75655) (xy 426.650698 -376.823856) (xy 426.650691 -376.823915)
			(xy 429.928739 -376.823915) (xy 429.928739 -376.756491) (xy 429.936814 -376.689553) (xy 429.95285 -376.624064)
			(xy 429.976615 -376.560967) (xy 430.007766 -376.501171) (xy 430.045856 -376.445537) (xy 430.06772 -376.419872)
			(xy 430.073513 -376.412725) (xy 430.080029 -376.395536) (xy 430.08042 -376.386344) (xy 430.08042 -375.894092)
			(xy 430.080009 -375.884905) (xy 430.073496 -375.867721) (xy 430.06772 -375.860564) (xy 430.045887 -375.834873)
			(xy 430.007796 -375.779243) (xy 429.976643 -375.71945) (xy 429.952876 -375.656357) (xy 429.936837 -375.590871)
			(xy 429.928759 -375.523935) (xy 429.928756 -375.456513) (xy 429.936829 -375.389577) (xy 429.952861 -375.324089)
			(xy 429.976623 -375.260994) (xy 430.007771 -375.201199) (xy 430.045857 -375.145565) (xy 430.06772 -375.1199)
			(xy 430.073501 -375.112744) (xy 430.080024 -375.095562) (xy 430.08042 -375.086372) (xy 430.08042 -374.928638)
			(xy 430.080957 -374.918516) (xy 430.088669 -374.8998) (xy 430.10294 -374.885443) (xy 430.121609 -374.877619)
			(xy 430.131728 -374.877076) (xy 430.848008 -374.877076) (xy 430.85816 -374.877515) (xy 430.876907 -374.885308)
			(xy 430.89123 -374.899699) (xy 430.898933 -374.918484) (xy 430.899316 -374.928638) (xy 430.899316 -375.086372)
			(xy 430.899736 -375.095558) (xy 430.906242 -375.112743) (xy 430.912016 -375.1199) (xy 430.933911 -375.14554)
			(xy 430.971998 -375.201178) (xy 431.003146 -375.260978) (xy 431.026908 -375.324078) (xy 431.04294 -375.38957)
			(xy 431.051013 -375.456511) (xy 431.051011 -375.523937) (xy 431.042932 -375.590877) (xy 431.026893 -375.656368)
			(xy 431.003126 -375.719466) (xy 430.971973 -375.779263) (xy 430.933881 -375.834898) (xy 430.912016 -375.860564)
			(xy 430.906212 -375.867704) (xy 430.899701 -375.884898) (xy 430.899316 -375.894092) (xy 430.899316 -376.386344)
			(xy 430.899701 -376.395534) (xy 430.906232 -376.412718) (xy 430.912016 -376.419872) (xy 430.933883 -376.445534)
			(xy 430.971971 -376.50117) (xy 431.003121 -376.560966) (xy 431.026884 -376.624064) (xy 431.042918 -376.689553)
			(xy 431.050994 -376.756491) (xy 431.050994 -376.756551) (xy 434.329058 -376.756551) (xy 434.337101 -376.689729)
			(xy 434.353073 -376.624348) (xy 434.376744 -376.561343) (xy 434.407775 -376.50162) (xy 434.445721 -376.446033)
			(xy 434.467508 -376.42038) (xy 434.473296 -376.413229) (xy 434.479816 -376.396043) (xy 434.480208 -376.386852)
			(xy 434.480208 -375.893584) (xy 434.479804 -375.884396) (xy 434.473286 -375.867212) (xy 434.467508 -375.860056)
			(xy 434.445753 -375.834378) (xy 434.407805 -375.778794) (xy 434.376772 -375.719074) (xy 434.353099 -375.656073)
			(xy 434.337124 -375.590694) (xy 434.329078 -375.523875) (xy 434.329075 -375.456573) (xy 434.337116 -375.389753)
			(xy 434.353084 -375.324373) (xy 434.376752 -375.26137) (xy 434.40778 -375.201647) (xy 434.445723 -375.146061)
			(xy 434.467508 -375.120408) (xy 434.473285 -375.113249) (xy 434.479811 -375.096069) (xy 434.480208 -375.08688)
			(xy 434.480208 -374.928638) (xy 434.480694 -374.918473) (xy 434.488461 -374.899684) (xy 434.502827 -374.885299)
			(xy 434.521605 -374.877508) (xy 434.53177 -374.877076) (xy 435.24805 -374.877076) (xy 435.258223 -374.877506)
			(xy 435.277024 -374.885281) (xy 435.291412 -374.899666) (xy 435.299192 -374.918465) (xy 435.299612 -374.928638)
			(xy 435.299612 -375.08688) (xy 435.300029 -375.096067) (xy 435.306538 -375.113251) (xy 435.312312 -375.120408)
			(xy 435.334133 -375.146034) (xy 435.372084 -375.201623) (xy 435.403118 -375.26135) (xy 435.426791 -375.324358)
			(xy 435.442764 -375.389744) (xy 435.450806 -375.45657) (xy 435.450803 -375.523878) (xy 435.442755 -375.590704)
			(xy 435.426777 -375.656088) (xy 435.403099 -375.719094) (xy 435.372059 -375.778819) (xy 435.334103 -375.834404)
			(xy 435.312312 -375.860056) (xy 435.306511 -375.867198) (xy 435.299998 -375.884391) (xy 435.299612 -375.893584)
			(xy 435.299612 -376.386852) (xy 435.300042 -376.396037) (xy 435.306542 -376.413222) (xy 435.312312 -376.42038)
			(xy 435.334105 -376.446028) (xy 435.372057 -376.501614) (xy 435.403093 -376.561338) (xy 435.426768 -376.624343)
			(xy 435.442742 -376.689726) (xy 435.450786 -376.75655) (xy 435.450786 -376.823856) (xy 435.442741 -376.89068)
			(xy 435.426766 -376.956063) (xy 435.40309 -377.019068) (xy 435.372054 -377.078791) (xy 435.334101 -377.134376)
			(xy 435.312312 -377.160028) (xy 435.306522 -377.167178) (xy 435.300003 -377.184365) (xy 435.299612 -377.193556)
			(xy 435.299612 -377.35129) (xy 435.299227 -377.361467) (xy 435.291436 -377.380271) (xy 435.277038 -377.394658)
			(xy 435.258228 -377.402435) (xy 435.24805 -377.402852) (xy 434.53177 -377.402852) (xy 434.521609 -377.402391)
			(xy 434.502837 -377.394605) (xy 434.488473 -377.380229) (xy 434.480701 -377.361451) (xy 434.480208 -377.35129)
			(xy 434.480208 -377.193556) (xy 434.479817 -377.184367) (xy 434.47329 -377.167183) (xy 434.467508 -377.160028)
			(xy 434.445725 -377.134372) (xy 434.407778 -377.078786) (xy 434.376746 -377.019062) (xy 434.353075 -376.956058)
			(xy 434.337103 -376.890677) (xy 434.329059 -376.823855) (xy 434.329058 -376.756551) (xy 431.050994 -376.756551)
			(xy 431.050993 -376.823915) (xy 431.042917 -376.890853) (xy 431.026882 -376.956342) (xy 431.003118 -377.019439)
			(xy 430.971968 -377.079236) (xy 430.93388 -377.13487) (xy 430.912016 -377.160536) (xy 430.906223 -377.167684)
			(xy 430.899706 -377.184872) (xy 430.899316 -377.194064) (xy 430.899316 -377.35129) (xy 430.898864 -377.361421)
			(xy 430.891131 -377.380151) (xy 430.876834 -377.394509) (xy 430.858137 -377.402321) (xy 430.848008 -377.402852)
			(xy 430.131728 -377.402852) (xy 430.121582 -377.402357) (xy 430.10284 -377.39458) (xy 430.088518 -377.380207)
			(xy 430.080808 -377.361437) (xy 430.08042 -377.35129) (xy 430.08042 -377.194064) (xy 430.080023 -377.184876)
			(xy 430.0735 -377.167692) (xy 430.06772 -377.160536) (xy 430.045859 -377.134868) (xy 430.007769 -377.079234)
			(xy 429.976617 -377.019439) (xy 429.952852 -376.956342) (xy 429.936815 -376.890853) (xy 429.928739 -376.823915)
			(xy 426.650691 -376.823915) (xy 426.642653 -376.890679) (xy 426.626679 -376.956062) (xy 426.603004 -377.019067)
			(xy 426.571968 -377.07879) (xy 426.534017 -377.134376) (xy 426.512228 -377.160028) (xy 426.506428 -377.167171)
			(xy 426.499918 -377.184363) (xy 426.499528 -377.193556) (xy 426.499528 -377.35129) (xy 426.499127 -377.361465)
			(xy 426.491339 -377.380266) (xy 426.476946 -377.394653) (xy 426.458141 -377.402432) (xy 426.447966 -377.402852)
			(xy 425.731686 -377.402852) (xy 425.721526 -377.402378) (xy 425.702755 -377.394597) (xy 425.68839 -377.380225)
			(xy 425.680618 -377.36145) (xy 425.680124 -377.35129) (xy 425.680124 -377.193556) (xy 425.67973 -377.184367)
			(xy 425.673204 -377.167183) (xy 425.667424 -377.160028) (xy 425.645641 -377.134372) (xy 425.607693 -377.078786)
			(xy 425.57666 -377.019063) (xy 425.552988 -376.956059) (xy 425.537015 -376.890677) (xy 425.528971 -376.823855)
			(xy 425.52897 -376.756551) (xy 422.250906 -376.756551) (xy 422.250905 -376.823915) (xy 422.24283 -376.890853)
			(xy 422.226795 -376.956342) (xy 422.203032 -377.019438) (xy 422.171882 -377.079235) (xy 422.133795 -377.13487)
			(xy 422.111932 -377.160536) (xy 422.106129 -377.167677) (xy 422.09962 -377.184871) (xy 422.099232 -377.194064)
			(xy 422.099232 -377.35129) (xy 422.098764 -377.36142) (xy 422.091035 -377.380146) (xy 422.076742 -377.394503)
			(xy 422.058051 -377.402318) (xy 422.047924 -377.402852) (xy 421.331644 -377.402852) (xy 421.321544 -377.40228)
			(xy 421.302877 -377.394567) (xy 421.288583 -377.380297) (xy 421.280837 -377.361643) (xy 421.280336 -377.351544)
			(xy 421.280336 -377.194064) (xy 421.279935 -377.184876) (xy 421.273414 -377.167692) (xy 421.267636 -377.160536)
			(xy 421.245775 -377.134868) (xy 421.207684 -377.079235) (xy 421.176531 -377.019439) (xy 421.152765 -376.956343)
			(xy 421.136728 -376.890854) (xy 421.128651 -376.823915) (xy 391.450846 -376.823915) (xy 391.442809 -376.890678)
			(xy 391.426837 -376.956059) (xy 391.403165 -377.019064) (xy 391.372134 -377.078788) (xy 391.334187 -377.134375)
			(xy 391.3124 -377.160028) (xy 391.306609 -377.167177) (xy 391.300091 -377.184365) (xy 391.2997 -377.193556)
			(xy 391.2997 -377.35129) (xy 391.299159 -377.361442) (xy 391.291395 -377.380204) (xy 391.277044 -377.394568)
			(xy 391.25829 -377.40235) (xy 391.248138 -377.402852) (xy 390.531858 -377.402852) (xy 390.521696 -377.402401)
			(xy 390.502924 -377.394611) (xy 390.48856 -377.380232) (xy 390.480789 -377.361452) (xy 390.480296 -377.35129)
			(xy 390.480296 -377.193556) (xy 390.479908 -377.184366) (xy 390.473379 -377.167182) (xy 390.467596 -377.160028)
			(xy 390.445814 -377.134372) (xy 390.407867 -377.078785) (xy 390.376836 -377.019062) (xy 390.353165 -376.956058)
			(xy 390.337193 -376.890676) (xy 390.329149 -376.823855) (xy 387.051084 -376.823855) (xy 387.051084 -376.823915)
			(xy 387.043008 -376.890853) (xy 387.026972 -376.956343) (xy 387.003208 -377.01944) (xy 386.972057 -377.079236)
			(xy 386.933968 -377.134871) (xy 386.912104 -377.160536) (xy 386.90631 -377.167683) (xy 386.899794 -377.184872)
			(xy 386.899404 -377.194064) (xy 386.899404 -377.35129) (xy 386.898867 -377.361411) (xy 386.89115 -377.380123)
			(xy 386.87688 -377.394478) (xy 386.858214 -377.402306) (xy 386.848096 -377.402852) (xy 386.131816 -377.402852)
			(xy 386.121669 -377.402366) (xy 386.102927 -377.394586) (xy 386.088605 -377.380209) (xy 386.080896 -377.361438)
			(xy 386.080508 -377.35129) (xy 386.080508 -377.194064) (xy 386.080114 -377.184875) (xy 386.073589 -377.167691)
			(xy 386.067808 -377.160536) (xy 386.045948 -377.134868) (xy 386.007858 -377.079234) (xy 385.976707 -377.019438)
			(xy 385.952942 -376.956342) (xy 385.936906 -376.890853) (xy 385.92883 -376.823915) (xy 382.650782 -376.823915)
			(xy 382.642744 -376.89068) (xy 382.626769 -376.956063) (xy 382.603094 -377.019068) (xy 382.572058 -377.078791)
			(xy 382.534105 -377.134376) (xy 382.512316 -377.160028) (xy 382.506527 -377.167179) (xy 382.500007 -377.184365)
			(xy 382.499616 -377.193556) (xy 382.499616 -377.35129) (xy 382.499227 -377.361467) (xy 382.491437 -377.38027)
			(xy 382.47704 -377.394657) (xy 382.458231 -377.402434) (xy 382.448054 -377.402852) (xy 381.731774 -377.402852)
			(xy 381.721613 -377.402388) (xy 381.702842 -377.394603) (xy 381.688477 -377.380228) (xy 381.680705 -377.361451)
			(xy 381.680212 -377.35129) (xy 381.680212 -377.193556) (xy 381.67982 -377.184367) (xy 381.673294 -377.167183)
			(xy 381.667512 -377.160028) (xy 381.645729 -377.134372) (xy 381.607782 -377.078786) (xy 381.57675 -377.019062)
			(xy 381.553078 -376.956058) (xy 381.537106 -376.890677) (xy 381.529062 -376.823855) (xy 381.529061 -376.756551)
			(xy 378.250997 -376.756551) (xy 378.250996 -376.823915) (xy 378.24292 -376.890853) (xy 378.226885 -376.956342)
			(xy 378.203121 -377.019439) (xy 378.171971 -377.079235) (xy 378.133884 -377.13487) (xy 378.11202 -377.160536)
			(xy 378.106228 -377.167685) (xy 378.09971 -377.184872) (xy 378.09932 -377.194064) (xy 378.09932 -377.35129)
			(xy 378.098864 -377.361421) (xy 378.091132 -377.38015) (xy 378.076836 -377.394508) (xy 378.058141 -377.40232)
			(xy 378.048012 -377.402852) (xy 377.331732 -377.402852) (xy 377.321586 -377.402353) (xy 377.302845 -377.394578)
			(xy 377.288522 -377.380206) (xy 377.280812 -377.361437) (xy 377.280424 -377.35129) (xy 377.280424 -377.194064)
			(xy 377.280026 -377.184876) (xy 377.273503 -377.167692) (xy 377.267724 -377.160536) (xy 377.245863 -377.134868)
			(xy 377.207773 -377.079234) (xy 377.17662 -377.019439) (xy 377.152855 -376.956342) (xy 377.136819 -376.890853)
			(xy 377.128742 -376.823915) (xy 347.450937 -376.823915) (xy 347.4429 -376.890678) (xy 347.426927 -376.95606)
			(xy 347.403255 -377.019065) (xy 347.372223 -377.078788) (xy 347.334275 -377.134376) (xy 347.312488 -377.160028)
			(xy 347.306696 -377.167176) (xy 347.300179 -377.184364) (xy 347.299788 -377.193556) (xy 347.299788 -377.35129)
			(xy 347.299259 -377.361444) (xy 347.291493 -377.380208) (xy 347.277138 -377.394573) (xy 347.25838 -377.402352)
			(xy 347.248226 -377.402852) (xy 346.531946 -377.402852) (xy 346.521776 -377.402398) (xy 346.502981 -377.394627)
			(xy 346.488594 -377.38025) (xy 346.480809 -377.36146) (xy 346.480384 -377.35129) (xy 346.480384 -377.193556)
			(xy 346.479999 -377.184366) (xy 346.473468 -377.167182) (xy 346.467684 -377.160028) (xy 346.445899 -377.134373)
			(xy 346.407947 -377.078788) (xy 346.376911 -377.019065) (xy 346.353236 -376.956061) (xy 346.337262 -376.890679)
			(xy 346.329216 -376.823856) (xy 343.051175 -376.823856) (xy 343.051175 -376.823915) (xy 343.043099 -376.890854)
			(xy 343.027063 -376.956343) (xy 343.003298 -377.01944) (xy 342.972146 -377.079236) (xy 342.934056 -377.134871)
			(xy 342.912192 -377.160536) (xy 342.906397 -377.167682) (xy 342.899882 -377.184872) (xy 342.899492 -377.194064)
			(xy 342.899492 -377.35129) (xy 342.898966 -377.361412) (xy 342.891248 -377.380127) (xy 342.876974 -377.394483)
			(xy 342.858303 -377.402308) (xy 342.848184 -377.402852) (xy 342.131904 -377.402852) (xy 342.121757 -377.402376)
			(xy 342.103014 -377.394592) (xy 342.088693 -377.380212) (xy 342.080984 -377.361439) (xy 342.080596 -377.35129)
			(xy 342.080596 -377.194064) (xy 342.080204 -377.184875) (xy 342.073678 -377.167691) (xy 342.067896 -377.160536)
			(xy 342.046036 -377.134867) (xy 342.007948 -377.079233) (xy 341.976797 -377.019438) (xy 341.953033 -376.956341)
			(xy 341.936997 -376.890852) (xy 341.928921 -376.823915) (xy 338.650849 -376.823915) (xy 338.642812 -376.890677)
			(xy 338.62684 -376.956059) (xy 338.603168 -377.019064) (xy 338.572137 -377.078788) (xy 338.534191 -377.134375)
			(xy 338.512404 -377.160028) (xy 338.506614 -377.167178) (xy 338.500095 -377.184365) (xy 338.499704 -377.193556)
			(xy 338.499704 -377.35129) (xy 338.49916 -377.361442) (xy 338.491396 -377.380203) (xy 338.477047 -377.394567)
			(xy 338.458293 -377.402349) (xy 338.448142 -377.402852) (xy 337.731862 -377.402852) (xy 337.721701 -377.402397)
			(xy 337.702929 -377.394609) (xy 337.688564 -377.380231) (xy 337.680793 -377.361452) (xy 337.6803 -377.35129)
			(xy 337.6803 -377.193556) (xy 337.679911 -377.184367) (xy 337.673383 -377.167182) (xy 337.6676 -377.160028)
			(xy 337.645817 -377.134372) (xy 337.607871 -377.078785) (xy 337.57684 -377.019062) (xy 337.553168 -376.956058)
			(xy 337.537196 -376.890677) (xy 337.529152 -376.823855) (xy 334.251087 -376.823855) (xy 334.251087 -376.823915)
			(xy 334.243011 -376.890853) (xy 334.226976 -376.956342) (xy 334.203211 -377.019439) (xy 334.172061 -377.079236)
			(xy 334.133972 -377.134871) (xy 334.112108 -377.160536) (xy 334.106315 -377.167684) (xy 334.099798 -377.184872)
			(xy 334.099408 -377.194064) (xy 334.099408 -377.35129) (xy 334.098867 -377.36141) (xy 334.091151 -377.380122)
			(xy 334.076882 -377.394477) (xy 334.058217 -377.402305) (xy 334.0481 -377.402852) (xy 333.33182 -377.402852)
			(xy 333.321674 -377.402363) (xy 333.302932 -377.394584) (xy 333.288609 -377.380209) (xy 333.2809 -377.361438)
			(xy 333.280512 -377.35129) (xy 333.280512 -377.194064) (xy 333.280117 -377.184875) (xy 333.273592 -377.167691)
			(xy 333.267812 -377.160536) (xy 333.245952 -377.134868) (xy 333.207862 -377.079234) (xy 333.17671 -377.019438)
			(xy 333.152945 -376.956342) (xy 333.136909 -376.890853) (xy 333.128833 -376.823915) (xy 303.451057 -376.823915)
			(xy 303.44298 -376.890854) (xy 303.426944 -376.956344) (xy 303.403178 -377.019441) (xy 303.372025 -377.079237)
			(xy 303.333933 -377.134871) (xy 303.312068 -377.160536) (xy 303.30627 -377.16768) (xy 303.299757 -377.184871)
			(xy 303.299368 -377.194064) (xy 303.299368 -377.35129) (xy 303.298865 -377.361415) (xy 303.291142 -377.380135)
			(xy 303.276861 -377.394491) (xy 303.258182 -377.402312) (xy 303.24806 -377.402852) (xy 302.53178 -377.402852)
			(xy 302.521631 -377.402396) (xy 302.502888 -377.394604) (xy 302.488567 -377.380218) (xy 302.480859 -377.361441)
			(xy 302.480472 -377.35129) (xy 302.480472 -377.194064) (xy 302.480085 -377.184874) (xy 302.473556 -377.16769)
			(xy 302.467772 -377.160536) (xy 302.445913 -377.134867) (xy 302.407826 -377.079232) (xy 302.376677 -377.019436)
			(xy 302.352913 -376.95634) (xy 302.336879 -376.890852) (xy 302.328803 -376.823914) (xy 302.328802 -376.756492)
			(xy 299.050731 -376.756492) (xy 299.050738 -376.756551) (xy 299.050738 -376.823856) (xy 299.042693 -376.890678)
			(xy 299.026721 -376.95606) (xy 299.003048 -377.019065) (xy 298.972016 -377.078789) (xy 298.934067 -377.134376)
			(xy 298.91228 -377.160028) (xy 298.906487 -377.167175) (xy 298.899971 -377.184364) (xy 298.89958 -377.193556)
			(xy 298.89958 -377.35129) (xy 298.899059 -377.361445) (xy 298.891291 -377.38021) (xy 298.876934 -377.394575)
			(xy 298.858173 -377.402353) (xy 298.848018 -377.402852) (xy 298.131738 -377.402852) (xy 298.121568 -377.402405)
			(xy 298.102772 -377.39463) (xy 298.088385 -377.380252) (xy 298.080601 -377.36146) (xy 298.080176 -377.35129)
			(xy 298.080176 -377.193556) (xy 298.079792 -377.184366) (xy 298.073261 -377.167182) (xy 298.067476 -377.160028)
			(xy 298.045691 -377.134373) (xy 298.00774 -377.078788) (xy 297.976704 -377.019065) (xy 297.95303 -376.956061)
			(xy 297.937055 -376.890679) (xy 297.92901 -376.823856) (xy 294.650969 -376.823856) (xy 294.650969 -376.823915)
			(xy 294.642893 -376.890854) (xy 294.626856 -376.956343) (xy 294.603091 -377.019441) (xy 294.571939 -377.079237)
			(xy 294.533849 -377.134871) (xy 294.511984 -377.160536) (xy 294.506188 -377.167681) (xy 294.499673 -377.184872)
			(xy 294.499284 -377.194064) (xy 294.499284 -377.35129) (xy 294.498766 -377.361413) (xy 294.491046 -377.38013)
			(xy 294.47677 -377.394485) (xy 294.458096 -377.402309) (xy 294.447976 -377.402852) (xy 293.731696 -377.402852)
			(xy 293.721593 -377.402319) (xy 293.702925 -377.39459) (xy 293.688632 -377.380308) (xy 293.680889 -377.361646)
			(xy 293.680388 -377.351544) (xy 293.680388 -377.194064) (xy 293.679998 -377.184875) (xy 293.673471 -377.16769)
			(xy 293.667688 -377.160536) (xy 293.645828 -377.134867) (xy 293.60774 -377.079233) (xy 293.57659 -377.019437)
			(xy 293.552826 -376.956341) (xy 293.536791 -376.890852) (xy 293.528715 -376.823915) (xy 290.250643 -376.823915)
			(xy 290.242606 -376.890678) (xy 290.226633 -376.95606) (xy 290.202962 -377.019064) (xy 290.17193 -377.078788)
			(xy 290.133983 -377.134375) (xy 290.112196 -377.160028) (xy 290.106405 -377.167177) (xy 290.099887 -377.184365)
			(xy 290.099496 -377.193556) (xy 290.099496 -377.35129) (xy 290.098959 -377.361443) (xy 290.091194 -377.380205)
			(xy 290.076842 -377.39457) (xy 290.058087 -377.402351) (xy 290.047934 -377.402852) (xy 289.331654 -377.402852)
			(xy 289.321492 -377.402404) (xy 289.30272 -377.394613) (xy 289.288356 -377.380233) (xy 289.280585 -377.361452)
			(xy 289.280092 -377.35129) (xy 289.280092 -377.193556) (xy 289.279705 -377.184366) (xy 289.273176 -377.167182)
			(xy 289.267392 -377.160028) (xy 289.245607 -377.134373) (xy 289.207654 -377.078788) (xy 289.176618 -377.019066)
			(xy 289.152942 -376.956061) (xy 289.136968 -376.890679) (xy 289.128922 -376.823856) (xy 273.068299 -376.823856)
			(xy 273.100384 -376.843252) (xy 273.210304 -376.919124) (xy 273.315441 -377.001494) (xy 273.415414 -377.090062)
			(xy 273.509856 -377.184504) (xy 273.598424 -377.284477) (xy 273.680794 -377.389614) (xy 273.756666 -377.499534)
			(xy 273.825762 -377.613833) (xy 273.887832 -377.732096) (xy 273.942647 -377.853891) (xy 273.990009 -377.978774)
			(xy 274.029744 -378.106288) (xy 274.061707 -378.235969) (xy 274.077801 -378.323794) (xy 286.928742 -378.323794)
			(xy 286.928744 -378.256367) (xy 286.936824 -378.189426) (xy 286.952863 -378.123935) (xy 286.976633 -378.060837)
			(xy 287.007789 -378.00104) (xy 287.045885 -377.945406) (xy 287.067752 -377.919742) (xy 287.073562 -377.912607)
			(xy 287.080067 -377.895408) (xy 287.080452 -377.886214) (xy 287.080452 -377.728734) (xy 287.080955 -377.718608)
			(xy 287.088674 -377.699885) (xy 287.102955 -377.685528) (xy 287.121637 -377.677709) (xy 287.13176 -377.677172)
			(xy 287.84804 -377.677172) (xy 287.858148 -377.677652) (xy 287.876822 -377.685397) (xy 287.891114 -377.699695)
			(xy 287.898852 -377.718372) (xy 287.899348 -377.72848) (xy 287.899348 -377.886214) (xy 287.899763 -377.8954)
			(xy 287.906275 -377.912584) (xy 287.912048 -377.919742) (xy 287.933888 -377.945427) (xy 287.971981 -378.001058)
			(xy 288.003136 -378.060851) (xy 288.026904 -378.123945) (xy 288.042943 -378.189432) (xy 288.051021 -378.256369)
			(xy 288.051024 -378.323734) (xy 291.329062 -378.323734) (xy 291.329064 -378.256427) (xy 291.337111 -378.189602)
			(xy 291.353086 -378.124219) (xy 291.376762 -378.061213) (xy 291.407799 -378.001489) (xy 291.445751 -377.945902)
			(xy 291.46754 -377.92025) (xy 291.473345 -377.913111) (xy 291.479854 -377.895916) (xy 291.48024 -377.886722)
			(xy 291.48024 -377.728734) (xy 291.480692 -377.718564) (xy 291.488466 -377.69977) (xy 291.502843 -377.685384)
			(xy 291.521633 -377.677598) (xy 291.531802 -377.677172) (xy 292.248082 -377.677172) (xy 292.258257 -377.677579)
			(xy 292.277058 -377.685365) (xy 292.291444 -377.699756) (xy 292.299224 -377.718559) (xy 292.299644 -377.728734)
			(xy 292.299644 -377.886722) (xy 292.300056 -377.895909) (xy 292.30657 -377.913092) (xy 292.312344 -377.92025)
			(xy 292.334107 -377.945923) (xy 292.372057 -378.001506) (xy 292.403093 -378.061227) (xy 292.426768 -378.124228)
			(xy 292.442743 -378.189608) (xy 292.450789 -378.256429) (xy 292.450792 -378.323732) (xy 292.450785 -378.323794)
			(xy 295.72883 -378.323794) (xy 295.728832 -378.256367) (xy 295.736911 -378.189427) (xy 295.752951 -378.123936)
			(xy 295.776719 -378.060837) (xy 295.807875 -378.001041) (xy 295.845969 -377.945407) (xy 295.867836 -377.919742)
			(xy 295.873644 -377.912605) (xy 295.880151 -377.895408) (xy 295.880536 -377.886214) (xy 295.880536 -377.728734)
			(xy 295.881055 -377.71861) (xy 295.88877 -377.69989) (xy 295.903047 -377.685533) (xy 295.921723 -377.677712)
			(xy 295.931844 -377.677172) (xy 296.648124 -377.677172) (xy 296.658276 -377.677601) (xy 296.677024 -377.6854)
			(xy 296.691345 -377.699793) (xy 296.699049 -377.71858) (xy 296.699432 -377.728734) (xy 296.699432 -377.886214)
			(xy 296.699851 -377.8954) (xy 296.70636 -377.912584) (xy 296.712132 -377.919742) (xy 296.733969 -377.945429)
			(xy 296.772057 -378.001061) (xy 296.803207 -378.060855) (xy 296.826971 -378.123949) (xy 296.843007 -378.189435)
			(xy 296.851085 -378.25637) (xy 296.851087 -378.323791) (xy 296.851087 -378.323794) (xy 300.128621 -378.323794)
			(xy 300.128623 -378.256367) (xy 300.136702 -378.189427) (xy 300.152741 -378.123936) (xy 300.176509 -378.060838)
			(xy 300.207664 -378.001041) (xy 300.245758 -377.945407) (xy 300.267624 -377.919742) (xy 300.27343 -377.912604)
			(xy 300.279938 -377.895408) (xy 300.280324 -377.886214) (xy 300.280324 -377.728734) (xy 300.280854 -377.718611)
			(xy 300.288568 -377.699894) (xy 300.302841 -377.685537) (xy 300.321512 -377.677714) (xy 300.331632 -377.677172)
			(xy 301.047912 -377.677172) (xy 301.058063 -377.677611) (xy 301.076811 -377.685405) (xy 301.091133 -377.699796)
			(xy 301.098837 -377.718581) (xy 301.09922 -377.728734) (xy 301.09922 -377.886214) (xy 301.099619 -377.895402)
			(xy 301.10614 -377.912587) (xy 301.11192 -377.919742) (xy 301.133758 -377.945429) (xy 301.171846 -378.001061)
			(xy 301.202997 -378.060854) (xy 301.226761 -378.123948) (xy 301.242798 -378.189434) (xy 301.250876 -378.25637)
			(xy 301.250878 -378.323734) (xy 330.92918 -378.323734) (xy 330.929182 -378.256427) (xy 330.937229 -378.189602)
			(xy 330.953206 -378.124218) (xy 330.976882 -378.061212) (xy 331.00792 -378.001488) (xy 331.045874 -377.945902)
			(xy 331.067664 -377.92025) (xy 331.073472 -377.913113) (xy 331.079978 -377.895916) (xy 331.080364 -377.886722)
			(xy 331.080364 -377.728734) (xy 331.080792 -377.718561) (xy 331.088571 -377.699763) (xy 331.102956 -377.685376)
			(xy 331.121753 -377.677594) (xy 331.131926 -377.677172) (xy 331.848206 -377.677172) (xy 331.858382 -377.67756)
			(xy 331.877184 -377.685353) (xy 331.891569 -377.69975) (xy 331.899348 -377.718557) (xy 331.899768 -377.728734)
			(xy 331.899768 -377.886722) (xy 331.900175 -377.895909) (xy 331.906692 -377.913093) (xy 331.912468 -377.92025)
			(xy 331.93423 -377.945923) (xy 331.972179 -378.001507) (xy 332.003213 -378.061228) (xy 332.026887 -378.124229)
			(xy 332.042861 -378.189609) (xy 332.050907 -378.256429) (xy 332.05091 -378.323732) (xy 332.050903 -378.323793)
			(xy 335.328973 -378.323793) (xy 335.328975 -378.256368) (xy 335.337053 -378.189429) (xy 335.35309 -378.123939)
			(xy 335.376855 -378.060841) (xy 335.408007 -378.001044) (xy 335.446096 -377.945408) (xy 335.46796 -377.919742)
			(xy 335.473771 -377.912607) (xy 335.480275 -377.895409) (xy 335.48066 -377.886214) (xy 335.48066 -377.728734)
			(xy 335.481155 -377.718607) (xy 335.488875 -377.699883) (xy 335.50316 -377.685525) (xy 335.521844 -377.677708)
			(xy 335.531968 -377.677172) (xy 336.248248 -377.677172) (xy 336.258402 -377.677582) (xy 336.27715 -377.685388)
			(xy 336.29147 -377.699787) (xy 336.299173 -377.718578) (xy 336.299556 -377.728734) (xy 336.299556 -377.886214)
			(xy 336.299969 -377.895401) (xy 336.306482 -377.912585) (xy 336.312256 -377.919742) (xy 336.334096 -377.945428)
			(xy 336.372188 -378.001058) (xy 336.403343 -378.060851) (xy 336.42711 -378.123945) (xy 336.443149 -378.189433)
			(xy 336.451227 -378.256369) (xy 336.45123 -378.323734) (xy 339.729268 -378.323734) (xy 339.72927 -378.256427)
			(xy 339.737317 -378.189602) (xy 339.753293 -378.124218) (xy 339.776969 -378.061213) (xy 339.808006 -378.001489)
			(xy 339.845958 -377.945902) (xy 339.867748 -377.92025) (xy 339.873554 -377.913112) (xy 339.880062 -377.895916)
			(xy 339.880448 -377.886722) (xy 339.880448 -377.728734) (xy 339.880892 -377.718563) (xy 339.888668 -377.699768)
			(xy 339.903047 -377.685381) (xy 339.92184 -377.677597) (xy 339.93201 -377.677172) (xy 340.64829 -377.677172)
			(xy 340.658465 -377.677573) (xy 340.677266 -377.685361) (xy 340.691653 -377.699754) (xy 340.699432 -377.718559)
			(xy 340.699852 -377.728734) (xy 340.699852 -377.886722) (xy 340.700262 -377.895909) (xy 340.706777 -377.913093)
			(xy 340.712552 -377.92025) (xy 340.734314 -377.945923) (xy 340.772264 -378.001506) (xy 340.803299 -378.061227)
			(xy 340.826974 -378.124229) (xy 340.842949 -378.189608) (xy 340.850995 -378.256429) (xy 340.850998 -378.323732)
			(xy 340.850998 -378.323734) (xy 344.129059 -378.323734) (xy 344.129061 -378.256427) (xy 344.137108 -378.189603)
			(xy 344.153083 -378.124219) (xy 344.176759 -378.061213) (xy 344.207795 -378.001489) (xy 344.245747 -377.945902)
			(xy 344.267536 -377.92025) (xy 344.273341 -377.913111) (xy 344.27985 -377.895916) (xy 344.280236 -377.886722)
			(xy 344.280236 -377.728734) (xy 344.280692 -377.718565) (xy 344.288465 -377.699771) (xy 344.302841 -377.685385)
			(xy 344.321629 -377.677599) (xy 344.331798 -377.677172) (xy 345.048078 -377.677172) (xy 345.058252 -377.677583)
			(xy 345.077053 -377.685367) (xy 345.09144 -377.699757) (xy 345.099219 -377.71856) (xy 345.09964 -377.728734)
			(xy 345.09964 -377.886722) (xy 345.100053 -377.895909) (xy 345.106566 -377.913092) (xy 345.11234 -377.92025)
			(xy 345.134103 -377.945923) (xy 345.172054 -378.001506) (xy 345.203089 -378.061226) (xy 345.226764 -378.124228)
			(xy 345.24274 -378.189608) (xy 345.250786 -378.256429) (xy 345.250789 -378.323732) (xy 345.250789 -378.323734)
			(xy 374.929089 -378.323734) (xy 374.929092 -378.256427) (xy 374.937139 -378.189602) (xy 374.953116 -378.124218)
			(xy 374.976793 -378.061212) (xy 375.007831 -378.001488) (xy 375.045786 -377.945902) (xy 375.067576 -377.92025)
			(xy 375.073374 -377.913105) (xy 375.079888 -377.895915) (xy 375.080276 -377.886722) (xy 375.080276 -377.728734)
			(xy 375.080693 -377.71856) (xy 375.088474 -377.699759) (xy 375.102862 -377.685371) (xy 375.121664 -377.677592)
			(xy 375.131838 -377.677172) (xy 375.848118 -377.677172) (xy 375.858295 -377.67755) (xy 375.877097 -377.685347)
			(xy 375.891482 -377.699747) (xy 375.89926 -377.718557) (xy 375.89968 -377.728734) (xy 375.89968 -377.886722)
			(xy 375.900084 -377.89591) (xy 375.906602 -377.913094) (xy 375.91238 -377.92025) (xy 375.934142 -377.945923)
			(xy 375.97209 -378.001507) (xy 376.003123 -378.061228) (xy 376.026797 -378.12423) (xy 376.042771 -378.189609)
			(xy 376.050817 -378.256429) (xy 376.050819 -378.323732) (xy 376.050812 -378.323793) (xy 379.328882 -378.323793)
			(xy 379.328884 -378.256368) (xy 379.336962 -378.189428) (xy 379.352999 -378.123938) (xy 379.376765 -378.06084)
			(xy 379.407917 -378.001043) (xy 379.446007 -377.945408) (xy 379.467872 -377.919742) (xy 379.473684 -377.912608)
			(xy 379.480188 -377.895409) (xy 379.480572 -377.886214) (xy 379.480572 -377.728734) (xy 379.481056 -377.718606)
			(xy 379.488778 -377.699879) (xy 379.503066 -377.685521) (xy 379.521754 -377.677706) (xy 379.53188 -377.677172)
			(xy 380.24816 -377.677172) (xy 380.258308 -377.677654) (xy 380.277054 -377.685431) (xy 380.291378 -377.699809)
			(xy 380.299084 -377.718584) (xy 380.299468 -377.728734) (xy 380.299468 -377.886214) (xy 380.299878 -377.895401)
			(xy 380.306393 -377.912585) (xy 380.312168 -377.919742) (xy 380.334008 -377.945428) (xy 380.372099 -378.001059)
			(xy 380.403253 -378.060852) (xy 380.42702 -378.123946) (xy 380.443058 -378.189433) (xy 380.451137 -378.256369)
			(xy 380.451139 -378.323734) (xy 383.729177 -378.323734) (xy 383.729179 -378.256427) (xy 383.737226 -378.189602)
			(xy 383.753202 -378.124218) (xy 383.776879 -378.061212) (xy 383.807917 -378.001488) (xy 383.84587 -377.945902)
			(xy 383.86766 -377.92025) (xy 383.873468 -377.913113) (xy 383.879974 -377.895916) (xy 383.88036 -377.886722)
			(xy 383.88036 -377.728734) (xy 383.880792 -377.718562) (xy 383.88857 -377.699764) (xy 383.902954 -377.685377)
			(xy 383.92175 -377.677595) (xy 383.931922 -377.677172) (xy 384.648202 -377.677172) (xy 384.658378 -377.677563)
			(xy 384.677179 -377.685355) (xy 384.691565 -377.699751) (xy 384.699344 -377.718558) (xy 384.699764 -377.728734)
			(xy 384.699764 -377.886722) (xy 384.700172 -377.895909) (xy 384.706688 -377.913093) (xy 384.712464 -377.92025)
			(xy 384.734226 -377.945923) (xy 384.772175 -378.001507) (xy 384.803209 -378.061228) (xy 384.826884 -378.124229)
			(xy 384.842858 -378.189609) (xy 384.850904 -378.256429) (xy 384.850907 -378.323732) (xy 384.850907 -378.323734)
			(xy 388.128968 -378.323734) (xy 388.12897 -378.256427) (xy 388.137017 -378.189602) (xy 388.152993 -378.124218)
			(xy 388.176669 -378.061213) (xy 388.207706 -378.001489) (xy 388.245658 -377.945902) (xy 388.267448 -377.92025)
			(xy 388.273254 -377.913112) (xy 388.279762 -377.895916) (xy 388.280148 -377.886722) (xy 388.280148 -377.728734)
			(xy 388.280592 -377.718563) (xy 388.288368 -377.699768) (xy 388.302747 -377.685381) (xy 388.32154 -377.677597)
			(xy 388.33171 -377.677172) (xy 389.04799 -377.677172) (xy 389.058165 -377.677573) (xy 389.076966 -377.685361)
			(xy 389.091353 -377.699754) (xy 389.099132 -377.718559) (xy 389.099552 -377.728734) (xy 389.099552 -377.886722)
			(xy 389.099962 -377.895909) (xy 389.106477 -377.913093) (xy 389.112252 -377.92025) (xy 389.134014 -377.945923)
			(xy 389.171964 -378.001506) (xy 389.202999 -378.061227) (xy 389.226674 -378.124229) (xy 389.242649 -378.189608)
			(xy 389.250695 -378.256429) (xy 389.250698 -378.323732) (xy 389.250698 -378.323734) (xy 418.928998 -378.323734)
			(xy 418.929001 -378.256426) (xy 418.937048 -378.189601) (xy 418.953025 -378.124217) (xy 418.976703 -378.061211)
			(xy 419.007742 -378.001487) (xy 419.045697 -377.945902) (xy 419.067488 -377.92025) (xy 419.073287 -377.913106)
			(xy 419.079801 -377.895915) (xy 419.080188 -377.886722) (xy 419.080188 -377.728734) (xy 419.080593 -377.718558)
			(xy 419.088376 -377.699755) (xy 419.102768 -377.685367) (xy 419.121574 -377.67759) (xy 419.13175 -377.677172)
			(xy 419.84803 -377.677172) (xy 419.858208 -377.67754) (xy 419.87701 -377.685341) (xy 419.891395 -377.699744)
			(xy 419.899173 -377.718556) (xy 419.899592 -377.728734) (xy 419.899592 -377.886722) (xy 419.899993 -377.89591)
			(xy 419.906513 -377.913094) (xy 419.912292 -377.92025) (xy 419.934053 -377.945924) (xy 419.972001 -378.001508)
			(xy 420.003034 -378.061229) (xy 420.026706 -378.12423) (xy 420.04268 -378.189609) (xy 420.050726 -378.256429)
			(xy 420.050728 -378.323732) (xy 420.050721 -378.323793) (xy 423.328791 -378.323793) (xy 423.328793 -378.256368)
			(xy 423.336871 -378.189428) (xy 423.352909 -378.123938) (xy 423.376675 -378.06084) (xy 423.407828 -378.001043)
			(xy 423.445919 -377.945408) (xy 423.467784 -377.919742) (xy 423.473586 -377.9126) (xy 423.480098 -377.895407)
			(xy 423.480484 -377.886214) (xy 423.480484 -377.728734) (xy 423.480956 -377.718604) (xy 423.488681 -377.699875)
			(xy 423.502972 -377.685516) (xy 423.521664 -377.677704) (xy 423.531792 -377.677172) (xy 424.248072 -377.677172)
			(xy 424.258189 -377.677638) (xy 424.276887 -377.685372) (xy 424.291201 -377.699673) (xy 424.298953 -377.718363)
			(xy 424.29938 -377.72848) (xy 424.29938 -377.886214) (xy 424.299788 -377.895401) (xy 424.306303 -377.912585)
			(xy 424.31208 -377.919742) (xy 424.333919 -377.945428) (xy 424.37201 -378.001059) (xy 424.403163 -378.060852)
			(xy 424.426929 -378.123946) (xy 424.442967 -378.189433) (xy 424.451046 -378.256369) (xy 424.451048 -378.323734)
			(xy 427.729086 -378.323734) (xy 427.729089 -378.256427) (xy 427.737136 -378.189602) (xy 427.753113 -378.124218)
			(xy 427.77679 -378.061212) (xy 427.807828 -378.001488) (xy 427.845782 -377.945902) (xy 427.867572 -377.92025)
			(xy 427.873381 -377.913114) (xy 427.879886 -377.895916) (xy 427.880272 -377.886722) (xy 427.880272 -377.728734)
			(xy 427.880693 -377.71856) (xy 427.888473 -377.69976) (xy 427.90286 -377.685373) (xy 427.92166 -377.677593)
			(xy 427.931834 -377.677172) (xy 428.648114 -377.677172) (xy 428.658291 -377.677553) (xy 428.677092 -377.685349)
			(xy 428.691478 -377.699748) (xy 428.699256 -377.718557) (xy 428.699676 -377.728734) (xy 428.699676 -377.886722)
			(xy 428.700081 -377.89591) (xy 428.706599 -377.913094) (xy 428.712376 -377.92025) (xy 428.734137 -377.945924)
			(xy 428.772086 -378.001507) (xy 428.80312 -378.061228) (xy 428.826793 -378.12423) (xy 428.842767 -378.189609)
			(xy 428.850813 -378.256429) (xy 428.850816 -378.323732) (xy 428.850816 -378.323734) (xy 432.128877 -378.323734)
			(xy 432.128879 -378.256427) (xy 432.136926 -378.189602) (xy 432.152902 -378.124218) (xy 432.176579 -378.061212)
			(xy 432.207617 -378.001488) (xy 432.24557 -377.945902) (xy 432.26736 -377.92025) (xy 432.273168 -377.913113)
			(xy 432.279674 -377.895916) (xy 432.28006 -377.886722) (xy 432.28006 -377.728734) (xy 432.280492 -377.718562)
			(xy 432.28827 -377.699764) (xy 432.302654 -377.685377) (xy 432.32145 -377.677595) (xy 432.331622 -377.677172)
			(xy 433.047902 -377.677172) (xy 433.058078 -377.677563) (xy 433.076879 -377.685355) (xy 433.091265 -377.699751)
			(xy 433.099044 -377.718558) (xy 433.099464 -377.728734) (xy 433.099464 -377.886722) (xy 433.099872 -377.895909)
			(xy 433.106388 -377.913093) (xy 433.112164 -377.92025) (xy 433.133926 -377.945923) (xy 433.171875 -378.001507)
			(xy 433.202909 -378.061228) (xy 433.226584 -378.124229) (xy 433.242558 -378.189609) (xy 433.250604 -378.256429)
			(xy 433.250607 -378.323732) (xy 433.242565 -378.390553) (xy 433.226595 -378.455933) (xy 433.202925 -378.518937)
			(xy 433.171895 -378.57866) (xy 433.13395 -378.634246) (xy 433.112164 -378.659898) (xy 433.106381 -378.667053)
			(xy 433.099859 -378.684236) (xy 433.099464 -378.693426) (xy 433.099464 -379.186694) (xy 433.099885 -379.19588)
			(xy 433.106392 -379.213064) (xy 433.112164 -379.220222) (xy 433.133997 -379.245837) (xy 433.171944 -379.301429)
			(xy 433.202975 -379.361158) (xy 433.226645 -379.424167) (xy 433.242615 -379.489554) (xy 433.250655 -379.55638)
			(xy 433.250651 -379.623689) (xy 433.242603 -379.690515) (xy 433.226625 -379.755899) (xy 433.202947 -379.818906)
			(xy 433.171909 -379.878631) (xy 433.133955 -379.934218) (xy 433.112164 -379.95987) (xy 433.106351 -379.967003)
			(xy 433.099847 -379.984203) (xy 433.099464 -379.993398) (xy 433.099464 -380.151386) (xy 433.099025 -380.161556)
			(xy 433.091245 -380.180351) (xy 433.076864 -380.194736) (xy 433.058072 -380.202522) (xy 433.047902 -380.202948)
			(xy 432.331622 -380.202948) (xy 432.32145 -380.202518) (xy 432.302653 -380.194737) (xy 432.288267 -380.180353)
			(xy 432.280484 -380.161558) (xy 432.28006 -380.151386) (xy 432.28006 -379.993398) (xy 432.279637 -379.984212)
			(xy 432.273131 -379.967029) (xy 432.26736 -379.95987) (xy 432.245617 -379.934181) (xy 432.207665 -379.8786)
			(xy 432.176629 -379.818882) (xy 432.152953 -379.755882) (xy 432.136976 -379.690504) (xy 432.128928 -379.623685)
			(xy 432.128924 -379.556384) (xy 432.136964 -379.489564) (xy 432.152932 -379.424184) (xy 432.176601 -379.361181)
			(xy 432.20763 -379.301459) (xy 432.245575 -379.245874) (xy 432.26736 -379.220222) (xy 432.27318 -379.213093)
			(xy 432.279679 -379.19589) (xy 432.28006 -379.186694) (xy 432.28006 -378.693426) (xy 432.279624 -378.684242)
			(xy 432.273127 -378.667058) (xy 432.26736 -378.659898) (xy 432.245546 -378.634267) (xy 432.207596 -378.578678)
			(xy 432.176563 -378.518952) (xy 432.152891 -378.455945) (xy 432.136919 -378.39056) (xy 432.128877 -378.323734)
			(xy 428.850816 -378.323734) (xy 428.842774 -378.390552) (xy 428.826805 -378.455933) (xy 428.803136 -378.518936)
			(xy 428.772106 -378.578659) (xy 428.734161 -378.634245) (xy 428.712376 -378.659898) (xy 428.706595 -378.667054)
			(xy 428.700072 -378.684236) (xy 428.699676 -378.693426) (xy 428.699676 -379.186694) (xy 428.700094 -379.19588)
			(xy 428.706603 -379.213064) (xy 428.712376 -379.220222) (xy 428.734209 -379.245837) (xy 428.772155 -379.301429)
			(xy 428.803185 -379.361158) (xy 428.826855 -379.424167) (xy 428.842824 -379.489554) (xy 428.850865 -379.55638)
			(xy 428.85086 -379.623689) (xy 428.842812 -379.690514) (xy 428.826835 -379.755899) (xy 428.803157 -379.818905)
			(xy 428.772119 -379.87863) (xy 428.734166 -379.934218) (xy 428.712376 -379.95987) (xy 428.706564 -379.967004)
			(xy 428.70006 -379.984203) (xy 428.699676 -379.993398) (xy 428.699676 -380.151386) (xy 428.699156 -380.161541)
			(xy 428.691388 -380.180307) (xy 428.677031 -380.194673) (xy 428.658269 -380.20245) (xy 428.648114 -380.202948)
			(xy 427.931834 -380.202948) (xy 427.921663 -380.202508) (xy 427.902866 -380.194731) (xy 427.88848 -380.180351)
			(xy 427.880696 -380.161557) (xy 427.880272 -380.151386) (xy 427.880272 -379.993398) (xy 427.879869 -379.98421)
			(xy 427.873351 -379.967025) (xy 427.867572 -379.95987) (xy 427.845829 -379.934181) (xy 427.807876 -379.878601)
			(xy 427.776839 -379.818882) (xy 427.753162 -379.755883) (xy 427.737185 -379.690505) (xy 427.729137 -379.623686)
			(xy 427.729133 -379.556384) (xy 427.737173 -379.489564) (xy 427.753142 -379.424183) (xy 427.776811 -379.361181)
			(xy 427.807841 -379.301459) (xy 427.845786 -379.245874) (xy 427.867572 -379.220222) (xy 427.873393 -379.213094)
			(xy 427.879891 -379.19589) (xy 427.880272 -379.186694) (xy 427.880272 -378.693426) (xy 427.879856 -378.684239)
			(xy 427.873347 -378.667055) (xy 427.867572 -378.659898) (xy 427.845758 -378.634267) (xy 427.807808 -378.578678)
			(xy 427.776774 -378.518952) (xy 427.753101 -378.455945) (xy 427.737129 -378.39056) (xy 427.729086 -378.323734)
			(xy 424.451048 -378.323734) (xy 424.451048 -378.323791) (xy 424.442974 -378.390728) (xy 424.426941 -378.456216)
			(xy 424.403179 -378.519312) (xy 424.37203 -378.579107) (xy 424.333943 -378.634741) (xy 424.31208 -378.660406)
			(xy 424.306296 -378.66756) (xy 424.299775 -378.684744) (xy 424.29938 -378.693934) (xy 424.29938 -379.186186)
			(xy 424.299802 -379.195372) (xy 424.306308 -379.212556) (xy 424.31208 -379.219714) (xy 424.33399 -379.245342)
			(xy 424.372079 -379.300981) (xy 424.403228 -379.360782) (xy 424.426991 -379.423884) (xy 424.443024 -379.489378)
			(xy 424.451096 -379.556321) (xy 424.451092 -379.623748) (xy 424.443011 -379.69069) (xy 424.42697 -379.756182)
			(xy 424.4032 -379.819281) (xy 424.372043 -379.879078) (xy 424.333947 -379.934713) (xy 424.31208 -379.960378)
			(xy 424.306266 -379.96751) (xy 424.299762 -379.984711) (xy 424.29938 -379.993906) (xy 424.29938 -380.151386)
			(xy 424.298863 -380.161509) (xy 424.291143 -380.180226) (xy 424.276866 -380.194583) (xy 424.258193 -380.202406)
			(xy 424.248072 -380.202948) (xy 423.531792 -380.202948) (xy 423.521689 -380.202422) (xy 423.50302 -380.194691)
			(xy 423.488727 -380.180407) (xy 423.480984 -380.161743) (xy 423.480484 -380.15164) (xy 423.480484 -379.993906)
			(xy 423.480075 -379.984719) (xy 423.473561 -379.967534) (xy 423.467784 -379.960378) (xy 423.445966 -379.934675)
			(xy 423.407877 -379.879046) (xy 423.376725 -379.819255) (xy 423.352959 -379.756163) (xy 423.336921 -379.690678)
			(xy 423.328841 -379.623744) (xy 423.328837 -379.556325) (xy 423.336908 -379.48939) (xy 423.352938 -379.423904)
			(xy 423.376697 -379.360809) (xy 423.407841 -379.301014) (xy 423.445923 -379.245379) (xy 423.467784 -379.219714)
			(xy 423.473598 -379.212581) (xy 423.480103 -379.195381) (xy 423.480484 -379.186186) (xy 423.480484 -378.693934)
			(xy 423.480061 -378.684748) (xy 423.473557 -378.667563) (xy 423.467784 -378.660406) (xy 423.445895 -378.634762)
			(xy 423.407808 -378.579124) (xy 423.376659 -378.519324) (xy 423.352897 -378.456225) (xy 423.336864 -378.390733)
			(xy 423.328791 -378.323793) (xy 420.050721 -378.323793) (xy 420.042687 -378.390552) (xy 420.026718 -378.455932)
			(xy 420.003049 -378.518936) (xy 419.972021 -378.578659) (xy 419.934077 -378.634245) (xy 419.912292 -378.659898)
			(xy 419.906513 -378.667056) (xy 419.899988 -378.684237) (xy 419.899592 -378.693426) (xy 419.899592 -379.186694)
			(xy 419.900007 -379.195881) (xy 419.906518 -379.213065) (xy 419.912292 -379.220222) (xy 419.934124 -379.245837)
			(xy 419.972069 -379.30143) (xy 420.003099 -379.361159) (xy 420.026768 -379.424168) (xy 420.042737 -379.489554)
			(xy 420.050777 -379.556381) (xy 420.050772 -379.623689) (xy 420.042724 -379.690514) (xy 420.026747 -379.755898)
			(xy 420.003071 -379.818905) (xy 419.972034 -379.87863) (xy 419.934082 -379.934217) (xy 419.912292 -379.95987)
			(xy 419.906482 -379.967006) (xy 419.899976 -379.984204) (xy 419.899592 -379.993398) (xy 419.899592 -380.151386)
			(xy 419.899056 -380.161539) (xy 419.891292 -380.180302) (xy 419.876939 -380.194667) (xy 419.858183 -380.202447)
			(xy 419.84803 -380.202948) (xy 419.13175 -380.202948) (xy 419.12158 -380.202495) (xy 419.102784 -380.194724)
			(xy 419.088396 -380.180347) (xy 419.080612 -380.161556) (xy 419.080188 -380.151386) (xy 419.080188 -379.993398)
			(xy 419.079781 -379.98421) (xy 419.073266 -379.967026) (xy 419.067488 -379.95987) (xy 419.045744 -379.934181)
			(xy 419.007791 -379.878601) (xy 418.976753 -379.818883) (xy 418.953075 -379.755883) (xy 418.937097 -379.690505)
			(xy 418.929049 -379.623686) (xy 418.929045 -379.556383) (xy 418.937085 -379.489563) (xy 418.953055 -379.424183)
			(xy 418.976724 -379.36118) (xy 419.007755 -379.301458) (xy 419.045702 -379.245873) (xy 419.067488 -379.220222)
			(xy 419.073299 -379.213087) (xy 419.079805 -379.195889) (xy 419.080188 -379.186694) (xy 419.080188 -378.693426)
			(xy 419.079768 -378.68424) (xy 419.073262 -378.667055) (xy 419.067488 -378.659898) (xy 419.045673 -378.634268)
			(xy 419.007722 -378.578679) (xy 418.976687 -378.518953) (xy 418.953014 -378.455946) (xy 418.937041 -378.39056)
			(xy 418.928998 -378.323734) (xy 389.250698 -378.323734) (xy 389.242656 -378.390553) (xy 389.226686 -378.455934)
			(xy 389.203015 -378.518937) (xy 389.171985 -378.57866) (xy 389.134038 -378.634246) (xy 389.112252 -378.659898)
			(xy 389.106468 -378.667052) (xy 389.099947 -378.684236) (xy 389.099552 -378.693426) (xy 389.099552 -379.186694)
			(xy 389.099976 -379.19588) (xy 389.106481 -379.213063) (xy 389.112252 -379.220222) (xy 389.134085 -379.245837)
			(xy 389.172033 -379.301428) (xy 389.203065 -379.361157) (xy 389.226736 -379.424166) (xy 389.242706 -379.489553)
			(xy 389.250746 -379.55638) (xy 389.250742 -379.623689) (xy 389.242693 -379.690515) (xy 389.226715 -379.7559)
			(xy 389.203037 -379.818906) (xy 389.171998 -379.878631) (xy 389.134043 -379.934218) (xy 389.112252 -379.95987)
			(xy 389.106437 -379.967002) (xy 389.099935 -379.984203) (xy 389.099552 -379.993398) (xy 389.099552 -380.151386)
			(xy 389.099125 -380.161558) (xy 389.091342 -380.180354) (xy 389.076958 -380.19474) (xy 389.058162 -380.202524)
			(xy 389.04799 -380.202948) (xy 388.33171 -380.202948) (xy 388.321537 -380.202528) (xy 388.30274 -380.194743)
			(xy 388.288354 -380.180357) (xy 388.280571 -380.161559) (xy 388.280148 -380.151386) (xy 388.280148 -379.993398)
			(xy 388.279728 -379.984212) (xy 388.27322 -379.967028) (xy 388.267448 -379.95987) (xy 388.245705 -379.934181)
			(xy 388.207755 -379.8786) (xy 388.176719 -379.818881) (xy 388.153043 -379.755882) (xy 388.137067 -379.690504)
			(xy 388.129019 -379.623685) (xy 388.129015 -379.556384) (xy 388.137054 -379.489564) (xy 388.153023 -379.424184)
			(xy 388.176691 -379.361182) (xy 388.207719 -379.30146) (xy 388.245663 -379.245874) (xy 388.267448 -379.220222)
			(xy 388.273266 -379.213092) (xy 388.279767 -379.19589) (xy 388.280148 -379.186694) (xy 388.280148 -378.693426)
			(xy 388.279715 -378.684241) (xy 388.273216 -378.667057) (xy 388.267448 -378.659898) (xy 388.245634 -378.634267)
			(xy 388.207686 -378.578678) (xy 388.176653 -378.518951) (xy 388.152981 -378.455944) (xy 388.13701 -378.390559)
			(xy 388.128968 -378.323734) (xy 384.850907 -378.323734) (xy 384.842865 -378.390553) (xy 384.826895 -378.455933)
			(xy 384.803225 -378.518937) (xy 384.772195 -378.57866) (xy 384.73425 -378.634246) (xy 384.712464 -378.659898)
			(xy 384.706681 -378.667053) (xy 384.700159 -378.684236) (xy 384.699764 -378.693426) (xy 384.699764 -379.186694)
			(xy 384.700185 -379.19588) (xy 384.706692 -379.213064) (xy 384.712464 -379.220222) (xy 384.734297 -379.245837)
			(xy 384.772244 -379.301429) (xy 384.803275 -379.361158) (xy 384.826945 -379.424167) (xy 384.842915 -379.489554)
			(xy 384.850955 -379.55638) (xy 384.850951 -379.623689) (xy 384.842903 -379.690515) (xy 384.826925 -379.755899)
			(xy 384.803247 -379.818906) (xy 384.772209 -379.878631) (xy 384.734255 -379.934218) (xy 384.712464 -379.95987)
			(xy 384.706651 -379.967003) (xy 384.700147 -379.984203) (xy 384.699764 -379.993398) (xy 384.699764 -380.151386)
			(xy 384.699325 -380.161556) (xy 384.691545 -380.180351) (xy 384.677164 -380.194736) (xy 384.658372 -380.202522)
			(xy 384.648202 -380.202948) (xy 383.931922 -380.202948) (xy 383.92175 -380.202518) (xy 383.902953 -380.194737)
			(xy 383.888567 -380.180353) (xy 383.880784 -380.161558) (xy 383.88036 -380.151386) (xy 383.88036 -379.993398)
			(xy 383.879937 -379.984212) (xy 383.873431 -379.967029) (xy 383.86766 -379.95987) (xy 383.845917 -379.934181)
			(xy 383.807965 -379.8786) (xy 383.776929 -379.818882) (xy 383.753253 -379.755882) (xy 383.737276 -379.690504)
			(xy 383.729228 -379.623685) (xy 383.729224 -379.556384) (xy 383.737264 -379.489564) (xy 383.753232 -379.424184)
			(xy 383.776901 -379.361181) (xy 383.80793 -379.301459) (xy 383.845875 -379.245874) (xy 383.86766 -379.220222)
			(xy 383.87348 -379.213093) (xy 383.879979 -379.19589) (xy 383.88036 -379.186694) (xy 383.88036 -378.693426)
			(xy 383.879924 -378.684242) (xy 383.873427 -378.667058) (xy 383.86766 -378.659898) (xy 383.845846 -378.634267)
			(xy 383.807896 -378.578678) (xy 383.776863 -378.518952) (xy 383.753191 -378.455945) (xy 383.737219 -378.39056)
			(xy 383.729177 -378.323734) (xy 380.451139 -378.323734) (xy 380.451139 -378.323792) (xy 380.443065 -378.390729)
			(xy 380.427031 -378.456217) (xy 380.403269 -378.519313) (xy 380.372119 -378.579108) (xy 380.334032 -378.634741)
			(xy 380.312168 -378.660406) (xy 380.306382 -378.667559) (xy 380.299862 -378.684744) (xy 380.299468 -378.693934)
			(xy 380.299468 -379.186186) (xy 380.299892 -379.195372) (xy 380.306397 -379.212556) (xy 380.312168 -379.219714)
			(xy 380.334078 -379.245341) (xy 380.372168 -379.300981) (xy 380.403318 -379.360782) (xy 380.427081 -379.423884)
			(xy 380.443114 -379.489378) (xy 380.451187 -379.556321) (xy 380.451183 -379.623749) (xy 380.443102 -379.69069)
			(xy 380.427061 -379.756182) (xy 380.40329 -379.819281) (xy 380.372132 -379.879079) (xy 380.334036 -379.934713)
			(xy 380.312168 -379.960378) (xy 380.306352 -379.967509) (xy 380.29985 -379.984711) (xy 380.299468 -379.993906)
			(xy 380.299468 -380.151386) (xy 380.298962 -380.161511) (xy 380.291241 -380.18023) (xy 380.27696 -380.194587)
			(xy 380.258282 -380.202408) (xy 380.24816 -380.202948) (xy 379.53188 -380.202948) (xy 379.521731 -380.202496)
			(xy 379.502987 -380.194703) (xy 379.488666 -380.180316) (xy 379.480958 -380.161537) (xy 379.480572 -380.151386)
			(xy 379.480572 -379.993906) (xy 379.480165 -379.984718) (xy 379.47365 -379.967534) (xy 379.467872 -379.960378)
			(xy 379.446054 -379.934675) (xy 379.407966 -379.879045) (xy 379.376815 -379.819254) (xy 379.353049 -379.756162)
			(xy 379.337011 -379.690678) (xy 379.328932 -379.623744) (xy 379.328928 -379.556325) (xy 379.336999 -379.48939)
			(xy 379.353029 -379.423904) (xy 379.376787 -379.360809) (xy 379.40793 -379.301014) (xy 379.446012 -379.24538)
			(xy 379.467872 -379.219714) (xy 379.473696 -379.212589) (xy 379.480192 -379.195383) (xy 379.480572 -379.186186)
			(xy 379.480572 -378.693934) (xy 379.480152 -378.684748) (xy 379.473646 -378.667563) (xy 379.467872 -378.660406)
			(xy 379.445983 -378.634761) (xy 379.407897 -378.579123) (xy 379.376749 -378.519324) (xy 379.352988 -378.456224)
			(xy 379.336955 -378.390733) (xy 379.328882 -378.323793) (xy 376.050812 -378.323793) (xy 376.042778 -378.390552)
			(xy 376.026808 -378.455933) (xy 376.003139 -378.518936) (xy 375.97211 -378.578659) (xy 375.934166 -378.634246)
			(xy 375.91238 -378.659898) (xy 375.906599 -378.667054) (xy 375.900076 -378.684236) (xy 375.89968 -378.693426)
			(xy 375.89968 -379.186694) (xy 375.900098 -379.19588) (xy 375.906607 -379.213064) (xy 375.91238 -379.220222)
			(xy 375.934212 -379.245837) (xy 375.972159 -379.301429) (xy 376.003189 -379.361158) (xy 376.026858 -379.424168)
			(xy 376.042827 -379.489554) (xy 376.050868 -379.55638) (xy 376.050863 -379.623689) (xy 376.042815 -379.690514)
			(xy 376.026838 -379.755899) (xy 376.003161 -379.818905) (xy 375.972123 -379.87863) (xy 375.93417 -379.934218)
			(xy 375.91238 -379.95987) (xy 375.906569 -379.967005) (xy 375.900064 -379.984203) (xy 375.89968 -379.993398)
			(xy 375.89968 -380.151386) (xy 375.899156 -380.161541) (xy 375.891389 -380.180306) (xy 375.877033 -380.194671)
			(xy 375.858272 -380.202449) (xy 375.848118 -380.202948) (xy 375.131838 -380.202948) (xy 375.121667 -380.202505)
			(xy 375.102871 -380.19473) (xy 375.088484 -380.18035) (xy 375.0807 -380.161557) (xy 375.080276 -380.151386)
			(xy 375.080276 -379.993398) (xy 375.079872 -379.98421) (xy 375.073355 -379.967025) (xy 375.067576 -379.95987)
			(xy 375.045832 -379.934181) (xy 375.00788 -379.878601) (xy 374.976842 -379.818883) (xy 374.953165 -379.755883)
			(xy 374.937188 -379.690505) (xy 374.92914 -379.623686) (xy 374.929136 -379.556384) (xy 374.937176 -379.489563)
			(xy 374.953145 -379.424183) (xy 374.976814 -379.361181) (xy 375.007844 -379.301459) (xy 375.04579 -379.245874)
			(xy 375.067576 -379.220222) (xy 375.073385 -379.213086) (xy 375.079893 -379.195889) (xy 375.080276 -379.186694)
			(xy 375.080276 -378.693426) (xy 375.079859 -378.684239) (xy 375.073351 -378.667055) (xy 375.067576 -378.659898)
			(xy 375.045762 -378.634267) (xy 375.007811 -378.578679) (xy 374.976777 -378.518952) (xy 374.953104 -378.455945)
			(xy 374.937132 -378.39056) (xy 374.929089 -378.323734) (xy 345.250789 -378.323734) (xy 345.242747 -378.390553)
			(xy 345.226776 -378.455934) (xy 345.203105 -378.518938) (xy 345.172074 -378.57866) (xy 345.134127 -378.634246)
			(xy 345.11234 -378.659898) (xy 345.106554 -378.667051) (xy 345.100035 -378.684236) (xy 345.09964 -378.693426)
			(xy 345.09964 -379.186694) (xy 345.100066 -379.195879) (xy 345.10657 -379.213063) (xy 345.11234 -379.220222)
			(xy 345.134174 -379.245837) (xy 345.172123 -379.301428) (xy 345.203155 -379.361156) (xy 345.226826 -379.424166)
			(xy 345.242797 -379.489553) (xy 345.250837 -379.55638) (xy 345.250833 -379.623689) (xy 345.242784 -379.690515)
			(xy 345.226806 -379.7559) (xy 345.203127 -379.818907) (xy 345.172087 -379.878632) (xy 345.134131 -379.934218)
			(xy 345.11234 -379.95987) (xy 345.106524 -379.967001) (xy 345.100023 -379.984203) (xy 345.09964 -379.993398)
			(xy 345.09964 -380.151386) (xy 345.099224 -380.161559) (xy 345.09144 -380.180358) (xy 345.077051 -380.194744)
			(xy 345.058252 -380.202526) (xy 345.048078 -380.202948) (xy 344.331798 -380.202948) (xy 344.321625 -380.202537)
			(xy 344.302827 -380.194749) (xy 344.288442 -380.180359) (xy 344.280659 -380.16156) (xy 344.280236 -380.151386)
			(xy 344.280236 -379.993398) (xy 344.279819 -379.984212) (xy 344.273309 -379.967028) (xy 344.267536 -379.95987)
			(xy 344.245794 -379.93418) (xy 344.207844 -379.878599) (xy 344.176809 -379.818881) (xy 344.153133 -379.755881)
			(xy 344.137157 -379.690504) (xy 344.12911 -379.623685) (xy 344.129106 -379.556384) (xy 344.137145 -379.489565)
			(xy 344.153113 -379.424185) (xy 344.17678 -379.361182) (xy 344.207808 -379.30146) (xy 344.245751 -379.245874)
			(xy 344.267536 -379.220222) (xy 344.273353 -379.213091) (xy 344.279855 -379.19589) (xy 344.280236 -379.186694)
			(xy 344.280236 -378.693426) (xy 344.279805 -378.684241) (xy 344.273305 -378.667057) (xy 344.267536 -378.659898)
			(xy 344.245723 -378.634267) (xy 344.207775 -378.578677) (xy 344.176743 -378.518951) (xy 344.153072 -378.455944)
			(xy 344.137101 -378.390559) (xy 344.129059 -378.323734) (xy 340.850998 -378.323734) (xy 340.842956 -378.390553)
			(xy 340.826986 -378.455934) (xy 340.803315 -378.518937) (xy 340.772285 -378.57866) (xy 340.734338 -378.634246)
			(xy 340.712552 -378.659898) (xy 340.706768 -378.667052) (xy 340.700247 -378.684236) (xy 340.699852 -378.693426)
			(xy 340.699852 -379.186694) (xy 340.700276 -379.19588) (xy 340.706781 -379.213063) (xy 340.712552 -379.220222)
			(xy 340.734385 -379.245837) (xy 340.772333 -379.301428) (xy 340.803365 -379.361157) (xy 340.827036 -379.424166)
			(xy 340.843006 -379.489553) (xy 340.851046 -379.55638) (xy 340.851042 -379.623689) (xy 340.842993 -379.690515)
			(xy 340.827015 -379.7559) (xy 340.803337 -379.818906) (xy 340.772298 -379.878631) (xy 340.734343 -379.934218)
			(xy 340.712552 -379.95987) (xy 340.706737 -379.967002) (xy 340.700235 -379.984203) (xy 340.699852 -379.993398)
			(xy 340.699852 -380.151386) (xy 340.699425 -380.161558) (xy 340.691642 -380.180354) (xy 340.677258 -380.19474)
			(xy 340.658462 -380.202524) (xy 340.64829 -380.202948) (xy 339.93201 -380.202948) (xy 339.921837 -380.202528)
			(xy 339.90304 -380.194743) (xy 339.888654 -380.180357) (xy 339.880871 -380.161559) (xy 339.880448 -380.151386)
			(xy 339.880448 -379.993398) (xy 339.880028 -379.984212) (xy 339.87352 -379.967028) (xy 339.867748 -379.95987)
			(xy 339.846005 -379.934181) (xy 339.808055 -379.8786) (xy 339.777019 -379.818881) (xy 339.753343 -379.755882)
			(xy 339.737367 -379.690504) (xy 339.729319 -379.623685) (xy 339.729315 -379.556384) (xy 339.737354 -379.489564)
			(xy 339.753323 -379.424184) (xy 339.776991 -379.361182) (xy 339.808019 -379.30146) (xy 339.845963 -379.245874)
			(xy 339.867748 -379.220222) (xy 339.873566 -379.213092) (xy 339.880067 -379.19589) (xy 339.880448 -379.186694)
			(xy 339.880448 -378.693426) (xy 339.880015 -378.684241) (xy 339.873516 -378.667057) (xy 339.867748 -378.659898)
			(xy 339.845934 -378.634267) (xy 339.807986 -378.578678) (xy 339.776953 -378.518951) (xy 339.753281 -378.455944)
			(xy 339.73731 -378.390559) (xy 339.729268 -378.323734) (xy 336.45123 -378.323734) (xy 336.45123 -378.323792)
			(xy 336.443156 -378.390729) (xy 336.427122 -378.456217) (xy 336.403359 -378.519313) (xy 336.372208 -378.579108)
			(xy 336.33412 -378.634742) (xy 336.312256 -378.660406) (xy 336.306469 -378.667558) (xy 336.29995 -378.684743)
			(xy 336.299556 -378.693934) (xy 336.299556 -379.186186) (xy 336.299983 -379.195371) (xy 336.306486 -379.212555)
			(xy 336.312256 -379.219714) (xy 336.334167 -379.245341) (xy 336.372257 -379.30098) (xy 336.403408 -379.360781)
			(xy 336.427172 -379.423883) (xy 336.443205 -379.489377) (xy 336.451278 -379.55632) (xy 336.451274 -379.623749)
			(xy 336.443193 -379.690691) (xy 336.427151 -379.756183) (xy 336.40338 -379.819282) (xy 336.372221 -379.879079)
			(xy 336.334124 -379.934713) (xy 336.312256 -379.960378) (xy 336.306438 -379.967508) (xy 336.299937 -379.98471)
			(xy 336.299556 -379.993906) (xy 336.299556 -380.151386) (xy 336.299062 -380.161512) (xy 336.291338 -380.180234)
			(xy 336.277054 -380.194591) (xy 336.258372 -380.20241) (xy 336.248248 -380.202948) (xy 335.531968 -380.202948)
			(xy 335.521818 -380.202506) (xy 335.503074 -380.194708) (xy 335.488753 -380.180319) (xy 335.481046 -380.161538)
			(xy 335.48066 -380.151386) (xy 335.48066 -379.993906) (xy 335.480234 -379.984721) (xy 335.47373 -379.967537)
			(xy 335.46796 -379.960378) (xy 335.446143 -379.934675) (xy 335.408055 -379.879045) (xy 335.376905 -379.819253)
			(xy 335.35314 -379.756162) (xy 335.337102 -379.690678) (xy 335.329023 -379.623744) (xy 335.329019 -379.556325)
			(xy 335.33709 -379.48939) (xy 335.353119 -379.423904) (xy 335.376876 -379.36081) (xy 335.40802 -379.301015)
			(xy 335.4461 -379.24538) (xy 335.46796 -379.219714) (xy 335.473783 -379.212588) (xy 335.48028 -379.195382)
			(xy 335.48066 -379.186186) (xy 335.48066 -378.693934) (xy 335.48022 -378.68475) (xy 335.473726 -378.667566)
			(xy 335.46796 -378.660406) (xy 335.446072 -378.634761) (xy 335.407987 -378.579123) (xy 335.376839 -378.519323)
			(xy 335.353078 -378.456224) (xy 335.337046 -378.390733) (xy 335.328973 -378.323793) (xy 332.050903 -378.323793)
			(xy 332.042868 -378.390553) (xy 332.026898 -378.455933) (xy 332.003229 -378.518937) (xy 331.972199 -378.578659)
			(xy 331.934254 -378.634246) (xy 331.912468 -378.659898) (xy 331.906686 -378.667053) (xy 331.900163 -378.684236)
			(xy 331.899768 -378.693426) (xy 331.899768 -379.186694) (xy 331.900188 -379.19588) (xy 331.906696 -379.213064)
			(xy 331.912468 -379.220222) (xy 331.934301 -379.245837) (xy 331.972248 -379.301429) (xy 332.003279 -379.361158)
			(xy 332.026949 -379.424167) (xy 332.042918 -379.489554) (xy 332.050958 -379.55638) (xy 332.050954 -379.623689)
			(xy 332.042906 -379.690514) (xy 332.026928 -379.755899) (xy 332.00325 -379.818906) (xy 331.972212 -379.878631)
			(xy 331.934258 -379.934218) (xy 331.912468 -379.95987) (xy 331.906655 -379.967003) (xy 331.900151 -379.984203)
			(xy 331.899768 -379.993398) (xy 331.899768 -380.151386) (xy 331.899325 -380.161556) (xy 331.891546 -380.180349)
			(xy 331.877166 -380.194734) (xy 331.858376 -380.202521) (xy 331.848206 -380.202948) (xy 331.131926 -380.202948)
			(xy 331.121754 -380.202514) (xy 331.102958 -380.194735) (xy 331.088571 -380.180352) (xy 331.080788 -380.161558)
			(xy 331.080364 -380.151386) (xy 331.080364 -379.993398) (xy 331.07994 -379.984213) (xy 331.073434 -379.967029)
			(xy 331.067664 -379.95987) (xy 331.045921 -379.934181) (xy 331.007969 -379.8786) (xy 330.976932 -379.818882)
			(xy 330.953256 -379.755882) (xy 330.937279 -379.690504) (xy 330.929231 -379.623686) (xy 330.929227 -379.556384)
			(xy 330.937267 -379.489564) (xy 330.953235 -379.424184) (xy 330.976904 -379.361181) (xy 331.007933 -379.301459)
			(xy 331.045878 -379.245874) (xy 331.067664 -379.220222) (xy 331.073484 -379.213094) (xy 331.079983 -379.19589)
			(xy 331.080364 -379.186694) (xy 331.080364 -378.693426) (xy 331.079927 -378.684242) (xy 331.07343 -378.667058)
			(xy 331.067664 -378.659898) (xy 331.04585 -378.634267) (xy 331.0079 -378.578678) (xy 330.976866 -378.518952)
			(xy 330.953194 -378.455945) (xy 330.937222 -378.39056) (xy 330.92918 -378.323734) (xy 301.250878 -378.323734)
			(xy 301.250878 -378.323791) (xy 301.242805 -378.390727) (xy 301.226773 -378.456215) (xy 301.203013 -378.51931)
			(xy 301.171866 -378.579106) (xy 301.133782 -378.63474) (xy 301.11192 -378.660406) (xy 301.106141 -378.667564)
			(xy 301.099615 -378.684745) (xy 301.09922 -378.693934) (xy 301.09922 -379.186186) (xy 301.099632 -379.195373)
			(xy 301.106144 -379.212558) (xy 301.11192 -379.219714) (xy 301.133828 -379.245342) (xy 301.171914 -379.300983)
			(xy 301.203062 -379.360784) (xy 301.226823 -379.423886) (xy 301.242854 -379.489379) (xy 301.250926 -379.556321)
			(xy 301.250922 -379.623748) (xy 301.242842 -379.690689) (xy 301.226802 -379.75618) (xy 301.203034 -379.819279)
			(xy 301.171879 -379.879077) (xy 301.133786 -379.934712) (xy 301.11192 -379.960378) (xy 301.10611 -379.967514)
			(xy 301.099603 -379.984711) (xy 301.09922 -379.993906) (xy 301.09922 -380.151386) (xy 301.098761 -380.161517)
			(xy 301.09103 -380.180245) (xy 301.076735 -380.194603) (xy 301.058041 -380.202416) (xy 301.047912 -380.202948)
			(xy 300.331632 -380.202948) (xy 300.321486 -380.202453) (xy 300.302743 -380.194677) (xy 300.28842 -380.180304)
			(xy 300.280711 -380.161534) (xy 300.280324 -380.151386) (xy 300.280324 -379.993906) (xy 300.279906 -379.98472)
			(xy 300.273397 -379.967536) (xy 300.267624 -379.960378) (xy 300.245804 -379.934676) (xy 300.207713 -379.879047)
			(xy 300.176559 -379.819256) (xy 300.152791 -379.756164) (xy 300.136751 -379.690679) (xy 300.128672 -379.623745)
			(xy 300.128667 -379.556324) (xy 300.136739 -379.489389) (xy 300.15277 -379.423902) (xy 300.17653 -379.360807)
			(xy 300.207677 -379.301012) (xy 300.245762 -379.245379) (xy 300.267624 -379.219714) (xy 300.273442 -379.212584)
			(xy 300.279943 -379.195382) (xy 300.280324 -379.186186) (xy 300.280324 -378.693934) (xy 300.279892 -378.684749)
			(xy 300.273393 -378.667565) (xy 300.267624 -378.660406) (xy 300.245734 -378.634762) (xy 300.207644 -378.579125)
			(xy 300.176493 -378.519326) (xy 300.152729 -378.456227) (xy 300.136695 -378.390735) (xy 300.128621 -378.323794)
			(xy 296.851087 -378.323794) (xy 296.843014 -378.390727) (xy 296.826983 -378.456214) (xy 296.803223 -378.51931)
			(xy 296.772077 -378.579105) (xy 296.733993 -378.63474) (xy 296.712132 -378.660406) (xy 296.706342 -378.667556)
			(xy 296.699825 -378.684743) (xy 296.699432 -378.693934) (xy 296.699432 -379.186186) (xy 296.699864 -379.195371)
			(xy 296.706364 -379.212554) (xy 296.712132 -379.219714) (xy 296.73404 -379.245342) (xy 296.772125 -379.300983)
			(xy 296.803272 -379.360785) (xy 296.827032 -379.423886) (xy 296.843064 -379.489379) (xy 296.851135 -379.556321)
			(xy 296.851131 -379.623748) (xy 296.843051 -379.690689) (xy 296.827012 -379.75618) (xy 296.803244 -379.819279)
			(xy 296.77209 -379.879076) (xy 296.733998 -379.934712) (xy 296.712132 -379.960378) (xy 296.706312 -379.967506)
			(xy 296.699813 -379.98471) (xy 296.699432 -379.993906) (xy 296.699432 -380.151386) (xy 296.698961 -380.161515)
			(xy 296.691233 -380.180241) (xy 296.676941 -380.194599) (xy 296.658251 -380.202414) (xy 296.648124 -380.202948)
			(xy 295.931844 -380.202948) (xy 295.921699 -380.202443) (xy 295.902957 -380.194671) (xy 295.888633 -380.1803)
			(xy 295.880924 -380.161533) (xy 295.880536 -380.151386) (xy 295.880536 -379.993906) (xy 295.880115 -379.98472)
			(xy 295.873608 -379.967536) (xy 295.867836 -379.960378) (xy 295.846016 -379.934676) (xy 295.807924 -379.879048)
			(xy 295.776769 -379.819257) (xy 295.753 -379.756165) (xy 295.736961 -379.69068) (xy 295.728881 -379.623745)
			(xy 295.728876 -379.556324) (xy 295.736948 -379.489388) (xy 295.75298 -379.423901) (xy 295.776741 -379.360806)
			(xy 295.807888 -379.301012) (xy 295.845974 -379.245379) (xy 295.867836 -379.219714) (xy 295.873656 -379.212586)
			(xy 295.880156 -379.195382) (xy 295.880536 -379.186186) (xy 295.880536 -378.693934) (xy 295.880101 -378.68475)
			(xy 295.873604 -378.667565) (xy 295.867836 -378.660406) (xy 295.845945 -378.634762) (xy 295.807855 -378.579126)
			(xy 295.776703 -378.519327) (xy 295.752939 -378.456227) (xy 295.736904 -378.390735) (xy 295.72883 -378.323794)
			(xy 292.450785 -378.323794) (xy 292.44275 -378.390553) (xy 292.426779 -378.455934) (xy 292.403109 -378.518938)
			(xy 292.372077 -378.57866) (xy 292.334131 -378.634246) (xy 292.312344 -378.659898) (xy 292.306559 -378.667051)
			(xy 292.300039 -378.684236) (xy 292.299644 -378.693426) (xy 292.299644 -379.186694) (xy 292.30007 -379.195879)
			(xy 292.306574 -379.213063) (xy 292.312344 -379.220222) (xy 292.334178 -379.245837) (xy 292.372126 -379.301428)
			(xy 292.403158 -379.361157) (xy 292.426829 -379.424166) (xy 292.4428 -379.489553) (xy 292.45084 -379.55638)
			(xy 292.450836 -379.623689) (xy 292.442787 -379.690515) (xy 292.426809 -379.7559) (xy 292.40313 -379.818907)
			(xy 292.372091 -379.878631) (xy 292.334135 -379.934218) (xy 292.312344 -379.95987) (xy 292.306528 -379.967001)
			(xy 292.300027 -379.984203) (xy 292.299644 -379.993398) (xy 292.299644 -380.151386) (xy 292.299224 -380.161559)
			(xy 292.291441 -380.180357) (xy 292.277054 -380.194743) (xy 292.258255 -380.202525) (xy 292.248082 -380.202948)
			(xy 291.531802 -380.202948) (xy 291.521629 -380.202534) (xy 291.502831 -380.194747) (xy 291.488446 -380.180358)
			(xy 291.480663 -380.161559) (xy 291.48024 -380.151386) (xy 291.48024 -379.993398) (xy 291.479822 -379.984212)
			(xy 291.473313 -379.967028) (xy 291.46754 -379.95987) (xy 291.445798 -379.934181) (xy 291.407847 -379.878599)
			(xy 291.376812 -379.818881) (xy 291.353137 -379.755881) (xy 291.337161 -379.690504) (xy 291.329113 -379.623685)
			(xy 291.329109 -379.556384) (xy 291.337148 -379.489564) (xy 291.353116 -379.424185) (xy 291.376784 -379.361182)
			(xy 291.407812 -379.30146) (xy 291.445755 -379.245874) (xy 291.46754 -379.220222) (xy 291.473357 -379.213092)
			(xy 291.479859 -379.19589) (xy 291.48024 -379.186694) (xy 291.48024 -378.693426) (xy 291.479809 -378.684241)
			(xy 291.473309 -378.667057) (xy 291.46754 -378.659898) (xy 291.445727 -378.634267) (xy 291.407778 -378.578678)
			(xy 291.376746 -378.518951) (xy 291.353075 -378.455944) (xy 291.337104 -378.390559) (xy 291.329062 -378.323734)
			(xy 288.051024 -378.323734) (xy 288.051024 -378.323792) (xy 288.04295 -378.390729) (xy 288.026915 -378.456218)
			(xy 288.003152 -378.519314) (xy 287.972001 -378.579109) (xy 287.933912 -378.634742) (xy 287.912048 -378.660406)
			(xy 287.90626 -378.667557) (xy 287.899742 -378.684743) (xy 287.899348 -378.693934) (xy 287.899348 -379.186186)
			(xy 287.899776 -379.195371) (xy 287.906279 -379.212555) (xy 287.912048 -379.219714) (xy 287.933959 -379.245341)
			(xy 287.97205 -379.30098) (xy 288.003201 -379.360781) (xy 288.026965 -379.423883) (xy 288.042999 -379.489377)
			(xy 288.051072 -379.55632) (xy 288.051068 -379.623749) (xy 288.042987 -379.690691) (xy 288.026945 -379.756183)
			(xy 288.003173 -379.819282) (xy 287.972014 -379.879079) (xy 287.933917 -379.934714) (xy 287.912048 -379.960378)
			(xy 287.906229 -379.967507) (xy 287.899729 -379.98471) (xy 287.899348 -379.993906) (xy 287.899348 -380.151386)
			(xy 287.898862 -380.161513) (xy 287.891136 -380.180236) (xy 287.87685 -380.194594) (xy 287.858165 -380.202411)
			(xy 287.84804 -380.202948) (xy 287.13176 -380.202948) (xy 287.121655 -380.202449) (xy 287.102985 -380.194707)
			(xy 287.088693 -380.180415) (xy 287.080951 -380.161745) (xy 287.080452 -380.15164) (xy 287.080452 -379.993906)
			(xy 287.080027 -379.984721) (xy 287.073523 -379.967537) (xy 287.067752 -379.960378) (xy 287.045931 -379.934676)
			(xy 287.007838 -379.879048) (xy 286.976682 -379.819258) (xy 286.952913 -379.756165) (xy 286.936873 -379.69068)
			(xy 286.928793 -379.623745) (xy 286.928788 -379.556324) (xy 286.936861 -379.489388) (xy 286.952893 -379.423901)
			(xy 286.976654 -379.360806) (xy 287.007802 -379.301011) (xy 287.045889 -379.245378) (xy 287.067752 -379.219714)
			(xy 287.073574 -379.212587) (xy 287.080072 -379.195382) (xy 287.080452 -379.186186) (xy 287.080452 -378.693934)
			(xy 287.080014 -378.68475) (xy 287.073519 -378.667566) (xy 287.067752 -378.660406) (xy 287.045861 -378.634763)
			(xy 287.007769 -378.579126) (xy 286.976617 -378.519328) (xy 286.952852 -378.456228) (xy 286.936817 -378.390735)
			(xy 286.928742 -378.323794) (xy 274.077801 -378.323794) (xy 274.085782 -378.367343) (xy 274.101882 -378.499931)
			(xy 274.109946 -378.633249) (xy 274.11045 -378.70003) (xy 274.109946 -378.766811) (xy 274.101882 -378.900129)
			(xy 274.085782 -379.032717) (xy 274.061707 -379.164091) (xy 274.029744 -379.293772) (xy 273.990009 -379.421286)
			(xy 273.942647 -379.546169) (xy 273.887832 -379.667964) (xy 273.825762 -379.786227) (xy 273.756666 -379.900526)
			(xy 273.680794 -380.010446) (xy 273.598424 -380.115583) (xy 273.509856 -380.215556) (xy 273.415414 -380.309998)
			(xy 273.315441 -380.398566) (xy 273.210304 -380.480936) (xy 273.100384 -380.556808) (xy 272.986085 -380.625904)
			(xy 272.92786 -380.656463) (xy 289.128932 -380.656463) (xy 289.136975 -380.589641) (xy 289.152947 -380.524259)
			(xy 289.17662 -380.461255) (xy 289.207654 -380.401532) (xy 289.245604 -380.345947) (xy 289.267392 -380.320296)
			(xy 289.273172 -380.313139) (xy 289.279697 -380.295958) (xy 289.280092 -380.286768) (xy 289.280092 -379.7935)
			(xy 289.279684 -379.784313) (xy 289.273169 -379.767128) (xy 289.267392 -379.759972) (xy 289.24565 -379.734282)
			(xy 289.207696 -379.678702) (xy 289.176658 -379.618984) (xy 289.15298 -379.555985) (xy 289.137002 -379.490606)
			(xy 289.128953 -379.423787) (xy 289.128949 -379.356485) (xy 289.136989 -379.289665) (xy 289.152959 -379.224284)
			(xy 289.176628 -379.161282) (xy 289.207659 -379.10156) (xy 289.245606 -379.045975) (xy 289.267392 -379.020324)
			(xy 289.273202 -379.013189) (xy 289.279709 -378.995991) (xy 289.280092 -378.986796) (xy 289.280092 -378.828554)
			(xy 289.280595 -378.818399) (xy 289.288376 -378.799638) (xy 289.302738 -378.785276) (xy 289.321499 -378.777495)
			(xy 289.331654 -378.776992) (xy 290.047934 -378.776992) (xy 290.058088 -378.777504) (xy 290.076849 -378.785281)
			(xy 290.091212 -378.799641) (xy 290.098993 -378.8184) (xy 290.099496 -378.828554) (xy 290.099496 -378.986796)
			(xy 290.099909 -378.995983) (xy 290.106421 -379.013167) (xy 290.112196 -379.020324) (xy 290.13403 -379.045938)
			(xy 290.171975 -379.101531) (xy 290.203004 -379.16126) (xy 290.226673 -379.224269) (xy 290.242641 -379.289656)
			(xy 290.250681 -379.356482) (xy 290.250677 -379.42379) (xy 290.242628 -379.490615) (xy 290.226651 -379.556)
			(xy 290.202975 -379.619006) (xy 290.171938 -379.678731) (xy 290.133986 -379.734319) (xy 290.112196 -379.759972)
			(xy 290.106386 -379.767108) (xy 290.099879 -379.784305) (xy 290.099496 -379.7935) (xy 290.099496 -380.286768)
			(xy 290.099922 -380.295953) (xy 290.106425 -380.313138) (xy 290.112196 -380.320296) (xy 290.134002 -380.345932)
			(xy 290.171948 -380.401522) (xy 290.202979 -380.461248) (xy 290.226649 -380.524255) (xy 290.242619 -380.589638)
			(xy 290.250654 -380.656404) (xy 293.528724 -380.656404) (xy 293.536798 -380.589467) (xy 293.552831 -380.52398)
			(xy 293.576592 -380.460884) (xy 293.60774 -380.401088) (xy 293.645826 -380.345453) (xy 293.667688 -380.319788)
			(xy 293.673471 -380.312633) (xy 293.679994 -380.29545) (xy 293.680388 -380.28626) (xy 293.680388 -379.794008)
			(xy 293.679977 -379.784821) (xy 293.673464 -379.767636) (xy 293.667688 -379.76048) (xy 293.645872 -379.734776)
			(xy 293.607782 -379.679146) (xy 293.57663 -379.619356) (xy 293.552864 -379.556264) (xy 293.536825 -379.49078)
			(xy 293.528746 -379.423846) (xy 293.528741 -379.356426) (xy 293.536812 -379.289491) (xy 293.552842 -379.224005)
			(xy 293.576601 -379.16091) (xy 293.607745 -379.101115) (xy 293.645827 -379.045481) (xy 293.667688 -379.019816)
			(xy 293.673501 -379.012683) (xy 293.680006 -378.995483) (xy 293.680388 -378.986288) (xy 293.680388 -378.828554)
			(xy 293.680887 -378.818431) (xy 293.688621 -378.799718) (xy 293.702902 -378.785366) (xy 293.721575 -378.777539)
			(xy 293.731696 -378.776992) (xy 294.447976 -378.776992) (xy 294.458096 -378.777435) (xy 294.476798 -378.785174)
			(xy 294.491112 -378.799482) (xy 294.49886 -378.81818) (xy 294.499284 -378.8283) (xy 294.499284 -378.986288)
			(xy 294.499704 -378.995474) (xy 294.506211 -379.012658) (xy 294.511984 -379.019816) (xy 294.533896 -379.045442)
			(xy 294.571984 -379.101082) (xy 294.603134 -379.160883) (xy 294.626896 -379.223985) (xy 294.642928 -379.289479)
			(xy 294.651001 -379.356422) (xy 294.650996 -379.42385) (xy 294.642915 -379.490792) (xy 294.626874 -379.556284)
			(xy 294.603104 -379.619383) (xy 294.571947 -379.67918) (xy 294.533851 -379.734815) (xy 294.511984 -379.76048)
			(xy 294.506169 -379.767612) (xy 294.499666 -379.784813) (xy 294.499284 -379.794008) (xy 294.499284 -380.28626)
			(xy 294.499717 -380.295445) (xy 294.506215 -380.312629) (xy 294.511984 -380.319788) (xy 294.533868 -380.345437)
			(xy 294.571957 -380.401073) (xy 294.603108 -380.460872) (xy 294.626872 -380.523971) (xy 294.642906 -380.589462)
			(xy 294.650981 -380.656402) (xy 294.650981 -380.656463) (xy 297.92902 -380.656463) (xy 297.937062 -380.589641)
			(xy 297.953034 -380.52426) (xy 297.976707 -380.461256) (xy 298.00774 -380.401533) (xy 298.045688 -380.345948)
			(xy 298.067476 -380.320296) (xy 298.073254 -380.313137) (xy 298.079781 -380.295957) (xy 298.080176 -380.286768)
			(xy 298.080176 -379.7935) (xy 298.079771 -379.784312) (xy 298.073254 -379.767128) (xy 298.067476 -379.759972)
			(xy 298.045734 -379.734282) (xy 298.007782 -379.678701) (xy 297.976744 -379.618984) (xy 297.953067 -379.555984)
			(xy 297.93709 -379.490606) (xy 297.929041 -379.423787) (xy 297.929037 -379.356485) (xy 297.937077 -379.289665)
			(xy 297.953046 -379.224285) (xy 297.976715 -379.161283) (xy 298.007745 -379.101561) (xy 298.04569 -379.045976)
			(xy 298.067476 -379.020324) (xy 298.073285 -379.013187) (xy 298.079793 -378.99599) (xy 298.080176 -378.986796)
			(xy 298.080176 -378.828554) (xy 298.080597 -378.818389) (xy 298.088393 -378.799611) (xy 298.102782 -378.785246)
			(xy 298.121572 -378.77748) (xy 298.131738 -378.776992) (xy 298.848018 -378.776992) (xy 298.858171 -378.777517)
			(xy 298.876932 -378.785289) (xy 298.891295 -378.799644) (xy 298.899077 -378.818401) (xy 298.89958 -378.828554)
			(xy 298.89958 -378.986796) (xy 298.899996 -378.995982) (xy 298.906506 -379.013167) (xy 298.91228 -379.020324)
			(xy 298.934114 -379.045938) (xy 298.972061 -379.10153) (xy 299.003091 -379.161259) (xy 299.02676 -379.224269)
			(xy 299.042729 -379.289655) (xy 299.050769 -379.356482) (xy 299.050765 -379.42379) (xy 299.042716 -379.490616)
			(xy 299.026739 -379.556) (xy 299.003061 -379.619007) (xy 298.972023 -379.678732) (xy 298.93407 -379.73432)
			(xy 298.91228 -379.759972) (xy 298.906468 -379.767106) (xy 298.899963 -379.784305) (xy 298.89958 -379.7935)
			(xy 298.89958 -380.286768) (xy 298.90001 -380.295953) (xy 298.90651 -380.313137) (xy 298.91228 -380.320296)
			(xy 298.934087 -380.345932) (xy 298.972034 -380.401521) (xy 299.003065 -380.461247) (xy 299.026736 -380.524254)
			(xy 299.042707 -380.589638) (xy 299.050742 -380.656404) (xy 302.328812 -380.656404) (xy 302.336886 -380.589468)
			(xy 302.352918 -380.52398) (xy 302.376679 -380.460884) (xy 302.407826 -380.401089) (xy 302.44591 -380.345454)
			(xy 302.467772 -380.319788) (xy 302.473565 -380.312641) (xy 302.48008 -380.295451) (xy 302.480472 -380.28626)
			(xy 302.480472 -379.794008) (xy 302.480064 -379.78482) (xy 302.47355 -379.767636) (xy 302.467772 -379.76048)
			(xy 302.445956 -379.734775) (xy 302.407868 -379.679146) (xy 302.376717 -379.619355) (xy 302.352951 -379.556263)
			(xy 302.336913 -379.490779) (xy 302.328834 -379.423846) (xy 302.328829 -379.356426) (xy 302.3369 -379.289492)
			(xy 302.35293 -379.224006) (xy 302.376687 -379.160911) (xy 302.407831 -379.101116) (xy 302.445912 -379.045482)
			(xy 302.467772 -379.019816) (xy 302.473595 -379.01269) (xy 302.480092 -378.995485) (xy 302.480472 -378.986288)
			(xy 302.480472 -378.828554) (xy 302.48089 -378.81842) (xy 302.488639 -378.799692) (xy 302.502946 -378.785336)
			(xy 302.521648 -378.777525) (xy 302.53178 -378.776992) (xy 303.24806 -378.776992) (xy 303.258211 -378.777454)
			(xy 303.27696 -378.785235) (xy 303.291285 -378.79962) (xy 303.298987 -378.818402) (xy 303.299368 -378.828554)
			(xy 303.299368 -378.986288) (xy 303.299791 -378.995474) (xy 303.306296 -379.012658) (xy 303.312068 -379.019816)
			(xy 303.33398 -379.045442) (xy 303.37207 -379.101081) (xy 303.40322 -379.160883) (xy 303.426983 -379.223985)
			(xy 303.443016 -379.289479) (xy 303.451089 -379.356422) (xy 303.451084 -379.42385) (xy 303.443003 -379.490792)
			(xy 303.426962 -379.556284) (xy 303.403191 -379.619383) (xy 303.372032 -379.679181) (xy 303.333936 -379.734815)
			(xy 303.312068 -379.76048) (xy 303.306251 -379.76761) (xy 303.299749 -379.784812) (xy 303.299368 -379.794008)
			(xy 303.299368 -380.28626) (xy 303.299805 -380.295444) (xy 303.306301 -380.312628) (xy 303.312068 -380.319788)
			(xy 303.333953 -380.345436) (xy 303.372043 -380.401073) (xy 303.403195 -380.460871) (xy 303.426959 -380.52397)
			(xy 303.442994 -380.589461) (xy 303.451069 -380.656402) (xy 303.451069 -380.656404) (xy 333.128842 -380.656404)
			(xy 333.136916 -380.589467) (xy 333.15295 -380.523979) (xy 333.176713 -380.460883) (xy 333.207862 -380.401087)
			(xy 333.245949 -380.345453) (xy 333.267812 -380.319788) (xy 333.273598 -380.312635) (xy 333.280118 -380.29545)
			(xy 333.280512 -380.28626) (xy 333.280512 -379.794008) (xy 333.280095 -379.784822) (xy 333.273586 -379.767637)
			(xy 333.267812 -379.76048) (xy 333.245995 -379.734776) (xy 333.207904 -379.679147) (xy 333.17675 -379.619357)
			(xy 333.152983 -379.556265) (xy 333.136944 -379.49078) (xy 333.128864 -379.423846) (xy 333.12886 -379.356426)
			(xy 333.136931 -379.289491) (xy 333.152962 -379.224004) (xy 333.176721 -379.160909) (xy 333.207867 -379.101115)
			(xy 333.24595 -379.045481) (xy 333.267812 -379.019816) (xy 333.273628 -379.012685) (xy 333.280131 -378.995483)
			(xy 333.280512 -378.986288) (xy 333.280512 -378.828554) (xy 333.280988 -378.818428) (xy 333.288726 -378.799711)
			(xy 333.303015 -378.785357) (xy 333.321696 -378.777535) (xy 333.33182 -378.776992) (xy 334.0481 -378.776992)
			(xy 334.058253 -378.777422) (xy 334.077004 -378.785216) (xy 334.091327 -378.79961) (xy 334.099028 -378.818399)
			(xy 334.099408 -378.828554) (xy 334.099408 -378.986288) (xy 334.099822 -378.995475) (xy 334.106333 -379.012659)
			(xy 334.112108 -379.019816) (xy 334.134019 -379.045442) (xy 334.172106 -379.101083) (xy 334.203254 -379.160884)
			(xy 334.227015 -379.223986) (xy 334.243047 -379.28948) (xy 334.251119 -379.356422) (xy 334.251114 -379.42385)
			(xy 334.243034 -379.490791) (xy 334.226994 -379.556283) (xy 334.203224 -379.619382) (xy 334.172068 -379.679179)
			(xy 334.133975 -379.734815) (xy 334.112108 -379.76048) (xy 334.106296 -379.767614) (xy 334.09979 -379.784813)
			(xy 334.099408 -379.794008) (xy 334.099408 -380.28626) (xy 334.099836 -380.295445) (xy 334.106337 -380.31263)
			(xy 334.112108 -380.319788) (xy 334.133991 -380.345437) (xy 334.172079 -380.401074) (xy 334.203228 -380.460873)
			(xy 334.226991 -380.523972) (xy 334.243025 -380.589463) (xy 334.251099 -380.656402) (xy 334.251099 -380.656464)
			(xy 337.529162 -380.656464) (xy 337.537203 -380.589643) (xy 337.553173 -380.524262) (xy 337.576842 -380.461259)
			(xy 337.607871 -380.401536) (xy 337.645815 -380.345949) (xy 337.6676 -380.320296) (xy 337.673381 -380.31314)
			(xy 337.679905 -380.295958) (xy 337.6803 -380.286768) (xy 337.6803 -379.7935) (xy 337.67989 -379.784313)
			(xy 337.673376 -379.767129) (xy 337.6676 -379.759972) (xy 337.645861 -379.734281) (xy 337.607913 -379.678699)
			(xy 337.57688 -379.61898) (xy 337.553206 -379.555981) (xy 337.537231 -379.490604) (xy 337.529183 -379.423786)
			(xy 337.529179 -379.356486) (xy 337.537218 -379.289667) (xy 337.553185 -379.224288) (xy 337.57685 -379.161286)
			(xy 337.607876 -379.101563) (xy 337.645816 -379.045977) (xy 337.6676 -379.020324) (xy 337.673411 -379.013189)
			(xy 337.679917 -378.995991) (xy 337.6803 -378.986796) (xy 337.6803 -378.828554) (xy 337.680795 -378.818398)
			(xy 337.688577 -378.799635) (xy 337.702942 -378.785273) (xy 337.721706 -378.777493) (xy 337.731862 -378.776992)
			(xy 338.448142 -378.776992) (xy 338.458297 -378.777498) (xy 338.477058 -378.785278) (xy 338.49142 -378.799639)
			(xy 338.499201 -378.818399) (xy 338.499704 -378.828554) (xy 338.499704 -378.986796) (xy 338.500115 -378.995983)
			(xy 338.506628 -379.013167) (xy 338.512404 -379.020324) (xy 338.534237 -379.045938) (xy 338.572182 -379.101531)
			(xy 338.603211 -379.16126) (xy 338.626879 -379.22427) (xy 338.642847 -379.289656) (xy 338.650887 -379.356482)
			(xy 338.650883 -379.42379) (xy 338.642834 -379.490615) (xy 338.626858 -379.556) (xy 338.603181 -379.619006)
			(xy 338.572145 -379.678731) (xy 338.534193 -379.734319) (xy 338.512404 -379.759972) (xy 338.506595 -379.767108)
			(xy 338.500088 -379.784306) (xy 338.499704 -379.7935) (xy 338.499704 -380.286768) (xy 338.500129 -380.295954)
			(xy 338.506632 -380.313138) (xy 338.512404 -380.320296) (xy 338.53421 -380.345933) (xy 338.572155 -380.401522)
			(xy 338.603185 -380.461248) (xy 338.626855 -380.524255) (xy 338.642826 -380.589639) (xy 338.65086 -380.656404)
			(xy 341.92893 -380.656404) (xy 341.937004 -380.589467) (xy 341.953037 -380.523979) (xy 341.976799 -380.460883)
			(xy 342.007947 -380.401088) (xy 342.046033 -380.345453) (xy 342.067896 -380.319788) (xy 342.07368 -380.312634)
			(xy 342.080202 -380.29545) (xy 342.080596 -380.28626) (xy 342.080596 -379.794008) (xy 342.080183 -379.784821)
			(xy 342.073671 -379.767637) (xy 342.067896 -379.76048) (xy 342.046079 -379.734776) (xy 342.007989 -379.679147)
			(xy 341.976837 -379.619356) (xy 341.95307 -379.556264) (xy 341.937032 -379.49078) (xy 341.928952 -379.423846)
			(xy 341.928948 -379.356426) (xy 341.937019 -379.289491) (xy 341.953049 -379.224005) (xy 341.976807 -379.16091)
			(xy 342.007952 -379.101115) (xy 342.046035 -379.045481) (xy 342.067896 -379.019816) (xy 342.07371 -379.012683)
			(xy 342.080215 -378.995483) (xy 342.080596 -378.986288) (xy 342.080596 -378.828554) (xy 342.081088 -378.81843)
			(xy 342.088822 -378.799716) (xy 342.103106 -378.785363) (xy 342.121782 -378.777538) (xy 342.131904 -378.776992)
			(xy 342.848184 -378.776992) (xy 342.858336 -378.777434) (xy 342.877087 -378.785223) (xy 342.89141 -378.799614)
			(xy 342.899112 -378.8184) (xy 342.899492 -378.828554) (xy 342.899492 -378.986288) (xy 342.89991 -378.995474)
			(xy 342.906418 -379.012659) (xy 342.912192 -379.019816) (xy 342.934103 -379.045442) (xy 342.972191 -379.101082)
			(xy 343.00334 -379.160884) (xy 343.027102 -379.223986) (xy 343.043135 -379.28948) (xy 343.051207 -379.356422)
			(xy 343.051202 -379.42385) (xy 343.043122 -379.490792) (xy 343.027081 -379.556283) (xy 343.003311 -379.619382)
			(xy 342.972154 -379.67918) (xy 342.934059 -379.734815) (xy 342.912192 -379.76048) (xy 342.906378 -379.767613)
			(xy 342.899874 -379.784813) (xy 342.899492 -379.794008) (xy 342.899492 -380.28626) (xy 342.899923 -380.295445)
			(xy 342.906422 -380.312629) (xy 342.912192 -380.319788) (xy 342.934076 -380.345437) (xy 342.972165 -380.401074)
			(xy 343.003315 -380.460872) (xy 343.027078 -380.523971) (xy 343.043113 -380.589462) (xy 343.051187 -380.656402)
			(xy 343.051187 -380.656463) (xy 346.329226 -380.656463) (xy 346.337269 -380.589641) (xy 346.353241 -380.524259)
			(xy 346.376913 -380.461255) (xy 346.407947 -380.401533) (xy 346.445896 -380.345948) (xy 346.467684 -380.320296)
			(xy 346.473463 -380.313138) (xy 346.479989 -380.295957) (xy 346.480384 -380.286768) (xy 346.480384 -379.7935)
			(xy 346.479977 -379.784312) (xy 346.473462 -379.767128) (xy 346.467684 -379.759972) (xy 346.445942 -379.734282)
			(xy 346.407989 -379.678702) (xy 346.376951 -379.618984) (xy 346.353274 -379.555984) (xy 346.337296 -379.490606)
			(xy 346.329247 -379.423787) (xy 346.329243 -379.356485) (xy 346.337283 -379.289665) (xy 346.353252 -379.224285)
			(xy 346.376922 -379.161282) (xy 346.407952 -379.10156) (xy 346.445898 -379.045976) (xy 346.467684 -379.020324)
			(xy 346.473493 -379.013188) (xy 346.480001 -378.99599) (xy 346.480384 -378.986796) (xy 346.480384 -378.828554)
			(xy 346.480797 -378.818388) (xy 346.488595 -378.799609) (xy 346.502986 -378.785243) (xy 346.521779 -378.777479)
			(xy 346.531946 -378.776992) (xy 347.248226 -378.776992) (xy 347.25838 -378.777511) (xy 347.277141 -378.785285)
			(xy 347.291504 -378.799642) (xy 347.299285 -378.8184) (xy 347.299788 -378.828554) (xy 347.299788 -378.986796)
			(xy 347.300203 -378.995983) (xy 347.306714 -379.013167) (xy 347.312488 -379.020324) (xy 347.334322 -379.045938)
			(xy 347.372268 -379.10153) (xy 347.403297 -379.161259) (xy 347.426966 -379.224269) (xy 347.442935 -379.289656)
			(xy 347.450975 -379.356482) (xy 347.450971 -379.42379) (xy 347.442922 -379.490616) (xy 347.426945 -379.556)
			(xy 347.403268 -379.619007) (xy 347.372231 -379.678732) (xy 347.334278 -379.734319) (xy 347.312488 -379.759972)
			(xy 347.306677 -379.767107) (xy 347.300171 -379.784305) (xy 347.299788 -379.7935) (xy 347.299788 -380.286768)
			(xy 347.300216 -380.295953) (xy 347.306718 -380.313138) (xy 347.312488 -380.320296) (xy 347.334295 -380.345932)
			(xy 347.372241 -380.401522) (xy 347.403272 -380.461248) (xy 347.426942 -380.524254) (xy 347.442913 -380.589638)
			(xy 347.450948 -380.656404) (xy 377.128751 -380.656404) (xy 377.136826 -380.589466) (xy 377.15286 -380.523978)
			(xy 377.176623 -380.460882) (xy 377.207772 -380.401087) (xy 377.24586 -380.345453) (xy 377.267724 -380.319788)
			(xy 377.273511 -380.312636) (xy 377.280031 -380.295451) (xy 377.280424 -380.28626) (xy 377.280424 -379.794008)
			(xy 377.280005 -379.784822) (xy 377.273497 -379.767638) (xy 377.267724 -379.76048) (xy 377.245906 -379.734776)
			(xy 377.207815 -379.679148) (xy 377.17666 -379.619357) (xy 377.152893 -379.556265) (xy 377.136853 -379.490781)
			(xy 377.128773 -379.423846) (xy 377.128769 -379.356426) (xy 377.13684 -379.28949) (xy 377.152871 -379.224004)
			(xy 377.176631 -379.160909) (xy 377.207777 -379.101114) (xy 377.245862 -379.045481) (xy 377.267724 -379.019816)
			(xy 377.273542 -379.012686) (xy 377.280043 -378.995484) (xy 377.280424 -378.986288) (xy 377.280424 -378.828554)
			(xy 377.280888 -378.818426) (xy 377.288628 -378.799707) (xy 377.302921 -378.785353) (xy 377.321607 -378.777533)
			(xy 377.331732 -378.776992) (xy 378.048012 -378.776992) (xy 378.058166 -378.777411) (xy 378.076917 -378.785209)
			(xy 378.09124 -378.799607) (xy 378.098941 -378.818398) (xy 378.09932 -378.828554) (xy 378.09932 -378.986288)
			(xy 378.099731 -378.995475) (xy 378.106244 -379.01266) (xy 378.11202 -379.019816) (xy 378.13393 -379.045443)
			(xy 378.172016 -379.101083) (xy 378.203164 -379.160885) (xy 378.226924 -379.223987) (xy 378.242956 -379.28948)
			(xy 378.251028 -379.356423) (xy 378.251023 -379.42385) (xy 378.242943 -379.490791) (xy 378.226903 -379.556282)
			(xy 378.203134 -379.619381) (xy 378.171979 -379.679179) (xy 378.133886 -379.734814) (xy 378.11202 -379.76048)
			(xy 378.106209 -379.767615) (xy 378.099702 -379.784813) (xy 378.09932 -379.794008) (xy 378.09932 -380.28626)
			(xy 378.099745 -380.295446) (xy 378.106248 -380.312631) (xy 378.11202 -380.319788) (xy 378.133903 -380.345437)
			(xy 378.17199 -380.401075) (xy 378.203138 -380.460873) (xy 378.226901 -380.523972) (xy 378.242934 -380.589463)
			(xy 378.251008 -380.656403) (xy 378.251008 -380.656464) (xy 381.529071 -380.656464) (xy 381.537113 -380.589643)
			(xy 381.553083 -380.524262) (xy 381.576752 -380.461258) (xy 381.607782 -380.401535) (xy 381.645726 -380.345948)
			(xy 381.667512 -380.320296) (xy 381.673294 -380.313141) (xy 381.679817 -380.295958) (xy 381.680212 -380.286768)
			(xy 381.680212 -379.7935) (xy 381.679799 -379.784313) (xy 381.673287 -379.767129) (xy 381.667512 -379.759972)
			(xy 381.645773 -379.73428) (xy 381.607824 -379.678699) (xy 381.57679 -379.618981) (xy 381.553116 -379.555981)
			(xy 381.537141 -379.490604) (xy 381.529093 -379.423786) (xy 381.529089 -379.356486) (xy 381.537128 -379.289667)
			(xy 381.553095 -379.224288) (xy 381.576761 -379.161285) (xy 381.607787 -379.101563) (xy 381.645728 -379.045977)
			(xy 381.667512 -379.020324) (xy 381.673325 -379.01319) (xy 381.679829 -378.995991) (xy 381.680212 -378.986796)
			(xy 381.680212 -378.828554) (xy 381.680695 -378.818397) (xy 381.68848 -378.799631) (xy 381.702848 -378.785269)
			(xy 381.721616 -378.777491) (xy 381.731774 -378.776992) (xy 382.448054 -378.776992) (xy 382.458203 -378.77757)
			(xy 382.476962 -378.785321) (xy 382.491328 -378.79966) (xy 382.499112 -378.818406) (xy 382.499616 -378.828554)
			(xy 382.499616 -378.986796) (xy 382.500025 -378.995983) (xy 382.506539 -379.013168) (xy 382.512316 -379.020324)
			(xy 382.534153 -379.045936) (xy 382.572103 -379.101528) (xy 382.603137 -379.161256) (xy 382.626809 -379.224266)
			(xy 382.64278 -379.289654) (xy 382.650821 -379.356481) (xy 382.650816 -379.423791) (xy 382.642767 -379.490618)
			(xy 382.626787 -379.556003) (xy 382.603107 -379.61901) (xy 382.572066 -379.678734) (xy 382.534108 -379.734321)
			(xy 382.512316 -379.759972) (xy 382.506508 -379.767109) (xy 382.5 -379.784306) (xy 382.499616 -379.7935)
			(xy 382.499616 -380.286768) (xy 382.500038 -380.295954) (xy 382.506543 -380.313139) (xy 382.512316 -380.320296)
			(xy 382.534125 -380.345931) (xy 382.572076 -380.401519) (xy 382.603111 -380.461245) (xy 382.626784 -380.524251)
			(xy 382.642757 -380.589636) (xy 382.650793 -380.656404) (xy 385.928839 -380.656404) (xy 385.936913 -380.589467)
			(xy 385.952947 -380.523979) (xy 385.976709 -380.460883) (xy 386.007858 -380.401087) (xy 386.045945 -380.345453)
			(xy 386.067808 -380.319788) (xy 386.073593 -380.312635) (xy 386.080114 -380.29545) (xy 386.080508 -380.28626)
			(xy 386.080508 -379.794008) (xy 386.080092 -379.784821) (xy 386.073582 -379.767637) (xy 386.067808 -379.76048)
			(xy 386.045991 -379.734776) (xy 386.0079 -379.679147) (xy 385.976747 -379.619356) (xy 385.95298 -379.556265)
			(xy 385.936941 -379.49078) (xy 385.928861 -379.423846) (xy 385.928857 -379.356426) (xy 385.936928 -379.289491)
			(xy 385.952958 -379.224004) (xy 385.976718 -379.160909) (xy 386.007863 -379.101115) (xy 386.045947 -379.045481)
			(xy 386.067808 -379.019816) (xy 386.073624 -379.012684) (xy 386.080127 -378.995483) (xy 386.080508 -378.986288)
			(xy 386.080508 -378.828554) (xy 386.080988 -378.818428) (xy 386.088725 -378.799712) (xy 386.103012 -378.785359)
			(xy 386.121693 -378.777535) (xy 386.131816 -378.776992) (xy 386.848096 -378.776992) (xy 386.858249 -378.777425)
			(xy 386.877 -378.785218) (xy 386.891323 -378.799611) (xy 386.899024 -378.818399) (xy 386.899404 -378.828554)
			(xy 386.899404 -378.986288) (xy 386.899819 -378.995475) (xy 386.906329 -379.012659) (xy 386.912104 -379.019816)
			(xy 386.934015 -379.045442) (xy 386.972102 -379.101083) (xy 387.00325 -379.160884) (xy 387.027012 -379.223986)
			(xy 387.043044 -379.28948) (xy 387.051116 -379.356422) (xy 387.051111 -379.42385) (xy 387.043031 -379.490791)
			(xy 387.02699 -379.556283) (xy 387.003221 -379.619382) (xy 386.972065 -379.679179) (xy 386.933971 -379.734815)
			(xy 386.912104 -379.76048) (xy 386.906291 -379.767614) (xy 386.899786 -379.784813) (xy 386.899404 -379.794008)
			(xy 386.899404 -380.28626) (xy 386.899832 -380.295445) (xy 386.906333 -380.31263) (xy 386.912104 -380.319788)
			(xy 386.933987 -380.345437) (xy 386.972075 -380.401074) (xy 387.003225 -380.460872) (xy 387.026988 -380.523971)
			(xy 387.043022 -380.589462) (xy 387.051096 -380.656402) (xy 387.051096 -380.656464) (xy 390.329159 -380.656464)
			(xy 390.3372 -380.589643) (xy 390.35317 -380.524263) (xy 390.376839 -380.461259) (xy 390.407867 -380.401536)
			(xy 390.445811 -380.345949) (xy 390.467596 -380.320296) (xy 390.473376 -380.313139) (xy 390.479901 -380.295958)
			(xy 390.480296 -380.286768) (xy 390.480296 -379.7935) (xy 390.479887 -379.784313) (xy 390.473372 -379.767128)
			(xy 390.467596 -379.759972) (xy 390.445857 -379.73428) (xy 390.407909 -379.678699) (xy 390.376876 -379.61898)
			(xy 390.353203 -379.555981) (xy 390.337228 -379.490604) (xy 390.32918 -379.423786) (xy 390.329176 -379.356486)
			(xy 390.337215 -379.289667) (xy 390.353181 -379.224288) (xy 390.376847 -379.161286) (xy 390.407872 -379.101563)
			(xy 390.445812 -379.045977) (xy 390.467596 -379.020324) (xy 390.473407 -379.013189) (xy 390.479913 -378.995991)
			(xy 390.480296 -378.986796) (xy 390.480296 -378.828554) (xy 390.480795 -378.818398) (xy 390.488576 -378.799636)
			(xy 390.50294 -378.785274) (xy 390.521702 -378.777494) (xy 390.531858 -378.776992) (xy 391.248138 -378.776992)
			(xy 391.258293 -378.777501) (xy 391.277054 -378.785279) (xy 391.291416 -378.79964) (xy 391.299197 -378.8184)
			(xy 391.2997 -378.828554) (xy 391.2997 -378.986796) (xy 391.300112 -378.995983) (xy 391.306625 -379.013167)
			(xy 391.3124 -379.020324) (xy 391.334234 -379.045938) (xy 391.372178 -379.101531) (xy 391.403207 -379.16126)
			(xy 391.426876 -379.224269) (xy 391.442844 -379.289656) (xy 391.450884 -379.356482) (xy 391.45088 -379.42379)
			(xy 391.442831 -379.490615) (xy 391.426855 -379.556) (xy 391.403178 -379.619006) (xy 391.372141 -379.678731)
			(xy 391.334189 -379.734319) (xy 391.3124 -379.759972) (xy 391.30659 -379.767108) (xy 391.300083 -379.784306)
			(xy 391.2997 -379.7935) (xy 391.2997 -380.286768) (xy 391.300126 -380.295954) (xy 391.306629 -380.313138)
			(xy 391.3124 -380.320296) (xy 391.334206 -380.345933) (xy 391.372152 -380.401522) (xy 391.403182 -380.461248)
			(xy 391.426852 -380.524255) (xy 391.442822 -380.589638) (xy 391.450857 -380.656404) (xy 421.12866 -380.656404)
			(xy 421.136735 -380.589466) (xy 421.152769 -380.523978) (xy 421.176533 -380.460881) (xy 421.207683 -380.401086)
			(xy 421.245772 -380.345453) (xy 421.267636 -380.319788) (xy 421.273425 -380.312637) (xy 421.279943 -380.295451)
			(xy 421.280336 -380.28626) (xy 421.280336 -379.794008) (xy 421.279914 -379.784822) (xy 421.273408 -379.767638)
			(xy 421.267636 -379.76048) (xy 421.245818 -379.734776) (xy 421.207725 -379.679148) (xy 421.176571 -379.619358)
			(xy 421.152802 -379.556266) (xy 421.136762 -379.490781) (xy 421.128682 -379.423846) (xy 421.128678 -379.356426)
			(xy 421.136749 -379.28949) (xy 421.152781 -379.224003) (xy 421.176541 -379.160908) (xy 421.207688 -379.101114)
			(xy 421.245774 -379.045481) (xy 421.267636 -379.019816) (xy 421.273455 -379.012687) (xy 421.279956 -378.995484)
			(xy 421.280336 -378.986288) (xy 421.280336 -378.828554) (xy 421.280789 -378.818425) (xy 421.288531 -378.799703)
			(xy 421.302827 -378.785349) (xy 421.321517 -378.777531) (xy 421.331644 -378.776992) (xy 422.047924 -378.776992)
			(xy 422.058033 -378.777465) (xy 422.076711 -378.785209) (xy 422.091004 -378.79951) (xy 422.09874 -378.81819)
			(xy 422.099232 -378.8283) (xy 422.099232 -378.986288) (xy 422.099663 -378.995473) (xy 422.106164 -379.012656)
			(xy 422.111932 -379.019816) (xy 422.133842 -379.045443) (xy 422.171927 -379.101084) (xy 422.203074 -379.160885)
			(xy 422.226834 -379.223987) (xy 422.242865 -379.289481) (xy 422.250937 -379.356423) (xy 422.250932 -379.423849)
			(xy 422.242852 -379.49079) (xy 422.226813 -379.556282) (xy 422.203045 -379.61938) (xy 422.17189 -379.679178)
			(xy 422.133798 -379.734814) (xy 422.111932 -379.76048) (xy 422.106111 -379.767607) (xy 422.099613 -379.784812)
			(xy 422.099232 -379.794008) (xy 422.099232 -380.28626) (xy 422.099677 -380.295443) (xy 422.106168 -380.312627)
			(xy 422.111932 -380.319788) (xy 422.133814 -380.345438) (xy 422.171901 -380.401075) (xy 422.203049 -380.460874)
			(xy 422.22681 -380.523973) (xy 422.242843 -380.589463) (xy 422.250917 -380.656403) (xy 422.250917 -380.656463)
			(xy 425.52898 -380.656463) (xy 425.537022 -380.589642) (xy 425.552992 -380.524262) (xy 425.576662 -380.461258)
			(xy 425.607692 -380.401535) (xy 425.645638 -380.345948) (xy 425.667424 -380.320296) (xy 425.673208 -380.313142)
			(xy 425.679729 -380.295958) (xy 425.680124 -380.286768) (xy 425.680124 -379.7935) (xy 425.679709 -379.784313)
			(xy 425.673198 -379.767129) (xy 425.667424 -379.759972) (xy 425.645684 -379.734281) (xy 425.607735 -379.678699)
			(xy 425.5767 -379.618981) (xy 425.553026 -379.555982) (xy 425.53705 -379.490605) (xy 425.529002 -379.423787)
			(xy 425.528998 -379.356486) (xy 425.537037 -379.289667) (xy 425.553004 -379.224287) (xy 425.576671 -379.161285)
			(xy 425.607698 -379.101563) (xy 425.64564 -379.045977) (xy 425.667424 -379.020324) (xy 425.673238 -379.013191)
			(xy 425.679742 -378.995991) (xy 425.680124 -378.986796) (xy 425.680124 -378.828554) (xy 425.680595 -378.818395)
			(xy 425.688382 -378.799628) (xy 425.702754 -378.785264) (xy 425.721527 -378.777489) (xy 425.731686 -378.776992)
			(xy 426.447966 -378.776992) (xy 426.458116 -378.77756) (xy 426.476875 -378.785315) (xy 426.49124 -378.799657)
			(xy 426.499024 -378.818405) (xy 426.499528 -378.828554) (xy 426.499528 -378.986796) (xy 426.499934 -378.995984)
			(xy 426.50645 -379.013168) (xy 426.512228 -379.020324) (xy 426.534064 -379.045937) (xy 426.572014 -379.101528)
			(xy 426.603047 -379.161257) (xy 426.626718 -379.224267) (xy 426.642689 -379.289654) (xy 426.65073 -379.356481)
			(xy 426.650725 -379.423791) (xy 426.642676 -379.490617) (xy 426.626697 -379.556003) (xy 426.603017 -379.619009)
			(xy 426.571977 -379.678734) (xy 426.53402 -379.73432) (xy 426.512228 -379.759972) (xy 426.50641 -379.767101)
			(xy 426.49991 -379.784304) (xy 426.499528 -379.7935) (xy 426.499528 -380.286768) (xy 426.499947 -380.295954)
			(xy 426.506454 -380.313139) (xy 426.512228 -380.320296) (xy 426.534036 -380.345932) (xy 426.571987 -380.40152)
			(xy 426.603021 -380.461245) (xy 426.626694 -380.524252) (xy 426.642667 -380.589636) (xy 426.650703 -380.656404)
			(xy 429.928748 -380.656404) (xy 429.936823 -380.589467) (xy 429.952857 -380.523978) (xy 429.976619 -380.460882)
			(xy 430.007769 -380.401087) (xy 430.045857 -380.345453) (xy 430.06772 -380.319788) (xy 430.073506 -380.312636)
			(xy 430.080027 -380.295451) (xy 430.08042 -380.28626) (xy 430.08042 -379.794008) (xy 430.080001 -379.784822)
			(xy 430.073493 -379.767638) (xy 430.06772 -379.76048) (xy 430.045902 -379.734776) (xy 430.007811 -379.679148)
			(xy 429.976657 -379.619357) (xy 429.952889 -379.556265) (xy 429.93685 -379.490781) (xy 429.92877 -379.423846)
			(xy 429.928766 -379.356426) (xy 429.936837 -379.289491) (xy 429.952868 -379.224004) (xy 429.976628 -379.160909)
			(xy 430.007774 -379.101114) (xy 430.045858 -379.045481) (xy 430.06772 -379.019816) (xy 430.073537 -379.012685)
			(xy 430.080039 -378.995484) (xy 430.08042 -378.986288) (xy 430.08042 -378.828554) (xy 430.080888 -378.818427)
			(xy 430.088628 -378.799708) (xy 430.102919 -378.785354) (xy 430.121603 -378.777533) (xy 430.131728 -378.776992)
			(xy 430.848008 -378.776992) (xy 430.858162 -378.777415) (xy 430.876913 -378.785212) (xy 430.891235 -378.799608)
			(xy 430.898936 -378.818398) (xy 430.899316 -378.828554) (xy 430.899316 -378.986288) (xy 430.899728 -378.995475)
			(xy 430.90624 -379.01266) (xy 430.912016 -379.019816) (xy 430.933927 -379.045443) (xy 430.972013 -379.101083)
			(xy 431.003161 -379.160885) (xy 431.026921 -379.223987) (xy 431.042953 -379.28948) (xy 431.051025 -379.356422)
			(xy 431.05102 -379.42385) (xy 431.04294 -379.490791) (xy 431.0269 -379.556282) (xy 431.003131 -379.619381)
			(xy 430.971976 -379.679179) (xy 430.933882 -379.734814) (xy 430.912016 -379.76048) (xy 430.906205 -379.767615)
			(xy 430.899698 -379.784813) (xy 430.899316 -379.794008) (xy 430.899316 -380.28626) (xy 430.899742 -380.295446)
			(xy 430.906244 -380.31263) (xy 430.912016 -380.319788) (xy 430.933899 -380.345437) (xy 430.971986 -380.401074)
			(xy 431.003135 -380.460873) (xy 431.026897 -380.523972) (xy 431.042931 -380.589463) (xy 431.051005 -380.656403)
			(xy 431.051005 -380.656464) (xy 434.329068 -380.656464) (xy 434.33711 -380.589643) (xy 434.35308 -380.524262)
			(xy 434.376749 -380.461259) (xy 434.407778 -380.401535) (xy 434.445722 -380.345949) (xy 434.467508 -380.320296)
			(xy 434.47329 -380.31314) (xy 434.479813 -380.295958) (xy 434.480208 -380.286768) (xy 434.480208 -379.7935)
			(xy 434.479796 -379.784313) (xy 434.473283 -379.767129) (xy 434.467508 -379.759972) (xy 434.445769 -379.73428)
			(xy 434.407821 -379.678699) (xy 434.376787 -379.61898) (xy 434.353113 -379.555981) (xy 434.337137 -379.490604)
			(xy 434.32909 -379.423786) (xy 434.329086 -379.356486) (xy 434.337125 -379.289667) (xy 434.353091 -379.224288)
			(xy 434.376757 -379.161286) (xy 434.407783 -379.101563) (xy 434.445724 -379.045977) (xy 434.467508 -379.020324)
			(xy 434.47332 -379.01319) (xy 434.479825 -378.995991) (xy 434.480208 -378.986796) (xy 434.480208 -378.828554)
			(xy 434.480695 -378.818397) (xy 434.488479 -378.799633) (xy 434.502846 -378.78527) (xy 434.521613 -378.777492)
			(xy 434.53177 -378.776992) (xy 435.24805 -378.776992) (xy 435.258213 -378.777504) (xy 435.276998 -378.785264)
			(xy 435.291383 -378.799622) (xy 435.299177 -378.818392) (xy 435.299612 -378.828554) (xy 435.299612 -378.986796)
			(xy 435.300021 -378.995983) (xy 435.306535 -379.013168) (xy 435.312312 -379.020324) (xy 435.334148 -379.045937)
			(xy 435.372099 -379.101528) (xy 435.403133 -379.161256) (xy 435.426805 -379.224266) (xy 435.442776 -379.289654)
			(xy 435.450817 -379.356481) (xy 435.450813 -379.423791) (xy 435.442763 -379.490618) (xy 435.426784 -379.556003)
			(xy 435.403103 -379.61901) (xy 435.372062 -379.678734) (xy 435.334104 -379.73432) (xy 435.312312 -379.759972)
			(xy 435.306504 -379.767109) (xy 435.299996 -379.784306) (xy 435.299612 -379.7935) (xy 435.299612 -380.286768)
			(xy 435.300035 -380.295954) (xy 435.306539 -380.313139) (xy 435.312312 -380.320296) (xy 435.334121 -380.345931)
			(xy 435.372072 -380.401519) (xy 435.403107 -380.461244) (xy 435.426781 -380.524251) (xy 435.442754 -380.589636)
			(xy 435.450797 -380.656461) (xy 435.450796 -380.723769) (xy 435.442749 -380.790594) (xy 435.426772 -380.855977)
			(xy 435.403095 -380.918983) (xy 435.372057 -380.978707) (xy 435.334102 -381.034292) (xy 435.312312 -381.059944)
			(xy 435.306516 -381.067089) (xy 435.3 -381.08428) (xy 435.299612 -381.093472) (xy 435.299612 -381.251206)
			(xy 435.29924 -381.261384) (xy 435.291444 -381.280189) (xy 435.277041 -381.294575) (xy 435.258229 -381.302351)
			(xy 435.24805 -381.302768) (xy 434.53177 -381.302768) (xy 434.521611 -381.302291) (xy 434.502842 -381.294508)
			(xy 434.488478 -381.280138) (xy 434.480704 -381.261365) (xy 434.480208 -381.251206) (xy 434.480208 -381.093472)
			(xy 434.47981 -381.084284) (xy 434.473288 -381.067099) (xy 434.467508 -381.059944) (xy 434.445741 -381.034275)
			(xy 434.407793 -380.97869) (xy 434.376761 -380.918969) (xy 434.353088 -380.855967) (xy 434.337115 -380.790587)
			(xy 434.32907 -380.723766) (xy 434.329068 -380.656464) (xy 431.051005 -380.656464) (xy 431.051003 -380.723827)
			(xy 431.042926 -380.790767) (xy 431.026889 -380.856257) (xy 431.003123 -380.919354) (xy 430.971971 -380.979151)
			(xy 430.933881 -381.034786) (xy 430.912016 -381.060452) (xy 430.906217 -381.067595) (xy 430.899703 -381.084787)
			(xy 430.899316 -381.09398) (xy 430.899316 -381.251206) (xy 430.898877 -381.261338) (xy 430.891139 -381.280068)
			(xy 430.876838 -381.294426) (xy 430.858138 -381.302237) (xy 430.848008 -381.302768) (xy 430.131728 -381.302768)
			(xy 430.121572 -381.302355) (xy 430.102814 -381.294563) (xy 430.088488 -381.280163) (xy 430.080793 -381.261364)
			(xy 430.08042 -381.251206) (xy 430.08042 -381.09398) (xy 430.080015 -381.084792) (xy 430.073497 -381.067608)
			(xy 430.06772 -381.060452) (xy 430.045875 -381.034771) (xy 430.007784 -380.979139) (xy 429.976632 -380.919345)
			(xy 429.952865 -380.85625) (xy 429.936828 -380.790763) (xy 429.92875 -380.723826) (xy 429.928748 -380.656404)
			(xy 426.650703 -380.656404) (xy 426.65071 -380.656461) (xy 426.650708 -380.723769) (xy 426.642661 -380.790593)
			(xy 426.626685 -380.855977) (xy 426.603009 -380.918982) (xy 426.571971 -380.978706) (xy 426.534018 -381.034292)
			(xy 426.512228 -381.059944) (xy 426.506422 -381.067082) (xy 426.499915 -381.084278) (xy 426.499528 -381.093472)
			(xy 426.499528 -381.251206) (xy 426.49914 -381.261382) (xy 426.491347 -381.280184) (xy 426.47695 -381.294569)
			(xy 426.458143 -381.302348) (xy 426.447966 -381.302768) (xy 425.731686 -381.302768) (xy 425.721528 -381.302278)
			(xy 425.70276 -381.2945) (xy 425.688395 -381.280133) (xy 425.68062 -381.261364) (xy 425.680124 -381.251206)
			(xy 425.680124 -381.093472) (xy 425.679722 -381.084284) (xy 425.673202 -381.0671) (xy 425.667424 -381.059944)
			(xy 425.645656 -381.034276) (xy 425.607708 -380.978691) (xy 425.576675 -380.91897) (xy 425.553001 -380.855967)
			(xy 425.537027 -380.790587) (xy 425.528982 -380.723767) (xy 425.52898 -380.656463) (xy 422.250917 -380.656463)
			(xy 422.250915 -380.723827) (xy 422.242838 -380.790766) (xy 422.226801 -380.856256) (xy 422.203036 -380.919354)
			(xy 422.171885 -380.979151) (xy 422.133796 -381.034786) (xy 422.111932 -381.060452) (xy 422.106123 -381.067588)
			(xy 422.099618 -381.084786) (xy 422.099232 -381.09398) (xy 422.099232 -381.251206) (xy 422.098777 -381.261337)
			(xy 422.091042 -381.280063) (xy 422.076746 -381.29442) (xy 422.058052 -381.302234) (xy 422.047924 -381.302768)
			(xy 421.331644 -381.302768) (xy 421.32152 -381.302347) (xy 421.302812 -381.294608) (xy 421.288495 -381.280292)
			(xy 421.280754 -381.261584) (xy 421.280336 -381.25146) (xy 421.280336 -381.09398) (xy 421.279927 -381.084793)
			(xy 421.273412 -381.067609) (xy 421.267636 -381.060452) (xy 421.24579 -381.034771) (xy 421.207699 -380.97914)
			(xy 421.176545 -380.919346) (xy 421.152778 -380.856251) (xy 421.13674 -380.790764) (xy 421.128662 -380.723826)
			(xy 421.12866 -380.656404) (xy 391.450857 -380.656404) (xy 391.450864 -380.656462) (xy 391.450863 -380.723768)
			(xy 391.442817 -380.790591) (xy 391.426843 -380.855974) (xy 391.40317 -380.918979) (xy 391.372136 -380.978704)
			(xy 391.334188 -381.034291) (xy 391.3124 -381.059944) (xy 391.306602 -381.067088) (xy 391.300088 -381.08428)
			(xy 391.2997 -381.093472) (xy 391.2997 -381.251206) (xy 391.299172 -381.261359) (xy 391.291403 -381.280121)
			(xy 391.277048 -381.294485) (xy 391.258291 -381.302266) (xy 391.248138 -381.302768) (xy 390.531858 -381.302768)
			(xy 390.521698 -381.302301) (xy 390.502929 -381.294514) (xy 390.488566 -381.28014) (xy 390.480792 -381.261366)
			(xy 390.480296 -381.251206) (xy 390.480296 -381.093472) (xy 390.4799 -381.084283) (xy 390.473377 -381.067099)
			(xy 390.467596 -381.059944) (xy 390.445829 -381.034275) (xy 390.407883 -380.97869) (xy 390.376851 -380.918968)
			(xy 390.353179 -380.855966) (xy 390.337206 -380.790586) (xy 390.329161 -380.723766) (xy 390.329159 -380.656464)
			(xy 387.051096 -380.656464) (xy 387.051094 -380.723828) (xy 387.043016 -380.790767) (xy 387.026979 -380.856257)
			(xy 387.003213 -380.919355) (xy 386.97206 -380.979152) (xy 386.933969 -381.034787) (xy 386.912104 -381.060452)
			(xy 386.906303 -381.067594) (xy 386.899791 -381.084787) (xy 386.899404 -381.09398) (xy 386.899404 -381.251206)
			(xy 386.89888 -381.261328) (xy 386.891158 -381.280041) (xy 386.876884 -381.294395) (xy 386.858215 -381.302222)
			(xy 386.848096 -381.302768) (xy 386.131816 -381.302768) (xy 386.121659 -381.302365) (xy 386.102901 -381.294568)
			(xy 386.088576 -381.280166) (xy 386.080881 -381.261365) (xy 386.080508 -381.251206) (xy 386.080508 -381.09398)
			(xy 386.080106 -381.084792) (xy 386.073587 -381.067608) (xy 386.067808 -381.060452) (xy 386.045963 -381.034771)
			(xy 386.007874 -380.979139) (xy 385.976722 -380.919345) (xy 385.952956 -380.85625) (xy 385.936919 -380.790763)
			(xy 385.928841 -380.723826) (xy 385.928839 -380.656404) (xy 382.650793 -380.656404) (xy 382.6508 -380.656461)
			(xy 382.650799 -380.723769) (xy 382.642752 -380.790593) (xy 382.626775 -380.855977) (xy 382.603098 -380.918983)
			(xy 382.57206 -380.978707) (xy 382.534106 -381.034292) (xy 382.512316 -381.059944) (xy 382.50652 -381.06709)
			(xy 382.500005 -381.08428) (xy 382.499616 -381.093472) (xy 382.499616 -381.251206) (xy 382.49924 -381.261384)
			(xy 382.491444 -381.280187) (xy 382.477044 -381.294574) (xy 382.458232 -381.30235) (xy 382.448054 -381.302768)
			(xy 381.731774 -381.302768) (xy 381.721615 -381.302288) (xy 381.702847 -381.294506) (xy 381.688482 -381.280137)
			(xy 381.680708 -381.261365) (xy 381.680212 -381.251206) (xy 381.680212 -381.093472) (xy 381.679813 -381.084284)
			(xy 381.673291 -381.0671) (xy 381.667512 -381.059944) (xy 381.645745 -381.034275) (xy 381.607797 -380.978691)
			(xy 381.576764 -380.918969) (xy 381.553092 -380.855967) (xy 381.537118 -380.790587) (xy 381.529073 -380.723767)
			(xy 381.529071 -380.656464) (xy 378.251008 -380.656464) (xy 378.251006 -380.723827) (xy 378.242929 -380.790767)
			(xy 378.226892 -380.856257) (xy 378.203126 -380.919354) (xy 378.171974 -380.979151) (xy 378.133884 -381.034786)
			(xy 378.11202 -381.060452) (xy 378.106221 -381.067596) (xy 378.099707 -381.084787) (xy 378.09932 -381.09398)
			(xy 378.09932 -381.251206) (xy 378.098877 -381.261338) (xy 378.09114 -381.280067) (xy 378.07684 -381.294424)
			(xy 378.058142 -381.302236) (xy 378.048012 -381.302768) (xy 377.331732 -381.302768) (xy 377.321576 -381.302352)
			(xy 377.302818 -381.294561) (xy 377.288492 -381.280162) (xy 377.280797 -381.261364) (xy 377.280424 -381.251206)
			(xy 377.280424 -381.09398) (xy 377.280018 -381.084792) (xy 377.273501 -381.067608) (xy 377.267724 -381.060452)
			(xy 377.245879 -381.034771) (xy 377.207788 -380.979139) (xy 377.176635 -380.919345) (xy 377.152869 -380.856251)
			(xy 377.136831 -380.790763) (xy 377.128753 -380.723826) (xy 377.128751 -380.656404) (xy 347.450948 -380.656404)
			(xy 347.450955 -380.656462) (xy 347.450954 -380.723768) (xy 347.442908 -380.790592) (xy 347.426934 -380.855975)
			(xy 347.40326 -380.91898) (xy 347.372226 -380.978704) (xy 347.334276 -381.034291) (xy 347.312488 -381.059944)
			(xy 347.306689 -381.067087) (xy 347.300176 -381.084279) (xy 347.299788 -381.093472) (xy 347.299788 -381.251206)
			(xy 347.299272 -381.261361) (xy 347.2915 -381.280125) (xy 347.277142 -381.294489) (xy 347.258381 -381.302268)
			(xy 347.248226 -381.302768) (xy 346.531946 -381.302768) (xy 346.521778 -381.302299) (xy 346.502986 -381.29453)
			(xy 346.488599 -381.280158) (xy 346.480812 -381.261373) (xy 346.480384 -381.251206) (xy 346.480384 -381.093472)
			(xy 346.479991 -381.084283) (xy 346.473466 -381.067099) (xy 346.467684 -381.059944) (xy 346.445915 -381.034276)
			(xy 346.407962 -380.978693) (xy 346.376926 -380.918972) (xy 346.35325 -380.85597) (xy 346.337274 -380.790589)
			(xy 346.329228 -380.723767) (xy 346.329226 -380.656463) (xy 343.051187 -380.656463) (xy 343.051185 -380.723828)
			(xy 343.043107 -380.790767) (xy 343.027069 -380.856258) (xy 343.003303 -380.919356) (xy 342.972149 -380.979152)
			(xy 342.934057 -381.034787) (xy 342.912192 -381.060452) (xy 342.90639 -381.067593) (xy 342.899879 -381.084787)
			(xy 342.899492 -381.09398) (xy 342.899492 -381.251206) (xy 342.898979 -381.261329) (xy 342.891255 -381.280044)
			(xy 342.876978 -381.294399) (xy 342.858304 -381.302224) (xy 342.848184 -381.302768) (xy 342.131904 -381.302768)
			(xy 342.121746 -381.302374) (xy 342.102988 -381.294574) (xy 342.088663 -381.280168) (xy 342.080969 -381.261366)
			(xy 342.080596 -381.251206) (xy 342.080596 -381.09398) (xy 342.080196 -381.084792) (xy 342.073675 -381.067608)
			(xy 342.067896 -381.060452) (xy 342.046052 -381.03477) (xy 342.007963 -380.979138) (xy 341.976811 -380.919344)
			(xy 341.953046 -380.856249) (xy 341.93701 -380.790762) (xy 341.928932 -380.723826) (xy 341.92893 -380.656404)
			(xy 338.65086 -380.656404) (xy 338.650867 -380.656462) (xy 338.650866 -380.723768) (xy 338.64282 -380.790591)
			(xy 338.626846 -380.855974) (xy 338.603173 -380.918979) (xy 338.57214 -380.978704) (xy 338.534192 -381.034291)
			(xy 338.512404 -381.059944) (xy 338.506607 -381.067089) (xy 338.500092 -381.08428) (xy 338.499704 -381.093472)
			(xy 338.499704 -381.251206) (xy 338.499172 -381.261359) (xy 338.491404 -381.28012) (xy 338.47705 -381.294484)
			(xy 338.458295 -381.302265) (xy 338.448142 -381.302768) (xy 337.731862 -381.302768) (xy 337.721703 -381.302298)
			(xy 337.702934 -381.294512) (xy 337.68857 -381.280139) (xy 337.680796 -381.261366) (xy 337.6803 -381.251206)
			(xy 337.6803 -381.093472) (xy 337.679904 -381.084283) (xy 337.67338 -381.067099) (xy 337.6676 -381.059944)
			(xy 337.645833 -381.034275) (xy 337.607886 -380.97869) (xy 337.576854 -380.918969) (xy 337.553182 -380.855966)
			(xy 337.537209 -380.790587) (xy 337.529164 -380.723766) (xy 337.529162 -380.656464) (xy 334.251099 -380.656464)
			(xy 334.251097 -380.723828) (xy 334.243019 -380.790767) (xy 334.226982 -380.856257) (xy 334.203216 -380.919355)
			(xy 334.172063 -380.979152) (xy 334.133973 -381.034787) (xy 334.112108 -381.060452) (xy 334.106308 -381.067595)
			(xy 334.099795 -381.084787) (xy 334.099408 -381.09398) (xy 334.099408 -381.251206) (xy 334.09888 -381.261327)
			(xy 334.091159 -381.280039) (xy 334.076886 -381.294394) (xy 334.058218 -381.302221) (xy 334.0481 -381.302768)
			(xy 333.33182 -381.302768) (xy 333.321663 -381.302362) (xy 333.302905 -381.294567) (xy 333.28858 -381.280165)
			(xy 333.280885 -381.261365) (xy 333.280512 -381.251206) (xy 333.280512 -381.09398) (xy 333.280109 -381.084792)
			(xy 333.27359 -381.067608) (xy 333.267812 -381.060452) (xy 333.245967 -381.034771) (xy 333.207877 -380.979139)
			(xy 333.176725 -380.919345) (xy 333.152959 -380.85625) (xy 333.136922 -380.790763) (xy 333.128844 -380.723826)
			(xy 333.128842 -380.656404) (xy 303.451069 -380.656404) (xy 303.451067 -380.723828) (xy 303.442989 -380.790768)
			(xy 303.42695 -380.856259) (xy 303.403182 -380.919357) (xy 303.372027 -380.979153) (xy 303.333934 -381.034787)
			(xy 303.312068 -381.060452) (xy 303.306263 -381.067591) (xy 303.299754 -381.084786) (xy 303.299368 -381.09398)
			(xy 303.299368 -381.251206) (xy 303.298878 -381.261332) (xy 303.29115 -381.280052) (xy 303.276865 -381.294408)
			(xy 303.258184 -381.302228) (xy 303.24806 -381.302768) (xy 302.53178 -381.302768) (xy 302.521621 -381.302394)
			(xy 302.502861 -381.294586) (xy 302.488538 -381.280174) (xy 302.480844 -381.261368) (xy 302.480472 -381.251206)
			(xy 302.480472 -381.09398) (xy 302.480078 -381.084791) (xy 302.473554 -381.067607) (xy 302.467772 -381.060452)
			(xy 302.445929 -381.03477) (xy 302.407841 -380.979137) (xy 302.376691 -380.919343) (xy 302.352927 -380.856248)
			(xy 302.336891 -380.790762) (xy 302.328814 -380.723826) (xy 302.328812 -380.656404) (xy 299.050742 -380.656404)
			(xy 299.050749 -380.656462) (xy 299.050747 -380.723768) (xy 299.042702 -380.790592) (xy 299.026727 -380.855975)
			(xy 299.003053 -380.91898) (xy 298.972018 -380.978704) (xy 298.934068 -381.034292) (xy 298.91228 -381.059944)
			(xy 298.90648 -381.067087) (xy 298.899968 -381.084279) (xy 298.89958 -381.093472) (xy 298.89958 -381.251206)
			(xy 298.899072 -381.261362) (xy 298.891299 -381.280128) (xy 298.876938 -381.294492) (xy 298.858174 -381.302269)
			(xy 298.848018 -381.302768) (xy 298.131738 -381.302768) (xy 298.12157 -381.302305) (xy 298.102777 -381.294534)
			(xy 298.088391 -381.28016) (xy 298.080604 -381.261374) (xy 298.080176 -381.251206) (xy 298.080176 -381.093472)
			(xy 298.079785 -381.084283) (xy 298.073258 -381.067098) (xy 298.067476 -381.059944) (xy 298.045707 -381.034276)
			(xy 298.007755 -380.978693) (xy 297.976719 -380.918972) (xy 297.953043 -380.855969) (xy 297.937068 -380.790589)
			(xy 297.929022 -380.723767) (xy 297.92902 -380.656463) (xy 294.650981 -380.656463) (xy 294.650979 -380.723828)
			(xy 294.642901 -380.790768) (xy 294.626863 -380.856258) (xy 294.603096 -380.919356) (xy 294.571942 -380.979153)
			(xy 294.53385 -381.034787) (xy 294.511984 -381.060452) (xy 294.506181 -381.067593) (xy 294.499671 -381.084787)
			(xy 294.499284 -381.09398) (xy 294.499284 -381.251206) (xy 294.498779 -381.26133) (xy 294.491054 -381.280047)
			(xy 294.476773 -381.294402) (xy 294.458097 -381.302225) (xy 294.447976 -381.302768) (xy 293.731696 -381.302768)
			(xy 293.721569 -381.302386) (xy 293.70286 -381.294631) (xy 293.688544 -381.280303) (xy 293.680805 -381.261587)
			(xy 293.680388 -381.25146) (xy 293.680388 -381.09398) (xy 293.67999 -381.084791) (xy 293.673468 -381.067607)
			(xy 293.667688 -381.060452) (xy 293.645844 -381.03477) (xy 293.607756 -380.979138) (xy 293.576605 -380.919344)
			(xy 293.55284 -380.856249) (xy 293.536803 -380.790762) (xy 293.528726 -380.723826) (xy 293.528724 -380.656404)
			(xy 290.250654 -380.656404) (xy 290.250661 -380.656462) (xy 290.25066 -380.723768) (xy 290.242614 -380.790591)
			(xy 290.22664 -380.855974) (xy 290.202966 -380.918979) (xy 290.171933 -380.978704) (xy 290.133984 -381.034291)
			(xy 290.112196 -381.059944) (xy 290.106398 -381.067088) (xy 290.099884 -381.084279) (xy 290.099496 -381.093472)
			(xy 290.099496 -381.251206) (xy 290.098972 -381.26136) (xy 290.091202 -381.280123) (xy 290.076846 -381.294486)
			(xy 290.058088 -381.302267) (xy 290.047934 -381.302768) (xy 289.331654 -381.302768) (xy 289.321494 -381.302304)
			(xy 289.302725 -381.294516) (xy 289.288362 -381.280141) (xy 289.280588 -381.261366) (xy 289.280092 -381.251206)
			(xy 289.280092 -381.093472) (xy 289.279697 -381.084283) (xy 289.273173 -381.067099) (xy 289.267392 -381.059944)
			(xy 289.245622 -381.034276) (xy 289.207669 -380.978693) (xy 289.176632 -380.918972) (xy 289.152956 -380.85597)
			(xy 289.13698 -380.790589) (xy 289.128934 -380.723767) (xy 289.128932 -380.656463) (xy 272.92786 -380.656463)
			(xy 272.867822 -380.687974) (xy 272.746027 -380.742789) (xy 272.621144 -380.790151) (xy 272.49363 -380.829886)
			(xy 272.363949 -380.861849) (xy 272.232575 -380.885924) (xy 272.099987 -380.902024) (xy 271.966669 -380.910088)
			(xy 271.833107 -380.910088) (xy 271.699789 -380.902024) (xy 271.567201 -380.885924) (xy 271.435827 -380.861849)
			(xy 271.306146 -380.829886) (xy 271.178632 -380.790151) (xy 271.053749 -380.742789) (xy 270.931954 -380.687974)
			(xy 270.813691 -380.625904) (xy 270.699392 -380.556808) (xy 270.589472 -380.480936) (xy 270.484335 -380.398566)
			(xy 270.384362 -380.309998) (xy 270.28992 -380.215556) (xy 270.201352 -380.115583) (xy 270.118982 -380.010446)
			(xy 270.04311 -379.900526) (xy 269.974014 -379.786227) (xy 269.911944 -379.667964) (xy 269.857129 -379.546169)
			(xy 269.809767 -379.421286) (xy 269.770032 -379.293772) (xy 269.738069 -379.164091) (xy 269.713994 -379.032717)
			(xy 269.697894 -378.900129) (xy 269.68983 -378.766811) (xy 262.508217 -378.766811) (xy 262.561832 -378.820426)
			(xy 262.579147 -378.8384) (xy 262.608475 -378.878779) (xy 262.631125 -378.92325) (xy 262.646539 -378.970716)
			(xy 262.654337 -379.020009) (xy 262.654796 -379.044962) (xy 262.654796 -382.223705) (xy 286.928753 -382.223705)
			(xy 286.928754 -382.15628) (xy 286.936832 -382.08934) (xy 286.95287 -382.02385) (xy 286.976638 -381.960752)
			(xy 287.007792 -381.900956) (xy 287.045886 -381.845322) (xy 287.067752 -381.819658) (xy 287.073555 -381.812518)
			(xy 287.080065 -381.795323) (xy 287.080452 -381.78613) (xy 287.080452 -381.628904) (xy 287.080987 -381.618801)
			(xy 287.088715 -381.600133) (xy 287.102996 -381.585839) (xy 287.121658 -381.578096) (xy 287.13176 -381.577596)
			(xy 287.84804 -381.577596) (xy 287.858151 -381.578052) (xy 287.876829 -381.585802) (xy 287.891122 -381.600108)
			(xy 287.898856 -381.618793) (xy 287.899348 -381.628904) (xy 287.899348 -381.78613) (xy 287.899755 -381.795317)
			(xy 287.906272 -381.812501) (xy 287.912048 -381.819658) (xy 287.933904 -381.84533) (xy 287.971996 -381.900963)
			(xy 288.00315 -381.960757) (xy 288.026917 -382.023853) (xy 288.042955 -382.089342) (xy 288.051033 -382.156281)
			(xy 288.051034 -382.223645) (xy 291.329073 -382.223645) (xy 291.329074 -382.15634) (xy 291.337119 -382.089516)
			(xy 291.353093 -382.024133) (xy 291.376767 -381.961128) (xy 291.407801 -381.901405) (xy 291.445751 -381.845818)
			(xy 291.46754 -381.820166) (xy 291.473339 -381.813022) (xy 291.479851 -381.795831) (xy 291.48024 -381.786638)
			(xy 291.48024 -381.628904) (xy 291.48062 -381.618777) (xy 291.488375 -381.600066) (xy 291.502703 -381.58575)
			(xy 291.52142 -381.578012) (xy 291.531548 -381.577596) (xy 292.248082 -381.577596) (xy 292.258202 -381.57814)
			(xy 292.276915 -381.585854) (xy 292.29127 -381.600122) (xy 292.299098 -381.618787) (xy 292.299644 -381.628904)
			(xy 292.299644 -381.786638) (xy 292.300049 -381.795826) (xy 292.306568 -381.813009) (xy 292.312344 -381.820166)
			(xy 292.334122 -381.845826) (xy 292.372072 -381.901411) (xy 292.403107 -381.961133) (xy 292.426781 -382.024137)
			(xy 292.442755 -382.089518) (xy 292.450801 -382.15634) (xy 292.450801 -382.223645) (xy 292.450794 -382.223705)
			(xy 295.728841 -382.223705) (xy 295.728842 -382.15628) (xy 295.73692 -382.08934) (xy 295.752957 -382.02385)
			(xy 295.776724 -381.960753) (xy 295.807878 -381.900957) (xy 295.84597 -381.845323) (xy 295.867836 -381.819658)
			(xy 295.873637 -381.812516) (xy 295.880148 -381.795323) (xy 295.880536 -381.78613) (xy 295.880536 -381.628904)
			(xy 295.88092 -381.618777) (xy 295.888674 -381.600067) (xy 295.903001 -381.585751) (xy 295.921717 -381.578012)
			(xy 295.931844 -381.577596) (xy 296.648124 -381.577596) (xy 296.658234 -381.578065) (xy 296.676912 -381.58581)
			(xy 296.691206 -381.600112) (xy 296.69894 -381.618794) (xy 296.699432 -381.628904) (xy 296.699432 -381.78613)
			(xy 296.699843 -381.795317) (xy 296.706358 -381.8125) (xy 296.712132 -381.819658) (xy 296.733985 -381.845332)
			(xy 296.772072 -381.900966) (xy 296.803221 -381.960761) (xy 296.826985 -382.023857) (xy 296.84302 -382.089345)
			(xy 296.851096 -382.156281) (xy 296.851097 -382.223704) (xy 296.851097 -382.223705) (xy 300.128632 -382.223705)
			(xy 300.128633 -382.15628) (xy 300.13671 -382.089341) (xy 300.152748 -382.023851) (xy 300.176514 -381.960753)
			(xy 300.207667 -381.900957) (xy 300.245759 -381.845323) (xy 300.267624 -381.819658) (xy 300.273424 -381.812515)
			(xy 300.279936 -381.795323) (xy 300.280324 -381.78613) (xy 300.280324 -381.628904) (xy 300.28072 -381.618779)
			(xy 300.288471 -381.600071) (xy 300.302794 -381.585755) (xy 300.321507 -381.578014) (xy 300.331632 -381.577596)
			(xy 301.047912 -381.577596) (xy 301.058021 -381.578075) (xy 301.076699 -381.585816) (xy 301.090993 -381.600115)
			(xy 301.098728 -381.618795) (xy 301.09922 -381.628904) (xy 301.09922 -381.78613) (xy 301.099611 -381.795319)
			(xy 301.106138 -381.812504) (xy 301.11192 -381.819658) (xy 301.133773 -381.845332) (xy 301.171861 -381.900965)
			(xy 301.203011 -381.960761) (xy 301.226775 -382.023856) (xy 301.242811 -382.089344) (xy 301.250887 -382.156281)
			(xy 301.250888 -382.223646) (xy 330.929191 -382.223646) (xy 330.929192 -382.156339) (xy 330.937238 -382.089516)
			(xy 330.953213 -382.024133) (xy 330.976888 -381.961128) (xy 331.007923 -381.901404) (xy 331.045875 -381.845818)
			(xy 331.067664 -381.820166) (xy 331.073465 -381.813025) (xy 331.079975 -381.795831) (xy 331.080364 -381.786638)
			(xy 331.080364 -381.628904) (xy 331.080824 -381.618755) (xy 331.088612 -381.600009) (xy 331.102996 -381.585687)
			(xy 331.121775 -381.577981) (xy 331.131926 -381.577596) (xy 331.848206 -381.577596) (xy 331.858328 -381.57812)
			(xy 331.877041 -381.585842) (xy 331.891395 -381.600116) (xy 331.899222 -381.618785) (xy 331.899768 -381.628904)
			(xy 331.899768 -381.786638) (xy 331.900167 -381.795826) (xy 331.906689 -381.81301) (xy 331.912468 -381.820166)
			(xy 331.934246 -381.845826) (xy 331.972195 -381.901412) (xy 332.003228 -381.961134) (xy 332.026901 -382.024138)
			(xy 332.042874 -382.089519) (xy 332.050919 -382.15634) (xy 332.05092 -382.223645) (xy 332.050913 -382.223704)
			(xy 335.328984 -382.223704) (xy 335.328985 -382.156281) (xy 335.337061 -382.089342) (xy 335.353096 -382.023853)
			(xy 335.37686 -381.960756) (xy 335.40801 -381.900959) (xy 335.446097 -381.845324) (xy 335.46796 -381.819658)
			(xy 335.473764 -381.812519) (xy 335.480273 -381.795323) (xy 335.48066 -381.78613) (xy 335.48066 -381.628904)
			(xy 335.481187 -381.6188) (xy 335.488916 -381.60013) (xy 335.5032 -381.585837) (xy 335.521865 -381.578095)
			(xy 335.531968 -381.577596) (xy 336.248248 -381.577596) (xy 336.258359 -381.578046) (xy 336.277038 -381.585799)
			(xy 336.291331 -381.600106) (xy 336.299064 -381.618792) (xy 336.299556 -381.628904) (xy 336.299556 -381.78613)
			(xy 336.299962 -381.795317) (xy 336.30648 -381.812501) (xy 336.312256 -381.819658) (xy 336.334112 -381.845331)
			(xy 336.372204 -381.900963) (xy 336.403357 -381.960758) (xy 336.427124 -382.023854) (xy 336.443161 -382.089342)
			(xy 336.451239 -382.156281) (xy 336.45124 -382.223645) (xy 339.729279 -382.223645) (xy 339.72928 -382.156339)
			(xy 339.737325 -382.089516) (xy 339.753299 -382.024133) (xy 339.776974 -381.961128) (xy 339.808009 -381.901404)
			(xy 339.845959 -381.845818) (xy 339.867748 -381.820166) (xy 339.873547 -381.813023) (xy 339.880059 -381.795831)
			(xy 339.880448 -381.786638) (xy 339.880448 -381.628904) (xy 339.880924 -381.618757) (xy 339.888708 -381.600014)
			(xy 339.903088 -381.585693) (xy 339.921861 -381.577984) (xy 339.93201 -381.577596) (xy 340.64829 -381.577596)
			(xy 340.658411 -381.578133) (xy 340.677123 -381.58585) (xy 340.691478 -381.60012) (xy 340.699306 -381.618786)
			(xy 340.699852 -381.628904) (xy 340.699852 -381.786638) (xy 340.700255 -381.795826) (xy 340.706775 -381.813009)
			(xy 340.712552 -381.820166) (xy 340.73433 -381.845826) (xy 340.77228 -381.901411) (xy 340.803314 -381.961134)
			(xy 340.826988 -382.024137) (xy 340.842962 -382.089518) (xy 340.851007 -382.15634) (xy 340.851007 -382.223645)
			(xy 344.12907 -382.223645) (xy 344.129071 -382.15634) (xy 344.137116 -382.089516) (xy 344.15309 -382.024134)
			(xy 344.176764 -381.961129) (xy 344.207798 -381.901405) (xy 344.245748 -381.845818) (xy 344.267536 -381.820166)
			(xy 344.273334 -381.813022) (xy 344.279847 -381.79583) (xy 344.280236 -381.786638) (xy 344.280236 -381.628904)
			(xy 344.280626 -381.618746) (xy 344.288427 -381.599986) (xy 344.302834 -381.585662) (xy 344.321637 -381.577968)
			(xy 344.331798 -381.577596) (xy 345.048078 -381.577596) (xy 345.058198 -381.578143) (xy 345.07691 -381.585856)
			(xy 345.091266 -381.600123) (xy 345.099094 -381.618787) (xy 345.09964 -381.628904) (xy 345.09964 -381.786638)
			(xy 345.100045 -381.795825) (xy 345.106564 -381.813009) (xy 345.11234 -381.820166) (xy 345.134118 -381.845826)
			(xy 345.172069 -381.901411) (xy 345.203104 -381.961133) (xy 345.226778 -382.024137) (xy 345.242752 -382.089518)
			(xy 345.250798 -382.15634) (xy 345.250798 -382.223645) (xy 345.250798 -382.223646) (xy 374.9291 -382.223646)
			(xy 374.929101 -382.156339) (xy 374.937147 -382.089515) (xy 374.953122 -382.024132) (xy 374.976798 -381.961127)
			(xy 375.007834 -381.901404) (xy 375.045787 -381.845818) (xy 375.067576 -381.820166) (xy 375.073367 -381.813016)
			(xy 375.079886 -381.795829) (xy 375.080276 -381.786638) (xy 375.080276 -381.628904) (xy 375.080724 -381.618753)
			(xy 375.088514 -381.600005) (xy 375.102902 -381.585683) (xy 375.121685 -381.577979) (xy 375.131838 -381.577596)
			(xy 375.848118 -381.577596) (xy 375.85824 -381.57811) (xy 375.876954 -381.585836) (xy 375.891308 -381.600113)
			(xy 375.899134 -381.618784) (xy 375.89968 -381.628904) (xy 375.89968 -381.786638) (xy 375.900076 -381.795827)
			(xy 375.9066 -381.813011) (xy 375.91238 -381.820166) (xy 375.934157 -381.845826) (xy 375.972105 -381.901412)
			(xy 376.003138 -381.961135) (xy 376.02681 -382.024138) (xy 376.042784 -382.089519) (xy 376.050828 -382.156341)
			(xy 376.050829 -382.223644) (xy 376.050822 -382.223704) (xy 379.328893 -382.223704) (xy 379.328894 -382.156281)
			(xy 379.33697 -382.089342) (xy 379.353006 -382.023853) (xy 379.37677 -381.960756) (xy 379.40792 -381.900959)
			(xy 379.446008 -381.845324) (xy 379.467872 -381.819658) (xy 379.473678 -381.81252) (xy 379.480185 -381.795324)
			(xy 379.480572 -381.78613) (xy 379.480572 -381.628904) (xy 379.481088 -381.618799) (xy 379.488819 -381.600126)
			(xy 379.503106 -381.585832) (xy 379.521775 -381.578092) (xy 379.53188 -381.577596) (xy 380.24816 -381.577596)
			(xy 380.258279 -381.578049) (xy 380.276981 -381.585783) (xy 380.291297 -381.600088) (xy 380.299044 -381.618785)
			(xy 380.299468 -381.628904) (xy 380.299468 -381.78613) (xy 380.299871 -381.795318) (xy 380.30639 -381.812502)
			(xy 380.312168 -381.819658) (xy 380.334023 -381.845331) (xy 380.372114 -381.900963) (xy 380.403267 -381.960758)
			(xy 380.427033 -382.023854) (xy 380.443071 -382.089343) (xy 380.451148 -382.156281) (xy 380.451149 -382.223646)
			(xy 383.729188 -382.223646) (xy 383.729189 -382.156339) (xy 383.737235 -382.089516) (xy 383.753209 -382.024133)
			(xy 383.776884 -381.961128) (xy 383.80792 -381.901404) (xy 383.845871 -381.845818) (xy 383.86766 -381.820166)
			(xy 383.873461 -381.813024) (xy 383.879971 -381.795831) (xy 383.88036 -381.786638) (xy 383.88036 -381.628904)
			(xy 383.880824 -381.618755) (xy 383.888611 -381.600011) (xy 383.902994 -381.585689) (xy 383.921771 -381.577981)
			(xy 383.931922 -381.577596) (xy 384.648202 -381.577596) (xy 384.658323 -381.578124) (xy 384.677036 -381.585844)
			(xy 384.691391 -381.600117) (xy 384.699218 -381.618786) (xy 384.699764 -381.628904) (xy 384.699764 -381.786638)
			(xy 384.700164 -381.795826) (xy 384.706686 -381.81301) (xy 384.712464 -381.820166) (xy 384.734242 -381.845826)
			(xy 384.772191 -381.901412) (xy 384.803224 -381.961134) (xy 384.826898 -382.024137) (xy 384.842871 -382.089519)
			(xy 384.850916 -382.15634) (xy 384.850917 -382.223645) (xy 388.128979 -382.223645) (xy 388.12898 -382.156339)
			(xy 388.137025 -382.089516) (xy 388.152999 -382.024133) (xy 388.176674 -381.961128) (xy 388.207709 -381.901404)
			(xy 388.245659 -381.845818) (xy 388.267448 -381.820166) (xy 388.273247 -381.813023) (xy 388.279759 -381.795831)
			(xy 388.280148 -381.786638) (xy 388.280148 -381.628904) (xy 388.280624 -381.618757) (xy 388.288408 -381.600014)
			(xy 388.302788 -381.585693) (xy 388.321561 -381.577984) (xy 388.33171 -381.577596) (xy 389.04799 -381.577596)
			(xy 389.058111 -381.578133) (xy 389.076823 -381.58585) (xy 389.091178 -381.60012) (xy 389.099006 -381.618786)
			(xy 389.099552 -381.628904) (xy 389.099552 -381.786638) (xy 389.099955 -381.795826) (xy 389.106475 -381.813009)
			(xy 389.112252 -381.820166) (xy 389.13403 -381.845826) (xy 389.17198 -381.901411) (xy 389.203014 -381.961134)
			(xy 389.226688 -382.024137) (xy 389.242662 -382.089518) (xy 389.250707 -382.15634) (xy 389.250707 -382.223645)
			(xy 389.250707 -382.223646) (xy 418.92901 -382.223646) (xy 418.92901 -382.156339) (xy 418.937056 -382.089515)
			(xy 418.953032 -382.024132) (xy 418.976708 -381.961127) (xy 419.007745 -381.901403) (xy 419.045698 -381.845818)
			(xy 419.067488 -381.820166) (xy 419.07328 -381.813018) (xy 419.079798 -381.79583) (xy 419.080188 -381.786638)
			(xy 419.080188 -381.628904) (xy 419.080688 -381.618797) (xy 419.088422 -381.600121) (xy 419.102714 -381.585827)
			(xy 419.121389 -381.57809) (xy 419.131496 -381.577596) (xy 419.84803 -381.577596) (xy 419.858153 -381.578101)
			(xy 419.876867 -381.58583) (xy 419.89122 -381.60011) (xy 419.899046 -381.618783) (xy 419.899592 -381.628904)
			(xy 419.899592 -381.786638) (xy 419.899986 -381.795827) (xy 419.906511 -381.813011) (xy 419.912292 -381.820166)
			(xy 419.934069 -381.845827) (xy 419.972016 -381.901413) (xy 420.003048 -381.961135) (xy 420.02672 -382.024139)
			(xy 420.042693 -382.089519) (xy 420.050737 -382.156341) (xy 420.050738 -382.223644) (xy 420.050731 -382.223705)
			(xy 423.328802 -382.223705) (xy 423.328803 -382.15628) (xy 423.33688 -382.089342) (xy 423.352916 -382.023852)
			(xy 423.37668 -381.960755) (xy 423.407831 -381.900959) (xy 423.44592 -381.845324) (xy 423.467784 -381.819658)
			(xy 423.473579 -381.812512) (xy 423.480095 -381.795322) (xy 423.480484 -381.78613) (xy 423.480484 -381.628904)
			(xy 423.480988 -381.618798) (xy 423.488721 -381.600122) (xy 423.503012 -381.585828) (xy 423.521686 -381.57809)
			(xy 423.531792 -381.577596) (xy 424.248072 -381.577596) (xy 424.258192 -381.578039) (xy 424.276895 -381.585777)
			(xy 424.29121 -381.600085) (xy 424.298957 -381.618784) (xy 424.29938 -381.628904) (xy 424.29938 -381.78613)
			(xy 424.29978 -381.795318) (xy 424.306301 -381.812502) (xy 424.31208 -381.819658) (xy 424.333935 -381.845331)
			(xy 424.372025 -381.900964) (xy 424.403177 -381.960759) (xy 424.426943 -382.023855) (xy 424.44298 -382.089343)
			(xy 424.451057 -382.156281) (xy 424.451058 -382.223646) (xy 427.729097 -382.223646) (xy 427.729098 -382.156339)
			(xy 427.737144 -382.089515) (xy 427.753119 -382.024132) (xy 427.776794 -381.961127) (xy 427.807831 -381.901404)
			(xy 427.845783 -381.845818) (xy 427.867572 -381.820166) (xy 427.873374 -381.813025) (xy 427.879883 -381.795831)
			(xy 427.880272 -381.786638) (xy 427.880272 -381.628904) (xy 427.880724 -381.618754) (xy 427.888513 -381.600007)
			(xy 427.9029 -381.585684) (xy 427.921682 -381.577979) (xy 427.931834 -381.577596) (xy 428.648114 -381.577596)
			(xy 428.658236 -381.578114) (xy 428.676949 -381.585838) (xy 428.691303 -381.600114) (xy 428.69913 -381.618785)
			(xy 428.699676 -381.628904) (xy 428.699676 -381.786638) (xy 428.700073 -381.795826) (xy 428.706596 -381.81301)
			(xy 428.712376 -381.820166) (xy 428.734154 -381.845826) (xy 428.772102 -381.901412) (xy 428.803135 -381.961135)
			(xy 428.826807 -382.024138) (xy 428.84278 -382.089519) (xy 428.850825 -382.15634) (xy 428.850826 -382.223644)
			(xy 428.850826 -382.223646) (xy 432.128888 -382.223646) (xy 432.128889 -382.156339) (xy 432.136935 -382.089516)
			(xy 432.152909 -382.024133) (xy 432.176584 -381.961128) (xy 432.20762 -381.901404) (xy 432.245571 -381.845818)
			(xy 432.26736 -381.820166) (xy 432.273161 -381.813024) (xy 432.279671 -381.795831) (xy 432.28006 -381.786638)
			(xy 432.28006 -381.628904) (xy 432.280524 -381.618755) (xy 432.288311 -381.600011) (xy 432.302694 -381.585689)
			(xy 432.321471 -381.577981) (xy 432.331622 -381.577596) (xy 433.047902 -381.577596) (xy 433.058023 -381.578124)
			(xy 433.076736 -381.585844) (xy 433.091091 -381.600117) (xy 433.098918 -381.618786) (xy 433.099464 -381.628904)
			(xy 433.099464 -381.786638) (xy 433.099864 -381.795826) (xy 433.106386 -381.81301) (xy 433.112164 -381.820166)
			(xy 433.133942 -381.845826) (xy 433.171891 -381.901412) (xy 433.202924 -381.961134) (xy 433.226598 -382.024137)
			(xy 433.242571 -382.089519) (xy 433.250616 -382.15634) (xy 433.250617 -382.223645) (xy 433.242574 -382.290466)
			(xy 433.226602 -382.355848) (xy 433.202931 -382.418852) (xy 433.171899 -382.478576) (xy 433.133951 -382.534162)
			(xy 433.112164 -382.559814) (xy 433.106374 -382.566964) (xy 433.099856 -382.584151) (xy 433.099464 -382.593342)
			(xy 433.099464 -383.086864) (xy 433.0999 -383.096048) (xy 433.106397 -383.113232) (xy 433.112164 -383.120392)
			(xy 433.133967 -383.146031) (xy 433.171916 -383.20162) (xy 433.202948 -383.261345) (xy 433.226386 -383.323727)
			(xy 434.32903 -383.323727) (xy 434.329034 -383.256419) (xy 434.337081 -383.189595) (xy 434.353057 -383.124211)
			(xy 434.376732 -383.061205) (xy 434.407768 -383.00148) (xy 434.445719 -382.945893) (xy 434.467508 -382.92024)
			(xy 434.473313 -382.913101) (xy 434.479823 -382.895906) (xy 434.480208 -382.886712) (xy 434.480208 -382.728724)
			(xy 434.480641 -382.71857) (xy 434.48843 -382.699817) (xy 434.502824 -382.685492) (xy 434.521614 -382.677793)
			(xy 434.53177 -382.677416) (xy 435.24805 -382.677416) (xy 435.258171 -382.677967) (xy 435.276886 -382.685674)
			(xy 435.291243 -382.69994) (xy 435.299068 -382.718607) (xy 435.299612 -382.728724) (xy 435.299612 -382.886712)
			(xy 435.300014 -382.8959) (xy 435.306533 -382.913084) (xy 435.312312 -382.92024) (xy 435.334066 -382.945921)
			(xy 435.372019 -383.001502) (xy 435.403056 -383.061221) (xy 435.426733 -383.124222) (xy 435.44271 -383.189601)
			(xy 435.450758 -383.256421) (xy 435.450761 -383.323724) (xy 435.44272 -383.390546) (xy 435.426749 -383.455926)
			(xy 435.403079 -383.518929) (xy 435.372047 -383.578652) (xy 435.334099 -383.634237) (xy 435.312312 -383.659888)
			(xy 435.306497 -383.66702) (xy 435.299993 -383.684221) (xy 435.299612 -383.693416) (xy 435.299612 -384.186684)
			(xy 435.300027 -384.195871) (xy 435.306537 -384.213055) (xy 435.312312 -384.220212) (xy 435.334137 -384.245834)
			(xy 435.372087 -384.301424) (xy 435.403122 -384.361151) (xy 435.426795 -384.42416) (xy 435.442767 -384.489546)
			(xy 435.450809 -384.556373) (xy 435.450805 -384.623681) (xy 435.442757 -384.690507) (xy 435.426779 -384.755892)
			(xy 435.4031 -384.818898) (xy 435.37206 -384.878623) (xy 435.334103 -384.934208) (xy 435.312312 -384.95986)
			(xy 435.306509 -384.967001) (xy 435.299998 -384.984195) (xy 435.299612 -384.993388) (xy 435.299612 -385.151376)
			(xy 435.299159 -385.161527) (xy 435.291374 -385.180277) (xy 435.276987 -385.194601) (xy 435.258203 -385.202303)
			(xy 435.24805 -385.202684) (xy 434.53177 -385.202684) (xy 434.521644 -385.202199) (xy 434.502927 -385.194466)
			(xy 434.488573 -385.180179) (xy 434.48075 -385.161499) (xy 434.480208 -385.151376) (xy 434.480208 -384.993388)
			(xy 434.479802 -384.9842) (xy 434.473285 -384.967016) (xy 434.467508 -384.95986) (xy 434.445757 -384.934178)
			(xy 434.407809 -384.878595) (xy 434.376776 -384.818876) (xy 434.353102 -384.755875) (xy 434.337128 -384.690497)
			(xy 434.329081 -384.623678) (xy 434.329078 -384.556376) (xy 434.337118 -384.489557) (xy 434.353086 -384.424177)
			(xy 434.376753 -384.361174) (xy 434.407781 -384.301451) (xy 434.445723 -384.245864) (xy 434.467508 -384.220212)
			(xy 434.473325 -384.213082) (xy 434.479827 -384.19588) (xy 434.480208 -384.186684) (xy 434.480208 -383.693416)
			(xy 434.479788 -383.68423) (xy 434.473281 -383.667046) (xy 434.467508 -383.659888) (xy 434.445686 -383.634265)
			(xy 434.40774 -383.578673) (xy 434.37671 -383.518945) (xy 434.353041 -383.455937) (xy 434.337071 -383.390552)
			(xy 434.32903 -383.323727) (xy 433.226386 -383.323727) (xy 433.22662 -383.324351) (xy 433.242592 -383.389735)
			(xy 433.250634 -383.456559) (xy 433.250633 -383.523865) (xy 433.242587 -383.590689) (xy 433.226613 -383.656072)
			(xy 433.202938 -383.719077) (xy 433.171903 -383.778801) (xy 433.133953 -383.834388) (xy 433.112164 -383.86004)
			(xy 433.106363 -383.867182) (xy 433.099852 -383.884375) (xy 433.099464 -383.893568) (xy 433.099464 -384.051556)
			(xy 433.099042 -384.061712) (xy 433.091254 -384.08047) (xy 433.076856 -384.094796) (xy 433.05806 -384.102491)
			(xy 433.047902 -384.102864) (xy 432.331622 -384.102864) (xy 432.321497 -384.102356) (xy 432.302777 -384.094636)
			(xy 432.28842 -384.080356) (xy 432.2806 -384.061678) (xy 432.28006 -384.051556) (xy 432.28006 -383.893568)
			(xy 432.279652 -383.884381) (xy 432.273135 -383.867197) (xy 432.26736 -383.86004) (xy 432.245587 -383.834375)
			(xy 432.207637 -383.778791) (xy 432.176602 -383.719069) (xy 432.152927 -383.656066) (xy 432.136952 -383.590686)
			(xy 432.128907 -383.523864) (xy 432.128905 -383.45656) (xy 432.136948 -383.389738) (xy 432.15292 -383.324357)
			(xy 432.176592 -383.261353) (xy 432.207624 -383.20163) (xy 432.245573 -383.146044) (xy 432.26736 -383.120392)
			(xy 432.27315 -383.113242) (xy 432.279667 -383.096055) (xy 432.28006 -383.086864) (xy 432.28006 -382.593342)
			(xy 432.279616 -382.584159) (xy 432.273125 -382.566975) (xy 432.26736 -382.559814) (xy 432.245562 -382.53417)
			(xy 432.207612 -382.478583) (xy 432.176578 -382.418858) (xy 432.152905 -382.355853) (xy 432.136932 -382.290469)
			(xy 432.128888 -382.223646) (xy 428.850826 -382.223646) (xy 428.842783 -382.290466) (xy 428.826812 -382.355848)
			(xy 428.803141 -382.418852) (xy 428.772109 -382.478575) (xy 428.734163 -382.534162) (xy 428.712376 -382.559814)
			(xy 428.706588 -382.566965) (xy 428.700069 -382.584151) (xy 428.699676 -382.593342) (xy 428.699676 -383.086864)
			(xy 428.700109 -383.096049) (xy 428.706607 -383.113233) (xy 428.712376 -383.120392) (xy 428.734179 -383.146031)
			(xy 428.772126 -383.20162) (xy 428.803158 -383.261345) (xy 428.826616 -383.323786) (xy 429.928711 -383.323786)
			(xy 429.928714 -383.25636) (xy 429.936794 -383.189418) (xy 429.952834 -383.123927) (xy 429.976603 -383.060829)
			(xy 430.007759 -383.001032) (xy 430.045853 -382.945397) (xy 430.06772 -382.919732) (xy 430.07353 -382.912597)
			(xy 430.080036 -382.895398) (xy 430.08042 -382.886204) (xy 430.08042 -382.728724) (xy 430.080836 -382.718601)
			(xy 430.08858 -382.699894) (xy 430.102897 -382.685578) (xy 430.121605 -382.677835) (xy 430.131728 -382.677416)
			(xy 430.848008 -382.677416) (xy 430.858133 -382.67781) (xy 430.87684 -382.685564) (xy 430.891154 -382.699887)
			(xy 430.898896 -382.718599) (xy 430.899316 -382.728724) (xy 430.899316 -382.886204) (xy 430.899721 -382.895392)
			(xy 430.906238 -382.912576) (xy 430.912016 -382.919732) (xy 430.933844 -382.945427) (xy 430.971933 -383.001057)
			(xy 431.003084 -383.06085) (xy 431.02685 -383.123943) (xy 431.042887 -383.189428) (xy 431.050966 -383.256363)
			(xy 431.050969 -383.323783) (xy 431.042897 -383.390719) (xy 431.026866 -383.456206) (xy 431.003106 -383.519301)
			(xy 430.971961 -383.579096) (xy 430.933877 -383.634731) (xy 430.912016 -383.660396) (xy 430.90624 -383.667556)
			(xy 430.899713 -383.684735) (xy 430.899316 -383.693924) (xy 430.899316 -384.186176) (xy 430.899734 -384.195362)
			(xy 430.906242 -384.212547) (xy 430.912016 -384.219704) (xy 430.933915 -384.24534) (xy 430.972001 -384.300979)
			(xy 431.00315 -384.36078) (xy 431.026911 -384.42388) (xy 431.042944 -384.489373) (xy 431.051016 -384.556314)
			(xy 431.051013 -384.62374) (xy 431.042934 -384.690681) (xy 431.026895 -384.756171) (xy 431.003128 -384.81927)
			(xy 430.971974 -384.879067) (xy 430.933882 -384.934702) (xy 430.912016 -384.960368) (xy 430.90621 -384.967507)
			(xy 430.8997 -384.984702) (xy 430.899316 -384.993896) (xy 430.899316 -385.151376) (xy 430.898865 -385.161495)
			(xy 430.891128 -385.180195) (xy 430.876822 -385.19451) (xy 430.858127 -385.202259) (xy 430.848008 -385.202684)
			(xy 430.131728 -385.202684) (xy 430.121605 -385.202261) (xy 430.102899 -385.194519) (xy 430.088583 -385.180204)
			(xy 430.08084 -385.161499) (xy 430.08042 -385.151376) (xy 430.08042 -384.993896) (xy 430.080008 -384.984709)
			(xy 430.073495 -384.967525) (xy 430.06772 -384.960368) (xy 430.045891 -384.934674) (xy 430.0078 -384.879044)
			(xy 429.976646 -384.819252) (xy 429.952879 -384.756159) (xy 429.936841 -384.690673) (xy 429.928761 -384.623738)
			(xy 429.928758 -384.556316) (xy 429.936831 -384.48938) (xy 429.952863 -384.423893) (xy 429.976624 -384.360797)
			(xy 430.007772 -384.301002) (xy 430.045857 -384.245369) (xy 430.06772 -384.219704) (xy 430.0735 -384.212547)
			(xy 430.080024 -384.195365) (xy 430.08042 -384.186176) (xy 430.08042 -383.693924) (xy 430.079994 -383.684739)
			(xy 430.073491 -383.667554) (xy 430.06772 -383.660396) (xy 430.04582 -383.63476) (xy 430.007731 -383.579122)
			(xy 429.976581 -383.519322) (xy 429.952818 -383.456221) (xy 429.936784 -383.390728) (xy 429.928711 -383.323786)
			(xy 428.826616 -383.323786) (xy 428.826829 -383.324352) (xy 428.842801 -383.389735) (xy 428.850843 -383.456559)
			(xy 428.850842 -383.523865) (xy 428.842797 -383.590688) (xy 428.826822 -383.656071) (xy 428.803148 -383.719077)
			(xy 428.772114 -383.778801) (xy 428.734164 -383.834388) (xy 428.712376 -383.86004) (xy 428.706577 -383.867183)
			(xy 428.700065 -383.884375) (xy 428.699676 -383.893568) (xy 428.699676 -384.051556) (xy 428.699242 -384.06171)
			(xy 428.691456 -384.080466) (xy 428.677063 -384.094792) (xy 428.65827 -384.102489) (xy 428.648114 -384.102864)
			(xy 427.931834 -384.102864) (xy 427.92171 -384.102345) (xy 427.90299 -384.09463) (xy 427.888633 -384.080353)
			(xy 427.880812 -384.061677) (xy 427.880272 -384.051556) (xy 427.880272 -383.893568) (xy 427.879883 -383.884378)
			(xy 427.873355 -383.867194) (xy 427.867572 -383.86004) (xy 427.845799 -383.834375) (xy 427.807848 -383.778791)
			(xy 427.776812 -383.71907) (xy 427.753137 -383.656067) (xy 427.737162 -383.590686) (xy 427.729116 -383.523864)
			(xy 427.729114 -383.45656) (xy 427.737157 -383.389738) (xy 427.75313 -383.324356) (xy 427.776802 -383.261352)
			(xy 427.807835 -383.201629) (xy 427.845784 -383.146044) (xy 427.867572 -383.120392) (xy 427.873363 -383.113243)
			(xy 427.879879 -383.096055) (xy 427.880272 -383.086864) (xy 427.880272 -382.593342) (xy 427.879848 -382.584156)
			(xy 427.873344 -382.566971) (xy 427.867572 -382.559814) (xy 427.845774 -382.53417) (xy 427.807823 -382.478583)
			(xy 427.776788 -382.418859) (xy 427.753115 -382.355853) (xy 427.737141 -382.29047) (xy 427.729097 -382.223646)
			(xy 424.451058 -382.223646) (xy 424.451058 -382.223704) (xy 424.442983 -382.290642) (xy 424.426948 -382.356131)
			(xy 424.403184 -382.419227) (xy 424.372033 -382.479023) (xy 424.333944 -382.534657) (xy 424.31208 -382.560322)
			(xy 424.306289 -382.567471) (xy 424.299772 -382.584659) (xy 424.29938 -382.59385) (xy 424.29938 -383.086356)
			(xy 424.299816 -383.09554) (xy 424.306312 -383.112725) (xy 424.31208 -383.119884) (xy 424.33396 -383.145536)
			(xy 424.37205 -383.201172) (xy 424.403201 -383.26097) (xy 424.426837 -383.323727) (xy 425.528942 -383.323727)
			(xy 425.528946 -383.256419) (xy 425.536993 -383.189594) (xy 425.55297 -383.12421) (xy 425.576646 -383.061204)
			(xy 425.607682 -383.00148) (xy 425.645635 -382.945892) (xy 425.667424 -382.92024) (xy 425.673231 -382.913103)
			(xy 425.679739 -382.895906) (xy 425.680124 -382.886712) (xy 425.680124 -382.728724) (xy 425.680536 -382.7186)
			(xy 425.688281 -382.699892) (xy 425.702599 -382.685576) (xy 425.721308 -382.677834) (xy 425.731432 -382.677416)
			(xy 426.447966 -382.677416) (xy 426.458088 -382.677954) (xy 426.476803 -382.685666) (xy 426.49116 -382.699937)
			(xy 426.498984 -382.718606) (xy 426.499528 -382.728724) (xy 426.499528 -382.886712) (xy 426.499926 -382.895901)
			(xy 426.506447 -382.913085) (xy 426.512228 -382.92024) (xy 426.533981 -382.945921) (xy 426.571933 -383.001502)
			(xy 426.60297 -383.061222) (xy 426.626646 -383.124223) (xy 426.642623 -383.189602) (xy 426.65067 -383.256422)
			(xy 426.650673 -383.323724) (xy 426.642632 -383.390545) (xy 426.626662 -383.455926) (xy 426.602992 -383.518929)
			(xy 426.571961 -383.578651) (xy 426.534014 -383.634236) (xy 426.512228 -383.659888) (xy 426.506403 -383.667013)
			(xy 426.499907 -383.684219) (xy 426.499528 -383.693416) (xy 426.499528 -384.186684) (xy 426.499939 -384.195871)
			(xy 426.506451 -384.213056) (xy 426.512228 -384.220212) (xy 426.534052 -384.245834) (xy 426.572002 -384.301424)
			(xy 426.603036 -384.361152) (xy 426.626708 -384.42416) (xy 426.64268 -384.489546) (xy 426.650721 -384.556373)
			(xy 426.650718 -384.623681) (xy 426.64267 -384.690507) (xy 426.626692 -384.755892) (xy 426.603014 -384.818898)
			(xy 426.571974 -384.878622) (xy 426.534019 -384.934208) (xy 426.512228 -384.95986) (xy 426.506415 -384.966993)
			(xy 426.499912 -384.984193) (xy 426.499528 -384.993388) (xy 426.499528 -385.151376) (xy 426.499065 -385.161494)
			(xy 426.49133 -385.180191) (xy 426.477028 -385.194505) (xy 426.458337 -385.202257) (xy 426.44822 -385.202684)
			(xy 425.731686 -385.202684) (xy 425.721561 -385.202185) (xy 425.702845 -385.194457) (xy 425.68849 -385.180175)
			(xy 425.680667 -385.161498) (xy 425.680124 -385.151376) (xy 425.680124 -384.993388) (xy 425.679714 -384.984201)
			(xy 425.6732 -384.967017) (xy 425.667424 -384.95986) (xy 425.645672 -384.934178) (xy 425.607723 -384.878596)
			(xy 425.576689 -384.818876) (xy 425.553015 -384.755876) (xy 425.53704 -384.690497) (xy 425.528994 -384.623678)
			(xy 425.52899 -384.556376) (xy 425.537031 -384.489556) (xy 425.552999 -384.424176) (xy 425.576667 -384.361173)
			(xy 425.607696 -384.301451) (xy 425.645639 -384.245865) (xy 425.667424 -384.220212) (xy 425.673243 -384.213083)
			(xy 425.679744 -384.19588) (xy 425.680124 -384.186684) (xy 425.680124 -383.693416) (xy 425.679701 -383.68423)
			(xy 425.673195 -383.667046) (xy 425.667424 -383.659888) (xy 425.645601 -383.634265) (xy 425.607655 -383.578674)
			(xy 425.576624 -383.518946) (xy 425.552954 -383.455938) (xy 425.536984 -383.390552) (xy 425.528942 -383.323727)
			(xy 424.426837 -383.323727) (xy 424.426965 -383.324068) (xy 424.443 -383.389559) (xy 424.451075 -383.456499)
			(xy 424.451074 -383.523925) (xy 424.442996 -383.590864) (xy 424.426958 -383.656355) (xy 424.403191 -383.719452)
			(xy 424.372038 -383.779249) (xy 424.333946 -383.834883) (xy 424.31208 -383.860548) (xy 424.306278 -383.867689)
			(xy 424.299767 -383.884883) (xy 424.29938 -383.894076) (xy 424.29938 -384.051556) (xy 424.298947 -384.061678)
			(xy 424.29121 -384.080385) (xy 424.276898 -384.094701) (xy 424.258194 -384.102444) (xy 424.248072 -384.102864)
			(xy 423.531792 -384.102864) (xy 423.521665 -384.10249) (xy 423.502954 -384.094732) (xy 423.488639 -384.080402)
			(xy 423.4809 -384.061684) (xy 423.480484 -384.051556) (xy 423.480484 -383.894076) (xy 423.480089 -383.884887)
			(xy 423.473565 -383.867703) (xy 423.467784 -383.860548) (xy 423.445936 -383.83487) (xy 423.407848 -383.779237)
			(xy 423.376698 -383.719442) (xy 423.352933 -383.656347) (xy 423.336897 -383.59086) (xy 423.32882 -383.523923)
			(xy 423.328819 -383.456501) (xy 423.336893 -383.389564) (xy 423.352926 -383.324076) (xy 423.376688 -383.26098)
			(xy 423.407836 -383.201184) (xy 423.445922 -383.145549) (xy 423.467784 -383.119884) (xy 423.473568 -383.11273)
			(xy 423.480091 -383.095546) (xy 423.480484 -383.086356) (xy 423.480484 -382.59385) (xy 423.480054 -382.584665)
			(xy 423.473554 -382.56748) (xy 423.467784 -382.560322) (xy 423.445911 -382.534665) (xy 423.407823 -382.479029)
			(xy 423.376674 -382.419231) (xy 423.352911 -382.356133) (xy 423.336877 -382.290643) (xy 423.328802 -382.223705)
			(xy 420.050731 -382.223705) (xy 420.042695 -382.290466) (xy 420.026725 -382.355847) (xy 420.003054 -382.418851)
			(xy 419.972024 -382.478574) (xy 419.934078 -382.534161) (xy 419.912292 -382.559814) (xy 419.906506 -382.566967)
			(xy 419.899985 -382.584151) (xy 419.899592 -382.593342) (xy 419.899592 -383.086864) (xy 419.900021 -383.096049)
			(xy 419.906522 -383.113234) (xy 419.912292 -383.120392) (xy 419.934094 -383.146032) (xy 419.972041 -383.201621)
			(xy 420.003072 -383.261346) (xy 420.02653 -383.323787) (xy 421.128623 -383.323787) (xy 421.128626 -383.256359)
			(xy 421.136706 -383.189418) (xy 421.152747 -383.123926) (xy 421.176516 -383.060828) (xy 421.207673 -383.001031)
			(xy 421.245769 -382.945397) (xy 421.267636 -382.919732) (xy 421.273449 -382.912598) (xy 421.279953 -382.895399)
			(xy 421.280336 -382.886204) (xy 421.280336 -382.728724) (xy 421.280736 -382.718599) (xy 421.288483 -382.699889)
			(xy 421.302805 -382.685572) (xy 421.321518 -382.677832) (xy 421.331644 -382.677416) (xy 422.047924 -382.677416)
			(xy 422.058036 -382.677866) (xy 422.076718 -382.685614) (xy 422.091013 -382.699922) (xy 422.098744 -382.718611)
			(xy 422.099232 -382.728724) (xy 422.099232 -382.886204) (xy 422.099656 -382.895389) (xy 422.106162 -382.912573)
			(xy 422.111932 -382.919732) (xy 422.133759 -382.945427) (xy 422.171847 -383.001058) (xy 422.202998 -383.06085)
			(xy 422.226762 -383.123943) (xy 422.242799 -383.189428) (xy 422.250878 -383.256363) (xy 422.250881 -383.323783)
			(xy 422.242809 -383.390718) (xy 422.226778 -383.456205) (xy 422.20302 -383.5193) (xy 422.171875 -383.579096)
			(xy 422.133793 -383.63473) (xy 422.111932 -383.660396) (xy 422.106146 -383.667549) (xy 422.099627 -383.684734)
			(xy 422.099232 -383.693924) (xy 422.099232 -384.186176) (xy 422.099669 -384.19536) (xy 422.106166 -384.212544)
			(xy 422.111932 -384.219704) (xy 422.13383 -384.245341) (xy 422.171916 -384.30098) (xy 422.203063 -384.36078)
			(xy 422.226824 -384.423881) (xy 422.242856 -384.489373) (xy 422.250928 -384.556314) (xy 422.250925 -384.62374)
			(xy 422.242846 -384.69068) (xy 422.226808 -384.756171) (xy 422.203041 -384.819269) (xy 422.171888 -384.879066)
			(xy 422.133797 -384.934702) (xy 422.111932 -384.960368) (xy 422.106116 -384.967499) (xy 422.099615 -384.984701)
			(xy 422.099232 -384.993896) (xy 422.099232 -385.151376) (xy 422.098696 -385.161479) (xy 422.090972 -385.180151)
			(xy 422.076691 -385.194445) (xy 422.058027 -385.202187) (xy 422.047924 -385.202684) (xy 421.331644 -385.202684)
			(xy 421.321522 -385.202247) (xy 421.302817 -385.194511) (xy 421.2885 -385.1802) (xy 421.280756 -385.161497)
			(xy 421.280336 -385.151376) (xy 421.280336 -384.993896) (xy 421.27992 -384.98471) (xy 421.27341 -384.967526)
			(xy 421.267636 -384.960368) (xy 421.245806 -384.934674) (xy 421.207714 -384.879045) (xy 421.17656 -384.819253)
			(xy 421.152792 -384.756159) (xy 421.136753 -384.690673) (xy 421.128674 -384.623738) (xy 421.12867 -384.556316)
			(xy 421.136743 -384.48938) (xy 421.152776 -384.423892) (xy 421.176538 -384.360797) (xy 421.207686 -384.301002)
			(xy 421.245773 -384.245369) (xy 421.267636 -384.219704) (xy 421.273418 -384.212549) (xy 421.27994 -384.195366)
			(xy 421.280336 -384.186176) (xy 421.280336 -383.693924) (xy 421.279906 -383.684739) (xy 421.273405 -383.667555)
			(xy 421.267636 -383.660396) (xy 421.245735 -383.634761) (xy 421.207645 -383.579123) (xy 421.176494 -383.519323)
			(xy 421.152731 -383.456222) (xy 421.136696 -383.390729) (xy 421.128623 -383.323787) (xy 420.02653 -383.323787)
			(xy 420.026742 -383.324352) (xy 420.042713 -383.389736) (xy 420.050756 -383.456559) (xy 420.050754 -383.523865)
			(xy 420.042709 -383.590688) (xy 420.026735 -383.656071) (xy 420.003062 -383.719076) (xy 419.972028 -383.7788)
			(xy 419.93408 -383.834387) (xy 419.912292 -383.86004) (xy 419.906495 -383.867185) (xy 419.899981 -383.884376)
			(xy 419.899592 -383.893568) (xy 419.899592 -384.051556) (xy 419.899148 -384.061677) (xy 419.891413 -384.080381)
			(xy 419.877104 -384.094697) (xy 419.858404 -384.102442) (xy 419.848284 -384.102864) (xy 419.13175 -384.102864)
			(xy 419.121627 -384.102333) (xy 419.102908 -384.094622) (xy 419.08855 -384.080349) (xy 419.080728 -384.061676)
			(xy 419.080188 -384.051556) (xy 419.080188 -383.893568) (xy 419.079796 -383.884379) (xy 419.07327 -383.867194)
			(xy 419.067488 -383.86004) (xy 419.045715 -383.834376) (xy 419.007762 -383.778792) (xy 418.976725 -383.719071)
			(xy 418.95305 -383.656068) (xy 418.937074 -383.590686) (xy 418.929028 -383.523864) (xy 418.929026 -383.45656)
			(xy 418.93707 -383.389737) (xy 418.953042 -383.324355) (xy 418.976716 -383.261351) (xy 419.00775 -383.201629)
			(xy 419.0457 -383.146043) (xy 419.067488 -383.120392) (xy 419.073269 -383.113236) (xy 419.079793 -383.096054)
			(xy 419.080188 -383.086864) (xy 419.080188 -382.593342) (xy 419.07976 -382.584157) (xy 419.073259 -382.566972)
			(xy 419.067488 -382.559814) (xy 419.045689 -382.534171) (xy 419.007737 -382.478584) (xy 418.976702 -382.41886)
			(xy 418.953027 -382.355854) (xy 418.937054 -382.29047) (xy 418.92901 -382.223646) (xy 389.250707 -382.223646)
			(xy 389.242664 -382.290467) (xy 389.226692 -382.355848) (xy 389.20302 -382.418853) (xy 389.171987 -382.478576)
			(xy 389.134039 -382.534162) (xy 389.112252 -382.559814) (xy 389.106461 -382.566963) (xy 389.099944 -382.584151)
			(xy 389.099552 -382.593342) (xy 389.099552 -383.086864) (xy 389.09999 -383.096048) (xy 389.106485 -383.113232)
			(xy 389.112252 -383.120392) (xy 389.134056 -383.146031) (xy 389.172005 -383.201619) (xy 389.203038 -383.261344)
			(xy 389.226475 -383.323726) (xy 390.329121 -383.323726) (xy 390.329125 -383.256419) (xy 390.337172 -383.189595)
			(xy 390.353147 -383.124211) (xy 390.376822 -383.061206) (xy 390.407857 -383.001481) (xy 390.445807 -382.945893)
			(xy 390.467596 -382.92024) (xy 390.4734 -382.9131) (xy 390.47991 -382.895906) (xy 390.480296 -382.886712)
			(xy 390.480296 -382.728724) (xy 390.480741 -382.718572) (xy 390.488528 -382.699821) (xy 390.502918 -382.685497)
			(xy 390.521704 -382.677795) (xy 390.531858 -382.677416) (xy 391.248138 -382.677416) (xy 391.258264 -382.677895)
			(xy 391.276982 -382.685631) (xy 391.291336 -382.699919) (xy 391.299158 -382.7186) (xy 391.2997 -382.728724)
			(xy 391.2997 -382.886712) (xy 391.300105 -382.8959) (xy 391.306622 -382.913084) (xy 391.3124 -382.92024)
			(xy 391.334151 -382.945922) (xy 391.372099 -383.001505) (xy 391.403131 -383.061225) (xy 391.426804 -383.124225)
			(xy 391.442779 -383.189603) (xy 391.450825 -383.256422) (xy 391.450828 -383.323724) (xy 391.442788 -383.390543)
			(xy 391.42682 -383.455923) (xy 391.403153 -383.518926) (xy 391.372126 -383.578649) (xy 391.334184 -383.634235)
			(xy 391.3124 -383.659888) (xy 391.306584 -383.667019) (xy 391.300081 -383.68422) (xy 391.2997 -383.693416)
			(xy 391.2997 -384.186684) (xy 391.300118 -384.19587) (xy 391.306626 -384.213055) (xy 391.3124 -384.220212)
			(xy 391.334222 -384.245836) (xy 391.372167 -384.301427) (xy 391.403197 -384.361155) (xy 391.426866 -384.424163)
			(xy 391.442835 -384.489548) (xy 391.450876 -384.556374) (xy 391.450872 -384.623681) (xy 391.442825 -384.690505)
			(xy 391.42685 -384.755889) (xy 391.403175 -384.818895) (xy 391.372139 -384.878619) (xy 391.334189 -384.934207)
			(xy 391.3124 -384.95986) (xy 391.306595 -384.967) (xy 391.300086 -384.984194) (xy 391.2997 -384.993388)
			(xy 391.2997 -385.151376) (xy 391.299259 -385.161529) (xy 391.291471 -385.180281) (xy 391.27708 -385.194605)
			(xy 391.258292 -385.202305) (xy 391.248138 -385.202684) (xy 390.531858 -385.202684) (xy 390.521732 -385.202209)
			(xy 390.503014 -385.194471) (xy 390.48866 -385.180182) (xy 390.480838 -385.1615) (xy 390.480296 -385.151376)
			(xy 390.480296 -384.993388) (xy 390.479892 -384.9842) (xy 390.473374 -384.967016) (xy 390.467596 -384.95986)
			(xy 390.445845 -384.934178) (xy 390.407898 -384.878595) (xy 390.376865 -384.818875) (xy 390.353192 -384.755875)
			(xy 390.337218 -384.690496) (xy 390.329172 -384.623678) (xy 390.329169 -384.556376) (xy 390.337209 -384.489557)
			(xy 390.353176 -384.424177) (xy 390.376843 -384.361174) (xy 390.40787 -384.301452) (xy 390.445812 -384.245865)
			(xy 390.467596 -384.220212) (xy 390.473412 -384.21308) (xy 390.479915 -384.19588) (xy 390.480296 -384.186684)
			(xy 390.480296 -383.693416) (xy 390.479879 -383.68423) (xy 390.47337 -383.667045) (xy 390.467596 -383.659888)
			(xy 390.445774 -383.634264) (xy 390.407829 -383.578673) (xy 390.3768 -383.518945) (xy 390.353131 -383.455937)
			(xy 390.337162 -383.390552) (xy 390.329121 -383.323726) (xy 389.226475 -383.323726) (xy 389.22671 -383.324351)
			(xy 389.242682 -383.389735) (xy 389.250725 -383.456559) (xy 389.250724 -383.523865) (xy 389.242678 -383.590689)
			(xy 389.226703 -383.656072) (xy 389.203028 -383.719078) (xy 389.171992 -383.778802) (xy 389.134041 -383.834388)
			(xy 389.112252 -383.86004) (xy 389.10645 -383.867181) (xy 389.09994 -383.884375) (xy 389.099552 -383.893568)
			(xy 389.099552 -384.051556) (xy 389.099043 -384.061701) (xy 389.091272 -384.080442) (xy 389.076902 -384.094765)
			(xy 389.058136 -384.102476) (xy 389.04799 -384.102864) (xy 388.33171 -384.102864) (xy 388.321584 -384.102365)
			(xy 388.302864 -384.094642) (xy 388.288508 -384.080359) (xy 388.280687 -384.061679) (xy 388.280148 -384.051556)
			(xy 388.280148 -383.893568) (xy 388.279742 -383.884381) (xy 388.273224 -383.867197) (xy 388.267448 -383.86004)
			(xy 388.245676 -383.834375) (xy 388.207726 -383.778791) (xy 388.176692 -383.719069) (xy 388.153018 -383.656066)
			(xy 388.137043 -383.590685) (xy 388.128998 -383.523864) (xy 388.128996 -383.45656) (xy 388.137039 -383.389738)
			(xy 388.15301 -383.324357) (xy 388.176682 -383.261353) (xy 388.207714 -383.20163) (xy 388.245661 -383.146044)
			(xy 388.267448 -383.120392) (xy 388.273236 -383.113241) (xy 388.279755 -383.096055) (xy 388.280148 -383.086864)
			(xy 388.280148 -382.593342) (xy 388.279707 -382.584158) (xy 388.273213 -382.566974) (xy 388.267448 -382.559814)
			(xy 388.24565 -382.53417) (xy 388.207701 -382.478583) (xy 388.176668 -382.418858) (xy 388.152995 -382.355852)
			(xy 388.137022 -382.290469) (xy 388.128979 -382.223645) (xy 384.850917 -382.223645) (xy 384.842874 -382.290466)
			(xy 384.826902 -382.355848) (xy 384.803231 -382.418852) (xy 384.772199 -382.478576) (xy 384.734251 -382.534162)
			(xy 384.712464 -382.559814) (xy 384.706674 -382.566964) (xy 384.700156 -382.584151) (xy 384.699764 -382.593342)
			(xy 384.699764 -383.086864) (xy 384.7002 -383.096048) (xy 384.706697 -383.113232) (xy 384.712464 -383.120392)
			(xy 384.734267 -383.146031) (xy 384.772216 -383.20162) (xy 384.803248 -383.261345) (xy 384.826708 -383.323786)
			(xy 385.928802 -383.323786) (xy 385.928805 -383.25636) (xy 385.936885 -383.189419) (xy 385.952924 -383.123928)
			(xy 385.976693 -383.060829) (xy 386.007848 -383.001032) (xy 386.045942 -382.945397) (xy 386.067808 -382.919732)
			(xy 386.073617 -382.912596) (xy 386.080124 -382.895398) (xy 386.080508 -382.886204) (xy 386.080508 -382.728724)
			(xy 386.080936 -382.718602) (xy 386.088677 -382.699897) (xy 386.102991 -382.685582) (xy 386.121694 -382.677837)
			(xy 386.131816 -382.677416) (xy 386.848096 -382.677416) (xy 386.85822 -382.67782) (xy 386.876927 -382.685569)
			(xy 386.891242 -382.69989) (xy 386.898984 -382.7186) (xy 386.899404 -382.728724) (xy 386.899404 -382.886204)
			(xy 386.899811 -382.895391) (xy 386.906327 -382.912576) (xy 386.912104 -382.919732) (xy 386.933932 -382.945426)
			(xy 386.972022 -383.001057) (xy 387.003174 -383.060849) (xy 387.02694 -383.123942) (xy 387.042978 -383.189428)
			(xy 387.051057 -383.256363) (xy 387.05106 -383.323783) (xy 387.042988 -383.390719) (xy 387.026956 -383.456206)
			(xy 387.003196 -383.519301) (xy 386.97205 -383.579097) (xy 386.933966 -383.634731) (xy 386.912104 -383.660396)
			(xy 386.906327 -383.667555) (xy 386.899801 -383.684735) (xy 386.899404 -383.693924) (xy 386.899404 -384.186176)
			(xy 386.899825 -384.195362) (xy 386.906331 -384.212547) (xy 386.912104 -384.219704) (xy 386.934003 -384.24534)
			(xy 386.972091 -384.300979) (xy 387.003239 -384.360779) (xy 387.027001 -384.42388) (xy 387.043034 -384.489372)
			(xy 387.051107 -384.556314) (xy 387.051104 -384.62374) (xy 387.043025 -384.690681) (xy 387.026985 -384.756172)
			(xy 387.003217 -384.81927) (xy 386.972063 -384.879068) (xy 386.93397 -384.934703) (xy 386.912104 -384.960368)
			(xy 386.906297 -384.967506) (xy 386.899788 -384.984702) (xy 386.899404 -384.993896) (xy 386.899404 -385.151376)
			(xy 386.898965 -385.161496) (xy 386.891225 -385.180199) (xy 386.876916 -385.194514) (xy 386.858216 -385.202261)
			(xy 386.848096 -385.202684) (xy 386.131816 -385.202684) (xy 386.121693 -385.202271) (xy 386.102986 -385.194525)
			(xy 386.088671 -385.180207) (xy 386.080928 -385.1615) (xy 386.080508 -385.151376) (xy 386.080508 -384.993896)
			(xy 386.080098 -384.984709) (xy 386.073584 -384.967525) (xy 386.067808 -384.960368) (xy 386.045979 -384.934674)
			(xy 386.007889 -384.879044) (xy 385.976736 -384.819251) (xy 385.95297 -384.756158) (xy 385.936931 -384.690673)
			(xy 385.928852 -384.623738) (xy 385.928849 -384.556317) (xy 385.936922 -384.489381) (xy 385.952954 -384.423893)
			(xy 385.976714 -384.360798) (xy 386.007861 -384.301003) (xy 386.045946 -384.245369) (xy 386.067808 -384.219704)
			(xy 386.073586 -384.212546) (xy 386.080112 -384.195365) (xy 386.080508 -384.186176) (xy 386.080508 -383.693924)
			(xy 386.080084 -383.684738) (xy 386.07358 -383.667554) (xy 386.067808 -383.660396) (xy 386.045908 -383.63476)
			(xy 386.00782 -383.579122) (xy 385.976671 -383.519321) (xy 385.952908 -383.456221) (xy 385.936875 -383.390728)
			(xy 385.928802 -383.323786) (xy 384.826708 -383.323786) (xy 384.82692 -383.324351) (xy 384.842892 -383.389735)
			(xy 384.850934 -383.456559) (xy 384.850933 -383.523865) (xy 384.842887 -383.590689) (xy 384.826913 -383.656072)
			(xy 384.803238 -383.719077) (xy 384.772203 -383.778801) (xy 384.734253 -383.834388) (xy 384.712464 -383.86004)
			(xy 384.706663 -383.867182) (xy 384.700152 -383.884375) (xy 384.699764 -383.893568) (xy 384.699764 -384.051556)
			(xy 384.699342 -384.061712) (xy 384.691554 -384.08047) (xy 384.677156 -384.094796) (xy 384.65836 -384.102491)
			(xy 384.648202 -384.102864) (xy 383.931922 -384.102864) (xy 383.921797 -384.102356) (xy 383.903077 -384.094636)
			(xy 383.88872 -384.080356) (xy 383.8809 -384.061678) (xy 383.88036 -384.051556) (xy 383.88036 -383.893568)
			(xy 383.879952 -383.884381) (xy 383.873435 -383.867197) (xy 383.86766 -383.86004) (xy 383.845887 -383.834375)
			(xy 383.807937 -383.778791) (xy 383.776902 -383.719069) (xy 383.753227 -383.656066) (xy 383.737252 -383.590686)
			(xy 383.729207 -383.523864) (xy 383.729205 -383.45656) (xy 383.737248 -383.389738) (xy 383.75322 -383.324357)
			(xy 383.776892 -383.261353) (xy 383.807924 -383.20163) (xy 383.845873 -383.146044) (xy 383.86766 -383.120392)
			(xy 383.87345 -383.113242) (xy 383.879967 -383.096055) (xy 383.88036 -383.086864) (xy 383.88036 -382.593342)
			(xy 383.879916 -382.584159) (xy 383.873425 -382.566975) (xy 383.86766 -382.559814) (xy 383.845862 -382.53417)
			(xy 383.807912 -382.478583) (xy 383.776878 -382.418858) (xy 383.753205 -382.355853) (xy 383.737232 -382.290469)
			(xy 383.729188 -382.223646) (xy 380.451149 -382.223646) (xy 380.451149 -382.223704) (xy 380.443073 -382.290642)
			(xy 380.427038 -382.356131) (xy 380.403273 -382.419228) (xy 380.372122 -382.479024) (xy 380.334032 -382.534657)
			(xy 380.312168 -382.560322) (xy 380.306375 -382.56747) (xy 380.299859 -382.584658) (xy 380.299468 -382.59385)
			(xy 380.299468 -383.086356) (xy 380.299907 -383.09554) (xy 380.306401 -383.112724) (xy 380.312168 -383.119884)
			(xy 380.334049 -383.145536) (xy 380.372139 -383.201171) (xy 380.403291 -383.260969) (xy 380.426928 -383.323727)
			(xy 381.529033 -383.323727) (xy 381.529037 -383.256419) (xy 381.537084 -383.189595) (xy 381.55306 -383.124211)
			(xy 381.576736 -383.061205) (xy 381.607772 -383.00148) (xy 381.645723 -382.945893) (xy 381.667512 -382.92024)
			(xy 381.673318 -382.913101) (xy 381.679827 -382.895906) (xy 381.680212 -382.886712) (xy 381.680212 -382.728724)
			(xy 381.680641 -382.71857) (xy 381.688431 -382.699816) (xy 381.702826 -382.685491) (xy 381.721618 -382.677793)
			(xy 381.731774 -382.677416) (xy 382.448054 -382.677416) (xy 382.458175 -382.677964) (xy 382.47689 -382.685672)
			(xy 382.491247 -382.699939) (xy 382.499072 -382.718606) (xy 382.499616 -382.728724) (xy 382.499616 -382.886712)
			(xy 382.500017 -382.8959) (xy 382.506537 -382.913085) (xy 382.512316 -382.92024) (xy 382.53407 -382.945921)
			(xy 382.572023 -383.001502) (xy 382.60306 -383.061221) (xy 382.626737 -383.124222) (xy 382.642713 -383.189601)
			(xy 382.650761 -383.256421) (xy 382.650764 -383.323724) (xy 382.642723 -383.390545) (xy 382.626753 -383.455926)
			(xy 382.603082 -383.518929) (xy 382.57205 -383.578652) (xy 382.534103 -383.634236) (xy 382.512316 -383.659888)
			(xy 382.506501 -383.667021) (xy 382.499997 -383.684221) (xy 382.499616 -383.693416) (xy 382.499616 -384.186684)
			(xy 382.50003 -384.195871) (xy 382.506541 -384.213055) (xy 382.512316 -384.220212) (xy 382.53414 -384.245834)
			(xy 382.572091 -384.301424) (xy 382.603125 -384.361151) (xy 382.626798 -384.42416) (xy 382.64277 -384.489546)
			(xy 382.650812 -384.556373) (xy 382.650808 -384.623681) (xy 382.64276 -384.690507) (xy 382.626782 -384.755892)
			(xy 382.603103 -384.818898) (xy 382.572063 -384.878622) (xy 382.534107 -384.934208) (xy 382.512316 -384.95986)
			(xy 382.506513 -384.967001) (xy 382.500002 -384.984195) (xy 382.499616 -384.993388) (xy 382.499616 -385.151376)
			(xy 382.499159 -385.161527) (xy 382.491375 -385.180275) (xy 382.476989 -385.194599) (xy 382.458206 -385.202303)
			(xy 382.448054 -385.202684) (xy 381.731774 -385.202684) (xy 381.721649 -385.202196) (xy 381.702931 -385.194464)
			(xy 381.688577 -385.180179) (xy 381.680754 -385.161499) (xy 381.680212 -385.151376) (xy 381.680212 -384.993388)
			(xy 381.679805 -384.984201) (xy 381.673289 -384.967016) (xy 381.667512 -384.95986) (xy 381.64576 -384.934178)
			(xy 381.607812 -384.878596) (xy 381.576779 -384.818876) (xy 381.553105 -384.755875) (xy 381.537131 -384.690497)
			(xy 381.529084 -384.623678) (xy 381.529081 -384.556376) (xy 381.537121 -384.489557) (xy 381.553089 -384.424177)
			(xy 381.576757 -384.361174) (xy 381.607784 -384.301451) (xy 381.645727 -384.245864) (xy 381.667512 -384.220212)
			(xy 381.67333 -384.213082) (xy 381.679831 -384.19588) (xy 381.680212 -384.186684) (xy 381.680212 -383.693416)
			(xy 381.679791 -383.68423) (xy 381.673285 -383.667046) (xy 381.667512 -383.659888) (xy 381.64569 -383.634265)
			(xy 381.607744 -383.578673) (xy 381.576714 -383.518946) (xy 381.553044 -383.455937) (xy 381.537074 -383.390552)
			(xy 381.529033 -383.323727) (xy 380.426928 -383.323727) (xy 380.427056 -383.324068) (xy 380.443091 -383.389559)
			(xy 380.451166 -383.456499) (xy 380.451165 -383.523925) (xy 380.443087 -383.590865) (xy 380.427049 -383.656355)
			(xy 380.403281 -383.719453) (xy 380.372127 -383.779249) (xy 380.334034 -383.834883) (xy 380.312168 -383.860548)
			(xy 380.306364 -383.867688) (xy 380.299855 -383.884883) (xy 380.299468 -383.894076) (xy 380.299468 -384.051556)
			(xy 380.299047 -384.06168) (xy 380.291308 -384.080388) (xy 380.276992 -384.094705) (xy 380.258284 -384.102446)
			(xy 380.24816 -384.102864) (xy 379.53188 -384.102864) (xy 379.521752 -384.1025) (xy 379.503041 -384.094738)
			(xy 379.488726 -384.080405) (xy 379.480988 -384.061685) (xy 379.480572 -384.051556) (xy 379.480572 -383.894076)
			(xy 379.48018 -383.884887) (xy 379.473654 -383.867702) (xy 379.467872 -383.860548) (xy 379.446025 -383.834869)
			(xy 379.407937 -383.779236) (xy 379.376788 -383.719441) (xy 379.353024 -383.656346) (xy 379.336988 -383.590859)
			(xy 379.328911 -383.523923) (xy 379.32891 -383.456501) (xy 379.336984 -383.389564) (xy 379.353017 -383.324077)
			(xy 379.376778 -383.260981) (xy 379.407925 -383.201185) (xy 379.44601 -383.14555) (xy 379.467872 -383.119884)
			(xy 379.473667 -383.112738) (xy 379.48018 -383.095548) (xy 379.480572 -383.086356) (xy 379.480572 -382.59385)
			(xy 379.480144 -382.584665) (xy 379.473643 -382.56748) (xy 379.467872 -382.560322) (xy 379.445999 -382.534664)
			(xy 379.407913 -382.479028) (xy 379.376764 -382.419231) (xy 379.353002 -382.356133) (xy 379.336968 -382.290643)
			(xy 379.328893 -382.223704) (xy 376.050822 -382.223704) (xy 376.042786 -382.290466) (xy 376.026815 -382.355847)
			(xy 376.003144 -382.418851) (xy 375.972113 -382.478575) (xy 375.934167 -382.534162) (xy 375.91238 -382.559814)
			(xy 375.906593 -382.566966) (xy 375.900073 -382.584151) (xy 375.89968 -382.593342) (xy 375.89968 -383.086864)
			(xy 375.900112 -383.096049) (xy 375.906611 -383.113233) (xy 375.91238 -383.120392) (xy 375.934183 -383.146031)
			(xy 375.97213 -383.20162) (xy 376.003162 -383.261346) (xy 376.02662 -383.323786) (xy 377.128714 -383.323786)
			(xy 377.128717 -383.256359) (xy 377.136797 -383.189418) (xy 377.152837 -383.123927) (xy 377.176606 -383.060828)
			(xy 377.207762 -383.001031) (xy 377.245857 -382.945397) (xy 377.267724 -382.919732) (xy 377.273535 -382.912597)
			(xy 377.28004 -382.895399) (xy 377.280424 -382.886204) (xy 377.280424 -382.728724) (xy 377.280836 -382.7186)
			(xy 377.288581 -382.699892) (xy 377.302899 -382.685576) (xy 377.321608 -382.677834) (xy 377.331732 -382.677416)
			(xy 378.048012 -382.677416) (xy 378.058137 -382.677806) (xy 378.076844 -382.685561) (xy 378.091159 -382.699886)
			(xy 378.098901 -382.718598) (xy 378.09932 -382.728724) (xy 378.09932 -382.886204) (xy 378.099724 -382.895392)
			(xy 378.106241 -382.912576) (xy 378.11202 -382.919732) (xy 378.133848 -382.945427) (xy 378.171936 -383.001058)
			(xy 378.203088 -383.06085) (xy 378.226853 -383.123943) (xy 378.24289 -383.189428) (xy 378.250969 -383.256363)
			(xy 378.250972 -383.323783) (xy 378.2429 -383.390719) (xy 378.226869 -383.456205) (xy 378.20311 -383.519301)
			(xy 378.171964 -383.579096) (xy 378.133881 -383.63473) (xy 378.11202 -383.660396) (xy 378.106245 -383.667557)
			(xy 378.099717 -383.684735) (xy 378.09932 -383.693924) (xy 378.09932 -384.186176) (xy 378.099737 -384.195363)
			(xy 378.106245 -384.212547) (xy 378.11202 -384.219704) (xy 378.133919 -384.24534) (xy 378.172005 -384.30098)
			(xy 378.203153 -384.36078) (xy 378.226914 -384.423881) (xy 378.242947 -384.489373) (xy 378.251019 -384.556314)
			(xy 378.251016 -384.62374) (xy 378.242937 -384.69068) (xy 378.226898 -384.756171) (xy 378.203131 -384.81927)
			(xy 378.171977 -384.879067) (xy 378.133885 -384.934702) (xy 378.11202 -384.960368) (xy 378.106214 -384.967507)
			(xy 378.099704 -384.984702) (xy 378.09932 -384.993896) (xy 378.09932 -385.151376) (xy 378.098865 -385.161494)
			(xy 378.091128 -385.180194) (xy 378.076824 -385.194508) (xy 378.05813 -385.202258) (xy 378.048012 -385.202684)
			(xy 377.331732 -385.202684) (xy 377.32161 -385.202258) (xy 377.302903 -385.194517) (xy 377.288587 -385.180203)
			(xy 377.280844 -385.161498) (xy 377.280424 -385.151376) (xy 377.280424 -384.993896) (xy 377.280011 -384.984709)
			(xy 377.273499 -384.967525) (xy 377.267724 -384.960368) (xy 377.245895 -384.934674) (xy 377.207803 -384.879044)
			(xy 377.17665 -384.819252) (xy 377.152882 -384.756159) (xy 377.136844 -384.690673) (xy 377.128765 -384.623738)
			(xy 377.128761 -384.556316) (xy 377.136834 -384.48938) (xy 377.152866 -384.423893) (xy 377.176627 -384.360797)
			(xy 377.207775 -384.301002) (xy 377.245861 -384.245369) (xy 377.267724 -384.219704) (xy 377.273504 -384.212547)
			(xy 377.280028 -384.195365) (xy 377.280424 -384.186176) (xy 377.280424 -383.693924) (xy 377.279997 -383.684739)
			(xy 377.273494 -383.667555) (xy 377.267724 -383.660396) (xy 377.245824 -383.63476) (xy 377.207735 -383.579122)
			(xy 377.176584 -383.519322) (xy 377.152821 -383.456221) (xy 377.136787 -383.390728) (xy 377.128714 -383.323786)
			(xy 376.02662 -383.323786) (xy 376.026833 -383.324352) (xy 376.042804 -383.389735) (xy 376.050846 -383.456559)
			(xy 376.050845 -383.523865) (xy 376.0428 -383.590688) (xy 376.026826 -383.656071) (xy 376.003152 -383.719076)
			(xy 375.972118 -383.778801) (xy 375.934168 -383.834388) (xy 375.91238 -383.86004) (xy 375.906582 -383.867184)
			(xy 375.900069 -383.884375) (xy 375.89968 -383.893568) (xy 375.89968 -384.051556) (xy 375.899242 -384.06171)
			(xy 375.891457 -384.080465) (xy 375.877065 -384.094791) (xy 375.858274 -384.102488) (xy 375.848118 -384.102864)
			(xy 375.131838 -384.102864) (xy 375.121714 -384.102342) (xy 375.102995 -384.094628) (xy 375.088637 -384.080352)
			(xy 375.080816 -384.061677) (xy 375.080276 -384.051556) (xy 375.080276 -383.893568) (xy 375.079886 -383.884379)
			(xy 375.073359 -383.867194) (xy 375.067576 -383.86004) (xy 375.045803 -383.834375) (xy 375.007851 -383.778792)
			(xy 374.976815 -383.71907) (xy 374.95314 -383.656067) (xy 374.937165 -383.590686) (xy 374.929119 -383.523864)
			(xy 374.929117 -383.45656) (xy 374.93716 -383.389738) (xy 374.953133 -383.324356) (xy 374.976805 -383.261352)
			(xy 375.007839 -383.201629) (xy 375.045788 -383.146044) (xy 375.067576 -383.120392) (xy 375.073356 -383.113235)
			(xy 375.079881 -383.096054) (xy 375.080276 -383.086864) (xy 375.080276 -382.593342) (xy 375.079851 -382.584156)
			(xy 375.073348 -382.566971) (xy 375.067576 -382.559814) (xy 375.045777 -382.53417) (xy 375.007826 -382.478584)
			(xy 374.976792 -382.418859) (xy 374.953118 -382.355853) (xy 374.937144 -382.29047) (xy 374.9291 -382.223646)
			(xy 345.250798 -382.223646) (xy 345.242755 -382.290467) (xy 345.226782 -382.355849) (xy 345.20311 -382.418853)
			(xy 345.172077 -382.478576) (xy 345.134128 -382.534162) (xy 345.11234 -382.559814) (xy 345.106548 -382.566962)
			(xy 345.100032 -382.584151) (xy 345.09964 -382.593342) (xy 345.09964 -383.086864) (xy 345.100081 -383.096048)
			(xy 345.106575 -383.113232) (xy 345.11234 -383.120392) (xy 345.134144 -383.146031) (xy 345.172094 -383.201619)
			(xy 345.203127 -383.261344) (xy 345.226566 -383.323727) (xy 346.329188 -383.323727) (xy 346.329192 -383.256419)
			(xy 346.33724 -383.189593) (xy 346.353218 -383.124208) (xy 346.376897 -383.061202) (xy 346.407937 -383.001478)
			(xy 346.445893 -382.945892) (xy 346.467684 -382.92024) (xy 346.473487 -382.913099) (xy 346.479998 -382.895905)
			(xy 346.480384 -382.886712) (xy 346.480384 -382.728724) (xy 346.480841 -382.718573) (xy 346.488625 -382.699825)
			(xy 346.503011 -382.685501) (xy 346.521794 -382.677797) (xy 346.531946 -382.677416) (xy 347.248226 -382.677416)
			(xy 347.258351 -382.677904) (xy 347.277069 -382.685636) (xy 347.291423 -382.699921) (xy 347.299246 -382.718601)
			(xy 347.299788 -382.728724) (xy 347.299788 -382.886712) (xy 347.300195 -382.895899) (xy 347.306711 -382.913084)
			(xy 347.312488 -382.92024) (xy 347.33424 -382.945922) (xy 347.372188 -383.001504) (xy 347.403221 -383.061224)
			(xy 347.426895 -383.124225) (xy 347.442869 -383.189603) (xy 347.450916 -383.256422) (xy 347.450919 -383.323724)
			(xy 347.442879 -383.390543) (xy 347.426911 -383.455923) (xy 347.403243 -383.518926) (xy 347.372216 -383.578649)
			(xy 347.334273 -383.634236) (xy 347.312488 -383.659888) (xy 347.30667 -383.667018) (xy 347.300169 -383.68422)
			(xy 347.299788 -383.693416) (xy 347.299788 -384.186684) (xy 347.300209 -384.19587) (xy 347.306715 -384.213054)
			(xy 347.312488 -384.220212) (xy 347.33431 -384.245835) (xy 347.372256 -384.301427) (xy 347.403286 -384.361154)
			(xy 347.426956 -384.424163) (xy 347.442926 -384.489548) (xy 347.450967 -384.556373) (xy 347.450963 -384.623681)
			(xy 347.442916 -384.690505) (xy 347.42694 -384.755889) (xy 347.403264 -384.818895) (xy 347.372228 -384.87862)
			(xy 347.334277 -384.934207) (xy 347.312488 -384.95986) (xy 347.306682 -384.966999) (xy 347.300173 -384.984194)
			(xy 347.299788 -384.993388) (xy 347.299788 -385.151376) (xy 347.299359 -385.16153) (xy 347.291569 -385.180284)
			(xy 347.277174 -385.194609) (xy 347.258382 -385.202307) (xy 347.248226 -385.202684) (xy 346.531946 -385.202684)
			(xy 346.521825 -385.202136) (xy 346.50311 -385.194428) (xy 346.488753 -385.180161) (xy 346.480928 -385.161494)
			(xy 346.480384 -385.151376) (xy 346.480384 -384.993388) (xy 346.479983 -384.9842) (xy 346.473463 -384.967015)
			(xy 346.467684 -384.95986) (xy 346.44593 -384.934179) (xy 346.407977 -384.878598) (xy 346.37694 -384.818879)
			(xy 346.353263 -384.755878) (xy 346.337287 -384.690499) (xy 346.329239 -384.623679) (xy 346.329236 -384.556376)
			(xy 346.337277 -384.489555) (xy 346.353247 -384.424174) (xy 346.376918 -384.361171) (xy 346.40795 -384.301448)
			(xy 346.445897 -384.245864) (xy 346.467684 -384.220212) (xy 346.473499 -384.213079) (xy 346.480003 -384.195879)
			(xy 346.480384 -384.186684) (xy 346.480384 -383.693416) (xy 346.47997 -383.684229) (xy 346.473459 -383.667045)
			(xy 346.467684 -383.659888) (xy 346.44586 -383.634266) (xy 346.407909 -383.578676) (xy 346.376875 -383.518949)
			(xy 346.353202 -383.45594) (xy 346.33723 -383.390554) (xy 346.329188 -383.323727) (xy 345.226566 -383.323727)
			(xy 345.2268 -383.32435) (xy 345.242773 -383.389734) (xy 345.250816 -383.456559) (xy 345.250814 -383.523865)
			(xy 345.242768 -383.590689) (xy 345.226793 -383.656073) (xy 345.203118 -383.719078) (xy 345.172081 -383.778802)
			(xy 345.134129 -383.834388) (xy 345.11234 -383.86004) (xy 345.106537 -383.86718) (xy 345.100028 -383.884375)
			(xy 345.09964 -383.893568) (xy 345.09964 -384.051556) (xy 345.099143 -384.061702) (xy 345.09137 -384.080446)
			(xy 345.076996 -384.094769) (xy 345.058226 -384.102478) (xy 345.048078 -384.102864) (xy 344.331798 -384.102864)
			(xy 344.321672 -384.102375) (xy 344.302951 -384.094647) (xy 344.288595 -384.080362) (xy 344.280775 -384.06168)
			(xy 344.280236 -384.051556) (xy 344.280236 -383.893568) (xy 344.279833 -383.88438) (xy 344.273313 -383.867196)
			(xy 344.267536 -383.86004) (xy 344.245764 -383.834375) (xy 344.207815 -383.77879) (xy 344.176781 -383.719068)
			(xy 344.153108 -383.656066) (xy 344.137134 -383.590685) (xy 344.129089 -383.523864) (xy 344.129087 -383.45656)
			(xy 344.13713 -383.389739) (xy 344.153101 -383.324358) (xy 344.176772 -383.261354) (xy 344.207803 -383.201631)
			(xy 344.24575 -383.146044) (xy 344.267536 -383.120392) (xy 344.273323 -383.11324) (xy 344.279843 -383.096055)
			(xy 344.280236 -383.086864) (xy 344.280236 -382.593342) (xy 344.279797 -382.584158) (xy 344.273303 -382.566974)
			(xy 344.267536 -382.559814) (xy 344.245738 -382.53417) (xy 344.20779 -382.478582) (xy 344.176757 -382.418858)
			(xy 344.153085 -382.355852) (xy 344.137113 -382.290469) (xy 344.12907 -382.223645) (xy 340.851007 -382.223645)
			(xy 340.842964 -382.290467) (xy 340.826992 -382.355848) (xy 340.80332 -382.418853) (xy 340.772287 -382.478576)
			(xy 340.734339 -382.534162) (xy 340.712552 -382.559814) (xy 340.706761 -382.566963) (xy 340.700244 -382.584151)
			(xy 340.699852 -382.593342) (xy 340.699852 -383.086864) (xy 340.70029 -383.096048) (xy 340.706785 -383.113232)
			(xy 340.712552 -383.120392) (xy 340.734356 -383.146031) (xy 340.772305 -383.201619) (xy 340.803338 -383.261344)
			(xy 340.826798 -383.323786) (xy 341.928893 -383.323786) (xy 341.928896 -383.25636) (xy 341.936975 -383.189419)
			(xy 341.953015 -383.123928) (xy 341.976783 -383.06083) (xy 342.007937 -383.001032) (xy 342.04603 -382.945397)
			(xy 342.067896 -382.919732) (xy 342.073703 -382.912594) (xy 342.080212 -382.895398) (xy 342.080596 -382.886204)
			(xy 342.080596 -382.728724) (xy 342.081035 -382.718604) (xy 342.088775 -382.699901) (xy 342.103084 -382.685586)
			(xy 342.121784 -382.677839) (xy 342.131904 -382.677416) (xy 342.848184 -382.677416) (xy 342.858307 -382.677829)
			(xy 342.877014 -382.685575) (xy 342.891329 -382.699893) (xy 342.899072 -382.7186) (xy 342.899492 -382.728724)
			(xy 342.899492 -382.886204) (xy 342.899902 -382.895391) (xy 342.906416 -382.912575) (xy 342.912192 -382.919732)
			(xy 342.934021 -382.945426) (xy 342.972111 -383.001056) (xy 343.003264 -383.060849) (xy 343.02703 -383.123942)
			(xy 343.043069 -383.189427) (xy 343.051148 -383.256362) (xy 343.051151 -383.323783) (xy 343.043078 -383.390719)
			(xy 343.027046 -383.456207) (xy 343.003286 -383.519302) (xy 342.972139 -383.579097) (xy 342.934054 -383.634731)
			(xy 342.912192 -383.660396) (xy 342.906414 -383.667554) (xy 342.899888 -383.684735) (xy 342.899492 -383.693924)
			(xy 342.899492 -384.186176) (xy 342.899916 -384.195362) (xy 342.90642 -384.212546) (xy 342.912192 -384.219704)
			(xy 342.934092 -384.24534) (xy 342.97218 -384.300978) (xy 343.003329 -384.360779) (xy 343.027092 -384.423879)
			(xy 343.043125 -384.489372) (xy 343.051198 -384.556314) (xy 343.051195 -384.62374) (xy 343.043115 -384.690681)
			(xy 343.027076 -384.756172) (xy 343.003307 -384.819271) (xy 342.972152 -384.879068) (xy 342.934058 -384.934703)
			(xy 342.912192 -384.960368) (xy 342.906383 -384.967504) (xy 342.899876 -384.984702) (xy 342.899492 -384.993896)
			(xy 342.899492 -385.151376) (xy 342.899064 -385.161498) (xy 342.891323 -385.180203) (xy 342.877009 -385.194518)
			(xy 342.858306 -385.202263) (xy 342.848184 -385.202684) (xy 342.131904 -385.202684) (xy 342.12178 -385.20228)
			(xy 342.103073 -385.194531) (xy 342.088758 -385.18021) (xy 342.081016 -385.1615) (xy 342.080596 -385.151376)
			(xy 342.080596 -384.993896) (xy 342.080189 -384.984709) (xy 342.073673 -384.967524) (xy 342.067896 -384.960368)
			(xy 342.046068 -384.934674) (xy 342.007978 -384.879043) (xy 341.976826 -384.819251) (xy 341.95306 -384.756158)
			(xy 341.937022 -384.690672) (xy 341.928943 -384.623737) (xy 341.92894 -384.556317) (xy 341.937012 -384.489381)
			(xy 341.953044 -384.423894) (xy 341.976804 -384.360799) (xy 342.00795 -384.301003) (xy 342.046034 -384.245369)
			(xy 342.067896 -384.219704) (xy 342.073673 -384.212545) (xy 342.080199 -384.195365) (xy 342.080596 -384.186176)
			(xy 342.080596 -383.693924) (xy 342.080175 -383.684738) (xy 342.073669 -383.667553) (xy 342.067896 -383.660396)
			(xy 342.045997 -383.63476) (xy 342.007909 -383.579121) (xy 341.976761 -383.519321) (xy 341.952999 -383.45622)
			(xy 341.936966 -383.390728) (xy 341.928893 -383.323786) (xy 340.826798 -383.323786) (xy 340.82701 -383.324351)
			(xy 340.842982 -383.389735) (xy 340.851025 -383.456559) (xy 340.851024 -383.523865) (xy 340.842978 -383.590689)
			(xy 340.827003 -383.656072) (xy 340.803328 -383.719078) (xy 340.772292 -383.778802) (xy 340.734341 -383.834388)
			(xy 340.712552 -383.86004) (xy 340.70675 -383.867181) (xy 340.70024 -383.884375) (xy 340.699852 -383.893568)
			(xy 340.699852 -384.051556) (xy 340.699343 -384.061701) (xy 340.691572 -384.080442) (xy 340.677202 -384.094765)
			(xy 340.658436 -384.102476) (xy 340.64829 -384.102864) (xy 339.93201 -384.102864) (xy 339.921884 -384.102365)
			(xy 339.903164 -384.094642) (xy 339.888808 -384.080359) (xy 339.880987 -384.061679) (xy 339.880448 -384.051556)
			(xy 339.880448 -383.893568) (xy 339.880042 -383.884381) (xy 339.873524 -383.867197) (xy 339.867748 -383.86004)
			(xy 339.845976 -383.834375) (xy 339.808026 -383.778791) (xy 339.776992 -383.719069) (xy 339.753318 -383.656066)
			(xy 339.737343 -383.590685) (xy 339.729298 -383.523864) (xy 339.729296 -383.45656) (xy 339.737339 -383.389738)
			(xy 339.75331 -383.324357) (xy 339.776982 -383.261353) (xy 339.808014 -383.20163) (xy 339.845961 -383.146044)
			(xy 339.867748 -383.120392) (xy 339.873536 -383.113241) (xy 339.880055 -383.096055) (xy 339.880448 -383.086864)
			(xy 339.880448 -382.593342) (xy 339.880007 -382.584158) (xy 339.873513 -382.566974) (xy 339.867748 -382.559814)
			(xy 339.84595 -382.53417) (xy 339.808001 -382.478583) (xy 339.776968 -382.418858) (xy 339.753295 -382.355852)
			(xy 339.737322 -382.290469) (xy 339.729279 -382.223645) (xy 336.45124 -382.223645) (xy 336.45124 -382.223704)
			(xy 336.443164 -382.290643) (xy 336.427128 -382.356132) (xy 336.403363 -382.419228) (xy 336.372211 -382.479024)
			(xy 336.334121 -382.534658) (xy 336.312256 -382.560322) (xy 336.306462 -382.567469) (xy 336.299947 -382.584658)
			(xy 336.299556 -382.59385) (xy 336.299556 -383.086356) (xy 336.299997 -383.09554) (xy 336.306491 -383.112724)
			(xy 336.312256 -383.119884) (xy 336.334137 -383.145536) (xy 336.372228 -383.201171) (xy 336.403381 -383.260969)
			(xy 336.427018 -383.323726) (xy 337.529124 -383.323726) (xy 337.529128 -383.256419) (xy 337.537175 -383.189595)
			(xy 337.55315 -383.124211) (xy 337.576825 -383.061205) (xy 337.607861 -383.001481) (xy 337.645811 -382.945893)
			(xy 337.6676 -382.92024) (xy 337.673405 -382.9131) (xy 337.679914 -382.895906) (xy 337.6803 -382.886712)
			(xy 337.6803 -382.728724) (xy 337.680741 -382.718571) (xy 337.688529 -382.699819) (xy 337.70292 -382.685495)
			(xy 337.721708 -382.677795) (xy 337.731862 -382.677416) (xy 338.448142 -382.677416) (xy 338.458268 -382.677891)
			(xy 338.476986 -382.685629) (xy 338.49134 -382.699918) (xy 338.499162 -382.7186) (xy 338.499704 -382.728724)
			(xy 338.499704 -382.886712) (xy 338.500108 -382.8959) (xy 338.506626 -382.913084) (xy 338.512404 -382.92024)
			(xy 338.534155 -382.945922) (xy 338.572102 -383.001505) (xy 338.603135 -383.061225) (xy 338.626808 -383.124225)
			(xy 338.642782 -383.189604) (xy 338.650828 -383.256422) (xy 338.650831 -383.323724) (xy 338.642791 -383.390543)
			(xy 338.626824 -383.455923) (xy 338.603157 -383.518926) (xy 338.57213 -383.578648) (xy 338.534188 -383.634235)
			(xy 338.512404 -383.659888) (xy 338.506588 -383.66702) (xy 338.500085 -383.68422) (xy 338.499704 -383.693416)
			(xy 338.499704 -384.186684) (xy 338.500121 -384.19587) (xy 338.50663 -384.213055) (xy 338.512404 -384.220212)
			(xy 338.534226 -384.245836) (xy 338.572171 -384.301427) (xy 338.6032 -384.361155) (xy 338.626869 -384.424163)
			(xy 338.642838 -384.489548) (xy 338.650879 -384.556374) (xy 338.650875 -384.623681) (xy 338.642828 -384.690505)
			(xy 338.626853 -384.755889) (xy 338.603178 -384.818894) (xy 338.572143 -384.878619) (xy 338.534193 -384.934207)
			(xy 338.512404 -384.95986) (xy 338.5066 -384.967) (xy 338.50009 -384.984194) (xy 338.499704 -384.993388)
			(xy 338.499704 -385.151376) (xy 338.499259 -385.161528) (xy 338.491472 -385.180279) (xy 338.477082 -385.194603)
			(xy 338.458296 -385.202305) (xy 338.448142 -385.202684) (xy 337.731862 -385.202684) (xy 337.721736 -385.202205)
			(xy 337.703018 -385.194469) (xy 337.688664 -385.180181) (xy 337.680842 -385.1615) (xy 337.6803 -385.151376)
			(xy 337.6803 -384.993388) (xy 337.679895 -384.9842) (xy 337.673378 -384.967016) (xy 337.6676 -384.95986)
			(xy 337.645849 -384.934178) (xy 337.607901 -384.878595) (xy 337.576869 -384.818875) (xy 337.553196 -384.755875)
			(xy 337.537221 -384.690497) (xy 337.529175 -384.623678) (xy 337.529172 -384.556376) (xy 337.537212 -384.489557)
			(xy 337.55318 -384.424177) (xy 337.576847 -384.361174) (xy 337.607874 -384.301451) (xy 337.645816 -384.245865)
			(xy 337.6676 -384.220212) (xy 337.673416 -384.213081) (xy 337.679919 -384.19588) (xy 337.6803 -384.186684)
			(xy 337.6803 -383.693416) (xy 337.679882 -383.68423) (xy 337.673374 -383.667045) (xy 337.6676 -383.659888)
			(xy 337.645778 -383.634264) (xy 337.607833 -383.578673) (xy 337.576803 -383.518945) (xy 337.553134 -383.455937)
			(xy 337.537165 -383.390552) (xy 337.529124 -383.323726) (xy 336.427018 -383.323726) (xy 336.427146 -383.324067)
			(xy 336.443182 -383.389559) (xy 336.451257 -383.456499) (xy 336.451256 -383.523925) (xy 336.443177 -383.590865)
			(xy 336.427139 -383.656356) (xy 336.403371 -383.719453) (xy 336.372216 -383.77925) (xy 336.334122 -383.834883)
			(xy 336.312256 -383.860548) (xy 336.306451 -383.867687) (xy 336.299943 -383.884882) (xy 336.299556 -383.894076)
			(xy 336.299556 -384.051556) (xy 336.29898 -384.061655) (xy 336.291267 -384.080321) (xy 336.276999 -384.094616)
			(xy 336.258346 -384.102362) (xy 336.248248 -384.102864) (xy 335.531968 -384.102864) (xy 335.521839 -384.102509)
			(xy 335.503128 -384.094744) (xy 335.488813 -384.080408) (xy 335.481076 -384.061686) (xy 335.48066 -384.051556)
			(xy 335.48066 -383.894076) (xy 335.480248 -383.884889) (xy 335.473734 -383.867706) (xy 335.46796 -383.860548)
			(xy 335.446113 -383.834869) (xy 335.408027 -383.779236) (xy 335.376877 -383.719441) (xy 335.353114 -383.656346)
			(xy 335.337079 -383.590859) (xy 335.329002 -383.523923) (xy 335.329001 -383.456501) (xy 335.337074 -383.389565)
			(xy 335.353107 -383.324077) (xy 335.376868 -383.260981) (xy 335.408014 -383.201185) (xy 335.446098 -383.14555)
			(xy 335.46796 -383.119884) (xy 335.473753 -383.112737) (xy 335.480268 -383.095548) (xy 335.48066 -383.086356)
			(xy 335.48066 -382.59385) (xy 335.480213 -382.584667) (xy 335.473723 -382.567483) (xy 335.46796 -382.560322)
			(xy 335.446088 -382.534664) (xy 335.408002 -382.479028) (xy 335.376854 -382.41923) (xy 335.353092 -382.356132)
			(xy 335.337058 -382.290643) (xy 335.328984 -382.223704) (xy 332.050913 -382.223704) (xy 332.042877 -382.290466)
			(xy 332.026905 -382.355848) (xy 332.003234 -382.418852) (xy 331.972202 -382.478575) (xy 331.934255 -382.534162)
			(xy 331.912468 -382.559814) (xy 331.906679 -382.566964) (xy 331.90016 -382.584151) (xy 331.899768 -382.593342)
			(xy 331.899768 -383.086864) (xy 331.900203 -383.096048) (xy 331.9067 -383.113233) (xy 331.912468 -383.120392)
			(xy 331.934271 -383.146031) (xy 331.972219 -383.20162) (xy 332.003251 -383.261345) (xy 332.026711 -383.323786)
			(xy 333.128805 -383.323786) (xy 333.128808 -383.25636) (xy 333.136888 -383.189419) (xy 333.152927 -383.123927)
			(xy 333.176696 -383.060829) (xy 333.207852 -383.001032) (xy 333.245945 -382.945397) (xy 333.267812 -382.919732)
			(xy 333.273621 -382.912596) (xy 333.280128 -382.895398) (xy 333.280512 -382.886204) (xy 333.280512 -382.728724)
			(xy 333.280936 -382.718602) (xy 333.288678 -382.699896) (xy 333.302993 -382.685581) (xy 333.321698 -382.677837)
			(xy 333.33182 -382.677416) (xy 334.0481 -382.677416) (xy 334.058224 -382.677816) (xy 334.076931 -382.685568)
			(xy 334.091246 -382.699889) (xy 334.098988 -382.718599) (xy 334.099408 -382.728724) (xy 334.099408 -382.886204)
			(xy 334.099815 -382.895392) (xy 334.106331 -382.912576) (xy 334.112108 -382.919732) (xy 334.133936 -382.945427)
			(xy 334.172026 -383.001057) (xy 334.203177 -383.060849) (xy 334.226943 -383.123942) (xy 334.242981 -383.189428)
			(xy 334.25106 -383.256363) (xy 334.251063 -383.323783) (xy 334.242991 -383.390719) (xy 334.226959 -383.456206)
			(xy 334.2032 -383.519301) (xy 334.172053 -383.579096) (xy 334.13397 -383.634731) (xy 334.112108 -383.660396)
			(xy 334.106332 -383.667556) (xy 334.099805 -383.684735) (xy 334.099408 -383.693924) (xy 334.099408 -384.186176)
			(xy 334.099828 -384.195362) (xy 334.106335 -384.212547) (xy 334.112108 -384.219704) (xy 334.134007 -384.24534)
			(xy 334.172094 -384.300979) (xy 334.203243 -384.360779) (xy 334.227005 -384.42388) (xy 334.243037 -384.489373)
			(xy 334.25111 -384.556314) (xy 334.251107 -384.62374) (xy 334.243028 -384.690681) (xy 334.226989 -384.756172)
			(xy 334.203221 -384.81927) (xy 334.172066 -384.879067) (xy 334.133974 -384.934703) (xy 334.112108 -384.960368)
			(xy 334.106301 -384.967506) (xy 334.099792 -384.984702) (xy 334.099408 -384.993896) (xy 334.099408 -385.151376)
			(xy 334.098965 -385.161496) (xy 334.091226 -385.180198) (xy 334.076918 -385.194512) (xy 334.05822 -385.20226)
			(xy 334.0481 -385.202684) (xy 333.33182 -385.202684) (xy 333.321697 -385.202267) (xy 333.302991 -385.194523)
			(xy 333.288675 -385.180206) (xy 333.280932 -385.161499) (xy 333.280512 -385.151376) (xy 333.280512 -384.993896)
			(xy 333.280101 -384.984709) (xy 333.273587 -384.967525) (xy 333.267812 -384.960368) (xy 333.245983 -384.934674)
			(xy 333.207892 -384.879044) (xy 333.176739 -384.819252) (xy 333.152973 -384.756158) (xy 333.136934 -384.690673)
			(xy 333.128855 -384.623738) (xy 333.128852 -384.556316) (xy 333.136925 -384.48938) (xy 333.152957 -384.423893)
			(xy 333.176717 -384.360798) (xy 333.207865 -384.301003) (xy 333.24595 -384.245369) (xy 333.267812 -384.219704)
			(xy 333.273591 -384.212546) (xy 333.280116 -384.195365) (xy 333.280512 -384.186176) (xy 333.280512 -383.693924)
			(xy 333.280088 -383.684738) (xy 333.273583 -383.667554) (xy 333.267812 -383.660396) (xy 333.245912 -383.63476)
			(xy 333.207824 -383.579122) (xy 333.176674 -383.519322) (xy 333.152911 -383.456221) (xy 333.136878 -383.390728)
			(xy 333.128805 -383.323786) (xy 332.026711 -383.323786) (xy 332.026923 -383.324351) (xy 332.042895 -383.389735)
			(xy 332.050937 -383.456559) (xy 332.050936 -383.523865) (xy 332.04289 -383.590689) (xy 332.026916 -383.656072)
			(xy 332.003242 -383.719077) (xy 331.972207 -383.778801) (xy 331.934257 -383.834388) (xy 331.912468 -383.86004)
			(xy 331.906668 -383.867183) (xy 331.900156 -383.884375) (xy 331.899768 -383.893568) (xy 331.899768 -384.051556)
			(xy 331.899342 -384.061711) (xy 331.891555 -384.080469) (xy 331.877159 -384.094795) (xy 331.858363 -384.10249)
			(xy 331.848206 -384.102864) (xy 331.131926 -384.102864) (xy 331.121801 -384.102352) (xy 331.103082 -384.094634)
			(xy 331.088724 -384.080355) (xy 331.080904 -384.061678) (xy 331.080364 -384.051556) (xy 331.080364 -383.893568)
			(xy 331.079955 -383.884381) (xy 331.073439 -383.867198) (xy 331.067664 -383.86004) (xy 331.045891 -383.834375)
			(xy 331.00794 -383.778791) (xy 330.976905 -383.71907) (xy 330.95323 -383.656067) (xy 330.937256 -383.590686)
			(xy 330.92921 -383.523864) (xy 330.929208 -383.45656) (xy 330.937251 -383.389738) (xy 330.953223 -383.324356)
			(xy 330.976895 -383.261352) (xy 331.007928 -383.20163) (xy 331.045877 -383.146044) (xy 331.067664 -383.120392)
			(xy 331.073454 -383.113243) (xy 331.079971 -383.096055) (xy 331.080364 -383.086864) (xy 331.080364 -382.593342)
			(xy 331.079919 -382.584159) (xy 331.073428 -382.566975) (xy 331.067664 -382.559814) (xy 331.045866 -382.53417)
			(xy 331.007916 -382.478583) (xy 330.976881 -382.418859) (xy 330.953208 -382.355853) (xy 330.937235 -382.29047)
			(xy 330.929191 -382.223646) (xy 301.250888 -382.223646) (xy 301.250888 -382.223704) (xy 301.242813 -382.290641)
			(xy 301.226779 -382.356129) (xy 301.203017 -382.419226) (xy 301.171869 -382.479022) (xy 301.133783 -382.534656)
			(xy 301.11192 -382.560322) (xy 301.106134 -382.567475) (xy 301.099612 -382.584659) (xy 301.09922 -382.59385)
			(xy 301.09922 -383.086356) (xy 301.099647 -383.095542) (xy 301.106148 -383.112726) (xy 301.11192 -383.119884)
			(xy 301.133799 -383.145537) (xy 301.171886 -383.201173) (xy 301.203035 -383.260972) (xy 301.22669 -383.323786)
			(xy 302.328775 -383.323786) (xy 302.328778 -383.25636) (xy 302.336857 -383.18942) (xy 302.352895 -383.123929)
			(xy 302.376662 -383.060831) (xy 302.407816 -383.001033) (xy 302.445907 -382.945398) (xy 302.467772 -382.919732)
			(xy 302.473589 -382.912601) (xy 302.480089 -382.895399) (xy 302.480472 -382.886204) (xy 302.480472 -382.728724)
			(xy 302.480935 -382.718606) (xy 302.48867 -382.699909) (xy 302.502972 -382.685595) (xy 302.521663 -382.677843)
			(xy 302.53178 -382.677416) (xy 303.24806 -382.677416) (xy 303.258182 -382.677849) (xy 303.276888 -382.685587)
			(xy 303.291204 -382.699899) (xy 303.298948 -382.718602) (xy 303.299368 -382.728724) (xy 303.299368 -382.886204)
			(xy 303.299783 -382.89539) (xy 303.306294 -382.912575) (xy 303.312068 -382.919732) (xy 303.333898 -382.945426)
			(xy 303.37199 -383.001056) (xy 303.403144 -383.060847) (xy 303.426911 -383.123941) (xy 303.44295 -383.189427)
			(xy 303.451029 -383.256362) (xy 303.451033 -383.323784) (xy 303.44296 -383.39072) (xy 303.426927 -383.456208)
			(xy 303.403166 -383.519303) (xy 303.372017 -383.579098) (xy 303.333931 -383.634731) (xy 303.312068 -383.660396)
			(xy 303.306286 -383.667552) (xy 303.299764 -383.684734) (xy 303.299368 -383.693924) (xy 303.299368 -384.186176)
			(xy 303.299797 -384.195361) (xy 303.306299 -384.212545) (xy 303.312068 -384.219704) (xy 303.333968 -384.24534)
			(xy 303.372058 -384.300978) (xy 303.403209 -384.360778) (xy 303.426973 -384.423878) (xy 303.443007 -384.489371)
			(xy 303.45108 -384.556313) (xy 303.451077 -384.623741) (xy 303.442997 -384.690682) (xy 303.426957 -384.756173)
			(xy 303.403187 -384.819272) (xy 303.37203 -384.879069) (xy 303.333935 -384.934703) (xy 303.312068 -384.960368)
			(xy 303.306256 -384.967502) (xy 303.299751 -384.984701) (xy 303.299368 -384.993896) (xy 303.299368 -385.151376)
			(xy 303.298964 -385.161501) (xy 303.291218 -385.18021) (xy 303.276897 -385.194527) (xy 303.258185 -385.202267)
			(xy 303.24806 -385.202684) (xy 302.53178 -385.202684) (xy 302.521654 -385.2023) (xy 302.502947 -385.194542)
			(xy 302.488633 -385.180216) (xy 302.480891 -385.161502) (xy 302.480472 -385.151376) (xy 302.480472 -384.993896)
			(xy 302.48007 -384.984708) (xy 302.473551 -384.967523) (xy 302.467772 -384.960368) (xy 302.445944 -384.934673)
			(xy 302.407856 -384.879042) (xy 302.376706 -384.81925) (xy 302.352941 -384.756157) (xy 302.336904 -384.690672)
			(xy 302.328825 -384.623737) (xy 302.328822 -384.556317) (xy 302.336894 -384.489382) (xy 302.352925 -384.423895)
			(xy 302.376684 -384.3608) (xy 302.407829 -384.301004) (xy 302.445911 -384.24537) (xy 302.467772 -384.219704)
			(xy 302.473558 -384.212552) (xy 302.480077 -384.195366) (xy 302.480472 -384.186176) (xy 302.480472 -383.693924)
			(xy 302.480057 -383.684737) (xy 302.473547 -383.667552) (xy 302.467772 -383.660396) (xy 302.445874 -383.634759)
			(xy 302.407788 -383.57912) (xy 302.37664 -383.51932) (xy 302.352879 -383.456219) (xy 302.336847 -383.390727)
			(xy 302.328775 -383.323786) (xy 301.22669 -383.323786) (xy 301.226797 -383.32407) (xy 301.242831 -383.38956)
			(xy 301.250905 -383.4565) (xy 301.250904 -383.523924) (xy 301.242827 -383.590863) (xy 301.22679 -383.656353)
			(xy 301.203025 -383.71945) (xy 301.171874 -383.779247) (xy 301.133784 -383.834882) (xy 301.11192 -383.860548)
			(xy 301.106123 -383.867693) (xy 301.099608 -383.884884) (xy 301.09922 -383.894076) (xy 301.09922 -384.051556)
			(xy 301.098748 -384.061673) (xy 301.091018 -384.080372) (xy 301.076719 -384.094687) (xy 301.058029 -384.102437)
			(xy 301.047912 -384.102864) (xy 300.331632 -384.102864) (xy 300.321507 -384.102457) (xy 300.302797 -384.094713)
			(xy 300.28848 -384.080393) (xy 300.28074 -384.061681) (xy 300.280324 -384.051556) (xy 300.280324 -383.894076)
			(xy 300.27992 -383.884888) (xy 300.273402 -383.867704) (xy 300.267624 -383.860548) (xy 300.245775 -383.83487)
			(xy 300.207684 -383.779238) (xy 300.176531 -383.719444) (xy 300.152765 -383.656349) (xy 300.136728 -383.590861)
			(xy 300.12865 -383.523923) (xy 300.128649 -383.456501) (xy 300.136724 -383.389563) (xy 300.152758 -383.324074)
			(xy 300.176522 -383.260978) (xy 300.207672 -383.201183) (xy 300.24576 -383.145549) (xy 300.267624 -383.119884)
			(xy 300.273413 -383.112733) (xy 300.279931 -383.095547) (xy 300.280324 -383.086356) (xy 300.280324 -382.59385)
			(xy 300.279884 -382.584666) (xy 300.273391 -382.567482) (xy 300.267624 -382.560322) (xy 300.245749 -382.534665)
			(xy 300.207659 -382.47903) (xy 300.176508 -382.419233) (xy 300.152743 -382.356135) (xy 300.136708 -382.290645)
			(xy 300.128632 -382.223705) (xy 296.851097 -382.223705) (xy 296.843022 -382.290641) (xy 296.826989 -382.356129)
			(xy 296.803227 -382.419225) (xy 296.77208 -382.479021) (xy 296.733994 -382.534656) (xy 296.712132 -382.560322)
			(xy 296.706335 -382.567467) (xy 296.699823 -382.584658) (xy 296.699432 -382.59385) (xy 296.699432 -383.086356)
			(xy 296.699878 -383.095539) (xy 296.706368 -383.112723) (xy 296.712132 -383.119884) (xy 296.734011 -383.145537)
			(xy 296.772097 -383.201174) (xy 296.803245 -383.260972) (xy 296.826877 -383.323727) (xy 297.928982 -383.323727)
			(xy 297.928985 -383.256419) (xy 297.937033 -383.189593) (xy 297.953011 -383.124208) (xy 297.97669 -383.061202)
			(xy 298.007729 -383.001478) (xy 298.045685 -382.945891) (xy 298.067476 -382.92024) (xy 298.073278 -382.913098)
			(xy 298.07979 -382.895905) (xy 298.080176 -382.886712) (xy 298.080176 -382.728724) (xy 298.080641 -382.718574)
			(xy 298.088424 -382.699827) (xy 298.102807 -382.685504) (xy 298.121587 -382.677799) (xy 298.131738 -382.677416)
			(xy 298.848018 -382.677416) (xy 298.858143 -382.677911) (xy 298.87686 -382.68564) (xy 298.891215 -382.699923)
			(xy 298.899038 -382.718602) (xy 298.89958 -382.728724) (xy 298.89958 -382.886712) (xy 298.899989 -382.895899)
			(xy 298.906504 -382.913083) (xy 298.91228 -382.92024) (xy 298.934031 -382.945922) (xy 298.97198 -383.001504)
			(xy 299.003014 -383.061224) (xy 299.026688 -383.124225) (xy 299.042663 -383.189603) (xy 299.050709 -383.256422)
			(xy 299.050713 -383.323724) (xy 299.042672 -383.390544) (xy 299.026704 -383.455924) (xy 299.003036 -383.518926)
			(xy 298.972008 -383.578649) (xy 298.934065 -383.634235) (xy 298.91228 -383.659888) (xy 298.906461 -383.667017)
			(xy 298.89996 -383.68422) (xy 298.89958 -383.693416) (xy 298.89958 -384.186684) (xy 298.900003 -384.19587)
			(xy 298.906508 -384.213054) (xy 298.91228 -384.220212) (xy 298.934103 -384.245835) (xy 298.972049 -384.301426)
			(xy 299.00308 -384.361154) (xy 299.02675 -384.424162) (xy 299.04272 -384.489548) (xy 299.050761 -384.556373)
			(xy 299.050757 -384.623681) (xy 299.04271 -384.690506) (xy 299.026734 -384.75589) (xy 299.003058 -384.818895)
			(xy 298.972021 -384.87862) (xy 298.934069 -384.934208) (xy 298.91228 -384.95986) (xy 298.906473 -384.966998)
			(xy 298.899965 -384.984194) (xy 298.89958 -384.993388) (xy 298.89958 -385.151376) (xy 298.899159 -385.161531)
			(xy 298.891367 -385.180287) (xy 298.87697 -385.194612) (xy 298.858175 -385.202309) (xy 298.848018 -385.202684)
			(xy 298.131738 -385.202684) (xy 298.121617 -385.202143) (xy 298.102901 -385.194432) (xy 298.088544 -385.180162)
			(xy 298.08072 -385.161494) (xy 298.080176 -385.151376) (xy 298.080176 -384.993388) (xy 298.079777 -384.9842)
			(xy 298.073256 -384.967015) (xy 298.067476 -384.95986) (xy 298.045723 -384.934179) (xy 298.00777 -384.878598)
			(xy 297.976733 -384.818878) (xy 297.953057 -384.755878) (xy 297.93708 -384.690499) (xy 297.929033 -384.623679)
			(xy 297.92903 -384.556376) (xy 297.937071 -384.489555) (xy 297.953041 -384.424174) (xy 297.976711 -384.361171)
			(xy 298.007742 -384.301449) (xy 298.045689 -384.245864) (xy 298.067476 -384.220212) (xy 298.07329 -384.213079)
			(xy 298.079795 -384.195879) (xy 298.080176 -384.186684) (xy 298.080176 -383.693416) (xy 298.079764 -383.684229)
			(xy 298.073252 -383.667044) (xy 298.067476 -383.659888) (xy 298.045651 -383.634266) (xy 298.007701 -383.578676)
			(xy 297.976668 -383.518948) (xy 297.952995 -383.45594) (xy 297.937024 -383.390554) (xy 297.928982 -383.323727)
			(xy 296.826877 -383.323727) (xy 296.827007 -383.324071) (xy 296.84304 -383.389561) (xy 296.851114 -383.4565)
			(xy 296.851113 -383.523924) (xy 296.843036 -383.590863) (xy 296.827 -383.656352) (xy 296.803235 -383.71945)
			(xy 296.772084 -383.779247) (xy 296.733996 -383.834882) (xy 296.712132 -383.860548) (xy 296.706324 -383.867685)
			(xy 296.699818 -383.884882) (xy 296.699432 -383.894076) (xy 296.699432 -384.051556) (xy 296.698949 -384.061672)
			(xy 296.691221 -384.080368) (xy 296.676925 -384.094683) (xy 296.658239 -384.102435) (xy 296.648124 -384.102864)
			(xy 295.931844 -384.102864) (xy 295.92172 -384.102447) (xy 295.90301 -384.094707) (xy 295.888693 -384.08039)
			(xy 295.880953 -384.06168) (xy 295.880536 -384.051556) (xy 295.880536 -383.894076) (xy 295.880129 -383.884889)
			(xy 295.873612 -383.867705) (xy 295.867836 -383.860548) (xy 295.845986 -383.83487) (xy 295.807895 -383.779238)
			(xy 295.776742 -383.719444) (xy 295.752975 -383.656349) (xy 295.736937 -383.590861) (xy 295.728859 -383.523924)
			(xy 295.728858 -383.4565) (xy 295.736933 -383.389563) (xy 295.752968 -383.324074) (xy 295.776732 -383.260978)
			(xy 295.807883 -383.201182) (xy 295.845972 -383.145549) (xy 295.867836 -383.119884) (xy 295.873626 -383.112735)
			(xy 295.880144 -383.095547) (xy 295.880536 -383.086356) (xy 295.880536 -382.59385) (xy 295.880094 -382.584666)
			(xy 295.873601 -382.567482) (xy 295.867836 -382.560322) (xy 295.845961 -382.534665) (xy 295.80787 -382.479031)
			(xy 295.776718 -382.419233) (xy 295.752953 -382.356135) (xy 295.736917 -382.290645) (xy 295.728841 -382.223705)
			(xy 292.450794 -382.223705) (xy 292.442758 -382.290467) (xy 292.426786 -382.355849) (xy 292.403113 -382.418853)
			(xy 292.37208 -382.478576) (xy 292.334131 -382.534162) (xy 292.312344 -382.559814) (xy 292.306552 -382.566962)
			(xy 292.300036 -382.584151) (xy 292.299644 -382.593342) (xy 292.299644 -383.086864) (xy 292.300084 -383.096048)
			(xy 292.306578 -383.113232) (xy 292.312344 -383.120392) (xy 292.334148 -383.146031) (xy 292.372098 -383.201619)
			(xy 292.403131 -383.261344) (xy 292.426592 -383.323786) (xy 293.528687 -383.323786) (xy 293.52869 -383.25636)
			(xy 293.536769 -383.189419) (xy 293.552808 -383.123928) (xy 293.576576 -383.06083) (xy 293.60773 -383.001033)
			(xy 293.645822 -382.945397) (xy 293.667688 -382.919732) (xy 293.673495 -382.912594) (xy 293.680004 -382.895398)
			(xy 293.680388 -382.886204) (xy 293.680388 -382.728724) (xy 293.680835 -382.718605) (xy 293.688573 -382.699904)
			(xy 293.70288 -382.685589) (xy 293.721577 -382.677841) (xy 293.731696 -382.677416) (xy 294.447976 -382.677416)
			(xy 294.458099 -382.677836) (xy 294.476805 -382.685579) (xy 294.491121 -382.699895) (xy 294.498864 -382.718601)
			(xy 294.499284 -382.728724) (xy 294.499284 -382.886204) (xy 294.499696 -382.895391) (xy 294.506209 -382.912575)
			(xy 294.511984 -382.919732) (xy 294.533813 -382.945426) (xy 294.571904 -383.001056) (xy 294.603057 -383.060848)
			(xy 294.626824 -383.123941) (xy 294.642863 -383.189427) (xy 294.650942 -383.256362) (xy 294.650945 -383.323784)
			(xy 294.642872 -383.39072) (xy 294.62684 -383.456207) (xy 294.603079 -383.519302) (xy 294.571932 -383.579097)
			(xy 294.533846 -383.634731) (xy 294.511984 -383.660396) (xy 294.506205 -383.667553) (xy 294.49968 -383.684735)
			(xy 294.499284 -383.693924) (xy 294.499284 -384.186176) (xy 294.499709 -384.195361) (xy 294.506213 -384.212546)
			(xy 294.511984 -384.219704) (xy 294.533884 -384.24534) (xy 294.571973 -384.300978) (xy 294.603123 -384.360778)
			(xy 294.626885 -384.423879) (xy 294.642919 -384.489372) (xy 294.650992 -384.556314) (xy 294.650989 -384.62374)
			(xy 294.642909 -384.690681) (xy 294.626869 -384.756173) (xy 294.603101 -384.819271) (xy 294.571945 -384.879068)
			(xy 294.533851 -384.934703) (xy 294.511984 -384.960368) (xy 294.506174 -384.967504) (xy 294.499668 -384.984702)
			(xy 294.499284 -384.993896) (xy 294.499284 -385.151376) (xy 294.498864 -385.161499) (xy 294.491121 -385.180205)
			(xy 294.476805 -385.194521) (xy 294.458099 -385.202264) (xy 294.447976 -385.202684) (xy 293.731696 -385.202684)
			(xy 293.721571 -385.202287) (xy 293.702865 -385.194534) (xy 293.68855 -385.180212) (xy 293.680808 -385.161501)
			(xy 293.680388 -385.151376) (xy 293.680388 -384.993896) (xy 293.679982 -384.984708) (xy 293.673466 -384.967524)
			(xy 293.667688 -384.960368) (xy 293.64586 -384.934673) (xy 293.607771 -384.879043) (xy 293.576619 -384.819251)
			(xy 293.552854 -384.756158) (xy 293.536816 -384.690672) (xy 293.528737 -384.623737) (xy 293.528734 -384.556317)
			(xy 293.536806 -384.489381) (xy 293.552838 -384.423894) (xy 293.576597 -384.360799) (xy 293.607743 -384.301004)
			(xy 293.645827 -384.245369) (xy 293.667688 -384.219704) (xy 293.673464 -384.212544) (xy 293.679991 -384.195365)
			(xy 293.680388 -384.186176) (xy 293.680388 -383.693924) (xy 293.679969 -383.684738) (xy 293.673462 -383.667553)
			(xy 293.667688 -383.660396) (xy 293.645789 -383.63476) (xy 293.607702 -383.579121) (xy 293.576554 -383.51932)
			(xy 293.552792 -383.45622) (xy 293.53676 -383.390727) (xy 293.528687 -383.323786) (xy 292.426592 -383.323786)
			(xy 292.426804 -383.32435) (xy 292.442776 -383.389734) (xy 292.450819 -383.456559) (xy 292.450818 -383.523865)
			(xy 292.442772 -383.590689) (xy 292.426797 -383.656073) (xy 292.403121 -383.719078) (xy 292.372085 -383.778802)
			(xy 292.334133 -383.834388) (xy 292.312344 -383.86004) (xy 292.306541 -383.86718) (xy 292.300032 -383.884375)
			(xy 292.299644 -383.893568) (xy 292.299644 -384.051556) (xy 292.299149 -384.06167) (xy 292.291423 -384.080364)
			(xy 292.277132 -384.094679) (xy 292.258449 -384.102433) (xy 292.248336 -384.102864) (xy 291.531802 -384.102864)
			(xy 291.521676 -384.102372) (xy 291.502956 -384.094645) (xy 291.488599 -384.080361) (xy 291.480779 -384.06168)
			(xy 291.48024 -384.051556) (xy 291.48024 -383.893568) (xy 291.479836 -383.88438) (xy 291.473317 -383.867197)
			(xy 291.46754 -383.86004) (xy 291.445768 -383.834375) (xy 291.407819 -383.77879) (xy 291.376785 -383.719068)
			(xy 291.353111 -383.656066) (xy 291.337137 -383.590685) (xy 291.329092 -383.523864) (xy 291.32909 -383.45656)
			(xy 291.337133 -383.389739) (xy 291.353104 -383.324357) (xy 291.376775 -383.261354) (xy 291.407806 -383.20163)
			(xy 291.445753 -383.146044) (xy 291.46754 -383.120392) (xy 291.473328 -383.113241) (xy 291.479847 -383.096055)
			(xy 291.48024 -383.086864) (xy 291.48024 -382.593342) (xy 291.4798 -382.584158) (xy 291.473306 -382.566974)
			(xy 291.46754 -382.559814) (xy 291.445742 -382.53417) (xy 291.407794 -382.478582) (xy 291.376761 -382.418858)
			(xy 291.353088 -382.355852) (xy 291.337116 -382.290469) (xy 291.329073 -382.223645) (xy 288.051034 -382.223645)
			(xy 288.051034 -382.223704) (xy 288.042958 -382.290643) (xy 288.026922 -382.356132) (xy 288.003157 -382.419229)
			(xy 287.972004 -382.479024) (xy 287.933913 -382.534658) (xy 287.912048 -382.560322) (xy 287.906253 -382.567468)
			(xy 287.899739 -382.584658) (xy 287.899348 -382.59385) (xy 287.899348 -383.086356) (xy 287.899791 -383.095539)
			(xy 287.906283 -383.112723) (xy 287.912048 -383.119884) (xy 287.93393 -383.145535) (xy 287.972021 -383.201171)
			(xy 288.003174 -383.260968) (xy 288.026812 -383.323727) (xy 289.128894 -383.323727) (xy 289.128898 -383.256418)
			(xy 289.136946 -383.189593) (xy 289.152924 -383.124208) (xy 289.176604 -383.061202) (xy 289.207644 -383.001477)
			(xy 289.245601 -382.945891) (xy 289.267392 -382.92024) (xy 289.273196 -382.9131) (xy 289.279706 -382.895905)
			(xy 289.280092 -382.886712) (xy 289.280092 -382.728724) (xy 289.280535 -382.718604) (xy 289.288274 -382.699902)
			(xy 289.302582 -382.685588) (xy 289.32128 -382.67784) (xy 289.3314 -382.677416) (xy 290.047934 -382.677416)
			(xy 290.05806 -382.677898) (xy 290.076777 -382.685632) (xy 290.091132 -382.69992) (xy 290.098954 -382.7186)
			(xy 290.099496 -382.728724) (xy 290.099496 -382.886712) (xy 290.099901 -382.8959) (xy 290.106419 -382.913084)
			(xy 290.112196 -382.92024) (xy 290.133947 -382.945922) (xy 290.171895 -383.001505) (xy 290.202928 -383.061225)
			(xy 290.226601 -383.124225) (xy 290.242576 -383.189603) (xy 290.250622 -383.256422) (xy 290.250625 -383.323724)
			(xy 290.242585 -383.390543) (xy 290.226617 -383.455923) (xy 290.20295 -383.518926) (xy 290.171923 -383.578649)
			(xy 290.133981 -383.634235) (xy 290.112196 -383.659888) (xy 290.106379 -383.667019) (xy 290.099877 -383.68422)
			(xy 290.099496 -383.693416) (xy 290.099496 -384.186684) (xy 290.099915 -384.19587) (xy 290.106423 -384.213055)
			(xy 290.112196 -384.220212) (xy 290.134018 -384.245836) (xy 290.171963 -384.301427) (xy 290.202993 -384.361155)
			(xy 290.226662 -384.424163) (xy 290.242632 -384.489548) (xy 290.250673 -384.556373) (xy 290.250669 -384.623681)
			(xy 290.242622 -384.690505) (xy 290.226646 -384.755889) (xy 290.202971 -384.818895) (xy 290.171936 -384.87862)
			(xy 290.133985 -384.934207) (xy 290.112196 -384.95986) (xy 290.106391 -384.966999) (xy 290.099881 -384.984194)
			(xy 290.099496 -384.993388) (xy 290.099496 -385.151376) (xy 290.099064 -385.161497) (xy 290.091323 -385.180201)
			(xy 290.077011 -385.194517) (xy 290.058309 -385.202262) (xy 290.048188 -385.202684) (xy 289.331654 -385.202684)
			(xy 289.321527 -385.202212) (xy 289.30281 -385.194473) (xy 289.288456 -385.180183) (xy 289.280634 -385.1615)
			(xy 289.280092 -385.151376) (xy 289.280092 -384.993388) (xy 289.279689 -384.9842) (xy 289.273171 -384.967016)
			(xy 289.267392 -384.95986) (xy 289.245638 -384.934179) (xy 289.207685 -384.878598) (xy 289.176647 -384.818879)
			(xy 289.15297 -384.755878) (xy 289.136993 -384.690499) (xy 289.128945 -384.623679) (xy 289.128942 -384.556375)
			(xy 289.136983 -384.489554) (xy 289.152954 -384.424174) (xy 289.176625 -384.36117) (xy 289.207657 -384.301448)
			(xy 289.245605 -384.245863) (xy 289.267392 -384.220212) (xy 289.273208 -384.21308) (xy 289.279711 -384.195879)
			(xy 289.280092 -384.186684) (xy 289.280092 -383.693416) (xy 289.279676 -383.684229) (xy 289.273167 -383.667045)
			(xy 289.267392 -383.659888) (xy 289.245567 -383.634266) (xy 289.207616 -383.578676) (xy 289.176581 -383.518949)
			(xy 289.152908 -383.45594) (xy 289.136936 -383.390554) (xy 289.128894 -383.323727) (xy 288.026812 -383.323727)
			(xy 288.02694 -383.324067) (xy 288.042976 -383.389558) (xy 288.051051 -383.456499) (xy 288.05105 -383.523925)
			(xy 288.042971 -383.590865) (xy 288.026933 -383.656356) (xy 288.003164 -383.719454) (xy 287.972009 -383.77925)
			(xy 287.933915 -383.834884) (xy 287.912048 -383.860548) (xy 287.906242 -383.867686) (xy 287.899734 -383.884882)
			(xy 287.899348 -383.894076) (xy 287.899348 -384.051556) (xy 287.898849 -384.06167) (xy 287.891124 -384.080363)
			(xy 287.876834 -384.094677) (xy 287.858153 -384.102432) (xy 287.84804 -384.102864) (xy 287.13176 -384.102864)
			(xy 287.12163 -384.102516) (xy 287.102919 -384.094748) (xy 287.088605 -384.08041) (xy 287.080868 -384.061686)
			(xy 287.080452 -384.051556) (xy 287.080452 -383.894076) (xy 287.080042 -383.884889) (xy 287.073527 -383.867705)
			(xy 287.067752 -383.860548) (xy 287.045902 -383.834871) (xy 287.007809 -383.779239) (xy 286.976655 -383.719445)
			(xy 286.952888 -383.65635) (xy 286.936849 -383.590862) (xy 286.928772 -383.523924) (xy 286.92877 -383.4565)
			(xy 286.936845 -383.389562) (xy 286.952881 -383.324073) (xy 286.976645 -383.260977) (xy 287.007797 -383.201182)
			(xy 287.045887 -383.145548) (xy 287.067752 -383.119884) (xy 287.073544 -383.112736) (xy 287.08006 -383.095547)
			(xy 287.080452 -383.086356) (xy 287.080452 -382.59385) (xy 287.080006 -382.584667) (xy 287.073516 -382.567483)
			(xy 287.067752 -382.560322) (xy 287.045876 -382.534666) (xy 287.007785 -382.479031) (xy 286.976631 -382.419234)
			(xy 286.952865 -382.356136) (xy 286.936829 -382.290645) (xy 286.928753 -382.223705) (xy 262.654796 -382.223705)
			(xy 262.654796 -385.608376) (xy 454.303373 -385.608376) (xy 454.303373 -385.479236) (xy 454.311323 -385.350341)
			(xy 454.327193 -385.222181) (xy 454.350922 -385.09524) (xy 454.382421 -384.970001) (xy 454.42157 -384.846938)
			(xy 454.468221 -384.726519) (xy 454.522196 -384.6092) (xy 454.583291 -384.495426) (xy 454.651274 -384.385629)
			(xy 454.725888 -384.280226) (xy 454.806849 -384.179616) (xy 454.893849 -384.084181) (xy 454.98656 -383.994282)
			(xy 455.08463 -383.910261) (xy 455.187685 -383.832437) (xy 455.295336 -383.761105) (xy 455.407175 -383.696535)
			(xy 455.522776 -383.638973) (xy 455.641701 -383.588636) (xy 455.7635 -383.545716) (xy 455.88771 -383.510375)
			(xy 456.013859 -383.482748) (xy 456.141471 -383.462939) (xy 456.27006 -383.451023) (xy 456.399138 -383.447047)
			(xy 456.528216 -383.451023) (xy 456.656805 -383.462939) (xy 456.784417 -383.482748) (xy 456.910566 -383.510375)
			(xy 457.034776 -383.545716) (xy 457.156575 -383.588636) (xy 457.2755 -383.638973) (xy 457.391101 -383.696535)
			(xy 457.50294 -383.761105) (xy 457.610591 -383.832437) (xy 457.713646 -383.910261) (xy 457.811716 -383.994282)
			(xy 457.904427 -384.084181) (xy 457.991427 -384.179616) (xy 458.072388 -384.280226) (xy 458.147002 -384.385629)
			(xy 458.214985 -384.495426) (xy 458.27608 -384.6092) (xy 458.330055 -384.726519) (xy 458.376706 -384.846938)
			(xy 458.415855 -384.970001) (xy 458.447354 -385.09524) (xy 458.471083 -385.222181) (xy 458.486953 -385.350341)
			(xy 458.494903 -385.479236) (xy 458.4954 -385.543806) (xy 458.494903 -385.608376) (xy 458.486953 -385.737271)
			(xy 458.471083 -385.865431) (xy 458.447354 -385.992372) (xy 458.415855 -386.117611) (xy 458.376706 -386.240674)
			(xy 458.330055 -386.361093) (xy 458.27608 -386.478412) (xy 458.214985 -386.592186) (xy 458.147002 -386.701983)
			(xy 458.072388 -386.807386) (xy 457.991427 -386.907996) (xy 457.904427 -387.003431) (xy 457.811716 -387.09333)
			(xy 457.713646 -387.177351) (xy 457.610591 -387.255175) (xy 457.50294 -387.326507) (xy 457.391101 -387.391077)
			(xy 457.2755 -387.448639) (xy 457.156575 -387.498976) (xy 457.034776 -387.541896) (xy 456.910566 -387.577237)
			(xy 456.784417 -387.604864) (xy 456.656805 -387.624673) (xy 456.528216 -387.636589) (xy 456.399138 -387.640566)
			(xy 456.27006 -387.636589) (xy 456.141471 -387.624673) (xy 456.013859 -387.604864) (xy 455.88771 -387.577237)
			(xy 455.7635 -387.541896) (xy 455.641701 -387.498976) (xy 455.522776 -387.448639) (xy 455.407175 -387.391077)
			(xy 455.295336 -387.326507) (xy 455.187685 -387.255175) (xy 455.08463 -387.177351) (xy 454.98656 -387.09333)
			(xy 454.893849 -387.003431) (xy 454.806849 -386.907996) (xy 454.725888 -386.807386) (xy 454.651274 -386.701983)
			(xy 454.583291 -386.592186) (xy 454.522196 -386.478412) (xy 454.468221 -386.361093) (xy 454.42157 -386.240674)
			(xy 454.382421 -386.117611) (xy 454.350922 -385.992372) (xy 454.327193 -385.865431) (xy 454.311323 -385.737271)
			(xy 454.303373 -385.608376) (xy 262.654796 -385.608376) (xy 262.654796 -387.940042) (xy 262.654324 -387.964992)
			(xy 262.646505 -388.014277) (xy 262.631083 -388.061734) (xy 262.608436 -388.1062) (xy 262.57912 -388.146581)
			(xy 262.561832 -388.164578) (xy 259.433314 -391.293096) (xy 259.415316 -391.310383) (xy 259.374941 -391.339708)
			(xy 259.330476 -391.362356) (xy 259.283016 -391.377771) (xy 259.233728 -391.385573) (xy 259.208778 -391.38606)
			(xy 245.30812 -391.38606) (xy 245.29805 -391.38648) (xy 245.279451 -391.394203) (xy 245.272052 -391.401046)
			(xy 244.461792 -392.211306) (xy 244.454956 -392.218709) (xy 244.447234 -392.237306) (xy 244.446806 -392.247374)
			(xy 244.446806 -397.823885) (xy 286.928734 -397.823885) (xy 286.928737 -397.756458) (xy 286.936817 -397.689516)
			(xy 286.952859 -397.624024) (xy 286.976629 -397.560925) (xy 287.007787 -397.501128) (xy 287.045884 -397.445494)
			(xy 287.067752 -397.41983) (xy 287.073567 -397.412698) (xy 287.080069 -397.395497) (xy 287.080452 -397.386302)
			(xy 287.080452 -396.89405) (xy 287.080006 -396.884867) (xy 287.073516 -396.867683) (xy 287.067752 -396.860522)
			(xy 287.045876 -396.834866) (xy 287.007785 -396.779231) (xy 286.976631 -396.719434) (xy 286.952865 -396.656336)
			(xy 286.936829 -396.590845) (xy 286.928753 -396.523905) (xy 286.928754 -396.45648) (xy 286.936832 -396.38954)
			(xy 286.95287 -396.32405) (xy 286.976638 -396.260952) (xy 287.007792 -396.201156) (xy 287.045886 -396.145522)
			(xy 287.067752 -396.119858) (xy 287.073555 -396.112718) (xy 287.080065 -396.095523) (xy 287.080452 -396.08633)
			(xy 287.080452 -395.92885) (xy 287.080968 -395.918725) (xy 287.088682 -395.900003) (xy 287.102959 -395.885644)
			(xy 287.121638 -395.877825) (xy 287.13176 -395.877288) (xy 287.84804 -395.877288) (xy 287.858195 -395.877689)
			(xy 287.876946 -395.885495) (xy 287.891268 -395.899898) (xy 287.898968 -395.918693) (xy 287.899348 -395.92885)
			(xy 287.899348 -396.08633) (xy 287.899755 -396.095517) (xy 287.906272 -396.112701) (xy 287.912048 -396.119858)
			(xy 287.933904 -396.14553) (xy 287.971996 -396.201163) (xy 288.00315 -396.260957) (xy 288.026917 -396.324053)
			(xy 288.042955 -396.389542) (xy 288.051033 -396.456481) (xy 288.051034 -396.523904) (xy 288.042958 -396.590843)
			(xy 288.026922 -396.656332) (xy 288.003157 -396.719429) (xy 287.972004 -396.779224) (xy 287.933913 -396.834858)
			(xy 287.912048 -396.860522) (xy 287.906253 -396.867668) (xy 287.899739 -396.884858) (xy 287.899348 -396.89405)
			(xy 287.899348 -397.386302) (xy 287.899769 -397.395488) (xy 287.906276 -397.412672) (xy 287.912048 -397.41983)
			(xy 287.933876 -397.445525) (xy 287.97197 -397.501154) (xy 288.000733 -397.556355) (xy 289.128926 -397.556355)
			(xy 289.13697 -397.489532) (xy 289.152943 -397.42415) (xy 289.176617 -397.361145) (xy 289.207652 -397.301423)
			(xy 289.245603 -397.245837) (xy 289.267392 -397.220186) (xy 289.273176 -397.213032) (xy 289.279698 -397.195848)
			(xy 289.280092 -397.186658) (xy 289.280092 -397.028924) (xy 289.280541 -397.018772) (xy 289.288327 -397.000022)
			(xy 289.302715 -396.985698) (xy 289.321501 -396.977996) (xy 289.331654 -396.977616) (xy 290.047934 -396.977616)
			(xy 290.05806 -396.978098) (xy 290.076777 -396.985832) (xy 290.091132 -397.00012) (xy 290.098954 -397.0188)
			(xy 290.099496 -397.028924) (xy 290.099496 -397.186658) (xy 290.099927 -397.195843) (xy 290.106426 -397.213027)
			(xy 290.112196 -397.220186) (xy 290.133992 -397.245831) (xy 290.171939 -397.301419) (xy 290.20297 -397.361144)
			(xy 290.22664 -397.424149) (xy 290.242612 -397.489532) (xy 290.250654 -397.556355) (xy 290.250653 -397.62366)
			(xy 290.242609 -397.690483) (xy 290.226636 -397.755865) (xy 290.202963 -397.81887) (xy 290.200388 -397.823825)
			(xy 291.329053 -397.823825) (xy 291.329057 -397.756517) (xy 291.337105 -397.689692) (xy 291.353082 -397.624308)
			(xy 291.376759 -397.561302) (xy 291.407796 -397.501577) (xy 291.44575 -397.44599) (xy 291.46754 -397.420338)
			(xy 291.47335 -397.413203) (xy 291.479856 -397.396004) (xy 291.48024 -397.38681) (xy 291.48024 -396.893542)
			(xy 291.4798 -396.884358) (xy 291.473306 -396.867174) (xy 291.46754 -396.860014) (xy 291.445742 -396.83437)
			(xy 291.407794 -396.778782) (xy 291.376761 -396.719058) (xy 291.353088 -396.656052) (xy 291.337116 -396.590669)
			(xy 291.329073 -396.523845) (xy 291.329074 -396.45654) (xy 291.337119 -396.389716) (xy 291.353093 -396.324333)
			(xy 291.376767 -396.261328) (xy 291.407801 -396.201605) (xy 291.445751 -396.146018) (xy 291.46754 -396.120366)
			(xy 291.473339 -396.113222) (xy 291.479851 -396.096031) (xy 291.48024 -396.086838) (xy 291.48024 -395.92885)
			(xy 291.480705 -395.918681) (xy 291.488474 -395.899887) (xy 291.502847 -395.885501) (xy 291.521634 -395.877714)
			(xy 291.531802 -395.877288) (xy 292.248082 -395.877288) (xy 292.258259 -395.87768) (xy 292.277063 -395.885468)
			(xy 292.29145 -395.899864) (xy 292.299227 -395.918673) (xy 292.299644 -395.92885) (xy 292.299644 -396.086838)
			(xy 292.300049 -396.096026) (xy 292.306568 -396.113209) (xy 292.312344 -396.120366) (xy 292.334122 -396.146026)
			(xy 292.372072 -396.201611) (xy 292.403107 -396.261333) (xy 292.426781 -396.324337) (xy 292.442755 -396.389718)
			(xy 292.450801 -396.45654) (xy 292.450801 -396.523845) (xy 292.442758 -396.590667) (xy 292.426786 -396.656049)
			(xy 292.403113 -396.719053) (xy 292.37208 -396.778776) (xy 292.334131 -396.834362) (xy 292.312344 -396.860014)
			(xy 292.306552 -396.867162) (xy 292.300036 -396.884351) (xy 292.299644 -396.893542) (xy 292.299644 -397.38681)
			(xy 292.300062 -397.395996) (xy 292.306572 -397.41318) (xy 292.312344 -397.420338) (xy 292.334095 -397.446021)
			(xy 292.372046 -397.501602) (xy 292.40047 -397.556296) (xy 293.528718 -397.556296) (xy 293.536793 -397.489359)
			(xy 293.552827 -397.42387) (xy 293.576589 -397.360774) (xy 293.607738 -397.300978) (xy 293.645825 -397.245343)
			(xy 293.667688 -397.219678) (xy 293.673475 -397.212526) (xy 293.679996 -397.195341) (xy 293.680388 -397.18615)
			(xy 293.680388 -397.028924) (xy 293.680835 -397.018805) (xy 293.688573 -397.000104) (xy 293.70288 -396.985789)
			(xy 293.721577 -396.978041) (xy 293.731696 -396.977616) (xy 294.447976 -396.977616) (xy 294.458099 -396.978036)
			(xy 294.476805 -396.985779) (xy 294.491121 -397.000095) (xy 294.498864 -397.018801) (xy 294.499284 -397.028924)
			(xy 294.499284 -397.18615) (xy 294.499722 -397.195334) (xy 294.506217 -397.212519) (xy 294.511984 -397.219678)
			(xy 294.533858 -397.245335) (xy 294.571948 -397.30097) (xy 294.603099 -397.360767) (xy 294.626863 -397.423865)
			(xy 294.642899 -397.489356) (xy 294.650974 -397.556295) (xy 294.650973 -397.62372) (xy 294.642896 -397.690659)
			(xy 294.626859 -397.756149) (xy 294.603093 -397.819246) (xy 294.600676 -397.823885) (xy 295.728821 -397.823885)
			(xy 295.728825 -397.756458) (xy 295.736905 -397.689516) (xy 295.752946 -397.624025) (xy 295.776716 -397.560926)
			(xy 295.807873 -397.501129) (xy 295.845969 -397.445495) (xy 295.867836 -397.41983) (xy 295.873649 -397.412697)
			(xy 295.880153 -397.395497) (xy 295.880536 -397.386302) (xy 295.880536 -396.89405) (xy 295.880094 -396.884866)
			(xy 295.873601 -396.867682) (xy 295.867836 -396.860522) (xy 295.845961 -396.834865) (xy 295.80787 -396.779231)
			(xy 295.776718 -396.719433) (xy 295.752953 -396.656335) (xy 295.736917 -396.590845) (xy 295.728841 -396.523905)
			(xy 295.728842 -396.45648) (xy 295.73692 -396.38954) (xy 295.752957 -396.32405) (xy 295.776724 -396.260953)
			(xy 295.807878 -396.201157) (xy 295.84597 -396.145523) (xy 295.867836 -396.119858) (xy 295.873637 -396.112716)
			(xy 295.880148 -396.095523) (xy 295.880536 -396.08633) (xy 295.880536 -395.92885) (xy 295.881067 -395.918727)
			(xy 295.888778 -395.900008) (xy 295.903051 -395.88565) (xy 295.921724 -395.877828) (xy 295.931844 -395.877288)
			(xy 296.648124 -395.877288) (xy 296.658278 -395.877702) (xy 296.677029 -395.885503) (xy 296.691351 -395.899902)
			(xy 296.699052 -395.918694) (xy 296.699432 -395.92885) (xy 296.699432 -396.08633) (xy 296.699843 -396.095517)
			(xy 296.706358 -396.1127) (xy 296.712132 -396.119858) (xy 296.733985 -396.145532) (xy 296.772072 -396.201166)
			(xy 296.803221 -396.260961) (xy 296.826985 -396.324057) (xy 296.84302 -396.389545) (xy 296.851096 -396.456481)
			(xy 296.851097 -396.523904) (xy 296.843022 -396.590841) (xy 296.826989 -396.656329) (xy 296.803227 -396.719425)
			(xy 296.77208 -396.779221) (xy 296.733994 -396.834856) (xy 296.712132 -396.860522) (xy 296.706335 -396.867667)
			(xy 296.699823 -396.884858) (xy 296.699432 -396.89405) (xy 296.699432 -397.386302) (xy 296.699856 -397.395487)
			(xy 296.706362 -397.412671) (xy 296.712132 -397.41983) (xy 296.733958 -397.445527) (xy 296.772045 -397.501157)
			(xy 296.800802 -397.556355) (xy 297.929014 -397.556355) (xy 297.937057 -397.489532) (xy 297.95303 -397.42415)
			(xy 297.976704 -397.361146) (xy 298.007738 -397.301423) (xy 298.045688 -397.245838) (xy 298.067476 -397.220186)
			(xy 298.073258 -397.21303) (xy 298.079782 -397.195848) (xy 298.080176 -397.186658) (xy 298.080176 -397.028924)
			(xy 298.080641 -397.018774) (xy 298.088424 -397.000027) (xy 298.102807 -396.985704) (xy 298.121587 -396.977999)
			(xy 298.131738 -396.977616) (xy 298.848018 -396.977616) (xy 298.858143 -396.978111) (xy 298.87686 -396.98584)
			(xy 298.891215 -397.000123) (xy 298.899038 -397.018802) (xy 298.89958 -397.028924) (xy 298.89958 -397.186658)
			(xy 298.900015 -397.195842) (xy 298.906512 -397.213027) (xy 298.91228 -397.220186) (xy 298.934077 -397.24583)
			(xy 298.972024 -397.301418) (xy 299.003056 -397.361143) (xy 299.026728 -397.424149) (xy 299.042699 -397.489532)
			(xy 299.050742 -397.556355) (xy 299.050741 -397.62366) (xy 299.042697 -397.690483) (xy 299.026723 -397.755866)
			(xy 299.00305 -397.818871) (xy 299.000445 -397.823885) (xy 300.128612 -397.823885) (xy 300.128616 -397.756458)
			(xy 300.136696 -397.689517) (xy 300.152736 -397.624025) (xy 300.176506 -397.560927) (xy 300.207662 -397.501129)
			(xy 300.245757 -397.445495) (xy 300.267624 -397.41983) (xy 300.273436 -397.412696) (xy 300.27994 -397.395497)
			(xy 300.280324 -397.386302) (xy 300.280324 -396.89405) (xy 300.279884 -396.884866) (xy 300.273391 -396.867682)
			(xy 300.267624 -396.860522) (xy 300.245749 -396.834865) (xy 300.207659 -396.77923) (xy 300.176508 -396.719433)
			(xy 300.152743 -396.656335) (xy 300.136708 -396.590845) (xy 300.128632 -396.523905) (xy 300.128633 -396.45648)
			(xy 300.13671 -396.389541) (xy 300.152748 -396.324051) (xy 300.176514 -396.260953) (xy 300.207667 -396.201157)
			(xy 300.245759 -396.145523) (xy 300.267624 -396.119858) (xy 300.273424 -396.112715) (xy 300.279936 -396.095523)
			(xy 300.280324 -396.08633) (xy 300.280324 -395.92885) (xy 300.280867 -395.918728) (xy 300.288576 -395.900011)
			(xy 300.302845 -395.885654) (xy 300.321514 -395.87783) (xy 300.331632 -395.877288) (xy 301.047912 -395.877288)
			(xy 301.058065 -395.877711) (xy 301.076816 -395.885509) (xy 301.091138 -395.899904) (xy 301.09884 -395.918694)
			(xy 301.09922 -395.92885) (xy 301.09922 -396.08633) (xy 301.099611 -396.095519) (xy 301.106138 -396.112704)
			(xy 301.11192 -396.119858) (xy 301.133773 -396.145532) (xy 301.171861 -396.201165) (xy 301.203011 -396.260961)
			(xy 301.226775 -396.324056) (xy 301.242811 -396.389544) (xy 301.250887 -396.456481) (xy 301.250888 -396.523904)
			(xy 301.242813 -396.590841) (xy 301.226779 -396.656329) (xy 301.203017 -396.719426) (xy 301.171869 -396.779222)
			(xy 301.133783 -396.834856) (xy 301.11192 -396.860522) (xy 301.106134 -396.867675) (xy 301.099612 -396.884859)
			(xy 301.09922 -396.89405) (xy 301.09922 -397.386302) (xy 301.099625 -397.39549) (xy 301.106142 -397.412674)
			(xy 301.11192 -397.41983) (xy 301.133746 -397.445526) (xy 301.171834 -397.501157) (xy 301.200562 -397.556296)
			(xy 302.328806 -397.556296) (xy 302.336881 -397.489359) (xy 302.352914 -397.423871) (xy 302.376676 -397.360775)
			(xy 302.407824 -397.300979) (xy 302.44591 -397.245344) (xy 302.467772 -397.219678) (xy 302.473569 -397.212534)
			(xy 302.480081 -397.195342) (xy 302.480472 -397.18615) (xy 302.480472 -397.028924) (xy 302.480935 -397.018806)
			(xy 302.48867 -397.000109) (xy 302.502972 -396.985795) (xy 302.521663 -396.978043) (xy 302.53178 -396.977616)
			(xy 303.24806 -396.977616) (xy 303.258182 -396.978049) (xy 303.276888 -396.985787) (xy 303.291204 -397.000099)
			(xy 303.298948 -397.018802) (xy 303.299368 -397.028924) (xy 303.299368 -397.18615) (xy 303.299809 -397.195334)
			(xy 303.306302 -397.212518) (xy 303.312068 -397.219678) (xy 303.333943 -397.245335) (xy 303.372033 -397.30097)
			(xy 303.403185 -397.360767) (xy 303.426951 -397.423865) (xy 303.442986 -397.489355) (xy 303.451062 -397.556295)
			(xy 303.451061 -397.62372) (xy 303.442984 -397.69066) (xy 303.426946 -397.75615) (xy 303.403179 -397.819247)
			(xy 303.372026 -397.879043) (xy 303.333934 -397.934677) (xy 303.312068 -397.960342) (xy 303.306267 -397.967484)
			(xy 303.299756 -397.984677) (xy 303.299368 -397.99387) (xy 303.299368 -398.486376) (xy 303.299797 -398.495561)
			(xy 303.306299 -398.512745) (xy 303.312068 -398.519904) (xy 303.333968 -398.54554) (xy 303.372058 -398.601178)
			(xy 303.403209 -398.660978) (xy 303.426973 -398.724078) (xy 303.443007 -398.789571) (xy 303.45108 -398.856513)
			(xy 303.451077 -398.923941) (xy 303.442997 -398.990882) (xy 303.426957 -399.056373) (xy 303.403187 -399.119472)
			(xy 303.37203 -399.179269) (xy 303.333935 -399.234903) (xy 303.312068 -399.260568) (xy 303.306256 -399.267702)
			(xy 303.299751 -399.284901) (xy 303.299368 -399.294096) (xy 303.299368 -399.451576) (xy 303.298964 -399.461701)
			(xy 303.291218 -399.48041) (xy 303.276897 -399.494727) (xy 303.258185 -399.502467) (xy 303.24806 -399.502884)
			(xy 302.53178 -399.502884) (xy 302.521654 -399.5025) (xy 302.502947 -399.494742) (xy 302.488633 -399.480416)
			(xy 302.480891 -399.461702) (xy 302.480472 -399.451576) (xy 302.480472 -399.294096) (xy 302.48007 -399.284908)
			(xy 302.473551 -399.267723) (xy 302.467772 -399.260568) (xy 302.445944 -399.234873) (xy 302.407856 -399.179242)
			(xy 302.376706 -399.11945) (xy 302.352941 -399.056357) (xy 302.336904 -398.990872) (xy 302.328825 -398.923937)
			(xy 302.328822 -398.856517) (xy 302.336894 -398.789582) (xy 302.352925 -398.724095) (xy 302.376684 -398.661)
			(xy 302.407829 -398.601204) (xy 302.445911 -398.54557) (xy 302.467772 -398.519904) (xy 302.473558 -398.512752)
			(xy 302.480077 -398.495566) (xy 302.480472 -398.486376) (xy 302.480472 -397.99387) (xy 302.480082 -397.98468)
			(xy 302.473555 -397.967496) (xy 302.467772 -397.960342) (xy 302.445919 -397.934668) (xy 302.407832 -397.879034)
			(xy 302.376682 -397.819239) (xy 302.352919 -397.756143) (xy 302.336883 -397.690656) (xy 302.328807 -397.623719)
			(xy 302.328806 -397.556296) (xy 301.200562 -397.556296) (xy 301.202986 -397.560949) (xy 301.226751 -397.624042)
			(xy 301.242789 -397.689527) (xy 301.250867 -397.756461) (xy 301.250871 -397.823882) (xy 301.242799 -397.890817)
			(xy 301.226768 -397.956304) (xy 301.203009 -398.019399) (xy 301.171864 -398.079194) (xy 301.133781 -398.134828)
			(xy 301.11192 -398.160494) (xy 301.106146 -398.167655) (xy 301.099617 -398.184833) (xy 301.09922 -398.194022)
			(xy 301.09922 -398.351502) (xy 301.098774 -398.361634) (xy 301.091038 -398.380362) (xy 301.076739 -398.39472)
			(xy 301.058042 -398.402532) (xy 301.047912 -398.403064) (xy 300.331632 -398.403064) (xy 300.321475 -398.402652)
			(xy 300.302717 -398.39486) (xy 300.288391 -398.38046) (xy 300.280696 -398.361661) (xy 300.280324 -398.351502)
			(xy 300.280324 -398.194022) (xy 300.279898 -398.184837) (xy 300.273395 -398.167652) (xy 300.267624 -398.160494)
			(xy 300.245722 -398.13486) (xy 300.207633 -398.079222) (xy 300.176482 -398.019421) (xy 300.152719 -397.95632)
			(xy 300.136686 -397.890827) (xy 300.128612 -397.823885) (xy 299.000445 -397.823885) (xy 298.972017 -397.878595)
			(xy 298.934068 -397.934182) (xy 298.91228 -397.959834) (xy 298.906484 -397.96698) (xy 298.89997 -397.98417)
			(xy 298.89958 -397.993362) (xy 298.89958 -398.486884) (xy 298.900003 -398.49607) (xy 298.906508 -398.513254)
			(xy 298.91228 -398.520412) (xy 298.934103 -398.546035) (xy 298.972049 -398.601626) (xy 299.00308 -398.661354)
			(xy 299.02675 -398.724362) (xy 299.04272 -398.789748) (xy 299.050761 -398.856573) (xy 299.050757 -398.923881)
			(xy 299.04271 -398.990706) (xy 299.026734 -399.05609) (xy 299.003058 -399.119095) (xy 298.972021 -399.17882)
			(xy 298.934069 -399.234408) (xy 298.91228 -399.26006) (xy 298.906473 -399.267198) (xy 298.899965 -399.284394)
			(xy 298.89958 -399.293588) (xy 298.89958 -399.451576) (xy 298.899159 -399.461731) (xy 298.891367 -399.480487)
			(xy 298.87697 -399.494812) (xy 298.858175 -399.502509) (xy 298.848018 -399.502884) (xy 298.131738 -399.502884)
			(xy 298.121617 -399.502343) (xy 298.102901 -399.494632) (xy 298.088544 -399.480362) (xy 298.08072 -399.461694)
			(xy 298.080176 -399.451576) (xy 298.080176 -399.293588) (xy 298.079777 -399.2844) (xy 298.073256 -399.267215)
			(xy 298.067476 -399.26006) (xy 298.045723 -399.234379) (xy 298.00777 -399.178798) (xy 297.976733 -399.119078)
			(xy 297.953057 -399.056078) (xy 297.93708 -398.990699) (xy 297.929033 -398.923879) (xy 297.92903 -398.856576)
			(xy 297.937071 -398.789755) (xy 297.953041 -398.724374) (xy 297.976711 -398.661371) (xy 298.007742 -398.601649)
			(xy 298.045689 -398.546064) (xy 298.067476 -398.520412) (xy 298.07329 -398.513279) (xy 298.079795 -398.496079)
			(xy 298.080176 -398.486884) (xy 298.080176 -397.993362) (xy 298.079789 -397.984172) (xy 298.07326 -397.966988)
			(xy 298.067476 -397.959834) (xy 298.045697 -397.934174) (xy 298.007746 -397.87859) (xy 297.97671 -397.818868)
			(xy 297.953035 -397.755864) (xy 297.93706 -397.690482) (xy 297.929015 -397.62366) (xy 297.929014 -397.556355)
			(xy 296.800802 -397.556355) (xy 296.803196 -397.56095) (xy 296.826961 -397.624042) (xy 296.842998 -397.689527)
			(xy 296.851076 -397.756461) (xy 296.85108 -397.823881) (xy 296.843008 -397.890817) (xy 296.826978 -397.956303)
			(xy 296.803219 -398.019398) (xy 296.772075 -398.079194) (xy 296.733993 -398.134828) (xy 296.712132 -398.160494)
			(xy 296.706347 -398.167647) (xy 296.699827 -398.184832) (xy 296.699432 -398.194022) (xy 296.699432 -398.351502)
			(xy 296.698974 -398.361632) (xy 296.691241 -398.380359) (xy 296.676945 -398.394716) (xy 296.658252 -398.40253)
			(xy 296.648124 -398.403064) (xy 295.931844 -398.403064) (xy 295.921688 -398.402642) (xy 295.90293 -398.394854)
			(xy 295.888604 -398.380456) (xy 295.880909 -398.36166) (xy 295.880536 -398.351502) (xy 295.880536 -398.194022)
			(xy 295.880107 -398.184837) (xy 295.873606 -398.167653) (xy 295.867836 -398.160494) (xy 295.845933 -398.13486)
			(xy 295.807843 -398.079222) (xy 295.776692 -398.019422) (xy 295.752929 -397.956321) (xy 295.736895 -397.890827)
			(xy 295.728821 -397.823885) (xy 294.600676 -397.823885) (xy 294.57194 -397.879043) (xy 294.533849 -397.934677)
			(xy 294.511984 -397.960342) (xy 294.506185 -397.967486) (xy 294.499672 -397.984677) (xy 294.499284 -397.99387)
			(xy 294.499284 -398.486376) (xy 294.499709 -398.495561) (xy 294.506213 -398.512746) (xy 294.511984 -398.519904)
			(xy 294.533884 -398.54554) (xy 294.571973 -398.601178) (xy 294.603123 -398.660978) (xy 294.626885 -398.724079)
			(xy 294.642919 -398.789572) (xy 294.650992 -398.856514) (xy 294.650989 -398.92394) (xy 294.642909 -398.990881)
			(xy 294.626869 -399.056373) (xy 294.603101 -399.119471) (xy 294.571945 -399.179268) (xy 294.533851 -399.234903)
			(xy 294.511984 -399.260568) (xy 294.506174 -399.267704) (xy 294.499668 -399.284902) (xy 294.499284 -399.294096)
			(xy 294.499284 -399.451576) (xy 294.498864 -399.461699) (xy 294.491121 -399.480405) (xy 294.476805 -399.494721)
			(xy 294.458099 -399.502464) (xy 294.447976 -399.502884) (xy 293.731696 -399.502884) (xy 293.721571 -399.502487)
			(xy 293.702865 -399.494734) (xy 293.68855 -399.480412) (xy 293.680808 -399.461701) (xy 293.680388 -399.451576)
			(xy 293.680388 -399.294096) (xy 293.679982 -399.284908) (xy 293.673466 -399.267724) (xy 293.667688 -399.260568)
			(xy 293.64586 -399.234873) (xy 293.607771 -399.179243) (xy 293.576619 -399.119451) (xy 293.552854 -399.056358)
			(xy 293.536816 -398.990872) (xy 293.528737 -398.923937) (xy 293.528734 -398.856517) (xy 293.536806 -398.789581)
			(xy 293.552838 -398.724094) (xy 293.576597 -398.660999) (xy 293.607743 -398.601204) (xy 293.645827 -398.545569)
			(xy 293.667688 -398.519904) (xy 293.673464 -398.512744) (xy 293.679991 -398.495565) (xy 293.680388 -398.486376)
			(xy 293.680388 -397.99387) (xy 293.679995 -397.984681) (xy 293.673469 -397.967497) (xy 293.667688 -397.960342)
			(xy 293.645834 -397.934668) (xy 293.607746 -397.879035) (xy 293.576596 -397.81924) (xy 293.552831 -397.756144)
			(xy 293.536796 -397.690656) (xy 293.528719 -397.623719) (xy 293.528718 -397.556296) (xy 292.40047 -397.556296)
			(xy 292.403082 -397.561322) (xy 292.426757 -397.624322) (xy 292.442733 -397.689701) (xy 292.450781 -397.75652)
			(xy 292.450784 -397.823823) (xy 292.442744 -397.890643) (xy 292.426774 -397.956023) (xy 292.403105 -398.019026)
			(xy 292.372075 -398.078748) (xy 292.33413 -398.134334) (xy 292.312344 -398.159986) (xy 292.306522 -398.167113)
			(xy 292.300024 -398.184318) (xy 292.299644 -398.193514) (xy 292.299644 -398.351502) (xy 292.299237 -398.361676)
			(xy 292.291448 -398.380474) (xy 292.277057 -398.39486) (xy 292.258256 -398.402641) (xy 292.248082 -398.403064)
			(xy 291.531802 -398.403064) (xy 291.521645 -398.402565) (xy 291.502876 -398.394792) (xy 291.488511 -398.380427)
			(xy 291.480736 -398.361659) (xy 291.48024 -398.351502) (xy 291.48024 -398.193514) (xy 291.479814 -398.184329)
			(xy 291.473311 -398.167145) (xy 291.46754 -398.159986) (xy 291.445715 -398.134365) (xy 291.407767 -398.078774)
			(xy 291.376735 -398.019046) (xy 291.353065 -397.956037) (xy 291.337094 -397.890651) (xy 291.329053 -397.823825)
			(xy 290.200388 -397.823825) (xy 290.171931 -397.878594) (xy 290.133983 -397.934181) (xy 290.112196 -397.959834)
			(xy 290.106402 -397.966981) (xy 290.099886 -397.98417) (xy 290.099496 -397.993362) (xy 290.099496 -398.486884)
			(xy 290.099915 -398.49607) (xy 290.106423 -398.513255) (xy 290.112196 -398.520412) (xy 290.134018 -398.546036)
			(xy 290.171963 -398.601627) (xy 290.202993 -398.661355) (xy 290.226662 -398.724363) (xy 290.242632 -398.789748)
			(xy 290.250673 -398.856573) (xy 290.250669 -398.923881) (xy 290.242622 -398.990705) (xy 290.226646 -399.056089)
			(xy 290.202971 -399.119095) (xy 290.171936 -399.17882) (xy 290.133985 -399.234407) (xy 290.112196 -399.26006)
			(xy 290.106391 -399.267199) (xy 290.099881 -399.284394) (xy 290.099496 -399.293588) (xy 290.099496 -399.451576)
			(xy 290.099059 -399.461729) (xy 290.09127 -399.480482) (xy 290.076878 -399.494806) (xy 290.058089 -399.502506)
			(xy 290.047934 -399.502884) (xy 289.331654 -399.502884) (xy 289.321527 -399.502412) (xy 289.30281 -399.494673)
			(xy 289.288456 -399.480383) (xy 289.280634 -399.4617) (xy 289.280092 -399.451576) (xy 289.280092 -399.293588)
			(xy 289.279689 -399.2844) (xy 289.273171 -399.267216) (xy 289.267392 -399.26006) (xy 289.245638 -399.234379)
			(xy 289.207685 -399.178798) (xy 289.176647 -399.119079) (xy 289.15297 -399.056078) (xy 289.136993 -398.990699)
			(xy 289.128945 -398.923879) (xy 289.128942 -398.856575) (xy 289.136983 -398.789754) (xy 289.152954 -398.724374)
			(xy 289.176625 -398.66137) (xy 289.207657 -398.601648) (xy 289.245605 -398.546063) (xy 289.267392 -398.520412)
			(xy 289.273208 -398.51328) (xy 289.279711 -398.496079) (xy 289.280092 -398.486884) (xy 289.280092 -397.993362)
			(xy 289.279702 -397.984173) (xy 289.273175 -397.966988) (xy 289.267392 -397.959834) (xy 289.245612 -397.934174)
			(xy 289.20766 -397.87859) (xy 289.176623 -397.818868) (xy 289.152948 -397.755865) (xy 289.136972 -397.690483)
			(xy 289.128927 -397.62366) (xy 289.128926 -397.556355) (xy 288.000733 -397.556355) (xy 288.003125 -397.560946)
			(xy 288.026894 -397.624039) (xy 288.042933 -397.689525) (xy 288.051013 -397.756461) (xy 288.051016 -397.823882)
			(xy 288.042944 -397.890819) (xy 288.026911 -397.956307) (xy 288.003148 -398.019402) (xy 287.971999 -398.079197)
			(xy 287.933912 -398.13483) (xy 287.912048 -398.160494) (xy 287.906265 -398.167649) (xy 287.899744 -398.184832)
			(xy 287.899348 -398.194022) (xy 287.899348 -398.351502) (xy 287.898875 -398.36163) (xy 287.891144 -398.380354)
			(xy 287.876853 -398.39471) (xy 287.858166 -398.402527) (xy 287.84804 -398.403064) (xy 287.13176 -398.403064)
			(xy 287.121599 -398.40271) (xy 287.102839 -398.394895) (xy 287.088515 -398.380477) (xy 287.080824 -398.361666)
			(xy 287.080452 -398.351502) (xy 287.080452 -398.194022) (xy 287.08002 -398.184837) (xy 287.07352 -398.167653)
			(xy 287.067752 -398.160494) (xy 287.045849 -398.13486) (xy 287.007758 -398.079223) (xy 286.976606 -398.019423)
			(xy 286.952842 -397.956321) (xy 286.936807 -397.890828) (xy 286.928734 -397.823885) (xy 244.446806 -397.823885)
			(xy 244.446806 -399.877788) (xy 244.446297 -399.902737) (xy 244.438487 -399.952019) (xy 244.423074 -399.999476)
			(xy 244.400434 -400.043943) (xy 244.371126 -400.084326) (xy 244.353842 -400.102324) (xy 243.288058 -401.168108)
			(xy 243.270087 -401.185424) (xy 243.229704 -401.214744) (xy 243.185232 -401.237387) (xy 243.137766 -401.252795)
			(xy 243.088474 -401.260589) (xy 243.063522 -401.261072) (xy 239.143794 -401.261072) (xy 239.133722 -401.261475)
			(xy 239.115123 -401.269209) (xy 239.107726 -401.276058) (xy 238.659987 -401.723797) (xy 286.928745 -401.723797)
			(xy 286.928747 -401.65637) (xy 286.936826 -401.58943) (xy 286.952865 -401.523939) (xy 286.976634 -401.460841)
			(xy 287.00779 -401.401044) (xy 287.045885 -401.34541) (xy 287.067752 -401.319746) (xy 287.07356 -401.312609)
			(xy 287.080067 -401.295412) (xy 287.080452 -401.286218) (xy 287.080452 -400.793966) (xy 287.080046 -400.784779)
			(xy 287.073528 -400.767595) (xy 287.067752 -400.760438) (xy 287.045892 -400.734769) (xy 287.0078 -400.679136)
			(xy 286.976646 -400.619341) (xy 286.952879 -400.556244) (xy 286.936842 -400.490755) (xy 286.928764 -400.423817)
			(xy 286.928764 -400.356392) (xy 286.93684 -400.289454) (xy 286.952876 -400.223964) (xy 286.976642 -400.160867)
			(xy 287.007795 -400.101072) (xy 287.045887 -400.045438) (xy 287.067752 -400.019774) (xy 287.073549 -400.012629)
			(xy 287.080062 -399.995438) (xy 287.080452 -399.986246) (xy 287.080452 -399.828766) (xy 287.080899 -399.818636)
			(xy 287.08864 -399.799911) (xy 287.102939 -399.785556) (xy 287.121632 -399.77774) (xy 287.13176 -399.777204)
			(xy 287.84804 -399.777204) (xy 287.858197 -399.777589) (xy 287.876951 -399.785399) (xy 287.891273 -399.799806)
			(xy 287.898971 -399.818606) (xy 287.899348 -399.828766) (xy 287.899348 -399.986246) (xy 287.899796 -399.995429)
			(xy 287.906285 -400.012613) (xy 287.912048 -400.019774) (xy 287.93392 -400.045433) (xy 287.972012 -400.101068)
			(xy 288.003165 -400.160864) (xy 288.026931 -400.223962) (xy 288.042968 -400.289452) (xy 288.051044 -400.356392)
			(xy 288.051043 -400.423817) (xy 288.042966 -400.490757) (xy 288.026928 -400.556247) (xy 288.003161 -400.619344)
			(xy 287.972007 -400.67914) (xy 287.933914 -400.734774) (xy 287.912048 -400.760438) (xy 287.906246 -400.767579)
			(xy 287.899736 -400.784773) (xy 287.899348 -400.793966) (xy 287.899348 -401.286218) (xy 287.899761 -401.295405)
			(xy 287.906274 -401.312588) (xy 287.912048 -401.319746) (xy 287.933892 -401.345428) (xy 287.971985 -401.401059)
			(xy 288.00314 -401.460852) (xy 288.026907 -401.523947) (xy 288.042946 -401.589435) (xy 288.051024 -401.656372)
			(xy 288.051026 -401.723795) (xy 288.042952 -401.790733) (xy 288.026917 -401.856221) (xy 288.003153 -401.919317)
			(xy 287.972002 -401.979113) (xy 287.933912 -402.034746) (xy 287.912048 -402.06041) (xy 287.906258 -402.06756)
			(xy 287.899741 -402.084747) (xy 287.899348 -402.093938) (xy 287.899348 -402.251418) (xy 287.898888 -402.261547)
			(xy 287.891152 -402.280271) (xy 287.876858 -402.294627) (xy 287.858167 -402.302444) (xy 287.84804 -402.30298)
			(xy 287.13176 -402.30298) (xy 287.121601 -402.302611) (xy 287.102844 -402.294798) (xy 287.088521 -402.280385)
			(xy 287.080826 -402.26158) (xy 287.080452 -402.251418) (xy 287.080452 -402.093938) (xy 287.080012 -402.084754)
			(xy 287.073518 -402.06757) (xy 287.067752 -402.06041) (xy 287.045865 -402.034763) (xy 287.007773 -401.979127)
			(xy 286.97662 -401.919329) (xy 286.952855 -401.85623) (xy 286.93682 -401.790738) (xy 286.928745 -401.723797)
			(xy 238.659987 -401.723797) (xy 237.559965 -402.823819) (xy 289.128886 -402.823819) (xy 289.12889 -402.756509)
			(xy 289.13694 -402.689682) (xy 289.15292 -402.624297) (xy 289.1766 -402.56129) (xy 289.207642 -402.501565)
			(xy 289.2456 -402.445979) (xy 289.267392 -402.420328) (xy 289.273201 -402.413191) (xy 289.279708 -402.395994)
			(xy 289.280092 -402.3868) (xy 289.280092 -401.893532) (xy 289.279668 -401.884346) (xy 289.273164 -401.867162)
			(xy 289.267392 -401.860004) (xy 289.245583 -401.834369) (xy 289.207631 -401.778781) (xy 289.176596 -401.719056)
			(xy 289.152922 -401.656049) (xy 289.136949 -401.590664) (xy 289.128906 -401.523839) (xy 289.128907 -401.456531)
			(xy 289.136954 -401.389706) (xy 289.152931 -401.324322) (xy 289.176608 -401.261317) (xy 289.207647 -401.201593)
			(xy 289.245601 -401.146007) (xy 289.267392 -401.120356) (xy 289.273189 -401.113211) (xy 289.279704 -401.09602)
			(xy 289.280092 -401.086828) (xy 289.280092 -400.92884) (xy 289.280554 -400.918689) (xy 289.288335 -400.89994)
			(xy 289.30272 -400.885615) (xy 289.321502 -400.877913) (xy 289.331654 -400.877532) (xy 290.047934 -400.877532)
			(xy 290.058062 -400.877998) (xy 290.076782 -400.885736) (xy 290.091137 -400.900028) (xy 290.098957 -400.918714)
			(xy 290.099496 -400.92884) (xy 290.099496 -401.086828) (xy 290.099893 -401.096017) (xy 290.106416 -401.113201)
			(xy 290.112196 -401.120356) (xy 290.133963 -401.146025) (xy 290.17191 -401.20161) (xy 290.202942 -401.261331)
			(xy 290.226615 -401.324334) (xy 290.242588 -401.389713) (xy 290.250633 -401.456534) (xy 290.250635 -401.523836)
			(xy 290.242593 -401.590657) (xy 290.226624 -401.656038) (xy 290.202955 -401.719041) (xy 290.200515 -401.723737)
			(xy 291.329064 -401.723737) (xy 291.329066 -401.65643) (xy 291.337113 -401.589606) (xy 291.353088 -401.524222)
			(xy 291.376763 -401.461217) (xy 291.407799 -401.401493) (xy 291.445751 -401.345906) (xy 291.46754 -401.320254)
			(xy 291.473344 -401.313114) (xy 291.479853 -401.295919) (xy 291.48024 -401.286726) (xy 291.48024 -400.793458)
			(xy 291.479841 -400.78427) (xy 291.473319 -400.767086) (xy 291.46754 -400.75993) (xy 291.445758 -400.734273)
			(xy 291.407809 -400.678687) (xy 291.376776 -400.618964) (xy 291.353103 -400.55596) (xy 291.337129 -400.490579)
			(xy 291.329085 -400.423757) (xy 291.329084 -400.356452) (xy 291.337128 -400.28963) (xy 291.3531 -400.224248)
			(xy 291.376772 -400.161244) (xy 291.407805 -400.101521) (xy 291.445753 -400.045934) (xy 291.46754 -400.020282)
			(xy 291.473332 -400.013134) (xy 291.479848 -399.995945) (xy 291.48024 -399.986754) (xy 291.48024 -399.828766)
			(xy 291.480706 -399.818606) (xy 291.488492 -399.799835) (xy 291.502866 -399.785471) (xy 291.521641 -399.777698)
			(xy 291.531802 -399.777204) (xy 292.248082 -399.777204) (xy 292.258234 -399.777747) (xy 292.276997 -399.785509)
			(xy 292.291361 -399.79986) (xy 292.299143 -399.818614) (xy 292.299644 -399.828766) (xy 292.299644 -399.986754)
			(xy 292.300089 -399.995937) (xy 292.30658 -400.013121) (xy 292.312344 -400.020282) (xy 292.334138 -400.045929)
			(xy 292.372088 -400.101516) (xy 292.403122 -400.16124) (xy 292.426795 -400.224245) (xy 292.442768 -400.289628)
			(xy 292.450812 -400.356452) (xy 292.450811 -400.423757) (xy 292.442766 -400.490581) (xy 292.426792 -400.555963)
			(xy 292.403118 -400.618968) (xy 292.372083 -400.678692) (xy 292.334132 -400.734278) (xy 292.312344 -400.75993)
			(xy 292.306545 -400.767073) (xy 292.300033 -400.784266) (xy 292.299644 -400.793458) (xy 292.299644 -401.286726)
			(xy 292.300054 -401.295913) (xy 292.306569 -401.313097) (xy 292.312344 -401.320254) (xy 292.33411 -401.345924)
			(xy 292.372061 -401.401507) (xy 292.403096 -401.461228) (xy 292.426771 -401.524231) (xy 292.442746 -401.589611)
			(xy 292.450792 -401.656432) (xy 292.450794 -401.723735) (xy 292.442752 -401.790557) (xy 292.426781 -401.855938)
			(xy 292.40311 -401.918941) (xy 292.372078 -401.978664) (xy 292.334131 -402.03425) (xy 292.312344 -402.059902)
			(xy 292.306557 -402.067054) (xy 292.300038 -402.084239) (xy 292.299644 -402.09343) (xy 292.299644 -402.251418)
			(xy 292.299181 -402.261579) (xy 292.291397 -402.280352) (xy 292.277022 -402.294718) (xy 292.258244 -402.302488)
			(xy 292.248082 -402.30298) (xy 291.531802 -402.30298) (xy 291.521647 -402.302465) (xy 291.502881 -402.294695)
			(xy 291.488516 -402.280336) (xy 291.480739 -402.261573) (xy 291.48024 -402.251418) (xy 291.48024 -402.09343)
			(xy 291.479806 -402.084246) (xy 291.473308 -402.067061) (xy 291.46754 -402.059902) (xy 291.44573 -402.034268)
			(xy 291.407782 -401.978679) (xy 291.37675 -401.918953) (xy 291.353078 -401.855946) (xy 291.337107 -401.790561)
			(xy 291.329064 -401.723737) (xy 290.200515 -401.723737) (xy 290.171926 -401.778764) (xy 290.133981 -401.834351)
			(xy 290.112196 -401.860004) (xy 290.106415 -401.86716) (xy 290.099891 -401.884342) (xy 290.099496 -401.893532)
			(xy 290.099496 -402.3868) (xy 290.099907 -402.395987) (xy 290.10642 -402.413171) (xy 290.112196 -402.420328)
			(xy 290.133935 -402.44602) (xy 290.171883 -402.501601) (xy 290.202916 -402.56132) (xy 290.22659 -402.624319)
			(xy 290.242566 -402.689696) (xy 290.250613 -402.756514) (xy 290.250617 -402.823814) (xy 290.250609 -402.823878)
			(xy 293.528678 -402.823878) (xy 293.528683 -402.75645) (xy 293.536763 -402.689509) (xy 293.552803 -402.624017)
			(xy 293.576572 -402.560919) (xy 293.607728 -402.501121) (xy 293.645822 -402.445485) (xy 293.667688 -402.41982)
			(xy 293.6735 -402.412685) (xy 293.680006 -402.395487) (xy 293.680388 -402.386292) (xy 293.680388 -401.89404)
			(xy 293.679961 -401.884854) (xy 293.67346 -401.86767) (xy 293.667688 -401.860512) (xy 293.645805 -401.834863)
			(xy 293.607717 -401.779226) (xy 293.576568 -401.719427) (xy 293.552806 -401.656328) (xy 293.536772 -401.590837)
			(xy 293.528698 -401.523897) (xy 293.5287 -401.456472) (xy 293.536777 -401.389533) (xy 293.552815 -401.324043)
			(xy 293.576581 -401.260945) (xy 293.607733 -401.201149) (xy 293.645823 -401.145513) (xy 293.667688 -401.119848)
			(xy 293.673488 -401.112705) (xy 293.680001 -401.095513) (xy 293.680388 -401.08632) (xy 293.680388 -400.92884)
			(xy 293.680849 -400.918722) (xy 293.688581 -400.900021) (xy 293.702884 -400.885706) (xy 293.721578 -400.877957)
			(xy 293.731696 -400.877532) (xy 294.447976 -400.877532) (xy 294.458101 -400.877936) (xy 294.47681 -400.885682)
			(xy 294.491127 -400.900003) (xy 294.498867 -400.918715) (xy 294.499284 -400.92884) (xy 294.499284 -401.08632)
			(xy 294.499688 -401.095508) (xy 294.506206 -401.112692) (xy 294.511984 -401.119848) (xy 294.533829 -401.145529)
			(xy 294.571919 -401.201161) (xy 294.603072 -401.260955) (xy 294.626838 -401.32405) (xy 294.642875 -401.389537)
			(xy 294.650953 -401.456474) (xy 294.650955 -401.523896) (xy 294.64288 -401.590833) (xy 294.626847 -401.656322)
			(xy 294.603084 -401.719418) (xy 294.600803 -401.723797) (xy 295.728833 -401.723797) (xy 295.728835 -401.65637)
			(xy 295.736913 -401.58943) (xy 295.752952 -401.523939) (xy 295.77672 -401.460841) (xy 295.807876 -401.401045)
			(xy 295.845969 -401.345411) (xy 295.867836 -401.319746) (xy 295.873643 -401.312608) (xy 295.88015 -401.295412)
			(xy 295.880536 -401.286218) (xy 295.880536 -400.793966) (xy 295.880134 -400.784778) (xy 295.873614 -400.767594)
			(xy 295.867836 -400.760438) (xy 295.845977 -400.734769) (xy 295.807885 -400.679135) (xy 295.776732 -400.61934)
			(xy 295.752966 -400.556244) (xy 295.736929 -400.490755) (xy 295.728852 -400.423816) (xy 295.728852 -400.356393)
			(xy 295.736928 -400.289454) (xy 295.752964 -400.223965) (xy 295.776729 -400.160868) (xy 295.807881 -400.101072)
			(xy 295.845971 -400.045439) (xy 295.867836 -400.019774) (xy 295.873631 -400.012628) (xy 295.880146 -399.995438)
			(xy 295.880536 -399.986246) (xy 295.880536 -399.828766) (xy 295.880999 -399.818638) (xy 295.888737 -399.799916)
			(xy 295.90303 -399.785561) (xy 295.921718 -399.777743) (xy 295.931844 -399.777204) (xy 296.648124 -399.777204)
			(xy 296.65828 -399.777602) (xy 296.677034 -399.785406) (xy 296.691357 -399.79981) (xy 296.699055 -399.818608)
			(xy 296.699432 -399.828766) (xy 296.699432 -399.986246) (xy 296.699883 -399.995429) (xy 296.70637 -400.012613)
			(xy 296.712132 -400.019774) (xy 296.734001 -400.045435) (xy 296.772087 -400.101071) (xy 296.803236 -400.160868)
			(xy 296.826998 -400.223965) (xy 296.843032 -400.289455) (xy 296.851107 -400.356393) (xy 296.851107 -400.423816)
			(xy 296.843031 -400.490754) (xy 296.826996 -400.556243) (xy 296.803232 -400.61934) (xy 296.772083 -400.679137)
			(xy 296.733995 -400.734772) (xy 296.712132 -400.760438) (xy 296.706329 -400.767578) (xy 296.69982 -400.784773)
			(xy 296.699432 -400.793966) (xy 296.699432 -401.286218) (xy 296.699849 -401.295404) (xy 296.70636 -401.312588)
			(xy 296.712132 -401.319746) (xy 296.733973 -401.34543) (xy 296.77206 -401.401062) (xy 296.80321 -401.460856)
			(xy 296.826974 -401.523951) (xy 296.84301 -401.589437) (xy 296.851088 -401.656373) (xy 296.85109 -401.723794)
			(xy 296.843016 -401.79073) (xy 296.826984 -401.856218) (xy 296.803224 -401.919314) (xy 296.772078 -401.979109)
			(xy 296.733994 -402.034744) (xy 296.712132 -402.06041) (xy 296.70634 -402.067558) (xy 296.699825 -402.084747)
			(xy 296.699432 -402.093938) (xy 296.699432 -402.251418) (xy 296.698988 -402.261549) (xy 296.691249 -402.280276)
			(xy 296.676949 -402.294633) (xy 296.658253 -402.302447) (xy 296.648124 -402.30298) (xy 295.931844 -402.30298)
			(xy 295.92169 -402.302542) (xy 295.902935 -402.294757) (xy 295.888609 -402.280365) (xy 295.880912 -402.261574)
			(xy 295.880536 -402.251418) (xy 295.880536 -402.093938) (xy 295.880099 -402.084754) (xy 295.873603 -402.06757)
			(xy 295.867836 -402.06041) (xy 295.845949 -402.034763) (xy 295.807859 -401.979127) (xy 295.776707 -401.919328)
			(xy 295.752942 -401.856229) (xy 295.736907 -401.790737) (xy 295.728833 -401.723797) (xy 294.600803 -401.723797)
			(xy 294.571935 -401.779213) (xy 294.533847 -401.834847) (xy 294.511984 -401.860512) (xy 294.506198 -401.867665)
			(xy 294.499678 -401.88485) (xy 294.499284 -401.89404) (xy 294.499284 -402.386292) (xy 294.499702 -402.395478)
			(xy 294.506211 -402.412662) (xy 294.511984 -402.41982) (xy 294.533801 -402.445524) (xy 294.571893 -402.501152)
			(xy 294.603046 -402.560943) (xy 294.626814 -402.624035) (xy 294.642853 -402.68952) (xy 294.650933 -402.756454)
			(xy 294.650937 -402.823819) (xy 297.928973 -402.823819) (xy 297.928978 -402.756509) (xy 297.937027 -402.689683)
			(xy 297.953006 -402.624297) (xy 297.976686 -402.561291) (xy 298.007727 -402.501566) (xy 298.045684 -402.445979)
			(xy 298.067476 -402.420328) (xy 298.073283 -402.41319) (xy 298.079792 -402.395994) (xy 298.080176 -402.3868)
			(xy 298.080176 -401.893532) (xy 298.079756 -401.884346) (xy 298.07325 -401.867161) (xy 298.067476 -401.860004)
			(xy 298.045668 -401.834368) (xy 298.007717 -401.77878) (xy 297.976683 -401.719055) (xy 297.953009 -401.656048)
			(xy 297.937037 -401.590664) (xy 297.928993 -401.523839) (xy 297.928995 -401.456531) (xy 297.937042 -401.389707)
			(xy 297.953018 -401.324323) (xy 297.976695 -401.261318) (xy 298.007732 -401.201594) (xy 298.045686 -401.146008)
			(xy 298.067476 -401.120356) (xy 298.073271 -401.113209) (xy 298.079787 -401.09602) (xy 298.080176 -401.086828)
			(xy 298.080176 -400.92884) (xy 298.080654 -400.918691) (xy 298.088432 -400.899945) (xy 298.102811 -400.885621)
			(xy 298.121588 -400.877915) (xy 298.131738 -400.877532) (xy 298.848018 -400.877532) (xy 298.858145 -400.878011)
			(xy 298.876865 -400.885744) (xy 298.89122 -400.900032) (xy 298.89904 -400.918716) (xy 298.89958 -400.92884)
			(xy 298.89958 -401.086828) (xy 298.899981 -401.096016) (xy 298.906502 -401.1132) (xy 298.91228 -401.120356)
			(xy 298.934048 -401.146024) (xy 298.971996 -401.201609) (xy 299.003029 -401.261331) (xy 299.026702 -401.324333)
			(xy 299.042676 -401.389713) (xy 299.050721 -401.456533) (xy 299.050723 -401.523837) (xy 299.042681 -401.590657)
			(xy 299.026711 -401.656038) (xy 299.003041 -401.719042) (xy 299.000571 -401.723796) (xy 300.128624 -401.723796)
			(xy 300.128626 -401.656371) (xy 300.136704 -401.58943) (xy 300.152743 -401.52394) (xy 300.17651 -401.460842)
			(xy 300.207665 -401.401045) (xy 300.245758 -401.345411) (xy 300.267624 -401.319746) (xy 300.273429 -401.312607)
			(xy 300.279938 -401.295412) (xy 300.280324 -401.286218) (xy 300.280324 -400.793966) (xy 300.279925 -400.784778)
			(xy 300.273403 -400.767594) (xy 300.267624 -400.760438) (xy 300.245765 -400.734768) (xy 300.207675 -400.679135)
			(xy 300.176522 -400.61934) (xy 300.152757 -400.556243) (xy 300.13672 -400.490755) (xy 300.128643 -400.423816)
			(xy 300.128643 -400.356393) (xy 300.136719 -400.289454) (xy 300.152754 -400.223965) (xy 300.176519 -400.160869)
			(xy 300.20767 -400.101073) (xy 300.24576 -400.045439) (xy 300.267624 -400.019774) (xy 300.273417 -400.012626)
			(xy 300.279933 -399.995438) (xy 300.280324 -399.986246) (xy 300.280324 -399.828766) (xy 300.280798 -399.818639)
			(xy 300.288534 -399.79992) (xy 300.302824 -399.785566) (xy 300.321507 -399.777745) (xy 300.331632 -399.777204)
			(xy 301.047912 -399.777204) (xy 301.058067 -399.777612) (xy 301.076821 -399.785412) (xy 301.091144 -399.799813)
			(xy 301.098843 -399.818608) (xy 301.09922 -399.828766) (xy 301.09922 -399.986246) (xy 301.099652 -399.995431)
			(xy 301.10615 -400.012616) (xy 301.11192 -400.019774) (xy 301.133789 -400.045435) (xy 301.171876 -400.10107)
			(xy 301.203026 -400.160867) (xy 301.226789 -400.223965) (xy 301.242823 -400.289454) (xy 301.250898 -400.356393)
			(xy 301.250898 -400.423816) (xy 301.242821 -400.490755) (xy 301.226786 -400.556244) (xy 301.203022 -400.619341)
			(xy 301.171872 -400.679137) (xy 301.133784 -400.734772) (xy 301.11192 -400.760438) (xy 301.106127 -400.767586)
			(xy 301.09961 -400.784774) (xy 301.09922 -400.793966) (xy 301.09922 -401.286218) (xy 301.099617 -401.295407)
			(xy 301.106139 -401.312591) (xy 301.11192 -401.319746) (xy 301.133762 -401.345429) (xy 301.17185 -401.401062)
			(xy 301.203 -401.460856) (xy 301.226765 -401.52395) (xy 301.242801 -401.589437) (xy 301.250878 -401.656373)
			(xy 301.25088 -401.723794) (xy 301.242807 -401.790731) (xy 301.226775 -401.856218) (xy 301.203014 -401.919314)
			(xy 301.171867 -401.97911) (xy 301.133782 -402.034744) (xy 301.11192 -402.06041) (xy 301.106139 -402.067566)
			(xy 301.099614 -402.084748) (xy 301.09922 -402.093938) (xy 301.09922 -402.251418) (xy 301.098787 -402.261551)
			(xy 301.091046 -402.28028) (xy 301.076743 -402.294637) (xy 301.058043 -402.302449) (xy 301.047912 -402.30298)
			(xy 300.331632 -402.30298) (xy 300.321477 -402.302552) (xy 300.302722 -402.294763) (xy 300.288396 -402.280368)
			(xy 300.280699 -402.261575) (xy 300.280324 -402.251418) (xy 300.280324 -402.093938) (xy 300.27989 -402.084753)
			(xy 300.273392 -402.067569) (xy 300.267624 -402.06041) (xy 300.245738 -402.034763) (xy 300.207648 -401.979126)
			(xy 300.176497 -401.919328) (xy 300.152733 -401.856229) (xy 300.136698 -401.790737) (xy 300.128624 -401.723796)
			(xy 299.000571 -401.723796) (xy 298.972011 -401.778765) (xy 298.934066 -401.834352) (xy 298.91228 -401.860004)
			(xy 298.906497 -401.867159) (xy 298.899975 -401.884342) (xy 298.89958 -401.893532) (xy 298.89958 -402.3868)
			(xy 298.899994 -402.395987) (xy 298.906505 -402.413171) (xy 298.91228 -402.420328) (xy 298.93402 -402.446019)
			(xy 298.971969 -402.501601) (xy 299.003003 -402.561319) (xy 299.026678 -402.624318) (xy 299.042653 -402.689696)
			(xy 299.050701 -402.756513) (xy 299.050705 -402.823814) (xy 299.050697 -402.823877) (xy 302.328766 -402.823877)
			(xy 302.328771 -402.75645) (xy 302.336851 -402.689509) (xy 302.35289 -402.624018) (xy 302.376659 -402.560919)
			(xy 302.407814 -402.501122) (xy 302.445906 -402.445486) (xy 302.467772 -402.41982) (xy 302.473594 -402.412693)
			(xy 302.480091 -402.395488) (xy 302.480472 -402.386292) (xy 302.480472 -401.89404) (xy 302.480049 -401.884854)
			(xy 302.473545 -401.867669) (xy 302.467772 -401.860512) (xy 302.445889 -401.834863) (xy 302.407803 -401.779225)
			(xy 302.376655 -401.719426) (xy 302.352893 -401.656328) (xy 302.33686 -401.590837) (xy 302.328786 -401.523897)
			(xy 302.328788 -401.456473) (xy 302.336865 -401.389534) (xy 302.352902 -401.324044) (xy 302.376667 -401.260946)
			(xy 302.407819 -401.201149) (xy 302.445908 -401.145514) (xy 302.467772 -401.119848) (xy 302.473582 -401.112713)
			(xy 302.480087 -401.095514) (xy 302.480472 -401.08632) (xy 302.480472 -400.92884) (xy 302.480948 -400.918724)
			(xy 302.488678 -400.900026) (xy 302.502976 -400.885712) (xy 302.521664 -400.87796) (xy 302.53178 -400.877532)
			(xy 303.24806 -400.877532) (xy 303.258184 -400.87795) (xy 303.276893 -400.885691) (xy 303.291209 -400.900007)
			(xy 303.29895 -400.918716) (xy 303.299368 -400.92884) (xy 303.299368 -401.08632) (xy 303.299776 -401.095507)
			(xy 303.306292 -401.112691) (xy 303.312068 -401.119848) (xy 303.333913 -401.145529) (xy 303.372005 -401.20116)
			(xy 303.403158 -401.260954) (xy 303.426925 -401.324049) (xy 303.442963 -401.389537) (xy 303.451041 -401.456474)
			(xy 303.451043 -401.523896) (xy 303.442968 -401.590834) (xy 303.426934 -401.656322) (xy 303.40317 -401.719418)
			(xy 303.37202 -401.779214) (xy 303.333932 -401.834847) (xy 303.312068 -401.860512) (xy 303.30628 -401.867663)
			(xy 303.299761 -401.884849) (xy 303.299368 -401.89404) (xy 303.299368 -402.386292) (xy 303.299789 -402.395478)
			(xy 303.306296 -402.412662) (xy 303.312068 -402.41982) (xy 303.333886 -402.445524) (xy 303.371978 -402.501152)
			(xy 303.403133 -402.560942) (xy 303.426901 -402.624034) (xy 303.442941 -402.689519) (xy 303.451021 -402.756454)
			(xy 303.451025 -402.823874) (xy 303.442954 -402.89081) (xy 303.426922 -402.956297) (xy 303.403162 -403.019392)
			(xy 303.372015 -403.079186) (xy 303.33393 -403.134819) (xy 303.312068 -403.160484) (xy 303.306249 -403.167613)
			(xy 303.299749 -403.184816) (xy 303.299368 -403.194012) (xy 303.299368 -403.351492) (xy 303.298977 -403.361618)
			(xy 303.291225 -403.380328) (xy 303.276901 -403.394643) (xy 303.258186 -403.402383) (xy 303.24806 -403.4028)
			(xy 302.53178 -403.4028) (xy 302.52167 -403.402331) (xy 302.502991 -403.394587) (xy 302.488697 -403.380285)
			(xy 302.480963 -403.361602) (xy 302.480472 -403.351492) (xy 302.480472 -403.194012) (xy 302.480062 -403.184825)
			(xy 302.473549 -403.16764) (xy 302.467772 -403.160484) (xy 302.445862 -403.134857) (xy 302.407776 -403.079216)
			(xy 302.376629 -403.019415) (xy 302.352869 -402.956313) (xy 302.336838 -402.890819) (xy 302.328766 -402.823877)
			(xy 299.050697 -402.823877) (xy 299.042666 -402.890633) (xy 299.026699 -402.956013) (xy 299.003032 -403.019015)
			(xy 298.972006 -403.078737) (xy 298.934064 -403.134323) (xy 298.91228 -403.159976) (xy 298.906466 -403.167109)
			(xy 298.899963 -403.184309) (xy 298.89958 -403.193504) (xy 298.89958 -403.351492) (xy 298.899171 -403.361648)
			(xy 298.891375 -403.380404) (xy 298.876974 -403.394729) (xy 298.858176 -403.402425) (xy 298.848018 -403.4028)
			(xy 298.131738 -403.4028) (xy 298.121619 -403.402243) (xy 298.102906 -403.394535) (xy 298.08855 -403.380271)
			(xy 298.080722 -403.361608) (xy 298.080176 -403.351492) (xy 298.080176 -403.193504) (xy 298.079769 -403.184316)
			(xy 298.073254 -403.167132) (xy 298.067476 -403.159976) (xy 298.04564 -403.134363) (xy 298.00769 -403.078772)
			(xy 297.976657 -403.019043) (xy 297.952985 -402.956034) (xy 297.937014 -402.890646) (xy 297.928973 -402.823819)
			(xy 294.650937 -402.823819) (xy 294.650937 -402.823874) (xy 294.642866 -402.890809) (xy 294.626835 -402.956296)
			(xy 294.603076 -403.019391) (xy 294.57193 -403.079186) (xy 294.533846 -403.134819) (xy 294.511984 -403.160484)
			(xy 294.506167 -403.167615) (xy 294.499665 -403.184816) (xy 294.499284 -403.194012) (xy 294.499284 -403.351492)
			(xy 294.498877 -403.361616) (xy 294.491129 -403.380322) (xy 294.476809 -403.394638) (xy 294.4581 -403.40238)
			(xy 294.447976 -403.4028) (xy 293.731696 -403.4028) (xy 293.721573 -403.402387) (xy 293.70287 -403.394638)
			(xy 293.688556 -403.38032) (xy 293.68081 -403.361615) (xy 293.680388 -403.351492) (xy 293.680388 -403.194012)
			(xy 293.679975 -403.184825) (xy 293.673464 -403.167641) (xy 293.667688 -403.160484) (xy 293.645777 -403.134857)
			(xy 293.607691 -403.079217) (xy 293.576543 -403.019415) (xy 293.552782 -402.956314) (xy 293.53675 -402.89082)
			(xy 293.528678 -402.823878) (xy 290.250609 -402.823878) (xy 290.242579 -402.890633) (xy 290.226612 -402.956012)
			(xy 290.202946 -403.019014) (xy 290.17192 -403.078737) (xy 290.133979 -403.134323) (xy 290.112196 -403.159976)
			(xy 290.106384 -403.16711) (xy 290.099879 -403.184309) (xy 290.099496 -403.193504) (xy 290.099496 -403.351492)
			(xy 290.099072 -403.361646) (xy 290.091278 -403.380399) (xy 290.076882 -403.394723) (xy 290.05809 -403.402422)
			(xy 290.047934 -403.4028) (xy 289.331654 -403.4028) (xy 289.321529 -403.402312) (xy 289.302815 -403.394577)
			(xy 289.288461 -403.380292) (xy 289.280637 -403.361614) (xy 289.280092 -403.351492) (xy 289.280092 -403.193504)
			(xy 289.279682 -403.184317) (xy 289.273168 -403.167132) (xy 289.267392 -403.159976) (xy 289.245556 -403.134363)
			(xy 289.207605 -403.078772) (xy 289.176571 -403.019044) (xy 289.152898 -402.956034) (xy 289.136927 -402.890647)
			(xy 289.128886 -402.823819) (xy 237.559965 -402.823819) (xy 237.421928 -402.961856) (xy 237.415119 -402.969281)
			(xy 237.40738 -402.987861) (xy 237.406942 -402.997924) (xy 237.406942 -405.623708) (xy 286.928756 -405.623708)
			(xy 286.928757 -405.556283) (xy 286.936834 -405.489343) (xy 286.952872 -405.423853) (xy 286.976639 -405.360756)
			(xy 287.007793 -405.30096) (xy 287.045886 -405.245326) (xy 287.067752 -405.219662) (xy 287.073554 -405.212521)
			(xy 287.080064 -405.195327) (xy 287.080452 -405.186134) (xy 287.080452 -404.693882) (xy 287.080039 -404.684695)
			(xy 287.073526 -404.667512) (xy 287.067752 -404.660354) (xy 287.045908 -404.634672) (xy 287.007815 -404.579041)
			(xy 286.97666 -404.519248) (xy 286.952893 -404.456153) (xy 286.936854 -404.390665) (xy 286.928776 -404.323728)
			(xy 286.928774 -404.256305) (xy 286.936848 -404.189367) (xy 286.952883 -404.123879) (xy 286.976647 -404.060783)
			(xy 287.007798 -404.000987) (xy 287.045888 -403.945354) (xy 287.067752 -403.91969) (xy 287.073542 -403.91254)
			(xy 287.080059 -403.895353) (xy 287.080452 -403.886162) (xy 287.080452 -403.728682) (xy 287.080912 -403.718553)
			(xy 287.088648 -403.699829) (xy 287.102942 -403.685473) (xy 287.121633 -403.677656) (xy 287.13176 -403.67712)
			(xy 287.84804 -403.67712) (xy 287.858199 -403.677489) (xy 287.876956 -403.685302) (xy 287.891279 -403.699715)
			(xy 287.898974 -403.71852) (xy 287.899348 -403.728682) (xy 287.899348 -403.886162) (xy 287.899788 -403.895346)
			(xy 287.906282 -403.91253) (xy 287.912048 -403.91969) (xy 287.933935 -403.945337) (xy 287.972027 -404.000973)
			(xy 288.00318 -404.060771) (xy 288.026945 -404.12387) (xy 288.04298 -404.189362) (xy 288.051055 -404.256303)
			(xy 288.051053 -404.32373) (xy 288.042974 -404.39067) (xy 288.026935 -404.456161) (xy 288.003166 -404.519259)
			(xy 287.97201 -404.579056) (xy 287.933915 -404.63469) (xy 287.912048 -404.660354) (xy 287.90624 -404.667491)
			(xy 287.899733 -404.684688) (xy 287.899348 -404.693882) (xy 287.899348 -405.186134) (xy 287.899754 -405.195321)
			(xy 287.906272 -405.212505) (xy 287.912048 -405.219662) (xy 287.933908 -405.245331) (xy 287.972 -405.300964)
			(xy 288.003154 -405.360759) (xy 288.026921 -405.423856) (xy 288.042958 -405.489345) (xy 288.051036 -405.556283)
			(xy 288.051036 -405.623708) (xy 288.04296 -405.690646) (xy 288.026924 -405.756136) (xy 288.003158 -405.819233)
			(xy 287.972005 -405.879028) (xy 287.933913 -405.934662) (xy 287.912048 -405.960326) (xy 287.906251 -405.967471)
			(xy 287.899738 -405.984662) (xy 287.899348 -405.993854) (xy 287.899348 -406.151334) (xy 287.898901 -406.161464)
			(xy 287.89116 -406.180189) (xy 287.876861 -406.194544) (xy 287.858168 -406.20236) (xy 287.84804 -406.202896)
			(xy 287.13176 -406.202896) (xy 287.121603 -406.202511) (xy 287.102849 -406.194701) (xy 287.088527 -406.180294)
			(xy 287.080829 -406.161494) (xy 287.080452 -406.151334) (xy 287.080452 -405.993854) (xy 287.080004 -405.984671)
			(xy 287.073515 -405.967487) (xy 287.067752 -405.960326) (xy 287.04588 -405.934667) (xy 287.007788 -405.879032)
			(xy 286.976635 -405.819236) (xy 286.952869 -405.756138) (xy 286.936832 -405.690648) (xy 286.928756 -405.623708)
			(xy 237.406942 -405.623708) (xy 237.406942 -406.72373) (xy 289.128897 -406.72373) (xy 289.1289 -406.656422)
			(xy 289.136948 -406.589596) (xy 289.152926 -406.524211) (xy 289.176605 -406.461205) (xy 289.207645 -406.401481)
			(xy 289.245601 -406.345895) (xy 289.267392 -406.320244) (xy 289.273194 -406.313103) (xy 289.279706 -406.295909)
			(xy 289.280092 -406.286716) (xy 289.280092 -405.793448) (xy 289.279661 -405.784263) (xy 289.273162 -405.767078)
			(xy 289.267392 -405.75992) (xy 289.245599 -405.734272) (xy 289.207647 -405.678686) (xy 289.176611 -405.618962)
			(xy 289.152936 -405.555957) (xy 289.136961 -405.490574) (xy 289.128917 -405.42375) (xy 289.128917 -405.356444)
			(xy 289.136962 -405.28962) (xy 289.152937 -405.224237) (xy 289.176613 -405.161232) (xy 289.20765 -405.101509)
			(xy 289.245602 -405.045923) (xy 289.267392 -405.020272) (xy 289.273182 -405.013122) (xy 289.279701 -404.995935)
			(xy 289.280092 -404.986744) (xy 289.280092 -404.828756) (xy 289.280486 -404.8186) (xy 289.288294 -404.799848)
			(xy 289.302699 -404.785527) (xy 289.321496 -404.777827) (xy 289.331654 -404.777448) (xy 290.047934 -404.777448)
			(xy 290.058064 -404.777899) (xy 290.076787 -404.785639) (xy 290.091143 -404.799936) (xy 290.098959 -404.818628)
			(xy 290.099496 -404.828756) (xy 290.099496 -404.986744) (xy 290.099886 -404.995933) (xy 290.106414 -405.013117)
			(xy 290.112196 -405.020272) (xy 290.133979 -405.045928) (xy 290.171925 -405.101515) (xy 290.202957 -405.161238)
			(xy 290.226628 -405.224242) (xy 290.242601 -405.289623) (xy 290.250644 -405.356445) (xy 290.250645 -405.423749)
			(xy 290.242602 -405.490571) (xy 290.22663 -405.555952) (xy 290.202959 -405.618957) (xy 290.200522 -405.623648)
			(xy 291.329076 -405.623648) (xy 291.329076 -405.556343) (xy 291.337121 -405.48952) (xy 291.353095 -405.424137)
			(xy 291.376768 -405.361132) (xy 291.407802 -405.301409) (xy 291.445752 -405.245822) (xy 291.46754 -405.22017)
			(xy 291.473337 -405.213025) (xy 291.47985 -405.195834) (xy 291.48024 -405.186642) (xy 291.48024 -404.693374)
			(xy 291.479833 -404.684187) (xy 291.473316 -404.667003) (xy 291.46754 -404.659846) (xy 291.445774 -404.634176)
			(xy 291.407825 -404.578592) (xy 291.37679 -404.518871) (xy 291.353116 -404.455869) (xy 291.337142 -404.390489)
			(xy 291.329096 -404.323668) (xy 291.329094 -404.256365) (xy 291.337136 -404.189544) (xy 291.353106 -404.124163)
			(xy 291.376777 -404.061159) (xy 291.407808 -404.001436) (xy 291.445754 -403.94585) (xy 291.46754 -403.920198)
			(xy 291.473325 -403.913045) (xy 291.479846 -403.89586) (xy 291.48024 -403.88667) (xy 291.48024 -403.728682)
			(xy 291.480718 -403.718523) (xy 291.488499 -403.699753) (xy 291.50287 -403.685388) (xy 291.521643 -403.677615)
			(xy 291.531802 -403.67712) (xy 292.248082 -403.67712) (xy 292.258236 -403.677648) (xy 292.277002 -403.685413)
			(xy 292.291367 -403.699768) (xy 292.299145 -403.718528) (xy 292.299644 -403.728682) (xy 292.299644 -403.88667)
			(xy 292.300081 -403.895854) (xy 292.306577 -403.913038) (xy 292.312344 -403.920198) (xy 292.334154 -403.945832)
			(xy 292.372103 -404.001421) (xy 292.403137 -404.061147) (xy 292.426809 -404.124153) (xy 292.442781 -404.189538)
			(xy 292.450824 -404.256363) (xy 292.450822 -404.32367) (xy 292.442775 -404.390495) (xy 292.426799 -404.455878)
			(xy 292.403123 -404.518884) (xy 292.372086 -404.578608) (xy 292.334134 -404.634194) (xy 292.312344 -404.659846)
			(xy 292.306539 -404.666985) (xy 292.300031 -404.68418) (xy 292.299644 -404.693374) (xy 292.299644 -405.186642)
			(xy 292.300047 -405.19583) (xy 292.306567 -405.213013) (xy 292.312344 -405.22017) (xy 292.334126 -405.245827)
			(xy 292.372076 -405.301412) (xy 292.403111 -405.361135) (xy 292.426785 -405.424139) (xy 292.442758 -405.489521)
			(xy 292.450803 -405.556343) (xy 292.450804 -405.623648) (xy 292.44276 -405.69047) (xy 292.426787 -405.755852)
			(xy 292.403114 -405.818857) (xy 292.372081 -405.87858) (xy 292.334132 -405.934166) (xy 292.312344 -405.959818)
			(xy 292.30655 -405.966965) (xy 292.300035 -405.984154) (xy 292.299644 -405.993346) (xy 292.299644 -406.151334)
			(xy 292.299194 -406.161496) (xy 292.291405 -406.18027) (xy 292.277026 -406.194634) (xy 292.258245 -406.202404)
			(xy 292.248082 -406.202896) (xy 291.531802 -406.202896) (xy 291.521649 -406.202366) (xy 291.502886 -406.194598)
			(xy 291.488522 -406.180244) (xy 291.480741 -406.161487) (xy 291.48024 -406.151334) (xy 291.48024 -405.993346)
			(xy 291.479799 -405.984162) (xy 291.473306 -405.966978) (xy 291.46754 -405.959818) (xy 291.445746 -405.934171)
			(xy 291.407797 -405.878584) (xy 291.376764 -405.818859) (xy 291.353092 -405.755854) (xy 291.337119 -405.690471)
			(xy 291.329076 -405.623648) (xy 290.200522 -405.623648) (xy 290.171928 -405.67868) (xy 290.133982 -405.734267)
			(xy 290.112196 -405.75992) (xy 290.106408 -405.767071) (xy 290.099888 -405.784257) (xy 290.099496 -405.793448)
			(xy 290.099496 -406.286716) (xy 290.099899 -406.295904) (xy 290.106418 -406.313088) (xy 290.112196 -406.320244)
			(xy 290.133951 -406.345922) (xy 290.171899 -406.401506) (xy 290.202931 -406.461226) (xy 290.226605 -406.524227)
			(xy 290.242579 -406.589606) (xy 290.250625 -406.656425) (xy 290.250628 -406.723727) (xy 290.250621 -406.723789)
			(xy 293.52869 -406.723789) (xy 293.528692 -406.656363) (xy 293.536771 -406.589423) (xy 293.55281 -406.523932)
			(xy 293.576577 -406.460834) (xy 293.607731 -406.401037) (xy 293.645823 -406.345401) (xy 293.667688 -406.319736)
			(xy 293.673493 -406.312597) (xy 293.680003 -406.295402) (xy 293.680388 -406.286208) (xy 293.680388 -405.793956)
			(xy 293.680002 -405.784766) (xy 293.673472 -405.767582) (xy 293.667688 -405.760428) (xy 293.645821 -405.734766)
			(xy 293.607733 -405.679131) (xy 293.576583 -405.619334) (xy 293.552819 -405.556237) (xy 293.536785 -405.490747)
			(xy 293.528709 -405.423809) (xy 293.52871 -405.356385) (xy 293.536786 -405.289447) (xy 293.552821 -405.223958)
			(xy 293.576585 -405.160861) (xy 293.607736 -405.101064) (xy 293.645824 -405.045429) (xy 293.667688 -405.019764)
			(xy 293.673481 -405.012616) (xy 293.679998 -404.995428) (xy 293.680388 -404.986236) (xy 293.680388 -404.828756)
			(xy 293.680849 -404.818646) (xy 293.688599 -404.799969) (xy 293.702903 -404.785676) (xy 293.721586 -404.777941)
			(xy 293.731696 -404.777448) (xy 294.447976 -404.777448) (xy 294.458077 -404.778003) (xy 294.476745 -404.785723)
			(xy 294.491038 -404.799998) (xy 294.498783 -404.818656) (xy 294.499284 -404.828756) (xy 294.499284 -404.986236)
			(xy 294.49968 -404.995425) (xy 294.506204 -405.012609) (xy 294.511984 -405.019764) (xy 294.533845 -405.045432)
			(xy 294.571934 -405.101066) (xy 294.603086 -405.160862) (xy 294.626851 -405.223958) (xy 294.642888 -405.289447)
			(xy 294.650964 -405.356385) (xy 294.650964 -405.423809) (xy 294.642889 -405.490747) (xy 294.626853 -405.556236)
			(xy 294.603089 -405.619333) (xy 294.60081 -405.623708) (xy 295.728844 -405.623708) (xy 295.728845 -405.556283)
			(xy 295.736922 -405.489344) (xy 295.752959 -405.423854) (xy 295.776725 -405.360757) (xy 295.807879 -405.30096)
			(xy 295.84597 -405.245327) (xy 295.867836 -405.219662) (xy 295.873636 -405.212519) (xy 295.880148 -405.195327)
			(xy 295.880536 -405.186134) (xy 295.880536 -404.693882) (xy 295.880126 -404.684695) (xy 295.873611 -404.667511)
			(xy 295.867836 -404.660354) (xy 295.845992 -404.634672) (xy 295.807901 -404.57904) (xy 295.776747 -404.519247)
			(xy 295.75298 -404.456152) (xy 295.736942 -404.390665) (xy 295.728864 -404.323728) (xy 295.728862 -404.256305)
			(xy 295.736936 -404.189368) (xy 295.75297 -404.123879) (xy 295.776733 -404.060783) (xy 295.807884 -404.000988)
			(xy 295.845972 -403.945355) (xy 295.867836 -403.91969) (xy 295.873624 -403.912539) (xy 295.880143 -403.895353)
			(xy 295.880536 -403.886162) (xy 295.880536 -403.728682) (xy 295.881011 -403.718555) (xy 295.888744 -403.699834)
			(xy 295.903034 -403.685478) (xy 295.921719 -403.677659) (xy 295.931844 -403.67712) (xy 296.648124 -403.67712)
			(xy 296.658282 -403.677502) (xy 296.677039 -403.685309) (xy 296.691362 -403.699718) (xy 296.699058 -403.718521)
			(xy 296.699432 -403.728682) (xy 296.699432 -403.886162) (xy 296.699876 -403.895345) (xy 296.706368 -403.912529)
			(xy 296.712132 -403.91969) (xy 296.734016 -403.945338) (xy 296.772102 -404.000976) (xy 296.80325 -404.060775)
			(xy 296.827012 -404.123874) (xy 296.843045 -404.189364) (xy 296.851118 -404.256304) (xy 296.851117 -404.323729)
			(xy 296.843039 -404.390668) (xy 296.827002 -404.456158) (xy 296.803237 -404.519256) (xy 296.772085 -404.579053)
			(xy 296.733996 -404.634688) (xy 296.712132 -404.660354) (xy 296.706322 -404.667489) (xy 296.699817 -404.684688)
			(xy 296.699432 -404.693882) (xy 296.699432 -405.186134) (xy 296.699841 -405.195321) (xy 296.706357 -405.212505)
			(xy 296.712132 -405.219662) (xy 296.733989 -405.245333) (xy 296.772076 -405.300967) (xy 296.803225 -405.360763)
			(xy 296.826988 -405.423859) (xy 296.843023 -405.489347) (xy 296.851099 -405.556284) (xy 296.851099 -405.623707)
			(xy 296.843025 -405.690644) (xy 296.826991 -405.756132) (xy 296.803229 -405.819229) (xy 296.77208 -405.879025)
			(xy 296.733994 -405.93466) (xy 296.712132 -405.960326) (xy 296.706334 -405.96747) (xy 296.699822 -405.984662)
			(xy 296.699432 -405.993854) (xy 296.699432 -406.151334) (xy 296.699001 -406.161466) (xy 296.691256 -406.180194)
			(xy 296.676953 -406.19455) (xy 296.658254 -406.202363) (xy 296.648124 -406.202896) (xy 295.931844 -406.202896)
			(xy 295.921692 -406.202442) (xy 295.90294 -406.19466) (xy 295.888615 -406.180273) (xy 295.880915 -406.161487)
			(xy 295.880536 -406.151334) (xy 295.880536 -405.993854) (xy 295.880092 -405.984671) (xy 295.873601 -405.967486)
			(xy 295.867836 -405.960326) (xy 295.845965 -405.934666) (xy 295.807874 -405.879032) (xy 295.776722 -405.819235)
			(xy 295.752956 -405.756137) (xy 295.73692 -405.690647) (xy 295.728844 -405.623708) (xy 294.60081 -405.623708)
			(xy 294.571938 -405.679129) (xy 294.533848 -405.734763) (xy 294.511984 -405.760428) (xy 294.506191 -405.767576)
			(xy 294.499675 -405.784764) (xy 294.499284 -405.793956) (xy 294.499284 -406.286208) (xy 294.499694 -406.295395)
			(xy 294.506208 -406.312579) (xy 294.511984 -406.319736) (xy 294.533817 -406.345427) (xy 294.571908 -406.401057)
			(xy 294.603061 -406.46085) (xy 294.626827 -406.523943) (xy 294.642866 -406.58943) (xy 294.650944 -406.656365)
			(xy 294.650947 -406.72373) (xy 297.928985 -406.72373) (xy 297.928988 -406.656422) (xy 297.937036 -406.589596)
			(xy 297.953013 -406.524212) (xy 297.976691 -406.461206) (xy 298.00773 -406.401482) (xy 298.045685 -406.345896)
			(xy 298.067476 -406.320244) (xy 298.073276 -406.313101) (xy 298.079789 -406.295909) (xy 298.080176 -406.286716)
			(xy 298.080176 -405.793448) (xy 298.079748 -405.784263) (xy 298.073247 -405.767078) (xy 298.067476 -405.75992)
			(xy 298.045683 -405.734272) (xy 298.007732 -405.678685) (xy 297.976697 -405.618962) (xy 297.953023 -405.555957)
			(xy 297.937049 -405.490574) (xy 297.929005 -405.42375) (xy 297.929005 -405.356444) (xy 297.93705 -405.28962)
			(xy 297.953025 -405.224238) (xy 297.9767 -405.161233) (xy 298.007735 -405.101509) (xy 298.045687 -405.045924)
			(xy 298.067476 -405.020272) (xy 298.073264 -405.013121) (xy 298.079785 -404.995935) (xy 298.080176 -404.986744)
			(xy 298.080176 -404.828756) (xy 298.080585 -404.818602) (xy 298.088391 -404.799853) (xy 298.102791 -404.785532)
			(xy 298.121582 -404.77783) (xy 298.131738 -404.777448) (xy 298.848018 -404.777448) (xy 298.858147 -404.777912)
			(xy 298.87687 -404.785647) (xy 298.891226 -404.79994) (xy 298.899043 -404.818629) (xy 298.89958 -404.828756)
			(xy 298.89958 -404.986744) (xy 298.899973 -404.995933) (xy 298.906499 -405.013117) (xy 298.91228 -405.020272)
			(xy 298.934063 -405.045928) (xy 298.972011 -405.101514) (xy 299.003043 -405.161237) (xy 299.026716 -405.224241)
			(xy 299.042688 -405.289623) (xy 299.050732 -405.356445) (xy 299.050733 -405.423749) (xy 299.042689 -405.490571)
			(xy 299.026717 -405.555953) (xy 299.003046 -405.618957) (xy 299.000577 -405.623708) (xy 300.128635 -405.623708)
			(xy 300.128635 -405.556283) (xy 300.136712 -405.489344) (xy 300.152749 -405.423854) (xy 300.176515 -405.360757)
			(xy 300.207668 -405.300961) (xy 300.245759 -405.245327) (xy 300.267624 -405.219662) (xy 300.273422 -405.212518)
			(xy 300.279935 -405.195326) (xy 300.280324 -405.186134) (xy 300.280324 -404.693882) (xy 300.279917 -404.684695)
			(xy 300.273401 -404.66751) (xy 300.267624 -404.660354) (xy 300.245781 -404.634671) (xy 300.20769 -404.57904)
			(xy 300.176537 -404.519246) (xy 300.15277 -404.456152) (xy 300.136733 -404.390664) (xy 300.128655 -404.323728)
			(xy 300.128653 -404.256305) (xy 300.136727 -404.189368) (xy 300.152761 -404.12388) (xy 300.176523 -404.060784)
			(xy 300.207673 -404.000989) (xy 300.245761 -403.945355) (xy 300.267624 -403.91969) (xy 300.27341 -403.912538)
			(xy 300.27993 -403.895352) (xy 300.280324 -403.886162) (xy 300.280324 -403.728682) (xy 300.280811 -403.718556)
			(xy 300.288542 -403.699837) (xy 300.302828 -403.685482) (xy 300.321509 -403.677661) (xy 300.331632 -403.67712)
			(xy 301.047912 -403.67712) (xy 301.058069 -403.677512) (xy 301.076826 -403.685315) (xy 301.09115 -403.699721)
			(xy 301.098846 -403.718522) (xy 301.09922 -403.728682) (xy 301.09922 -403.886162) (xy 301.099644 -403.895348)
			(xy 301.106147 -403.912533) (xy 301.11192 -403.91969) (xy 301.133805 -403.945338) (xy 301.171892 -404.000975)
			(xy 301.20304 -404.060774) (xy 301.226802 -404.123873) (xy 301.242836 -404.189364) (xy 301.250909 -404.256304)
			(xy 301.250907 -404.323729) (xy 301.24283 -404.390668) (xy 301.226793 -404.456158) (xy 301.203027 -404.519256)
			(xy 301.171875 -404.579053) (xy 301.133785 -404.634688) (xy 301.11192 -404.660354) (xy 301.10612 -404.667497)
			(xy 301.099607 -404.684689) (xy 301.09922 -404.693882) (xy 301.09922 -405.186134) (xy 301.099609 -405.195323)
			(xy 301.106137 -405.212508) (xy 301.11192 -405.219662) (xy 301.133777 -405.245332) (xy 301.171865 -405.300967)
			(xy 301.203015 -405.360762) (xy 301.226778 -405.423859) (xy 301.242814 -405.489347) (xy 301.25089 -405.556284)
			(xy 301.25089 -405.623707) (xy 301.242815 -405.690644) (xy 301.226781 -405.756133) (xy 301.203018 -405.819229)
			(xy 301.17187 -405.879026) (xy 301.133783 -405.93466) (xy 301.11192 -405.960326) (xy 301.106132 -405.967478)
			(xy 301.099612 -405.984663) (xy 301.09922 -405.993854) (xy 301.09922 -406.151334) (xy 301.0988 -406.161468)
			(xy 301.091054 -406.180197) (xy 301.076747 -406.194554) (xy 301.058044 -406.202365) (xy 301.047912 -406.202896)
			(xy 300.331632 -406.202896) (xy 300.321479 -406.202452) (xy 300.302727 -406.194667) (xy 300.288402 -406.180276)
			(xy 300.280702 -406.161488) (xy 300.280324 -406.151334) (xy 300.280324 -405.993854) (xy 300.279882 -405.98467)
			(xy 300.27339 -405.967486) (xy 300.267624 -405.960326) (xy 300.245753 -405.934666) (xy 300.207663 -405.879031)
			(xy 300.176511 -405.819235) (xy 300.152747 -405.756137) (xy 300.136711 -405.690647) (xy 300.128635 -405.623708)
			(xy 299.000577 -405.623708) (xy 298.972014 -405.678681) (xy 298.934067 -405.734268) (xy 298.91228 -405.75992)
			(xy 298.90649 -405.76707) (xy 298.899972 -405.784257) (xy 298.89958 -405.793448) (xy 298.89958 -406.286716)
			(xy 298.899987 -406.295903) (xy 298.906503 -406.313088) (xy 298.91228 -406.320244) (xy 298.934035 -406.345922)
			(xy 298.971984 -406.401506) (xy 299.003018 -406.461226) (xy 299.026691 -406.524227) (xy 299.042666 -406.589606)
			(xy 299.050712 -406.656425) (xy 299.050715 -406.723727) (xy 299.050708 -406.723789) (xy 302.328777 -406.723789)
			(xy 302.32878 -406.656363) (xy 302.336859 -406.589423) (xy 302.352897 -406.523933) (xy 302.376664 -406.460835)
			(xy 302.407816 -406.401037) (xy 302.445907 -406.345402) (xy 302.467772 -406.319736) (xy 302.473587 -406.312604)
			(xy 302.480089 -406.295403) (xy 302.480472 -406.286208) (xy 302.480472 -405.793956) (xy 302.480089 -405.784766)
			(xy 302.473557 -405.767581) (xy 302.467772 -405.760428) (xy 302.445905 -405.734766) (xy 302.407818 -405.67913)
			(xy 302.376669 -405.619333) (xy 302.352907 -405.556236) (xy 302.336872 -405.490747) (xy 302.328797 -405.423809)
			(xy 302.328798 -405.356385) (xy 302.336873 -405.289447) (xy 302.352908 -405.223958) (xy 302.376672 -405.160861)
			(xy 302.407821 -405.101065) (xy 302.445909 -405.04543) (xy 302.467772 -405.019764) (xy 302.473575 -405.012624)
			(xy 302.480084 -404.995429) (xy 302.480472 -404.986236) (xy 302.480472 -404.828756) (xy 302.480948 -404.818648)
			(xy 302.488695 -404.799974) (xy 302.502994 -404.785682) (xy 302.521672 -404.777944) (xy 302.53178 -404.777448)
			(xy 303.24806 -404.777448) (xy 303.25816 -404.778017) (xy 303.276827 -404.785732) (xy 303.291121 -404.800002)
			(xy 303.298867 -404.818657) (xy 303.299368 -404.828756) (xy 303.299368 -404.986236) (xy 303.299768 -404.995424)
			(xy 303.30629 -405.012608) (xy 303.312068 -405.019764) (xy 303.333929 -405.045432) (xy 303.37202 -405.101065)
			(xy 303.403173 -405.160861) (xy 303.426939 -405.223957) (xy 303.442975 -405.289447) (xy 303.451052 -405.356385)
			(xy 303.451052 -405.423809) (xy 303.442976 -405.490748) (xy 303.42694 -405.556237) (xy 303.403175 -405.619334)
			(xy 303.372023 -405.67913) (xy 303.333933 -405.734763) (xy 303.312068 -405.760428) (xy 303.306273 -405.767574)
			(xy 303.299758 -405.784764) (xy 303.299368 -405.793956) (xy 303.299368 -406.286208) (xy 303.299781 -406.295395)
			(xy 303.306294 -406.312579) (xy 303.312068 -406.319736) (xy 303.333902 -406.345427) (xy 303.371993 -406.401057)
			(xy 303.403147 -406.460849) (xy 303.426915 -406.523943) (xy 303.442953 -406.589429) (xy 303.451032 -406.656365)
			(xy 303.451035 -406.723787) (xy 303.442962 -406.790724) (xy 303.426929 -406.856211) (xy 303.403167 -406.919307)
			(xy 303.372018 -406.979102) (xy 303.333931 -407.034735) (xy 303.312068 -407.0604) (xy 303.306285 -407.067555)
			(xy 303.299763 -407.084738) (xy 303.299368 -407.093928) (xy 303.299368 -407.251408) (xy 303.29899 -407.261535)
			(xy 303.291233 -407.280245) (xy 303.276904 -407.29456) (xy 303.258187 -407.302299) (xy 303.24806 -407.302716)
			(xy 302.53178 -407.302716) (xy 302.521672 -407.302232) (xy 302.502996 -407.294491) (xy 302.488703 -407.280194)
			(xy 302.480966 -407.261516) (xy 302.480472 -407.251408) (xy 302.480472 -407.093928) (xy 302.480055 -407.084741)
			(xy 302.473547 -407.067557) (xy 302.467772 -407.0604) (xy 302.445878 -407.03476) (xy 302.407792 -406.979121)
			(xy 302.376644 -406.919321) (xy 302.352883 -406.856221) (xy 302.33685 -406.790729) (xy 302.328777 -406.723789)
			(xy 299.050708 -406.723789) (xy 299.042674 -406.790547) (xy 299.026705 -406.855927) (xy 299.003037 -406.91893)
			(xy 298.972009 -406.978653) (xy 298.934065 -407.034239) (xy 298.91228 -407.059892) (xy 298.906502 -407.06705)
			(xy 298.899977 -407.084231) (xy 298.89958 -407.09342) (xy 298.89958 -407.251408) (xy 298.899184 -407.261565)
			(xy 298.891382 -407.280321) (xy 298.876978 -407.294645) (xy 298.858177 -407.302341) (xy 298.848018 -407.302716)
			(xy 298.131738 -407.302716) (xy 298.121608 -407.302241) (xy 298.10288 -407.294517) (xy 298.088521 -407.280227)
			(xy 298.080708 -407.261535) (xy 298.080176 -407.251408) (xy 298.080176 -407.09342) (xy 298.079762 -407.084233)
			(xy 298.073252 -407.067048) (xy 298.067476 -407.059892) (xy 298.045656 -407.034266) (xy 298.007706 -406.978677)
			(xy 297.976672 -406.91895) (xy 297.952999 -406.855942) (xy 297.937027 -406.790556) (xy 297.928985 -406.72373)
			(xy 294.650947 -406.72373) (xy 294.650947 -406.723787) (xy 294.642874 -406.790723) (xy 294.626842 -406.856211)
			(xy 294.60308 -406.919306) (xy 294.571933 -406.979101) (xy 294.533847 -407.034735) (xy 294.511984 -407.0604)
			(xy 294.506203 -407.067556) (xy 294.49968 -407.084738) (xy 294.499284 -407.093928) (xy 294.499284 -407.251408)
			(xy 294.49889 -407.261533) (xy 294.491136 -407.28024) (xy 294.476813 -407.294554) (xy 294.458101 -407.302296)
			(xy 294.447976 -407.302716) (xy 293.731696 -407.302716) (xy 293.721589 -407.302218) (xy 293.702914 -407.294482)
			(xy 293.68862 -407.28019) (xy 293.680882 -407.261515) (xy 293.680388 -407.251408) (xy 293.680388 -407.093928)
			(xy 293.679967 -407.084742) (xy 293.673461 -407.067557) (xy 293.667688 -407.0604) (xy 293.645793 -407.03476)
			(xy 293.607706 -406.979122) (xy 293.576557 -406.919322) (xy 293.552796 -406.856222) (xy 293.536763 -406.79073)
			(xy 293.52869 -406.723789) (xy 290.250621 -406.723789) (xy 290.242587 -406.790547) (xy 290.226619 -406.855927)
			(xy 290.202951 -406.91893) (xy 290.171924 -406.978653) (xy 290.133981 -407.034239) (xy 290.112196 -407.059892)
			(xy 290.10642 -407.067052) (xy 290.099893 -407.084231) (xy 290.099496 -407.09342) (xy 290.099496 -407.251408)
			(xy 290.099085 -407.261563) (xy 290.091286 -407.280316) (xy 290.076886 -407.29464) (xy 290.058091 -407.302338)
			(xy 290.047934 -407.302716) (xy 289.331654 -407.302716) (xy 289.321519 -407.30231) (xy 289.302788 -407.294559)
			(xy 289.288432 -407.280248) (xy 289.280622 -407.261541) (xy 289.280092 -407.251408) (xy 289.280092 -407.09342)
			(xy 289.279674 -407.084234) (xy 289.273166 -407.067049) (xy 289.267392 -407.059892) (xy 289.245571 -407.034266)
			(xy 289.20762 -406.978677) (xy 289.176585 -406.918951) (xy 289.152912 -406.855943) (xy 289.136939 -406.790557)
			(xy 289.128897 -406.72373) (xy 237.406942 -406.72373) (xy 237.406942 -409.523887) (xy 286.928735 -409.523887)
			(xy 286.928738 -409.456459) (xy 286.936818 -409.389518) (xy 286.952859 -409.324026) (xy 286.97663 -409.260927)
			(xy 287.007788 -409.20113) (xy 287.045884 -409.145496) (xy 287.067752 -409.119832) (xy 287.073566 -409.1127)
			(xy 287.080069 -409.095499) (xy 287.080452 -409.086304) (xy 287.080452 -408.594052) (xy 287.080005 -408.584869)
			(xy 287.073516 -408.567685) (xy 287.067752 -408.560524) (xy 287.045878 -408.534866) (xy 287.007786 -408.479232)
			(xy 286.976633 -408.419435) (xy 286.952867 -408.356337) (xy 286.936831 -408.290847) (xy 286.928755 -408.223907)
			(xy 286.928755 -408.156481) (xy 286.936833 -408.089542) (xy 286.952871 -408.024051) (xy 286.976638 -407.960954)
			(xy 287.007793 -407.901158) (xy 287.045886 -407.845524) (xy 287.067752 -407.81986) (xy 287.073554 -407.812719)
			(xy 287.080064 -407.795525) (xy 287.080452 -407.786332) (xy 287.080452 -407.628852) (xy 287.080945 -407.618746)
			(xy 287.088689 -407.600076) (xy 287.102983 -407.585785) (xy 287.121654 -407.578043) (xy 287.13176 -407.577544)
			(xy 287.84804 -407.577544) (xy 287.858144 -407.578051) (xy 287.876813 -407.585791) (xy 287.891104 -407.600081)
			(xy 287.898847 -407.618748) (xy 287.899348 -407.628852) (xy 287.899348 -407.786332) (xy 287.899755 -407.795519)
			(xy 287.906272 -407.812703) (xy 287.912048 -407.81986) (xy 287.933906 -407.845531) (xy 287.971998 -407.901163)
			(xy 288.003152 -407.960958) (xy 288.026919 -408.024055) (xy 288.042957 -408.089543) (xy 288.051034 -408.156482)
			(xy 288.051035 -408.223906) (xy 288.042959 -408.290845) (xy 288.026923 -408.356334) (xy 288.003157 -408.419431)
			(xy 287.972004 -408.479226) (xy 287.933913 -408.53486) (xy 287.912048 -408.560524) (xy 287.906252 -408.56767)
			(xy 287.899739 -408.58486) (xy 287.899348 -408.594052) (xy 287.899348 -409.086304) (xy 287.899768 -409.09549)
			(xy 287.906276 -409.112674) (xy 287.912048 -409.119832) (xy 287.933878 -409.145526) (xy 287.971972 -409.201155)
			(xy 288.003127 -409.260947) (xy 288.026895 -409.32404) (xy 288.042935 -409.389526) (xy 288.051014 -409.456462)
			(xy 288.051018 -409.523884) (xy 288.042945 -409.590821) (xy 288.026911 -409.656308) (xy 288.003149 -409.719404)
			(xy 287.971999 -409.779199) (xy 287.933912 -409.834832) (xy 287.912048 -409.860496) (xy 287.906264 -409.86765)
			(xy 287.899743 -409.884834) (xy 287.899348 -409.894024) (xy 287.899348 -410.051504) (xy 287.898819 -410.061607)
			(xy 287.891089 -410.080276) (xy 287.876806 -410.094569) (xy 287.858143 -410.102312) (xy 287.84804 -410.102812)
			(xy 287.13176 -410.102812) (xy 287.12165 -410.102348) (xy 287.102973 -410.094599) (xy 287.08868 -410.080296)
			(xy 287.080945 -410.061614) (xy 287.080452 -410.051504) (xy 287.080452 -409.894024) (xy 287.080019 -409.884839)
			(xy 287.07352 -409.867655) (xy 287.067752 -409.860496) (xy 287.045851 -409.834861) (xy 287.00776 -409.779223)
			(xy 286.976608 -409.719423) (xy 286.952843 -409.656322) (xy 286.936809 -409.590829) (xy 286.928735 -409.523887)
			(xy 237.406942 -409.523887) (xy 237.406942 -410.623642) (xy 289.128908 -410.623642) (xy 289.12891 -410.556334)
			(xy 289.136956 -410.48951) (xy 289.152933 -410.424126) (xy 289.176609 -410.361121) (xy 289.207648 -410.301397)
			(xy 289.245602 -410.245811) (xy 289.267392 -410.22016) (xy 289.273187 -410.213014) (xy 289.279703 -410.195824)
			(xy 289.280092 -410.186632) (xy 289.280092 -409.693364) (xy 289.279701 -409.684175) (xy 289.273174 -409.66699)
			(xy 289.267392 -409.659836) (xy 289.245614 -409.634175) (xy 289.207662 -409.578591) (xy 289.176625 -409.518869)
			(xy 289.152949 -409.455866) (xy 289.136974 -409.390484) (xy 289.128928 -409.323662) (xy 289.128927 -409.256356)
			(xy 289.136971 -409.189534) (xy 289.152944 -409.124152) (xy 289.176618 -409.061147) (xy 289.207653 -409.001425)
			(xy 289.245603 -408.945839) (xy 289.267392 -408.920188) (xy 289.273175 -408.913033) (xy 289.279698 -408.89585)
			(xy 289.280092 -408.88666) (xy 289.280092 -408.728672) (xy 289.280498 -408.718517) (xy 289.288302 -408.699766)
			(xy 289.302703 -408.685443) (xy 289.321497 -408.677743) (xy 289.331654 -408.677364) (xy 290.047934 -408.677364)
			(xy 290.058066 -408.677799) (xy 290.076792 -408.685543) (xy 290.091148 -408.699845) (xy 290.098962 -408.718542)
			(xy 290.099496 -408.728672) (xy 290.099496 -408.88666) (xy 290.099926 -408.895845) (xy 290.106426 -408.91303)
			(xy 290.112196 -408.920188) (xy 290.133994 -408.945831) (xy 290.171941 -409.00142) (xy 290.202971 -409.061145)
			(xy 290.226642 -409.12415) (xy 290.242613 -409.189533) (xy 290.250656 -409.256356) (xy 290.250655 -409.323662)
			(xy 290.24261 -409.390484) (xy 290.226637 -409.455867) (xy 290.202964 -409.518872) (xy 290.200389 -409.523827)
			(xy 291.329055 -409.523827) (xy 291.329058 -409.456519) (xy 291.337106 -409.389694) (xy 291.353082 -409.32431)
			(xy 291.376759 -409.261304) (xy 291.407797 -409.201579) (xy 291.44575 -409.145992) (xy 291.46754 -409.12034)
			(xy 291.47335 -409.113204) (xy 291.479855 -409.096006) (xy 291.48024 -409.086812) (xy 291.48024 -408.593544)
			(xy 291.4798 -408.58436) (xy 291.473306 -408.567176) (xy 291.46754 -408.560016) (xy 291.445744 -408.53437)
			(xy 291.407796 -408.478783) (xy 291.376763 -408.419059) (xy 291.35309 -408.356053) (xy 291.337118 -408.29067)
			(xy 291.329074 -408.223847) (xy 291.329075 -408.156541) (xy 291.33712 -408.089718) (xy 291.353094 -408.024335)
			(xy 291.376767 -407.96133) (xy 291.407802 -407.901607) (xy 291.445752 -407.84602) (xy 291.46754 -407.820368)
			(xy 291.473338 -407.813224) (xy 291.479851 -407.796032) (xy 291.48024 -407.78684) (xy 291.48024 -407.628852)
			(xy 291.480583 -407.61869) (xy 291.488402 -407.599929) (xy 291.502823 -407.585606) (xy 291.521637 -407.577915)
			(xy 291.531802 -407.577544) (xy 292.248082 -407.577544) (xy 292.258208 -407.578041) (xy 292.27693 -407.585764)
			(xy 292.291287 -407.600047) (xy 292.299106 -407.618729) (xy 292.299644 -407.628852) (xy 292.299644 -407.78684)
			(xy 292.300048 -407.796028) (xy 292.306567 -407.813211) (xy 292.312344 -407.820368) (xy 292.334124 -407.846026)
			(xy 292.372074 -407.901612) (xy 292.403109 -407.961334) (xy 292.426783 -408.024338) (xy 292.442757 -408.089719)
			(xy 292.450802 -408.156542) (xy 292.450803 -408.223846) (xy 292.442759 -408.290669) (xy 292.426786 -408.356051)
			(xy 292.403114 -408.419055) (xy 292.372081 -408.478778) (xy 292.334132 -408.534364) (xy 292.312344 -408.560016)
			(xy 292.306551 -408.567164) (xy 292.300036 -408.584353) (xy 292.299644 -408.593544) (xy 292.299644 -409.086812)
			(xy 292.300061 -409.095998) (xy 292.306571 -409.113182) (xy 292.312344 -409.12034) (xy 292.334097 -409.146021)
			(xy 292.372048 -409.201603) (xy 292.403083 -409.261322) (xy 292.426759 -409.324323) (xy 292.442735 -409.389702)
			(xy 292.450782 -409.456522) (xy 292.450786 -409.523824) (xy 292.442745 -409.590645) (xy 292.426775 -409.656025)
			(xy 292.403106 -409.719028) (xy 292.372076 -409.77875) (xy 292.33413 -409.834336) (xy 292.312344 -409.859988)
			(xy 292.306521 -409.867114) (xy 292.300024 -409.884319) (xy 292.299644 -409.893516) (xy 292.299644 -410.051504)
			(xy 292.299182 -410.061653) (xy 292.291394 -410.080397) (xy 292.27701 -410.094718) (xy 292.258233 -410.102426)
			(xy 292.248082 -410.102812) (xy 291.531802 -410.102812) (xy 291.521682 -410.102273) (xy 291.502971 -410.094556)
			(xy 291.488616 -410.080286) (xy 291.480788 -410.061621) (xy 291.48024 -410.051504) (xy 291.48024 -409.893516)
			(xy 291.479813 -409.884331) (xy 291.47331 -409.867147) (xy 291.46754 -409.859988) (xy 291.445717 -409.834365)
			(xy 291.407769 -409.778774) (xy 291.376737 -409.719047) (xy 291.353066 -409.656039) (xy 291.337096 -409.590653)
			(xy 291.329055 -409.523827) (xy 290.200389 -409.523827) (xy 290.171931 -409.578596) (xy 290.133983 -409.634183)
			(xy 290.112196 -409.659836) (xy 290.106401 -409.666982) (xy 290.099886 -409.684172) (xy 290.099496 -409.693364)
			(xy 290.099496 -410.186632) (xy 290.099891 -410.195821) (xy 290.106415 -410.213005) (xy 290.112196 -410.22016)
			(xy 290.133967 -410.245826) (xy 290.171914 -410.301411) (xy 290.202946 -410.361133) (xy 290.226618 -410.424136)
			(xy 290.242591 -410.489516) (xy 290.250636 -410.556336) (xy 290.250638 -410.62364) (xy 290.250631 -410.6237)
			(xy 293.528701 -410.6237) (xy 293.528702 -410.556276) (xy 293.53678 -410.489336) (xy 293.552816 -410.423847)
			(xy 293.576582 -410.360749) (xy 293.607734 -410.300952) (xy 293.645824 -410.245317) (xy 293.667688 -410.219652)
			(xy 293.673486 -410.212508) (xy 293.68 -410.195317) (xy 293.680388 -410.186124) (xy 293.680388 -409.693872)
			(xy 293.679994 -409.684683) (xy 293.673469 -409.667499) (xy 293.667688 -409.660344) (xy 293.645836 -409.634669)
			(xy 293.607748 -409.579035) (xy 293.576597 -409.519241) (xy 293.552833 -409.456145) (xy 293.536797 -409.390657)
			(xy 293.52872 -409.32372) (xy 293.528719 -409.256298) (xy 293.536794 -409.189361) (xy 293.552828 -409.123872)
			(xy 293.57659 -409.060776) (xy 293.607739 -409.00098) (xy 293.645825 -408.945345) (xy 293.667688 -408.91968)
			(xy 293.673474 -408.912527) (xy 293.679995 -408.895343) (xy 293.680388 -408.886152) (xy 293.680388 -408.728672)
			(xy 293.680862 -408.718563) (xy 293.688606 -408.699886) (xy 293.702907 -408.685593) (xy 293.721587 -408.677857)
			(xy 293.731696 -408.677364) (xy 294.447976 -408.677364) (xy 294.458079 -408.677904) (xy 294.47675 -408.685627)
			(xy 294.491044 -408.699907) (xy 294.498786 -408.71857) (xy 294.499284 -408.728672) (xy 294.499284 -408.886152)
			(xy 294.499721 -408.895336) (xy 294.506216 -408.912521) (xy 294.511984 -408.91968) (xy 294.53386 -408.945335)
			(xy 294.57195 -409.000971) (xy 294.603101 -409.060768) (xy 294.626865 -409.123866) (xy 294.6429 -409.189357)
			(xy 294.650975 -409.256297) (xy 294.650974 -409.323721) (xy 294.642897 -409.390661) (xy 294.62686 -409.456151)
			(xy 294.603093 -409.519248) (xy 294.600676 -409.523887) (xy 295.728823 -409.523887) (xy 295.728826 -409.456459)
			(xy 295.736906 -409.389518) (xy 295.752947 -409.324026) (xy 295.776716 -409.260928) (xy 295.807873 -409.201131)
			(xy 295.845969 -409.145497) (xy 295.867836 -409.119832) (xy 295.873649 -409.112698) (xy 295.880153 -409.095499)
			(xy 295.880536 -409.086304) (xy 295.880536 -408.594052) (xy 295.880093 -408.584869) (xy 295.873601 -408.567684)
			(xy 295.867836 -408.560524) (xy 295.845963 -408.534866) (xy 295.807872 -408.479231) (xy 295.77672 -408.419434)
			(xy 295.752954 -408.356336) (xy 295.736918 -408.290846) (xy 295.728843 -408.223907) (xy 295.728843 -408.156481)
			(xy 295.736921 -408.089542) (xy 295.752958 -408.024052) (xy 295.776725 -407.960955) (xy 295.807878 -407.901159)
			(xy 295.84597 -407.845525) (xy 295.867836 -407.81986) (xy 295.873637 -407.812718) (xy 295.880148 -407.795525)
			(xy 295.880536 -407.786332) (xy 295.880536 -407.628852) (xy 295.880947 -407.618736) (xy 295.888707 -407.60005)
			(xy 295.903027 -407.585755) (xy 295.921727 -407.578029) (xy 295.931844 -407.577544) (xy 296.648124 -407.577544)
			(xy 296.658227 -407.578064) (xy 296.676895 -407.585799) (xy 296.691187 -407.600084) (xy 296.698931 -407.618749)
			(xy 296.699432 -407.628852) (xy 296.699432 -407.786332) (xy 296.699842 -407.795519) (xy 296.706357 -407.812703)
			(xy 296.712132 -407.81986) (xy 296.733987 -407.845532) (xy 296.772074 -407.901167) (xy 296.803223 -407.960962)
			(xy 296.826986 -408.024058) (xy 296.843021 -408.089546) (xy 296.851097 -408.156483) (xy 296.851098 -408.223905)
			(xy 296.843024 -408.290842) (xy 296.82699 -408.356331) (xy 296.803228 -408.419427) (xy 296.77208 -408.479223)
			(xy 296.733994 -408.534858) (xy 296.712132 -408.560524) (xy 296.706334 -408.567668) (xy 296.699822 -408.58486)
			(xy 296.699432 -408.594052) (xy 296.699432 -409.086304) (xy 296.699856 -409.095489) (xy 296.706362 -409.112673)
			(xy 296.712132 -409.119832) (xy 296.733959 -409.145527) (xy 296.772047 -409.201158) (xy 296.803198 -409.26095)
			(xy 296.826962 -409.324043) (xy 296.842999 -409.389528) (xy 296.851078 -409.456463) (xy 296.851081 -409.523883)
			(xy 296.843009 -409.590818) (xy 296.826978 -409.656305) (xy 296.80322 -409.7194) (xy 296.772075 -409.779196)
			(xy 296.733993 -409.83483) (xy 296.712132 -409.860496) (xy 296.706346 -409.867649) (xy 296.699827 -409.884834)
			(xy 296.699432 -409.894024) (xy 296.699432 -410.051504) (xy 296.698919 -410.061609) (xy 296.691186 -410.080281)
			(xy 296.676898 -410.094575) (xy 296.658229 -410.102315) (xy 296.648124 -410.102812) (xy 295.931844 -410.102812)
			(xy 295.921726 -410.102348) (xy 295.903026 -410.094617) (xy 295.88871 -410.080315) (xy 295.880961 -410.061622)
			(xy 295.880536 -410.051504) (xy 295.880536 -409.894024) (xy 295.880106 -409.884839) (xy 295.873605 -409.867655)
			(xy 295.867836 -409.860496) (xy 295.845935 -409.834861) (xy 295.807845 -409.779223) (xy 295.776694 -409.719423)
			(xy 295.752931 -409.656322) (xy 295.736896 -409.590829) (xy 295.728823 -409.523887) (xy 294.600676 -409.523887)
			(xy 294.57194 -409.579045) (xy 294.533849 -409.634679) (xy 294.511984 -409.660344) (xy 294.506184 -409.667487)
			(xy 294.499672 -409.684679) (xy 294.499284 -409.693872) (xy 294.499284 -410.186124) (xy 294.499686 -410.195312)
			(xy 294.506206 -410.212496) (xy 294.511984 -410.219652) (xy 294.533833 -410.24533) (xy 294.571923 -410.300962)
			(xy 294.603075 -410.360757) (xy 294.626841 -410.423852) (xy 294.642878 -410.489339) (xy 294.650956 -410.556277)
			(xy 294.650957 -410.623641) (xy 297.928996 -410.623641) (xy 297.928998 -410.556334) (xy 297.937044 -410.48951)
			(xy 297.95302 -410.424127) (xy 297.976696 -410.361121) (xy 298.007733 -410.301398) (xy 298.045686 -410.245812)
			(xy 298.067476 -410.22016) (xy 298.073269 -410.213012) (xy 298.079787 -410.195824) (xy 298.080176 -410.186632)
			(xy 298.080176 -409.693364) (xy 298.079788 -409.684174) (xy 298.07326 -409.66699) (xy 298.067476 -409.659836)
			(xy 298.045699 -409.634175) (xy 298.007747 -409.57859) (xy 297.976712 -409.518868) (xy 297.953037 -409.455865)
			(xy 297.937062 -409.390484) (xy 297.929016 -409.323661) (xy 297.929015 -409.256357) (xy 297.937058 -409.189534)
			(xy 297.953031 -409.124152) (xy 297.976704 -409.061148) (xy 298.007738 -409.001425) (xy 298.045688 -408.94584)
			(xy 298.067476 -408.920188) (xy 298.073257 -408.913032) (xy 298.079782 -408.89585) (xy 298.080176 -408.88666)
			(xy 298.080176 -408.728672) (xy 298.080598 -408.718519) (xy 298.088398 -408.699771) (xy 298.102794 -408.685449)
			(xy 298.121583 -408.677746) (xy 298.131738 -408.677364) (xy 298.848018 -408.677364) (xy 298.858149 -408.677812)
			(xy 298.876875 -408.68555) (xy 298.891232 -408.699849) (xy 298.899046 -408.718543) (xy 298.89958 -408.728672)
			(xy 298.89958 -408.88666) (xy 298.900014 -408.895845) (xy 298.906512 -408.913029) (xy 298.91228 -408.920188)
			(xy 298.934079 -408.945831) (xy 298.972026 -409.001419) (xy 299.003058 -409.061144) (xy 299.026729 -409.12415)
			(xy 299.042701 -409.189533) (xy 299.050744 -409.256356) (xy 299.050743 -409.323662) (xy 299.042698 -409.390485)
			(xy 299.026724 -409.455868) (xy 299.003051 -409.518873) (xy 299.000446 -409.523886) (xy 300.128614 -409.523886)
			(xy 300.128617 -409.456459) (xy 300.136697 -409.389518) (xy 300.152737 -409.324027) (xy 300.176506 -409.260928)
			(xy 300.207662 -409.201131) (xy 300.245757 -409.145497) (xy 300.267624 -409.119832) (xy 300.273435 -409.112697)
			(xy 300.27994 -409.095499) (xy 300.280324 -409.086304) (xy 300.280324 -408.594052) (xy 300.279883 -408.584868)
			(xy 300.27339 -408.567684) (xy 300.267624 -408.560524) (xy 300.245751 -408.534866) (xy 300.207661 -408.479231)
			(xy 300.17651 -408.419434) (xy 300.152745 -408.356336) (xy 300.136709 -408.290846) (xy 300.128634 -408.223906)
			(xy 300.128634 -408.156482) (xy 300.136711 -408.089542) (xy 300.152748 -408.024053) (xy 300.176514 -407.960955)
			(xy 300.207667 -407.901159) (xy 300.245759 -407.845525) (xy 300.267624 -407.81986) (xy 300.273423 -407.812717)
			(xy 300.279935 -407.795525) (xy 300.280324 -407.786332) (xy 300.280324 -407.628852) (xy 300.280747 -407.618737)
			(xy 300.288504 -407.600053) (xy 300.302821 -407.585759) (xy 300.321516 -407.578031) (xy 300.331632 -407.577544)
			(xy 301.047912 -407.577544) (xy 301.058015 -407.578074) (xy 301.076682 -407.585805) (xy 301.090975 -407.600088)
			(xy 301.098719 -407.61875) (xy 301.09922 -407.628852) (xy 301.09922 -407.786332) (xy 301.09961 -407.795521)
			(xy 301.106137 -407.812706) (xy 301.11192 -407.81986) (xy 301.133775 -407.845532) (xy 301.171863 -407.901166)
			(xy 301.203013 -407.960962) (xy 301.226777 -408.024057) (xy 301.242812 -408.089545) (xy 301.250888 -408.156483)
			(xy 301.250889 -408.223905) (xy 301.242814 -408.290843) (xy 301.22678 -408.356331) (xy 301.203018 -408.419427)
			(xy 301.171869 -408.479224) (xy 301.133783 -408.534858) (xy 301.11192 -408.560524) (xy 301.106133 -408.567676)
			(xy 301.099612 -408.584861) (xy 301.09922 -408.594052) (xy 301.09922 -409.086304) (xy 301.099624 -409.095492)
			(xy 301.106141 -409.112676) (xy 301.11192 -409.119832) (xy 301.133748 -409.145527) (xy 301.171836 -409.201158)
			(xy 301.202988 -409.26095) (xy 301.226753 -409.324043) (xy 301.24279 -409.389528) (xy 301.250869 -409.456463)
			(xy 301.250872 -409.523883) (xy 301.2428 -409.590819) (xy 301.226769 -409.656305) (xy 301.20301 -409.719401)
			(xy 301.171864 -409.779196) (xy 301.133781 -409.83483) (xy 301.11192 -409.860496) (xy 301.106145 -409.867657)
			(xy 301.099617 -409.884835) (xy 301.09922 -409.894024) (xy 301.09922 -410.051504) (xy 301.098719 -410.06161)
			(xy 301.090983 -410.080285) (xy 301.076692 -410.094579) (xy 301.058018 -410.102317) (xy 301.047912 -410.102812)
			(xy 300.331632 -410.102812) (xy 300.321513 -410.102358) (xy 300.302812 -410.094623) (xy 300.288497 -410.080318)
			(xy 300.280749 -410.061623) (xy 300.280324 -410.051504) (xy 300.280324 -409.894024) (xy 300.279897 -409.884839)
			(xy 300.273394 -409.867655) (xy 300.267624 -409.860496) (xy 300.245724 -409.83486) (xy 300.207635 -409.779222)
			(xy 300.176484 -409.719422) (xy 300.152721 -409.656321) (xy 300.136687 -409.590828) (xy 300.128614 -409.523886)
			(xy 299.000446 -409.523886) (xy 298.972017 -409.578597) (xy 298.934068 -409.634184) (xy 298.91228 -409.659836)
			(xy 298.906483 -409.666981) (xy 298.899969 -409.684172) (xy 298.89958 -409.693364) (xy 298.89958 -410.186632)
			(xy 298.899979 -410.19582) (xy 298.906501 -410.213004) (xy 298.91228 -410.22016) (xy 298.934052 -410.245825)
			(xy 298.972 -410.30141) (xy 299.003032 -410.361132) (xy 299.026705 -410.424135) (xy 299.042679 -410.489515)
			(xy 299.050724 -410.556336) (xy 299.050725 -410.62364) (xy 299.050718 -410.6237) (xy 302.328789 -410.6237)
			(xy 302.32879 -410.556276) (xy 302.336867 -410.489337) (xy 302.352904 -410.423847) (xy 302.376668 -410.36075)
			(xy 302.407819 -410.300953) (xy 302.445908 -410.245318) (xy 302.467772 -410.219652) (xy 302.47358 -410.212515)
			(xy 302.480086 -410.195318) (xy 302.480472 -410.186124) (xy 302.480472 -409.693872) (xy 302.480082 -409.684683)
			(xy 302.473555 -409.667498) (xy 302.467772 -409.660344) (xy 302.445921 -409.634669) (xy 302.407834 -409.579035)
			(xy 302.376684 -409.51924) (xy 302.35292 -409.456144) (xy 302.336885 -409.390657) (xy 302.328808 -409.32372)
			(xy 302.328807 -409.256298) (xy 302.336882 -409.189361) (xy 302.352915 -409.123873) (xy 302.376677 -409.060777)
			(xy 302.407824 -409.000981) (xy 302.44591 -408.945346) (xy 302.467772 -408.91968) (xy 302.473568 -408.912535)
			(xy 302.480081 -408.895344) (xy 302.480472 -408.886152) (xy 302.480472 -408.728672) (xy 302.480961 -408.718565)
			(xy 302.488703 -408.699891) (xy 302.502998 -408.685599) (xy 302.521673 -408.67786) (xy 302.53178 -408.677364)
			(xy 303.24806 -408.677364) (xy 303.258175 -408.677848) (xy 303.276871 -408.685576) (xy 303.291186 -408.699872)
			(xy 303.298939 -408.718557) (xy 303.299368 -408.728672) (xy 303.299368 -408.886152) (xy 303.299809 -408.895336)
			(xy 303.306302 -408.91252) (xy 303.312068 -408.91968) (xy 303.333945 -408.945335) (xy 303.372035 -409.00097)
			(xy 303.403187 -409.060768) (xy 303.426952 -409.123866) (xy 303.442988 -409.189356) (xy 303.451063 -409.256296)
			(xy 303.451062 -409.323722) (xy 303.442985 -409.390661) (xy 303.426947 -409.456151) (xy 303.40318 -409.519249)
			(xy 303.372026 -409.579045) (xy 303.333934 -409.634679) (xy 303.312068 -409.660344) (xy 303.306266 -409.667485)
			(xy 303.299755 -409.684679) (xy 303.299368 -409.693872) (xy 303.299368 -410.186124) (xy 303.299774 -410.195312)
			(xy 303.306291 -410.212495) (xy 303.312068 -410.219652) (xy 303.333917 -410.24533) (xy 303.372009 -410.300962)
			(xy 303.403162 -410.360756) (xy 303.426928 -410.423851) (xy 303.442966 -410.489339) (xy 303.451044 -410.556276)
			(xy 303.451045 -410.6237) (xy 303.44297 -410.690637) (xy 303.426935 -410.756126) (xy 303.403172 -410.819222)
			(xy 303.372021 -410.879018) (xy 303.333932 -410.934651) (xy 303.312068 -410.960316) (xy 303.306278 -410.967466)
			(xy 303.29976 -410.984653) (xy 303.299368 -410.993844) (xy 303.299368 -411.151324) (xy 303.299003 -411.161452)
			(xy 303.291241 -411.180162) (xy 303.276909 -411.194477) (xy 303.258189 -411.202216) (xy 303.24806 -411.202632)
			(xy 302.53178 -411.202632) (xy 302.521674 -411.202132) (xy 302.503001 -411.194394) (xy 302.488708 -411.180102)
			(xy 302.480969 -411.16143) (xy 302.480472 -411.151324) (xy 302.480472 -410.993844) (xy 302.480047 -410.984658)
			(xy 302.473544 -410.967474) (xy 302.467772 -410.960316) (xy 302.445893 -410.934663) (xy 302.407807 -410.879026)
			(xy 302.376658 -410.819228) (xy 302.352896 -410.75613) (xy 302.336863 -410.690639) (xy 302.328789 -410.6237)
			(xy 299.050718 -410.6237) (xy 299.042683 -410.690461) (xy 299.026712 -410.755842) (xy 299.003042 -410.818846)
			(xy 298.972012 -410.878569) (xy 298.934066 -410.934156) (xy 298.91228 -410.959808) (xy 298.906495 -410.966961)
			(xy 298.899974 -410.984146) (xy 298.89958 -410.993336) (xy 298.89958 -411.151324) (xy 298.899198 -411.161482)
			(xy 298.891391 -411.180239) (xy 298.876982 -411.194562) (xy 298.858179 -411.202258) (xy 298.848018 -411.202632)
			(xy 298.131738 -411.202632) (xy 298.12161 -411.202141) (xy 298.102885 -411.194421) (xy 298.088526 -411.180135)
			(xy 298.080711 -411.161449) (xy 298.080176 -411.151324) (xy 298.080176 -410.993336) (xy 298.079754 -410.98415)
			(xy 298.073249 -410.966965) (xy 298.067476 -410.959808) (xy 298.045672 -410.934169) (xy 298.007721 -410.878582)
			(xy 297.976686 -410.818857) (xy 297.953013 -410.75585) (xy 297.93704 -410.690466) (xy 297.928996 -410.623641)
			(xy 294.650957 -410.623641) (xy 294.650957 -410.623699) (xy 294.642883 -410.690637) (xy 294.626848 -410.756125)
			(xy 294.603085 -410.819221) (xy 294.571935 -410.879017) (xy 294.533848 -410.934651) (xy 294.511984 -410.960316)
			(xy 294.506196 -410.967467) (xy 294.499677 -410.984653) (xy 294.499284 -410.993844) (xy 294.499284 -411.151324)
			(xy 294.498834 -411.161436) (xy 294.491086 -411.180118) (xy 294.476778 -411.194413) (xy 294.458089 -411.202144)
			(xy 294.447976 -411.202632) (xy 293.731696 -411.202632) (xy 293.721591 -411.202119) (xy 293.702919 -411.194386)
			(xy 293.688625 -411.180098) (xy 293.680885 -411.161429) (xy 293.680388 -411.151324) (xy 293.680388 -410.993844)
			(xy 293.679959 -410.984659) (xy 293.673459 -410.967474) (xy 293.667688 -410.960316) (xy 293.645809 -410.934664)
			(xy 293.607721 -410.879027) (xy 293.576572 -410.819229) (xy 293.552809 -410.75613) (xy 293.536775 -410.69064)
			(xy 293.528701 -410.6237) (xy 290.250631 -410.6237) (xy 290.242595 -410.69046) (xy 290.226625 -410.755841)
			(xy 290.202956 -410.818845) (xy 290.171926 -410.878568) (xy 290.133982 -410.934155) (xy 290.112196 -410.959808)
			(xy 290.106413 -410.966963) (xy 290.09989 -410.984146) (xy 290.099496 -410.993336) (xy 290.099496 -411.151324)
			(xy 290.099098 -411.16148) (xy 290.091294 -411.180234) (xy 290.07689 -411.194557) (xy 290.058092 -411.202255)
			(xy 290.047934 -411.202632) (xy 289.331654 -411.202632) (xy 289.321521 -411.20221) (xy 289.302793 -411.194462)
			(xy 289.288438 -411.180156) (xy 289.280625 -411.161455) (xy 289.280092 -411.151324) (xy 289.280092 -410.993336)
			(xy 289.279666 -410.98415) (xy 289.273164 -410.966966) (xy 289.267392 -410.959808) (xy 289.245587 -410.934169)
			(xy 289.207635 -410.878582) (xy 289.1766 -410.818857) (xy 289.152925 -410.755851) (xy 289.136952 -410.690467)
			(xy 289.128908 -410.623642) (xy 237.406942 -410.623642) (xy 237.406942 -412.06928) (xy 237.406417 -412.094228)
			(xy 237.39861 -412.143509) (xy 237.383199 -412.190966) (xy 237.360564 -412.235432) (xy 237.33126 -412.275817)
			(xy 237.313978 -412.293816) (xy 235.9787 -413.629094) (xy 235.960708 -413.646388) (xy 235.920331 -413.675711)
			(xy 235.875865 -413.698359) (xy 235.828403 -413.713772) (xy 235.779115 -413.721572) (xy 235.754164 -413.722058)
			(xy 208.805526 -413.722058) (xy 208.780578 -413.721525) (xy 208.731298 -413.713719) (xy 208.683841 -413.69831)
			(xy 208.639375 -413.675677) (xy 208.59899 -413.646375) (xy 208.58099 -413.629094) (xy 207.025748 -412.073852)
			(xy 207.008419 -412.055891) (xy 206.979094 -412.015508) (xy 206.956447 -411.971034) (xy 206.941036 -411.923565)
			(xy 206.933241 -411.87427) (xy 206.932784 -411.849316) (xy 206.932784 -389.931402) (xy 206.932362 -389.921332)
			(xy 206.924639 -389.902734) (xy 206.917798 -389.895334) (xy 204.423264 -387.4008) (xy 204.405961 -387.382815)
			(xy 204.376631 -387.342439) (xy 204.353979 -387.297971) (xy 204.338563 -387.250507) (xy 204.330761 -387.201216)
			(xy 204.3303 -387.176264) (xy 204.3303 -378.650754) (xy 204.31379 -378.625608) (xy 204.299566 -378.619512)
			(xy 204.274196 -378.60805) (xy 204.226725 -378.578976) (xy 204.183985 -378.543309) (xy 204.146885 -378.501809)
			(xy 204.116211 -378.455355) (xy 204.092616 -378.404937) (xy 204.076601 -378.351623) (xy 204.068507 -378.296548)
			(xy 204.068504 -378.240882) (xy 197.862607 -378.240882) (xy 197.885782 -378.367343) (xy 197.901882 -378.499931)
			(xy 197.909946 -378.633249) (xy 197.91045 -378.70003) (xy 197.909946 -378.766811) (xy 197.901882 -378.900129)
			(xy 197.885782 -379.032717) (xy 197.861707 -379.164091) (xy 197.829744 -379.293772) (xy 197.790009 -379.421286)
			(xy 197.742647 -379.546169) (xy 197.687832 -379.667964) (xy 197.625762 -379.786227) (xy 197.556666 -379.900526)
			(xy 197.480794 -380.010446) (xy 197.398424 -380.115583) (xy 197.309856 -380.215556) (xy 197.215414 -380.309998)
			(xy 197.115441 -380.398566) (xy 197.010304 -380.480936) (xy 196.900384 -380.556808) (xy 196.786085 -380.625904)
			(xy 196.667822 -380.687974) (xy 196.546027 -380.742789) (xy 196.421144 -380.790151) (xy 196.29363 -380.829886)
			(xy 196.163949 -380.861849) (xy 196.032575 -380.885924) (xy 195.899987 -380.902024) (xy 195.766669 -380.910088)
			(xy 195.633107 -380.910088) (xy 195.499789 -380.902024) (xy 195.367201 -380.885924) (xy 195.235827 -380.861849)
			(xy 195.106146 -380.829886) (xy 194.978632 -380.790151) (xy 194.853749 -380.742789) (xy 194.731954 -380.687974)
			(xy 194.613691 -380.625904) (xy 194.499392 -380.556808) (xy 194.389472 -380.480936) (xy 194.284335 -380.398566)
			(xy 194.184362 -380.309998) (xy 194.08992 -380.215556) (xy 194.001352 -380.115583) (xy 193.918982 -380.010446)
			(xy 193.84311 -379.900526) (xy 193.774014 -379.786227) (xy 193.711944 -379.667964) (xy 193.657129 -379.546169)
			(xy 193.609767 -379.421286) (xy 193.570032 -379.293772) (xy 193.538069 -379.164091) (xy 193.513994 -379.032717)
			(xy 193.497894 -378.900129) (xy 193.48983 -378.766811) (xy 173.519592 -378.766811) (xy 173.519592 -379.186694)
			(xy 173.520007 -379.195881) (xy 173.526518 -379.213065) (xy 173.532292 -379.220222) (xy 173.554124 -379.245837)
			(xy 173.592069 -379.30143) (xy 173.623099 -379.361159) (xy 173.646768 -379.424168) (xy 173.662737 -379.489554)
			(xy 173.670777 -379.556381) (xy 173.670772 -379.623689) (xy 173.662724 -379.690514) (xy 173.646747 -379.755898)
			(xy 173.623071 -379.818905) (xy 173.592034 -379.87863) (xy 173.554082 -379.934217) (xy 173.532292 -379.95987)
			(xy 173.526482 -379.967006) (xy 173.519976 -379.984204) (xy 173.519592 -379.993398) (xy 173.519592 -380.151386)
			(xy 173.519056 -380.161539) (xy 173.511292 -380.180302) (xy 173.496939 -380.194667) (xy 173.478183 -380.202447)
			(xy 173.46803 -380.202948) (xy 172.75175 -380.202948) (xy 172.74158 -380.202495) (xy 172.722784 -380.194724)
			(xy 172.708396 -380.180347) (xy 172.700612 -380.161556) (xy 172.700188 -380.151386) (xy 172.700188 -379.993398)
			(xy 172.699781 -379.98421) (xy 172.693266 -379.967026) (xy 172.687488 -379.95987) (xy 172.665744 -379.934181)
			(xy 172.627791 -379.878601) (xy 172.596753 -379.818883) (xy 172.573075 -379.755883) (xy 172.557097 -379.690505)
			(xy 172.549049 -379.623686) (xy 172.549045 -379.556383) (xy 172.557085 -379.489563) (xy 172.573055 -379.424183)
			(xy 172.596724 -379.36118) (xy 172.627755 -379.301458) (xy 172.665702 -379.245873) (xy 172.687488 -379.220222)
			(xy 172.693299 -379.213087) (xy 172.699805 -379.195889) (xy 172.700188 -379.186694) (xy 172.700188 -378.693426)
			(xy 172.699768 -378.68424) (xy 172.693262 -378.667055) (xy 172.687488 -378.659898) (xy 172.665673 -378.634268)
			(xy 172.627722 -378.578679) (xy 172.596687 -378.518953) (xy 172.573014 -378.455946) (xy 172.557041 -378.39056)
			(xy 172.548998 -378.323734) (xy 169.270937 -378.323734) (xy 169.262897 -378.390552) (xy 169.246928 -378.455932)
			(xy 169.22326 -378.518935) (xy 169.192232 -378.578658) (xy 169.154289 -378.634245) (xy 169.132504 -378.659898)
			(xy 169.126726 -378.667057) (xy 169.1202 -378.684237) (xy 169.119804 -378.693426) (xy 169.119804 -379.186694)
			(xy 169.120216 -379.195881) (xy 169.126728 -379.213065) (xy 169.132504 -379.220222) (xy 169.154336 -379.245838)
			(xy 169.19228 -379.30143) (xy 169.223309 -379.361159) (xy 169.246977 -379.424169) (xy 169.262946 -379.489555)
			(xy 169.270986 -379.556381) (xy 169.270982 -379.623689) (xy 169.262933 -379.690513) (xy 169.246957 -379.755898)
			(xy 169.223281 -379.818904) (xy 169.192245 -379.878629) (xy 169.154293 -379.934217) (xy 169.132504 -379.95987)
			(xy 169.126696 -379.967007) (xy 169.120188 -379.984204) (xy 169.119804 -379.993398) (xy 169.119804 -380.151386)
			(xy 169.119256 -380.161538) (xy 169.111494 -380.180299) (xy 169.097146 -380.194663) (xy 169.078393 -380.202445)
			(xy 169.068242 -380.202948) (xy 168.351962 -380.202948) (xy 168.3418 -380.202497) (xy 168.323027 -380.194708)
			(xy 168.308663 -380.180329) (xy 168.300892 -380.161548) (xy 168.3004 -380.151386) (xy 168.3004 -379.993398)
			(xy 168.299991 -379.984211) (xy 168.293476 -379.967026) (xy 168.2877 -379.95987) (xy 168.265959 -379.93418)
			(xy 168.228011 -379.878598) (xy 168.196978 -379.818879) (xy 168.173304 -379.75588) (xy 168.157329 -379.690503)
			(xy 168.149282 -379.623685) (xy 168.149278 -379.556384) (xy 168.157317 -379.489565) (xy 168.173284 -379.424186)
			(xy 168.19695 -379.361184) (xy 168.227975 -379.301461) (xy 168.265916 -379.245875) (xy 168.2877 -379.220222)
			(xy 168.293512 -379.213088) (xy 168.300018 -379.195889) (xy 168.3004 -379.186694) (xy 168.3004 -378.693426)
			(xy 168.299977 -378.68424) (xy 168.293472 -378.667056) (xy 168.2877 -378.659898) (xy 168.265888 -378.634266)
			(xy 168.227942 -378.578676) (xy 168.196912 -378.518949) (xy 168.173243 -378.455942) (xy 168.157273 -378.390558)
			(xy 168.149231 -378.323734) (xy 164.871169 -378.323734) (xy 164.871169 -378.323791) (xy 164.863096 -378.390728)
			(xy 164.847063 -378.456215) (xy 164.823302 -378.519311) (xy 164.792155 -378.579106) (xy 164.75407 -378.634741)
			(xy 164.732208 -378.660406) (xy 164.726427 -378.667563) (xy 164.719903 -378.684744) (xy 164.719508 -378.693934)
			(xy 164.719508 -379.186186) (xy 164.719923 -379.195373) (xy 164.726433 -379.212557) (xy 164.732208 -379.219714)
			(xy 164.754117 -379.245342) (xy 164.792204 -379.300982) (xy 164.823352 -379.360784) (xy 164.847113 -379.423885)
			(xy 164.863145 -379.489379) (xy 164.871217 -379.556321) (xy 164.871213 -379.623748) (xy 164.863133 -379.690689)
			(xy 164.847093 -379.756181) (xy 164.823324 -379.81928) (xy 164.792168 -379.879077) (xy 164.754074 -379.934713)
			(xy 164.732208 -379.960378) (xy 164.726397 -379.967513) (xy 164.719891 -379.984711) (xy 164.719508 -379.993906)
			(xy 164.719508 -380.151386) (xy 164.718963 -380.161506) (xy 164.711249 -380.180218) (xy 164.696981 -380.194573)
			(xy 164.678317 -380.202401) (xy 164.6682 -380.202948) (xy 163.95192 -380.202948) (xy 163.941773 -380.202463)
			(xy 163.92303 -380.194683) (xy 163.908708 -380.180306) (xy 163.900999 -380.161534) (xy 163.900612 -380.151386)
			(xy 163.900612 -379.993906) (xy 163.900196 -379.98472) (xy 163.893686 -379.967535) (xy 163.887912 -379.960378)
			(xy 163.866093 -379.934676) (xy 163.828002 -379.879047) (xy 163.796849 -379.819256) (xy 163.773081 -379.756164)
			(xy 163.757042 -379.690679) (xy 163.748963 -379.623745) (xy 163.748958 -379.556324) (xy 163.75703 -379.489389)
			(xy 163.773061 -379.423902) (xy 163.79682 -379.360807) (xy 163.827966 -379.301013) (xy 163.86605 -379.245379)
			(xy 163.887912 -379.219714) (xy 163.893729 -379.212583) (xy 163.900231 -379.195382) (xy 163.900612 -379.186186)
			(xy 163.900612 -378.693934) (xy 163.900183 -378.684749) (xy 163.893682 -378.667565) (xy 163.887912 -378.660406)
			(xy 163.866022 -378.634762) (xy 163.827933 -378.579125) (xy 163.796783 -378.519326) (xy 163.77302 -378.456226)
			(xy 163.756986 -378.390734) (xy 163.748912 -378.323793) (xy 160.470867 -378.323793) (xy 160.462831 -378.390554)
			(xy 160.44686 -378.455935) (xy 160.423188 -378.518939) (xy 160.392156 -378.578661) (xy 160.354207 -378.634246)
			(xy 160.33242 -378.659898) (xy 160.326644 -378.667058) (xy 160.320116 -378.684237) (xy 160.31972 -378.693426)
			(xy 160.31972 -379.186694) (xy 160.320129 -379.195881) (xy 160.326643 -379.213066) (xy 160.33242 -379.220222)
			(xy 160.354254 -379.245836) (xy 160.392205 -379.301427) (xy 160.423238 -379.361156) (xy 160.44691 -379.424165)
			(xy 160.462881 -379.489552) (xy 160.470922 -379.55638) (xy 160.470918 -379.623689) (xy 160.462869 -379.690516)
			(xy 160.44689 -379.755901) (xy 160.42321 -379.818908) (xy 160.392169 -379.878632) (xy 160.354212 -379.934219)
			(xy 160.33242 -379.95987) (xy 160.326614 -379.967008) (xy 160.320104 -379.984204) (xy 160.31972 -379.993398)
			(xy 160.31972 -380.151386) (xy 160.319324 -380.161562) (xy 160.311536 -380.180364) (xy 160.297141 -380.194751)
			(xy 160.278334 -380.202529) (xy 160.268158 -380.202948) (xy 159.551878 -380.202948) (xy 159.541717 -380.202484)
			(xy 159.522945 -380.1947) (xy 159.50858 -380.180325) (xy 159.500808 -380.161547) (xy 159.500316 -380.151386)
			(xy 159.500316 -379.993398) (xy 159.499903 -379.984211) (xy 159.493391 -379.967027) (xy 159.487616 -379.95987)
			(xy 159.465874 -379.93418) (xy 159.427926 -379.878599) (xy 159.396892 -379.81888) (xy 159.373217 -379.75588)
			(xy 159.357242 -379.690503) (xy 159.349195 -379.623685) (xy 159.34919 -379.556384) (xy 159.35723 -379.489565)
			(xy 159.373197 -379.424186) (xy 159.396864 -379.361183) (xy 159.42789 -379.301461) (xy 159.465832 -379.245875)
			(xy 159.487616 -379.220222) (xy 159.49343 -379.213089) (xy 159.499934 -379.195889) (xy 159.500316 -379.186694)
			(xy 159.500316 -378.693426) (xy 159.49989 -378.684241) (xy 159.493387 -378.667056) (xy 159.487616 -378.659898)
			(xy 159.465803 -378.634267) (xy 159.427857 -378.578677) (xy 159.396826 -378.51895) (xy 159.373156 -378.455943)
			(xy 159.357185 -378.390558) (xy 159.349143 -378.323734) (xy 129.670819 -378.323734) (xy 129.662778 -378.390552)
			(xy 129.646808 -378.455933) (xy 129.623139 -378.518936) (xy 129.59211 -378.578659) (xy 129.554166 -378.634246)
			(xy 129.53238 -378.659898) (xy 129.526599 -378.667054) (xy 129.520076 -378.684236) (xy 129.51968 -378.693426)
			(xy 129.51968 -379.186694) (xy 129.520098 -379.19588) (xy 129.526607 -379.213064) (xy 129.53238 -379.220222)
			(xy 129.554212 -379.245837) (xy 129.592159 -379.301429) (xy 129.623189 -379.361158) (xy 129.646858 -379.424168)
			(xy 129.662827 -379.489554) (xy 129.670868 -379.55638) (xy 129.670863 -379.623689) (xy 129.662815 -379.690514)
			(xy 129.646838 -379.755899) (xy 129.623161 -379.818905) (xy 129.592123 -379.87863) (xy 129.55417 -379.934218)
			(xy 129.53238 -379.95987) (xy 129.526569 -379.967005) (xy 129.520064 -379.984203) (xy 129.51968 -379.993398)
			(xy 129.51968 -380.151386) (xy 129.519156 -380.161541) (xy 129.511389 -380.180306) (xy 129.497033 -380.194671)
			(xy 129.478272 -380.202449) (xy 129.468118 -380.202948) (xy 128.751838 -380.202948) (xy 128.741667 -380.202505)
			(xy 128.722871 -380.19473) (xy 128.708484 -380.18035) (xy 128.7007 -380.161557) (xy 128.700276 -380.151386)
			(xy 128.700276 -379.993398) (xy 128.699872 -379.98421) (xy 128.693355 -379.967025) (xy 128.687576 -379.95987)
			(xy 128.665832 -379.934181) (xy 128.62788 -379.878601) (xy 128.596842 -379.818883) (xy 128.573165 -379.755883)
			(xy 128.557188 -379.690505) (xy 128.54914 -379.623686) (xy 128.549136 -379.556384) (xy 128.557176 -379.489563)
			(xy 128.573145 -379.424183) (xy 128.596814 -379.361181) (xy 128.627844 -379.301459) (xy 128.66579 -379.245874)
			(xy 128.687576 -379.220222) (xy 128.693385 -379.213086) (xy 128.699893 -379.195889) (xy 128.700276 -379.186694)
			(xy 128.700276 -378.693426) (xy 128.699859 -378.684239) (xy 128.693351 -378.667055) (xy 128.687576 -378.659898)
			(xy 128.665762 -378.634267) (xy 128.627811 -378.578679) (xy 128.596777 -378.518952) (xy 128.573104 -378.455945)
			(xy 128.557132 -378.39056) (xy 128.549089 -378.323734) (xy 125.271028 -378.323734) (xy 125.262987 -378.390552)
			(xy 125.247018 -378.455932) (xy 125.223349 -378.518936) (xy 125.192321 -378.578659) (xy 125.154377 -378.634245)
			(xy 125.132592 -378.659898) (xy 125.126813 -378.667056) (xy 125.120288 -378.684237) (xy 125.119892 -378.693426)
			(xy 125.119892 -379.186694) (xy 125.120307 -379.195881) (xy 125.126818 -379.213065) (xy 125.132592 -379.220222)
			(xy 125.154424 -379.245837) (xy 125.192369 -379.30143) (xy 125.223399 -379.361159) (xy 125.247068 -379.424168)
			(xy 125.263037 -379.489554) (xy 125.271077 -379.556381) (xy 125.271072 -379.623689) (xy 125.263024 -379.690514)
			(xy 125.247047 -379.755898) (xy 125.223371 -379.818905) (xy 125.192334 -379.87863) (xy 125.154382 -379.934217)
			(xy 125.132592 -379.95987) (xy 125.126782 -379.967006) (xy 125.120276 -379.984204) (xy 125.119892 -379.993398)
			(xy 125.119892 -380.151386) (xy 125.119356 -380.161539) (xy 125.111592 -380.180302) (xy 125.097239 -380.194667)
			(xy 125.078483 -380.202447) (xy 125.06833 -380.202948) (xy 124.35205 -380.202948) (xy 124.34188 -380.202495)
			(xy 124.323084 -380.194724) (xy 124.308696 -380.180347) (xy 124.300912 -380.161556) (xy 124.300488 -380.151386)
			(xy 124.300488 -379.993398) (xy 124.300081 -379.98421) (xy 124.293566 -379.967026) (xy 124.287788 -379.95987)
			(xy 124.266044 -379.934181) (xy 124.228091 -379.878601) (xy 124.197053 -379.818883) (xy 124.173375 -379.755883)
			(xy 124.157397 -379.690505) (xy 124.149349 -379.623686) (xy 124.149345 -379.556383) (xy 124.157385 -379.489563)
			(xy 124.173355 -379.424183) (xy 124.197024 -379.36118) (xy 124.228055 -379.301458) (xy 124.266002 -379.245873)
			(xy 124.287788 -379.220222) (xy 124.293599 -379.213087) (xy 124.300105 -379.195889) (xy 124.300488 -379.186694)
			(xy 124.300488 -378.693426) (xy 124.300068 -378.68424) (xy 124.293562 -378.667055) (xy 124.287788 -378.659898)
			(xy 124.265973 -378.634268) (xy 124.228022 -378.578679) (xy 124.196987 -378.518953) (xy 124.173314 -378.455946)
			(xy 124.157341 -378.39056) (xy 124.149298 -378.323734) (xy 120.87126 -378.323734) (xy 120.87126 -378.323791)
			(xy 120.863187 -378.390728) (xy 120.847154 -378.456216) (xy 120.823392 -378.519311) (xy 120.792244 -378.579107)
			(xy 120.754159 -378.634741) (xy 120.732296 -378.660406) (xy 120.726514 -378.667561) (xy 120.719991 -378.684744)
			(xy 120.719596 -378.693934) (xy 120.719596 -379.186186) (xy 120.720014 -379.195372) (xy 120.726522 -379.212557)
			(xy 120.732296 -379.219714) (xy 120.754205 -379.245342) (xy 120.792293 -379.300982) (xy 120.823442 -379.360783)
			(xy 120.847204 -379.423885) (xy 120.863236 -379.489378) (xy 120.871308 -379.556321) (xy 120.871304 -379.623748)
			(xy 120.863224 -379.69069) (xy 120.847183 -379.756181) (xy 120.823414 -379.81928) (xy 120.792257 -379.879078)
			(xy 120.754163 -379.934713) (xy 120.732296 -379.960378) (xy 120.726483 -379.967512) (xy 120.719978 -379.984711)
			(xy 120.719596 -379.993906) (xy 120.719596 -380.151386) (xy 120.719063 -380.161507) (xy 120.711347 -380.180221)
			(xy 120.697075 -380.194577) (xy 120.678406 -380.202403) (xy 120.668288 -380.202948) (xy 119.952008 -380.202948)
			(xy 119.94186 -380.202473) (xy 119.923117 -380.194689) (xy 119.908795 -380.180309) (xy 119.901087 -380.161535)
			(xy 119.9007 -380.151386) (xy 119.9007 -379.993906) (xy 119.900287 -379.984719) (xy 119.893775 -379.967535)
			(xy 119.888 -379.960378) (xy 119.866181 -379.934675) (xy 119.828091 -379.879046) (xy 119.796938 -379.819255)
			(xy 119.773172 -379.756163) (xy 119.757133 -379.690679) (xy 119.749053 -379.623745) (xy 119.749049 -379.556325)
			(xy 119.757121 -379.489389) (xy 119.773151 -379.423903) (xy 119.79691 -379.360808) (xy 119.828056 -379.301013)
			(xy 119.866139 -379.245379) (xy 119.888 -379.219714) (xy 119.893816 -379.212582) (xy 119.900319 -379.195381)
			(xy 119.9007 -379.186186) (xy 119.9007 -378.693934) (xy 119.900273 -378.684749) (xy 119.893771 -378.667564)
			(xy 119.888 -378.660406) (xy 119.86611 -378.634762) (xy 119.828023 -378.579124) (xy 119.796873 -378.519325)
			(xy 119.77311 -378.456226) (xy 119.757077 -378.390734) (xy 119.749003 -378.323793) (xy 116.470957 -378.323793)
			(xy 116.462922 -378.390554) (xy 116.44695 -378.455936) (xy 116.423278 -378.518939) (xy 116.392245 -378.578662)
			(xy 116.354296 -378.634247) (xy 116.332508 -378.659898) (xy 116.326731 -378.667057) (xy 116.320204 -378.684237)
			(xy 116.319808 -378.693426) (xy 116.319808 -379.186694) (xy 116.320219 -379.195881) (xy 116.326732 -379.213066)
			(xy 116.332508 -379.220222) (xy 116.354343 -379.245836) (xy 116.392293 -379.301427) (xy 116.423328 -379.361155)
			(xy 116.447 -379.424165) (xy 116.462971 -379.489552) (xy 116.471013 -379.55638) (xy 116.471009 -379.623689)
			(xy 116.462959 -379.690516) (xy 116.44698 -379.755901) (xy 116.423299 -379.818908) (xy 116.392258 -379.878633)
			(xy 116.3543 -379.934219) (xy 116.332508 -379.95987) (xy 116.3267 -379.967007) (xy 116.320192 -379.984204)
			(xy 116.319808 -379.993398) (xy 116.319808 -380.151386) (xy 116.319256 -380.161537) (xy 116.311495 -380.180297)
			(xy 116.297148 -380.194661) (xy 116.278397 -380.202445) (xy 116.268246 -380.202948) (xy 115.551966 -380.202948)
			(xy 115.541804 -380.202494) (xy 115.523032 -380.194706) (xy 115.508667 -380.180328) (xy 115.500896 -380.161548)
			(xy 115.500404 -380.151386) (xy 115.500404 -379.993398) (xy 115.499994 -379.984211) (xy 115.49348 -379.967027)
			(xy 115.487704 -379.95987) (xy 115.465963 -379.93418) (xy 115.428015 -379.878598) (xy 115.396981 -379.81888)
			(xy 115.373307 -379.75588) (xy 115.357332 -379.690503) (xy 115.349285 -379.623685) (xy 115.349281 -379.556384)
			(xy 115.35732 -379.489565) (xy 115.373287 -379.424186) (xy 115.396953 -379.361184) (xy 115.427979 -379.301461)
			(xy 115.46592 -379.245875) (xy 115.487704 -379.220222) (xy 115.493517 -379.213088) (xy 115.500022 -379.195889)
			(xy 115.500404 -379.186694) (xy 115.500404 -378.693426) (xy 115.49998 -378.68424) (xy 115.493476 -378.667056)
			(xy 115.487704 -378.659898) (xy 115.465892 -378.634266) (xy 115.427946 -378.578676) (xy 115.396916 -378.518949)
			(xy 115.373246 -378.455942) (xy 115.357276 -378.390558) (xy 115.349234 -378.323734) (xy 85.670933 -378.323734)
			(xy 85.670933 -378.323792) (xy 85.662859 -378.390729) (xy 85.646825 -378.456217) (xy 85.623062 -378.519313)
			(xy 85.591912 -378.579108) (xy 85.553824 -378.634741) (xy 85.53196 -378.660406) (xy 85.526173 -378.667558)
			(xy 85.519654 -378.684743) (xy 85.51926 -378.693934) (xy 85.51926 -379.186186) (xy 85.519686 -379.195371)
			(xy 85.526189 -379.212555) (xy 85.53196 -379.219714) (xy 85.553871 -379.245341) (xy 85.591961 -379.30098)
			(xy 85.623111 -379.360781) (xy 85.646875 -379.423883) (xy 85.662908 -379.489377) (xy 85.670981 -379.55632)
			(xy 85.670977 -379.623749) (xy 85.662896 -379.690691) (xy 85.646854 -379.756183) (xy 85.623083 -379.819282)
			(xy 85.591925 -379.879079) (xy 85.553828 -379.934713) (xy 85.53196 -379.960378) (xy 85.526143 -379.967508)
			(xy 85.519641 -379.98471) (xy 85.51926 -379.993906) (xy 85.51926 -380.151386) (xy 85.518762 -380.161512)
			(xy 85.511039 -380.180233) (xy 85.496756 -380.194589) (xy 85.478075 -380.202409) (xy 85.467952 -380.202948)
			(xy 84.751672 -380.202948) (xy 84.741567 -380.202439) (xy 84.722898 -380.194701) (xy 84.708606 -380.180412)
			(xy 84.700863 -380.161744) (xy 84.700364 -380.15164) (xy 84.700364 -379.993906) (xy 84.699937 -379.984721)
			(xy 84.693433 -379.967537) (xy 84.687664 -379.960378) (xy 84.665846 -379.934675) (xy 84.627759 -379.879045)
			(xy 84.596608 -379.819254) (xy 84.572843 -379.756162) (xy 84.556805 -379.690678) (xy 84.548726 -379.623744)
			(xy 84.548722 -379.556325) (xy 84.556793 -379.48939) (xy 84.572822 -379.423904) (xy 84.59658 -379.36081)
			(xy 84.627723 -379.301014) (xy 84.665804 -379.24538) (xy 84.687664 -379.219714) (xy 84.693487 -379.212588)
			(xy 84.699984 -379.195383) (xy 84.700364 -379.186186) (xy 84.700364 -378.693934) (xy 84.699923 -378.68475)
			(xy 84.693429 -378.667566) (xy 84.687664 -378.660406) (xy 84.665776 -378.634761) (xy 84.62769 -378.579123)
			(xy 84.596543 -378.519324) (xy 84.572781 -378.456224) (xy 84.556749 -378.390733) (xy 84.548676 -378.323793)
			(xy 81.271142 -378.323793) (xy 81.263068 -378.390729) (xy 81.247035 -378.456217) (xy 81.223272 -378.519312)
			(xy 81.192123 -378.579108) (xy 81.154035 -378.634741) (xy 81.132172 -378.660406) (xy 81.126387 -378.667559)
			(xy 81.119866 -378.684744) (xy 81.119472 -378.693934) (xy 81.119472 -379.186186) (xy 81.119895 -379.195372)
			(xy 81.126401 -379.212556) (xy 81.132172 -379.219714) (xy 81.154082 -379.245341) (xy 81.192171 -379.300981)
			(xy 81.223322 -379.360782) (xy 81.247084 -379.423884) (xy 81.263118 -379.489378) (xy 81.27119 -379.556321)
			(xy 81.271186 -379.623748) (xy 81.263105 -379.69069) (xy 81.247064 -379.756182) (xy 81.223293 -379.819281)
			(xy 81.192136 -379.879079) (xy 81.15404 -379.934713) (xy 81.132172 -379.960378) (xy 81.126356 -379.967509)
			(xy 81.119854 -379.984711) (xy 81.119472 -379.993906) (xy 81.119472 -380.151386) (xy 81.118962 -380.16151)
			(xy 81.111241 -380.180229) (xy 81.096962 -380.194585) (xy 81.078286 -380.202407) (xy 81.068164 -380.202948)
			(xy 80.351884 -380.202948) (xy 80.34178 -380.202429) (xy 80.323111 -380.194695) (xy 80.308818 -380.180409)
			(xy 80.301076 -380.161744) (xy 80.300576 -380.15164) (xy 80.300576 -379.993906) (xy 80.300168 -379.984718)
			(xy 80.293654 -379.967534) (xy 80.287876 -379.960378) (xy 80.266058 -379.934675) (xy 80.22797 -379.879045)
			(xy 80.196818 -379.819254) (xy 80.173052 -379.756162) (xy 80.157015 -379.690678) (xy 80.148935 -379.623744)
			(xy 80.148931 -379.556325) (xy 80.157002 -379.48939) (xy 80.173032 -379.423904) (xy 80.19679 -379.360809)
			(xy 80.227934 -379.301014) (xy 80.266016 -379.24538) (xy 80.287876 -379.219714) (xy 80.293689 -379.21258)
			(xy 80.300195 -379.195381) (xy 80.300576 -379.186186) (xy 80.300576 -378.693934) (xy 80.300155 -378.684748)
			(xy 80.29365 -378.667563) (xy 80.287876 -378.660406) (xy 80.265987 -378.634761) (xy 80.227901 -378.579123)
			(xy 80.196753 -378.519324) (xy 80.172991 -378.456225) (xy 80.156958 -378.390733) (xy 80.148885 -378.323793)
			(xy 76.870815 -378.323793) (xy 76.862781 -378.390552) (xy 76.846812 -378.455933) (xy 76.823143 -378.518936)
			(xy 76.792114 -378.578659) (xy 76.75417 -378.634246) (xy 76.732384 -378.659898) (xy 76.726604 -378.667055)
			(xy 76.72008 -378.684236) (xy 76.719684 -378.693426) (xy 76.719684 -379.186694) (xy 76.720101 -379.19588)
			(xy 76.72661 -379.213065) (xy 76.732384 -379.220222) (xy 76.754216 -379.245837) (xy 76.792162 -379.30143)
			(xy 76.823192 -379.361158) (xy 76.846861 -379.424168) (xy 76.86283 -379.489554) (xy 76.870871 -379.55638)
			(xy 76.870866 -379.623689) (xy 76.862818 -379.690514) (xy 76.846841 -379.755899) (xy 76.823164 -379.818905)
			(xy 76.792127 -379.87863) (xy 76.754174 -379.934218) (xy 76.732384 -379.95987) (xy 76.726573 -379.967005)
			(xy 76.720068 -379.984203) (xy 76.719684 -379.993398) (xy 76.719684 -380.151386) (xy 76.719156 -380.16154)
			(xy 76.71139 -380.180305) (xy 76.697035 -380.19467) (xy 76.678276 -380.202449) (xy 76.668122 -380.202948)
			(xy 75.951842 -380.202948) (xy 75.941671 -380.202501) (xy 75.922875 -380.194728) (xy 75.908488 -380.180349)
			(xy 75.900704 -380.161556) (xy 75.90028 -380.151386) (xy 75.90028 -379.993398) (xy 75.899875 -379.98421)
			(xy 75.893358 -379.967026) (xy 75.88758 -379.95987) (xy 75.865836 -379.934181) (xy 75.827883 -379.878601)
			(xy 75.796846 -379.818883) (xy 75.773169 -379.755883) (xy 75.757191 -379.690505) (xy 75.749143 -379.623686)
			(xy 75.749139 -379.556383) (xy 75.757179 -379.489563) (xy 75.773148 -379.424183) (xy 75.796818 -379.36118)
			(xy 75.827848 -379.301458) (xy 75.865794 -379.245874) (xy 75.88758 -379.220222) (xy 75.89339 -379.213086)
			(xy 75.899897 -379.195889) (xy 75.90028 -379.186694) (xy 75.90028 -378.693426) (xy 75.899862 -378.68424)
			(xy 75.893354 -378.667055) (xy 75.88758 -378.659898) (xy 75.865766 -378.634267) (xy 75.827815 -378.578679)
			(xy 75.79678 -378.518953) (xy 75.773107 -378.455945) (xy 75.757135 -378.39056) (xy 75.749092 -378.323734)
			(xy 72.471054 -378.323734) (xy 72.471054 -378.323791) (xy 72.46298 -378.390728) (xy 72.446947 -378.456216)
			(xy 72.423186 -378.519312) (xy 72.392037 -378.579107) (xy 72.353951 -378.634741) (xy 72.332088 -378.660406)
			(xy 72.326305 -378.667561) (xy 72.319783 -378.684744) (xy 72.319388 -378.693934) (xy 72.319388 -379.186186)
			(xy 72.319808 -379.195372) (xy 72.326315 -379.212556) (xy 72.332088 -379.219714) (xy 72.353998 -379.245342)
			(xy 72.392086 -379.300981) (xy 72.423235 -379.360783) (xy 72.446997 -379.423884) (xy 72.46303 -379.489378)
			(xy 72.471102 -379.556321) (xy 72.471098 -379.623748) (xy 72.463017 -379.69069) (xy 72.446977 -379.756182)
			(xy 72.423207 -379.819281) (xy 72.39205 -379.879078) (xy 72.353955 -379.934713) (xy 72.332088 -379.960378)
			(xy 72.326274 -379.967511) (xy 72.31977 -379.984711) (xy 72.319388 -379.993906) (xy 72.319388 -380.151386)
			(xy 72.318863 -380.161508) (xy 72.311145 -380.180224) (xy 72.296871 -380.19458) (xy 72.278199 -380.202404)
			(xy 72.26808 -380.202948) (xy 71.5518 -380.202948) (xy 71.541652 -380.202479) (xy 71.522909 -380.194693)
			(xy 71.508587 -380.180311) (xy 71.500879 -380.161536) (xy 71.500492 -380.151386) (xy 71.500492 -379.993906)
			(xy 71.500081 -379.984719) (xy 71.493568 -379.967534) (xy 71.487792 -379.960378) (xy 71.465974 -379.934675)
			(xy 71.427884 -379.879046) (xy 71.396732 -379.819255) (xy 71.372965 -379.756163) (xy 71.356927 -379.690678)
			(xy 71.348847 -379.623744) (xy 71.348843 -379.556325) (xy 71.356914 -379.48939) (xy 71.372945 -379.423903)
			(xy 71.396703 -379.360808) (xy 71.427848 -379.301013) (xy 71.465931 -379.245379) (xy 71.487792 -379.219714)
			(xy 71.493607 -379.212582) (xy 71.500111 -379.195381) (xy 71.500492 -379.186186) (xy 71.500492 -378.693934)
			(xy 71.500067 -378.684748) (xy 71.493564 -378.667564) (xy 71.487792 -378.660406) (xy 71.465903 -378.634762)
			(xy 71.427815 -378.579124) (xy 71.396666 -378.519325) (xy 71.372904 -378.456225) (xy 71.35687 -378.390734)
			(xy 71.348797 -378.323793) (xy 41.671024 -378.323793) (xy 41.66295 -378.390729) (xy 41.646915 -378.456218)
			(xy 41.623152 -378.519314) (xy 41.592001 -378.579109) (xy 41.553912 -378.634742) (xy 41.532048 -378.660406)
			(xy 41.52626 -378.667557) (xy 41.519742 -378.684743) (xy 41.519348 -378.693934) (xy 41.519348 -379.186186)
			(xy 41.519776 -379.195371) (xy 41.526279 -379.212555) (xy 41.532048 -379.219714) (xy 41.553959 -379.245341)
			(xy 41.59205 -379.30098) (xy 41.623201 -379.360781) (xy 41.646965 -379.423883) (xy 41.662999 -379.489377)
			(xy 41.671072 -379.55632) (xy 41.671068 -379.623749) (xy 41.662987 -379.690691) (xy 41.646945 -379.756183)
			(xy 41.623173 -379.819282) (xy 41.592014 -379.879079) (xy 41.553917 -379.934714) (xy 41.532048 -379.960378)
			(xy 41.526229 -379.967507) (xy 41.519729 -379.98471) (xy 41.519348 -379.993906) (xy 41.519348 -380.151386)
			(xy 41.518862 -380.161513) (xy 41.511136 -380.180236) (xy 41.49685 -380.194594) (xy 41.478165 -380.202411)
			(xy 41.46804 -380.202948) (xy 40.75176 -380.202948) (xy 40.741609 -380.202512) (xy 40.722865 -380.194712)
			(xy 40.708545 -380.180321) (xy 40.700838 -380.161539) (xy 40.700452 -380.151386) (xy 40.700452 -379.993906)
			(xy 40.700027 -379.984721) (xy 40.693523 -379.967537) (xy 40.687752 -379.960378) (xy 40.665931 -379.934676)
			(xy 40.627838 -379.879048) (xy 40.596682 -379.819258) (xy 40.572913 -379.756165) (xy 40.556873 -379.69068)
			(xy 40.548793 -379.623745) (xy 40.548788 -379.556324) (xy 40.556861 -379.489388) (xy 40.572893 -379.423901)
			(xy 40.596654 -379.360806) (xy 40.627802 -379.301011) (xy 40.665889 -379.245378) (xy 40.687752 -379.219714)
			(xy 40.693574 -379.212587) (xy 40.700072 -379.195382) (xy 40.700452 -379.186186) (xy 40.700452 -378.693934)
			(xy 40.700014 -378.68475) (xy 40.693519 -378.667566) (xy 40.687752 -378.660406) (xy 40.665861 -378.634763)
			(xy 40.627769 -378.579126) (xy 40.596617 -378.519328) (xy 40.572852 -378.456228) (xy 40.556817 -378.390735)
			(xy 40.548742 -378.323794) (xy 37.271233 -378.323794) (xy 37.263159 -378.390729) (xy 37.247125 -378.456217)
			(xy 37.223362 -378.519313) (xy 37.192212 -378.579108) (xy 37.154124 -378.634741) (xy 37.13226 -378.660406)
			(xy 37.126473 -378.667558) (xy 37.119954 -378.684743) (xy 37.11956 -378.693934) (xy 37.11956 -379.186186)
			(xy 37.119986 -379.195371) (xy 37.126489 -379.212555) (xy 37.13226 -379.219714) (xy 37.154171 -379.245341)
			(xy 37.192261 -379.30098) (xy 37.223411 -379.360781) (xy 37.247175 -379.423883) (xy 37.263208 -379.489377)
			(xy 37.271281 -379.55632) (xy 37.271277 -379.623749) (xy 37.263196 -379.690691) (xy 37.247154 -379.756183)
			(xy 37.223383 -379.819282) (xy 37.192225 -379.879079) (xy 37.154128 -379.934713) (xy 37.13226 -379.960378)
			(xy 37.126443 -379.967508) (xy 37.119941 -379.98471) (xy 37.11956 -379.993906) (xy 37.11956 -380.151386)
			(xy 37.119062 -380.161512) (xy 37.111339 -380.180233) (xy 37.097056 -380.194589) (xy 37.078375 -380.202409)
			(xy 37.068252 -380.202948) (xy 36.351972 -380.202948) (xy 36.341822 -380.202502) (xy 36.323078 -380.194707)
			(xy 36.308758 -380.180318) (xy 36.30105 -380.161538) (xy 36.300664 -380.151386) (xy 36.300664 -379.993906)
			(xy 36.300237 -379.984721) (xy 36.293733 -379.967537) (xy 36.287964 -379.960378) (xy 36.266146 -379.934675)
			(xy 36.228059 -379.879045) (xy 36.196908 -379.819254) (xy 36.173143 -379.756162) (xy 36.157105 -379.690678)
			(xy 36.149026 -379.623744) (xy 36.149022 -379.556325) (xy 36.157093 -379.48939) (xy 36.173122 -379.423904)
			(xy 36.19688 -379.36081) (xy 36.228023 -379.301014) (xy 36.266104 -379.24538) (xy 36.287964 -379.219714)
			(xy 36.293787 -379.212588) (xy 36.300284 -379.195383) (xy 36.300664 -379.186186) (xy 36.300664 -378.693934)
			(xy 36.300223 -378.68475) (xy 36.293729 -378.667566) (xy 36.287964 -378.660406) (xy 36.266076 -378.634761)
			(xy 36.22799 -378.579123) (xy 36.196843 -378.519324) (xy 36.173081 -378.456224) (xy 36.157049 -378.390733)
			(xy 36.148976 -378.323793) (xy 32.870906 -378.323793) (xy 32.862871 -378.390552) (xy 32.846902 -378.455933)
			(xy 32.823232 -378.518936) (xy 32.792203 -378.578659) (xy 32.754258 -378.634246) (xy 32.732472 -378.659898)
			(xy 32.72669 -378.667053) (xy 32.720167 -378.684236) (xy 32.719772 -378.693426) (xy 32.719772 -379.186694)
			(xy 32.720191 -379.19588) (xy 32.726699 -379.213064) (xy 32.732472 -379.220222) (xy 32.754305 -379.245837)
			(xy 32.792251 -379.301429) (xy 32.823282 -379.361158) (xy 32.846952 -379.424167) (xy 32.862921 -379.489554)
			(xy 32.870962 -379.55638) (xy 32.870957 -379.623689) (xy 32.862909 -379.690514) (xy 32.846931 -379.755899)
			(xy 32.823254 -379.818905) (xy 32.792216 -379.87863) (xy 32.754262 -379.934218) (xy 32.732472 -379.95987)
			(xy 32.72666 -379.967004) (xy 32.720155 -379.984203) (xy 32.719772 -379.993398) (xy 32.719772 -380.151386)
			(xy 32.719325 -380.161556) (xy 32.711547 -380.180348) (xy 32.697168 -380.194733) (xy 32.678379 -380.20252)
			(xy 32.66821 -380.202948) (xy 31.95193 -380.202948) (xy 31.941759 -380.202511) (xy 31.922962 -380.194733)
			(xy 31.908576 -380.180351) (xy 31.900792 -380.161557) (xy 31.900368 -380.151386) (xy 31.900368 -379.993398)
			(xy 31.899944 -379.984213) (xy 31.893438 -379.967029) (xy 31.887668 -379.95987) (xy 31.865925 -379.934181)
			(xy 31.827973 -379.878601) (xy 31.796936 -379.818882) (xy 31.773259 -379.755883) (xy 31.757282 -379.690505)
			(xy 31.749234 -379.623686) (xy 31.74923 -379.556384) (xy 31.75727 -379.489564) (xy 31.773239 -379.424184)
			(xy 31.796908 -379.361181) (xy 31.827937 -379.301459) (xy 31.865882 -379.245874) (xy 31.887668 -379.220222)
			(xy 31.893488 -379.213094) (xy 31.899987 -379.19589) (xy 31.900368 -379.186694) (xy 31.900368 -378.693426)
			(xy 31.89993 -378.684242) (xy 31.893434 -378.667058) (xy 31.887668 -378.659898) (xy 31.865854 -378.634267)
			(xy 31.827904 -378.578678) (xy 31.79687 -378.518952) (xy 31.773198 -378.455945) (xy 31.757226 -378.39056)
			(xy 31.749183 -378.323734) (xy 28.471145 -378.323734) (xy 28.471145 -378.323792) (xy 28.463071 -378.390728)
			(xy 28.447038 -378.456216) (xy 28.423275 -378.519312) (xy 28.392126 -378.579108) (xy 28.354039 -378.634741)
			(xy 28.332176 -378.660406) (xy 28.326392 -378.66756) (xy 28.31987 -378.684744) (xy 28.319476 -378.693934)
			(xy 28.319476 -379.186186) (xy 28.319898 -379.195372) (xy 28.326404 -379.212556) (xy 28.332176 -379.219714)
			(xy 28.354036 -379.245382) (xy 28.392125 -379.301016) (xy 28.423276 -379.360812) (xy 28.447 -379.423801)
			(xy 29.549058 -379.423801) (xy 29.549059 -379.356496) (xy 29.557103 -379.289673) (xy 29.573076 -379.224291)
			(xy 29.596749 -379.161286) (xy 29.627783 -379.101562) (xy 29.665732 -379.045976) (xy 29.68752 -379.020324)
			(xy 29.693334 -379.013191) (xy 29.699837 -378.995991) (xy 29.70022 -378.986796) (xy 29.70022 -378.828554)
			(xy 29.700695 -378.818396) (xy 29.708482 -378.799629) (xy 29.722852 -378.785266) (xy 29.741623 -378.77749)
			(xy 29.751782 -378.776992) (xy 30.468062 -378.776992) (xy 30.478212 -378.777564) (xy 30.496971 -378.785317)
			(xy 30.511336 -378.799658) (xy 30.51912 -378.818405) (xy 30.519624 -378.828554) (xy 30.519624 -378.986796)
			(xy 30.520031 -378.995984) (xy 30.526546 -379.013168) (xy 30.532324 -379.020324) (xy 30.55411 -379.045978)
			(xy 30.592059 -379.101564) (xy 30.623093 -379.161287) (xy 30.646766 -379.224291) (xy 30.662739 -379.289673)
			(xy 30.670784 -379.356496) (xy 30.670784 -379.423801) (xy 30.66274 -379.490624) (xy 30.646767 -379.556006)
			(xy 30.623094 -379.61901) (xy 30.592061 -379.678734) (xy 30.554112 -379.73432) (xy 30.532324 -379.759972)
			(xy 30.526517 -379.76711) (xy 30.520008 -379.784306) (xy 30.519624 -379.7935) (xy 30.519624 -380.286768)
			(xy 30.520044 -380.295954) (xy 30.52655 -380.313139) (xy 30.532324 -380.320296) (xy 30.554132 -380.345932)
			(xy 30.592083 -380.40152) (xy 30.623117 -380.461245) (xy 30.646791 -380.524252) (xy 30.662763 -380.589636)
			(xy 30.6708 -380.656404) (xy 33.948845 -380.656404) (xy 33.95692 -380.589467) (xy 33.972953 -380.523978)
			(xy 33.996716 -380.460882) (xy 34.027865 -380.401087) (xy 34.065953 -380.345453) (xy 34.087816 -380.319788)
			(xy 34.093602 -380.312635) (xy 34.100122 -380.29545) (xy 34.100516 -380.28626) (xy 34.100516 -379.794008)
			(xy 34.100098 -379.784822) (xy 34.093589 -379.767638) (xy 34.087816 -379.76048) (xy 34.065999 -379.734776)
			(xy 34.027907 -379.679148) (xy 33.996754 -379.619357) (xy 33.972986 -379.556265) (xy 33.956947 -379.49078)
			(xy 33.948867 -379.423846) (xy 33.948863 -379.356426) (xy 33.956934 -379.289491) (xy 33.972965 -379.224004)
			(xy 33.996724 -379.160909) (xy 34.02787 -379.101114) (xy 34.065954 -379.045481) (xy 34.087816 -379.019816)
			(xy 34.093633 -379.012685) (xy 34.100135 -378.995484) (xy 34.100516 -378.986288) (xy 34.100516 -378.828554)
			(xy 34.100988 -378.818427) (xy 34.108727 -378.79971) (xy 34.123017 -378.785356) (xy 34.1417 -378.777534)
			(xy 34.151824 -378.776992) (xy 34.868104 -378.776992) (xy 34.878257 -378.777418) (xy 34.897008 -378.785214)
			(xy 34.911331 -378.799609) (xy 34.919032 -378.818399) (xy 34.919412 -378.828554) (xy 34.919412 -378.986288)
			(xy 34.919825 -378.995475) (xy 34.926336 -379.012659) (xy 34.932112 -379.019816) (xy 34.954023 -379.045443)
			(xy 34.992109 -379.101083) (xy 35.023257 -379.160885) (xy 35.047018 -379.223986) (xy 35.06305 -379.28948)
			(xy 35.071122 -379.356422) (xy 35.071117 -379.42385) (xy 35.063037 -379.490791) (xy 35.046997 -379.556283)
			(xy 35.023228 -379.619381) (xy 34.992072 -379.679179) (xy 34.953978 -379.734815) (xy 34.932112 -379.76048)
			(xy 34.9263 -379.767615) (xy 34.919794 -379.784813) (xy 34.919412 -379.794008) (xy 34.919412 -380.28626)
			(xy 34.919839 -380.295446) (xy 34.92634 -380.31263) (xy 34.932112 -380.319788) (xy 34.953995 -380.345437)
			(xy 34.992083 -380.401074) (xy 35.023232 -380.460873) (xy 35.046994 -380.523972) (xy 35.063028 -380.589463)
			(xy 35.071102 -380.656403) (xy 35.071102 -380.656464) (xy 38.349165 -380.656464) (xy 38.357207 -380.589643)
			(xy 38.373176 -380.524262) (xy 38.396845 -380.461259) (xy 38.427874 -380.401536) (xy 38.465819 -380.345949)
			(xy 38.487604 -380.320296) (xy 38.493385 -380.31314) (xy 38.499909 -380.295958) (xy 38.500304 -380.286768)
			(xy 38.500304 -379.7935) (xy 38.499893 -379.784313) (xy 38.49338 -379.767129) (xy 38.487604 -379.759972)
			(xy 38.465865 -379.73428) (xy 38.427917 -379.678699) (xy 38.396884 -379.61898) (xy 38.37321 -379.555981)
			(xy 38.357234 -379.490604) (xy 38.349187 -379.423786) (xy 38.349183 -379.356486) (xy 38.357221 -379.289667)
			(xy 38.373188 -379.224288) (xy 38.396854 -379.161286) (xy 38.42788 -379.101563) (xy 38.465821 -379.045977)
			(xy 38.487604 -379.020324) (xy 38.493416 -379.01319) (xy 38.499921 -378.995991) (xy 38.500304 -378.986796)
			(xy 38.500304 -378.828554) (xy 38.500795 -378.818397) (xy 38.508578 -378.799634) (xy 38.522944 -378.785271)
			(xy 38.541709 -378.777493) (xy 38.551866 -378.776992) (xy 39.268146 -378.776992) (xy 39.278301 -378.777495)
			(xy 39.297062 -378.785276) (xy 39.311424 -378.799638) (xy 39.319205 -378.818399) (xy 39.319708 -378.828554)
			(xy 39.319708 -378.986796) (xy 39.320118 -378.995983) (xy 39.326632 -379.013168) (xy 39.332408 -379.020324)
			(xy 39.354244 -379.045937) (xy 39.392195 -379.101528) (xy 39.423229 -379.161256) (xy 39.446902 -379.224266)
			(xy 39.462873 -379.289653) (xy 39.470914 -379.356481) (xy 39.47091 -379.423791) (xy 39.46286 -379.490618)
			(xy 39.44688 -379.556003) (xy 39.4232 -379.61901) (xy 39.392158 -379.678735) (xy 39.3542 -379.734321)
			(xy 39.332408 -379.759972) (xy 39.326599 -379.767109) (xy 39.320092 -379.784306) (xy 39.319708 -379.7935)
			(xy 39.319708 -380.286768) (xy 39.320132 -380.295954) (xy 39.326636 -380.313138) (xy 39.332408 -380.320296)
			(xy 39.354217 -380.345931) (xy 39.392169 -380.401519) (xy 39.423204 -380.461244) (xy 39.446878 -380.524251)
			(xy 39.462851 -380.589636) (xy 39.470887 -380.656404) (xy 42.748933 -380.656404) (xy 42.757007 -380.589467)
			(xy 42.773041 -380.523979) (xy 42.796803 -380.460883) (xy 42.827951 -380.401087) (xy 42.866037 -380.345453)
			(xy 42.8879 -380.319788) (xy 42.893684 -380.312634) (xy 42.900206 -380.29545) (xy 42.9006 -380.28626)
			(xy 42.9006 -379.794008) (xy 42.900186 -379.784821) (xy 42.893675 -379.767637) (xy 42.8879 -379.76048)
			(xy 42.866083 -379.734776) (xy 42.827993 -379.679147) (xy 42.79684 -379.619356) (xy 42.773073 -379.556264)
			(xy 42.757035 -379.49078) (xy 42.748955 -379.423846) (xy 42.748951 -379.356426) (xy 42.757022 -379.289491)
			(xy 42.773052 -379.224005) (xy 42.796811 -379.16091) (xy 42.827956 -379.101115) (xy 42.866039 -379.045481)
			(xy 42.8879 -379.019816) (xy 42.893715 -379.012684) (xy 42.900219 -378.995483) (xy 42.9006 -378.986288)
			(xy 42.9006 -378.828554) (xy 42.901088 -378.818429) (xy 42.908823 -378.799715) (xy 42.923108 -378.785361)
			(xy 42.941786 -378.777537) (xy 42.951908 -378.776992) (xy 43.668188 -378.776992) (xy 43.67834 -378.777431)
			(xy 43.697091 -378.785221) (xy 43.711414 -378.799613) (xy 43.719116 -378.8184) (xy 43.719496 -378.828554)
			(xy 43.719496 -378.986288) (xy 43.719913 -378.995474) (xy 43.726422 -379.012659) (xy 43.732196 -379.019816)
			(xy 43.754107 -379.045442) (xy 43.792195 -379.101082) (xy 43.823344 -379.160884) (xy 43.847105 -379.223986)
			(xy 43.863138 -379.28948) (xy 43.87121 -379.356422) (xy 43.871205 -379.42385) (xy 43.863125 -379.490791)
			(xy 43.847084 -379.556283) (xy 43.823314 -379.619382) (xy 43.792158 -379.67918) (xy 43.754063 -379.734815)
			(xy 43.732196 -379.76048) (xy 43.726382 -379.767613) (xy 43.719878 -379.784813) (xy 43.719496 -379.794008)
			(xy 43.719496 -380.28626) (xy 43.719926 -380.295445) (xy 43.726426 -380.31263) (xy 43.732196 -380.319788)
			(xy 43.75408 -380.345437) (xy 43.792168 -380.401074) (xy 43.823318 -380.460872) (xy 43.847081 -380.523971)
			(xy 43.863116 -380.589462) (xy 43.87119 -380.656402) (xy 43.87119 -380.656463) (xy 73.548987 -380.656463)
			(xy 73.557029 -380.589642) (xy 73.572999 -380.524261) (xy 73.596669 -380.461258) (xy 73.6277 -380.401535)
			(xy 73.665646 -380.345948) (xy 73.687432 -380.320296) (xy 73.693217 -380.313143) (xy 73.699738 -380.295958)
			(xy 73.700132 -380.286768) (xy 73.700132 -379.7935) (xy 73.699715 -379.784314) (xy 73.693205 -379.76713)
			(xy 73.687432 -379.759972) (xy 73.665692 -379.734281) (xy 73.627742 -379.6787) (xy 73.596707 -379.618982)
			(xy 73.573032 -379.555982) (xy 73.557056 -379.490605) (xy 73.549008 -379.423787) (xy 73.549004 -379.356486)
			(xy 73.557043 -379.289666) (xy 73.573011 -379.224287) (xy 73.596678 -379.161285) (xy 73.627705 -379.101562)
			(xy 73.665648 -379.045976) (xy 73.687432 -379.020324) (xy 73.693247 -379.013192) (xy 73.69975 -378.995991)
			(xy 73.700132 -378.986796) (xy 73.700132 -378.828554) (xy 73.700596 -378.818394) (xy 73.708384 -378.799625)
			(xy 73.722759 -378.785262) (xy 73.741534 -378.777488) (xy 73.751694 -378.776992) (xy 74.467974 -378.776992)
			(xy 74.478125 -378.777553) (xy 74.496884 -378.785311) (xy 74.511249 -378.799655) (xy 74.519032 -378.818404)
			(xy 74.519536 -378.828554) (xy 74.519536 -378.986796) (xy 74.519962 -378.995981) (xy 74.526466 -379.013165)
			(xy 74.532236 -379.020324) (xy 74.554072 -379.045937) (xy 74.592021 -379.101528) (xy 74.623053 -379.161257)
			(xy 74.646725 -379.224267) (xy 74.662695 -379.289654) (xy 74.670736 -379.356481) (xy 74.670731 -379.423791)
			(xy 74.662682 -379.490617) (xy 74.646703 -379.556002) (xy 74.623024 -379.619009) (xy 74.591984 -379.678734)
			(xy 74.554028 -379.73432) (xy 74.532236 -379.759972) (xy 74.526419 -379.767102) (xy 74.519918 -379.784304)
			(xy 74.519536 -379.7935) (xy 74.519536 -380.286768) (xy 74.519976 -380.295952) (xy 74.52647 -380.313136)
			(xy 74.532236 -380.320296) (xy 74.554044 -380.345932) (xy 74.591994 -380.40152) (xy 74.623028 -380.461246)
			(xy 74.6467 -380.524252) (xy 74.662673 -380.589637) (xy 74.670709 -380.656404) (xy 77.948754 -380.656404)
			(xy 77.956829 -380.589466) (xy 77.972863 -380.523978) (xy 77.996626 -380.460882) (xy 78.027776 -380.401086)
			(xy 78.065864 -380.345453) (xy 78.087728 -380.319788) (xy 78.093516 -380.312637) (xy 78.100035 -380.295451)
			(xy 78.100428 -380.28626) (xy 78.100428 -379.794008) (xy 78.100008 -379.784822) (xy 78.093501 -379.767638)
			(xy 78.087728 -379.76048) (xy 78.06591 -379.734776) (xy 78.027818 -379.679148) (xy 77.996664 -379.619357)
			(xy 77.972896 -379.556265) (xy 77.956856 -379.490781) (xy 77.948776 -379.423846) (xy 77.948772 -379.356426)
			(xy 77.956843 -379.28949) (xy 77.972874 -379.224004) (xy 77.996634 -379.160909) (xy 78.027781 -379.101114)
			(xy 78.065866 -379.045481) (xy 78.087728 -379.019816) (xy 78.093546 -379.012686) (xy 78.100047 -378.995484)
			(xy 78.100428 -378.986288) (xy 78.100428 -378.828554) (xy 78.100889 -378.818426) (xy 78.108629 -378.799706)
			(xy 78.122923 -378.785352) (xy 78.14161 -378.777532) (xy 78.151736 -378.776992) (xy 78.868016 -378.776992)
			(xy 78.878125 -378.777472) (xy 78.896802 -378.785213) (xy 78.911096 -378.799512) (xy 78.918831 -378.818191)
			(xy 78.919324 -378.8283) (xy 78.919324 -378.986288) (xy 78.919734 -378.995475) (xy 78.926247 -379.01266)
			(xy 78.932024 -379.019816) (xy 78.953934 -379.045443) (xy 78.99202 -379.101083) (xy 79.023167 -379.160885)
			(xy 79.046928 -379.223987) (xy 79.062959 -379.28948) (xy 79.071031 -379.356423) (xy 79.071026 -379.42385)
			(xy 79.062946 -379.490791) (xy 79.046906 -379.556282) (xy 79.023138 -379.619381) (xy 78.991983 -379.679179)
			(xy 78.95389 -379.734814) (xy 78.932024 -379.76048) (xy 78.926214 -379.767616) (xy 78.919706 -379.784813)
			(xy 78.919324 -379.794008) (xy 78.919324 -380.28626) (xy 78.919748 -380.295446) (xy 78.926251 -380.312631)
			(xy 78.932024 -380.319788) (xy 78.953907 -380.345437) (xy 78.991993 -380.401075) (xy 79.023142 -380.460873)
			(xy 79.046904 -380.523972) (xy 79.062937 -380.589463) (xy 79.071011 -380.656403) (xy 79.071011 -380.656464)
			(xy 82.349074 -380.656464) (xy 82.357116 -380.589643) (xy 82.373086 -380.524262) (xy 82.396755 -380.461258)
			(xy 82.427785 -380.401535) (xy 82.46573 -380.345948) (xy 82.487516 -380.320296) (xy 82.493299 -380.313141)
			(xy 82.499821 -380.295958) (xy 82.500216 -380.286768) (xy 82.500216 -379.7935) (xy 82.499803 -379.784313)
			(xy 82.493291 -379.767129) (xy 82.487516 -379.759972) (xy 82.465776 -379.734281) (xy 82.427828 -379.678699)
			(xy 82.396794 -379.618981) (xy 82.373119 -379.555982) (xy 82.357144 -379.490604) (xy 82.349096 -379.423786)
			(xy 82.349092 -379.356486) (xy 82.357131 -379.289667) (xy 82.373098 -379.224288) (xy 82.396764 -379.161285)
			(xy 82.427791 -379.101563) (xy 82.465732 -379.045977) (xy 82.487516 -379.020324) (xy 82.493329 -379.013191)
			(xy 82.499833 -378.995991) (xy 82.500216 -378.986796) (xy 82.500216 -378.828554) (xy 82.500695 -378.818396)
			(xy 82.508481 -378.79963) (xy 82.52285 -378.785267) (xy 82.54162 -378.777491) (xy 82.551778 -378.776992)
			(xy 83.268058 -378.776992) (xy 83.278207 -378.777567) (xy 83.296967 -378.785319) (xy 83.311332 -378.799659)
			(xy 83.319116 -378.818405) (xy 83.31962 -378.828554) (xy 83.31962 -378.986796) (xy 83.320028 -378.995984)
			(xy 83.326543 -379.013168) (xy 83.33232 -379.020324) (xy 83.354156 -379.045937) (xy 83.392107 -379.101528)
			(xy 83.42314 -379.161256) (xy 83.446812 -379.224266) (xy 83.462783 -379.289654) (xy 83.470824 -379.356481)
			(xy 83.470819 -379.423791) (xy 83.46277 -379.490618) (xy 83.446791 -379.556003) (xy 83.423111 -379.61901)
			(xy 83.392069 -379.678734) (xy 83.354112 -379.734321) (xy 83.33232 -379.759972) (xy 83.326513 -379.76711)
			(xy 83.320004 -379.784306) (xy 83.31962 -379.7935) (xy 83.31962 -380.286768) (xy 83.320041 -380.295954)
			(xy 83.326547 -380.313139) (xy 83.33232 -380.320296) (xy 83.354129 -380.345931) (xy 83.392079 -380.401519)
			(xy 83.423114 -380.461245) (xy 83.446788 -380.524252) (xy 83.46276 -380.589636) (xy 83.470797 -380.656404)
			(xy 86.748842 -380.656404) (xy 86.756916 -380.589467) (xy 86.77295 -380.523979) (xy 86.796713 -380.460883)
			(xy 86.827862 -380.401087) (xy 86.865949 -380.345453) (xy 86.887812 -380.319788) (xy 86.893598 -380.312635)
			(xy 86.900118 -380.29545) (xy 86.900512 -380.28626) (xy 86.900512 -379.794008) (xy 86.900095 -379.784822)
			(xy 86.893586 -379.767637) (xy 86.887812 -379.76048) (xy 86.865995 -379.734776) (xy 86.827904 -379.679147)
			(xy 86.79675 -379.619357) (xy 86.772983 -379.556265) (xy 86.756944 -379.49078) (xy 86.748864 -379.423846)
			(xy 86.74886 -379.356426) (xy 86.756931 -379.289491) (xy 86.772962 -379.224004) (xy 86.796721 -379.160909)
			(xy 86.827867 -379.101115) (xy 86.86595 -379.045481) (xy 86.887812 -379.019816) (xy 86.893628 -379.012685)
			(xy 86.900131 -378.995483) (xy 86.900512 -378.986288) (xy 86.900512 -378.828554) (xy 86.900988 -378.818428)
			(xy 86.908726 -378.799711) (xy 86.923015 -378.785357) (xy 86.941696 -378.777535) (xy 86.95182 -378.776992)
			(xy 87.6681 -378.776992) (xy 87.678208 -378.777485) (xy 87.696884 -378.785221) (xy 87.711179 -378.799516)
			(xy 87.718915 -378.818192) (xy 87.719408 -378.8283) (xy 87.719408 -378.986288) (xy 87.719822 -378.995475)
			(xy 87.726333 -379.012659) (xy 87.732108 -379.019816) (xy 87.754019 -379.045442) (xy 87.792106 -379.101083)
			(xy 87.823254 -379.160884) (xy 87.847015 -379.223986) (xy 87.863047 -379.28948) (xy 87.871119 -379.356422)
			(xy 87.871114 -379.42385) (xy 87.863034 -379.490791) (xy 87.846994 -379.556283) (xy 87.823224 -379.619382)
			(xy 87.792068 -379.679179) (xy 87.753975 -379.734815) (xy 87.732108 -379.76048) (xy 87.726296 -379.767614)
			(xy 87.71979 -379.784813) (xy 87.719408 -379.794008) (xy 87.719408 -380.28626) (xy 87.719836 -380.295445)
			(xy 87.726337 -380.31263) (xy 87.732108 -380.319788) (xy 87.753991 -380.345437) (xy 87.792079 -380.401074)
			(xy 87.823228 -380.460873) (xy 87.846991 -380.523972) (xy 87.863025 -380.589463) (xy 87.871099 -380.656402)
			(xy 87.871097 -380.723828) (xy 87.863019 -380.790767) (xy 87.846982 -380.856257) (xy 87.838954 -380.877572)
			(xy 105.0036 -380.877572) (xy 105.0036 -380.013972) (xy 105.00409 -379.983988) (xy 105.011918 -379.924532)
			(xy 105.027439 -379.866607) (xy 105.050388 -379.811203) (xy 105.080372 -379.759269) (xy 105.116878 -379.711693)
			(xy 105.159283 -379.669288) (xy 105.206859 -379.632782) (xy 105.258793 -379.602798) (xy 105.314197 -379.579849)
			(xy 105.372122 -379.564328) (xy 105.431578 -379.5565) (xy 105.491546 -379.5565) (xy 105.551002 -379.564328)
			(xy 105.608927 -379.579849) (xy 105.664331 -379.602798) (xy 105.716265 -379.632782) (xy 105.763841 -379.669288)
			(xy 105.806246 -379.711693) (xy 105.842752 -379.759269) (xy 105.872736 -379.811203) (xy 105.895685 -379.866607)
			(xy 105.911206 -379.924532) (xy 105.919034 -379.983988) (xy 105.919524 -380.013972) (xy 105.919524 -380.656403)
			(xy 117.548873 -380.656403) (xy 117.556947 -380.589466) (xy 117.572982 -380.523977) (xy 117.596746 -380.460881)
			(xy 117.627898 -380.401085) (xy 117.665987 -380.345452) (xy 117.687852 -380.319788) (xy 117.693643 -380.312639)
			(xy 117.700159 -380.295451) (xy 117.700552 -380.28626) (xy 117.700552 -379.794008) (xy 117.700126 -379.784823)
			(xy 117.693622 -379.767639) (xy 117.687852 -379.76048) (xy 117.666033 -379.734777) (xy 117.62794 -379.679149)
			(xy 117.596784 -379.619358) (xy 117.573015 -379.556266) (xy 117.556975 -379.490781) (xy 117.548894 -379.423846)
			(xy 117.54889 -379.356426) (xy 117.556962 -379.28949) (xy 117.572994 -379.224003) (xy 117.596755 -379.160908)
			(xy 117.627903 -379.101113) (xy 117.665989 -379.04548) (xy 117.687852 -379.019816) (xy 117.693673 -379.012688)
			(xy 117.700172 -378.995484) (xy 117.700552 -378.986288) (xy 117.700552 -378.828554) (xy 117.700989 -378.818423)
			(xy 117.708734 -378.799698) (xy 117.723036 -378.785343) (xy 117.741731 -378.777528) (xy 117.75186 -378.776992)
			(xy 118.46814 -378.776992) (xy 118.478296 -378.777389) (xy 118.497047 -378.785196) (xy 118.511369 -378.7996)
			(xy 118.519069 -378.818396) (xy 118.519448 -378.828554) (xy 118.519448 -378.986288) (xy 118.519875 -378.995473)
			(xy 118.526378 -379.012657) (xy 118.532148 -379.019816) (xy 118.554061 -379.045441) (xy 118.592152 -379.10108)
			(xy 118.623303 -379.160882) (xy 118.647067 -379.223984) (xy 118.663101 -379.289478) (xy 118.671174 -379.356422)
			(xy 118.671169 -379.42385) (xy 118.663088 -379.490793) (xy 118.647046 -379.556285) (xy 118.623274 -379.619384)
			(xy 118.592115 -379.679181) (xy 118.554017 -379.734816) (xy 118.532148 -379.76048) (xy 118.526329 -379.767609)
			(xy 118.519829 -379.784812) (xy 118.519448 -379.794008) (xy 118.519448 -380.28626) (xy 118.519889 -380.295444)
			(xy 118.526382 -380.312628) (xy 118.532148 -380.319788) (xy 118.554033 -380.345436) (xy 118.592125 -380.401072)
			(xy 118.623278 -380.46087) (xy 118.647043 -380.523969) (xy 118.663079 -380.589461) (xy 118.671154 -380.656402)
			(xy 118.671154 -380.656463) (xy 121.949193 -380.656463) (xy 121.957235 -380.589642) (xy 121.973206 -380.524261)
			(xy 121.996876 -380.461257) (xy 122.027907 -380.401534) (xy 122.065854 -380.345948) (xy 122.08764 -380.320296)
			(xy 122.093426 -380.313143) (xy 122.099946 -380.295958) (xy 122.10034 -380.286768) (xy 122.10034 -379.7935)
			(xy 122.099921 -379.784314) (xy 122.093413 -379.76713) (xy 122.08764 -379.759972) (xy 122.0659 -379.734281)
			(xy 122.027949 -379.6787) (xy 121.996914 -379.618982) (xy 121.973238 -379.555982) (xy 121.957262 -379.490605)
			(xy 121.949214 -379.423787) (xy 121.94921 -379.356485) (xy 121.957249 -379.289666) (xy 121.973217 -379.224287)
			(xy 121.996884 -379.161284) (xy 122.027912 -379.101562) (xy 122.065855 -379.045976) (xy 122.08764 -379.020324)
			(xy 122.093456 -379.013193) (xy 122.099958 -378.995991) (xy 122.10034 -378.986796) (xy 122.10034 -378.828554)
			(xy 122.100796 -378.818393) (xy 122.108586 -378.799623) (xy 122.122963 -378.785259) (xy 122.141741 -378.777486)
			(xy 122.151902 -378.776992) (xy 122.868182 -378.776992) (xy 122.878333 -378.777547) (xy 122.897093 -378.785307)
			(xy 122.911457 -378.799653) (xy 122.919241 -378.818404) (xy 122.919744 -378.828554) (xy 122.919744 -378.986796)
			(xy 122.920169 -378.995981) (xy 122.926674 -379.013165) (xy 122.932444 -379.020324) (xy 122.95428 -379.045937)
			(xy 122.992228 -379.101529) (xy 123.02326 -379.161257) (xy 123.046931 -379.224267) (xy 123.062901 -379.289654)
			(xy 123.070942 -379.356482) (xy 123.070937 -379.423791) (xy 123.062888 -379.490617) (xy 123.04691 -379.556002)
			(xy 123.023231 -379.619009) (xy 122.992191 -379.678733) (xy 122.954235 -379.73432) (xy 122.932444 -379.759972)
			(xy 122.926627 -379.767103) (xy 122.920126 -379.784305) (xy 122.919744 -379.7935) (xy 122.919744 -380.286768)
			(xy 122.920182 -380.295952) (xy 122.926678 -380.313136) (xy 122.932444 -380.320296) (xy 122.954252 -380.345932)
			(xy 122.992201 -380.40152) (xy 123.023235 -380.461246) (xy 123.046907 -380.524252) (xy 123.062879 -380.589637)
			(xy 123.070915 -380.656404) (xy 126.34896 -380.656404) (xy 126.357035 -380.589466) (xy 126.373069 -380.523978)
			(xy 126.396833 -380.460881) (xy 126.427983 -380.401086) (xy 126.466072 -380.345453) (xy 126.487936 -380.319788)
			(xy 126.493725 -380.312637) (xy 126.500243 -380.295451) (xy 126.500636 -380.28626) (xy 126.500636 -379.794008)
			(xy 126.500214 -379.784822) (xy 126.493708 -379.767638) (xy 126.487936 -379.76048) (xy 126.466118 -379.734776)
			(xy 126.428025 -379.679148) (xy 126.396871 -379.619358) (xy 126.373102 -379.556266) (xy 126.357062 -379.490781)
			(xy 126.348982 -379.423846) (xy 126.348978 -379.356426) (xy 126.357049 -379.28949) (xy 126.373081 -379.224003)
			(xy 126.396841 -379.160908) (xy 126.427988 -379.101114) (xy 126.466074 -379.045481) (xy 126.487936 -379.019816)
			(xy 126.493755 -379.012687) (xy 126.500256 -378.995484) (xy 126.500636 -378.986288) (xy 126.500636 -378.828554)
			(xy 126.501089 -378.818425) (xy 126.508831 -378.799703) (xy 126.523127 -378.785349) (xy 126.541817 -378.777531)
			(xy 126.551944 -378.776992) (xy 127.268224 -378.776992) (xy 127.278379 -378.777402) (xy 127.29713 -378.785204)
			(xy 127.311452 -378.799604) (xy 127.319153 -378.818397) (xy 127.319532 -378.828554) (xy 127.319532 -378.986288)
			(xy 127.319963 -378.995473) (xy 127.326464 -379.012656) (xy 127.332232 -379.019816) (xy 127.354142 -379.045443)
			(xy 127.392227 -379.101084) (xy 127.423374 -379.160885) (xy 127.447134 -379.223987) (xy 127.463165 -379.289481)
			(xy 127.471237 -379.356423) (xy 127.471232 -379.423849) (xy 127.463152 -379.49079) (xy 127.447113 -379.556282)
			(xy 127.423345 -379.61938) (xy 127.39219 -379.679178) (xy 127.354098 -379.734814) (xy 127.332232 -379.76048)
			(xy 127.326411 -379.767607) (xy 127.319913 -379.784812) (xy 127.319532 -379.794008) (xy 127.319532 -380.28626)
			(xy 127.319977 -380.295443) (xy 127.326468 -380.312627) (xy 127.332232 -380.319788) (xy 127.354114 -380.345438)
			(xy 127.392201 -380.401075) (xy 127.423349 -380.460874) (xy 127.44711 -380.523973) (xy 127.463143 -380.589463)
			(xy 127.471217 -380.656403) (xy 127.471217 -380.656463) (xy 130.74928 -380.656463) (xy 130.757322 -380.589642)
			(xy 130.773292 -380.524262) (xy 130.796962 -380.461258) (xy 130.827992 -380.401535) (xy 130.865938 -380.345948)
			(xy 130.887724 -380.320296) (xy 130.893508 -380.313142) (xy 130.900029 -380.295958) (xy 130.900424 -380.286768)
			(xy 130.900424 -379.7935) (xy 130.900009 -379.784313) (xy 130.893498 -379.767129) (xy 130.887724 -379.759972)
			(xy 130.865984 -379.734281) (xy 130.828035 -379.678699) (xy 130.797 -379.618981) (xy 130.773326 -379.555982)
			(xy 130.75735 -379.490605) (xy 130.749302 -379.423787) (xy 130.749298 -379.356486) (xy 130.757337 -379.289667)
			(xy 130.773304 -379.224287) (xy 130.796971 -379.161285) (xy 130.827998 -379.101563) (xy 130.86594 -379.045977)
			(xy 130.887724 -379.020324) (xy 130.893538 -379.013191) (xy 130.900042 -378.995991) (xy 130.900424 -378.986796)
			(xy 130.900424 -378.828554) (xy 130.900895 -378.818395) (xy 130.908682 -378.799628) (xy 130.923054 -378.785264)
			(xy 130.941827 -378.777489) (xy 130.951986 -378.776992) (xy 131.668266 -378.776992) (xy 131.678416 -378.77756)
			(xy 131.697175 -378.785315) (xy 131.71154 -378.799657) (xy 131.719324 -378.818405) (xy 131.719828 -378.828554)
			(xy 131.719828 -378.986796) (xy 131.720234 -378.995984) (xy 131.72675 -379.013168) (xy 131.732528 -379.020324)
			(xy 131.754364 -379.045937) (xy 131.792314 -379.101528) (xy 131.823347 -379.161257) (xy 131.847018 -379.224267)
			(xy 131.862989 -379.289654) (xy 131.87103 -379.356481) (xy 131.871025 -379.423791) (xy 131.862976 -379.490617)
			(xy 131.846997 -379.556003) (xy 131.823317 -379.619009) (xy 131.792277 -379.678734) (xy 131.75432 -379.73432)
			(xy 131.732528 -379.759972) (xy 131.72671 -379.767101) (xy 131.72021 -379.784304) (xy 131.719828 -379.7935)
			(xy 131.719828 -380.286768) (xy 131.720247 -380.295954) (xy 131.726754 -380.313139) (xy 131.732528 -380.320296)
			(xy 131.754336 -380.345932) (xy 131.792287 -380.40152) (xy 131.823321 -380.461245) (xy 131.846994 -380.524252)
			(xy 131.862967 -380.589636) (xy 131.871003 -380.656404) (xy 161.548806 -380.656404) (xy 161.55688 -380.589468)
			(xy 161.572912 -380.523981) (xy 161.596672 -380.460885) (xy 161.627819 -380.401089) (xy 161.665902 -380.345454)
			(xy 161.687764 -380.319788) (xy 161.693556 -380.31264) (xy 161.700072 -380.295451) (xy 161.700464 -380.28626)
			(xy 161.700464 -379.794008) (xy 161.700036 -379.784823) (xy 161.693533 -379.767639) (xy 161.687764 -379.76048)
			(xy 161.665948 -379.734775) (xy 161.627861 -379.679146) (xy 161.59671 -379.619354) (xy 161.572945 -379.556263)
			(xy 161.556907 -379.490779) (xy 161.548828 -379.423846) (xy 161.548823 -379.356426) (xy 161.556894 -379.289492)
			(xy 161.572923 -379.224006) (xy 161.59668 -379.160911) (xy 161.627824 -379.101116) (xy 161.665904 -379.045482)
			(xy 161.687764 -379.019816) (xy 161.693587 -379.01269) (xy 161.700084 -378.995484) (xy 161.700464 -378.986288)
			(xy 161.700464 -378.828554) (xy 161.70089 -378.818421) (xy 161.708637 -378.799695) (xy 161.722942 -378.785339)
			(xy 161.741641 -378.777526) (xy 161.751772 -378.776992) (xy 162.468052 -378.776992) (xy 162.47817 -378.777455)
			(xy 162.496871 -378.785186) (xy 162.511187 -378.799488) (xy 162.518935 -378.818182) (xy 162.51936 -378.8283)
			(xy 162.51936 -378.986288) (xy 162.519785 -378.995473) (xy 162.526289 -379.012658) (xy 162.53206 -379.019816)
			(xy 162.553973 -379.045442) (xy 162.592062 -379.101081) (xy 162.623213 -379.160882) (xy 162.646977 -379.223984)
			(xy 162.66301 -379.289479) (xy 162.671083 -379.356422) (xy 162.671078 -379.42385) (xy 162.662997 -379.490792)
			(xy 162.646955 -379.556285) (xy 162.623184 -379.619384) (xy 162.592025 -379.679181) (xy 162.553928 -379.734815)
			(xy 162.53206 -379.76048) (xy 162.526242 -379.76761) (xy 162.519741 -379.784812) (xy 162.51936 -379.794008)
			(xy 162.51936 -380.28626) (xy 162.519799 -380.295444) (xy 162.526294 -380.312628) (xy 162.53206 -380.319788)
			(xy 162.553945 -380.345436) (xy 162.592036 -380.401072) (xy 162.623188 -380.460871) (xy 162.646953 -380.52397)
			(xy 162.662988 -380.589461) (xy 162.671063 -380.656402) (xy 162.671063 -380.656463) (xy 165.949102 -380.656463)
			(xy 165.957144 -380.589642) (xy 165.973115 -380.524261) (xy 165.996786 -380.461257) (xy 166.027818 -380.401534)
			(xy 166.065765 -380.345948) (xy 166.087552 -380.320296) (xy 166.093339 -380.313144) (xy 166.099858 -380.295959)
			(xy 166.100252 -380.286768) (xy 166.100252 -379.7935) (xy 166.09983 -379.784314) (xy 166.093323 -379.76713)
			(xy 166.087552 -379.759972) (xy 166.065811 -379.734281) (xy 166.02786 -379.678701) (xy 165.996824 -379.618982)
			(xy 165.973148 -379.555983) (xy 165.957171 -379.490605) (xy 165.949123 -379.423787) (xy 165.949119 -379.356485)
			(xy 165.957158 -379.289666) (xy 165.973127 -379.224286) (xy 165.996795 -379.161284) (xy 166.027823 -379.101562)
			(xy 166.065767 -379.045976) (xy 166.087552 -379.020324) (xy 166.09337 -379.013194) (xy 166.09987 -378.995992)
			(xy 166.100252 -378.986796) (xy 166.100252 -378.828554) (xy 166.100696 -378.818392) (xy 166.108488 -378.799619)
			(xy 166.122869 -378.785255) (xy 166.141651 -378.777484) (xy 166.151814 -378.776992) (xy 166.868094 -378.776992)
			(xy 166.878246 -378.777537) (xy 166.897006 -378.785301) (xy 166.91137 -378.79965) (xy 166.919153 -378.818403)
			(xy 166.919656 -378.828554) (xy 166.919656 -378.986796) (xy 166.920078 -378.995982) (xy 166.926584 -379.013166)
			(xy 166.932356 -379.020324) (xy 166.954191 -379.045937) (xy 166.992139 -379.101529) (xy 167.02317 -379.161258)
			(xy 167.046841 -379.224268) (xy 167.06281 -379.289655) (xy 167.070851 -379.356482) (xy 167.070847 -379.423791)
			(xy 167.062798 -379.490617) (xy 167.046819 -379.556001) (xy 167.023141 -379.619008) (xy 166.992102 -379.678733)
			(xy 166.954147 -379.73432) (xy 166.932356 -379.759972) (xy 166.926541 -379.767104) (xy 166.920038 -379.784305)
			(xy 166.919656 -379.7935) (xy 166.919656 -380.286768) (xy 166.920091 -380.295952) (xy 166.926588 -380.313137)
			(xy 166.932356 -380.320296) (xy 166.954164 -380.345932) (xy 166.992112 -380.40152) (xy 167.023145 -380.461246)
			(xy 167.046817 -380.524253) (xy 167.062789 -380.589637) (xy 167.070824 -380.656403) (xy 170.34887 -380.656403)
			(xy 170.356944 -380.589466) (xy 170.372979 -380.523977) (xy 170.396743 -380.460881) (xy 170.427894 -380.401086)
			(xy 170.465984 -380.345452) (xy 170.487848 -380.319788) (xy 170.493638 -380.312638) (xy 170.500155 -380.295451)
			(xy 170.500548 -380.28626) (xy 170.500548 -379.794008) (xy 170.500123 -379.784823) (xy 170.493619 -379.767639)
			(xy 170.487848 -379.76048) (xy 170.46603 -379.734777) (xy 170.427936 -379.679149) (xy 170.396781 -379.619358)
			(xy 170.373012 -379.556266) (xy 170.356971 -379.490781) (xy 170.348891 -379.423846) (xy 170.348887 -379.356426)
			(xy 170.356959 -379.28949) (xy 170.37299 -379.224003) (xy 170.396751 -379.160908) (xy 170.427899 -379.101113)
			(xy 170.465985 -379.04548) (xy 170.487848 -379.019816) (xy 170.493669 -379.012688) (xy 170.500168 -378.995484)
			(xy 170.500548 -378.986288) (xy 170.500548 -378.828554) (xy 170.500989 -378.818423) (xy 170.508734 -378.7997)
			(xy 170.523034 -378.785345) (xy 170.541727 -378.777529) (xy 170.551856 -378.776992) (xy 171.268136 -378.776992)
			(xy 171.278291 -378.777392) (xy 171.297043 -378.785198) (xy 171.311365 -378.799601) (xy 171.319065 -378.818396)
			(xy 171.319444 -378.828554) (xy 171.319444 -378.986288) (xy 171.319872 -378.995473) (xy 171.326375 -379.012657)
			(xy 171.332144 -379.019816) (xy 171.354057 -379.045441) (xy 171.392148 -379.10108) (xy 171.4233 -379.160881)
			(xy 171.447064 -379.223984) (xy 171.463098 -379.289478) (xy 171.47117 -379.356422) (xy 171.471166 -379.42385)
			(xy 171.463085 -379.490793) (xy 171.447042 -379.556285) (xy 171.42327 -379.619384) (xy 171.392111 -379.679182)
			(xy 171.354013 -379.734816) (xy 171.332144 -379.76048) (xy 171.326324 -379.767608) (xy 171.319825 -379.784812)
			(xy 171.319444 -379.794008) (xy 171.319444 -380.28626) (xy 171.319886 -380.295444) (xy 171.326379 -380.312628)
			(xy 171.332144 -380.319788) (xy 171.35403 -380.345436) (xy 171.392121 -380.401072) (xy 171.423274 -380.46087)
			(xy 171.44704 -380.523969) (xy 171.463076 -380.589461) (xy 171.471151 -380.656402) (xy 171.471151 -380.656463)
			(xy 174.74919 -380.656463) (xy 174.757232 -380.589642) (xy 174.773202 -380.524261) (xy 174.796873 -380.461258)
			(xy 174.827904 -380.401535) (xy 174.86585 -380.345948) (xy 174.887636 -380.320296) (xy 174.893421 -380.313143)
			(xy 174.899942 -380.295958) (xy 174.900336 -380.286768) (xy 174.900336 -379.7935) (xy 174.899918 -379.784314)
			(xy 174.893409 -379.76713) (xy 174.887636 -379.759972) (xy 174.865896 -379.734281) (xy 174.827946 -379.6787)
			(xy 174.796911 -379.618982) (xy 174.773235 -379.555982) (xy 174.757259 -379.490605) (xy 174.749211 -379.423787)
			(xy 174.749207 -379.356486) (xy 174.757246 -379.289666) (xy 174.773214 -379.224287) (xy 174.796881 -379.161284)
			(xy 174.827909 -379.101562) (xy 174.865851 -379.045976) (xy 174.887636 -379.020324) (xy 174.893452 -379.013193)
			(xy 174.899954 -378.995991) (xy 174.900336 -378.986796) (xy 174.900336 -378.828554) (xy 174.900796 -378.818394)
			(xy 174.908585 -378.799624) (xy 174.922961 -378.78526) (xy 174.941737 -378.777487) (xy 174.951898 -378.776992)
			(xy 175.668178 -378.776992) (xy 175.678329 -378.77755) (xy 175.697089 -378.785309) (xy 175.711453 -378.799654)
			(xy 175.719237 -378.818404) (xy 175.71974 -378.828554) (xy 175.71974 -378.986796) (xy 175.720166 -378.995981)
			(xy 175.72667 -379.013165) (xy 175.73244 -379.020324) (xy 175.754276 -379.045937) (xy 175.792225 -379.101529)
			(xy 175.823257 -379.161257) (xy 175.846928 -379.224267) (xy 175.862898 -379.289654) (xy 175.870939 -379.356481)
			(xy 175.870934 -379.423791) (xy 175.862885 -379.490617) (xy 175.846907 -379.556002) (xy 175.823227 -379.619009)
			(xy 175.792187 -379.678734) (xy 175.754231 -379.73432) (xy 175.73244 -379.759972) (xy 175.726623 -379.767102)
			(xy 175.720122 -379.784305) (xy 175.71974 -379.7935) (xy 175.71974 -380.286768) (xy 175.720179 -380.295952)
			(xy 175.726674 -380.313136) (xy 175.73244 -380.320296) (xy 175.754248 -380.345932) (xy 175.792198 -380.40152)
			(xy 175.823231 -380.461246) (xy 175.846904 -380.524252) (xy 175.862876 -380.589637) (xy 175.870919 -380.656462)
			(xy 175.870917 -380.723769) (xy 175.862871 -380.790593) (xy 175.846895 -380.855977) (xy 175.823219 -380.918982)
			(xy 175.792182 -380.978706) (xy 175.75423 -381.034292) (xy 175.73244 -381.059944) (xy 175.726635 -381.067083)
			(xy 175.720127 -381.084278) (xy 175.71974 -381.093472) (xy 175.71974 -381.251206) (xy 175.71934 -381.261381)
			(xy 175.711549 -381.28018) (xy 175.697156 -381.294565) (xy 175.678353 -381.302346) (xy 175.668178 -381.302768)
			(xy 174.951898 -381.302768) (xy 174.941741 -381.302268) (xy 174.922973 -381.294494) (xy 174.908608 -381.280131)
			(xy 174.900832 -381.261363) (xy 174.900336 -381.251206) (xy 174.900336 -381.093472) (xy 174.899931 -381.084284)
			(xy 174.893413 -381.067101) (xy 174.887636 -381.059944) (xy 174.865868 -381.034275) (xy 174.827919 -380.978691)
			(xy 174.796885 -380.91897) (xy 174.773211 -380.855968) (xy 174.757237 -380.790587) (xy 174.749191 -380.723767)
			(xy 174.74919 -380.656463) (xy 171.471151 -380.656463) (xy 171.471149 -380.723828) (xy 171.46307 -380.790769)
			(xy 171.447031 -380.85626) (xy 171.423262 -380.919358) (xy 171.392106 -380.979154) (xy 171.354011 -381.034788)
			(xy 171.332144 -381.060452) (xy 171.326336 -381.067589) (xy 171.31983 -381.084786) (xy 171.319444 -381.09398)
			(xy 171.319444 -381.251206) (xy 171.318978 -381.261335) (xy 171.311245 -381.280059) (xy 171.296952 -381.294416)
			(xy 171.278263 -381.302232) (xy 171.268136 -381.302768) (xy 170.551856 -381.302768) (xy 170.541695 -381.302414)
			(xy 170.522936 -381.294598) (xy 170.508613 -381.28018) (xy 170.50092 -381.26137) (xy 170.500548 -381.251206)
			(xy 170.500548 -381.09398) (xy 170.500137 -381.084793) (xy 170.493623 -381.067609) (xy 170.487848 -381.060452)
			(xy 170.466002 -381.034771) (xy 170.42791 -380.97914) (xy 170.396755 -380.919347) (xy 170.372988 -380.856252)
			(xy 170.35695 -380.790764) (xy 170.348871 -380.723827) (xy 170.34887 -380.656403) (xy 167.070824 -380.656403)
			(xy 167.070831 -380.656462) (xy 167.070829 -380.723768) (xy 167.062783 -380.790592) (xy 167.046808 -380.855976)
			(xy 167.023133 -380.918981) (xy 166.992097 -380.978705) (xy 166.954145 -381.034292) (xy 166.932356 -381.059944)
			(xy 166.926553 -381.067084) (xy 166.920043 -381.084279) (xy 166.919656 -381.093472) (xy 166.919656 -381.251206)
			(xy 166.919171 -381.261365) (xy 166.911394 -381.280135) (xy 166.897025 -381.2945) (xy 166.878253 -381.302274)
			(xy 166.868094 -381.302768) (xy 166.151814 -381.302768) (xy 166.141644 -381.302325) (xy 166.122851 -381.294546)
			(xy 166.108466 -381.280166) (xy 166.100679 -381.261376) (xy 166.100252 -381.251206) (xy 166.100252 -381.093472)
			(xy 166.099844 -381.084285) (xy 166.093327 -381.067101) (xy 166.087552 -381.059944) (xy 166.065784 -381.034276)
			(xy 166.027833 -380.978692) (xy 165.996799 -380.918971) (xy 165.973124 -380.855968) (xy 165.957149 -380.790588)
			(xy 165.949103 -380.723767) (xy 165.949102 -380.656463) (xy 162.671063 -380.656463) (xy 162.671061 -380.723828)
			(xy 162.662983 -380.790768) (xy 162.646944 -380.856259) (xy 162.623176 -380.919357) (xy 162.59202 -380.979153)
			(xy 162.553927 -381.034787) (xy 162.53206 -381.060452) (xy 162.526254 -381.06759) (xy 162.519746 -381.084786)
			(xy 162.51936 -381.09398) (xy 162.51936 -381.251206) (xy 162.518878 -381.261333) (xy 162.511148 -381.280054)
			(xy 162.496861 -381.29441) (xy 162.478177 -381.302229) (xy 162.468052 -381.302768) (xy 161.751772 -381.302768)
			(xy 161.741644 -381.302406) (xy 161.722933 -381.294643) (xy 161.708619 -381.28031) (xy 161.70088 -381.261589)
			(xy 161.700464 -381.25146) (xy 161.700464 -381.09398) (xy 161.700049 -381.084794) (xy 161.693537 -381.06761)
			(xy 161.687764 -381.060452) (xy 161.665921 -381.03477) (xy 161.627834 -380.979137) (xy 161.596684 -380.919343)
			(xy 161.572921 -380.856248) (xy 161.556885 -380.790762) (xy 161.548808 -380.723826) (xy 161.548806 -380.656404)
			(xy 131.871003 -380.656404) (xy 131.87101 -380.656461) (xy 131.871008 -380.723769) (xy 131.862961 -380.790593)
			(xy 131.846985 -380.855977) (xy 131.823309 -380.918982) (xy 131.792271 -380.978706) (xy 131.754318 -381.034292)
			(xy 131.732528 -381.059944) (xy 131.726722 -381.067082) (xy 131.720215 -381.084278) (xy 131.719828 -381.093472)
			(xy 131.719828 -381.251206) (xy 131.71944 -381.261382) (xy 131.711647 -381.280184) (xy 131.69725 -381.294569)
			(xy 131.678443 -381.302348) (xy 131.668266 -381.302768) (xy 130.951986 -381.302768) (xy 130.941828 -381.302278)
			(xy 130.92306 -381.2945) (xy 130.908695 -381.280133) (xy 130.90092 -381.261364) (xy 130.900424 -381.251206)
			(xy 130.900424 -381.093472) (xy 130.900022 -381.084284) (xy 130.893502 -381.0671) (xy 130.887724 -381.059944)
			(xy 130.865956 -381.034276) (xy 130.828008 -380.978691) (xy 130.796975 -380.91897) (xy 130.773301 -380.855967)
			(xy 130.757327 -380.790587) (xy 130.749282 -380.723767) (xy 130.74928 -380.656463) (xy 127.471217 -380.656463)
			(xy 127.471215 -380.723827) (xy 127.463138 -380.790766) (xy 127.447101 -380.856256) (xy 127.423336 -380.919354)
			(xy 127.392185 -380.979151) (xy 127.354096 -381.034786) (xy 127.332232 -381.060452) (xy 127.326423 -381.067588)
			(xy 127.319918 -381.084786) (xy 127.319532 -381.09398) (xy 127.319532 -381.251206) (xy 127.319077 -381.261337)
			(xy 127.311342 -381.280063) (xy 127.297046 -381.29442) (xy 127.278352 -381.302234) (xy 127.268224 -381.302768)
			(xy 126.551944 -381.302768) (xy 126.541789 -381.302342) (xy 126.523031 -381.294555) (xy 126.508705 -381.280159)
			(xy 126.50101 -381.261363) (xy 126.500636 -381.251206) (xy 126.500636 -381.09398) (xy 126.500227 -381.084793)
			(xy 126.493712 -381.067609) (xy 126.487936 -381.060452) (xy 126.46609 -381.034771) (xy 126.427999 -380.97914)
			(xy 126.396845 -380.919346) (xy 126.373078 -380.856251) (xy 126.35704 -380.790764) (xy 126.348962 -380.723826)
			(xy 126.34896 -380.656404) (xy 123.070915 -380.656404) (xy 123.070922 -380.656462) (xy 123.07092 -380.723769)
			(xy 123.062874 -380.790593) (xy 123.046898 -380.855976) (xy 123.023223 -380.918982) (xy 122.992186 -380.978706)
			(xy 122.954234 -381.034292) (xy 122.932444 -381.059944) (xy 122.926639 -381.067083) (xy 122.920131 -381.084279)
			(xy 122.919744 -381.093472) (xy 122.919744 -381.251206) (xy 122.919341 -381.26138) (xy 122.91155 -381.280178)
			(xy 122.897158 -381.294564) (xy 122.878356 -381.302345) (xy 122.868182 -381.302768) (xy 122.151902 -381.302768)
			(xy 122.141745 -381.302265) (xy 122.122977 -381.294492) (xy 122.108612 -381.28013) (xy 122.100836 -381.261363)
			(xy 122.10034 -381.251206) (xy 122.10034 -381.093472) (xy 122.099934 -381.084285) (xy 122.093417 -381.067101)
			(xy 122.08764 -381.059944) (xy 122.065872 -381.034276) (xy 122.027923 -380.978691) (xy 121.996888 -380.91897)
			(xy 121.973215 -380.855968) (xy 121.95724 -380.790588) (xy 121.949194 -380.723767) (xy 121.949193 -380.656463)
			(xy 118.671154 -380.656463) (xy 118.671152 -380.723828) (xy 118.663073 -380.790769) (xy 118.647034 -380.85626)
			(xy 118.623265 -380.919357) (xy 118.592109 -380.979154) (xy 118.554015 -381.034788) (xy 118.532148 -381.060452)
			(xy 118.52634 -381.067589) (xy 118.519834 -381.084786) (xy 118.519448 -381.09398) (xy 118.519448 -381.251206)
			(xy 118.518978 -381.261335) (xy 118.511246 -381.280058) (xy 118.496954 -381.294415) (xy 118.478266 -381.302231)
			(xy 118.46814 -381.302768) (xy 117.75186 -381.302768) (xy 117.741699 -381.30241) (xy 117.72294 -381.294596)
			(xy 117.708617 -381.280179) (xy 117.700924 -381.261369) (xy 117.700552 -381.251206) (xy 117.700552 -381.09398)
			(xy 117.70014 -381.084793) (xy 117.693626 -381.06761) (xy 117.687852 -381.060452) (xy 117.666006 -381.034771)
			(xy 117.627913 -380.97914) (xy 117.596759 -380.919347) (xy 117.572991 -380.856252) (xy 117.556953 -380.790764)
			(xy 117.548874 -380.723827) (xy 117.548873 -380.656403) (xy 105.919524 -380.656403) (xy 105.919524 -380.877572)
			(xy 105.919034 -380.907556) (xy 105.911206 -380.967012) (xy 105.895685 -381.024937) (xy 105.872736 -381.080341)
			(xy 105.842752 -381.132275) (xy 105.806246 -381.179851) (xy 105.763841 -381.222256) (xy 105.716265 -381.258762)
			(xy 105.664331 -381.288746) (xy 105.608927 -381.311695) (xy 105.551002 -381.327216) (xy 105.491546 -381.335044)
			(xy 105.431578 -381.335044) (xy 105.372122 -381.327216) (xy 105.314197 -381.311695) (xy 105.258793 -381.288746)
			(xy 105.206859 -381.258762) (xy 105.159283 -381.222256) (xy 105.116878 -381.179851) (xy 105.080372 -381.132275)
			(xy 105.050388 -381.080341) (xy 105.027439 -381.024937) (xy 105.011918 -380.967012) (xy 105.00409 -380.907556)
			(xy 105.0036 -380.877572) (xy 87.838954 -380.877572) (xy 87.823216 -380.919355) (xy 87.792063 -380.979152)
			(xy 87.753973 -381.034787) (xy 87.732108 -381.060452) (xy 87.726308 -381.067595) (xy 87.719795 -381.084787)
			(xy 87.719408 -381.09398) (xy 87.719408 -381.251206) (xy 87.71888 -381.261327) (xy 87.711159 -381.280039)
			(xy 87.696886 -381.294394) (xy 87.678218 -381.302221) (xy 87.6681 -381.302768) (xy 86.95182 -381.302768)
			(xy 86.941695 -381.302367) (xy 86.922985 -381.294619) (xy 86.908669 -381.280298) (xy 86.900929 -381.261585)
			(xy 86.900512 -381.25146) (xy 86.900512 -381.09398) (xy 86.900109 -381.084792) (xy 86.89359 -381.067608)
			(xy 86.887812 -381.060452) (xy 86.865967 -381.034771) (xy 86.827877 -380.979139) (xy 86.796725 -380.919345)
			(xy 86.772959 -380.85625) (xy 86.756922 -380.790763) (xy 86.748844 -380.723826) (xy 86.748842 -380.656404)
			(xy 83.470797 -380.656404) (xy 83.470804 -380.656461) (xy 83.470802 -380.723769) (xy 83.462755 -380.790593)
			(xy 83.446779 -380.855977) (xy 83.423102 -380.918983) (xy 83.392064 -380.978706) (xy 83.35411 -381.034292)
			(xy 83.33232 -381.059944) (xy 83.326525 -381.06709) (xy 83.320009 -381.08428) (xy 83.31962 -381.093472)
			(xy 83.31962 -381.251206) (xy 83.31924 -381.261383) (xy 83.311445 -381.280186) (xy 83.297046 -381.294572)
			(xy 83.278236 -381.302349) (xy 83.268058 -381.302768) (xy 82.551778 -381.302768) (xy 82.54162 -381.302285)
			(xy 82.522851 -381.294504) (xy 82.508487 -381.280136) (xy 82.500712 -381.261365) (xy 82.500216 -381.251206)
			(xy 82.500216 -381.093472) (xy 82.499816 -381.084284) (xy 82.493295 -381.0671) (xy 82.487516 -381.059944)
			(xy 82.465749 -381.034275) (xy 82.427801 -380.978691) (xy 82.396768 -380.918969) (xy 82.373095 -380.855967)
			(xy 82.357121 -380.790587) (xy 82.349076 -380.723767) (xy 82.349074 -380.656464) (xy 79.071011 -380.656464)
			(xy 79.071009 -380.723827) (xy 79.062932 -380.790767) (xy 79.046895 -380.856256) (xy 79.02313 -380.919354)
			(xy 78.991978 -380.979151) (xy 78.953888 -381.034786) (xy 78.932024 -381.060452) (xy 78.926226 -381.067596)
			(xy 78.919711 -381.084787) (xy 78.919324 -381.09398) (xy 78.919324 -381.251206) (xy 78.918877 -381.261337)
			(xy 78.911141 -381.280066) (xy 78.896842 -381.294423) (xy 78.878145 -381.302235) (xy 78.868016 -381.302768)
			(xy 78.151736 -381.302768) (xy 78.141612 -381.302354) (xy 78.122903 -381.294611) (xy 78.108586 -381.280294)
			(xy 78.100846 -381.261584) (xy 78.100428 -381.25146) (xy 78.100428 -381.09398) (xy 78.100021 -381.084793)
			(xy 78.093505 -381.067609) (xy 78.087728 -381.060452) (xy 78.065883 -381.034771) (xy 78.027792 -380.979139)
			(xy 77.996638 -380.919346) (xy 77.972872 -380.856251) (xy 77.956834 -380.790763) (xy 77.948756 -380.723826)
			(xy 77.948754 -380.656404) (xy 74.670709 -380.656404) (xy 74.670716 -380.656462) (xy 74.670714 -380.723769)
			(xy 74.662667 -380.790593) (xy 74.646691 -380.855977) (xy 74.623015 -380.918982) (xy 74.591978 -380.978706)
			(xy 74.554026 -381.034292) (xy 74.532236 -381.059944) (xy 74.52643 -381.067082) (xy 74.519923 -381.084278)
			(xy 74.519536 -381.093472) (xy 74.519536 -381.251206) (xy 74.51914 -381.261381) (xy 74.511349 -381.280181)
			(xy 74.496954 -381.294567) (xy 74.478149 -381.302347) (xy 74.467974 -381.302768) (xy 73.751694 -381.302768)
			(xy 73.741537 -381.302272) (xy 73.722769 -381.294496) (xy 73.708404 -381.280131) (xy 73.700628 -381.261363)
			(xy 73.700132 -381.251206) (xy 73.700132 -381.093472) (xy 73.699728 -381.084284) (xy 73.693209 -381.0671)
			(xy 73.687432 -381.059944) (xy 73.665664 -381.034275) (xy 73.627715 -380.978691) (xy 73.596682 -380.91897)
			(xy 73.573008 -380.855967) (xy 73.557034 -380.790587) (xy 73.548988 -380.723767) (xy 73.548987 -380.656463)
			(xy 43.87119 -380.656463) (xy 43.871188 -380.723828) (xy 43.86311 -380.790767) (xy 43.847073 -380.856258)
			(xy 43.823306 -380.919355) (xy 43.792153 -380.979152) (xy 43.754061 -381.034787) (xy 43.732196 -381.060452)
			(xy 43.726394 -381.067594) (xy 43.719883 -381.084787) (xy 43.719496 -381.09398) (xy 43.719496 -381.251206)
			(xy 43.718979 -381.261329) (xy 43.711256 -381.280043) (xy 43.69698 -381.294398) (xy 43.678308 -381.302223)
			(xy 43.668188 -381.302768) (xy 42.951908 -381.302768) (xy 42.94175 -381.302371) (xy 42.922992 -381.294572)
			(xy 42.908667 -381.280167) (xy 42.900973 -381.261366) (xy 42.9006 -381.251206) (xy 42.9006 -381.09398)
			(xy 42.9002 -381.084792) (xy 42.893679 -381.067607) (xy 42.8879 -381.060452) (xy 42.866056 -381.034771)
			(xy 42.827966 -380.979138) (xy 42.796815 -380.919344) (xy 42.773049 -380.85625) (xy 42.757013 -380.790763)
			(xy 42.748935 -380.723826) (xy 42.748933 -380.656404) (xy 39.470887 -380.656404) (xy 39.470894 -380.656461)
			(xy 39.470893 -380.723769) (xy 39.462846 -380.790594) (xy 39.446869 -380.855978) (xy 39.423192 -380.918983)
			(xy 39.392153 -380.978707) (xy 39.354199 -381.034293) (xy 39.332408 -381.059944) (xy 39.326611 -381.067089)
			(xy 39.320096 -381.08428) (xy 39.319708 -381.093472) (xy 39.319708 -381.251206) (xy 39.319173 -381.261358)
			(xy 39.311405 -381.280119) (xy 39.297052 -381.294482) (xy 39.278298 -381.302265) (xy 39.268146 -381.302768)
			(xy 38.551866 -381.302768) (xy 38.541707 -381.302295) (xy 38.522938 -381.29451) (xy 38.508574 -381.280138)
			(xy 38.5008 -381.261365) (xy 38.500304 -381.251206) (xy 38.500304 -381.093472) (xy 38.499907 -381.084283)
			(xy 38.493384 -381.067099) (xy 38.487604 -381.059944) (xy 38.465837 -381.034275) (xy 38.42789 -380.97869)
			(xy 38.396858 -380.918969) (xy 38.373185 -380.855966) (xy 38.357212 -380.790587) (xy 38.349167 -380.723766)
			(xy 38.349165 -380.656464) (xy 35.071102 -380.656464) (xy 35.0711 -380.723828) (xy 35.063023 -380.790767)
			(xy 35.046985 -380.856257) (xy 35.023219 -380.919355) (xy 34.992067 -380.979151) (xy 34.953977 -381.034787)
			(xy 34.932112 -381.060452) (xy 34.926312 -381.067595) (xy 34.919799 -381.084787) (xy 34.919412 -381.09398)
			(xy 34.919412 -381.251206) (xy 34.91888 -381.261327) (xy 34.91116 -381.280038) (xy 34.896888 -381.294392)
			(xy 34.878222 -381.30222) (xy 34.868104 -381.302768) (xy 34.151824 -381.302768) (xy 34.141667 -381.302358)
			(xy 34.122909 -381.294565) (xy 34.108584 -381.280164) (xy 34.100889 -381.261365) (xy 34.100516 -381.251206)
			(xy 34.100516 -381.09398) (xy 34.100112 -381.084792) (xy 34.093594 -381.067608) (xy 34.087816 -381.060452)
			(xy 34.065971 -381.034771) (xy 34.027881 -380.979139) (xy 33.996728 -380.919345) (xy 33.972962 -380.85625)
			(xy 33.956925 -380.790763) (xy 33.948847 -380.723826) (xy 33.948845 -380.656404) (xy 30.6708 -380.656404)
			(xy 30.670807 -380.656461) (xy 30.670805 -380.723769) (xy 30.662758 -380.790593) (xy 30.646782 -380.855977)
			(xy 30.623105 -380.918982) (xy 30.592068 -380.978706) (xy 30.554114 -381.034292) (xy 30.532324 -381.059944)
			(xy 30.526529 -381.067091) (xy 30.520013 -381.08428) (xy 30.519624 -381.093472) (xy 30.519624 -381.251206)
			(xy 30.51924 -381.261383) (xy 30.511446 -381.280185) (xy 30.497048 -381.294571) (xy 30.478239 -381.302349)
			(xy 30.468062 -381.302768) (xy 29.751782 -381.302768) (xy 29.741624 -381.302282) (xy 29.722855 -381.294502)
			(xy 29.708491 -381.280135) (xy 29.700716 -381.261364) (xy 29.70022 -381.251206) (xy 29.70022 -381.093472)
			(xy 29.699819 -381.084284) (xy 29.693298 -381.0671) (xy 29.68752 -381.059944) (xy 29.665752 -381.034276)
			(xy 29.627804 -380.978691) (xy 29.596771 -380.918969) (xy 29.573098 -380.855967) (xy 29.557124 -380.790587)
			(xy 29.549079 -380.723767) (xy 29.549077 -380.656463) (xy 29.557119 -380.589643) (xy 29.573089 -380.524262)
			(xy 29.596759 -380.461258) (xy 29.627789 -380.401535) (xy 29.665734 -380.345948) (xy 29.68752 -380.320296)
			(xy 29.693303 -380.313141) (xy 29.699825 -380.295958) (xy 29.70022 -380.286768) (xy 29.70022 -379.7935)
			(xy 29.699806 -379.784313) (xy 29.693295 -379.767129) (xy 29.68752 -379.759972) (xy 29.66573 -379.734322)
			(xy 29.627781 -379.678735) (xy 29.596748 -379.619011) (xy 29.573075 -379.556006) (xy 29.557102 -379.490624)
			(xy 29.549058 -379.423801) (xy 28.447 -379.423801) (xy 28.447041 -379.423909) (xy 28.463077 -379.489397)
			(xy 28.471153 -379.556335) (xy 28.471153 -379.623759) (xy 28.463078 -379.690697) (xy 28.447043 -379.756186)
			(xy 28.423279 -379.819282) (xy 28.392128 -379.879078) (xy 28.35404 -379.934713) (xy 28.332176 -379.960378)
			(xy 28.326361 -379.96751) (xy 28.319858 -379.984711) (xy 28.319476 -379.993906) (xy 28.319476 -380.151386)
			(xy 28.318962 -380.16151) (xy 28.311242 -380.180228) (xy 28.296964 -380.194584) (xy 28.278289 -380.202406)
			(xy 28.268168 -380.202948) (xy 27.551888 -380.202948) (xy 27.541784 -380.202426) (xy 27.523115 -380.194693)
			(xy 27.508823 -380.180408) (xy 27.50108 -380.161743) (xy 27.50058 -380.15164) (xy 27.50058 -379.993906)
			(xy 27.500171 -379.984719) (xy 27.493657 -379.967534) (xy 27.48788 -379.960378) (xy 27.466012 -379.934716)
			(xy 27.427923 -379.879081) (xy 27.396771 -379.819285) (xy 27.373007 -379.756187) (xy 27.356972 -379.690698)
			(xy 27.348896 -379.623759) (xy 27.348896 -379.556335) (xy 27.356973 -379.489396) (xy 27.373009 -379.423907)
			(xy 27.396774 -379.36081) (xy 27.427926 -379.301013) (xy 27.466015 -379.245379) (xy 27.48788 -379.219714)
			(xy 27.493693 -379.21258) (xy 27.500199 -379.195381) (xy 27.50058 -379.186186) (xy 27.50058 -378.693934)
			(xy 27.500158 -378.684748) (xy 27.493653 -378.667563) (xy 27.48788 -378.660406) (xy 27.465991 -378.634761)
			(xy 27.427905 -378.579124) (xy 27.396756 -378.519324) (xy 27.372994 -378.456225) (xy 27.356961 -378.390733)
			(xy 27.348888 -378.323793) (xy 0.509016 -378.323793) (xy 0.509016 -382.223705) (xy 27.348899 -382.223705)
			(xy 27.3489 -382.15628) (xy 27.356976 -382.089342) (xy 27.373012 -382.023853) (xy 27.396777 -381.960755)
			(xy 27.427928 -381.900959) (xy 27.466016 -381.845324) (xy 27.48788 -381.819658) (xy 27.493675 -381.812511)
			(xy 27.500191 -381.795322) (xy 27.50058 -381.78613) (xy 27.50058 -381.628904) (xy 27.501088 -381.618798)
			(xy 27.508821 -381.600124) (xy 27.52311 -381.58583) (xy 27.541782 -381.578091) (xy 27.551888 -381.577596)
			(xy 28.268168 -381.577596) (xy 28.278288 -381.578042) (xy 28.29699 -381.585779) (xy 28.311306 -381.600086)
			(xy 28.319053 -381.618784) (xy 28.319476 -381.628904) (xy 28.319476 -381.78613) (xy 28.319877 -381.795318)
			(xy 28.326398 -381.812502) (xy 28.332176 -381.819658) (xy 28.354031 -381.845331) (xy 28.392122 -381.900964)
			(xy 28.423274 -381.960759) (xy 28.44704 -382.023855) (xy 28.463077 -382.089343) (xy 28.471154 -382.156281)
			(xy 28.471155 -382.223646) (xy 31.749194 -382.223646) (xy 31.749195 -382.156339) (xy 31.757241 -382.089516)
			(xy 31.773216 -382.024132) (xy 31.796891 -381.961127) (xy 31.827927 -381.901404) (xy 31.865879 -381.845818)
			(xy 31.887668 -381.820166) (xy 31.89347 -381.813025) (xy 31.899979 -381.795831) (xy 31.900368 -381.786638)
			(xy 31.900368 -381.628904) (xy 31.900824 -381.618754) (xy 31.908613 -381.600008) (xy 31.922998 -381.585686)
			(xy 31.941778 -381.57798) (xy 31.95193 -381.577596) (xy 32.66821 -381.577596) (xy 32.678332 -381.578117)
			(xy 32.697045 -381.58584) (xy 32.711399 -381.600115) (xy 32.719226 -381.618785) (xy 32.719772 -381.628904)
			(xy 32.719772 -381.786638) (xy 32.72017 -381.795826) (xy 32.726693 -381.81301) (xy 32.732472 -381.820166)
			(xy 32.75425 -381.845826) (xy 32.792198 -381.901412) (xy 32.823231 -381.961134) (xy 32.846904 -382.024138)
			(xy 32.862877 -382.089519) (xy 32.870922 -382.15634) (xy 32.870923 -382.223645) (xy 32.870916 -382.223704)
			(xy 36.148987 -382.223704) (xy 36.148988 -382.156281) (xy 36.157064 -382.089342) (xy 36.1731 -382.023853)
			(xy 36.196863 -381.960756) (xy 36.228013 -381.900959) (xy 36.266101 -381.845324) (xy 36.287964 -381.819658)
			(xy 36.293769 -381.812519) (xy 36.300277 -381.795323) (xy 36.300664 -381.78613) (xy 36.300664 -381.628904)
			(xy 36.301188 -381.6188) (xy 36.308917 -381.600129) (xy 36.323202 -381.585835) (xy 36.341868 -381.578094)
			(xy 36.351972 -381.577596) (xy 37.068252 -381.577596) (xy 37.078371 -381.578055) (xy 37.097073 -381.585787)
			(xy 37.111388 -381.60009) (xy 37.119136 -381.618786) (xy 37.11956 -381.628904) (xy 37.11956 -381.78613)
			(xy 37.119965 -381.795318) (xy 37.126483 -381.812501) (xy 37.13226 -381.819658) (xy 37.154116 -381.845331)
			(xy 37.192207 -381.900963) (xy 37.223361 -381.960758) (xy 37.247127 -382.023854) (xy 37.263164 -382.089343)
			(xy 37.271242 -382.156281) (xy 37.271243 -382.223704) (xy 37.271243 -382.223705) (xy 40.548753 -382.223705)
			(xy 40.548754 -382.15628) (xy 40.556832 -382.08934) (xy 40.57287 -382.02385) (xy 40.596638 -381.960752)
			(xy 40.627792 -381.900956) (xy 40.665886 -381.845322) (xy 40.687752 -381.819658) (xy 40.693555 -381.812518)
			(xy 40.700065 -381.795323) (xy 40.700452 -381.78613) (xy 40.700452 -381.628904) (xy 40.700987 -381.618801)
			(xy 40.708715 -381.600133) (xy 40.722996 -381.585839) (xy 40.741658 -381.578096) (xy 40.75176 -381.577596)
			(xy 41.46804 -381.577596) (xy 41.478151 -381.578052) (xy 41.496829 -381.585802) (xy 41.511122 -381.600108)
			(xy 41.518856 -381.618793) (xy 41.519348 -381.628904) (xy 41.519348 -381.78613) (xy 41.519755 -381.795317)
			(xy 41.526272 -381.812501) (xy 41.532048 -381.819658) (xy 41.553904 -381.84533) (xy 41.591996 -381.900963)
			(xy 41.62315 -381.960757) (xy 41.646917 -382.023853) (xy 41.662955 -382.089342) (xy 41.671033 -382.156281)
			(xy 41.671034 -382.223645) (xy 44.949073 -382.223645) (xy 44.949074 -382.15634) (xy 44.957119 -382.089516)
			(xy 44.973093 -382.024133) (xy 44.996767 -381.961128) (xy 45.027801 -381.901405) (xy 45.065751 -381.845818)
			(xy 45.08754 -381.820166) (xy 45.093339 -381.813022) (xy 45.099851 -381.795831) (xy 45.10024 -381.786638)
			(xy 45.10024 -381.628904) (xy 45.100626 -381.618745) (xy 45.108427 -381.599985) (xy 45.122836 -381.58566)
			(xy 45.141641 -381.577968) (xy 45.151802 -381.577596) (xy 45.868082 -381.577596) (xy 45.878202 -381.57814)
			(xy 45.896915 -381.585854) (xy 45.91127 -381.600122) (xy 45.919098 -381.618787) (xy 45.919644 -381.628904)
			(xy 45.919644 -381.786638) (xy 45.920049 -381.795826) (xy 45.926568 -381.813009) (xy 45.932344 -381.820166)
			(xy 45.954122 -381.845826) (xy 45.992072 -381.901411) (xy 46.023107 -381.961133) (xy 46.046781 -382.024137)
			(xy 46.062755 -382.089518) (xy 46.070801 -382.15634) (xy 46.070801 -382.223645) (xy 46.070794 -382.223705)
			(xy 71.348808 -382.223705) (xy 71.348809 -382.15628) (xy 71.356886 -382.089342) (xy 71.372922 -382.023852)
			(xy 71.396687 -381.960755) (xy 71.427838 -381.900958) (xy 71.465928 -381.845323) (xy 71.487792 -381.819658)
			(xy 71.493588 -381.812512) (xy 71.500103 -381.795322) (xy 71.500492 -381.78613) (xy 71.500492 -381.628904)
			(xy 71.500919 -381.618783) (xy 71.508664 -381.600081) (xy 71.522977 -381.585767) (xy 71.541679 -381.57802)
			(xy 71.5518 -381.577596) (xy 72.26808 -381.577596) (xy 72.278201 -381.578032) (xy 72.296903 -381.585773)
			(xy 72.311218 -381.600083) (xy 72.318965 -381.618783) (xy 72.319388 -381.628904) (xy 72.319388 -381.78613)
			(xy 72.319786 -381.795318) (xy 72.326308 -381.812503) (xy 72.332088 -381.819658) (xy 72.353943 -381.845331)
			(xy 72.392032 -381.900964) (xy 72.423184 -381.960759) (xy 72.446949 -382.023855) (xy 72.462986 -382.089343)
			(xy 72.471063 -382.156281) (xy 72.471064 -382.223646) (xy 75.749104 -382.223646) (xy 75.749104 -382.156339)
			(xy 75.75715 -382.089515) (xy 75.773125 -382.024132) (xy 75.796801 -381.961127) (xy 75.827838 -381.901403)
			(xy 75.86579 -381.845818) (xy 75.88758 -381.820166) (xy 75.893371 -381.813017) (xy 75.89989 -381.795829)
			(xy 75.90028 -381.786638) (xy 75.90028 -381.628904) (xy 75.900725 -381.618753) (xy 75.908515 -381.600004)
			(xy 75.922904 -381.585681) (xy 75.941689 -381.577978) (xy 75.951842 -381.577596) (xy 76.668122 -381.577596)
			(xy 76.678245 -381.578107) (xy 76.696958 -381.585834) (xy 76.711312 -381.600112) (xy 76.719138 -381.618784)
			(xy 76.719684 -381.628904) (xy 76.719684 -381.786638) (xy 76.720079 -381.795827) (xy 76.726604 -381.813011)
			(xy 76.732384 -381.820166) (xy 76.754161 -381.845826) (xy 76.792109 -381.901412) (xy 76.823141 -381.961135)
			(xy 76.846814 -382.024138) (xy 76.862787 -382.089519) (xy 76.870831 -382.156341) (xy 76.870832 -382.223644)
			(xy 76.870825 -382.223704) (xy 80.148896 -382.223704) (xy 80.148897 -382.15628) (xy 80.156973 -382.089342)
			(xy 80.173009 -382.023853) (xy 80.196773 -381.960755) (xy 80.227924 -381.900959) (xy 80.266012 -381.845324)
			(xy 80.287876 -381.819658) (xy 80.29367 -381.812511) (xy 80.300187 -381.795322) (xy 80.300576 -381.78613)
			(xy 80.300576 -381.628904) (xy 80.301088 -381.618798) (xy 80.30882 -381.600125) (xy 80.323108 -381.585831)
			(xy 80.341779 -381.578092) (xy 80.351884 -381.577596) (xy 81.068164 -381.577596) (xy 81.078284 -381.578046)
			(xy 81.096986 -381.585781) (xy 81.111301 -381.600087) (xy 81.119048 -381.618785) (xy 81.119472 -381.628904)
			(xy 81.119472 -381.78613) (xy 81.119874 -381.795318) (xy 81.126394 -381.812502) (xy 81.132172 -381.819658)
			(xy 81.154027 -381.845331) (xy 81.192118 -381.900964) (xy 81.223271 -381.960759) (xy 81.247037 -382.023854)
			(xy 81.263074 -382.089343) (xy 81.271151 -382.156281) (xy 81.271152 -382.223704) (xy 84.548687 -382.223704)
			(xy 84.548688 -382.156281) (xy 84.556764 -382.089342) (xy 84.5728 -382.023853) (xy 84.596563 -381.960756)
			(xy 84.627713 -381.900959) (xy 84.665801 -381.845324) (xy 84.687664 -381.819658) (xy 84.693469 -381.812519)
			(xy 84.699977 -381.795323) (xy 84.700364 -381.78613) (xy 84.700364 -381.628904) (xy 84.700888 -381.6188)
			(xy 84.708617 -381.600129) (xy 84.722902 -381.585835) (xy 84.741568 -381.578094) (xy 84.751672 -381.577596)
			(xy 85.467952 -381.577596) (xy 85.478071 -381.578055) (xy 85.496773 -381.585787) (xy 85.511088 -381.60009)
			(xy 85.518836 -381.618786) (xy 85.51926 -381.628904) (xy 85.51926 -381.78613) (xy 85.519665 -381.795318)
			(xy 85.526183 -381.812501) (xy 85.53196 -381.819658) (xy 85.553816 -381.845331) (xy 85.591907 -381.900963)
			(xy 85.623061 -381.960758) (xy 85.646827 -382.023854) (xy 85.662864 -382.089343) (xy 85.670942 -382.156281)
			(xy 85.670943 -382.223646) (xy 88.948982 -382.223646) (xy 88.948983 -382.156339) (xy 88.957028 -382.089516)
			(xy 88.973003 -382.024133) (xy 88.996677 -381.961128) (xy 89.027712 -381.901404) (xy 89.065663 -381.845818)
			(xy 89.087452 -381.820166) (xy 89.093252 -381.813023) (xy 89.099763 -381.795831) (xy 89.100152 -381.786638)
			(xy 89.100152 -381.628904) (xy 89.100624 -381.618756) (xy 89.108409 -381.600013) (xy 89.12279 -381.585691)
			(xy 89.141564 -381.577983) (xy 89.151714 -381.577596) (xy 89.867994 -381.577596) (xy 89.878115 -381.57813)
			(xy 89.896828 -381.585848) (xy 89.911183 -381.600119) (xy 89.91901 -381.618786) (xy 89.919556 -381.628904)
			(xy 89.919556 -381.786638) (xy 89.919958 -381.795826) (xy 89.926478 -381.81301) (xy 89.932256 -381.820166)
			(xy 89.954034 -381.845826) (xy 89.991983 -381.901411) (xy 90.023017 -381.961134) (xy 90.046691 -382.024137)
			(xy 90.062665 -382.089519) (xy 90.07071 -382.15634) (xy 90.070711 -382.223645) (xy 115.349246 -382.223645)
			(xy 115.349247 -382.15634) (xy 115.357291 -382.089517) (xy 115.373264 -382.024135) (xy 115.396937 -381.96113)
			(xy 115.427969 -381.901406) (xy 115.465917 -381.845819) (xy 115.487704 -381.820166) (xy 115.493498 -381.813019)
			(xy 115.500014 -381.79583) (xy 115.500404 -381.786638) (xy 115.500404 -381.628904) (xy 115.500825 -381.61875)
			(xy 115.50862 -381.599997) (xy 115.523017 -381.585673) (xy 115.54181 -381.577974) (xy 115.551966 -381.577596)
			(xy 116.268246 -381.577596) (xy 116.27837 -381.578088) (xy 116.297084 -381.585822) (xy 116.311437 -381.600106)
			(xy 116.319262 -381.618782) (xy 116.319808 -381.628904) (xy 116.319808 -381.786638) (xy 116.320198 -381.795827)
			(xy 116.326725 -381.813012) (xy 116.332508 -381.820166) (xy 116.354288 -381.845826) (xy 116.39224 -381.90141)
			(xy 116.423277 -381.961132) (xy 116.446952 -382.024135) (xy 116.462928 -382.089517) (xy 116.470973 -382.15634)
			(xy 116.470974 -382.223645) (xy 116.470967 -382.223705) (xy 119.749014 -382.223705) (xy 119.749015 -382.15628)
			(xy 119.757092 -382.089341) (xy 119.773128 -382.023852) (xy 119.796894 -381.960754) (xy 119.828046 -381.900958)
			(xy 119.866135 -381.845323) (xy 119.888 -381.819658) (xy 119.893797 -381.812513) (xy 119.900311 -381.795322)
			(xy 119.9007 -381.78613) (xy 119.9007 -381.628904) (xy 119.901119 -381.618782) (xy 119.908866 -381.600078)
			(xy 119.923182 -381.585764) (xy 119.941886 -381.578019) (xy 119.952008 -381.577596) (xy 120.668288 -381.577596)
			(xy 120.678409 -381.578026) (xy 120.697112 -381.585769) (xy 120.711426 -381.600081) (xy 120.719173 -381.618783)
			(xy 120.719596 -381.628904) (xy 120.719596 -381.78613) (xy 120.719992 -381.795319) (xy 120.726516 -381.812503)
			(xy 120.732296 -381.819658) (xy 120.75415 -381.845331) (xy 120.79224 -381.900965) (xy 120.823391 -381.96076)
			(xy 120.847156 -382.023855) (xy 120.863192 -382.089344) (xy 120.871269 -382.156281) (xy 120.87127 -382.223646)
			(xy 124.14931 -382.223646) (xy 124.14931 -382.156339) (xy 124.157356 -382.089515) (xy 124.173332 -382.024132)
			(xy 124.197008 -381.961127) (xy 124.228045 -381.901403) (xy 124.265998 -381.845818) (xy 124.287788 -381.820166)
			(xy 124.29358 -381.813018) (xy 124.300098 -381.79583) (xy 124.300488 -381.786638) (xy 124.300488 -381.628904)
			(xy 124.300925 -381.618752) (xy 124.308717 -381.600002) (xy 124.323109 -381.585679) (xy 124.341896 -381.577977)
			(xy 124.35205 -381.577596) (xy 125.06833 -381.577596) (xy 125.078453 -381.578101) (xy 125.097167 -381.58583)
			(xy 125.11152 -381.60011) (xy 125.119346 -381.618783) (xy 125.119892 -381.628904) (xy 125.119892 -381.786638)
			(xy 125.120286 -381.795827) (xy 125.126811 -381.813011) (xy 125.132592 -381.820166) (xy 125.154369 -381.845827)
			(xy 125.192316 -381.901413) (xy 125.223348 -381.961135) (xy 125.24702 -382.024139) (xy 125.262993 -382.089519)
			(xy 125.271037 -382.156341) (xy 125.271038 -382.223644) (xy 125.271038 -382.223646) (xy 128.5491 -382.223646)
			(xy 128.549101 -382.156339) (xy 128.557147 -382.089515) (xy 128.573122 -382.024132) (xy 128.596798 -381.961127)
			(xy 128.627834 -381.901404) (xy 128.665787 -381.845818) (xy 128.687576 -381.820166) (xy 128.693367 -381.813016)
			(xy 128.699886 -381.795829) (xy 128.700276 -381.786638) (xy 128.700276 -381.628904) (xy 128.700724 -381.618753)
			(xy 128.708514 -381.600005) (xy 128.722902 -381.585683) (xy 128.741685 -381.577979) (xy 128.751838 -381.577596)
			(xy 129.468118 -381.577596) (xy 129.47824 -381.57811) (xy 129.496954 -381.585836) (xy 129.511308 -381.600113)
			(xy 129.519134 -381.618784) (xy 129.51968 -381.628904) (xy 129.51968 -381.786638) (xy 129.520076 -381.795827)
			(xy 129.5266 -381.813011) (xy 129.53238 -381.820166) (xy 129.554157 -381.845826) (xy 129.592105 -381.901412)
			(xy 129.623138 -381.961135) (xy 129.64681 -382.024138) (xy 129.662784 -382.089519) (xy 129.670828 -382.156341)
			(xy 129.670829 -382.223644) (xy 129.670829 -382.223645) (xy 159.349155 -382.223645) (xy 159.349156 -382.15634)
			(xy 159.3572 -382.089517) (xy 159.373174 -382.024134) (xy 159.396847 -381.96113) (xy 159.42788 -381.901406)
			(xy 159.465828 -381.845818) (xy 159.487616 -381.820166) (xy 159.493411 -381.81302) (xy 159.499926 -381.79583)
			(xy 159.500316 -381.786638) (xy 159.500316 -381.628904) (xy 159.50072 -381.61878) (xy 159.508469 -381.600073)
			(xy 159.52279 -381.585758) (xy 159.5415 -381.578016) (xy 159.551624 -381.577596) (xy 160.268158 -381.577596)
			(xy 160.278277 -381.57816) (xy 160.296988 -381.585866) (xy 160.311345 -381.600128) (xy 160.319173 -381.618789)
			(xy 160.31972 -381.628904) (xy 160.31972 -381.786638) (xy 160.320108 -381.795828) (xy 160.326637 -381.813012)
			(xy 160.33242 -381.820166) (xy 160.354199 -381.845826) (xy 160.392151 -381.90141) (xy 160.423187 -381.961132)
			(xy 160.446862 -382.024136) (xy 160.462837 -382.089518) (xy 160.470882 -382.15634) (xy 160.470883 -382.223645)
			(xy 160.470876 -382.223705) (xy 163.748923 -382.223705) (xy 163.748924 -382.15628) (xy 163.757001 -382.089341)
			(xy 163.773038 -382.023851) (xy 163.796804 -381.960754) (xy 163.827956 -381.900957) (xy 163.866047 -381.845323)
			(xy 163.887912 -381.819658) (xy 163.89371 -381.812514) (xy 163.900224 -381.795323) (xy 163.900612 -381.78613)
			(xy 163.900612 -381.628904) (xy 163.90102 -381.61878) (xy 163.908769 -381.600074) (xy 163.923088 -381.58576)
			(xy 163.941796 -381.578016) (xy 163.95192 -381.577596) (xy 164.6682 -381.577596) (xy 164.678322 -381.578016)
			(xy 164.697025 -381.585763) (xy 164.711339 -381.600079) (xy 164.719085 -381.618782) (xy 164.719508 -381.628904)
			(xy 164.719508 -381.78613) (xy 164.719902 -381.795319) (xy 164.726426 -381.812503) (xy 164.732208 -381.819658)
			(xy 164.754062 -381.845331) (xy 164.79215 -381.900965) (xy 164.823301 -381.96076) (xy 164.847065 -382.023856)
			(xy 164.863101 -382.089344) (xy 164.871178 -382.156281) (xy 164.871179 -382.223645) (xy 168.149243 -382.223645)
			(xy 168.149244 -382.15634) (xy 168.157288 -382.089517) (xy 168.173261 -382.024135) (xy 168.196933 -381.96113)
			(xy 168.227965 -381.901406) (xy 168.265913 -381.845819) (xy 168.2877 -381.820166) (xy 168.293494 -381.813019)
			(xy 168.30001 -381.79583) (xy 168.3004 -381.786638) (xy 168.3004 -381.628904) (xy 168.300825 -381.61875)
			(xy 168.308619 -381.599998) (xy 168.323015 -381.585674) (xy 168.341806 -381.577975) (xy 168.351962 -381.577596)
			(xy 169.068242 -381.577596) (xy 169.078366 -381.578091) (xy 169.09708 -381.585824) (xy 169.111433 -381.600107)
			(xy 169.119258 -381.618783) (xy 169.119804 -381.628904) (xy 169.119804 -381.786638) (xy 169.120195 -381.795827)
			(xy 169.126722 -381.813012) (xy 169.132504 -381.820166) (xy 169.154281 -381.845827) (xy 169.192227 -381.901413)
			(xy 169.223258 -381.961136) (xy 169.24693 -382.024139) (xy 169.262902 -382.08952) (xy 169.270946 -382.156341)
			(xy 169.270947 -382.223644) (xy 169.270947 -382.223646) (xy 172.54901 -382.223646) (xy 172.54901 -382.156339)
			(xy 172.557056 -382.089515) (xy 172.573032 -382.024132) (xy 172.596708 -381.961127) (xy 172.627745 -381.901403)
			(xy 172.665698 -381.845818) (xy 172.687488 -381.820166) (xy 172.69328 -381.813018) (xy 172.699798 -381.79583)
			(xy 172.700188 -381.786638) (xy 172.700188 -381.628904) (xy 172.700625 -381.618752) (xy 172.708417 -381.600002)
			(xy 172.722809 -381.585679) (xy 172.741596 -381.577977) (xy 172.75175 -381.577596) (xy 173.46803 -381.577596)
			(xy 173.478153 -381.578101) (xy 173.496867 -381.58583) (xy 173.51122 -381.60011) (xy 173.519046 -381.618783)
			(xy 173.519592 -381.628904) (xy 173.519592 -381.786638) (xy 173.519986 -381.795827) (xy 173.526511 -381.813011)
			(xy 173.532292 -381.820166) (xy 173.554069 -381.845827) (xy 173.592016 -381.901413) (xy 173.623048 -381.961135)
			(xy 173.64672 -382.024139) (xy 173.662693 -382.089519) (xy 173.670737 -382.156341) (xy 173.670738 -382.223644)
			(xy 173.662695 -382.290466) (xy 173.646725 -382.355847) (xy 173.623054 -382.418851) (xy 173.592024 -382.478574)
			(xy 173.554078 -382.534161) (xy 173.532292 -382.559814) (xy 173.526506 -382.566967) (xy 173.519985 -382.584151)
			(xy 173.519592 -382.593342) (xy 173.519592 -383.086864) (xy 173.520021 -383.096049) (xy 173.526522 -383.113234)
			(xy 173.532292 -383.120392) (xy 173.554094 -383.146032) (xy 173.592041 -383.201621) (xy 173.623072 -383.261346)
			(xy 173.646507 -383.323727) (xy 174.749152 -383.323727) (xy 174.749155 -383.256419) (xy 174.757202 -383.189594)
			(xy 174.773179 -383.12421) (xy 174.796856 -383.061204) (xy 174.827893 -383.001479) (xy 174.865846 -382.945892)
			(xy 174.887636 -382.92024) (xy 174.893445 -382.913104) (xy 174.899951 -382.895906) (xy 174.900336 -382.886712)
			(xy 174.900336 -382.728724) (xy 174.900742 -382.718567) (xy 174.908536 -382.699808) (xy 174.922939 -382.685482)
			(xy 174.941739 -382.677788) (xy 174.951898 -382.677416) (xy 175.668178 -382.677416) (xy 175.6783 -382.677944)
			(xy 175.697017 -382.68566) (xy 175.711373 -382.699933) (xy 175.719197 -382.718605) (xy 175.71974 -382.728724)
			(xy 175.71974 -382.886712) (xy 175.720158 -382.895898) (xy 175.726668 -382.913082) (xy 175.73244 -382.92024)
			(xy 175.754193 -382.945921) (xy 175.792144 -383.001503) (xy 175.82318 -383.061222) (xy 175.846856 -383.124223)
			(xy 175.862832 -383.189602) (xy 175.870879 -383.256422) (xy 175.870883 -383.323724) (xy 175.862842 -383.390545)
			(xy 175.846872 -383.455925) (xy 175.823202 -383.518928) (xy 175.792172 -383.578651) (xy 175.754226 -383.634236)
			(xy 175.73244 -383.659888) (xy 175.726616 -383.667014) (xy 175.720119 -383.684219) (xy 175.71974 -383.693416)
			(xy 175.71974 -384.186684) (xy 175.720171 -384.195869) (xy 175.726672 -384.213053) (xy 175.73244 -384.220212)
			(xy 175.754264 -384.245835) (xy 175.792213 -384.301425) (xy 175.823246 -384.361152) (xy 175.846918 -384.424161)
			(xy 175.862889 -384.489547) (xy 175.87093 -384.556373) (xy 175.870927 -384.623681) (xy 175.862879 -384.690507)
			(xy 175.846902 -384.755891) (xy 175.823224 -384.818897) (xy 175.792185 -384.878622) (xy 175.754231 -384.934208)
			(xy 175.73244 -384.95986) (xy 175.726628 -384.966994) (xy 175.720124 -384.984193) (xy 175.71974 -384.993388)
			(xy 175.71974 -385.151376) (xy 175.71926 -385.161524) (xy 175.71148 -385.180268) (xy 175.697101 -385.194591)
			(xy 175.678327 -385.202298) (xy 175.668178 -385.202684) (xy 174.951898 -385.202684) (xy 174.941774 -385.202176)
			(xy 174.923058 -385.194452) (xy 174.908702 -385.180172) (xy 174.900879 -385.161497) (xy 174.900336 -385.151376)
			(xy 174.900336 -384.993388) (xy 174.899924 -384.984201) (xy 174.893411 -384.967017) (xy 174.887636 -384.95986)
			(xy 174.865884 -384.934179) (xy 174.827934 -384.878596) (xy 174.7969 -384.818877) (xy 174.773225 -384.755876)
			(xy 174.75725 -384.690497) (xy 174.749203 -384.623678) (xy 174.749199 -384.556376) (xy 174.75724 -384.489556)
			(xy 174.773209 -384.424176) (xy 174.796878 -384.361173) (xy 174.827906 -384.30145) (xy 174.865851 -384.245864)
			(xy 174.887636 -384.220212) (xy 174.893457 -384.213084) (xy 174.899956 -384.19588) (xy 174.900336 -384.186684)
			(xy 174.900336 -383.693416) (xy 174.89991 -383.684231) (xy 174.893407 -383.667046) (xy 174.887636 -383.659888)
			(xy 174.865813 -383.634265) (xy 174.827865 -383.578674) (xy 174.796834 -383.518947) (xy 174.773163 -383.455938)
			(xy 174.757193 -383.390553) (xy 174.749152 -383.323727) (xy 173.646507 -383.323727) (xy 173.646742 -383.324352)
			(xy 173.662713 -383.389736) (xy 173.670756 -383.456559) (xy 173.670754 -383.523865) (xy 173.662709 -383.590688)
			(xy 173.646735 -383.656071) (xy 173.623062 -383.719076) (xy 173.592028 -383.7788) (xy 173.55408 -383.834387)
			(xy 173.532292 -383.86004) (xy 173.526495 -383.867185) (xy 173.519981 -383.884376) (xy 173.519592 -383.893568)
			(xy 173.519592 -384.051556) (xy 173.519142 -384.061708) (xy 173.51136 -384.080461) (xy 173.496971 -384.094786)
			(xy 173.478184 -384.102486) (xy 173.46803 -384.102864) (xy 172.75175 -384.102864) (xy 172.741627 -384.102333)
			(xy 172.722908 -384.094622) (xy 172.70855 -384.080349) (xy 172.700728 -384.061676) (xy 172.700188 -384.051556)
			(xy 172.700188 -383.893568) (xy 172.699796 -383.884379) (xy 172.69327 -383.867194) (xy 172.687488 -383.86004)
			(xy 172.665715 -383.834376) (xy 172.627762 -383.778792) (xy 172.596725 -383.719071) (xy 172.57305 -383.656068)
			(xy 172.557074 -383.590686) (xy 172.549028 -383.523864) (xy 172.549026 -383.45656) (xy 172.55707 -383.389737)
			(xy 172.573042 -383.324355) (xy 172.596716 -383.261351) (xy 172.62775 -383.201629) (xy 172.6657 -383.146043)
			(xy 172.687488 -383.120392) (xy 172.693269 -383.113236) (xy 172.699793 -383.096054) (xy 172.700188 -383.086864)
			(xy 172.700188 -382.593342) (xy 172.69976 -382.584157) (xy 172.693259 -382.566972) (xy 172.687488 -382.559814)
			(xy 172.665689 -382.534171) (xy 172.627737 -382.478584) (xy 172.596702 -382.41886) (xy 172.573027 -382.355854)
			(xy 172.557054 -382.29047) (xy 172.54901 -382.223646) (xy 169.270947 -382.223646) (xy 169.262905 -382.290465)
			(xy 169.246934 -382.355847) (xy 169.223264 -382.41885) (xy 169.192235 -382.478574) (xy 169.15429 -382.534161)
			(xy 169.132504 -382.559814) (xy 169.126719 -382.566968) (xy 169.120197 -382.584152) (xy 169.119804 -382.593342)
			(xy 169.119804 -383.086864) (xy 169.120231 -383.096049) (xy 169.126733 -383.113234) (xy 169.132504 -383.120392)
			(xy 169.154306 -383.146032) (xy 169.192252 -383.201621) (xy 169.223282 -383.261347) (xy 169.246739 -383.323787)
			(xy 170.348832 -383.323787) (xy 170.348835 -383.256359) (xy 170.356915 -383.189418) (xy 170.372956 -383.123926)
			(xy 170.396726 -383.060827) (xy 170.427884 -383.001031) (xy 170.46598 -382.945396) (xy 170.487848 -382.919732)
			(xy 170.493662 -382.912599) (xy 170.500165 -382.895399) (xy 170.500548 -382.886204) (xy 170.500548 -382.728724)
			(xy 170.501103 -382.718623) (xy 170.508823 -382.699955) (xy 170.523098 -382.685662) (xy 170.541756 -382.677917)
			(xy 170.551856 -382.677416) (xy 171.268136 -382.677416) (xy 171.278249 -382.677856) (xy 171.296931 -382.685608)
			(xy 171.311225 -382.699919) (xy 171.318956 -382.71861) (xy 171.319444 -382.728724) (xy 171.319444 -382.886204)
			(xy 171.319865 -382.89539) (xy 171.326372 -382.912574) (xy 171.332144 -382.919732) (xy 171.353975 -382.945425)
			(xy 171.392068 -383.001055) (xy 171.423223 -383.060846) (xy 171.446992 -383.12394) (xy 171.463032 -383.189426)
			(xy 171.471111 -383.256362) (xy 171.471115 -383.323784) (xy 171.463041 -383.390721) (xy 171.447008 -383.456209)
			(xy 171.423246 -383.519304) (xy 171.392096 -383.579099) (xy 171.354008 -383.634732) (xy 171.332144 -383.660396)
			(xy 171.32636 -383.66755) (xy 171.319839 -383.684734) (xy 171.319444 -383.693924) (xy 171.319444 -384.186176)
			(xy 171.319878 -384.19536) (xy 171.326376 -384.212544) (xy 171.332144 -384.219704) (xy 171.354045 -384.245339)
			(xy 171.392137 -384.300977) (xy 171.423289 -384.360776) (xy 171.447054 -384.423877) (xy 171.463088 -384.489371)
			(xy 171.471162 -384.556313) (xy 171.471159 -384.623741) (xy 171.463078 -384.690683) (xy 171.447037 -384.756174)
			(xy 171.423267 -384.819273) (xy 171.392109 -384.87907) (xy 171.354012 -384.934704) (xy 171.332144 -384.960368)
			(xy 171.326329 -384.9675) (xy 171.319827 -384.984701) (xy 171.319444 -384.993896) (xy 171.319444 -385.151376)
			(xy 171.318896 -385.161478) (xy 171.311175 -385.180147) (xy 171.296897 -385.194441) (xy 171.278237 -385.202185)
			(xy 171.268136 -385.202684) (xy 170.551856 -385.202684) (xy 170.541742 -385.20225) (xy 170.52306 -385.194495)
			(xy 170.508766 -385.180183) (xy 170.501036 -385.16149) (xy 170.500548 -385.151376) (xy 170.500548 -384.993896)
			(xy 170.500129 -384.98471) (xy 170.49362 -384.967526) (xy 170.487848 -384.960368) (xy 170.466018 -384.934674)
			(xy 170.427925 -384.879045) (xy 170.39677 -384.819253) (xy 170.373001 -384.75616) (xy 170.356962 -384.690674)
			(xy 170.348883 -384.623738) (xy 170.348879 -384.556316) (xy 170.356952 -384.489379) (xy 170.372985 -384.423892)
			(xy 170.396748 -384.360796) (xy 170.427897 -384.301001) (xy 170.465984 -384.245368) (xy 170.487848 -384.219704)
			(xy 170.493631 -384.21255) (xy 170.500153 -384.195366) (xy 170.500548 -384.186176) (xy 170.500548 -383.693924)
			(xy 170.500116 -383.684739) (xy 170.493616 -383.667555) (xy 170.487848 -383.660396) (xy 170.465947 -383.634761)
			(xy 170.427856 -383.579123) (xy 170.396704 -383.519323) (xy 170.37294 -383.456222) (xy 170.356906 -383.390729)
			(xy 170.348832 -383.323787) (xy 169.246739 -383.323787) (xy 169.246952 -383.324353) (xy 169.262922 -383.389736)
			(xy 169.270965 -383.456559) (xy 169.270963 -383.523865) (xy 169.262918 -383.590688) (xy 169.246945 -383.65607)
			(xy 169.223272 -383.719075) (xy 169.192239 -383.7788) (xy 169.154291 -383.834387) (xy 169.132504 -383.86004)
			(xy 169.126708 -383.867186) (xy 169.120193 -383.884376) (xy 169.119804 -383.893568) (xy 169.119804 -384.051556)
			(xy 169.119342 -384.061707) (xy 169.111562 -384.080457) (xy 169.097177 -384.094782) (xy 169.078394 -384.102484)
			(xy 169.068242 -384.102864) (xy 168.351962 -384.102864) (xy 168.341833 -384.102405) (xy 168.323112 -384.094665)
			(xy 168.308757 -384.080371) (xy 168.300939 -384.061682) (xy 168.3004 -384.051556) (xy 168.3004 -383.893568)
			(xy 168.300005 -383.884379) (xy 168.293481 -383.867195) (xy 168.2877 -383.86004) (xy 168.265929 -383.834374)
			(xy 168.227982 -383.778789) (xy 168.196951 -383.719067) (xy 168.173279 -383.656064) (xy 168.157306 -383.590684)
			(xy 168.149261 -383.523864) (xy 168.149259 -383.456561) (xy 168.157301 -383.38974) (xy 168.173272 -383.324359)
			(xy 168.196941 -383.261355) (xy 168.22797 -383.201632) (xy 168.265914 -383.146045) (xy 168.2877 -383.120392)
			(xy 168.293482 -383.113237) (xy 168.300006 -383.096054) (xy 168.3004 -383.086864) (xy 168.3004 -382.593342)
			(xy 168.29997 -382.584157) (xy 168.29347 -382.566972) (xy 168.2877 -382.559814) (xy 168.265904 -382.534169)
			(xy 168.227958 -382.478581) (xy 168.196927 -382.418856) (xy 168.173256 -382.355851) (xy 168.157285 -382.290468)
			(xy 168.149243 -382.223645) (xy 164.871179 -382.223645) (xy 164.871179 -382.223704) (xy 164.863104 -382.290641)
			(xy 164.84707 -382.35613) (xy 164.823307 -382.419226) (xy 164.792158 -382.479022) (xy 164.754071 -382.534657)
			(xy 164.732208 -382.560322) (xy 164.726421 -382.567474) (xy 164.7199 -382.584659) (xy 164.719508 -382.59385)
			(xy 164.719508 -383.086356) (xy 164.719937 -383.095541) (xy 164.726437 -383.112726) (xy 164.732208 -383.119884)
			(xy 164.754087 -383.145536) (xy 164.792175 -383.201173) (xy 164.823325 -383.260971) (xy 164.846959 -383.323727)
			(xy 165.949064 -383.323727) (xy 165.949067 -383.256419) (xy 165.957115 -383.189594) (xy 165.973092 -383.124209)
			(xy 165.996769 -383.061203) (xy 166.027808 -383.001479) (xy 166.065762 -382.945892) (xy 166.087552 -382.92024)
			(xy 166.093363 -382.913105) (xy 166.099868 -382.895907) (xy 166.100252 -382.886712) (xy 166.100252 -382.728724)
			(xy 166.10074 -382.718577) (xy 166.108519 -382.699835) (xy 166.122895 -382.685512) (xy 166.141666 -382.677803)
			(xy 166.151814 -382.677416) (xy 166.868094 -382.677416) (xy 166.878217 -382.677931) (xy 166.896934 -382.685652)
			(xy 166.911289 -382.699929) (xy 166.919113 -382.718603) (xy 166.919656 -382.728724) (xy 166.919656 -382.886712)
			(xy 166.92007 -382.895899) (xy 166.926582 -382.913082) (xy 166.932356 -382.92024) (xy 166.954108 -382.945921)
			(xy 166.992059 -383.001503) (xy 167.023094 -383.061223) (xy 167.046769 -383.124224) (xy 167.062744 -383.189602)
			(xy 167.070791 -383.256422) (xy 167.070795 -383.323724) (xy 167.062754 -383.390544) (xy 167.046785 -383.455925)
			(xy 167.023116 -383.518928) (xy 166.992086 -383.57865) (xy 166.954142 -383.634236) (xy 166.932356 -383.659888)
			(xy 166.926534 -383.667015) (xy 166.920036 -383.68422) (xy 166.919656 -383.693416) (xy 166.919656 -384.186684)
			(xy 166.920084 -384.195869) (xy 166.926586 -384.213053) (xy 166.932356 -384.220212) (xy 166.954179 -384.245835)
			(xy 166.992127 -384.301425) (xy 167.023159 -384.361153) (xy 167.04683 -384.424161) (xy 167.062801 -384.489547)
			(xy 167.070842 -384.556373) (xy 167.070839 -384.623681) (xy 167.062791 -384.690506) (xy 167.046814 -384.75589)
			(xy 167.023137 -384.818897) (xy 166.9921 -384.878621) (xy 166.954146 -384.934208) (xy 166.932356 -384.95986)
			(xy 166.926546 -384.966995) (xy 166.92004 -384.984194) (xy 166.919656 -384.993388) (xy 166.919656 -385.151376)
			(xy 166.91916 -385.161522) (xy 166.911383 -385.180263) (xy 166.89701 -385.194585) (xy 166.878241 -385.202296)
			(xy 166.868094 -385.202684) (xy 166.151814 -385.202684) (xy 166.141691 -385.202163) (xy 166.122975 -385.194444)
			(xy 166.108619 -385.180169) (xy 166.100795 -385.161496) (xy 166.100252 -385.151376) (xy 166.100252 -384.993388)
			(xy 166.099836 -384.984202) (xy 166.093325 -384.967018) (xy 166.087552 -384.95986) (xy 166.065799 -384.934179)
			(xy 166.027849 -384.878597) (xy 165.996813 -384.818877) (xy 165.973138 -384.755877) (xy 165.957162 -384.690498)
			(xy 165.949115 -384.623678) (xy 165.949111 -384.556376) (xy 165.957152 -384.489555) (xy 165.973122 -384.424175)
			(xy 165.996791 -384.361172) (xy 166.027821 -384.30145) (xy 166.065766 -384.245864) (xy 166.087552 -384.220212)
			(xy 166.093375 -384.213086) (xy 166.099872 -384.19588) (xy 166.100252 -384.186684) (xy 166.100252 -383.693416)
			(xy 166.099823 -383.684231) (xy 166.093321 -383.667047) (xy 166.087552 -383.659888) (xy 166.065728 -383.634265)
			(xy 166.02778 -383.578675) (xy 165.996747 -383.518947) (xy 165.973076 -383.455939) (xy 165.957105 -383.390553)
			(xy 165.949064 -383.323727) (xy 164.846959 -383.323727) (xy 164.847088 -383.32407) (xy 164.863122 -383.38956)
			(xy 164.871196 -383.4565) (xy 164.871195 -383.523924) (xy 164.863117 -383.590864) (xy 164.84708 -383.656353)
			(xy 164.823315 -383.719451) (xy 164.792163 -383.779248) (xy 164.754073 -383.834883) (xy 164.732208 -383.860548)
			(xy 164.726409 -383.867692) (xy 164.719896 -383.884883) (xy 164.719508 -383.894076) (xy 164.719508 -384.051556)
			(xy 164.719048 -384.061675) (xy 164.711316 -384.080376) (xy 164.697013 -384.094691) (xy 164.678318 -384.102439)
			(xy 164.6682 -384.102864) (xy 163.95192 -384.102864) (xy 163.941794 -384.102467) (xy 163.923084 -384.094719)
			(xy 163.908768 -384.080396) (xy 163.901028 -384.061682) (xy 163.900612 -384.051556) (xy 163.900612 -383.894076)
			(xy 163.900211 -383.884888) (xy 163.893691 -383.867704) (xy 163.887912 -383.860548) (xy 163.866063 -383.83487)
			(xy 163.827973 -383.779238) (xy 163.796821 -383.719443) (xy 163.773056 -383.656348) (xy 163.757019 -383.59086)
			(xy 163.748941 -383.523923) (xy 163.74894 -383.456501) (xy 163.757014 -383.389563) (xy 163.773049 -383.324075)
			(xy 163.796811 -383.260979) (xy 163.827961 -383.201183) (xy 163.866049 -383.145549) (xy 163.887912 -383.119884)
			(xy 163.893699 -383.112732) (xy 163.900219 -383.095547) (xy 163.900612 -383.086356) (xy 163.900612 -382.59385)
			(xy 163.900175 -382.584666) (xy 163.89368 -382.567481) (xy 163.887912 -382.560322) (xy 163.866038 -382.534665)
			(xy 163.827949 -382.47903) (xy 163.796798 -382.419232) (xy 163.773034 -382.356134) (xy 163.756998 -382.290644)
			(xy 163.748923 -382.223705) (xy 160.470876 -382.223705) (xy 160.46284 -382.290468) (xy 160.446866 -382.35585)
			(xy 160.423193 -382.418854) (xy 160.392159 -382.478577) (xy 160.354208 -382.534162) (xy 160.33242 -382.559814)
			(xy 160.326637 -382.566969) (xy 160.320114 -382.584152) (xy 160.31972 -382.593342) (xy 160.31972 -383.086864)
			(xy 160.320143 -383.09605) (xy 160.326647 -383.113235) (xy 160.33242 -383.120392) (xy 160.354225 -383.146031)
			(xy 160.392176 -383.201618) (xy 160.42321 -383.261343) (xy 160.446672 -383.323786) (xy 161.548769 -383.323786)
			(xy 161.548772 -383.25636) (xy 161.556851 -383.18942) (xy 161.572889 -383.123929) (xy 161.596656 -383.060831)
			(xy 161.627809 -383.001034) (xy 161.665899 -382.945398) (xy 161.687764 -382.919732) (xy 161.69358 -382.912601)
			(xy 161.700081 -382.895399) (xy 161.700464 -382.886204) (xy 161.700464 -382.728724) (xy 161.701004 -382.718621)
			(xy 161.708727 -382.69995) (xy 161.723007 -382.685656) (xy 161.74167 -382.677914) (xy 161.751772 -382.677416)
			(xy 162.468052 -382.677416) (xy 162.478173 -382.677856) (xy 162.496879 -382.685591) (xy 162.511195 -382.699901)
			(xy 162.51894 -382.718603) (xy 162.51936 -382.728724) (xy 162.51936 -382.886204) (xy 162.519777 -382.89539)
			(xy 162.526287 -382.912574) (xy 162.53206 -382.919732) (xy 162.55389 -382.945426) (xy 162.591982 -383.001055)
			(xy 162.623137 -383.060847) (xy 162.646905 -383.12394) (xy 162.662944 -383.189426) (xy 162.671023 -383.256362)
			(xy 162.671027 -383.323784) (xy 162.662954 -383.39072) (xy 162.646921 -383.456208) (xy 162.623159 -383.519303)
			(xy 162.59201 -383.579098) (xy 162.553923 -383.634731) (xy 162.53206 -383.660396) (xy 162.526278 -383.667551)
			(xy 162.519755 -383.684734) (xy 162.51936 -383.693924) (xy 162.51936 -384.186176) (xy 162.51979 -384.195361)
			(xy 162.526291 -384.212545) (xy 162.53206 -384.219704) (xy 162.553961 -384.245339) (xy 162.592051 -384.300977)
			(xy 162.623202 -384.360777) (xy 162.646966 -384.423878) (xy 162.663 -384.489371) (xy 162.671074 -384.556313)
			(xy 162.671071 -384.623741) (xy 162.662991 -384.690682) (xy 162.64695 -384.756174) (xy 162.62318 -384.819272)
			(xy 162.592023 -384.879069) (xy 162.553928 -384.934703) (xy 162.53206 -384.960368) (xy 162.526247 -384.967501)
			(xy 162.519743 -384.984701) (xy 162.51936 -384.993896) (xy 162.51936 -385.151376) (xy 162.518964 -385.161502)
			(xy 162.511216 -385.180213) (xy 162.496893 -385.194529) (xy 162.478178 -385.202268) (xy 162.468052 -385.202684)
			(xy 161.751772 -385.202684) (xy 161.741659 -385.202238) (xy 161.722978 -385.194488) (xy 161.708683 -385.180179)
			(xy 161.700952 -385.161489) (xy 161.700464 -385.151376) (xy 161.700464 -384.993896) (xy 161.700041 -384.98471)
			(xy 161.693535 -384.967527) (xy 161.687764 -384.960368) (xy 161.665937 -384.934673) (xy 161.627849 -384.879042)
			(xy 161.596699 -384.819249) (xy 161.572934 -384.756157) (xy 161.556897 -384.690671) (xy 161.548819 -384.623737)
			(xy 161.548816 -384.556317) (xy 161.556888 -384.489382) (xy 161.572918 -384.423895) (xy 161.596677 -384.3608)
			(xy 161.627821 -384.301005) (xy 161.665903 -384.24537) (xy 161.687764 -384.219704) (xy 161.693549 -384.212551)
			(xy 161.700069 -384.195366) (xy 161.700464 -384.186176) (xy 161.700464 -383.693924) (xy 161.700028 -383.68474)
			(xy 161.693531 -383.667556) (xy 161.687764 -383.660396) (xy 161.665866 -383.634759) (xy 161.627781 -383.57912)
			(xy 161.596634 -383.519319) (xy 161.572873 -383.456219) (xy 161.556841 -383.390727) (xy 161.548769 -383.323786)
			(xy 160.446672 -383.323786) (xy 160.446884 -383.32435) (xy 160.462857 -383.389734) (xy 160.470901 -383.456558)
			(xy 160.470899 -383.523866) (xy 160.462853 -383.59069) (xy 160.446877 -383.656074) (xy 160.423201 -383.719079)
			(xy 160.392163 -383.778803) (xy 160.35421 -383.834388) (xy 160.33242 -383.86004) (xy 160.326626 -383.867187)
			(xy 160.320109 -383.884376) (xy 160.31972 -383.893568) (xy 160.31972 -384.051556) (xy 160.319248 -384.061673)
			(xy 160.311518 -384.080372) (xy 160.297219 -384.094687) (xy 160.278529 -384.102437) (xy 160.268412 -384.102864)
			(xy 159.551878 -384.102864) (xy 159.54175 -384.102392) (xy 159.523029 -384.094657) (xy 159.508674 -384.080367)
			(xy 159.500855 -384.061681) (xy 159.500316 -384.051556) (xy 159.500316 -383.893568) (xy 159.499918 -383.88438)
			(xy 159.493395 -383.867196) (xy 159.487616 -383.86004) (xy 159.465845 -383.834375) (xy 159.427897 -383.77879)
			(xy 159.396864 -383.719068) (xy 159.373191 -383.656065) (xy 159.357218 -383.590684) (xy 159.349173 -383.523864)
			(xy 159.349172 -383.45656) (xy 159.357214 -383.389739) (xy 159.373184 -383.324358) (xy 159.396854 -383.261354)
			(xy 159.427884 -383.201631) (xy 159.46583 -383.146044) (xy 159.487616 -383.120392) (xy 159.4934 -383.113238)
			(xy 159.499922 -383.096054) (xy 159.500316 -383.086864) (xy 159.500316 -382.593342) (xy 159.499882 -382.584157)
			(xy 159.493384 -382.566973) (xy 159.487616 -382.559814) (xy 159.465819 -382.53417) (xy 159.427872 -382.478582)
			(xy 159.396841 -382.418857) (xy 159.373169 -382.355851) (xy 159.357198 -382.290468) (xy 159.349155 -382.223645)
			(xy 129.670829 -382.223645) (xy 129.662786 -382.290466) (xy 129.646815 -382.355847) (xy 129.623144 -382.418851)
			(xy 129.592113 -382.478575) (xy 129.554167 -382.534162) (xy 129.53238 -382.559814) (xy 129.526593 -382.566966)
			(xy 129.520073 -382.584151) (xy 129.51968 -382.593342) (xy 129.51968 -383.086864) (xy 129.520112 -383.096049)
			(xy 129.526611 -383.113233) (xy 129.53238 -383.120392) (xy 129.554183 -383.146031) (xy 129.59213 -383.20162)
			(xy 129.623162 -383.261346) (xy 129.646598 -383.323727) (xy 130.749242 -383.323727) (xy 130.749246 -383.256419)
			(xy 130.757293 -383.189594) (xy 130.77327 -383.12421) (xy 130.796946 -383.061204) (xy 130.827982 -383.00148)
			(xy 130.865935 -382.945892) (xy 130.887724 -382.92024) (xy 130.893531 -382.913103) (xy 130.900039 -382.895906)
			(xy 130.900424 -382.886712) (xy 130.900424 -382.728724) (xy 130.900842 -382.718568) (xy 130.908634 -382.699812)
			(xy 130.923032 -382.685487) (xy 130.941828 -382.67779) (xy 130.951986 -382.677416) (xy 131.668266 -382.677416)
			(xy 131.678388 -382.677954) (xy 131.697103 -382.685666) (xy 131.71146 -382.699937) (xy 131.719284 -382.718606)
			(xy 131.719828 -382.728724) (xy 131.719828 -382.886712) (xy 131.720226 -382.895901) (xy 131.726747 -382.913085)
			(xy 131.732528 -382.92024) (xy 131.754281 -382.945921) (xy 131.792233 -383.001502) (xy 131.82327 -383.061222)
			(xy 131.846946 -383.124223) (xy 131.862923 -383.189602) (xy 131.87097 -383.256422) (xy 131.870973 -383.323724)
			(xy 131.862932 -383.390545) (xy 131.846962 -383.455926) (xy 131.823292 -383.518929) (xy 131.792261 -383.578651)
			(xy 131.754314 -383.634236) (xy 131.732528 -383.659888) (xy 131.726703 -383.667013) (xy 131.720207 -383.684219)
			(xy 131.719828 -383.693416) (xy 131.719828 -384.186684) (xy 131.720239 -384.195871) (xy 131.726751 -384.213056)
			(xy 131.732528 -384.220212) (xy 131.754352 -384.245834) (xy 131.792302 -384.301424) (xy 131.823336 -384.361152)
			(xy 131.847008 -384.42416) (xy 131.86298 -384.489546) (xy 131.871021 -384.556373) (xy 131.871018 -384.623681)
			(xy 131.86297 -384.690507) (xy 131.846992 -384.755892) (xy 131.823314 -384.818898) (xy 131.792274 -384.878622)
			(xy 131.754319 -384.934208) (xy 131.732528 -384.95986) (xy 131.726715 -384.966993) (xy 131.720212 -384.984193)
			(xy 131.719828 -384.993388) (xy 131.719828 -385.151376) (xy 131.719359 -385.161525) (xy 131.711577 -385.180272)
			(xy 131.697195 -385.194595) (xy 131.678417 -385.202301) (xy 131.668266 -385.202684) (xy 130.951986 -385.202684)
			(xy 130.941861 -385.202185) (xy 130.923145 -385.194457) (xy 130.90879 -385.180175) (xy 130.900967 -385.161498)
			(xy 130.900424 -385.151376) (xy 130.900424 -384.993388) (xy 130.900014 -384.984201) (xy 130.8935 -384.967017)
			(xy 130.887724 -384.95986) (xy 130.865972 -384.934178) (xy 130.828023 -384.878596) (xy 130.796989 -384.818876)
			(xy 130.773315 -384.755876) (xy 130.75734 -384.690497) (xy 130.749294 -384.623678) (xy 130.74929 -384.556376)
			(xy 130.757331 -384.489556) (xy 130.773299 -384.424176) (xy 130.796967 -384.361173) (xy 130.827996 -384.301451)
			(xy 130.865939 -384.245865) (xy 130.887724 -384.220212) (xy 130.893543 -384.213083) (xy 130.900044 -384.19588)
			(xy 130.900424 -384.186684) (xy 130.900424 -383.693416) (xy 130.900001 -383.68423) (xy 130.893495 -383.667046)
			(xy 130.887724 -383.659888) (xy 130.865901 -383.634265) (xy 130.827955 -383.578674) (xy 130.796924 -383.518946)
			(xy 130.773254 -383.455938) (xy 130.757284 -383.390552) (xy 130.749242 -383.323727) (xy 129.646598 -383.323727)
			(xy 129.646833 -383.324352) (xy 129.662804 -383.389735) (xy 129.670846 -383.456559) (xy 129.670845 -383.523865)
			(xy 129.6628 -383.590688) (xy 129.646826 -383.656071) (xy 129.623152 -383.719076) (xy 129.592118 -383.778801)
			(xy 129.554168 -383.834388) (xy 129.53238 -383.86004) (xy 129.526582 -383.867184) (xy 129.520069 -383.884375)
			(xy 129.51968 -383.893568) (xy 129.51968 -384.051556) (xy 129.519242 -384.06171) (xy 129.511457 -384.080465)
			(xy 129.497065 -384.094791) (xy 129.478274 -384.102488) (xy 129.468118 -384.102864) (xy 128.751838 -384.102864)
			(xy 128.741714 -384.102342) (xy 128.722995 -384.094628) (xy 128.708637 -384.080352) (xy 128.700816 -384.061677)
			(xy 128.700276 -384.051556) (xy 128.700276 -383.893568) (xy 128.699886 -383.884379) (xy 128.693359 -383.867194)
			(xy 128.687576 -383.86004) (xy 128.665803 -383.834375) (xy 128.627851 -383.778792) (xy 128.596815 -383.71907)
			(xy 128.57314 -383.656067) (xy 128.557165 -383.590686) (xy 128.549119 -383.523864) (xy 128.549117 -383.45656)
			(xy 128.55716 -383.389738) (xy 128.573133 -383.324356) (xy 128.596805 -383.261352) (xy 128.627839 -383.201629)
			(xy 128.665788 -383.146044) (xy 128.687576 -383.120392) (xy 128.693356 -383.113235) (xy 128.699881 -383.096054)
			(xy 128.700276 -383.086864) (xy 128.700276 -382.593342) (xy 128.699851 -382.584156) (xy 128.693348 -382.566971)
			(xy 128.687576 -382.559814) (xy 128.665777 -382.53417) (xy 128.627826 -382.478584) (xy 128.596792 -382.418859)
			(xy 128.573118 -382.355853) (xy 128.557144 -382.29047) (xy 128.5491 -382.223646) (xy 125.271038 -382.223646)
			(xy 125.262995 -382.290466) (xy 125.247025 -382.355847) (xy 125.223354 -382.418851) (xy 125.192324 -382.478574)
			(xy 125.154378 -382.534161) (xy 125.132592 -382.559814) (xy 125.126806 -382.566967) (xy 125.120285 -382.584151)
			(xy 125.119892 -382.593342) (xy 125.119892 -383.086864) (xy 125.120321 -383.096049) (xy 125.126822 -383.113234)
			(xy 125.132592 -383.120392) (xy 125.154394 -383.146032) (xy 125.192341 -383.201621) (xy 125.223372 -383.261346)
			(xy 125.24683 -383.323787) (xy 126.348923 -383.323787) (xy 126.348926 -383.256359) (xy 126.357006 -383.189418)
			(xy 126.373047 -383.123926) (xy 126.396816 -383.060828) (xy 126.427973 -383.001031) (xy 126.466069 -382.945397)
			(xy 126.487936 -382.919732) (xy 126.493749 -382.912598) (xy 126.500253 -382.895399) (xy 126.500636 -382.886204)
			(xy 126.500636 -382.728724) (xy 126.501036 -382.718599) (xy 126.508783 -382.699889) (xy 126.523105 -382.685572)
			(xy 126.541818 -382.677832) (xy 126.551944 -382.677416) (xy 127.268224 -382.677416) (xy 127.278336 -382.677866)
			(xy 127.297018 -382.685614) (xy 127.311313 -382.699922) (xy 127.319044 -382.718611) (xy 127.319532 -382.728724)
			(xy 127.319532 -382.886204) (xy 127.319956 -382.895389) (xy 127.326462 -382.912573) (xy 127.332232 -382.919732)
			(xy 127.354059 -382.945427) (xy 127.392147 -383.001058) (xy 127.423298 -383.06085) (xy 127.447062 -383.123943)
			(xy 127.463099 -383.189428) (xy 127.471178 -383.256363) (xy 127.471181 -383.323783) (xy 127.463109 -383.390718)
			(xy 127.447078 -383.456205) (xy 127.42332 -383.5193) (xy 127.392175 -383.579096) (xy 127.354093 -383.63473)
			(xy 127.332232 -383.660396) (xy 127.326446 -383.667549) (xy 127.319927 -383.684734) (xy 127.319532 -383.693924)
			(xy 127.319532 -384.186176) (xy 127.319969 -384.19536) (xy 127.326466 -384.212544) (xy 127.332232 -384.219704)
			(xy 127.35413 -384.245341) (xy 127.392216 -384.30098) (xy 127.423363 -384.36078) (xy 127.447124 -384.423881)
			(xy 127.463156 -384.489373) (xy 127.471228 -384.556314) (xy 127.471225 -384.62374) (xy 127.463146 -384.69068)
			(xy 127.447108 -384.756171) (xy 127.423341 -384.819269) (xy 127.392188 -384.879066) (xy 127.354097 -384.934702)
			(xy 127.332232 -384.960368) (xy 127.326416 -384.967499) (xy 127.319915 -384.984701) (xy 127.319532 -384.993896)
			(xy 127.319532 -385.151376) (xy 127.318996 -385.161479) (xy 127.311272 -385.180151) (xy 127.296991 -385.194445)
			(xy 127.278327 -385.202187) (xy 127.268224 -385.202684) (xy 126.551944 -385.202684) (xy 126.541822 -385.202247)
			(xy 126.523117 -385.194511) (xy 126.5088 -385.1802) (xy 126.501056 -385.161497) (xy 126.500636 -385.151376)
			(xy 126.500636 -384.993896) (xy 126.50022 -384.98471) (xy 126.49371 -384.967526) (xy 126.487936 -384.960368)
			(xy 126.466106 -384.934674) (xy 126.428014 -384.879045) (xy 126.39686 -384.819253) (xy 126.373092 -384.756159)
			(xy 126.357053 -384.690673) (xy 126.348974 -384.623738) (xy 126.34897 -384.556316) (xy 126.357043 -384.48938)
			(xy 126.373076 -384.423892) (xy 126.396838 -384.360797) (xy 126.427986 -384.301002) (xy 126.466073 -384.245369)
			(xy 126.487936 -384.219704) (xy 126.493718 -384.212549) (xy 126.50024 -384.195366) (xy 126.500636 -384.186176)
			(xy 126.500636 -383.693924) (xy 126.500206 -383.684739) (xy 126.493705 -383.667555) (xy 126.487936 -383.660396)
			(xy 126.466035 -383.634761) (xy 126.427945 -383.579123) (xy 126.396794 -383.519323) (xy 126.373031 -383.456222)
			(xy 126.356996 -383.390729) (xy 126.348923 -383.323787) (xy 125.24683 -383.323787) (xy 125.247042 -383.324352)
			(xy 125.263013 -383.389736) (xy 125.271056 -383.456559) (xy 125.271054 -383.523865) (xy 125.263009 -383.590688)
			(xy 125.247035 -383.656071) (xy 125.223362 -383.719076) (xy 125.192328 -383.7788) (xy 125.15438 -383.834387)
			(xy 125.132592 -383.86004) (xy 125.126795 -383.867185) (xy 125.120281 -383.884376) (xy 125.119892 -383.893568)
			(xy 125.119892 -384.051556) (xy 125.119442 -384.061708) (xy 125.11166 -384.080461) (xy 125.097271 -384.094786)
			(xy 125.078484 -384.102486) (xy 125.06833 -384.102864) (xy 124.35205 -384.102864) (xy 124.341927 -384.102333)
			(xy 124.323208 -384.094622) (xy 124.30885 -384.080349) (xy 124.301028 -384.061676) (xy 124.300488 -384.051556)
			(xy 124.300488 -383.893568) (xy 124.300096 -383.884379) (xy 124.29357 -383.867194) (xy 124.287788 -383.86004)
			(xy 124.266015 -383.834376) (xy 124.228062 -383.778792) (xy 124.197025 -383.719071) (xy 124.17335 -383.656068)
			(xy 124.157374 -383.590686) (xy 124.149328 -383.523864) (xy 124.149326 -383.45656) (xy 124.15737 -383.389737)
			(xy 124.173342 -383.324355) (xy 124.197016 -383.261351) (xy 124.22805 -383.201629) (xy 124.266 -383.146043)
			(xy 124.287788 -383.120392) (xy 124.293569 -383.113236) (xy 124.300093 -383.096054) (xy 124.300488 -383.086864)
			(xy 124.300488 -382.593342) (xy 124.30006 -382.584157) (xy 124.293559 -382.566972) (xy 124.287788 -382.559814)
			(xy 124.265989 -382.534171) (xy 124.228037 -382.478584) (xy 124.197002 -382.41886) (xy 124.173327 -382.355854)
			(xy 124.157354 -382.29047) (xy 124.14931 -382.223646) (xy 120.87127 -382.223646) (xy 120.87127 -382.223704)
			(xy 120.863195 -382.290642) (xy 120.84716 -382.35613) (xy 120.823397 -382.419227) (xy 120.792247 -382.479023)
			(xy 120.75416 -382.534657) (xy 120.732296 -382.560322) (xy 120.726507 -382.567473) (xy 120.719988 -382.584659)
			(xy 120.719596 -382.59385) (xy 120.719596 -383.086356) (xy 120.720028 -383.095541) (xy 120.726527 -383.112725)
			(xy 120.732296 -383.119884) (xy 120.754176 -383.145536) (xy 120.792264 -383.201173) (xy 120.823415 -383.26097)
			(xy 120.847049 -383.323727) (xy 121.949155 -383.323727) (xy 121.949158 -383.256419) (xy 121.957206 -383.189594)
			(xy 121.973182 -383.12421) (xy 121.996859 -383.061204) (xy 122.027897 -383.001479) (xy 122.06585 -382.945892)
			(xy 122.08764 -382.92024) (xy 122.09345 -382.913104) (xy 122.099955 -382.895906) (xy 122.10034 -382.886712)
			(xy 122.10034 -382.728724) (xy 122.100742 -382.718566) (xy 122.108537 -382.699807) (xy 122.122941 -382.685481)
			(xy 122.141742 -382.677788) (xy 122.151902 -382.677416) (xy 122.868182 -382.677416) (xy 122.878305 -382.677941)
			(xy 122.897021 -382.685658) (xy 122.911377 -382.699932) (xy 122.919201 -382.718604) (xy 122.919744 -382.728724)
			(xy 122.919744 -382.886712) (xy 122.920161 -382.895898) (xy 122.926671 -382.913082) (xy 122.932444 -382.92024)
			(xy 122.954197 -382.945921) (xy 122.992148 -383.001503) (xy 123.023183 -383.061222) (xy 123.046859 -383.124223)
			(xy 123.062835 -383.189602) (xy 123.070882 -383.256422) (xy 123.070886 -383.323724) (xy 123.062845 -383.390545)
			(xy 123.046875 -383.455925) (xy 123.023206 -383.518928) (xy 122.992176 -383.57865) (xy 122.95423 -383.634236)
			(xy 122.932444 -383.659888) (xy 122.926621 -383.667014) (xy 122.920124 -383.684219) (xy 122.919744 -383.693416)
			(xy 122.919744 -384.186684) (xy 122.920174 -384.195869) (xy 122.926675 -384.213053) (xy 122.932444 -384.220212)
			(xy 122.954268 -384.245835) (xy 122.992217 -384.301425) (xy 123.023249 -384.361152) (xy 123.046921 -384.424161)
			(xy 123.062892 -384.489547) (xy 123.070933 -384.556373) (xy 123.07093 -384.623681) (xy 123.062882 -384.690507)
			(xy 123.046905 -384.755891) (xy 123.023227 -384.818897) (xy 122.992189 -384.878622) (xy 122.954235 -384.934208)
			(xy 122.932444 -384.95986) (xy 122.926633 -384.966994) (xy 122.920128 -384.984193) (xy 122.919744 -384.993388)
			(xy 122.919744 -385.151376) (xy 122.91926 -385.161523) (xy 122.91148 -385.180267) (xy 122.897103 -385.194589)
			(xy 122.878331 -385.202298) (xy 122.868182 -385.202684) (xy 122.151902 -385.202684) (xy 122.141778 -385.202172)
			(xy 122.123062 -385.19445) (xy 122.108706 -385.180171) (xy 122.100883 -385.161497) (xy 122.10034 -385.151376)
			(xy 122.10034 -384.993388) (xy 122.099927 -384.984201) (xy 122.093414 -384.967017) (xy 122.08764 -384.95986)
			(xy 122.065888 -384.934179) (xy 122.027938 -384.878596) (xy 121.996903 -384.818877) (xy 121.973228 -384.755876)
			(xy 121.957253 -384.690498) (xy 121.949206 -384.623678) (xy 121.949202 -384.556376) (xy 121.957243 -384.489556)
			(xy 121.973212 -384.424176) (xy 121.996881 -384.361173) (xy 122.02791 -384.30145) (xy 122.065855 -384.245864)
			(xy 122.08764 -384.220212) (xy 122.093461 -384.213085) (xy 122.09996 -384.19588) (xy 122.10034 -384.186684)
			(xy 122.10034 -383.693416) (xy 122.099913 -383.684231) (xy 122.09341 -383.667047) (xy 122.08764 -383.659888)
			(xy 122.065817 -383.634265) (xy 122.027869 -383.578674) (xy 121.996837 -383.518947) (xy 121.973166 -383.455939)
			(xy 121.957196 -383.390553) (xy 121.949155 -383.323727) (xy 120.847049 -383.323727) (xy 120.847178 -383.324069)
			(xy 120.863212 -383.38956) (xy 120.871287 -383.4565) (xy 120.871286 -383.523925) (xy 120.863208 -383.590864)
			(xy 120.847171 -383.656354) (xy 120.823405 -383.719452) (xy 120.792252 -383.779248) (xy 120.754161 -383.834883)
			(xy 120.732296 -383.860548) (xy 120.726496 -383.867691) (xy 120.719984 -383.884883) (xy 120.719596 -383.894076)
			(xy 120.719596 -384.051556) (xy 120.719148 -384.061676) (xy 120.711413 -384.080379) (xy 120.697106 -384.094695)
			(xy 120.678408 -384.102441) (xy 120.668288 -384.102864) (xy 119.952008 -384.102864) (xy 119.941882 -384.102477)
			(xy 119.923171 -384.094724) (xy 119.908855 -384.080399) (xy 119.901116 -384.061683) (xy 119.9007 -384.051556)
			(xy 119.9007 -383.894076) (xy 119.900302 -383.884888) (xy 119.89378 -383.867703) (xy 119.888 -383.860548)
			(xy 119.866152 -383.83487) (xy 119.828063 -383.779237) (xy 119.796911 -383.719443) (xy 119.773146 -383.656348)
			(xy 119.75711 -383.59086) (xy 119.749032 -383.523923) (xy 119.749031 -383.456501) (xy 119.757105 -383.389564)
			(xy 119.773139 -383.324075) (xy 119.796901 -383.260979) (xy 119.82805 -383.201184) (xy 119.866137 -383.145549)
			(xy 119.888 -383.119884) (xy 119.893786 -383.112731) (xy 119.900307 -383.095547) (xy 119.9007 -383.086356)
			(xy 119.9007 -382.59385) (xy 119.900266 -382.584665) (xy 119.893769 -382.567481) (xy 119.888 -382.560322)
			(xy 119.866126 -382.534665) (xy 119.828038 -382.479029) (xy 119.796888 -382.419232) (xy 119.773124 -382.356134)
			(xy 119.757089 -382.290644) (xy 119.749014 -382.223705) (xy 116.470967 -382.223705) (xy 116.46293 -382.290468)
			(xy 116.446957 -382.35585) (xy 116.423283 -382.418855) (xy 116.392248 -382.478577) (xy 116.354297 -382.534163)
			(xy 116.332508 -382.559814) (xy 116.326724 -382.566968) (xy 116.320202 -382.584152) (xy 116.319808 -382.593342)
			(xy 116.319808 -383.086864) (xy 116.320234 -383.09605) (xy 116.326736 -383.113234) (xy 116.332508 -383.120392)
			(xy 116.354313 -383.146031) (xy 116.392265 -383.201618) (xy 116.4233 -383.261343) (xy 116.446764 -383.323787)
			(xy 117.548835 -383.323787) (xy 117.548838 -383.256359) (xy 117.556918 -383.189418) (xy 117.572959 -383.123926)
			(xy 117.59673 -383.060827) (xy 117.627888 -383.00103) (xy 117.665984 -382.945396) (xy 117.687852 -382.919732)
			(xy 117.693666 -382.9126) (xy 117.700169 -382.895399) (xy 117.700552 -382.886204) (xy 117.700552 -382.728724)
			(xy 117.701103 -382.718623) (xy 117.708824 -382.699954) (xy 117.7231 -382.68566) (xy 117.741759 -382.677916)
			(xy 117.75186 -382.677416) (xy 118.46814 -382.677416) (xy 118.478253 -382.677853) (xy 118.496935 -382.685607)
			(xy 118.511229 -382.699918) (xy 118.51896 -382.71861) (xy 118.519448 -382.728724) (xy 118.519448 -382.886204)
			(xy 118.519868 -382.89539) (xy 118.526376 -382.912574) (xy 118.532148 -382.919732) (xy 118.553978 -382.945426)
			(xy 118.592072 -383.001055) (xy 118.623227 -383.060847) (xy 118.646995 -383.12394) (xy 118.663035 -383.189426)
			(xy 118.671114 -383.256362) (xy 118.671118 -383.323784) (xy 118.663045 -383.390721) (xy 118.647011 -383.456208)
			(xy 118.623249 -383.519304) (xy 118.592099 -383.579099) (xy 118.554012 -383.634732) (xy 118.532148 -383.660396)
			(xy 118.526364 -383.66755) (xy 118.519843 -383.684734) (xy 118.519448 -383.693924) (xy 118.519448 -384.186176)
			(xy 118.519881 -384.195361) (xy 118.52638 -384.212545) (xy 118.532148 -384.219704) (xy 118.554049 -384.245339)
			(xy 118.59214 -384.300977) (xy 118.623292 -384.360777) (xy 118.647057 -384.423878) (xy 118.663091 -384.489371)
			(xy 118.671165 -384.556313) (xy 118.671162 -384.623741) (xy 118.663082 -384.690682) (xy 118.647041 -384.756174)
			(xy 118.62327 -384.819273) (xy 118.592112 -384.87907) (xy 118.554016 -384.934704) (xy 118.532148 -384.960368)
			(xy 118.526334 -384.9675) (xy 118.519831 -384.984701) (xy 118.519448 -384.993896) (xy 118.519448 -385.151376)
			(xy 118.518897 -385.161477) (xy 118.511176 -385.180146) (xy 118.4969 -385.19444) (xy 118.478241 -385.202184)
			(xy 118.46814 -385.202684) (xy 117.75186 -385.202684) (xy 117.741747 -385.202247) (xy 117.723065 -385.194493)
			(xy 117.708771 -385.180182) (xy 117.70104 -385.16149) (xy 117.700552 -385.151376) (xy 117.700552 -384.993896)
			(xy 117.700132 -384.98471) (xy 117.693624 -384.967526) (xy 117.687852 -384.960368) (xy 117.666022 -384.934674)
			(xy 117.627928 -384.879045) (xy 117.596773 -384.819253) (xy 117.573005 -384.75616) (xy 117.556965 -384.690674)
			(xy 117.548886 -384.623738) (xy 117.548882 -384.556316) (xy 117.556955 -384.489379) (xy 117.572989 -384.423892)
			(xy 117.596751 -384.360796) (xy 117.627901 -384.301001) (xy 117.665988 -384.245368) (xy 117.687852 -384.219704)
			(xy 117.693636 -384.21255) (xy 117.700157 -384.195366) (xy 117.700552 -384.186176) (xy 117.700552 -383.693924)
			(xy 117.700119 -383.684739) (xy 117.69362 -383.667555) (xy 117.687852 -383.660396) (xy 117.665951 -383.634761)
			(xy 117.62786 -383.579123) (xy 117.596708 -383.519323) (xy 117.572943 -383.456222) (xy 117.556909 -383.390729)
			(xy 117.548835 -383.323787) (xy 116.446764 -383.323787) (xy 116.446975 -383.324349) (xy 116.462948 -383.389733)
			(xy 116.470992 -383.456558) (xy 116.47099 -383.523866) (xy 116.462944 -383.59069) (xy 116.446967 -383.656074)
			(xy 116.423291 -383.719079) (xy 116.392252 -383.778803) (xy 116.354298 -383.834389) (xy 116.332508 -383.86004)
			(xy 116.326713 -383.867186) (xy 116.320197 -383.884376) (xy 116.319808 -383.893568) (xy 116.319808 -384.051556)
			(xy 116.319342 -384.061706) (xy 116.311563 -384.080456) (xy 116.297179 -384.094781) (xy 116.278398 -384.102483)
			(xy 116.268246 -384.102864) (xy 115.551966 -384.102864) (xy 115.541838 -384.102401) (xy 115.523116 -384.094663)
			(xy 115.508761 -384.08037) (xy 115.500943 -384.061682) (xy 115.500404 -384.051556) (xy 115.500404 -383.893568)
			(xy 115.500009 -383.884379) (xy 115.493485 -383.867195) (xy 115.487704 -383.86004) (xy 115.465933 -383.834374)
			(xy 115.427986 -383.778789) (xy 115.396954 -383.719067) (xy 115.373282 -383.656064) (xy 115.357309 -383.590684)
			(xy 115.349264 -383.523864) (xy 115.349262 -383.45656) (xy 115.357305 -383.38974) (xy 115.373275 -383.324359)
			(xy 115.396944 -383.261355) (xy 115.427974 -383.201632) (xy 115.465918 -383.146045) (xy 115.487704 -383.120392)
			(xy 115.493487 -383.113237) (xy 115.50001 -383.096054) (xy 115.500404 -383.086864) (xy 115.500404 -382.593342)
			(xy 115.499973 -382.584157) (xy 115.493474 -382.566973) (xy 115.487704 -382.559814) (xy 115.465908 -382.534169)
			(xy 115.427961 -382.478581) (xy 115.39693 -382.418856) (xy 115.37326 -382.355851) (xy 115.357288 -382.290468)
			(xy 115.349246 -382.223645) (xy 90.070711 -382.223645) (xy 90.062667 -382.290467) (xy 90.046695 -382.355848)
			(xy 90.023023 -382.418852) (xy 89.991991 -382.478576) (xy 89.954043 -382.534162) (xy 89.932256 -382.559814)
			(xy 89.926465 -382.566963) (xy 89.919948 -382.584151) (xy 89.919556 -382.593342) (xy 89.919556 -383.086864)
			(xy 89.919994 -383.096048) (xy 89.926489 -383.113232) (xy 89.932256 -383.120392) (xy 89.95406 -383.146031)
			(xy 89.992008 -383.201619) (xy 90.023041 -383.261345) (xy 90.046478 -383.323726) (xy 91.149124 -383.323726)
			(xy 91.149128 -383.256419) (xy 91.157175 -383.189595) (xy 91.17315 -383.124211) (xy 91.196825 -383.061205)
			(xy 91.227861 -383.001481) (xy 91.265811 -382.945893) (xy 91.2876 -382.92024) (xy 91.293405 -382.9131)
			(xy 91.299914 -382.895906) (xy 91.3003 -382.886712) (xy 91.3003 -382.728724) (xy 91.300741 -382.718571)
			(xy 91.308529 -382.699819) (xy 91.32292 -382.685495) (xy 91.341708 -382.677795) (xy 91.351862 -382.677416)
			(xy 92.068142 -382.677416) (xy 92.078268 -382.677891) (xy 92.096986 -382.685629) (xy 92.11134 -382.699918)
			(xy 92.119162 -382.7186) (xy 92.119704 -382.728724) (xy 92.119704 -382.886712) (xy 92.120108 -382.8959)
			(xy 92.126626 -382.913084) (xy 92.132404 -382.92024) (xy 92.154155 -382.945922) (xy 92.192102 -383.001505)
			(xy 92.223135 -383.061225) (xy 92.246808 -383.124225) (xy 92.262782 -383.189604) (xy 92.270828 -383.256422)
			(xy 92.270831 -383.323724) (xy 92.262791 -383.390543) (xy 92.246824 -383.455923) (xy 92.223157 -383.518926)
			(xy 92.19213 -383.578648) (xy 92.154188 -383.634235) (xy 92.132404 -383.659888) (xy 92.126588 -383.66702)
			(xy 92.120085 -383.68422) (xy 92.119704 -383.693416) (xy 92.119704 -384.186684) (xy 92.120121 -384.19587)
			(xy 92.12663 -384.213055) (xy 92.132404 -384.220212) (xy 92.154226 -384.245836) (xy 92.192171 -384.301427)
			(xy 92.2232 -384.361155) (xy 92.246869 -384.424163) (xy 92.262838 -384.489548) (xy 92.270879 -384.556374)
			(xy 92.270875 -384.623681) (xy 92.262828 -384.690505) (xy 92.246853 -384.755889) (xy 92.223178 -384.818894)
			(xy 92.192143 -384.878619) (xy 92.154193 -384.934207) (xy 92.132404 -384.95986) (xy 92.1266 -384.967)
			(xy 92.12009 -384.984194) (xy 92.119704 -384.993388) (xy 92.119704 -385.151376) (xy 92.119259 -385.161528)
			(xy 92.111472 -385.180279) (xy 92.097082 -385.194603) (xy 92.078296 -385.202305) (xy 92.068142 -385.202684)
			(xy 91.351862 -385.202684) (xy 91.341736 -385.202205) (xy 91.323018 -385.194469) (xy 91.308664 -385.180181)
			(xy 91.300842 -385.1615) (xy 91.3003 -385.151376) (xy 91.3003 -384.993388) (xy 91.299895 -384.9842)
			(xy 91.293378 -384.967016) (xy 91.2876 -384.95986) (xy 91.265849 -384.934178) (xy 91.227901 -384.878595)
			(xy 91.196869 -384.818875) (xy 91.173196 -384.755875) (xy 91.157221 -384.690497) (xy 91.149175 -384.623678)
			(xy 91.149172 -384.556376) (xy 91.157212 -384.489557) (xy 91.17318 -384.424177) (xy 91.196847 -384.361174)
			(xy 91.227874 -384.301451) (xy 91.265816 -384.245865) (xy 91.2876 -384.220212) (xy 91.293416 -384.213081)
			(xy 91.299919 -384.19588) (xy 91.3003 -384.186684) (xy 91.3003 -383.693416) (xy 91.299882 -383.68423)
			(xy 91.293374 -383.667045) (xy 91.2876 -383.659888) (xy 91.265778 -383.634264) (xy 91.227833 -383.578673)
			(xy 91.196803 -383.518945) (xy 91.173134 -383.455937) (xy 91.157165 -383.390552) (xy 91.149124 -383.323726)
			(xy 90.046478 -383.323726) (xy 90.046713 -383.324351) (xy 90.062685 -383.389735) (xy 90.070728 -383.456559)
			(xy 90.070727 -383.523865) (xy 90.062681 -383.590689) (xy 90.046706 -383.656072) (xy 90.023031 -383.719077)
			(xy 89.991996 -383.778801) (xy 89.954045 -383.834388) (xy 89.932256 -383.86004) (xy 89.926454 -383.867181)
			(xy 89.919944 -383.884375) (xy 89.919556 -383.893568) (xy 89.919556 -384.051556) (xy 89.919043 -384.0617)
			(xy 89.911273 -384.080441) (xy 89.896905 -384.094764) (xy 89.87814 -384.102475) (xy 89.867994 -384.102864)
			(xy 89.151714 -384.102864) (xy 89.141589 -384.102362) (xy 89.122869 -384.09464) (xy 89.108512 -384.080358)
			(xy 89.100692 -384.061679) (xy 89.100152 -384.051556) (xy 89.100152 -383.893568) (xy 89.099745 -383.884381)
			(xy 89.093228 -383.867197) (xy 89.087452 -383.86004) (xy 89.06568 -383.834375) (xy 89.02773 -383.778791)
			(xy 88.996695 -383.719069) (xy 88.973021 -383.656066) (xy 88.957046 -383.590685) (xy 88.949001 -383.523864)
			(xy 88.948999 -383.45656) (xy 88.957042 -383.389738) (xy 88.973014 -383.324357) (xy 88.996685 -383.261353)
			(xy 89.027717 -383.20163) (xy 89.065665 -383.146044) (xy 89.087452 -383.120392) (xy 89.093241 -383.113242)
			(xy 89.099759 -383.096055) (xy 89.100152 -383.086864) (xy 89.100152 -382.593342) (xy 89.09971 -382.584158)
			(xy 89.093217 -382.566975) (xy 89.087452 -382.559814) (xy 89.065654 -382.53417) (xy 89.027704 -382.478583)
			(xy 88.996671 -382.418858) (xy 88.972998 -382.355853) (xy 88.957025 -382.290469) (xy 88.948982 -382.223646)
			(xy 85.670943 -382.223646) (xy 85.670943 -382.223704) (xy 85.662867 -382.290643) (xy 85.646832 -382.356132)
			(xy 85.623067 -382.419228) (xy 85.591915 -382.479024) (xy 85.553825 -382.534657) (xy 85.53196 -382.560322)
			(xy 85.526167 -382.567469) (xy 85.519651 -382.584658) (xy 85.51926 -382.59385) (xy 85.51926 -383.086356)
			(xy 85.5197 -383.09554) (xy 85.526194 -383.112724) (xy 85.53196 -383.119884) (xy 85.553841 -383.145536)
			(xy 85.591932 -383.201171) (xy 85.623084 -383.260969) (xy 85.646743 -383.323786) (xy 86.748805 -383.323786)
			(xy 86.748808 -383.25636) (xy 86.756888 -383.189419) (xy 86.772927 -383.123927) (xy 86.796696 -383.060829)
			(xy 86.827852 -383.001032) (xy 86.865945 -382.945397) (xy 86.887812 -382.919732) (xy 86.893621 -382.912596)
			(xy 86.900128 -382.895398) (xy 86.900512 -382.886204) (xy 86.900512 -382.728724) (xy 86.900936 -382.718602)
			(xy 86.908678 -382.699896) (xy 86.922993 -382.685581) (xy 86.941698 -382.677837) (xy 86.95182 -382.677416)
			(xy 87.6681 -382.677416) (xy 87.678224 -382.677816) (xy 87.696931 -382.685568) (xy 87.711246 -382.699889)
			(xy 87.718988 -382.718599) (xy 87.719408 -382.728724) (xy 87.719408 -382.886204) (xy 87.719815 -382.895392)
			(xy 87.726331 -382.912576) (xy 87.732108 -382.919732) (xy 87.753936 -382.945427) (xy 87.792026 -383.001057)
			(xy 87.823177 -383.060849) (xy 87.846943 -383.123942) (xy 87.862981 -383.189428) (xy 87.87106 -383.256363)
			(xy 87.871063 -383.323783) (xy 87.862991 -383.390719) (xy 87.846959 -383.456206) (xy 87.8232 -383.519301)
			(xy 87.792053 -383.579096) (xy 87.75397 -383.634731) (xy 87.732108 -383.660396) (xy 87.726332 -383.667556)
			(xy 87.719805 -383.684735) (xy 87.719408 -383.693924) (xy 87.719408 -384.186176) (xy 87.719828 -384.195362)
			(xy 87.726335 -384.212547) (xy 87.732108 -384.219704) (xy 87.754007 -384.24534) (xy 87.792094 -384.300979)
			(xy 87.823243 -384.360779) (xy 87.847005 -384.42388) (xy 87.863037 -384.489373) (xy 87.87111 -384.556314)
			(xy 87.871107 -384.62374) (xy 87.863028 -384.690681) (xy 87.846989 -384.756172) (xy 87.823221 -384.81927)
			(xy 87.792066 -384.879067) (xy 87.753974 -384.934703) (xy 87.732108 -384.960368) (xy 87.726301 -384.967506)
			(xy 87.719792 -384.984702) (xy 87.719408 -384.993896) (xy 87.719408 -385.151376) (xy 87.718965 -385.161496)
			(xy 87.711226 -385.180198) (xy 87.696918 -385.194512) (xy 87.67822 -385.20226) (xy 87.6681 -385.202684)
			(xy 86.95182 -385.202684) (xy 86.941697 -385.202267) (xy 86.922991 -385.194523) (xy 86.908675 -385.180206)
			(xy 86.900932 -385.161499) (xy 86.900512 -385.151376) (xy 86.900512 -384.993896) (xy 86.900101 -384.984709)
			(xy 86.893587 -384.967525) (xy 86.887812 -384.960368) (xy 86.865983 -384.934674) (xy 86.827892 -384.879044)
			(xy 86.796739 -384.819252) (xy 86.772973 -384.756158) (xy 86.756934 -384.690673) (xy 86.748855 -384.623738)
			(xy 86.748852 -384.556316) (xy 86.756925 -384.48938) (xy 86.772957 -384.423893) (xy 86.796717 -384.360798)
			(xy 86.827865 -384.301003) (xy 86.86595 -384.245369) (xy 86.887812 -384.219704) (xy 86.893591 -384.212546)
			(xy 86.900116 -384.195365) (xy 86.900512 -384.186176) (xy 86.900512 -383.693924) (xy 86.900088 -383.684738)
			(xy 86.893583 -383.667554) (xy 86.887812 -383.660396) (xy 86.865912 -383.63476) (xy 86.827824 -383.579122)
			(xy 86.796674 -383.519322) (xy 86.772911 -383.456221) (xy 86.756878 -383.390728) (xy 86.748805 -383.323786)
			(xy 85.646743 -383.323786) (xy 85.646849 -383.324068) (xy 85.662885 -383.389559) (xy 85.67096 -383.456499)
			(xy 85.670959 -383.523925) (xy 85.662881 -383.590865) (xy 85.646842 -383.656355) (xy 85.623074 -383.719453)
			(xy 85.59192 -383.77925) (xy 85.553826 -383.834883) (xy 85.53196 -383.860548) (xy 85.526156 -383.867687)
			(xy 85.519647 -383.884883) (xy 85.51926 -383.894076) (xy 85.51926 -384.051556) (xy 85.518847 -384.061681)
			(xy 85.511106 -384.080391) (xy 85.496787 -384.094708) (xy 85.478077 -384.102448) (xy 85.467952 -384.102864)
			(xy 84.751672 -384.102864) (xy 84.741543 -384.102506) (xy 84.722832 -384.094742) (xy 84.708517 -384.080407)
			(xy 84.70078 -384.061685) (xy 84.700364 -384.051556) (xy 84.700364 -383.894076) (xy 84.699951 -383.884889)
			(xy 84.693438 -383.867706) (xy 84.687664 -383.860548) (xy 84.665817 -383.834869) (xy 84.62773 -383.779236)
			(xy 84.596581 -383.719441) (xy 84.572817 -383.656346) (xy 84.556782 -383.590859) (xy 84.548705 -383.523923)
			(xy 84.548704 -383.456501) (xy 84.556778 -383.389565) (xy 84.57281 -383.324077) (xy 84.596571 -383.260981)
			(xy 84.627718 -383.201185) (xy 84.665802 -383.14555) (xy 84.687664 -383.119884) (xy 84.693458 -383.112737)
			(xy 84.699972 -383.095548) (xy 84.700364 -383.086356) (xy 84.700364 -382.59385) (xy 84.699916 -382.584667)
			(xy 84.693427 -382.567483) (xy 84.687664 -382.560322) (xy 84.665791 -382.534664) (xy 84.627705 -382.479028)
			(xy 84.596557 -382.41923) (xy 84.572795 -382.356132) (xy 84.556761 -382.290643) (xy 84.548687 -382.223704)
			(xy 81.271152 -382.223704) (xy 81.263076 -382.290642) (xy 81.247041 -382.356131) (xy 81.223277 -382.419228)
			(xy 81.192126 -382.479023) (xy 81.154036 -382.534657) (xy 81.132172 -382.560322) (xy 81.12638 -382.56747)
			(xy 81.119863 -382.584659) (xy 81.119472 -382.59385) (xy 81.119472 -383.086356) (xy 81.11991 -383.09554)
			(xy 81.126405 -383.112724) (xy 81.132172 -383.119884) (xy 81.154053 -383.145536) (xy 81.192143 -383.201172)
			(xy 81.223294 -383.260969) (xy 81.246931 -383.323727) (xy 82.349036 -383.323727) (xy 82.34904 -383.256419)
			(xy 82.357087 -383.189595) (xy 82.373063 -383.124211) (xy 82.396739 -383.061205) (xy 82.427775 -383.00148)
			(xy 82.465727 -382.945892) (xy 82.487516 -382.92024) (xy 82.493322 -382.913102) (xy 82.499831 -382.895906)
			(xy 82.500216 -382.886712) (xy 82.500216 -382.728724) (xy 82.500636 -382.718601) (xy 82.508379 -382.699895)
			(xy 82.522695 -382.685579) (xy 82.541401 -382.677836) (xy 82.551524 -382.677416) (xy 83.268058 -382.677416)
			(xy 83.278179 -382.67796) (xy 83.296895 -382.68567) (xy 83.311252 -382.699938) (xy 83.319076 -382.718606)
			(xy 83.31962 -382.728724) (xy 83.31962 -382.886712) (xy 83.32002 -382.8959) (xy 83.32654 -382.913085)
			(xy 83.33232 -382.92024) (xy 83.354074 -382.945921) (xy 83.392026 -383.001502) (xy 83.423063 -383.061221)
			(xy 83.44674 -383.124222) (xy 83.462717 -383.189601) (xy 83.470764 -383.256421) (xy 83.470767 -383.323724)
			(xy 83.462726 -383.390545) (xy 83.446756 -383.455926) (xy 83.423085 -383.518929) (xy 83.392054 -383.578651)
			(xy 83.354107 -383.634236) (xy 83.33232 -383.659888) (xy 83.326506 -383.667021) (xy 83.320001 -383.684221)
			(xy 83.31962 -383.693416) (xy 83.31962 -384.186684) (xy 83.320033 -384.195871) (xy 83.326544 -384.213056)
			(xy 83.33232 -384.220212) (xy 83.354144 -384.245835) (xy 83.392095 -384.301424) (xy 83.423129 -384.361152)
			(xy 83.446801 -384.42416) (xy 83.462773 -384.489546) (xy 83.470815 -384.556373) (xy 83.470812 -384.623681)
			(xy 83.462763 -384.690507) (xy 83.446785 -384.755892) (xy 83.423107 -384.818898) (xy 83.392067 -384.878622)
			(xy 83.354111 -384.934208) (xy 83.33232 -384.95986) (xy 83.326518 -384.967001) (xy 83.320006 -384.984195)
			(xy 83.31962 -384.993388) (xy 83.31962 -385.151376) (xy 83.319165 -385.161494) (xy 83.311428 -385.180194)
			(xy 83.297124 -385.194508) (xy 83.27843 -385.202258) (xy 83.268312 -385.202684) (xy 82.551778 -385.202684)
			(xy 82.541653 -385.202192) (xy 82.522936 -385.194462) (xy 82.508581 -385.180178) (xy 82.500758 -385.161499)
			(xy 82.500216 -385.151376) (xy 82.500216 -384.993388) (xy 82.499808 -384.984201) (xy 82.493293 -384.967016)
			(xy 82.487516 -384.95986) (xy 82.465765 -384.934178) (xy 82.427816 -384.878595) (xy 82.396783 -384.818876)
			(xy 82.373109 -384.755875) (xy 82.357134 -384.690497) (xy 82.349088 -384.623678) (xy 82.349084 -384.556376)
			(xy 82.357125 -384.489556) (xy 82.373093 -384.424177) (xy 82.396761 -384.361174) (xy 82.427788 -384.301451)
			(xy 82.465731 -384.245865) (xy 82.487516 -384.220212) (xy 82.493334 -384.213082) (xy 82.499835 -384.19588)
			(xy 82.500216 -384.186684) (xy 82.500216 -383.693416) (xy 82.499794 -383.68423) (xy 82.493288 -383.667046)
			(xy 82.487516 -383.659888) (xy 82.465694 -383.634265) (xy 82.427747 -383.578674) (xy 82.396717 -383.518946)
			(xy 82.373047 -383.455938) (xy 82.357077 -383.390552) (xy 82.349036 -383.323727) (xy 81.246931 -383.323727)
			(xy 81.247059 -383.324068) (xy 81.263094 -383.389559) (xy 81.271169 -383.456499) (xy 81.271168 -383.523925)
			(xy 81.26309 -383.590865) (xy 81.247052 -383.656355) (xy 81.223285 -383.719453) (xy 81.19213 -383.779249)
			(xy 81.154038 -383.834883) (xy 81.132172 -383.860548) (xy 81.126369 -383.867688) (xy 81.119859 -383.884883)
			(xy 81.119472 -383.894076) (xy 81.119472 -384.051556) (xy 81.119047 -384.061679) (xy 81.111308 -384.080387)
			(xy 81.096994 -384.094704) (xy 81.078287 -384.102446) (xy 81.068164 -384.102864) (xy 80.351884 -384.102864)
			(xy 80.341756 -384.102496) (xy 80.323045 -384.094736) (xy 80.30873 -384.080405) (xy 80.300992 -384.061685)
			(xy 80.300576 -384.051556) (xy 80.300576 -383.894076) (xy 80.300183 -383.884887) (xy 80.293658 -383.867703)
			(xy 80.287876 -383.860548) (xy 80.266029 -383.834869) (xy 80.227941 -383.779236) (xy 80.196791 -383.719442)
			(xy 80.173027 -383.656347) (xy 80.156991 -383.590859) (xy 80.148914 -383.523923) (xy 80.148913 -383.456501)
			(xy 80.156987 -383.389564) (xy 80.17302 -383.324076) (xy 80.196781 -383.26098) (xy 80.227929 -383.201184)
			(xy 80.266014 -383.14555) (xy 80.287876 -383.119884) (xy 80.293659 -383.112729) (xy 80.300183 -383.095546)
			(xy 80.300576 -383.086356) (xy 80.300576 -382.59385) (xy 80.300147 -382.584665) (xy 80.293647 -382.56748)
			(xy 80.287876 -382.560322) (xy 80.266003 -382.534664) (xy 80.227916 -382.479028) (xy 80.196767 -382.419231)
			(xy 80.173005 -382.356133) (xy 80.156971 -382.290643) (xy 80.148896 -382.223704) (xy 76.870825 -382.223704)
			(xy 76.862789 -382.290466) (xy 76.846818 -382.355847) (xy 76.823147 -382.418851) (xy 76.792117 -382.478575)
			(xy 76.75417 -382.534162) (xy 76.732384 -382.559814) (xy 76.726597 -382.566966) (xy 76.720077 -382.584151)
			(xy 76.719684 -382.593342) (xy 76.719684 -383.086864) (xy 76.720115 -383.096049) (xy 76.726615 -383.113233)
			(xy 76.732384 -383.120392) (xy 76.754187 -383.146031) (xy 76.792134 -383.20162) (xy 76.823165 -383.261346)
			(xy 76.846624 -383.323787) (xy 77.948717 -383.323787) (xy 77.94872 -383.256359) (xy 77.9568 -383.189418)
			(xy 77.97284 -383.123927) (xy 77.99661 -383.060828) (xy 78.027766 -383.001031) (xy 78.065861 -382.945397)
			(xy 78.087728 -382.919732) (xy 78.09354 -382.912598) (xy 78.100045 -382.895399) (xy 78.100428 -382.886204)
			(xy 78.100428 -382.728724) (xy 78.100836 -382.7186) (xy 78.108582 -382.699891) (xy 78.122901 -382.685575)
			(xy 78.141611 -382.677834) (xy 78.151736 -382.677416) (xy 78.868016 -382.677416) (xy 78.878142 -382.677803)
			(xy 78.896849 -382.685559) (xy 78.911163 -382.699885) (xy 78.918905 -382.718598) (xy 78.919324 -382.728724)
			(xy 78.919324 -382.886204) (xy 78.919727 -382.895392) (xy 78.926245 -382.912577) (xy 78.932024 -382.919732)
			(xy 78.953852 -382.945427) (xy 78.99194 -383.001058) (xy 79.023091 -383.06085) (xy 79.046856 -383.123943)
			(xy 79.062893 -383.189428) (xy 79.070972 -383.256363) (xy 79.070975 -383.323783) (xy 79.062903 -383.390719)
			(xy 79.046872 -383.456205) (xy 79.023113 -383.519301) (xy 78.991968 -383.579096) (xy 78.953885 -383.63473)
			(xy 78.932024 -383.660396) (xy 78.926249 -383.667557) (xy 78.919721 -383.684735) (xy 78.919324 -383.693924)
			(xy 78.919324 -384.186176) (xy 78.91974 -384.195363) (xy 78.926249 -384.212547) (xy 78.932024 -384.219704)
			(xy 78.953922 -384.24534) (xy 78.992009 -384.30098) (xy 79.023156 -384.36078) (xy 79.046917 -384.423881)
			(xy 79.06295 -384.489373) (xy 79.071022 -384.556314) (xy 79.071019 -384.62374) (xy 79.06294 -384.69068)
			(xy 79.046901 -384.756171) (xy 79.023134 -384.819269) (xy 78.991981 -384.879067) (xy 78.953889 -384.934702)
			(xy 78.932024 -384.960368) (xy 78.926219 -384.967507) (xy 78.919709 -384.984702) (xy 78.919324 -384.993896)
			(xy 78.919324 -385.151376) (xy 78.918865 -385.161494) (xy 78.911129 -385.180193) (xy 78.896826 -385.194507)
			(xy 78.878134 -385.202257) (xy 78.868016 -385.202684) (xy 78.151736 -385.202684) (xy 78.141614 -385.202254)
			(xy 78.122908 -385.194515) (xy 78.108592 -385.180202) (xy 78.100848 -385.161498) (xy 78.100428 -385.151376)
			(xy 78.100428 -384.993896) (xy 78.100014 -384.984709) (xy 78.093502 -384.967525) (xy 78.087728 -384.960368)
			(xy 78.065898 -384.934674) (xy 78.027807 -384.879044) (xy 77.996653 -384.819252) (xy 77.972886 -384.756159)
			(xy 77.956847 -384.690673) (xy 77.948768 -384.623738) (xy 77.948764 -384.556316) (xy 77.956837 -384.48938)
			(xy 77.972869 -384.423893) (xy 77.996631 -384.360797) (xy 78.027779 -384.301002) (xy 78.065865 -384.245369)
			(xy 78.087728 -384.219704) (xy 78.093509 -384.212548) (xy 78.100032 -384.195366) (xy 78.100428 -384.186176)
			(xy 78.100428 -383.693924) (xy 78.1 -383.684739) (xy 78.093498 -383.667555) (xy 78.087728 -383.660396)
			(xy 78.065828 -383.63476) (xy 78.027738 -383.579122) (xy 77.996587 -383.519322) (xy 77.972824 -383.456221)
			(xy 77.95679 -383.390728) (xy 77.948717 -383.323787) (xy 76.846624 -383.323787) (xy 76.846836 -383.324352)
			(xy 76.862807 -383.389735) (xy 76.870849 -383.456559) (xy 76.870848 -383.523865) (xy 76.862803 -383.590688)
			(xy 76.846829 -383.656071) (xy 76.823155 -383.719076) (xy 76.792121 -383.7788) (xy 76.754172 -383.834388)
			(xy 76.732384 -383.86004) (xy 76.726586 -383.867184) (xy 76.720073 -383.884376) (xy 76.719684 -383.893568)
			(xy 76.719684 -384.051556) (xy 76.719242 -384.061709) (xy 76.711458 -384.080464) (xy 76.697067 -384.094789)
			(xy 76.678277 -384.102488) (xy 76.668122 -384.102864) (xy 75.951842 -384.102864) (xy 75.941718 -384.102339)
			(xy 75.922999 -384.094626) (xy 75.908642 -384.080351) (xy 75.90082 -384.061677) (xy 75.90028 -384.051556)
			(xy 75.90028 -383.893568) (xy 75.89989 -383.884379) (xy 75.893363 -383.867194) (xy 75.88758 -383.86004)
			(xy 75.865807 -383.834375) (xy 75.827855 -383.778792) (xy 75.796819 -383.71907) (xy 75.773143 -383.656067)
			(xy 75.757168 -383.590686) (xy 75.749122 -383.523864) (xy 75.74912 -383.45656) (xy 75.757164 -383.389738)
			(xy 75.773136 -383.324356) (xy 75.796809 -383.261352) (xy 75.827842 -383.201629) (xy 75.865792 -383.146044)
			(xy 75.88758 -383.120392) (xy 75.89336 -383.113235) (xy 75.899885 -383.096054) (xy 75.90028 -383.086864)
			(xy 75.90028 -382.593342) (xy 75.899854 -382.584156) (xy 75.893352 -382.566972) (xy 75.88758 -382.559814)
			(xy 75.865781 -382.53417) (xy 75.82783 -382.478584) (xy 75.796795 -382.418859) (xy 75.773121 -382.355854)
			(xy 75.757147 -382.29047) (xy 75.749104 -382.223646) (xy 72.471064 -382.223646) (xy 72.471064 -382.223704)
			(xy 72.462989 -382.290642) (xy 72.446954 -382.356131) (xy 72.42319 -382.419227) (xy 72.39204 -382.479023)
			(xy 72.353952 -382.534657) (xy 72.332088 -382.560322) (xy 72.326298 -382.567472) (xy 72.31978 -382.584659)
			(xy 72.319388 -382.59385) (xy 72.319388 -383.086356) (xy 72.319822 -383.095541) (xy 72.326319 -383.112725)
			(xy 72.332088 -383.119884) (xy 72.353968 -383.145536) (xy 72.392057 -383.201172) (xy 72.423208 -383.26097)
			(xy 72.446843 -383.323727) (xy 73.548949 -383.323727) (xy 73.548952 -383.256419) (xy 73.556999 -383.189594)
			(xy 73.572976 -383.12421) (xy 73.596652 -383.061204) (xy 73.62769 -383.001479) (xy 73.665642 -382.945892)
			(xy 73.687432 -382.92024) (xy 73.693241 -382.913103) (xy 73.699747 -382.895906) (xy 73.700132 -382.886712)
			(xy 73.700132 -382.728724) (xy 73.700542 -382.718567) (xy 73.708335 -382.699809) (xy 73.722736 -382.685484)
			(xy 73.741535 -382.677789) (xy 73.751694 -382.677416) (xy 74.467974 -382.677416) (xy 74.478096 -382.677947)
			(xy 74.496812 -382.685662) (xy 74.511169 -382.699934) (xy 74.518993 -382.718605) (xy 74.519536 -382.728724)
			(xy 74.519536 -382.886712) (xy 74.519955 -382.895898) (xy 74.526464 -382.913082) (xy 74.532236 -382.92024)
			(xy 74.553989 -382.945921) (xy 74.591941 -383.001503) (xy 74.622977 -383.061222) (xy 74.646653 -383.124223)
			(xy 74.662629 -383.189602) (xy 74.670676 -383.256422) (xy 74.670679 -383.323724) (xy 74.662639 -383.390545)
			(xy 74.646669 -383.455925) (xy 74.622999 -383.518928) (xy 74.591968 -383.578651) (xy 74.554022 -383.634236)
			(xy 74.532236 -383.659888) (xy 74.526412 -383.667013) (xy 74.519915 -383.684219) (xy 74.519536 -383.693416)
			(xy 74.519536 -384.186684) (xy 74.519968 -384.195869) (xy 74.526468 -384.213052) (xy 74.532236 -384.220212)
			(xy 74.55406 -384.245835) (xy 74.592009 -384.301425) (xy 74.623043 -384.361152) (xy 74.646714 -384.424161)
			(xy 74.662686 -384.489547) (xy 74.670727 -384.556373) (xy 74.670724 -384.623681) (xy 74.662676 -384.690507)
			(xy 74.646698 -384.755891) (xy 74.623021 -384.818897) (xy 74.591982 -384.878622) (xy 74.554027 -384.934208)
			(xy 74.532236 -384.95986) (xy 74.526424 -384.966994) (xy 74.51992 -384.984193) (xy 74.519536 -384.993388)
			(xy 74.519536 -385.151376) (xy 74.51906 -385.161524) (xy 74.511279 -385.180269) (xy 74.496899 -385.194592)
			(xy 74.478124 -385.202299) (xy 74.467974 -385.202684) (xy 73.751694 -385.202684) (xy 73.74157 -385.202179)
			(xy 73.722853 -385.194454) (xy 73.708498 -385.180173) (xy 73.700675 -385.161497) (xy 73.700132 -385.151376)
			(xy 73.700132 -384.993388) (xy 73.699721 -384.984201) (xy 73.693207 -384.967017) (xy 73.687432 -384.95986)
			(xy 73.66568 -384.934178) (xy 73.627731 -384.878596) (xy 73.596696 -384.818877) (xy 73.573022 -384.755876)
			(xy 73.557047 -384.690497) (xy 73.549 -384.623678) (xy 73.548996 -384.556376) (xy 73.557037 -384.489556)
			(xy 73.573006 -384.424176) (xy 73.596674 -384.361173) (xy 73.627703 -384.30145) (xy 73.665647 -384.245864)
			(xy 73.687432 -384.220212) (xy 73.693253 -384.213084) (xy 73.699752 -384.19588) (xy 73.700132 -384.186684)
			(xy 73.700132 -383.693416) (xy 73.699707 -383.684231) (xy 73.693203 -383.667046) (xy 73.687432 -383.659888)
			(xy 73.665609 -383.634265) (xy 73.627662 -383.578674) (xy 73.59663 -383.518946) (xy 73.57296 -383.455938)
			(xy 73.55699 -383.390553) (xy 73.548949 -383.323727) (xy 72.446843 -383.323727) (xy 72.446972 -383.324069)
			(xy 72.463006 -383.38956) (xy 72.471081 -383.456499) (xy 72.47108 -383.523925) (xy 72.463002 -383.590864)
			(xy 72.446964 -383.656354) (xy 72.423198 -383.719452) (xy 72.392045 -383.779248) (xy 72.353953 -383.834883)
			(xy 72.332088 -383.860548) (xy 72.326287 -383.86769) (xy 72.319775 -383.884883) (xy 72.319388 -383.894076)
			(xy 72.319388 -384.051556) (xy 72.318948 -384.061677) (xy 72.311212 -384.080382) (xy 72.296902 -384.094698)
			(xy 72.278201 -384.102443) (xy 72.26808 -384.102864) (xy 71.5518 -384.102864) (xy 71.541673 -384.102483)
			(xy 71.522963 -384.094728) (xy 71.508647 -384.0804) (xy 71.500908 -384.061683) (xy 71.500492 -384.051556)
			(xy 71.500492 -383.894076) (xy 71.500095 -383.884887) (xy 71.493572 -383.867703) (xy 71.487792 -383.860548)
			(xy 71.465944 -383.83487) (xy 71.427855 -383.779237) (xy 71.396704 -383.719442) (xy 71.37294 -383.656347)
			(xy 71.356903 -383.59086) (xy 71.348826 -383.523923) (xy 71.348825 -383.456501) (xy 71.356899 -383.389564)
			(xy 71.372933 -383.324076) (xy 71.396695 -383.26098) (xy 71.427843 -383.201184) (xy 71.465929 -383.145549)
			(xy 71.487792 -383.119884) (xy 71.493577 -383.11273) (xy 71.500099 -383.095546) (xy 71.500492 -383.086356)
			(xy 71.500492 -382.59385) (xy 71.50006 -382.584665) (xy 71.493562 -382.56748) (xy 71.487792 -382.560322)
			(xy 71.465918 -382.534665) (xy 71.427831 -382.479029) (xy 71.396681 -382.419231) (xy 71.372918 -382.356134)
			(xy 71.356883 -382.290644) (xy 71.348808 -382.223705) (xy 46.070794 -382.223705) (xy 46.062758 -382.290467)
			(xy 46.046786 -382.355849) (xy 46.023113 -382.418853) (xy 45.99208 -382.478576) (xy 45.954131 -382.534162)
			(xy 45.932344 -382.559814) (xy 45.926552 -382.566962) (xy 45.920036 -382.584151) (xy 45.919644 -382.593342)
			(xy 45.919644 -383.086864) (xy 45.920084 -383.096048) (xy 45.926578 -383.113232) (xy 45.932344 -383.120392)
			(xy 45.954148 -383.146031) (xy 45.992098 -383.201619) (xy 46.023131 -383.261344) (xy 46.04657 -383.323727)
			(xy 47.149191 -383.323727) (xy 47.149195 -383.256419) (xy 47.157243 -383.189593) (xy 47.173221 -383.124208)
			(xy 47.1969 -383.061202) (xy 47.22794 -383.001477) (xy 47.265897 -382.945892) (xy 47.287688 -382.92024)
			(xy 47.293491 -382.913099) (xy 47.300002 -382.895905) (xy 47.300388 -382.886712) (xy 47.300388 -382.728724)
			(xy 47.300841 -382.718573) (xy 47.308626 -382.699823) (xy 47.323013 -382.685499) (xy 47.341797 -382.677797)
			(xy 47.35195 -382.677416) (xy 48.06823 -382.677416) (xy 48.078356 -382.677901) (xy 48.097073 -382.685634)
			(xy 48.111427 -382.699921) (xy 48.11925 -382.718601) (xy 48.119792 -382.728724) (xy 48.119792 -382.886712)
			(xy 48.120198 -382.8959) (xy 48.126715 -382.913084) (xy 48.132492 -382.92024) (xy 48.154243 -382.945922)
			(xy 48.192191 -383.001505) (xy 48.223224 -383.061224) (xy 48.246898 -383.124225) (xy 48.262872 -383.189603)
			(xy 48.270919 -383.256422) (xy 48.270922 -383.323724) (xy 48.262882 -383.390543) (xy 48.246914 -383.455923)
			(xy 48.223247 -383.518926) (xy 48.192219 -383.578649) (xy 48.154277 -383.634236) (xy 48.132492 -383.659888)
			(xy 48.126675 -383.667018) (xy 48.120173 -383.68422) (xy 48.119792 -383.693416) (xy 48.119792 -384.186684)
			(xy 48.120212 -384.19587) (xy 48.126719 -384.213054) (xy 48.132492 -384.220212) (xy 48.154314 -384.245835)
			(xy 48.19226 -384.301427) (xy 48.22329 -384.361155) (xy 48.246959 -384.424163) (xy 48.262929 -384.489548)
			(xy 48.27097 -384.556373) (xy 48.270966 -384.623681) (xy 48.262919 -384.690505) (xy 48.246943 -384.755889)
			(xy 48.223268 -384.818895) (xy 48.192232 -384.87862) (xy 48.154281 -384.934207) (xy 48.132492 -384.95986)
			(xy 48.126687 -384.966999) (xy 48.120177 -384.984194) (xy 48.119792 -384.993388) (xy 48.119792 -385.151376)
			(xy 48.119359 -385.16153) (xy 48.11157 -385.180283) (xy 48.097176 -385.194608) (xy 48.078386 -385.202307)
			(xy 48.06823 -385.202684) (xy 47.35195 -385.202684) (xy 47.341829 -385.202133) (xy 47.323114 -385.194426)
			(xy 47.308757 -385.18016) (xy 47.300932 -385.161493) (xy 47.300388 -385.151376) (xy 47.300388 -384.993388)
			(xy 47.299986 -384.9842) (xy 47.293467 -384.967016) (xy 47.287688 -384.95986) (xy 47.265934 -384.934179)
			(xy 47.227981 -384.878598) (xy 47.196944 -384.818879) (xy 47.173267 -384.755878) (xy 47.15729 -384.690499)
			(xy 47.149242 -384.623679) (xy 47.149239 -384.556376) (xy 47.15728 -384.489554) (xy 47.173251 -384.424174)
			(xy 47.196921 -384.361171) (xy 47.227953 -384.301448) (xy 47.265901 -384.245863) (xy 47.287688 -384.220212)
			(xy 47.293503 -384.21308) (xy 47.300007 -384.195879) (xy 47.300388 -384.186684) (xy 47.300388 -383.693416)
			(xy 47.299973 -383.684229) (xy 47.293463 -383.667045) (xy 47.287688 -383.659888) (xy 47.265863 -383.634266)
			(xy 47.227913 -383.578676) (xy 47.196878 -383.518949) (xy 47.173205 -383.45594) (xy 47.157233 -383.390554)
			(xy 47.149191 -383.323727) (xy 46.04657 -383.323727) (xy 46.046804 -383.32435) (xy 46.062776 -383.389734)
			(xy 46.070819 -383.456559) (xy 46.070818 -383.523865) (xy 46.062772 -383.590689) (xy 46.046797 -383.656073)
			(xy 46.023121 -383.719078) (xy 45.992085 -383.778802) (xy 45.954133 -383.834388) (xy 45.932344 -383.86004)
			(xy 45.926541 -383.86718) (xy 45.920032 -383.884375) (xy 45.919644 -383.893568) (xy 45.919644 -384.051556)
			(xy 45.919143 -384.061702) (xy 45.91137 -384.080445) (xy 45.896998 -384.094768) (xy 45.878229 -384.102477)
			(xy 45.868082 -384.102864) (xy 45.151802 -384.102864) (xy 45.141676 -384.102372) (xy 45.122956 -384.094645)
			(xy 45.108599 -384.080361) (xy 45.100779 -384.06168) (xy 45.10024 -384.051556) (xy 45.10024 -383.893568)
			(xy 45.099836 -383.88438) (xy 45.093317 -383.867197) (xy 45.08754 -383.86004) (xy 45.065768 -383.834375)
			(xy 45.027819 -383.77879) (xy 44.996785 -383.719068) (xy 44.973111 -383.656066) (xy 44.957137 -383.590685)
			(xy 44.949092 -383.523864) (xy 44.94909 -383.45656) (xy 44.957133 -383.389739) (xy 44.973104 -383.324357)
			(xy 44.996775 -383.261354) (xy 45.027806 -383.20163) (xy 45.065753 -383.146044) (xy 45.08754 -383.120392)
			(xy 45.093328 -383.113241) (xy 45.099847 -383.096055) (xy 45.10024 -383.086864) (xy 45.10024 -382.593342)
			(xy 45.0998 -382.584158) (xy 45.093306 -382.566974) (xy 45.08754 -382.559814) (xy 45.065742 -382.53417)
			(xy 45.027794 -382.478582) (xy 44.996761 -382.418858) (xy 44.973088 -382.355852) (xy 44.957116 -382.290469)
			(xy 44.949073 -382.223645) (xy 41.671034 -382.223645) (xy 41.671034 -382.223704) (xy 41.662958 -382.290643)
			(xy 41.646922 -382.356132) (xy 41.623157 -382.419229) (xy 41.592004 -382.479024) (xy 41.553913 -382.534658)
			(xy 41.532048 -382.560322) (xy 41.526253 -382.567468) (xy 41.519739 -382.584658) (xy 41.519348 -382.59385)
			(xy 41.519348 -383.086356) (xy 41.519791 -383.095539) (xy 41.526283 -383.112723) (xy 41.532048 -383.119884)
			(xy 41.55393 -383.145535) (xy 41.592021 -383.201171) (xy 41.623174 -383.260968) (xy 41.646834 -383.323786)
			(xy 42.748896 -383.323786) (xy 42.748899 -383.25636) (xy 42.756978 -383.189419) (xy 42.773018 -383.123928)
			(xy 42.796786 -383.06083) (xy 42.827941 -383.001032) (xy 42.866034 -382.945397) (xy 42.8879 -382.919732)
			(xy 42.893708 -382.912595) (xy 42.900216 -382.895398) (xy 42.9006 -382.886204) (xy 42.9006 -382.728724)
			(xy 42.901035 -382.718603) (xy 42.908776 -382.6999) (xy 42.923086 -382.685585) (xy 42.941787 -382.677839)
			(xy 42.951908 -382.677416) (xy 43.668188 -382.677416) (xy 43.678312 -382.677826) (xy 43.697018 -382.685573)
			(xy 43.711333 -382.699892) (xy 43.719076 -382.7186) (xy 43.719496 -382.728724) (xy 43.719496 -382.886204)
			(xy 43.719905 -382.895391) (xy 43.72642 -382.912575) (xy 43.732196 -382.919732) (xy 43.754025 -382.945426)
			(xy 43.792115 -383.001057) (xy 43.823267 -383.060849) (xy 43.847034 -383.123942) (xy 43.863072 -383.189427)
			(xy 43.871151 -383.256363) (xy 43.871154 -383.323783) (xy 43.863081 -383.390719) (xy 43.84705 -383.456206)
			(xy 43.823289 -383.519302) (xy 43.792143 -383.579097) (xy 43.754058 -383.634731) (xy 43.732196 -383.660396)
			(xy 43.726418 -383.667554) (xy 43.719892 -383.684735) (xy 43.719496 -383.693924) (xy 43.719496 -384.186176)
			(xy 43.719919 -384.195362) (xy 43.726424 -384.212546) (xy 43.732196 -384.219704) (xy 43.754095 -384.24534)
			(xy 43.792183 -384.300979) (xy 43.823333 -384.360779) (xy 43.847095 -384.42388) (xy 43.863128 -384.489372)
			(xy 43.871201 -384.556314) (xy 43.871198 -384.62374) (xy 43.863118 -384.690681) (xy 43.847079 -384.756172)
			(xy 43.823311 -384.819271) (xy 43.792156 -384.879068) (xy 43.754062 -384.934703) (xy 43.732196 -384.960368)
			(xy 43.726388 -384.967505) (xy 43.71988 -384.984702) (xy 43.719496 -384.993896) (xy 43.719496 -385.151376)
			(xy 43.719064 -385.161497) (xy 43.711323 -385.180201) (xy 43.697011 -385.194517) (xy 43.678309 -385.202262)
			(xy 43.668188 -385.202684) (xy 42.951908 -385.202684) (xy 42.941784 -385.202277) (xy 42.923078 -385.194529)
			(xy 42.908762 -385.180209) (xy 42.90102 -385.1615) (xy 42.9006 -385.151376) (xy 42.9006 -384.993896)
			(xy 42.900192 -384.984709) (xy 42.893677 -384.967524) (xy 42.8879 -384.960368) (xy 42.866071 -384.934674)
			(xy 42.827982 -384.879043) (xy 42.796829 -384.819251) (xy 42.773063 -384.756158) (xy 42.757025 -384.690672)
			(xy 42.748946 -384.623737) (xy 42.748943 -384.556317) (xy 42.757015 -384.489381) (xy 42.773047 -384.423894)
			(xy 42.796807 -384.360798) (xy 42.827954 -384.301003) (xy 42.866038 -384.245369) (xy 42.8879 -384.219704)
			(xy 42.893677 -384.212545) (xy 42.900204 -384.195365) (xy 42.9006 -384.186176) (xy 42.9006 -383.693924)
			(xy 42.900178 -383.684738) (xy 42.893673 -383.667554) (xy 42.8879 -383.660396) (xy 42.866001 -383.63476)
			(xy 42.827913 -383.579121) (xy 42.796764 -383.519321) (xy 42.773002 -383.45622) (xy 42.756969 -383.390728)
			(xy 42.748896 -383.323786) (xy 41.646834 -383.323786) (xy 41.64694 -383.324067) (xy 41.662976 -383.389558)
			(xy 41.671051 -383.456499) (xy 41.67105 -383.523925) (xy 41.662971 -383.590865) (xy 41.646933 -383.656356)
			(xy 41.623164 -383.719454) (xy 41.592009 -383.77925) (xy 41.553915 -383.834884) (xy 41.532048 -383.860548)
			(xy 41.526242 -383.867686) (xy 41.519734 -383.884882) (xy 41.519348 -383.894076) (xy 41.519348 -384.051556)
			(xy 41.518849 -384.06167) (xy 41.511124 -384.080363) (xy 41.496834 -384.094677) (xy 41.478153 -384.102432)
			(xy 41.46804 -384.102864) (xy 40.75176 -384.102864) (xy 40.74163 -384.102516) (xy 40.722919 -384.094748)
			(xy 40.708605 -384.08041) (xy 40.700868 -384.061686) (xy 40.700452 -384.051556) (xy 40.700452 -383.894076)
			(xy 40.700042 -383.884889) (xy 40.693527 -383.867705) (xy 40.687752 -383.860548) (xy 40.665902 -383.834871)
			(xy 40.627809 -383.779239) (xy 40.596655 -383.719445) (xy 40.572888 -383.65635) (xy 40.556849 -383.590862)
			(xy 40.548772 -383.523924) (xy 40.54877 -383.4565) (xy 40.556845 -383.389562) (xy 40.572881 -383.324073)
			(xy 40.596645 -383.260977) (xy 40.627797 -383.201182) (xy 40.665887 -383.145548) (xy 40.687752 -383.119884)
			(xy 40.693544 -383.112736) (xy 40.70006 -383.095547) (xy 40.700452 -383.086356) (xy 40.700452 -382.59385)
			(xy 40.700006 -382.584667) (xy 40.693516 -382.567483) (xy 40.687752 -382.560322) (xy 40.665876 -382.534666)
			(xy 40.627785 -382.479031) (xy 40.596631 -382.419234) (xy 40.572865 -382.356136) (xy 40.556829 -382.290645)
			(xy 40.548753 -382.223705) (xy 37.271243 -382.223705) (xy 37.263167 -382.290643) (xy 37.247132 -382.356132)
			(xy 37.223367 -382.419228) (xy 37.192215 -382.479024) (xy 37.154125 -382.534657) (xy 37.13226 -382.560322)
			(xy 37.126467 -382.567469) (xy 37.119951 -382.584658) (xy 37.11956 -382.59385) (xy 37.11956 -383.086356)
			(xy 37.12 -383.09554) (xy 37.126494 -383.112724) (xy 37.13226 -383.119884) (xy 37.154141 -383.145536)
			(xy 37.192232 -383.201171) (xy 37.223384 -383.260969) (xy 37.247021 -383.323727) (xy 38.349127 -383.323727)
			(xy 38.349131 -383.256419) (xy 38.357178 -383.189595) (xy 38.373154 -383.124211) (xy 38.396829 -383.061205)
			(xy 38.427864 -383.00148) (xy 38.465815 -382.945893) (xy 38.487604 -382.92024) (xy 38.493409 -382.913101)
			(xy 38.499919 -382.895906) (xy 38.500304 -382.886712) (xy 38.500304 -382.728724) (xy 38.500741 -382.718571)
			(xy 38.50853 -382.699818) (xy 38.522922 -382.685494) (xy 38.541711 -382.677794) (xy 38.551866 -382.677416)
			(xy 39.268146 -382.677416) (xy 39.278273 -382.677888) (xy 39.29699 -382.685627) (xy 39.311344 -382.699917)
			(xy 39.319166 -382.7186) (xy 39.319708 -382.728724) (xy 39.319708 -382.886712) (xy 39.320111 -382.8959)
			(xy 39.326629 -382.913084) (xy 39.332408 -382.92024) (xy 39.354162 -382.945921) (xy 39.392115 -383.001502)
			(xy 39.423153 -383.061221) (xy 39.44683 -383.124222) (xy 39.462807 -383.189601) (xy 39.470855 -383.256421)
			(xy 39.470858 -383.323725) (xy 39.462817 -383.390546) (xy 39.446846 -383.455926) (xy 39.423175 -383.51893)
			(xy 39.392143 -383.578652) (xy 39.354195 -383.634237) (xy 39.332408 -383.659888) (xy 39.326592 -383.66702)
			(xy 39.320089 -383.684221) (xy 39.319708 -383.693416) (xy 39.319708 -384.186684) (xy 39.320124 -384.195871)
			(xy 39.326633 -384.213055) (xy 39.332408 -384.220212) (xy 39.354233 -384.245834) (xy 39.392184 -384.301424)
			(xy 39.423219 -384.361151) (xy 39.446892 -384.42416) (xy 39.462864 -384.489546) (xy 39.470906 -384.556373)
			(xy 39.470902 -384.623682) (xy 39.462854 -384.690507) (xy 39.446876 -384.755892) (xy 39.423196 -384.818898)
			(xy 39.392156 -384.878623) (xy 39.354199 -384.934209) (xy 39.332408 -384.95986) (xy 39.326604 -384.967)
			(xy 39.320094 -384.984195) (xy 39.319708 -384.993388) (xy 39.319708 -385.151376) (xy 39.319259 -385.161528)
			(xy 39.311473 -385.180278) (xy 39.297085 -385.194602) (xy 39.278299 -385.202304) (xy 39.268146 -385.202684)
			(xy 38.551866 -385.202684) (xy 38.54174 -385.202202) (xy 38.523023 -385.194468) (xy 38.508668 -385.18018)
			(xy 38.500846 -385.1615) (xy 38.500304 -385.151376) (xy 38.500304 -384.993388) (xy 38.499899 -384.9842)
			(xy 38.493381 -384.967016) (xy 38.487604 -384.95986) (xy 38.465853 -384.934178) (xy 38.427905 -384.878595)
			(xy 38.396872 -384.818875) (xy 38.373199 -384.755875) (xy 38.357224 -384.690497) (xy 38.349178 -384.623678)
			(xy 38.349175 -384.556376) (xy 38.357215 -384.489557) (xy 38.373183 -384.424177) (xy 38.39685 -384.361174)
			(xy 38.427877 -384.301451) (xy 38.465819 -384.245865) (xy 38.487604 -384.220212) (xy 38.493421 -384.213081)
			(xy 38.499923 -384.19588) (xy 38.500304 -384.186684) (xy 38.500304 -383.693416) (xy 38.499885 -383.68423)
			(xy 38.493377 -383.667045) (xy 38.487604 -383.659888) (xy 38.465782 -383.634264) (xy 38.427837 -383.578673)
			(xy 38.396807 -383.518945) (xy 38.373138 -383.455937) (xy 38.357168 -383.390552) (xy 38.349127 -383.323727)
			(xy 37.247021 -383.323727) (xy 37.247149 -383.324068) (xy 37.263185 -383.389559) (xy 37.27126 -383.456499)
			(xy 37.271259 -383.523925) (xy 37.263181 -383.590865) (xy 37.247142 -383.656355) (xy 37.223374 -383.719453)
			(xy 37.19222 -383.77925) (xy 37.154126 -383.834883) (xy 37.13226 -383.860548) (xy 37.126456 -383.867687)
			(xy 37.119947 -383.884883) (xy 37.11956 -383.894076) (xy 37.11956 -384.051556) (xy 37.119147 -384.061681)
			(xy 37.111406 -384.080391) (xy 37.097087 -384.094708) (xy 37.078377 -384.102448) (xy 37.068252 -384.102864)
			(xy 36.351972 -384.102864) (xy 36.341843 -384.102506) (xy 36.323132 -384.094742) (xy 36.308817 -384.080407)
			(xy 36.30108 -384.061685) (xy 36.300664 -384.051556) (xy 36.300664 -383.894076) (xy 36.300251 -383.884889)
			(xy 36.293738 -383.867706) (xy 36.287964 -383.860548) (xy 36.266117 -383.834869) (xy 36.22803 -383.779236)
			(xy 36.196881 -383.719441) (xy 36.173117 -383.656346) (xy 36.157082 -383.590859) (xy 36.149005 -383.523923)
			(xy 36.149004 -383.456501) (xy 36.157078 -383.389565) (xy 36.17311 -383.324077) (xy 36.196871 -383.260981)
			(xy 36.228018 -383.201185) (xy 36.266102 -383.14555) (xy 36.287964 -383.119884) (xy 36.293758 -383.112737)
			(xy 36.300272 -383.095548) (xy 36.300664 -383.086356) (xy 36.300664 -382.59385) (xy 36.300216 -382.584667)
			(xy 36.293727 -382.567483) (xy 36.287964 -382.560322) (xy 36.266091 -382.534664) (xy 36.228005 -382.479028)
			(xy 36.196857 -382.41923) (xy 36.173095 -382.356132) (xy 36.157061 -382.290643) (xy 36.148987 -382.223704)
			(xy 32.870916 -382.223704) (xy 32.86288 -382.290466) (xy 32.846909 -382.355848) (xy 32.823237 -382.418852)
			(xy 32.792206 -382.478575) (xy 32.754259 -382.534162) (xy 32.732472 -382.559814) (xy 32.726683 -382.566965)
			(xy 32.720165 -382.584151) (xy 32.719772 -382.593342) (xy 32.719772 -383.086864) (xy 32.720206 -383.096049)
			(xy 32.726704 -383.113233) (xy 32.732472 -383.120392) (xy 32.754275 -383.146031) (xy 32.792223 -383.20162)
			(xy 32.823255 -383.261345) (xy 32.846714 -383.323786) (xy 33.948808 -383.323786) (xy 33.948811 -383.25636)
			(xy 33.956891 -383.189419) (xy 33.972931 -383.123927) (xy 33.996699 -383.060829) (xy 34.027855 -383.001032)
			(xy 34.065949 -382.945397) (xy 34.087816 -382.919732) (xy 34.093626 -382.912596) (xy 34.100132 -382.895398)
			(xy 34.100516 -382.886204) (xy 34.100516 -382.728724) (xy 34.100936 -382.718601) (xy 34.108679 -382.699895)
			(xy 34.122995 -382.685579) (xy 34.141701 -382.677836) (xy 34.151824 -382.677416) (xy 34.868104 -382.677416)
			(xy 34.878229 -382.677813) (xy 34.896935 -382.685566) (xy 34.91125 -382.699888) (xy 34.918992 -382.718599)
			(xy 34.919412 -382.728724) (xy 34.919412 -382.886204) (xy 34.919818 -382.895392) (xy 34.926334 -382.912576)
			(xy 34.932112 -382.919732) (xy 34.95394 -382.945427) (xy 34.992029 -383.001057) (xy 35.023181 -383.060849)
			(xy 35.046946 -383.123942) (xy 35.062984 -383.189428) (xy 35.071063 -383.256363) (xy 35.071066 -383.323783)
			(xy 35.062994 -383.390719) (xy 35.046962 -383.456206) (xy 35.023203 -383.519301) (xy 34.992057 -383.579096)
			(xy 34.953973 -383.634731) (xy 34.932112 -383.660396) (xy 34.926336 -383.667556) (xy 34.919809 -383.684735)
			(xy 34.919412 -383.693924) (xy 34.919412 -384.186176) (xy 34.919831 -384.195362) (xy 34.926338 -384.212547)
			(xy 34.932112 -384.219704) (xy 34.954011 -384.24534) (xy 34.992098 -384.300979) (xy 35.023246 -384.36078)
			(xy 35.047008 -384.42388) (xy 35.06304 -384.489373) (xy 35.071113 -384.556314) (xy 35.07111 -384.62374)
			(xy 35.063031 -384.690681) (xy 35.046992 -384.756172) (xy 35.023224 -384.81927) (xy 34.99207 -384.879067)
			(xy 34.953978 -384.934703) (xy 34.932112 -384.960368) (xy 34.926305 -384.967506) (xy 34.919796 -384.984702)
			(xy 34.919412 -384.993896) (xy 34.919412 -385.151376) (xy 34.918965 -385.161495) (xy 34.911227 -385.180196)
			(xy 34.89692 -385.194511) (xy 34.878223 -385.202259) (xy 34.868104 -385.202684) (xy 34.151824 -385.202684)
			(xy 34.141701 -385.202264) (xy 34.122995 -385.194521) (xy 34.108679 -385.180205) (xy 34.100936 -385.161499)
			(xy 34.100516 -385.151376) (xy 34.100516 -384.993896) (xy 34.100104 -384.984709) (xy 34.093591 -384.967525)
			(xy 34.087816 -384.960368) (xy 34.065987 -384.934674) (xy 34.027896 -384.879044) (xy 33.996743 -384.819252)
			(xy 33.972976 -384.756159) (xy 33.956937 -384.690673) (xy 33.948858 -384.623738) (xy 33.948855 -384.556316)
			(xy 33.956928 -384.48938) (xy 33.97296 -384.423893) (xy 33.996721 -384.360798) (xy 34.027868 -384.301003)
			(xy 34.065954 -384.245369) (xy 34.087816 -384.219704) (xy 34.093595 -384.212547) (xy 34.10012 -384.195365)
			(xy 34.100516 -384.186176) (xy 34.100516 -383.693924) (xy 34.100091 -383.684739) (xy 34.093587 -383.667554)
			(xy 34.087816 -383.660396) (xy 34.065916 -383.63476) (xy 34.027827 -383.579122) (xy 33.996677 -383.519322)
			(xy 33.972915 -383.456221) (xy 33.956881 -383.390728) (xy 33.948808 -383.323786) (xy 32.846714 -383.323786)
			(xy 32.846926 -383.324351) (xy 32.862898 -383.389735) (xy 32.87094 -383.456559) (xy 32.870939 -383.523865)
			(xy 32.862893 -383.590689) (xy 32.846919 -383.656072) (xy 32.823245 -383.719077) (xy 32.79221 -383.778801)
			(xy 32.75426 -383.834388) (xy 32.732472 -383.86004) (xy 32.726672 -383.867183) (xy 32.72016 -383.884375)
			(xy 32.719772 -383.893568) (xy 32.719772 -384.051556) (xy 32.719342 -384.061711) (xy 32.711555 -384.080468)
			(xy 32.697161 -384.094793) (xy 32.678367 -384.10249) (xy 32.66821 -384.102864) (xy 31.95193 -384.102864)
			(xy 31.941806 -384.102349) (xy 31.923086 -384.094632) (xy 31.908729 -384.080354) (xy 31.900908 -384.061678)
			(xy 31.900368 -384.051556) (xy 31.900368 -383.893568) (xy 31.899958 -383.884381) (xy 31.893443 -383.867197)
			(xy 31.887668 -383.86004) (xy 31.865895 -383.834375) (xy 31.827944 -383.778791) (xy 31.796908 -383.71907)
			(xy 31.773234 -383.656067) (xy 31.757259 -383.590686) (xy 31.749213 -383.523864) (xy 31.749211 -383.45656)
			(xy 31.757254 -383.389738) (xy 31.773226 -383.324356) (xy 31.796899 -383.261352) (xy 31.827932 -383.201629)
			(xy 31.86588 -383.146044) (xy 31.887668 -383.120392) (xy 31.893459 -383.113243) (xy 31.899975 -383.096055)
			(xy 31.900368 -383.086864) (xy 31.900368 -382.593342) (xy 31.899923 -382.584159) (xy 31.893432 -382.566975)
			(xy 31.887668 -382.559814) (xy 31.86587 -382.53417) (xy 31.827919 -382.478583) (xy 31.796885 -382.418859)
			(xy 31.773211 -382.355853) (xy 31.757238 -382.29047) (xy 31.749194 -382.223646) (xy 28.471155 -382.223646)
			(xy 28.471155 -382.223704) (xy 28.463079 -382.290642) (xy 28.447044 -382.356131) (xy 28.42328 -382.419228)
			(xy 28.392129 -382.479023) (xy 28.35404 -382.534657) (xy 28.332176 -382.560322) (xy 28.326385 -382.567471)
			(xy 28.319868 -382.584659) (xy 28.319476 -382.59385) (xy 28.319476 -383.086356) (xy 28.319913 -383.09554)
			(xy 28.326409 -383.112725) (xy 28.332176 -383.119884) (xy 28.354057 -383.145536) (xy 28.392146 -383.201172)
			(xy 28.423298 -383.26097) (xy 28.446934 -383.323727) (xy 29.549039 -383.323727) (xy 29.549043 -383.256419)
			(xy 29.55709 -383.189594) (xy 29.573066 -383.12421) (xy 29.596742 -383.061205) (xy 29.627779 -383.00148)
			(xy 29.665731 -382.945892) (xy 29.68752 -382.92024) (xy 29.693327 -382.913102) (xy 29.699835 -382.895906)
			(xy 29.70022 -382.886712) (xy 29.70022 -382.728724) (xy 29.700636 -382.718601) (xy 29.70838 -382.699894)
			(xy 29.722697 -382.685578) (xy 29.741405 -382.677835) (xy 29.751528 -382.677416) (xy 30.468062 -382.677416)
			(xy 30.478183 -382.677957) (xy 30.496899 -382.685668) (xy 30.511256 -382.699938) (xy 30.51908 -382.718606)
			(xy 30.519624 -382.728724) (xy 30.519624 -382.886712) (xy 30.520023 -382.8959) (xy 30.526544 -382.913085)
			(xy 30.532324 -382.92024) (xy 30.554077 -382.945921) (xy 30.59203 -383.001502) (xy 30.623067 -383.061222)
			(xy 30.646743 -383.124222) (xy 30.66272 -383.189601) (xy 30.670767 -383.256421) (xy 30.67077 -383.323724)
			(xy 30.662729 -383.390545) (xy 30.646759 -383.455926) (xy 30.623089 -383.518929) (xy 30.592058 -383.578651)
			(xy 30.554111 -383.634236) (xy 30.532324 -383.659888) (xy 30.52651 -383.667021) (xy 30.520005 -383.684221)
			(xy 30.519624 -383.693416) (xy 30.519624 -384.186684) (xy 30.520036 -384.195871) (xy 30.526548 -384.213056)
			(xy 30.532324 -384.220212) (xy 30.554149 -384.245834) (xy 30.592099 -384.301424) (xy 30.623132 -384.361152)
			(xy 30.646805 -384.42416) (xy 30.662776 -384.489546) (xy 30.670818 -384.556373) (xy 30.670815 -384.623681)
			(xy 30.662767 -384.690507) (xy 30.646789 -384.755892) (xy 30.62311 -384.818898) (xy 30.592071 -384.878622)
			(xy 30.554115 -384.934209) (xy 30.532324 -384.95986) (xy 30.526522 -384.967002) (xy 30.52001 -384.984195)
			(xy 30.519624 -384.993388) (xy 30.519624 -385.151376) (xy 30.519165 -385.161494) (xy 30.511429 -385.180193)
			(xy 30.497126 -385.194507) (xy 30.478434 -385.202257) (xy 30.468316 -385.202684) (xy 29.751782 -385.202684)
			(xy 29.741657 -385.202189) (xy 29.72294 -385.19446) (xy 29.708585 -385.180177) (xy 29.700762 -385.161498)
			(xy 29.70022 -385.151376) (xy 29.70022 -384.993388) (xy 29.699811 -384.984201) (xy 29.693296 -384.967017)
			(xy 29.68752 -384.95986) (xy 29.665769 -384.934178) (xy 29.62782 -384.878596) (xy 29.596786 -384.818876)
			(xy 29.573112 -384.755875) (xy 29.557137 -384.690497) (xy 29.549091 -384.623678) (xy 29.549087 -384.556376)
			(xy 29.557128 -384.489556) (xy 29.573096 -384.424176) (xy 29.596764 -384.361174) (xy 29.627792 -384.301451)
			(xy 29.665735 -384.245865) (xy 29.68752 -384.220212) (xy 29.693339 -384.213083) (xy 29.69984 -384.19588)
			(xy 29.70022 -384.186684) (xy 29.70022 -383.693416) (xy 29.699797 -383.68423) (xy 29.693292 -383.667046)
			(xy 29.68752 -383.659888) (xy 29.665697 -383.634265) (xy 29.627751 -383.578674) (xy 29.59672 -383.518946)
			(xy 29.57305 -383.455938) (xy 29.55708 -383.390552) (xy 29.549039 -383.323727) (xy 28.446934 -383.323727)
			(xy 28.447062 -383.324068) (xy 28.463097 -383.389559) (xy 28.471172 -383.456499) (xy 28.471171 -383.523925)
			(xy 28.463093 -383.590865) (xy 28.447055 -383.656355) (xy 28.423288 -383.719452) (xy 28.392134 -383.779249)
			(xy 28.354042 -383.834883) (xy 28.332176 -383.860548) (xy 28.326374 -383.867689) (xy 28.319863 -383.884883)
			(xy 28.319476 -383.894076) (xy 28.319476 -384.051556) (xy 28.319047 -384.061679) (xy 28.311309 -384.080386)
			(xy 28.296996 -384.094702) (xy 28.27829 -384.102445) (xy 28.268168 -384.102864) (xy 27.551888 -384.102864)
			(xy 27.54176 -384.102493) (xy 27.523049 -384.094734) (xy 27.508734 -384.080404) (xy 27.500996 -384.061684)
			(xy 27.50058 -384.051556) (xy 27.50058 -383.894076) (xy 27.500186 -383.884887) (xy 27.493661 -383.867703)
			(xy 27.48788 -383.860548) (xy 27.466032 -383.834869) (xy 27.427945 -383.779236) (xy 27.396794 -383.719442)
			(xy 27.37303 -383.656347) (xy 27.356994 -383.59086) (xy 27.348917 -383.523923) (xy 27.348916 -383.456501)
			(xy 27.35699 -383.389564) (xy 27.373023 -383.324076) (xy 27.396784 -383.26098) (xy 27.427932 -383.201184)
			(xy 27.466018 -383.14555) (xy 27.48788 -383.119884) (xy 27.493664 -383.112729) (xy 27.500187 -383.095546)
			(xy 27.50058 -383.086356) (xy 27.50058 -382.59385) (xy 27.50015 -382.584665) (xy 27.49365 -382.56748)
			(xy 27.48788 -382.560322) (xy 27.466007 -382.534665) (xy 27.42792 -382.479028) (xy 27.396771 -382.419231)
			(xy 27.373008 -382.356133) (xy 27.356974 -382.290643) (xy 27.348899 -382.223705) (xy 0.509016 -382.223705)
			(xy 0.509016 -385.583938) (xy 100.447856 -385.583938) (xy 100.447856 -384.720338) (xy 100.448346 -384.690354)
			(xy 100.456174 -384.630898) (xy 100.471695 -384.572973) (xy 100.494644 -384.517569) (xy 100.524628 -384.465635)
			(xy 100.561134 -384.418059) (xy 100.603539 -384.375654) (xy 100.651115 -384.339148) (xy 100.703049 -384.309164)
			(xy 100.758453 -384.286215) (xy 100.816378 -384.270694) (xy 100.875834 -384.262866) (xy 100.935802 -384.262866)
			(xy 100.995258 -384.270694) (xy 101.053183 -384.286215) (xy 101.108587 -384.309164) (xy 101.160521 -384.339148)
			(xy 101.208097 -384.375654) (xy 101.250502 -384.418059) (xy 101.287008 -384.465635) (xy 101.316992 -384.517569)
			(xy 101.339941 -384.572973) (xy 101.355462 -384.630898) (xy 101.36329 -384.690354) (xy 101.36378 -384.720338)
			(xy 101.36378 -385.319283) (xy 104.635826 -385.319283) (xy 104.635826 -385.259317) (xy 104.643653 -385.199864)
			(xy 104.659172 -385.141942) (xy 104.682119 -385.08654) (xy 104.7121 -385.034608) (xy 104.748603 -384.987032)
			(xy 104.791004 -384.944628) (xy 104.838576 -384.908121) (xy 104.890506 -384.878136) (xy 104.945906 -384.855184)
			(xy 105.003827 -384.83966) (xy 105.063279 -384.831828) (xy 105.093262 -384.831336) (xy 105.956862 -384.831336)
			(xy 105.986849 -384.831807) (xy 106.046311 -384.83963) (xy 106.104243 -384.855149) (xy 106.159653 -384.878097)
			(xy 106.211594 -384.908081) (xy 106.259176 -384.944589) (xy 106.301586 -384.986995) (xy 106.338098 -385.034574)
			(xy 106.368087 -385.086513) (xy 106.391039 -385.141921) (xy 106.406562 -385.199852) (xy 106.414391 -385.259313)
			(xy 106.414391 -385.319287) (xy 106.406562 -385.378748) (xy 106.391039 -385.436679) (xy 106.368087 -385.492087)
			(xy 106.338098 -385.544026) (xy 106.301586 -385.591605) (xy 106.259176 -385.634011) (xy 106.211594 -385.670519)
			(xy 106.159653 -385.700503) (xy 106.104243 -385.723451) (xy 106.046311 -385.73897) (xy 105.986849 -385.746793)
			(xy 105.956862 -385.74726) (xy 105.093262 -385.74726) (xy 105.063279 -385.746772) (xy 105.003827 -385.73894)
			(xy 104.945906 -385.723416) (xy 104.890506 -385.700464) (xy 104.838576 -385.670479) (xy 104.791004 -385.633972)
			(xy 104.748603 -385.591568) (xy 104.7121 -385.543992) (xy 104.682119 -385.49206) (xy 104.659172 -385.436658)
			(xy 104.643653 -385.378736) (xy 104.635826 -385.319283) (xy 101.36378 -385.319283) (xy 101.36378 -385.583938)
			(xy 101.36329 -385.613922) (xy 101.355462 -385.673378) (xy 101.339941 -385.731303) (xy 101.316992 -385.786707)
			(xy 101.287008 -385.838641) (xy 101.250502 -385.886217) (xy 101.208097 -385.928622) (xy 101.160521 -385.965128)
			(xy 101.108587 -385.995112) (xy 101.053183 -386.018061) (xy 100.995258 -386.033582) (xy 100.935802 -386.04141)
			(xy 100.875834 -386.04141) (xy 100.816378 -386.033582) (xy 100.758453 -386.018061) (xy 100.703049 -385.995112)
			(xy 100.651115 -385.965128) (xy 100.603539 -385.928622) (xy 100.561134 -385.886217) (xy 100.524628 -385.838641)
			(xy 100.494644 -385.786707) (xy 100.471695 -385.731303) (xy 100.456174 -385.673378) (xy 100.448346 -385.613922)
			(xy 100.447856 -385.583938) (xy 0.509016 -385.583938) (xy 0.509016 -388.37489) (xy 1.56972 -388.37489)
			(xy 1.56972 -387.51129) (xy 1.57021 -387.481322) (xy 1.578033 -387.4219) (xy 1.593546 -387.364007)
			(xy 1.616482 -387.308634) (xy 1.646449 -387.256728) (xy 1.682936 -387.209178) (xy 1.725316 -387.166798)
			(xy 1.772866 -387.130311) (xy 1.824772 -387.100344) (xy 1.880145 -387.077408) (xy 1.938038 -387.061895)
			(xy 1.99746 -387.054072) (xy 2.057396 -387.054072) (xy 2.116818 -387.061895) (xy 2.174711 -387.077408)
			(xy 2.230084 -387.100344) (xy 2.28199 -387.130311) (xy 2.32954 -387.166798) (xy 2.37192 -387.209178)
			(xy 2.408407 -387.256728) (xy 2.438374 -387.308634) (xy 2.46131 -387.364007) (xy 2.476823 -387.4219)
			(xy 2.484646 -387.481322) (xy 2.485136 -387.51129) (xy 2.485136 -388.37489) (xy 2.484646 -388.404858)
			(xy 2.476823 -388.46428) (xy 2.46131 -388.522173) (xy 2.438374 -388.577546) (xy 2.408407 -388.629452)
			(xy 2.37192 -388.677002) (xy 2.32954 -388.719382) (xy 2.28199 -388.755869) (xy 2.230084 -388.785836)
			(xy 2.174711 -388.808772) (xy 2.116818 -388.824285) (xy 2.057396 -388.832108) (xy 1.99746 -388.832108)
			(xy 1.938038 -388.824285) (xy 1.880145 -388.808772) (xy 1.824772 -388.785836) (xy 1.772866 -388.755869)
			(xy 1.725316 -388.719382) (xy 1.682936 -388.677002) (xy 1.646449 -388.629452) (xy 1.616482 -388.577546)
			(xy 1.593546 -388.522173) (xy 1.578033 -388.46428) (xy 1.57021 -388.404858) (xy 1.56972 -388.37489)
			(xy 0.509016 -388.37489) (xy 0.509016 -398.164722) (xy 3.141726 -398.164722) (xy 3.141726 -398.035362)
			(xy 3.149849 -397.906256) (xy 3.166062 -397.777916) (xy 3.190302 -397.650846) (xy 3.222472 -397.52555)
			(xy 3.262447 -397.40252) (xy 3.310068 -397.282244) (xy 3.365147 -397.165195) (xy 3.427467 -397.051835)
			(xy 3.496782 -396.942612) (xy 3.572818 -396.837957) (xy 3.655276 -396.738283) (xy 3.743829 -396.643983)
			(xy 3.838129 -396.55543) (xy 3.937803 -396.472972) (xy 4.042458 -396.396936) (xy 4.151681 -396.327621)
			(xy 4.265041 -396.265301) (xy 4.38209 -396.210222) (xy 4.502366 -396.162601) (xy 4.625396 -396.122626)
			(xy 4.750692 -396.090456) (xy 4.877762 -396.066216) (xy 5.006102 -396.050003) (xy 5.135208 -396.04188)
			(xy 5.199888 -396.041372) (xy 6.800088 -396.041372) (xy 6.864769 -396.041866) (xy 6.993875 -396.049988)
			(xy 7.122217 -396.066201) (xy 7.249287 -396.090441) (xy 7.374584 -396.122612) (xy 7.497614 -396.162587)
			(xy 7.617892 -396.210208) (xy 7.734942 -396.265287) (xy 7.848302 -396.327608) (xy 7.957526 -396.396923)
			(xy 8.062181 -396.47296) (xy 8.161856 -396.555418) (xy 8.256157 -396.643972) (xy 8.344711 -396.738272)
			(xy 8.427169 -396.837947) (xy 8.503206 -396.942603) (xy 8.572521 -397.051826) (xy 8.634842 -397.165187)
			(xy 8.689921 -397.282236) (xy 8.737543 -397.402514) (xy 8.777518 -397.525544) (xy 8.809688 -397.650841)
			(xy 8.833928 -397.777911) (xy 8.839736 -397.823885) (xy 27.348879 -397.823885) (xy 27.348883 -397.756458)
			(xy 27.356962 -397.689518) (xy 27.373001 -397.624027) (xy 27.396769 -397.560929) (xy 27.427923 -397.501131)
			(xy 27.466014 -397.445496) (xy 27.48788 -397.41983) (xy 27.493686 -397.412692) (xy 27.500196 -397.395496)
			(xy 27.50058 -397.386302) (xy 27.50058 -396.89405) (xy 27.50015 -396.884865) (xy 27.49365 -396.86768)
			(xy 27.48788 -396.860522) (xy 27.466007 -396.834865) (xy 27.42792 -396.779228) (xy 27.396771 -396.719431)
			(xy 27.373008 -396.656333) (xy 27.356974 -396.590843) (xy 27.348899 -396.523905) (xy 27.3489 -396.45648)
			(xy 27.356976 -396.389542) (xy 27.373012 -396.324053) (xy 27.396777 -396.260955) (xy 27.427928 -396.201159)
			(xy 27.466016 -396.145524) (xy 27.48788 -396.119858) (xy 27.493675 -396.112711) (xy 27.500191 -396.095522)
			(xy 27.50058 -396.08633) (xy 27.50058 -395.92885) (xy 27.501069 -395.918722) (xy 27.508787 -395.899994)
			(xy 27.523074 -395.885635) (xy 27.541762 -395.877821) (xy 27.551888 -395.877288) (xy 28.268168 -395.877288)
			(xy 28.278319 -395.877747) (xy 28.297068 -395.88553) (xy 28.311392 -395.899915) (xy 28.319095 -395.918698)
			(xy 28.319476 -395.92885) (xy 28.319476 -396.08633) (xy 28.319877 -396.095518) (xy 28.326398 -396.112702)
			(xy 28.332176 -396.119858) (xy 28.354031 -396.145531) (xy 28.392122 -396.201164) (xy 28.423274 -396.260959)
			(xy 28.44704 -396.324055) (xy 28.463077 -396.389543) (xy 28.471154 -396.456481) (xy 28.471155 -396.523904)
			(xy 28.463079 -396.590842) (xy 28.447044 -396.656331) (xy 28.42328 -396.719428) (xy 28.392129 -396.779223)
			(xy 28.35404 -396.834857) (xy 28.332176 -396.860522) (xy 28.326385 -396.867671) (xy 28.319868 -396.884859)
			(xy 28.319476 -396.89405) (xy 28.319476 -397.386302) (xy 28.31989 -397.395489) (xy 28.326402 -397.412673)
			(xy 28.332176 -397.41983) (xy 28.354003 -397.445526) (xy 28.392095 -397.501155) (xy 28.420857 -397.556356)
			(xy 29.549071 -397.556356) (xy 29.557114 -397.489534) (xy 29.573085 -397.424153) (xy 29.596756 -397.361149)
			(xy 29.627787 -397.301425) (xy 29.665733 -397.245838) (xy 29.68752 -397.220186) (xy 29.693307 -397.213034)
			(xy 29.699827 -397.195849) (xy 29.70022 -397.186658) (xy 29.70022 -397.028924) (xy 29.700641 -397.018769)
			(xy 29.708433 -397.000013) (xy 29.72283 -396.985688) (xy 29.741625 -396.977991) (xy 29.751782 -396.977616)
			(xy 30.468062 -396.977616) (xy 30.478183 -396.978157) (xy 30.496899 -396.985868) (xy 30.511256 -397.000138)
			(xy 30.51908 -397.018806) (xy 30.519624 -397.028924) (xy 30.519624 -397.186658) (xy 30.520049 -397.195844)
			(xy 30.526552 -397.213029) (xy 30.532324 -397.220186) (xy 30.554123 -397.24583) (xy 30.592074 -397.301416)
			(xy 30.623108 -397.361141) (xy 30.646782 -397.424147) (xy 30.662756 -397.48953) (xy 30.6708 -397.556354)
			(xy 30.670799 -397.623661) (xy 30.662753 -397.690485) (xy 30.646778 -397.755868) (xy 30.623102 -397.818873)
			(xy 30.620528 -397.823826) (xy 31.749174 -397.823826) (xy 31.749178 -397.756517) (xy 31.757226 -397.689691)
			(xy 31.773204 -397.624307) (xy 31.796882 -397.5613) (xy 31.827922 -397.501576) (xy 31.865877 -397.44599)
			(xy 31.887668 -397.420338) (xy 31.893482 -397.413205) (xy 31.899984 -397.396005) (xy 31.900368 -397.38681)
			(xy 31.900368 -396.893542) (xy 31.899923 -396.884359) (xy 31.893432 -396.867175) (xy 31.887668 -396.860014)
			(xy 31.86587 -396.83437) (xy 31.827919 -396.778783) (xy 31.796885 -396.719059) (xy 31.773211 -396.656053)
			(xy 31.757238 -396.59067) (xy 31.749194 -396.523846) (xy 31.749195 -396.456539) (xy 31.757241 -396.389716)
			(xy 31.773216 -396.324332) (xy 31.796891 -396.261327) (xy 31.827927 -396.201604) (xy 31.865879 -396.146018)
			(xy 31.887668 -396.120366) (xy 31.89347 -396.113225) (xy 31.899979 -396.096031) (xy 31.900368 -396.086838)
			(xy 31.900368 -395.92885) (xy 31.900805 -395.918678) (xy 31.90858 -395.899879) (xy 31.922962 -395.885491)
			(xy 31.941758 -395.877709) (xy 31.95193 -395.877288) (xy 32.66821 -395.877288) (xy 32.678388 -395.877657)
			(xy 32.697193 -395.885455) (xy 32.711579 -395.899858) (xy 32.719355 -395.918671) (xy 32.719772 -395.92885)
			(xy 32.719772 -396.086838) (xy 32.72017 -396.096026) (xy 32.726693 -396.11321) (xy 32.732472 -396.120366)
			(xy 32.75425 -396.146026) (xy 32.792198 -396.201612) (xy 32.823231 -396.261334) (xy 32.846904 -396.324338)
			(xy 32.862877 -396.389719) (xy 32.870922 -396.45654) (xy 32.870923 -396.523845) (xy 32.86288 -396.590666)
			(xy 32.846909 -396.656048) (xy 32.823237 -396.719052) (xy 32.792206 -396.778775) (xy 32.754259 -396.834362)
			(xy 32.732472 -396.860014) (xy 32.726683 -396.867165) (xy 32.720165 -396.884351) (xy 32.719772 -396.893542)
			(xy 32.719772 -397.38681) (xy 32.720183 -397.395997) (xy 32.726697 -397.413181) (xy 32.732472 -397.420338)
			(xy 32.754222 -397.446021) (xy 32.792171 -397.501603) (xy 32.820593 -397.556296) (xy 33.948839 -397.556296)
			(xy 33.956914 -397.489358) (xy 33.972949 -397.423869) (xy 33.996713 -397.360773) (xy 34.027863 -397.300977)
			(xy 34.065952 -397.245343) (xy 34.087816 -397.219678) (xy 34.093606 -397.212528) (xy 34.100124 -397.195341)
			(xy 34.100516 -397.18615) (xy 34.100516 -397.028924) (xy 34.100936 -397.018801) (xy 34.108679 -397.000095)
			(xy 34.122995 -396.985779) (xy 34.141701 -396.978036) (xy 34.151824 -396.977616) (xy 34.868104 -396.977616)
			(xy 34.878229 -396.978013) (xy 34.896935 -396.985766) (xy 34.91125 -397.000088) (xy 34.918992 -397.018799)
			(xy 34.919412 -397.028924) (xy 34.919412 -397.18615) (xy 34.919843 -397.195335) (xy 34.926342 -397.21252)
			(xy 34.932112 -397.219678) (xy 34.953985 -397.245335) (xy 34.992073 -397.300971) (xy 35.023223 -397.360769)
			(xy 35.046986 -397.423867) (xy 35.06302 -397.489356) (xy 35.071095 -397.556295) (xy 35.071094 -397.62372)
			(xy 35.063017 -397.690658) (xy 35.046981 -397.756148) (xy 35.023216 -397.819245) (xy 35.020799 -397.823884)
			(xy 36.148967 -397.823884) (xy 36.148971 -397.756458) (xy 36.15705 -397.689518) (xy 36.173088 -397.624028)
			(xy 36.196855 -397.560929) (xy 36.228008 -397.501132) (xy 36.266099 -397.445496) (xy 36.287964 -397.41983)
			(xy 36.293781 -397.412699) (xy 36.300282 -397.395497) (xy 36.300664 -397.386302) (xy 36.300664 -396.89405)
			(xy 36.300216 -396.884867) (xy 36.293727 -396.867683) (xy 36.287964 -396.860522) (xy 36.266091 -396.834864)
			(xy 36.228005 -396.779228) (xy 36.196857 -396.71943) (xy 36.173095 -396.656332) (xy 36.157061 -396.590843)
			(xy 36.148987 -396.523904) (xy 36.148988 -396.456481) (xy 36.157064 -396.389542) (xy 36.1731 -396.324053)
			(xy 36.196863 -396.260956) (xy 36.228013 -396.201159) (xy 36.266101 -396.145524) (xy 36.287964 -396.119858)
			(xy 36.293769 -396.112719) (xy 36.300277 -396.095523) (xy 36.300664 -396.08633) (xy 36.300664 -395.92885)
			(xy 36.301168 -395.918724) (xy 36.308884 -395.899999) (xy 36.323166 -395.88564) (xy 36.341848 -395.877823)
			(xy 36.351972 -395.877288) (xy 37.068252 -395.877288) (xy 37.078402 -395.877761) (xy 37.097151 -395.885538)
			(xy 37.111475 -395.899919) (xy 37.119179 -395.918699) (xy 37.11956 -395.92885) (xy 37.11956 -396.08633)
			(xy 37.119965 -396.095518) (xy 37.126483 -396.112701) (xy 37.13226 -396.119858) (xy 37.154116 -396.145531)
			(xy 37.192207 -396.201163) (xy 37.223361 -396.260958) (xy 37.247127 -396.324054) (xy 37.263164 -396.389543)
			(xy 37.271242 -396.456481) (xy 37.271243 -396.523904) (xy 37.263167 -396.590843) (xy 37.247132 -396.656332)
			(xy 37.223367 -396.719428) (xy 37.192215 -396.779224) (xy 37.154125 -396.834857) (xy 37.13226 -396.860522)
			(xy 37.126467 -396.867669) (xy 37.119951 -396.884858) (xy 37.11956 -396.89405) (xy 37.11956 -397.386302)
			(xy 37.119978 -397.395488) (xy 37.126487 -397.412672) (xy 37.13226 -397.41983) (xy 37.154088 -397.445525)
			(xy 37.192181 -397.501155) (xy 37.220943 -397.556356) (xy 38.349159 -397.556356) (xy 38.357201 -397.489534)
			(xy 38.373172 -397.424153) (xy 38.396842 -397.361149) (xy 38.427873 -397.301426) (xy 38.465818 -397.245839)
			(xy 38.487604 -397.220186) (xy 38.493389 -397.213033) (xy 38.499911 -397.195848) (xy 38.500304 -397.186658)
			(xy 38.500304 -397.028924) (xy 38.500741 -397.018771) (xy 38.50853 -397.000018) (xy 38.522922 -396.985694)
			(xy 38.541711 -396.977994) (xy 38.551866 -396.977616) (xy 39.268146 -396.977616) (xy 39.278273 -396.978088)
			(xy 39.29699 -396.985827) (xy 39.311344 -397.000117) (xy 39.319166 -397.0188) (xy 39.319708 -397.028924)
			(xy 39.319708 -397.186658) (xy 39.320136 -397.195843) (xy 39.326637 -397.213028) (xy 39.332408 -397.220186)
			(xy 39.354207 -397.245829) (xy 39.392159 -397.301416) (xy 39.423195 -397.36114) (xy 39.446869 -397.424146)
			(xy 39.462843 -397.48953) (xy 39.470887 -397.556354) (xy 39.470887 -397.623661) (xy 39.462841 -397.690485)
			(xy 39.446865 -397.755869) (xy 39.423189 -397.818874) (xy 39.420585 -397.823885) (xy 40.548734 -397.823885)
			(xy 40.548737 -397.756458) (xy 40.556817 -397.689516) (xy 40.572859 -397.624024) (xy 40.596629 -397.560925)
			(xy 40.627787 -397.501128) (xy 40.665884 -397.445494) (xy 40.687752 -397.41983) (xy 40.693567 -397.412698)
			(xy 40.700069 -397.395497) (xy 40.700452 -397.386302) (xy 40.700452 -396.89405) (xy 40.700006 -396.884867)
			(xy 40.693516 -396.867683) (xy 40.687752 -396.860522) (xy 40.665876 -396.834866) (xy 40.627785 -396.779231)
			(xy 40.596631 -396.719434) (xy 40.572865 -396.656336) (xy 40.556829 -396.590845) (xy 40.548753 -396.523905)
			(xy 40.548754 -396.45648) (xy 40.556832 -396.38954) (xy 40.57287 -396.32405) (xy 40.596638 -396.260952)
			(xy 40.627792 -396.201156) (xy 40.665886 -396.145522) (xy 40.687752 -396.119858) (xy 40.693555 -396.112718)
			(xy 40.700065 -396.095523) (xy 40.700452 -396.08633) (xy 40.700452 -395.92885) (xy 40.700968 -395.918725)
			(xy 40.708682 -395.900003) (xy 40.722959 -395.885644) (xy 40.741638 -395.877825) (xy 40.75176 -395.877288)
			(xy 41.46804 -395.877288) (xy 41.478195 -395.877689) (xy 41.496946 -395.885495) (xy 41.511268 -395.899898)
			(xy 41.518968 -395.918693) (xy 41.519348 -395.92885) (xy 41.519348 -396.08633) (xy 41.519755 -396.095517)
			(xy 41.526272 -396.112701) (xy 41.532048 -396.119858) (xy 41.553904 -396.14553) (xy 41.591996 -396.201163)
			(xy 41.62315 -396.260957) (xy 41.646917 -396.324053) (xy 41.662955 -396.389542) (xy 41.671033 -396.456481)
			(xy 41.671034 -396.523904) (xy 41.662958 -396.590843) (xy 41.646922 -396.656332) (xy 41.623157 -396.719429)
			(xy 41.592004 -396.779224) (xy 41.553913 -396.834858) (xy 41.532048 -396.860522) (xy 41.526253 -396.867668)
			(xy 41.519739 -396.884858) (xy 41.519348 -396.89405) (xy 41.519348 -397.386302) (xy 41.519769 -397.395488)
			(xy 41.526276 -397.412672) (xy 41.532048 -397.41983) (xy 41.553876 -397.445525) (xy 41.59197 -397.501154)
			(xy 41.620702 -397.556296) (xy 42.748927 -397.556296) (xy 42.757002 -397.489358) (xy 42.773037 -397.42387)
			(xy 42.7968 -397.360774) (xy 42.827949 -397.300978) (xy 42.866037 -397.245343) (xy 42.8879 -397.219678)
			(xy 42.893688 -397.212527) (xy 42.900208 -397.195341) (xy 42.9006 -397.18615) (xy 42.9006 -397.028924)
			(xy 42.901035 -397.018803) (xy 42.908776 -397.0001) (xy 42.923086 -396.985785) (xy 42.941787 -396.978039)
			(xy 42.951908 -396.977616) (xy 43.668188 -396.977616) (xy 43.678312 -396.978026) (xy 43.697018 -396.985773)
			(xy 43.711333 -397.000092) (xy 43.719076 -397.0188) (xy 43.719496 -397.028924) (xy 43.719496 -397.18615)
			(xy 43.719931 -397.195335) (xy 43.726427 -397.212519) (xy 43.732196 -397.219678) (xy 43.75407 -397.245335)
			(xy 43.792159 -397.300971) (xy 43.823309 -397.360768) (xy 43.847073 -397.423866) (xy 43.863108 -397.489356)
			(xy 43.871183 -397.556295) (xy 43.871182 -397.62372) (xy 43.863105 -397.690659) (xy 43.847068 -397.756148)
			(xy 43.823303 -397.819246) (xy 43.820917 -397.823825) (xy 44.949053 -397.823825) (xy 44.949057 -397.756517)
			(xy 44.957105 -397.689692) (xy 44.973082 -397.624308) (xy 44.996759 -397.561302) (xy 45.027796 -397.501577)
			(xy 45.06575 -397.44599) (xy 45.08754 -397.420338) (xy 45.09335 -397.413203) (xy 45.099856 -397.396004)
			(xy 45.10024 -397.38681) (xy 45.10024 -396.893542) (xy 45.0998 -396.884358) (xy 45.093306 -396.867174)
			(xy 45.08754 -396.860014) (xy 45.065742 -396.83437) (xy 45.027794 -396.778782) (xy 44.996761 -396.719058)
			(xy 44.973088 -396.656052) (xy 44.957116 -396.590669) (xy 44.949073 -396.523845) (xy 44.949074 -396.45654)
			(xy 44.957119 -396.389716) (xy 44.973093 -396.324333) (xy 44.996767 -396.261328) (xy 45.027801 -396.201605)
			(xy 45.065751 -396.146018) (xy 45.08754 -396.120366) (xy 45.093339 -396.113222) (xy 45.099851 -396.096031)
			(xy 45.10024 -396.086838) (xy 45.10024 -395.92885) (xy 45.100705 -395.918681) (xy 45.108474 -395.899887)
			(xy 45.122847 -395.885501) (xy 45.141634 -395.877714) (xy 45.151802 -395.877288) (xy 45.868082 -395.877288)
			(xy 45.878259 -395.87768) (xy 45.897063 -395.885468) (xy 45.91145 -395.899864) (xy 45.919227 -395.918673)
			(xy 45.919644 -395.92885) (xy 45.919644 -396.086838) (xy 45.920049 -396.096026) (xy 45.926568 -396.113209)
			(xy 45.932344 -396.120366) (xy 45.954122 -396.146026) (xy 45.992072 -396.201611) (xy 46.023107 -396.261333)
			(xy 46.046781 -396.324337) (xy 46.062755 -396.389718) (xy 46.070801 -396.45654) (xy 46.070801 -396.523845)
			(xy 46.062758 -396.590667) (xy 46.046786 -396.656049) (xy 46.023113 -396.719053) (xy 45.99208 -396.778776)
			(xy 45.954131 -396.834362) (xy 45.932344 -396.860014) (xy 45.926552 -396.867162) (xy 45.920036 -396.884351)
			(xy 45.919644 -396.893542) (xy 45.919644 -397.38681) (xy 45.920062 -397.395996) (xy 45.926572 -397.41318)
			(xy 45.932344 -397.420338) (xy 45.954095 -397.446021) (xy 45.992046 -397.501602) (xy 46.020501 -397.556355)
			(xy 47.149223 -397.556355) (xy 47.157267 -397.489532) (xy 47.17324 -397.42415) (xy 47.196914 -397.361146)
			(xy 47.227949 -397.301423) (xy 47.265899 -397.245837) (xy 47.287688 -397.220186) (xy 47.293472 -397.213032)
			(xy 47.299994 -397.195848) (xy 47.300388 -397.186658) (xy 47.300388 -397.028924) (xy 47.300841 -397.018773)
			(xy 47.308626 -397.000023) (xy 47.323013 -396.985699) (xy 47.341797 -396.977997) (xy 47.35195 -396.977616)
			(xy 48.06823 -396.977616) (xy 48.078356 -396.978101) (xy 48.097073 -396.985834) (xy 48.111427 -397.000121)
			(xy 48.11925 -397.018801) (xy 48.119792 -397.028924) (xy 48.119792 -397.186658) (xy 48.120224 -397.195843)
			(xy 48.126723 -397.213027) (xy 48.132492 -397.220186) (xy 48.154289 -397.24583) (xy 48.192235 -397.301419)
			(xy 48.223266 -397.361144) (xy 48.246937 -397.424149) (xy 48.262908 -397.489532) (xy 48.270951 -397.556355)
			(xy 48.27095 -397.62366) (xy 48.262906 -397.690483) (xy 48.246933 -397.755865) (xy 48.22326 -397.81887)
			(xy 48.192227 -397.878594) (xy 48.154279 -397.934181) (xy 48.132492 -397.959834) (xy 48.126698 -397.966981)
			(xy 48.120182 -397.98417) (xy 48.119792 -397.993362) (xy 48.119792 -398.486884) (xy 48.120212 -398.49607)
			(xy 48.126719 -398.513254) (xy 48.132492 -398.520412) (xy 48.154314 -398.546035) (xy 48.19226 -398.601627)
			(xy 48.22329 -398.661355) (xy 48.246959 -398.724363) (xy 48.262929 -398.789748) (xy 48.27097 -398.856573)
			(xy 48.270966 -398.923881) (xy 48.262919 -398.990705) (xy 48.246943 -399.056089) (xy 48.223268 -399.119095)
			(xy 48.192232 -399.17882) (xy 48.154281 -399.234407) (xy 48.132492 -399.26006) (xy 48.126687 -399.267199)
			(xy 48.120177 -399.284394) (xy 48.119792 -399.293588) (xy 48.119792 -399.451576) (xy 48.119359 -399.46173)
			(xy 48.11157 -399.480483) (xy 48.097176 -399.494808) (xy 48.078386 -399.502507) (xy 48.06823 -399.502884)
			(xy 47.35195 -399.502884) (xy 47.341829 -399.502333) (xy 47.323114 -399.494626) (xy 47.308757 -399.48036)
			(xy 47.300932 -399.461693) (xy 47.300388 -399.451576) (xy 47.300388 -399.293588) (xy 47.299986 -399.2844)
			(xy 47.293467 -399.267216) (xy 47.287688 -399.26006) (xy 47.265934 -399.234379) (xy 47.227981 -399.178798)
			(xy 47.196944 -399.119079) (xy 47.173267 -399.056078) (xy 47.15729 -398.990699) (xy 47.149242 -398.923879)
			(xy 47.149239 -398.856576) (xy 47.15728 -398.789754) (xy 47.173251 -398.724374) (xy 47.196921 -398.661371)
			(xy 47.227953 -398.601648) (xy 47.265901 -398.546063) (xy 47.287688 -398.520412) (xy 47.293503 -398.51328)
			(xy 47.300007 -398.496079) (xy 47.300388 -398.486884) (xy 47.300388 -397.993362) (xy 47.299999 -397.984172)
			(xy 47.293471 -397.966988) (xy 47.287688 -397.959834) (xy 47.265909 -397.934174) (xy 47.227956 -397.87859)
			(xy 47.19692 -397.818868) (xy 47.173244 -397.755864) (xy 47.157269 -397.690483) (xy 47.149224 -397.62366)
			(xy 47.149223 -397.556355) (xy 46.020501 -397.556355) (xy 46.023082 -397.561322) (xy 46.046757 -397.624322)
			(xy 46.062733 -397.689701) (xy 46.070781 -397.75652) (xy 46.070784 -397.823823) (xy 46.062744 -397.890643)
			(xy 46.046774 -397.956023) (xy 46.023105 -398.019026) (xy 45.992075 -398.078748) (xy 45.95413 -398.134334)
			(xy 45.932344 -398.159986) (xy 45.926522 -398.167113) (xy 45.920024 -398.184318) (xy 45.919644 -398.193514)
			(xy 45.919644 -398.351502) (xy 45.919237 -398.361676) (xy 45.911448 -398.380474) (xy 45.897057 -398.39486)
			(xy 45.878256 -398.402641) (xy 45.868082 -398.403064) (xy 45.151802 -398.403064) (xy 45.141645 -398.402565)
			(xy 45.122876 -398.394792) (xy 45.108511 -398.380427) (xy 45.100736 -398.361659) (xy 45.10024 -398.351502)
			(xy 45.10024 -398.193514) (xy 45.099814 -398.184329) (xy 45.093311 -398.167145) (xy 45.08754 -398.159986)
			(xy 45.065715 -398.134365) (xy 45.027767 -398.078774) (xy 44.996735 -398.019046) (xy 44.973065 -397.956037)
			(xy 44.957094 -397.890651) (xy 44.949053 -397.823825) (xy 43.820917 -397.823825) (xy 43.792151 -397.879042)
			(xy 43.754061 -397.934677) (xy 43.732196 -397.960342) (xy 43.726399 -397.967487) (xy 43.719885 -397.984678)
			(xy 43.719496 -397.99387) (xy 43.719496 -398.486376) (xy 43.719919 -398.495562) (xy 43.726424 -398.512746)
			(xy 43.732196 -398.519904) (xy 43.754095 -398.54554) (xy 43.792183 -398.601179) (xy 43.823333 -398.660979)
			(xy 43.847095 -398.72408) (xy 43.863128 -398.789572) (xy 43.871201 -398.856514) (xy 43.871198 -398.92394)
			(xy 43.863118 -398.990881) (xy 43.847079 -399.056372) (xy 43.823311 -399.119471) (xy 43.792156 -399.179268)
			(xy 43.754062 -399.234903) (xy 43.732196 -399.260568) (xy 43.726388 -399.267705) (xy 43.71988 -399.284902)
			(xy 43.719496 -399.294096) (xy 43.719496 -399.451576) (xy 43.719064 -399.461697) (xy 43.711323 -399.480401)
			(xy 43.697011 -399.494717) (xy 43.678309 -399.502462) (xy 43.668188 -399.502884) (xy 42.951908 -399.502884)
			(xy 42.941784 -399.502477) (xy 42.923078 -399.494729) (xy 42.908762 -399.480409) (xy 42.90102 -399.4617)
			(xy 42.9006 -399.451576) (xy 42.9006 -399.294096) (xy 42.900192 -399.284909) (xy 42.893677 -399.267724)
			(xy 42.8879 -399.260568) (xy 42.866071 -399.234874) (xy 42.827982 -399.179243) (xy 42.796829 -399.119451)
			(xy 42.773063 -399.056358) (xy 42.757025 -398.990872) (xy 42.748946 -398.923937) (xy 42.748943 -398.856517)
			(xy 42.757015 -398.789581) (xy 42.773047 -398.724094) (xy 42.796807 -398.660998) (xy 42.827954 -398.601203)
			(xy 42.866038 -398.545569) (xy 42.8879 -398.519904) (xy 42.893677 -398.512745) (xy 42.900204 -398.495565)
			(xy 42.9006 -398.486376) (xy 42.9006 -397.99387) (xy 42.900204 -397.984681) (xy 42.893681 -397.967497)
			(xy 42.8879 -397.960342) (xy 42.866046 -397.934669) (xy 42.827957 -397.879035) (xy 42.796806 -397.81924)
			(xy 42.773041 -397.756144) (xy 42.757005 -397.690656) (xy 42.748928 -397.623719) (xy 42.748927 -397.556296)
			(xy 41.620702 -397.556296) (xy 41.623125 -397.560946) (xy 41.646894 -397.624039) (xy 41.662933 -397.689525)
			(xy 41.671013 -397.756461) (xy 41.671016 -397.823882) (xy 41.662944 -397.890819) (xy 41.646911 -397.956307)
			(xy 41.623148 -398.019402) (xy 41.591999 -398.079197) (xy 41.553912 -398.13483) (xy 41.532048 -398.160494)
			(xy 41.526265 -398.167649) (xy 41.519744 -398.184832) (xy 41.519348 -398.194022) (xy 41.519348 -398.351502)
			(xy 41.518875 -398.36163) (xy 41.511144 -398.380354) (xy 41.496853 -398.39471) (xy 41.478166 -398.402527)
			(xy 41.46804 -398.403064) (xy 40.75176 -398.403064) (xy 40.741599 -398.40271) (xy 40.722839 -398.394895)
			(xy 40.708515 -398.380477) (xy 40.700824 -398.361666) (xy 40.700452 -398.351502) (xy 40.700452 -398.194022)
			(xy 40.70002 -398.184837) (xy 40.69352 -398.167653) (xy 40.687752 -398.160494) (xy 40.665849 -398.13486)
			(xy 40.627758 -398.079223) (xy 40.596606 -398.019423) (xy 40.572842 -397.956321) (xy 40.556807 -397.890828)
			(xy 40.548734 -397.823885) (xy 39.420585 -397.823885) (xy 39.392151 -397.878597) (xy 39.354198 -397.934183)
			(xy 39.332408 -397.959834) (xy 39.326615 -397.966982) (xy 39.320098 -397.98417) (xy 39.319708 -397.993362)
			(xy 39.319708 -398.486884) (xy 39.320124 -398.496071) (xy 39.326633 -398.513255) (xy 39.332408 -398.520412)
			(xy 39.354233 -398.546034) (xy 39.392184 -398.601624) (xy 39.423219 -398.661351) (xy 39.446892 -398.72436)
			(xy 39.462864 -398.789746) (xy 39.470906 -398.856573) (xy 39.470902 -398.923882) (xy 39.462854 -398.990707)
			(xy 39.446876 -399.056092) (xy 39.423196 -399.119098) (xy 39.392156 -399.178823) (xy 39.354199 -399.234409)
			(xy 39.332408 -399.26006) (xy 39.326604 -399.2672) (xy 39.320094 -399.284395) (xy 39.319708 -399.293588)
			(xy 39.319708 -399.451576) (xy 39.319259 -399.461728) (xy 39.311473 -399.480478) (xy 39.297085 -399.494802)
			(xy 39.278299 -399.502504) (xy 39.268146 -399.502884) (xy 38.551866 -399.502884) (xy 38.54174 -399.502402)
			(xy 38.523023 -399.494668) (xy 38.508668 -399.48038) (xy 38.500846 -399.4617) (xy 38.500304 -399.451576)
			(xy 38.500304 -399.293588) (xy 38.499899 -399.2844) (xy 38.493381 -399.267216) (xy 38.487604 -399.26006)
			(xy 38.465853 -399.234378) (xy 38.427905 -399.178795) (xy 38.396872 -399.119075) (xy 38.373199 -399.056075)
			(xy 38.357224 -398.990697) (xy 38.349178 -398.923878) (xy 38.349175 -398.856576) (xy 38.357215 -398.789757)
			(xy 38.373183 -398.724377) (xy 38.39685 -398.661374) (xy 38.427877 -398.601651) (xy 38.465819 -398.546065)
			(xy 38.487604 -398.520412) (xy 38.493421 -398.513281) (xy 38.499923 -398.49608) (xy 38.500304 -398.486884)
			(xy 38.500304 -397.993362) (xy 38.499911 -397.984173) (xy 38.493385 -397.966989) (xy 38.487604 -397.959834)
			(xy 38.465827 -397.934173) (xy 38.42788 -397.878587) (xy 38.396849 -397.818865) (xy 38.373177 -397.755861)
			(xy 38.357204 -397.69048) (xy 38.34916 -397.623659) (xy 38.349159 -397.556356) (xy 37.220943 -397.556356)
			(xy 37.223335 -397.560946) (xy 37.247103 -397.624039) (xy 37.263142 -397.689525) (xy 37.271222 -397.756461)
			(xy 37.271225 -397.823882) (xy 37.263153 -397.890819) (xy 37.24712 -397.956306) (xy 37.223358 -398.019402)
			(xy 37.19221 -398.079196) (xy 37.154123 -398.134829) (xy 37.13226 -398.160494) (xy 37.126478 -398.16765)
			(xy 37.119956 -398.184832) (xy 37.11956 -398.194022) (xy 37.11956 -398.351502) (xy 37.119075 -398.361629)
			(xy 37.111347 -398.38035) (xy 37.09706 -398.394706) (xy 37.078376 -398.402525) (xy 37.068252 -398.403064)
			(xy 36.351972 -398.403064) (xy 36.341812 -398.402701) (xy 36.323052 -398.394889) (xy 36.308728 -398.380474)
			(xy 36.301036 -398.361665) (xy 36.300664 -398.351502) (xy 36.300664 -398.194022) (xy 36.300229 -398.184838)
			(xy 36.293731 -398.167654) (xy 36.287964 -398.160494) (xy 36.266064 -398.134859) (xy 36.227979 -398.079219)
			(xy 36.196832 -398.019419) (xy 36.173071 -397.956318) (xy 36.15704 -397.890825) (xy 36.148967 -397.823884)
			(xy 35.020799 -397.823884) (xy 34.992065 -397.879042) (xy 34.953976 -397.934677) (xy 34.932112 -397.960342)
			(xy 34.926316 -397.967488) (xy 34.919801 -397.984678) (xy 34.919412 -397.99387) (xy 34.919412 -398.486376)
			(xy 34.919831 -398.495562) (xy 34.926338 -398.512747) (xy 34.932112 -398.519904) (xy 34.954011 -398.54554)
			(xy 34.992098 -398.601179) (xy 35.023246 -398.66098) (xy 35.047008 -398.72408) (xy 35.06304 -398.789573)
			(xy 35.071113 -398.856514) (xy 35.07111 -398.92394) (xy 35.063031 -398.990881) (xy 35.046992 -399.056372)
			(xy 35.023224 -399.11947) (xy 34.99207 -399.179267) (xy 34.953978 -399.234903) (xy 34.932112 -399.260568)
			(xy 34.926305 -399.267706) (xy 34.919796 -399.284902) (xy 34.919412 -399.294096) (xy 34.919412 -399.451576)
			(xy 34.918965 -399.461695) (xy 34.911227 -399.480396) (xy 34.89692 -399.494711) (xy 34.878223 -399.502459)
			(xy 34.868104 -399.502884) (xy 34.151824 -399.502884) (xy 34.141701 -399.502464) (xy 34.122995 -399.494721)
			(xy 34.108679 -399.480405) (xy 34.100936 -399.461699) (xy 34.100516 -399.451576) (xy 34.100516 -399.294096)
			(xy 34.100104 -399.284909) (xy 34.093591 -399.267725) (xy 34.087816 -399.260568) (xy 34.065987 -399.234874)
			(xy 34.027896 -399.179244) (xy 33.996743 -399.119452) (xy 33.972976 -399.056359) (xy 33.956937 -398.990873)
			(xy 33.948858 -398.923938) (xy 33.948855 -398.856516) (xy 33.956928 -398.78958) (xy 33.97296 -398.724093)
			(xy 33.996721 -398.660998) (xy 34.027868 -398.601203) (xy 34.065954 -398.545569) (xy 34.087816 -398.519904)
			(xy 34.093595 -398.512747) (xy 34.10012 -398.495565) (xy 34.100516 -398.486376) (xy 34.100516 -397.99387)
			(xy 34.100117 -397.984682) (xy 34.093595 -397.967498) (xy 34.087816 -397.960342) (xy 34.065961 -397.934669)
			(xy 34.027871 -397.879036) (xy 33.996719 -397.819241) (xy 33.972954 -397.756145) (xy 33.956917 -397.690657)
			(xy 33.94884 -397.623719) (xy 33.948839 -397.556296) (xy 32.820593 -397.556296) (xy 32.823205 -397.561323)
			(xy 32.84688 -397.624323) (xy 32.862855 -397.689702) (xy 32.870902 -397.756521) (xy 32.870905 -397.823822)
			(xy 32.862865 -397.890642) (xy 32.846897 -397.956022) (xy 32.823229 -398.019025) (xy 32.7922 -398.078747)
			(xy 32.754257 -398.134334) (xy 32.732472 -398.159986) (xy 32.726653 -398.167115) (xy 32.720152 -398.184318)
			(xy 32.719772 -398.193514) (xy 32.719772 -398.351502) (xy 32.719268 -398.361659) (xy 32.711495 -398.380426)
			(xy 32.697133 -398.394791) (xy 32.678367 -398.402567) (xy 32.66821 -398.403064) (xy 31.95193 -398.403064)
			(xy 31.941761 -398.402611) (xy 31.922967 -398.394837) (xy 31.908581 -398.38046) (xy 31.900795 -398.361671)
			(xy 31.900368 -398.351502) (xy 31.900368 -398.193514) (xy 31.899936 -398.184329) (xy 31.893436 -398.167146)
			(xy 31.887668 -398.159986) (xy 31.865842 -398.134365) (xy 31.827892 -398.078775) (xy 31.796859 -398.019047)
			(xy 31.773187 -397.956039) (xy 31.757216 -397.890652) (xy 31.749174 -397.823826) (xy 30.620528 -397.823826)
			(xy 30.592066 -397.878596) (xy 30.554113 -397.934182) (xy 30.532324 -397.959834) (xy 30.526533 -397.966984)
			(xy 30.520014 -397.984171) (xy 30.519624 -397.993362) (xy 30.519624 -398.486884) (xy 30.520036 -398.496071)
			(xy 30.526548 -398.513256) (xy 30.532324 -398.520412) (xy 30.554149 -398.546034) (xy 30.592099 -398.601624)
			(xy 30.623132 -398.661352) (xy 30.646805 -398.72436) (xy 30.662776 -398.789746) (xy 30.670818 -398.856573)
			(xy 30.670815 -398.923881) (xy 30.662767 -398.990707) (xy 30.646789 -399.056092) (xy 30.62311 -399.119098)
			(xy 30.592071 -399.178822) (xy 30.554115 -399.234409) (xy 30.532324 -399.26006) (xy 30.526522 -399.267202)
			(xy 30.52001 -399.284395) (xy 30.519624 -399.293588) (xy 30.519624 -399.451576) (xy 30.519159 -399.461726)
			(xy 30.511376 -399.480473) (xy 30.496993 -399.494796) (xy 30.478213 -399.502501) (xy 30.468062 -399.502884)
			(xy 29.751782 -399.502884) (xy 29.741657 -399.502389) (xy 29.72294 -399.49466) (xy 29.708585 -399.480377)
			(xy 29.700762 -399.461698) (xy 29.70022 -399.451576) (xy 29.70022 -399.293588) (xy 29.699811 -399.284401)
			(xy 29.693296 -399.267217) (xy 29.68752 -399.26006) (xy 29.665769 -399.234378) (xy 29.62782 -399.178796)
			(xy 29.596786 -399.119076) (xy 29.573112 -399.056075) (xy 29.557137 -398.990697) (xy 29.549091 -398.923878)
			(xy 29.549087 -398.856576) (xy 29.557128 -398.789756) (xy 29.573096 -398.724376) (xy 29.596764 -398.661374)
			(xy 29.627792 -398.601651) (xy 29.665735 -398.546065) (xy 29.68752 -398.520412) (xy 29.693339 -398.513283)
			(xy 29.69984 -398.49608) (xy 29.70022 -398.486884) (xy 29.70022 -397.993362) (xy 29.699824 -397.984173)
			(xy 29.6933 -397.966989) (xy 29.68752 -397.959834) (xy 29.665743 -397.934174) (xy 29.627795 -397.878588)
			(xy 29.596762 -397.818865) (xy 29.57309 -397.755862) (xy 29.557116 -397.690481) (xy 29.549072 -397.623659)
			(xy 29.549071 -397.556356) (xy 28.420857 -397.556356) (xy 28.423249 -397.560947) (xy 28.447016 -397.62404)
			(xy 28.463055 -397.689526) (xy 28.471134 -397.756461) (xy 28.471138 -397.823882) (xy 28.463065 -397.890818)
			(xy 28.447033 -397.956305) (xy 28.423272 -398.019401) (xy 28.392124 -398.079196) (xy 28.354039 -398.134829)
			(xy 28.332176 -398.160494) (xy 28.326397 -398.167651) (xy 28.319873 -398.184833) (xy 28.319476 -398.194022)
			(xy 28.319476 -398.351502) (xy 28.318975 -398.361627) (xy 28.31125 -398.380345) (xy 28.296968 -398.394701)
			(xy 28.27829 -398.402523) (xy 28.268168 -398.403064) (xy 27.551888 -398.403064) (xy 27.541729 -398.402688)
			(xy 27.522969 -398.394881) (xy 27.508645 -398.38047) (xy 27.500952 -398.361664) (xy 27.50058 -398.351502)
			(xy 27.50058 -398.194022) (xy 27.500164 -398.184835) (xy 27.493655 -398.167651) (xy 27.48788 -398.160494)
			(xy 27.465979 -398.134859) (xy 27.427893 -398.07922) (xy 27.396745 -398.019419) (xy 27.372984 -397.956318)
			(xy 27.356952 -397.890826) (xy 27.348879 -397.823885) (xy 8.839736 -397.823885) (xy 8.850142 -397.906253)
			(xy 8.858264 -398.035359) (xy 8.858264 -398.164721) (xy 8.850142 -398.293827) (xy 8.833928 -398.422169)
			(xy 8.809688 -398.549239) (xy 8.777518 -398.674536) (xy 8.737543 -398.797566) (xy 8.689921 -398.917844)
			(xy 8.634842 -399.034893) (xy 8.572521 -399.148254) (xy 8.503206 -399.257477) (xy 8.427169 -399.362133)
			(xy 8.344711 -399.461808) (xy 8.256157 -399.556108) (xy 8.161856 -399.644662) (xy 8.062181 -399.72712)
			(xy 7.957526 -399.803157) (xy 7.848302 -399.872472) (xy 7.734942 -399.934793) (xy 7.617892 -399.989872)
			(xy 7.497614 -400.037493) (xy 7.374584 -400.077468) (xy 7.249287 -400.109639) (xy 7.122217 -400.133879)
			(xy 6.993875 -400.150092) (xy 6.864769 -400.158214) (xy 6.800088 -400.158712) (xy 5.199888 -400.158712)
			(xy 5.135208 -400.158204) (xy 5.006102 -400.150081) (xy 4.877762 -400.133868) (xy 4.750692 -400.109628)
			(xy 4.625396 -400.077458) (xy 4.502366 -400.037483) (xy 4.38209 -399.989862) (xy 4.265041 -399.934783)
			(xy 4.151681 -399.872463) (xy 4.042458 -399.803148) (xy 3.937803 -399.727112) (xy 3.838129 -399.644654)
			(xy 3.743829 -399.556101) (xy 3.655276 -399.461801) (xy 3.572818 -399.362127) (xy 3.496782 -399.257472)
			(xy 3.427467 -399.148249) (xy 3.365147 -399.034889) (xy 3.310068 -398.91784) (xy 3.262447 -398.797564)
			(xy 3.222472 -398.674534) (xy 3.190302 -398.549238) (xy 3.166062 -398.422168) (xy 3.149849 -398.293828)
			(xy 3.141726 -398.164722) (xy 0.509016 -398.164722) (xy 0.509016 -401.723796) (xy 27.348891 -401.723796)
			(xy 27.348893 -401.656371) (xy 27.35697 -401.589432) (xy 27.373007 -401.523942) (xy 27.396773 -401.460844)
			(xy 27.427925 -401.401047) (xy 27.466015 -401.345412) (xy 27.48788 -401.319746) (xy 27.49368 -401.312603)
			(xy 27.500193 -401.295411) (xy 27.50058 -401.286218) (xy 27.50058 -400.793966) (xy 27.500191 -400.784777)
			(xy 27.493663 -400.767592) (xy 27.48788 -400.760438) (xy 27.466023 -400.734768) (xy 27.427935 -400.679133)
			(xy 27.396785 -400.619338) (xy 27.373022 -400.556241) (xy 27.356986 -400.490753) (xy 27.34891 -400.423816)
			(xy 27.34891 -400.356393) (xy 27.356985 -400.289456) (xy 27.373019 -400.223967) (xy 27.396782 -400.160871)
			(xy 27.42793 -400.101074) (xy 27.466017 -400.04544) (xy 27.48788 -400.019774) (xy 27.493668 -400.012622)
			(xy 27.500188 -399.995437) (xy 27.50058 -399.986246) (xy 27.50058 -399.828766) (xy 27.501 -399.818632)
			(xy 27.508746 -399.799903) (xy 27.523053 -399.785546) (xy 27.541756 -399.777735) (xy 27.551888 -399.777204)
			(xy 28.268168 -399.777204) (xy 28.278321 -399.777648) (xy 28.297073 -399.785433) (xy 28.311398 -399.799824)
			(xy 28.319098 -399.818612) (xy 28.319476 -399.828766) (xy 28.319476 -399.986246) (xy 28.319918 -399.99543)
			(xy 28.32641 -400.012614) (xy 28.332176 -400.019774) (xy 28.354047 -400.045434) (xy 28.392137 -400.101069)
			(xy 28.423289 -400.160865) (xy 28.447053 -400.223963) (xy 28.463089 -400.289453) (xy 28.471165 -400.356392)
			(xy 28.471165 -400.423817) (xy 28.463088 -400.490756) (xy 28.447051 -400.556246) (xy 28.423285 -400.619343)
			(xy 28.392132 -400.679139) (xy 28.354041 -400.734773) (xy 28.332176 -400.760438) (xy 28.326378 -400.767582)
			(xy 28.319865 -400.784774) (xy 28.319476 -400.793966) (xy 28.319476 -401.286218) (xy 28.319883 -401.295405)
			(xy 28.326399 -401.31259) (xy 28.332176 -401.319746) (xy 28.354019 -401.345429) (xy 28.39211 -401.40106)
			(xy 28.423263 -401.460854) (xy 28.446989 -401.523838) (xy 29.549051 -401.523838) (xy 29.549053 -401.456532)
			(xy 29.557098 -401.389708) (xy 29.573073 -401.324325) (xy 29.596747 -401.26132) (xy 29.627782 -401.201596)
			(xy 29.665732 -401.146008) (xy 29.68752 -401.120356) (xy 29.69332 -401.113213) (xy 29.699832 -401.096021)
			(xy 29.70022 -401.086828) (xy 29.70022 -400.92884) (xy 29.700655 -400.918686) (xy 29.708441 -400.899931)
			(xy 29.722834 -400.885605) (xy 29.741626 -400.877908) (xy 29.751782 -400.877532) (xy 30.468062 -400.877532)
			(xy 30.478185 -400.878058) (xy 30.496904 -400.885771) (xy 30.511261 -400.900046) (xy 30.519083 -400.91872)
			(xy 30.519624 -400.92884) (xy 30.519624 -401.086828) (xy 30.520015 -401.096017) (xy 30.526542 -401.113202)
			(xy 30.532324 -401.120356) (xy 30.554093 -401.146024) (xy 30.592045 -401.201607) (xy 30.623081 -401.261328)
			(xy 30.646757 -401.324331) (xy 30.662732 -401.389711) (xy 30.670778 -401.456533) (xy 30.67078 -401.523837)
			(xy 30.662738 -401.590659) (xy 30.646766 -401.65604) (xy 30.623093 -401.719044) (xy 30.620654 -401.723737)
			(xy 31.749186 -401.723737) (xy 31.749188 -401.65643) (xy 31.757235 -401.589605) (xy 31.773211 -401.524221)
			(xy 31.796887 -401.461216) (xy 31.827925 -401.401492) (xy 31.865878 -401.345906) (xy 31.887668 -401.320254)
			(xy 31.893475 -401.313116) (xy 31.899981 -401.29592) (xy 31.900368 -401.286726) (xy 31.900368 -400.793458)
			(xy 31.899963 -400.784271) (xy 31.893444 -400.767087) (xy 31.887668 -400.75993) (xy 31.865885 -400.734273)
			(xy 31.827935 -400.678688) (xy 31.796899 -400.618966) (xy 31.773225 -400.555962) (xy 31.757251 -400.49058)
			(xy 31.749206 -400.423757) (xy 31.749205 -400.356452) (xy 31.757249 -400.289629) (xy 31.773222 -400.224247)
			(xy 31.796896 -400.161243) (xy 31.82793 -400.10152) (xy 31.86588 -400.045934) (xy 31.887668 -400.020282)
			(xy 31.893463 -400.013136) (xy 31.899977 -399.995946) (xy 31.900368 -399.986754) (xy 31.900368 -399.828766)
			(xy 31.900806 -399.818602) (xy 31.908597 -399.799827) (xy 31.92298 -399.785462) (xy 31.941766 -399.777694)
			(xy 31.95193 -399.777204) (xy 32.66821 -399.777204) (xy 32.678364 -399.777725) (xy 32.697127 -399.785496)
			(xy 32.711491 -399.799853) (xy 32.719271 -399.818612) (xy 32.719772 -399.828766) (xy 32.719772 -399.986754)
			(xy 32.720211 -399.995938) (xy 32.726705 -400.013122) (xy 32.732472 -400.020282) (xy 32.754265 -400.045929)
			(xy 32.792213 -400.101517) (xy 32.823246 -400.161241) (xy 32.846918 -400.224246) (xy 32.86289 -400.289629)
			(xy 32.870933 -400.356452) (xy 32.870933 -400.423757) (xy 32.862888 -400.49058) (xy 32.846915 -400.555962)
			(xy 32.823242 -400.618967) (xy 32.792209 -400.678691) (xy 32.75426 -400.734278) (xy 32.732472 -400.75993)
			(xy 32.726677 -400.767076) (xy 32.720162 -400.784266) (xy 32.719772 -400.793458) (xy 32.719772 -401.286726)
			(xy 32.720176 -401.295914) (xy 32.726695 -401.313098) (xy 32.732472 -401.320254) (xy 32.754237 -401.345924)
			(xy 32.792186 -401.401508) (xy 32.82322 -401.46123) (xy 32.846893 -401.524232) (xy 32.862868 -401.589612)
			(xy 32.870913 -401.656432) (xy 32.870915 -401.723735) (xy 32.862873 -401.790556) (xy 32.846903 -401.855937)
			(xy 32.823233 -401.91894) (xy 32.792203 -401.978663) (xy 32.754258 -402.03425) (xy 32.732472 -402.059902)
			(xy 32.726688 -402.067056) (xy 32.720167 -402.08424) (xy 32.719772 -402.09343) (xy 32.719772 -402.251418)
			(xy 32.719282 -402.261576) (xy 32.711503 -402.280343) (xy 32.697137 -402.294708) (xy 32.678368 -402.302483)
			(xy 32.66821 -402.30298) (xy 31.95193 -402.30298) (xy 31.941763 -402.302512) (xy 31.922972 -402.29474)
			(xy 31.908587 -402.280368) (xy 31.900798 -402.261585) (xy 31.900368 -402.251418) (xy 31.900368 -402.09343)
			(xy 31.899928 -402.084246) (xy 31.893434 -402.067062) (xy 31.887668 -402.059902) (xy 31.865858 -402.034268)
			(xy 31.827908 -401.97868) (xy 31.796874 -401.918954) (xy 31.773201 -401.855947) (xy 31.757229 -401.790562)
			(xy 31.749186 -401.723737) (xy 30.620654 -401.723737) (xy 30.59206 -401.778767) (xy 30.554112 -401.834352)
			(xy 30.532324 -401.860004) (xy 30.526546 -401.867163) (xy 30.520019 -401.884343) (xy 30.519624 -401.893532)
			(xy 30.519624 -402.3868) (xy 30.520029 -402.395988) (xy 30.526546 -402.413172) (xy 30.532324 -402.420328)
			(xy 30.554114 -402.445978) (xy 30.592063 -402.501565) (xy 30.623097 -402.561289) (xy 30.64677 -402.624293)
			(xy 30.662743 -402.689676) (xy 30.670787 -402.756499) (xy 30.670787 -402.823804) (xy 30.670778 -402.823878)
			(xy 33.948799 -402.823878) (xy 33.948804 -402.75645) (xy 33.956885 -402.689508) (xy 33.972926 -402.624016)
			(xy 33.996696 -402.560917) (xy 34.027853 -402.50112) (xy 34.065949 -402.445485) (xy 34.087816 -402.41982)
			(xy 34.093631 -402.412688) (xy 34.100134 -402.395487) (xy 34.100516 -402.386292) (xy 34.100516 -401.89404)
			(xy 34.100083 -401.884855) (xy 34.093585 -401.867671) (xy 34.087816 -401.860512) (xy 34.065932 -401.834863)
			(xy 34.027843 -401.779227) (xy 33.996692 -401.719428) (xy 33.972928 -401.656329) (xy 33.956894 -401.590838)
			(xy 33.948819 -401.523898) (xy 33.948821 -401.456472) (xy 33.956899 -401.389532) (xy 33.972937 -401.324042)
			(xy 33.996704 -401.260944) (xy 34.027858 -401.201147) (xy 34.06595 -401.145513) (xy 34.087816 -401.119848)
			(xy 34.093619 -401.112707) (xy 34.100129 -401.095513) (xy 34.100516 -401.08632) (xy 34.100516 -400.92884)
			(xy 34.100949 -400.918718) (xy 34.108687 -400.900012) (xy 34.122999 -400.885696) (xy 34.141702 -400.877952)
			(xy 34.151824 -400.877532) (xy 34.868104 -400.877532) (xy 34.878231 -400.877914) (xy 34.89694 -400.885669)
			(xy 34.911256 -400.899997) (xy 34.918995 -400.918713) (xy 34.919412 -400.92884) (xy 34.919412 -401.08632)
			(xy 34.91981 -401.095509) (xy 34.926332 -401.112693) (xy 34.932112 -401.119848) (xy 34.953956 -401.14553)
			(xy 34.992044 -401.201162) (xy 35.023195 -401.260956) (xy 35.04696 -401.324051) (xy 35.062997 -401.389538)
			(xy 35.071074 -401.456474) (xy 35.071076 -401.523896) (xy 35.063002 -401.590833) (xy 35.046969 -401.65632)
			(xy 35.023208 -401.719416) (xy 35.020926 -401.723796) (xy 36.148978 -401.723796) (xy 36.14898 -401.656371)
			(xy 36.157058 -401.589432) (xy 36.173095 -401.523942) (xy 36.19686 -401.460845) (xy 36.228011 -401.401047)
			(xy 36.2661 -401.345412) (xy 36.287964 -401.319746) (xy 36.293774 -401.312611) (xy 36.300279 -401.295412)
			(xy 36.300664 -401.286218) (xy 36.300664 -400.793966) (xy 36.300256 -400.784779) (xy 36.293739 -400.767595)
			(xy 36.287964 -400.760438) (xy 36.266107 -400.734767) (xy 36.228021 -400.679133) (xy 36.196872 -400.619337)
			(xy 36.173109 -400.556241) (xy 36.157074 -400.490753) (xy 36.148998 -400.423816) (xy 36.148998 -400.356393)
			(xy 36.157072 -400.289456) (xy 36.173106 -400.223968) (xy 36.196868 -400.160871) (xy 36.228016 -400.101075)
			(xy 36.266102 -400.04544) (xy 36.287964 -400.019774) (xy 36.293762 -400.01263) (xy 36.300274 -399.995438)
			(xy 36.300664 -399.986246) (xy 36.300664 -399.828766) (xy 36.301099 -399.818634) (xy 36.308843 -399.799908)
			(xy 36.323145 -399.785552) (xy 36.341842 -399.777738) (xy 36.351972 -399.777204) (xy 37.068252 -399.777204)
			(xy 37.078404 -399.777661) (xy 37.097156 -399.785442) (xy 37.111481 -399.799828) (xy 37.119181 -399.818613)
			(xy 37.11956 -399.828766) (xy 37.11956 -399.986246) (xy 37.120005 -399.995429) (xy 37.126496 -400.012613)
			(xy 37.13226 -400.019774) (xy 37.154131 -400.045434) (xy 37.192222 -400.101068) (xy 37.223375 -400.160865)
			(xy 37.247141 -400.223962) (xy 37.263177 -400.289453) (xy 37.271253 -400.356392) (xy 37.271252 -400.423817)
			(xy 37.263175 -400.490756) (xy 37.247138 -400.556246) (xy 37.223371 -400.619344) (xy 37.192218 -400.67914)
			(xy 37.154126 -400.734773) (xy 37.13226 -400.760438) (xy 37.12646 -400.76758) (xy 37.119948 -400.784773)
			(xy 37.11956 -400.793966) (xy 37.11956 -401.286218) (xy 37.11997 -401.295405) (xy 37.126485 -401.312589)
			(xy 37.13226 -401.319746) (xy 37.154104 -401.345428) (xy 37.192196 -401.40106) (xy 37.22335 -401.460853)
			(xy 37.247117 -401.523948) (xy 37.263155 -401.589435) (xy 37.271233 -401.656372) (xy 37.271235 -401.723795)
			(xy 37.263161 -401.790732) (xy 37.247127 -401.856221) (xy 37.223363 -401.919317) (xy 37.192213 -401.979112)
			(xy 37.154124 -402.034745) (xy 37.13226 -402.06041) (xy 37.126472 -402.067561) (xy 37.119953 -402.084747)
			(xy 37.11956 -402.093938) (xy 37.11956 -402.251418) (xy 37.119088 -402.261546) (xy 37.111355 -402.280268)
			(xy 37.097064 -402.294623) (xy 37.078378 -402.302442) (xy 37.068252 -402.30298) (xy 36.351972 -402.30298)
			(xy 36.341814 -402.302601) (xy 36.323057 -402.294792) (xy 36.308734 -402.280383) (xy 36.301038 -402.261579)
			(xy 36.300664 -402.251418) (xy 36.300664 -402.093938) (xy 36.300221 -402.084755) (xy 36.293729 -402.067571)
			(xy 36.287964 -402.06041) (xy 36.26608 -402.034762) (xy 36.227994 -401.979124) (xy 36.196846 -401.919325)
			(xy 36.173085 -401.856226) (xy 36.157052 -401.790735) (xy 36.148978 -401.723796) (xy 35.020926 -401.723796)
			(xy 34.99206 -401.779212) (xy 34.953974 -401.834847) (xy 34.932112 -401.860512) (xy 34.926329 -401.867667)
			(xy 34.919806 -401.88485) (xy 34.919412 -401.89404) (xy 34.919412 -402.386292) (xy 34.919823 -402.395479)
			(xy 34.926336 -402.412664) (xy 34.932112 -402.41982) (xy 34.953928 -402.445524) (xy 34.992018 -402.501154)
			(xy 35.02317 -402.560944) (xy 35.046936 -402.624036) (xy 35.062975 -402.68952) (xy 35.071054 -402.756454)
			(xy 35.071059 -402.823818) (xy 38.349119 -402.823818) (xy 38.349123 -402.75651) (xy 38.357172 -402.689685)
			(xy 38.373149 -402.6243) (xy 38.396825 -402.561294) (xy 38.427862 -402.501569) (xy 38.465814 -402.445981)
			(xy 38.487604 -402.420328) (xy 38.493414 -402.413192) (xy 38.499921 -402.395995) (xy 38.500304 -402.3868)
			(xy 38.500304 -401.893532) (xy 38.499878 -401.884347) (xy 38.493375 -401.867162) (xy 38.487604 -401.860004)
			(xy 38.465798 -401.834368) (xy 38.427852 -401.778778) (xy 38.396821 -401.719052) (xy 38.373151 -401.656045)
			(xy 38.357181 -401.590662) (xy 38.349139 -401.523838) (xy 38.34914 -401.456532) (xy 38.357186 -401.389709)
			(xy 38.37316 -401.324326) (xy 38.396834 -401.261321) (xy 38.427867 -401.201596) (xy 38.465816 -401.146009)
			(xy 38.487604 -401.120356) (xy 38.493402 -401.113212) (xy 38.499916 -401.096021) (xy 38.500304 -401.086828)
			(xy 38.500304 -400.92884) (xy 38.500755 -400.918688) (xy 38.508538 -400.899936) (xy 38.522926 -400.885611)
			(xy 38.541712 -400.87791) (xy 38.551866 -400.877532) (xy 39.268146 -400.877532) (xy 39.278275 -400.877989)
			(xy 39.296995 -400.88573) (xy 39.31135 -400.900025) (xy 39.319169 -400.918714) (xy 39.319708 -400.92884)
			(xy 39.319708 -401.086828) (xy 39.320103 -401.096017) (xy 39.326627 -401.113201) (xy 39.332408 -401.120356)
			(xy 39.354178 -401.146024) (xy 39.392131 -401.201607) (xy 39.423168 -401.261328) (xy 39.446844 -401.32433)
			(xy 39.46282 -401.389711) (xy 39.470866 -401.456533) (xy 39.470868 -401.523837) (xy 39.462825 -401.590659)
			(xy 39.446853 -401.656041) (xy 39.42318 -401.719045) (xy 39.420711 -401.723797) (xy 40.548745 -401.723797)
			(xy 40.548747 -401.65637) (xy 40.556826 -401.58943) (xy 40.572865 -401.523939) (xy 40.596634 -401.460841)
			(xy 40.62779 -401.401044) (xy 40.665885 -401.34541) (xy 40.687752 -401.319746) (xy 40.69356 -401.312609)
			(xy 40.700067 -401.295412) (xy 40.700452 -401.286218) (xy 40.700452 -400.793966) (xy 40.700046 -400.784779)
			(xy 40.693528 -400.767595) (xy 40.687752 -400.760438) (xy 40.665892 -400.734769) (xy 40.6278 -400.679136)
			(xy 40.596646 -400.619341) (xy 40.572879 -400.556244) (xy 40.556842 -400.490755) (xy 40.548764 -400.423817)
			(xy 40.548764 -400.356392) (xy 40.55684 -400.289454) (xy 40.572876 -400.223964) (xy 40.596642 -400.160867)
			(xy 40.627795 -400.101072) (xy 40.665887 -400.045438) (xy 40.687752 -400.019774) (xy 40.693549 -400.012629)
			(xy 40.700062 -399.995438) (xy 40.700452 -399.986246) (xy 40.700452 -399.828766) (xy 40.700899 -399.818636)
			(xy 40.70864 -399.799911) (xy 40.722939 -399.785556) (xy 40.741632 -399.77774) (xy 40.75176 -399.777204)
			(xy 41.46804 -399.777204) (xy 41.478197 -399.777589) (xy 41.496951 -399.785399) (xy 41.511273 -399.799806)
			(xy 41.518971 -399.818606) (xy 41.519348 -399.828766) (xy 41.519348 -399.986246) (xy 41.519796 -399.995429)
			(xy 41.526285 -400.012613) (xy 41.532048 -400.019774) (xy 41.55392 -400.045433) (xy 41.592012 -400.101068)
			(xy 41.623165 -400.160864) (xy 41.646931 -400.223962) (xy 41.662968 -400.289452) (xy 41.671044 -400.356392)
			(xy 41.671043 -400.423817) (xy 41.662966 -400.490757) (xy 41.646928 -400.556247) (xy 41.623161 -400.619344)
			(xy 41.592007 -400.67914) (xy 41.553914 -400.734774) (xy 41.532048 -400.760438) (xy 41.526246 -400.767579)
			(xy 41.519736 -400.784773) (xy 41.519348 -400.793966) (xy 41.519348 -401.286218) (xy 41.519761 -401.295405)
			(xy 41.526274 -401.312588) (xy 41.532048 -401.319746) (xy 41.553892 -401.345428) (xy 41.591985 -401.401059)
			(xy 41.62314 -401.460852) (xy 41.646907 -401.523947) (xy 41.662946 -401.589435) (xy 41.671024 -401.656372)
			(xy 41.671026 -401.723795) (xy 41.662952 -401.790733) (xy 41.646917 -401.856221) (xy 41.623153 -401.919317)
			(xy 41.592002 -401.979113) (xy 41.553912 -402.034746) (xy 41.532048 -402.06041) (xy 41.526258 -402.06756)
			(xy 41.519741 -402.084747) (xy 41.519348 -402.093938) (xy 41.519348 -402.251418) (xy 41.518888 -402.261547)
			(xy 41.511152 -402.280271) (xy 41.496858 -402.294627) (xy 41.478167 -402.302444) (xy 41.46804 -402.30298)
			(xy 40.75176 -402.30298) (xy 40.741601 -402.302611) (xy 40.722844 -402.294798) (xy 40.708521 -402.280385)
			(xy 40.700826 -402.26158) (xy 40.700452 -402.251418) (xy 40.700452 -402.093938) (xy 40.700012 -402.084754)
			(xy 40.693518 -402.06757) (xy 40.687752 -402.06041) (xy 40.665865 -402.034763) (xy 40.627773 -401.979127)
			(xy 40.59662 -401.919329) (xy 40.572855 -401.85623) (xy 40.55682 -401.790738) (xy 40.548745 -401.723797)
			(xy 39.420711 -401.723797) (xy 39.392146 -401.778768) (xy 39.354196 -401.834353) (xy 39.332408 -401.860004)
			(xy 39.326628 -401.867161) (xy 39.320103 -401.884342) (xy 39.319708 -401.893532) (xy 39.319708 -402.3868)
			(xy 39.320116 -402.395987) (xy 39.326631 -402.413172) (xy 39.332408 -402.420328) (xy 39.35415 -402.446018)
			(xy 39.392104 -402.501598) (xy 39.423142 -402.561316) (xy 39.44682 -402.624315) (xy 39.462798 -402.689694)
			(xy 39.470847 -402.756513) (xy 39.470851 -402.823815) (xy 39.470843 -402.823878) (xy 42.748887 -402.823878)
			(xy 42.748892 -402.75645) (xy 42.756972 -402.689509) (xy 42.773013 -402.624017) (xy 42.796782 -402.560918)
			(xy 42.827939 -402.501121) (xy 42.866033 -402.445485) (xy 42.8879 -402.41982) (xy 42.893713 -402.412686)
			(xy 42.900218 -402.395487) (xy 42.9006 -402.386292) (xy 42.9006 -401.89404) (xy 42.900171 -401.884855)
			(xy 42.89367 -401.86767) (xy 42.8879 -401.860512) (xy 42.866016 -401.834863) (xy 42.827928 -401.779226)
			(xy 42.796778 -401.719428) (xy 42.773015 -401.656329) (xy 42.756981 -401.590838) (xy 42.748907 -401.523898)
			(xy 42.748909 -401.456472) (xy 42.756987 -401.389533) (xy 42.773024 -401.324043) (xy 42.796791 -401.260945)
			(xy 42.827944 -401.201148) (xy 42.866035 -401.145513) (xy 42.8879 -401.119848) (xy 42.893701 -401.112706)
			(xy 42.900213 -401.095513) (xy 42.9006 -401.08632) (xy 42.9006 -400.92884) (xy 42.901049 -400.91872)
			(xy 42.908784 -400.900017) (xy 42.923091 -400.885702) (xy 42.941788 -400.877955) (xy 42.951908 -400.877532)
			(xy 43.668188 -400.877532) (xy 43.678314 -400.877927) (xy 43.697023 -400.885677) (xy 43.711339 -400.9)
			(xy 43.719079 -400.918714) (xy 43.719496 -400.92884) (xy 43.719496 -401.08632) (xy 43.719897 -401.095508)
			(xy 43.726417 -401.112692) (xy 43.732196 -401.119848) (xy 43.75404 -401.145529) (xy 43.79213 -401.201162)
			(xy 43.823282 -401.260955) (xy 43.847047 -401.32405) (xy 43.863084 -401.389537) (xy 43.871162 -401.456474)
			(xy 43.871164 -401.523896) (xy 43.86309 -401.590833) (xy 43.847056 -401.656321) (xy 43.823294 -401.719417)
			(xy 43.821044 -401.723737) (xy 44.949064 -401.723737) (xy 44.949066 -401.65643) (xy 44.957113 -401.589606)
			(xy 44.973088 -401.524222) (xy 44.996763 -401.461217) (xy 45.027799 -401.401493) (xy 45.065751 -401.345906)
			(xy 45.08754 -401.320254) (xy 45.093344 -401.313114) (xy 45.099853 -401.295919) (xy 45.10024 -401.286726)
			(xy 45.10024 -400.793458) (xy 45.099841 -400.78427) (xy 45.093319 -400.767086) (xy 45.08754 -400.75993)
			(xy 45.065758 -400.734273) (xy 45.027809 -400.678687) (xy 44.996776 -400.618964) (xy 44.973103 -400.55596)
			(xy 44.957129 -400.490579) (xy 44.949085 -400.423757) (xy 44.949084 -400.356452) (xy 44.957128 -400.28963)
			(xy 44.9731 -400.224248) (xy 44.996772 -400.161244) (xy 45.027805 -400.101521) (xy 45.065753 -400.045934)
			(xy 45.08754 -400.020282) (xy 45.093332 -400.013134) (xy 45.099848 -399.995945) (xy 45.10024 -399.986754)
			(xy 45.10024 -399.828766) (xy 45.100706 -399.818606) (xy 45.108492 -399.799835) (xy 45.122866 -399.785471)
			(xy 45.141641 -399.777698) (xy 45.151802 -399.777204) (xy 45.868082 -399.777204) (xy 45.878234 -399.777747)
			(xy 45.896997 -399.785509) (xy 45.911361 -399.79986) (xy 45.919143 -399.818614) (xy 45.919644 -399.828766)
			(xy 45.919644 -399.986754) (xy 45.920089 -399.995937) (xy 45.92658 -400.013121) (xy 45.932344 -400.020282)
			(xy 45.954138 -400.045929) (xy 45.992088 -400.101516) (xy 46.023122 -400.16124) (xy 46.046795 -400.224245)
			(xy 46.062768 -400.289628) (xy 46.070812 -400.356452) (xy 46.070811 -400.423757) (xy 46.062766 -400.490581)
			(xy 46.046792 -400.555963) (xy 46.023118 -400.618968) (xy 45.992083 -400.678692) (xy 45.954132 -400.734278)
			(xy 45.932344 -400.75993) (xy 45.926545 -400.767073) (xy 45.920033 -400.784266) (xy 45.919644 -400.793458)
			(xy 45.919644 -401.286726) (xy 45.920054 -401.295913) (xy 45.926569 -401.313097) (xy 45.932344 -401.320254)
			(xy 45.95411 -401.345924) (xy 45.992061 -401.401507) (xy 46.023096 -401.461228) (xy 46.046771 -401.524231)
			(xy 46.062746 -401.589611) (xy 46.070792 -401.656432) (xy 46.070794 -401.723735) (xy 46.062752 -401.790557)
			(xy 46.046781 -401.855938) (xy 46.02311 -401.918941) (xy 45.992078 -401.978664) (xy 45.954131 -402.03425)
			(xy 45.932344 -402.059902) (xy 45.926557 -402.067054) (xy 45.920038 -402.084239) (xy 45.919644 -402.09343)
			(xy 45.919644 -402.251418) (xy 45.919181 -402.261579) (xy 45.911397 -402.280352) (xy 45.897022 -402.294718)
			(xy 45.878244 -402.302488) (xy 45.868082 -402.30298) (xy 45.151802 -402.30298) (xy 45.141647 -402.302465)
			(xy 45.122881 -402.294695) (xy 45.108516 -402.280336) (xy 45.100739 -402.261573) (xy 45.10024 -402.251418)
			(xy 45.10024 -402.09343) (xy 45.099806 -402.084246) (xy 45.093308 -402.067061) (xy 45.08754 -402.059902)
			(xy 45.06573 -402.034268) (xy 45.027782 -401.978679) (xy 44.99675 -401.918953) (xy 44.973078 -401.855946)
			(xy 44.957107 -401.790561) (xy 44.949064 -401.723737) (xy 43.821044 -401.723737) (xy 43.792146 -401.779213)
			(xy 43.754059 -401.834847) (xy 43.732196 -401.860512) (xy 43.726411 -401.867666) (xy 43.71989 -401.88485)
			(xy 43.719496 -401.89404) (xy 43.719496 -402.386292) (xy 43.719911 -402.395479) (xy 43.726421 -402.412663)
			(xy 43.732196 -402.41982) (xy 43.754013 -402.445524) (xy 43.792103 -402.501153) (xy 43.823256 -402.560944)
			(xy 43.847023 -402.624036) (xy 43.863062 -402.68952) (xy 43.871142 -402.756454) (xy 43.871146 -402.823874)
			(xy 43.863075 -402.890809) (xy 43.847045 -402.956295) (xy 43.823286 -403.01939) (xy 43.792141 -403.079185)
			(xy 43.754057 -403.134819) (xy 43.732196 -403.160484) (xy 43.726381 -403.167616) (xy 43.719877 -403.184817)
			(xy 43.719496 -403.194012) (xy 43.719496 -403.351492) (xy 43.719077 -403.361614) (xy 43.711331 -403.380319)
			(xy 43.697015 -403.394633) (xy 43.67831 -403.402378) (xy 43.668188 -403.4028) (xy 42.951908 -403.4028)
			(xy 42.941786 -403.402377) (xy 42.923083 -403.394632) (xy 42.908768 -403.380317) (xy 42.901023 -403.361614)
			(xy 42.9006 -403.351492) (xy 42.9006 -403.194012) (xy 42.900184 -403.184825) (xy 42.893674 -403.167641)
			(xy 42.8879 -403.160484) (xy 42.865989 -403.134858) (xy 42.827902 -403.079218) (xy 42.796753 -403.019416)
			(xy 42.772992 -402.956314) (xy 42.756959 -402.89082) (xy 42.748887 -402.823878) (xy 39.470843 -402.823878)
			(xy 39.462811 -402.890635) (xy 39.446841 -402.956016) (xy 39.423172 -403.019018) (xy 39.392141 -403.07874)
			(xy 39.354194 -403.134325) (xy 39.332408 -403.159976) (xy 39.326598 -403.167111) (xy 39.320091 -403.184309)
			(xy 39.319708 -403.193504) (xy 39.319708 -403.351492) (xy 39.319272 -403.361645) (xy 39.311481 -403.380395)
			(xy 39.297088 -403.394719) (xy 39.278301 -403.40242) (xy 39.268146 -403.4028) (xy 38.551866 -403.4028)
			(xy 38.541742 -403.402303) (xy 38.523028 -403.394571) (xy 38.508674 -403.380289) (xy 38.500849 -403.361613)
			(xy 38.500304 -403.351492) (xy 38.500304 -403.193504) (xy 38.499891 -403.184317) (xy 38.493379 -403.167133)
			(xy 38.487604 -403.159976) (xy 38.46577 -403.134362) (xy 38.427825 -403.078769) (xy 38.396796 -403.01904)
			(xy 38.373127 -402.956031) (xy 38.357159 -402.890644) (xy 38.349119 -402.823818) (xy 35.071059 -402.823818)
			(xy 35.071059 -402.823874) (xy 35.062988 -402.890809) (xy 35.046958 -402.956295) (xy 35.023199 -403.01939)
			(xy 34.992055 -403.079185) (xy 34.953973 -403.134819) (xy 34.932112 -403.160484) (xy 34.926299 -403.167617)
			(xy 34.919794 -403.184817) (xy 34.919412 -403.194012) (xy 34.919412 -403.351492) (xy 34.918978 -403.361612)
			(xy 34.911234 -403.380314) (xy 34.896924 -403.394628) (xy 34.878224 -403.402375) (xy 34.868104 -403.4028)
			(xy 34.151824 -403.4028) (xy 34.141703 -403.402365) (xy 34.123 -403.394624) (xy 34.108685 -403.380314)
			(xy 34.100939 -403.361613) (xy 34.100516 -403.351492) (xy 34.100516 -403.194012) (xy 34.100096 -403.184826)
			(xy 34.093589 -403.167642) (xy 34.087816 -403.160484) (xy 34.065904 -403.134858) (xy 34.027816 -403.079218)
			(xy 33.996666 -403.019417) (xy 33.972904 -402.956315) (xy 33.956872 -402.890821) (xy 33.948799 -402.823878)
			(xy 30.670778 -402.823878) (xy 30.662742 -402.890627) (xy 30.646769 -402.956009) (xy 30.623096 -403.019014)
			(xy 30.592062 -403.078738) (xy 30.554112 -403.134324) (xy 30.532324 -403.159976) (xy 30.526515 -403.167113)
			(xy 30.520007 -403.18431) (xy 30.519624 -403.193504) (xy 30.519624 -403.351492) (xy 30.519172 -403.361643)
			(xy 30.511384 -403.38039) (xy 30.496997 -403.394713) (xy 30.478214 -403.402417) (xy 30.468062 -403.4028)
			(xy 29.751782 -403.4028) (xy 29.741659 -403.40229) (xy 29.722945 -403.394563) (xy 29.708591 -403.380285)
			(xy 29.700765 -403.361612) (xy 29.70022 -403.351492) (xy 29.70022 -403.193504) (xy 29.699804 -403.184318)
			(xy 29.693294 -403.167133) (xy 29.68752 -403.159976) (xy 29.665734 -403.134322) (xy 29.627785 -403.078736)
			(xy 29.596752 -403.019013) (xy 29.573079 -402.956008) (xy 29.557106 -402.890626) (xy 29.549061 -402.823804)
			(xy 29.549061 -402.756499) (xy 29.557105 -402.689677) (xy 29.573078 -402.624294) (xy 29.59675 -402.56129)
			(xy 29.627784 -402.501566) (xy 29.665732 -402.44598) (xy 29.68752 -402.420328) (xy 29.693332 -402.413194)
			(xy 29.699837 -402.395995) (xy 29.70022 -402.3868) (xy 29.70022 -401.893532) (xy 29.69979 -401.884347)
			(xy 29.69329 -401.867163) (xy 29.68752 -401.860004) (xy 29.665713 -401.834368) (xy 29.627766 -401.778779)
			(xy 29.596735 -401.719053) (xy 29.573064 -401.656046) (xy 29.557093 -401.590662) (xy 29.549051 -401.523838)
			(xy 28.446989 -401.523838) (xy 28.44703 -401.523948) (xy 28.463067 -401.589436) (xy 28.471145 -401.656372)
			(xy 28.471147 -401.723795) (xy 28.463073 -401.790732) (xy 28.447039 -401.85622) (xy 28.423277 -401.919316)
			(xy 28.392127 -401.979111) (xy 28.354039 -402.034745) (xy 28.332176 -402.06041) (xy 28.32639 -402.067562)
			(xy 28.31987 -402.084748) (xy 28.319476 -402.093938) (xy 28.319476 -402.251418) (xy 28.318989 -402.261544)
			(xy 28.311258 -402.280263) (xy 28.296972 -402.294618) (xy 28.278291 -402.302439) (xy 28.268168 -402.30298)
			(xy 27.551888 -402.30298) (xy 27.541731 -402.302588) (xy 27.522974 -402.294785) (xy 27.50865 -402.280379)
			(xy 27.500954 -402.261578) (xy 27.50058 -402.251418) (xy 27.50058 -402.093938) (xy 27.500156 -402.084752)
			(xy 27.493653 -402.067567) (xy 27.48788 -402.06041) (xy 27.465995 -402.034762) (xy 27.427908 -401.979125)
			(xy 27.39676 -401.919326) (xy 27.372998 -401.856227) (xy 27.356964 -401.790736) (xy 27.348891 -401.723796)
			(xy 0.509016 -401.723796) (xy 0.509016 -405.623707) (xy 27.348902 -405.623707) (xy 27.348902 -405.556284)
			(xy 27.356979 -405.489345) (xy 27.373014 -405.423856) (xy 27.396778 -405.360759) (xy 27.427928 -405.300963)
			(xy 27.466016 -405.245328) (xy 27.48788 -405.219662) (xy 27.493673 -405.212514) (xy 27.50019 -405.195326)
			(xy 27.50058 -405.186134) (xy 27.50058 -404.693882) (xy 27.500183 -404.684693) (xy 27.493661 -404.667509)
			(xy 27.48788 -404.660354) (xy 27.466038 -404.634671) (xy 27.42795 -404.579038) (xy 27.3968 -404.519244)
			(xy 27.373035 -404.45615) (xy 27.356999 -404.390663) (xy 27.348922 -404.323727) (xy 27.34892 -404.256306)
			(xy 27.356993 -404.189369) (xy 27.373025 -404.123882) (xy 27.396786 -404.060786) (xy 27.427933 -404.00099)
			(xy 27.466018 -403.945356) (xy 27.48788 -403.91969) (xy 27.493661 -403.912534) (xy 27.500186 -403.895352)
			(xy 27.50058 -403.886162) (xy 27.50058 -403.728682) (xy 27.501013 -403.718549) (xy 27.508754 -403.69982)
			(xy 27.523057 -403.685463) (xy 27.541757 -403.677651) (xy 27.551888 -403.67712) (xy 28.268168 -403.67712)
			(xy 28.278323 -403.677548) (xy 28.297078 -403.685337) (xy 28.311404 -403.699732) (xy 28.319101 -403.718525)
			(xy 28.319476 -403.728682) (xy 28.319476 -403.886162) (xy 28.31991 -403.895347) (xy 28.326408 -403.912531)
			(xy 28.332176 -403.91969) (xy 28.354062 -403.945337) (xy 28.392152 -404.000974) (xy 28.423303 -404.060772)
			(xy 28.447067 -404.123871) (xy 28.463102 -404.189363) (xy 28.471176 -404.256304) (xy 28.471174 -404.323729)
			(xy 28.463096 -404.39067) (xy 28.447057 -404.45616) (xy 28.42329 -404.519258) (xy 28.392135 -404.579055)
			(xy 28.354042 -404.634689) (xy 28.332176 -404.660354) (xy 28.326371 -404.667493) (xy 28.319862 -404.684688)
			(xy 28.319476 -404.693882) (xy 28.319476 -405.186134) (xy 28.319875 -405.195322) (xy 28.326397 -405.212506)
			(xy 28.332176 -405.219662) (xy 28.354035 -405.245332) (xy 28.392125 -405.300965) (xy 28.423278 -405.36076)
			(xy 28.447043 -405.423857) (xy 28.46308 -405.489345) (xy 28.471157 -405.556284) (xy 28.471157 -405.623707)
			(xy 28.463081 -405.690646) (xy 28.447046 -405.756135) (xy 28.423281 -405.819231) (xy 28.39213 -405.879027)
			(xy 28.35404 -405.934661) (xy 28.332176 -405.960326) (xy 28.326383 -405.967474) (xy 28.319867 -405.984662)
			(xy 28.319476 -405.993854) (xy 28.319476 -406.151334) (xy 28.319002 -406.161461) (xy 28.311266 -406.18018)
			(xy 28.296976 -406.194534) (xy 28.278293 -406.202355) (xy 28.268168 -406.202896) (xy 27.551888 -406.202896)
			(xy 27.541733 -406.202488) (xy 27.522979 -406.194688) (xy 27.508656 -406.180287) (xy 27.500957 -406.161492)
			(xy 27.50058 -406.151334) (xy 27.50058 -405.993854) (xy 27.500148 -405.984669) (xy 27.49365 -405.967484)
			(xy 27.48788 -405.960326) (xy 27.466011 -405.934665) (xy 27.427924 -405.87903) (xy 27.396774 -405.819233)
			(xy 27.373011 -405.756135) (xy 27.356977 -405.690646) (xy 27.348902 -405.623707) (xy 0.509016 -405.623707)
			(xy 0.509016 -406.72373) (xy 29.549042 -406.72373) (xy 29.549045 -406.656422) (xy 29.557092 -406.589598)
			(xy 29.573068 -406.524214) (xy 29.596744 -406.461208) (xy 29.627779 -406.401484) (xy 29.665731 -406.345896)
			(xy 29.68752 -406.320244) (xy 29.693325 -406.313105) (xy 29.699834 -406.29591) (xy 29.70022 -406.286716)
			(xy 29.70022 -405.793448) (xy 29.699782 -405.784264) (xy 29.693287 -405.767079) (xy 29.68752 -405.75992)
			(xy 29.665729 -405.734271) (xy 29.627781 -405.678684) (xy 29.596749 -405.618959) (xy 29.573078 -405.555955)
			(xy 29.557105 -405.490572) (xy 29.549062 -405.423749) (xy 29.549062 -405.356444) (xy 29.557107 -405.289622)
			(xy 29.573079 -405.22424) (xy 29.596752 -405.161235) (xy 29.627784 -405.101511) (xy 29.665733 -405.045924)
			(xy 29.68752 -405.020272) (xy 29.693313 -405.013125) (xy 29.699829 -404.995936) (xy 29.70022 -404.986744)
			(xy 29.70022 -404.828756) (xy 29.700586 -404.818597) (xy 29.7084 -404.799839) (xy 29.722814 -404.785517)
			(xy 29.74162 -404.777822) (xy 29.751782 -404.777448) (xy 30.468062 -404.777448) (xy 30.478187 -404.777958)
			(xy 30.496909 -404.785675) (xy 30.511267 -404.799954) (xy 30.519086 -404.818634) (xy 30.519624 -404.828756)
			(xy 30.519624 -404.986744) (xy 30.520008 -404.995934) (xy 30.526539 -405.013118) (xy 30.532324 -405.020272)
			(xy 30.554109 -405.045927) (xy 30.59206 -405.101512) (xy 30.623096 -405.161235) (xy 30.64677 -405.224239)
			(xy 30.662745 -405.289621) (xy 30.67079 -405.356444) (xy 30.67079 -405.42375) (xy 30.662746 -405.490573)
			(xy 30.646772 -405.555955) (xy 30.623098 -405.61896) (xy 30.620661 -405.623649) (xy 31.749197 -405.623649)
			(xy 31.749198 -405.556342) (xy 31.757243 -405.489519) (xy 31.773217 -405.424136) (xy 31.796892 -405.361131)
			(xy 31.827928 -405.301408) (xy 31.865879 -405.245822) (xy 31.887668 -405.22017) (xy 31.893468 -405.213028)
			(xy 31.899979 -405.195835) (xy 31.900368 -405.186642) (xy 31.900368 -404.693374) (xy 31.899955 -404.684187)
			(xy 31.893441 -404.667004) (xy 31.887668 -404.659846) (xy 31.865901 -404.634176) (xy 31.82795 -404.578593)
			(xy 31.796914 -404.518872) (xy 31.773239 -404.45587) (xy 31.757263 -404.39049) (xy 31.749217 -404.323668)
			(xy 31.749215 -404.256365) (xy 31.757257 -404.189543) (xy 31.773229 -404.124162) (xy 31.7969 -404.061158)
			(xy 31.827933 -404.001435) (xy 31.865881 -403.94585) (xy 31.887668 -403.920198) (xy 31.893456 -403.913047)
			(xy 31.899974 -403.895861) (xy 31.900368 -403.88667) (xy 31.900368 -403.728682) (xy 31.90075 -403.718506)
			(xy 31.908547 -403.699705) (xy 31.922945 -403.68532) (xy 31.941753 -403.677541) (xy 31.95193 -403.67712)
			(xy 32.66821 -403.67712) (xy 32.678366 -403.677625) (xy 32.697132 -403.685399) (xy 32.711496 -403.699761)
			(xy 32.719273 -403.718526) (xy 32.719772 -403.728682) (xy 32.719772 -403.88667) (xy 32.720203 -403.895855)
			(xy 32.726703 -403.913039) (xy 32.732472 -403.920198) (xy 32.754281 -403.945832) (xy 32.792229 -404.001422)
			(xy 32.82326 -404.061148) (xy 32.846931 -404.124155) (xy 32.862902 -404.189539) (xy 32.870945 -404.256363)
			(xy 32.870943 -404.32367) (xy 32.862897 -404.390494) (xy 32.846922 -404.455877) (xy 32.823247 -404.518882)
			(xy 32.792212 -404.578607) (xy 32.754261 -404.634194) (xy 32.732472 -404.659846) (xy 32.72667 -404.666987)
			(xy 32.720159 -404.684181) (xy 32.719772 -404.693374) (xy 32.719772 -405.186642) (xy 32.720168 -405.195831)
			(xy 32.726692 -405.213014) (xy 32.732472 -405.22017) (xy 32.754254 -405.245827) (xy 32.792202 -405.301413)
			(xy 32.823235 -405.361136) (xy 32.846907 -405.42414) (xy 32.862881 -405.489521) (xy 32.870925 -405.556343)
			(xy 32.870926 -405.623648) (xy 32.862882 -405.69047) (xy 32.84691 -405.755851) (xy 32.823239 -405.818856)
			(xy 32.792207 -405.878579) (xy 32.754259 -405.934166) (xy 32.732472 -405.959818) (xy 32.726682 -405.966967)
			(xy 32.720164 -405.984155) (xy 32.719772 -405.993346) (xy 32.719772 -406.151334) (xy 32.719295 -406.161493)
			(xy 32.711511 -406.180261) (xy 32.697141 -406.194624) (xy 32.678369 -406.202399) (xy 32.66821 -406.202896)
			(xy 31.95193 -406.202896) (xy 31.941778 -406.202343) (xy 31.923016 -406.194585) (xy 31.908651 -406.180237)
			(xy 31.900869 -406.161485) (xy 31.900368 -406.151334) (xy 31.900368 -405.993346) (xy 31.899921 -405.984163)
			(xy 31.893431 -405.966979) (xy 31.887668 -405.959818) (xy 31.865874 -405.934171) (xy 31.827923 -405.878584)
			(xy 31.796888 -405.81886) (xy 31.773215 -405.755855) (xy 31.757241 -405.690472) (xy 31.749197 -405.623649)
			(xy 30.620661 -405.623649) (xy 30.592063 -405.678683) (xy 30.554113 -405.734268) (xy 30.532324 -405.75992)
			(xy 30.526539 -405.767074) (xy 30.520017 -405.784258) (xy 30.519624 -405.793448) (xy 30.519624 -406.286716)
			(xy 30.520021 -406.295905) (xy 30.526543 -406.313089) (xy 30.532324 -406.320244) (xy 30.554081 -406.345922)
			(xy 30.592034 -406.401503) (xy 30.62307 -406.461223) (xy 30.646746 -406.524224) (xy 30.662723 -406.589604)
			(xy 30.67077 -406.656424) (xy 30.670773 -406.723728) (xy 30.670766 -406.723789) (xy 33.948811 -406.723789)
			(xy 33.948814 -406.656363) (xy 33.956893 -406.589422) (xy 33.972932 -406.523931) (xy 33.996701 -406.460833)
			(xy 34.027856 -406.401036) (xy 34.06595 -406.345401) (xy 34.087816 -406.319736) (xy 34.093624 -406.312599)
			(xy 34.100131 -406.295402) (xy 34.100516 -406.286208) (xy 34.100516 -405.793956) (xy 34.100123 -405.784767)
			(xy 34.093597 -405.767583) (xy 34.087816 -405.760428) (xy 34.065948 -405.734766) (xy 34.027858 -405.679132)
			(xy 33.996706 -405.619335) (xy 33.972942 -405.556238) (xy 33.956906 -405.490748) (xy 33.94883 -405.423809)
			(xy 33.948831 -405.356385) (xy 33.956907 -405.289446) (xy 33.972944 -405.223957) (xy 33.996709 -405.160859)
			(xy 34.027861 -405.101063) (xy 34.065951 -405.045429) (xy 34.087816 -405.019764) (xy 34.093612 -405.012619)
			(xy 34.100127 -404.995428) (xy 34.100516 -404.986236) (xy 34.100516 -404.828756) (xy 34.10095 -404.818642)
			(xy 34.108705 -404.79996) (xy 34.123017 -404.785666) (xy 34.14171 -404.777936) (xy 34.151824 -404.777448)
			(xy 34.868104 -404.777448) (xy 34.878207 -404.777981) (xy 34.896875 -404.78571) (xy 34.911168 -404.799992)
			(xy 34.918911 -404.818654) (xy 34.919412 -404.828756) (xy 34.919412 -404.986236) (xy 34.919802 -404.995425)
			(xy 34.926329 -405.01261) (xy 34.932112 -405.019764) (xy 34.953972 -405.045433) (xy 34.99206 -405.101067)
			(xy 35.02321 -405.160863) (xy 35.046974 -405.223959) (xy 35.063009 -405.289448) (xy 35.071085 -405.356385)
			(xy 35.071085 -405.423809) (xy 35.06301 -405.490746) (xy 35.046976 -405.556235) (xy 35.023212 -405.619332)
			(xy 35.020933 -405.623707) (xy 36.14899 -405.623707) (xy 36.14899 -405.556284) (xy 36.157066 -405.489346)
			(xy 36.173101 -405.423857) (xy 36.196864 -405.36076) (xy 36.228014 -405.300963) (xy 36.266101 -405.245328)
			(xy 36.287964 -405.219662) (xy 36.293767 -405.212522) (xy 36.300276 -405.195327) (xy 36.300664 -405.186134)
			(xy 36.300664 -404.693882) (xy 36.300248 -404.684696) (xy 36.293737 -404.667512) (xy 36.287964 -404.660354)
			(xy 36.266123 -404.63467) (xy 36.228036 -404.579038) (xy 36.196886 -404.519244) (xy 36.173122 -404.456149)
			(xy 36.157087 -404.390663) (xy 36.149009 -404.323727) (xy 36.149007 -404.256306) (xy 36.157081 -404.18937)
			(xy 36.173113 -404.123882) (xy 36.196873 -404.060787) (xy 36.228019 -404.000991) (xy 36.266103 -403.945356)
			(xy 36.287964 -403.91969) (xy 36.293755 -403.912541) (xy 36.300271 -403.895353) (xy 36.300664 -403.886162)
			(xy 36.300664 -403.728682) (xy 36.301112 -403.718551) (xy 36.30885 -403.699825) (xy 36.323149 -403.685468)
			(xy 36.341843 -403.677654) (xy 36.351972 -403.67712) (xy 37.068252 -403.67712) (xy 37.078405 -403.677561)
			(xy 37.097161 -403.685345) (xy 37.111486 -403.699736) (xy 37.119184 -403.718527) (xy 37.11956 -403.728682)
			(xy 37.11956 -403.886162) (xy 37.119998 -403.895346) (xy 37.126493 -403.91253) (xy 37.13226 -403.91969)
			(xy 37.154147 -403.945337) (xy 37.192238 -404.000973) (xy 37.22339 -404.060771) (xy 37.247154 -404.123871)
			(xy 37.26319 -404.189362) (xy 37.271264 -404.256303) (xy 37.271262 -404.32373) (xy 37.263184 -404.39067)
			(xy 37.247145 -404.456161) (xy 37.223376 -404.519259) (xy 37.192221 -404.579055) (xy 37.154127 -404.634689)
			(xy 37.13226 -404.660354) (xy 37.126453 -404.667492) (xy 37.119946 -404.684688) (xy 37.11956 -404.693882)
			(xy 37.11956 -405.186134) (xy 37.119963 -405.195322) (xy 37.126483 -405.212506) (xy 37.13226 -405.219662)
			(xy 37.154119 -405.245331) (xy 37.192211 -405.300964) (xy 37.223364 -405.36076) (xy 37.24713 -405.423856)
			(xy 37.263168 -405.489345) (xy 37.271245 -405.556284) (xy 37.271245 -405.623707) (xy 37.263169 -405.690646)
			(xy 37.247133 -405.756135) (xy 37.223368 -405.819232) (xy 37.192216 -405.879028) (xy 37.154125 -405.934661)
			(xy 37.13226 -405.960326) (xy 37.126465 -405.967472) (xy 37.11995 -405.984662) (xy 37.11956 -405.993854)
			(xy 37.11956 -406.151334) (xy 37.119101 -406.161463) (xy 37.111362 -406.180185) (xy 37.097068 -406.19454)
			(xy 37.078379 -406.202358) (xy 37.068252 -406.202896) (xy 36.351972 -406.202896) (xy 36.341816 -406.202501)
			(xy 36.323062 -406.194696) (xy 36.308739 -406.180291) (xy 36.301041 -406.161493) (xy 36.300664 -406.151334)
			(xy 36.300664 -405.993854) (xy 36.300214 -405.984671) (xy 36.293726 -405.967487) (xy 36.287964 -405.960326)
			(xy 36.266095 -405.934665) (xy 36.228009 -405.879029) (xy 36.196861 -405.819232) (xy 36.173099 -405.756135)
			(xy 36.157065 -405.690645) (xy 36.14899 -405.623707) (xy 35.020933 -405.623707) (xy 34.992063 -405.679128)
			(xy 34.953975 -405.734763) (xy 34.932112 -405.760428) (xy 34.926322 -405.767578) (xy 34.919803 -405.784765)
			(xy 34.919412 -405.793956) (xy 34.919412 -406.286208) (xy 34.919816 -406.295396) (xy 34.926334 -406.31258)
			(xy 34.932112 -406.319736) (xy 34.953944 -406.345427) (xy 34.992033 -406.401058) (xy 35.023184 -406.460851)
			(xy 35.04695 -406.523945) (xy 35.062987 -406.58943) (xy 35.071065 -406.656366) (xy 35.071068 -406.723729)
			(xy 38.34913 -406.723729) (xy 38.349133 -406.656422) (xy 38.35718 -406.589598) (xy 38.373155 -406.524215)
			(xy 38.39683 -406.461209) (xy 38.427865 -406.401484) (xy 38.465815 -406.345897) (xy 38.487604 -406.320244)
			(xy 38.493407 -406.313104) (xy 38.499918 -406.295909) (xy 38.500304 -406.286716) (xy 38.500304 -405.793448)
			(xy 38.49987 -405.784263) (xy 38.493373 -405.767079) (xy 38.487604 -405.75992) (xy 38.465813 -405.734271)
			(xy 38.427867 -405.678683) (xy 38.396836 -405.618959) (xy 38.373165 -405.555954) (xy 38.357193 -405.490572)
			(xy 38.34915 -405.423749) (xy 38.34915 -405.356445) (xy 38.357194 -405.289622) (xy 38.373167 -405.22424)
			(xy 38.396838 -405.161236) (xy 38.42787 -405.101512) (xy 38.465817 -405.045925) (xy 38.487604 -405.020272)
			(xy 38.493395 -405.013123) (xy 38.499913 -404.995935) (xy 38.500304 -404.986744) (xy 38.500304 -404.828756)
			(xy 38.500686 -404.818599) (xy 38.508497 -404.799844) (xy 38.522905 -404.785523) (xy 38.541706 -404.777825)
			(xy 38.551866 -404.777448) (xy 39.268146 -404.777448) (xy 39.278277 -404.777889) (xy 39.297 -404.785634)
			(xy 39.311355 -404.799934) (xy 39.319171 -404.818627) (xy 39.319708 -404.828756) (xy 39.319708 -404.986744)
			(xy 39.320095 -404.995934) (xy 39.326624 -405.013118) (xy 39.332408 -405.020272) (xy 39.354193 -405.045927)
			(xy 39.392146 -405.101512) (xy 39.423182 -405.161234) (xy 39.446858 -405.224239) (xy 39.462832 -405.289621)
			(xy 39.470878 -405.356444) (xy 39.470878 -405.42375) (xy 39.462833 -405.490573) (xy 39.446859 -405.555956)
			(xy 39.423185 -405.61896) (xy 39.420718 -405.623708) (xy 40.548756 -405.623708) (xy 40.548757 -405.556283)
			(xy 40.556834 -405.489343) (xy 40.572872 -405.423853) (xy 40.596639 -405.360756) (xy 40.627793 -405.30096)
			(xy 40.665886 -405.245326) (xy 40.687752 -405.219662) (xy 40.693554 -405.212521) (xy 40.700064 -405.195327)
			(xy 40.700452 -405.186134) (xy 40.700452 -404.693882) (xy 40.700039 -404.684695) (xy 40.693526 -404.667512)
			(xy 40.687752 -404.660354) (xy 40.665908 -404.634672) (xy 40.627815 -404.579041) (xy 40.59666 -404.519248)
			(xy 40.572893 -404.456153) (xy 40.556854 -404.390665) (xy 40.548776 -404.323728) (xy 40.548774 -404.256305)
			(xy 40.556848 -404.189367) (xy 40.572883 -404.123879) (xy 40.596647 -404.060783) (xy 40.627798 -404.000987)
			(xy 40.665888 -403.945354) (xy 40.687752 -403.91969) (xy 40.693542 -403.91254) (xy 40.700059 -403.895353)
			(xy 40.700452 -403.886162) (xy 40.700452 -403.728682) (xy 40.700912 -403.718553) (xy 40.708648 -403.699829)
			(xy 40.722942 -403.685473) (xy 40.741633 -403.677656) (xy 40.75176 -403.67712) (xy 41.46804 -403.67712)
			(xy 41.478199 -403.677489) (xy 41.496956 -403.685302) (xy 41.511279 -403.699715) (xy 41.518974 -403.71852)
			(xy 41.519348 -403.728682) (xy 41.519348 -403.886162) (xy 41.519788 -403.895346) (xy 41.526282 -403.91253)
			(xy 41.532048 -403.91969) (xy 41.553935 -403.945337) (xy 41.592027 -404.000973) (xy 41.62318 -404.060771)
			(xy 41.646945 -404.12387) (xy 41.66298 -404.189362) (xy 41.671055 -404.256303) (xy 41.671053 -404.32373)
			(xy 41.662974 -404.39067) (xy 41.646935 -404.456161) (xy 41.623166 -404.519259) (xy 41.59201 -404.579056)
			(xy 41.553915 -404.63469) (xy 41.532048 -404.660354) (xy 41.52624 -404.667491) (xy 41.519733 -404.684688)
			(xy 41.519348 -404.693882) (xy 41.519348 -405.186134) (xy 41.519754 -405.195321) (xy 41.526272 -405.212505)
			(xy 41.532048 -405.219662) (xy 41.553908 -405.245331) (xy 41.592 -405.300964) (xy 41.623154 -405.360759)
			(xy 41.646921 -405.423856) (xy 41.662958 -405.489345) (xy 41.671036 -405.556283) (xy 41.671036 -405.623708)
			(xy 41.66296 -405.690646) (xy 41.646924 -405.756136) (xy 41.623158 -405.819233) (xy 41.592005 -405.879028)
			(xy 41.553913 -405.934662) (xy 41.532048 -405.960326) (xy 41.526251 -405.967471) (xy 41.519738 -405.984662)
			(xy 41.519348 -405.993854) (xy 41.519348 -406.151334) (xy 41.518901 -406.161464) (xy 41.51116 -406.180189)
			(xy 41.496861 -406.194544) (xy 41.478168 -406.20236) (xy 41.46804 -406.202896) (xy 40.75176 -406.202896)
			(xy 40.741603 -406.202511) (xy 40.722849 -406.194701) (xy 40.708527 -406.180294) (xy 40.700829 -406.161494)
			(xy 40.700452 -406.151334) (xy 40.700452 -405.993854) (xy 40.700004 -405.984671) (xy 40.693515 -405.967487)
			(xy 40.687752 -405.960326) (xy 40.66588 -405.934667) (xy 40.627788 -405.879032) (xy 40.596635 -405.819236)
			(xy 40.572869 -405.756138) (xy 40.556832 -405.690648) (xy 40.548756 -405.623708) (xy 39.420718 -405.623708)
			(xy 39.392149 -405.678683) (xy 39.354197 -405.734269) (xy 39.332408 -405.75992) (xy 39.326621 -405.767072)
			(xy 39.3201 -405.784257) (xy 39.319708 -405.793448) (xy 39.319708 -406.286716) (xy 39.320109 -406.295904)
			(xy 39.326629 -406.313088) (xy 39.332408 -406.320244) (xy 39.354166 -406.345921) (xy 39.392119 -406.401503)
			(xy 39.423157 -406.461222) (xy 39.446834 -406.524224) (xy 39.46281 -406.589604) (xy 39.470858 -406.656424)
			(xy 39.470861 -406.723728) (xy 39.470854 -406.723789) (xy 42.748899 -406.723789) (xy 42.748901 -406.656363)
			(xy 42.756981 -406.589422) (xy 42.773019 -406.523932) (xy 42.796787 -406.460833) (xy 42.827942 -406.401036)
			(xy 42.866034 -406.345401) (xy 42.8879 -406.319736) (xy 42.893706 -406.312598) (xy 42.900215 -406.295402)
			(xy 42.9006 -406.286208) (xy 42.9006 -405.793956) (xy 42.900211 -405.784767) (xy 42.893683 -405.767582)
			(xy 42.8879 -405.760428) (xy 42.866032 -405.734766) (xy 42.827944 -405.679131) (xy 42.796793 -405.619334)
			(xy 42.773029 -405.556237) (xy 42.756994 -405.490748) (xy 42.748918 -405.423809) (xy 42.748919 -405.356385)
			(xy 42.756995 -405.289446) (xy 42.773031 -405.223957) (xy 42.796795 -405.16086) (xy 42.827947 -405.101064)
			(xy 42.866036 -405.045429) (xy 42.8879 -405.019764) (xy 42.893694 -405.012617) (xy 42.90021 -404.995428)
			(xy 42.9006 -404.986236) (xy 42.9006 -404.828756) (xy 42.901049 -404.818644) (xy 42.908801 -404.799965)
			(xy 42.923109 -404.785672) (xy 42.941796 -404.777939) (xy 42.951908 -404.777448) (xy 43.668188 -404.777448)
			(xy 43.67829 -404.777994) (xy 43.696958 -404.785718) (xy 43.711251 -404.799995) (xy 43.718995 -404.818655)
			(xy 43.719496 -404.828756) (xy 43.719496 -404.986236) (xy 43.71989 -404.995425) (xy 43.726415 -405.012609)
			(xy 43.732196 -405.019764) (xy 43.754056 -405.045432) (xy 43.792145 -405.101066) (xy 43.823296 -405.160862)
			(xy 43.847061 -405.223959) (xy 43.863097 -405.289447) (xy 43.871173 -405.356385) (xy 43.871173 -405.423809)
			(xy 43.863098 -405.490747) (xy 43.847063 -405.556236) (xy 43.823299 -405.619332) (xy 43.792148 -405.679128)
			(xy 43.75406 -405.734763) (xy 43.732196 -405.760428) (xy 43.726405 -405.767577) (xy 43.719887 -405.784765)
			(xy 43.719496 -405.793956) (xy 43.719496 -406.286208) (xy 43.719903 -406.295395) (xy 43.726419 -406.31258)
			(xy 43.732196 -406.319736) (xy 43.754029 -406.345427) (xy 43.792119 -406.401058) (xy 43.823271 -406.46085)
			(xy 43.847037 -406.523944) (xy 43.863075 -406.58943) (xy 43.871153 -406.656365) (xy 43.871156 -406.72373)
			(xy 47.149194 -406.72373) (xy 47.149197 -406.656422) (xy 47.157245 -406.589596) (xy 47.173223 -406.524212)
			(xy 47.196901 -406.461206) (xy 47.227941 -406.401481) (xy 47.265897 -406.345896) (xy 47.287688 -406.320244)
			(xy 47.293489 -406.313102) (xy 47.300002 -406.295909) (xy 47.300388 -406.286716) (xy 47.300388 -405.793448)
			(xy 47.299958 -405.784263) (xy 47.293458 -405.767078) (xy 47.287688 -405.75992) (xy 47.265895 -405.734272)
			(xy 47.227943 -405.678686) (xy 47.196907 -405.618962) (xy 47.173232 -405.555957) (xy 47.157258 -405.490574)
			(xy 47.149214 -405.42375) (xy 47.149214 -405.356444) (xy 47.157259 -405.28962) (xy 47.173234 -405.224237)
			(xy 47.19691 -405.161232) (xy 47.227946 -405.101509) (xy 47.265899 -405.045924) (xy 47.287688 -405.020272)
			(xy 47.293478 -405.013122) (xy 47.299997 -404.995935) (xy 47.300388 -404.986744) (xy 47.300388 -404.828756)
			(xy 47.300785 -404.818601) (xy 47.308593 -404.79985) (xy 47.322997 -404.785528) (xy 47.341792 -404.777828)
			(xy 47.35195 -404.777448) (xy 48.06823 -404.777448) (xy 48.07836 -404.777902) (xy 48.097083 -404.785641)
			(xy 48.111439 -404.799937) (xy 48.119255 -404.818629) (xy 48.119792 -404.828756) (xy 48.119792 -404.986744)
			(xy 48.120183 -404.995933) (xy 48.12671 -405.013117) (xy 48.132492 -405.020272) (xy 48.154275 -405.045928)
			(xy 48.192222 -405.101514) (xy 48.223254 -405.161238) (xy 48.246925 -405.224242) (xy 48.262897 -405.289623)
			(xy 48.270941 -405.356445) (xy 48.270942 -405.423749) (xy 48.262899 -405.490571) (xy 48.246927 -405.555952)
			(xy 48.223256 -405.618957) (xy 48.192225 -405.67868) (xy 48.154279 -405.734267) (xy 48.132492 -405.75992)
			(xy 48.126704 -405.767071) (xy 48.120184 -405.784257) (xy 48.119792 -405.793448) (xy 48.119792 -406.286716)
			(xy 48.120196 -406.295904) (xy 48.126714 -406.313088) (xy 48.132492 -406.320244) (xy 48.154247 -406.345922)
			(xy 48.192195 -406.401506) (xy 48.223228 -406.461226) (xy 48.246901 -406.524227) (xy 48.262876 -406.589606)
			(xy 48.270922 -406.656425) (xy 48.270925 -406.723727) (xy 48.262884 -406.790547) (xy 48.246916 -406.855927)
			(xy 48.223248 -406.91893) (xy 48.19222 -406.978653) (xy 48.154277 -407.034239) (xy 48.132492 -407.059892)
			(xy 48.126715 -407.067051) (xy 48.120189 -407.084231) (xy 48.119792 -407.09342) (xy 48.119792 -407.251408)
			(xy 48.119385 -407.261564) (xy 48.111585 -407.280318) (xy 48.097184 -407.294641) (xy 48.078388 -407.302339)
			(xy 48.06823 -407.302716) (xy 47.35195 -407.302716) (xy 47.341821 -407.302231) (xy 47.323093 -407.294512)
			(xy 47.308733 -407.280224) (xy 47.30092 -407.261534) (xy 47.300388 -407.251408) (xy 47.300388 -407.09342)
			(xy 47.299971 -407.084233) (xy 47.293462 -407.067049) (xy 47.287688 -407.059892) (xy 47.265867 -407.034266)
			(xy 47.227916 -406.978677) (xy 47.196882 -406.91895) (xy 47.173209 -406.855942) (xy 47.157236 -406.790556)
			(xy 47.149194 -406.72373) (xy 43.871156 -406.72373) (xy 43.871156 -406.723787) (xy 43.863084 -406.790723)
			(xy 43.847051 -406.85621) (xy 43.823291 -406.919306) (xy 43.792143 -406.979101) (xy 43.754058 -407.034735)
			(xy 43.732196 -407.0604) (xy 43.726416 -407.067557) (xy 43.719892 -407.084739) (xy 43.719496 -407.093928)
			(xy 43.719496 -407.251408) (xy 43.71909 -407.261531) (xy 43.711339 -407.280236) (xy 43.697019 -407.29455)
			(xy 43.678312 -407.302294) (xy 43.668188 -407.302716) (xy 42.951908 -407.302716) (xy 42.941802 -407.302209)
			(xy 42.923127 -407.294477) (xy 42.908832 -407.280187) (xy 42.901094 -407.261514) (xy 42.9006 -407.251408)
			(xy 42.9006 -407.093928) (xy 42.900176 -407.084742) (xy 42.893672 -407.067558) (xy 42.8879 -407.0604)
			(xy 42.866005 -407.034761) (xy 42.827917 -406.979122) (xy 42.796768 -406.919323) (xy 42.773005 -406.856222)
			(xy 42.756972 -406.79073) (xy 42.748899 -406.723789) (xy 39.470854 -406.723789) (xy 39.462819 -406.790549)
			(xy 39.446848 -406.85593) (xy 39.423176 -406.918933) (xy 39.392144 -406.978656) (xy 39.354195 -407.034241)
			(xy 39.332408 -407.059892) (xy 39.326633 -407.067053) (xy 39.320105 -407.084231) (xy 39.319708 -407.09342)
			(xy 39.319708 -407.251408) (xy 39.319285 -407.261562) (xy 39.311488 -407.280313) (xy 39.297092 -407.294635)
			(xy 39.278302 -407.302336) (xy 39.268146 -407.302716) (xy 38.551866 -407.302716) (xy 38.541732 -407.3023)
			(xy 38.523001 -407.294553) (xy 38.508645 -407.280245) (xy 38.500835 -407.261541) (xy 38.500304 -407.251408)
			(xy 38.500304 -407.09342) (xy 38.499883 -407.084234) (xy 38.493377 -407.06705) (xy 38.487604 -407.059892)
			(xy 38.465786 -407.034265) (xy 38.42784 -406.978674) (xy 38.39681 -406.918947) (xy 38.373141 -406.855939)
			(xy 38.357171 -406.790554) (xy 38.34913 -406.723729) (xy 35.071068 -406.723729) (xy 35.071068 -406.723786)
			(xy 35.062996 -406.790722) (xy 35.046964 -406.856209) (xy 35.023204 -406.919305) (xy 34.992058 -406.9791)
			(xy 34.953974 -407.034735) (xy 34.932112 -407.0604) (xy 34.926334 -407.067559) (xy 34.919808 -407.084739)
			(xy 34.919412 -407.093928) (xy 34.919412 -407.251408) (xy 34.918922 -407.261516) (xy 34.911184 -407.280192)
			(xy 34.896888 -407.294486) (xy 34.878212 -407.302222) (xy 34.868104 -407.302716) (xy 34.151824 -407.302716)
			(xy 34.141705 -407.302265) (xy 34.123005 -407.294528) (xy 34.10869 -407.280222) (xy 34.100941 -407.261527)
			(xy 34.100516 -407.251408) (xy 34.100516 -407.093928) (xy 34.100089 -407.084743) (xy 34.093586 -407.067558)
			(xy 34.087816 -407.0604) (xy 34.06592 -407.034761) (xy 34.027831 -406.979123) (xy 33.996681 -406.919323)
			(xy 33.972918 -406.856223) (xy 33.956884 -406.790731) (xy 33.948811 -406.723789) (xy 30.670766 -406.723789)
			(xy 30.662731 -406.790549) (xy 30.646761 -406.855929) (xy 30.62309 -406.918933) (xy 30.592058 -406.978655)
			(xy 30.554111 -407.03424) (xy 30.532324 -407.059892) (xy 30.526551 -407.067054) (xy 30.520022 -407.084232)
			(xy 30.519624 -407.09342) (xy 30.519624 -407.251408) (xy 30.519185 -407.26156) (xy 30.511392 -407.280307)
			(xy 30.497001 -407.29463) (xy 30.478216 -407.302333) (xy 30.468062 -407.302716) (xy 29.751782 -407.302716)
			(xy 29.741649 -407.302287) (xy 29.722919 -407.294545) (xy 29.708561 -407.280241) (xy 29.700751 -407.261539)
			(xy 29.70022 -407.251408) (xy 29.70022 -407.09342) (xy 29.699796 -407.084234) (xy 29.693291 -407.06705)
			(xy 29.68752 -407.059892) (xy 29.665701 -407.034265) (xy 29.627755 -406.978675) (xy 29.596724 -406.918948)
			(xy 29.573054 -406.85594) (xy 29.557084 -406.790555) (xy 29.549042 -406.72373) (xy 0.509016 -406.72373)
			(xy 0.509016 -409.523886) (xy 27.348881 -409.523886) (xy 27.348884 -409.45646) (xy 27.356963 -409.38952)
			(xy 27.373002 -409.324029) (xy 27.396769 -409.26093) (xy 27.427923 -409.201133) (xy 27.466015 -409.145498)
			(xy 27.48788 -409.119832) (xy 27.493686 -409.112693) (xy 27.500196 -409.095498) (xy 27.50058 -409.086304)
			(xy 27.50058 -408.594052) (xy 27.500149 -408.584867) (xy 27.49365 -408.567682) (xy 27.48788 -408.560524)
			(xy 27.466009 -408.534865) (xy 27.427922 -408.479229) (xy 27.396772 -408.419432) (xy 27.37301 -408.356334)
			(xy 27.356975 -408.290845) (xy 27.3489 -408.223906) (xy 27.348901 -408.156482) (xy 27.356977 -408.089544)
			(xy 27.373013 -408.024054) (xy 27.396777 -407.960957) (xy 27.427928 -407.901161) (xy 27.466016 -407.845526)
			(xy 27.48788 -407.81986) (xy 27.493674 -407.812713) (xy 27.500191 -407.795524) (xy 27.50058 -407.786332)
			(xy 27.50058 -407.628852) (xy 27.501045 -407.618743) (xy 27.508795 -407.600067) (xy 27.523098 -407.585775)
			(xy 27.541778 -407.578038) (xy 27.551888 -407.577544) (xy 28.268168 -407.577544) (xy 28.278268 -407.57811)
			(xy 28.296935 -407.585826) (xy 28.311229 -407.600098) (xy 28.318975 -407.618753) (xy 28.319476 -407.628852)
			(xy 28.319476 -407.786332) (xy 28.319876 -407.79552) (xy 28.326397 -407.812704) (xy 28.332176 -407.81986)
			(xy 28.354033 -407.845531) (xy 28.392123 -407.901164) (xy 28.423276 -407.96096) (xy 28.447042 -408.024056)
			(xy 28.463078 -408.089544) (xy 28.471155 -408.156482) (xy 28.471156 -408.223906) (xy 28.46308 -408.290844)
			(xy 28.447045 -408.356333) (xy 28.423281 -408.419429) (xy 28.39213 -408.479225) (xy 28.35404 -408.534859)
			(xy 28.332176 -408.560524) (xy 28.326384 -408.567672) (xy 28.319867 -408.584861) (xy 28.319476 -408.594052)
			(xy 28.319476 -409.086304) (xy 28.319889 -409.095491) (xy 28.326401 -409.112675) (xy 28.332176 -409.119832)
			(xy 28.354005 -409.145526) (xy 28.392097 -409.201156) (xy 28.42325 -409.260948) (xy 28.447018 -409.324041)
			(xy 28.463056 -409.389527) (xy 28.471135 -409.456462) (xy 28.471139 -409.523884) (xy 28.463066 -409.59082)
			(xy 28.447034 -409.656307) (xy 28.423273 -409.719403) (xy 28.392125 -409.779198) (xy 28.354039 -409.834831)
			(xy 28.332176 -409.860496) (xy 28.326396 -409.867653) (xy 28.319872 -409.884835) (xy 28.319476 -409.894024)
			(xy 28.319476 -410.051504) (xy 28.319087 -410.06163) (xy 28.311333 -410.080338) (xy 28.297008 -410.094653)
			(xy 28.278294 -410.102394) (xy 28.268168 -410.102812) (xy 27.551888 -410.102812) (xy 27.54178 -410.102325)
			(xy 27.523104 -410.094585) (xy 27.50881 -410.080289) (xy 27.501074 -410.061612) (xy 27.50058 -410.051504)
			(xy 27.50058 -409.894024) (xy 27.500163 -409.884837) (xy 27.493655 -409.867653) (xy 27.48788 -409.860496)
			(xy 27.465981 -409.83486) (xy 27.427895 -409.77922) (xy 27.396747 -409.71942) (xy 27.372986 -409.656319)
			(xy 27.356953 -409.590827) (xy 27.348881 -409.523886) (xy 0.509016 -409.523886) (xy 0.509016 -410.623641)
			(xy 29.549054 -410.623641) (xy 29.549055 -410.556335) (xy 29.5571 -410.489512) (xy 29.573074 -410.424129)
			(xy 29.596748 -410.361124) (xy 29.627782 -410.301399) (xy 29.665732 -410.245812) (xy 29.68752 -410.22016)
			(xy 29.693318 -410.213016) (xy 29.699831 -410.195825) (xy 29.70022 -410.186632) (xy 29.70022 -409.693364)
			(xy 29.699823 -409.684176) (xy 29.6933 -409.666992) (xy 29.68752 -409.659836) (xy 29.665745 -409.634174)
			(xy 29.627797 -409.578588) (xy 29.596764 -409.518866) (xy 29.573091 -409.455863) (xy 29.557118 -409.390482)
			(xy 29.549073 -409.323661) (xy 29.549072 -409.256357) (xy 29.557115 -409.189536) (xy 29.573086 -409.124154)
			(xy 29.596757 -409.06115) (xy 29.627787 -409.001427) (xy 29.665734 -408.94584) (xy 29.68752 -408.920188)
			(xy 29.693306 -408.913036) (xy 29.699827 -408.895851) (xy 29.70022 -408.88666) (xy 29.70022 -408.728672)
			(xy 29.700599 -408.718514) (xy 29.708408 -408.699757) (xy 29.722817 -408.685434) (xy 29.741621 -408.677738)
			(xy 29.751782 -408.677364) (xy 30.468062 -408.677364) (xy 30.478189 -408.677859) (xy 30.496914 -408.685578)
			(xy 30.511272 -408.699863) (xy 30.519089 -408.718547) (xy 30.519624 -408.728672) (xy 30.519624 -408.88666)
			(xy 30.520048 -408.895846) (xy 30.526551 -408.913031) (xy 30.532324 -408.920188) (xy 30.554125 -408.94583)
			(xy 30.592075 -409.001417) (xy 30.62311 -409.061142) (xy 30.646784 -409.124148) (xy 30.662757 -409.189531)
			(xy 30.670801 -409.256356) (xy 30.6708 -409.323662) (xy 30.662754 -409.390486) (xy 30.646779 -409.45587)
			(xy 30.623103 -409.518875) (xy 30.62053 -409.523827) (xy 31.749176 -409.523827) (xy 31.749179 -409.456519)
			(xy 31.757227 -409.389693) (xy 31.773205 -409.324309) (xy 31.796883 -409.261302) (xy 31.827922 -409.201578)
			(xy 31.865877 -409.145992) (xy 31.887668 -409.12034) (xy 31.893481 -409.113207) (xy 31.899984 -409.096007)
			(xy 31.900368 -409.086812) (xy 31.900368 -408.593544) (xy 31.899922 -408.584361) (xy 31.893432 -408.567177)
			(xy 31.887668 -408.560016) (xy 31.865872 -408.534371) (xy 31.827921 -408.478784) (xy 31.796887 -408.41906)
			(xy 31.773213 -408.356054) (xy 31.75724 -408.290671) (xy 31.749196 -408.223847) (xy 31.749197 -408.156541)
			(xy 31.757242 -408.089717) (xy 31.773217 -408.024334) (xy 31.796892 -407.961329) (xy 31.827927 -407.901606)
			(xy 31.865879 -407.84602) (xy 31.887668 -407.820368) (xy 31.893469 -407.813226) (xy 31.899979 -407.796033)
			(xy 31.900368 -407.78684) (xy 31.900368 -407.628852) (xy 31.900782 -407.618699) (xy 31.908587 -407.599952)
			(xy 31.922985 -407.585631) (xy 31.941775 -407.577927) (xy 31.95193 -407.577544) (xy 32.66821 -407.577544)
			(xy 32.678338 -407.578019) (xy 32.69706 -407.58575) (xy 32.711416 -407.60004) (xy 32.719234 -407.618727)
			(xy 32.719772 -407.628852) (xy 32.719772 -407.78684) (xy 32.720169 -407.796028) (xy 32.726693 -407.813212)
			(xy 32.732472 -407.820368) (xy 32.754252 -407.846027) (xy 32.7922 -407.901612) (xy 32.823233 -407.961335)
			(xy 32.846906 -408.024339) (xy 32.862879 -408.08972) (xy 32.870924 -408.156542) (xy 32.870924 -408.223846)
			(xy 32.862881 -408.290668) (xy 32.846909 -408.35605) (xy 32.823238 -408.419054) (xy 32.792206 -408.478777)
			(xy 32.754259 -408.534364) (xy 32.732472 -408.560016) (xy 32.726682 -408.567166) (xy 32.720164 -408.584353)
			(xy 32.719772 -408.593544) (xy 32.719772 -409.086812) (xy 32.720183 -409.095999) (xy 32.726697 -409.113183)
			(xy 32.732472 -409.12034) (xy 32.754224 -409.146022) (xy 32.792173 -409.201604) (xy 32.823207 -409.261324)
			(xy 32.846881 -409.324324) (xy 32.862857 -409.389703) (xy 32.870903 -409.456522) (xy 32.870907 -409.523824)
			(xy 32.862866 -409.590644) (xy 32.846897 -409.656024) (xy 32.823229 -409.719027) (xy 32.792201 -409.778749)
			(xy 32.754257 -409.834336) (xy 32.732472 -409.859988) (xy 32.726652 -409.867116) (xy 32.720152 -409.88432)
			(xy 32.719772 -409.893516) (xy 32.719772 -410.051504) (xy 32.719381 -410.061662) (xy 32.711579 -410.08042)
			(xy 32.697172 -410.094744) (xy 32.67837 -410.102438) (xy 32.66821 -410.102812) (xy 31.95193 -410.102812)
			(xy 31.941812 -410.102251) (xy 31.923101 -410.094542) (xy 31.908745 -410.080279) (xy 31.900916 -410.061619)
			(xy 31.900368 -410.051504) (xy 31.900368 -409.893516) (xy 31.899935 -409.884332) (xy 31.893436 -409.867148)
			(xy 31.887668 -409.859988) (xy 31.865844 -409.834366) (xy 31.827894 -409.778775) (xy 31.796861 -409.719048)
			(xy 31.773189 -409.65604) (xy 31.757217 -409.590654) (xy 31.749176 -409.523827) (xy 30.62053 -409.523827)
			(xy 30.592066 -409.578598) (xy 30.554113 -409.634184) (xy 30.532324 -409.659836) (xy 30.526532 -409.666985)
			(xy 30.520014 -409.684172) (xy 30.519624 -409.693364) (xy 30.519624 -410.186632) (xy 30.520014 -410.195821)
			(xy 30.526541 -410.213006) (xy 30.532324 -410.22016) (xy 30.554097 -410.245825) (xy 30.592049 -410.301408)
			(xy 30.623085 -410.36113) (xy 30.64676 -410.424133) (xy 30.662735 -410.489514) (xy 30.670781 -410.556336)
			(xy 30.670783 -410.62364) (xy 30.670776 -410.623701) (xy 33.948822 -410.623701) (xy 33.948823 -410.556275)
			(xy 33.956901 -410.489336) (xy 33.972939 -410.423846) (xy 33.996705 -410.360748) (xy 34.027859 -410.300951)
			(xy 34.065951 -410.245317) (xy 34.087816 -410.219652) (xy 34.093617 -410.21251) (xy 34.100129 -410.195317)
			(xy 34.100516 -410.186124) (xy 34.100516 -409.693872) (xy 34.100116 -409.684684) (xy 34.093595 -409.6675)
			(xy 34.087816 -409.660344) (xy 34.065963 -409.634669) (xy 34.027873 -409.579037) (xy 33.996721 -409.519242)
			(xy 33.972955 -409.456146) (xy 33.956919 -409.390658) (xy 33.948842 -409.323721) (xy 33.948841 -409.256297)
			(xy 33.956915 -409.18936) (xy 33.97295 -409.123871) (xy 33.996714 -409.060775) (xy 34.027864 -409.000979)
			(xy 34.065952 -408.945345) (xy 34.087816 -408.91968) (xy 34.093605 -408.91253) (xy 34.100124 -408.895343)
			(xy 34.100516 -408.886152) (xy 34.100516 -408.728672) (xy 34.100962 -408.718559) (xy 34.108712 -408.699878)
			(xy 34.123021 -408.685583) (xy 34.141711 -408.677852) (xy 34.151824 -408.677364) (xy 34.868104 -408.677364)
			(xy 34.878209 -408.677881) (xy 34.89688 -408.685613) (xy 34.911173 -408.6999) (xy 34.918914 -408.718568)
			(xy 34.919412 -408.728672) (xy 34.919412 -408.886152) (xy 34.919842 -408.895337) (xy 34.926342 -408.912522)
			(xy 34.932112 -408.91968) (xy 34.953987 -408.945336) (xy 34.992075 -409.000972) (xy 35.023224 -409.06077)
			(xy 35.046987 -409.123868) (xy 35.063022 -409.189358) (xy 35.071096 -409.256297) (xy 35.071095 -409.323721)
			(xy 35.063018 -409.39066) (xy 35.046982 -409.45615) (xy 35.023217 -409.519247) (xy 35.0208 -409.523886)
			(xy 36.148969 -409.523886) (xy 36.148972 -409.45646) (xy 36.157051 -409.38952) (xy 36.173089 -409.324029)
			(xy 36.196856 -409.260931) (xy 36.228009 -409.201134) (xy 36.266099 -409.145498) (xy 36.287964 -409.119832)
			(xy 36.29378 -409.112701) (xy 36.300281 -409.095499) (xy 36.300664 -409.086304) (xy 36.300664 -408.594052)
			(xy 36.300215 -408.584869) (xy 36.293727 -408.567685) (xy 36.287964 -408.560524) (xy 36.266093 -408.534865)
			(xy 36.228007 -408.479228) (xy 36.196859 -408.419431) (xy 36.173097 -408.356334) (xy 36.157063 -408.290844)
			(xy 36.148988 -408.223906) (xy 36.148989 -408.156482) (xy 36.157065 -408.089544) (xy 36.1731 -408.024055)
			(xy 36.196864 -407.960958) (xy 36.228014 -407.901161) (xy 36.266101 -407.845526) (xy 36.287964 -407.81986)
			(xy 36.293768 -407.81272) (xy 36.300276 -407.795525) (xy 36.300664 -407.786332) (xy 36.300664 -407.628852)
			(xy 36.301145 -407.618745) (xy 36.308892 -407.600072) (xy 36.323189 -407.585781) (xy 36.341864 -407.578041)
			(xy 36.351972 -407.577544) (xy 37.068252 -407.577544) (xy 37.078351 -407.578123) (xy 37.097017 -407.585835)
			(xy 37.111312 -407.600102) (xy 37.119058 -407.618754) (xy 37.11956 -407.628852) (xy 37.11956 -407.786332)
			(xy 37.119964 -407.79552) (xy 37.126483 -407.812703) (xy 37.13226 -407.81986) (xy 37.154118 -407.845531)
			(xy 37.192209 -407.901164) (xy 37.223362 -407.960959) (xy 37.247129 -408.024055) (xy 37.263166 -408.089544)
			(xy 37.271243 -408.156482) (xy 37.271244 -408.223906) (xy 37.263168 -408.290844) (xy 37.247132 -408.356333)
			(xy 37.223367 -408.41943) (xy 37.192215 -408.479226) (xy 37.154125 -408.534859) (xy 37.13226 -408.560524)
			(xy 37.126466 -408.567671) (xy 37.119951 -408.58486) (xy 37.11956 -408.594052) (xy 37.11956 -409.086304)
			(xy 37.119977 -409.09549) (xy 37.126487 -409.112674) (xy 37.13226 -409.119832) (xy 37.15409 -409.145526)
			(xy 37.192182 -409.201155) (xy 37.223337 -409.260947) (xy 37.247105 -409.32404) (xy 37.263144 -409.389526)
			(xy 37.271223 -409.456462) (xy 37.271227 -409.523884) (xy 37.263154 -409.59082) (xy 37.247121 -409.656308)
			(xy 37.223359 -409.719403) (xy 37.19221 -409.779198) (xy 37.154123 -409.834831) (xy 37.13226 -409.860496)
			(xy 37.126478 -409.867651) (xy 37.119955 -409.884834) (xy 37.11956 -409.894024) (xy 37.11956 -410.051504)
			(xy 37.119186 -410.061632) (xy 37.111429 -410.080343) (xy 37.097099 -410.094659) (xy 37.07838 -410.102396)
			(xy 37.068252 -410.102812) (xy 36.351972 -410.102812) (xy 36.341863 -410.102338) (xy 36.323186 -410.094594)
			(xy 36.308893 -410.080293) (xy 36.301157 -410.061613) (xy 36.300664 -410.051504) (xy 36.300664 -409.894024)
			(xy 36.300228 -409.88484) (xy 36.293731 -409.867656) (xy 36.287964 -409.860496) (xy 36.266066 -409.834859)
			(xy 36.227981 -409.77922) (xy 36.196834 -409.719419) (xy 36.173073 -409.656319) (xy 36.157041 -409.590827)
			(xy 36.148969 -409.523886) (xy 35.0208 -409.523886) (xy 34.992066 -409.579044) (xy 34.953976 -409.634679)
			(xy 34.932112 -409.660344) (xy 34.926316 -409.667489) (xy 34.9198 -409.68468) (xy 34.919412 -409.693872)
			(xy 34.919412 -410.186124) (xy 34.919808 -410.195313) (xy 34.926331 -410.212497) (xy 34.932112 -410.219652)
			(xy 34.95396 -410.24533) (xy 34.992048 -410.300963) (xy 35.023199 -410.360758) (xy 35.046964 -410.423853)
			(xy 35.063 -410.48934) (xy 35.071077 -410.556277) (xy 35.071078 -410.623641) (xy 38.349141 -410.623641)
			(xy 38.349143 -410.556335) (xy 38.357188 -410.489512) (xy 38.373162 -410.424129) (xy 38.396835 -410.361124)
			(xy 38.427868 -410.3014) (xy 38.465816 -410.245813) (xy 38.487604 -410.22016) (xy 38.493401 -410.213015)
			(xy 38.499915 -410.195824) (xy 38.500304 -410.186632) (xy 38.500304 -409.693364) (xy 38.49991 -409.684175)
			(xy 38.493385 -409.666991) (xy 38.487604 -409.659836) (xy 38.465829 -409.634174) (xy 38.427882 -409.578588)
			(xy 38.39685 -409.518865) (xy 38.373178 -409.455862) (xy 38.357206 -409.390482) (xy 38.349161 -409.323661)
			(xy 38.34916 -409.256357) (xy 38.357202 -409.189536) (xy 38.373173 -409.124155) (xy 38.396843 -409.061151)
			(xy 38.427873 -409.001428) (xy 38.465818 -408.945841) (xy 38.487604 -408.920188) (xy 38.493389 -408.913034)
			(xy 38.49991 -408.89585) (xy 38.500304 -408.88666) (xy 38.500304 -408.728672) (xy 38.500699 -408.718516)
			(xy 38.508504 -408.699762) (xy 38.522909 -408.685439) (xy 38.541707 -408.677741) (xy 38.551866 -408.677364)
			(xy 39.268146 -408.677364) (xy 39.278279 -408.67779) (xy 39.297005 -408.685537) (xy 39.311361 -408.699842)
			(xy 39.319174 -408.718541) (xy 39.319708 -408.728672) (xy 39.319708 -408.88666) (xy 39.320136 -408.895845)
			(xy 39.326637 -408.91303) (xy 39.332408 -408.920188) (xy 39.354209 -408.94583) (xy 39.392161 -409.001416)
			(xy 39.423197 -409.061141) (xy 39.446871 -409.124147) (xy 39.462845 -409.189531) (xy 39.470889 -409.256356)
			(xy 39.470888 -409.323663) (xy 39.462842 -409.390487) (xy 39.446866 -409.45587) (xy 39.423189 -409.518876)
			(xy 39.420585 -409.523887) (xy 40.548735 -409.523887) (xy 40.548738 -409.456459) (xy 40.556818 -409.389518)
			(xy 40.572859 -409.324026) (xy 40.59663 -409.260927) (xy 40.627788 -409.20113) (xy 40.665884 -409.145496)
			(xy 40.687752 -409.119832) (xy 40.693566 -409.1127) (xy 40.700069 -409.095499) (xy 40.700452 -409.086304)
			(xy 40.700452 -408.594052) (xy 40.700005 -408.584869) (xy 40.693516 -408.567685) (xy 40.687752 -408.560524)
			(xy 40.665878 -408.534866) (xy 40.627786 -408.479232) (xy 40.596633 -408.419435) (xy 40.572867 -408.356337)
			(xy 40.556831 -408.290847) (xy 40.548755 -408.223907) (xy 40.548755 -408.156481) (xy 40.556833 -408.089542)
			(xy 40.572871 -408.024051) (xy 40.596638 -407.960954) (xy 40.627793 -407.901158) (xy 40.665886 -407.845524)
			(xy 40.687752 -407.81986) (xy 40.693554 -407.812719) (xy 40.700064 -407.795525) (xy 40.700452 -407.786332)
			(xy 40.700452 -407.628852) (xy 40.700945 -407.618746) (xy 40.708689 -407.600076) (xy 40.722983 -407.585785)
			(xy 40.741654 -407.578043) (xy 40.75176 -407.577544) (xy 41.46804 -407.577544) (xy 41.478144 -407.578051)
			(xy 41.496813 -407.585791) (xy 41.511104 -407.600081) (xy 41.518847 -407.618748) (xy 41.519348 -407.628852)
			(xy 41.519348 -407.786332) (xy 41.519755 -407.795519) (xy 41.526272 -407.812703) (xy 41.532048 -407.81986)
			(xy 41.553906 -407.845531) (xy 41.591998 -407.901163) (xy 41.623152 -407.960958) (xy 41.646919 -408.024055)
			(xy 41.662957 -408.089543) (xy 41.671034 -408.156482) (xy 41.671035 -408.223906) (xy 41.662959 -408.290845)
			(xy 41.646923 -408.356334) (xy 41.623157 -408.419431) (xy 41.592004 -408.479226) (xy 41.553913 -408.53486)
			(xy 41.532048 -408.560524) (xy 41.526252 -408.56767) (xy 41.519739 -408.58486) (xy 41.519348 -408.594052)
			(xy 41.519348 -409.086304) (xy 41.519768 -409.09549) (xy 41.526276 -409.112674) (xy 41.532048 -409.119832)
			(xy 41.553878 -409.145526) (xy 41.591972 -409.201155) (xy 41.623127 -409.260947) (xy 41.646895 -409.32404)
			(xy 41.662935 -409.389526) (xy 41.671014 -409.456462) (xy 41.671018 -409.523884) (xy 41.662945 -409.590821)
			(xy 41.646911 -409.656308) (xy 41.623149 -409.719404) (xy 41.591999 -409.779199) (xy 41.553912 -409.834832)
			(xy 41.532048 -409.860496) (xy 41.526264 -409.86765) (xy 41.519743 -409.884834) (xy 41.519348 -409.894024)
			(xy 41.519348 -410.051504) (xy 41.518819 -410.061607) (xy 41.511089 -410.080276) (xy 41.496806 -410.094569)
			(xy 41.478143 -410.102312) (xy 41.46804 -410.102812) (xy 40.75176 -410.102812) (xy 40.74165 -410.102348)
			(xy 40.722973 -410.094599) (xy 40.70868 -410.080296) (xy 40.700945 -410.061614) (xy 40.700452 -410.051504)
			(xy 40.700452 -409.894024) (xy 40.700019 -409.884839) (xy 40.69352 -409.867655) (xy 40.687752 -409.860496)
			(xy 40.665851 -409.834861) (xy 40.62776 -409.779223) (xy 40.596608 -409.719423) (xy 40.572843 -409.656322)
			(xy 40.556809 -409.590829) (xy 40.548735 -409.523887) (xy 39.420585 -409.523887) (xy 39.392152 -409.578599)
			(xy 39.354198 -409.634185) (xy 39.332408 -409.659836) (xy 39.326615 -409.666984) (xy 39.320098 -409.684172)
			(xy 39.319708 -409.693364) (xy 39.319708 -410.186632) (xy 39.320101 -410.195821) (xy 39.326626 -410.213005)
			(xy 39.332408 -410.22016) (xy 39.354182 -410.245824) (xy 39.392134 -410.301408) (xy 39.423171 -410.361129)
			(xy 39.446847 -410.424132) (xy 39.462823 -410.489513) (xy 39.470869 -410.556336) (xy 39.470871 -410.62364)
			(xy 39.470864 -410.6237) (xy 42.74891 -410.6237) (xy 42.748911 -410.556276) (xy 42.756989 -410.489336)
			(xy 42.773026 -410.423846) (xy 42.796792 -410.360749) (xy 42.827944 -410.300952) (xy 42.866035 -410.245317)
			(xy 42.8879 -410.219652) (xy 42.893699 -410.212509) (xy 42.900212 -410.195317) (xy 42.9006 -410.186124)
			(xy 42.9006 -409.693872) (xy 42.900204 -409.684683) (xy 42.89368 -409.667499) (xy 42.8879 -409.660344)
			(xy 42.866048 -409.634669) (xy 42.827959 -409.579036) (xy 42.796808 -409.519241) (xy 42.773043 -409.456145)
			(xy 42.757006 -409.390658) (xy 42.74893 -409.32372) (xy 42.748928 -409.256298) (xy 42.757003 -409.18936)
			(xy 42.773037 -409.123872) (xy 42.7968 -409.060775) (xy 42.827949 -409.00098) (xy 42.866037 -408.945345)
			(xy 42.8879 -408.91968) (xy 42.893688 -408.912528) (xy 42.900208 -408.895343) (xy 42.9006 -408.886152)
			(xy 42.9006 -408.728672) (xy 42.901062 -408.718561) (xy 42.908809 -408.699883) (xy 42.923113 -408.685589)
			(xy 42.941797 -408.677855) (xy 42.951908 -408.677364) (xy 43.668188 -408.677364) (xy 43.678292 -408.677894)
			(xy 43.696963 -408.685621) (xy 43.711257 -408.699904) (xy 43.718998 -408.718569) (xy 43.719496 -408.728672)
			(xy 43.719496 -408.886152) (xy 43.71993 -408.895337) (xy 43.726427 -408.912521) (xy 43.732196 -408.91968)
			(xy 43.754072 -408.945335) (xy 43.792161 -409.000971) (xy 43.823311 -409.060769) (xy 43.847075 -409.123867)
			(xy 43.863109 -409.189357) (xy 43.871184 -409.256297) (xy 43.871183 -409.323721) (xy 43.863106 -409.390661)
			(xy 43.847069 -409.45615) (xy 43.823304 -409.519248) (xy 43.792151 -409.579044) (xy 43.754061 -409.634679)
			(xy 43.732196 -409.660344) (xy 43.726398 -409.667488) (xy 43.719884 -409.684679) (xy 43.719496 -409.693872)
			(xy 43.719496 -410.186124) (xy 43.719895 -410.195312) (xy 43.726417 -410.212497) (xy 43.732196 -410.219652)
			(xy 43.754044 -410.24533) (xy 43.792134 -410.300963) (xy 43.823285 -410.360757) (xy 43.847051 -410.423852)
			(xy 43.863087 -410.48934) (xy 43.871165 -410.556277) (xy 43.871166 -410.623642) (xy 47.149205 -410.623642)
			(xy 47.149207 -410.556334) (xy 47.157253 -410.48951) (xy 47.173229 -410.424126) (xy 47.196906 -410.361121)
			(xy 47.227944 -410.301397) (xy 47.265898 -410.245812) (xy 47.287688 -410.22016) (xy 47.293483 -410.213013)
			(xy 47.299999 -410.195824) (xy 47.300388 -410.186632) (xy 47.300388 -409.693364) (xy 47.299998 -409.684175)
			(xy 47.293471 -409.66699) (xy 47.287688 -409.659836) (xy 47.265911 -409.634175) (xy 47.227958 -409.578591)
			(xy 47.196922 -409.518869) (xy 47.173246 -409.455866) (xy 47.157271 -409.390484) (xy 47.149225 -409.323662)
			(xy 47.149224 -409.256357) (xy 47.157268 -409.189534) (xy 47.173241 -409.124152) (xy 47.196914 -409.061148)
			(xy 47.227949 -409.001425) (xy 47.2659 -408.945839) (xy 47.287688 -408.920188) (xy 47.293471 -408.913033)
			(xy 47.299994 -408.89585) (xy 47.300388 -408.88666) (xy 47.300388 -408.728672) (xy 47.300798 -408.718518)
			(xy 47.308601 -408.699767) (xy 47.323001 -408.685445) (xy 47.341793 -408.677744) (xy 47.35195 -408.677364)
			(xy 48.06823 -408.677364) (xy 48.078362 -408.677803) (xy 48.097088 -408.685545) (xy 48.111444 -408.699846)
			(xy 48.119258 -408.718542) (xy 48.119792 -408.728672) (xy 48.119792 -408.88666) (xy 48.120223 -408.895845)
			(xy 48.126722 -408.913029) (xy 48.132492 -408.920188) (xy 48.154291 -408.945831) (xy 48.192237 -409.001419)
			(xy 48.223268 -409.061145) (xy 48.246939 -409.12415) (xy 48.26291 -409.189533) (xy 48.270953 -409.256356)
			(xy 48.270952 -409.323662) (xy 48.262907 -409.390485) (xy 48.246933 -409.455867) (xy 48.223261 -409.518872)
			(xy 48.192228 -409.578596) (xy 48.15428 -409.634183) (xy 48.132492 -409.659836) (xy 48.126697 -409.666982)
			(xy 48.120182 -409.684172) (xy 48.119792 -409.693364) (xy 48.119792 -410.186632) (xy 48.120188 -410.195821)
			(xy 48.126712 -410.213005) (xy 48.132492 -410.22016) (xy 48.154263 -410.245825) (xy 48.19221 -410.301411)
			(xy 48.223243 -410.361133) (xy 48.246915 -410.424135) (xy 48.262888 -410.489516) (xy 48.270933 -410.556336)
			(xy 48.270934 -410.62364) (xy 48.262892 -410.690461) (xy 48.246922 -410.755842) (xy 48.223252 -410.818845)
			(xy 48.192223 -410.878569) (xy 48.154278 -410.934155) (xy 48.132492 -410.959808) (xy 48.126709 -410.966963)
			(xy 48.120186 -410.984146) (xy 48.119792 -410.993336) (xy 48.119792 -411.151324) (xy 48.119398 -411.161481)
			(xy 48.111593 -411.180235) (xy 48.097188 -411.194558) (xy 48.078389 -411.202255) (xy 48.06823 -411.202632)
			(xy 47.35195 -411.202632) (xy 47.341823 -411.202132) (xy 47.323098 -411.194415) (xy 47.308739 -411.180132)
			(xy 47.300923 -411.161448) (xy 47.300388 -411.151324) (xy 47.300388 -410.993336) (xy 47.299963 -410.98415)
			(xy 47.29346 -410.966966) (xy 47.287688 -410.959808) (xy 47.265883 -410.934169) (xy 47.227932 -410.878582)
			(xy 47.196896 -410.818857) (xy 47.173222 -410.755851) (xy 47.157249 -410.690466) (xy 47.149205 -410.623642)
			(xy 43.871166 -410.623642) (xy 43.871166 -410.623699) (xy 43.863092 -410.690636) (xy 43.847058 -410.756125)
			(xy 43.823295 -410.819221) (xy 43.792146 -410.879017) (xy 43.754059 -410.934651) (xy 43.732196 -410.960316)
			(xy 43.72641 -410.967468) (xy 43.719889 -410.984653) (xy 43.719496 -410.993844) (xy 43.719496 -411.151324)
			(xy 43.719035 -411.161435) (xy 43.711288 -411.180114) (xy 43.696984 -411.194408) (xy 43.678299 -411.202142)
			(xy 43.668188 -411.202632) (xy 42.951908 -411.202632) (xy 42.941804 -411.202109) (xy 42.923132 -411.19438)
			(xy 42.908838 -411.180095) (xy 42.901097 -411.161428) (xy 42.9006 -411.151324) (xy 42.9006 -410.993844)
			(xy 42.900169 -410.984659) (xy 42.89367 -410.967474) (xy 42.8879 -410.960316) (xy 42.86602 -410.934664)
			(xy 42.827932 -410.879027) (xy 42.796782 -410.819229) (xy 42.773019 -410.756131) (xy 42.756984 -410.69064)
			(xy 42.74891 -410.6237) (xy 39.470864 -410.6237) (xy 39.462827 -410.690463) (xy 39.446854 -410.755845)
			(xy 39.423181 -410.818849) (xy 39.392147 -410.878572) (xy 39.354196 -410.934157) (xy 39.332408 -410.959808)
			(xy 39.326626 -410.966964) (xy 39.320103 -410.984146) (xy 39.319708 -410.993336) (xy 39.319708 -411.151324)
			(xy 39.319298 -411.161479) (xy 39.311496 -411.18023) (xy 39.297096 -411.194552) (xy 39.278303 -411.202253)
			(xy 39.268146 -411.202632) (xy 38.551866 -411.202632) (xy 38.541734 -411.202201) (xy 38.523006 -411.194456)
			(xy 38.50865 -411.180153) (xy 38.500837 -411.161454) (xy 38.500304 -411.151324) (xy 38.500304 -410.993336)
			(xy 38.499876 -410.984151) (xy 38.493375 -410.966966) (xy 38.487604 -410.959808) (xy 38.465802 -410.934168)
			(xy 38.427856 -410.878579) (xy 38.396825 -410.818854) (xy 38.373155 -410.755848) (xy 38.357184 -410.690464)
			(xy 38.349141 -410.623641) (xy 35.071078 -410.623641) (xy 35.071078 -410.623699) (xy 35.063004 -410.690636)
			(xy 35.046971 -410.756124) (xy 35.023209 -410.81922) (xy 34.992061 -410.879016) (xy 34.953975 -410.934651)
			(xy 34.932112 -410.960316) (xy 34.926328 -410.96747) (xy 34.919805 -410.984654) (xy 34.919412 -410.993844)
			(xy 34.919412 -411.151324) (xy 34.918935 -411.161433) (xy 34.911192 -411.180109) (xy 34.896893 -411.194403)
			(xy 34.878213 -411.202139) (xy 34.868104 -411.202632) (xy 34.151824 -411.202632) (xy 34.141721 -411.202096)
			(xy 34.123049 -411.194372) (xy 34.108755 -411.180091) (xy 34.101013 -411.161427) (xy 34.100516 -411.151324)
			(xy 34.100516 -410.993844) (xy 34.100081 -410.98466) (xy 34.093584 -410.967475) (xy 34.087816 -410.960316)
			(xy 34.065936 -410.934664) (xy 34.027846 -410.879028) (xy 33.996696 -410.81923) (xy 33.972932 -410.756131)
			(xy 33.956897 -410.690641) (xy 33.948822 -410.623701) (xy 30.670776 -410.623701) (xy 30.66274 -410.690462)
			(xy 30.646767 -410.755844) (xy 30.623095 -410.818848) (xy 30.592061 -410.878571) (xy 30.554112 -410.934156)
			(xy 30.532324 -410.959808) (xy 30.526544 -410.966965) (xy 30.520019 -410.984146) (xy 30.519624 -410.993336)
			(xy 30.519624 -411.151324) (xy 30.519199 -411.161477) (xy 30.5114 -411.180225) (xy 30.497005 -411.194547)
			(xy 30.478217 -411.20225) (xy 30.468062 -411.202632) (xy 29.751782 -411.202632) (xy 29.741651 -411.202188)
			(xy 29.722924 -411.194449) (xy 29.708567 -411.180149) (xy 29.700753 -411.161453) (xy 29.70022 -411.151324)
			(xy 29.70022 -410.993336) (xy 29.699788 -410.984151) (xy 29.693289 -410.966967) (xy 29.68752 -410.959808)
			(xy 29.665717 -410.934169) (xy 29.62777 -410.87858) (xy 29.596738 -410.818854) (xy 29.573067 -410.755848)
			(xy 29.557096 -410.690465) (xy 29.549054 -410.623641) (xy 0.509016 -410.623641) (xy 0.509016 -416.589972)
			(xy 0.509537 -416.645741) (xy 0.517873 -416.756967) (xy 0.534497 -416.867259) (xy 0.559316 -416.976001)
			(xy 0.592193 -417.082584) (xy 0.632942 -417.186412) (xy 0.681337 -417.286904) (xy 0.682829 -417.289488)
			(xy 53.073808 -417.289488) (xy 53.073808 -394.27912) (xy 66.477388 -394.27912) (xy 66.525648 -394.32738)
			(xy 66.525648 -397.823885) (xy 71.348788 -397.823885) (xy 71.348792 -397.756458) (xy 71.356871 -397.689518)
			(xy 71.372911 -397.624026) (xy 71.396679 -397.560928) (xy 71.427833 -397.501131) (xy 71.465926 -397.445495)
			(xy 71.487792 -397.41983) (xy 71.4936 -397.412693) (xy 71.500108 -397.395496) (xy 71.500492 -397.386302)
			(xy 71.500492 -396.89405) (xy 71.50006 -396.884865) (xy 71.493562 -396.86768) (xy 71.487792 -396.860522)
			(xy 71.465918 -396.834865) (xy 71.427831 -396.779229) (xy 71.396681 -396.719431) (xy 71.372918 -396.656334)
			(xy 71.356883 -396.590844) (xy 71.348808 -396.523905) (xy 71.348809 -396.45648) (xy 71.356886 -396.389542)
			(xy 71.372922 -396.324052) (xy 71.396687 -396.260955) (xy 71.427838 -396.201158) (xy 71.465928 -396.145523)
			(xy 71.487792 -396.119858) (xy 71.493588 -396.112712) (xy 71.500103 -396.095522) (xy 71.500492 -396.08633)
			(xy 71.500492 -395.92885) (xy 71.501066 -395.918732) (xy 71.508769 -395.900021) (xy 71.523028 -395.885665)
			(xy 71.541686 -395.877836) (xy 71.5518 -395.877288) (xy 72.26808 -395.877288) (xy 72.278231 -395.877738)
			(xy 72.296981 -395.885524) (xy 72.311305 -395.899912) (xy 72.319007 -395.918697) (xy 72.319388 -395.92885)
			(xy 72.319388 -396.08633) (xy 72.319786 -396.095518) (xy 72.326308 -396.112703) (xy 72.332088 -396.119858)
			(xy 72.353943 -396.145531) (xy 72.392032 -396.201164) (xy 72.423184 -396.260959) (xy 72.446949 -396.324055)
			(xy 72.462986 -396.389543) (xy 72.471063 -396.456481) (xy 72.471064 -396.523904) (xy 72.462989 -396.590842)
			(xy 72.446954 -396.656331) (xy 72.42319 -396.719427) (xy 72.39204 -396.779223) (xy 72.353952 -396.834857)
			(xy 72.332088 -396.860522) (xy 72.326298 -396.867672) (xy 72.31978 -396.884859) (xy 72.319388 -396.89405)
			(xy 72.319388 -397.386302) (xy 72.3198 -397.395489) (xy 72.326313 -397.412673) (xy 72.332088 -397.41983)
			(xy 72.353915 -397.445526) (xy 72.392006 -397.501156) (xy 72.420766 -397.556355) (xy 73.54898 -397.556355)
			(xy 73.557023 -397.489534) (xy 73.572995 -397.424152) (xy 73.596666 -397.361148) (xy 73.627698 -397.301425)
			(xy 73.665645 -397.245838) (xy 73.687432 -397.220186) (xy 73.693221 -397.213036) (xy 73.69974 -397.195849)
			(xy 73.700132 -397.186658) (xy 73.700132 -397.028924) (xy 73.700542 -397.018767) (xy 73.708335 -397.000009)
			(xy 73.722736 -396.985684) (xy 73.741535 -396.977989) (xy 73.751694 -396.977616) (xy 74.467974 -396.977616)
			(xy 74.478096 -396.978147) (xy 74.496812 -396.985862) (xy 74.511169 -397.000134) (xy 74.518993 -397.018805)
			(xy 74.519536 -397.028924) (xy 74.519536 -397.186658) (xy 74.519981 -397.195841) (xy 74.526472 -397.213025)
			(xy 74.532236 -397.220186) (xy 74.554034 -397.24583) (xy 74.591984 -397.301417) (xy 74.623019 -397.361141)
			(xy 74.646692 -397.424147) (xy 74.662665 -397.48953) (xy 74.670709 -397.556354) (xy 74.670708 -397.623661)
			(xy 74.662662 -397.690484) (xy 74.646687 -397.755867) (xy 74.623012 -397.818872) (xy 74.620438 -397.823826)
			(xy 75.749084 -397.823826) (xy 75.749087 -397.756517) (xy 75.757136 -397.689691) (xy 75.773114 -397.624306)
			(xy 75.796793 -397.5613) (xy 75.827833 -397.501576) (xy 75.865789 -397.44599) (xy 75.88758 -397.420338)
			(xy 75.893383 -397.413197) (xy 75.899895 -397.396003) (xy 75.90028 -397.38681) (xy 75.90028 -396.893542)
			(xy 75.899854 -396.884356) (xy 75.893352 -396.867172) (xy 75.88758 -396.860014) (xy 75.865781 -396.83437)
			(xy 75.82783 -396.778784) (xy 75.796795 -396.719059) (xy 75.773121 -396.656054) (xy 75.757147 -396.59067)
			(xy 75.749104 -396.523846) (xy 75.749104 -396.456539) (xy 75.75715 -396.389715) (xy 75.773125 -396.324332)
			(xy 75.796801 -396.261327) (xy 75.827838 -396.201603) (xy 75.86579 -396.146018) (xy 75.88758 -396.120366)
			(xy 75.893371 -396.113217) (xy 75.89989 -396.096029) (xy 75.90028 -396.086838) (xy 75.90028 -395.92885)
			(xy 75.900706 -395.918676) (xy 75.908482 -395.899875) (xy 75.922868 -395.885487) (xy 75.941668 -395.877707)
			(xy 75.951842 -395.877288) (xy 76.668122 -395.877288) (xy 76.678301 -395.877647) (xy 76.697106 -395.885449)
			(xy 76.711492 -395.899855) (xy 76.719267 -395.91867) (xy 76.719684 -395.92885) (xy 76.719684 -396.086838)
			(xy 76.720079 -396.096027) (xy 76.726604 -396.113211) (xy 76.732384 -396.120366) (xy 76.754161 -396.146026)
			(xy 76.792109 -396.201612) (xy 76.823141 -396.261335) (xy 76.846814 -396.324338) (xy 76.862787 -396.389719)
			(xy 76.870831 -396.456541) (xy 76.870832 -396.523844) (xy 76.862789 -396.590666) (xy 76.846818 -396.656047)
			(xy 76.823147 -396.719051) (xy 76.792117 -396.778775) (xy 76.75417 -396.834362) (xy 76.732384 -396.860014)
			(xy 76.726597 -396.867166) (xy 76.720077 -396.884351) (xy 76.719684 -396.893542) (xy 76.719684 -397.38681)
			(xy 76.720093 -397.395997) (xy 76.726608 -397.413181) (xy 76.732384 -397.420338) (xy 76.754133 -397.446021)
			(xy 76.792082 -397.501604) (xy 76.820503 -397.556296) (xy 77.948748 -397.556296) (xy 77.956824 -397.489358)
			(xy 77.972859 -397.423869) (xy 77.996623 -397.360772) (xy 78.027774 -397.300977) (xy 78.065864 -397.245343)
			(xy 78.087728 -397.219678) (xy 78.09352 -397.21253) (xy 78.100037 -397.195341) (xy 78.100428 -397.18615)
			(xy 78.100428 -397.028924) (xy 78.100836 -397.0188) (xy 78.108582 -397.000091) (xy 78.122901 -396.985775)
			(xy 78.141611 -396.978034) (xy 78.151736 -396.977616) (xy 78.868016 -396.977616) (xy 78.878142 -396.978003)
			(xy 78.896849 -396.985759) (xy 78.911163 -397.000085) (xy 78.918905 -397.018798) (xy 78.919324 -397.028924)
			(xy 78.919324 -397.18615) (xy 78.919753 -397.195335) (xy 78.926253 -397.21252) (xy 78.932024 -397.219678)
			(xy 78.953897 -397.245336) (xy 78.991984 -397.300972) (xy 79.023133 -397.360769) (xy 79.046895 -397.423867)
			(xy 79.062929 -397.489357) (xy 79.071004 -397.556296) (xy 79.071003 -397.62372) (xy 79.062927 -397.690658)
			(xy 79.046891 -397.756147) (xy 79.023127 -397.819245) (xy 79.02071 -397.823885) (xy 80.148876 -397.823885)
			(xy 80.14888 -397.756458) (xy 80.156959 -397.689518) (xy 80.172998 -397.624027) (xy 80.196765 -397.560929)
			(xy 80.227919 -397.501131) (xy 80.266011 -397.445496) (xy 80.287876 -397.41983) (xy 80.293682 -397.412691)
			(xy 80.300192 -397.395496) (xy 80.300576 -397.386302) (xy 80.300576 -396.89405) (xy 80.300147 -396.884865)
			(xy 80.293647 -396.86768) (xy 80.287876 -396.860522) (xy 80.266003 -396.834864) (xy 80.227916 -396.779228)
			(xy 80.196767 -396.719431) (xy 80.173005 -396.656333) (xy 80.156971 -396.590843) (xy 80.148896 -396.523904)
			(xy 80.148897 -396.45648) (xy 80.156973 -396.389542) (xy 80.173009 -396.324053) (xy 80.196773 -396.260955)
			(xy 80.227924 -396.201159) (xy 80.266012 -396.145524) (xy 80.287876 -396.119858) (xy 80.29367 -396.112711)
			(xy 80.300187 -396.095522) (xy 80.300576 -396.08633) (xy 80.300576 -395.92885) (xy 80.301069 -395.918722)
			(xy 80.308787 -395.899995) (xy 80.323072 -395.885636) (xy 80.341759 -395.877821) (xy 80.351884 -395.877288)
			(xy 81.068164 -395.877288) (xy 81.078314 -395.877751) (xy 81.097063 -395.885532) (xy 81.111388 -395.899917)
			(xy 81.119091 -395.918698) (xy 81.119472 -395.92885) (xy 81.119472 -396.08633) (xy 81.119874 -396.095518)
			(xy 81.126394 -396.112702) (xy 81.132172 -396.119858) (xy 81.154027 -396.145531) (xy 81.192118 -396.201164)
			(xy 81.223271 -396.260959) (xy 81.247037 -396.324054) (xy 81.263074 -396.389543) (xy 81.271151 -396.456481)
			(xy 81.271152 -396.523904) (xy 81.263076 -396.590842) (xy 81.247041 -396.656331) (xy 81.223277 -396.719428)
			(xy 81.192126 -396.779223) (xy 81.154036 -396.834857) (xy 81.132172 -396.860522) (xy 81.12638 -396.86767)
			(xy 81.119863 -396.884859) (xy 81.119472 -396.89405) (xy 81.119472 -397.386302) (xy 81.119887 -397.395489)
			(xy 81.126398 -397.412673) (xy 81.132172 -397.41983) (xy 81.154 -397.445526) (xy 81.192091 -397.501155)
			(xy 81.220853 -397.556356) (xy 82.349068 -397.556356) (xy 82.357111 -397.489534) (xy 82.373082 -397.424153)
			(xy 82.396753 -397.361149) (xy 82.427783 -397.301425) (xy 82.46573 -397.245838) (xy 82.487516 -397.220186)
			(xy 82.493303 -397.213034) (xy 82.499823 -397.195849) (xy 82.500216 -397.186658) (xy 82.500216 -397.028924)
			(xy 82.500641 -397.018769) (xy 82.508432 -397.000014) (xy 82.522828 -396.98569) (xy 82.541621 -396.977992)
			(xy 82.551778 -396.977616) (xy 83.268058 -396.977616) (xy 83.278179 -396.97816) (xy 83.296895 -396.98587)
			(xy 83.311252 -397.000138) (xy 83.319076 -397.018806) (xy 83.31962 -397.028924) (xy 83.31962 -397.186658)
			(xy 83.320046 -397.195844) (xy 83.326548 -397.213028) (xy 83.33232 -397.220186) (xy 83.354119 -397.24583)
			(xy 83.39207 -397.301416) (xy 83.423105 -397.361141) (xy 83.446779 -397.424146) (xy 83.462753 -397.48953)
			(xy 83.470796 -397.556354) (xy 83.470796 -397.623661) (xy 83.46275 -397.690485) (xy 83.446775 -397.755868)
			(xy 83.423099 -397.818873) (xy 83.420495 -397.823884) (xy 84.548667 -397.823884) (xy 84.548671 -397.756458)
			(xy 84.55675 -397.689518) (xy 84.572788 -397.624028) (xy 84.596555 -397.560929) (xy 84.627708 -397.501132)
			(xy 84.665799 -397.445496) (xy 84.687664 -397.41983) (xy 84.693481 -397.412699) (xy 84.699982 -397.395497)
			(xy 84.700364 -397.386302) (xy 84.700364 -396.89405) (xy 84.699916 -396.884867) (xy 84.693427 -396.867683)
			(xy 84.687664 -396.860522) (xy 84.665791 -396.834864) (xy 84.627705 -396.779228) (xy 84.596557 -396.71943)
			(xy 84.572795 -396.656332) (xy 84.556761 -396.590843) (xy 84.548687 -396.523904) (xy 84.548688 -396.456481)
			(xy 84.556764 -396.389542) (xy 84.5728 -396.324053) (xy 84.596563 -396.260956) (xy 84.627713 -396.201159)
			(xy 84.665801 -396.145524) (xy 84.687664 -396.119858) (xy 84.693469 -396.112719) (xy 84.699977 -396.095523)
			(xy 84.700364 -396.08633) (xy 84.700364 -395.92885) (xy 84.700868 -395.918724) (xy 84.708584 -395.899999)
			(xy 84.722866 -395.88564) (xy 84.741548 -395.877823) (xy 84.751672 -395.877288) (xy 85.467952 -395.877288)
			(xy 85.478102 -395.877761) (xy 85.496851 -395.885538) (xy 85.511175 -395.899919) (xy 85.518879 -395.918699)
			(xy 85.51926 -395.92885) (xy 85.51926 -396.08633) (xy 85.519665 -396.095518) (xy 85.526183 -396.112701)
			(xy 85.53196 -396.119858) (xy 85.553816 -396.145531) (xy 85.591907 -396.201163) (xy 85.623061 -396.260958)
			(xy 85.646827 -396.324054) (xy 85.662864 -396.389543) (xy 85.670942 -396.456481) (xy 85.670943 -396.523904)
			(xy 85.662867 -396.590843) (xy 85.646832 -396.656332) (xy 85.623067 -396.719428) (xy 85.591915 -396.779224)
			(xy 85.553825 -396.834857) (xy 85.53196 -396.860522) (xy 85.526167 -396.867669) (xy 85.519651 -396.884858)
			(xy 85.51926 -396.89405) (xy 85.51926 -397.386302) (xy 85.519678 -397.395488) (xy 85.526187 -397.412672)
			(xy 85.53196 -397.41983) (xy 85.553788 -397.445525) (xy 85.591881 -397.501155) (xy 85.620612 -397.556296)
			(xy 86.748836 -397.556296) (xy 86.756911 -397.489358) (xy 86.772946 -397.423869) (xy 86.79671 -397.360773)
			(xy 86.82786 -397.300977) (xy 86.865948 -397.245343) (xy 86.887812 -397.219678) (xy 86.893602 -397.212528)
			(xy 86.90012 -397.195341) (xy 86.900512 -397.18615) (xy 86.900512 -397.028924) (xy 86.900936 -397.018802)
			(xy 86.908678 -397.000096) (xy 86.922993 -396.985781) (xy 86.941698 -396.978037) (xy 86.95182 -396.977616)
			(xy 87.6681 -396.977616) (xy 87.678224 -396.978016) (xy 87.696931 -396.985768) (xy 87.711246 -397.000089)
			(xy 87.718988 -397.018799) (xy 87.719408 -397.028924) (xy 87.719408 -397.18615) (xy 87.71984 -397.195335)
			(xy 87.726338 -397.21252) (xy 87.732108 -397.219678) (xy 87.753982 -397.245335) (xy 87.792069 -397.300971)
			(xy 87.823219 -397.360769) (xy 87.846982 -397.423866) (xy 87.863017 -397.489356) (xy 87.871092 -397.556295)
			(xy 87.871091 -397.62372) (xy 87.863014 -397.690658) (xy 87.846978 -397.756148) (xy 87.823213 -397.819245)
			(xy 87.820827 -397.823826) (xy 88.948962 -397.823826) (xy 88.948966 -397.756517) (xy 88.957014 -397.689692)
			(xy 88.972991 -397.624307) (xy 88.996669 -397.561301) (xy 89.027707 -397.501577) (xy 89.065661 -397.44599)
			(xy 89.087452 -397.420338) (xy 89.093264 -397.413204) (xy 89.099768 -397.396005) (xy 89.100152 -397.38681)
			(xy 89.100152 -396.893542) (xy 89.09971 -396.884358) (xy 89.093217 -396.867175) (xy 89.087452 -396.860014)
			(xy 89.065654 -396.83437) (xy 89.027704 -396.778783) (xy 88.996671 -396.719058) (xy 88.972998 -396.656053)
			(xy 88.957025 -396.590669) (xy 88.948982 -396.523846) (xy 88.948983 -396.456539) (xy 88.957028 -396.389716)
			(xy 88.973003 -396.324333) (xy 88.996677 -396.261328) (xy 89.027712 -396.201604) (xy 89.065663 -396.146018)
			(xy 89.087452 -396.120366) (xy 89.093252 -396.113223) (xy 89.099763 -396.096031) (xy 89.100152 -396.086838)
			(xy 89.100152 -395.92885) (xy 89.100605 -395.91868) (xy 89.108376 -395.899884) (xy 89.122753 -395.885496)
			(xy 89.141544 -395.877712) (xy 89.151714 -395.877288) (xy 89.867994 -395.877288) (xy 89.878171 -395.87767)
			(xy 89.896976 -395.885462) (xy 89.911362 -395.899861) (xy 89.919139 -395.918672) (xy 89.919556 -395.92885)
			(xy 89.919556 -396.086838) (xy 89.919958 -396.096026) (xy 89.926478 -396.11321) (xy 89.932256 -396.120366)
			(xy 89.954034 -396.146026) (xy 89.991983 -396.201611) (xy 90.023017 -396.261334) (xy 90.046691 -396.324337)
			(xy 90.062665 -396.389719) (xy 90.07071 -396.45654) (xy 90.070711 -396.523845) (xy 90.062667 -396.590667)
			(xy 90.046695 -396.656048) (xy 90.023023 -396.719052) (xy 89.991991 -396.778776) (xy 89.954043 -396.834362)
			(xy 89.932256 -396.860014) (xy 89.926465 -396.867163) (xy 89.919948 -396.884351) (xy 89.919556 -396.893542)
			(xy 89.919556 -397.38681) (xy 89.919971 -397.395996) (xy 89.926482 -397.41318) (xy 89.932256 -397.420338)
			(xy 89.954006 -397.446021) (xy 89.991957 -397.501603) (xy 90.020411 -397.556356) (xy 91.149156 -397.556356)
			(xy 91.157198 -397.489535) (xy 91.173169 -397.424153) (xy 91.196839 -397.361149) (xy 91.227869 -397.301426)
			(xy 91.265814 -397.245839) (xy 91.2876 -397.220186) (xy 91.293385 -397.213033) (xy 91.299907 -397.195848)
			(xy 91.3003 -397.186658) (xy 91.3003 -397.028924) (xy 91.300741 -397.018771) (xy 91.308529 -397.000019)
			(xy 91.32292 -396.985695) (xy 91.341708 -396.977995) (xy 91.351862 -396.977616) (xy 92.068142 -396.977616)
			(xy 92.078268 -396.978091) (xy 92.096986 -396.985829) (xy 92.11134 -397.000118) (xy 92.119162 -397.0188)
			(xy 92.119704 -397.028924) (xy 92.119704 -397.186658) (xy 92.120133 -397.195843) (xy 92.126634 -397.213028)
			(xy 92.132404 -397.220186) (xy 92.1542 -397.245831) (xy 92.192146 -397.301419) (xy 92.223176 -397.361144)
			(xy 92.246847 -397.42415) (xy 92.262818 -397.489532) (xy 92.27086 -397.556355) (xy 92.270859 -397.62366)
			(xy 92.262815 -397.690483) (xy 92.246842 -397.755865) (xy 92.22317 -397.81887) (xy 92.220595 -397.823825)
			(xy 115.349226 -397.823825) (xy 115.349229 -397.756518) (xy 115.357277 -397.689693) (xy 115.373253 -397.624309)
			(xy 115.396928 -397.561303) (xy 115.427964 -397.501578) (xy 115.465915 -397.445991) (xy 115.487704 -397.420338)
			(xy 115.49351 -397.413199) (xy 115.500019 -397.396004) (xy 115.500404 -397.38681) (xy 115.500404 -396.893542)
			(xy 115.499973 -396.884357) (xy 115.493474 -396.867173) (xy 115.487704 -396.860014) (xy 115.465908 -396.834369)
			(xy 115.427961 -396.778781) (xy 115.39693 -396.719056) (xy 115.37326 -396.656051) (xy 115.357288 -396.590668)
			(xy 115.349246 -396.523845) (xy 115.349247 -396.45654) (xy 115.357291 -396.389717) (xy 115.373264 -396.324335)
			(xy 115.396937 -396.26133) (xy 115.427969 -396.201606) (xy 115.465917 -396.146019) (xy 115.487704 -396.120366)
			(xy 115.493498 -396.113219) (xy 115.500014 -396.09603) (xy 115.500404 -396.086838) (xy 115.500404 -395.92885)
			(xy 115.500904 -395.918686) (xy 115.508666 -395.899899) (xy 115.523028 -395.885513) (xy 115.541803 -395.87772)
			(xy 115.551966 -395.877288) (xy 116.268246 -395.877288) (xy 116.278427 -395.877627) (xy 116.297232 -395.885437)
			(xy 116.311617 -395.899849) (xy 116.319392 -395.918668) (xy 116.319808 -395.92885) (xy 116.319808 -396.086838)
			(xy 116.320198 -396.096027) (xy 116.326725 -396.113212) (xy 116.332508 -396.120366) (xy 116.354288 -396.146026)
			(xy 116.39224 -396.20161) (xy 116.423277 -396.261332) (xy 116.446952 -396.324335) (xy 116.462928 -396.389717)
			(xy 116.470973 -396.45654) (xy 116.470974 -396.523845) (xy 116.46293 -396.590668) (xy 116.446957 -396.65605)
			(xy 116.423283 -396.719055) (xy 116.392248 -396.778777) (xy 116.354297 -396.834363) (xy 116.332508 -396.860014)
			(xy 116.326724 -396.867168) (xy 116.320202 -396.884352) (xy 116.319808 -396.893542) (xy 116.319808 -397.38681)
			(xy 116.320212 -397.395998) (xy 116.32673 -397.413182) (xy 116.332508 -397.420338) (xy 116.35426 -397.44602)
			(xy 116.392213 -397.501601) (xy 116.42064 -397.556296) (xy 117.548866 -397.556296) (xy 117.556942 -397.489357)
			(xy 117.572978 -397.423868) (xy 117.596743 -397.360771) (xy 117.627896 -397.300976) (xy 117.665987 -397.245342)
			(xy 117.687852 -397.219678) (xy 117.693647 -397.212532) (xy 117.700161 -397.195342) (xy 117.700552 -397.18615)
			(xy 117.700552 -397.028924) (xy 117.701103 -397.018823) (xy 117.708824 -397.000154) (xy 117.7231 -396.98586)
			(xy 117.741759 -396.978116) (xy 117.75186 -396.977616) (xy 118.46814 -396.977616) (xy 118.478253 -396.978053)
			(xy 118.496935 -396.985807) (xy 118.511229 -397.000118) (xy 118.51896 -397.01881) (xy 118.519448 -397.028924)
			(xy 118.519448 -397.18615) (xy 118.519894 -397.195333) (xy 118.526384 -397.212517) (xy 118.532148 -397.219678)
			(xy 118.554024 -397.245334) (xy 118.592115 -397.300969) (xy 118.623269 -397.360766) (xy 118.647035 -397.423864)
			(xy 118.663071 -397.489355) (xy 118.671147 -397.556295) (xy 118.671146 -397.62372) (xy 118.663068 -397.69066)
			(xy 118.64703 -397.75615) (xy 118.623262 -397.819248) (xy 118.620846 -397.823885) (xy 119.748994 -397.823885)
			(xy 119.748998 -397.756458) (xy 119.757077 -397.689517) (xy 119.773117 -397.624026) (xy 119.796885 -397.560928)
			(xy 119.828041 -397.50113) (xy 119.866134 -397.445495) (xy 119.888 -397.41983) (xy 119.893809 -397.412693)
			(xy 119.900316 -397.395496) (xy 119.9007 -397.386302) (xy 119.9007 -396.89405) (xy 119.900266 -396.884865)
			(xy 119.893769 -396.867681) (xy 119.888 -396.860522) (xy 119.866126 -396.834865) (xy 119.828038 -396.779229)
			(xy 119.796888 -396.719432) (xy 119.773124 -396.656334) (xy 119.757089 -396.590844) (xy 119.749014 -396.523905)
			(xy 119.749015 -396.45648) (xy 119.757092 -396.389541) (xy 119.773128 -396.324052) (xy 119.796894 -396.260954)
			(xy 119.828046 -396.201158) (xy 119.866135 -396.145523) (xy 119.888 -396.119858) (xy 119.893797 -396.112713)
			(xy 119.900311 -396.095522) (xy 119.9007 -396.08633) (xy 119.9007 -395.92885) (xy 119.901266 -395.918731)
			(xy 119.90897 -395.900019) (xy 119.923232 -395.885662) (xy 119.941893 -395.877834) (xy 119.952008 -395.877288)
			(xy 120.668288 -395.877288) (xy 120.678408 -395.877725) (xy 120.697109 -395.885467) (xy 120.711424 -395.899777)
			(xy 120.719171 -395.918476) (xy 120.719596 -395.928596) (xy 120.719596 -396.08633) (xy 120.719992 -396.095519)
			(xy 120.726516 -396.112703) (xy 120.732296 -396.119858) (xy 120.75415 -396.145531) (xy 120.79224 -396.201165)
			(xy 120.823391 -396.26096) (xy 120.847156 -396.324055) (xy 120.863192 -396.389544) (xy 120.871269 -396.456481)
			(xy 120.87127 -396.523904) (xy 120.863195 -396.590842) (xy 120.84716 -396.65633) (xy 120.823397 -396.719427)
			(xy 120.792247 -396.779223) (xy 120.75416 -396.834857) (xy 120.732296 -396.860522) (xy 120.726507 -396.867673)
			(xy 120.719988 -396.884859) (xy 120.719596 -396.89405) (xy 120.719596 -397.386302) (xy 120.720006 -397.395489)
			(xy 120.72652 -397.412673) (xy 120.732296 -397.41983) (xy 120.754123 -397.445526) (xy 120.792213 -397.501156)
			(xy 120.820972 -397.556355) (xy 121.949186 -397.556355) (xy 121.95723 -397.489533) (xy 121.973202 -397.424152)
			(xy 121.996873 -397.361148) (xy 122.027905 -397.301425) (xy 122.065853 -397.245838) (xy 122.08764 -397.220186)
			(xy 122.09343 -397.213036) (xy 122.099948 -397.195849) (xy 122.10034 -397.186658) (xy 122.10034 -397.028924)
			(xy 122.100736 -397.018798) (xy 122.108484 -397.000087) (xy 122.122807 -396.985771) (xy 122.141522 -396.978032)
			(xy 122.151648 -396.977616) (xy 122.868182 -396.977616) (xy 122.878305 -396.978141) (xy 122.897021 -396.985858)
			(xy 122.911377 -397.000132) (xy 122.919201 -397.018804) (xy 122.919744 -397.028924) (xy 122.919744 -397.186658)
			(xy 122.920187 -397.195841) (xy 122.926679 -397.213026) (xy 122.932444 -397.220186) (xy 122.954242 -397.24583)
			(xy 122.992192 -397.301417) (xy 123.023225 -397.361142) (xy 123.046898 -397.424147) (xy 123.062871 -397.489531)
			(xy 123.070915 -397.556354) (xy 123.070914 -397.623661) (xy 123.062868 -397.690484) (xy 123.046894 -397.755867)
			(xy 123.023219 -397.818872) (xy 123.020645 -397.823826) (xy 124.14929 -397.823826) (xy 124.149293 -397.756517)
			(xy 124.157342 -397.689691) (xy 124.17332 -397.624306) (xy 124.197 -397.5613) (xy 124.22804 -397.501575)
			(xy 124.265997 -397.44599) (xy 124.287788 -397.420338) (xy 124.293592 -397.413198) (xy 124.300103 -397.396004)
			(xy 124.300488 -397.38681) (xy 124.300488 -396.893542) (xy 124.30006 -396.884357) (xy 124.293559 -396.867172)
			(xy 124.287788 -396.860014) (xy 124.265989 -396.834371) (xy 124.228037 -396.778784) (xy 124.197002 -396.71906)
			(xy 124.173327 -396.656054) (xy 124.157354 -396.59067) (xy 124.14931 -396.523846) (xy 124.14931 -396.456539)
			(xy 124.157356 -396.389715) (xy 124.173332 -396.324332) (xy 124.197008 -396.261327) (xy 124.228045 -396.201603)
			(xy 124.265998 -396.146018) (xy 124.287788 -396.120366) (xy 124.29358 -396.113218) (xy 124.300098 -396.09603)
			(xy 124.300488 -396.086838) (xy 124.300488 -395.92885) (xy 124.300906 -395.918675) (xy 124.308684 -395.899872)
			(xy 124.323072 -395.885484) (xy 124.341875 -395.877706) (xy 124.35205 -395.877288) (xy 125.06833 -395.877288)
			(xy 125.07851 -395.87764) (xy 125.097315 -395.885445) (xy 125.1117 -395.899852) (xy 125.119475 -395.91867)
			(xy 125.119892 -395.92885) (xy 125.119892 -396.086838) (xy 125.120286 -396.096027) (xy 125.126811 -396.113211)
			(xy 125.132592 -396.120366) (xy 125.154369 -396.146027) (xy 125.192316 -396.201613) (xy 125.223348 -396.261335)
			(xy 125.24702 -396.324339) (xy 125.262993 -396.389719) (xy 125.271037 -396.456541) (xy 125.271038 -396.523844)
			(xy 125.262995 -396.590666) (xy 125.247025 -396.656047) (xy 125.223354 -396.719051) (xy 125.192324 -396.778774)
			(xy 125.154378 -396.834361) (xy 125.132592 -396.860014) (xy 125.126806 -396.867167) (xy 125.120285 -396.884351)
			(xy 125.119892 -396.893542) (xy 125.119892 -397.38681) (xy 125.120299 -397.395998) (xy 125.126815 -397.413182)
			(xy 125.132592 -397.420338) (xy 125.154341 -397.446021) (xy 125.192289 -397.501604) (xy 125.22071 -397.556296)
			(xy 126.348954 -397.556296) (xy 126.35703 -397.489357) (xy 126.373065 -397.423869) (xy 126.39683 -397.360772)
			(xy 126.427981 -397.300976) (xy 126.466071 -397.245343) (xy 126.487936 -397.219678) (xy 126.493729 -397.21253)
			(xy 126.500245 -397.195342) (xy 126.500636 -397.18615) (xy 126.500636 -397.028924) (xy 126.501036 -397.018799)
			(xy 126.508783 -397.000089) (xy 126.523105 -396.985772) (xy 126.541818 -396.978032) (xy 126.551944 -396.977616)
			(xy 127.268224 -396.977616) (xy 127.278336 -396.978066) (xy 127.297018 -396.985814) (xy 127.311313 -397.000122)
			(xy 127.319044 -397.018811) (xy 127.319532 -397.028924) (xy 127.319532 -397.18615) (xy 127.319981 -397.195333)
			(xy 127.326469 -397.212517) (xy 127.332232 -397.219678) (xy 127.354105 -397.245336) (xy 127.392191 -397.300972)
			(xy 127.423339 -397.36077) (xy 127.447102 -397.423867) (xy 127.463135 -397.489357) (xy 127.47121 -397.556296)
			(xy 127.471209 -397.623719) (xy 127.463133 -397.690658) (xy 127.447097 -397.756147) (xy 127.423333 -397.819244)
			(xy 127.420946 -397.823826) (xy 128.54908 -397.823826) (xy 128.549084 -397.756517) (xy 128.557132 -397.689691)
			(xy 128.57311 -397.624306) (xy 128.596789 -397.5613) (xy 128.627829 -397.501576) (xy 128.665785 -397.445989)
			(xy 128.687576 -397.420338) (xy 128.693379 -397.413197) (xy 128.69989 -397.396003) (xy 128.700276 -397.38681)
			(xy 128.700276 -396.893542) (xy 128.699851 -396.884356) (xy 128.693348 -396.867171) (xy 128.687576 -396.860014)
			(xy 128.665777 -396.83437) (xy 128.627826 -396.778784) (xy 128.596792 -396.719059) (xy 128.573118 -396.656053)
			(xy 128.557144 -396.59067) (xy 128.5491 -396.523846) (xy 128.549101 -396.456539) (xy 128.557147 -396.389715)
			(xy 128.573122 -396.324332) (xy 128.596798 -396.261327) (xy 128.627834 -396.201604) (xy 128.665787 -396.146018)
			(xy 128.687576 -396.120366) (xy 128.693367 -396.113216) (xy 128.699886 -396.096029) (xy 128.700276 -396.086838)
			(xy 128.700276 -395.92885) (xy 128.700706 -395.918677) (xy 128.708481 -395.899876) (xy 128.722866 -395.885488)
			(xy 128.741665 -395.877708) (xy 128.751838 -395.877288) (xy 129.468118 -395.877288) (xy 129.478297 -395.87765)
			(xy 129.497102 -395.885451) (xy 129.511487 -395.899856) (xy 129.519263 -395.91867) (xy 129.51968 -395.92885)
			(xy 129.51968 -396.086838) (xy 129.520076 -396.096027) (xy 129.5266 -396.113211) (xy 129.53238 -396.120366)
			(xy 129.554157 -396.146026) (xy 129.592105 -396.201612) (xy 129.623138 -396.261335) (xy 129.64681 -396.324338)
			(xy 129.662784 -396.389719) (xy 129.670828 -396.456541) (xy 129.670829 -396.523844) (xy 129.662786 -396.590666)
			(xy 129.646815 -396.656047) (xy 129.623144 -396.719051) (xy 129.592113 -396.778775) (xy 129.554167 -396.834362)
			(xy 129.53238 -396.860014) (xy 129.526593 -396.867166) (xy 129.520073 -396.884351) (xy 129.51968 -396.893542)
			(xy 129.51968 -397.38681) (xy 129.52009 -397.395997) (xy 129.526604 -397.413181) (xy 129.53238 -397.420338)
			(xy 129.55413 -397.446021) (xy 129.592078 -397.501604) (xy 129.620531 -397.556356) (xy 130.749274 -397.556356)
			(xy 130.757317 -397.489534) (xy 130.773288 -397.424152) (xy 130.796959 -397.361148) (xy 130.827991 -397.301425)
			(xy 130.865937 -397.245838) (xy 130.887724 -397.220186) (xy 130.893512 -397.213035) (xy 130.900031 -397.195849)
			(xy 130.900424 -397.186658) (xy 130.900424 -397.028924) (xy 130.900842 -397.018768) (xy 130.908634 -397.000012)
			(xy 130.923032 -396.985687) (xy 130.941828 -396.97799) (xy 130.951986 -396.977616) (xy 131.668266 -396.977616)
			(xy 131.678388 -396.978154) (xy 131.697103 -396.985866) (xy 131.71146 -397.000137) (xy 131.719284 -397.018806)
			(xy 131.719828 -397.028924) (xy 131.719828 -397.186658) (xy 131.720252 -397.195844) (xy 131.726756 -397.213029)
			(xy 131.732528 -397.220186) (xy 131.754326 -397.24583) (xy 131.792277 -397.301417) (xy 131.823312 -397.361141)
			(xy 131.846985 -397.424147) (xy 131.862959 -397.48953) (xy 131.871003 -397.556354) (xy 131.871002 -397.623661)
			(xy 131.862956 -397.690485) (xy 131.846981 -397.755868) (xy 131.823306 -397.818873) (xy 131.792269 -397.878596)
			(xy 131.754317 -397.934182) (xy 131.732528 -397.959834) (xy 131.726726 -397.966975) (xy 131.720217 -397.984169)
			(xy 131.719828 -397.993362) (xy 131.719828 -398.486884) (xy 131.720239 -398.496071) (xy 131.726751 -398.513256)
			(xy 131.732528 -398.520412) (xy 131.754352 -398.546034) (xy 131.792302 -398.601624) (xy 131.823336 -398.661352)
			(xy 131.847008 -398.72436) (xy 131.86298 -398.789746) (xy 131.871021 -398.856573) (xy 131.871018 -398.923881)
			(xy 131.86297 -398.990707) (xy 131.846992 -399.056092) (xy 131.823314 -399.119098) (xy 131.792274 -399.178822)
			(xy 131.754319 -399.234408) (xy 131.732528 -399.26006) (xy 131.726715 -399.267193) (xy 131.720212 -399.284393)
			(xy 131.719828 -399.293588) (xy 131.719828 -399.451576) (xy 131.719359 -399.461725) (xy 131.711577 -399.480472)
			(xy 131.697195 -399.494795) (xy 131.678417 -399.502501) (xy 131.668266 -399.502884) (xy 130.951986 -399.502884)
			(xy 130.941861 -399.502385) (xy 130.923145 -399.494657) (xy 130.90879 -399.480375) (xy 130.900967 -399.461698)
			(xy 130.900424 -399.451576) (xy 130.900424 -399.293588) (xy 130.900014 -399.284401) (xy 130.8935 -399.267217)
			(xy 130.887724 -399.26006) (xy 130.865972 -399.234378) (xy 130.828023 -399.178796) (xy 130.796989 -399.119076)
			(xy 130.773315 -399.056076) (xy 130.75734 -398.990697) (xy 130.749294 -398.923878) (xy 130.74929 -398.856576)
			(xy 130.757331 -398.789756) (xy 130.773299 -398.724376) (xy 130.796967 -398.661373) (xy 130.827996 -398.601651)
			(xy 130.865939 -398.546065) (xy 130.887724 -398.520412) (xy 130.893543 -398.513283) (xy 130.900044 -398.49608)
			(xy 130.900424 -398.486884) (xy 130.900424 -397.993362) (xy 130.900027 -397.984174) (xy 130.893504 -397.96699)
			(xy 130.887724 -397.959834) (xy 130.865946 -397.934174) (xy 130.827998 -397.878588) (xy 130.796965 -397.818865)
			(xy 130.773293 -397.755862) (xy 130.75732 -397.690481) (xy 130.749275 -397.62366) (xy 130.749274 -397.556356)
			(xy 129.620531 -397.556356) (xy 129.623112 -397.561323) (xy 129.646786 -397.624324) (xy 129.662761 -397.689702)
			(xy 129.670808 -397.756521) (xy 129.670811 -397.823822) (xy 129.662771 -397.890642) (xy 129.646803 -397.956022)
			(xy 129.623135 -398.019025) (xy 129.592108 -398.078747) (xy 129.554165 -398.134333) (xy 129.53238 -398.159986)
			(xy 129.526562 -398.167116) (xy 129.520061 -398.184318) (xy 129.51968 -398.193514) (xy 129.51968 -398.351502)
			(xy 129.519169 -398.361658) (xy 129.511397 -398.380423) (xy 129.497037 -398.394788) (xy 129.478274 -398.402565)
			(xy 129.468118 -398.403064) (xy 128.751838 -398.403064) (xy 128.741669 -398.402605) (xy 128.722876 -398.394833)
			(xy 128.70849 -398.380458) (xy 128.700703 -398.361671) (xy 128.700276 -398.351502) (xy 128.700276 -398.193514)
			(xy 128.699865 -398.184327) (xy 128.693352 -398.167142) (xy 128.687576 -398.159986) (xy 128.66575 -398.134365)
			(xy 128.627799 -398.078775) (xy 128.596766 -398.019048) (xy 128.573093 -397.956039) (xy 128.557122 -397.890652)
			(xy 128.54908 -397.823826) (xy 127.420946 -397.823826) (xy 127.392183 -397.879041) (xy 127.354095 -397.934676)
			(xy 127.332232 -397.960342) (xy 127.326427 -397.967481) (xy 127.319919 -397.984676) (xy 127.319532 -397.99387)
			(xy 127.319532 -398.486376) (xy 127.319969 -398.49556) (xy 127.326466 -398.512744) (xy 127.332232 -398.519904)
			(xy 127.35413 -398.545541) (xy 127.392216 -398.60118) (xy 127.423363 -398.66098) (xy 127.447124 -398.724081)
			(xy 127.463156 -398.789573) (xy 127.471228 -398.856514) (xy 127.471225 -398.92394) (xy 127.463146 -398.99088)
			(xy 127.447108 -399.056371) (xy 127.423341 -399.119469) (xy 127.392188 -399.179266) (xy 127.354097 -399.234902)
			(xy 127.332232 -399.260568) (xy 127.326416 -399.267699) (xy 127.319915 -399.284901) (xy 127.319532 -399.294096)
			(xy 127.319532 -399.451576) (xy 127.318996 -399.461679) (xy 127.311272 -399.480351) (xy 127.296991 -399.494645)
			(xy 127.278327 -399.502387) (xy 127.268224 -399.502884) (xy 126.551944 -399.502884) (xy 126.541822 -399.502447)
			(xy 126.523117 -399.494711) (xy 126.5088 -399.4804) (xy 126.501056 -399.461697) (xy 126.500636 -399.451576)
			(xy 126.500636 -399.294096) (xy 126.50022 -399.28491) (xy 126.49371 -399.267726) (xy 126.487936 -399.260568)
			(xy 126.466106 -399.234874) (xy 126.428014 -399.179245) (xy 126.39686 -399.119453) (xy 126.373092 -399.056359)
			(xy 126.357053 -398.990873) (xy 126.348974 -398.923938) (xy 126.34897 -398.856516) (xy 126.357043 -398.78958)
			(xy 126.373076 -398.724092) (xy 126.396838 -398.660997) (xy 126.427986 -398.601202) (xy 126.466073 -398.545569)
			(xy 126.487936 -398.519904) (xy 126.493718 -398.512749) (xy 126.50024 -398.495566) (xy 126.500636 -398.486376)
			(xy 126.500636 -397.99387) (xy 126.500232 -397.984682) (xy 126.493713 -397.967498) (xy 126.487936 -397.960342)
			(xy 126.466081 -397.934669) (xy 126.427989 -397.879037) (xy 126.396836 -397.819242) (xy 126.37307 -397.756146)
			(xy 126.357032 -397.690657) (xy 126.348955 -397.623719) (xy 126.348954 -397.556296) (xy 125.22071 -397.556296)
			(xy 125.223323 -397.561324) (xy 125.246996 -397.624324) (xy 125.262971 -397.689702) (xy 125.271018 -397.756521)
			(xy 125.271021 -397.823822) (xy 125.262981 -397.890642) (xy 125.247013 -397.956021) (xy 125.223346 -398.019024)
			(xy 125.192319 -398.078747) (xy 125.154377 -398.134334) (xy 125.132592 -398.159986) (xy 125.126775 -398.167117)
			(xy 125.120273 -398.184318) (xy 125.119892 -398.193514) (xy 125.119892 -398.351502) (xy 125.119369 -398.361656)
			(xy 125.111599 -398.38042) (xy 125.097243 -398.394784) (xy 125.078484 -398.402563) (xy 125.06833 -398.403064)
			(xy 124.35205 -398.403064) (xy 124.341882 -398.402595) (xy 124.323089 -398.394827) (xy 124.308702 -398.380455)
			(xy 124.300915 -398.36167) (xy 124.300488 -398.351502) (xy 124.300488 -398.193514) (xy 124.300074 -398.184327)
			(xy 124.293563 -398.167143) (xy 124.287788 -398.159986) (xy 124.265961 -398.134365) (xy 124.228011 -398.078775)
			(xy 124.196976 -398.019048) (xy 124.173304 -397.956039) (xy 124.157332 -397.890653) (xy 124.14929 -397.823826)
			(xy 123.020645 -397.823826) (xy 122.992184 -397.878596) (xy 122.954233 -397.934182) (xy 122.932444 -397.959834)
			(xy 122.926644 -397.966976) (xy 122.920133 -397.984169) (xy 122.919744 -397.993362) (xy 122.919744 -398.486884)
			(xy 122.920174 -398.496069) (xy 122.926675 -398.513253) (xy 122.932444 -398.520412) (xy 122.954268 -398.546035)
			(xy 122.992217 -398.601625) (xy 123.023249 -398.661352) (xy 123.046921 -398.724361) (xy 123.062892 -398.789747)
			(xy 123.070933 -398.856573) (xy 123.07093 -398.923881) (xy 123.062882 -398.990707) (xy 123.046905 -399.056091)
			(xy 123.023227 -399.119097) (xy 122.992189 -399.178822) (xy 122.954235 -399.234408) (xy 122.932444 -399.26006)
			(xy 122.926633 -399.267194) (xy 122.920128 -399.284393) (xy 122.919744 -399.293588) (xy 122.919744 -399.451576)
			(xy 122.919196 -399.461678) (xy 122.911475 -399.480347) (xy 122.897197 -399.494641) (xy 122.878537 -399.502385)
			(xy 122.868436 -399.502884) (xy 122.151902 -399.502884) (xy 122.141778 -399.502372) (xy 122.123062 -399.49465)
			(xy 122.108706 -399.480371) (xy 122.100883 -399.461697) (xy 122.10034 -399.451576) (xy 122.10034 -399.293588)
			(xy 122.099927 -399.284401) (xy 122.093414 -399.267217) (xy 122.08764 -399.26006) (xy 122.065888 -399.234379)
			(xy 122.027938 -399.178796) (xy 121.996903 -399.119077) (xy 121.973228 -399.056076) (xy 121.957253 -398.990698)
			(xy 121.949206 -398.923878) (xy 121.949202 -398.856576) (xy 121.957243 -398.789756) (xy 121.973212 -398.724376)
			(xy 121.996881 -398.661373) (xy 122.02791 -398.60165) (xy 122.065855 -398.546064) (xy 122.08764 -398.520412)
			(xy 122.093461 -398.513285) (xy 122.09996 -398.49608) (xy 122.10034 -398.486884) (xy 122.10034 -397.993362)
			(xy 122.099939 -397.984174) (xy 122.093418 -397.96699) (xy 122.08764 -397.959834) (xy 122.065862 -397.934174)
			(xy 122.027913 -397.878588) (xy 121.996879 -397.818866) (xy 121.973206 -397.755863) (xy 121.957232 -397.690481)
			(xy 121.949187 -397.62366) (xy 121.949186 -397.556355) (xy 120.820972 -397.556355) (xy 120.823365 -397.560948)
			(xy 120.847132 -397.624041) (xy 120.86317 -397.689526) (xy 120.871249 -397.756461) (xy 120.871253 -397.823882)
			(xy 120.86318 -397.890818) (xy 120.847149 -397.956305) (xy 120.823389 -398.0194) (xy 120.792242 -398.079195)
			(xy 120.754158 -398.134829) (xy 120.732296 -398.160494) (xy 120.726519 -398.167653) (xy 120.719993 -398.184833)
			(xy 120.719596 -398.194022) (xy 120.719596 -398.351502) (xy 120.719076 -398.361624) (xy 120.711354 -398.380339)
			(xy 120.697079 -398.394694) (xy 120.678408 -398.402519) (xy 120.668288 -398.403064) (xy 119.952008 -398.403064)
			(xy 119.941882 -398.402677) (xy 119.923171 -398.394924) (xy 119.908855 -398.380599) (xy 119.901116 -398.361883)
			(xy 119.9007 -398.351756) (xy 119.9007 -398.194022) (xy 119.900279 -398.184836) (xy 119.893773 -398.167651)
			(xy 119.888 -398.160494) (xy 119.866099 -398.13486) (xy 119.828011 -398.079221) (xy 119.796862 -398.01942)
			(xy 119.7731 -397.956319) (xy 119.757067 -397.890826) (xy 119.748994 -397.823885) (xy 118.620846 -397.823885)
			(xy 118.592108 -397.879044) (xy 118.554014 -397.934678) (xy 118.532148 -397.960342) (xy 118.526345 -397.967482)
			(xy 118.519835 -397.984677) (xy 118.519448 -397.99387) (xy 118.519448 -398.486376) (xy 118.519881 -398.495561)
			(xy 118.52638 -398.512745) (xy 118.532148 -398.519904) (xy 118.554049 -398.545539) (xy 118.59214 -398.601177)
			(xy 118.623292 -398.660977) (xy 118.647057 -398.724078) (xy 118.663091 -398.789571) (xy 118.671165 -398.856513)
			(xy 118.671162 -398.923941) (xy 118.663082 -398.990882) (xy 118.647041 -399.056374) (xy 118.62327 -399.119473)
			(xy 118.592112 -399.17927) (xy 118.554016 -399.234904) (xy 118.532148 -399.260568) (xy 118.526334 -399.2677)
			(xy 118.519831 -399.284901) (xy 118.519448 -399.294096) (xy 118.519448 -399.451576) (xy 118.518897 -399.461677)
			(xy 118.511176 -399.480346) (xy 118.4969 -399.49464) (xy 118.478241 -399.502384) (xy 118.46814 -399.502884)
			(xy 117.75186 -399.502884) (xy 117.741747 -399.502447) (xy 117.723065 -399.494693) (xy 117.708771 -399.480382)
			(xy 117.70104 -399.46169) (xy 117.700552 -399.451576) (xy 117.700552 -399.294096) (xy 117.700132 -399.28491)
			(xy 117.693624 -399.267726) (xy 117.687852 -399.260568) (xy 117.666022 -399.234874) (xy 117.627928 -399.179245)
			(xy 117.596773 -399.119453) (xy 117.573005 -399.05636) (xy 117.556965 -398.990874) (xy 117.548886 -398.923938)
			(xy 117.548882 -398.856516) (xy 117.556955 -398.789579) (xy 117.572989 -398.724092) (xy 117.596751 -398.660996)
			(xy 117.627901 -398.601201) (xy 117.665988 -398.545568) (xy 117.687852 -398.519904) (xy 117.693636 -398.51275)
			(xy 117.700157 -398.495566) (xy 117.700552 -398.486376) (xy 117.700552 -397.99387) (xy 117.700145 -397.984683)
			(xy 117.693628 -397.967499) (xy 117.687852 -397.960342) (xy 117.665996 -397.93467) (xy 117.627904 -397.879037)
			(xy 117.59675 -397.819243) (xy 117.572983 -397.756147) (xy 117.556945 -397.690658) (xy 117.548867 -397.623719)
			(xy 117.548866 -397.556296) (xy 116.42064 -397.556296) (xy 116.423251 -397.56132) (xy 116.446929 -397.624321)
			(xy 116.462906 -397.6897) (xy 116.470954 -397.75652) (xy 116.470957 -397.823823) (xy 116.462916 -397.890644)
			(xy 116.446945 -397.956025) (xy 116.423275 -398.019028) (xy 116.392243 -398.07875) (xy 116.354295 -398.134335)
			(xy 116.332508 -398.159986) (xy 116.326693 -398.167118) (xy 116.320189 -398.184319) (xy 116.319808 -398.193514)
			(xy 116.319808 -398.351502) (xy 116.319269 -398.361654) (xy 116.311503 -398.380415) (xy 116.297152 -398.394778)
			(xy 116.278398 -398.402561) (xy 116.268246 -398.403064) (xy 115.551966 -398.403064) (xy 115.541806 -398.402595)
			(xy 115.523037 -398.394809) (xy 115.508673 -398.380436) (xy 115.500899 -398.361662) (xy 115.500404 -398.351502)
			(xy 115.500404 -398.193514) (xy 115.499986 -398.184328) (xy 115.493478 -398.167143) (xy 115.487704 -398.159986)
			(xy 115.46588 -398.134364) (xy 115.427935 -398.078772) (xy 115.396905 -398.019044) (xy 115.373236 -397.956036)
			(xy 115.357267 -397.89065) (xy 115.349226 -397.823825) (xy 92.220595 -397.823825) (xy 92.192138 -397.878594)
			(xy 92.154191 -397.934181) (xy 92.132404 -397.959834) (xy 92.126611 -397.966982) (xy 92.120094 -397.98417)
			(xy 92.119704 -397.993362) (xy 92.119704 -398.486884) (xy 92.120121 -398.49607) (xy 92.12663 -398.513255)
			(xy 92.132404 -398.520412) (xy 92.154226 -398.546036) (xy 92.192171 -398.601627) (xy 92.2232 -398.661355)
			(xy 92.246869 -398.724363) (xy 92.262838 -398.789748) (xy 92.270879 -398.856574) (xy 92.270875 -398.923881)
			(xy 92.262828 -398.990705) (xy 92.246853 -399.056089) (xy 92.223178 -399.119094) (xy 92.192143 -399.178819)
			(xy 92.154193 -399.234407) (xy 92.132404 -399.26006) (xy 92.1266 -399.2672) (xy 92.12009 -399.284394)
			(xy 92.119704 -399.293588) (xy 92.119704 -399.451576) (xy 92.119259 -399.461728) (xy 92.111472 -399.480479)
			(xy 92.097082 -399.494803) (xy 92.078296 -399.502505) (xy 92.068142 -399.502884) (xy 91.351862 -399.502884)
			(xy 91.341736 -399.502405) (xy 91.323018 -399.494669) (xy 91.308664 -399.480381) (xy 91.300842 -399.4617)
			(xy 91.3003 -399.451576) (xy 91.3003 -399.293588) (xy 91.299895 -399.2844) (xy 91.293378 -399.267216)
			(xy 91.2876 -399.26006) (xy 91.265849 -399.234378) (xy 91.227901 -399.178795) (xy 91.196869 -399.119075)
			(xy 91.173196 -399.056075) (xy 91.157221 -398.990697) (xy 91.149175 -398.923878) (xy 91.149172 -398.856576)
			(xy 91.157212 -398.789757) (xy 91.17318 -398.724377) (xy 91.196847 -398.661374) (xy 91.227874 -398.601651)
			(xy 91.265816 -398.546065) (xy 91.2876 -398.520412) (xy 91.293416 -398.513281) (xy 91.299919 -398.49608)
			(xy 91.3003 -398.486884) (xy 91.3003 -397.993362) (xy 91.299908 -397.984173) (xy 91.293382 -397.966989)
			(xy 91.2876 -397.959834) (xy 91.265823 -397.934173) (xy 91.227877 -397.878587) (xy 91.196845 -397.818864)
			(xy 91.173174 -397.755861) (xy 91.157201 -397.69048) (xy 91.149157 -397.623659) (xy 91.149156 -397.556356)
			(xy 90.020411 -397.556356) (xy 90.022992 -397.561322) (xy 90.046667 -397.624323) (xy 90.062643 -397.689701)
			(xy 90.07069 -397.75652) (xy 90.070693 -397.823822) (xy 90.062653 -397.890643) (xy 90.046684 -397.956023)
			(xy 90.023015 -398.019026) (xy 89.991986 -398.078748) (xy 89.954041 -398.134334) (xy 89.932256 -398.159986)
			(xy 89.926435 -398.167114) (xy 89.919936 -398.184318) (xy 89.919556 -398.193514) (xy 89.919556 -398.351502)
			(xy 89.919138 -398.361674) (xy 89.911351 -398.38047) (xy 89.896964 -398.394855) (xy 89.878167 -398.402639)
			(xy 89.867994 -398.403064) (xy 89.151714 -398.403064) (xy 89.141544 -398.402625) (xy 89.122749 -398.394845)
			(xy 89.108364 -398.380464) (xy 89.100578 -398.361672) (xy 89.100152 -398.351502) (xy 89.100152 -398.193514)
			(xy 89.099724 -398.184329) (xy 89.093221 -398.167145) (xy 89.087452 -398.159986) (xy 89.065626 -398.134365)
			(xy 89.027678 -398.078774) (xy 88.996645 -398.019047) (xy 88.972974 -397.956038) (xy 88.957004 -397.890652)
			(xy 88.948962 -397.823826) (xy 87.820827 -397.823826) (xy 87.792062 -397.879042) (xy 87.753972 -397.934677)
			(xy 87.732108 -397.960342) (xy 87.726312 -397.967488) (xy 87.719797 -397.984678) (xy 87.719408 -397.99387)
			(xy 87.719408 -398.486376) (xy 87.719828 -398.495562) (xy 87.726335 -398.512747) (xy 87.732108 -398.519904)
			(xy 87.754007 -398.54554) (xy 87.792094 -398.601179) (xy 87.823243 -398.660979) (xy 87.847005 -398.72408)
			(xy 87.863037 -398.789573) (xy 87.87111 -398.856514) (xy 87.871107 -398.92394) (xy 87.863028 -398.990881)
			(xy 87.846989 -399.056372) (xy 87.823221 -399.11947) (xy 87.792066 -399.179267) (xy 87.753974 -399.234903)
			(xy 87.732108 -399.260568) (xy 87.726301 -399.267706) (xy 87.719792 -399.284902) (xy 87.719408 -399.294096)
			(xy 87.719408 -399.451576) (xy 87.718965 -399.461696) (xy 87.711226 -399.480398) (xy 87.696918 -399.494712)
			(xy 87.67822 -399.50246) (xy 87.6681 -399.502884) (xy 86.95182 -399.502884) (xy 86.941697 -399.502467)
			(xy 86.922991 -399.494723) (xy 86.908675 -399.480406) (xy 86.900932 -399.461699) (xy 86.900512 -399.451576)
			(xy 86.900512 -399.294096) (xy 86.900101 -399.284909) (xy 86.893587 -399.267725) (xy 86.887812 -399.260568)
			(xy 86.865983 -399.234874) (xy 86.827892 -399.179244) (xy 86.796739 -399.119452) (xy 86.772973 -399.056358)
			(xy 86.756934 -398.990873) (xy 86.748855 -398.923938) (xy 86.748852 -398.856516) (xy 86.756925 -398.78958)
			(xy 86.772957 -398.724093) (xy 86.796717 -398.660998) (xy 86.827865 -398.601203) (xy 86.86595 -398.545569)
			(xy 86.887812 -398.519904) (xy 86.893591 -398.512746) (xy 86.900116 -398.495565) (xy 86.900512 -398.486376)
			(xy 86.900512 -397.99387) (xy 86.900114 -397.984682) (xy 86.893592 -397.967497) (xy 86.887812 -397.960342)
			(xy 86.865957 -397.934669) (xy 86.827868 -397.879036) (xy 86.796716 -397.819241) (xy 86.772951 -397.756145)
			(xy 86.756914 -397.690657) (xy 86.748837 -397.623719) (xy 86.748836 -397.556296) (xy 85.620612 -397.556296)
			(xy 85.623035 -397.560946) (xy 85.646803 -397.624039) (xy 85.662842 -397.689525) (xy 85.670922 -397.756461)
			(xy 85.670925 -397.823882) (xy 85.662853 -397.890819) (xy 85.64682 -397.956306) (xy 85.623058 -398.019402)
			(xy 85.59191 -398.079196) (xy 85.553823 -398.134829) (xy 85.53196 -398.160494) (xy 85.526178 -398.16765)
			(xy 85.519656 -398.184832) (xy 85.51926 -398.194022) (xy 85.51926 -398.351502) (xy 85.518775 -398.361629)
			(xy 85.511047 -398.38035) (xy 85.49676 -398.394706) (xy 85.478076 -398.402525) (xy 85.467952 -398.403064)
			(xy 84.751672 -398.403064) (xy 84.741512 -398.402701) (xy 84.722752 -398.394889) (xy 84.708428 -398.380474)
			(xy 84.700736 -398.361665) (xy 84.700364 -398.351502) (xy 84.700364 -398.194022) (xy 84.699929 -398.184838)
			(xy 84.693431 -398.167654) (xy 84.687664 -398.160494) (xy 84.665764 -398.134859) (xy 84.627679 -398.079219)
			(xy 84.596532 -398.019419) (xy 84.572771 -397.956318) (xy 84.55674 -397.890825) (xy 84.548667 -397.823884)
			(xy 83.420495 -397.823884) (xy 83.392062 -397.878597) (xy 83.35411 -397.934182) (xy 83.33232 -397.959834)
			(xy 83.326529 -397.966983) (xy 83.32001 -397.984171) (xy 83.31962 -397.993362) (xy 83.31962 -398.486884)
			(xy 83.320033 -398.496071) (xy 83.326544 -398.513256) (xy 83.33232 -398.520412) (xy 83.354144 -398.546035)
			(xy 83.392095 -398.601624) (xy 83.423129 -398.661352) (xy 83.446801 -398.72436) (xy 83.462773 -398.789746)
			(xy 83.470815 -398.856573) (xy 83.470812 -398.923881) (xy 83.462763 -398.990707) (xy 83.446785 -399.056092)
			(xy 83.423107 -399.119098) (xy 83.392067 -399.178822) (xy 83.354111 -399.234408) (xy 83.33232 -399.26006)
			(xy 83.326518 -399.267201) (xy 83.320006 -399.284395) (xy 83.31962 -399.293588) (xy 83.31962 -399.451576)
			(xy 83.319159 -399.461726) (xy 83.311375 -399.480474) (xy 83.296991 -399.494798) (xy 83.27821 -399.502502)
			(xy 83.268058 -399.502884) (xy 82.551778 -399.502884) (xy 82.541653 -399.502392) (xy 82.522936 -399.494662)
			(xy 82.508581 -399.480378) (xy 82.500758 -399.461699) (xy 82.500216 -399.451576) (xy 82.500216 -399.293588)
			(xy 82.499808 -399.284401) (xy 82.493293 -399.267216) (xy 82.487516 -399.26006) (xy 82.465765 -399.234378)
			(xy 82.427816 -399.178795) (xy 82.396783 -399.119076) (xy 82.373109 -399.056075) (xy 82.357134 -398.990697)
			(xy 82.349088 -398.923878) (xy 82.349084 -398.856576) (xy 82.357125 -398.789756) (xy 82.373093 -398.724377)
			(xy 82.396761 -398.661374) (xy 82.427788 -398.601651) (xy 82.465731 -398.546065) (xy 82.487516 -398.520412)
			(xy 82.493334 -398.513282) (xy 82.499835 -398.49608) (xy 82.500216 -398.486884) (xy 82.500216 -397.993362)
			(xy 82.499821 -397.984173) (xy 82.493296 -397.966989) (xy 82.487516 -397.959834) (xy 82.465739 -397.934174)
			(xy 82.427791 -397.878588) (xy 82.396759 -397.818865) (xy 82.373086 -397.755862) (xy 82.357113 -397.690481)
			(xy 82.349069 -397.623659) (xy 82.349068 -397.556356) (xy 81.220853 -397.556356) (xy 81.223245 -397.560947)
			(xy 81.247013 -397.62404) (xy 81.263052 -397.689525) (xy 81.271131 -397.756461) (xy 81.271135 -397.823882)
			(xy 81.263062 -397.890818) (xy 81.24703 -397.956306) (xy 81.223269 -398.019401) (xy 81.192121 -398.079196)
			(xy 81.154035 -398.134829) (xy 81.132172 -398.160494) (xy 81.126392 -398.167651) (xy 81.119868 -398.184832)
			(xy 81.119472 -398.194022) (xy 81.119472 -398.351502) (xy 81.118975 -398.361627) (xy 81.111249 -398.380346)
			(xy 81.096966 -398.394702) (xy 81.078287 -398.402523) (xy 81.068164 -398.403064) (xy 80.351884 -398.403064)
			(xy 80.341724 -398.402691) (xy 80.322965 -398.394883) (xy 80.30864 -398.380471) (xy 80.300948 -398.361664)
			(xy 80.300576 -398.351502) (xy 80.300576 -398.194022) (xy 80.300161 -398.184835) (xy 80.293651 -398.16765)
			(xy 80.287876 -398.160494) (xy 80.265976 -398.134859) (xy 80.22789 -398.07922) (xy 80.196742 -398.019419)
			(xy 80.172981 -397.956318) (xy 80.156949 -397.890826) (xy 80.148876 -397.823885) (xy 79.02071 -397.823885)
			(xy 78.991976 -397.879041) (xy 78.953888 -397.934676) (xy 78.932024 -397.960342) (xy 78.92623 -397.967489)
			(xy 78.919713 -397.984678) (xy 78.919324 -397.99387) (xy 78.919324 -398.486376) (xy 78.91974 -398.495563)
			(xy 78.926249 -398.512747) (xy 78.932024 -398.519904) (xy 78.953922 -398.54554) (xy 78.992009 -398.60118)
			(xy 79.023156 -398.66098) (xy 79.046917 -398.724081) (xy 79.06295 -398.789573) (xy 79.071022 -398.856514)
			(xy 79.071019 -398.92394) (xy 79.06294 -398.99088) (xy 79.046901 -399.056371) (xy 79.023134 -399.119469)
			(xy 78.991981 -399.179267) (xy 78.953889 -399.234902) (xy 78.932024 -399.260568) (xy 78.926219 -399.267707)
			(xy 78.919709 -399.284902) (xy 78.919324 -399.294096) (xy 78.919324 -399.451576) (xy 78.918865 -399.461694)
			(xy 78.911129 -399.480393) (xy 78.896826 -399.494707) (xy 78.878134 -399.502457) (xy 78.868016 -399.502884)
			(xy 78.151736 -399.502884) (xy 78.141614 -399.502454) (xy 78.122908 -399.494715) (xy 78.108592 -399.480402)
			(xy 78.100848 -399.461698) (xy 78.100428 -399.451576) (xy 78.100428 -399.294096) (xy 78.100014 -399.284909)
			(xy 78.093502 -399.267725) (xy 78.087728 -399.260568) (xy 78.065898 -399.234874) (xy 78.027807 -399.179244)
			(xy 77.996653 -399.119452) (xy 77.972886 -399.056359) (xy 77.956847 -398.990873) (xy 77.948768 -398.923938)
			(xy 77.948764 -398.856516) (xy 77.956837 -398.78958) (xy 77.972869 -398.724093) (xy 77.996631 -398.660997)
			(xy 78.027779 -398.601202) (xy 78.065865 -398.545569) (xy 78.087728 -398.519904) (xy 78.093509 -398.512748)
			(xy 78.100032 -398.495566) (xy 78.100428 -398.486376) (xy 78.100428 -397.99387) (xy 78.100026 -397.984682)
			(xy 78.093506 -397.967498) (xy 78.087728 -397.960342) (xy 78.065873 -397.934669) (xy 78.027782 -397.879036)
			(xy 77.996629 -397.819241) (xy 77.972863 -397.756146) (xy 77.956826 -397.690657) (xy 77.948749 -397.623719)
			(xy 77.948748 -397.556296) (xy 76.820503 -397.556296) (xy 76.823115 -397.561323) (xy 76.846789 -397.624324)
			(xy 76.862764 -397.689702) (xy 76.870811 -397.756521) (xy 76.870814 -397.823822) (xy 76.862774 -397.890642)
			(xy 76.846806 -397.956022) (xy 76.823139 -398.019024) (xy 76.792111 -398.078747) (xy 76.754168 -398.134333)
			(xy 76.732384 -398.159986) (xy 76.726567 -398.167116) (xy 76.720065 -398.184318) (xy 76.719684 -398.193514)
			(xy 76.719684 -398.351502) (xy 76.719169 -398.361657) (xy 76.711398 -398.380422) (xy 76.697039 -398.394787)
			(xy 76.678277 -398.402565) (xy 76.668122 -398.403064) (xy 75.951842 -398.403064) (xy 75.941673 -398.402602)
			(xy 75.92288 -398.394831) (xy 75.908494 -398.380457) (xy 75.900707 -398.36167) (xy 75.90028 -398.351502)
			(xy 75.90028 -398.193514) (xy 75.899868 -398.184327) (xy 75.893356 -398.167142) (xy 75.88758 -398.159986)
			(xy 75.865754 -398.134365) (xy 75.827803 -398.078775) (xy 75.79677 -398.019048) (xy 75.773097 -397.956039)
			(xy 75.757126 -397.890653) (xy 75.749084 -397.823826) (xy 74.620438 -397.823826) (xy 74.591977 -397.878596)
			(xy 74.554025 -397.934182) (xy 74.532236 -397.959834) (xy 74.526435 -397.966975) (xy 74.519925 -397.984169)
			(xy 74.519536 -397.993362) (xy 74.519536 -398.486884) (xy 74.519968 -398.496069) (xy 74.526468 -398.513252)
			(xy 74.532236 -398.520412) (xy 74.55406 -398.546035) (xy 74.592009 -398.601625) (xy 74.623043 -398.661352)
			(xy 74.646714 -398.724361) (xy 74.662686 -398.789747) (xy 74.670727 -398.856573) (xy 74.670724 -398.923881)
			(xy 74.662676 -398.990707) (xy 74.646698 -399.056091) (xy 74.623021 -399.119097) (xy 74.591982 -399.178822)
			(xy 74.554027 -399.234408) (xy 74.532236 -399.26006) (xy 74.526424 -399.267194) (xy 74.51992 -399.284393)
			(xy 74.519536 -399.293588) (xy 74.519536 -399.451576) (xy 74.51906 -399.461724) (xy 74.511279 -399.480469)
			(xy 74.496899 -399.494792) (xy 74.478124 -399.502499) (xy 74.467974 -399.502884) (xy 73.751694 -399.502884)
			(xy 73.74157 -399.502379) (xy 73.722853 -399.494654) (xy 73.708498 -399.480373) (xy 73.700675 -399.461697)
			(xy 73.700132 -399.451576) (xy 73.700132 -399.293588) (xy 73.699721 -399.284401) (xy 73.693207 -399.267217)
			(xy 73.687432 -399.26006) (xy 73.66568 -399.234378) (xy 73.627731 -399.178796) (xy 73.596696 -399.119077)
			(xy 73.573022 -399.056076) (xy 73.557047 -398.990697) (xy 73.549 -398.923878) (xy 73.548996 -398.856576)
			(xy 73.557037 -398.789756) (xy 73.573006 -398.724376) (xy 73.596674 -398.661373) (xy 73.627703 -398.60165)
			(xy 73.665647 -398.546064) (xy 73.687432 -398.520412) (xy 73.693253 -398.513284) (xy 73.699752 -398.49608)
			(xy 73.700132 -398.486884) (xy 73.700132 -397.993362) (xy 73.699733 -397.984174) (xy 73.693211 -397.96699)
			(xy 73.687432 -397.959834) (xy 73.665654 -397.934174) (xy 73.627705 -397.878588) (xy 73.596672 -397.818866)
			(xy 73.572999 -397.755862) (xy 73.557026 -397.690481) (xy 73.548981 -397.62366) (xy 73.54898 -397.556355)
			(xy 72.420766 -397.556355) (xy 72.423159 -397.560948) (xy 72.446926 -397.62404) (xy 72.462964 -397.689526)
			(xy 72.471043 -397.756461) (xy 72.471047 -397.823882) (xy 72.462974 -397.890818) (xy 72.446942 -397.956305)
			(xy 72.423182 -398.0194) (xy 72.392035 -398.079195) (xy 72.35395 -398.134829) (xy 72.332088 -398.160494)
			(xy 72.32631 -398.167652) (xy 72.319785 -398.184833) (xy 72.319388 -398.194022) (xy 72.319388 -398.351502)
			(xy 72.318876 -398.361625) (xy 72.311153 -398.380341) (xy 72.296875 -398.394696) (xy 72.278201 -398.40252)
			(xy 72.26808 -398.403064) (xy 71.5518 -398.403064) (xy 71.541641 -398.402678) (xy 71.522882 -398.394875)
			(xy 71.508557 -398.380467) (xy 71.500864 -398.361663) (xy 71.500492 -398.351502) (xy 71.500492 -398.194022)
			(xy 71.500073 -398.184836) (xy 71.493566 -398.167651) (xy 71.487792 -398.160494) (xy 71.465891 -398.134859)
			(xy 71.427804 -398.07922) (xy 71.396655 -398.01942) (xy 71.372894 -397.956319) (xy 71.356861 -397.890826)
			(xy 71.348788 -397.823885) (xy 66.525648 -397.823885) (xy 66.525648 -401.723796) (xy 71.3488 -401.723796)
			(xy 71.348802 -401.656371) (xy 71.35688 -401.589431) (xy 71.372917 -401.523941) (xy 71.396683 -401.460843)
			(xy 71.427836 -401.401046) (xy 71.465927 -401.345411) (xy 71.487792 -401.319746) (xy 71.493593 -401.312604)
			(xy 71.500105 -401.295411) (xy 71.500492 -401.286218) (xy 71.500492 -400.793966) (xy 71.5001 -400.784777)
			(xy 71.493574 -400.767592) (xy 71.487792 -400.760438) (xy 71.465934 -400.734768) (xy 71.427846 -400.679134)
			(xy 71.396695 -400.619338) (xy 71.372931 -400.556242) (xy 71.356896 -400.490754) (xy 71.348819 -400.423816)
			(xy 71.348819 -400.356393) (xy 71.356894 -400.289455) (xy 71.372928 -400.223967) (xy 71.396692 -400.16087)
			(xy 71.427841 -400.101074) (xy 71.465929 -400.045439) (xy 71.487792 -400.019774) (xy 71.493581 -400.012623)
			(xy 71.500101 -399.995437) (xy 71.500492 -399.986246) (xy 71.500492 -399.828766) (xy 71.500997 -399.818643)
			(xy 71.508727 -399.79993) (xy 71.523007 -399.785577) (xy 71.54168 -399.77775) (xy 71.5518 -399.777204)
			(xy 72.26808 -399.777204) (xy 72.278233 -399.777638) (xy 72.296986 -399.785428) (xy 72.31131 -399.799821)
			(xy 72.31901 -399.818611) (xy 72.319388 -399.828766) (xy 72.319388 -399.986246) (xy 72.319827 -399.99543)
			(xy 72.326321 -400.012615) (xy 72.332088 -400.019774) (xy 72.353958 -400.045434) (xy 72.392048 -400.101069)
			(xy 72.423199 -400.160866) (xy 72.446963 -400.223963) (xy 72.462999 -400.289453) (xy 72.471074 -400.356392)
			(xy 72.471074 -400.423817) (xy 72.462997 -400.490756) (xy 72.44696 -400.556245) (xy 72.423195 -400.619342)
			(xy 72.392043 -400.679139) (xy 72.353953 -400.734773) (xy 72.332088 -400.760438) (xy 72.326291 -400.767583)
			(xy 72.319777 -400.784774) (xy 72.319388 -400.793966) (xy 72.319388 -401.286218) (xy 72.319792 -401.295406)
			(xy 72.32631 -401.31259) (xy 72.332088 -401.319746) (xy 72.353931 -401.345429) (xy 72.392021 -401.401061)
			(xy 72.423173 -401.460854) (xy 72.446939 -401.523949) (xy 72.462977 -401.589436) (xy 72.471054 -401.656372)
			(xy 72.471056 -401.723795) (xy 72.462982 -401.790732) (xy 72.446949 -401.85622) (xy 72.423187 -401.919316)
			(xy 72.392038 -401.979111) (xy 72.353951 -402.034745) (xy 72.332088 -402.06041) (xy 72.326303 -402.067564)
			(xy 72.319782 -402.084748) (xy 72.319388 -402.093938) (xy 72.319388 -402.251418) (xy 72.318889 -402.261542)
			(xy 72.311161 -402.280259) (xy 72.296879 -402.294614) (xy 72.278202 -402.302437) (xy 72.26808 -402.30298)
			(xy 71.5518 -402.30298) (xy 71.541643 -402.302578) (xy 71.522887 -402.294779) (xy 71.508563 -402.280376)
			(xy 71.500867 -402.261577) (xy 71.500492 -402.251418) (xy 71.500492 -402.093938) (xy 71.500065 -402.084753)
			(xy 71.493563 -402.067568) (xy 71.487792 -402.06041) (xy 71.465907 -402.034762) (xy 71.427819 -401.979125)
			(xy 71.39667 -401.919326) (xy 71.372907 -401.856227) (xy 71.356874 -401.790736) (xy 71.3488 -401.723796)
			(xy 66.525648 -401.723796) (xy 66.525648 -402.823818) (xy 73.54894 -402.823818) (xy 73.548944 -402.75651)
			(xy 73.556993 -402.689684) (xy 73.572971 -402.624299) (xy 73.596649 -402.561293) (xy 73.627687 -402.501568)
			(xy 73.665642 -402.44598) (xy 73.687432 -402.420328) (xy 73.693246 -402.413195) (xy 73.699749 -402.395995)
			(xy 73.700132 -402.3868) (xy 73.700132 -401.893532) (xy 73.699699 -401.884347) (xy 73.6932 -401.867163)
			(xy 73.687432 -401.860004) (xy 73.665625 -401.834368) (xy 73.627677 -401.778779) (xy 73.596645 -401.719053)
			(xy 73.572974 -401.656047) (xy 73.557002 -401.590662) (xy 73.54896 -401.523838) (xy 73.548962 -401.456532)
			(xy 73.557008 -401.389708) (xy 73.572982 -401.324325) (xy 73.596657 -401.261319) (xy 73.627692 -401.201595)
			(xy 73.665643 -401.146008) (xy 73.687432 -401.120356) (xy 73.693234 -401.113215) (xy 73.699745 -401.096021)
			(xy 73.700132 -401.086828) (xy 73.700132 -400.92884) (xy 73.700555 -400.918685) (xy 73.708343 -400.899927)
			(xy 73.722741 -400.885601) (xy 73.741537 -400.877906) (xy 73.751694 -400.877532) (xy 74.467974 -400.877532)
			(xy 74.478098 -400.878047) (xy 74.496817 -400.885765) (xy 74.511174 -400.900043) (xy 74.518996 -400.918719)
			(xy 74.519536 -400.92884) (xy 74.519536 -401.086828) (xy 74.519947 -401.096015) (xy 74.526462 -401.113198)
			(xy 74.532236 -401.120356) (xy 74.554005 -401.146024) (xy 74.591956 -401.201608) (xy 74.622991 -401.261329)
			(xy 74.646666 -401.324331) (xy 74.662641 -401.389712) (xy 74.670687 -401.456533) (xy 74.670689 -401.523837)
			(xy 74.662647 -401.590659) (xy 74.646675 -401.65604) (xy 74.623004 -401.719044) (xy 74.620565 -401.723737)
			(xy 75.749095 -401.723737) (xy 75.749097 -401.65643) (xy 75.757144 -401.589605) (xy 75.773121 -401.524221)
			(xy 75.796798 -401.461215) (xy 75.827836 -401.401492) (xy 75.86579 -401.345906) (xy 75.88758 -401.320254)
			(xy 75.893376 -401.313108) (xy 75.899892 -401.295918) (xy 75.90028 -401.286726) (xy 75.90028 -400.793458)
			(xy 75.899895 -400.784268) (xy 75.893364 -400.767084) (xy 75.88758 -400.75993) (xy 75.865797 -400.734274)
			(xy 75.827845 -400.678689) (xy 75.79681 -400.618966) (xy 75.773135 -400.555962) (xy 75.75716 -400.49058)
			(xy 75.749115 -400.423757) (xy 75.749114 -400.356452) (xy 75.757158 -400.289629) (xy 75.773132 -400.224247)
			(xy 75.796806 -400.161242) (xy 75.827841 -400.101519) (xy 75.865791 -400.045934) (xy 75.88758 -400.020282)
			(xy 75.893364 -400.013128) (xy 75.899887 -399.995944) (xy 75.90028 -399.986754) (xy 75.90028 -399.828766)
			(xy 75.900637 -399.818587) (xy 75.908441 -399.799783) (xy 75.922847 -399.785398) (xy 75.941662 -399.777622)
			(xy 75.951842 -399.777204) (xy 76.668122 -399.777204) (xy 76.678277 -399.777714) (xy 76.69704 -399.78549)
			(xy 76.711404 -399.79985) (xy 76.719183 -399.818611) (xy 76.719684 -399.828766) (xy 76.719684 -399.986754)
			(xy 76.72012 -399.995938) (xy 76.726616 -400.013123) (xy 76.732384 -400.020282) (xy 76.754177 -400.04593)
			(xy 76.792124 -400.101517) (xy 76.823156 -400.161242) (xy 76.846827 -400.224247) (xy 76.862799 -400.289629)
			(xy 76.870842 -400.356452) (xy 76.870842 -400.423757) (xy 76.862798 -400.49058) (xy 76.846825 -400.555962)
			(xy 76.823152 -400.618967) (xy 76.792119 -400.678691) (xy 76.754171 -400.734278) (xy 76.732384 -400.75993)
			(xy 76.72659 -400.767077) (xy 76.720074 -400.784266) (xy 76.719684 -400.793458) (xy 76.719684 -401.286726)
			(xy 76.720085 -401.295914) (xy 76.726605 -401.313098) (xy 76.732384 -401.320254) (xy 76.754149 -401.345924)
			(xy 76.792097 -401.401509) (xy 76.82313 -401.46123) (xy 76.846803 -401.524232) (xy 76.862777 -401.589612)
			(xy 76.870823 -401.656432) (xy 76.870825 -401.723735) (xy 76.862783 -401.790556) (xy 76.846813 -401.855936)
			(xy 76.823144 -401.91894) (xy 76.792114 -401.978663) (xy 76.75417 -402.03425) (xy 76.732384 -402.059902)
			(xy 76.726602 -402.067058) (xy 76.720079 -402.08424) (xy 76.719684 -402.09343) (xy 76.719684 -402.251418)
			(xy 76.719182 -402.261574) (xy 76.711406 -402.28034) (xy 76.697043 -402.294704) (xy 76.678278 -402.302481)
			(xy 76.668122 -402.30298) (xy 75.951842 -402.30298) (xy 75.941675 -402.302502) (xy 75.922885 -402.294734)
			(xy 75.908499 -402.280365) (xy 75.90071 -402.261584) (xy 75.90028 -402.251418) (xy 75.90028 -402.09343)
			(xy 75.89986 -402.084244) (xy 75.893354 -402.067059) (xy 75.88758 -402.059902) (xy 75.865769 -402.034268)
			(xy 75.827819 -401.97868) (xy 75.796784 -401.918954) (xy 75.773111 -401.855947) (xy 75.757138 -401.790562)
			(xy 75.749095 -401.723737) (xy 74.620565 -401.723737) (xy 74.591971 -401.778767) (xy 74.554023 -401.834352)
			(xy 74.532236 -401.860004) (xy 74.526447 -401.867155) (xy 74.51993 -401.884341) (xy 74.519536 -401.893532)
			(xy 74.519536 -402.3868) (xy 74.519961 -402.395985) (xy 74.526466 -402.413169) (xy 74.532236 -402.420328)
			(xy 74.553977 -402.446019) (xy 74.591929 -402.501599) (xy 74.622966 -402.561317) (xy 74.646642 -402.624317)
			(xy 74.662619 -402.689694) (xy 74.670668 -402.756513) (xy 74.670672 -402.823815) (xy 74.670664 -402.823878)
			(xy 77.948708 -402.823878) (xy 77.948713 -402.75645) (xy 77.956794 -402.689508) (xy 77.972835 -402.624016)
			(xy 77.996606 -402.560917) (xy 78.027764 -402.501119) (xy 78.06586 -402.445485) (xy 78.087728 -402.41982)
			(xy 78.093545 -402.412689) (xy 78.100047 -402.395488) (xy 78.100428 -402.386292) (xy 78.100428 -401.89404)
			(xy 78.099992 -401.884856) (xy 78.093496 -401.867671) (xy 78.087728 -401.860512) (xy 78.065843 -401.834863)
			(xy 78.027753 -401.779227) (xy 77.996602 -401.719429) (xy 77.972838 -401.65633) (xy 77.956803 -401.590838)
			(xy 77.948728 -401.523898) (xy 77.94873 -401.456472) (xy 77.956808 -401.389532) (xy 77.972847 -401.324041)
			(xy 77.996614 -401.260944) (xy 78.027769 -401.201147) (xy 78.065862 -401.145513) (xy 78.087728 -401.119848)
			(xy 78.093533 -401.112709) (xy 78.100042 -401.095514) (xy 78.100428 -401.08632) (xy 78.100428 -400.92884)
			(xy 78.10085 -400.918717) (xy 78.10859 -400.900009) (xy 78.122905 -400.885692) (xy 78.141613 -400.87795)
			(xy 78.151736 -400.877532) (xy 78.868016 -400.877532) (xy 78.878144 -400.877903) (xy 78.896854 -400.885663)
			(xy 78.911169 -400.899993) (xy 78.918908 -400.918712) (xy 78.919324 -400.92884) (xy 78.919324 -401.08632)
			(xy 78.919719 -401.095509) (xy 78.926243 -401.112693) (xy 78.932024 -401.119848) (xy 78.953867 -401.14553)
			(xy 78.991955 -401.201163) (xy 79.023105 -401.260957) (xy 79.04687 -401.324051) (xy 79.062906 -401.389538)
			(xy 79.070983 -401.456474) (xy 79.070985 -401.523896) (xy 79.062911 -401.590832) (xy 79.046879 -401.65632)
			(xy 79.023118 -401.719416) (xy 79.020837 -401.723796) (xy 80.148888 -401.723796) (xy 80.14889 -401.656371)
			(xy 80.156967 -401.589432) (xy 80.173004 -401.523942) (xy 80.19677 -401.460844) (xy 80.227922 -401.401047)
			(xy 80.266012 -401.345412) (xy 80.287876 -401.319746) (xy 80.293675 -401.312603) (xy 80.300189 -401.295411)
			(xy 80.300576 -401.286218) (xy 80.300576 -400.793966) (xy 80.300187 -400.784776) (xy 80.293659 -400.767592)
			(xy 80.287876 -400.760438) (xy 80.266019 -400.734767) (xy 80.227931 -400.679133) (xy 80.196782 -400.619337)
			(xy 80.173018 -400.556241) (xy 80.156983 -400.490753) (xy 80.148907 -400.423816) (xy 80.148907 -400.356393)
			(xy 80.156982 -400.289456) (xy 80.173016 -400.223967) (xy 80.196778 -400.160871) (xy 80.227927 -400.101075)
			(xy 80.266013 -400.04544) (xy 80.287876 -400.019774) (xy 80.293663 -400.012622) (xy 80.300184 -399.995437)
			(xy 80.300576 -399.986246) (xy 80.300576 -399.828766) (xy 80.301 -399.818633) (xy 80.308745 -399.799904)
			(xy 80.323051 -399.785548) (xy 80.341753 -399.777736) (xy 80.351884 -399.777204) (xy 81.068164 -399.777204)
			(xy 81.078316 -399.777651) (xy 81.097069 -399.785436) (xy 81.111393 -399.799825) (xy 81.119094 -399.818612)
			(xy 81.119472 -399.828766) (xy 81.119472 -399.986246) (xy 81.119914 -399.99543) (xy 81.126406 -400.012614)
			(xy 81.132172 -400.019774) (xy 81.154043 -400.045434) (xy 81.192133 -400.101069) (xy 81.223285 -400.160865)
			(xy 81.24705 -400.223963) (xy 81.263086 -400.289453) (xy 81.271162 -400.356392) (xy 81.271161 -400.423817)
			(xy 81.263085 -400.490756) (xy 81.247048 -400.556246) (xy 81.223282 -400.619343) (xy 81.192129 -400.679139)
			(xy 81.154037 -400.734773) (xy 81.132172 -400.760438) (xy 81.126373 -400.767581) (xy 81.11986 -400.784773)
			(xy 81.119472 -400.793966) (xy 81.119472 -401.286218) (xy 81.11988 -401.295405) (xy 81.126396 -401.312589)
			(xy 81.132172 -401.319746) (xy 81.154015 -401.345429) (xy 81.192107 -401.40106) (xy 81.22326 -401.460854)
			(xy 81.247026 -401.523948) (xy 81.263064 -401.589435) (xy 81.271142 -401.656372) (xy 81.271144 -401.723795)
			(xy 81.26307 -401.790732) (xy 81.247036 -401.85622) (xy 81.223273 -401.919316) (xy 81.192124 -401.979112)
			(xy 81.154036 -402.034745) (xy 81.132172 -402.06041) (xy 81.126385 -402.067562) (xy 81.119865 -402.084747)
			(xy 81.119472 -402.093938) (xy 81.119472 -402.251418) (xy 81.118989 -402.261544) (xy 81.111257 -402.280264)
			(xy 81.09697 -402.294619) (xy 81.078288 -402.30244) (xy 81.068164 -402.30298) (xy 80.351884 -402.30298)
			(xy 80.341726 -402.302591) (xy 80.32297 -402.294787) (xy 80.308646 -402.28038) (xy 80.30095 -402.261578)
			(xy 80.300576 -402.251418) (xy 80.300576 -402.093938) (xy 80.300153 -402.084752) (xy 80.293649 -402.067567)
			(xy 80.287876 -402.06041) (xy 80.265991 -402.034762) (xy 80.227905 -401.979125) (xy 80.196756 -401.919326)
			(xy 80.172994 -401.856227) (xy 80.156961 -401.790736) (xy 80.148888 -401.723796) (xy 79.020837 -401.723796)
			(xy 78.991971 -401.779212) (xy 78.953886 -401.834846) (xy 78.932024 -401.860512) (xy 78.926243 -401.867668)
			(xy 78.919718 -401.88485) (xy 78.919324 -401.89404) (xy 78.919324 -402.386292) (xy 78.919733 -402.395479)
			(xy 78.926247 -402.412664) (xy 78.932024 -402.41982) (xy 78.95384 -402.445525) (xy 78.991929 -402.501154)
			(xy 79.02308 -402.560945) (xy 79.046846 -402.624037) (xy 79.062884 -402.689521) (xy 79.070963 -402.756454)
			(xy 79.070968 -402.823818) (xy 82.349028 -402.823818) (xy 82.349032 -402.75651) (xy 82.357081 -402.689684)
			(xy 82.373058 -402.6243) (xy 82.396735 -402.561293) (xy 82.427773 -402.501568) (xy 82.465726 -402.44598)
			(xy 82.487516 -402.420328) (xy 82.493327 -402.413193) (xy 82.499833 -402.395995) (xy 82.500216 -402.3868)
			(xy 82.500216 -401.893532) (xy 82.499787 -401.884347) (xy 82.493286 -401.867163) (xy 82.487516 -401.860004)
			(xy 82.465709 -401.834368) (xy 82.427763 -401.778778) (xy 82.396731 -401.719052) (xy 82.373061 -401.656046)
			(xy 82.35709 -401.590662) (xy 82.349048 -401.523838) (xy 82.34905 -401.456532) (xy 82.357095 -401.389708)
			(xy 82.37307 -401.324325) (xy 82.396744 -401.26132) (xy 82.427778 -401.201596) (xy 82.465728 -401.146008)
			(xy 82.487516 -401.120356) (xy 82.493316 -401.113213) (xy 82.499828 -401.096021) (xy 82.500216 -401.086828)
			(xy 82.500216 -400.92884) (xy 82.500655 -400.918687) (xy 82.50844 -400.899932) (xy 82.522832 -400.885607)
			(xy 82.541623 -400.877908) (xy 82.551778 -400.877532) (xy 83.268058 -400.877532) (xy 83.278181 -400.878061)
			(xy 83.2969 -400.885773) (xy 83.311257 -400.900047) (xy 83.319079 -400.91872) (xy 83.31962 -400.92884)
			(xy 83.31962 -401.086828) (xy 83.320012 -401.096017) (xy 83.326538 -401.113202) (xy 83.33232 -401.120356)
			(xy 83.354089 -401.146024) (xy 83.392041 -401.201607) (xy 83.423078 -401.261328) (xy 83.446753 -401.324331)
			(xy 83.462729 -401.389711) (xy 83.470775 -401.456533) (xy 83.470777 -401.523837) (xy 83.462734 -401.590659)
			(xy 83.446762 -401.656041) (xy 83.42309 -401.719044) (xy 83.420621 -401.723796) (xy 84.548678 -401.723796)
			(xy 84.54868 -401.656371) (xy 84.556758 -401.589432) (xy 84.572795 -401.523942) (xy 84.59656 -401.460845)
			(xy 84.627711 -401.401047) (xy 84.6658 -401.345412) (xy 84.687664 -401.319746) (xy 84.693474 -401.312611)
			(xy 84.699979 -401.295412) (xy 84.700364 -401.286218) (xy 84.700364 -400.793966) (xy 84.699956 -400.784779)
			(xy 84.693439 -400.767595) (xy 84.687664 -400.760438) (xy 84.665807 -400.734767) (xy 84.627721 -400.679133)
			(xy 84.596572 -400.619337) (xy 84.572809 -400.556241) (xy 84.556774 -400.490753) (xy 84.548698 -400.423816)
			(xy 84.548698 -400.356393) (xy 84.556772 -400.289456) (xy 84.572806 -400.223968) (xy 84.596568 -400.160871)
			(xy 84.627716 -400.101075) (xy 84.665802 -400.04544) (xy 84.687664 -400.019774) (xy 84.693462 -400.01263)
			(xy 84.699974 -399.995438) (xy 84.700364 -399.986246) (xy 84.700364 -399.828766) (xy 84.700799 -399.818634)
			(xy 84.708543 -399.799908) (xy 84.722845 -399.785552) (xy 84.741542 -399.777738) (xy 84.751672 -399.777204)
			(xy 85.467952 -399.777204) (xy 85.478104 -399.777661) (xy 85.496856 -399.785442) (xy 85.511181 -399.799828)
			(xy 85.518881 -399.818613) (xy 85.51926 -399.828766) (xy 85.51926 -399.986246) (xy 85.519705 -399.995429)
			(xy 85.526196 -400.012613) (xy 85.53196 -400.019774) (xy 85.553831 -400.045434) (xy 85.591922 -400.101068)
			(xy 85.623075 -400.160865) (xy 85.646841 -400.223962) (xy 85.662877 -400.289453) (xy 85.670953 -400.356392)
			(xy 85.670952 -400.423817) (xy 85.662875 -400.490756) (xy 85.646838 -400.556246) (xy 85.623071 -400.619344)
			(xy 85.591918 -400.67914) (xy 85.553826 -400.734773) (xy 85.53196 -400.760438) (xy 85.52616 -400.76758)
			(xy 85.519648 -400.784773) (xy 85.51926 -400.793966) (xy 85.51926 -401.286218) (xy 85.51967 -401.295405)
			(xy 85.526185 -401.312589) (xy 85.53196 -401.319746) (xy 85.553804 -401.345428) (xy 85.591896 -401.40106)
			(xy 85.62305 -401.460853) (xy 85.646817 -401.523948) (xy 85.662855 -401.589435) (xy 85.670933 -401.656372)
			(xy 85.670935 -401.723795) (xy 85.662861 -401.790732) (xy 85.646827 -401.856221) (xy 85.623063 -401.919317)
			(xy 85.591913 -401.979112) (xy 85.553824 -402.034745) (xy 85.53196 -402.06041) (xy 85.526172 -402.067561)
			(xy 85.519653 -402.084747) (xy 85.51926 -402.093938) (xy 85.51926 -402.251418) (xy 85.518788 -402.261546)
			(xy 85.511055 -402.280268) (xy 85.496764 -402.294623) (xy 85.478078 -402.302442) (xy 85.467952 -402.30298)
			(xy 84.751672 -402.30298) (xy 84.741514 -402.302601) (xy 84.722757 -402.294792) (xy 84.708434 -402.280383)
			(xy 84.700738 -402.261579) (xy 84.700364 -402.251418) (xy 84.700364 -402.093938) (xy 84.699921 -402.084755)
			(xy 84.693429 -402.067571) (xy 84.687664 -402.06041) (xy 84.66578 -402.034762) (xy 84.627694 -401.979124)
			(xy 84.596546 -401.919325) (xy 84.572785 -401.856226) (xy 84.556752 -401.790735) (xy 84.548678 -401.723796)
			(xy 83.420621 -401.723796) (xy 83.392057 -401.778767) (xy 83.354108 -401.834352) (xy 83.33232 -401.860004)
			(xy 83.326542 -401.867162) (xy 83.320015 -401.884343) (xy 83.31962 -401.893532) (xy 83.31962 -402.3868)
			(xy 83.320026 -402.395988) (xy 83.326542 -402.413172) (xy 83.33232 -402.420328) (xy 83.354062 -402.446018)
			(xy 83.392015 -402.501598) (xy 83.423052 -402.561316) (xy 83.44673 -402.624316) (xy 83.462707 -402.689694)
			(xy 83.470756 -402.756513) (xy 83.47076 -402.823815) (xy 83.470752 -402.823878) (xy 86.748796 -402.823878)
			(xy 86.748801 -402.75645) (xy 86.756882 -402.689508) (xy 86.772922 -402.624016) (xy 86.796693 -402.560918)
			(xy 86.82785 -402.50112) (xy 86.865945 -402.445485) (xy 86.887812 -402.41982) (xy 86.893626 -402.412687)
			(xy 86.90013 -402.395487) (xy 86.900512 -402.386292) (xy 86.900512 -401.89404) (xy 86.90008 -401.884855)
			(xy 86.893581 -401.867671) (xy 86.887812 -401.860512) (xy 86.865928 -401.834863) (xy 86.827839 -401.779227)
			(xy 86.796689 -401.719428) (xy 86.772925 -401.656329) (xy 86.756891 -401.590838) (xy 86.748816 -401.523898)
			(xy 86.748818 -401.456472) (xy 86.756896 -401.389532) (xy 86.772934 -401.324042) (xy 86.796701 -401.260944)
			(xy 86.827855 -401.201148) (xy 86.865946 -401.145513) (xy 86.887812 -401.119848) (xy 86.893615 -401.112707)
			(xy 86.900125 -401.095513) (xy 86.900512 -401.08632) (xy 86.900512 -400.92884) (xy 86.900949 -400.918719)
			(xy 86.908686 -400.900014) (xy 86.922997 -400.885698) (xy 86.941699 -400.877953) (xy 86.95182 -400.877532)
			(xy 87.6681 -400.877532) (xy 87.678226 -400.877917) (xy 87.696936 -400.885671) (xy 87.711252 -400.899997)
			(xy 87.718991 -400.918713) (xy 87.719408 -400.92884) (xy 87.719408 -401.08632) (xy 87.719807 -401.095508)
			(xy 87.726328 -401.112693) (xy 87.732108 -401.119848) (xy 87.753952 -401.14553) (xy 87.792041 -401.201162)
			(xy 87.823192 -401.260956) (xy 87.846957 -401.324051) (xy 87.862994 -401.389538) (xy 87.871071 -401.456474)
			(xy 87.871073 -401.523896) (xy 87.862999 -401.590833) (xy 87.846966 -401.656321) (xy 87.823204 -401.719417)
			(xy 87.820954 -401.723737) (xy 115.349237 -401.723737) (xy 115.349239 -401.65643) (xy 115.357285 -401.589607)
			(xy 115.373259 -401.524224) (xy 115.396933 -401.461219) (xy 115.427967 -401.401494) (xy 115.465916 -401.345907)
			(xy 115.487704 -401.320254) (xy 115.493503 -401.313111) (xy 115.500016 -401.295919) (xy 115.500404 -401.286726)
			(xy 115.500404 -400.793458) (xy 115.500013 -400.784269) (xy 115.493486 -400.767085) (xy 115.487704 -400.75993)
			(xy 115.465923 -400.734273) (xy 115.427977 -400.678686) (xy 115.396945 -400.618963) (xy 115.373273 -400.555959)
			(xy 115.357301 -400.490578) (xy 115.349257 -400.423756) (xy 115.349256 -400.356453) (xy 115.357299 -400.289631)
			(xy 115.373271 -400.22425) (xy 115.396941 -400.161245) (xy 115.427972 -400.101522) (xy 115.465918 -400.045935)
			(xy 115.487704 -400.020282) (xy 115.493491 -400.01313) (xy 115.500011 -399.995945) (xy 115.500404 -399.986754)
			(xy 115.500404 -399.828766) (xy 115.500905 -399.81861) (xy 115.508684 -399.799847) (xy 115.523047 -399.785484)
			(xy 115.54181 -399.777705) (xy 115.551966 -399.777204) (xy 116.268246 -399.777204) (xy 116.278403 -399.777695)
			(xy 116.297166 -399.785478) (xy 116.311529 -399.799844) (xy 116.319307 -399.818609) (xy 116.319808 -399.828766)
			(xy 116.319808 -399.986754) (xy 116.320238 -399.995939) (xy 116.326738 -400.013124) (xy 116.332508 -400.020282)
			(xy 116.354303 -400.045929) (xy 116.392255 -400.101515) (xy 116.423291 -400.161238) (xy 116.446966 -400.224244)
			(xy 116.46294 -400.289627) (xy 116.470985 -400.356451) (xy 116.470984 -400.423758) (xy 116.462939 -400.490582)
			(xy 116.446963 -400.555965) (xy 116.423288 -400.61897) (xy 116.392251 -400.678693) (xy 116.354298 -400.734279)
			(xy 116.332508 -400.75993) (xy 116.326717 -400.767079) (xy 116.320199 -400.784267) (xy 116.319808 -400.793458)
			(xy 116.319808 -401.286726) (xy 116.320204 -401.295915) (xy 116.326727 -401.313099) (xy 116.332508 -401.320254)
			(xy 116.354276 -401.345923) (xy 116.392229 -401.401506) (xy 116.423266 -401.461227) (xy 116.446942 -401.524229)
			(xy 116.462918 -401.58961) (xy 116.470965 -401.656431) (xy 116.470967 -401.723736) (xy 116.462924 -401.790558)
			(xy 116.446952 -401.855939) (xy 116.423279 -401.918943) (xy 116.392246 -401.978666) (xy 116.354296 -402.034251)
			(xy 116.332508 -402.059902) (xy 116.326729 -402.06706) (xy 116.320204 -402.084241) (xy 116.319808 -402.09343)
			(xy 116.319808 -402.251418) (xy 116.319283 -402.261571) (xy 116.311511 -402.280332) (xy 116.297156 -402.294695)
			(xy 116.278399 -402.302477) (xy 116.268246 -402.30298) (xy 115.551966 -402.30298) (xy 115.541808 -402.302495)
			(xy 115.523042 -402.294713) (xy 115.508678 -402.280345) (xy 115.500902 -402.261576) (xy 115.500404 -402.251418)
			(xy 115.500404 -402.09343) (xy 115.499978 -402.084244) (xy 115.493475 -402.06706) (xy 115.487704 -402.059902)
			(xy 115.465896 -402.034267) (xy 115.42795 -401.978677) (xy 115.396919 -401.918951) (xy 115.373249 -401.855944)
			(xy 115.357279 -401.79056) (xy 115.349237 -401.723737) (xy 87.820954 -401.723737) (xy 87.792056 -401.779212)
			(xy 87.75397 -401.834847) (xy 87.732108 -401.860512) (xy 87.726325 -401.867667) (xy 87.719802 -401.88485)
			(xy 87.719408 -401.89404) (xy 87.719408 -402.386292) (xy 87.71982 -402.395479) (xy 87.726332 -402.412663)
			(xy 87.732108 -402.41982) (xy 87.753925 -402.445524) (xy 87.792014 -402.501153) (xy 87.823166 -402.560944)
			(xy 87.846933 -402.624036) (xy 87.862972 -402.68952) (xy 87.871051 -402.756454) (xy 87.871055 -402.823874)
			(xy 87.871055 -402.823878) (xy 117.548826 -402.823878) (xy 117.548831 -402.75645) (xy 117.556912 -402.689507)
			(xy 117.572954 -402.624015) (xy 117.596726 -402.560916) (xy 117.627885 -402.501119) (xy 117.665983 -402.445484)
			(xy 117.687852 -402.41982) (xy 117.693671 -402.412691) (xy 117.700171 -402.395488) (xy 117.700552 -402.386292)
			(xy 117.700552 -401.89404) (xy 117.700111 -401.884856) (xy 117.693618 -401.867672) (xy 117.687852 -401.860512)
			(xy 117.665967 -401.834864) (xy 117.627875 -401.779228) (xy 117.596722 -401.71943) (xy 117.572957 -401.656331)
			(xy 117.556921 -401.590839) (xy 117.548846 -401.523898) (xy 117.548848 -401.456472) (xy 117.556927 -401.389531)
			(xy 117.572966 -401.32404) (xy 117.596735 -401.260943) (xy 117.627891 -401.201146) (xy 117.665985 -401.145512)
			(xy 117.687852 -401.119848) (xy 117.69366 -401.112711) (xy 117.700166 -401.095514) (xy 117.700552 -401.08632)
			(xy 117.700552 -400.92884) (xy 117.701117 -400.91874) (xy 117.708832 -400.900072) (xy 117.723105 -400.885777)
			(xy 117.741761 -400.878033) (xy 117.75186 -400.877532) (xy 118.46814 -400.877532) (xy 118.478255 -400.877953)
			(xy 118.49694 -400.88571) (xy 118.511235 -400.900027) (xy 118.518963 -400.918724) (xy 118.519448 -400.92884)
			(xy 118.519448 -401.08632) (xy 118.51986 -401.095507) (xy 118.526374 -401.11269) (xy 118.532148 -401.119848)
			(xy 118.553994 -401.145529) (xy 118.592087 -401.20116) (xy 118.623241 -401.260953) (xy 118.647009 -401.324048)
			(xy 118.663047 -401.389536) (xy 118.671126 -401.456473) (xy 118.671127 -401.523897) (xy 118.663053 -401.590834)
			(xy 118.647018 -401.656323) (xy 118.623254 -401.719419) (xy 118.620974 -401.723796) (xy 119.749006 -401.723796)
			(xy 119.749008 -401.656371) (xy 119.757086 -401.589431) (xy 119.773123 -401.523941) (xy 119.79689 -401.460843)
			(xy 119.828043 -401.401046) (xy 119.866135 -401.345411) (xy 119.888 -401.319746) (xy 119.893802 -401.312605)
			(xy 119.900313 -401.295411) (xy 119.9007 -401.286218) (xy 119.9007 -400.793966) (xy 119.900306 -400.784777)
			(xy 119.893781 -400.767593) (xy 119.888 -400.760438) (xy 119.866142 -400.734768) (xy 119.828053 -400.679134)
			(xy 119.796902 -400.619339) (xy 119.773138 -400.556242) (xy 119.757102 -400.490754) (xy 119.749025 -400.423816)
			(xy 119.749025 -400.356393) (xy 119.7571 -400.289455) (xy 119.773135 -400.223966) (xy 119.796898 -400.16087)
			(xy 119.828048 -400.101074) (xy 119.866136 -400.045439) (xy 119.888 -400.019774) (xy 119.89379 -400.012624)
			(xy 119.900309 -399.995437) (xy 119.9007 -399.986246) (xy 119.9007 -399.828766) (xy 119.901197 -399.818642)
			(xy 119.908929 -399.799928) (xy 119.923211 -399.785574) (xy 119.941887 -399.777749) (xy 119.952008 -399.777204)
			(xy 120.668288 -399.777204) (xy 120.67841 -399.777626) (xy 120.697114 -399.785371) (xy 120.711429 -399.799686)
			(xy 120.719174 -399.81839) (xy 120.719596 -399.828512) (xy 120.719596 -399.986246) (xy 120.720033 -399.99543)
			(xy 120.726528 -400.012615) (xy 120.732296 -400.019774) (xy 120.754166 -400.045434) (xy 120.792255 -400.101069)
			(xy 120.823405 -400.160866) (xy 120.847169 -400.223964) (xy 120.863205 -400.289454) (xy 120.87128 -400.356392)
			(xy 120.87128 -400.423817) (xy 120.863203 -400.490755) (xy 120.847167 -400.556245) (xy 120.823402 -400.619342)
			(xy 120.79225 -400.679138) (xy 120.75416 -400.734773) (xy 120.732296 -400.760438) (xy 120.7265 -400.767584)
			(xy 120.719985 -400.784774) (xy 120.719596 -400.793966) (xy 120.719596 -401.286218) (xy 120.719998 -401.295406)
			(xy 120.726517 -401.31259) (xy 120.732296 -401.319746) (xy 120.754138 -401.345429) (xy 120.792228 -401.401061)
			(xy 120.82338 -401.460855) (xy 120.847146 -401.523949) (xy 120.863183 -401.589436) (xy 120.87126 -401.656372)
			(xy 120.871262 -401.723794) (xy 120.863189 -401.790731) (xy 120.847155 -401.856219) (xy 120.823394 -401.919315)
			(xy 120.792245 -401.979111) (xy 120.754159 -402.034745) (xy 120.732296 -402.06041) (xy 120.726512 -402.067564)
			(xy 120.71999 -402.084748) (xy 120.719596 -402.093938) (xy 120.719596 -402.251418) (xy 120.719089 -402.261541)
			(xy 120.711362 -402.280256) (xy 120.697083 -402.294611) (xy 120.678409 -402.302436) (xy 120.668288 -402.30298)
			(xy 119.952008 -402.30298) (xy 119.941884 -402.302577) (xy 119.923176 -402.294828) (xy 119.908861 -402.280507)
			(xy 119.901119 -402.261797) (xy 119.9007 -402.251672) (xy 119.9007 -402.093938) (xy 119.900272 -402.084753)
			(xy 119.893771 -402.067568) (xy 119.888 -402.06041) (xy 119.866114 -402.034763) (xy 119.828026 -401.979126)
			(xy 119.796877 -401.919327) (xy 119.773114 -401.856228) (xy 119.75708 -401.790736) (xy 119.749006 -401.723796)
			(xy 118.620974 -401.723796) (xy 118.592102 -401.779215) (xy 118.554013 -401.834848) (xy 118.532148 -401.860512)
			(xy 118.526357 -401.867661) (xy 118.519841 -401.884849) (xy 118.519448 -401.89404) (xy 118.519448 -402.386292)
			(xy 118.519874 -402.395477) (xy 118.526378 -402.412661) (xy 118.532148 -402.41982) (xy 118.553967 -402.445523)
			(xy 118.59206 -402.501151) (xy 118.623216 -402.560942) (xy 118.646985 -402.624034) (xy 118.663025 -402.689519)
			(xy 118.671106 -402.756454) (xy 118.67111 -402.823818) (xy 121.949146 -402.823818) (xy 121.94915 -402.756509)
			(xy 121.957199 -402.689684) (xy 121.973177 -402.624299) (xy 121.996856 -402.561292) (xy 122.027895 -402.501567)
			(xy 122.065849 -402.44598) (xy 122.08764 -402.420328) (xy 122.093455 -402.413196) (xy 122.099958 -402.395995)
			(xy 122.10034 -402.3868) (xy 122.10034 -401.893532) (xy 122.099905 -401.884348) (xy 122.093408 -401.867164)
			(xy 122.08764 -401.860004) (xy 122.065832 -401.834368) (xy 122.027884 -401.778779) (xy 121.996852 -401.719054)
			(xy 121.97318 -401.656047) (xy 121.957208 -401.590663) (xy 121.949166 -401.523838) (xy 121.949168 -401.456532)
			(xy 121.957214 -401.389708) (xy 121.973189 -401.324324) (xy 121.996864 -401.261319) (xy 122.0279 -401.201595)
			(xy 122.065851 -401.146008) (xy 122.08764 -401.120356) (xy 122.093443 -401.113215) (xy 122.099953 -401.096021)
			(xy 122.10034 -401.086828) (xy 122.10034 -400.92884) (xy 122.10075 -400.918715) (xy 122.108492 -400.900005)
			(xy 122.122812 -400.885688) (xy 122.141523 -400.877948) (xy 122.151648 -400.877532) (xy 122.868182 -400.877532)
			(xy 122.878307 -400.878041) (xy 122.897026 -400.885761) (xy 122.911383 -400.900041) (xy 122.919204 -400.918718)
			(xy 122.919744 -400.92884) (xy 122.919744 -401.086828) (xy 122.920153 -401.096015) (xy 122.926669 -401.113199)
			(xy 122.932444 -401.120356) (xy 122.954212 -401.146024) (xy 122.992163 -401.201608) (xy 123.023198 -401.261329)
			(xy 123.046873 -401.324332) (xy 123.062848 -401.389712) (xy 123.070894 -401.456533) (xy 123.070895 -401.523837)
			(xy 123.062853 -401.590658) (xy 123.046882 -401.65604) (xy 123.02321 -401.719043) (xy 123.020771 -401.723737)
			(xy 124.149301 -401.723737) (xy 124.149303 -401.65643) (xy 124.15735 -401.589605) (xy 124.173327 -401.524221)
			(xy 124.197004 -401.461215) (xy 124.228043 -401.401491) (xy 124.265997 -401.345906) (xy 124.287788 -401.320254)
			(xy 124.293585 -401.313109) (xy 124.3001 -401.295918) (xy 124.300488 -401.286726) (xy 124.300488 -400.793458)
			(xy 124.300101 -400.784268) (xy 124.293572 -400.767084) (xy 124.287788 -400.75993) (xy 124.266005 -400.734274)
			(xy 124.228052 -400.678689) (xy 124.197016 -400.618966) (xy 124.173341 -400.555962) (xy 124.157366 -400.49058)
			(xy 124.149321 -400.423757) (xy 124.14932 -400.356452) (xy 124.157365 -400.289629) (xy 124.173338 -400.224246)
			(xy 124.197013 -400.161242) (xy 124.228048 -400.101519) (xy 124.265999 -400.045933) (xy 124.287788 -400.020282)
			(xy 124.293573 -400.013129) (xy 124.300095 -399.995944) (xy 124.300488 -399.986754) (xy 124.300488 -399.828766)
			(xy 124.300837 -399.818586) (xy 124.308643 -399.799781) (xy 124.323052 -399.785395) (xy 124.341869 -399.777621)
			(xy 124.35205 -399.777204) (xy 125.06833 -399.777204) (xy 125.078486 -399.777708) (xy 125.097249 -399.785486)
			(xy 125.111612 -399.799848) (xy 125.119391 -399.818611) (xy 125.119892 -399.828766) (xy 125.119892 -399.986754)
			(xy 125.120326 -399.995939) (xy 125.126823 -400.013123) (xy 125.132592 -400.020282) (xy 125.154385 -400.04593)
			(xy 125.192331 -400.101518) (xy 125.223363 -400.161242) (xy 125.247034 -400.224247) (xy 125.263005 -400.289629)
			(xy 125.271049 -400.356452) (xy 125.271048 -400.423757) (xy 125.263004 -400.490579) (xy 125.247031 -400.555962)
			(xy 125.223359 -400.618966) (xy 125.192327 -400.67869) (xy 125.154379 -400.734277) (xy 125.132592 -400.75993)
			(xy 125.126799 -400.767078) (xy 125.120283 -400.784266) (xy 125.119892 -400.793458) (xy 125.119892 -401.286726)
			(xy 125.120291 -401.295914) (xy 125.126813 -401.313099) (xy 125.132592 -401.320254) (xy 125.154357 -401.345924)
			(xy 125.192305 -401.401509) (xy 125.223337 -401.46123) (xy 125.24701 -401.524232) (xy 125.262983 -401.589612)
			(xy 125.271029 -401.656432) (xy 125.271031 -401.723735) (xy 125.262989 -401.790555) (xy 125.24702 -401.855936)
			(xy 125.223351 -401.918939) (xy 125.192322 -401.978663) (xy 125.154377 -402.034249) (xy 125.132592 -402.059902)
			(xy 125.126811 -402.067058) (xy 125.120287 -402.08424) (xy 125.119892 -402.09343) (xy 125.119892 -402.251418)
			(xy 125.119382 -402.261573) (xy 125.111608 -402.280337) (xy 125.097247 -402.294701) (xy 125.078485 -402.30248)
			(xy 125.06833 -402.30298) (xy 124.35205 -402.30298) (xy 124.341884 -402.302496) (xy 124.323094 -402.29473)
			(xy 124.308708 -402.280363) (xy 124.300918 -402.261584) (xy 124.300488 -402.251418) (xy 124.300488 -402.09343)
			(xy 124.300066 -402.084244) (xy 124.293561 -402.067059) (xy 124.287788 -402.059902) (xy 124.265977 -402.034268)
			(xy 124.228026 -401.97868) (xy 124.196991 -401.918955) (xy 124.173317 -401.855948) (xy 124.157344 -401.790563)
			(xy 124.149301 -401.723737) (xy 123.020771 -401.723737) (xy 122.992178 -401.778766) (xy 122.954231 -401.834352)
			(xy 122.932444 -401.860004) (xy 122.926656 -401.867155) (xy 122.920138 -401.884341) (xy 122.919744 -401.893532)
			(xy 122.919744 -402.3868) (xy 122.920167 -402.395986) (xy 122.926673 -402.413169) (xy 122.932444 -402.420328)
			(xy 122.954185 -402.446019) (xy 122.992136 -402.501599) (xy 123.023173 -402.561317) (xy 123.046849 -402.624317)
			(xy 123.062826 -402.689695) (xy 123.070874 -402.756513) (xy 123.070878 -402.823815) (xy 123.07087 -402.823878)
			(xy 126.348914 -402.823878) (xy 126.348919 -402.75645) (xy 126.357 -402.689508) (xy 126.373042 -402.624016)
			(xy 126.396813 -402.560916) (xy 126.427971 -402.501119) (xy 126.466068 -402.445485) (xy 126.487936 -402.41982)
			(xy 126.493754 -402.41269) (xy 126.500255 -402.395488) (xy 126.500636 -402.386292) (xy 126.500636 -401.89404)
			(xy 126.500198 -401.884856) (xy 126.493703 -401.867672) (xy 126.487936 -401.860512) (xy 126.466051 -401.834864)
			(xy 126.427961 -401.779227) (xy 126.396809 -401.719429) (xy 126.373044 -401.65633) (xy 126.357009 -401.590839)
			(xy 126.348934 -401.523898) (xy 126.348936 -401.456472) (xy 126.357014 -401.389532) (xy 126.373053 -401.324041)
			(xy 126.396821 -401.260943) (xy 126.427976 -401.201147) (xy 126.46607 -401.145513) (xy 126.487936 -401.119848)
			(xy 126.493742 -401.112709) (xy 126.50025 -401.095514) (xy 126.500636 -401.08632) (xy 126.500636 -400.92884)
			(xy 126.50105 -400.918716) (xy 126.508791 -400.900006) (xy 126.523109 -400.885689) (xy 126.54182 -400.877949)
			(xy 126.551944 -400.877532) (xy 127.268224 -400.877532) (xy 127.278352 -400.877897) (xy 127.297062 -400.885659)
			(xy 127.311377 -400.899991) (xy 127.319116 -400.918711) (xy 127.319532 -400.92884) (xy 127.319532 -401.08632)
			(xy 127.319948 -401.095506) (xy 127.326459 -401.11269) (xy 127.332232 -401.119848) (xy 127.354075 -401.14553)
			(xy 127.392162 -401.201163) (xy 127.423312 -401.260957) (xy 127.447076 -401.324052) (xy 127.463112 -401.389538)
			(xy 127.471189 -401.456474) (xy 127.471191 -401.523896) (xy 127.463117 -401.590832) (xy 127.447085 -401.65632)
			(xy 127.423324 -401.719415) (xy 127.421073 -401.723737) (xy 128.549092 -401.723737) (xy 128.549094 -401.65643)
			(xy 128.557141 -401.589605) (xy 128.573117 -401.524221) (xy 128.596794 -401.461216) (xy 128.627832 -401.401492)
			(xy 128.665786 -401.345906) (xy 128.687576 -401.320254) (xy 128.693372 -401.313108) (xy 128.699888 -401.295918)
			(xy 128.700276 -401.286726) (xy 128.700276 -400.793458) (xy 128.699891 -400.784268) (xy 128.69336 -400.767084)
			(xy 128.687576 -400.75993) (xy 128.665793 -400.734273) (xy 128.627842 -400.678688) (xy 128.596806 -400.618966)
			(xy 128.573131 -400.555962) (xy 128.557157 -400.49058) (xy 128.549112 -400.423757) (xy 128.549111 -400.356452)
			(xy 128.557155 -400.289629) (xy 128.573129 -400.224247) (xy 128.596802 -400.161242) (xy 128.627837 -400.101519)
			(xy 128.665788 -400.045934) (xy 128.687576 -400.020282) (xy 128.69336 -400.013128) (xy 128.699883 -399.995944)
			(xy 128.700276 -399.986754) (xy 128.700276 -399.828766) (xy 128.700637 -399.818587) (xy 128.70844 -399.799785)
			(xy 128.722845 -399.7854) (xy 128.741659 -399.777623) (xy 128.751838 -399.777204) (xy 129.468118 -399.777204)
			(xy 129.478273 -399.777718) (xy 129.497036 -399.785492) (xy 129.511399 -399.799851) (xy 129.519179 -399.818611)
			(xy 129.51968 -399.828766) (xy 129.51968 -399.986754) (xy 129.520117 -399.995938) (xy 129.526612 -400.013123)
			(xy 129.53238 -400.020282) (xy 129.554173 -400.045929) (xy 129.592121 -400.101517) (xy 129.623152 -400.161241)
			(xy 129.646824 -400.224247) (xy 129.662796 -400.289629) (xy 129.670839 -400.356452) (xy 129.670839 -400.423757)
			(xy 129.662794 -400.49058) (xy 129.646821 -400.555962) (xy 129.623149 -400.618967) (xy 129.592116 -400.678691)
			(xy 129.554168 -400.734278) (xy 129.53238 -400.75993) (xy 129.526586 -400.767077) (xy 129.52007 -400.784266)
			(xy 129.51968 -400.793458) (xy 129.51968 -401.286726) (xy 129.520082 -401.295914) (xy 129.526602 -401.313098)
			(xy 129.53238 -401.320254) (xy 129.554146 -401.345924) (xy 129.592094 -401.401508) (xy 129.623127 -401.46123)
			(xy 129.6468 -401.524232) (xy 129.662774 -401.589612) (xy 129.67082 -401.656432) (xy 129.670822 -401.723735)
			(xy 129.66278 -401.790556) (xy 129.64681 -401.855937) (xy 129.623141 -401.91894) (xy 129.592111 -401.978663)
			(xy 129.554166 -402.03425) (xy 129.53238 -402.059902) (xy 129.526598 -402.067057) (xy 129.520075 -402.08424)
			(xy 129.51968 -402.09343) (xy 129.51968 -402.251418) (xy 129.519182 -402.261575) (xy 129.511405 -402.280341)
			(xy 129.497041 -402.294705) (xy 129.478275 -402.302482) (xy 129.468118 -402.30298) (xy 128.751838 -402.30298)
			(xy 128.741671 -402.302505) (xy 128.722881 -402.294736) (xy 128.708495 -402.280366) (xy 128.700706 -402.261584)
			(xy 128.700276 -402.251418) (xy 128.700276 -402.09343) (xy 128.699857 -402.084244) (xy 128.69335 -402.067059)
			(xy 128.687576 -402.059902) (xy 128.665766 -402.034268) (xy 128.627815 -401.97868) (xy 128.596781 -401.918954)
			(xy 128.573108 -401.855947) (xy 128.557135 -401.790562) (xy 128.549092 -401.723737) (xy 127.421073 -401.723737)
			(xy 127.392178 -401.779211) (xy 127.354094 -401.834846) (xy 127.332232 -401.860512) (xy 127.32644 -401.86766)
			(xy 127.319924 -401.884849) (xy 127.319532 -401.89404) (xy 127.319532 -402.386292) (xy 127.319961 -402.395477)
			(xy 127.326463 -402.412661) (xy 127.332232 -402.41982) (xy 127.354048 -402.445525) (xy 127.392136 -402.501154)
			(xy 127.423287 -402.560945) (xy 127.447052 -402.624037) (xy 127.46309 -402.689521) (xy 127.471169 -402.756454)
			(xy 127.471174 -402.823818) (xy 130.749234 -402.823818) (xy 130.749238 -402.75651) (xy 130.757287 -402.689684)
			(xy 130.773265 -402.624299) (xy 130.796942 -402.561293) (xy 130.82798 -402.501568) (xy 130.865934 -402.44598)
			(xy 130.887724 -402.420328) (xy 130.893536 -402.413194) (xy 130.900041 -402.395995) (xy 130.900424 -402.3868)
			(xy 130.900424 -401.893532) (xy 130.899993 -401.884347) (xy 130.893493 -401.867163) (xy 130.887724 -401.860004)
			(xy 130.865917 -401.834368) (xy 130.82797 -401.778779) (xy 130.796938 -401.719053) (xy 130.773267 -401.656046)
			(xy 130.757296 -401.590662) (xy 130.749254 -401.523838) (xy 130.749256 -401.456532) (xy 130.757301 -401.389708)
			(xy 130.773276 -401.324325) (xy 130.79695 -401.26132) (xy 130.827985 -401.201595) (xy 130.865935 -401.146008)
			(xy 130.887724 -401.120356) (xy 130.893525 -401.113214) (xy 130.900036 -401.096021) (xy 130.900424 -401.086828)
			(xy 130.900424 -400.92884) (xy 130.900855 -400.918686) (xy 130.908642 -400.899929) (xy 130.923036 -400.885604)
			(xy 130.94183 -400.877907) (xy 130.951986 -400.877532) (xy 131.668266 -400.877532) (xy 131.67839 -400.878054)
			(xy 131.697108 -400.88577) (xy 131.711465 -400.900045) (xy 131.719287 -400.918719) (xy 131.719828 -400.92884)
			(xy 131.719828 -401.086828) (xy 131.720218 -401.096017) (xy 131.726745 -401.113202) (xy 131.732528 -401.120356)
			(xy 131.754297 -401.146024) (xy 131.792249 -401.201607) (xy 131.823285 -401.261328) (xy 131.84696 -401.324331)
			(xy 131.862935 -401.389712) (xy 131.870981 -401.456533) (xy 131.870983 -401.523837) (xy 131.862941 -401.590659)
			(xy 131.846969 -401.65604) (xy 131.823297 -401.719044) (xy 131.792264 -401.778767) (xy 131.754315 -401.834352)
			(xy 131.732528 -401.860004) (xy 131.726738 -401.867154) (xy 131.720222 -401.884341) (xy 131.719828 -401.893532)
			(xy 131.719828 -402.3868) (xy 131.720232 -402.395988) (xy 131.726749 -402.413173) (xy 131.732528 -402.420328)
			(xy 131.75427 -402.446019) (xy 131.792222 -402.501599) (xy 131.823259 -402.561317) (xy 131.846936 -402.624316)
			(xy 131.862913 -402.689694) (xy 131.870962 -402.756513) (xy 131.870966 -402.823815) (xy 131.862926 -402.890635)
			(xy 131.846957 -402.956015) (xy 131.823289 -403.019017) (xy 131.792259 -403.078739) (xy 131.754314 -403.134324)
			(xy 131.732528 -403.159976) (xy 131.726708 -403.167104) (xy 131.720209 -403.184308) (xy 131.719828 -403.193504)
			(xy 131.719828 -403.351492) (xy 131.719372 -403.361642) (xy 131.711585 -403.380389) (xy 131.697199 -403.394712)
			(xy 131.678418 -403.402417) (xy 131.668266 -403.4028) (xy 130.951986 -403.4028) (xy 130.941863 -403.402286)
			(xy 130.92315 -403.394561) (xy 130.908795 -403.380284) (xy 130.90097 -403.361612) (xy 130.900424 -403.351492)
			(xy 130.900424 -403.193504) (xy 130.900007 -403.184318) (xy 130.893498 -403.167133) (xy 130.887724 -403.159976)
			(xy 130.86589 -403.134362) (xy 130.827943 -403.07877) (xy 130.796913 -403.019041) (xy 130.773243 -402.956032)
			(xy 130.757274 -402.890645) (xy 130.749234 -402.823818) (xy 127.471174 -402.823818) (xy 127.471174 -402.823874)
			(xy 127.463103 -402.890808) (xy 127.447074 -402.956294) (xy 127.423316 -403.019389) (xy 127.392173 -403.079184)
			(xy 127.354092 -403.134818) (xy 127.332232 -403.160484) (xy 127.326409 -403.16761) (xy 127.319912 -403.184816)
			(xy 127.319532 -403.194012) (xy 127.319532 -403.351492) (xy 127.319009 -403.361596) (xy 127.31128 -403.380268)
			(xy 127.296995 -403.394562) (xy 127.278328 -403.402303) (xy 127.268224 -403.4028) (xy 126.551944 -403.4028)
			(xy 126.541824 -403.402348) (xy 126.523122 -403.394614) (xy 126.508806 -403.380308) (xy 126.501059 -403.361611)
			(xy 126.500636 -403.351492) (xy 126.500636 -403.194012) (xy 126.500212 -403.184826) (xy 126.493707 -403.167642)
			(xy 126.487936 -403.160484) (xy 126.466024 -403.134858) (xy 126.427934 -403.079219) (xy 126.396783 -403.019418)
			(xy 126.37302 -402.956315) (xy 126.356987 -402.890821) (xy 126.348914 -402.823878) (xy 123.07087 -402.823878)
			(xy 123.062839 -402.890634) (xy 123.04687 -402.956014) (xy 123.023202 -403.019017) (xy 122.992173 -403.078739)
			(xy 122.954229 -403.134324) (xy 122.932444 -403.159976) (xy 122.926626 -403.167106) (xy 122.920126 -403.184308)
			(xy 122.919744 -403.193504) (xy 122.919744 -403.351492) (xy 122.919209 -403.361595) (xy 122.911483 -403.380264)
			(xy 122.897201 -403.394558) (xy 122.878538 -403.402301) (xy 122.868436 -403.4028) (xy 122.151902 -403.4028)
			(xy 122.14178 -403.402273) (xy 122.123067 -403.394553) (xy 122.108712 -403.38028) (xy 122.100886 -403.361611)
			(xy 122.10034 -403.351492) (xy 122.10034 -403.193504) (xy 122.099919 -403.184318) (xy 122.093412 -403.167134)
			(xy 122.08764 -403.159976) (xy 122.065805 -403.134363) (xy 122.027857 -403.078771) (xy 121.996826 -403.019042)
			(xy 121.973156 -402.956032) (xy 121.957186 -402.890645) (xy 121.949146 -402.823818) (xy 118.67111 -402.823818)
			(xy 118.67111 -402.823874) (xy 118.663038 -402.89081) (xy 118.647006 -402.956297) (xy 118.623245 -403.019392)
			(xy 118.592097 -403.079187) (xy 118.554011 -403.13482) (xy 118.532148 -403.160484) (xy 118.526327 -403.167612)
			(xy 118.519828 -403.184816) (xy 118.519448 -403.194012) (xy 118.519448 -403.351492) (xy 118.51891 -403.361594)
			(xy 118.511183 -403.380263) (xy 118.496903 -403.394557) (xy 118.478242 -403.4023) (xy 118.46814 -403.4028)
			(xy 117.75186 -403.4028) (xy 117.741749 -403.402348) (xy 117.72307 -403.394597) (xy 117.708776 -403.38029)
			(xy 117.701043 -403.361604) (xy 117.700552 -403.351492) (xy 117.700552 -403.194012) (xy 117.700125 -403.184827)
			(xy 117.693622 -403.167643) (xy 117.687852 -403.160484) (xy 117.665939 -403.134859) (xy 117.627848 -403.07922)
			(xy 117.596697 -403.019418) (xy 117.572933 -402.956316) (xy 117.556899 -402.890822) (xy 117.548826 -402.823878)
			(xy 87.871055 -402.823878) (xy 87.862984 -402.890809) (xy 87.846954 -402.956295) (xy 87.823196 -403.01939)
			(xy 87.792051 -403.079185) (xy 87.753969 -403.134819) (xy 87.732108 -403.160484) (xy 87.726294 -403.167617)
			(xy 87.71979 -403.184817) (xy 87.719408 -403.194012) (xy 87.719408 -403.351492) (xy 87.718978 -403.361613)
			(xy 87.711234 -403.380315) (xy 87.696922 -403.394629) (xy 87.678221 -403.402376) (xy 87.6681 -403.4028)
			(xy 86.95182 -403.4028) (xy 86.941699 -403.402368) (xy 86.922996 -403.394626) (xy 86.908681 -403.380315)
			(xy 86.900935 -403.361613) (xy 86.900512 -403.351492) (xy 86.900512 -403.194012) (xy 86.900093 -403.184826)
			(xy 86.893585 -403.167642) (xy 86.887812 -403.160484) (xy 86.8659 -403.134858) (xy 86.827812 -403.079218)
			(xy 86.796663 -403.019417) (xy 86.772901 -402.956315) (xy 86.756869 -402.890821) (xy 86.748796 -402.823878)
			(xy 83.470752 -402.823878) (xy 83.46272 -402.890635) (xy 83.446751 -402.956015) (xy 83.423082 -403.019018)
			(xy 83.392052 -403.07874) (xy 83.354106 -403.134324) (xy 83.33232 -403.159976) (xy 83.326511 -403.167113)
			(xy 83.320003 -403.18431) (xy 83.31962 -403.193504) (xy 83.31962 -403.351492) (xy 83.319172 -403.361643)
			(xy 83.311383 -403.380391) (xy 83.296995 -403.394714) (xy 83.278211 -403.402418) (xy 83.268058 -403.4028)
			(xy 82.551778 -403.4028) (xy 82.541655 -403.402293) (xy 82.522941 -403.394565) (xy 82.508586 -403.380286)
			(xy 82.500761 -403.361613) (xy 82.500216 -403.351492) (xy 82.500216 -403.193504) (xy 82.4998 -403.184318)
			(xy 82.49329 -403.167133) (xy 82.487516 -403.159976) (xy 82.465682 -403.134362) (xy 82.427736 -403.07877)
			(xy 82.396706 -403.019041) (xy 82.373037 -402.956031) (xy 82.357068 -402.890645) (xy 82.349028 -402.823818)
			(xy 79.070968 -402.823818) (xy 79.070968 -402.823874) (xy 79.062897 -402.890808) (xy 79.046867 -402.956294)
			(xy 79.023109 -403.019389) (xy 78.991966 -403.079184) (xy 78.953884 -403.134818) (xy 78.932024 -403.160484)
			(xy 78.926212 -403.167618) (xy 78.919706 -403.184817) (xy 78.919324 -403.194012) (xy 78.919324 -403.351492)
			(xy 78.918809 -403.361597) (xy 78.911078 -403.380271) (xy 78.896791 -403.394565) (xy 78.878121 -403.402304)
			(xy 78.868016 -403.4028) (xy 78.151736 -403.4028) (xy 78.141616 -403.402354) (xy 78.122913 -403.394618)
			(xy 78.108598 -403.38031) (xy 78.100851 -403.361612) (xy 78.100428 -403.351492) (xy 78.100428 -403.194012)
			(xy 78.100006 -403.184826) (xy 78.0935 -403.167642) (xy 78.087728 -403.160484) (xy 78.065816 -403.134858)
			(xy 78.027727 -403.079219) (xy 77.996577 -403.019417) (xy 77.972814 -402.956315) (xy 77.956781 -402.890821)
			(xy 77.948708 -402.823878) (xy 74.670664 -402.823878) (xy 74.662632 -402.890635) (xy 74.646664 -402.956014)
			(xy 74.622995 -403.019017) (xy 74.591966 -403.078739) (xy 74.554022 -403.134324) (xy 74.532236 -403.159976)
			(xy 74.526417 -403.167105) (xy 74.519917 -403.184308) (xy 74.519536 -403.193504) (xy 74.519536 -403.351492)
			(xy 74.519073 -403.361641) (xy 74.511286 -403.380386) (xy 74.496903 -403.394709) (xy 74.478125 -403.402415)
			(xy 74.467974 -403.4028) (xy 73.751694 -403.4028) (xy 73.741572 -403.402279) (xy 73.722858 -403.394557)
			(xy 73.708504 -403.380282) (xy 73.700678 -403.361611) (xy 73.700132 -403.351492) (xy 73.700132 -403.193504)
			(xy 73.699713 -403.184318) (xy 73.693205 -403.167134) (xy 73.687432 -403.159976) (xy 73.665597 -403.134363)
			(xy 73.62765 -403.07877) (xy 73.59662 -403.019041) (xy 73.57295 -402.956032) (xy 73.55698 -402.890645)
			(xy 73.54894 -402.823818) (xy 66.525648 -402.823818) (xy 66.525648 -405.623707) (xy 71.348811 -405.623707)
			(xy 71.348811 -405.556283) (xy 71.356888 -405.489345) (xy 71.372924 -405.423856) (xy 71.396688 -405.360759)
			(xy 71.427839 -405.300962) (xy 71.465928 -405.245327) (xy 71.487792 -405.219662) (xy 71.493586 -405.212515)
			(xy 71.500103 -405.195326) (xy 71.500492 -405.186134) (xy 71.500492 -404.693882) (xy 71.500092 -404.684694)
			(xy 71.493571 -404.667509) (xy 71.487792 -404.660354) (xy 71.46595 -404.634671) (xy 71.427861 -404.579039)
			(xy 71.39671 -404.519245) (xy 71.372945 -404.45615) (xy 71.356908 -404.390664) (xy 71.348831 -404.323727)
			(xy 71.348829 -404.256306) (xy 71.356902 -404.189369) (xy 71.372935 -404.123881) (xy 71.396696 -404.060785)
			(xy 71.427844 -404.00099) (xy 71.46593 -403.945355) (xy 71.487792 -403.91969) (xy 71.493574 -403.912535)
			(xy 71.500098 -403.895352) (xy 71.500492 -403.886162) (xy 71.500492 -403.728682) (xy 71.50101 -403.71856)
			(xy 71.508735 -403.699847) (xy 71.523011 -403.685493) (xy 71.541681 -403.677666) (xy 71.5518 -403.67712)
			(xy 72.26808 -403.67712) (xy 72.278235 -403.677538) (xy 72.296991 -403.685331) (xy 72.311316 -403.699729)
			(xy 72.319013 -403.718525) (xy 72.319388 -403.728682) (xy 72.319388 -403.886162) (xy 72.319819 -403.895347)
			(xy 72.326319 -403.912531) (xy 72.332088 -403.91969) (xy 72.353974 -403.945337) (xy 72.392063 -404.000974)
			(xy 72.423213 -404.060773) (xy 72.446977 -404.123872) (xy 72.463011 -404.189363) (xy 72.471085 -404.256304)
			(xy 72.471083 -404.323729) (xy 72.463005 -404.390669) (xy 72.446967 -404.45616) (xy 72.4232 -404.519258)
			(xy 72.392046 -404.579054) (xy 72.353954 -404.634689) (xy 72.332088 -404.660354) (xy 72.326285 -404.667494)
			(xy 72.319774 -404.684689) (xy 72.319388 -404.693882) (xy 72.319388 -405.186134) (xy 72.319784 -405.195323)
			(xy 72.326308 -405.212507) (xy 72.332088 -405.219662) (xy 72.353946 -405.245332) (xy 72.392036 -405.300965)
			(xy 72.423188 -405.360761) (xy 72.446953 -405.423857) (xy 72.462989 -405.489346) (xy 72.471066 -405.556284)
			(xy 72.471066 -405.623707) (xy 72.462991 -405.690645) (xy 72.446956 -405.756134) (xy 72.423191 -405.819231)
			(xy 72.392041 -405.879027) (xy 72.353952 -405.934661) (xy 72.332088 -405.960326) (xy 72.326297 -405.967475)
			(xy 72.319779 -405.984663) (xy 72.319388 -405.993854) (xy 72.319388 -406.151334) (xy 72.318902 -406.161459)
			(xy 72.311168 -406.180176) (xy 72.296883 -406.19453) (xy 72.278203 -406.202353) (xy 72.26808 -406.202896)
			(xy 71.5518 -406.202896) (xy 71.541645 -406.202478) (xy 71.522892 -406.194682) (xy 71.508569 -406.180284)
			(xy 71.50087 -406.161491) (xy 71.500492 -406.151334) (xy 71.500492 -405.993854) (xy 71.500058 -405.984669)
			(xy 71.493561 -405.967485) (xy 71.487792 -405.960326) (xy 71.465922 -405.934665) (xy 71.427834 -405.87903)
			(xy 71.396684 -405.819233) (xy 71.372921 -405.756136) (xy 71.356886 -405.690646) (xy 71.348811 -405.623707)
			(xy 66.525648 -405.623707) (xy 66.525648 -406.72373) (xy 73.548951 -406.72373) (xy 73.548954 -406.656422)
			(xy 73.557001 -406.589598) (xy 73.572978 -406.524214) (xy 73.596654 -406.461208) (xy 73.62769 -406.401483)
			(xy 73.665642 -406.345896) (xy 73.687432 -406.320244) (xy 73.693239 -406.313106) (xy 73.699747 -406.29591)
			(xy 73.700132 -406.286716) (xy 73.700132 -405.793448) (xy 73.699691 -405.784264) (xy 73.693198 -405.76708)
			(xy 73.687432 -405.75992) (xy 73.66564 -405.734271) (xy 73.627692 -405.678684) (xy 73.596659 -405.61896)
			(xy 73.572987 -405.555955) (xy 73.557015 -405.490572) (xy 73.548971 -405.42375) (xy 73.548971 -405.356444)
			(xy 73.557016 -405.289622) (xy 73.572989 -405.224239) (xy 73.596662 -405.161235) (xy 73.627695 -405.101511)
			(xy 73.665644 -405.045924) (xy 73.687432 -405.020272) (xy 73.693227 -405.013126) (xy 73.699742 -404.995936)
			(xy 73.700132 -404.986744) (xy 73.700132 -404.828756) (xy 73.700486 -404.818595) (xy 73.708302 -404.799836)
			(xy 73.72272 -404.785513) (xy 73.74153 -404.77782) (xy 73.751694 -404.777448) (xy 74.467974 -404.777448)
			(xy 74.4781 -404.777948) (xy 74.496822 -404.785669) (xy 74.51118 -404.799951) (xy 74.518998 -404.818633)
			(xy 74.519536 -404.828756) (xy 74.519536 -404.986744) (xy 74.519939 -404.995932) (xy 74.526459 -405.013115)
			(xy 74.532236 -405.020272) (xy 74.55402 -405.045927) (xy 74.591971 -405.101513) (xy 74.623006 -405.161235)
			(xy 74.64668 -405.22424) (xy 74.662654 -405.289622) (xy 74.670699 -405.356444) (xy 74.670699 -405.42375)
			(xy 74.662655 -405.490572) (xy 74.646682 -405.555955) (xy 74.623008 -405.618959) (xy 74.620571 -405.623649)
			(xy 75.749106 -405.623649) (xy 75.749107 -405.556342) (xy 75.757152 -405.489519) (xy 75.773127 -405.424136)
			(xy 75.796802 -405.361131) (xy 75.827839 -405.301407) (xy 75.865791 -405.245822) (xy 75.88758 -405.22017)
			(xy 75.893369 -405.21302) (xy 75.899889 -405.195833) (xy 75.90028 -405.186642) (xy 75.90028 -404.693374)
			(xy 75.899887 -404.684185) (xy 75.893362 -404.667001) (xy 75.88758 -404.659846) (xy 75.865813 -404.634177)
			(xy 75.827861 -404.578594) (xy 75.796824 -404.518873) (xy 75.773148 -404.45587) (xy 75.757173 -404.39049)
			(xy 75.749126 -404.323669) (xy 75.749124 -404.256365) (xy 75.757167 -404.189543) (xy 75.773138 -404.124161)
			(xy 75.796811 -404.061157) (xy 75.827844 -404.001435) (xy 75.865792 -403.94585) (xy 75.88758 -403.920198)
			(xy 75.893358 -403.913039) (xy 75.899884 -403.895859) (xy 75.90028 -403.88667) (xy 75.90028 -403.728682)
			(xy 75.90065 -403.718504) (xy 75.908449 -403.699701) (xy 75.922851 -403.685315) (xy 75.941664 -403.677538)
			(xy 75.951842 -403.67712) (xy 76.668122 -403.67712) (xy 76.678279 -403.677615) (xy 76.697045 -403.685393)
			(xy 76.711409 -403.699758) (xy 76.719186 -403.718525) (xy 76.719684 -403.728682) (xy 76.719684 -403.88667)
			(xy 76.720112 -403.895855) (xy 76.726614 -403.91304) (xy 76.732384 -403.920198) (xy 76.754193 -403.945833)
			(xy 76.792139 -404.001422) (xy 76.82317 -404.061148) (xy 76.846841 -404.124155) (xy 76.862812 -404.189539)
			(xy 76.870854 -404.256363) (xy 76.870852 -404.32367) (xy 76.862806 -404.390493) (xy 76.846831 -404.455877)
			(xy 76.823157 -404.518882) (xy 76.792122 -404.578606) (xy 76.754172 -404.634194) (xy 76.732384 -404.659846)
			(xy 76.726584 -404.666988) (xy 76.720072 -404.684181) (xy 76.719684 -404.693374) (xy 76.719684 -405.186642)
			(xy 76.720077 -405.195831) (xy 76.726603 -405.213015) (xy 76.732384 -405.22017) (xy 76.754165 -405.245827)
			(xy 76.792113 -405.301414) (xy 76.823145 -405.361137) (xy 76.846817 -405.42414) (xy 76.86279 -405.489522)
			(xy 76.870834 -405.556343) (xy 76.870835 -405.623648) (xy 76.862791 -405.690469) (xy 76.84682 -405.755851)
			(xy 76.823149 -405.818855) (xy 76.792117 -405.878579) (xy 76.754171 -405.934166) (xy 76.732384 -405.959818)
			(xy 76.726595 -405.966969) (xy 76.720077 -405.984155) (xy 76.719684 -405.993346) (xy 76.719684 -406.151334)
			(xy 76.719195 -406.161491) (xy 76.711414 -406.180257) (xy 76.697047 -406.19462) (xy 76.678279 -406.202397)
			(xy 76.668122 -406.202896) (xy 75.951842 -406.202896) (xy 75.941677 -406.202403) (xy 75.92289 -406.194638)
			(xy 75.908505 -406.180274) (xy 75.900712 -406.161498) (xy 75.90028 -406.151334) (xy 75.90028 -405.993346)
			(xy 75.899852 -405.984161) (xy 75.893351 -405.966976) (xy 75.88758 -405.959818) (xy 75.865785 -405.934171)
			(xy 75.827834 -405.878585) (xy 75.796799 -405.818861) (xy 75.773124 -405.755856) (xy 75.757151 -405.690472)
			(xy 75.749106 -405.623649) (xy 74.620571 -405.623649) (xy 74.591974 -405.678682) (xy 74.554024 -405.734268)
			(xy 74.532236 -405.75992) (xy 74.526441 -405.767066) (xy 74.519927 -405.784256) (xy 74.519536 -405.793448)
			(xy 74.519536 -406.286716) (xy 74.519953 -406.295902) (xy 74.526464 -406.313086) (xy 74.532236 -406.320244)
			(xy 74.553993 -406.345922) (xy 74.591944 -406.401504) (xy 74.62298 -406.461224) (xy 74.646656 -406.524225)
			(xy 74.662632 -406.589604) (xy 74.670679 -406.656424) (xy 74.670682 -406.723727) (xy 74.670675 -406.723789)
			(xy 77.94872 -406.723789) (xy 77.948723 -406.656363) (xy 77.956802 -406.589422) (xy 77.972842 -406.52393)
			(xy 77.996611 -406.460832) (xy 78.027767 -406.401035) (xy 78.065861 -406.345401) (xy 78.087728 -406.319736)
			(xy 78.093538 -406.3126) (xy 78.100044 -406.295402) (xy 78.100428 -406.286208) (xy 78.100428 -405.793956)
			(xy 78.100033 -405.784767) (xy 78.093508 -405.767584) (xy 78.087728 -405.760428) (xy 78.065859 -405.734766)
			(xy 78.027769 -405.679132) (xy 77.996617 -405.619336) (xy 77.972851 -405.556238) (xy 77.956815 -405.490748)
			(xy 77.948739 -405.423809) (xy 77.94874 -405.356385) (xy 77.956816 -405.289446) (xy 77.972853 -405.223956)
			(xy 77.996619 -405.160859) (xy 78.027772 -405.101063) (xy 78.065863 -405.045429) (xy 78.087728 -405.019764)
			(xy 78.093526 -405.01262) (xy 78.100039 -404.995428) (xy 78.100428 -404.986236) (xy 78.100428 -404.828756)
			(xy 78.10085 -404.818641) (xy 78.108607 -404.799956) (xy 78.122924 -404.785662) (xy 78.14162 -404.777934)
			(xy 78.151736 -404.777448) (xy 78.868016 -404.777448) (xy 78.878119 -404.777971) (xy 78.896788 -404.785704)
			(xy 78.91108 -404.799989) (xy 78.918823 -404.818653) (xy 78.919324 -404.828756) (xy 78.919324 -404.986236)
			(xy 78.919712 -404.995426) (xy 78.92624 -405.01261) (xy 78.932024 -405.019764) (xy 78.953883 -405.045433)
			(xy 78.99197 -405.101067) (xy 79.02312 -405.160863) (xy 79.046883 -405.22396) (xy 79.062918 -405.289448)
			(xy 79.070994 -405.356386) (xy 79.070995 -405.423808) (xy 79.062919 -405.490746) (xy 79.046885 -405.556235)
			(xy 79.023122 -405.619331) (xy 79.020843 -405.623707) (xy 80.148899 -405.623707) (xy 80.148899 -405.556284)
			(xy 80.156975 -405.489345) (xy 80.173011 -405.423856) (xy 80.196775 -405.360759) (xy 80.227925 -405.300963)
			(xy 80.266013 -405.245328) (xy 80.287876 -405.219662) (xy 80.293668 -405.212514) (xy 80.300186 -405.195326)
			(xy 80.300576 -405.186134) (xy 80.300576 -404.693882) (xy 80.30018 -404.684693) (xy 80.293657 -404.667509)
			(xy 80.287876 -404.660354) (xy 80.266034 -404.634671) (xy 80.227947 -404.579038) (xy 80.196796 -404.519244)
			(xy 80.173032 -404.45615) (xy 80.156996 -404.390663) (xy 80.148918 -404.323727) (xy 80.148917 -404.256306)
			(xy 80.15699 -404.189369) (xy 80.173022 -404.123882) (xy 80.196783 -404.060786) (xy 80.22793 -404.00099)
			(xy 80.266014 -403.945356) (xy 80.287876 -403.91969) (xy 80.293657 -403.912533) (xy 80.300182 -403.895352)
			(xy 80.300576 -403.886162) (xy 80.300576 -403.728682) (xy 80.301013 -403.71855) (xy 80.308753 -403.699821)
			(xy 80.323055 -403.685464) (xy 80.341754 -403.677652) (xy 80.351884 -403.67712) (xy 81.068164 -403.67712)
			(xy 81.078318 -403.677552) (xy 81.097074 -403.685339) (xy 81.111399 -403.699733) (xy 81.119096 -403.718526)
			(xy 81.119472 -403.728682) (xy 81.119472 -403.886162) (xy 81.119907 -403.895346) (xy 81.126404 -403.912531)
			(xy 81.132172 -403.91969) (xy 81.154059 -403.945337) (xy 81.192148 -404.000973) (xy 81.2233 -404.060772)
			(xy 81.247064 -404.123871) (xy 81.263099 -404.189363) (xy 81.271173 -404.256304) (xy 81.271171 -404.32373)
			(xy 81.263093 -404.39067) (xy 81.247054 -404.45616) (xy 81.223286 -404.519258) (xy 81.192131 -404.579055)
			(xy 81.154038 -404.634689) (xy 81.132172 -404.660354) (xy 81.126366 -404.667493) (xy 81.119858 -404.684688)
			(xy 81.119472 -404.693882) (xy 81.119472 -405.186134) (xy 81.119872 -405.195322) (xy 81.126393 -405.212506)
			(xy 81.132172 -405.219662) (xy 81.154031 -405.245332) (xy 81.192122 -405.300965) (xy 81.223274 -405.36076)
			(xy 81.24704 -405.423857) (xy 81.263077 -405.489345) (xy 81.271154 -405.556284) (xy 81.271154 -405.623707)
			(xy 81.263078 -405.690646) (xy 81.247043 -405.756135) (xy 81.223278 -405.819232) (xy 81.192126 -405.879027)
			(xy 81.154037 -405.934661) (xy 81.132172 -405.960326) (xy 81.126378 -405.967473) (xy 81.119862 -405.984662)
			(xy 81.119472 -405.993854) (xy 81.119472 -406.151334) (xy 81.119002 -406.161461) (xy 81.111265 -406.180181)
			(xy 81.096974 -406.194536) (xy 81.078289 -406.202356) (xy 81.068164 -406.202896) (xy 80.351884 -406.202896)
			(xy 80.341728 -406.202492) (xy 80.322975 -406.19469) (xy 80.308652 -406.180288) (xy 80.300953 -406.161492)
			(xy 80.300576 -406.151334) (xy 80.300576 -405.993854) (xy 80.300145 -405.984669) (xy 80.293646 -405.967484)
			(xy 80.287876 -405.960326) (xy 80.266007 -405.934665) (xy 80.22792 -405.879029) (xy 80.196771 -405.819232)
			(xy 80.173008 -405.756135) (xy 80.156974 -405.690646) (xy 80.148899 -405.623707) (xy 79.020843 -405.623707)
			(xy 78.991974 -405.679127) (xy 78.953887 -405.734762) (xy 78.932024 -405.760428) (xy 78.926236 -405.767579)
			(xy 78.919715 -405.784765) (xy 78.919324 -405.793956) (xy 78.919324 -406.286208) (xy 78.919725 -406.295396)
			(xy 78.926244 -406.312581) (xy 78.932024 -406.319736) (xy 78.953856 -406.345428) (xy 78.991944 -406.401059)
			(xy 79.023095 -406.460852) (xy 79.046859 -406.523945) (xy 79.062896 -406.589431) (xy 79.070974 -406.656366)
			(xy 79.070977 -406.72373) (xy 82.349039 -406.72373) (xy 82.349042 -406.656422) (xy 82.357089 -406.589598)
			(xy 82.373065 -406.524214) (xy 82.39674 -406.461209) (xy 82.427776 -406.401484) (xy 82.465727 -406.345896)
			(xy 82.487516 -406.320244) (xy 82.493321 -406.313105) (xy 82.49983 -406.29591) (xy 82.500216 -406.286716)
			(xy 82.500216 -405.793448) (xy 82.499779 -405.784264) (xy 82.493284 -405.767079) (xy 82.487516 -405.75992)
			(xy 82.465725 -405.734271) (xy 82.427778 -405.678683) (xy 82.396746 -405.618959) (xy 82.373074 -405.555954)
			(xy 82.357102 -405.490572) (xy 82.349059 -405.423749) (xy 82.349059 -405.356445) (xy 82.357103 -405.289622)
			(xy 82.373076 -405.22424) (xy 82.396748 -405.161235) (xy 82.427781 -405.101511) (xy 82.465729 -405.045924)
			(xy 82.487516 -405.020272) (xy 82.493309 -405.013124) (xy 82.499825 -404.995936) (xy 82.500216 -404.986744)
			(xy 82.500216 -404.828756) (xy 82.500586 -404.818597) (xy 82.508399 -404.799841) (xy 82.522811 -404.785518)
			(xy 82.541617 -404.777823) (xy 82.551778 -404.777448) (xy 83.268058 -404.777448) (xy 83.278183 -404.777961)
			(xy 83.296905 -404.785677) (xy 83.311263 -404.799955) (xy 83.319082 -404.818634) (xy 83.31962 -404.828756)
			(xy 83.31962 -404.986744) (xy 83.320004 -404.995934) (xy 83.326535 -405.013118) (xy 83.33232 -405.020272)
			(xy 83.354105 -405.045927) (xy 83.392057 -405.101512) (xy 83.423092 -405.161235) (xy 83.446767 -405.224239)
			(xy 83.462742 -405.289621) (xy 83.470787 -405.356444) (xy 83.470787 -405.42375) (xy 83.462743 -405.490573)
			(xy 83.446769 -405.555955) (xy 83.423095 -405.61896) (xy 83.420628 -405.623707) (xy 84.54869 -405.623707)
			(xy 84.54869 -405.556284) (xy 84.556766 -405.489346) (xy 84.572801 -405.423857) (xy 84.596564 -405.36076)
			(xy 84.627714 -405.300963) (xy 84.665801 -405.245328) (xy 84.687664 -405.219662) (xy 84.693467 -405.212522)
			(xy 84.699976 -405.195327) (xy 84.700364 -405.186134) (xy 84.700364 -404.693882) (xy 84.699948 -404.684696)
			(xy 84.693437 -404.667512) (xy 84.687664 -404.660354) (xy 84.665823 -404.63467) (xy 84.627736 -404.579038)
			(xy 84.596586 -404.519244) (xy 84.572822 -404.456149) (xy 84.556787 -404.390663) (xy 84.548709 -404.323727)
			(xy 84.548707 -404.256306) (xy 84.556781 -404.18937) (xy 84.572813 -404.123882) (xy 84.596573 -404.060787)
			(xy 84.627719 -404.000991) (xy 84.665803 -403.945356) (xy 84.687664 -403.91969) (xy 84.693455 -403.912541)
			(xy 84.699971 -403.895353) (xy 84.700364 -403.886162) (xy 84.700364 -403.728682) (xy 84.700812 -403.718551)
			(xy 84.70855 -403.699825) (xy 84.722849 -403.685468) (xy 84.741543 -403.677654) (xy 84.751672 -403.67712)
			(xy 85.467952 -403.67712) (xy 85.478105 -403.677561) (xy 85.496861 -403.685345) (xy 85.511186 -403.699736)
			(xy 85.518884 -403.718527) (xy 85.51926 -403.728682) (xy 85.51926 -403.886162) (xy 85.519698 -403.895346)
			(xy 85.526193 -403.91253) (xy 85.53196 -403.91969) (xy 85.553847 -403.945337) (xy 85.591938 -404.000973)
			(xy 85.62309 -404.060771) (xy 85.646854 -404.123871) (xy 85.66289 -404.189362) (xy 85.670964 -404.256303)
			(xy 85.670962 -404.32373) (xy 85.662884 -404.39067) (xy 85.646845 -404.456161) (xy 85.623076 -404.519259)
			(xy 85.591921 -404.579055) (xy 85.553827 -404.634689) (xy 85.53196 -404.660354) (xy 85.526153 -404.667492)
			(xy 85.519646 -404.684688) (xy 85.51926 -404.693882) (xy 85.51926 -405.186134) (xy 85.519663 -405.195322)
			(xy 85.526183 -405.212506) (xy 85.53196 -405.219662) (xy 85.553819 -405.245331) (xy 85.591911 -405.300964)
			(xy 85.623064 -405.36076) (xy 85.64683 -405.423856) (xy 85.662868 -405.489345) (xy 85.670945 -405.556284)
			(xy 85.670945 -405.623707) (xy 85.662869 -405.690646) (xy 85.646833 -405.756135) (xy 85.623068 -405.819232)
			(xy 85.591916 -405.879028) (xy 85.553825 -405.934661) (xy 85.53196 -405.960326) (xy 85.526165 -405.967472)
			(xy 85.51965 -405.984662) (xy 85.51926 -405.993854) (xy 85.51926 -406.151334) (xy 85.518801 -406.161463)
			(xy 85.511062 -406.180185) (xy 85.496768 -406.19454) (xy 85.478079 -406.202358) (xy 85.467952 -406.202896)
			(xy 84.751672 -406.202896) (xy 84.741516 -406.202501) (xy 84.722762 -406.194696) (xy 84.708439 -406.180291)
			(xy 84.700741 -406.161493) (xy 84.700364 -406.151334) (xy 84.700364 -405.993854) (xy 84.699914 -405.984671)
			(xy 84.693426 -405.967487) (xy 84.687664 -405.960326) (xy 84.665795 -405.934665) (xy 84.627709 -405.879029)
			(xy 84.596561 -405.819232) (xy 84.572799 -405.756135) (xy 84.556765 -405.690645) (xy 84.54869 -405.623707)
			(xy 83.420628 -405.623707) (xy 83.39206 -405.678683) (xy 83.354109 -405.734268) (xy 83.33232 -405.75992)
			(xy 83.326535 -405.767073) (xy 83.320013 -405.784258) (xy 83.31962 -405.793448) (xy 83.31962 -406.286716)
			(xy 83.320018 -406.295905) (xy 83.32654 -406.313089) (xy 83.33232 -406.320244) (xy 83.354077 -406.345921)
			(xy 83.39203 -406.401503) (xy 83.423067 -406.461223) (xy 83.446743 -406.524224) (xy 83.46272 -406.589604)
			(xy 83.470767 -406.656424) (xy 83.47077 -406.723728) (xy 83.470763 -406.723789) (xy 86.748808 -406.723789)
			(xy 86.748811 -406.656363) (xy 86.75689 -406.589422) (xy 86.772929 -406.523931) (xy 86.796697 -406.460833)
			(xy 86.827852 -406.401036) (xy 86.865946 -406.345401) (xy 86.887812 -406.319736) (xy 86.89362 -406.312599)
			(xy 86.900127 -406.295402) (xy 86.900512 -406.286208) (xy 86.900512 -405.793956) (xy 86.90012 -405.784767)
			(xy 86.893594 -405.767583) (xy 86.887812 -405.760428) (xy 86.865944 -405.734766) (xy 86.827854 -405.679131)
			(xy 86.796703 -405.619335) (xy 86.772939 -405.556238) (xy 86.756903 -405.490748) (xy 86.748827 -405.423809)
			(xy 86.748828 -405.356385) (xy 86.756904 -405.289446) (xy 86.77294 -405.223957) (xy 86.796706 -405.16086)
			(xy 86.827857 -405.101063) (xy 86.865947 -405.045429) (xy 86.887812 -405.019764) (xy 86.893608 -405.012618)
			(xy 86.900123 -404.995428) (xy 86.900512 -404.986236) (xy 86.900512 -404.828756) (xy 86.900949 -404.818643)
			(xy 86.908704 -404.799961) (xy 86.923015 -404.785668) (xy 86.941706 -404.777937) (xy 86.95182 -404.777448)
			(xy 87.6681 -404.777448) (xy 87.678202 -404.777984) (xy 87.696871 -404.785712) (xy 87.711163 -404.799993)
			(xy 87.718907 -404.818654) (xy 87.719408 -404.828756) (xy 87.719408 -404.986236) (xy 87.719799 -404.995425)
			(xy 87.726326 -405.01261) (xy 87.732108 -405.019764) (xy 87.753968 -405.045433) (xy 87.792056 -405.101067)
			(xy 87.823206 -405.160863) (xy 87.846971 -405.223959) (xy 87.863006 -405.289448) (xy 87.871082 -405.356385)
			(xy 87.871082 -405.423809) (xy 87.863007 -405.490746) (xy 87.846972 -405.556235) (xy 87.823209 -405.619332)
			(xy 87.792059 -405.679128) (xy 87.753971 -405.734763) (xy 87.732108 -405.760428) (xy 87.726318 -405.767578)
			(xy 87.719799 -405.784765) (xy 87.719408 -405.793956) (xy 87.719408 -406.286208) (xy 87.719813 -406.295396)
			(xy 87.72633 -406.31258) (xy 87.732108 -406.319736) (xy 87.75394 -406.345427) (xy 87.792029 -406.401058)
			(xy 87.823181 -406.460851) (xy 87.846947 -406.523944) (xy 87.862984 -406.58943) (xy 87.871062 -406.656365)
			(xy 87.871065 -406.723729) (xy 91.149127 -406.723729) (xy 91.14913 -406.656423) (xy 91.157177 -406.589598)
			(xy 91.173152 -406.524215) (xy 91.196827 -406.461209) (xy 91.227861 -406.401484) (xy 91.265812 -406.345897)
			(xy 91.2876 -406.320244) (xy 91.293403 -406.313103) (xy 91.299914 -406.295909) (xy 91.3003 -406.286716)
			(xy 91.3003 -405.793448) (xy 91.299867 -405.784263) (xy 91.293369 -405.767079) (xy 91.2876 -405.75992)
			(xy 91.26581 -405.734271) (xy 91.227863 -405.678683) (xy 91.196832 -405.618958) (xy 91.173162 -405.555954)
			(xy 91.15719 -405.490572) (xy 91.149147 -405.423749) (xy 91.149147 -405.356445) (xy 91.157191 -405.289622)
			(xy 91.173163 -405.224241) (xy 91.196835 -405.161236) (xy 91.227866 -405.101512) (xy 91.265813 -405.045925)
			(xy 91.2876 -405.020272) (xy 91.293391 -405.013123) (xy 91.299909 -404.995935) (xy 91.3003 -404.986744)
			(xy 91.3003 -404.828756) (xy 91.300686 -404.818599) (xy 91.308496 -404.799846) (xy 91.322903 -404.785524)
			(xy 91.341703 -404.777826) (xy 91.351862 -404.777448) (xy 92.068142 -404.777448) (xy 92.078272 -404.777892)
			(xy 92.096996 -404.785635) (xy 92.111351 -404.799934) (xy 92.119167 -404.818628) (xy 92.119704 -404.828756)
			(xy 92.119704 -404.986744) (xy 92.120092 -404.995934) (xy 92.126621 -405.013118) (xy 92.132404 -405.020272)
			(xy 92.154186 -405.045928) (xy 92.192133 -405.101515) (xy 92.223164 -405.161238) (xy 92.246835 -405.224242)
			(xy 92.262807 -405.289624) (xy 92.270851 -405.356445) (xy 92.270851 -405.423749) (xy 92.262808 -405.490571)
			(xy 92.246837 -405.555952) (xy 92.223166 -405.618956) (xy 92.220728 -405.623648) (xy 115.349248 -405.623648)
			(xy 115.349249 -405.556343) (xy 115.357293 -405.489521) (xy 115.373266 -405.424139) (xy 115.396938 -405.361134)
			(xy 115.42797 -405.30141) (xy 115.465917 -405.245823) (xy 115.487704 -405.22017) (xy 115.493496 -405.213022)
			(xy 115.500013 -405.195834) (xy 115.500404 -405.186642) (xy 115.500404 -404.693374) (xy 115.500006 -404.684186)
			(xy 115.493484 -404.667001) (xy 115.487704 -404.659846) (xy 115.465939 -404.634176) (xy 115.427992 -404.578591)
			(xy 115.396959 -404.51887) (xy 115.373287 -404.455868) (xy 115.357314 -404.390488) (xy 115.349268 -404.323668)
			(xy 115.349266 -404.256365) (xy 115.357308 -404.189545) (xy 115.373277 -404.124164) (xy 115.396946 -404.061161)
			(xy 115.427975 -404.001437) (xy 115.465919 -403.945851) (xy 115.487704 -403.920198) (xy 115.493484 -403.913041)
			(xy 115.500009 -403.89586) (xy 115.500404 -403.88667) (xy 115.500404 -403.728682) (xy 115.500918 -403.718527)
			(xy 115.508692 -403.699764) (xy 115.523051 -403.685401) (xy 115.541811 -403.677621) (xy 115.551966 -403.67712)
			(xy 116.268246 -403.67712) (xy 116.278404 -403.677595) (xy 116.297171 -403.685382) (xy 116.311534 -403.699752)
			(xy 116.31931 -403.718523) (xy 116.319808 -403.728682) (xy 116.319808 -403.88667) (xy 116.320231 -403.895856)
			(xy 116.326735 -403.91304) (xy 116.332508 -403.920198) (xy 116.354319 -403.945832) (xy 116.392271 -404.00142)
			(xy 116.423306 -404.061145) (xy 116.44698 -404.124152) (xy 116.462953 -404.189537) (xy 116.470996 -404.256363)
			(xy 116.470994 -404.32367) (xy 116.462947 -404.390495) (xy 116.44697 -404.455879) (xy 116.423292 -404.518885)
			(xy 116.392254 -404.578609) (xy 116.354299 -404.634195) (xy 116.332508 -404.659846) (xy 116.32671 -404.66699)
			(xy 116.320196 -404.684181) (xy 116.319808 -404.693374) (xy 116.319808 -405.186642) (xy 116.320196 -405.195832)
			(xy 116.326725 -405.213016) (xy 116.332508 -405.22017) (xy 116.354291 -405.245826) (xy 116.392244 -405.301411)
			(xy 116.42328 -405.361133) (xy 116.446956 -405.424137) (xy 116.462931 -405.48952) (xy 116.470976 -405.556343)
			(xy 116.470977 -405.623648) (xy 116.462932 -405.690471) (xy 116.446958 -405.755854) (xy 116.423284 -405.818858)
			(xy 116.392249 -405.878581) (xy 116.354297 -405.934167) (xy 116.332508 -405.959818) (xy 116.326722 -405.966971)
			(xy 116.320201 -405.984155) (xy 116.319808 -405.993346) (xy 116.319808 -406.151334) (xy 116.319296 -406.161488)
			(xy 116.311519 -406.180249) (xy 116.297159 -406.194612) (xy 116.2784 -406.202393) (xy 116.268246 -406.202896)
			(xy 115.551966 -406.202896) (xy 115.54181 -406.202395) (xy 115.523047 -406.194616) (xy 115.508684 -406.180253)
			(xy 115.500905 -406.16149) (xy 115.500404 -406.151334) (xy 115.500404 -405.993346) (xy 115.499971 -405.984161)
			(xy 115.493473 -405.966977) (xy 115.487704 -405.959818) (xy 115.465911 -405.93417) (xy 115.427965 -405.878582)
			(xy 115.396934 -405.818858) (xy 115.373263 -405.755853) (xy 115.357292 -405.69047) (xy 115.349248 -405.623648)
			(xy 92.220728 -405.623648) (xy 92.192136 -405.67868) (xy 92.15419 -405.734267) (xy 92.132404 -405.75992)
			(xy 92.126617 -405.767072) (xy 92.120096 -405.784257) (xy 92.119704 -405.793448) (xy 92.119704 -406.286716)
			(xy 92.120106 -406.295904) (xy 92.126625 -406.313088) (xy 92.132404 -406.320244) (xy 92.154159 -406.345923)
			(xy 92.192106 -406.401506) (xy 92.223138 -406.461227) (xy 92.246811 -406.524228) (xy 92.262785 -406.589606)
			(xy 92.270831 -406.656425) (xy 92.270834 -406.723727) (xy 92.270826 -406.72379) (xy 117.548838 -406.72379)
			(xy 117.548841 -406.656362) (xy 117.55692 -406.589421) (xy 117.572961 -406.523929) (xy 117.596731 -406.460831)
			(xy 117.627888 -406.401034) (xy 117.665984 -406.3454) (xy 117.687852 -406.319736) (xy 117.693665 -406.312602)
			(xy 117.700168 -406.295403) (xy 117.700552 -406.286208) (xy 117.700552 -405.793956) (xy 117.700151 -405.784768)
			(xy 117.69363 -405.767585) (xy 117.687852 -405.760428) (xy 117.665982 -405.734767) (xy 117.62789 -405.679133)
			(xy 117.596737 -405.619337) (xy 117.572971 -405.556239) (xy 117.556934 -405.490749) (xy 117.548857 -405.42381)
			(xy 117.548858 -405.356384) (xy 117.556935 -405.289445) (xy 117.572972 -405.223955) (xy 117.596739 -405.160858)
			(xy 117.627893 -405.101062) (xy 117.665986 -405.045428) (xy 117.687852 -405.019764) (xy 117.693653 -405.012622)
			(xy 117.700164 -404.995429) (xy 117.700552 -404.986236) (xy 117.700552 -404.828756) (xy 117.701048 -404.81865)
			(xy 117.708791 -404.79998) (xy 117.723084 -404.785689) (xy 117.741754 -404.777947) (xy 117.75186 -404.777448)
			(xy 118.46814 -404.777448) (xy 118.478245 -404.777951) (xy 118.496914 -404.785692) (xy 118.511206 -404.799983)
			(xy 118.518948 -404.818651) (xy 118.519448 -404.828756) (xy 118.519448 -404.986236) (xy 118.519853 -404.995424)
			(xy 118.526372 -405.012607) (xy 118.532148 -405.019764) (xy 118.55401 -405.045432) (xy 118.592102 -405.101065)
			(xy 118.623256 -405.16086) (xy 118.647023 -405.223957) (xy 118.66306 -405.289446) (xy 118.671137 -405.356385)
			(xy 118.671137 -405.423809) (xy 118.663061 -405.490748) (xy 118.647024 -405.556238) (xy 118.623258 -405.619335)
			(xy 118.62098 -405.623708) (xy 119.749017 -405.623708) (xy 119.749017 -405.556283) (xy 119.757094 -405.489345)
			(xy 119.77313 -405.423855) (xy 119.796895 -405.360758) (xy 119.828046 -405.300962) (xy 119.866136 -405.245327)
			(xy 119.888 -405.219662) (xy 119.893795 -405.212516) (xy 119.900311 -405.195326) (xy 119.9007 -405.186134)
			(xy 119.9007 -404.693882) (xy 119.900298 -404.684694) (xy 119.893779 -404.66751) (xy 119.888 -404.660354)
			(xy 119.866158 -404.634671) (xy 119.828068 -404.579039) (xy 119.796917 -404.519245) (xy 119.773151 -404.456151)
			(xy 119.757114 -404.390664) (xy 119.749037 -404.323727) (xy 119.749035 -404.256306) (xy 119.757108 -404.189369)
			(xy 119.773141 -404.123881) (xy 119.796903 -404.060785) (xy 119.828051 -404.000989) (xy 119.866137 -403.945355)
			(xy 119.888 -403.91969) (xy 119.893783 -403.912535) (xy 119.900306 -403.895352) (xy 119.9007 -403.886162)
			(xy 119.9007 -403.728682) (xy 119.90121 -403.718559) (xy 119.908937 -403.699845) (xy 119.923215 -403.685491)
			(xy 119.941888 -403.677665) (xy 119.952008 -403.67712) (xy 120.668288 -403.67712) (xy 120.678412 -403.677526)
			(xy 120.697119 -403.685274) (xy 120.711435 -403.699594) (xy 120.719177 -403.718304) (xy 120.719596 -403.728428)
			(xy 120.719596 -403.886162) (xy 120.720025 -403.895347) (xy 120.726526 -403.912532) (xy 120.732296 -403.91969)
			(xy 120.754182 -403.945337) (xy 120.79227 -404.000974) (xy 120.82342 -404.060773) (xy 120.847183 -404.123872)
			(xy 120.863217 -404.189363) (xy 120.871291 -404.256304) (xy 120.871289 -404.323729) (xy 120.863211 -404.390669)
			(xy 120.847173 -404.456159) (xy 120.823407 -404.519257) (xy 120.792253 -404.579054) (xy 120.754161 -404.634689)
			(xy 120.732296 -404.660354) (xy 120.726494 -404.667495) (xy 120.719983 -404.684689) (xy 120.719596 -404.693882)
			(xy 120.719596 -405.186134) (xy 120.719991 -405.195323) (xy 120.726515 -405.212507) (xy 120.732296 -405.219662)
			(xy 120.754154 -405.245332) (xy 120.792243 -405.300966) (xy 120.823395 -405.360761) (xy 120.847159 -405.423858)
			(xy 120.863195 -405.489346) (xy 120.871272 -405.556284) (xy 120.871272 -405.623707) (xy 120.863197 -405.690645)
			(xy 120.847162 -405.756134) (xy 120.823398 -405.81923) (xy 120.792248 -405.879026) (xy 120.75416 -405.934661)
			(xy 120.732296 -405.960326) (xy 120.726505 -405.967475) (xy 120.719987 -405.984663) (xy 120.719596 -405.993854)
			(xy 120.719596 -406.151334) (xy 120.719102 -406.161458) (xy 120.71137 -406.180174) (xy 120.697087 -406.194527)
			(xy 120.67841 -406.202352) (xy 120.668288 -406.202896) (xy 119.952008 -406.202896) (xy 119.941886 -406.202477)
			(xy 119.923181 -406.194731) (xy 119.908867 -406.180415) (xy 119.901122 -406.16171) (xy 119.9007 -406.151588)
			(xy 119.9007 -405.993854) (xy 119.900264 -405.98467) (xy 119.893768 -405.967485) (xy 119.888 -405.960326)
			(xy 119.86613 -405.934666) (xy 119.828042 -405.87903) (xy 119.796891 -405.819234) (xy 119.773127 -405.756136)
			(xy 119.757092 -405.690646) (xy 119.749017 -405.623708) (xy 118.62098 -405.623708) (xy 118.592105 -405.67913)
			(xy 118.554014 -405.734764) (xy 118.532148 -405.760428) (xy 118.526351 -405.767572) (xy 118.519838 -405.784764)
			(xy 118.519448 -405.793956) (xy 118.519448 -406.286208) (xy 118.519866 -406.295394) (xy 118.526375 -406.312578)
			(xy 118.532148 -406.319736) (xy 118.553982 -406.345426) (xy 118.592075 -406.401056) (xy 118.62323 -406.460848)
			(xy 118.646999 -406.523942) (xy 118.663038 -406.589429) (xy 118.671117 -406.656365) (xy 118.67112 -406.72373)
			(xy 121.949157 -406.72373) (xy 121.94916 -406.656422) (xy 121.957208 -406.589597) (xy 121.973184 -406.524213)
			(xy 121.99686 -406.461207) (xy 122.027897 -406.401483) (xy 122.06585 -406.345896) (xy 122.08764 -406.320244)
			(xy 122.093448 -406.313107) (xy 122.099955 -406.29591) (xy 122.10034 -406.286716) (xy 122.10034 -405.793448)
			(xy 122.099898 -405.784264) (xy 122.093405 -405.76708) (xy 122.08764 -405.75992) (xy 122.065848 -405.734271)
			(xy 122.027899 -405.678684) (xy 121.996866 -405.61896) (xy 121.973194 -405.555955) (xy 121.957221 -405.490573)
			(xy 121.949177 -405.42375) (xy 121.949177 -405.356444) (xy 121.957222 -405.289621) (xy 121.973195 -405.224239)
			(xy 121.996869 -405.161234) (xy 122.027902 -405.101511) (xy 122.065852 -405.045924) (xy 122.08764 -405.020272)
			(xy 122.093436 -405.013127) (xy 122.09995 -404.995936) (xy 122.10034 -404.986744) (xy 122.10034 -404.828756)
			(xy 122.100681 -404.818626) (xy 122.108451 -404.799913) (xy 122.122791 -404.785599) (xy 122.141517 -404.777863)
			(xy 122.151648 -404.777448) (xy 122.868182 -404.777448) (xy 122.878309 -404.777941) (xy 122.897031 -404.785665)
			(xy 122.911388 -404.799949) (xy 122.919207 -404.818632) (xy 122.919744 -404.828756) (xy 122.919744 -404.986744)
			(xy 122.920145 -404.995932) (xy 122.926666 -405.013116) (xy 122.932444 -405.020272) (xy 122.954228 -405.045927)
			(xy 122.992178 -405.101513) (xy 123.023213 -405.161236) (xy 123.046886 -405.22424) (xy 123.06286 -405.289622)
			(xy 123.070905 -405.356444) (xy 123.070905 -405.42375) (xy 123.062861 -405.490572) (xy 123.046888 -405.555954)
			(xy 123.023215 -405.618959) (xy 123.020778 -405.623649) (xy 124.149312 -405.623649) (xy 124.149313 -405.556342)
			(xy 124.157358 -405.489518) (xy 124.173333 -405.424135) (xy 124.197009 -405.36113) (xy 124.228046 -405.301407)
			(xy 124.265998 -405.245822) (xy 124.287788 -405.22017) (xy 124.293578 -405.21302) (xy 124.300097 -405.195833)
			(xy 124.300488 -405.186642) (xy 124.300488 -404.693374) (xy 124.300093 -404.684185) (xy 124.293569 -404.667001)
			(xy 124.287788 -404.659846) (xy 124.26602 -404.634177) (xy 124.228068 -404.578594) (xy 124.197031 -404.518873)
			(xy 124.173355 -404.455871) (xy 124.157379 -404.39049) (xy 124.149332 -404.323669) (xy 124.14933 -404.256364)
			(xy 124.157373 -404.189542) (xy 124.173345 -404.124161) (xy 124.197017 -404.061157) (xy 124.228051 -404.001435)
			(xy 124.266 -403.945849) (xy 124.287788 -403.920198) (xy 124.293567 -403.91304) (xy 124.300092 -403.895859)
			(xy 124.300488 -403.88667) (xy 124.300488 -403.728682) (xy 124.30085 -403.718503) (xy 124.308651 -403.699698)
			(xy 124.323056 -403.685313) (xy 124.34187 -403.677537) (xy 124.35205 -403.67712) (xy 125.06833 -403.67712)
			(xy 125.078487 -403.677608) (xy 125.097254 -403.685389) (xy 125.111617 -403.699756) (xy 125.119394 -403.718524)
			(xy 125.119892 -403.728682) (xy 125.119892 -403.88667) (xy 125.120318 -403.895855) (xy 125.126821 -403.91304)
			(xy 125.132592 -403.920198) (xy 125.1544 -403.945833) (xy 125.192347 -404.001422) (xy 125.223377 -404.061149)
			(xy 125.247047 -404.124155) (xy 125.263018 -404.189539) (xy 125.27106 -404.256363) (xy 125.271058 -404.32367)
			(xy 125.263012 -404.390493) (xy 125.247038 -404.455876) (xy 125.223364 -404.518882) (xy 125.19233 -404.578606)
			(xy 125.15438 -404.634193) (xy 125.132592 -404.659846) (xy 125.126792 -404.666989) (xy 125.12028 -404.684181)
			(xy 125.119892 -404.693374) (xy 125.119892 -405.186642) (xy 125.120284 -405.195831) (xy 125.12681 -405.213015)
			(xy 125.132592 -405.22017) (xy 125.154373 -405.245827) (xy 125.19232 -405.301414) (xy 125.223352 -405.361137)
			(xy 125.247023 -405.424141) (xy 125.262996 -405.489522) (xy 125.27104 -405.556343) (xy 125.271041 -405.623647)
			(xy 125.262998 -405.690469) (xy 125.247026 -405.755851) (xy 125.223355 -405.818855) (xy 125.192325 -405.878578)
			(xy 125.154378 -405.934165) (xy 125.132592 -405.959818) (xy 125.126804 -405.96697) (xy 125.120285 -405.984155)
			(xy 125.119892 -405.993346) (xy 125.119892 -406.151334) (xy 125.119395 -406.16149) (xy 125.111615 -406.180254)
			(xy 125.097251 -406.194617) (xy 125.078486 -406.202396) (xy 125.06833 -406.202896) (xy 124.35205 -406.202896)
			(xy 124.341886 -406.202396) (xy 124.323099 -406.194634) (xy 124.308713 -406.180272) (xy 124.30092 -406.161497)
			(xy 124.300488 -406.151334) (xy 124.300488 -405.993346) (xy 124.300059 -405.984161) (xy 124.293559 -405.966976)
			(xy 124.287788 -405.959818) (xy 124.265993 -405.934171) (xy 124.228041 -405.878585) (xy 124.197005 -405.818861)
			(xy 124.173331 -405.755856) (xy 124.157357 -405.690473) (xy 124.149312 -405.623649) (xy 123.020778 -405.623649)
			(xy 122.992181 -405.678682) (xy 122.954232 -405.734268) (xy 122.932444 -405.75992) (xy 122.92665 -405.767066)
			(xy 122.920135 -405.784256) (xy 122.919744 -405.793448) (xy 122.919744 -406.286716) (xy 122.920159 -406.295902)
			(xy 122.926671 -406.313086) (xy 122.932444 -406.320244) (xy 122.954201 -406.345922) (xy 122.992152 -406.401504)
			(xy 123.023187 -406.461224) (xy 123.046862 -406.524225) (xy 123.062838 -406.589605) (xy 123.070885 -406.656425)
			(xy 123.070888 -406.723727) (xy 123.070881 -406.723789) (xy 126.348926 -406.723789) (xy 126.348929 -406.656363)
			(xy 126.357008 -406.589421) (xy 126.373048 -406.52393) (xy 126.396818 -406.460832) (xy 126.427974 -406.401035)
			(xy 126.466069 -406.345401) (xy 126.487936 -406.319736) (xy 126.493747 -406.312601) (xy 126.500252 -406.295403)
			(xy 126.500636 -406.286208) (xy 126.500636 -405.793956) (xy 126.500239 -405.784768) (xy 126.493715 -405.767584)
			(xy 126.487936 -405.760428) (xy 126.466067 -405.734767) (xy 126.427976 -405.679132) (xy 126.396823 -405.619336)
			(xy 126.373058 -405.556239) (xy 126.357022 -405.490749) (xy 126.348945 -405.423809) (xy 126.348946 -405.356385)
			(xy 126.357023 -405.289445) (xy 126.37306 -405.223956) (xy 126.396826 -405.160859) (xy 126.427979 -405.101062)
			(xy 126.466071 -405.045429) (xy 126.487936 -405.019764) (xy 126.493735 -405.012621) (xy 126.500247 -404.995429)
			(xy 126.500636 -404.986236) (xy 126.500636 -404.828756) (xy 126.50105 -404.81864) (xy 126.508809 -404.799954)
			(xy 126.523128 -404.785659) (xy 126.541827 -404.777933) (xy 126.551944 -404.777448) (xy 127.268224 -404.777448)
			(xy 127.278328 -404.777964) (xy 127.296997 -404.7857) (xy 127.311289 -404.799986) (xy 127.319032 -404.818652)
			(xy 127.319532 -404.828756) (xy 127.319532 -404.986236) (xy 127.31994 -404.995423) (xy 127.326457 -405.012607)
			(xy 127.332232 -405.019764) (xy 127.354091 -405.045433) (xy 127.392178 -405.101068) (xy 127.423327 -405.160864)
			(xy 127.44709 -405.22396) (xy 127.463125 -405.289448) (xy 127.4712 -405.356386) (xy 127.471201 -405.423808)
			(xy 127.463126 -405.490746) (xy 127.447092 -405.556234) (xy 127.423329 -405.619331) (xy 127.42108 -405.623649)
			(xy 128.549103 -405.623649) (xy 128.549104 -405.556342) (xy 128.557149 -405.489519) (xy 128.573124 -405.424136)
			(xy 128.596799 -405.361131) (xy 128.627835 -405.301407) (xy 128.665787 -405.245822) (xy 128.687576 -405.22017)
			(xy 128.693365 -405.213019) (xy 128.699885 -405.195833) (xy 128.700276 -405.186642) (xy 128.700276 -404.693374)
			(xy 128.699884 -404.684185) (xy 128.693358 -404.667) (xy 128.687576 -404.659846) (xy 128.665809 -404.634177)
			(xy 128.627857 -404.578593) (xy 128.596821 -404.518873) (xy 128.573145 -404.45587) (xy 128.557169 -404.39049)
			(xy 128.549123 -404.323669) (xy 128.549121 -404.256365) (xy 128.557164 -404.189543) (xy 128.573135 -404.124161)
			(xy 128.596807 -404.061158) (xy 128.62784 -404.001435) (xy 128.665789 -403.94585) (xy 128.687576 -403.920198)
			(xy 128.693353 -403.913039) (xy 128.69988 -403.895859) (xy 128.700276 -403.88667) (xy 128.700276 -403.728682)
			(xy 128.70065 -403.718505) (xy 128.708448 -403.699702) (xy 128.722849 -403.685317) (xy 128.74166 -403.677539)
			(xy 128.751838 -403.67712) (xy 129.468118 -403.67712) (xy 129.478275 -403.677618) (xy 129.497041 -403.685395)
			(xy 129.511405 -403.699759) (xy 129.519182 -403.718525) (xy 129.51968 -403.728682) (xy 129.51968 -403.88667)
			(xy 129.520109 -403.895855) (xy 129.52661 -403.913039) (xy 129.53238 -403.920198) (xy 129.554189 -403.945833)
			(xy 129.592136 -404.001422) (xy 129.623167 -404.061148) (xy 129.646838 -404.124155) (xy 129.662809 -404.189539)
			(xy 129.670851 -404.256363) (xy 129.670849 -404.32367) (xy 129.662803 -404.390494) (xy 129.646828 -404.455877)
			(xy 129.623154 -404.518882) (xy 129.592119 -404.578606) (xy 129.554169 -404.634194) (xy 129.53238 -404.659846)
			(xy 129.526579 -404.666988) (xy 129.520068 -404.684181) (xy 129.51968 -404.693374) (xy 129.51968 -405.186642)
			(xy 129.520074 -405.195831) (xy 129.5266 -405.213015) (xy 129.53238 -405.22017) (xy 129.554161 -405.245827)
			(xy 129.592109 -405.301413) (xy 129.623142 -405.361136) (xy 129.646814 -405.42414) (xy 129.662787 -405.489522)
			(xy 129.670831 -405.556343) (xy 129.670832 -405.623648) (xy 129.662788 -405.690469) (xy 129.646817 -405.755851)
			(xy 129.623145 -405.818855) (xy 129.592114 -405.878579) (xy 129.554167 -405.934166) (xy 129.53238 -405.959818)
			(xy 129.526591 -405.966968) (xy 129.520072 -405.984155) (xy 129.51968 -405.993346) (xy 129.51968 -406.151334)
			(xy 129.519195 -406.161492) (xy 129.511413 -406.180258) (xy 129.497045 -406.194622) (xy 129.478276 -406.202398)
			(xy 129.468118 -406.202896) (xy 128.751838 -406.202896) (xy 128.741673 -406.202406) (xy 128.722886 -406.19464)
			(xy 128.708501 -406.180275) (xy 128.700708 -406.161498) (xy 128.700276 -406.151334) (xy 128.700276 -405.993346)
			(xy 128.699849 -405.984161) (xy 128.693347 -405.966976) (xy 128.687576 -405.959818) (xy 128.665781 -405.934171)
			(xy 128.62783 -405.878585) (xy 128.596795 -405.818861) (xy 128.573121 -405.755856) (xy 128.557148 -405.690472)
			(xy 128.549103 -405.623649) (xy 127.42108 -405.623649) (xy 127.392181 -405.679127) (xy 127.354095 -405.734762)
			(xy 127.332232 -405.760428) (xy 127.326433 -405.767571) (xy 127.319922 -405.784763) (xy 127.319532 -405.793956)
			(xy 127.319532 -406.286208) (xy 127.319954 -406.295394) (xy 127.326461 -406.312577) (xy 127.332232 -406.319736)
			(xy 127.354063 -406.345428) (xy 127.392151 -406.401059) (xy 127.423301 -406.460852) (xy 127.447066 -406.523945)
			(xy 127.463103 -406.589431) (xy 127.471181 -406.656366) (xy 127.471183 -406.72373) (xy 130.749245 -406.72373)
			(xy 130.749248 -406.656422) (xy 130.757295 -406.589598) (xy 130.773271 -406.524214) (xy 130.796947 -406.461208)
			(xy 130.827983 -406.401484) (xy 130.865935 -406.345896) (xy 130.887724 -406.320244) (xy 130.89353 -406.313105)
			(xy 130.900038 -406.29591) (xy 130.900424 -406.286716) (xy 130.900424 -405.793448) (xy 130.899985 -405.784264)
			(xy 130.893491 -405.76708) (xy 130.887724 -405.75992) (xy 130.865933 -405.734271) (xy 130.827985 -405.678684)
			(xy 130.796953 -405.61896) (xy 130.773281 -405.555955) (xy 130.757309 -405.490572) (xy 130.749265 -405.42375)
			(xy 130.749265 -405.356444) (xy 130.75731 -405.289622) (xy 130.773283 -405.22424) (xy 130.796955 -405.161235)
			(xy 130.827988 -405.101511) (xy 130.865936 -405.045924) (xy 130.887724 -405.020272) (xy 130.893518 -405.013125)
			(xy 130.900033 -404.995936) (xy 130.900424 -404.986744) (xy 130.900424 -404.828756) (xy 130.900786 -404.818596)
			(xy 130.908601 -404.799838) (xy 130.923016 -404.785515) (xy 130.941823 -404.777822) (xy 130.951986 -404.777448)
			(xy 131.668266 -404.777448) (xy 131.678391 -404.777955) (xy 131.697113 -404.785673) (xy 131.711471 -404.799953)
			(xy 131.71929 -404.818633) (xy 131.719828 -404.828756) (xy 131.719828 -404.986744) (xy 131.720211 -404.995934)
			(xy 131.726743 -405.013119) (xy 131.732528 -405.020272) (xy 131.754313 -405.045927) (xy 131.792264 -405.101512)
			(xy 131.823299 -405.161235) (xy 131.846974 -405.224239) (xy 131.862948 -405.289622) (xy 131.870993 -405.356444)
			(xy 131.870993 -405.42375) (xy 131.862949 -405.490573) (xy 131.846975 -405.555955) (xy 131.823302 -405.618959)
			(xy 131.792267 -405.678683) (xy 131.754316 -405.734268) (xy 131.732528 -405.75992) (xy 131.726732 -405.767065)
			(xy 131.720219 -405.784256) (xy 131.719828 -405.793448) (xy 131.719828 -406.286716) (xy 131.720224 -406.295905)
			(xy 131.726747 -406.313089) (xy 131.732528 -406.320244) (xy 131.754285 -406.345922) (xy 131.792237 -406.401504)
			(xy 131.823274 -406.461223) (xy 131.84695 -406.524225) (xy 131.862926 -406.589604) (xy 131.870973 -406.656424)
			(xy 131.870976 -406.723728) (xy 131.862934 -406.790548) (xy 131.846964 -406.855929) (xy 131.823293 -406.918933)
			(xy 131.792262 -406.978655) (xy 131.754315 -407.03424) (xy 131.732528 -407.059892) (xy 131.726744 -407.067045)
			(xy 131.720224 -407.08423) (xy 131.719828 -407.09342) (xy 131.719828 -407.251408) (xy 131.719385 -407.261559)
			(xy 131.711592 -407.280306) (xy 131.697203 -407.294628) (xy 131.678419 -407.302333) (xy 131.668266 -407.302716)
			(xy 130.951986 -407.302716) (xy 130.941853 -407.302283) (xy 130.923123 -407.294543) (xy 130.908766 -407.28024)
			(xy 130.900955 -407.261539) (xy 130.900424 -407.251408) (xy 130.900424 -407.09342) (xy 130.899999 -407.084235)
			(xy 130.893495 -407.06705) (xy 130.887724 -407.059892) (xy 130.865905 -407.034266) (xy 130.827958 -406.978675)
			(xy 130.796927 -406.918948) (xy 130.773257 -406.85594) (xy 130.757287 -406.790555) (xy 130.749245 -406.72373)
			(xy 127.471183 -406.72373) (xy 127.471183 -406.723786) (xy 127.463111 -406.790722) (xy 127.44708 -406.856209)
			(xy 127.423321 -406.919304) (xy 127.392176 -406.9791) (xy 127.354093 -407.034734) (xy 127.332232 -407.0604)
			(xy 127.326445 -407.067551) (xy 127.319926 -407.084737) (xy 127.319532 -407.093928) (xy 127.319532 -407.251408)
			(xy 127.319022 -407.261513) (xy 127.311288 -407.280185) (xy 127.296999 -407.294479) (xy 127.278329 -407.302219)
			(xy 127.268224 -407.302716) (xy 126.551944 -407.302716) (xy 126.541826 -407.302248) (xy 126.523127 -407.294518)
			(xy 126.508812 -407.280217) (xy 126.501062 -407.261525) (xy 126.500636 -407.251408) (xy 126.500636 -407.093928)
			(xy 126.500204 -407.084743) (xy 126.493705 -407.067559) (xy 126.487936 -407.0604) (xy 126.466039 -407.034761)
			(xy 126.427949 -406.979124) (xy 126.396798 -406.919324) (xy 126.373034 -406.856224) (xy 126.357 -406.790731)
			(xy 126.348926 -406.723789) (xy 123.070881 -406.723789) (xy 123.062847 -406.790548) (xy 123.046877 -406.855929)
			(xy 123.023207 -406.918932) (xy 122.992176 -406.978654) (xy 122.95423 -407.03424) (xy 122.932444 -407.059892)
			(xy 122.926661 -407.067047) (xy 122.92014 -407.08423) (xy 122.919744 -407.09342) (xy 122.919744 -407.251408)
			(xy 122.919222 -407.261512) (xy 122.91149 -407.280182) (xy 122.897205 -407.294475) (xy 122.878539 -407.302217)
			(xy 122.868436 -407.302716) (xy 122.151902 -407.302716) (xy 122.14177 -407.30227) (xy 122.123041 -407.294535)
			(xy 122.108683 -407.280236) (xy 122.100871 -407.261538) (xy 122.10034 -407.251408) (xy 122.10034 -407.09342)
			(xy 122.099911 -407.084235) (xy 122.09341 -407.067051) (xy 122.08764 -407.059892) (xy 122.065821 -407.034266)
			(xy 122.027873 -406.978676) (xy 121.996841 -406.918949) (xy 121.97317 -406.855941) (xy 121.957199 -406.790555)
			(xy 121.949157 -406.72373) (xy 118.67112 -406.72373) (xy 118.67112 -406.723787) (xy 118.663047 -406.790724)
			(xy 118.647013 -406.856212) (xy 118.62325 -406.919308) (xy 118.5921 -406.979103) (xy 118.554012 -407.034736)
			(xy 118.532148 -407.0604) (xy 118.526362 -407.067553) (xy 118.519843 -407.084738) (xy 118.519448 -407.093928)
			(xy 118.519448 -407.251408) (xy 118.518922 -407.261511) (xy 118.511191 -407.28018) (xy 118.496907 -407.294473)
			(xy 118.478243 -407.302216) (xy 118.46814 -407.302716) (xy 117.75186 -407.302716) (xy 117.741751 -407.302248)
			(xy 117.723075 -407.2945) (xy 117.708782 -407.280198) (xy 117.701046 -407.261518) (xy 117.700552 -407.251408)
			(xy 117.700552 -407.093928) (xy 117.700117 -407.084744) (xy 117.693619 -407.06756) (xy 117.687852 -407.0604)
			(xy 117.665955 -407.034762) (xy 117.627864 -406.979124) (xy 117.596711 -406.919325) (xy 117.572947 -406.856225)
			(xy 117.556912 -406.790732) (xy 117.548838 -406.72379) (xy 92.270826 -406.72379) (xy 92.262793 -406.790546)
			(xy 92.246825 -406.855926) (xy 92.223158 -406.918929) (xy 92.192131 -406.978652) (xy 92.154188 -407.034239)
			(xy 92.132404 -407.059892) (xy 92.126629 -407.067052) (xy 92.120101 -407.084231) (xy 92.119704 -407.09342)
			(xy 92.119704 -407.251408) (xy 92.119285 -407.261562) (xy 92.111487 -407.280314) (xy 92.09709 -407.294637)
			(xy 92.078298 -407.302337) (xy 92.068142 -407.302716) (xy 91.351862 -407.302716) (xy 91.341727 -407.302303)
			(xy 91.322997 -407.294555) (xy 91.308641 -407.280246) (xy 91.30083 -407.261541) (xy 91.3003 -407.251408)
			(xy 91.3003 -407.09342) (xy 91.29988 -407.084234) (xy 91.293373 -407.067049) (xy 91.2876 -407.059892)
			(xy 91.265782 -407.034265) (xy 91.227837 -406.978674) (xy 91.196807 -406.918947) (xy 91.173138 -406.855939)
			(xy 91.157168 -406.790554) (xy 91.149127 -406.723729) (xy 87.871065 -406.723729) (xy 87.871065 -406.723786)
			(xy 87.862993 -406.790722) (xy 87.846961 -406.85621) (xy 87.823201 -406.919305) (xy 87.792054 -406.9791)
			(xy 87.75397 -407.034735) (xy 87.732108 -407.0604) (xy 87.72633 -407.067558) (xy 87.719804 -407.084739)
			(xy 87.719408 -407.093928) (xy 87.719408 -407.251408) (xy 87.718921 -407.261516) (xy 87.711183 -407.280193)
			(xy 87.696886 -407.294487) (xy 87.678208 -407.302223) (xy 87.6681 -407.302716) (xy 86.95182 -407.302716)
			(xy 86.941701 -407.302268) (xy 86.923001 -407.29453) (xy 86.908686 -407.280223) (xy 86.900937 -407.261527)
			(xy 86.900512 -407.251408) (xy 86.900512 -407.093928) (xy 86.900086 -407.084743) (xy 86.893583 -407.067558)
			(xy 86.887812 -407.0604) (xy 86.865916 -407.034761) (xy 86.827828 -406.979123) (xy 86.796678 -406.919323)
			(xy 86.772915 -406.856223) (xy 86.756881 -406.790731) (xy 86.748808 -406.723789) (xy 83.470763 -406.723789)
			(xy 83.462728 -406.790549) (xy 83.446757 -406.85593) (xy 83.423086 -406.918933) (xy 83.392055 -406.978655)
			(xy 83.354107 -407.03424) (xy 83.33232 -407.059892) (xy 83.326547 -407.067054) (xy 83.320017 -407.084231)
			(xy 83.31962 -407.09342) (xy 83.31962 -407.251408) (xy 83.319185 -407.26156) (xy 83.311391 -407.280309)
			(xy 83.296998 -407.294631) (xy 83.278212 -407.302334) (xy 83.268058 -407.302716) (xy 82.551778 -407.302716)
			(xy 82.541644 -407.30229) (xy 82.522914 -407.294547) (xy 82.508557 -407.280242) (xy 82.500747 -407.26154)
			(xy 82.500216 -407.251408) (xy 82.500216 -407.09342) (xy 82.499792 -407.084234) (xy 82.493288 -407.06705)
			(xy 82.487516 -407.059892) (xy 82.465698 -407.034265) (xy 82.427751 -406.978675) (xy 82.396721 -406.918947)
			(xy 82.373051 -406.85594) (xy 82.35708 -406.790555) (xy 82.349039 -406.72373) (xy 79.070977 -406.72373)
			(xy 79.070977 -406.723786) (xy 79.062905 -406.790722) (xy 79.046874 -406.856209) (xy 79.023114 -406.919304)
			(xy 78.991969 -406.9791) (xy 78.953885 -407.034734) (xy 78.932024 -407.0604) (xy 78.926248 -407.06756)
			(xy 78.91972 -407.084739) (xy 78.919324 -407.093928) (xy 78.919324 -407.251408) (xy 78.918822 -407.261514)
			(xy 78.911086 -407.280188) (xy 78.896795 -407.294482) (xy 78.878122 -407.30222) (xy 78.868016 -407.302716)
			(xy 78.151736 -407.302716) (xy 78.141618 -407.302255) (xy 78.122918 -407.294521) (xy 78.108603 -407.280219)
			(xy 78.100854 -407.261526) (xy 78.100428 -407.251408) (xy 78.100428 -407.093928) (xy 78.099998 -407.084743)
			(xy 78.093497 -407.067559) (xy 78.087728 -407.0604) (xy 78.065832 -407.034761) (xy 78.027742 -406.979124)
			(xy 77.996591 -406.919324) (xy 77.972828 -406.856224) (xy 77.956793 -406.790731) (xy 77.94872 -406.723789)
			(xy 74.670675 -406.723789) (xy 74.662641 -406.790548) (xy 74.64667 -406.855929) (xy 74.623 -406.918932)
			(xy 74.591969 -406.978655) (xy 74.554022 -407.03424) (xy 74.532236 -407.059892) (xy 74.526453 -407.067046)
			(xy 74.519932 -407.08423) (xy 74.519536 -407.09342) (xy 74.519536 -407.251408) (xy 74.519085 -407.261558)
			(xy 74.511294 -407.280304) (xy 74.496907 -407.294625) (xy 74.478126 -407.302331) (xy 74.467974 -407.302716)
			(xy 73.751694 -407.302716) (xy 73.741562 -407.302277) (xy 73.722832 -407.294539) (xy 73.708474 -407.280238)
			(xy 73.700663 -407.261538) (xy 73.700132 -407.251408) (xy 73.700132 -407.09342) (xy 73.699705 -407.084235)
			(xy 73.693202 -407.067051) (xy 73.687432 -407.059892) (xy 73.665613 -407.034266) (xy 73.627666 -406.978675)
			(xy 73.596634 -406.918948) (xy 73.572963 -406.85594) (xy 73.556993 -406.790555) (xy 73.548951 -406.72373)
			(xy 66.525648 -406.72373) (xy 66.525648 -409.523886) (xy 71.34879 -409.523886) (xy 71.348793 -409.45646)
			(xy 71.356872 -409.389519) (xy 71.372911 -409.324028) (xy 71.396679 -409.26093) (xy 71.427834 -409.201133)
			(xy 71.465926 -409.145497) (xy 71.487792 -409.119832) (xy 71.493599 -409.112694) (xy 71.500108 -409.095498)
			(xy 71.500492 -409.086304) (xy 71.500492 -408.594052) (xy 71.500059 -408.584867) (xy 71.493561 -408.567682)
			(xy 71.487792 -408.560524) (xy 71.46592 -408.534865) (xy 71.427833 -408.479229) (xy 71.396683 -408.419432)
			(xy 71.372919 -408.356335) (xy 71.356885 -408.290845) (xy 71.348809 -408.223906) (xy 71.34881 -408.156482)
			(xy 71.356887 -408.089543) (xy 71.372923 -408.024054) (xy 71.396688 -407.960957) (xy 71.427839 -407.90116)
			(xy 71.465928 -407.845525) (xy 71.487792 -407.81986) (xy 71.493587 -407.812714) (xy 71.500103 -407.795524)
			(xy 71.500492 -407.786332) (xy 71.500492 -407.628852) (xy 71.500946 -407.618741) (xy 71.508698 -407.600063)
			(xy 71.523004 -407.585771) (xy 71.541689 -407.578036) (xy 71.5518 -407.577544) (xy 72.26808 -407.577544)
			(xy 72.278181 -407.5781) (xy 72.296848 -407.585821) (xy 72.311141 -407.600095) (xy 72.318887 -407.618752)
			(xy 72.319388 -407.628852) (xy 72.319388 -407.786332) (xy 72.319785 -407.795521) (xy 72.326308 -407.812705)
			(xy 72.332088 -407.81986) (xy 72.353945 -407.845532) (xy 72.392034 -407.901165) (xy 72.423186 -407.96096)
			(xy 72.446951 -408.024056) (xy 72.462988 -408.089545) (xy 72.471064 -408.156482) (xy 72.471065 -408.223906)
			(xy 72.46299 -408.290844) (xy 72.446955 -408.356332) (xy 72.423191 -408.419429) (xy 72.39204 -408.479225)
			(xy 72.353952 -408.534859) (xy 72.332088 -408.560524) (xy 72.326297 -408.567673) (xy 72.31978 -408.584861)
			(xy 72.319388 -408.594052) (xy 72.319388 -409.086304) (xy 72.319799 -409.095491) (xy 72.326313 -409.112675)
			(xy 72.332088 -409.119832) (xy 72.353917 -409.145526) (xy 72.392008 -409.201156) (xy 72.423161 -409.260948)
			(xy 72.446927 -409.324042) (xy 72.462966 -409.389527) (xy 72.471045 -409.456462) (xy 72.471048 -409.523884)
			(xy 72.462975 -409.59082) (xy 72.446943 -409.656307) (xy 72.423183 -409.719402) (xy 72.392035 -409.779197)
			(xy 72.35395 -409.834831) (xy 72.332088 -409.860496) (xy 72.326309 -409.867654) (xy 72.319784 -409.884835)
			(xy 72.319388 -409.894024) (xy 72.319388 -410.051504) (xy 72.318987 -410.061628) (xy 72.311235 -410.080334)
			(xy 72.296914 -410.094649) (xy 72.278204 -410.102392) (xy 72.26808 -410.102812) (xy 71.5518 -410.102812)
			(xy 71.541693 -410.102315) (xy 71.523017 -410.09458) (xy 71.508723 -410.080286) (xy 71.500986 -410.061611)
			(xy 71.500492 -410.051504) (xy 71.500492 -409.894024) (xy 71.500072 -409.884838) (xy 71.493565 -409.867653)
			(xy 71.487792 -409.860496) (xy 71.465893 -409.83486) (xy 71.427806 -409.779221) (xy 71.396657 -409.719421)
			(xy 71.372895 -409.65632) (xy 71.356863 -409.590827) (xy 71.34879 -409.523886) (xy 66.525648 -409.523886)
			(xy 66.525648 -410.623641) (xy 73.548963 -410.623641) (xy 73.548964 -410.556335) (xy 73.55701 -410.489511)
			(xy 73.572984 -410.424128) (xy 73.596658 -410.361123) (xy 73.627693 -410.301399) (xy 73.665643 -410.245812)
			(xy 73.687432 -410.22016) (xy 73.693232 -410.213017) (xy 73.699744 -410.195825) (xy 73.700132 -410.186632)
			(xy 73.700132 -409.693364) (xy 73.699732 -409.684176) (xy 73.69321 -409.666992) (xy 73.687432 -409.659836)
			(xy 73.665656 -409.634174) (xy 73.627707 -409.578589) (xy 73.596674 -409.518867) (xy 73.573001 -409.455863)
			(xy 73.557027 -409.390482) (xy 73.548982 -409.323661) (xy 73.548981 -409.256357) (xy 73.557024 -409.189535)
			(xy 73.572995 -409.124154) (xy 73.596667 -409.06115) (xy 73.627698 -409.001427) (xy 73.665645 -408.94584)
			(xy 73.687432 -408.920188) (xy 73.69322 -408.913037) (xy 73.699739 -408.895851) (xy 73.700132 -408.88666)
			(xy 73.700132 -408.728672) (xy 73.700499 -408.718512) (xy 73.70831 -408.699753) (xy 73.722724 -408.685429)
			(xy 73.741532 -408.677736) (xy 73.751694 -408.677364) (xy 74.467974 -408.677364) (xy 74.478102 -408.677848)
			(xy 74.496827 -408.685572) (xy 74.511185 -408.69986) (xy 74.519001 -408.718546) (xy 74.519536 -408.728672)
			(xy 74.519536 -408.88666) (xy 74.51998 -408.895843) (xy 74.526472 -408.913027) (xy 74.532236 -408.920188)
			(xy 74.554036 -408.94583) (xy 74.591986 -409.001418) (xy 74.62302 -409.061142) (xy 74.646694 -409.124148)
			(xy 74.662666 -409.189532) (xy 74.67071 -409.256356) (xy 74.670709 -409.323662) (xy 74.662663 -409.390486)
			(xy 74.646688 -409.455869) (xy 74.623013 -409.518874) (xy 74.620439 -409.523827) (xy 75.749085 -409.523827)
			(xy 75.749088 -409.456519) (xy 75.757137 -409.389693) (xy 75.773115 -409.324308) (xy 75.796793 -409.261302)
			(xy 75.827833 -409.201578) (xy 75.865789 -409.145992) (xy 75.88758 -409.12034) (xy 75.893382 -409.113199)
			(xy 75.899894 -409.096005) (xy 75.90028 -409.086812) (xy 75.90028 -408.593544) (xy 75.899853 -408.584358)
			(xy 75.893352 -408.567174) (xy 75.88758 -408.560016) (xy 75.865783 -408.534371) (xy 75.827832 -408.478784)
			(xy 75.796797 -408.41906) (xy 75.773123 -408.356055) (xy 75.757149 -408.290671) (xy 75.749105 -408.223847)
			(xy 75.749106 -408.156541) (xy 75.757151 -408.089717) (xy 75.773126 -408.024334) (xy 75.796802 -407.961329)
			(xy 75.827838 -407.901605) (xy 75.865791 -407.84602) (xy 75.88758 -407.820368) (xy 75.89337 -407.813218)
			(xy 75.899889 -407.796031) (xy 75.90028 -407.78684) (xy 75.90028 -407.628852) (xy 75.900682 -407.618697)
			(xy 75.90849 -407.599948) (xy 75.922892 -407.585627) (xy 75.941685 -407.577925) (xy 75.951842 -407.577544)
			(xy 76.668122 -407.577544) (xy 76.678251 -407.578008) (xy 76.696973 -407.585744) (xy 76.711329 -407.600037)
			(xy 76.719147 -407.618726) (xy 76.719684 -407.628852) (xy 76.719684 -407.78684) (xy 76.720078 -407.796029)
			(xy 76.726603 -407.813213) (xy 76.732384 -407.820368) (xy 76.754163 -407.846027) (xy 76.792111 -407.901613)
			(xy 76.823143 -407.961336) (xy 76.846815 -408.024339) (xy 76.862788 -408.08972) (xy 76.870833 -408.156542)
			(xy 76.870833 -408.223846) (xy 76.86279 -408.290668) (xy 76.846819 -408.356049) (xy 76.823148 -408.419053)
			(xy 76.792117 -408.478777) (xy 76.754171 -408.534364) (xy 76.732384 -408.560016) (xy 76.726596 -408.567167)
			(xy 76.720077 -408.584353) (xy 76.719684 -408.593544) (xy 76.719684 -409.086812) (xy 76.720092 -409.095999)
			(xy 76.726607 -409.113184) (xy 76.732384 -409.12034) (xy 76.754135 -409.146022) (xy 76.792084 -409.201605)
			(xy 76.823117 -409.261324) (xy 76.846791 -409.324325) (xy 76.862766 -409.389703) (xy 76.870812 -409.456522)
			(xy 76.870816 -409.523824) (xy 76.862775 -409.590644) (xy 76.846807 -409.656023) (xy 76.823139 -409.719026)
			(xy 76.792112 -409.778749) (xy 76.754169 -409.834335) (xy 76.732384 -409.859988) (xy 76.726566 -409.867118)
			(xy 76.720065 -409.88432) (xy 76.719684 -409.893516) (xy 76.719684 -410.051504) (xy 76.719281 -410.06166)
			(xy 76.711481 -410.080416) (xy 76.697079 -410.09474) (xy 76.678281 -410.102436) (xy 76.668122 -410.102812)
			(xy 75.951842 -410.102812) (xy 75.941724 -410.10224) (xy 75.923014 -410.094536) (xy 75.908658 -410.080276)
			(xy 75.900828 -410.061618) (xy 75.90028 -410.051504) (xy 75.90028 -409.893516) (xy 75.899867 -409.884329)
			(xy 75.893356 -409.867144) (xy 75.88758 -409.859988) (xy 75.865756 -409.834365) (xy 75.827805 -409.778776)
			(xy 75.796771 -409.719048) (xy 75.773099 -409.65604) (xy 75.757127 -409.590654) (xy 75.749085 -409.523827)
			(xy 74.620439 -409.523827) (xy 74.591977 -409.578598) (xy 74.554025 -409.634184) (xy 74.532236 -409.659836)
			(xy 74.526434 -409.666977) (xy 74.519924 -409.684171) (xy 74.519536 -409.693364) (xy 74.519536 -410.186632)
			(xy 74.519945 -410.195819) (xy 74.526461 -410.213002) (xy 74.532236 -410.22016) (xy 74.554009 -410.245825)
			(xy 74.59196 -410.301409) (xy 74.622995 -410.36113) (xy 74.64667 -410.424133) (xy 74.662644 -410.489514)
			(xy 74.67069 -410.556336) (xy 74.670692 -410.62364) (xy 74.670685 -410.623701) (xy 77.948731 -410.623701)
			(xy 77.948732 -410.556275) (xy 77.95681 -410.489335) (xy 77.972848 -410.423845) (xy 77.996615 -410.360747)
			(xy 78.02777 -410.300951) (xy 78.065862 -410.245317) (xy 78.087728 -410.219652) (xy 78.093531 -410.212512)
			(xy 78.100041 -410.195317) (xy 78.100428 -410.186124) (xy 78.100428 -409.693872) (xy 78.100025 -409.684684)
			(xy 78.093506 -409.6675) (xy 78.087728 -409.660344) (xy 78.065875 -409.63467) (xy 78.027784 -409.579037)
			(xy 77.996631 -409.519242) (xy 77.972865 -409.456147) (xy 77.956828 -409.390658) (xy 77.948751 -409.323721)
			(xy 77.94875 -409.256297) (xy 77.956825 -409.189359) (xy 77.97286 -409.123871) (xy 77.996624 -409.060774)
			(xy 78.027775 -409.000979) (xy 78.065864 -408.945345) (xy 78.087728 -408.91968) (xy 78.093519 -408.912531)
			(xy 78.100036 -408.895343) (xy 78.100428 -408.886152) (xy 78.100428 -408.728672) (xy 78.100794 -408.718544)
			(xy 78.108556 -408.699835) (xy 78.122888 -408.68552) (xy 78.141608 -408.677781) (xy 78.151736 -408.677364)
			(xy 78.868016 -408.677364) (xy 78.878121 -408.677871) (xy 78.896793 -408.685608) (xy 78.911086 -408.699897)
			(xy 78.918826 -408.718567) (xy 78.919324 -408.728672) (xy 78.919324 -408.886152) (xy 78.919752 -408.895337)
			(xy 78.926253 -408.912522) (xy 78.932024 -408.91968) (xy 78.953899 -408.945336) (xy 78.991986 -409.000972)
			(xy 79.023135 -409.06077) (xy 79.046897 -409.123868) (xy 79.062931 -409.189358) (xy 79.071005 -409.256297)
			(xy 79.071004 -409.323721) (xy 79.062928 -409.39066) (xy 79.046892 -409.456149) (xy 79.023127 -409.519246)
			(xy 79.02071 -409.523886) (xy 80.148878 -409.523886) (xy 80.148881 -409.45646) (xy 80.15696 -409.38952)
			(xy 80.172999 -409.324029) (xy 80.196766 -409.260931) (xy 80.227919 -409.201133) (xy 80.266011 -409.145498)
			(xy 80.287876 -409.119832) (xy 80.293681 -409.112693) (xy 80.300191 -409.095498) (xy 80.300576 -409.086304)
			(xy 80.300576 -408.594052) (xy 80.300146 -408.584867) (xy 80.293647 -408.567682) (xy 80.287876 -408.560524)
			(xy 80.266005 -408.534865) (xy 80.227918 -408.479229) (xy 80.196769 -408.419432) (xy 80.173006 -408.356334)
			(xy 80.156972 -408.290844) (xy 80.148897 -408.223906) (xy 80.148898 -408.156482) (xy 80.156974 -408.089544)
			(xy 80.17301 -408.024055) (xy 80.196774 -407.960957) (xy 80.227924 -407.901161) (xy 80.266012 -407.845526)
			(xy 80.287876 -407.81986) (xy 80.293669 -407.812712) (xy 80.300187 -407.795524) (xy 80.300576 -407.786332)
			(xy 80.300576 -407.628852) (xy 80.301045 -407.618743) (xy 80.308794 -407.600069) (xy 80.323095 -407.585776)
			(xy 80.341775 -407.578039) (xy 80.351884 -407.577544) (xy 81.068164 -407.577544) (xy 81.078264 -407.578113)
			(xy 81.09693 -407.585829) (xy 81.111224 -407.600099) (xy 81.11897 -407.618753) (xy 81.119472 -407.628852)
			(xy 81.119472 -407.786332) (xy 81.119873 -407.79552) (xy 81.126394 -407.812704) (xy 81.132172 -407.81986)
			(xy 81.154029 -407.845531) (xy 81.19212 -407.901164) (xy 81.223273 -407.960959) (xy 81.247038 -408.024056)
			(xy 81.263075 -408.089544) (xy 81.271152 -408.156482) (xy 81.271153 -408.223906) (xy 81.263077 -408.290844)
			(xy 81.247042 -408.356333) (xy 81.223277 -408.41943) (xy 81.192126 -408.479225) (xy 81.154036 -408.534859)
			(xy 81.132172 -408.560524) (xy 81.126379 -408.567672) (xy 81.119863 -408.58486) (xy 81.119472 -408.594052)
			(xy 81.119472 -409.086304) (xy 81.119886 -409.095491) (xy 81.126398 -409.112675) (xy 81.132172 -409.119832)
			(xy 81.154002 -409.145526) (xy 81.192093 -409.201156) (xy 81.223247 -409.260948) (xy 81.247014 -409.324041)
			(xy 81.263053 -409.389527) (xy 81.271132 -409.456462) (xy 81.271136 -409.523884) (xy 81.263063 -409.59082)
			(xy 81.247031 -409.656307) (xy 81.223269 -409.719403) (xy 81.192121 -409.779198) (xy 81.154035 -409.834831)
			(xy 81.132172 -409.860496) (xy 81.126391 -409.867652) (xy 81.119868 -409.884834) (xy 81.119472 -409.894024)
			(xy 81.119472 -410.051504) (xy 81.119086 -410.06163) (xy 81.111332 -410.080339) (xy 81.097006 -410.094654)
			(xy 81.078291 -410.102394) (xy 81.068164 -410.102812) (xy 80.351884 -410.102812) (xy 80.341776 -410.102328)
			(xy 80.3231 -410.094587) (xy 80.308806 -410.08029) (xy 80.30107 -410.061612) (xy 80.300576 -410.051504)
			(xy 80.300576 -409.894024) (xy 80.30016 -409.884837) (xy 80.293651 -409.867653) (xy 80.287876 -409.860496)
			(xy 80.265978 -409.83486) (xy 80.227891 -409.77922) (xy 80.196744 -409.71942) (xy 80.172983 -409.656319)
			(xy 80.15695 -409.590827) (xy 80.148878 -409.523886) (xy 79.02071 -409.523886) (xy 78.991976 -409.579043)
			(xy 78.953888 -409.634678) (xy 78.932024 -409.660344) (xy 78.926229 -409.667491) (xy 78.919713 -409.68468)
			(xy 78.919324 -409.693872) (xy 78.919324 -410.186124) (xy 78.919717 -410.195313) (xy 78.926242 -410.212497)
			(xy 78.932024 -410.219652) (xy 78.953871 -410.245331) (xy 78.991959 -410.300964) (xy 79.023109 -410.360758)
			(xy 79.046873 -410.423853) (xy 79.062909 -410.489341) (xy 79.070986 -410.556277) (xy 79.070987 -410.623641)
			(xy 82.349051 -410.623641) (xy 82.349052 -410.556335) (xy 82.357097 -410.489512) (xy 82.373071 -410.424129)
			(xy 82.396745 -410.361124) (xy 82.427779 -410.3014) (xy 82.465728 -410.245812) (xy 82.487516 -410.22016)
			(xy 82.493314 -410.213016) (xy 82.499827 -410.195824) (xy 82.500216 -410.186632) (xy 82.500216 -409.693364)
			(xy 82.49982 -409.684175) (xy 82.493296 -409.666991) (xy 82.487516 -409.659836) (xy 82.465741 -409.634174)
			(xy 82.427793 -409.578588) (xy 82.39676 -409.518866) (xy 82.373088 -409.455863) (xy 82.357115 -409.390482)
			(xy 82.34907 -409.323661) (xy 82.349069 -409.256357) (xy 82.357112 -409.189536) (xy 82.373083 -409.124155)
			(xy 82.396753 -409.061151) (xy 82.427784 -409.001427) (xy 82.46573 -408.94584) (xy 82.487516 -408.920188)
			(xy 82.493302 -408.913035) (xy 82.499822 -408.89585) (xy 82.500216 -408.88666) (xy 82.500216 -408.728672)
			(xy 82.500599 -408.718514) (xy 82.508407 -408.699758) (xy 82.522815 -408.685435) (xy 82.541618 -408.677739)
			(xy 82.551778 -408.677364) (xy 83.268058 -408.677364) (xy 83.278185 -408.677862) (xy 83.29691 -408.68558)
			(xy 83.311268 -408.699864) (xy 83.319085 -408.718548) (xy 83.31962 -408.728672) (xy 83.31962 -408.88666)
			(xy 83.320045 -408.895846) (xy 83.326548 -408.913031) (xy 83.33232 -408.920188) (xy 83.354121 -408.94583)
			(xy 83.392072 -409.001417) (xy 83.423107 -409.061141) (xy 83.446781 -409.124147) (xy 83.462754 -409.189531)
			(xy 83.470798 -409.256356) (xy 83.470797 -409.323662) (xy 83.462751 -409.390487) (xy 83.446775 -409.45587)
			(xy 83.423099 -409.518875) (xy 83.420495 -409.523886) (xy 84.548669 -409.523886) (xy 84.548672 -409.45646)
			(xy 84.556751 -409.38952) (xy 84.572789 -409.324029) (xy 84.596556 -409.260931) (xy 84.627709 -409.201134)
			(xy 84.665799 -409.145498) (xy 84.687664 -409.119832) (xy 84.69348 -409.112701) (xy 84.699981 -409.095499)
			(xy 84.700364 -409.086304) (xy 84.700364 -408.594052) (xy 84.699915 -408.584869) (xy 84.693427 -408.567685)
			(xy 84.687664 -408.560524) (xy 84.665793 -408.534865) (xy 84.627707 -408.479228) (xy 84.596559 -408.419431)
			(xy 84.572797 -408.356334) (xy 84.556763 -408.290844) (xy 84.548688 -408.223906) (xy 84.548689 -408.156482)
			(xy 84.556765 -408.089544) (xy 84.5728 -408.024055) (xy 84.596564 -407.960958) (xy 84.627714 -407.901161)
			(xy 84.665801 -407.845526) (xy 84.687664 -407.81986) (xy 84.693468 -407.81272) (xy 84.699976 -407.795525)
			(xy 84.700364 -407.786332) (xy 84.700364 -407.628852) (xy 84.700845 -407.618745) (xy 84.708592 -407.600072)
			(xy 84.722889 -407.585781) (xy 84.741564 -407.578041) (xy 84.751672 -407.577544) (xy 85.467952 -407.577544)
			(xy 85.478051 -407.578123) (xy 85.496717 -407.585835) (xy 85.511012 -407.600102) (xy 85.518758 -407.618754)
			(xy 85.51926 -407.628852) (xy 85.51926 -407.786332) (xy 85.519664 -407.79552) (xy 85.526183 -407.812703)
			(xy 85.53196 -407.81986) (xy 85.553818 -407.845531) (xy 85.591909 -407.901164) (xy 85.623062 -407.960959)
			(xy 85.646829 -408.024055) (xy 85.662866 -408.089544) (xy 85.670943 -408.156482) (xy 85.670944 -408.223906)
			(xy 85.662868 -408.290844) (xy 85.646832 -408.356333) (xy 85.623067 -408.41943) (xy 85.591915 -408.479226)
			(xy 85.553825 -408.534859) (xy 85.53196 -408.560524) (xy 85.526166 -408.567671) (xy 85.519651 -408.58486)
			(xy 85.51926 -408.594052) (xy 85.51926 -409.086304) (xy 85.519677 -409.09549) (xy 85.526187 -409.112674)
			(xy 85.53196 -409.119832) (xy 85.55379 -409.145526) (xy 85.591882 -409.201155) (xy 85.623037 -409.260947)
			(xy 85.646805 -409.32404) (xy 85.662844 -409.389526) (xy 85.670923 -409.456462) (xy 85.670927 -409.523884)
			(xy 85.662854 -409.59082) (xy 85.646821 -409.656308) (xy 85.623059 -409.719403) (xy 85.59191 -409.779198)
			(xy 85.553823 -409.834831) (xy 85.53196 -409.860496) (xy 85.526178 -409.867651) (xy 85.519655 -409.884834)
			(xy 85.51926 -409.894024) (xy 85.51926 -410.051504) (xy 85.518886 -410.061632) (xy 85.511129 -410.080343)
			(xy 85.496799 -410.094659) (xy 85.47808 -410.102396) (xy 85.467952 -410.102812) (xy 84.751672 -410.102812)
			(xy 84.741563 -410.102338) (xy 84.722886 -410.094594) (xy 84.708593 -410.080293) (xy 84.700857 -410.061613)
			(xy 84.700364 -410.051504) (xy 84.700364 -409.894024) (xy 84.699928 -409.88484) (xy 84.693431 -409.867656)
			(xy 84.687664 -409.860496) (xy 84.665766 -409.834859) (xy 84.627681 -409.77922) (xy 84.596534 -409.719419)
			(xy 84.572773 -409.656319) (xy 84.556741 -409.590827) (xy 84.548669 -409.523886) (xy 83.420495 -409.523886)
			(xy 83.392063 -409.578599) (xy 83.35411 -409.634184) (xy 83.33232 -409.659836) (xy 83.326528 -409.666985)
			(xy 83.32001 -409.684172) (xy 83.31962 -409.693364) (xy 83.31962 -410.186632) (xy 83.32001 -410.195821)
			(xy 83.326537 -410.213006) (xy 83.33232 -410.22016) (xy 83.354093 -410.245825) (xy 83.392045 -410.301408)
			(xy 83.423081 -410.36113) (xy 83.446757 -410.424133) (xy 83.462732 -410.489514) (xy 83.470778 -410.556336)
			(xy 83.47078 -410.62364) (xy 83.470773 -410.623701) (xy 86.748819 -410.623701) (xy 86.74882 -410.556275)
			(xy 86.756898 -410.489336) (xy 86.772936 -410.423846) (xy 86.796702 -410.360748) (xy 86.827855 -410.300952)
			(xy 86.865947 -410.245317) (xy 86.887812 -410.219652) (xy 86.893613 -410.21251) (xy 86.900125 -410.195317)
			(xy 86.900512 -410.186124) (xy 86.900512 -409.693872) (xy 86.900113 -409.684684) (xy 86.893591 -409.6675)
			(xy 86.887812 -409.660344) (xy 86.865959 -409.634669) (xy 86.82787 -409.579036) (xy 86.796718 -409.519242)
			(xy 86.772952 -409.456146) (xy 86.756916 -409.390658) (xy 86.748839 -409.32372) (xy 86.748837 -409.256298)
			(xy 86.756912 -409.18936) (xy 86.772947 -409.123871) (xy 86.79671 -409.060775) (xy 86.82786 -409.000979)
			(xy 86.865948 -408.945345) (xy 86.887812 -408.91968) (xy 86.893601 -408.912529) (xy 86.90012 -408.895343)
			(xy 86.900512 -408.886152) (xy 86.900512 -408.728672) (xy 86.900962 -408.71856) (xy 86.908711 -408.699879)
			(xy 86.923019 -408.685585) (xy 86.941708 -408.677853) (xy 86.95182 -408.677364) (xy 87.6681 -408.677364)
			(xy 87.678204 -408.677884) (xy 87.696876 -408.685615) (xy 87.711169 -408.699901) (xy 87.71891 -408.718568)
			(xy 87.719408 -408.728672) (xy 87.719408 -408.886152) (xy 87.719839 -408.895337) (xy 87.726338 -408.912522)
			(xy 87.732108 -408.91968) (xy 87.753983 -408.945336) (xy 87.792071 -409.000972) (xy 87.823221 -409.060769)
			(xy 87.846984 -409.123867) (xy 87.863019 -409.189358) (xy 87.871093 -409.256297) (xy 87.871092 -409.323721)
			(xy 87.863015 -409.39066) (xy 87.846979 -409.45615) (xy 87.823214 -409.519247) (xy 87.792062 -409.579044)
			(xy 87.753972 -409.634679) (xy 87.732108 -409.660344) (xy 87.726311 -409.667489) (xy 87.719796 -409.68468)
			(xy 87.719408 -409.693872) (xy 87.719408 -410.186124) (xy 87.719805 -410.195313) (xy 87.726328 -410.212497)
			(xy 87.732108 -410.219652) (xy 87.753956 -410.24533) (xy 87.792045 -410.300963) (xy 87.823196 -410.360758)
			(xy 87.84696 -410.423853) (xy 87.862997 -410.48934) (xy 87.871074 -410.556277) (xy 87.871075 -410.623641)
			(xy 91.149138 -410.623641) (xy 91.14914 -410.556335) (xy 91.157185 -410.489512) (xy 91.173158 -410.42413)
			(xy 91.196831 -410.361125) (xy 91.227864 -410.3014) (xy 91.265813 -410.245813) (xy 91.2876 -410.22016)
			(xy 91.293396 -410.213014) (xy 91.299911 -410.195824) (xy 91.3003 -410.186632) (xy 91.3003 -409.693364)
			(xy 91.299907 -409.684175) (xy 91.293382 -409.666991) (xy 91.2876 -409.659836) (xy 91.265825 -409.634174)
			(xy 91.227879 -409.578588) (xy 91.196847 -409.518865) (xy 91.173175 -409.455862) (xy 91.157203 -409.390482)
			(xy 91.149158 -409.323661) (xy 91.149157 -409.256357) (xy 91.157199 -409.189536) (xy 91.17317 -409.124155)
			(xy 91.19684 -409.061151) (xy 91.227869 -409.001428) (xy 91.265814 -408.945841) (xy 91.2876 -408.920188)
			(xy 91.293384 -408.913034) (xy 91.299906 -408.89585) (xy 91.3003 -408.88666) (xy 91.3003 -408.728672)
			(xy 91.300699 -408.718516) (xy 91.308503 -408.699763) (xy 91.322907 -408.685441) (xy 91.341704 -408.677742)
			(xy 91.351862 -408.677364) (xy 92.068142 -408.677364) (xy 92.078274 -408.677793) (xy 92.097001 -408.685539)
			(xy 92.111357 -408.699843) (xy 92.11917 -408.718542) (xy 92.119704 -408.728672) (xy 92.119704 -408.88666)
			(xy 92.120132 -408.895845) (xy 92.126633 -408.91303) (xy 92.132404 -408.920188) (xy 92.154202 -408.945831)
			(xy 92.192148 -409.00142) (xy 92.223178 -409.061145) (xy 92.246848 -409.124151) (xy 92.262819 -409.189534)
			(xy 92.270862 -409.256356) (xy 92.270861 -409.323662) (xy 92.262816 -409.390484) (xy 92.246843 -409.455867)
			(xy 92.223171 -409.518871) (xy 92.220596 -409.523827) (xy 115.349227 -409.523827) (xy 115.349231 -409.456519)
			(xy 115.357278 -409.389695) (xy 115.373254 -409.324311) (xy 115.396929 -409.261305) (xy 115.427964 -409.20158)
			(xy 115.465915 -409.145993) (xy 115.487704 -409.12034) (xy 115.493509 -409.113201) (xy 115.500019 -409.096006)
			(xy 115.500404 -409.086812) (xy 115.500404 -408.593544) (xy 115.499972 -408.584359) (xy 115.493473 -408.567175)
			(xy 115.487704 -408.560016) (xy 115.465909 -408.53437) (xy 115.427963 -408.478782) (xy 115.396932 -408.419057)
			(xy 115.373261 -408.356052) (xy 115.35729 -408.290669) (xy 115.349247 -408.223846) (xy 115.349248 -408.156541)
			(xy 115.357292 -408.089719) (xy 115.373265 -408.024337) (xy 115.396937 -407.961332) (xy 115.427969 -407.901608)
			(xy 115.465917 -407.846021) (xy 115.487704 -407.820368) (xy 115.493497 -407.81322) (xy 115.500014 -407.796032)
			(xy 115.500404 -407.78684) (xy 115.500404 -407.628852) (xy 115.500846 -407.61874) (xy 115.5086 -407.60006)
			(xy 115.52291 -407.585767) (xy 115.541599 -407.578034) (xy 115.551712 -407.577544) (xy 116.268246 -407.577544)
			(xy 116.278376 -407.577989) (xy 116.297099 -407.585733) (xy 116.311454 -407.600031) (xy 116.319271 -407.618724)
			(xy 116.319808 -407.628852) (xy 116.319808 -407.78684) (xy 116.320197 -407.79603) (xy 116.326725 -407.813214)
			(xy 116.332508 -407.820368) (xy 116.354289 -407.846026) (xy 116.392242 -407.90161) (xy 116.423279 -407.961333)
			(xy 116.446954 -408.024336) (xy 116.462929 -408.089718) (xy 116.470975 -408.156541) (xy 116.470976 -408.223847)
			(xy 116.462931 -408.29067) (xy 116.446958 -408.356052) (xy 116.423283 -408.419056) (xy 116.392248 -408.478779)
			(xy 116.354297 -408.534365) (xy 116.332508 -408.560016) (xy 116.326723 -408.56717) (xy 116.320201 -408.584354)
			(xy 116.319808 -408.593544) (xy 116.319808 -409.086812) (xy 116.320211 -409.096) (xy 116.326729 -409.113184)
			(xy 116.332508 -409.12034) (xy 116.354262 -409.146021) (xy 116.392215 -409.201602) (xy 116.423253 -409.261321)
			(xy 116.44693 -409.324322) (xy 116.462907 -409.389701) (xy 116.470955 -409.456521) (xy 116.470958 -409.523825)
			(xy 116.462917 -409.590646) (xy 116.446946 -409.656026) (xy 116.423275 -409.71903) (xy 116.392243 -409.778752)
			(xy 116.354295 -409.834337) (xy 116.332508 -409.859988) (xy 116.326692 -409.86712) (xy 116.320189 -409.884321)
			(xy 116.319808 -409.893516) (xy 116.319808 -410.051504) (xy 116.319318 -410.061612) (xy 116.311581 -410.080289)
			(xy 116.297285 -410.094583) (xy 116.278608 -410.102319) (xy 116.2685 -410.102812) (xy 115.551966 -410.102812)
			(xy 115.541844 -410.102303) (xy 115.523131 -410.094574) (xy 115.508778 -410.080295) (xy 115.500951 -410.061624)
			(xy 115.500404 -410.051504) (xy 115.500404 -409.893516) (xy 115.499985 -409.88433) (xy 115.493477 -409.867145)
			(xy 115.487704 -409.859988) (xy 115.465882 -409.834364) (xy 115.427937 -409.778773) (xy 115.396907 -409.719045)
			(xy 115.373238 -409.656037) (xy 115.357268 -409.590652) (xy 115.349227 -409.523827) (xy 92.220596 -409.523827)
			(xy 92.192139 -409.578596) (xy 92.154191 -409.634183) (xy 92.132404 -409.659836) (xy 92.12661 -409.666983)
			(xy 92.120094 -409.684172) (xy 92.119704 -409.693364) (xy 92.119704 -410.186632) (xy 92.120098 -410.195821)
			(xy 92.126623 -410.213005) (xy 92.132404 -410.22016) (xy 92.154175 -410.245826) (xy 92.192121 -410.301411)
			(xy 92.223153 -410.361133) (xy 92.246825 -410.424136) (xy 92.262797 -410.489516) (xy 92.270842 -410.556336)
			(xy 92.270844 -410.623639) (xy 92.270837 -410.623701) (xy 117.548849 -410.623701) (xy 117.54885 -410.556275)
			(xy 117.556929 -410.489335) (xy 117.572967 -410.423844) (xy 117.596736 -410.360746) (xy 117.627891 -410.30095)
			(xy 117.665985 -410.245316) (xy 117.687852 -410.219652) (xy 117.693658 -410.212514) (xy 117.700166 -410.195318)
			(xy 117.700552 -410.186124) (xy 117.700552 -409.693872) (xy 117.700144 -409.684685) (xy 117.693627 -409.667501)
			(xy 117.687852 -409.660344) (xy 117.665998 -409.63467) (xy 117.627906 -409.579038) (xy 117.596751 -409.519243)
			(xy 117.572984 -409.456148) (xy 117.556946 -409.390659) (xy 117.548869 -409.323721) (xy 117.548868 -409.256297)
			(xy 117.556943 -409.189359) (xy 117.572979 -409.12387) (xy 117.596744 -409.060773) (xy 117.627896 -409.000978)
			(xy 117.665987 -408.945344) (xy 117.687852 -408.91968) (xy 117.693646 -408.912533) (xy 117.700161 -408.895344)
			(xy 117.700552 -408.886152) (xy 117.700552 -408.728672) (xy 117.701061 -408.718567) (xy 117.708799 -408.699898)
			(xy 117.723088 -408.685606) (xy 117.741756 -408.677863) (xy 117.75186 -408.677364) (xy 118.46814 -408.677364)
			(xy 118.478247 -408.677852) (xy 118.496919 -408.685596) (xy 118.511211 -408.699891) (xy 118.518951 -408.718565)
			(xy 118.519448 -408.728672) (xy 118.519448 -408.886152) (xy 118.519893 -408.895335) (xy 118.526384 -408.912519)
			(xy 118.532148 -408.91968) (xy 118.554026 -408.945335) (xy 118.592117 -409.000969) (xy 118.62327 -409.060767)
			(xy 118.647036 -409.123865) (xy 118.663072 -409.189356) (xy 118.671148 -409.256296) (xy 118.671147 -409.323722)
			(xy 118.663069 -409.390662) (xy 118.647031 -409.456152) (xy 118.623263 -409.51925) (xy 118.620848 -409.523886)
			(xy 119.748996 -409.523886) (xy 119.748999 -409.45646) (xy 119.757078 -409.389519) (xy 119.773118 -409.324028)
			(xy 119.796886 -409.26093) (xy 119.828041 -409.201132) (xy 119.866134 -409.145497) (xy 119.888 -409.119832)
			(xy 119.893808 -409.112695) (xy 119.900316 -409.095498) (xy 119.9007 -409.086304) (xy 119.9007 -408.594052)
			(xy 119.900265 -408.584867) (xy 119.893769 -408.567683) (xy 119.888 -408.560524) (xy 119.866128 -408.534865)
			(xy 119.82804 -408.47923) (xy 119.796889 -408.419433) (xy 119.773126 -408.356335) (xy 119.757091 -408.290845)
			(xy 119.749015 -408.223906) (xy 119.749016 -408.156482) (xy 119.757093 -408.089543) (xy 119.773129 -408.024054)
			(xy 119.796894 -407.960956) (xy 119.828046 -407.90116) (xy 119.866136 -407.845525) (xy 119.888 -407.81986)
			(xy 119.893796 -407.812714) (xy 119.900311 -407.795524) (xy 119.9007 -407.786332) (xy 119.9007 -407.628852)
			(xy 119.901146 -407.61874) (xy 119.908899 -407.600061) (xy 119.923208 -407.585768) (xy 119.941896 -407.578035)
			(xy 119.952008 -407.577544) (xy 120.668288 -407.577544) (xy 120.678389 -407.578094) (xy 120.697056 -407.585817)
			(xy 120.71135 -407.600093) (xy 120.719095 -407.618752) (xy 120.719596 -407.628852) (xy 120.719596 -407.786332)
			(xy 120.719991 -407.795521) (xy 120.726515 -407.812705) (xy 120.732296 -407.81986) (xy 120.754152 -407.845532)
			(xy 120.792241 -407.901165) (xy 120.823393 -407.96096) (xy 120.847158 -408.024056) (xy 120.863194 -408.089545)
			(xy 120.87127 -408.156482) (xy 120.871271 -408.223906) (xy 120.863196 -408.290843) (xy 120.847161 -408.356332)
			(xy 120.823398 -408.419429) (xy 120.792248 -408.479225) (xy 120.75416 -408.534859) (xy 120.732296 -408.560524)
			(xy 120.726506 -408.567674) (xy 120.719988 -408.584861) (xy 120.719596 -408.594052) (xy 120.719596 -409.086304)
			(xy 120.720005 -409.095491) (xy 120.72652 -409.112675) (xy 120.732296 -409.119832) (xy 120.754125 -409.145526)
			(xy 120.792215 -409.201157) (xy 120.823367 -409.260949) (xy 120.847134 -409.324042) (xy 120.863172 -409.389527)
			(xy 120.871251 -409.456463) (xy 120.871254 -409.523883) (xy 120.863181 -409.590819) (xy 120.84715 -409.656306)
			(xy 120.823389 -409.719402) (xy 120.792243 -409.779197) (xy 120.754158 -409.834831) (xy 120.732296 -409.860496)
			(xy 120.726518 -409.867654) (xy 120.719992 -409.884835) (xy 120.719596 -409.894024) (xy 120.719596 -410.051504)
			(xy 120.719187 -410.061627) (xy 120.711437 -410.080332) (xy 120.697118 -410.094646) (xy 120.678411 -410.10239)
			(xy 120.668288 -410.102812) (xy 119.952008 -410.102812) (xy 119.941888 -410.102378) (xy 119.923186 -410.094634)
			(xy 119.908872 -410.080324) (xy 119.901125 -410.061624) (xy 119.9007 -410.051504) (xy 119.9007 -409.894024)
			(xy 119.900278 -409.884838) (xy 119.893773 -409.867654) (xy 119.888 -409.860496) (xy 119.866101 -409.83486)
			(xy 119.828013 -409.779221) (xy 119.796864 -409.719421) (xy 119.773102 -409.65632) (xy 119.757069 -409.590828)
			(xy 119.748996 -409.523886) (xy 118.620848 -409.523886) (xy 118.592108 -409.579046) (xy 118.554015 -409.63468)
			(xy 118.532148 -409.660344) (xy 118.526344 -409.667484) (xy 118.519835 -409.684679) (xy 118.519448 -409.693872)
			(xy 118.519448 -410.186124) (xy 118.519858 -410.195311) (xy 118.526373 -410.212495) (xy 118.532148 -410.219652)
			(xy 118.553998 -410.245329) (xy 118.592091 -410.300961) (xy 118.623245 -410.360755) (xy 118.647012 -410.42385)
			(xy 118.663051 -410.489338) (xy 118.671128 -410.556276) (xy 118.67113 -410.623641) (xy 121.949169 -410.623641)
			(xy 121.94917 -410.556335) (xy 121.957216 -410.489511) (xy 121.97319 -410.424128) (xy 121.996865 -410.361123)
			(xy 122.0279 -410.301399) (xy 122.065851 -410.245812) (xy 122.08764 -410.22016) (xy 122.093441 -410.213018)
			(xy 122.099952 -410.195825) (xy 122.10034 -410.186632) (xy 122.10034 -409.693364) (xy 122.099938 -409.684176)
			(xy 122.093418 -409.666992) (xy 122.08764 -409.659836) (xy 122.065864 -409.634174) (xy 122.027915 -409.578589)
			(xy 121.996881 -409.518867) (xy 121.973208 -409.455864) (xy 121.957234 -409.390483) (xy 121.949189 -409.323661)
			(xy 121.949188 -409.256357) (xy 121.957231 -409.189535) (xy 121.973202 -409.124154) (xy 121.996874 -409.06115)
			(xy 122.027906 -409.001427) (xy 122.065853 -408.94584) (xy 122.08764 -408.920188) (xy 122.093429 -408.913038)
			(xy 122.099947 -408.895851) (xy 122.10034 -408.88666) (xy 122.10034 -408.728672) (xy 122.100694 -408.718543)
			(xy 122.108459 -408.699831) (xy 122.122795 -408.685516) (xy 122.141518 -408.677779) (xy 122.151648 -408.677364)
			(xy 122.868182 -408.677364) (xy 122.878311 -408.677842) (xy 122.897036 -408.685568) (xy 122.911394 -408.699858)
			(xy 122.919209 -408.718546) (xy 122.919744 -408.728672) (xy 122.919744 -408.88666) (xy 122.920186 -408.895844)
			(xy 122.926679 -408.913028) (xy 122.932444 -408.920188) (xy 122.954244 -408.94583) (xy 122.992193 -409.001418)
			(xy 123.023227 -409.061143) (xy 123.0469 -409.124148) (xy 123.062873 -409.189532) (xy 123.070916 -409.256356)
			(xy 123.070915 -409.323662) (xy 123.062869 -409.390486) (xy 123.046895 -409.455869) (xy 123.02322 -409.518874)
			(xy 123.020646 -409.523827) (xy 124.149291 -409.523827) (xy 124.149295 -409.456519) (xy 124.157343 -409.389693)
			(xy 124.173321 -409.324308) (xy 124.197 -409.261302) (xy 124.22804 -409.201577) (xy 124.265997 -409.145992)
			(xy 124.287788 -409.12034) (xy 124.293591 -409.113199) (xy 124.300102 -409.096005) (xy 124.300488 -409.086812)
			(xy 124.300488 -408.593544) (xy 124.300059 -408.584359) (xy 124.293559 -408.567174) (xy 124.287788 -408.560016)
			(xy 124.265991 -408.534371) (xy 124.228039 -408.478785) (xy 124.197004 -408.419061) (xy 124.173329 -408.356055)
			(xy 124.157355 -408.290671) (xy 124.149311 -408.223847) (xy 124.149312 -408.156541) (xy 124.157357 -408.089717)
			(xy 124.173333 -408.024333) (xy 124.197008 -407.961328) (xy 124.228045 -407.901605) (xy 124.265998 -407.84602)
			(xy 124.287788 -407.820368) (xy 124.293579 -407.813219) (xy 124.300097 -407.796031) (xy 124.300488 -407.78684)
			(xy 124.300488 -407.628852) (xy 124.300946 -407.618742) (xy 124.308697 -407.600065) (xy 124.323002 -407.585772)
			(xy 124.341685 -407.578037) (xy 124.351796 -407.577544) (xy 125.06833 -407.577544) (xy 125.078459 -407.578002)
			(xy 125.097182 -407.58574) (xy 125.111537 -407.600035) (xy 125.119355 -407.618725) (xy 125.119892 -407.628852)
			(xy 125.119892 -407.78684) (xy 125.120285 -407.796029) (xy 125.126811 -407.813213) (xy 125.132592 -407.820368)
			(xy 125.154371 -407.846027) (xy 125.192318 -407.901613) (xy 125.22335 -407.961336) (xy 125.247022 -408.02434)
			(xy 125.262994 -408.089721) (xy 125.271039 -408.156542) (xy 125.271039 -408.223846) (xy 125.262997 -408.290667)
			(xy 125.247025 -408.356049) (xy 125.223355 -408.419053) (xy 125.192324 -408.478776) (xy 125.154378 -408.534363)
			(xy 125.132592 -408.560016) (xy 125.126805 -408.567168) (xy 125.120285 -408.584353) (xy 125.119892 -408.593544)
			(xy 125.119892 -409.086812) (xy 125.120298 -409.096) (xy 125.126815 -409.113184) (xy 125.132592 -409.12034)
			(xy 125.154343 -409.146022) (xy 125.192291 -409.201605) (xy 125.223324 -409.261324) (xy 125.246998 -409.324325)
			(xy 125.262972 -409.389703) (xy 125.271019 -409.456522) (xy 125.271022 -409.523824) (xy 125.262982 -409.590643)
			(xy 125.247014 -409.656023) (xy 125.223347 -409.719026) (xy 125.192319 -409.778749) (xy 125.154377 -409.834336)
			(xy 125.132592 -409.859988) (xy 125.126775 -409.867118) (xy 125.120273 -409.88432) (xy 125.119892 -409.893516)
			(xy 125.119892 -410.051504) (xy 125.119487 -410.061628) (xy 125.111736 -410.080333) (xy 125.097416 -410.094647)
			(xy 125.078708 -410.102391) (xy 125.068584 -410.102812) (xy 124.35205 -410.102812) (xy 124.341933 -410.102234)
			(xy 124.323223 -410.094532) (xy 124.308867 -410.080274) (xy 124.301036 -410.061618) (xy 124.300488 -410.051504)
			(xy 124.300488 -409.893516) (xy 124.300073 -409.884329) (xy 124.293563 -409.867145) (xy 124.287788 -409.859988)
			(xy 124.265963 -409.834366) (xy 124.228013 -409.778776) (xy 124.196978 -409.719049) (xy 124.173305 -409.65604)
			(xy 124.157333 -409.590654) (xy 124.149291 -409.523827) (xy 123.020646 -409.523827) (xy 122.992184 -409.578598)
			(xy 122.954233 -409.634184) (xy 122.932444 -409.659836) (xy 122.926643 -409.666978) (xy 122.920132 -409.684171)
			(xy 122.919744 -409.693364) (xy 122.919744 -410.186632) (xy 122.920151 -410.195819) (xy 122.926668 -410.213003)
			(xy 122.932444 -410.22016) (xy 122.954216 -410.245825) (xy 122.992167 -410.301409) (xy 123.023202 -410.361131)
			(xy 123.046876 -410.424134) (xy 123.062851 -410.489514) (xy 123.070896 -410.556336) (xy 123.070898 -410.62364)
			(xy 123.070891 -410.623701) (xy 126.348937 -410.623701) (xy 126.348938 -410.556275) (xy 126.357016 -410.489335)
			(xy 126.373055 -410.423845) (xy 126.396822 -410.360747) (xy 126.427977 -410.300951) (xy 126.46607 -410.245317)
			(xy 126.487936 -410.219652) (xy 126.49374 -410.212512) (xy 126.500249 -410.195317) (xy 126.500636 -410.186124)
			(xy 126.500636 -409.693872) (xy 126.500231 -409.684684) (xy 126.493713 -409.667501) (xy 126.487936 -409.660344)
			(xy 126.466083 -409.63467) (xy 126.427991 -409.579037) (xy 126.396838 -409.519243) (xy 126.373071 -409.456147)
			(xy 126.357034 -409.390659) (xy 126.348957 -409.323721) (xy 126.348956 -409.256297) (xy 126.357031 -409.189359)
			(xy 126.373066 -409.12387) (xy 126.396831 -409.060774) (xy 126.427982 -409.000978) (xy 126.466071 -408.945345)
			(xy 126.487936 -408.91968) (xy 126.493728 -408.912532) (xy 126.500245 -408.895343) (xy 126.500636 -408.886152)
			(xy 126.500636 -408.728672) (xy 126.500994 -408.718543) (xy 126.508758 -408.699832) (xy 126.523093 -408.685517)
			(xy 126.541815 -408.67778) (xy 126.551944 -408.677364) (xy 127.268224 -408.677364) (xy 127.27833 -408.677864)
			(xy 127.297002 -408.685603) (xy 127.311294 -408.699895) (xy 127.319035 -408.718566) (xy 127.319532 -408.728672)
			(xy 127.319532 -408.886152) (xy 127.31998 -408.895335) (xy 127.326469 -408.912519) (xy 127.332232 -408.91968)
			(xy 127.354107 -408.945336) (xy 127.392193 -409.000973) (xy 127.423341 -409.06077) (xy 127.447103 -409.123868)
			(xy 127.463137 -409.189358) (xy 127.471211 -409.256297) (xy 127.47121 -409.323721) (xy 127.463134 -409.39066)
			(xy 127.447098 -409.456149) (xy 127.423334 -409.519246) (xy 127.420948 -409.523827) (xy 128.549082 -409.523827)
			(xy 128.549085 -409.456519) (xy 128.557133 -409.389693) (xy 128.573111 -409.324308) (xy 128.59679 -409.261302)
			(xy 128.627829 -409.201578) (xy 128.665785 -409.145991) (xy 128.687576 -409.12034) (xy 128.693378 -409.113198)
			(xy 128.69989 -409.096005) (xy 128.700276 -409.086812) (xy 128.700276 -408.593544) (xy 128.69985 -408.584358)
			(xy 128.693348 -408.567174) (xy 128.687576 -408.560016) (xy 128.665779 -408.534371) (xy 128.627828 -408.478784)
			(xy 128.596793 -408.41906) (xy 128.573119 -408.356055) (xy 128.557146 -408.290671) (xy 128.549102 -408.223847)
			(xy 128.549103 -408.156541) (xy 128.557148 -408.089717) (xy 128.573123 -408.024334) (xy 128.596798 -407.961329)
			(xy 128.627835 -407.901605) (xy 128.665787 -407.84602) (xy 128.687576 -407.820368) (xy 128.693366 -407.813218)
			(xy 128.699885 -407.796031) (xy 128.700276 -407.78684) (xy 128.700276 -407.628852) (xy 128.700745 -407.618743)
			(xy 128.708494 -407.600069) (xy 128.722795 -407.585776) (xy 128.741475 -407.578039) (xy 128.751584 -407.577544)
			(xy 129.468118 -407.577544) (xy 129.478246 -407.578012) (xy 129.496969 -407.585746) (xy 129.511325 -407.600038)
			(xy 129.519143 -407.618726) (xy 129.51968 -407.628852) (xy 129.51968 -407.78684) (xy 129.520075 -407.796029)
			(xy 129.5266 -407.813213) (xy 129.53238 -407.820368) (xy 129.554159 -407.846027) (xy 129.592107 -407.901613)
			(xy 129.62314 -407.961336) (xy 129.646812 -408.024339) (xy 129.662785 -408.08972) (xy 129.67083 -408.156542)
			(xy 129.67083 -408.223846) (xy 129.662787 -408.290668) (xy 129.646816 -408.356049) (xy 129.623145 -408.419053)
			(xy 129.592113 -408.478777) (xy 129.554167 -408.534364) (xy 129.53238 -408.560016) (xy 129.526592 -408.567167)
			(xy 129.520073 -408.584353) (xy 129.51968 -408.593544) (xy 129.51968 -409.086812) (xy 129.520089 -409.095999)
			(xy 129.526604 -409.113183) (xy 129.53238 -409.12034) (xy 129.554131 -409.146022) (xy 129.59208 -409.201604)
			(xy 129.623114 -409.261324) (xy 129.646788 -409.324325) (xy 129.662763 -409.389703) (xy 129.670809 -409.456522)
			(xy 129.670813 -409.523824) (xy 129.662772 -409.590644) (xy 129.646804 -409.656024) (xy 129.623136 -409.719026)
			(xy 129.592108 -409.778749) (xy 129.554165 -409.834335) (xy 129.53238 -409.859988) (xy 129.526561 -409.867117)
			(xy 129.52006 -409.88432) (xy 129.51968 -409.893516) (xy 129.51968 -410.051504) (xy 129.519287 -410.061629)
			(xy 129.511534 -410.080337) (xy 129.49721 -410.094651) (xy 129.478497 -410.102393) (xy 129.468372 -410.102812)
			(xy 128.751838 -410.102812) (xy 128.74172 -410.102244) (xy 128.72301 -410.094538) (xy 128.708654 -410.080277)
			(xy 128.700824 -410.061618) (xy 128.700276 -410.051504) (xy 128.700276 -409.893516) (xy 128.699864 -409.884329)
			(xy 128.693352 -409.867144) (xy 128.687576 -409.859988) (xy 128.665751 -409.834366) (xy 128.627801 -409.778776)
			(xy 128.596768 -409.719048) (xy 128.573095 -409.65604) (xy 128.557124 -409.590654) (xy 128.549082 -409.523827)
			(xy 127.420948 -409.523827) (xy 127.392184 -409.579043) (xy 127.354096 -409.634678) (xy 127.332232 -409.660344)
			(xy 127.326426 -409.667482) (xy 127.319919 -409.684678) (xy 127.319532 -409.693872) (xy 127.319532 -410.186124)
			(xy 127.319946 -410.19531) (xy 127.326459 -410.212494) (xy 127.332232 -410.219652) (xy 127.354079 -410.245331)
			(xy 127.392166 -410.300964) (xy 127.423316 -410.360759) (xy 127.44708 -410.423854) (xy 127.463115 -410.489341)
			(xy 127.471192 -410.556277) (xy 127.471193 -410.623641) (xy 130.749257 -410.623641) (xy 130.749258 -410.556335)
			(xy 130.757303 -410.489512) (xy 130.773278 -410.424129) (xy 130.796952 -410.361123) (xy 130.827986 -410.301399)
			(xy 130.865936 -410.245812) (xy 130.887724 -410.22016) (xy 130.893523 -410.213017) (xy 130.900035 -410.195825)
			(xy 130.900424 -410.186632) (xy 130.900424 -409.693364) (xy 130.900026 -409.684176) (xy 130.893503 -409.666992)
			(xy 130.887724 -409.659836) (xy 130.865948 -409.634174) (xy 130.828 -409.578589) (xy 130.796967 -409.518866)
			(xy 130.773294 -409.455863) (xy 130.757321 -409.390482) (xy 130.749276 -409.323661) (xy 130.749275 -409.256357)
			(xy 130.757318 -409.189536) (xy 130.773289 -409.124154) (xy 130.79696 -409.06115) (xy 130.827991 -409.001427)
			(xy 130.865937 -408.94584) (xy 130.887724 -408.920188) (xy 130.893511 -408.913036) (xy 130.900031 -408.895851)
			(xy 130.900424 -408.88666) (xy 130.900424 -408.728672) (xy 130.900799 -408.718513) (xy 130.908608 -408.699755)
			(xy 130.92302 -408.685432) (xy 130.941825 -408.677738) (xy 130.951986 -408.677364) (xy 131.668266 -408.677364)
			(xy 131.678393 -408.677855) (xy 131.697118 -408.685576) (xy 131.711477 -408.699862) (xy 131.719293 -408.718547)
			(xy 131.719828 -408.728672) (xy 131.719828 -408.88666) (xy 131.720251 -408.895846) (xy 131.726755 -408.913031)
			(xy 131.732528 -408.920188) (xy 131.754328 -408.94583) (xy 131.792279 -409.001417) (xy 131.823314 -409.061142)
			(xy 131.846987 -409.124148) (xy 131.86296 -409.189532) (xy 131.871004 -409.256356) (xy 131.871003 -409.323662)
			(xy 131.862957 -409.390486) (xy 131.846982 -409.45587) (xy 131.823306 -409.518875) (xy 131.79227 -409.578598)
			(xy 131.754317 -409.634184) (xy 131.732528 -409.659836) (xy 131.726725 -409.666976) (xy 131.720216 -409.684171)
			(xy 131.719828 -409.693364) (xy 131.719828 -410.186632) (xy 131.720217 -410.195822) (xy 131.726745 -410.213006)
			(xy 131.732528 -410.22016) (xy 131.754301 -410.245825) (xy 131.792252 -410.301409) (xy 131.823288 -410.36113)
			(xy 131.846963 -410.424133) (xy 131.862938 -410.489514) (xy 131.870984 -410.556336) (xy 131.870986 -410.62364)
			(xy 131.862943 -410.690462) (xy 131.84697 -410.755844) (xy 131.823298 -410.818848) (xy 131.792265 -410.878571)
			(xy 131.754316 -410.934156) (xy 131.732528 -410.959808) (xy 131.726737 -410.966957) (xy 131.720221 -410.984145)
			(xy 131.719828 -410.993336) (xy 131.719828 -411.151324) (xy 131.719399 -411.161476) (xy 131.7116 -411.180224)
			(xy 131.697207 -411.194545) (xy 131.67842 -411.202249) (xy 131.668266 -411.202632) (xy 130.951986 -411.202632)
			(xy 130.941855 -411.202184) (xy 130.923128 -411.194446) (xy 130.908772 -411.180148) (xy 130.900958 -411.161453)
			(xy 130.900424 -411.151324) (xy 130.900424 -410.993336) (xy 130.899991 -410.984151) (xy 130.893493 -410.966967)
			(xy 130.887724 -410.959808) (xy 130.865921 -410.934169) (xy 130.827974 -410.87858) (xy 130.796942 -410.818855)
			(xy 130.773271 -410.755848) (xy 130.757299 -410.690465) (xy 130.749257 -410.623641) (xy 127.471193 -410.623641)
			(xy 127.471193 -410.623699) (xy 127.463119 -410.690635) (xy 127.447087 -410.756123) (xy 127.423326 -410.819219)
			(xy 127.392179 -410.879015) (xy 127.354094 -410.93465) (xy 127.332232 -410.960316) (xy 127.326438 -410.967463)
			(xy 127.319924 -410.984652) (xy 127.319532 -410.993844) (xy 127.319532 -411.151324) (xy 127.319035 -411.16143)
			(xy 127.311296 -411.180103) (xy 127.297003 -411.194396) (xy 127.27833 -411.202135) (xy 127.268224 -411.202632)
			(xy 126.551944 -411.202632) (xy 126.541828 -411.202149) (xy 126.523132 -411.194421) (xy 126.508817 -411.180125)
			(xy 126.501065 -411.161439) (xy 126.500636 -411.151324) (xy 126.500636 -410.993844) (xy 126.500196 -410.98466)
			(xy 126.493702 -410.967476) (xy 126.487936 -410.960316) (xy 126.466055 -410.934664) (xy 126.427964 -410.879029)
			(xy 126.396812 -410.819231) (xy 126.373048 -410.756132) (xy 126.357012 -410.690641) (xy 126.348937 -410.623701)
			(xy 123.070891 -410.623701) (xy 123.062855 -410.690462) (xy 123.046883 -410.755843) (xy 123.023211 -410.818847)
			(xy 122.992179 -410.87857) (xy 122.954231 -410.934156) (xy 122.932444 -410.959808) (xy 122.926655 -410.966958)
			(xy 122.920137 -410.984145) (xy 122.919744 -410.993336) (xy 122.919744 -411.151324) (xy 122.919236 -411.161429)
			(xy 122.911498 -411.180099) (xy 122.897209 -411.194392) (xy 122.878541 -411.202133) (xy 122.868436 -411.202632)
			(xy 122.151902 -411.202632) (xy 122.141772 -411.202171) (xy 122.123046 -411.194439) (xy 122.108688 -411.180144)
			(xy 122.100874 -411.161452) (xy 122.10034 -411.151324) (xy 122.10034 -410.993336) (xy 122.099903 -410.984152)
			(xy 122.093407 -410.966968) (xy 122.08764 -410.959808) (xy 122.065836 -410.934169) (xy 122.027888 -410.878581)
			(xy 121.996855 -410.818855) (xy 121.973183 -410.755849) (xy 121.957211 -410.690465) (xy 121.949169 -410.623641)
			(xy 118.67113 -410.623641) (xy 118.67113 -410.6237) (xy 118.663055 -410.690638) (xy 118.647019 -410.756127)
			(xy 118.623255 -410.819223) (xy 118.592103 -410.879018) (xy 118.554013 -410.934652) (xy 118.532148 -410.960316)
			(xy 118.526356 -410.967464) (xy 118.51984 -410.984653) (xy 118.519448 -410.993844) (xy 118.519448 -411.151324)
			(xy 118.518936 -411.161428) (xy 118.511199 -411.180098) (xy 118.496911 -411.19439) (xy 118.478244 -411.202133)
			(xy 118.46814 -411.202632) (xy 117.75186 -411.202632) (xy 117.741753 -411.202148) (xy 117.72308 -411.194404)
			(xy 117.708787 -411.180107) (xy 117.701048 -411.161431) (xy 117.700552 -411.151324) (xy 117.700552 -410.993844)
			(xy 117.700109 -410.984661) (xy 117.693617 -410.967477) (xy 117.687852 -410.960316) (xy 117.66597 -410.934665)
			(xy 117.627879 -410.879029) (xy 117.596726 -410.819232) (xy 117.57296 -410.756133) (xy 117.556924 -410.690642)
			(xy 117.548849 -410.623701) (xy 92.270837 -410.623701) (xy 92.262802 -410.69046) (xy 92.246832 -410.755841)
			(xy 92.223163 -410.818845) (xy 92.192134 -410.878568) (xy 92.154189 -410.934155) (xy 92.132404 -410.959808)
			(xy 92.126622 -410.966964) (xy 92.120098 -410.984146) (xy 92.119704 -410.993336) (xy 92.119704 -411.151324)
			(xy 92.119298 -411.161479) (xy 92.111495 -411.180231) (xy 92.097094 -411.194554) (xy 92.078299 -411.202253)
			(xy 92.068142 -411.202632) (xy 91.351862 -411.202632) (xy 91.341729 -411.202204) (xy 91.323002 -411.194458)
			(xy 91.308646 -411.180154) (xy 91.300833 -411.161455) (xy 91.3003 -411.151324) (xy 91.3003 -410.993336)
			(xy 91.299873 -410.984151) (xy 91.293371 -410.966966) (xy 91.2876 -410.959808) (xy 91.265798 -410.934168)
			(xy 91.227852 -410.878579) (xy 91.196822 -410.818853) (xy 91.173151 -410.755847) (xy 91.157181 -410.690464)
			(xy 91.149138 -410.623641) (xy 87.871075 -410.623641) (xy 87.871075 -410.623699) (xy 87.863001 -410.690636)
			(xy 87.846967 -410.756124) (xy 87.823205 -410.81922) (xy 87.792057 -410.879016) (xy 87.753971 -410.934651)
			(xy 87.732108 -410.960316) (xy 87.726323 -410.96747) (xy 87.719801 -410.984654) (xy 87.719408 -410.993844)
			(xy 87.719408 -411.151324) (xy 87.718935 -411.161433) (xy 87.711191 -411.180111) (xy 87.69689 -411.194404)
			(xy 87.67821 -411.20214) (xy 87.6681 -411.202632) (xy 86.95182 -411.202632) (xy 86.941716 -411.202099)
			(xy 86.923045 -411.194374) (xy 86.90875 -411.180092) (xy 86.901009 -411.161427) (xy 86.900512 -411.151324)
			(xy 86.900512 -410.993844) (xy 86.900078 -410.984659) (xy 86.893581 -410.967475) (xy 86.887812 -410.960316)
			(xy 86.865932 -410.934664) (xy 86.827843 -410.879028) (xy 86.796692 -410.81923) (xy 86.772928 -410.756131)
			(xy 86.756894 -410.69064) (xy 86.748819 -410.623701) (xy 83.470773 -410.623701) (xy 83.462736 -410.690462)
			(xy 83.446764 -410.755844) (xy 83.423091 -410.818848) (xy 83.392058 -410.878571) (xy 83.354108 -410.934156)
			(xy 83.33232 -410.959808) (xy 83.32654 -410.966965) (xy 83.320015 -410.984146) (xy 83.31962 -410.993336)
			(xy 83.31962 -411.151324) (xy 83.319199 -411.161477) (xy 83.311399 -411.180226) (xy 83.297003 -411.194548)
			(xy 83.278213 -411.202251) (xy 83.268058 -411.202632) (xy 82.551778 -411.202632) (xy 82.541646 -411.202191)
			(xy 82.522919 -411.194451) (xy 82.508563 -411.18015) (xy 82.500749 -411.161454) (xy 82.500216 -411.151324)
			(xy 82.500216 -410.993336) (xy 82.499785 -410.984151) (xy 82.493285 -410.966967) (xy 82.487516 -410.959808)
			(xy 82.465713 -410.934169) (xy 82.427766 -410.87858) (xy 82.396735 -410.818854) (xy 82.373064 -410.755848)
			(xy 82.357093 -410.690465) (xy 82.349051 -410.623641) (xy 79.070987 -410.623641) (xy 79.070987 -410.623699)
			(xy 79.062913 -410.690636) (xy 79.04688 -410.756124) (xy 79.023119 -410.81922) (xy 78.991971 -410.879016)
			(xy 78.953886 -410.93465) (xy 78.932024 -410.960316) (xy 78.926241 -410.967471) (xy 78.919717 -410.984654)
			(xy 78.919324 -410.993844) (xy 78.919324 -411.151324) (xy 78.918835 -411.161431) (xy 78.911094 -411.180106)
			(xy 78.896799 -411.194399) (xy 78.878123 -411.202137) (xy 78.868016 -411.202632) (xy 78.151736 -411.202632)
			(xy 78.14162 -411.202155) (xy 78.122923 -411.194425) (xy 78.108609 -411.180127) (xy 78.100857 -411.16144)
			(xy 78.100428 -411.151324) (xy 78.100428 -410.993844) (xy 78.09999 -410.98466) (xy 78.093495 -410.967476)
			(xy 78.087728 -410.960316) (xy 78.065847 -410.934664) (xy 78.027757 -410.879028) (xy 77.996606 -410.819231)
			(xy 77.972841 -410.756132) (xy 77.956806 -410.690641) (xy 77.948731 -410.623701) (xy 74.670685 -410.623701)
			(xy 74.662649 -410.690462) (xy 74.646677 -410.755844) (xy 74.623005 -410.818848) (xy 74.591972 -410.87857)
			(xy 74.554023 -410.934156) (xy 74.532236 -410.959808) (xy 74.526446 -410.966957) (xy 74.519929 -410.984145)
			(xy 74.519536 -410.993336) (xy 74.519536 -411.151324) (xy 74.519099 -411.161475) (xy 74.511302 -411.180221)
			(xy 74.496911 -411.194542) (xy 74.478127 -411.202248) (xy 74.467974 -411.202632) (xy 73.751694 -411.202632)
			(xy 73.741563 -411.202177) (xy 73.722837 -411.194442) (xy 73.70848 -411.180146) (xy 73.700666 -411.161452)
			(xy 73.700132 -411.151324) (xy 73.700132 -410.993336) (xy 73.699697 -410.984152) (xy 73.6932 -410.966967)
			(xy 73.687432 -410.959808) (xy 73.665629 -410.934169) (xy 73.627681 -410.87858) (xy 73.596649 -410.818855)
			(xy 73.572977 -410.755849) (xy 73.557005 -410.690465) (xy 73.548963 -410.623641) (xy 66.525648 -410.623641)
			(xy 66.525648 -417.289488) (xy 66.525648 -417.371276) (xy 141.02334 -417.371276) (xy 141.02334 -394.305282)
			(xy 141.023796 -394.293166) (xy 141.031289 -394.270122) (xy 141.045535 -394.25052) (xy 141.06514 -394.23628)
			(xy 141.088186 -394.228793) (xy 141.100302 -394.22832) (xy 154.426158 -394.22832) (xy 154.57678 -394.378688)
			(xy 154.57678 -397.823825) (xy 159.349135 -397.823825) (xy 159.349138 -397.756518) (xy 159.357186 -397.689693)
			(xy 159.373162 -397.624309) (xy 159.396838 -397.561303) (xy 159.427875 -397.501578) (xy 159.465827 -397.44599)
			(xy 159.487616 -397.420338) (xy 159.493423 -397.4132) (xy 159.499931 -397.396004) (xy 159.500316 -397.38681)
			(xy 159.500316 -396.893542) (xy 159.499882 -396.884357) (xy 159.493384 -396.867173) (xy 159.487616 -396.860014)
			(xy 159.465819 -396.83437) (xy 159.427872 -396.778782) (xy 159.396841 -396.719057) (xy 159.373169 -396.656051)
			(xy 159.357198 -396.590668) (xy 159.349155 -396.523845) (xy 159.349156 -396.45654) (xy 159.3572 -396.389717)
			(xy 159.373174 -396.324334) (xy 159.396847 -396.26133) (xy 159.42788 -396.201606) (xy 159.465828 -396.146018)
			(xy 159.487616 -396.120366) (xy 159.493411 -396.11322) (xy 159.499926 -396.09603) (xy 159.500316 -396.086838)
			(xy 159.500316 -395.92885) (xy 159.500804 -395.918684) (xy 159.508569 -395.899895) (xy 159.522934 -395.885509)
			(xy 159.541713 -395.877718) (xy 159.551878 -395.877288) (xy 160.268158 -395.877288) (xy 160.278333 -395.877699)
			(xy 160.297136 -395.88548) (xy 160.311525 -395.89987) (xy 160.319302 -395.918675) (xy 160.31972 -395.92885)
			(xy 160.31972 -396.086838) (xy 160.320108 -396.096028) (xy 160.326637 -396.113212) (xy 160.33242 -396.120366)
			(xy 160.354199 -396.146026) (xy 160.392151 -396.20161) (xy 160.423187 -396.261332) (xy 160.446862 -396.324336)
			(xy 160.462837 -396.389718) (xy 160.470882 -396.45654) (xy 160.470883 -396.523845) (xy 160.46284 -396.590668)
			(xy 160.446866 -396.65605) (xy 160.423193 -396.719054) (xy 160.392159 -396.778777) (xy 160.354208 -396.834362)
			(xy 160.33242 -396.860014) (xy 160.326637 -396.867169) (xy 160.320114 -396.884352) (xy 160.31972 -396.893542)
			(xy 160.31972 -397.38681) (xy 160.320121 -397.395998) (xy 160.326641 -397.413183) (xy 160.33242 -397.420338)
			(xy 160.354172 -397.44602) (xy 160.392124 -397.501601) (xy 160.420549 -397.556296) (xy 161.5488 -397.556296)
			(xy 161.556874 -397.489359) (xy 161.572908 -397.423871) (xy 161.596669 -397.360775) (xy 161.627817 -397.300979)
			(xy 161.665902 -397.245344) (xy 161.687764 -397.219678) (xy 161.69356 -397.212533) (xy 161.700073 -397.195342)
			(xy 161.700464 -397.18615) (xy 161.700464 -397.028924) (xy 161.701004 -397.018821) (xy 161.708727 -397.00015)
			(xy 161.723007 -396.985856) (xy 161.74167 -396.978114) (xy 161.751772 -396.977616) (xy 162.468052 -396.977616)
			(xy 162.478173 -396.978056) (xy 162.496879 -396.985791) (xy 162.511195 -397.000101) (xy 162.51894 -397.018803)
			(xy 162.51936 -397.028924) (xy 162.51936 -397.18615) (xy 162.519803 -397.195333) (xy 162.526295 -397.212518)
			(xy 162.53206 -397.219678) (xy 162.553935 -397.245334) (xy 162.592026 -397.300969) (xy 162.623179 -397.360766)
			(xy 162.646944 -397.423864) (xy 162.66298 -397.489355) (xy 162.671056 -397.556295) (xy 162.671055 -397.62372)
			(xy 162.662977 -397.69066) (xy 162.64694 -397.75615) (xy 162.623173 -397.819247) (xy 162.620757 -397.823885)
			(xy 163.748903 -397.823885) (xy 163.748907 -397.756458) (xy 163.756987 -397.689517) (xy 163.773027 -397.624026)
			(xy 163.796796 -397.560927) (xy 163.827951 -397.50113) (xy 163.866045 -397.445495) (xy 163.887912 -397.41983)
			(xy 163.893722 -397.412694) (xy 163.900228 -397.395497) (xy 163.900612 -397.386302) (xy 163.900612 -396.89405)
			(xy 163.900175 -396.884866) (xy 163.89368 -396.867681) (xy 163.887912 -396.860522) (xy 163.866038 -396.834865)
			(xy 163.827949 -396.77923) (xy 163.796798 -396.719432) (xy 163.773034 -396.656334) (xy 163.756998 -396.590844)
			(xy 163.748923 -396.523905) (xy 163.748924 -396.45648) (xy 163.757001 -396.389541) (xy 163.773038 -396.324051)
			(xy 163.796804 -396.260954) (xy 163.827956 -396.201157) (xy 163.866047 -396.145523) (xy 163.887912 -396.119858)
			(xy 163.89371 -396.112714) (xy 163.900224 -396.095523) (xy 163.900612 -396.08633) (xy 163.900612 -395.92885)
			(xy 163.901167 -395.91873) (xy 163.908873 -395.900015) (xy 163.923138 -395.885658) (xy 163.941803 -395.877832)
			(xy 163.95192 -395.877288) (xy 164.6682 -395.877288) (xy 164.678353 -395.877721) (xy 164.697103 -395.885515)
			(xy 164.711426 -395.899908) (xy 164.719127 -395.918695) (xy 164.719508 -395.92885) (xy 164.719508 -396.08633)
			(xy 164.719902 -396.095519) (xy 164.726426 -396.112703) (xy 164.732208 -396.119858) (xy 164.754062 -396.145531)
			(xy 164.79215 -396.201165) (xy 164.823301 -396.26096) (xy 164.847065 -396.324056) (xy 164.863101 -396.389544)
			(xy 164.871178 -396.456481) (xy 164.871179 -396.523904) (xy 164.863104 -396.590841) (xy 164.84707 -396.65633)
			(xy 164.823307 -396.719426) (xy 164.792158 -396.779222) (xy 164.754071 -396.834857) (xy 164.732208 -396.860522)
			(xy 164.726421 -396.867674) (xy 164.7199 -396.884859) (xy 164.719508 -396.89405) (xy 164.719508 -397.386302)
			(xy 164.719915 -397.395489) (xy 164.726431 -397.412674) (xy 164.732208 -397.41983) (xy 164.754034 -397.445526)
			(xy 164.792124 -397.501156) (xy 164.823276 -397.560948) (xy 164.846898 -397.62366) (xy 165.949096 -397.62366)
			(xy 165.949096 -397.556355) (xy 165.957139 -397.489533) (xy 165.973111 -397.424151) (xy 165.996783 -397.361147)
			(xy 166.027816 -397.301424) (xy 166.065765 -397.245838) (xy 166.087552 -397.220186) (xy 166.093343 -397.213037)
			(xy 166.09986 -397.195849) (xy 166.100252 -397.186658) (xy 166.100252 -397.028924) (xy 166.10074 -397.018777)
			(xy 166.108519 -397.000035) (xy 166.122895 -396.985712) (xy 166.141666 -396.978003) (xy 166.151814 -396.977616)
			(xy 166.868094 -396.977616) (xy 166.878217 -396.978131) (xy 166.896934 -396.985852) (xy 166.911289 -397.000129)
			(xy 166.919113 -397.018803) (xy 166.919656 -397.028924) (xy 166.919656 -397.186658) (xy 166.920096 -397.195842)
			(xy 166.92659 -397.213026) (xy 166.932356 -397.220186) (xy 166.954154 -397.24583) (xy 166.992103 -397.301417)
			(xy 167.023136 -397.361142) (xy 167.046808 -397.424148) (xy 167.062781 -397.489531) (xy 167.070824 -397.556355)
			(xy 167.070823 -397.62366) (xy 167.062778 -397.690484) (xy 167.046804 -397.755867) (xy 167.02313 -397.818872)
			(xy 167.020556 -397.823825) (xy 168.149223 -397.823825) (xy 168.149226 -397.756518) (xy 168.157274 -397.689693)
			(xy 168.17325 -397.624309) (xy 168.196925 -397.561304) (xy 168.22796 -397.501579) (xy 168.265911 -397.445991)
			(xy 168.2877 -397.420338) (xy 168.293505 -397.413199) (xy 168.300015 -397.396004) (xy 168.3004 -397.38681)
			(xy 168.3004 -396.893542) (xy 168.29997 -396.884357) (xy 168.29347 -396.867172) (xy 168.2877 -396.860014)
			(xy 168.265904 -396.834369) (xy 168.227958 -396.778781) (xy 168.196927 -396.719056) (xy 168.173256 -396.656051)
			(xy 168.157285 -396.590668) (xy 168.149243 -396.523845) (xy 168.149244 -396.45654) (xy 168.157288 -396.389717)
			(xy 168.173261 -396.324335) (xy 168.196933 -396.26133) (xy 168.227965 -396.201606) (xy 168.265913 -396.146019)
			(xy 168.2877 -396.120366) (xy 168.293494 -396.113219) (xy 168.30001 -396.09603) (xy 168.3004 -396.086838)
			(xy 168.3004 -395.92885) (xy 168.300904 -395.918686) (xy 168.308665 -395.8999) (xy 168.323026 -395.885515)
			(xy 168.341799 -395.877721) (xy 168.351962 -395.877288) (xy 169.068242 -395.877288) (xy 169.078423 -395.877631)
			(xy 169.097228 -395.885439) (xy 169.111613 -395.89985) (xy 169.119388 -395.918669) (xy 169.119804 -395.92885)
			(xy 169.119804 -396.086838) (xy 169.120195 -396.096027) (xy 169.126722 -396.113212) (xy 169.132504 -396.120366)
			(xy 169.154281 -396.146027) (xy 169.192227 -396.201613) (xy 169.223258 -396.261336) (xy 169.24693 -396.324339)
			(xy 169.262902 -396.38972) (xy 169.270946 -396.456541) (xy 169.270947 -396.523844) (xy 169.262905 -396.590665)
			(xy 169.246934 -396.656047) (xy 169.223264 -396.71905) (xy 169.192235 -396.778774) (xy 169.15429 -396.834361)
			(xy 169.132504 -396.860014) (xy 169.126719 -396.867168) (xy 169.120197 -396.884352) (xy 169.119804 -396.893542)
			(xy 169.119804 -397.38681) (xy 169.120209 -397.395998) (xy 169.126726 -397.413182) (xy 169.132504 -397.420338)
			(xy 169.154253 -397.446021) (xy 169.1922 -397.501604) (xy 169.22062 -397.556296) (xy 170.348863 -397.556296)
			(xy 170.356939 -397.489357) (xy 170.372975 -397.423868) (xy 170.39674 -397.360771) (xy 170.427892 -397.300976)
			(xy 170.465983 -397.245342) (xy 170.487848 -397.219678) (xy 170.493642 -397.212531) (xy 170.500157 -397.195342)
			(xy 170.500548 -397.18615) (xy 170.500548 -397.028924) (xy 170.501103 -397.018823) (xy 170.508823 -397.000155)
			(xy 170.523098 -396.985862) (xy 170.541756 -396.978117) (xy 170.551856 -396.977616) (xy 171.268136 -396.977616)
			(xy 171.278249 -396.978056) (xy 171.296931 -396.985808) (xy 171.311225 -397.000119) (xy 171.318956 -397.01881)
			(xy 171.319444 -397.028924) (xy 171.319444 -397.18615) (xy 171.319891 -397.195333) (xy 171.326381 -397.212517)
			(xy 171.332144 -397.219678) (xy 171.35402 -397.245334) (xy 171.392112 -397.300969) (xy 171.423265 -397.360766)
			(xy 171.447031 -397.423864) (xy 171.463068 -397.489355) (xy 171.471144 -397.556295) (xy 171.471143 -397.62372)
			(xy 171.463065 -397.69066) (xy 171.447027 -397.756151) (xy 171.423259 -397.819248) (xy 171.420874 -397.823826)
			(xy 172.54899 -397.823826) (xy 172.548993 -397.756517) (xy 172.557042 -397.689691) (xy 172.57302 -397.624306)
			(xy 172.5967 -397.5613) (xy 172.62774 -397.501575) (xy 172.665697 -397.44599) (xy 172.687488 -397.420338)
			(xy 172.693292 -397.413198) (xy 172.699803 -397.396004) (xy 172.700188 -397.38681) (xy 172.700188 -396.893542)
			(xy 172.69976 -396.884357) (xy 172.693259 -396.867172) (xy 172.687488 -396.860014) (xy 172.665689 -396.834371)
			(xy 172.627737 -396.778784) (xy 172.596702 -396.71906) (xy 172.573027 -396.656054) (xy 172.557054 -396.59067)
			(xy 172.54901 -396.523846) (xy 172.54901 -396.456539) (xy 172.557056 -396.389715) (xy 172.573032 -396.324332)
			(xy 172.596708 -396.261327) (xy 172.627745 -396.201603) (xy 172.665698 -396.146018) (xy 172.687488 -396.120366)
			(xy 172.69328 -396.113218) (xy 172.699798 -396.09603) (xy 172.700188 -396.086838) (xy 172.700188 -395.92885)
			(xy 172.700606 -395.918675) (xy 172.708384 -395.899872) (xy 172.722772 -395.885484) (xy 172.741575 -395.877706)
			(xy 172.75175 -395.877288) (xy 173.46803 -395.877288) (xy 173.47821 -395.87764) (xy 173.497015 -395.885445)
			(xy 173.5114 -395.899852) (xy 173.519175 -395.91867) (xy 173.519592 -395.92885) (xy 173.519592 -396.086838)
			(xy 173.519986 -396.096027) (xy 173.526511 -396.113211) (xy 173.532292 -396.120366) (xy 173.554069 -396.146027)
			(xy 173.592016 -396.201613) (xy 173.623048 -396.261335) (xy 173.64672 -396.324339) (xy 173.662693 -396.389719)
			(xy 173.670737 -396.456541) (xy 173.670738 -396.523844) (xy 173.662695 -396.590666) (xy 173.646725 -396.656047)
			(xy 173.623054 -396.719051) (xy 173.592024 -396.778774) (xy 173.554078 -396.834361) (xy 173.532292 -396.860014)
			(xy 173.526506 -396.867167) (xy 173.519985 -396.884351) (xy 173.519592 -396.893542) (xy 173.519592 -397.38681)
			(xy 173.519999 -397.395998) (xy 173.526515 -397.413182) (xy 173.532292 -397.420338) (xy 173.554041 -397.446021)
			(xy 173.591989 -397.501604) (xy 173.620441 -397.556355) (xy 174.749183 -397.556355) (xy 174.757226 -397.489534)
			(xy 174.773198 -397.424152) (xy 174.796869 -397.361148) (xy 174.827901 -397.301424) (xy 174.865849 -397.245838)
			(xy 174.887636 -397.220186) (xy 174.893426 -397.213036) (xy 174.899944 -397.195849) (xy 174.900336 -397.186658)
			(xy 174.900336 -397.028924) (xy 174.900742 -397.018767) (xy 174.908536 -397.000008) (xy 174.922939 -396.985682)
			(xy 174.941739 -396.977988) (xy 174.951898 -396.977616) (xy 175.668178 -396.977616) (xy 175.6783 -396.978144)
			(xy 175.697017 -396.98586) (xy 175.711373 -397.000133) (xy 175.719197 -397.018805) (xy 175.71974 -397.028924)
			(xy 175.71974 -397.186658) (xy 175.720184 -397.195841) (xy 175.726675 -397.213025) (xy 175.73244 -397.220186)
			(xy 175.754238 -397.24583) (xy 175.792188 -397.301417) (xy 175.823222 -397.361142) (xy 175.846895 -397.424147)
			(xy 175.862868 -397.489531) (xy 175.870912 -397.556354) (xy 175.870911 -397.623661) (xy 175.862865 -397.690484)
			(xy 175.846891 -397.755867) (xy 175.823216 -397.818872) (xy 175.79218 -397.878596) (xy 175.754229 -397.934182)
			(xy 175.73244 -397.959834) (xy 175.726639 -397.966976) (xy 175.720129 -397.984169) (xy 175.71974 -397.993362)
			(xy 175.71974 -398.486884) (xy 175.720171 -398.496069) (xy 175.726672 -398.513253) (xy 175.73244 -398.520412)
			(xy 175.754264 -398.546035) (xy 175.792213 -398.601625) (xy 175.823246 -398.661352) (xy 175.846918 -398.724361)
			(xy 175.862889 -398.789747) (xy 175.87093 -398.856573) (xy 175.870927 -398.923881) (xy 175.862879 -398.990707)
			(xy 175.846902 -399.056091) (xy 175.823224 -399.119097) (xy 175.792185 -399.178822) (xy 175.754231 -399.234408)
			(xy 175.73244 -399.26006) (xy 175.726628 -399.267194) (xy 175.720124 -399.284393) (xy 175.71974 -399.293588)
			(xy 175.71974 -399.451576) (xy 175.71926 -399.461724) (xy 175.71148 -399.480468) (xy 175.697101 -399.494791)
			(xy 175.678327 -399.502498) (xy 175.668178 -399.502884) (xy 174.951898 -399.502884) (xy 174.941774 -399.502376)
			(xy 174.923058 -399.494652) (xy 174.908702 -399.480372) (xy 174.900879 -399.461697) (xy 174.900336 -399.451576)
			(xy 174.900336 -399.293588) (xy 174.899924 -399.284401) (xy 174.893411 -399.267217) (xy 174.887636 -399.26006)
			(xy 174.865884 -399.234379) (xy 174.827934 -399.178796) (xy 174.7969 -399.119077) (xy 174.773225 -399.056076)
			(xy 174.75725 -398.990697) (xy 174.749203 -398.923878) (xy 174.749199 -398.856576) (xy 174.75724 -398.789756)
			(xy 174.773209 -398.724376) (xy 174.796878 -398.661373) (xy 174.827906 -398.60165) (xy 174.865851 -398.546064)
			(xy 174.887636 -398.520412) (xy 174.893457 -398.513284) (xy 174.899956 -398.49608) (xy 174.900336 -398.486884)
			(xy 174.900336 -397.993362) (xy 174.899936 -397.984174) (xy 174.893414 -397.96699) (xy 174.887636 -397.959834)
			(xy 174.865858 -397.934174) (xy 174.827909 -397.878588) (xy 174.796876 -397.818866) (xy 174.773202 -397.755863)
			(xy 174.757229 -397.690481) (xy 174.749184 -397.62366) (xy 174.749183 -397.556355) (xy 173.620441 -397.556355)
			(xy 173.623023 -397.561324) (xy 173.646696 -397.624324) (xy 173.662671 -397.689702) (xy 173.670718 -397.756521)
			(xy 173.670721 -397.823822) (xy 173.662681 -397.890642) (xy 173.646713 -397.956021) (xy 173.623046 -398.019024)
			(xy 173.592019 -398.078747) (xy 173.554077 -398.134334) (xy 173.532292 -398.159986) (xy 173.526475 -398.167117)
			(xy 173.519973 -398.184318) (xy 173.519592 -398.193514) (xy 173.519592 -398.351502) (xy 173.519069 -398.361656)
			(xy 173.511299 -398.38042) (xy 173.496943 -398.394784) (xy 173.478184 -398.402563) (xy 173.46803 -398.403064)
			(xy 172.75175 -398.403064) (xy 172.741582 -398.402595) (xy 172.722789 -398.394827) (xy 172.708402 -398.380455)
			(xy 172.700615 -398.36167) (xy 172.700188 -398.351502) (xy 172.700188 -398.193514) (xy 172.699774 -398.184327)
			(xy 172.693263 -398.167143) (xy 172.687488 -398.159986) (xy 172.665661 -398.134365) (xy 172.627711 -398.078775)
			(xy 172.596676 -398.019048) (xy 172.573004 -397.956039) (xy 172.557032 -397.890653) (xy 172.54899 -397.823826)
			(xy 171.420874 -397.823826) (xy 171.392104 -397.879044) (xy 171.354011 -397.934678) (xy 171.332144 -397.960342)
			(xy 171.32634 -397.967482) (xy 171.319831 -397.984677) (xy 171.319444 -397.99387) (xy 171.319444 -398.486376)
			(xy 171.319878 -398.49556) (xy 171.326376 -398.512744) (xy 171.332144 -398.519904) (xy 171.354045 -398.545539)
			(xy 171.392137 -398.601177) (xy 171.423289 -398.660976) (xy 171.447054 -398.724077) (xy 171.463088 -398.789571)
			(xy 171.471162 -398.856513) (xy 171.471159 -398.923941) (xy 171.463078 -398.990883) (xy 171.447037 -399.056374)
			(xy 171.423267 -399.119473) (xy 171.392109 -399.17927) (xy 171.354012 -399.234904) (xy 171.332144 -399.260568)
			(xy 171.326329 -399.2677) (xy 171.319827 -399.284901) (xy 171.319444 -399.294096) (xy 171.319444 -399.451576)
			(xy 171.318896 -399.461678) (xy 171.311175 -399.480347) (xy 171.296897 -399.494641) (xy 171.278237 -399.502385)
			(xy 171.268136 -399.502884) (xy 170.551856 -399.502884) (xy 170.541742 -399.50245) (xy 170.52306 -399.494695)
			(xy 170.508766 -399.480383) (xy 170.501036 -399.46169) (xy 170.500548 -399.451576) (xy 170.500548 -399.294096)
			(xy 170.500129 -399.28491) (xy 170.49362 -399.267726) (xy 170.487848 -399.260568) (xy 170.466018 -399.234874)
			(xy 170.427925 -399.179245) (xy 170.39677 -399.119453) (xy 170.373001 -399.05636) (xy 170.356962 -398.990874)
			(xy 170.348883 -398.923938) (xy 170.348879 -398.856516) (xy 170.356952 -398.789579) (xy 170.372985 -398.724092)
			(xy 170.396748 -398.660996) (xy 170.427897 -398.601201) (xy 170.465984 -398.545568) (xy 170.487848 -398.519904)
			(xy 170.493631 -398.51275) (xy 170.500153 -398.495566) (xy 170.500548 -398.486376) (xy 170.500548 -397.99387)
			(xy 170.500141 -397.984683) (xy 170.493624 -397.967499) (xy 170.487848 -397.960342) (xy 170.465992 -397.934669)
			(xy 170.4279 -397.879037) (xy 170.396746 -397.819242) (xy 170.372979 -397.756146) (xy 170.356942 -397.690658)
			(xy 170.348864 -397.623719) (xy 170.348863 -397.556296) (xy 169.22062 -397.556296) (xy 169.223233 -397.561324)
			(xy 169.246906 -397.624324) (xy 169.26288 -397.689702) (xy 169.270927 -397.756521) (xy 169.27093 -397.823822)
			(xy 169.26289 -397.890641) (xy 169.246923 -397.956021) (xy 169.223256 -398.019024) (xy 169.19223 -398.078746)
			(xy 169.154288 -398.134333) (xy 169.132504 -398.159986) (xy 169.126689 -398.167118) (xy 169.120185 -398.184319)
			(xy 169.119804 -398.193514) (xy 169.119804 -398.351502) (xy 169.119269 -398.361655) (xy 169.111502 -398.380416)
			(xy 169.097149 -398.394779) (xy 169.078394 -398.402561) (xy 169.068242 -398.403064) (xy 168.351962 -398.403064)
			(xy 168.341802 -398.402598) (xy 168.323032 -398.394811) (xy 168.308669 -398.380437) (xy 168.300895 -398.361662)
			(xy 168.3004 -398.351502) (xy 168.3004 -398.193514) (xy 168.299983 -398.184328) (xy 168.293474 -398.167143)
			(xy 168.2877 -398.159986) (xy 168.265876 -398.134364) (xy 168.227931 -398.078772) (xy 168.196902 -398.019044)
			(xy 168.173233 -397.956036) (xy 168.157263 -397.89065) (xy 168.149223 -397.823825) (xy 167.020556 -397.823825)
			(xy 166.992095 -397.878596) (xy 166.954145 -397.934182) (xy 166.932356 -397.959834) (xy 166.926557 -397.966977)
			(xy 166.920045 -397.984169) (xy 166.919656 -397.993362) (xy 166.919656 -398.486884) (xy 166.920084 -398.496069)
			(xy 166.926586 -398.513253) (xy 166.932356 -398.520412) (xy 166.954179 -398.546035) (xy 166.992127 -398.601625)
			(xy 167.023159 -398.661353) (xy 167.04683 -398.724361) (xy 167.062801 -398.789747) (xy 167.070842 -398.856573)
			(xy 167.070839 -398.923881) (xy 167.062791 -398.990706) (xy 167.046814 -399.05609) (xy 167.023137 -399.119097)
			(xy 166.9921 -399.178821) (xy 166.954146 -399.234408) (xy 166.932356 -399.26006) (xy 166.926546 -399.267195)
			(xy 166.92004 -399.284394) (xy 166.919656 -399.293588) (xy 166.919656 -399.451576) (xy 166.91916 -399.461722)
			(xy 166.911383 -399.480463) (xy 166.89701 -399.494785) (xy 166.878241 -399.502496) (xy 166.868094 -399.502884)
			(xy 166.151814 -399.502884) (xy 166.141691 -399.502363) (xy 166.122975 -399.494644) (xy 166.108619 -399.480369)
			(xy 166.100795 -399.461696) (xy 166.100252 -399.451576) (xy 166.100252 -399.293588) (xy 166.099836 -399.284402)
			(xy 166.093325 -399.267218) (xy 166.087552 -399.26006) (xy 166.065799 -399.234379) (xy 166.027849 -399.178797)
			(xy 165.996813 -399.119077) (xy 165.973138 -399.056077) (xy 165.957162 -398.990698) (xy 165.949115 -398.923878)
			(xy 165.949111 -398.856576) (xy 165.957152 -398.789755) (xy 165.973122 -398.724375) (xy 165.996791 -398.661372)
			(xy 166.027821 -398.60165) (xy 166.065766 -398.546064) (xy 166.087552 -398.520412) (xy 166.093375 -398.513286)
			(xy 166.099872 -398.49608) (xy 166.100252 -398.486884) (xy 166.100252 -397.993362) (xy 166.099848 -397.984174)
			(xy 166.093329 -397.966991) (xy 166.087552 -397.959834) (xy 166.065774 -397.934174) (xy 166.027824 -397.878589)
			(xy 165.99679 -397.818866) (xy 165.973116 -397.755863) (xy 165.957142 -397.690482) (xy 165.949096 -397.62366)
			(xy 164.846898 -397.62366) (xy 164.847042 -397.624041) (xy 164.863079 -397.689526) (xy 164.871158 -397.756461)
			(xy 164.871162 -397.823882) (xy 164.86309 -397.890817) (xy 164.847058 -397.956304) (xy 164.823299 -398.019399)
			(xy 164.792153 -398.079195) (xy 164.754069 -398.134829) (xy 164.732208 -398.160494) (xy 164.726432 -398.167654)
			(xy 164.719905 -398.184833) (xy 164.719508 -398.194022) (xy 164.719508 -398.351502) (xy 164.718976 -398.361623)
			(xy 164.711257 -398.380335) (xy 164.696985 -398.394689) (xy 164.678318 -398.402517) (xy 164.6682 -398.403064)
			(xy 163.95192 -398.403064) (xy 163.941763 -398.402661) (xy 163.923004 -398.394866) (xy 163.908678 -398.380462)
			(xy 163.900984 -398.361662) (xy 163.900612 -398.351502) (xy 163.900612 -398.194022) (xy 163.900188 -398.184836)
			(xy 163.893684 -398.167652) (xy 163.887912 -398.160494) (xy 163.86601 -398.13486) (xy 163.827922 -398.079221)
			(xy 163.796772 -398.019421) (xy 163.77301 -397.95632) (xy 163.756976 -397.890827) (xy 163.748903 -397.823885)
			(xy 162.620757 -397.823885) (xy 162.592019 -397.879044) (xy 162.553926 -397.934677) (xy 162.53206 -397.960342)
			(xy 162.526258 -397.967483) (xy 162.519748 -397.984677) (xy 162.51936 -397.99387) (xy 162.51936 -398.486376)
			(xy 162.51979 -398.495561) (xy 162.526291 -398.512745) (xy 162.53206 -398.519904) (xy 162.553961 -398.545539)
			(xy 162.592051 -398.601177) (xy 162.623202 -398.660977) (xy 162.646966 -398.724078) (xy 162.663 -398.789571)
			(xy 162.671074 -398.856513) (xy 162.671071 -398.923941) (xy 162.662991 -398.990882) (xy 162.64695 -399.056374)
			(xy 162.62318 -399.119472) (xy 162.592023 -399.179269) (xy 162.553928 -399.234903) (xy 162.53206 -399.260568)
			(xy 162.526247 -399.267701) (xy 162.519743 -399.284901) (xy 162.51936 -399.294096) (xy 162.51936 -399.451576)
			(xy 162.518964 -399.461702) (xy 162.511216 -399.480413) (xy 162.496893 -399.494729) (xy 162.478178 -399.502468)
			(xy 162.468052 -399.502884) (xy 161.751772 -399.502884) (xy 161.741659 -399.502438) (xy 161.722978 -399.494688)
			(xy 161.708683 -399.480379) (xy 161.700952 -399.461689) (xy 161.700464 -399.451576) (xy 161.700464 -399.294096)
			(xy 161.700041 -399.28491) (xy 161.693535 -399.267727) (xy 161.687764 -399.260568) (xy 161.665937 -399.234873)
			(xy 161.627849 -399.179242) (xy 161.596699 -399.119449) (xy 161.572934 -399.056357) (xy 161.556897 -398.990871)
			(xy 161.548819 -398.923937) (xy 161.548816 -398.856517) (xy 161.556888 -398.789582) (xy 161.572918 -398.724095)
			(xy 161.596677 -398.661) (xy 161.627821 -398.601205) (xy 161.665903 -398.54557) (xy 161.687764 -398.519904)
			(xy 161.693549 -398.512751) (xy 161.700069 -398.495566) (xy 161.700464 -398.486376) (xy 161.700464 -397.99387)
			(xy 161.700054 -397.984683) (xy 161.693538 -397.9675) (xy 161.687764 -397.960342) (xy 161.665911 -397.934668)
			(xy 161.627824 -397.879034) (xy 161.596675 -397.819239) (xy 161.572912 -397.756143) (xy 161.556877 -397.690655)
			(xy 161.548801 -397.623719) (xy 161.5488 -397.556296) (xy 160.420549 -397.556296) (xy 160.423161 -397.561321)
			(xy 160.446838 -397.624321) (xy 160.462815 -397.6897) (xy 160.470863 -397.75652) (xy 160.470866 -397.823823)
			(xy 160.462825 -397.890644) (xy 160.446855 -397.956024) (xy 160.423185 -398.019027) (xy 160.392154 -398.078749)
			(xy 160.354207 -398.134334) (xy 160.33242 -398.159986) (xy 160.326607 -398.16712) (xy 160.320101 -398.184319)
			(xy 160.31972 -398.193514) (xy 160.31972 -398.351502) (xy 160.319337 -398.361679) (xy 160.311543 -398.380482)
			(xy 160.297145 -398.394868) (xy 160.278335 -398.402645) (xy 160.268158 -398.403064) (xy 159.551878 -398.403064)
			(xy 159.541719 -398.402585) (xy 159.52295 -398.394804) (xy 159.508585 -398.380433) (xy 159.500811 -398.361661)
			(xy 159.500316 -398.351502) (xy 159.500316 -398.193514) (xy 159.499895 -398.184328) (xy 159.493388 -398.167144)
			(xy 159.487616 -398.159986) (xy 159.465792 -398.134364) (xy 159.427845 -398.078773) (xy 159.396815 -398.019045)
			(xy 159.373145 -397.956036) (xy 159.357176 -397.890651) (xy 159.349135 -397.823825) (xy 154.57678 -397.823825)
			(xy 154.57678 -401.723737) (xy 159.349146 -401.723737) (xy 159.349148 -401.65643) (xy 159.357194 -401.589607)
			(xy 159.373169 -401.524223) (xy 159.396843 -401.461218) (xy 159.427878 -401.401494) (xy 159.465828 -401.345906)
			(xy 159.487616 -401.320254) (xy 159.493416 -401.313112) (xy 159.499928 -401.295919) (xy 159.500316 -401.286726)
			(xy 159.500316 -400.793458) (xy 159.499923 -400.784269) (xy 159.493397 -400.767085) (xy 159.487616 -400.75993)
			(xy 159.465835 -400.734273) (xy 159.427887 -400.678686) (xy 159.396855 -400.618963) (xy 159.373183 -400.55596)
			(xy 159.35721 -400.490578) (xy 159.349166 -400.423757) (xy 159.349165 -400.356452) (xy 159.357209 -400.289631)
			(xy 159.37318 -400.224249) (xy 159.396851 -400.161245) (xy 159.427883 -400.101521) (xy 159.465829 -400.045934)
			(xy 159.487616 -400.020282) (xy 159.493405 -400.013131) (xy 159.499923 -399.995945) (xy 159.500316 -399.986754)
			(xy 159.500316 -399.828766) (xy 159.500805 -399.818609) (xy 159.508586 -399.799843) (xy 159.522953 -399.78548)
			(xy 159.541721 -399.777703) (xy 159.551878 -399.777204) (xy 160.268158 -399.777204) (xy 160.278323 -399.777697)
			(xy 160.29711 -399.785462) (xy 160.311495 -399.799826) (xy 160.319288 -399.818602) (xy 160.31972 -399.828766)
			(xy 160.31972 -399.986754) (xy 160.320148 -399.995939) (xy 160.326649 -400.013124) (xy 160.33242 -400.020282)
			(xy 160.354215 -400.045929) (xy 160.392166 -400.101515) (xy 160.423201 -400.161239) (xy 160.446876 -400.224244)
			(xy 160.462849 -400.289628) (xy 160.470894 -400.356451) (xy 160.470893 -400.423758) (xy 160.462848 -400.490581)
			(xy 160.446873 -400.555964) (xy 160.423198 -400.618969) (xy 160.392161 -400.678693) (xy 160.354209 -400.734278)
			(xy 160.33242 -400.75993) (xy 160.326631 -400.76708) (xy 160.320111 -400.784267) (xy 160.31972 -400.793458)
			(xy 160.31972 -401.286726) (xy 160.320113 -401.295915) (xy 160.326638 -401.313099) (xy 160.33242 -401.320254)
			(xy 160.354187 -401.345923) (xy 160.392139 -401.401506) (xy 160.423176 -401.461227) (xy 160.446852 -401.52423)
			(xy 160.462827 -401.58961) (xy 160.470874 -401.656431) (xy 160.470876 -401.723735) (xy 160.462833 -401.790557)
			(xy 160.446862 -401.855939) (xy 160.423189 -401.918943) (xy 160.392156 -401.978665) (xy 160.354208 -402.03425)
			(xy 160.33242 -402.059902) (xy 160.326642 -402.067061) (xy 160.320116 -402.084241) (xy 160.31972 -402.09343)
			(xy 160.31972 -402.251418) (xy 160.31935 -402.261596) (xy 160.311551 -402.280399) (xy 160.297149 -402.294785)
			(xy 160.278336 -402.302562) (xy 160.268158 -402.30298) (xy 159.551878 -402.30298) (xy 159.541721 -402.302485)
			(xy 159.522955 -402.294707) (xy 159.508591 -402.280342) (xy 159.500814 -402.261575) (xy 159.500316 -402.251418)
			(xy 159.500316 -402.09343) (xy 159.499888 -402.084245) (xy 159.493386 -402.06706) (xy 159.487616 -402.059902)
			(xy 159.465807 -402.034267) (xy 159.427861 -401.978678) (xy 159.39683 -401.918952) (xy 159.373159 -401.855945)
			(xy 159.357188 -401.790561) (xy 159.349146 -401.723737) (xy 154.57678 -401.723737) (xy 154.57678 -402.823877)
			(xy 161.54876 -402.823877) (xy 161.548765 -402.756451) (xy 161.556845 -402.68951) (xy 161.572884 -402.624018)
			(xy 161.596652 -402.56092) (xy 161.627806 -402.501122) (xy 161.665898 -402.445486) (xy 161.687764 -402.41982)
			(xy 161.693585 -402.412692) (xy 161.700083 -402.395488) (xy 161.700464 -402.386292) (xy 161.700464 -401.89404)
			(xy 161.70002 -401.884857) (xy 161.693528 -401.867673) (xy 161.687764 -401.860512) (xy 161.665882 -401.834862)
			(xy 161.627796 -401.779225) (xy 161.596648 -401.719426) (xy 161.572887 -401.656327) (xy 161.556854 -401.590837)
			(xy 161.54878 -401.523897) (xy 161.548782 -401.456473) (xy 161.556859 -401.389534) (xy 161.572896 -401.324044)
			(xy 161.59666 -401.260946) (xy 161.627811 -401.201149) (xy 161.6659 -401.145514) (xy 161.687764 -401.119848)
			(xy 161.693573 -401.112712) (xy 161.700078 -401.095514) (xy 161.700464 -401.08632) (xy 161.700464 -400.92884)
			(xy 161.700948 -400.918725) (xy 161.708676 -400.900029) (xy 161.722972 -400.885714) (xy 161.741657 -400.877961)
			(xy 161.751772 -400.877532) (xy 162.468052 -400.877532) (xy 162.478175 -400.877956) (xy 162.496884 -400.885694)
			(xy 162.511201 -400.900009) (xy 162.518942 -400.918717) (xy 162.51936 -400.92884) (xy 162.51936 -401.08632)
			(xy 162.519769 -401.095507) (xy 162.526285 -401.112691) (xy 162.53206 -401.119848) (xy 162.553906 -401.145529)
			(xy 162.591998 -401.20116) (xy 162.623151 -401.260954) (xy 162.646919 -401.324049) (xy 162.662957 -401.389536)
			(xy 162.671035 -401.456474) (xy 162.671037 -401.523896) (xy 162.662962 -401.590834) (xy 162.646927 -401.656323)
			(xy 162.623164 -401.719419) (xy 162.620884 -401.723796) (xy 163.748915 -401.723796) (xy 163.748917 -401.656371)
			(xy 163.756995 -401.589431) (xy 163.773033 -401.52394) (xy 163.7968 -401.460842) (xy 163.827954 -401.401046)
			(xy 163.866046 -401.345411) (xy 163.887912 -401.319746) (xy 163.893715 -401.312606) (xy 163.900226 -401.295411)
			(xy 163.900612 -401.286218) (xy 163.900612 -400.793966) (xy 163.900216 -400.784777) (xy 163.893692 -400.767593)
			(xy 163.887912 -400.760438) (xy 163.866054 -400.734768) (xy 163.827964 -400.679135) (xy 163.796812 -400.619339)
			(xy 163.773047 -400.556243) (xy 163.757011 -400.490754) (xy 163.748934 -400.423816) (xy 163.748934 -400.356393)
			(xy 163.757009 -400.289455) (xy 163.773044 -400.223966) (xy 163.796809 -400.160869) (xy 163.827959 -400.101073)
			(xy 163.866048 -400.045439) (xy 163.887912 -400.019774) (xy 163.893703 -400.012625) (xy 163.900221 -399.995437)
			(xy 163.900612 -399.986246) (xy 163.900612 -399.828766) (xy 163.901098 -399.818641) (xy 163.908832 -399.799924)
			(xy 163.923117 -399.78557) (xy 163.941797 -399.777747) (xy 163.95192 -399.777204) (xy 164.6682 -399.777204)
			(xy 164.678355 -399.777622) (xy 164.697108 -399.785418) (xy 164.711431 -399.799816) (xy 164.71913 -399.818609)
			(xy 164.719508 -399.828766) (xy 164.719508 -399.986246) (xy 164.719942 -399.995431) (xy 164.726439 -400.012615)
			(xy 164.732208 -400.019774) (xy 164.754078 -400.045435) (xy 164.792166 -400.10107) (xy 164.823316 -400.160867)
			(xy 164.847079 -400.223964) (xy 164.863114 -400.289454) (xy 164.871189 -400.356393) (xy 164.871189 -400.423817)
			(xy 164.863112 -400.490755) (xy 164.847076 -400.556244) (xy 164.823312 -400.619341) (xy 164.792161 -400.679138)
			(xy 164.754072 -400.734773) (xy 164.732208 -400.760438) (xy 164.726414 -400.767585) (xy 164.719897 -400.784774)
			(xy 164.719508 -400.793966) (xy 164.719508 -401.286218) (xy 164.719908 -401.295406) (xy 164.726429 -401.312591)
			(xy 164.732208 -401.319746) (xy 164.75405 -401.345429) (xy 164.792139 -401.401061) (xy 164.82329 -401.460855)
			(xy 164.847055 -401.52395) (xy 164.863092 -401.589436) (xy 164.871169 -401.656373) (xy 164.871171 -401.723794)
			(xy 164.863098 -401.790731) (xy 164.847065 -401.856219) (xy 164.823304 -401.919315) (xy 164.792156 -401.97911)
			(xy 164.75407 -402.034745) (xy 164.732208 -402.06041) (xy 164.726426 -402.067565) (xy 164.719902 -402.084748)
			(xy 164.719508 -402.093938) (xy 164.719508 -402.251418) (xy 164.71899 -402.26154) (xy 164.711265 -402.280253)
			(xy 164.696989 -402.294607) (xy 164.678319 -402.302434) (xy 164.6682 -402.30298) (xy 163.95192 -402.30298)
			(xy 163.941765 -402.302562) (xy 163.923009 -402.294769) (xy 163.908684 -402.280371) (xy 163.900987 -402.261575)
			(xy 163.900612 -402.251418) (xy 163.900612 -402.093938) (xy 163.900181 -402.084753) (xy 163.893681 -402.067569)
			(xy 163.887912 -402.06041) (xy 163.866026 -402.034763) (xy 163.827937 -401.979126) (xy 163.796787 -401.919327)
			(xy 163.773023 -401.856228) (xy 163.756989 -401.790737) (xy 163.748915 -401.723796) (xy 162.620884 -401.723796)
			(xy 162.592013 -401.779214) (xy 162.553924 -401.834847) (xy 162.53206 -401.860512) (xy 162.526271 -401.867662)
			(xy 162.519753 -401.884849) (xy 162.51936 -401.89404) (xy 162.51936 -402.386292) (xy 162.519783 -402.395478)
			(xy 162.526289 -402.412662) (xy 162.53206 -402.41982) (xy 162.553878 -402.445523) (xy 162.591971 -402.501152)
			(xy 162.623126 -402.560942) (xy 162.646895 -402.624034) (xy 162.662935 -402.689519) (xy 162.671015 -402.756454)
			(xy 162.671019 -402.823818) (xy 165.949055 -402.823818) (xy 165.94906 -402.756509) (xy 165.957109 -402.689683)
			(xy 165.973087 -402.624298) (xy 165.996766 -402.561292) (xy 166.027805 -402.501567) (xy 166.065761 -402.44598)
			(xy 166.087552 -402.420328) (xy 166.093368 -402.413197) (xy 166.09987 -402.395995) (xy 166.100252 -402.3868)
			(xy 166.100252 -401.893532) (xy 166.099815 -401.884348) (xy 166.093319 -401.867164) (xy 166.087552 -401.860004)
			(xy 166.065744 -401.834368) (xy 166.027795 -401.77878) (xy 165.996762 -401.719054) (xy 165.97309 -401.656047)
			(xy 165.957118 -401.590663) (xy 165.949075 -401.523838) (xy 165.949077 -401.456532) (xy 165.957123 -401.389707)
			(xy 165.973098 -401.324324) (xy 165.996774 -401.261318) (xy 166.02781 -401.201594) (xy 166.065762 -401.146008)
			(xy 166.087552 -401.120356) (xy 166.093356 -401.113216) (xy 166.099865 -401.096021) (xy 166.100252 -401.086828)
			(xy 166.100252 -400.92884) (xy 166.100754 -400.918694) (xy 166.108527 -400.899952) (xy 166.122899 -400.885629)
			(xy 166.141667 -400.87792) (xy 166.151814 -400.877532) (xy 166.868094 -400.877532) (xy 166.878219 -400.878031)
			(xy 166.896939 -400.885756) (xy 166.911295 -400.900038) (xy 166.919116 -400.918717) (xy 166.919656 -400.92884)
			(xy 166.919656 -401.086828) (xy 166.920063 -401.096015) (xy 166.92658 -401.113199) (xy 166.932356 -401.120356)
			(xy 166.954124 -401.146024) (xy 166.992074 -401.201608) (xy 167.023108 -401.26133) (xy 167.046782 -401.324332)
			(xy 167.062757 -401.389712) (xy 167.070803 -401.456533) (xy 167.070804 -401.523837) (xy 167.062762 -401.590658)
			(xy 167.046791 -401.656039) (xy 167.02312 -401.719043) (xy 167.020682 -401.723736) (xy 168.149234 -401.723736)
			(xy 168.149236 -401.65643) (xy 168.157282 -401.589607) (xy 168.173256 -401.524224) (xy 168.19693 -401.461219)
			(xy 168.227963 -401.401494) (xy 168.265912 -401.345907) (xy 168.2877 -401.320254) (xy 168.293499 -401.31311)
			(xy 168.300012 -401.295919) (xy 168.3004 -401.286726) (xy 168.3004 -400.793458) (xy 168.30001 -400.784269)
			(xy 168.293482 -400.767084) (xy 168.2877 -400.75993) (xy 168.265919 -400.734272) (xy 168.227973 -400.678686)
			(xy 168.196942 -400.618963) (xy 168.17327 -400.555959) (xy 168.157298 -400.490578) (xy 168.149254 -400.423756)
			(xy 168.149253 -400.356453) (xy 168.157296 -400.289631) (xy 168.173267 -400.22425) (xy 168.196938 -400.161246)
			(xy 168.227968 -400.101522) (xy 168.265914 -400.045935) (xy 168.2877 -400.020282) (xy 168.293487 -400.01313)
			(xy 168.300007 -399.995945) (xy 168.3004 -399.986754) (xy 168.3004 -399.828766) (xy 168.300905 -399.818611)
			(xy 168.308683 -399.799848) (xy 168.323045 -399.785485) (xy 168.341807 -399.777705) (xy 168.351962 -399.777204)
			(xy 169.068242 -399.777204) (xy 169.078398 -399.777698) (xy 169.097162 -399.78548) (xy 169.111524 -399.799845)
			(xy 169.119303 -399.81861) (xy 169.119804 -399.828766) (xy 169.119804 -399.986754) (xy 169.120235 -399.995939)
			(xy 169.126734 -400.013124) (xy 169.132504 -400.020282) (xy 169.154296 -400.04593) (xy 169.192242 -400.101518)
			(xy 169.223273 -400.161243) (xy 169.246943 -400.224248) (xy 169.262915 -400.28963) (xy 169.270958 -400.356452)
			(xy 169.270957 -400.423757) (xy 169.262913 -400.490579) (xy 169.246941 -400.555961) (xy 169.223269 -400.618966)
			(xy 169.192237 -400.67869) (xy 169.154291 -400.734277) (xy 169.132504 -400.75993) (xy 169.126713 -400.767079)
			(xy 169.120195 -400.784267) (xy 169.119804 -400.793458) (xy 169.119804 -401.286726) (xy 169.1202 -401.295915)
			(xy 169.126723 -401.313099) (xy 169.132504 -401.320254) (xy 169.154269 -401.345925) (xy 169.192215 -401.401509)
			(xy 169.223247 -401.461231) (xy 169.246919 -401.524233) (xy 169.262893 -401.589612) (xy 169.270938 -401.656432)
			(xy 169.27094 -401.723735) (xy 169.262899 -401.790555) (xy 169.246929 -401.855936) (xy 169.223261 -401.918939)
			(xy 169.192232 -401.978662) (xy 169.154289 -402.034249) (xy 169.132504 -402.059902) (xy 169.126725 -402.067059)
			(xy 169.1202 -402.084241) (xy 169.119804 -402.09343) (xy 169.119804 -402.251418) (xy 169.119283 -402.261572)
			(xy 169.11151 -402.280333) (xy 169.097154 -402.294697) (xy 169.078396 -402.302478) (xy 169.068242 -402.30298)
			(xy 168.351962 -402.30298) (xy 168.341804 -402.302498) (xy 168.323037 -402.294715) (xy 168.308674 -402.280346)
			(xy 168.300898 -402.261576) (xy 168.3004 -402.251418) (xy 168.3004 -402.09343) (xy 168.299975 -402.084244)
			(xy 168.293472 -402.06706) (xy 168.2877 -402.059902) (xy 168.265892 -402.034267) (xy 168.227946 -401.978677)
			(xy 168.196916 -401.918951) (xy 168.173246 -401.855944) (xy 168.157276 -401.79056) (xy 168.149234 -401.723736)
			(xy 167.020682 -401.723736) (xy 166.992089 -401.778766) (xy 166.954142 -401.834352) (xy 166.932356 -401.860004)
			(xy 166.92657 -401.867156) (xy 166.92005 -401.884342) (xy 166.919656 -401.893532) (xy 166.919656 -402.3868)
			(xy 166.920076 -402.395986) (xy 166.926584 -402.41317) (xy 166.932356 -402.420328) (xy 166.954097 -402.446019)
			(xy 166.992047 -402.5016) (xy 167.023083 -402.561318) (xy 167.046758 -402.624317) (xy 167.062735 -402.689695)
			(xy 167.070783 -402.756513) (xy 167.070787 -402.823815) (xy 167.070779 -402.823878) (xy 170.348823 -402.823878)
			(xy 170.348828 -402.75645) (xy 170.356909 -402.689507) (xy 170.372951 -402.624015) (xy 170.396723 -402.560916)
			(xy 170.427882 -402.501119) (xy 170.465979 -402.445484) (xy 170.487848 -402.41982) (xy 170.493667 -402.412691)
			(xy 170.500167 -402.395488) (xy 170.500548 -402.386292) (xy 170.500548 -401.89404) (xy 170.500108 -401.884856)
			(xy 170.493614 -401.867672) (xy 170.487848 -401.860512) (xy 170.465963 -401.834864) (xy 170.427871 -401.779228)
			(xy 170.396719 -401.71943) (xy 170.372954 -401.656331) (xy 170.356918 -401.590839) (xy 170.348843 -401.523898)
			(xy 170.348845 -401.456472) (xy 170.356924 -401.389531) (xy 170.372963 -401.324041) (xy 170.396731 -401.260943)
			(xy 170.427887 -401.201146) (xy 170.465981 -401.145512) (xy 170.487848 -401.119848) (xy 170.493655 -401.112711)
			(xy 170.500162 -401.095514) (xy 170.500548 -401.08632) (xy 170.500548 -400.92884) (xy 170.501117 -400.91874)
			(xy 170.508832 -400.900073) (xy 170.523102 -400.885779) (xy 170.541757 -400.878033) (xy 170.551856 -400.877532)
			(xy 171.268136 -400.877532) (xy 171.278265 -400.877887) (xy 171.296975 -400.885653) (xy 171.311289 -400.899989)
			(xy 171.319028 -400.918711) (xy 171.319444 -400.92884) (xy 171.319444 -401.08632) (xy 171.319857 -401.095507)
			(xy 171.32637 -401.11269) (xy 171.332144 -401.119848) (xy 171.35399 -401.145528) (xy 171.392083 -401.20116)
			(xy 171.423238 -401.260953) (xy 171.447006 -401.324048) (xy 171.463044 -401.389536) (xy 171.471123 -401.456473)
			(xy 171.471124 -401.523897) (xy 171.46305 -401.590834) (xy 171.447015 -401.656323) (xy 171.42325 -401.719419)
			(xy 171.421001 -401.723737) (xy 172.549001 -401.723737) (xy 172.549003 -401.65643) (xy 172.55705 -401.589605)
			(xy 172.573027 -401.524221) (xy 172.596704 -401.461215) (xy 172.627743 -401.401491) (xy 172.665697 -401.345906)
			(xy 172.687488 -401.320254) (xy 172.693285 -401.313109) (xy 172.6998 -401.295918) (xy 172.700188 -401.286726)
			(xy 172.700188 -400.793458) (xy 172.699801 -400.784268) (xy 172.693272 -400.767084) (xy 172.687488 -400.75993)
			(xy 172.665705 -400.734274) (xy 172.627752 -400.678689) (xy 172.596716 -400.618966) (xy 172.573041 -400.555962)
			(xy 172.557066 -400.49058) (xy 172.549021 -400.423757) (xy 172.54902 -400.356452) (xy 172.557065 -400.289629)
			(xy 172.573038 -400.224246) (xy 172.596713 -400.161242) (xy 172.627748 -400.101519) (xy 172.665699 -400.045933)
			(xy 172.687488 -400.020282) (xy 172.693273 -400.013129) (xy 172.699795 -399.995944) (xy 172.700188 -399.986754)
			(xy 172.700188 -399.828766) (xy 172.700537 -399.818586) (xy 172.708343 -399.799781) (xy 172.722752 -399.785395)
			(xy 172.741569 -399.777621) (xy 172.75175 -399.777204) (xy 173.46803 -399.777204) (xy 173.478186 -399.777708)
			(xy 173.496949 -399.785486) (xy 173.511312 -399.799848) (xy 173.519091 -399.818611) (xy 173.519592 -399.828766)
			(xy 173.519592 -399.986754) (xy 173.520026 -399.995939) (xy 173.526523 -400.013123) (xy 173.532292 -400.020282)
			(xy 173.554085 -400.04593) (xy 173.592031 -400.101518) (xy 173.623063 -400.161242) (xy 173.646734 -400.224247)
			(xy 173.662705 -400.289629) (xy 173.670749 -400.356452) (xy 173.670748 -400.423757) (xy 173.662704 -400.490579)
			(xy 173.646731 -400.555962) (xy 173.623059 -400.618966) (xy 173.592027 -400.67869) (xy 173.554079 -400.734277)
			(xy 173.532292 -400.75993) (xy 173.526499 -400.767078) (xy 173.519983 -400.784266) (xy 173.519592 -400.793458)
			(xy 173.519592 -401.286726) (xy 173.519991 -401.295914) (xy 173.526513 -401.313099) (xy 173.532292 -401.320254)
			(xy 173.554057 -401.345924) (xy 173.592005 -401.401509) (xy 173.623037 -401.46123) (xy 173.64671 -401.524232)
			(xy 173.662683 -401.589612) (xy 173.670729 -401.656432) (xy 173.670731 -401.723735) (xy 173.662689 -401.790555)
			(xy 173.64672 -401.855936) (xy 173.623051 -401.918939) (xy 173.592022 -401.978663) (xy 173.554077 -402.034249)
			(xy 173.532292 -402.059902) (xy 173.526511 -402.067058) (xy 173.519987 -402.08424) (xy 173.519592 -402.09343)
			(xy 173.519592 -402.251418) (xy 173.519082 -402.261573) (xy 173.511308 -402.280337) (xy 173.496947 -402.294701)
			(xy 173.478185 -402.30248) (xy 173.46803 -402.30298) (xy 172.75175 -402.30298) (xy 172.741584 -402.302496)
			(xy 172.722794 -402.29473) (xy 172.708408 -402.280363) (xy 172.700618 -402.261584) (xy 172.700188 -402.251418)
			(xy 172.700188 -402.09343) (xy 172.699766 -402.084244) (xy 172.693261 -402.067059) (xy 172.687488 -402.059902)
			(xy 172.665677 -402.034268) (xy 172.627726 -401.97868) (xy 172.596691 -401.918955) (xy 172.573017 -401.855948)
			(xy 172.557044 -401.790563) (xy 172.549001 -401.723737) (xy 171.421001 -401.723737) (xy 171.392099 -401.779215)
			(xy 171.354009 -401.834848) (xy 171.332144 -401.860512) (xy 171.326353 -401.867661) (xy 171.319836 -401.884849)
			(xy 171.319444 -401.89404) (xy 171.319444 -402.386292) (xy 171.31987 -402.395477) (xy 171.326374 -402.412661)
			(xy 171.332144 -402.41982) (xy 171.353963 -402.445523) (xy 171.392057 -402.501151) (xy 171.423213 -402.560941)
			(xy 171.446982 -402.624033) (xy 171.463022 -402.689518) (xy 171.471103 -402.756453) (xy 171.471107 -402.823818)
			(xy 174.749143 -402.823818) (xy 174.749147 -402.75651) (xy 174.757196 -402.689684) (xy 174.773174 -402.624299)
			(xy 174.796852 -402.561292) (xy 174.827891 -402.501567) (xy 174.865845 -402.44598) (xy 174.887636 -402.420328)
			(xy 174.89345 -402.413195) (xy 174.899953 -402.395995) (xy 174.900336 -402.3868) (xy 174.900336 -401.893532)
			(xy 174.899902 -401.884348) (xy 174.893404 -401.867163) (xy 174.887636 -401.860004) (xy 174.865829 -401.834368)
			(xy 174.827881 -401.778779) (xy 174.796848 -401.719053) (xy 174.773177 -401.656047) (xy 174.757205 -401.590663)
			(xy 174.749163 -401.523838) (xy 174.749165 -401.456532) (xy 174.757211 -401.389708) (xy 174.773186 -401.324324)
			(xy 174.796861 -401.261319) (xy 174.827896 -401.201595) (xy 174.865847 -401.146008) (xy 174.887636 -401.120356)
			(xy 174.893438 -401.113215) (xy 174.899949 -401.096021) (xy 174.900336 -401.086828) (xy 174.900336 -400.92884)
			(xy 174.900755 -400.918684) (xy 174.908544 -400.899926) (xy 174.922943 -400.8856) (xy 174.94174 -400.877905)
			(xy 174.951898 -400.877532) (xy 175.668178 -400.877532) (xy 175.678302 -400.878044) (xy 175.697022 -400.885763)
			(xy 175.711378 -400.900042) (xy 175.7192 -400.918718) (xy 175.71974 -400.92884) (xy 175.71974 -401.086828)
			(xy 175.72015 -401.096015) (xy 175.726665 -401.113198) (xy 175.73244 -401.120356) (xy 175.754209 -401.146024)
			(xy 175.792159 -401.201608) (xy 175.823195 -401.261329) (xy 175.846869 -401.324331) (xy 175.862844 -401.389712)
			(xy 175.870891 -401.456533) (xy 175.870892 -401.523837) (xy 175.86285 -401.590658) (xy 175.846878 -401.65604)
			(xy 175.823207 -401.719044) (xy 175.792175 -401.778766) (xy 175.754227 -401.834352) (xy 175.73244 -401.860004)
			(xy 175.726652 -401.867155) (xy 175.720134 -401.884341) (xy 175.71974 -401.893532) (xy 175.71974 -402.3868)
			(xy 175.720164 -402.395985) (xy 175.726669 -402.413169) (xy 175.73244 -402.420328) (xy 175.754181 -402.446019)
			(xy 175.792133 -402.501599) (xy 175.823169 -402.561317) (xy 175.846846 -402.624317) (xy 175.862823 -402.689694)
			(xy 175.870871 -402.756513) (xy 175.870875 -402.823815) (xy 175.862835 -402.890634) (xy 175.846867 -402.956014)
			(xy 175.823199 -403.019017) (xy 175.79217 -403.078739) (xy 175.754225 -403.134324) (xy 175.73244 -403.159976)
			(xy 175.726621 -403.167105) (xy 175.720122 -403.184308) (xy 175.71974 -403.193504) (xy 175.71974 -403.351492)
			(xy 175.719273 -403.361641) (xy 175.711487 -403.380385) (xy 175.697105 -403.394707) (xy 175.678328 -403.402415)
			(xy 175.668178 -403.4028) (xy 174.951898 -403.4028) (xy 174.941776 -403.402276) (xy 174.923063 -403.394555)
			(xy 174.908708 -403.380281) (xy 174.900882 -403.361611) (xy 174.900336 -403.351492) (xy 174.900336 -403.193504)
			(xy 174.899916 -403.184318) (xy 174.893408 -403.167134) (xy 174.887636 -403.159976) (xy 174.865801 -403.134363)
			(xy 174.827854 -403.078771) (xy 174.796823 -403.019042) (xy 174.773153 -402.956032) (xy 174.757183 -402.890645)
			(xy 174.749143 -402.823818) (xy 171.471107 -402.823818) (xy 171.471107 -402.823874) (xy 171.463035 -402.89081)
			(xy 171.447003 -402.956298) (xy 171.423242 -403.019393) (xy 171.392094 -403.079187) (xy 171.354007 -403.13482)
			(xy 171.332144 -403.160484) (xy 171.326322 -403.167611) (xy 171.319824 -403.184816) (xy 171.319444 -403.194012)
			(xy 171.319444 -403.351492) (xy 171.318909 -403.361595) (xy 171.311183 -403.380264) (xy 171.296901 -403.394558)
			(xy 171.278238 -403.402301) (xy 171.268136 -403.4028) (xy 170.551856 -403.4028) (xy 170.541744 -403.402351)
			(xy 170.523065 -403.394599) (xy 170.508772 -403.380291) (xy 170.501039 -403.361604) (xy 170.500548 -403.351492)
			(xy 170.500548 -403.194012) (xy 170.500121 -403.184827) (xy 170.493618 -403.167643) (xy 170.487848 -403.160484)
			(xy 170.465935 -403.134858) (xy 170.427845 -403.079219) (xy 170.396693 -403.019418) (xy 170.37293 -402.956316)
			(xy 170.356896 -402.890822) (xy 170.348823 -402.823878) (xy 167.070779 -402.823878) (xy 167.062748 -402.890634)
			(xy 167.04678 -402.956014) (xy 167.023112 -403.019016) (xy 166.992084 -403.078738) (xy 166.954141 -403.134324)
			(xy 166.932356 -403.159976) (xy 166.926539 -403.167107) (xy 166.920038 -403.184308) (xy 166.919656 -403.193504)
			(xy 166.919656 -403.351492) (xy 166.919173 -403.361639) (xy 166.911391 -403.38038) (xy 166.897014 -403.394702)
			(xy 166.878242 -403.402412) (xy 166.868094 -403.4028) (xy 166.151814 -403.4028) (xy 166.141693 -403.402263)
			(xy 166.12298 -403.394547) (xy 166.108624 -403.380277) (xy 166.100798 -403.36161) (xy 166.100252 -403.351492)
			(xy 166.100252 -403.193504) (xy 166.099828 -403.184318) (xy 166.093323 -403.167135) (xy 166.087552 -403.159976)
			(xy 166.065717 -403.134363) (xy 166.027768 -403.078771) (xy 165.996736 -403.019042) (xy 165.973066 -402.956033)
			(xy 165.957096 -402.890646) (xy 165.949055 -402.823818) (xy 162.671019 -402.823818) (xy 162.671019 -402.823874)
			(xy 162.662948 -402.89081) (xy 162.646916 -402.956297) (xy 162.623155 -403.019392) (xy 162.592008 -403.079187)
			(xy 162.553923 -403.13482) (xy 162.53206 -403.160484) (xy 162.52624 -403.167613) (xy 162.51974 -403.184816)
			(xy 162.51936 -403.194012) (xy 162.51936 -403.351492) (xy 162.518976 -403.361619) (xy 162.511224 -403.38033)
			(xy 162.496896 -403.394646) (xy 162.478179 -403.402384) (xy 162.468052 -403.4028) (xy 161.751772 -403.4028)
			(xy 161.741661 -403.402338) (xy 161.722983 -403.394591) (xy 161.708689 -403.380287) (xy 161.700955 -403.361603)
			(xy 161.700464 -403.351492) (xy 161.700464 -403.194012) (xy 161.700034 -403.184827) (xy 161.693532 -403.167643)
			(xy 161.687764 -403.160484) (xy 161.665854 -403.134857) (xy 161.627769 -403.079216) (xy 161.596623 -403.019414)
			(xy 161.572863 -402.956313) (xy 161.556832 -402.890819) (xy 161.54876 -402.823877) (xy 154.57678 -402.823877)
			(xy 154.57678 -405.623648) (xy 159.349158 -405.623648) (xy 159.349158 -405.556343) (xy 159.357202 -405.48952)
			(xy 159.373175 -405.424138) (xy 159.396848 -405.361133) (xy 159.427881 -405.301409) (xy 159.465829 -405.245822)
			(xy 159.487616 -405.22017) (xy 159.49341 -405.213023) (xy 159.499926 -405.195834) (xy 159.500316 -405.186642)
			(xy 159.500316 -404.693374) (xy 159.499915 -404.684186) (xy 159.493395 -404.667002) (xy 159.487616 -404.659846)
			(xy 159.465851 -404.634176) (xy 159.427903 -404.578591) (xy 159.39687 -404.51887) (xy 159.373197 -404.455868)
			(xy 159.357223 -404.390488) (xy 159.349177 -404.323668) (xy 159.349175 -404.256365) (xy 159.357217 -404.189544)
			(xy 159.373187 -404.124164) (xy 159.396856 -404.06116) (xy 159.427886 -404.001437) (xy 159.46583 -403.94585)
			(xy 159.487616 -403.920198) (xy 159.493398 -403.913042) (xy 159.499921 -403.89586) (xy 159.500316 -403.88667)
			(xy 159.500316 -403.728682) (xy 159.500818 -403.718526) (xy 159.508594 -403.69976) (xy 159.522957 -403.685396)
			(xy 159.541722 -403.677619) (xy 159.551878 -403.67712) (xy 160.268158 -403.67712) (xy 160.278325 -403.677598)
			(xy 160.297115 -403.685366) (xy 160.311501 -403.699735) (xy 160.31929 -403.718516) (xy 160.31972 -403.728682)
			(xy 160.31972 -403.88667) (xy 160.32014 -403.895856) (xy 160.326646 -403.913041) (xy 160.33242 -403.920198)
			(xy 160.354231 -403.945832) (xy 160.392181 -404.00142) (xy 160.423216 -404.061146) (xy 160.446889 -404.124153)
			(xy 160.462862 -404.189538) (xy 160.470905 -404.256363) (xy 160.470903 -404.32367) (xy 160.462856 -404.390495)
			(xy 160.446879 -404.455879) (xy 160.423202 -404.518885) (xy 160.392164 -404.578608) (xy 160.35421 -404.634194)
			(xy 160.33242 -404.659846) (xy 160.326624 -404.666992) (xy 160.320108 -404.684182) (xy 160.31972 -404.693374)
			(xy 160.31972 -405.186642) (xy 160.320105 -405.195832) (xy 160.326636 -405.213016) (xy 160.33242 -405.22017)
			(xy 160.354203 -405.245826) (xy 160.392155 -405.301411) (xy 160.42319 -405.361134) (xy 160.446865 -405.424138)
			(xy 160.46284 -405.48952) (xy 160.470885 -405.556343) (xy 160.470886 -405.623648) (xy 160.462842 -405.690471)
			(xy 160.446868 -405.755853) (xy 160.423194 -405.818858) (xy 160.392159 -405.878581) (xy 160.354209 -405.934166)
			(xy 160.33242 -405.959818) (xy 160.326636 -405.966972) (xy 160.320113 -405.984156) (xy 160.31972 -405.993346)
			(xy 160.31972 -406.151334) (xy 160.319363 -406.161513) (xy 160.311559 -406.180317) (xy 160.297153 -406.194702)
			(xy 160.278338 -406.202478) (xy 160.268158 -406.202896) (xy 159.551878 -406.202896) (xy 159.541723 -406.202386)
			(xy 159.52296 -406.19461) (xy 159.508596 -406.18025) (xy 159.500817 -406.161489) (xy 159.500316 -406.151334)
			(xy 159.500316 -405.993346) (xy 159.49988 -405.984162) (xy 159.493384 -405.966977) (xy 159.487616 -405.959818)
			(xy 159.465823 -405.93417) (xy 159.427876 -405.878583) (xy 159.396844 -405.818858) (xy 159.373173 -405.755853)
			(xy 159.357201 -405.690471) (xy 159.349158 -405.623648) (xy 154.57678 -405.623648) (xy 154.57678 -406.723789)
			(xy 161.548771 -406.723789) (xy 161.548774 -406.656363) (xy 161.556853 -406.589423) (xy 161.572891 -406.523933)
			(xy 161.596657 -406.460835) (xy 161.627809 -406.401038) (xy 161.665899 -406.345402) (xy 161.687764 -406.319736)
			(xy 161.693578 -406.312604) (xy 161.70008 -406.295403) (xy 161.700464 -406.286208) (xy 161.700464 -405.793956)
			(xy 161.700061 -405.784768) (xy 161.693541 -405.767585) (xy 161.687764 -405.760428) (xy 161.665897 -405.734765)
			(xy 161.627811 -405.67913) (xy 161.596663 -405.619333) (xy 161.5729 -405.556236) (xy 161.556866 -405.490747)
			(xy 161.548791 -405.423809) (xy 161.548792 -405.356385) (xy 161.556867 -405.289447) (xy 161.572902 -405.223959)
			(xy 161.596665 -405.160862) (xy 161.627814 -405.101065) (xy 161.665901 -405.04543) (xy 161.687764 -405.019764)
			(xy 161.693566 -405.012623) (xy 161.700076 -404.995429) (xy 161.700464 -404.986236) (xy 161.700464 -404.828756)
			(xy 161.700948 -404.818649) (xy 161.708694 -404.799977) (xy 161.72299 -404.785685) (xy 161.741665 -404.777945)
			(xy 161.751772 -404.777448) (xy 162.468052 -404.777448) (xy 162.478165 -404.777954) (xy 162.496858 -404.785677)
			(xy 162.511172 -404.799965) (xy 162.518928 -404.818644) (xy 162.51936 -404.828756) (xy 162.51936 -404.986236)
			(xy 162.519762 -404.995424) (xy 162.526282 -405.012608) (xy 162.53206 -405.019764) (xy 162.553921 -405.045432)
			(xy 162.592013 -405.101065) (xy 162.623166 -405.16086) (xy 162.646932 -405.223957) (xy 162.662969 -405.289446)
			(xy 162.671046 -405.356385) (xy 162.671046 -405.423809) (xy 162.66297 -405.490748) (xy 162.646934 -405.556237)
			(xy 162.623168 -405.619334) (xy 162.620889 -405.623708) (xy 163.748926 -405.623708) (xy 163.748926 -405.556283)
			(xy 163.757003 -405.489344) (xy 163.77304 -405.423855) (xy 163.796805 -405.360758) (xy 163.827957 -405.300961)
			(xy 163.866047 -405.245327) (xy 163.887912 -405.219662) (xy 163.893709 -405.212517) (xy 163.900223 -405.195326)
			(xy 163.900612 -405.186134) (xy 163.900612 -404.693882) (xy 163.900208 -404.684694) (xy 163.89369 -404.66751)
			(xy 163.887912 -404.660354) (xy 163.866069 -404.634671) (xy 163.827979 -404.579039) (xy 163.796827 -404.519246)
			(xy 163.773061 -404.456151) (xy 163.757023 -404.390664) (xy 163.748946 -404.323728) (xy 163.748944 -404.256305)
			(xy 163.757018 -404.189368) (xy 163.773051 -404.12388) (xy 163.796813 -404.060784) (xy 163.827962 -404.000989)
			(xy 163.866049 -403.945355) (xy 163.887912 -403.91969) (xy 163.893697 -403.912536) (xy 163.900218 -403.895352)
			(xy 163.900612 -403.886162) (xy 163.900612 -403.728682) (xy 163.901111 -403.718558) (xy 163.908839 -403.699841)
			(xy 163.923121 -403.685486) (xy 163.941798 -403.677663) (xy 163.95192 -403.67712) (xy 164.6682 -403.67712)
			(xy 164.678357 -403.677522) (xy 164.697113 -403.685321) (xy 164.711437 -403.699724) (xy 164.719133 -403.718523)
			(xy 164.719508 -403.728682) (xy 164.719508 -403.886162) (xy 164.719935 -403.895347) (xy 164.726437 -403.912532)
			(xy 164.732208 -403.91969) (xy 164.754093 -403.945338) (xy 164.792181 -404.000975) (xy 164.82333 -404.060774)
			(xy 164.847093 -404.123873) (xy 164.863126 -404.189364) (xy 164.8712 -404.256304) (xy 164.871198 -404.323729)
			(xy 164.86312 -404.390669) (xy 164.847083 -404.456159) (xy 164.823317 -404.519257) (xy 164.792164 -404.579054)
			(xy 164.754073 -404.634689) (xy 164.732208 -404.660354) (xy 164.726407 -404.667496) (xy 164.719895 -404.684689)
			(xy 164.719508 -404.693882) (xy 164.719508 -405.186134) (xy 164.7199 -405.195323) (xy 164.726426 -405.212508)
			(xy 164.732208 -405.219662) (xy 164.754066 -405.245332) (xy 164.792154 -405.300966) (xy 164.823305 -405.360762)
			(xy 164.847069 -405.423858) (xy 164.863104 -405.489346) (xy 164.871181 -405.556284) (xy 164.871181 -405.623707)
			(xy 164.863106 -405.690645) (xy 164.847072 -405.756133) (xy 164.823308 -405.81923) (xy 164.792159 -405.879026)
			(xy 164.754071 -405.934661) (xy 164.732208 -405.960326) (xy 164.726419 -405.967477) (xy 164.719899 -405.984663)
			(xy 164.719508 -405.993854) (xy 164.719508 -406.151334) (xy 164.719003 -406.161457) (xy 164.711273 -406.18017)
			(xy 164.696993 -406.194523) (xy 164.67832 -406.20235) (xy 164.6682 -406.202896) (xy 163.95192 -406.202896)
			(xy 163.941767 -406.202462) (xy 163.923014 -406.194672) (xy 163.90869 -406.180279) (xy 163.90099 -406.161489)
			(xy 163.900612 -406.151334) (xy 163.900612 -405.993854) (xy 163.900173 -405.98467) (xy 163.893679 -405.967485)
			(xy 163.887912 -405.960326) (xy 163.866042 -405.934666) (xy 163.827952 -405.879031) (xy 163.796801 -405.819234)
			(xy 163.773037 -405.756137) (xy 163.757001 -405.690647) (xy 163.748926 -405.623708) (xy 162.620889 -405.623708)
			(xy 162.592016 -405.67913) (xy 162.553925 -405.734763) (xy 162.53206 -405.760428) (xy 162.526264 -405.767573)
			(xy 162.51975 -405.784764) (xy 162.51936 -405.793956) (xy 162.51936 -406.286208) (xy 162.519775 -406.295394)
			(xy 162.526286 -406.312578) (xy 162.53206 -406.319736) (xy 162.553894 -406.345426) (xy 162.591986 -406.401056)
			(xy 162.623141 -406.460849) (xy 162.646908 -406.523942) (xy 162.662947 -406.589429) (xy 162.671026 -406.656365)
			(xy 162.671029 -406.72373) (xy 165.949066 -406.72373) (xy 165.949069 -406.656422) (xy 165.957117 -406.589597)
			(xy 165.973094 -406.524213) (xy 165.996771 -406.461207) (xy 166.027808 -406.401483) (xy 166.065762 -406.345896)
			(xy 166.087552 -406.320244) (xy 166.093361 -406.313108) (xy 166.099867 -406.29591) (xy 166.100252 -406.286716)
			(xy 166.100252 -405.793448) (xy 166.099807 -405.784265) (xy 166.093316 -405.767081) (xy 166.087552 -405.75992)
			(xy 166.06576 -405.734271) (xy 166.027811 -405.678685) (xy 165.996777 -405.618961) (xy 165.973104 -405.555956)
			(xy 165.957131 -405.490573) (xy 165.949087 -405.42375) (xy 165.949087 -405.356444) (xy 165.957132 -405.289621)
			(xy 165.973105 -405.224239) (xy 165.996779 -405.161234) (xy 166.027814 -405.10151) (xy 166.065764 -405.045924)
			(xy 166.087552 -405.020272) (xy 166.093349 -405.013128) (xy 166.099862 -404.995936) (xy 166.100252 -404.986744)
			(xy 166.100252 -404.828756) (xy 166.100685 -404.818605) (xy 166.108486 -404.799861) (xy 166.122878 -404.785541)
			(xy 166.141661 -404.777834) (xy 166.151814 -404.777448) (xy 166.868094 -404.777448) (xy 166.878221 -404.777932)
			(xy 166.896944 -404.785659) (xy 166.911301 -404.799946) (xy 166.919119 -404.818631) (xy 166.919656 -404.828756)
			(xy 166.919656 -404.986744) (xy 166.920055 -404.995932) (xy 166.926578 -405.013116) (xy 166.932356 -405.020272)
			(xy 166.95414 -405.045927) (xy 166.992089 -405.101513) (xy 167.023123 -405.161236) (xy 167.046796 -405.22424)
			(xy 167.062769 -405.289622) (xy 167.070814 -405.356445) (xy 167.070814 -405.423749) (xy 167.06277 -405.490572)
			(xy 167.046798 -405.555954) (xy 167.023125 -405.618958) (xy 167.020688 -405.623648) (xy 168.149245 -405.623648)
			(xy 168.149246 -405.556343) (xy 168.15729 -405.489521) (xy 168.173263 -405.424139) (xy 168.196934 -405.361134)
			(xy 168.227966 -405.30141) (xy 168.265913 -405.245823) (xy 168.2877 -405.22017) (xy 168.293492 -405.213021)
			(xy 168.300009 -405.195834) (xy 168.3004 -405.186642) (xy 168.3004 -404.693374) (xy 168.300003 -404.684185)
			(xy 168.29348 -404.667001) (xy 168.2877 -404.659846) (xy 168.265935 -404.634176) (xy 168.227988 -404.578591)
			(xy 168.196956 -404.518869) (xy 168.173284 -404.455867) (xy 168.15731 -404.390488) (xy 168.149265 -404.323668)
			(xy 168.149263 -404.256365) (xy 168.157305 -404.189545) (xy 168.173274 -404.124164) (xy 168.196943 -404.061161)
			(xy 168.227971 -404.001438) (xy 168.265915 -403.945851) (xy 168.2877 -403.920198) (xy 168.29348 -403.913041)
			(xy 168.300005 -403.89586) (xy 168.3004 -403.88667) (xy 168.3004 -403.728682) (xy 168.300917 -403.718528)
			(xy 168.308691 -403.699765) (xy 168.323049 -403.685402) (xy 168.341808 -403.677621) (xy 168.351962 -403.67712)
			(xy 169.068242 -403.67712) (xy 169.0784 -403.677599) (xy 169.097167 -403.685383) (xy 169.11153 -403.699753)
			(xy 169.119306 -403.718524) (xy 169.119804 -403.728682) (xy 169.119804 -403.88667) (xy 169.120228 -403.895856)
			(xy 169.126732 -403.91304) (xy 169.132504 -403.920198) (xy 169.154312 -403.945833) (xy 169.192257 -404.001423)
			(xy 169.223287 -404.061149) (xy 169.246957 -404.124156) (xy 169.262927 -404.18954) (xy 169.270969 -404.256364)
			(xy 169.270967 -404.32367) (xy 169.262921 -404.390493) (xy 169.246947 -404.455876) (xy 169.223274 -404.518881)
			(xy 169.19224 -404.578606) (xy 169.154292 -404.634193) (xy 169.132504 -404.659846) (xy 169.126706 -404.66699)
			(xy 169.120192 -404.684181) (xy 169.119804 -404.693374) (xy 169.119804 -405.186642) (xy 169.120193 -405.195832)
			(xy 169.126721 -405.213016) (xy 169.132504 -405.22017) (xy 169.154284 -405.245828) (xy 169.192231 -405.301414)
			(xy 169.223262 -405.361137) (xy 169.246933 -405.424141) (xy 169.262905 -405.489522) (xy 169.270949 -405.556344)
			(xy 169.27095 -405.623647) (xy 169.262907 -405.690469) (xy 169.246936 -405.75585) (xy 169.223266 -405.818854)
			(xy 169.192235 -405.878578) (xy 169.15429 -405.934165) (xy 169.132504 -405.959818) (xy 169.126718 -405.966971)
			(xy 169.120197 -405.984155) (xy 169.119804 -405.993346) (xy 169.119804 -406.151334) (xy 169.119296 -406.161489)
			(xy 169.111518 -406.180251) (xy 169.097157 -406.194613) (xy 169.078397 -406.202394) (xy 169.068242 -406.202896)
			(xy 168.351962 -406.202896) (xy 168.341806 -406.202399) (xy 168.323042 -406.194618) (xy 168.30868 -406.180254)
			(xy 168.300901 -406.16149) (xy 168.3004 -406.151334) (xy 168.3004 -405.993346) (xy 168.299968 -405.984161)
			(xy 168.293469 -405.966977) (xy 168.2877 -405.959818) (xy 168.265908 -405.93417) (xy 168.227961 -405.878582)
			(xy 168.196931 -405.818858) (xy 168.17326 -405.755853) (xy 168.157289 -405.69047) (xy 168.149245 -405.623648)
			(xy 167.020688 -405.623648) (xy 166.992092 -405.678681) (xy 166.954143 -405.734268) (xy 166.932356 -405.75992)
			(xy 166.926563 -405.767067) (xy 166.920047 -405.784256) (xy 166.919656 -405.793448) (xy 166.919656 -406.286716)
			(xy 166.920068 -406.295903) (xy 166.926582 -406.313087) (xy 166.932356 -406.320244) (xy 166.954112 -406.345922)
			(xy 166.992062 -406.401505) (xy 167.023097 -406.461225) (xy 167.046772 -406.524226) (xy 167.062747 -406.589605)
			(xy 167.070794 -406.656425) (xy 167.070797 -406.723727) (xy 167.070789 -406.72379) (xy 170.348835 -406.72379)
			(xy 170.348838 -406.656362) (xy 170.356917 -406.589421) (xy 170.372958 -406.52393) (xy 170.396728 -406.460831)
			(xy 170.427885 -406.401034) (xy 170.46598 -406.3454) (xy 170.487848 -406.319736) (xy 170.49366 -406.312602)
			(xy 170.500164 -406.295403) (xy 170.500548 -406.286208) (xy 170.500548 -405.793956) (xy 170.500148 -405.784768)
			(xy 170.493626 -405.767584) (xy 170.487848 -405.760428) (xy 170.465978 -405.734767) (xy 170.427887 -405.679133)
			(xy 170.396733 -405.619337) (xy 170.372967 -405.556239) (xy 170.356931 -405.490749) (xy 170.348854 -405.423809)
			(xy 170.348855 -405.356385) (xy 170.356932 -405.289445) (xy 170.372969 -405.223955) (xy 170.396736 -405.160858)
			(xy 170.42789 -405.101062) (xy 170.465982 -405.045428) (xy 170.487848 -405.019764) (xy 170.493648 -405.012622)
			(xy 170.500159 -404.995429) (xy 170.500548 -404.986236) (xy 170.500548 -404.828756) (xy 170.501048 -404.818651)
			(xy 170.50879 -404.799982) (xy 170.523082 -404.78569) (xy 170.541751 -404.777948) (xy 170.551856 -404.777448)
			(xy 171.268136 -404.777448) (xy 171.278241 -404.777954) (xy 171.29691 -404.785694) (xy 171.311201 -404.799984)
			(xy 171.318944 -404.818651) (xy 171.319444 -404.828756) (xy 171.319444 -404.986236) (xy 171.31985 -404.995423)
			(xy 171.326368 -405.012607) (xy 171.332144 -405.019764) (xy 171.354006 -405.045432) (xy 171.392099 -405.101064)
			(xy 171.423253 -405.16086) (xy 171.447019 -405.223956) (xy 171.463057 -405.289446) (xy 171.471134 -405.356385)
			(xy 171.471134 -405.423809) (xy 171.463058 -405.490748) (xy 171.447021 -405.556238) (xy 171.423255 -405.619335)
			(xy 171.421007 -405.623649) (xy 172.549012 -405.623649) (xy 172.549013 -405.556342) (xy 172.557058 -405.489518)
			(xy 172.573033 -405.424135) (xy 172.596709 -405.36113) (xy 172.627746 -405.301407) (xy 172.665698 -405.245822)
			(xy 172.687488 -405.22017) (xy 172.693278 -405.21302) (xy 172.699797 -405.195833) (xy 172.700188 -405.186642)
			(xy 172.700188 -404.693374) (xy 172.699793 -404.684185) (xy 172.693269 -404.667001) (xy 172.687488 -404.659846)
			(xy 172.66572 -404.634177) (xy 172.627768 -404.578594) (xy 172.596731 -404.518873) (xy 172.573055 -404.455871)
			(xy 172.557079 -404.39049) (xy 172.549032 -404.323669) (xy 172.54903 -404.256364) (xy 172.557073 -404.189542)
			(xy 172.573045 -404.124161) (xy 172.596717 -404.061157) (xy 172.627751 -404.001435) (xy 172.6657 -403.945849)
			(xy 172.687488 -403.920198) (xy 172.693267 -403.91304) (xy 172.699792 -403.895859) (xy 172.700188 -403.88667)
			(xy 172.700188 -403.728682) (xy 172.70055 -403.718503) (xy 172.708351 -403.699698) (xy 172.722756 -403.685313)
			(xy 172.74157 -403.677537) (xy 172.75175 -403.67712) (xy 173.46803 -403.67712) (xy 173.478187 -403.677608)
			(xy 173.496954 -403.685389) (xy 173.511317 -403.699756) (xy 173.519094 -403.718524) (xy 173.519592 -403.728682)
			(xy 173.519592 -403.88667) (xy 173.520018 -403.895855) (xy 173.526521 -403.91304) (xy 173.532292 -403.920198)
			(xy 173.5541 -403.945833) (xy 173.592047 -404.001422) (xy 173.623077 -404.061149) (xy 173.646747 -404.124155)
			(xy 173.662718 -404.189539) (xy 173.67076 -404.256363) (xy 173.670758 -404.32367) (xy 173.662712 -404.390493)
			(xy 173.646738 -404.455876) (xy 173.623064 -404.518882) (xy 173.59203 -404.578606) (xy 173.55408 -404.634193)
			(xy 173.532292 -404.659846) (xy 173.526492 -404.666989) (xy 173.51998 -404.684181) (xy 173.519592 -404.693374)
			(xy 173.519592 -405.186642) (xy 173.519984 -405.195831) (xy 173.52651 -405.213015) (xy 173.532292 -405.22017)
			(xy 173.554073 -405.245827) (xy 173.59202 -405.301414) (xy 173.623052 -405.361137) (xy 173.646723 -405.424141)
			(xy 173.662696 -405.489522) (xy 173.67074 -405.556343) (xy 173.670741 -405.623647) (xy 173.662698 -405.690469)
			(xy 173.646726 -405.755851) (xy 173.623055 -405.818855) (xy 173.592025 -405.878578) (xy 173.554078 -405.934165)
			(xy 173.532292 -405.959818) (xy 173.526504 -405.96697) (xy 173.519985 -405.984155) (xy 173.519592 -405.993346)
			(xy 173.519592 -406.151334) (xy 173.519095 -406.16149) (xy 173.511315 -406.180254) (xy 173.496951 -406.194617)
			(xy 173.478186 -406.202396) (xy 173.46803 -406.202896) (xy 172.75175 -406.202896) (xy 172.741586 -406.202396)
			(xy 172.722799 -406.194634) (xy 172.708413 -406.180272) (xy 172.70062 -406.161497) (xy 172.700188 -406.151334)
			(xy 172.700188 -405.993346) (xy 172.699759 -405.984161) (xy 172.693259 -405.966976) (xy 172.687488 -405.959818)
			(xy 172.665693 -405.934171) (xy 172.627741 -405.878585) (xy 172.596705 -405.818861) (xy 172.573031 -405.755856)
			(xy 172.557057 -405.690473) (xy 172.549012 -405.623649) (xy 171.421007 -405.623649) (xy 171.392102 -405.67913)
			(xy 171.35401 -405.734764) (xy 171.332144 -405.760428) (xy 171.326346 -405.767572) (xy 171.319834 -405.784764)
			(xy 171.319444 -405.793956) (xy 171.319444 -406.286208) (xy 171.319863 -406.295394) (xy 171.326372 -406.312578)
			(xy 171.332144 -406.319736) (xy 171.353978 -406.345426) (xy 171.392072 -406.401056) (xy 171.423227 -406.460848)
			(xy 171.446996 -406.523942) (xy 171.463035 -406.589428) (xy 171.471114 -406.656365) (xy 171.471117 -406.72373)
			(xy 174.749154 -406.72373) (xy 174.749157 -406.656422) (xy 174.757205 -406.589597) (xy 174.773181 -406.524213)
			(xy 174.796857 -406.461208) (xy 174.827894 -406.401483) (xy 174.865846 -406.345896) (xy 174.887636 -406.320244)
			(xy 174.893443 -406.313107) (xy 174.899951 -406.29591) (xy 174.900336 -406.286716) (xy 174.900336 -405.793448)
			(xy 174.899895 -405.784264) (xy 174.893402 -405.76708) (xy 174.887636 -405.75992) (xy 174.865844 -405.734271)
			(xy 174.827896 -405.678684) (xy 174.796863 -405.61896) (xy 174.77319 -405.555955) (xy 174.757218 -405.490573)
			(xy 174.749174 -405.42375) (xy 174.749174 -405.356444) (xy 174.757219 -405.289621) (xy 174.773192 -405.224239)
			(xy 174.796865 -405.161234) (xy 174.827899 -405.101511) (xy 174.865848 -405.045924) (xy 174.887636 -405.020272)
			(xy 174.893432 -405.013126) (xy 174.899946 -404.995936) (xy 174.900336 -404.986744) (xy 174.900336 -404.828756)
			(xy 174.900686 -404.818594) (xy 174.908503 -404.799834) (xy 174.922922 -404.785511) (xy 174.941734 -404.77782)
			(xy 174.951898 -404.777448) (xy 175.668178 -404.777448) (xy 175.678304 -404.777945) (xy 175.697027 -404.785667)
			(xy 175.711384 -404.79995) (xy 175.719202 -404.818632) (xy 175.71974 -404.828756) (xy 175.71974 -404.986744)
			(xy 175.720142 -404.995932) (xy 175.726663 -405.013115) (xy 175.73244 -405.020272) (xy 175.754224 -405.045927)
			(xy 175.792175 -405.101513) (xy 175.823209 -405.161236) (xy 175.846883 -405.22424) (xy 175.862857 -405.289622)
			(xy 175.870902 -405.356444) (xy 175.870902 -405.42375) (xy 175.862858 -405.490572) (xy 175.846885 -405.555954)
			(xy 175.823212 -405.618959) (xy 175.792178 -405.678682) (xy 175.754228 -405.734268) (xy 175.73244 -405.75992)
			(xy 175.726645 -405.767066) (xy 175.720131 -405.784256) (xy 175.71974 -405.793448) (xy 175.71974 -406.286716)
			(xy 175.720156 -406.295902) (xy 175.726667 -406.313086) (xy 175.73244 -406.320244) (xy 175.754197 -406.345922)
			(xy 175.792148 -406.401504) (xy 175.823184 -406.461224) (xy 175.846859 -406.524225) (xy 175.862835 -406.589604)
			(xy 175.870882 -406.656424) (xy 175.870885 -406.723727) (xy 175.862844 -406.790548) (xy 175.846873 -406.855929)
			(xy 175.823203 -406.918932) (xy 175.792173 -406.978655) (xy 175.754226 -407.03424) (xy 175.73244 -407.059892)
			(xy 175.726657 -407.067046) (xy 175.720136 -407.08423) (xy 175.71974 -407.09342) (xy 175.71974 -407.251408)
			(xy 175.719286 -407.261558) (xy 175.711495 -407.280302) (xy 175.697109 -407.294624) (xy 175.678329 -407.302331)
			(xy 175.668178 -407.302716) (xy 174.951898 -407.302716) (xy 174.941766 -407.302274) (xy 174.923036 -407.294537)
			(xy 174.908679 -407.280237) (xy 174.900867 -407.261538) (xy 174.900336 -407.251408) (xy 174.900336 -407.09342)
			(xy 174.899908 -407.084235) (xy 174.893406 -407.067051) (xy 174.887636 -407.059892) (xy 174.865817 -407.034266)
			(xy 174.827869 -406.978676) (xy 174.796837 -406.918948) (xy 174.773167 -406.85594) (xy 174.757196 -406.790555)
			(xy 174.749154 -406.72373) (xy 171.471117 -406.72373) (xy 171.471117 -406.723787) (xy 171.463044 -406.790724)
			(xy 171.44701 -406.856212) (xy 171.423247 -406.919308) (xy 171.392097 -406.979103) (xy 171.354008 -407.034736)
			(xy 171.332144 -407.0604) (xy 171.326358 -407.067552) (xy 171.319839 -407.084738) (xy 171.319444 -407.093928)
			(xy 171.319444 -407.251408) (xy 171.318922 -407.261512) (xy 171.31119 -407.280182) (xy 171.296905 -407.294475)
			(xy 171.278239 -407.302217) (xy 171.268136 -407.302716) (xy 170.551856 -407.302716) (xy 170.541746 -407.302251)
			(xy 170.52307 -407.294502) (xy 170.508778 -407.280199) (xy 170.501042 -407.261518) (xy 170.500548 -407.251408)
			(xy 170.500548 -407.093928) (xy 170.500114 -407.084744) (xy 170.493616 -407.067559) (xy 170.487848 -407.0604)
			(xy 170.465951 -407.034762) (xy 170.42786 -406.979124) (xy 170.396708 -406.919325) (xy 170.372944 -406.856224)
			(xy 170.356909 -406.790732) (xy 170.348835 -406.72379) (xy 167.070789 -406.72379) (xy 167.062756 -406.790548)
			(xy 167.046786 -406.855928) (xy 167.023117 -406.918931) (xy 166.992087 -406.978654) (xy 166.954142 -407.03424)
			(xy 166.932356 -407.059892) (xy 166.926575 -407.067048) (xy 166.920052 -407.08423) (xy 166.919656 -407.09342)
			(xy 166.919656 -407.251408) (xy 166.919186 -407.261556) (xy 166.911398 -407.280297) (xy 166.897017 -407.294618)
			(xy 166.878243 -407.302328) (xy 166.868094 -407.302716) (xy 166.151814 -407.302716) (xy 166.141683 -407.302261)
			(xy 166.122954 -407.294529) (xy 166.108595 -407.280233) (xy 166.100783 -407.261537) (xy 166.100252 -407.251408)
			(xy 166.100252 -407.09342) (xy 166.099821 -407.084235) (xy 166.093321 -407.067051) (xy 166.087552 -407.059892)
			(xy 166.065732 -407.034266) (xy 166.027784 -406.978676) (xy 165.996751 -406.918949) (xy 165.973079 -406.855941)
			(xy 165.957108 -406.790556) (xy 165.949066 -406.72373) (xy 162.671029 -406.72373) (xy 162.671029 -406.723787)
			(xy 162.662956 -406.790724) (xy 162.646923 -406.856212) (xy 162.62316 -406.919307) (xy 162.592011 -406.979102)
			(xy 162.553923 -407.034735) (xy 162.53206 -407.0604) (xy 162.526276 -407.067554) (xy 162.519755 -407.084738)
			(xy 162.51936 -407.093928) (xy 162.51936 -407.251408) (xy 162.518989 -407.261536) (xy 162.511231 -407.280247)
			(xy 162.4969 -407.294563) (xy 162.47818 -407.3023) (xy 162.468052 -407.302716) (xy 161.751772 -407.302716)
			(xy 161.741663 -407.302238) (xy 161.722988 -407.294494) (xy 161.708694 -407.280196) (xy 161.700958 -407.261517)
			(xy 161.700464 -407.251408) (xy 161.700464 -407.093928) (xy 161.700026 -407.084744) (xy 161.69353 -407.06756)
			(xy 161.687764 -407.0604) (xy 161.66587 -407.03476) (xy 161.627784 -406.979121) (xy 161.596637 -406.919321)
			(xy 161.572876 -406.856221) (xy 161.556844 -406.790729) (xy 161.548771 -406.723789) (xy 154.57678 -406.723789)
			(xy 154.57678 -409.523827) (xy 159.349136 -409.523827) (xy 159.34914 -409.456519) (xy 159.357187 -409.389695)
			(xy 159.373163 -409.324311) (xy 159.396839 -409.261305) (xy 159.427875 -409.20158) (xy 159.465827 -409.145992)
			(xy 159.487616 -409.12034) (xy 159.493422 -409.113202) (xy 159.499931 -409.096006) (xy 159.500316 -409.086812)
			(xy 159.500316 -408.593544) (xy 159.499881 -408.58436) (xy 159.493384 -408.567175) (xy 159.487616 -408.560016)
			(xy 159.465821 -408.53437) (xy 159.427874 -408.478782) (xy 159.396842 -408.419058) (xy 159.373171 -408.356052)
			(xy 159.357199 -408.29067) (xy 159.349156 -408.223847) (xy 159.349157 -408.156541) (xy 159.357201 -408.089719)
			(xy 159.373175 -408.024336) (xy 159.396847 -407.961331) (xy 159.42788 -407.901607) (xy 159.465828 -407.84602)
			(xy 159.487616 -407.820368) (xy 159.49341 -407.813221) (xy 159.499926 -407.796032) (xy 159.500316 -407.78684)
			(xy 159.500316 -407.628852) (xy 159.500683 -407.618693) (xy 159.508497 -407.599936) (xy 159.522911 -407.585614)
			(xy 159.541716 -407.577919) (xy 159.551878 -407.577544) (xy 160.268158 -407.577544) (xy 160.278283 -407.578061)
			(xy 160.297003 -407.585776) (xy 160.311361 -407.600053) (xy 160.319181 -407.61873) (xy 160.31972 -407.628852)
			(xy 160.31972 -407.78684) (xy 160.320107 -407.79603) (xy 160.326636 -407.813214) (xy 160.33242 -407.820368)
			(xy 160.354201 -407.846026) (xy 160.392153 -407.901611) (xy 160.423189 -407.961333) (xy 160.446864 -408.024337)
			(xy 160.462838 -408.089719) (xy 160.470884 -408.156541) (xy 160.470885 -408.223847) (xy 160.462841 -408.290669)
			(xy 160.446867 -408.356052) (xy 160.423194 -408.419056) (xy 160.392159 -408.478779) (xy 160.354208 -408.534364)
			(xy 160.33242 -408.560016) (xy 160.326636 -408.567171) (xy 160.320113 -408.584354) (xy 160.31972 -408.593544)
			(xy 160.31972 -409.086812) (xy 160.32012 -409.096) (xy 160.32664 -409.113185) (xy 160.33242 -409.12034)
			(xy 160.354174 -409.146021) (xy 160.392126 -409.201602) (xy 160.423163 -409.261321) (xy 160.44684 -409.324322)
			(xy 160.462817 -409.389701) (xy 160.470864 -409.456521) (xy 160.470867 -409.523824) (xy 160.462826 -409.590645)
			(xy 160.446856 -409.656026) (xy 160.423185 -409.719029) (xy 160.392154 -409.778751) (xy 160.354207 -409.834336)
			(xy 160.33242 -409.859988) (xy 160.326606 -409.867121) (xy 160.320101 -409.884321) (xy 160.31972 -409.893516)
			(xy 160.31972 -410.051504) (xy 160.319282 -410.061656) (xy 160.311489 -410.080404) (xy 160.297098 -410.094727)
			(xy 160.278312 -410.10243) (xy 160.268158 -410.102812) (xy 159.551878 -410.102812) (xy 159.541756 -410.102293)
			(xy 159.523044 -410.094568) (xy 159.508691 -410.080292) (xy 159.500863 -410.061623) (xy 159.500316 -410.051504)
			(xy 159.500316 -409.893516) (xy 159.499894 -409.88433) (xy 159.493388 -409.867146) (xy 159.487616 -409.859988)
			(xy 159.465794 -409.834365) (xy 159.427847 -409.778774) (xy 159.396817 -409.719046) (xy 159.373147 -409.656038)
			(xy 159.357177 -409.590652) (xy 159.349136 -409.523827) (xy 154.57678 -409.523827) (xy 154.57678 -410.6237)
			(xy 161.548783 -410.6237) (xy 161.548784 -410.556276) (xy 161.556861 -410.489337) (xy 161.572897 -410.423848)
			(xy 161.596662 -410.36075) (xy 161.627812 -410.300953) (xy 161.6659 -410.245318) (xy 161.687764 -410.219652)
			(xy 161.693571 -410.212515) (xy 161.700078 -410.195318) (xy 161.700464 -410.186124) (xy 161.700464 -409.693872)
			(xy 161.700053 -409.684685) (xy 161.693538 -409.667502) (xy 161.687764 -409.660344) (xy 161.665913 -409.634668)
			(xy 161.627826 -409.579035) (xy 161.596677 -409.519239) (xy 161.572914 -409.456144) (xy 161.556879 -409.390657)
			(xy 161.548802 -409.32372) (xy 161.548801 -409.256298) (xy 161.556875 -409.189361) (xy 161.572909 -409.123873)
			(xy 161.59667 -409.060777) (xy 161.627817 -409.000981) (xy 161.665902 -408.945346) (xy 161.687764 -408.91968)
			(xy 161.693559 -408.912534) (xy 161.700073 -408.895344) (xy 161.700464 -408.886152) (xy 161.700464 -408.728672)
			(xy 161.700961 -408.718566) (xy 161.708701 -408.699894) (xy 161.722994 -408.685601) (xy 161.741666 -408.677861)
			(xy 161.751772 -408.677364) (xy 162.468052 -408.677364) (xy 162.478167 -408.677854) (xy 162.496863 -408.68558)
			(xy 162.511177 -408.699874) (xy 162.518931 -408.718558) (xy 162.51936 -408.728672) (xy 162.51936 -408.886152)
			(xy 162.519802 -408.895336) (xy 162.526295 -408.91252) (xy 162.53206 -408.91968) (xy 162.553937 -408.945335)
			(xy 162.592028 -409.00097) (xy 162.623181 -409.060767) (xy 162.646946 -409.123866) (xy 162.662982 -409.189356)
			(xy 162.671057 -409.256296) (xy 162.671056 -409.323722) (xy 162.662978 -409.390662) (xy 162.64694 -409.456152)
			(xy 162.623173 -409.519249) (xy 162.620757 -409.523886) (xy 163.748905 -409.523886) (xy 163.748908 -409.45646)
			(xy 163.756988 -409.389519) (xy 163.773027 -409.324027) (xy 163.796796 -409.260929) (xy 163.827952 -409.201132)
			(xy 163.866045 -409.145497) (xy 163.887912 -409.119832) (xy 163.893721 -409.112696) (xy 163.900228 -409.095498)
			(xy 163.900612 -409.086304) (xy 163.900612 -408.594052) (xy 163.900174 -408.584868) (xy 163.893679 -408.567683)
			(xy 163.887912 -408.560524) (xy 163.86604 -408.534865) (xy 163.82795 -408.47923) (xy 163.796799 -408.419433)
			(xy 163.773035 -408.356335) (xy 163.757 -408.290845) (xy 163.748925 -408.223906) (xy 163.748925 -408.156482)
			(xy 163.757002 -408.089543) (xy 163.773039 -408.024053) (xy 163.796804 -407.960956) (xy 163.827957 -407.901159)
			(xy 163.866047 -407.845525) (xy 163.887912 -407.81986) (xy 163.893709 -407.812715) (xy 163.900223 -407.795524)
			(xy 163.900612 -407.786332) (xy 163.900612 -407.628852) (xy 163.901046 -407.618739) (xy 163.908802 -407.600057)
			(xy 163.923114 -407.585764) (xy 163.941806 -407.578033) (xy 163.95192 -407.577544) (xy 164.6682 -407.577544)
			(xy 164.678302 -407.578084) (xy 164.696969 -407.585811) (xy 164.711262 -407.60009) (xy 164.719007 -407.618751)
			(xy 164.719508 -407.628852) (xy 164.719508 -407.786332) (xy 164.719901 -407.795521) (xy 164.726426 -407.812705)
			(xy 164.732208 -407.81986) (xy 164.754064 -407.845532) (xy 164.792152 -407.901166) (xy 164.823303 -407.960961)
			(xy 164.847067 -408.024057) (xy 164.863103 -408.089545) (xy 164.871179 -408.156483) (xy 164.87118 -408.223905)
			(xy 164.863105 -408.290843) (xy 164.847071 -408.356332) (xy 164.823308 -408.419428) (xy 164.792158 -408.479224)
			(xy 164.754071 -408.534859) (xy 164.732208 -408.560524) (xy 164.72642 -408.567675) (xy 164.7199 -408.584861)
			(xy 164.719508 -408.594052) (xy 164.719508 -409.086304) (xy 164.719915 -409.095492) (xy 164.726431 -409.112676)
			(xy 164.732208 -409.119832) (xy 164.754036 -409.145527) (xy 164.792126 -409.201157) (xy 164.823277 -409.260949)
			(xy 164.847043 -409.324042) (xy 164.863081 -409.389528) (xy 164.87116 -409.456463) (xy 164.871163 -409.523883)
			(xy 164.863091 -409.590819) (xy 164.847059 -409.656306) (xy 164.8233 -409.719401) (xy 164.792153 -409.779196)
			(xy 164.75407 -409.834831) (xy 164.732208 -409.860496) (xy 164.726432 -409.867656) (xy 164.719905 -409.884835)
			(xy 164.719508 -409.894024) (xy 164.719508 -410.051504) (xy 164.719018 -410.061612) (xy 164.711281 -410.080289)
			(xy 164.696985 -410.094583) (xy 164.678308 -410.102319) (xy 164.6682 -410.102812) (xy 163.95192 -410.102812)
			(xy 163.9418 -410.102368) (xy 163.923099 -410.094629) (xy 163.908785 -410.080321) (xy 163.901037 -410.061624)
			(xy 163.900612 -410.051504) (xy 163.900612 -409.894024) (xy 163.900188 -409.884838) (xy 163.893683 -409.867654)
			(xy 163.887912 -409.860496) (xy 163.866012 -409.83486) (xy 163.827924 -409.779222) (xy 163.796774 -409.719422)
			(xy 163.773011 -409.656321) (xy 163.756978 -409.590828) (xy 163.748905 -409.523886) (xy 162.620757 -409.523886)
			(xy 162.592019 -409.579046) (xy 162.553926 -409.634679) (xy 162.53206 -409.660344) (xy 162.526257 -409.667485)
			(xy 162.519747 -409.684679) (xy 162.51936 -409.693872) (xy 162.51936 -410.186124) (xy 162.519768 -410.195311)
			(xy 162.526284 -410.212495) (xy 162.53206 -410.219652) (xy 162.55391 -410.24533) (xy 162.592001 -410.300961)
			(xy 162.623155 -410.360755) (xy 162.646922 -410.423851) (xy 162.66296 -410.489339) (xy 162.671038 -410.556276)
			(xy 162.671039 -410.623641) (xy 165.949078 -410.623641) (xy 165.949079 -410.556335) (xy 165.957125 -410.489511)
			(xy 165.9731 -410.424127) (xy 165.996775 -410.361122) (xy 166.027811 -410.301398) (xy 166.065763 -410.245812)
			(xy 166.087552 -410.22016) (xy 166.093354 -410.213019) (xy 166.099864 -410.195825) (xy 166.100252 -410.186632)
			(xy 166.100252 -409.693364) (xy 166.099847 -409.684176) (xy 166.093328 -409.666993) (xy 166.087552 -409.659836)
			(xy 166.065776 -409.634174) (xy 166.027826 -409.578589) (xy 165.996791 -409.518867) (xy 165.973117 -409.455864)
			(xy 165.957143 -409.390483) (xy 165.949098 -409.323661) (xy 165.949097 -409.256357) (xy 165.95714 -409.189535)
			(xy 165.973112 -409.124153) (xy 165.996784 -409.061149) (xy 166.027817 -409.001426) (xy 166.065765 -408.94584)
			(xy 166.087552 -408.920188) (xy 166.093343 -408.913039) (xy 166.099859 -408.895851) (xy 166.100252 -408.88666)
			(xy 166.100252 -408.728672) (xy 166.100698 -408.718522) (xy 166.108493 -408.699778) (xy 166.122882 -408.685458)
			(xy 166.141662 -408.67775) (xy 166.151814 -408.677364) (xy 166.868094 -408.677364) (xy 166.878223 -408.677832)
			(xy 166.896949 -408.685562) (xy 166.911306 -408.699855) (xy 166.919121 -408.718545) (xy 166.919656 -408.728672)
			(xy 166.919656 -408.88666) (xy 166.920095 -408.895844) (xy 166.92659 -408.913028) (xy 166.932356 -408.920188)
			(xy 166.954156 -408.94583) (xy 166.992105 -409.001418) (xy 167.023138 -409.061143) (xy 167.04681 -409.124149)
			(xy 167.062782 -409.189532) (xy 167.070826 -409.256356) (xy 167.070824 -409.323662) (xy 167.062779 -409.390486)
			(xy 167.046805 -409.455869) (xy 167.02313 -409.518874) (xy 167.020557 -409.523826) (xy 168.149224 -409.523826)
			(xy 168.149228 -409.456519) (xy 168.157275 -409.389695) (xy 168.17325 -409.324311) (xy 168.196925 -409.261305)
			(xy 168.227961 -409.201581) (xy 168.265911 -409.145993) (xy 168.2877 -409.12034) (xy 168.293505 -409.1132)
			(xy 168.300014 -409.096006) (xy 168.3004 -409.086812) (xy 168.3004 -408.593544) (xy 168.299969 -408.584359)
			(xy 168.29347 -408.567174) (xy 168.2877 -408.560016) (xy 168.265906 -408.53437) (xy 168.22796 -408.478782)
			(xy 168.196929 -408.419057) (xy 168.173258 -408.356052) (xy 168.157287 -408.290669) (xy 168.149244 -408.223846)
			(xy 168.149245 -408.156542) (xy 168.157289 -408.089719) (xy 168.173262 -408.024337) (xy 168.196934 -407.961332)
			(xy 168.227966 -407.901608) (xy 168.265913 -407.846021) (xy 168.2877 -407.820368) (xy 168.293493 -407.81322)
			(xy 168.30001 -407.796032) (xy 168.3004 -407.78684) (xy 168.3004 -407.628852) (xy 168.300782 -407.618695)
			(xy 168.308594 -407.599941) (xy 168.323002 -407.58562) (xy 168.341802 -407.577922) (xy 168.351962 -407.577544)
			(xy 169.068242 -407.577544) (xy 169.078372 -407.577992) (xy 169.097095 -407.585735) (xy 169.11145 -407.600032)
			(xy 169.119267 -407.618724) (xy 169.119804 -407.628852) (xy 169.119804 -407.78684) (xy 169.120194 -407.796029)
			(xy 169.126721 -407.813214) (xy 169.132504 -407.820368) (xy 169.154283 -407.846027) (xy 169.192229 -407.901614)
			(xy 169.22326 -407.961337) (xy 169.246931 -408.02434) (xy 169.262904 -408.089721) (xy 169.270948 -408.156542)
			(xy 169.270948 -408.223846) (xy 169.262906 -408.290667) (xy 169.246935 -408.356048) (xy 169.223265 -408.419052)
			(xy 169.192235 -408.478776) (xy 169.15429 -408.534363) (xy 169.132504 -408.560016) (xy 169.126719 -408.567169)
			(xy 169.120197 -408.584354) (xy 169.119804 -408.593544) (xy 169.119804 -409.086812) (xy 169.120208 -409.096)
			(xy 169.126726 -409.113184) (xy 169.132504 -409.12034) (xy 169.154255 -409.146022) (xy 169.192202 -409.201605)
			(xy 169.223235 -409.261325) (xy 169.246908 -409.324325) (xy 169.262882 -409.389704) (xy 169.270928 -409.456522)
			(xy 169.270931 -409.523824) (xy 169.262891 -409.590643) (xy 169.246924 -409.656023) (xy 169.223257 -409.719026)
			(xy 169.19223 -409.778748) (xy 169.154288 -409.834335) (xy 169.132504 -409.859988) (xy 169.126688 -409.86712)
			(xy 169.120185 -409.88432) (xy 169.119804 -409.893516) (xy 169.119804 -410.051504) (xy 169.119382 -410.061658)
			(xy 169.111586 -410.08041) (xy 169.097189 -410.094733) (xy 169.078398 -410.102433) (xy 169.068242 -410.102812)
			(xy 168.351962 -410.102812) (xy 168.341839 -410.102306) (xy 168.323127 -410.094575) (xy 168.308774 -410.080296)
			(xy 168.300947 -410.061624) (xy 168.3004 -410.051504) (xy 168.3004 -409.893516) (xy 168.299982 -409.88433)
			(xy 168.293474 -409.867145) (xy 168.2877 -409.859988) (xy 168.265878 -409.834364) (xy 168.227933 -409.778773)
			(xy 168.196903 -409.719045) (xy 168.173234 -409.656037) (xy 168.157265 -409.590652) (xy 168.149224 -409.523826)
			(xy 167.020557 -409.523826) (xy 166.992095 -409.578598) (xy 166.954145 -409.634184) (xy 166.932356 -409.659836)
			(xy 166.926556 -409.666979) (xy 166.920045 -409.684171) (xy 166.919656 -409.693364) (xy 166.919656 -410.186632)
			(xy 166.920061 -410.19582) (xy 166.926579 -410.213003) (xy 166.932356 -410.22016) (xy 166.954128 -410.245825)
			(xy 166.992078 -410.30141) (xy 167.023112 -410.361131) (xy 167.046786 -410.424134) (xy 167.06276 -410.489515)
			(xy 167.070805 -410.556336) (xy 167.070807 -410.62364) (xy 167.0708 -410.623701) (xy 170.348846 -410.623701)
			(xy 170.348847 -410.556275) (xy 170.356926 -410.489335) (xy 170.372964 -410.423844) (xy 170.396732 -410.360747)
			(xy 170.427888 -410.30095) (xy 170.465981 -410.245316) (xy 170.487848 -410.219652) (xy 170.493653 -410.212513)
			(xy 170.500162 -410.195318) (xy 170.500548 -410.186124) (xy 170.500548 -409.693872) (xy 170.50014 -409.684685)
			(xy 170.493624 -409.667501) (xy 170.487848 -409.660344) (xy 170.465994 -409.63467) (xy 170.427902 -409.579038)
			(xy 170.396748 -409.519243) (xy 170.372981 -409.456147) (xy 170.356943 -409.390659) (xy 170.348866 -409.323721)
			(xy 170.348865 -409.256297) (xy 170.35694 -409.189359) (xy 170.372976 -409.12387) (xy 170.396741 -409.060773)
			(xy 170.427893 -409.000978) (xy 170.465983 -408.945344) (xy 170.487848 -408.91968) (xy 170.493642 -408.912533)
			(xy 170.500157 -408.895344) (xy 170.500548 -408.886152) (xy 170.500548 -408.728672) (xy 170.501061 -408.718568)
			(xy 170.508798 -408.699899) (xy 170.523086 -408.685607) (xy 170.541752 -408.677864) (xy 170.551856 -408.677364)
			(xy 171.268136 -408.677364) (xy 171.278243 -408.677855) (xy 171.296915 -408.685598) (xy 171.311207 -408.699892)
			(xy 171.318947 -408.718565) (xy 171.319444 -408.728672) (xy 171.319444 -408.886152) (xy 171.31989 -408.895335)
			(xy 171.32638 -408.912519) (xy 171.332144 -408.91968) (xy 171.354022 -408.945335) (xy 171.392114 -409.000969)
			(xy 171.423267 -409.060766) (xy 171.447033 -409.123865) (xy 171.463069 -409.189356) (xy 171.471145 -409.256296)
			(xy 171.471144 -409.323722) (xy 171.463066 -409.390662) (xy 171.447028 -409.456152) (xy 171.42326 -409.51925)
			(xy 171.420875 -409.523827) (xy 172.548991 -409.523827) (xy 172.548995 -409.456519) (xy 172.557043 -409.389693)
			(xy 172.573021 -409.324308) (xy 172.5967 -409.261302) (xy 172.62774 -409.201577) (xy 172.665697 -409.145992)
			(xy 172.687488 -409.12034) (xy 172.693291 -409.113199) (xy 172.699802 -409.096005) (xy 172.700188 -409.086812)
			(xy 172.700188 -408.593544) (xy 172.699759 -408.584359) (xy 172.693259 -408.567174) (xy 172.687488 -408.560016)
			(xy 172.665691 -408.534371) (xy 172.627739 -408.478785) (xy 172.596704 -408.419061) (xy 172.573029 -408.356055)
			(xy 172.557055 -408.290671) (xy 172.549011 -408.223847) (xy 172.549012 -408.156541) (xy 172.557057 -408.089717)
			(xy 172.573033 -408.024333) (xy 172.596708 -407.961328) (xy 172.627745 -407.901605) (xy 172.665698 -407.84602)
			(xy 172.687488 -407.820368) (xy 172.693279 -407.813219) (xy 172.699797 -407.796031) (xy 172.700188 -407.78684)
			(xy 172.700188 -407.628852) (xy 172.700582 -407.618696) (xy 172.708391 -407.599945) (xy 172.722796 -407.585624)
			(xy 172.741592 -407.577924) (xy 172.75175 -407.577544) (xy 173.46803 -407.577544) (xy 173.478159 -407.578002)
			(xy 173.496882 -407.58574) (xy 173.511237 -407.600035) (xy 173.519055 -407.618725) (xy 173.519592 -407.628852)
			(xy 173.519592 -407.78684) (xy 173.519985 -407.796029) (xy 173.526511 -407.813213) (xy 173.532292 -407.820368)
			(xy 173.554071 -407.846027) (xy 173.592018 -407.901613) (xy 173.62305 -407.961336) (xy 173.646722 -408.02434)
			(xy 173.662694 -408.089721) (xy 173.670739 -408.156542) (xy 173.670739 -408.223846) (xy 173.662697 -408.290667)
			(xy 173.646725 -408.356049) (xy 173.623055 -408.419053) (xy 173.592024 -408.478776) (xy 173.554078 -408.534363)
			(xy 173.532292 -408.560016) (xy 173.526505 -408.567168) (xy 173.519985 -408.584353) (xy 173.519592 -408.593544)
			(xy 173.519592 -409.086812) (xy 173.519998 -409.096) (xy 173.526515 -409.113184) (xy 173.532292 -409.12034)
			(xy 173.554043 -409.146022) (xy 173.591991 -409.201605) (xy 173.623024 -409.261324) (xy 173.646698 -409.324325)
			(xy 173.662672 -409.389703) (xy 173.670719 -409.456522) (xy 173.670722 -409.523824) (xy 173.662682 -409.590643)
			(xy 173.646714 -409.656023) (xy 173.623047 -409.719026) (xy 173.592019 -409.778749) (xy 173.554077 -409.834336)
			(xy 173.532292 -409.859988) (xy 173.526475 -409.867118) (xy 173.519973 -409.88432) (xy 173.519592 -409.893516)
			(xy 173.519592 -410.051504) (xy 173.519181 -410.061659) (xy 173.511383 -410.080413) (xy 173.496983 -410.094737)
			(xy 173.478187 -410.102435) (xy 173.46803 -410.102812) (xy 172.75175 -410.102812) (xy 172.741633 -410.102234)
			(xy 172.722923 -410.094532) (xy 172.708567 -410.080274) (xy 172.700736 -410.061618) (xy 172.700188 -410.051504)
			(xy 172.700188 -409.893516) (xy 172.699773 -409.884329) (xy 172.693263 -409.867145) (xy 172.687488 -409.859988)
			(xy 172.665663 -409.834366) (xy 172.627713 -409.778776) (xy 172.596678 -409.719049) (xy 172.573005 -409.65604)
			(xy 172.557033 -409.590654) (xy 172.548991 -409.523827) (xy 171.420875 -409.523827) (xy 171.392104 -409.579046)
			(xy 171.354011 -409.63468) (xy 171.332144 -409.660344) (xy 171.326339 -409.667483) (xy 171.319831 -409.684679)
			(xy 171.319444 -409.693872) (xy 171.319444 -410.186124) (xy 171.319855 -410.195311) (xy 171.32637 -410.212494)
			(xy 171.332144 -410.219652) (xy 171.353994 -410.245329) (xy 171.392087 -410.300961) (xy 171.423242 -410.360755)
			(xy 171.447009 -410.42385) (xy 171.463047 -410.489338) (xy 171.471125 -410.556276) (xy 171.471127 -410.623641)
			(xy 174.749166 -410.623641) (xy 174.749167 -410.556335) (xy 174.757213 -410.489511) (xy 174.773187 -410.424128)
			(xy 174.796862 -410.361123) (xy 174.827897 -410.301399) (xy 174.865847 -410.245812) (xy 174.887636 -410.22016)
			(xy 174.893437 -410.213018) (xy 174.899948 -410.195825) (xy 174.900336 -410.186632) (xy 174.900336 -409.693364)
			(xy 174.899935 -409.684176) (xy 174.893414 -409.666992) (xy 174.887636 -409.659836) (xy 174.86586 -409.634174)
			(xy 174.827911 -409.578589) (xy 174.796878 -409.518867) (xy 174.773205 -409.455863) (xy 174.757231 -409.390482)
			(xy 174.749186 -409.323661) (xy 174.749185 -409.256357) (xy 174.757228 -409.189535) (xy 174.773199 -409.124154)
			(xy 174.79687 -409.06115) (xy 174.827902 -409.001427) (xy 174.865849 -408.94584) (xy 174.887636 -408.920188)
			(xy 174.893425 -408.913037) (xy 174.899943 -408.895851) (xy 174.900336 -408.88666) (xy 174.900336 -408.728672)
			(xy 174.900699 -408.718512) (xy 174.908511 -408.699752) (xy 174.922926 -408.685428) (xy 174.941735 -408.677736)
			(xy 174.951898 -408.677364) (xy 175.668178 -408.677364) (xy 175.678306 -408.677845) (xy 175.697032 -408.68557)
			(xy 175.711389 -408.699859) (xy 175.719205 -408.718546) (xy 175.71974 -408.728672) (xy 175.71974 -408.88666)
			(xy 175.720183 -408.895843) (xy 175.726675 -408.913028) (xy 175.73244 -408.920188) (xy 175.75424 -408.94583)
			(xy 175.79219 -409.001418) (xy 175.823224 -409.061142) (xy 175.846897 -409.124148) (xy 175.862869 -409.189532)
			(xy 175.870913 -409.256356) (xy 175.870912 -409.323662) (xy 175.862866 -409.390486) (xy 175.846891 -409.455869)
			(xy 175.823216 -409.518874) (xy 175.792181 -409.578598) (xy 175.754229 -409.634184) (xy 175.73244 -409.659836)
			(xy 175.726638 -409.666977) (xy 175.720128 -409.684171) (xy 175.71974 -409.693364) (xy 175.71974 -410.186632)
			(xy 175.720148 -410.195819) (xy 175.726665 -410.213003) (xy 175.73244 -410.22016) (xy 175.754213 -410.245825)
			(xy 175.792163 -410.301409) (xy 175.823198 -410.361131) (xy 175.846873 -410.424134) (xy 175.862848 -410.489514)
			(xy 175.870893 -410.556336) (xy 175.870895 -410.62364) (xy 175.862852 -410.690462) (xy 175.84688 -410.755843)
			(xy 175.823208 -410.818847) (xy 175.792176 -410.87857) (xy 175.754227 -410.934156) (xy 175.73244 -410.959808)
			(xy 175.72665 -410.966958) (xy 175.720133 -410.984145) (xy 175.71974 -410.993336) (xy 175.71974 -411.151324)
			(xy 175.719299 -411.161475) (xy 175.711503 -411.18022) (xy 175.697113 -411.194541) (xy 175.678331 -411.202247)
			(xy 175.668178 -411.202632) (xy 174.951898 -411.202632) (xy 174.941768 -411.202174) (xy 174.923041 -411.194441)
			(xy 174.908684 -411.180145) (xy 174.90087 -411.161452) (xy 174.900336 -411.151324) (xy 174.900336 -410.993336)
			(xy 174.8999 -410.984152) (xy 174.893403 -410.966968) (xy 174.887636 -410.959808) (xy 174.865833 -410.934169)
			(xy 174.827884 -410.87858) (xy 174.796852 -410.818855) (xy 174.77318 -410.755849) (xy 174.757208 -410.690465)
			(xy 174.749166 -410.623641) (xy 171.471127 -410.623641) (xy 171.471127 -410.6237) (xy 171.463052 -410.690638)
			(xy 171.447016 -410.756127) (xy 171.423251 -410.819223) (xy 171.392099 -410.879019) (xy 171.354009 -410.934652)
			(xy 171.332144 -410.960316) (xy 171.326351 -410.967464) (xy 171.319836 -410.984653) (xy 171.319444 -410.993844)
			(xy 171.319444 -411.151324) (xy 171.318936 -411.161429) (xy 171.311198 -411.180099) (xy 171.296909 -411.194392)
			(xy 171.278241 -411.202133) (xy 171.268136 -411.202632) (xy 170.551856 -411.202632) (xy 170.541748 -411.202152)
			(xy 170.523075 -411.194405) (xy 170.508783 -411.180108) (xy 170.501044 -411.161432) (xy 170.500548 -411.151324)
			(xy 170.500548 -410.993844) (xy 170.500106 -410.98466) (xy 170.493613 -410.967476) (xy 170.487848 -410.960316)
			(xy 170.465967 -410.934665) (xy 170.427875 -410.879029) (xy 170.396723 -410.819232) (xy 170.372957 -410.756133)
			(xy 170.356921 -410.690641) (xy 170.348846 -410.623701) (xy 167.0708 -410.623701) (xy 167.062764 -410.690461)
			(xy 167.046793 -410.755843) (xy 167.023122 -410.818847) (xy 166.99209 -410.87857) (xy 166.954143 -410.934156)
			(xy 166.932356 -410.959808) (xy 166.926568 -410.966959) (xy 166.920049 -410.984145) (xy 166.919656 -410.993336)
			(xy 166.919656 -411.151324) (xy 166.919199 -411.161473) (xy 166.911406 -411.180215) (xy 166.897021 -411.194535)
			(xy 166.878245 -411.202244) (xy 166.868094 -411.202632) (xy 166.151814 -411.202632) (xy 166.141685 -411.202161)
			(xy 166.122959 -411.194433) (xy 166.108601 -411.180141) (xy 166.100786 -411.161451) (xy 166.100252 -411.151324)
			(xy 166.100252 -410.993336) (xy 166.099813 -410.984152) (xy 166.093318 -410.966968) (xy 166.087552 -410.959808)
			(xy 166.065748 -410.934169) (xy 166.027799 -410.878581) (xy 165.996765 -410.818856) (xy 165.973093 -410.75585)
			(xy 165.957121 -410.690466) (xy 165.949078 -410.623641) (xy 162.671039 -410.623641) (xy 162.671039 -410.6237)
			(xy 162.662964 -410.690637) (xy 162.646929 -410.756126) (xy 162.623165 -410.819223) (xy 162.592014 -410.879018)
			(xy 162.553924 -410.934651) (xy 162.53206 -410.960316) (xy 162.526269 -410.967465) (xy 162.519752 -410.984653)
			(xy 162.51936 -410.993844) (xy 162.51936 -411.151324) (xy 162.519003 -411.161453) (xy 162.511239 -411.180165)
			(xy 162.496904 -411.19448) (xy 162.478182 -411.202217) (xy 162.468052 -411.202632) (xy 161.751772 -411.202632)
			(xy 161.741665 -411.202139) (xy 161.722993 -411.194398) (xy 161.7087 -411.180104) (xy 161.700961 -411.161431)
			(xy 161.700464 -411.151324) (xy 161.700464 -410.993844) (xy 161.700019 -410.984661) (xy 161.693528 -410.967477)
			(xy 161.687764 -410.960316) (xy 161.665886 -410.934663) (xy 161.6278 -410.879026) (xy 161.596652 -410.819228)
			(xy 161.57289 -410.756129) (xy 161.556857 -410.690639) (xy 161.548783 -410.6237) (xy 154.57678 -410.6237)
			(xy 154.57678 -417.371276) (xy 154.576371 -417.383441) (xy 154.568857 -417.406581) (xy 154.554556 -417.426265)
			(xy 154.53487 -417.440562) (xy 154.511729 -417.448073) (xy 154.499564 -417.448492) (xy 141.100302 -417.448492)
			(xy 141.088157 -417.448035) (xy 141.06506 -417.440516) (xy 141.045426 -417.426216) (xy 141.031183 -417.406541)
			(xy 141.02373 -417.383422) (xy 141.02334 -417.371276) (xy 66.525648 -417.371276) (xy 66.525648 -417.533836)
			(xy 66.525172 -417.545883) (xy 66.517735 -417.568802) (xy 66.503597 -417.588313) (xy 66.484133 -417.602517)
			(xy 66.46124 -417.610031) (xy 66.449194 -417.610544) (xy 53.151024 -417.610544) (xy 53.138954 -417.610016)
			(xy 53.115994 -417.602564) (xy 53.09646 -417.588383) (xy 53.082263 -417.56886) (xy 53.074793 -417.545905)
			(xy 53.074316 -417.533836) (xy 53.074316 -417.289488) (xy 53.073808 -417.289488) (xy 0.682829 -417.289488)
			(xy 0.737106 -417.383499) (xy 0.799937 -417.475656) (xy 0.86948 -417.56286) (xy 0.945345 -417.644623)
			(xy 1.027108 -417.720488) (xy 1.114312 -417.790031) (xy 1.206469 -417.852862) (xy 1.303064 -417.908631)
			(xy 1.403556 -417.957026) (xy 1.507384 -417.997775) (xy 1.613967 -418.030652) (xy 1.722709 -418.055471)
			(xy 1.833001 -418.072095) (xy 1.944227 -418.080431) (xy 1.999996 -418.080952) (xy 6.799834 -418.080952)
			(xy 6.80085 -418.081968) (xy 7.986268 -418.081968)
		)
		(stroke
			(width 0)
			(type solid)
		)
		(fill yes)
		(layer "In16.Cu")
		(net "GND")
	)
	(segment
		(start 108.660946 -392.778488)
		(end 108.660946 -393.731242)
		(width 0.13208)
		(layer "F.Cu")
		(net "BIC_USB_HUB_XOUT_R")
	)
	(segment
		(start 107.485434 -395.274292)
		(end 107.358434 -395.147292)
		(width 0.13208)
		(layer "F.Cu")
		(net "BIC_USB_HUB_XOUT_R")
	)
	(segment
		(start 108.64977 -393.76477)
		(end 108.638594 -393.753594)
		(width 0.13208)
		(layer "F.Cu")
		(net "BIC_USB_HUB_XOUT_R")
	)
	(segment
		(start 107.588812 -394.361416)
		(end 108.482384 -394.361416)
		(width 0.13208)
		(layer "F.Cu")
		(net "BIC_USB_HUB_XOUT_R")
	)
	(segment
		(start 108.554012 -395.096746)
		(end 108.376466 -395.274292)
		(width 0.13208)
		(layer "F.Cu")
		(net "BIC_USB_HUB_XOUT_R")
	)
	(segment
		(start 108.376466 -395.274292)
		(end 107.485434 -395.274292)
		(width 0.13208)
		(layer "F.Cu")
		(net "BIC_USB_HUB_XOUT_R")
	)
	(segment
		(start 108.482384 -394.361416)
		(end 108.64977 -394.19403)
		(width 0.13208)
		(layer "F.Cu")
		(net "BIC_USB_HUB_XOUT_R")
	)
	(segment
		(start 107.358434 -395.147292)
		(end 107.358434 -394.591794)
		(width 0.13208)
		(layer "F.Cu")
		(net "BIC_USB_HUB_XOUT_R")
	)
	(segment
		(start 107.358434 -394.591794)
		(end 107.588812 -394.361416)
		(width 0.13208)
		(layer "F.Cu")
		(net "BIC_USB_HUB_XOUT_R")
	)
	(segment
		(start 108.660946 -393.731242)
		(end 108.638594 -393.753594)
		(width 0.13208)
		(layer "F.Cu")
		(net "BIC_USB_HUB_XOUT_R")
	)
	(segment
		(start 108.64977 -394.19403)
		(end 108.64977 -393.76477)
		(width 0.13208)
		(layer "F.Cu")
		(net "BIC_USB_HUB_XOUT_R")
	)
	(segment
		(start 241.956336 -93.54439)
		(end 239.77219 -93.54439)
		(width 0.13208)
		(layer "F.Cu")
		(net "PEX_USB_HUB_XOUT_R")
	)
	(segment
		(start 239.64392 -93.41612)
		(end 239.378998 -93.41612)
		(width 0.13208)
		(layer "F.Cu")
		(net "PEX_USB_HUB_XOUT_R")
	)
	(segment
		(start 238.418878 -93.417644)
		(end 239.377474 -93.417644)
		(width 0.13208)
		(layer "F.Cu")
		(net "PEX_USB_HUB_XOUT_R")
	)
	(segment
		(start 242.606576 -92.89415)
		(end 241.956336 -93.54439)
		(width 0.13208)
		(layer "F.Cu")
		(net "PEX_USB_HUB_XOUT_R")
	)
	(segment
		(start 239.377474 -93.417644)
		(end 239.378998 -93.41612)
		(width 0.13208)
		(layer "F.Cu")
		(net "PEX_USB_HUB_XOUT_R")
	)
	(segment
		(start 239.77219 -93.54439)
		(end 239.64392 -93.41612)
		(width 0.13208)
		(layer "F.Cu")
		(net "PEX_USB_HUB_XOUT_R")
	)
	(segment
		(start 193.83883 -403.063202)
		(end 192.840864 -403.063202)
		(width 0.13208)
		(layer "F.Cu")
		(net "FM_UV_LT6700_VS")
	)
	(segment
		(start 192.840864 -403.063202)
		(end 192.828926 -403.07514)
		(width 0.13208)
		(layer "F.Cu")
		(net "FM_UV_LT6700_VS")
	)
	(segment
		(start 191.820292 -403.07514)
		(end 191.817498 -403.072346)
		(width 0.13208)
		(layer "F.Cu")
		(net "FM_UV_LT6700_VS")
	)
	(segment
		(start 191.734948 -405.363426)
		(end 190.881508 -406.216866)
		(width 0.13208)
		(layer "F.Cu")
		(net "FM_UV_LT6700_VS")
	)
	(segment
		(start 191.817498 -403.072346)
		(end 191.734948 -403.154896)
		(width 0.13208)
		(layer "F.Cu")
		(net "FM_UV_LT6700_VS")
	)
	(segment
		(start 191.734948 -404.444708)
		(end 191.734948 -405.363426)
		(width 0.13208)
		(layer "F.Cu")
		(net "FM_UV_LT6700_VS")
	)
	(segment
		(start 189.474856 -406.70734)
		(end 189.474856 -407.601674)
		(width 0.13208)
		(layer "F.Cu")
		(net "FM_UV_LT6700_VS")
	)
	(segment
		(start 189.96533 -406.216866)
		(end 189.474856 -406.70734)
		(width 0.13208)
		(layer "F.Cu")
		(net "FM_UV_LT6700_VS")
	)
	(segment
		(start 191.734948 -403.154896)
		(end 191.734948 -404.444708)
		(width 0.13208)
		(layer "F.Cu")
		(net "FM_UV_LT6700_VS")
	)
	(segment
		(start 190.881508 -406.216866)
		(end 189.96533 -406.216866)
		(width 0.13208)
		(layer "F.Cu")
		(net "FM_UV_LT6700_VS")
	)
	(segment
		(start 192.828926 -403.07514)
		(end 191.820292 -403.07514)
		(width 0.13208)
		(layer "F.Cu")
		(net "FM_UV_LT6700_VS")
	)
	(via
		(at 191.734948 -404.444708)
		(size 0.762)
		(drill 0.381)
		(layers "F.Cu" "B.Cu")
		(net "FM_UV_LT6700_VS")
	)
	(segment
		(start 257.576066 -343.844372)
		(end 257.577082 -343.843356)
		(width 0.13208)
		(layer "F.Cu")
		(net "HSC_OC_LT6700_VS")
	)
	(segment
		(start 259.028438 -342.4428)
		(end 258.996434 -342.410796)
		(width 0.13208)
		(layer "F.Cu")
		(net "HSC_OC_LT6700_VS")
	)
	(segment
		(start 257.576066 -344.916252)
		(end 257.576066 -343.844372)
		(width 0.13208)
		(layer "F.Cu")
		(net "HSC_OC_LT6700_VS")
	)
	(segment
		(start 258.996434 -343.55278)
		(end 258.996434 -342.410796)
		(width 0.13208)
		(layer "F.Cu")
		(net "HSC_OC_LT6700_VS")
	)
	(segment
		(start 261.002526 -342.4428)
		(end 259.028438 -342.4428)
		(width 0.13208)
		(layer "F.Cu")
		(net "HSC_OC_LT6700_VS")
	)
	(segment
		(start 257.633216 -343.787222)
		(end 258.761992 -343.787222)
		(width 0.13208)
		(layer "F.Cu")
		(net "HSC_OC_LT6700_VS")
	)
	(segment
		(start 258.761992 -343.787222)
		(end 258.853686 -343.695528)
		(width 0.13208)
		(layer "F.Cu")
		(net "HSC_OC_LT6700_VS")
	)
	(segment
		(start 258.853686 -343.695528)
		(end 258.996434 -343.55278)
		(width 0.13208)
		(layer "F.Cu")
		(net "HSC_OC_LT6700_VS")
	)
	(segment
		(start 257.577082 -343.843356)
		(end 257.633216 -343.787222)
		(width 0.13208)
		(layer "F.Cu")
		(net "HSC_OC_LT6700_VS")
	)
	(via
		(at 258.853686 -343.695528)
		(size 0.762)
		(drill 0.381)
		(layers "F.Cu" "B.Cu")
		(net "HSC_OC_LT6700_VS")
	)
	(segment
		(start 234.667552 -219.904056)
		(end 235.067348 -220.303852)
		(width 0.13208)
		(layer "F.Cu")
		(net "BOARD_TYPE_2_ADC_R")
	)
	(via
		(at 235.067348 -220.303852)
		(size 0.4572)
		(drill 0.254)
		(layers "F.Cu" "B.Cu")
		(net "BOARD_TYPE_2_ADC_R")
	)
	(via
		(at 243.72443 -233.249724)
		(size 0.508)
		(drill 0.254)
		(layers "F.Cu" "B.Cu")
		(net "BOARD_TYPE_2_ADC_R")
	)
	(segment
		(start 243.945664 -233.470958)
		(end 243.945664 -234.448096)
		(width 0.13208)
		(layer "B.Cu")
		(net "BOARD_TYPE_2_ADC_R")
	)
	(segment
		(start 242.511326 -233.656378)
		(end 243.128546 -233.656378)
		(width 0.13208)
		(layer "B.Cu")
		(net "BOARD_TYPE_2_ADC_R")
	)
	(segment
		(start 243.128546 -233.656378)
		(end 243.943632 -234.471464)
		(width 0.13208)
		(layer "B.Cu")
		(net "BOARD_TYPE_2_ADC_R")
	)
	(segment
		(start 243.72443 -233.249724)
		(end 243.945664 -233.470958)
		(width 0.13208)
		(layer "B.Cu")
		(net "BOARD_TYPE_2_ADC_R")
	)
	(segment
		(start 243.945664 -234.448096)
		(end 243.969032 -234.471464)
		(width 0.13208)
		(layer "B.Cu")
		(net "BOARD_TYPE_2_ADC_R")
	)
	(segment
		(start 243.943632 -234.471464)
		(end 243.969032 -234.471464)
		(width 0.13208)
		(layer "B.Cu")
		(net "BOARD_TYPE_2_ADC_R")
	)
	(segment
		(start 241.060732 -233.651044)
		(end 242.045744 -233.651044)
		(width 0.13208)
		(layer "B.Cu")
		(net "BOARD_TYPE_2_ADC_R")
	)
	(segment
		(start 242.051078 -233.656378)
		(end 242.074446 -233.679746)
		(width 0.13208)
		(layer "B.Cu")
		(net "BOARD_TYPE_2_ADC_R")
	)
	(segment
		(start 242.487958 -233.679746)
		(end 242.511326 -233.656378)
		(width 0.13208)
		(layer "B.Cu")
		(net "BOARD_TYPE_2_ADC_R")
	)
	(segment
		(start 242.045744 -233.651044)
		(end 242.051078 -233.656378)
		(width 0.13208)
		(layer "B.Cu")
		(net "BOARD_TYPE_2_ADC_R")
	)
	(segment
		(start 242.074446 -233.679746)
		(end 242.487958 -233.679746)
		(width 0.13208)
		(layer "B.Cu")
		(net "BOARD_TYPE_2_ADC_R")
	)
	(segment
		(start 237.823248 -222.373698)
		(end 236.469682 -222.373698)
		(width 0.15494)
		(layer "In5.Cu")
		(net "BOARD_TYPE_2_ADC_R")
	)
	(segment
		(start 238.168688 -222.719138)
		(end 237.823248 -222.373698)
		(width 0.15494)
		(layer "In5.Cu")
		(net "BOARD_TYPE_2_ADC_R")
	)
	(segment
		(start 243.72443 -233.249724)
		(end 241.703098 -231.228392)
		(width 0.15494)
		(layer "In5.Cu")
		(net "BOARD_TYPE_2_ADC_R")
	)
	(segment
		(start 238.168688 -226.687888)
		(end 238.168688 -222.719138)
		(width 0.15494)
		(layer "In5.Cu")
		(net "BOARD_TYPE_2_ADC_R")
	)
	(segment
		(start 236.28096 -220.674946)
		(end 235.909866 -220.303852)
		(width 0.15494)
		(layer "In5.Cu")
		(net "BOARD_TYPE_2_ADC_R")
	)
	(segment
		(start 236.28096 -222.184976)
		(end 236.28096 -220.674946)
		(width 0.15494)
		(layer "In5.Cu")
		(net "BOARD_TYPE_2_ADC_R")
	)
	(segment
		(start 236.469682 -222.373698)
		(end 236.28096 -222.184976)
		(width 0.15494)
		(layer "In5.Cu")
		(net "BOARD_TYPE_2_ADC_R")
	)
	(segment
		(start 241.703098 -231.228392)
		(end 241.703098 -230.222298)
		(width 0.15494)
		(layer "In5.Cu")
		(net "BOARD_TYPE_2_ADC_R")
	)
	(segment
		(start 241.703098 -230.222298)
		(end 238.168688 -226.687888)
		(width 0.15494)
		(layer "In5.Cu")
		(net "BOARD_TYPE_2_ADC_R")
	)
	(segment
		(start 235.909866 -220.303852)
		(end 235.067348 -220.303852)
		(width 0.15494)
		(layer "In5.Cu")
		(net "BOARD_TYPE_2_ADC_R")
	)
	(segment
		(start 233.067606 -219.904056)
		(end 233.467402 -220.303852)
		(width 0.13208)
		(layer "F.Cu")
		(net "BOARD_TYPE_1_ADC_R")
	)
	(via
		(at 206.77632 -219.573856)
		(size 0.508)
		(drill 0.254)
		(layers "F.Cu" "B.Cu")
		(net "BOARD_TYPE_1_ADC_R")
	)
	(via
		(at 233.467402 -220.303852)
		(size 0.4572)
		(drill 0.254)
		(layers "F.Cu" "B.Cu")
		(net "BOARD_TYPE_1_ADC_R")
	)
	(segment
		(start 206.77632 -219.573856)
		(end 206.710026 -219.64015)
		(width 0.13208)
		(layer "B.Cu")
		(net "BOARD_TYPE_1_ADC_R")
	)
	(segment
		(start 206.733394 -220.769434)
		(end 206.733394 -221.67088)
		(width 0.13208)
		(layer "B.Cu")
		(net "BOARD_TYPE_1_ADC_R")
	)
	(segment
		(start 206.733394 -221.67088)
		(end 206.710026 -221.694248)
		(width 0.13208)
		(layer "B.Cu")
		(net "BOARD_TYPE_1_ADC_R")
	)
	(segment
		(start 206.710026 -219.64015)
		(end 206.710026 -220.746066)
		(width 0.13208)
		(layer "B.Cu")
		(net "BOARD_TYPE_1_ADC_R")
	)
	(segment
		(start 206.710026 -220.746066)
		(end 206.733394 -220.769434)
		(width 0.13208)
		(layer "B.Cu")
		(net "BOARD_TYPE_1_ADC_R")
	)
	(segment
		(start 206.710026 -222.65767)
		(end 206.710026 -221.694248)
		(width 0.13208)
		(layer "B.Cu")
		(net "BOARD_TYPE_1_ADC_R")
	)
	(segment
		(start 233.467402 -220.303852)
		(end 233.617516 -220.303852)
		(width 0.0889)
		(layer "In15.Cu")
		(net "BOARD_TYPE_1_ADC_R")
	)
	(segment
		(start 209.808826 -221.67469)
		(end 208.877154 -221.67469)
		(width 0.15494)
		(layer "In15.Cu")
		(net "BOARD_TYPE_1_ADC_R")
	)
	(segment
		(start 219.013532 -220.8276)
		(end 210.655916 -220.8276)
		(width 0.15494)
		(layer "In15.Cu")
		(net "BOARD_TYPE_1_ADC_R")
	)
	(segment
		(start 233.870246 -218.904566)
		(end 233.432604 -218.466924)
		(width 0.15494)
		(layer "In15.Cu")
		(net "BOARD_TYPE_1_ADC_R")
	)
	(segment
		(start 233.870246 -220.051122)
		(end 233.870246 -218.904566)
		(width 0.0889)
		(layer "In15.Cu")
		(net "BOARD_TYPE_1_ADC_R")
	)
	(segment
		(start 208.877154 -221.67469)
		(end 206.77632 -219.573856)
		(width 0.15494)
		(layer "In15.Cu")
		(net "BOARD_TYPE_1_ADC_R")
	)
	(segment
		(start 233.617516 -220.303852)
		(end 233.870246 -220.051122)
		(width 0.0889)
		(layer "In15.Cu")
		(net "BOARD_TYPE_1_ADC_R")
	)
	(segment
		(start 221.374208 -218.466924)
		(end 219.013532 -220.8276)
		(width 0.15494)
		(layer "In15.Cu")
		(net "BOARD_TYPE_1_ADC_R")
	)
	(segment
		(start 233.432604 -218.466924)
		(end 221.374208 -218.466924)
		(width 0.15494)
		(layer "In15.Cu")
		(net "BOARD_TYPE_1_ADC_R")
	)
	(segment
		(start 210.655916 -220.8276)
		(end 209.808826 -221.67469)
		(width 0.15494)
		(layer "In15.Cu")
		(net "BOARD_TYPE_1_ADC_R")
	)
	(segment
		(start 233.867706 -219.904056)
		(end 234.267502 -220.303852)
		(width 0.13208)
		(layer "F.Cu")
		(net "BOARD_TYPE_0_ADC_R")
	)
	(via
		(at 229.569518 -223.46158)
		(size 0.508)
		(drill 0.254)
		(layers "F.Cu" "B.Cu")
		(net "BOARD_TYPE_0_ADC_R")
	)
	(via
		(at 234.267502 -220.303852)
		(size 0.4572)
		(drill 0.254)
		(layers "F.Cu" "B.Cu")
		(net "BOARD_TYPE_0_ADC_R")
	)
	(segment
		(start 232.503218 -221.507812)
		(end 232.263696 -221.747334)
		(width 0.0889)
		(layer "B.Cu")
		(net "BOARD_TYPE_0_ADC_R")
	)
	(segment
		(start 231.2289 -223.102932)
		(end 229.928166 -223.102932)
		(width 0.0889)
		(layer "B.Cu")
		(net "BOARD_TYPE_0_ADC_R")
	)
	(segment
		(start 232.263696 -221.747334)
		(end 232.263696 -222.06839)
		(width 0.0889)
		(layer "B.Cu")
		(net "BOARD_TYPE_0_ADC_R")
	)
	(segment
		(start 229.550468 -225.678746)
		(end 229.550468 -226.68357)
		(width 0.13208)
		(layer "B.Cu")
		(net "BOARD_TYPE_0_ADC_R")
	)
	(segment
		(start 232.03027 -222.301816)
		(end 231.70896 -222.301816)
		(width 0.0889)
		(layer "B.Cu")
		(net "BOARD_TYPE_0_ADC_R")
	)
	(segment
		(start 232.824274 -221.507812)
		(end 232.503218 -221.507812)
		(width 0.0889)
		(layer "B.Cu")
		(net "BOARD_TYPE_0_ADC_R")
	)
	(segment
		(start 231.46385 -222.546926)
		(end 231.46385 -222.867982)
		(width 0.0889)
		(layer "B.Cu")
		(net "BOARD_TYPE_0_ADC_R")
	)
	(segment
		(start 229.545134 -225.673412)
		(end 229.550468 -225.678746)
		(width 0.13208)
		(layer "B.Cu")
		(net "BOARD_TYPE_0_ADC_R")
	)
	(segment
		(start 229.546404 -225.672142)
		(end 229.545134 -225.673412)
		(width 0.13208)
		(layer "B.Cu")
		(net "BOARD_TYPE_0_ADC_R")
	)
	(segment
		(start 231.70896 -222.301816)
		(end 231.46385 -222.546926)
		(width 0.0889)
		(layer "B.Cu")
		(net "BOARD_TYPE_0_ADC_R")
	)
	(segment
		(start 229.546404 -224.667064)
		(end 229.546404 -223.484694)
		(width 0.13208)
		(layer "B.Cu")
		(net "BOARD_TYPE_0_ADC_R")
	)
	(segment
		(start 229.928166 -223.102932)
		(end 229.569518 -223.46158)
		(width 0.13208)
		(layer "B.Cu")
		(net "BOARD_TYPE_0_ADC_R")
	)
	(segment
		(start 232.263696 -222.06839)
		(end 232.03027 -222.301816)
		(width 0.0889)
		(layer "B.Cu")
		(net "BOARD_TYPE_0_ADC_R")
	)
	(segment
		(start 233.303064 -220.707712)
		(end 233.071162 -220.939614)
		(width 0.0889)
		(layer "B.Cu")
		(net "BOARD_TYPE_0_ADC_R")
	)
	(segment
		(start 233.863642 -220.707712)
		(end 233.303064 -220.707712)
		(width 0.0889)
		(layer "B.Cu")
		(net "BOARD_TYPE_0_ADC_R")
	)
	(segment
		(start 233.071162 -221.260924)
		(end 232.824274 -221.507812)
		(width 0.0889)
		(layer "B.Cu")
		(net "BOARD_TYPE_0_ADC_R")
	)
	(segment
		(start 229.546404 -223.484694)
		(end 229.569518 -223.46158)
		(width 0.13208)
		(layer "B.Cu")
		(net "BOARD_TYPE_0_ADC_R")
	)
	(segment
		(start 231.46385 -222.867982)
		(end 231.2289 -223.102932)
		(width 0.0889)
		(layer "B.Cu")
		(net "BOARD_TYPE_0_ADC_R")
	)
	(segment
		(start 229.546404 -224.667064)
		(end 229.546404 -225.672142)
		(width 0.13208)
		(layer "B.Cu")
		(net "BOARD_TYPE_0_ADC_R")
	)
	(segment
		(start 234.267502 -220.303852)
		(end 233.863642 -220.707712)
		(width 0.0889)
		(layer "B.Cu")
		(net "BOARD_TYPE_0_ADC_R")
	)
	(segment
		(start 233.071162 -220.939614)
		(end 233.071162 -221.260924)
		(width 0.0889)
		(layer "B.Cu")
		(net "BOARD_TYPE_0_ADC_R")
	)
	(segment
		(start 234.667552 -219.10421)
		(end 235.067348 -219.504006)
		(width 0.13208)
		(layer "F.Cu")
		(net "VR_TYPE_ADC_R")
	)
	(via
		(at 235.067348 -219.504006)
		(size 0.4572)
		(drill 0.254)
		(layers "F.Cu" "B.Cu")
		(net "VR_TYPE_ADC_R")
	)
	(via
		(at 236.107478 -225.871532)
		(size 0.508)
		(drill 0.254)
		(layers "F.Cu" "B.Cu")
		(net "VR_TYPE_ADC_R")
	)
	(segment
		(start 238.443008 -224.024444)
		(end 237.475776 -224.024444)
		(width 0.13208)
		(layer "B.Cu")
		(net "VR_TYPE_ADC_R")
	)
	(segment
		(start 236.400848 -224.599754)
		(end 236.400848 -225.651314)
		(width 0.13208)
		(layer "B.Cu")
		(net "VR_TYPE_ADC_R")
	)
	(segment
		(start 235.473748 -219.910406)
		(end 235.473748 -225.558858)
		(width 0.0889)
		(layer "B.Cu")
		(net "VR_TYPE_ADC_R")
	)
	(segment
		(start 236.540294 -224.460308)
		(end 236.400848 -224.599754)
		(width 0.13208)
		(layer "B.Cu")
		(net "VR_TYPE_ADC_R")
	)
	(segment
		(start 236.18063 -225.871532)
		(end 236.107478 -225.871532)
		(width 0.13208)
		(layer "B.Cu")
		(net "VR_TYPE_ADC_R")
	)
	(segment
		(start 236.913674 -224.460308)
		(end 236.540294 -224.460308)
		(width 0.13208)
		(layer "B.Cu")
		(net "VR_TYPE_ADC_R")
	)
	(segment
		(start 235.067348 -219.504006)
		(end 235.473748 -219.910406)
		(width 0.0889)
		(layer "B.Cu")
		(net "VR_TYPE_ADC_R")
	)
	(segment
		(start 237.349538 -224.024444)
		(end 236.913674 -224.460308)
		(width 0.13208)
		(layer "B.Cu")
		(net "VR_TYPE_ADC_R")
	)
	(segment
		(start 235.473748 -225.558858)
		(end 235.786422 -225.871532)
		(width 0.13208)
		(layer "B.Cu")
		(net "VR_TYPE_ADC_R")
	)
	(segment
		(start 235.786422 -225.871532)
		(end 236.107478 -225.871532)
		(width 0.13208)
		(layer "B.Cu")
		(net "VR_TYPE_ADC_R")
	)
	(segment
		(start 237.475776 -224.024444)
		(end 237.349538 -224.024444)
		(width 0.13208)
		(layer "B.Cu")
		(net "VR_TYPE_ADC_R")
	)
	(segment
		(start 236.400848 -225.651314)
		(end 236.18063 -225.871532)
		(width 0.13208)
		(layer "B.Cu")
		(net "VR_TYPE_ADC_R")
	)
	(segment
		(start 233.067606 -219.10421)
		(end 233.467402 -219.504006)
		(width 0.13208)
		(layer "F.Cu")
		(net "ADC_TYPE_ADC_R")
	)
	(via
		(at 211.95411 -224.672652)
		(size 0.508)
		(drill 0.254)
		(layers "F.Cu" "B.Cu")
		(net "ADC_TYPE_ADC_R")
	)
	(via
		(at 233.467402 -219.504006)
		(size 0.4572)
		(drill 0.254)
		(layers "F.Cu" "B.Cu")
		(net "ADC_TYPE_ADC_R")
	)
	(segment
		(start 211.346542 -225.28022)
		(end 210.782408 -225.28022)
		(width 0.13208)
		(layer "B.Cu")
		(net "ADC_TYPE_ADC_R")
	)
	(segment
		(start 209.67446 -225.271838)
		(end 209.356452 -225.271838)
		(width 0.13208)
		(layer "B.Cu")
		(net "ADC_TYPE_ADC_R")
	)
	(segment
		(start 209.682842 -225.28022)
		(end 209.67446 -225.271838)
		(width 0.13208)
		(layer "B.Cu")
		(net "ADC_TYPE_ADC_R")
	)
	(segment
		(start 209.145378 -225.482912)
		(end 209.145378 -226.61118)
		(width 0.13208)
		(layer "B.Cu")
		(net "ADC_TYPE_ADC_R")
	)
	(segment
		(start 211.95411 -224.672652)
		(end 211.346542 -225.28022)
		(width 0.13208)
		(layer "B.Cu")
		(net "ADC_TYPE_ADC_R")
	)
	(segment
		(start 209.356452 -225.271838)
		(end 209.145378 -225.482912)
		(width 0.13208)
		(layer "B.Cu")
		(net "ADC_TYPE_ADC_R")
	)
	(segment
		(start 210.782408 -225.28022)
		(end 209.682842 -225.28022)
		(width 0.13208)
		(layer "B.Cu")
		(net "ADC_TYPE_ADC_R")
	)
	(segment
		(start 209.145378 -226.61118)
		(end 208.709768 -227.04679)
		(width 0.13208)
		(layer "B.Cu")
		(net "ADC_TYPE_ADC_R")
	)
	(segment
		(start 208.709768 -227.04679)
		(end 208.679288 -227.04679)
		(width 0.13208)
		(layer "B.Cu")
		(net "ADC_TYPE_ADC_R")
	)
	(segment
		(start 218.513914 -221.834456)
		(end 221.523306 -218.825064)
		(width 0.15494)
		(layer "In15.Cu")
		(net "ADC_TYPE_ADC_R")
	)
	(segment
		(start 212.163914 -224.882456)
		(end 212.868764 -224.882456)
		(width 0.15494)
		(layer "In15.Cu")
		(net "ADC_TYPE_ADC_R")
	)
	(segment
		(start 215.337136 -221.834456)
		(end 218.513914 -221.834456)
		(width 0.15494)
		(layer "In15.Cu")
		(net "ADC_TYPE_ADC_R")
	)
	(segment
		(start 233.330242 -218.825064)
		(end 233.467402 -218.962224)
		(width 0.15494)
		(layer "In15.Cu")
		(net "ADC_TYPE_ADC_R")
	)
	(segment
		(start 213.99754 -223.174052)
		(end 215.337136 -221.834456)
		(width 0.15494)
		(layer "In15.Cu")
		(net "ADC_TYPE_ADC_R")
	)
	(segment
		(start 233.467402 -218.962224)
		(end 233.467402 -219.504006)
		(width 0.15494)
		(layer "In15.Cu")
		(net "ADC_TYPE_ADC_R")
	)
	(segment
		(start 221.523306 -218.825064)
		(end 233.330242 -218.825064)
		(width 0.15494)
		(layer "In15.Cu")
		(net "ADC_TYPE_ADC_R")
	)
	(segment
		(start 211.95411 -224.672652)
		(end 212.163914 -224.882456)
		(width 0.15494)
		(layer "In15.Cu")
		(net "ADC_TYPE_ADC_R")
	)
	(segment
		(start 213.99754 -223.75368)
		(end 213.99754 -223.174052)
		(width 0.15494)
		(layer "In15.Cu")
		(net "ADC_TYPE_ADC_R")
	)
	(segment
		(start 212.868764 -224.882456)
		(end 213.99754 -223.75368)
		(width 0.15494)
		(layer "In15.Cu")
		(net "ADC_TYPE_ADC_R")
	)
	(segment
		(start 202.413616 -307.949346)
		(end 202.034394 -307.949346)
		(width 0.13208)
		(layer "F.Cu")
		(net "SMB_PEX1_R_SCL")
	)
	(segment
		(start 202.287378 -303.465484)
		(end 201.970386 -303.148492)
		(width 0.13208)
		(layer "F.Cu")
		(net "SMB_PEX1_R_SCL")
	)
	(segment
		(start 202.774296 -304.955448)
		(end 202.540616 -305.189128)
		(width 0.13208)
		(layer "F.Cu")
		(net "SMB_PEX1_R_SCL")
	)
	(segment
		(start 201.901806 -307.949346)
		(end 201.702924 -307.750464)
		(width 0.13208)
		(layer "F.Cu")
		(net "SMB_PEX1_R_SCL")
	)
	(segment
		(start 202.287378 -303.851818)
		(end 202.287378 -303.465484)
		(width 0.13208)
		(layer "F.Cu")
		(net "SMB_PEX1_R_SCL")
	)
	(segment
		(start 201.702924 -307.40096)
		(end 202.036172 -307.067712)
		(width 0.13208)
		(layer "F.Cu")
		(net "SMB_PEX1_R_SCL")
	)
	(segment
		(start 202.034394 -307.949346)
		(end 201.901806 -307.949346)
		(width 0.13208)
		(layer "F.Cu")
		(net "SMB_PEX1_R_SCL")
	)
	(segment
		(start 202.774296 -304.338736)
		(end 202.287378 -303.851818)
		(width 0.13208)
		(layer "F.Cu")
		(net "SMB_PEX1_R_SCL")
	)
	(segment
		(start 202.540616 -307.822346)
		(end 202.413616 -307.949346)
		(width 0.13208)
		(layer "F.Cu")
		(net "SMB_PEX1_R_SCL")
	)
	(segment
		(start 202.036172 -307.067712)
		(end 202.036172 -306.449222)
		(width 0.13208)
		(layer "F.Cu")
		(net "SMB_PEX1_R_SCL")
	)
	(segment
		(start 201.970386 -303.148492)
		(end 201.970386 -302.708564)
		(width 0.13208)
		(layer "F.Cu")
		(net "SMB_PEX1_R_SCL")
	)
	(segment
		(start 202.774296 -304.338736)
		(end 202.774296 -304.955448)
		(width 0.13208)
		(layer "F.Cu")
		(net "SMB_PEX1_R_SCL")
	)
	(segment
		(start 201.702924 -307.750464)
		(end 201.702924 -307.40096)
		(width 0.13208)
		(layer "F.Cu")
		(net "SMB_PEX1_R_SCL")
	)
	(segment
		(start 202.540616 -305.189128)
		(end 202.540616 -307.822346)
		(width 0.13208)
		(layer "F.Cu")
		(net "SMB_PEX1_R_SCL")
	)
	(via
		(at 202.034394 -307.949346)
		(size 0.762)
		(drill 0.381)
		(layers "F.Cu" "B.Cu")
		(net "SMB_PEX1_R_SCL")
	)
	(segment
		(start 203.721716 -307.771292)
		(end 203.781914 -307.711094)
		(width 0.13208)
		(layer "F.Cu")
		(net "SMB_PEX1_R_SDA")
	)
	(segment
		(start 203.00442 -306.477924)
		(end 203.00442 -307.644292)
		(width 0.13208)
		(layer "F.Cu")
		(net "SMB_PEX1_R_SDA")
	)
	(segment
		(start 203.13142 -307.771292)
		(end 203.721716 -307.771292)
		(width 0.13208)
		(layer "F.Cu")
		(net "SMB_PEX1_R_SDA")
	)
	(segment
		(start 204.113384 -307.379624)
		(end 204.113384 -306.465732)
		(width 0.13208)
		(layer "F.Cu")
		(net "SMB_PEX1_R_SDA")
	)
	(segment
		(start 203.781914 -307.711094)
		(end 204.113384 -307.379624)
		(width 0.13208)
		(layer "F.Cu")
		(net "SMB_PEX1_R_SDA")
	)
	(segment
		(start 203.6572 -304.449226)
		(end 203.792582 -304.313844)
		(width 0.13208)
		(layer "F.Cu")
		(net "SMB_PEX1_R_SDA")
	)
	(segment
		(start 204.113384 -306.465732)
		(end 204.115416 -306.4637)
		(width 0.13208)
		(layer "F.Cu")
		(net "SMB_PEX1_R_SDA")
	)
	(segment
		(start 203.00442 -306.477924)
		(end 203.249276 -306.477924)
		(width 0.13208)
		(layer "F.Cu")
		(net "SMB_PEX1_R_SDA")
	)
	(segment
		(start 203.00442 -307.644292)
		(end 203.13142 -307.771292)
		(width 0.13208)
		(layer "F.Cu")
		(net "SMB_PEX1_R_SDA")
	)
	(segment
		(start 203.6572 -306.07)
		(end 203.6572 -304.449226)
		(width 0.13208)
		(layer "F.Cu")
		(net "SMB_PEX1_R_SDA")
	)
	(segment
		(start 203.249276 -306.477924)
		(end 203.6572 -306.07)
		(width 0.13208)
		(layer "F.Cu")
		(net "SMB_PEX1_R_SDA")
	)
	(via
		(at 203.781914 -307.711094)
		(size 0.762)
		(drill 0.381)
		(layers "F.Cu" "B.Cu")
		(net "SMB_PEX1_R_SDA")
	)
	(segment
		(start 86.943692 -303.349914)
		(end 86.943692 -303.273714)
		(width 0.13208)
		(layer "F.Cu")
		(net "SMB_PEX0_R_SCL")
	)
	(segment
		(start 87.136478 -306.474622)
		(end 87.421212 -306.189888)
		(width 0.13208)
		(layer "F.Cu")
		(net "SMB_PEX0_R_SCL")
	)
	(segment
		(start 86.969346 -304.490882)
		(end 86.969346 -303.375568)
		(width 0.13208)
		(layer "F.Cu")
		(net "SMB_PEX0_R_SCL")
	)
	(segment
		(start 86.929976 -303.28743)
		(end 86.943692 -303.273714)
		(width 0.13208)
		(layer "F.Cu")
		(net "SMB_PEX0_R_SCL")
	)
	(segment
		(start 87.421212 -306.189888)
		(end 87.421212 -305.081686)
		(width 0.13208)
		(layer "F.Cu")
		(net "SMB_PEX0_R_SCL")
	)
	(segment
		(start 85.933788 -303.28743)
		(end 86.929976 -303.28743)
		(width 0.13208)
		(layer "F.Cu")
		(net "SMB_PEX0_R_SCL")
	)
	(segment
		(start 87.421212 -305.081686)
		(end 86.969346 -304.62982)
		(width 0.13208)
		(layer "F.Cu")
		(net "SMB_PEX0_R_SCL")
	)
	(segment
		(start 86.969346 -304.62982)
		(end 86.969346 -304.490882)
		(width 0.13208)
		(layer "F.Cu")
		(net "SMB_PEX0_R_SCL")
	)
	(segment
		(start 86.969346 -303.375568)
		(end 86.943692 -303.349914)
		(width 0.13208)
		(layer "F.Cu")
		(net "SMB_PEX0_R_SCL")
	)
	(segment
		(start 86.906608 -306.474622)
		(end 87.136478 -306.474622)
		(width 0.13208)
		(layer "F.Cu")
		(net "SMB_PEX0_R_SCL")
	)
	(via
		(at 86.969346 -304.490882)
		(size 0.762)
		(drill 0.381)
		(layers "F.Cu" "B.Cu")
		(net "SMB_PEX0_R_SCL")
	)
	(segment
		(start 87.776558 -307.780944)
		(end 88.481408 -307.076094)
		(width 0.13208)
		(layer "F.Cu")
		(net "SMB_PEX0_R_SDA")
	)
	(segment
		(start 88.481408 -307.076094)
		(end 88.481408 -304.315622)
		(width 0.13208)
		(layer "F.Cu")
		(net "SMB_PEX0_R_SDA")
	)
	(segment
		(start 87.90305 -303.323498)
		(end 87.918544 -303.308004)
		(width 0.13208)
		(layer "F.Cu")
		(net "SMB_PEX0_R_SDA")
	)
	(segment
		(start 88.260428 -303.308004)
		(end 87.918544 -303.308004)
		(width 0.13208)
		(layer "F.Cu")
		(net "SMB_PEX0_R_SDA")
	)
	(segment
		(start 87.982298 -307.179726)
		(end 87.488776 -307.673248)
		(width 0.13208)
		(layer "F.Cu")
		(net "SMB_PEX0_R_SDA")
	)
	(segment
		(start 87.488776 -307.673248)
		(end 87.596472 -307.780944)
		(width 0.13208)
		(layer "F.Cu")
		(net "SMB_PEX0_R_SDA")
	)
	(segment
		(start 88.902286 -302.666146)
		(end 88.260428 -303.308004)
		(width 0.13208)
		(layer "F.Cu")
		(net "SMB_PEX0_R_SDA")
	)
	(segment
		(start 87.596472 -307.780944)
		(end 87.776558 -307.780944)
		(width 0.13208)
		(layer "F.Cu")
		(net "SMB_PEX0_R_SDA")
	)
	(segment
		(start 87.90305 -303.737264)
		(end 87.90305 -303.323498)
		(width 0.13208)
		(layer "F.Cu")
		(net "SMB_PEX0_R_SDA")
	)
	(segment
		(start 88.481408 -304.315622)
		(end 87.90305 -303.737264)
		(width 0.13208)
		(layer "F.Cu")
		(net "SMB_PEX0_R_SDA")
	)
	(segment
		(start 87.982298 -306.46497)
		(end 87.982298 -307.179726)
		(width 0.13208)
		(layer "F.Cu")
		(net "SMB_PEX0_R_SDA")
	)
	(segment
		(start 89.202768 -302.666146)
		(end 88.902286 -302.666146)
		(width 0.13208)
		(layer "F.Cu")
		(net "SMB_PEX0_R_SDA")
	)
	(via
		(at 87.488776 -307.673248)
		(size 0.762)
		(drill 0.381)
		(layers "F.Cu" "B.Cu")
		(net "SMB_PEX0_R_SDA")
	)
	(segment
		(start 434.955442 -310.215534)
		(end 434.955442 -306.770786)
		(width 0.13208)
		(layer "F.Cu")
		(net "SMB_PEX3_R_SDA")
	)
	(segment
		(start 435.093364 -310.925464)
		(end 435.093364 -310.353456)
		(width 0.13208)
		(layer "F.Cu")
		(net "SMB_PEX3_R_SDA")
	)
	(segment
		(start 436.262272 -306.423822)
		(end 435.302406 -306.423822)
		(width 0.13208)
		(layer "F.Cu")
		(net "SMB_PEX3_R_SDA")
	)
	(segment
		(start 435.093364 -310.353456)
		(end 434.955442 -310.215534)
		(width 0.13208)
		(layer "F.Cu")
		(net "SMB_PEX3_R_SDA")
	)
	(segment
		(start 434.955442 -306.770786)
		(end 435.285134 -306.441094)
		(width 0.13208)
		(layer "F.Cu")
		(net "SMB_PEX3_R_SDA")
	)
	(segment
		(start 435.302406 -306.423822)
		(end 435.285134 -306.441094)
		(width 0.13208)
		(layer "F.Cu")
		(net "SMB_PEX3_R_SDA")
	)
	(segment
		(start 433.695602 -306.063142)
		(end 434.06187 -306.42941)
		(width 0.13208)
		(layer "F.Cu")
		(net "SMB_PEX3_R_SCL")
	)
	(segment
		(start 434.29428 -304.71491)
		(end 433.695602 -305.313588)
		(width 0.13208)
		(layer "F.Cu")
		(net "SMB_PEX3_R_SCL")
	)
	(segment
		(start 434.296058 -306.42941)
		(end 434.296058 -307.668422)
		(width 0.13208)
		(layer "F.Cu")
		(net "SMB_PEX3_R_SCL")
	)
	(segment
		(start 433.695602 -305.313588)
		(end 433.695602 -306.063142)
		(width 0.13208)
		(layer "F.Cu")
		(net "SMB_PEX3_R_SCL")
	)
	(segment
		(start 434.296058 -307.668422)
		(end 434.02123 -307.94325)
		(width 0.13208)
		(layer "F.Cu")
		(net "SMB_PEX3_R_SCL")
	)
	(segment
		(start 434.02123 -307.94325)
		(end 434.02123 -310.92775)
		(width 0.13208)
		(layer "F.Cu")
		(net "SMB_PEX3_R_SCL")
	)
	(segment
		(start 434.06187 -306.42941)
		(end 434.296058 -306.42941)
		(width 0.13208)
		(layer "F.Cu")
		(net "SMB_PEX3_R_SCL")
	)
	(segment
		(start 318.104774 -306.593494)
		(end 318.104774 -305.582066)
		(width 0.13208)
		(layer "F.Cu")
		(net "SMB_PEX2_R_SCL")
	)
	(segment
		(start 317.12154 -302.893984)
		(end 317.30442 -302.893984)
		(width 0.13208)
		(layer "F.Cu")
		(net "SMB_PEX2_R_SCL")
	)
	(segment
		(start 318.002412 -306.695856)
		(end 317.11646 -306.695856)
		(width 0.13208)
		(layer "F.Cu")
		(net "SMB_PEX2_R_SCL")
	)
	(segment
		(start 318.104774 -306.593494)
		(end 318.002412 -306.695856)
		(width 0.13208)
		(layer "F.Cu")
		(net "SMB_PEX2_R_SCL")
	)
	(segment
		(start 316.670436 -306.249832)
		(end 316.670436 -303.345088)
		(width 0.13208)
		(layer "F.Cu")
		(net "SMB_PEX2_R_SCL")
	)
	(segment
		(start 317.3349 -302.863504)
		(end 318.22771 -302.863504)
		(width 0.13208)
		(layer "F.Cu")
		(net "SMB_PEX2_R_SCL")
	)
	(segment
		(start 318.104774 -305.582066)
		(end 317.830708 -305.308)
		(width 0.13208)
		(layer "F.Cu")
		(net "SMB_PEX2_R_SCL")
	)
	(segment
		(start 316.670436 -303.345088)
		(end 317.12154 -302.893984)
		(width 0.13208)
		(layer "F.Cu")
		(net "SMB_PEX2_R_SCL")
	)
	(segment
		(start 317.11646 -306.695856)
		(end 316.670436 -306.249832)
		(width 0.13208)
		(layer "F.Cu")
		(net "SMB_PEX2_R_SCL")
	)
	(segment
		(start 317.30442 -302.893984)
		(end 317.3349 -302.863504)
		(width 0.13208)
		(layer "F.Cu")
		(net "SMB_PEX2_R_SCL")
	)
	(via
		(at 318.104774 -306.593494)
		(size 0.762)
		(drill 0.381)
		(layers "F.Cu" "B.Cu")
		(net "SMB_PEX2_R_SCL")
	)
	(segment
		(start 319.215008 -305.308)
		(end 318.89319 -305.308)
		(width 0.13208)
		(layer "F.Cu")
		(net "SMB_PEX2_R_SDA")
	)
	(segment
		(start 319.539112 -307.461158)
		(end 319.539112 -307.509418)
		(width 0.13208)
		(layer "F.Cu")
		(net "SMB_PEX2_R_SDA")
	)
	(segment
		(start 320.17589 -306.475892)
		(end 320.17589 -306.82438)
		(width 0.13208)
		(layer "F.Cu")
		(net "SMB_PEX2_R_SDA")
	)
	(segment
		(start 319.853564 -304.669444)
		(end 319.215008 -305.308)
		(width 0.13208)
		(layer "F.Cu")
		(net "SMB_PEX2_R_SDA")
	)
	(segment
		(start 319.853564 -304.372518)
		(end 319.853564 -304.669444)
		(width 0.13208)
		(layer "F.Cu")
		(net "SMB_PEX2_R_SDA")
	)
	(segment
		(start 320.214752 -304.01133)
		(end 319.853564 -304.372518)
		(width 0.13208)
		(layer "F.Cu")
		(net "SMB_PEX2_R_SDA")
	)
	(segment
		(start 320.235834 -304.01133)
		(end 320.214752 -304.01133)
		(width 0.13208)
		(layer "F.Cu")
		(net "SMB_PEX2_R_SDA")
	)
	(segment
		(start 319.539112 -307.509418)
		(end 319.382394 -307.666136)
		(width 0.13208)
		(layer "F.Cu")
		(net "SMB_PEX2_R_SDA")
	)
	(segment
		(start 319.002664 -307.286406)
		(end 319.382394 -307.666136)
		(width 0.13208)
		(layer "F.Cu")
		(net "SMB_PEX2_R_SDA")
	)
	(segment
		(start 318.89319 -305.308)
		(end 318.89319 -306.430426)
		(width 0.13208)
		(layer "F.Cu")
		(net "SMB_PEX2_R_SDA")
	)
	(segment
		(start 320.17589 -306.82438)
		(end 319.539112 -307.461158)
		(width 0.13208)
		(layer "F.Cu")
		(net "SMB_PEX2_R_SDA")
	)
	(segment
		(start 319.002664 -306.5399)
		(end 319.002664 -307.286406)
		(width 0.13208)
		(layer "F.Cu")
		(net "SMB_PEX2_R_SDA")
	)
	(segment
		(start 318.89319 -306.430426)
		(end 319.002664 -306.5399)
		(width 0.13208)
		(layer "F.Cu")
		(net "SMB_PEX2_R_SDA")
	)
	(via
		(at 319.382394 -307.666136)
		(size 0.762)
		(drill 0.381)
		(layers "F.Cu" "B.Cu")
		(net "SMB_PEX2_R_SDA")
	)
	(segment
		(start 224.267776 -220.704156)
		(end 223.86798 -221.103952)
		(width 0.13208)
		(layer "F.Cu")
		(net "SMB_BIC_FPGA_R2_SDA")
	)
	(via
		(at 223.86798 -221.103952)
		(size 0.4572)
		(drill 0.254)
		(layers "F.Cu" "B.Cu")
		(net "SMB_BIC_FPGA_R2_SDA")
	)
	(via
		(at 221.851728 -222.141034)
		(size 0.6604)
		(drill 0.3302)
		(layers "F.Cu" "B.Cu")
		(net "SMB_BIC_FPGA_R2_SDA")
	)
	(segment
		(start 219.919296 -223.251268)
		(end 220.741494 -223.251268)
		(width 0.13208)
		(layer "B.Cu")
		(net "SMB_BIC_FPGA_R2_SDA")
	)
	(segment
		(start 220.741494 -223.251268)
		(end 221.851728 -222.141034)
		(width 0.13208)
		(layer "B.Cu")
		(net "SMB_BIC_FPGA_R2_SDA")
	)
	(segment
		(start 222.88881 -221.103952)
		(end 221.851728 -222.141034)
		(width 0.13208)
		(layer "B.Cu")
		(net "SMB_BIC_FPGA_R2_SDA")
	)
	(segment
		(start 223.86798 -221.103952)
		(end 222.88881 -221.103952)
		(width 0.13208)
		(layer "B.Cu")
		(net "SMB_BIC_FPGA_R2_SDA")
	)
	(segment
		(start 225.067622 -220.704156)
		(end 224.667826 -221.103952)
		(width 0.13208)
		(layer "F.Cu")
		(net "SMB_BIC_FPGA_R2_SCL")
	)
	(via
		(at 224.667826 -221.103952)
		(size 0.4572)
		(drill 0.254)
		(layers "F.Cu" "B.Cu")
		(net "SMB_BIC_FPGA_R2_SCL")
	)
	(via
		(at 221.456504 -220.745304)
		(size 0.6604)
		(drill 0.3302)
		(layers "F.Cu" "B.Cu")
		(net "SMB_BIC_FPGA_R2_SCL")
	)
	(segment
		(start 221.302834 -220.762068)
		(end 221.439994 -220.761814)
		(width 0.13208)
		(layer "B.Cu")
		(net "SMB_BIC_FPGA_R2_SCL")
	)
	(segment
		(start 220.32087 -220.762068)
		(end 221.302834 -220.762068)
		(width 0.13208)
		(layer "B.Cu")
		(net "SMB_BIC_FPGA_R2_SCL")
	)
	(segment
		(start 223.523048 -220.707712)
		(end 223.485456 -220.745304)
		(width 0.0889)
		(layer "B.Cu")
		(net "SMB_BIC_FPGA_R2_SCL")
	)
	(segment
		(start 223.485456 -220.745304)
		(end 221.456504 -220.745304)
		(width 0.13208)
		(layer "B.Cu")
		(net "SMB_BIC_FPGA_R2_SCL")
	)
	(segment
		(start 224.271586 -220.707712)
		(end 223.523048 -220.707712)
		(width 0.0889)
		(layer "B.Cu")
		(net "SMB_BIC_FPGA_R2_SCL")
	)
	(segment
		(start 224.667826 -221.103952)
		(end 224.271586 -220.707712)
		(width 0.0889)
		(layer "B.Cu")
		(net "SMB_BIC_FPGA_R2_SCL")
	)
	(segment
		(start 221.439994 -220.761814)
		(end 221.456504 -220.745304)
		(width 0.13208)
		(layer "B.Cu")
		(net "SMB_BIC_FPGA_R2_SCL")
	)
	(segment
		(start 259.092446 -338.013294)
		(end 260.111748 -338.013294)
		(width 0.13208)
		(layer "F.Cu")
		(net "OC_P2V5_COMP")
	)
	(segment
		(start 262.18388 -336.046318)
		(end 261.356348 -336.046318)
		(width 0.13208)
		(layer "F.Cu")
		(net "OC_P2V5_COMP")
	)
	(segment
		(start 263.348724 -336.444844)
		(end 263.348724 -339.233764)
		(width 0.13208)
		(layer "F.Cu")
		(net "OC_P2V5_COMP")
	)
	(segment
		(start 261.356348 -336.046318)
		(end 261.01167 -336.390996)
		(width 0.13208)
		(layer "F.Cu")
		(net "OC_P2V5_COMP")
	)
	(segment
		(start 259.092446 -338.013294)
		(end 259.092446 -336.521298)
		(width 0.13208)
		(layer "F.Cu")
		(net "OC_P2V5_COMP")
	)
	(segment
		(start 262.774176 -339.808312)
		(end 262.20293 -339.808312)
		(width 0.13208)
		(layer "F.Cu")
		(net "OC_P2V5_COMP")
	)
	(segment
		(start 260.111748 -338.013294)
		(end 260.12521 -338.026756)
		(width 0.13208)
		(layer "F.Cu")
		(net "OC_P2V5_COMP")
	)
	(segment
		(start 262.20293 -339.808312)
		(end 262.197088 -339.80247)
		(width 0.13208)
		(layer "F.Cu")
		(net "OC_P2V5_COMP")
	)
	(segment
		(start 261.01167 -336.390996)
		(end 259.6515 -336.390996)
		(width 0.13208)
		(layer "F.Cu")
		(net "OC_P2V5_COMP")
	)
	(segment
		(start 262.20293 -336.065368)
		(end 262.18388 -336.046318)
		(width 0.13208)
		(layer "F.Cu")
		(net "OC_P2V5_COMP")
	)
	(segment
		(start 262.969248 -336.065368)
		(end 263.348724 -336.444844)
		(width 0.13208)
		(layer "F.Cu")
		(net "OC_P2V5_COMP")
	)
	(segment
		(start 259.6515 -336.390996)
		(end 259.437124 -336.17662)
		(width 0.13208)
		(layer "F.Cu")
		(net "OC_P2V5_COMP")
	)
	(segment
		(start 259.092446 -336.521298)
		(end 259.437124 -336.17662)
		(width 0.13208)
		(layer "F.Cu")
		(net "OC_P2V5_COMP")
	)
	(segment
		(start 263.348724 -339.233764)
		(end 262.774176 -339.808312)
		(width 0.13208)
		(layer "F.Cu")
		(net "OC_P2V5_COMP")
	)
	(segment
		(start 262.20293 -336.065368)
		(end 262.969248 -336.065368)
		(width 0.13208)
		(layer "F.Cu")
		(net "OC_P2V5_COMP")
	)
	(via
		(at 259.437124 -336.17662)
		(size 0.762)
		(drill 0.381)
		(layers "F.Cu" "B.Cu")
		(net "OC_P2V5_COMP")
	)
	(segment
		(start 194.695064 -415.040826)
		(end 194.695064 -414.80486)
		(width 0.13208)
		(layer "F.Cu")
		(net "UV_P2V5_COMP")
	)
	(segment
		(start 200.601326 -413.88792)
		(end 200.601326 -412.464504)
		(width 0.13208)
		(layer "F.Cu")
		(net "UV_P2V5_COMP")
	)
	(segment
		(start 196.550788 -414.8582)
		(end 197.696836 -414.8582)
		(width 0.13208)
		(layer "F.Cu")
		(net "UV_P2V5_COMP")
	)
	(segment
		(start 197.734936 -414.8201)
		(end 199.669146 -414.8201)
		(width 0.13208)
		(layer "F.Cu")
		(net "UV_P2V5_COMP")
	)
	(segment
		(start 197.702932 -414.852104)
		(end 197.734936 -414.8201)
		(width 0.13208)
		(layer "F.Cu")
		(net "UV_P2V5_COMP")
	)
	(segment
		(start 194.987672 -415.333434)
		(end 194.695064 -415.040826)
		(width 0.13208)
		(layer "F.Cu")
		(net "UV_P2V5_COMP")
	)
	(segment
		(start 196.550788 -414.8582)
		(end 196.075554 -415.333434)
		(width 0.13208)
		(layer "F.Cu")
		(net "UV_P2V5_COMP")
	)
	(segment
		(start 197.696836 -414.8582)
		(end 197.702932 -414.852104)
		(width 0.13208)
		(layer "F.Cu")
		(net "UV_P2V5_COMP")
	)
	(segment
		(start 199.669146 -414.8201)
		(end 200.12279 -414.366456)
		(width 0.13208)
		(layer "F.Cu")
		(net "UV_P2V5_COMP")
	)
	(segment
		(start 196.075554 -415.333434)
		(end 194.987672 -415.333434)
		(width 0.13208)
		(layer "F.Cu")
		(net "UV_P2V5_COMP")
	)
	(segment
		(start 200.12279 -414.366456)
		(end 200.601326 -413.88792)
		(width 0.13208)
		(layer "F.Cu")
		(net "UV_P2V5_COMP")
	)
	(via
		(at 200.12279 -414.366456)
		(size 0.762)
		(drill 0.381)
		(layers "F.Cu" "B.Cu")
		(net "UV_P2V5_COMP")
	)
	(segment
		(start 261.00659 -334.165448)
		(end 260.451346 -333.610204)
		(width 0.13208)
		(layer "F.Cu")
		(net "HSC_OC_VOL")
	)
	(segment
		(start 262.697214 -332.655926)
		(end 262.697214 -333.908654)
		(width 0.13208)
		(layer "F.Cu")
		(net "HSC_OC_VOL")
	)
	(segment
		(start 259.397246 -333.612998)
		(end 259.399786 -333.615538)
		(width 0.13208)
		(layer "F.Cu")
		(net "HSC_OC_VOL")
	)
	(segment
		(start 259.399786 -333.615538)
		(end 260.446012 -333.615538)
		(width 0.13208)
		(layer "F.Cu")
		(net "HSC_OC_VOL")
	)
	(segment
		(start 262.685784 -332.644496)
		(end 262.697214 -332.655926)
		(width 0.13208)
		(layer "F.Cu")
		(net "HSC_OC_VOL")
	)
	(segment
		(start 258.401566 -333.612998)
		(end 259.397246 -333.612998)
		(width 0.13208)
		(layer "F.Cu")
		(net "HSC_OC_VOL")
	)
	(segment
		(start 262.44042 -334.165448)
		(end 262.20293 -334.165448)
		(width 0.13208)
		(layer "F.Cu")
		(net "HSC_OC_VOL")
	)
	(segment
		(start 262.685784 -332.495906)
		(end 262.685784 -332.644496)
		(width 0.13208)
		(layer "F.Cu")
		(net "HSC_OC_VOL")
	)
	(segment
		(start 260.446012 -333.615538)
		(end 260.451346 -333.610204)
		(width 0.13208)
		(layer "F.Cu")
		(net "HSC_OC_VOL")
	)
	(segment
		(start 262.813038 -332.368652)
		(end 262.685784 -332.495906)
		(width 0.13208)
		(layer "F.Cu")
		(net "HSC_OC_VOL")
	)
	(segment
		(start 263.941306 -332.368652)
		(end 262.813038 -332.368652)
		(width 0.13208)
		(layer "F.Cu")
		(net "HSC_OC_VOL")
	)
	(segment
		(start 264.182352 -332.609698)
		(end 263.941306 -332.368652)
		(width 0.13208)
		(layer "F.Cu")
		(net "HSC_OC_VOL")
	)
	(segment
		(start 262.697214 -333.908654)
		(end 262.44042 -334.165448)
		(width 0.13208)
		(layer "F.Cu")
		(net "HSC_OC_VOL")
	)
	(segment
		(start 262.20293 -334.165448)
		(end 261.00659 -334.165448)
		(width 0.13208)
		(layer "F.Cu")
		(net "HSC_OC_VOL")
	)
	(via
		(at 262.685784 -332.644496)
		(size 0.762)
		(drill 0.381)
		(layers "F.Cu" "B.Cu")
		(net "HSC_OC_VOL")
	)
	(segment
		(start 267.830554 -334.165448)
		(end 267.832332 -334.16367)
		(width 0.13208)
		(layer "F.Cu")
		(net "HSC_D_OC_R2")
	)
	(segment
		(start 264.90295 -334.165448)
		(end 266.490196 -334.165448)
		(width 0.13208)
		(layer "F.Cu")
		(net "HSC_D_OC_R2")
	)
	(segment
		(start 264.982452 -332.609698)
		(end 264.275824 -333.316326)
		(width 0.13208)
		(layer "F.Cu")
		(net "HSC_D_OC_R2")
	)
	(segment
		(start 266.490196 -334.165448)
		(end 267.830554 -334.165448)
		(width 0.13208)
		(layer "F.Cu")
		(net "HSC_D_OC_R2")
	)
	(segment
		(start 264.275824 -333.809086)
		(end 264.632186 -334.165448)
		(width 0.13208)
		(layer "F.Cu")
		(net "HSC_D_OC_R2")
	)
	(segment
		(start 264.275824 -333.316326)
		(end 264.275824 -333.809086)
		(width 0.13208)
		(layer "F.Cu")
		(net "HSC_D_OC_R2")
	)
	(segment
		(start 264.632186 -334.165448)
		(end 264.90295 -334.165448)
		(width 0.13208)
		(layer "F.Cu")
		(net "HSC_D_OC_R2")
	)
	(via
		(at 266.490196 -334.165448)
		(size 0.762)
		(drill 0.381)
		(layers "F.Cu" "B.Cu")
		(net "HSC_D_OC_R2")
	)
	(segment
		(start 189.169294 -412.673546)
		(end 189.023752 -412.673546)
		(width 0.13208)
		(layer "F.Cu")
		(net "HSC_UV_R2_N")
	)
	(segment
		(start 190.245238 -411.81909)
		(end 190.24219 -411.816042)
		(width 0.13208)
		(layer "F.Cu")
		(net "HSC_UV_R2_N")
	)
	(segment
		(start 190.97371 -411.090618)
		(end 190.245238 -411.81909)
		(width 0.13208)
		(layer "F.Cu")
		(net "HSC_UV_R2_N")
	)
	(segment
		(start 186.776868 -414.02762)
		(end 186.776868 -413.364934)
		(width 0.13208)
		(layer "F.Cu")
		(net "HSC_UV_R2_N")
	)
	(segment
		(start 188.938916 -412.758382)
		(end 189.023752 -412.673546)
		(width 0.13208)
		(layer "F.Cu")
		(net "HSC_UV_R2_N")
	)
	(segment
		(start 192.795144 -412.10484)
		(end 191.780922 -411.090618)
		(width 0.13208)
		(layer "F.Cu")
		(net "HSC_UV_R2_N")
	)
	(segment
		(start 187.38342 -412.758382)
		(end 188.938916 -412.758382)
		(width 0.13208)
		(layer "F.Cu")
		(net "HSC_UV_R2_N")
	)
	(segment
		(start 190.24219 -411.816042)
		(end 190.026798 -411.816042)
		(width 0.13208)
		(layer "F.Cu")
		(net "HSC_UV_R2_N")
	)
	(segment
		(start 191.780922 -411.090618)
		(end 190.97371 -411.090618)
		(width 0.13208)
		(layer "F.Cu")
		(net "HSC_UV_R2_N")
	)
	(segment
		(start 186.776868 -413.364934)
		(end 187.38342 -412.758382)
		(width 0.13208)
		(layer "F.Cu")
		(net "HSC_UV_R2_N")
	)
	(segment
		(start 190.026798 -411.816042)
		(end 189.169294 -412.673546)
		(width 0.13208)
		(layer "F.Cu")
		(net "HSC_UV_R2_N")
	)
	(via
		(at 189.023752 -412.673546)
		(size 0.762)
		(drill 0.381)
		(layers "F.Cu" "B.Cu")
		(net "HSC_UV_R2_N")
	)
	(segment
		(start 191.03975 -414.981136)
		(end 189.88786 -414.981136)
		(width 0.13208)
		(layer "F.Cu")
		(net "P12V_AUX_FP_TRIGGER")
	)
	(segment
		(start 191.156336 -411.708092)
		(end 191.51219 -411.708092)
		(width 0.13208)
		(layer "F.Cu")
		(net "P12V_AUX_FP_TRIGGER")
	)
	(segment
		(start 192.795144 -414.997646)
		(end 192.795144 -414.80486)
		(width 0.13208)
		(layer "F.Cu")
		(net "P12V_AUX_FP_TRIGGER")
	)
	(segment
		(start 191.0461 -414.987486)
		(end 191.384428 -415.325814)
		(width 0.13208)
		(layer "F.Cu")
		(net "P12V_AUX_FP_TRIGGER")
	)
	(segment
		(start 190.245238 -412.61919)
		(end 191.156336 -411.708092)
		(width 0.13208)
		(layer "F.Cu")
		(net "P12V_AUX_FP_TRIGGER")
	)
	(segment
		(start 192.375028 -414.153604)
		(end 192.795144 -414.57372)
		(width 0.13208)
		(layer "F.Cu")
		(net "P12V_AUX_FP_TRIGGER")
	)
	(segment
		(start 189.88532 -414.983676)
		(end 188.806074 -414.983676)
		(width 0.13208)
		(layer "F.Cu")
		(net "P12V_AUX_FP_TRIGGER")
	)
	(segment
		(start 189.88786 -414.981136)
		(end 189.88532 -414.983676)
		(width 0.13208)
		(layer "F.Cu")
		(net "P12V_AUX_FP_TRIGGER")
	)
	(segment
		(start 191.51219 -413.069786)
		(end 192.375028 -413.932624)
		(width 0.13208)
		(layer "F.Cu")
		(net "P12V_AUX_FP_TRIGGER")
	)
	(segment
		(start 191.384428 -415.325814)
		(end 192.466976 -415.325814)
		(width 0.13208)
		(layer "F.Cu")
		(net "P12V_AUX_FP_TRIGGER")
	)
	(segment
		(start 191.0461 -414.987486)
		(end 191.03975 -414.981136)
		(width 0.13208)
		(layer "F.Cu")
		(net "P12V_AUX_FP_TRIGGER")
	)
	(segment
		(start 191.51219 -411.708092)
		(end 191.51219 -413.069786)
		(width 0.13208)
		(layer "F.Cu")
		(net "P12V_AUX_FP_TRIGGER")
	)
	(segment
		(start 192.375028 -413.932624)
		(end 192.375028 -414.153604)
		(width 0.13208)
		(layer "F.Cu")
		(net "P12V_AUX_FP_TRIGGER")
	)
	(segment
		(start 192.466976 -415.325814)
		(end 192.795144 -414.997646)
		(width 0.13208)
		(layer "F.Cu")
		(net "P12V_AUX_FP_TRIGGER")
	)
	(segment
		(start 192.795144 -414.57372)
		(end 192.795144 -414.80486)
		(width 0.13208)
		(layer "F.Cu")
		(net "P12V_AUX_FP_TRIGGER")
	)
	(via
		(at 191.51219 -411.708092)
		(size 0.762)
		(drill 0.381)
		(layers "F.Cu" "B.Cu")
		(net "P12V_AUX_FP_TRIGGER")
	)
	(segment
		(start 263.57199 -219.148406)
		(end 264.982706 -220.559122)
		(width 0.13208)
		(layer "F.Cu")
		(net "SMB_BIC_FPGA_R1_SCL")
	)
	(segment
		(start 329.028044 -218.817444)
		(end 330.055982 -219.845382)
		(width 0.13208)
		(layer "F.Cu")
		(net "SMB_BIC_FPGA_R1_SCL")
	)
	(segment
		(start 334.525112 -219.583254)
		(end 334.89392 -219.214446)
		(width 0.13208)
		(layer "F.Cu")
		(net "SMB_BIC_FPGA_R1_SCL")
	)
	(segment
		(start 264.982706 -220.559122)
		(end 264.982706 -225.930968)
		(width 0.13208)
		(layer "F.Cu")
		(net "SMB_BIC_FPGA_R1_SCL")
	)
	(segment
		(start 334.89392 -219.214446)
		(end 334.89392 -219.187014)
		(width 0.13208)
		(layer "F.Cu")
		(net "SMB_BIC_FPGA_R1_SCL")
	)
	(segment
		(start 325.949056 -218.065604)
		(end 325.949056 -218.698064)
		(width 0.13208)
		(layer "F.Cu")
		(net "SMB_BIC_FPGA_R1_SCL")
	)
	(segment
		(start 256.26949 -234.644184)
		(end 256.26949 -234.697778)
		(width 0.13208)
		(layer "F.Cu")
		(net "SMB_BIC_FPGA_R1_SCL")
	)
	(segment
		(start 330.055982 -219.845382)
		(end 331.057758 -219.845382)
		(width 0.13208)
		(layer "F.Cu")
		(net "SMB_BIC_FPGA_R1_SCL")
	)
	(segment
		(start 325.64197 -217.758518)
		(end 325.453502 -217.57005)
		(width 0.13208)
		(layer "F.Cu")
		(net "SMB_BIC_FPGA_R1_SCL")
	)
	(segment
		(start 324.699376 -217.57005)
		(end 324.47992 -217.350594)
		(width 0.13208)
		(layer "F.Cu")
		(net "SMB_BIC_FPGA_R1_SCL")
	)
	(segment
		(start 325.64197 -217.758518)
		(end 325.949056 -218.065604)
		(width 0.13208)
		(layer "F.Cu")
		(net "SMB_BIC_FPGA_R1_SCL")
	)
	(segment
		(start 264.982706 -225.930968)
		(end 256.26949 -234.644184)
		(width 0.13208)
		(layer "F.Cu")
		(net "SMB_BIC_FPGA_R1_SCL")
	)
	(segment
		(start 325.949056 -218.698064)
		(end 326.068436 -218.817444)
		(width 0.13208)
		(layer "F.Cu")
		(net "SMB_BIC_FPGA_R1_SCL")
	)
	(segment
		(start 331.057758 -219.845382)
		(end 331.319886 -219.583254)
		(width 0.13208)
		(layer "F.Cu")
		(net "SMB_BIC_FPGA_R1_SCL")
	)
	(segment
		(start 325.453502 -217.57005)
		(end 324.699376 -217.57005)
		(width 0.13208)
		(layer "F.Cu")
		(net "SMB_BIC_FPGA_R1_SCL")
	)
	(segment
		(start 331.319886 -219.583254)
		(end 334.525112 -219.583254)
		(width 0.13208)
		(layer "F.Cu")
		(net "SMB_BIC_FPGA_R1_SCL")
	)
	(segment
		(start 324.47992 -217.350594)
		(end 322.967096 -217.350594)
		(width 0.13208)
		(layer "F.Cu")
		(net "SMB_BIC_FPGA_R1_SCL")
	)
	(segment
		(start 322.967096 -217.350594)
		(end 322.806568 -217.511122)
		(width 0.13208)
		(layer "F.Cu")
		(net "SMB_BIC_FPGA_R1_SCL")
	)
	(segment
		(start 326.068436 -218.817444)
		(end 329.028044 -218.817444)
		(width 0.13208)
		(layer "F.Cu")
		(net "SMB_BIC_FPGA_R1_SCL")
	)
	(via
		(at 256.26949 -234.697778)
		(size 0.508)
		(drill 0.254)
		(layers "F.Cu" "B.Cu")
		(net "SMB_BIC_FPGA_R1_SCL")
	)
	(via
		(at 322.806568 -217.511122)
		(size 0.508)
		(drill 0.254)
		(layers "F.Cu" "B.Cu")
		(net "SMB_BIC_FPGA_R1_SCL")
	)
	(via
		(at 325.64197 -217.758518)
		(size 0.762)
		(drill 0.381)
		(layers "F.Cu" "B.Cu")
		(net "SMB_BIC_FPGA_R1_SCL")
	)
	(via
		(at 206.39405 -223.731836)
		(size 0.508)
		(drill 0.254)
		(layers "F.Cu" "B.Cu")
		(net "SMB_BIC_FPGA_R1_SCL")
	)
	(via
		(at 263.57199 -219.148406)
		(size 0.508)
		(drill 0.254)
		(layers "F.Cu" "B.Cu")
		(net "SMB_BIC_FPGA_R1_SCL")
	)
	(segment
		(start 212.51926 -221.890844)
		(end 211.752434 -222.65767)
		(width 0.13208)
		(layer "B.Cu")
		(net "SMB_BIC_FPGA_R1_SCL")
	)
	(segment
		(start 208.93659 -223.035114)
		(end 208.239868 -223.731836)
		(width 0.13208)
		(layer "B.Cu")
		(net "SMB_BIC_FPGA_R1_SCL")
	)
	(segment
		(start 216.83345 -222.368872)
		(end 216.83345 -222.091504)
		(width 0.13208)
		(layer "B.Cu")
		(net "SMB_BIC_FPGA_R1_SCL")
	)
	(segment
		(start 211.752434 -222.65767)
		(end 211.5312 -222.65767)
		(width 0.13208)
		(layer "B.Cu")
		(net "SMB_BIC_FPGA_R1_SCL")
	)
	(segment
		(start 216.63279 -221.890844)
		(end 212.51926 -221.890844)
		(width 0.13208)
		(layer "B.Cu")
		(net "SMB_BIC_FPGA_R1_SCL")
	)
	(segment
		(start 211.5312 -222.65767)
		(end 211.153756 -223.035114)
		(width 0.13208)
		(layer "B.Cu")
		(net "SMB_BIC_FPGA_R1_SCL")
	)
	(segment
		(start 216.83345 -222.091504)
		(end 216.63279 -221.890844)
		(width 0.13208)
		(layer "B.Cu")
		(net "SMB_BIC_FPGA_R1_SCL")
	)
	(segment
		(start 208.239868 -223.731836)
		(end 206.39405 -223.731836)
		(width 0.13208)
		(layer "B.Cu")
		(net "SMB_BIC_FPGA_R1_SCL")
	)
	(segment
		(start 211.153756 -223.035114)
		(end 208.93659 -223.035114)
		(width 0.13208)
		(layer "B.Cu")
		(net "SMB_BIC_FPGA_R1_SCL")
	)
	(segment
		(start 231.293924 -233.729784)
		(end 240.377726 -233.729784)
		(width 0.15494)
		(layer "In13.Cu")
		(net "SMB_BIC_FPGA_R1_SCL")
	)
	(segment
		(start 210.872832 -229.117906)
		(end 224.188528 -229.117906)
		(width 0.15494)
		(layer "In13.Cu")
		(net "SMB_BIC_FPGA_R1_SCL")
	)
	(segment
		(start 206.39405 -223.731836)
		(end 207.540352 -223.731836)
		(width 0.15494)
		(layer "In13.Cu")
		(net "SMB_BIC_FPGA_R1_SCL")
	)
	(segment
		(start 249.780044 -235.251244)
		(end 251.840238 -235.251244)
		(width 0.15494)
		(layer "In13.Cu")
		(net "SMB_BIC_FPGA_R1_SCL")
	)
	(segment
		(start 247.04675 -233.9848)
		(end 248.5136 -233.9848)
		(width 0.15494)
		(layer "In13.Cu")
		(net "SMB_BIC_FPGA_R1_SCL")
	)
	(segment
		(start 228.26091 -232.709212)
		(end 228.26091 -233.672126)
		(width 0.15494)
		(layer "In13.Cu")
		(net "SMB_BIC_FPGA_R1_SCL")
	)
	(segment
		(start 210.333844 -226.525328)
		(end 210.333844 -228.578918)
		(width 0.15494)
		(layer "In13.Cu")
		(net "SMB_BIC_FPGA_R1_SCL")
	)
	(segment
		(start 253.048516 -234.042966)
		(end 255.552194 -234.042966)
		(width 0.15494)
		(layer "In13.Cu")
		(net "SMB_BIC_FPGA_R1_SCL")
	)
	(segment
		(start 228.26091 -233.672126)
		(end 228.67493 -234.086146)
		(width 0.15494)
		(layer "In13.Cu")
		(net "SMB_BIC_FPGA_R1_SCL")
	)
	(segment
		(start 240.377726 -233.729784)
		(end 241.74831 -232.3592)
		(width 0.15494)
		(layer "In13.Cu")
		(net "SMB_BIC_FPGA_R1_SCL")
	)
	(segment
		(start 207.540352 -223.731836)
		(end 210.333844 -226.525328)
		(width 0.15494)
		(layer "In13.Cu")
		(net "SMB_BIC_FPGA_R1_SCL")
	)
	(segment
		(start 226.682046 -228.530658)
		(end 227.972366 -229.820978)
		(width 0.15494)
		(layer "In13.Cu")
		(net "SMB_BIC_FPGA_R1_SCL")
	)
	(segment
		(start 224.188528 -229.117906)
		(end 224.775776 -228.530658)
		(width 0.15494)
		(layer "In13.Cu")
		(net "SMB_BIC_FPGA_R1_SCL")
	)
	(segment
		(start 248.5136 -233.9848)
		(end 249.780044 -235.251244)
		(width 0.15494)
		(layer "In13.Cu")
		(net "SMB_BIC_FPGA_R1_SCL")
	)
	(segment
		(start 227.972366 -232.420668)
		(end 228.26091 -232.709212)
		(width 0.15494)
		(layer "In13.Cu")
		(net "SMB_BIC_FPGA_R1_SCL")
	)
	(segment
		(start 228.67493 -234.086146)
		(end 230.937562 -234.086146)
		(width 0.15494)
		(layer "In13.Cu")
		(net "SMB_BIC_FPGA_R1_SCL")
	)
	(segment
		(start 227.972366 -229.820978)
		(end 227.972366 -232.420668)
		(width 0.15494)
		(layer "In13.Cu")
		(net "SMB_BIC_FPGA_R1_SCL")
	)
	(segment
		(start 210.333844 -228.578918)
		(end 210.872832 -229.117906)
		(width 0.15494)
		(layer "In13.Cu")
		(net "SMB_BIC_FPGA_R1_SCL")
	)
	(segment
		(start 230.937562 -234.086146)
		(end 231.293924 -233.729784)
		(width 0.15494)
		(layer "In13.Cu")
		(net "SMB_BIC_FPGA_R1_SCL")
	)
	(segment
		(start 241.74831 -232.3592)
		(end 244.2718 -232.3592)
		(width 0.15494)
		(layer "In13.Cu")
		(net "SMB_BIC_FPGA_R1_SCL")
	)
	(segment
		(start 256.207006 -234.697778)
		(end 256.26949 -234.697778)
		(width 0.15494)
		(layer "In13.Cu")
		(net "SMB_BIC_FPGA_R1_SCL")
	)
	(segment
		(start 224.775776 -228.530658)
		(end 226.682046 -228.530658)
		(width 0.15494)
		(layer "In13.Cu")
		(net "SMB_BIC_FPGA_R1_SCL")
	)
	(segment
		(start 255.552194 -234.042966)
		(end 256.207006 -234.697778)
		(width 0.15494)
		(layer "In13.Cu")
		(net "SMB_BIC_FPGA_R1_SCL")
	)
	(segment
		(start 251.840238 -235.251244)
		(end 253.048516 -234.042966)
		(width 0.15494)
		(layer "In13.Cu")
		(net "SMB_BIC_FPGA_R1_SCL")
	)
	(segment
		(start 245.084854 -233.172254)
		(end 247.04675 -233.9848)
		(width 0.15494)
		(layer "In13.Cu")
		(net "SMB_BIC_FPGA_R1_SCL")
	)
	(segment
		(start 244.2718 -232.3592)
		(end 245.084854 -233.172254)
		(width 0.15494)
		(layer "In13.Cu")
		(net "SMB_BIC_FPGA_R1_SCL")
	)
	(segment
		(start 263.57199 -219.148406)
		(end 264.38733 -219.148406)
		(width 0.15494)
		(layer "In15.Cu")
		(net "SMB_BIC_FPGA_R1_SCL")
	)
	(segment
		(start 304.60569 -218.887802)
		(end 305.98237 -217.511122)
		(width 0.15494)
		(layer "In15.Cu")
		(net "SMB_BIC_FPGA_R1_SCL")
	)
	(segment
		(start 289.239452 -218.887802)
		(end 304.60569 -218.887802)
		(width 0.15494)
		(layer "In15.Cu")
		(net "SMB_BIC_FPGA_R1_SCL")
	)
	(segment
		(start 288.537904 -219.58935)
		(end 289.239452 -218.887802)
		(width 0.15494)
		(layer "In15.Cu")
		(net "SMB_BIC_FPGA_R1_SCL")
	)
	(segment
		(start 305.98237 -217.511122)
		(end 322.806568 -217.511122)
		(width 0.15494)
		(layer "In15.Cu")
		(net "SMB_BIC_FPGA_R1_SCL")
	)
	(segment
		(start 264.38733 -219.148406)
		(end 264.828274 -219.58935)
		(width 0.15494)
		(layer "In15.Cu")
		(net "SMB_BIC_FPGA_R1_SCL")
	)
	(segment
		(start 264.828274 -219.58935)
		(end 288.537904 -219.58935)
		(width 0.15494)
		(layer "In15.Cu")
		(net "SMB_BIC_FPGA_R1_SCL")
	)
	(segment
		(start 330.533756 -221.864936)
		(end 330.71816 -221.680532)
		(width 0.13208)
		(layer "F.Cu")
		(net "SMB_BIC_FPGA_R1_SDA")
	)
	(segment
		(start 264.251186 -225.701606)
		(end 255.258062 -234.69473)
		(width 0.13208)
		(layer "F.Cu")
		(net "SMB_BIC_FPGA_R1_SDA")
	)
	(segment
		(start 264.251186 -220.49613)
		(end 264.251186 -225.701606)
		(width 0.13208)
		(layer "F.Cu")
		(net "SMB_BIC_FPGA_R1_SDA")
	)
	(segment
		(start 326.232774 -220.853)
		(end 325.9582 -220.578426)
		(width 0.13208)
		(layer "F.Cu")
		(net "SMB_BIC_FPGA_R1_SDA")
	)
	(segment
		(start 332.88224 -221.1832)
		(end 334.49768 -221.1832)
		(width 0.13208)
		(layer "F.Cu")
		(net "SMB_BIC_FPGA_R1_SDA")
	)
	(segment
		(start 328.019664 -220.853)
		(end 326.232774 -220.853)
		(width 0.13208)
		(layer "F.Cu")
		(net "SMB_BIC_FPGA_R1_SDA")
	)
	(segment
		(start 328.33056 -220.542104)
		(end 328.019664 -220.853)
		(width 0.13208)
		(layer "F.Cu")
		(net "SMB_BIC_FPGA_R1_SDA")
	)
	(segment
		(start 330.533756 -221.864936)
		(end 330.106782 -221.864936)
		(width 0.13208)
		(layer "F.Cu")
		(net "SMB_BIC_FPGA_R1_SDA")
	)
	(segment
		(start 334.49768 -221.1832)
		(end 334.89392 -220.78696)
		(width 0.13208)
		(layer "F.Cu")
		(net "SMB_BIC_FPGA_R1_SDA")
	)
	(segment
		(start 332.87589 -221.17685)
		(end 332.88224 -221.1832)
		(width 0.13208)
		(layer "F.Cu")
		(net "SMB_BIC_FPGA_R1_SDA")
	)
	(segment
		(start 325.9582 -220.120718)
		(end 325.70039 -219.862908)
		(width 0.13208)
		(layer "F.Cu")
		(net "SMB_BIC_FPGA_R1_SDA")
	)
	(segment
		(start 262.93699 -219.149422)
		(end 262.93699 -219.181934)
		(width 0.13208)
		(layer "F.Cu")
		(net "SMB_BIC_FPGA_R1_SDA")
	)
	(segment
		(start 328.78395 -220.542104)
		(end 328.33056 -220.542104)
		(width 0.13208)
		(layer "F.Cu")
		(net "SMB_BIC_FPGA_R1_SDA")
	)
	(segment
		(start 332.383638 -221.17685)
		(end 332.87589 -221.17685)
		(width 0.13208)
		(layer "F.Cu")
		(net "SMB_BIC_FPGA_R1_SDA")
	)
	(segment
		(start 325.9582 -220.578426)
		(end 325.9582 -220.120718)
		(width 0.13208)
		(layer "F.Cu")
		(net "SMB_BIC_FPGA_R1_SDA")
	)
	(segment
		(start 330.71816 -221.680532)
		(end 331.879956 -221.680532)
		(width 0.13208)
		(layer "F.Cu")
		(net "SMB_BIC_FPGA_R1_SDA")
	)
	(segment
		(start 262.93699 -219.181934)
		(end 264.251186 -220.49613)
		(width 0.13208)
		(layer "F.Cu")
		(net "SMB_BIC_FPGA_R1_SDA")
	)
	(segment
		(start 331.879956 -221.680532)
		(end 332.383638 -221.17685)
		(width 0.13208)
		(layer "F.Cu")
		(net "SMB_BIC_FPGA_R1_SDA")
	)
	(segment
		(start 330.106782 -221.864936)
		(end 328.78395 -220.542104)
		(width 0.13208)
		(layer "F.Cu")
		(net "SMB_BIC_FPGA_R1_SDA")
	)
	(via
		(at 262.93699 -219.149422)
		(size 0.508)
		(drill 0.254)
		(layers "F.Cu" "B.Cu")
		(net "SMB_BIC_FPGA_R1_SDA")
	)
	(via
		(at 330.533756 -221.864936)
		(size 0.762)
		(drill 0.381)
		(layers "F.Cu" "B.Cu")
		(net "SMB_BIC_FPGA_R1_SDA")
	)
	(via
		(at 325.70039 -219.862908)
		(size 0.508)
		(drill 0.254)
		(layers "F.Cu" "B.Cu")
		(net "SMB_BIC_FPGA_R1_SDA")
	)
	(via
		(at 255.258062 -234.69473)
		(size 0.508)
		(drill 0.254)
		(layers "F.Cu" "B.Cu")
		(net "SMB_BIC_FPGA_R1_SDA")
	)
	(via
		(at 206.303626 -224.430844)
		(size 0.508)
		(drill 0.254)
		(layers "F.Cu" "B.Cu")
		(net "SMB_BIC_FPGA_R1_SDA")
	)
	(via
		(at 332.87589 -221.17685)
		(size 0.508)
		(drill 0.254)
		(layers "F.Cu" "B.Cu")
		(net "SMB_BIC_FPGA_R1_SDA")
	)
	(segment
		(start 208.14157 -224.430844)
		(end 206.303626 -224.430844)
		(width 0.13208)
		(layer "B.Cu")
		(net "SMB_BIC_FPGA_R1_SDA")
	)
	(segment
		(start 210.058762 -223.61906)
		(end 209.642964 -223.61906)
		(width 0.13208)
		(layer "B.Cu")
		(net "SMB_BIC_FPGA_R1_SDA")
	)
	(segment
		(start 209.477356 -223.453452)
		(end 209.118962 -223.453452)
		(width 0.13208)
		(layer "B.Cu")
		(net "SMB_BIC_FPGA_R1_SDA")
	)
	(segment
		(start 209.118962 -223.453452)
		(end 208.14157 -224.430844)
		(width 0.13208)
		(layer "B.Cu")
		(net "SMB_BIC_FPGA_R1_SDA")
	)
	(segment
		(start 209.642964 -223.61906)
		(end 209.477356 -223.453452)
		(width 0.13208)
		(layer "B.Cu")
		(net "SMB_BIC_FPGA_R1_SDA")
	)
	(segment
		(start 227.019104 -233.084878)
		(end 227.510086 -232.593896)
		(width 0.15494)
		(layer "In13.Cu")
		(net "SMB_BIC_FPGA_R1_SDA")
	)
	(segment
		(start 227.548694 -234.644438)
		(end 227.019104 -234.114848)
		(width 0.15494)
		(layer "In13.Cu")
		(net "SMB_BIC_FPGA_R1_SDA")
	)
	(segment
		(start 208.778602 -225.669602)
		(end 207.539844 -224.430844)
		(width 0.15494)
		(layer "In13.Cu")
		(net "SMB_BIC_FPGA_R1_SDA")
	)
	(segment
		(start 224.380044 -229.580186)
		(end 209.587338 -229.580186)
		(width 0.15494)
		(layer "In13.Cu")
		(net "SMB_BIC_FPGA_R1_SDA")
	)
	(segment
		(start 244.089428 -232.71734)
		(end 242.26647 -232.71734)
		(width 0.15494)
		(layer "In13.Cu")
		(net "SMB_BIC_FPGA_R1_SDA")
	)
	(segment
		(start 249.627644 -235.71835)
		(end 248.320814 -234.41152)
		(width 0.15494)
		(layer "In13.Cu")
		(net "SMB_BIC_FPGA_R1_SDA")
	)
	(segment
		(start 207.539844 -224.430844)
		(end 206.303626 -224.430844)
		(width 0.15494)
		(layer "In13.Cu")
		(net "SMB_BIC_FPGA_R1_SDA")
	)
	(segment
		(start 209.587338 -229.580186)
		(end 208.778602 -228.77145)
		(width 0.15494)
		(layer "In13.Cu")
		(net "SMB_BIC_FPGA_R1_SDA")
	)
	(segment
		(start 246.909336 -234.41152)
		(end 244.988334 -233.616246)
		(width 0.15494)
		(layer "In13.Cu")
		(net "SMB_BIC_FPGA_R1_SDA")
	)
	(segment
		(start 252.148594 -235.71835)
		(end 249.627644 -235.71835)
		(width 0.15494)
		(layer "In13.Cu")
		(net "SMB_BIC_FPGA_R1_SDA")
	)
	(segment
		(start 231.245664 -234.644438)
		(end 227.548694 -234.644438)
		(width 0.15494)
		(layer "In13.Cu")
		(net "SMB_BIC_FPGA_R1_SDA")
	)
	(segment
		(start 227.510086 -232.593896)
		(end 227.510086 -230.012494)
		(width 0.15494)
		(layer "In13.Cu")
		(net "SMB_BIC_FPGA_R1_SDA")
	)
	(segment
		(start 208.778602 -228.77145)
		(end 208.778602 -225.669602)
		(width 0.15494)
		(layer "In13.Cu")
		(net "SMB_BIC_FPGA_R1_SDA")
	)
	(segment
		(start 244.988334 -233.616246)
		(end 244.089428 -232.71734)
		(width 0.15494)
		(layer "In13.Cu")
		(net "SMB_BIC_FPGA_R1_SDA")
	)
	(segment
		(start 240.666778 -234.317032)
		(end 231.57307 -234.317032)
		(width 0.15494)
		(layer "In13.Cu")
		(net "SMB_BIC_FPGA_R1_SDA")
	)
	(segment
		(start 227.019104 -234.114848)
		(end 227.019104 -233.084878)
		(width 0.15494)
		(layer "In13.Cu")
		(net "SMB_BIC_FPGA_R1_SDA")
	)
	(segment
		(start 253.16434 -234.702604)
		(end 252.148594 -235.71835)
		(width 0.15494)
		(layer "In13.Cu")
		(net "SMB_BIC_FPGA_R1_SDA")
	)
	(segment
		(start 227.510086 -230.012494)
		(end 226.49053 -228.992938)
		(width 0.15494)
		(layer "In13.Cu")
		(net "SMB_BIC_FPGA_R1_SDA")
	)
	(segment
		(start 248.320814 -234.41152)
		(end 246.909336 -234.41152)
		(width 0.15494)
		(layer "In13.Cu")
		(net "SMB_BIC_FPGA_R1_SDA")
	)
	(segment
		(start 242.26647 -232.71734)
		(end 240.666778 -234.317032)
		(width 0.15494)
		(layer "In13.Cu")
		(net "SMB_BIC_FPGA_R1_SDA")
	)
	(segment
		(start 255.250188 -234.702604)
		(end 253.16434 -234.702604)
		(width 0.15494)
		(layer "In13.Cu")
		(net "SMB_BIC_FPGA_R1_SDA")
	)
	(segment
		(start 255.258062 -234.69473)
		(end 255.250188 -234.702604)
		(width 0.15494)
		(layer "In13.Cu")
		(net "SMB_BIC_FPGA_R1_SDA")
	)
	(segment
		(start 224.967292 -228.992938)
		(end 224.380044 -229.580186)
		(width 0.15494)
		(layer "In13.Cu")
		(net "SMB_BIC_FPGA_R1_SDA")
	)
	(segment
		(start 226.49053 -228.992938)
		(end 224.967292 -228.992938)
		(width 0.15494)
		(layer "In13.Cu")
		(net "SMB_BIC_FPGA_R1_SDA")
	)
	(segment
		(start 231.57307 -234.317032)
		(end 231.245664 -234.644438)
		(width 0.15494)
		(layer "In13.Cu")
		(net "SMB_BIC_FPGA_R1_SDA")
	)
	(segment
		(start 321.073272 -218.028774)
		(end 323.889624 -218.028774)
		(width 0.15494)
		(layer "In15.Cu")
		(net "SMB_BIC_FPGA_R1_SDA")
	)
	(segment
		(start 325.70039 -219.404438)
		(end 325.70039 -219.862908)
		(width 0.15494)
		(layer "In15.Cu")
		(net "SMB_BIC_FPGA_R1_SDA")
	)
	(segment
		(start 262.93699 -219.197936)
		(end 263.37133 -219.632276)
		(width 0.15494)
		(layer "In15.Cu")
		(net "SMB_BIC_FPGA_R1_SDA")
	)
	(segment
		(start 262.93699 -219.149422)
		(end 262.93699 -219.197936)
		(width 0.15494)
		(layer "In15.Cu")
		(net "SMB_BIC_FPGA_R1_SDA")
	)
	(segment
		(start 264.36447 -219.632276)
		(end 264.679684 -219.94749)
		(width 0.15494)
		(layer "In15.Cu")
		(net "SMB_BIC_FPGA_R1_SDA")
	)
	(segment
		(start 324.77329 -218.91244)
		(end 325.208392 -218.91244)
		(width 0.15494)
		(layer "In15.Cu")
		(net "SMB_BIC_FPGA_R1_SDA")
	)
	(segment
		(start 264.679684 -219.94749)
		(end 288.739072 -219.94749)
		(width 0.15494)
		(layer "In15.Cu")
		(net "SMB_BIC_FPGA_R1_SDA")
	)
	(segment
		(start 323.889624 -218.028774)
		(end 324.77329 -218.91244)
		(width 0.15494)
		(layer "In15.Cu")
		(net "SMB_BIC_FPGA_R1_SDA")
	)
	(segment
		(start 304.987706 -219.383864)
		(end 306.414424 -217.957146)
		(width 0.15494)
		(layer "In15.Cu")
		(net "SMB_BIC_FPGA_R1_SDA")
	)
	(segment
		(start 263.37133 -219.632276)
		(end 264.36447 -219.632276)
		(width 0.15494)
		(layer "In15.Cu")
		(net "SMB_BIC_FPGA_R1_SDA")
	)
	(segment
		(start 321.001644 -217.957146)
		(end 321.073272 -218.028774)
		(width 0.15494)
		(layer "In15.Cu")
		(net "SMB_BIC_FPGA_R1_SDA")
	)
	(segment
		(start 289.302698 -219.383864)
		(end 304.987706 -219.383864)
		(width 0.15494)
		(layer "In15.Cu")
		(net "SMB_BIC_FPGA_R1_SDA")
	)
	(segment
		(start 306.414424 -217.957146)
		(end 321.001644 -217.957146)
		(width 0.15494)
		(layer "In15.Cu")
		(net "SMB_BIC_FPGA_R1_SDA")
	)
	(segment
		(start 325.208392 -218.91244)
		(end 325.70039 -219.404438)
		(width 0.15494)
		(layer "In15.Cu")
		(net "SMB_BIC_FPGA_R1_SDA")
	)
	(segment
		(start 288.739072 -219.94749)
		(end 289.302698 -219.383864)
		(width 0.15494)
		(layer "In15.Cu")
		(net "SMB_BIC_FPGA_R1_SDA")
	)
	(segment
		(start 407.293064 -392.016742)
		(end 406.037796 -392.016742)
		(width 0.13208)
		(layer "F.Cu")
		(net "PRSNT_GPU_A1_R_N")
	)
	(via
		(at 406.037796 -392.016742)
		(size 0.508)
		(drill 0.254)
		(layers "F.Cu" "B.Cu")
		(net "PRSNT_GPU_A1_R_N")
	)
	(segment
		(start 399.451068 -409.122626)
		(end 395.698218 -412.875476)
		(width 0.15494)
		(layer "In9.Cu")
		(net "PRSNT_GPU_A1_R_N")
	)
	(segment
		(start 399.451068 -394.770102)
		(end 399.451068 -409.122626)
		(width 0.15494)
		(layer "In9.Cu")
		(net "PRSNT_GPU_A1_R_N")
	)
	(segment
		(start 405.884888 -391.863834)
		(end 402.357336 -391.863834)
		(width 0.15494)
		(layer "In9.Cu")
		(net "PRSNT_GPU_A1_R_N")
	)
	(segment
		(start 389.475218 -412.875476)
		(end 388.68985 -412.090108)
		(width 0.15494)
		(layer "In9.Cu")
		(net "PRSNT_GPU_A1_R_N")
	)
	(segment
		(start 402.357336 -391.863834)
		(end 399.451068 -394.770102)
		(width 0.15494)
		(layer "In9.Cu")
		(net "PRSNT_GPU_A1_R_N")
	)
	(segment
		(start 395.698218 -412.875476)
		(end 389.475218 -412.875476)
		(width 0.15494)
		(layer "In9.Cu")
		(net "PRSNT_GPU_A1_R_N")
	)
	(segment
		(start 406.037796 -392.016742)
		(end 405.884888 -391.863834)
		(width 0.15494)
		(layer "In9.Cu")
		(net "PRSNT_GPU_A1_R_N")
	)
	(segment
		(start 415.232596 -392.7094)
		(end 416.707574 -394.184378)
		(width 0.13208)
		(layer "F.Cu")
		(net "PRSNT_GPU_A1_N")
	)
	(segment
		(start 408.785822 -392.7094)
		(end 415.232596 -392.7094)
		(width 0.13208)
		(layer "F.Cu")
		(net "PRSNT_GPU_A1_N")
	)
	(segment
		(start 408.093164 -392.016742)
		(end 408.785822 -392.7094)
		(width 0.13208)
		(layer "F.Cu")
		(net "PRSNT_GPU_A1_N")
	)
	(via
		(at 416.707574 -394.184378)
		(size 0.508)
		(drill 0.254)
		(layers "F.Cu" "B.Cu")
		(net "PRSNT_GPU_A1_N")
	)
	(segment
		(start 432.689762 -412.090108)
		(end 432.127152 -412.652718)
		(width 0.15494)
		(layer "In9.Cu")
		(net "PRSNT_GPU_A1_N")
	)
	(segment
		(start 418.225986 -395.70279)
		(end 416.707574 -394.184378)
		(width 0.15494)
		(layer "In9.Cu")
		(net "PRSNT_GPU_A1_N")
	)
	(segment
		(start 432.127152 -412.652718)
		(end 419.256464 -412.652718)
		(width 0.15494)
		(layer "In9.Cu")
		(net "PRSNT_GPU_A1_N")
	)
	(segment
		(start 419.256464 -412.652718)
		(end 418.225986 -411.62224)
		(width 0.15494)
		(layer "In9.Cu")
		(net "PRSNT_GPU_A1_N")
	)
	(segment
		(start 418.225986 -411.62224)
		(end 418.225986 -395.70279)
		(width 0.15494)
		(layer "In9.Cu")
		(net "PRSNT_GPU_A1_N")
	)
	(segment
		(start 320.10223 -389.98779)
		(end 320.76136 -389.98779)
		(width 0.13208)
		(layer "F.Cu")
		(net "PRSNT_GPU_A2_R_N")
	)
	(segment
		(start 320.76136 -389.98779)
		(end 320.774314 -389.974836)
		(width 0.13208)
		(layer "F.Cu")
		(net "PRSNT_GPU_A2_R_N")
	)
	(via
		(at 320.774314 -389.974836)
		(size 0.508)
		(drill 0.254)
		(layers "F.Cu" "B.Cu")
		(net "PRSNT_GPU_A2_R_N")
	)
	(segment
		(start 329.176888 -410.761434)
		(end 331.210412 -412.794958)
		(width 0.15494)
		(layer "In9.Cu")
		(net "PRSNT_GPU_A2_R_N")
	)
	(segment
		(start 320.774314 -390.64692)
		(end 321.805046 -391.677652)
		(width 0.15494)
		(layer "In9.Cu")
		(net "PRSNT_GPU_A2_R_N")
	)
	(segment
		(start 320.774314 -389.974836)
		(end 320.774314 -390.64692)
		(width 0.15494)
		(layer "In9.Cu")
		(net "PRSNT_GPU_A2_R_N")
	)
	(segment
		(start 331.210412 -412.794958)
		(end 335.185258 -412.794958)
		(width 0.15494)
		(layer "In9.Cu")
		(net "PRSNT_GPU_A2_R_N")
	)
	(segment
		(start 335.185258 -412.794958)
		(end 335.890108 -412.090108)
		(width 0.15494)
		(layer "In9.Cu")
		(net "PRSNT_GPU_A2_R_N")
	)
	(segment
		(start 326.833738 -391.677652)
		(end 329.176888 -394.020802)
		(width 0.15494)
		(layer "In9.Cu")
		(net "PRSNT_GPU_A2_R_N")
	)
	(segment
		(start 329.176888 -394.020802)
		(end 329.176888 -410.761434)
		(width 0.15494)
		(layer "In9.Cu")
		(net "PRSNT_GPU_A2_R_N")
	)
	(segment
		(start 321.805046 -391.677652)
		(end 326.833738 -391.677652)
		(width 0.15494)
		(layer "In9.Cu")
		(net "PRSNT_GPU_A2_R_N")
	)
	(segment
		(start 317.62319 -389.98779)
		(end 317.610236 -389.974836)
		(width 0.13208)
		(layer "F.Cu")
		(net "PRSNT_GPU_A2_N")
	)
	(segment
		(start 319.30213 -389.98779)
		(end 317.62319 -389.98779)
		(width 0.13208)
		(layer "F.Cu")
		(net "PRSNT_GPU_A2_N")
	)
	(via
		(at 317.610236 -389.974836)
		(size 0.508)
		(drill 0.254)
		(layers "F.Cu" "B.Cu")
		(net "PRSNT_GPU_A2_N")
	)
	(segment
		(start 315.31814 -390.548114)
		(end 316.27191 -390.548114)
		(width 0.15494)
		(layer "In9.Cu")
		(net "PRSNT_GPU_A2_N")
	)
	(segment
		(start 311.78881 -409.97378)
		(end 311.78881 -394.077444)
		(width 0.15494)
		(layer "In9.Cu")
		(net "PRSNT_GPU_A2_N")
	)
	(segment
		(start 291.889942 -412.090108)
		(end 293.549832 -413.749998)
		(width 0.15494)
		(layer "In9.Cu")
		(net "PRSNT_GPU_A2_N")
	)
	(segment
		(start 311.78881 -394.077444)
		(end 315.31814 -390.548114)
		(width 0.15494)
		(layer "In9.Cu")
		(net "PRSNT_GPU_A2_N")
	)
	(segment
		(start 308.012592 -413.749998)
		(end 311.78881 -409.97378)
		(width 0.15494)
		(layer "In9.Cu")
		(net "PRSNT_GPU_A2_N")
	)
	(segment
		(start 316.27191 -390.548114)
		(end 316.845188 -389.974836)
		(width 0.15494)
		(layer "In9.Cu")
		(net "PRSNT_GPU_A2_N")
	)
	(segment
		(start 293.549832 -413.749998)
		(end 308.012592 -413.749998)
		(width 0.15494)
		(layer "In9.Cu")
		(net "PRSNT_GPU_A2_N")
	)
	(segment
		(start 316.845188 -389.974836)
		(end 317.610236 -389.974836)
		(width 0.15494)
		(layer "In9.Cu")
		(net "PRSNT_GPU_A2_N")
	)
	(segment
		(start 150.335488 -385.590034)
		(end 150.115016 -385.369562)
		(width 0.13208)
		(layer "F.Cu")
		(net "PRSNT_GPU_A3_R_N")
	)
	(segment
		(start 150.115016 -384.41249)
		(end 150.941024 -383.586482)
		(width 0.13208)
		(layer "F.Cu")
		(net "PRSNT_GPU_A3_R_N")
	)
	(segment
		(start 150.941024 -383.586482)
		(end 150.941024 -382.471676)
		(width 0.13208)
		(layer "F.Cu")
		(net "PRSNT_GPU_A3_R_N")
	)
	(segment
		(start 150.115016 -385.369562)
		(end 150.115016 -384.41249)
		(width 0.13208)
		(layer "F.Cu")
		(net "PRSNT_GPU_A3_R_N")
	)
	(via
		(at 150.335488 -385.590034)
		(size 0.508)
		(drill 0.254)
		(layers "F.Cu" "B.Cu")
		(net "PRSNT_GPU_A3_R_N")
	)
	(via
		(at 198.161148 -358.863392)
		(size 0.508)
		(drill 0.254)
		(layers "F.Cu" "B.Cu")
		(net "PRSNT_GPU_A3_R_N")
	)
	(via
		(at 350.483932 -360.858054)
		(size 0.508)
		(drill 0.254)
		(layers "F.Cu" "B.Cu")
		(net "PRSNT_GPU_A3_R_N")
	)
	(segment
		(start 351.290128 -361.66425)
		(end 351.290128 -368.990118)
		(width 0.13208)
		(layer "B.Cu")
		(net "PRSNT_GPU_A3_R_N")
	)
	(segment
		(start 260.513576 -344.415364)
		(end 265.557508 -349.459296)
		(width 0.13208)
		(layer "B.Cu")
		(net "PRSNT_GPU_A3_R_N")
	)
	(segment
		(start 252.782578 -344.415364)
		(end 260.513576 -344.415364)
		(width 0.13208)
		(layer "B.Cu")
		(net "PRSNT_GPU_A3_R_N")
	)
	(segment
		(start 222.128334 -341.710518)
		(end 223.714818 -343.297002)
		(width 0.13208)
		(layer "B.Cu")
		(net "PRSNT_GPU_A3_R_N")
	)
	(segment
		(start 349.744284 -360.118406)
		(end 350.483932 -360.858054)
		(width 0.13208)
		(layer "B.Cu")
		(net "PRSNT_GPU_A3_R_N")
	)
	(segment
		(start 265.557508 -355.291136)
		(end 270.384778 -360.118406)
		(width 0.13208)
		(layer "B.Cu")
		(net "PRSNT_GPU_A3_R_N")
	)
	(segment
		(start 350.483932 -360.858054)
		(end 351.290128 -361.66425)
		(width 0.13208)
		(layer "B.Cu")
		(net "PRSNT_GPU_A3_R_N")
	)
	(segment
		(start 198.161148 -358.863392)
		(end 198.161148 -358.4956)
		(width 0.13208)
		(layer "B.Cu")
		(net "PRSNT_GPU_A3_R_N")
	)
	(segment
		(start 270.384778 -360.118406)
		(end 349.744284 -360.118406)
		(width 0.13208)
		(layer "B.Cu")
		(net "PRSNT_GPU_A3_R_N")
	)
	(segment
		(start 265.557508 -349.459296)
		(end 265.557508 -355.291136)
		(width 0.13208)
		(layer "B.Cu")
		(net "PRSNT_GPU_A3_R_N")
	)
	(segment
		(start 223.714818 -343.297002)
		(end 251.664216 -343.297002)
		(width 0.13208)
		(layer "B.Cu")
		(net "PRSNT_GPU_A3_R_N")
	)
	(segment
		(start 198.161148 -358.4956)
		(end 200.928986 -355.727762)
		(width 0.13208)
		(layer "B.Cu")
		(net "PRSNT_GPU_A3_R_N")
	)
	(segment
		(start 200.928986 -355.727762)
		(end 200.928986 -349.527622)
		(width 0.13208)
		(layer "B.Cu")
		(net "PRSNT_GPU_A3_R_N")
	)
	(segment
		(start 251.664216 -343.297002)
		(end 252.782578 -344.415364)
		(width 0.13208)
		(layer "B.Cu")
		(net "PRSNT_GPU_A3_R_N")
	)
	(segment
		(start 200.928986 -349.527622)
		(end 208.74609 -341.710518)
		(width 0.13208)
		(layer "B.Cu")
		(net "PRSNT_GPU_A3_R_N")
	)
	(segment
		(start 208.74609 -341.710518)
		(end 222.128334 -341.710518)
		(width 0.13208)
		(layer "B.Cu")
		(net "PRSNT_GPU_A3_R_N")
	)
	(segment
		(start 149.245574 -386.90042)
		(end 146.992594 -386.90042)
		(width 0.15494)
		(layer "In15.Cu")
		(net "PRSNT_GPU_A3_R_N")
	)
	(segment
		(start 197.517258 -358.863392)
		(end 198.161148 -358.863392)
		(width 0.15494)
		(layer "In15.Cu")
		(net "PRSNT_GPU_A3_R_N")
	)
	(segment
		(start 150.350474 -385.79552)
		(end 149.245574 -386.90042)
		(width 0.15494)
		(layer "In15.Cu")
		(net "PRSNT_GPU_A3_R_N")
	)
	(segment
		(start 146.992594 -386.90042)
		(end 146.293586 -387.599428)
		(width 0.15494)
		(layer "In15.Cu")
		(net "PRSNT_GPU_A3_R_N")
	)
	(segment
		(start 145.537428 -387.599428)
		(end 143.1544 -385.2164)
		(width 0.15494)
		(layer "In15.Cu")
		(net "PRSNT_GPU_A3_R_N")
	)
	(segment
		(start 150.335488 -385.590034)
		(end 150.350474 -385.60502)
		(width 0.15494)
		(layer "In15.Cu")
		(net "PRSNT_GPU_A3_R_N")
	)
	(segment
		(start 189.818518 -359.728008)
		(end 196.652642 -359.728008)
		(width 0.15494)
		(layer "In15.Cu")
		(net "PRSNT_GPU_A3_R_N")
	)
	(segment
		(start 146.293586 -387.599428)
		(end 145.537428 -387.599428)
		(width 0.15494)
		(layer "In15.Cu")
		(net "PRSNT_GPU_A3_R_N")
	)
	(segment
		(start 155.896564 -363.83849)
		(end 185.708036 -363.83849)
		(width 0.15494)
		(layer "In15.Cu")
		(net "PRSNT_GPU_A3_R_N")
	)
	(segment
		(start 196.652642 -359.728008)
		(end 197.517258 -358.863392)
		(width 0.15494)
		(layer "In15.Cu")
		(net "PRSNT_GPU_A3_R_N")
	)
	(segment
		(start 143.1544 -376.580654)
		(end 155.896564 -363.83849)
		(width 0.15494)
		(layer "In15.Cu")
		(net "PRSNT_GPU_A3_R_N")
	)
	(segment
		(start 150.350474 -385.60502)
		(end 150.350474 -385.79552)
		(width 0.15494)
		(layer "In15.Cu")
		(net "PRSNT_GPU_A3_R_N")
	)
	(segment
		(start 185.708036 -363.83849)
		(end 189.818518 -359.728008)
		(width 0.15494)
		(layer "In15.Cu")
		(net "PRSNT_GPU_A3_R_N")
	)
	(segment
		(start 143.1544 -385.2164)
		(end 143.1544 -376.580654)
		(width 0.15494)
		(layer "In15.Cu")
		(net "PRSNT_GPU_A3_R_N")
	)
	(segment
		(start 150.140924 -382.471676)
		(end 150.140924 -383.270252)
		(width 0.13208)
		(layer "F.Cu")
		(net "PRSNT_GPU_A3_N")
	)
	(segment
		(start 150.140924 -383.270252)
		(end 150.236174 -383.365502)
		(width 0.13208)
		(layer "F.Cu")
		(net "PRSNT_GPU_A3_N")
	)
	(via
		(at 150.236174 -383.365502)
		(size 0.508)
		(drill 0.254)
		(layers "F.Cu" "B.Cu")
		(net "PRSNT_GPU_A3_N")
	)
	(segment
		(start 156.937202 -366.681766)
		(end 173.001686 -366.681766)
		(width 0.15494)
		(layer "In15.Cu")
		(net "PRSNT_GPU_A3_N")
	)
	(segment
		(start 173.001686 -366.681766)
		(end 175.310038 -368.990118)
		(width 0.15494)
		(layer "In15.Cu")
		(net "PRSNT_GPU_A3_N")
	)
	(segment
		(start 147.294092 -379.729492)
		(end 147.294092 -376.324876)
		(width 0.15494)
		(layer "In15.Cu")
		(net "PRSNT_GPU_A3_N")
	)
	(segment
		(start 150.236174 -382.671574)
		(end 147.294092 -379.729492)
		(width 0.15494)
		(layer "In15.Cu")
		(net "PRSNT_GPU_A3_N")
	)
	(segment
		(start 150.236174 -383.365502)
		(end 150.236174 -382.671574)
		(width 0.15494)
		(layer "In15.Cu")
		(net "PRSNT_GPU_A3_N")
	)
	(segment
		(start 147.294092 -376.324876)
		(end 156.937202 -366.681766)
		(width 0.15494)
		(layer "In15.Cu")
		(net "PRSNT_GPU_A3_N")
	)
	(segment
		(start 365.788448 -395.863064)
		(end 364.945168 -395.863064)
		(width 0.13208)
		(layer "F.Cu")
		(net "PRSNT_SWB_B1_N")
	)
	(segment
		(start 366.717326 -396.791942)
		(end 365.788448 -395.863064)
		(width 0.13208)
		(layer "F.Cu")
		(net "PRSNT_SWB_B1_N")
	)
	(via
		(at 366.717326 -396.791942)
		(size 0.508)
		(drill 0.254)
		(layers "F.Cu" "B.Cu")
		(net "PRSNT_SWB_B1_N")
	)
	(segment
		(start 366.717326 -396.791942)
		(end 370.635022 -396.791942)
		(width 0.13208)
		(layer "B.Cu")
		(net "PRSNT_SWB_B1_N")
	)
	(segment
		(start 373.458486 -399.615406)
		(end 373.458486 -410.058616)
		(width 0.13208)
		(layer "B.Cu")
		(net "PRSNT_SWB_B1_N")
	)
	(segment
		(start 373.458486 -410.058616)
		(end 375.489978 -412.090108)
		(width 0.13208)
		(layer "B.Cu")
		(net "PRSNT_SWB_B1_N")
	)
	(segment
		(start 370.635022 -396.791942)
		(end 373.458486 -399.615406)
		(width 0.13208)
		(layer "B.Cu")
		(net "PRSNT_SWB_B1_N")
	)
	(segment
		(start 318.491616 -385.98983)
		(end 318.53886 -385.942586)
		(width 0.13208)
		(layer "F.Cu")
		(net "PRSNT_SWB_B2_N")
	)
	(segment
		(start 318.53886 -385.942586)
		(end 319.292732 -385.942586)
		(width 0.13208)
		(layer "F.Cu")
		(net "PRSNT_SWB_B2_N")
	)
	(via
		(at 318.491616 -385.98983)
		(size 0.508)
		(drill 0.254)
		(layers "F.Cu" "B.Cu")
		(net "PRSNT_SWB_B2_N")
	)
	(segment
		(start 328.17181 -367.351818)
		(end 332.05166 -367.351818)
		(width 0.13208)
		(layer "B.Cu")
		(net "PRSNT_SWB_B2_N")
	)
	(segment
		(start 332.05166 -367.351818)
		(end 333.68996 -368.990118)
		(width 0.13208)
		(layer "B.Cu")
		(net "PRSNT_SWB_B2_N")
	)
	(segment
		(start 318.491616 -377.032012)
		(end 328.17181 -367.351818)
		(width 0.13208)
		(layer "B.Cu")
		(net "PRSNT_SWB_B2_N")
	)
	(segment
		(start 318.491616 -385.98983)
		(end 318.491616 -377.032012)
		(width 0.13208)
		(layer "B.Cu")
		(net "PRSNT_SWB_B2_N")
	)
	(segment
		(start 147.673314 -382.453896)
		(end 146.803872 -382.453896)
		(width 0.13208)
		(layer "F.Cu")
		(net "PRSNT_SWB_B3_N")
	)
	(segment
		(start 146.803872 -382.453896)
		(end 146.794474 -382.444498)
		(width 0.13208)
		(layer "F.Cu")
		(net "PRSNT_SWB_B3_N")
	)
	(via
		(at 146.794474 -382.444498)
		(size 0.508)
		(drill 0.254)
		(layers "F.Cu" "B.Cu")
		(net "PRSNT_SWB_B3_N")
	)
	(segment
		(start 145.88109 -378.125736)
		(end 135.989822 -368.234468)
		(width 0.15494)
		(layer "In9.Cu")
		(net "PRSNT_SWB_B3_N")
	)
	(segment
		(start 145.88109 -381.010668)
		(end 145.88109 -378.125736)
		(width 0.15494)
		(layer "In9.Cu")
		(net "PRSNT_SWB_B3_N")
	)
	(segment
		(start 135.989822 -368.234468)
		(end 132.065776 -368.234468)
		(width 0.15494)
		(layer "In9.Cu")
		(net "PRSNT_SWB_B3_N")
	)
	(segment
		(start 132.065776 -368.234468)
		(end 131.310126 -368.990118)
		(width 0.15494)
		(layer "In9.Cu")
		(net "PRSNT_SWB_B3_N")
	)
	(segment
		(start 146.794474 -382.444498)
		(end 146.794474 -381.924052)
		(width 0.15494)
		(layer "In9.Cu")
		(net "PRSNT_SWB_B3_N")
	)
	(segment
		(start 146.794474 -381.924052)
		(end 145.88109 -381.010668)
		(width 0.15494)
		(layer "In9.Cu")
		(net "PRSNT_SWB_B3_N")
	)
	(segment
		(start 366.526318 -284.688534)
		(end 366.566196 -284.688534)
		(width 0.2286)
		(layer "F.Cu")
		(net "P0V8_PEX3_PVCC")
	)
	(segment
		(start 358.454198 -284.64002)
		(end 358.405684 -284.688534)
		(width 0.254)
		(layer "F.Cu")
		(net "P0V8_PEX3_PVCC")
	)
	(segment
		(start 366.61471 -284.64002)
		(end 366.566196 -284.688534)
		(width 0.254)
		(layer "F.Cu")
		(net "P0V8_PEX3_PVCC")
	)
	(segment
		(start 357.230934 -283.974032)
		(end 357.651304 -283.974032)
		(width 0.2286)
		(layer "F.Cu")
		(net "P0V8_PEX3_PVCC")
	)
	(segment
		(start 357.651304 -283.974032)
		(end 358.365806 -284.688534)
		(width 0.2286)
		(layer "F.Cu")
		(net "P0V8_PEX3_PVCC")
	)
	(segment
		(start 358.454198 -284.072584)
		(end 358.454198 -284.64002)
		(width 0.254)
		(layer "F.Cu")
		(net "P0V8_PEX3_PVCC")
	)
	(segment
		(start 366.61471 -284.072584)
		(end 366.61471 -284.64002)
		(width 0.254)
		(layer "F.Cu")
		(net "P0V8_PEX3_PVCC")
	)
	(segment
		(start 365.811816 -283.974032)
		(end 366.526318 -284.688534)
		(width 0.2286)
		(layer "F.Cu")
		(net "P0V8_PEX3_PVCC")
	)
	(segment
		(start 358.365806 -284.688534)
		(end 358.405684 -284.688534)
		(width 0.2286)
		(layer "F.Cu")
		(net "P0V8_PEX3_PVCC")
	)
	(segment
		(start 365.391446 -283.974032)
		(end 365.811816 -283.974032)
		(width 0.2286)
		(layer "F.Cu")
		(net "P0V8_PEX3_PVCC")
	)
	(via
		(at 358.454198 -284.072584)
		(size 0.508)
		(drill 0.254)
		(layers "F.Cu" "B.Cu")
		(net "P0V8_PEX3_PVCC")
	)
	(via
		(at 366.61471 -284.072584)
		(size 0.508)
		(drill 0.254)
		(layers "F.Cu" "B.Cu")
		(net "P0V8_PEX3_PVCC")
	)
	(segment
		(start 358.604566 -285.207456)
		(end 358.604566 -284.222952)
		(width 0.254)
		(layer "B.Cu")
		(net "P0V8_PEX3_PVCC")
	)
	(segment
		(start 358.308148 -284.218634)
		(end 358.454198 -284.072584)
		(width 0.254)
		(layer "B.Cu")
		(net "P0V8_PEX3_PVCC")
	)
	(segment
		(start 365.931196 -284.218634)
		(end 366.46866 -284.218634)
		(width 0.254)
		(layer "B.Cu")
		(net "P0V8_PEX3_PVCC")
	)
	(segment
		(start 366.46866 -284.218634)
		(end 366.61471 -284.072584)
		(width 0.254)
		(layer "B.Cu")
		(net "P0V8_PEX3_PVCC")
	)
	(segment
		(start 357.620316 -285.213298)
		(end 358.598724 -285.213298)
		(width 0.254)
		(layer "B.Cu")
		(net "P0V8_PEX3_PVCC")
	)
	(segment
		(start 357.770684 -284.218634)
		(end 358.308148 -284.218634)
		(width 0.254)
		(layer "B.Cu")
		(net "P0V8_PEX3_PVCC")
	)
	(segment
		(start 358.604566 -284.222952)
		(end 358.454198 -284.072584)
		(width 0.254)
		(layer "B.Cu")
		(net "P0V8_PEX3_PVCC")
	)
	(segment
		(start 358.598724 -285.213298)
		(end 358.604566 -285.207456)
		(width 0.254)
		(layer "B.Cu")
		(net "P0V8_PEX3_PVCC")
	)
	(segment
		(start 366.61471 -284.072584)
		(end 365.116618 -284.072584)
		(width 0.254)
		(layer "In5.Cu")
		(net "P0V8_PEX3_PVCC")
	)
	(segment
		(start 359.095802 -284.714188)
		(end 358.454198 -284.072584)
		(width 0.254)
		(layer "In5.Cu")
		(net "P0V8_PEX3_PVCC")
	)
	(segment
		(start 365.116618 -284.072584)
		(end 364.643416 -283.599382)
		(width 0.254)
		(layer "In5.Cu")
		(net "P0V8_PEX3_PVCC")
	)
	(segment
		(start 364.643416 -283.599382)
		(end 362.5977 -283.599382)
		(width 0.254)
		(layer "In5.Cu")
		(net "P0V8_PEX3_PVCC")
	)
	(segment
		(start 361.482894 -284.714188)
		(end 359.095802 -284.714188)
		(width 0.254)
		(layer "In5.Cu")
		(net "P0V8_PEX3_PVCC")
	)
	(segment
		(start 362.5977 -283.599382)
		(end 361.482894 -284.714188)
		(width 0.254)
		(layer "In5.Cu")
		(net "P0V8_PEX3_PVCC")
	)
	(segment
		(start 341.706708 -284.688534)
		(end 341.746586 -284.688534)
		(width 0.2286)
		(layer "F.Cu")
		(net "P0V8_PEX2_PVCC")
	)
	(segment
		(start 341.7951 -284.072584)
		(end 341.7951 -284.64002)
		(width 0.254)
		(layer "F.Cu")
		(net "P0V8_PEX2_PVCC")
	)
	(segment
		(start 341.7951 -284.64002)
		(end 341.746586 -284.688534)
		(width 0.254)
		(layer "F.Cu")
		(net "P0V8_PEX2_PVCC")
	)
	(segment
		(start 349.156274 -283.974032)
		(end 349.870776 -284.688534)
		(width 0.2286)
		(layer "F.Cu")
		(net "P0V8_PEX2_PVCC")
	)
	(segment
		(start 340.992206 -283.974032)
		(end 341.706708 -284.688534)
		(width 0.2286)
		(layer "F.Cu")
		(net "P0V8_PEX2_PVCC")
	)
	(segment
		(start 340.571836 -283.974032)
		(end 340.992206 -283.974032)
		(width 0.2286)
		(layer "F.Cu")
		(net "P0V8_PEX2_PVCC")
	)
	(segment
		(start 349.955612 -284.64002)
		(end 349.907098 -284.688534)
		(width 0.254)
		(layer "F.Cu")
		(net "P0V8_PEX2_PVCC")
	)
	(segment
		(start 349.870776 -284.688534)
		(end 349.907098 -284.688534)
		(width 0.2286)
		(layer "F.Cu")
		(net "P0V8_PEX2_PVCC")
	)
	(segment
		(start 348.732348 -283.974032)
		(end 349.156274 -283.974032)
		(width 0.2286)
		(layer "F.Cu")
		(net "P0V8_PEX2_PVCC")
	)
	(segment
		(start 349.955612 -284.072584)
		(end 349.955612 -284.64002)
		(width 0.254)
		(layer "F.Cu")
		(net "P0V8_PEX2_PVCC")
	)
	(via
		(at 349.955612 -284.072584)
		(size 0.508)
		(drill 0.254)
		(layers "F.Cu" "B.Cu")
		(net "P0V8_PEX2_PVCC")
	)
	(via
		(at 341.7951 -284.072584)
		(size 0.508)
		(drill 0.254)
		(layers "F.Cu" "B.Cu")
		(net "P0V8_PEX2_PVCC")
	)
	(segment
		(start 349.602806 -284.218634)
		(end 349.272098 -284.218634)
		(width 0.254)
		(layer "B.Cu")
		(net "P0V8_PEX2_PVCC")
	)
	(segment
		(start 340.923372 -285.169102)
		(end 340.93277 -285.159704)
		(width 0.254)
		(layer "B.Cu")
		(net "P0V8_PEX2_PVCC")
	)
	(segment
		(start 341.111586 -284.218634)
		(end 341.257636 -284.072584)
		(width 0.254)
		(layer "B.Cu")
		(net "P0V8_PEX2_PVCC")
	)
	(segment
		(start 349.955612 -284.072584)
		(end 349.602806 -284.218634)
		(width 0.254)
		(layer "B.Cu")
		(net "P0V8_PEX2_PVCC")
	)
	(segment
		(start 341.905082 -284.182566)
		(end 341.7951 -284.072584)
		(width 0.254)
		(layer "B.Cu")
		(net "P0V8_PEX2_PVCC")
	)
	(segment
		(start 340.93277 -285.159704)
		(end 341.905082 -285.159704)
		(width 0.254)
		(layer "B.Cu")
		(net "P0V8_PEX2_PVCC")
	)
	(segment
		(start 341.905082 -285.159704)
		(end 341.905082 -284.182566)
		(width 0.254)
		(layer "B.Cu")
		(net "P0V8_PEX2_PVCC")
	)
	(segment
		(start 341.257636 -284.072584)
		(end 341.7951 -284.072584)
		(width 0.254)
		(layer "B.Cu")
		(net "P0V8_PEX2_PVCC")
	)
	(segment
		(start 348.26956 -283.724604)
		(end 348.61754 -284.072584)
		(width 0.254)
		(layer "In5.Cu")
		(net "P0V8_PEX2_PVCC")
	)
	(segment
		(start 344.937334 -284.719522)
		(end 345.932252 -283.724604)
		(width 0.254)
		(layer "In5.Cu")
		(net "P0V8_PEX2_PVCC")
	)
	(segment
		(start 342.442038 -284.719522)
		(end 344.937334 -284.719522)
		(width 0.254)
		(layer "In5.Cu")
		(net "P0V8_PEX2_PVCC")
	)
	(segment
		(start 345.932252 -283.724604)
		(end 348.26956 -283.724604)
		(width 0.254)
		(layer "In5.Cu")
		(net "P0V8_PEX2_PVCC")
	)
	(segment
		(start 341.7951 -284.072584)
		(end 342.442038 -284.719522)
		(width 0.254)
		(layer "In5.Cu")
		(net "P0V8_PEX2_PVCC")
	)
	(segment
		(start 348.61754 -284.072584)
		(end 349.955612 -284.072584)
		(width 0.254)
		(layer "In5.Cu")
		(net "P0V8_PEX2_PVCC")
	)
	(segment
		(start 134.326122 -284.688534)
		(end 134.366 -284.688534)
		(width 0.2286)
		(layer "F.Cu")
		(net "P0V8_PEX1_PVCC")
	)
	(segment
		(start 125.030738 -283.974032)
		(end 125.451108 -283.974032)
		(width 0.2286)
		(layer "F.Cu")
		(net "P0V8_PEX1_PVCC")
	)
	(segment
		(start 126.16561 -284.688534)
		(end 126.205488 -284.688534)
		(width 0.2286)
		(layer "F.Cu")
		(net "P0V8_PEX1_PVCC")
	)
	(segment
		(start 133.61162 -283.974032)
		(end 134.326122 -284.688534)
		(width 0.2286)
		(layer "F.Cu")
		(net "P0V8_PEX1_PVCC")
	)
	(segment
		(start 126.254002 -284.072584)
		(end 126.254002 -284.64002)
		(width 0.254)
		(layer "F.Cu")
		(net "P0V8_PEX1_PVCC")
	)
	(segment
		(start 133.19125 -283.974032)
		(end 133.61162 -283.974032)
		(width 0.2286)
		(layer "F.Cu")
		(net "P0V8_PEX1_PVCC")
	)
	(segment
		(start 134.414514 -284.64002)
		(end 134.366 -284.688534)
		(width 0.254)
		(layer "F.Cu")
		(net "P0V8_PEX1_PVCC")
	)
	(segment
		(start 134.414514 -284.072584)
		(end 134.414514 -284.64002)
		(width 0.254)
		(layer "F.Cu")
		(net "P0V8_PEX1_PVCC")
	)
	(segment
		(start 125.451108 -283.974032)
		(end 126.16561 -284.688534)
		(width 0.2286)
		(layer "F.Cu")
		(net "P0V8_PEX1_PVCC")
	)
	(segment
		(start 126.254002 -284.64002)
		(end 126.205488 -284.688534)
		(width 0.254)
		(layer "F.Cu")
		(net "P0V8_PEX1_PVCC")
	)
	(via
		(at 134.414514 -284.072584)
		(size 0.508)
		(drill 0.254)
		(layers "F.Cu" "B.Cu")
		(net "P0V8_PEX1_PVCC")
	)
	(via
		(at 126.254002 -284.072584)
		(size 0.508)
		(drill 0.254)
		(layers "F.Cu" "B.Cu")
		(net "P0V8_PEX1_PVCC")
	)
	(segment
		(start 126.254002 -284.072584)
		(end 125.901196 -284.218634)
		(width 0.254)
		(layer "B.Cu")
		(net "P0V8_PEX1_PVCC")
	)
	(segment
		(start 125.901196 -284.218634)
		(end 125.570488 -284.218634)
		(width 0.254)
		(layer "B.Cu")
		(net "P0V8_PEX1_PVCC")
	)
	(segment
		(start 126.322328 -285.200598)
		(end 126.328678 -285.206948)
		(width 0.254)
		(layer "B.Cu")
		(net "P0V8_PEX1_PVCC")
	)
	(segment
		(start 126.328678 -285.206948)
		(end 126.328678 -284.14726)
		(width 0.254)
		(layer "B.Cu")
		(net "P0V8_PEX1_PVCC")
	)
	(segment
		(start 126.328678 -284.14726)
		(end 126.254002 -284.072584)
		(width 0.254)
		(layer "B.Cu")
		(net "P0V8_PEX1_PVCC")
	)
	(segment
		(start 125.357128 -285.200598)
		(end 126.322328 -285.200598)
		(width 0.254)
		(layer "B.Cu")
		(net "P0V8_PEX1_PVCC")
	)
	(segment
		(start 134.414514 -284.072584)
		(end 134.061708 -284.218634)
		(width 0.254)
		(layer "B.Cu")
		(net "P0V8_PEX1_PVCC")
	)
	(segment
		(start 134.061708 -284.218634)
		(end 133.731 -284.218634)
		(width 0.254)
		(layer "B.Cu")
		(net "P0V8_PEX1_PVCC")
	)
	(segment
		(start 128.093978 -284.714188)
		(end 129.304288 -284.714188)
		(width 0.254)
		(layer "In5.Cu")
		(net "P0V8_PEX1_PVCC")
	)
	(segment
		(start 133.143752 -284.072584)
		(end 134.414514 -284.072584)
		(width 0.254)
		(layer "In5.Cu")
		(net "P0V8_PEX1_PVCC")
	)
	(segment
		(start 129.304288 -284.714188)
		(end 130.302508 -283.715968)
		(width 0.254)
		(layer "In5.Cu")
		(net "P0V8_PEX1_PVCC")
	)
	(segment
		(start 127.452374 -284.072584)
		(end 128.093978 -284.714188)
		(width 0.254)
		(layer "In5.Cu")
		(net "P0V8_PEX1_PVCC")
	)
	(segment
		(start 130.302508 -283.715968)
		(end 132.787136 -283.715968)
		(width 0.254)
		(layer "In5.Cu")
		(net "P0V8_PEX1_PVCC")
	)
	(segment
		(start 132.787136 -283.715968)
		(end 133.143752 -284.072584)
		(width 0.254)
		(layer "In5.Cu")
		(net "P0V8_PEX1_PVCC")
	)
	(segment
		(start 126.254002 -284.072584)
		(end 127.452374 -284.072584)
		(width 0.254)
		(layer "In5.Cu")
		(net "P0V8_PEX1_PVCC")
	)
	(segment
		(start 116.532152 -283.974032)
		(end 116.943632 -283.974032)
		(width 0.2286)
		(layer "F.Cu")
		(net "P0V8_PEX0_PVCC")
	)
	(segment
		(start 109.506512 -284.688534)
		(end 109.54639 -284.688534)
		(width 0.2286)
		(layer "F.Cu")
		(net "P0V8_PEX0_PVCC")
	)
	(segment
		(start 109.594904 -284.64002)
		(end 109.54639 -284.688534)
		(width 0.254)
		(layer "F.Cu")
		(net "P0V8_PEX0_PVCC")
	)
	(segment
		(start 117.755416 -284.64002)
		(end 117.706902 -284.688534)
		(width 0.254)
		(layer "F.Cu")
		(net "P0V8_PEX0_PVCC")
	)
	(segment
		(start 117.755416 -284.072584)
		(end 117.755416 -284.64002)
		(width 0.254)
		(layer "F.Cu")
		(net "P0V8_PEX0_PVCC")
	)
	(segment
		(start 109.594904 -284.072584)
		(end 109.594904 -284.64002)
		(width 0.254)
		(layer "F.Cu")
		(net "P0V8_PEX0_PVCC")
	)
	(segment
		(start 108.79201 -283.974032)
		(end 109.506512 -284.688534)
		(width 0.2286)
		(layer "F.Cu")
		(net "P0V8_PEX0_PVCC")
	)
	(segment
		(start 108.37164 -283.974032)
		(end 108.79201 -283.974032)
		(width 0.2286)
		(layer "F.Cu")
		(net "P0V8_PEX0_PVCC")
	)
	(segment
		(start 117.658134 -284.688534)
		(end 117.706902 -284.688534)
		(width 0.2286)
		(layer "F.Cu")
		(net "P0V8_PEX0_PVCC")
	)
	(segment
		(start 116.943632 -283.974032)
		(end 117.658134 -284.688534)
		(width 0.2286)
		(layer "F.Cu")
		(net "P0V8_PEX0_PVCC")
	)
	(via
		(at 109.594904 -284.072584)
		(size 0.508)
		(drill 0.254)
		(layers "F.Cu" "B.Cu")
		(net "P0V8_PEX0_PVCC")
	)
	(via
		(at 117.755416 -284.072584)
		(size 0.508)
		(drill 0.254)
		(layers "F.Cu" "B.Cu")
		(net "P0V8_PEX0_PVCC")
	)
	(segment
		(start 109.682788 -285.180278)
		(end 109.682788 -284.160468)
		(width 0.254)
		(layer "B.Cu")
		(net "P0V8_PEX0_PVCC")
	)
	(segment
		(start 109.242098 -284.218634)
		(end 108.91139 -284.218634)
		(width 0.254)
		(layer "B.Cu")
		(net "P0V8_PEX0_PVCC")
	)
	(segment
		(start 117.40261 -284.218634)
		(end 117.071902 -284.218634)
		(width 0.254)
		(layer "B.Cu")
		(net "P0V8_PEX0_PVCC")
	)
	(segment
		(start 109.682788 -284.160468)
		(end 109.594904 -284.072584)
		(width 0.254)
		(layer "B.Cu")
		(net "P0V8_PEX0_PVCC")
	)
	(segment
		(start 109.678978 -285.176468)
		(end 109.682788 -285.180278)
		(width 0.254)
		(layer "B.Cu")
		(net "P0V8_PEX0_PVCC")
	)
	(segment
		(start 117.755416 -284.072584)
		(end 117.40261 -284.218634)
		(width 0.254)
		(layer "B.Cu")
		(net "P0V8_PEX0_PVCC")
	)
	(segment
		(start 109.594904 -284.072584)
		(end 109.242098 -284.218634)
		(width 0.254)
		(layer "B.Cu")
		(net "P0V8_PEX0_PVCC")
	)
	(segment
		(start 108.711238 -285.176468)
		(end 109.678978 -285.176468)
		(width 0.254)
		(layer "B.Cu")
		(net "P0V8_PEX0_PVCC")
	)
	(segment
		(start 117.755416 -284.072584)
		(end 117.45468 -284.072584)
		(width 0.254)
		(layer "In5.Cu")
		(net "P0V8_PEX0_PVCC")
	)
	(segment
		(start 117.45468 -284.072584)
		(end 116.928392 -283.546296)
		(width 0.254)
		(layer "In5.Cu")
		(net "P0V8_PEX0_PVCC")
	)
	(segment
		(start 110.247176 -284.724856)
		(end 109.594904 -284.072584)
		(width 0.254)
		(layer "In5.Cu")
		(net "P0V8_PEX0_PVCC")
	)
	(segment
		(start 116.928392 -283.546296)
		(end 113.76025 -283.546296)
		(width 0.254)
		(layer "In5.Cu")
		(net "P0V8_PEX0_PVCC")
	)
	(segment
		(start 113.76025 -283.546296)
		(end 112.58169 -284.724856)
		(width 0.254)
		(layer "In5.Cu")
		(net "P0V8_PEX0_PVCC")
	)
	(segment
		(start 112.58169 -284.724856)
		(end 110.247176 -284.724856)
		(width 0.254)
		(layer "In5.Cu")
		(net "P0V8_PEX0_PVCC")
	)
	(segment
		(start 122.956828 -281.144218)
		(end 122.820684 -281.280362)
		(width 0.2286)
		(layer "F.Cu")
		(net "P0V8_PEX0_EN3")
	)
	(segment
		(start 122.820684 -281.280362)
		(end 122.820684 -281.999182)
		(width 0.2286)
		(layer "F.Cu")
		(net "P0V8_PEX0_EN3")
	)
	(via
		(at 122.956828 -281.144218)
		(size 0.508)
		(drill 0.254)
		(layers "F.Cu" "B.Cu")
		(net "P0V8_PEX0_EN3")
	)
	(segment
		(start 124.101352 -281.410664)
		(end 123.223274 -281.410664)
		(width 0.13208)
		(layer "B.Cu")
		(net "P0V8_PEX0_EN3")
	)
	(segment
		(start 123.223274 -281.410664)
		(end 122.956828 -281.144218)
		(width 0.13208)
		(layer "B.Cu")
		(net "P0V8_PEX0_EN3")
	)
	(segment
		(start 122.956828 -281.144218)
		(end 122.930158 -281.170888)
		(width 0.13208)
		(layer "B.Cu")
		(net "P0V8_PEX0_EN3")
	)
	(segment
		(start 124.731526 -281.770074)
		(end 124.460762 -281.770074)
		(width 0.13208)
		(layer "B.Cu")
		(net "P0V8_PEX0_EN3")
	)
	(segment
		(start 122.930158 -281.170888)
		(end 122.930158 -282.238958)
		(width 0.13208)
		(layer "B.Cu")
		(net "P0V8_PEX0_EN3")
	)
	(segment
		(start 124.460762 -281.770074)
		(end 124.101352 -281.410664)
		(width 0.13208)
		(layer "B.Cu")
		(net "P0V8_PEX0_EN3")
	)
	(segment
		(start 114.322098 -281.280362)
		(end 114.322098 -281.999182)
		(width 0.2286)
		(layer "F.Cu")
		(net "P0V8_PEX0_EN2")
	)
	(segment
		(start 114.458242 -281.144218)
		(end 114.322098 -281.280362)
		(width 0.2286)
		(layer "F.Cu")
		(net "P0V8_PEX0_EN2")
	)
	(via
		(at 114.458242 -281.144218)
		(size 0.508)
		(drill 0.254)
		(layers "F.Cu" "B.Cu")
		(net "P0V8_PEX0_EN2")
	)
	(segment
		(start 115.75288 -281.762962)
		(end 115.699032 -281.762962)
		(width 0.13208)
		(layer "B.Cu")
		(net "P0V8_PEX0_EN2")
	)
	(segment
		(start 115.4176 -281.48153)
		(end 114.795554 -281.48153)
		(width 0.13208)
		(layer "B.Cu")
		(net "P0V8_PEX0_EN2")
	)
	(segment
		(start 114.433604 -282.251404)
		(end 114.433604 -281.168856)
		(width 0.13208)
		(layer "B.Cu")
		(net "P0V8_PEX0_EN2")
	)
	(segment
		(start 114.433604 -281.168856)
		(end 114.458242 -281.144218)
		(width 0.13208)
		(layer "B.Cu")
		(net "P0V8_PEX0_EN2")
	)
	(segment
		(start 115.75669 -281.766772)
		(end 115.75288 -281.762962)
		(width 0.13208)
		(layer "B.Cu")
		(net "P0V8_PEX0_EN2")
	)
	(segment
		(start 116.224558 -281.766772)
		(end 115.75669 -281.766772)
		(width 0.13208)
		(layer "B.Cu")
		(net "P0V8_PEX0_EN2")
	)
	(segment
		(start 115.699032 -281.762962)
		(end 115.4176 -281.48153)
		(width 0.13208)
		(layer "B.Cu")
		(net "P0V8_PEX0_EN2")
	)
	(segment
		(start 114.795554 -281.48153)
		(end 114.458242 -281.144218)
		(width 0.13208)
		(layer "B.Cu")
		(net "P0V8_PEX0_EN2")
	)
	(segment
		(start 106.29773 -281.144218)
		(end 106.161586 -281.280362)
		(width 0.2286)
		(layer "F.Cu")
		(net "P0V8_PEX0_EN1")
	)
	(segment
		(start 106.161586 -281.280362)
		(end 106.161586 -281.999182)
		(width 0.2286)
		(layer "F.Cu")
		(net "P0V8_PEX0_EN1")
	)
	(via
		(at 106.29773 -281.144218)
		(size 0.508)
		(drill 0.254)
		(layers "F.Cu" "B.Cu")
		(net "P0V8_PEX0_EN1")
	)
	(segment
		(start 106.323638 -282.228036)
		(end 106.323638 -281.170126)
		(width 0.13208)
		(layer "B.Cu")
		(net "P0V8_PEX0_EN1")
	)
	(segment
		(start 106.30027 -282.251404)
		(end 106.323638 -282.228036)
		(width 0.13208)
		(layer "B.Cu")
		(net "P0V8_PEX0_EN1")
	)
	(segment
		(start 106.323638 -281.170126)
		(end 106.29773 -281.144218)
		(width 0.13208)
		(layer "B.Cu")
		(net "P0V8_PEX0_EN1")
	)
	(segment
		(start 107.351068 -281.379422)
		(end 106.532934 -281.379422)
		(width 0.13208)
		(layer "B.Cu")
		(net "P0V8_PEX0_EN1")
	)
	(segment
		(start 107.739688 -281.768042)
		(end 107.351068 -281.379422)
		(width 0.13208)
		(layer "B.Cu")
		(net "P0V8_PEX0_EN1")
	)
	(segment
		(start 108.059982 -281.768042)
		(end 107.739688 -281.768042)
		(width 0.13208)
		(layer "B.Cu")
		(net "P0V8_PEX0_EN1")
	)
	(segment
		(start 106.532934 -281.379422)
		(end 106.323638 -281.170126)
		(width 0.13208)
		(layer "B.Cu")
		(net "P0V8_PEX0_EN1")
	)
	(segment
		(start 355.157024 -281.144218)
		(end 355.02088 -281.44978)
		(width 0.2286)
		(layer "F.Cu")
		(net "P0V8_PEX2_EN3")
	)
	(segment
		(start 355.02088 -281.44978)
		(end 355.02088 -281.999182)
		(width 0.2286)
		(layer "F.Cu")
		(net "P0V8_PEX2_EN3")
	)
	(via
		(at 355.157024 -281.144218)
		(size 0.508)
		(drill 0.254)
		(layers "F.Cu" "B.Cu")
		(net "P0V8_PEX2_EN3")
	)
	(segment
		(start 355.157024 -281.585162)
		(end 355.157024 -281.144218)
		(width 0.13208)
		(layer "B.Cu")
		(net "P0V8_PEX2_EN3")
	)
	(segment
		(start 356.665276 -281.766772)
		(end 356.273862 -281.375358)
		(width 0.13208)
		(layer "B.Cu")
		(net "P0V8_PEX2_EN3")
	)
	(segment
		(start 355.120702 -281.621484)
		(end 355.157024 -281.585162)
		(width 0.13208)
		(layer "B.Cu")
		(net "P0V8_PEX2_EN3")
	)
	(segment
		(start 356.918006 -281.766772)
		(end 356.665276 -281.766772)
		(width 0.13208)
		(layer "B.Cu")
		(net "P0V8_PEX2_EN3")
	)
	(segment
		(start 355.388164 -281.375358)
		(end 355.157024 -281.144218)
		(width 0.13208)
		(layer "B.Cu")
		(net "P0V8_PEX2_EN3")
	)
	(segment
		(start 355.120702 -282.259532)
		(end 355.120702 -281.621484)
		(width 0.13208)
		(layer "B.Cu")
		(net "P0V8_PEX2_EN3")
	)
	(segment
		(start 356.273862 -281.375358)
		(end 355.388164 -281.375358)
		(width 0.13208)
		(layer "B.Cu")
		(net "P0V8_PEX2_EN3")
	)
	(segment
		(start 363.181392 -281.44978)
		(end 363.181392 -281.999182)
		(width 0.2286)
		(layer "F.Cu")
		(net "P0V8_PEX2_EN4")
	)
	(segment
		(start 363.317536 -281.144218)
		(end 363.181392 -281.44978)
		(width 0.2286)
		(layer "F.Cu")
		(net "P0V8_PEX2_EN4")
	)
	(via
		(at 363.317536 -281.144218)
		(size 0.508)
		(drill 0.254)
		(layers "F.Cu" "B.Cu")
		(net "P0V8_PEX2_EN4")
	)
	(segment
		(start 365.087408 -281.773376)
		(end 364.875826 -281.773376)
		(width 0.13208)
		(layer "B.Cu")
		(net "P0V8_PEX2_EN4")
	)
	(segment
		(start 364.875826 -281.773376)
		(end 364.489746 -281.387296)
		(width 0.13208)
		(layer "B.Cu")
		(net "P0V8_PEX2_EN4")
	)
	(segment
		(start 363.317536 -281.585162)
		(end 363.317536 -281.144218)
		(width 0.13208)
		(layer "B.Cu")
		(net "P0V8_PEX2_EN4")
	)
	(segment
		(start 364.489746 -281.387296)
		(end 363.560614 -281.387296)
		(width 0.13208)
		(layer "B.Cu")
		(net "P0V8_PEX2_EN4")
	)
	(segment
		(start 363.310424 -282.244038)
		(end 363.310424 -281.592274)
		(width 0.13208)
		(layer "B.Cu")
		(net "P0V8_PEX2_EN4")
	)
	(segment
		(start 363.310424 -281.592274)
		(end 363.317536 -281.585162)
		(width 0.13208)
		(layer "B.Cu")
		(net "P0V8_PEX2_EN4")
	)
	(segment
		(start 363.560614 -281.387296)
		(end 363.317536 -281.144218)
		(width 0.13208)
		(layer "B.Cu")
		(net "P0V8_PEX2_EN4")
	)
	(segment
		(start 346.658438 -281.144218)
		(end 346.522294 -281.44978)
		(width 0.2286)
		(layer "F.Cu")
		(net "P0V8_PEX2_EN2")
	)
	(segment
		(start 346.522294 -281.44978)
		(end 346.522294 -281.999182)
		(width 0.2286)
		(layer "F.Cu")
		(net "P0V8_PEX2_EN2")
	)
	(via
		(at 346.658438 -281.144218)
		(size 0.508)
		(drill 0.254)
		(layers "F.Cu" "B.Cu")
		(net "P0V8_PEX2_EN2")
	)
	(segment
		(start 347.79458 -281.347672)
		(end 346.861892 -281.347672)
		(width 0.13208)
		(layer "B.Cu")
		(net "P0V8_PEX2_EN2")
	)
	(segment
		(start 346.625164 -282.244292)
		(end 346.625164 -281.618436)
		(width 0.13208)
		(layer "B.Cu")
		(net "P0V8_PEX2_EN2")
	)
	(segment
		(start 348.214188 -281.76728)
		(end 347.79458 -281.347672)
		(width 0.13208)
		(layer "B.Cu")
		(net "P0V8_PEX2_EN2")
	)
	(segment
		(start 346.625164 -281.618436)
		(end 346.658438 -281.585162)
		(width 0.13208)
		(layer "B.Cu")
		(net "P0V8_PEX2_EN2")
	)
	(segment
		(start 346.658438 -281.585162)
		(end 346.658438 -281.144218)
		(width 0.13208)
		(layer "B.Cu")
		(net "P0V8_PEX2_EN2")
	)
	(segment
		(start 348.435168 -281.76728)
		(end 348.214188 -281.76728)
		(width 0.13208)
		(layer "B.Cu")
		(net "P0V8_PEX2_EN2")
	)
	(segment
		(start 346.861892 -281.347672)
		(end 346.658438 -281.144218)
		(width 0.13208)
		(layer "B.Cu")
		(net "P0V8_PEX2_EN2")
	)
	(segment
		(start 338.361782 -281.44978)
		(end 338.361782 -281.999182)
		(width 0.2286)
		(layer "F.Cu")
		(net "P0V8_PEX2_EN1")
	)
	(segment
		(start 338.497926 -281.144218)
		(end 338.361782 -281.44978)
		(width 0.2286)
		(layer "F.Cu")
		(net "P0V8_PEX2_EN1")
	)
	(via
		(at 338.497926 -281.144218)
		(size 0.508)
		(drill 0.254)
		(layers "F.Cu" "B.Cu")
		(net "P0V8_PEX2_EN1")
	)
	(segment
		(start 338.44357 -282.244292)
		(end 338.44357 -281.639518)
		(width 0.13208)
		(layer "B.Cu")
		(net "P0V8_PEX2_EN1")
	)
	(segment
		(start 338.497926 -281.585162)
		(end 338.497926 -281.144218)
		(width 0.13208)
		(layer "B.Cu")
		(net "P0V8_PEX2_EN1")
	)
	(segment
		(start 340.033356 -281.767026)
		(end 339.66531 -281.39898)
		(width 0.13208)
		(layer "B.Cu")
		(net "P0V8_PEX2_EN1")
	)
	(segment
		(start 338.752688 -281.39898)
		(end 338.497926 -281.144218)
		(width 0.13208)
		(layer "B.Cu")
		(net "P0V8_PEX2_EN1")
	)
	(segment
		(start 338.44357 -281.639518)
		(end 338.497926 -281.585162)
		(width 0.13208)
		(layer "B.Cu")
		(net "P0V8_PEX2_EN1")
	)
	(segment
		(start 340.27999 -281.767026)
		(end 340.033356 -281.767026)
		(width 0.13208)
		(layer "B.Cu")
		(net "P0V8_PEX2_EN1")
	)
	(segment
		(start 339.66531 -281.39898)
		(end 338.752688 -281.39898)
		(width 0.13208)
		(layer "B.Cu")
		(net "P0V8_PEX2_EN1")
	)
	(segment
		(start 130.981196 -281.44978)
		(end 130.981196 -281.999182)
		(width 0.2286)
		(layer "F.Cu")
		(net "P0V8_PEX0_EN4")
	)
	(segment
		(start 131.11734 -281.144218)
		(end 130.981196 -281.44978)
		(width 0.2286)
		(layer "F.Cu")
		(net "P0V8_PEX0_EN4")
	)
	(via
		(at 131.11734 -281.144218)
		(size 0.508)
		(drill 0.254)
		(layers "F.Cu" "B.Cu")
		(net "P0V8_PEX0_EN4")
	)
	(segment
		(start 131.11734 -281.144218)
		(end 131.12369 -281.150568)
		(width 0.13208)
		(layer "B.Cu")
		(net "P0V8_PEX0_EN4")
	)
	(segment
		(start 131.340606 -281.367484)
		(end 131.12369 -281.150568)
		(width 0.13208)
		(layer "B.Cu")
		(net "P0V8_PEX0_EN4")
	)
	(segment
		(start 132.620766 -281.773122)
		(end 132.215128 -281.367484)
		(width 0.13208)
		(layer "B.Cu")
		(net "P0V8_PEX0_EN4")
	)
	(segment
		(start 132.215128 -281.367484)
		(end 131.340606 -281.367484)
		(width 0.13208)
		(layer "B.Cu")
		(net "P0V8_PEX0_EN4")
	)
	(segment
		(start 131.12369 -282.263088)
		(end 131.12369 -281.150568)
		(width 0.13208)
		(layer "B.Cu")
		(net "P0V8_PEX0_EN4")
	)
	(segment
		(start 132.8928 -281.773122)
		(end 132.620766 -281.773122)
		(width 0.13208)
		(layer "B.Cu")
		(net "P0V8_PEX0_EN4")
	)
	(segment
		(start 3.190494 -367.152682)
		(end 3.190494 -368.23269)
		(width 0.508)
		(layer "F.Cu")
		(net "PG12_USB_HUB_N")
	)
	(segment
		(start 6.914388 -366.192308)
		(end 7.58952 -366.192308)
		(width 0.508)
		(layer "F.Cu")
		(net "PG12_USB_HUB_N")
	)
	(segment
		(start 4.150106 -366.19307)
		(end 3.190494 -367.152682)
		(width 0.508)
		(layer "F.Cu")
		(net "PG12_USB_HUB_N")
	)
	(segment
		(start 4.150106 -366.19307)
		(end 4.150868 -366.192308)
		(width 0.508)
		(layer "F.Cu")
		(net "PG12_USB_HUB_N")
	)
	(segment
		(start 4.150868 -366.192308)
		(end 6.914388 -366.192308)
		(width 0.508)
		(layer "F.Cu")
		(net "PG12_USB_HUB_N")
	)
	(via
		(at 7.58952 -366.192308)
		(size 0.508)
		(drill 0.254)
		(layers "F.Cu" "B.Cu")
		(net "PG12_USB_HUB_N")
	)
	(segment
		(start 7.930134 -390.896856)
		(end 7.930134 -392.337036)
		(width 0.13208)
		(layer "F.Cu")
		(net "BIC_USB_8042_HUB_HS_SUSPEND")
	)
	(segment
		(start 7.930134 -392.337036)
		(end 7.930134 -392.563604)
		(width 0.13208)
		(layer "F.Cu")
		(net "BIC_USB_8042_HUB_HS_SUSPEND")
	)
	(segment
		(start 7.930134 -392.563604)
		(end 9.1059 -393.73937)
		(width 0.13208)
		(layer "F.Cu")
		(net "BIC_USB_8042_HUB_HS_SUSPEND")
	)
	(via
		(at 7.930134 -392.337036)
		(size 0.762)
		(drill 0.381)
		(layers "F.Cu" "B.Cu")
		(net "BIC_USB_8042_HUB_HS_SUSPEND")
	)
	(segment
		(start 10.275062 -392.458448)
		(end 10.546588 -392.458448)
		(width 0.13208)
		(layer "F.Cu")
		(net "BIC_USB_8042_HUB_OVCUR4")
	)
	(segment
		(start 11.956796 -393.543536)
		(end 11.956796 -393.737084)
		(width 0.13208)
		(layer "F.Cu")
		(net "BIC_USB_8042_HUB_OVCUR4")
	)
	(segment
		(start 8.930132 -391.113518)
		(end 10.275062 -392.458448)
		(width 0.13208)
		(layer "F.Cu")
		(net "BIC_USB_8042_HUB_OVCUR4")
	)
	(segment
		(start 10.546588 -392.458448)
		(end 10.871708 -392.458448)
		(width 0.13208)
		(layer "F.Cu")
		(net "BIC_USB_8042_HUB_OVCUR4")
	)
	(segment
		(start 10.871708 -392.458448)
		(end 11.956796 -393.543536)
		(width 0.13208)
		(layer "F.Cu")
		(net "BIC_USB_8042_HUB_OVCUR4")
	)
	(segment
		(start 8.930132 -390.896856)
		(end 8.930132 -391.113518)
		(width 0.13208)
		(layer "F.Cu")
		(net "BIC_USB_8042_HUB_OVCUR4")
	)
	(via
		(at 10.546588 -392.458448)
		(size 0.762)
		(drill 0.381)
		(layers "F.Cu" "B.Cu")
		(net "BIC_USB_8042_HUB_OVCUR4")
	)
	(segment
		(start 10.401554 -393.73937)
		(end 10.401554 -393.438634)
		(width 0.13208)
		(layer "F.Cu")
		(net "BIC_USB_8042_HUB_OVCUR3")
	)
	(segment
		(start 9.236456 -392.273536)
		(end 8.430006 -391.467086)
		(width 0.13208)
		(layer "F.Cu")
		(net "BIC_USB_8042_HUB_OVCUR3")
	)
	(segment
		(start 8.430006 -391.467086)
		(end 8.430006 -390.896856)
		(width 0.13208)
		(layer "F.Cu")
		(net "BIC_USB_8042_HUB_OVCUR3")
	)
	(segment
		(start 10.401554 -393.438634)
		(end 9.236456 -392.273536)
		(width 0.13208)
		(layer "F.Cu")
		(net "BIC_USB_8042_HUB_OVCUR3")
	)
	(via
		(at 9.236456 -392.273536)
		(size 0.762)
		(drill 0.381)
		(layers "F.Cu" "B.Cu")
		(net "BIC_USB_8042_HUB_OVCUR3")
	)
	(segment
		(start 6.930136 -391.836656)
		(end 6.608318 -392.158474)
		(width 0.13208)
		(layer "F.Cu")
		(net "BIC_USB_8042_HUB_OVCUR2")
	)
	(segment
		(start 6.608318 -393.28598)
		(end 6.662674 -393.340336)
		(width 0.13208)
		(layer "F.Cu")
		(net "BIC_USB_8042_HUB_OVCUR2")
	)
	(segment
		(start 6.930136 -390.896856)
		(end 6.930136 -391.836656)
		(width 0.13208)
		(layer "F.Cu")
		(net "BIC_USB_8042_HUB_OVCUR2")
	)
	(segment
		(start 6.608318 -392.158474)
		(end 6.608318 -393.28598)
		(width 0.13208)
		(layer "F.Cu")
		(net "BIC_USB_8042_HUB_OVCUR2")
	)
	(via
		(at 6.608318 -392.158474)
		(size 0.762)
		(drill 0.381)
		(layers "F.Cu" "B.Cu")
		(net "BIC_USB_8042_HUB_OVCUR2")
	)
	(segment
		(start 7.430008 -391.85596)
		(end 7.430008 -390.896856)
		(width 0.13208)
		(layer "F.Cu")
		(net "BIC_USB_8042_HUB_OVCUR1")
	)
	(segment
		(start 1.936496 -396.067788)
		(end 1.640078 -395.77137)
		(width 0.13208)
		(layer "F.Cu")
		(net "BIC_USB_8042_HUB_OVCUR1")
	)
	(segment
		(start 7.232904 -392.970004)
		(end 7.232904 -392.053064)
		(width 0.13208)
		(layer "F.Cu")
		(net "BIC_USB_8042_HUB_OVCUR1")
	)
	(segment
		(start 7.35076 -395.281912)
		(end 3.789426 -395.281912)
		(width 0.13208)
		(layer "F.Cu")
		(net "BIC_USB_8042_HUB_OVCUR1")
	)
	(segment
		(start 7.90067 -394.732002)
		(end 7.35076 -395.281912)
		(width 0.13208)
		(layer "F.Cu")
		(net "BIC_USB_8042_HUB_OVCUR1")
	)
	(segment
		(start 7.90067 -393.63777)
		(end 7.90067 -394.732002)
		(width 0.13208)
		(layer "F.Cu")
		(net "BIC_USB_8042_HUB_OVCUR1")
	)
	(segment
		(start 7.90067 -393.63777)
		(end 7.232904 -392.970004)
		(width 0.13208)
		(layer "F.Cu")
		(net "BIC_USB_8042_HUB_OVCUR1")
	)
	(segment
		(start 7.232904 -392.053064)
		(end 7.430008 -391.85596)
		(width 0.13208)
		(layer "F.Cu")
		(net "BIC_USB_8042_HUB_OVCUR1")
	)
	(segment
		(start 3.789426 -395.281912)
		(end 3.00355 -396.067788)
		(width 0.13208)
		(layer "F.Cu")
		(net "BIC_USB_8042_HUB_OVCUR1")
	)
	(segment
		(start 1.640078 -395.77137)
		(end 1.640078 -395.448282)
		(width 0.13208)
		(layer "F.Cu")
		(net "BIC_USB_8042_HUB_OVCUR1")
	)
	(segment
		(start 3.00355 -396.067788)
		(end 1.936496 -396.067788)
		(width 0.13208)
		(layer "F.Cu")
		(net "BIC_USB_8042_HUB_OVCUR1")
	)
	(via
		(at 7.90067 -393.63777)
		(size 0.762)
		(drill 0.381)
		(layers "F.Cu" "B.Cu")
		(net "BIC_USB_8042_HUB_OVCUR1")
	)
	(segment
		(start 5.35432 -392.567922)
		(end 5.35432 -391.950702)
		(width 0.13208)
		(layer "F.Cu")
		(net "BIC_USB_8042_HUB_VBUS")
	)
	(segment
		(start 5.683504 -393.346178)
		(end 4.682236 -393.346178)
		(width 0.13208)
		(layer "F.Cu")
		(net "BIC_USB_8042_HUB_VBUS")
	)
	(segment
		(start 6.43001 -391.322052)
		(end 6.43001 -390.896856)
		(width 0.13208)
		(layer "F.Cu")
		(net "BIC_USB_8042_HUB_VBUS")
	)
	(segment
		(start 5.684774 -393.344908)
		(end 5.684774 -392.898376)
		(width 0.13208)
		(layer "F.Cu")
		(net "BIC_USB_8042_HUB_VBUS")
	)
	(segment
		(start 5.80136 -391.950702)
		(end 6.43001 -391.322052)
		(width 0.13208)
		(layer "F.Cu")
		(net "BIC_USB_8042_HUB_VBUS")
	)
	(segment
		(start 5.35432 -391.950702)
		(end 5.80136 -391.950702)
		(width 0.13208)
		(layer "F.Cu")
		(net "BIC_USB_8042_HUB_VBUS")
	)
	(segment
		(start 5.684774 -392.898376)
		(end 5.35432 -392.567922)
		(width 0.13208)
		(layer "F.Cu")
		(net "BIC_USB_8042_HUB_VBUS")
	)
	(segment
		(start 5.684774 -393.344908)
		(end 5.683504 -393.346178)
		(width 0.13208)
		(layer "F.Cu")
		(net "BIC_USB_8042_HUB_VBUS")
	)
	(via
		(at 5.35432 -391.950702)
		(size 0.762)
		(drill 0.381)
		(layers "F.Cu" "B.Cu")
		(net "BIC_USB_8042_HUB_VBUS")
	)
	(segment
		(start 14.580108 -389.746744)
		(end 15.316962 -389.746744)
		(width 0.13208)
		(layer "F.Cu")
		(net "P1V2_USB_8042")
	)
	(segment
		(start 12.429998 -382.096772)
		(end 12.429998 -381.56769)
		(width 0.13208)
		(layer "F.Cu")
		(net "P1V2_USB_8042")
	)
	(segment
		(start 5.780024 -386.246878)
		(end 5.044186 -386.246878)
		(width 0.13208)
		(layer "F.Cu")
		(net "P1V2_USB_8042")
	)
	(segment
		(start 14.580108 -384.746754)
		(end 15.297658 -384.746754)
		(width 0.13208)
		(layer "F.Cu")
		(net "P1V2_USB_8042")
	)
	(segment
		(start 4.795266 -389.720836)
		(end 5.26923 -389.246872)
		(width 0.13208)
		(layer "F.Cu")
		(net "P1V2_USB_8042")
	)
	(segment
		(start 15.275814 -388.246874)
		(end 15.310358 -388.21233)
		(width 0.13208)
		(layer "F.Cu")
		(net "P1V2_USB_8042")
	)
	(segment
		(start 3.200146 -364.193074)
		(end 3.200146 -365.288322)
		(width 0.508)
		(layer "F.Cu")
		(net "P1V2_USB_8042")
	)
	(segment
		(start 9.93013 -382.096772)
		(end 9.93013 -381.345694)
		(width 0.13208)
		(layer "F.Cu")
		(net "P1V2_USB_8042")
	)
	(segment
		(start 12.429998 -381.56769)
		(end 12.214606 -381.352298)
		(width 0.13208)
		(layer "F.Cu")
		(net "P1V2_USB_8042")
	)
	(segment
		(start 5.26923 -389.246872)
		(end 5.780024 -389.246872)
		(width 0.13208)
		(layer "F.Cu")
		(net "P1V2_USB_8042")
	)
	(segment
		(start 8.430006 -382.096772)
		(end 8.430006 -381.348742)
		(width 0.13208)
		(layer "F.Cu")
		(net "P1V2_USB_8042")
	)
	(segment
		(start 14.580108 -388.246874)
		(end 15.275814 -388.246874)
		(width 0.13208)
		(layer "F.Cu")
		(net "P1V2_USB_8042")
	)
	(via
		(at 8.430006 -381.348742)
		(size 0.508)
		(drill 0.254)
		(layers "F.Cu" "B.Cu")
		(net "P1V2_USB_8042")
	)
	(via
		(at 15.316962 -389.746744)
		(size 0.508)
		(drill 0.254)
		(layers "F.Cu" "B.Cu")
		(net "P1V2_USB_8042")
	)
	(via
		(at 5.044186 -386.246878)
		(size 0.508)
		(drill 0.254)
		(layers "F.Cu" "B.Cu")
		(net "P1V2_USB_8042")
	)
	(via
		(at 12.214606 -381.352298)
		(size 0.508)
		(drill 0.254)
		(layers "F.Cu" "B.Cu")
		(net "P1V2_USB_8042")
	)
	(via
		(at 3.200146 -365.288322)
		(size 0.508)
		(drill 0.254)
		(layers "F.Cu" "B.Cu")
		(net "P1V2_USB_8042")
	)
	(via
		(at 4.795266 -389.720836)
		(size 0.508)
		(drill 0.254)
		(layers "F.Cu" "B.Cu")
		(net "P1V2_USB_8042")
	)
	(via
		(at 15.297658 -384.746754)
		(size 0.508)
		(drill 0.254)
		(layers "F.Cu" "B.Cu")
		(net "P1V2_USB_8042")
	)
	(via
		(at 15.310358 -388.21233)
		(size 0.508)
		(drill 0.254)
		(layers "F.Cu" "B.Cu")
		(net "P1V2_USB_8042")
	)
	(via
		(at 9.93013 -381.345694)
		(size 0.508)
		(drill 0.254)
		(layers "F.Cu" "B.Cu")
		(net "P1V2_USB_8042")
	)
	(segment
		(start 6.662674 -394.140436)
		(end 6.662674 -394.758418)
		(width 0.4572)
		(layer "F.Cu")
		(net "P3V3_USB_8042")
	)
	(segment
		(start 14.188948 -391.614914)
		(end 13.894562 -391.614914)
		(width 0.13208)
		(layer "F.Cu")
		(net "P3V3_USB_8042")
	)
	(segment
		(start 2.633218 -393.86637)
		(end 2.633218 -394.48232)
		(width 0.4572)
		(layer "F.Cu")
		(net "P3V3_USB_8042")
	)
	(segment
		(start 13.894562 -391.614914)
		(end 13.429996 -391.150348)
		(width 0.13208)
		(layer "F.Cu")
		(net "P3V3_USB_8042")
	)
	(segment
		(start 5.780024 -388.746746)
		(end 5.01269 -388.746746)
		(width 0.13208)
		(layer "F.Cu")
		(net "P3V3_USB_8042")
	)
	(segment
		(start 13.930122 -382.096772)
		(end 13.930122 -381.41275)
		(width 0.13208)
		(layer "F.Cu")
		(net "P3V3_USB_8042")
	)
	(segment
		(start 5.780024 -383.246884)
		(end 5.01523 -383.246884)
		(width 0.13208)
		(layer "F.Cu")
		(net "P3V3_USB_8042")
	)
	(segment
		(start 2.440178 -395.448282)
		(end 2.633218 -395.255242)
		(width 0.4572)
		(layer "F.Cu")
		(net "P3V3_USB_8042")
	)
	(segment
		(start 11.956796 -394.537184)
		(end 11.956796 -395.204442)
		(width 0.4572)
		(layer "F.Cu")
		(net "P3V3_USB_8042")
	)
	(segment
		(start 13.429996 -391.150348)
		(end 13.429996 -390.896856)
		(width 0.13208)
		(layer "F.Cu")
		(net "P3V3_USB_8042")
	)
	(segment
		(start 16.631412 -392.321034)
		(end 16.631412 -391.66292)
		(width 0.4572)
		(layer "F.Cu")
		(net "P3V3_USB_8042")
	)
	(segment
		(start 2.633218 -395.255242)
		(end 2.633218 -394.48232)
		(width 0.4572)
		(layer "F.Cu")
		(net "P3V3_USB_8042")
	)
	(segment
		(start 10.401554 -394.53947)
		(end 10.401554 -395.206728)
		(width 0.4572)
		(layer "F.Cu")
		(net "P3V3_USB_8042")
	)
	(segment
		(start 16.445738 -394.528802)
		(end 16.445738 -395.19606)
		(width 0.4572)
		(layer "F.Cu")
		(net "P3V3_USB_8042")
	)
	(via
		(at 5.01523 -383.246884)
		(size 0.508)
		(drill 0.254)
		(layers "F.Cu" "B.Cu")
		(net "P3V3_USB_8042")
	)
	(via
		(at 13.930122 -381.41275)
		(size 0.508)
		(drill 0.254)
		(layers "F.Cu" "B.Cu")
		(net "P3V3_USB_8042")
	)
	(via
		(at 10.401554 -395.206728)
		(size 0.508)
		(drill 0.254)
		(layers "F.Cu" "B.Cu")
		(net "P3V3_USB_8042")
	)
	(via
		(at 5.01269 -388.746746)
		(size 0.508)
		(drill 0.254)
		(layers "F.Cu" "B.Cu")
		(net "P3V3_USB_8042")
	)
	(via
		(at 16.631412 -391.66292)
		(size 0.508)
		(drill 0.254)
		(layers "F.Cu" "B.Cu")
		(net "P3V3_USB_8042")
	)
	(via
		(at 11.956796 -395.204442)
		(size 0.508)
		(drill 0.254)
		(layers "F.Cu" "B.Cu")
		(net "P3V3_USB_8042")
	)
	(via
		(at 2.633218 -394.48232)
		(size 0.508)
		(drill 0.254)
		(layers "F.Cu" "B.Cu")
		(net "P3V3_USB_8042")
	)
	(via
		(at 6.662674 -394.758418)
		(size 0.508)
		(drill 0.254)
		(layers "F.Cu" "B.Cu")
		(net "P3V3_USB_8042")
	)
	(via
		(at 16.445738 -395.19606)
		(size 0.508)
		(drill 0.254)
		(layers "F.Cu" "B.Cu")
		(net "P3V3_USB_8042")
	)
	(via
		(at 14.188948 -391.614914)
		(size 0.508)
		(drill 0.254)
		(layers "F.Cu" "B.Cu")
		(net "P3V3_USB_8042")
	)
	(segment
		(start 3.208528 -381.411226)
		(end 3.208528 -383.341118)
		(width 0.13208)
		(layer "F.Cu")
		(net "BIC_USB_8042_HUB_XOUT")
	)
	(segment
		(start 3.208528 -380.275846)
		(end 3.208528 -381.411226)
		(width 0.13208)
		(layer "F.Cu")
		(net "BIC_USB_8042_HUB_XOUT")
	)
	(segment
		(start 1.91643 -379.2601)
		(end 2.196846 -379.540516)
		(width 0.13208)
		(layer "F.Cu")
		(net "BIC_USB_8042_HUB_XOUT")
	)
	(segment
		(start 3.208528 -383.341118)
		(end 4.114292 -384.246882)
		(width 0.13208)
		(layer "F.Cu")
		(net "BIC_USB_8042_HUB_XOUT")
	)
	(segment
		(start 3.11531 -380.182628)
		(end 3.208528 -380.275846)
		(width 0.13208)
		(layer "F.Cu")
		(net "BIC_USB_8042_HUB_XOUT")
	)
	(segment
		(start 3.11531 -379.80239)
		(end 3.11531 -380.182628)
		(width 0.13208)
		(layer "F.Cu")
		(net "BIC_USB_8042_HUB_XOUT")
	)
	(segment
		(start 2.853436 -379.540516)
		(end 3.11531 -379.80239)
		(width 0.13208)
		(layer "F.Cu")
		(net "BIC_USB_8042_HUB_XOUT")
	)
	(segment
		(start 4.114292 -384.246882)
		(end 5.780024 -384.246882)
		(width 0.13208)
		(layer "F.Cu")
		(net "BIC_USB_8042_HUB_XOUT")
	)
	(segment
		(start 1.91643 -378.477272)
		(end 1.91643 -379.2601)
		(width 0.13208)
		(layer "F.Cu")
		(net "BIC_USB_8042_HUB_XOUT")
	)
	(segment
		(start 2.02311 -378.370592)
		(end 1.91643 -378.477272)
		(width 0.13208)
		(layer "F.Cu")
		(net "BIC_USB_8042_HUB_XOUT")
	)
	(segment
		(start 2.781808 -378.370592)
		(end 2.02311 -378.370592)
		(width 0.13208)
		(layer "F.Cu")
		(net "BIC_USB_8042_HUB_XOUT")
	)
	(segment
		(start 2.562606 -379.540516)
		(end 2.853436 -379.540516)
		(width 0.13208)
		(layer "F.Cu")
		(net "BIC_USB_8042_HUB_XOUT")
	)
	(segment
		(start 2.196846 -379.540516)
		(end 2.562606 -379.540516)
		(width 0.13208)
		(layer "F.Cu")
		(net "BIC_USB_8042_HUB_XOUT")
	)
	(via
		(at 2.562606 -379.540516)
		(size 0.508)
		(drill 0.254)
		(layers "F.Cu" "B.Cu")
		(net "BIC_USB_8042_HUB_XOUT")
	)
	(segment
		(start 4.11861 -380.182628)
		(end 4.11861 -379.62332)
		(width 0.13208)
		(layer "F.Cu")
		(net "BIC_USB_8042_HUB_XIN")
	)
	(segment
		(start 4.008628 -383.313686)
		(end 4.441698 -383.746756)
		(width 0.13208)
		(layer "F.Cu")
		(net "BIC_USB_8042_HUB_XIN")
	)
	(segment
		(start 4.008628 -380.29261)
		(end 4.008628 -381.411226)
		(width 0.13208)
		(layer "F.Cu")
		(net "BIC_USB_8042_HUB_XIN")
	)
	(segment
		(start 4.008628 -381.411226)
		(end 4.008628 -383.313686)
		(width 0.13208)
		(layer "F.Cu")
		(net "BIC_USB_8042_HUB_XIN")
	)
	(segment
		(start 4.11861 -380.182628)
		(end 4.008628 -380.29261)
		(width 0.13208)
		(layer "F.Cu")
		(net "BIC_USB_8042_HUB_XIN")
	)
	(segment
		(start 3.590544 -379.095254)
		(end 4.035806 -379.540516)
		(width 0.13208)
		(layer "F.Cu")
		(net "BIC_USB_8042_HUB_XIN")
	)
	(segment
		(start 4.441698 -383.746756)
		(end 5.780024 -383.746756)
		(width 0.13208)
		(layer "F.Cu")
		(net "BIC_USB_8042_HUB_XIN")
	)
	(segment
		(start 3.590544 -377.061476)
		(end 3.590544 -379.095254)
		(width 0.13208)
		(layer "F.Cu")
		(net "BIC_USB_8042_HUB_XIN")
	)
	(segment
		(start 4.11861 -379.62332)
		(end 4.035806 -379.540516)
		(width 0.13208)
		(layer "F.Cu")
		(net "BIC_USB_8042_HUB_XIN")
	)
	(segment
		(start 4.481576 -376.170444)
		(end 3.590544 -377.061476)
		(width 0.13208)
		(layer "F.Cu")
		(net "BIC_USB_8042_HUB_XIN")
	)
	(via
		(at 4.035806 -379.540516)
		(size 0.508)
		(drill 0.254)
		(layers "F.Cu" "B.Cu")
		(net "BIC_USB_8042_HUB_XIN")
	)
	(segment
		(start 13.464286 -377.588272)
		(end 13.802106 -377.925838)
		(width 0.13462)
		(layer "F.Cu")
		(net "USB2_GPU_HMC_USB8042_DN")
	)
	(segment
		(start 17.440656 -376.845576)
		(end 16.705834 -377.580398)
		(width 0.13462)
		(layer "F.Cu")
		(net "USB2_GPU_HMC_USB8042_DN")
	)
	(segment
		(start 18.410936 -374.16359)
		(end 18.517616 -374.27027)
		(width 0.13462)
		(layer "F.Cu")
		(net "USB2_GPU_HMC_USB8042_DN")
	)
	(segment
		(start 55.17515 -360.795316)
		(end 54.965854 -360.58602)
		(width 0.13462)
		(layer "F.Cu")
		(net "USB2_GPU_HMC_USB8042_DN")
	)
	(segment
		(start 18.410936 -370.68125)
		(end 18.410936 -371.08511)
		(width 0.13462)
		(layer "F.Cu")
		(net "USB2_GPU_HMC_USB8042_DN")
	)
	(segment
		(start 12.36599 -379.532388)
		(end 12.36599 -378.062744)
		(width 0.13462)
		(layer "F.Cu")
		(net "USB2_GPU_HMC_USB8042_DN")
	)
	(segment
		(start 18.517616 -374.67413)
		(end 18.410936 -374.78081)
		(width 0.13462)
		(layer "F.Cu")
		(net "USB2_GPU_HMC_USB8042_DN")
	)
	(segment
		(start 15.442438 -380.052834)
		(end 12.886436 -380.052834)
		(width 0.13462)
		(layer "F.Cu")
		(net "USB2_GPU_HMC_USB8042_DN")
	)
	(segment
		(start 18.410936 -372.73865)
		(end 18.410936 -373.14251)
		(width 0.13462)
		(layer "F.Cu")
		(net "USB2_GPU_HMC_USB8042_DN")
	)
	(segment
		(start 18.410936 -375.875296)
		(end 17.440656 -376.845576)
		(width 0.13462)
		(layer "F.Cu")
		(net "USB2_GPU_HMC_USB8042_DN")
	)
	(segment
		(start 12.843002 -377.585732)
		(end 13.464286 -377.588272)
		(width 0.13462)
		(layer "F.Cu")
		(net "USB2_GPU_HMC_USB8042_DN")
	)
	(segment
		(start 21.315426 -361.64012)
		(end 18.410936 -364.54461)
		(width 0.13462)
		(layer "F.Cu")
		(net "USB2_GPU_HMC_USB8042_DN")
	)
	(segment
		(start 18.410936 -371.71757)
		(end 18.410936 -372.12143)
		(width 0.13462)
		(layer "F.Cu")
		(net "USB2_GPU_HMC_USB8042_DN")
	)
	(segment
		(start 18.525236 -371.19941)
		(end 18.525236 -371.60327)
		(width 0.13462)
		(layer "F.Cu")
		(net "USB2_GPU_HMC_USB8042_DN")
	)
	(segment
		(start 15.962122 -380.572518)
		(end 15.442438 -380.052834)
		(width 0.13462)
		(layer "F.Cu")
		(net "USB2_GPU_HMC_USB8042_DN")
	)
	(segment
		(start 55.17515 -361.079796)
		(end 55.17515 -360.795316)
		(width 0.13462)
		(layer "F.Cu")
		(net "USB2_GPU_HMC_USB8042_DN")
	)
	(segment
		(start 54.404514 -361.850432)
		(end 55.17515 -361.079796)
		(width 0.13462)
		(layer "F.Cu")
		(net "USB2_GPU_HMC_USB8042_DN")
	)
	(segment
		(start 18.517616 -373.24919)
		(end 18.517616 -373.65305)
		(width 0.13462)
		(layer "F.Cu")
		(net "USB2_GPU_HMC_USB8042_DN")
	)
	(segment
		(start 18.410936 -373.14251)
		(end 18.517616 -373.24919)
		(width 0.13462)
		(layer "F.Cu")
		(net "USB2_GPU_HMC_USB8042_DN")
	)
	(segment
		(start 15.68704 -383.119376)
		(end 15.962122 -382.844294)
		(width 0.13462)
		(layer "F.Cu")
		(net "USB2_GPU_HMC_USB8042_DN")
	)
	(segment
		(start 18.410936 -374.78081)
		(end 18.410936 -375.875296)
		(width 0.13462)
		(layer "F.Cu")
		(net "USB2_GPU_HMC_USB8042_DN")
	)
	(segment
		(start 18.410936 -371.08511)
		(end 18.525236 -371.19941)
		(width 0.13462)
		(layer "F.Cu")
		(net "USB2_GPU_HMC_USB8042_DN")
	)
	(segment
		(start 18.548096 -370.54409)
		(end 18.410936 -370.68125)
		(width 0.13462)
		(layer "F.Cu")
		(net "USB2_GPU_HMC_USB8042_DN")
	)
	(segment
		(start 54.965854 -360.58602)
		(end 53.644546 -360.58602)
		(width 0.13462)
		(layer "F.Cu")
		(net "USB2_GPU_HMC_USB8042_DN")
	)
	(segment
		(start 18.410936 -373.75973)
		(end 18.410936 -374.16359)
		(width 0.13462)
		(layer "F.Cu")
		(net "USB2_GPU_HMC_USB8042_DN")
	)
	(segment
		(start 18.525236 -371.60327)
		(end 18.410936 -371.71757)
		(width 0.13462)
		(layer "F.Cu")
		(net "USB2_GPU_HMC_USB8042_DN")
	)
	(segment
		(start 12.36599 -378.062744)
		(end 12.843002 -377.585732)
		(width 0.13462)
		(layer "F.Cu")
		(net "USB2_GPU_HMC_USB8042_DN")
	)
	(segment
		(start 16.705834 -377.580398)
		(end 14.147546 -377.580398)
		(width 0.13462)
		(layer "F.Cu")
		(net "USB2_GPU_HMC_USB8042_DN")
	)
	(segment
		(start 18.517616 -374.27027)
		(end 18.517616 -374.67413)
		(width 0.13462)
		(layer "F.Cu")
		(net "USB2_GPU_HMC_USB8042_DN")
	)
	(segment
		(start 18.517616 -372.22811)
		(end 18.517616 -372.63197)
		(width 0.13462)
		(layer "F.Cu")
		(net "USB2_GPU_HMC_USB8042_DN")
	)
	(segment
		(start 53.644546 -360.58602)
		(end 52.590446 -361.64012)
		(width 0.13462)
		(layer "F.Cu")
		(net "USB2_GPU_HMC_USB8042_DN")
	)
	(segment
		(start 18.410936 -372.12143)
		(end 18.517616 -372.22811)
		(width 0.13462)
		(layer "F.Cu")
		(net "USB2_GPU_HMC_USB8042_DN")
	)
	(segment
		(start 14.147546 -377.580398)
		(end 13.802106 -377.925838)
		(width 0.13462)
		(layer "F.Cu")
		(net "USB2_GPU_HMC_USB8042_DN")
	)
	(segment
		(start 18.410936 -364.54461)
		(end 18.410936 -370.00307)
		(width 0.13462)
		(layer "F.Cu")
		(net "USB2_GPU_HMC_USB8042_DN")
	)
	(segment
		(start 18.517616 -372.63197)
		(end 18.410936 -372.73865)
		(width 0.13462)
		(layer "F.Cu")
		(net "USB2_GPU_HMC_USB8042_DN")
	)
	(segment
		(start 12.886436 -380.052834)
		(end 12.36599 -379.532388)
		(width 0.13462)
		(layer "F.Cu")
		(net "USB2_GPU_HMC_USB8042_DN")
	)
	(segment
		(start 14.580108 -383.246884)
		(end 14.777212 -383.246884)
		(width 0.13462)
		(layer "F.Cu")
		(net "USB2_GPU_HMC_USB8042_DN")
	)
	(segment
		(start 14.90472 -383.119376)
		(end 15.68704 -383.119376)
		(width 0.13462)
		(layer "F.Cu")
		(net "USB2_GPU_HMC_USB8042_DN")
	)
	(segment
		(start 52.590446 -361.64012)
		(end 21.315426 -361.64012)
		(width 0.13462)
		(layer "F.Cu")
		(net "USB2_GPU_HMC_USB8042_DN")
	)
	(segment
		(start 54.404514 -362.180632)
		(end 54.404514 -361.850432)
		(width 0.13462)
		(layer "F.Cu")
		(net "USB2_GPU_HMC_USB8042_DN")
	)
	(segment
		(start 15.962122 -382.844294)
		(end 15.962122 -380.572518)
		(width 0.13462)
		(layer "F.Cu")
		(net "USB2_GPU_HMC_USB8042_DN")
	)
	(segment
		(start 18.410936 -370.00307)
		(end 18.548096 -370.14023)
		(width 0.13462)
		(layer "F.Cu")
		(net "USB2_GPU_HMC_USB8042_DN")
	)
	(segment
		(start 14.777212 -383.246884)
		(end 14.90472 -383.119376)
		(width 0.13462)
		(layer "F.Cu")
		(net "USB2_GPU_HMC_USB8042_DN")
	)
	(segment
		(start 18.517616 -373.65305)
		(end 18.410936 -373.75973)
		(width 0.13462)
		(layer "F.Cu")
		(net "USB2_GPU_HMC_USB8042_DN")
	)
	(segment
		(start 18.548096 -370.14023)
		(end 18.548096 -370.54409)
		(width 0.13462)
		(layer "F.Cu")
		(net "USB2_GPU_HMC_USB8042_DN")
	)
	(via
		(at 17.440656 -376.845576)
		(size 0.4064)
		(drill 0.2032)
		(layers "F.Cu" "B.Cu")
		(net "USB2_GPU_HMC_USB8042_DN")
	)
	(segment
		(start 14.580108 -382.746758)
		(end 14.78915 -382.746758)
		(width 0.13462)
		(layer "F.Cu")
		(net "USB2_GPU_HMC_USB8042_DP")
	)
	(segment
		(start 52.476654 -361.3658)
		(end 53.530754 -360.3117)
		(width 0.13462)
		(layer "F.Cu")
		(net "USB2_GPU_HMC_USB8042_DP")
	)
	(segment
		(start 15.33398 -380.314454)
		(end 12.777978 -380.314454)
		(width 0.13462)
		(layer "F.Cu")
		(net "USB2_GPU_HMC_USB8042_DP")
	)
	(segment
		(start 55.079646 -360.3117)
		(end 55.44947 -360.681524)
		(width 0.13462)
		(layer "F.Cu")
		(net "USB2_GPU_HMC_USB8042_DP")
	)
	(segment
		(start 15.578582 -382.857756)
		(end 15.700502 -382.735836)
		(width 0.13462)
		(layer "F.Cu")
		(net "USB2_GPU_HMC_USB8042_DP")
	)
	(segment
		(start 56.271922 -361.909868)
		(end 56.271922 -362.155994)
		(width 0.13462)
		(layer "F.Cu")
		(net "USB2_GPU_HMC_USB8042_DP")
	)
	(segment
		(start 14.900148 -382.857756)
		(end 15.578582 -382.857756)
		(width 0.13462)
		(layer "F.Cu")
		(net "USB2_GPU_HMC_USB8042_DP")
	)
	(segment
		(start 14.78915 -382.746758)
		(end 14.900148 -382.857756)
		(width 0.13462)
		(layer "F.Cu")
		(net "USB2_GPU_HMC_USB8042_DP")
	)
	(segment
		(start 15.700502 -380.680976)
		(end 15.33398 -380.314454)
		(width 0.13462)
		(layer "F.Cu")
		(net "USB2_GPU_HMC_USB8042_DP")
	)
	(segment
		(start 18.136616 -364.430818)
		(end 21.201634 -361.3658)
		(width 0.13462)
		(layer "F.Cu")
		(net "USB2_GPU_HMC_USB8042_DP")
	)
	(segment
		(start 18.136616 -368.925602)
		(end 18.136616 -364.430818)
		(width 0.13462)
		(layer "F.Cu")
		(net "USB2_GPU_HMC_USB8042_DP")
	)
	(segment
		(start 12.10437 -377.954286)
		(end 12.735052 -377.323604)
		(width 0.13462)
		(layer "F.Cu")
		(net "USB2_GPU_HMC_USB8042_DP")
	)
	(segment
		(start 18.136616 -368.925602)
		(end 18.136616 -375.761504)
		(width 0.13462)
		(layer "F.Cu")
		(net "USB2_GPU_HMC_USB8042_DP")
	)
	(segment
		(start 16.592042 -377.306078)
		(end 14.1859 -377.306078)
		(width 0.13462)
		(layer "F.Cu")
		(net "USB2_GPU_HMC_USB8042_DP")
	)
	(segment
		(start 15.700502 -382.735836)
		(end 15.700502 -380.680976)
		(width 0.13462)
		(layer "F.Cu")
		(net "USB2_GPU_HMC_USB8042_DP")
	)
	(segment
		(start 14.1859 -377.306078)
		(end 13.805154 -376.925332)
		(width 0.13462)
		(layer "F.Cu")
		(net "USB2_GPU_HMC_USB8042_DP")
	)
	(segment
		(start 53.530754 -360.3117)
		(end 55.079646 -360.3117)
		(width 0.13462)
		(layer "F.Cu")
		(net "USB2_GPU_HMC_USB8042_DP")
	)
	(segment
		(start 13.404342 -377.326144)
		(end 13.805154 -376.925332)
		(width 0.13462)
		(layer "F.Cu")
		(net "USB2_GPU_HMC_USB8042_DP")
	)
	(segment
		(start 12.777978 -380.314454)
		(end 12.10437 -379.640846)
		(width 0.13462)
		(layer "F.Cu")
		(net "USB2_GPU_HMC_USB8042_DP")
	)
	(segment
		(start 12.10437 -379.640846)
		(end 12.10437 -377.954286)
		(width 0.13462)
		(layer "F.Cu")
		(net "USB2_GPU_HMC_USB8042_DP")
	)
	(segment
		(start 18.136616 -375.761504)
		(end 16.592042 -377.306078)
		(width 0.13462)
		(layer "F.Cu")
		(net "USB2_GPU_HMC_USB8042_DP")
	)
	(segment
		(start 21.201634 -361.3658)
		(end 52.476654 -361.3658)
		(width 0.13462)
		(layer "F.Cu")
		(net "USB2_GPU_HMC_USB8042_DP")
	)
	(segment
		(start 55.44947 -360.681524)
		(end 55.44947 -361.087416)
		(width 0.13462)
		(layer "F.Cu")
		(net "USB2_GPU_HMC_USB8042_DP")
	)
	(segment
		(start 55.44947 -361.087416)
		(end 56.271922 -361.909868)
		(width 0.13462)
		(layer "F.Cu")
		(net "USB2_GPU_HMC_USB8042_DP")
	)
	(segment
		(start 12.735052 -377.323604)
		(end 13.404342 -377.326144)
		(width 0.13462)
		(layer "F.Cu")
		(net "USB2_GPU_HMC_USB8042_DP")
	)
	(via
		(at 18.136616 -368.925602)
		(size 0.4064)
		(drill 0.2032)
		(layers "F.Cu" "B.Cu")
		(net "USB2_GPU_HMC_USB8042_DP")
	)
	(segment
		(start 103.536242 -375.624344)
		(end 103.536242 -374.171718)
		(width 0.13462)
		(layer "F.Cu")
		(net "USB2_BIC_USB8042_DN")
	)
	(segment
		(start 10.930128 -381.889762)
		(end 10.930128 -382.096772)
		(width 0.13462)
		(layer "F.Cu")
		(net "USB2_BIC_USB8042_DN")
	)
	(segment
		(start 105.760266 -368.884454)
		(end 105.760266 -367.223802)
		(width 0.13462)
		(layer "F.Cu")
		(net "USB2_BIC_USB8042_DN")
	)
	(segment
		(start 104.29494 -376.383042)
		(end 104.144064 -376.383042)
		(width 0.13462)
		(layer "F.Cu")
		(net "USB2_BIC_USB8042_DN")
	)
	(segment
		(start 104.517698 -379.723396)
		(end 104.517698 -379.3363)
		(width 0.13462)
		(layer "F.Cu")
		(net "USB2_BIC_USB8042_DN")
	)
	(segment
		(start 9.070086 -377.145042)
		(end 9.070086 -377.295918)
		(width 0.13462)
		(layer "F.Cu")
		(net "USB2_BIC_USB8042_DN")
	)
	(segment
		(start 57.469532 -358.311958)
		(end 52.788312 -358.311958)
		(width 0.13462)
		(layer "F.Cu")
		(net "USB2_BIC_USB8042_DN")
	)
	(segment
		(start 103.560118 -365.023654)
		(end 100.090224 -365.023654)
		(width 0.13462)
		(layer "F.Cu")
		(net "USB2_BIC_USB8042_DN")
	)
	(segment
		(start 10.22858 -378.303536)
		(end 10.51433 -378.589286)
		(width 0.13462)
		(layer "F.Cu")
		(net "USB2_BIC_USB8042_DN")
	)
	(segment
		(start 105.760266 -369.905534)
		(end 105.760266 -369.501674)
		(width 0.13462)
		(layer "F.Cu")
		(net "USB2_BIC_USB8042_DN")
	)
	(segment
		(start 105.391204 -377.479306)
		(end 105.017062 -377.105164)
		(width 0.13462)
		(layer "F.Cu")
		(net "USB2_BIC_USB8042_DN")
	)
	(segment
		(start 104.144064 -376.383042)
		(end 103.858314 -376.097292)
		(width 0.13462)
		(layer "F.Cu")
		(net "USB2_BIC_USB8042_DN")
	)
	(segment
		(start 10.799826 -379.025658)
		(end 10.799826 -381.75946)
		(width 0.13462)
		(layer "F.Cu")
		(net "USB2_BIC_USB8042_DN")
	)
	(segment
		(start 9.355582 -377.581414)
		(end 9.506458 -377.581414)
		(width 0.13462)
		(layer "F.Cu")
		(net "USB2_BIC_USB8042_DN")
	)
	(segment
		(start 105.760266 -371.543834)
		(end 105.653586 -371.437154)
		(width 0.13462)
		(layer "F.Cu")
		(net "USB2_BIC_USB8042_DN")
	)
	(segment
		(start 105.653586 -371.033294)
		(end 105.760266 -370.926614)
		(width 0.13462)
		(layer "F.Cu")
		(net "USB2_BIC_USB8042_DN")
	)
	(segment
		(start 104.517698 -379.3363)
		(end 105.391204 -378.462794)
		(width 0.13462)
		(layer "F.Cu")
		(net "USB2_BIC_USB8042_DN")
	)
	(segment
		(start 104.580436 -376.668538)
		(end 104.29494 -376.383042)
		(width 0.13462)
		(layer "F.Cu")
		(net "USB2_BIC_USB8042_DN")
	)
	(segment
		(start 8.784336 -376.859292)
		(end 9.070086 -377.145042)
		(width 0.13462)
		(layer "F.Cu")
		(net "USB2_BIC_USB8042_DN")
	)
	(segment
		(start 104.866186 -377.105164)
		(end 104.580436 -376.819414)
		(width 0.13462)
		(layer "F.Cu")
		(net "USB2_BIC_USB8042_DN")
	)
	(segment
		(start 103.858314 -376.097292)
		(end 103.858314 -375.946416)
		(width 0.13462)
		(layer "F.Cu")
		(net "USB2_BIC_USB8042_DN")
	)
	(segment
		(start 105.653586 -368.991134)
		(end 105.760266 -368.884454)
		(width 0.13462)
		(layer "F.Cu")
		(net "USB2_BIC_USB8042_DN")
	)
	(segment
		(start 105.653586 -370.416074)
		(end 105.653586 -370.012214)
		(width 0.13462)
		(layer "F.Cu")
		(net "USB2_BIC_USB8042_DN")
	)
	(segment
		(start 105.760266 -367.223802)
		(end 103.560118 -365.023654)
		(width 0.13462)
		(layer "F.Cu")
		(net "USB2_BIC_USB8042_DN")
	)
	(segment
		(start 105.760266 -371.947694)
		(end 105.760266 -371.543834)
		(width 0.13462)
		(layer "F.Cu")
		(net "USB2_BIC_USB8042_DN")
	)
	(segment
		(start 58.56732 -359.409746)
		(end 57.469532 -358.311958)
		(width 0.13462)
		(layer "F.Cu")
		(net "USB2_BIC_USB8042_DN")
	)
	(segment
		(start 10.077704 -378.303536)
		(end 10.22858 -378.303536)
		(width 0.13462)
		(layer "F.Cu")
		(net "USB2_BIC_USB8042_DN")
	)
	(segment
		(start 103.858314 -375.946416)
		(end 103.536242 -375.624344)
		(width 0.13462)
		(layer "F.Cu")
		(net "USB2_BIC_USB8042_DN")
	)
	(segment
		(start 9.792208 -377.867164)
		(end 9.792208 -378.01804)
		(width 0.13462)
		(layer "F.Cu")
		(net "USB2_BIC_USB8042_DN")
	)
	(segment
		(start 103.536242 -374.171718)
		(end 105.760266 -371.947694)
		(width 0.13462)
		(layer "F.Cu")
		(net "USB2_BIC_USB8042_DN")
	)
	(segment
		(start 9.792208 -378.01804)
		(end 10.077704 -378.303536)
		(width 0.13462)
		(layer "F.Cu")
		(net "USB2_BIC_USB8042_DN")
	)
	(segment
		(start 100.090224 -365.023654)
		(end 94.476316 -359.409746)
		(width 0.13462)
		(layer "F.Cu")
		(net "USB2_BIC_USB8042_DN")
	)
	(segment
		(start 8.032242 -376.258074)
		(end 8.63346 -376.859292)
		(width 0.13462)
		(layer "F.Cu")
		(net "USB2_BIC_USB8042_DN")
	)
	(segment
		(start 105.653586 -369.394994)
		(end 105.653586 -368.991134)
		(width 0.13462)
		(layer "F.Cu")
		(net "USB2_BIC_USB8042_DN")
	)
	(segment
		(start 104.580436 -376.819414)
		(end 104.580436 -376.668538)
		(width 0.13462)
		(layer "F.Cu")
		(net "USB2_BIC_USB8042_DN")
	)
	(segment
		(start 9.506458 -377.581414)
		(end 9.792208 -377.867164)
		(width 0.13462)
		(layer "F.Cu")
		(net "USB2_BIC_USB8042_DN")
	)
	(segment
		(start 51.94935 -359.15092)
		(end 19.493992 -359.15092)
		(width 0.13462)
		(layer "F.Cu")
		(net "USB2_BIC_USB8042_DN")
	)
	(segment
		(start 8.032242 -370.61267)
		(end 8.032242 -371.719602)
		(width 0.13462)
		(layer "F.Cu")
		(net "USB2_BIC_USB8042_DN")
	)
	(segment
		(start 52.788312 -358.311958)
		(end 51.94935 -359.15092)
		(width 0.13462)
		(layer "F.Cu")
		(net "USB2_BIC_USB8042_DN")
	)
	(segment
		(start 105.017062 -377.105164)
		(end 104.866186 -377.105164)
		(width 0.13462)
		(layer "F.Cu")
		(net "USB2_BIC_USB8042_DN")
	)
	(segment
		(start 105.653586 -371.437154)
		(end 105.653586 -371.033294)
		(width 0.13462)
		(layer "F.Cu")
		(net "USB2_BIC_USB8042_DN")
	)
	(segment
		(start 8.63346 -376.859292)
		(end 8.784336 -376.859292)
		(width 0.13462)
		(layer "F.Cu")
		(net "USB2_BIC_USB8042_DN")
	)
	(segment
		(start 105.653586 -370.012214)
		(end 105.760266 -369.905534)
		(width 0.13462)
		(layer "F.Cu")
		(net "USB2_BIC_USB8042_DN")
	)
	(segment
		(start 105.391204 -378.462794)
		(end 105.391204 -377.479306)
		(width 0.13462)
		(layer "F.Cu")
		(net "USB2_BIC_USB8042_DN")
	)
	(segment
		(start 9.070086 -377.295918)
		(end 9.355582 -377.581414)
		(width 0.13462)
		(layer "F.Cu")
		(net "USB2_BIC_USB8042_DN")
	)
	(segment
		(start 10.51433 -378.740162)
		(end 10.799826 -379.025658)
		(width 0.13462)
		(layer "F.Cu")
		(net "USB2_BIC_USB8042_DN")
	)
	(segment
		(start 19.493992 -359.15092)
		(end 8.032242 -370.61267)
		(width 0.13462)
		(layer "F.Cu")
		(net "USB2_BIC_USB8042_DN")
	)
	(segment
		(start 94.476316 -359.409746)
		(end 58.56732 -359.409746)
		(width 0.13462)
		(layer "F.Cu")
		(net "USB2_BIC_USB8042_DN")
	)
	(segment
		(start 10.51433 -378.589286)
		(end 10.51433 -378.740162)
		(width 0.13462)
		(layer "F.Cu")
		(net "USB2_BIC_USB8042_DN")
	)
	(segment
		(start 105.760266 -369.501674)
		(end 105.653586 -369.394994)
		(width 0.13462)
		(layer "F.Cu")
		(net "USB2_BIC_USB8042_DN")
	)
	(segment
		(start 8.032242 -371.719602)
		(end 8.032242 -376.258074)
		(width 0.13462)
		(layer "F.Cu")
		(net "USB2_BIC_USB8042_DN")
	)
	(segment
		(start 10.799826 -381.75946)
		(end 10.930128 -381.889762)
		(width 0.13462)
		(layer "F.Cu")
		(net "USB2_BIC_USB8042_DN")
	)
	(segment
		(start 105.760266 -370.522754)
		(end 105.653586 -370.416074)
		(width 0.13462)
		(layer "F.Cu")
		(net "USB2_BIC_USB8042_DN")
	)
	(segment
		(start 105.760266 -370.926614)
		(end 105.760266 -370.522754)
		(width 0.13462)
		(layer "F.Cu")
		(net "USB2_BIC_USB8042_DN")
	)
	(via
		(at 8.032242 -371.719602)
		(size 0.4064)
		(drill 0.2032)
		(layers "F.Cu" "B.Cu")
		(net "USB2_BIC_USB8042_DN")
	)
	(segment
		(start 106.385106 -379.222508)
		(end 106.385106 -379.698758)
		(width 0.13462)
		(layer "F.Cu")
		(net "USB2_BIC_USB8042_DP")
	)
	(segment
		(start 10.430002 -381.86741)
		(end 10.430002 -382.096772)
		(width 0.13462)
		(layer "F.Cu")
		(net "USB2_BIC_USB8042_DP")
	)
	(segment
		(start 10.538206 -381.759206)
		(end 10.430002 -381.86741)
		(width 0.13462)
		(layer "F.Cu")
		(net "USB2_BIC_USB8042_DP")
	)
	(segment
		(start 10.529316 -379.143006)
		(end 10.538206 -379.134116)
		(width 0.13462)
		(layer "F.Cu")
		(net "USB2_BIC_USB8042_DP")
	)
	(segment
		(start 7.757922 -370.498878)
		(end 19.3802 -358.8766)
		(width 0.13462)
		(layer "F.Cu")
		(net "USB2_BIC_USB8042_DP")
	)
	(segment
		(start 10.538206 -379.134116)
		(end 10.538206 -381.759206)
		(width 0.13462)
		(layer "F.Cu")
		(net "USB2_BIC_USB8042_DP")
	)
	(segment
		(start 58.675778 -359.148126)
		(end 94.584774 -359.148126)
		(width 0.13462)
		(layer "F.Cu")
		(net "USB2_BIC_USB8042_DP")
	)
	(segment
		(start 7.757922 -375.738136)
		(end 7.757922 -376.371866)
		(width 0.13462)
		(layer "F.Cu")
		(net "USB2_BIC_USB8042_DP")
	)
	(segment
		(start 7.757922 -376.371866)
		(end 10.529316 -379.14326)
		(width 0.13462)
		(layer "F.Cu")
		(net "USB2_BIC_USB8042_DP")
	)
	(segment
		(start 100.198682 -364.762034)
		(end 103.668576 -364.762034)
		(width 0.13462)
		(layer "F.Cu")
		(net "USB2_BIC_USB8042_DP")
	)
	(segment
		(start 105.652824 -377.370848)
		(end 105.652824 -378.490226)
		(width 0.13462)
		(layer "F.Cu")
		(net "USB2_BIC_USB8042_DP")
	)
	(segment
		(start 52.67452 -358.037638)
		(end 57.56529 -358.037638)
		(width 0.13462)
		(layer "F.Cu")
		(net "USB2_BIC_USB8042_DP")
	)
	(segment
		(start 106.021886 -367.115344)
		(end 106.021886 -372.056152)
		(width 0.13462)
		(layer "F.Cu")
		(net "USB2_BIC_USB8042_DP")
	)
	(segment
		(start 106.021886 -372.056152)
		(end 103.797862 -374.280176)
		(width 0.13462)
		(layer "F.Cu")
		(net "USB2_BIC_USB8042_DP")
	)
	(segment
		(start 103.797862 -374.280176)
		(end 103.797862 -375.515886)
		(width 0.13462)
		(layer "F.Cu")
		(net "USB2_BIC_USB8042_DP")
	)
	(segment
		(start 103.797862 -375.515886)
		(end 105.652824 -377.370848)
		(width 0.13462)
		(layer "F.Cu")
		(net "USB2_BIC_USB8042_DP")
	)
	(segment
		(start 94.584774 -359.148126)
		(end 100.198682 -364.762034)
		(width 0.13462)
		(layer "F.Cu")
		(net "USB2_BIC_USB8042_DP")
	)
	(segment
		(start 51.835558 -358.8766)
		(end 52.67452 -358.037638)
		(width 0.13462)
		(layer "F.Cu")
		(net "USB2_BIC_USB8042_DP")
	)
	(segment
		(start 10.529316 -379.14326)
		(end 10.529316 -379.143006)
		(width 0.13462)
		(layer "F.Cu")
		(net "USB2_BIC_USB8042_DP")
	)
	(segment
		(start 7.757922 -375.738136)
		(end 7.757922 -370.498878)
		(width 0.13462)
		(layer "F.Cu")
		(net "USB2_BIC_USB8042_DP")
	)
	(segment
		(start 57.56529 -358.037638)
		(end 58.675778 -359.148126)
		(width 0.13462)
		(layer "F.Cu")
		(net "USB2_BIC_USB8042_DP")
	)
	(segment
		(start 105.652824 -378.490226)
		(end 106.385106 -379.222508)
		(width 0.13462)
		(layer "F.Cu")
		(net "USB2_BIC_USB8042_DP")
	)
	(segment
		(start 103.668576 -364.762034)
		(end 106.021886 -367.115344)
		(width 0.13462)
		(layer "F.Cu")
		(net "USB2_BIC_USB8042_DP")
	)
	(segment
		(start 19.3802 -358.8766)
		(end 51.835558 -358.8766)
		(width 0.13462)
		(layer "F.Cu")
		(net "USB2_BIC_USB8042_DP")
	)
	(via
		(at 7.757922 -375.738136)
		(size 0.4064)
		(drill 0.2032)
		(layers "F.Cu" "B.Cu")
		(net "USB2_BIC_USB8042_DP")
	)
	(segment
		(start 56.915304 -359.468166)
		(end 57.949338 -360.5022)
		(width 0.13462)
		(layer "F.Cu")
		(net "USB2_MB_BMC_USB8042_DN")
	)
	(segment
		(start 99.97948 -384.157474)
		(end 99.97948 -384.377692)
		(width 0.13462)
		(layer "F.Cu")
		(net "USB2_MB_BMC_USB8042_DN")
	)
	(segment
		(start 2.32918 -387.811772)
		(end 2.617216 -387.811772)
		(width 0.13462)
		(layer "F.Cu")
		(net "USB2_MB_BMC_USB8042_DN")
	)
	(segment
		(start 102.265988 -381.458216)
		(end 100.807774 -382.91643)
		(width 0.13462)
		(layer "F.Cu")
		(net "USB2_MB_BMC_USB8042_DN")
	)
	(segment
		(start 2.327148 -387.810756)
		(end 2.328164 -387.810756)
		(width 0.13462)
		(layer "F.Cu")
		(net "USB2_MB_BMC_USB8042_DN")
	)
	(segment
		(start 99.350068 -365.933482)
		(end 99.511612 -365.933482)
		(width 0.13462)
		(layer "F.Cu")
		(net "USB2_MB_BMC_USB8042_DN")
	)
	(segment
		(start 5.780024 -387.746748)
		(end 5.563616 -387.746748)
		(width 0.13462)
		(layer "F.Cu")
		(net "USB2_MB_BMC_USB8042_DN")
	)
	(segment
		(start 94.701868 -361.285282)
		(end 94.863412 -361.285282)
		(width 0.13462)
		(layer "F.Cu")
		(net "USB2_MB_BMC_USB8042_DN")
	)
	(segment
		(start 52.453794 -360.19486)
		(end 53.180488 -359.468166)
		(width 0.13462)
		(layer "F.Cu")
		(net "USB2_MB_BMC_USB8042_DN")
	)
	(segment
		(start 94.416118 -360.999532)
		(end 94.701868 -361.285282)
		(width 0.13462)
		(layer "F.Cu")
		(net "USB2_MB_BMC_USB8042_DN")
	)
	(segment
		(start 100.807774 -382.91643)
		(end 100.807774 -383.32918)
		(width 0.13462)
		(layer "F.Cu")
		(net "USB2_MB_BMC_USB8042_DN")
	)
	(segment
		(start 101.370892 -367.792762)
		(end 101.370892 -370.37645)
		(width 0.13462)
		(layer "F.Cu")
		(net "USB2_MB_BMC_USB8042_DN")
	)
	(segment
		(start 97.061782 -363.483652)
		(end 99.064318 -365.486188)
		(width 0.13462)
		(layer "F.Cu")
		(net "USB2_MB_BMC_USB8042_DN")
	)
	(segment
		(start 101.370892 -373.181372)
		(end 102.265988 -374.076468)
		(width 0.13462)
		(layer "F.Cu")
		(net "USB2_MB_BMC_USB8042_DN")
	)
	(segment
		(start 101.370892 -371.41277)
		(end 101.256592 -371.52707)
		(width 0.13462)
		(layer "F.Cu")
		(net "USB2_MB_BMC_USB8042_DN")
	)
	(segment
		(start 16.317468 -364.28426)
		(end 20.406868 -360.19486)
		(width 0.13462)
		(layer "F.Cu")
		(net "USB2_MB_BMC_USB8042_DN")
	)
	(segment
		(start 57.949338 -360.5022)
		(end 94.08033 -360.5022)
		(width 0.13462)
		(layer "F.Cu")
		(net "USB2_MB_BMC_USB8042_DN")
	)
	(segment
		(start 95.596202 -362.018072)
		(end 95.881698 -362.303568)
		(width 0.13462)
		(layer "F.Cu")
		(net "USB2_MB_BMC_USB8042_DN")
	)
	(segment
		(start 94.08033 -360.5022)
		(end 94.416118 -360.837988)
		(width 0.13462)
		(layer "F.Cu")
		(net "USB2_MB_BMC_USB8042_DN")
	)
	(segment
		(start 99.797108 -366.380522)
		(end 100.082858 -366.666272)
		(width 0.13462)
		(layer "F.Cu")
		(net "USB2_MB_BMC_USB8042_DN")
	)
	(segment
		(start 101.256592 -371.52707)
		(end 101.256592 -371.93093)
		(width 0.13462)
		(layer "F.Cu")
		(net "USB2_MB_BMC_USB8042_DN")
	)
	(segment
		(start 101.256592 -370.49075)
		(end 101.256592 -370.89461)
		(width 0.13462)
		(layer "F.Cu")
		(net "USB2_MB_BMC_USB8042_DN")
	)
	(segment
		(start 96.614488 -363.036358)
		(end 96.614488 -363.197902)
		(width 0.13462)
		(layer "F.Cu")
		(net "USB2_MB_BMC_USB8042_DN")
	)
	(segment
		(start 2.027682 -387.51129)
		(end 2.327148 -387.810756)
		(width 0.13462)
		(layer "F.Cu")
		(net "USB2_MB_BMC_USB8042_DN")
	)
	(segment
		(start 2.328164 -387.810756)
		(end 2.32918 -387.811772)
		(width 0.13462)
		(layer "F.Cu")
		(net "USB2_MB_BMC_USB8042_DN")
	)
	(segment
		(start 5.563616 -387.746748)
		(end 5.437378 -387.872986)
		(width 0.13462)
		(layer "F.Cu")
		(net "USB2_MB_BMC_USB8042_DN")
	)
	(segment
		(start 96.328992 -362.750862)
		(end 96.614488 -363.036358)
		(width 0.13462)
		(layer "F.Cu")
		(net "USB2_MB_BMC_USB8042_DN")
	)
	(segment
		(start 94.863412 -361.285282)
		(end 95.148908 -361.570778)
		(width 0.13462)
		(layer "F.Cu")
		(net "USB2_MB_BMC_USB8042_DN")
	)
	(segment
		(start 95.434658 -362.018072)
		(end 95.596202 -362.018072)
		(width 0.13462)
		(layer "F.Cu")
		(net "USB2_MB_BMC_USB8042_DN")
	)
	(segment
		(start 96.900238 -363.483652)
		(end 97.061782 -363.483652)
		(width 0.13462)
		(layer "F.Cu")
		(net "USB2_MB_BMC_USB8042_DN")
	)
	(segment
		(start 2.617216 -387.811772)
		(end 2.989072 -387.438392)
		(width 0.13462)
		(layer "F.Cu")
		(net "USB2_MB_BMC_USB8042_DN")
	)
	(segment
		(start 94.416118 -360.837988)
		(end 94.416118 -360.999532)
		(width 0.13462)
		(layer "F.Cu")
		(net "USB2_MB_BMC_USB8042_DN")
	)
	(segment
		(start 20.406868 -360.19486)
		(end 52.453794 -360.19486)
		(width 0.13462)
		(layer "F.Cu")
		(net "USB2_MB_BMC_USB8042_DN")
	)
	(segment
		(start 9.96315 -372.07063)
		(end 9.67486 -371.78234)
		(width 0.13462)
		(layer "F.Cu")
		(net "USB2_MB_BMC_USB8042_DN")
	)
	(segment
		(start 95.148908 -361.570778)
		(end 95.148908 -361.732322)
		(width 0.13462)
		(layer "F.Cu")
		(net "USB2_MB_BMC_USB8042_DN")
	)
	(segment
		(start 99.064318 -365.486188)
		(end 99.064318 -365.647732)
		(width 0.13462)
		(layer "F.Cu")
		(net "USB2_MB_BMC_USB8042_DN")
	)
	(segment
		(start 99.511612 -365.933482)
		(end 99.797108 -366.218978)
		(width 0.13462)
		(layer "F.Cu")
		(net "USB2_MB_BMC_USB8042_DN")
	)
	(segment
		(start 95.148908 -361.732322)
		(end 95.434658 -362.018072)
		(width 0.13462)
		(layer "F.Cu")
		(net "USB2_MB_BMC_USB8042_DN")
	)
	(segment
		(start 96.614488 -363.197902)
		(end 96.900238 -363.483652)
		(width 0.13462)
		(layer "F.Cu")
		(net "USB2_MB_BMC_USB8042_DN")
	)
	(segment
		(start 100.082858 -366.666272)
		(end 100.244402 -366.666272)
		(width 0.13462)
		(layer "F.Cu")
		(net "USB2_MB_BMC_USB8042_DN")
	)
	(segment
		(start 95.881698 -362.465112)
		(end 96.167448 -362.750862)
		(width 0.13462)
		(layer "F.Cu")
		(net "USB2_MB_BMC_USB8042_DN")
	)
	(segment
		(start 100.244402 -366.666272)
		(end 101.370892 -367.792762)
		(width 0.13462)
		(layer "F.Cu")
		(net "USB2_MB_BMC_USB8042_DN")
	)
	(segment
		(start 99.797108 -366.218978)
		(end 99.797108 -366.380522)
		(width 0.13462)
		(layer "F.Cu")
		(net "USB2_MB_BMC_USB8042_DN")
	)
	(segment
		(start 101.256592 -370.89461)
		(end 101.370892 -371.00891)
		(width 0.13462)
		(layer "F.Cu")
		(net "USB2_MB_BMC_USB8042_DN")
	)
	(segment
		(start 9.67486 -370.926868)
		(end 16.317468 -364.28426)
		(width 0.13462)
		(layer "F.Cu")
		(net "USB2_MB_BMC_USB8042_DN")
	)
	(segment
		(start 53.180488 -359.468166)
		(end 56.915304 -359.468166)
		(width 0.13462)
		(layer "F.Cu")
		(net "USB2_MB_BMC_USB8042_DN")
	)
	(segment
		(start 102.265988 -374.076468)
		(end 102.265988 -381.458216)
		(width 0.13462)
		(layer "F.Cu")
		(net "USB2_MB_BMC_USB8042_DN")
	)
	(segment
		(start 101.256592 -371.93093)
		(end 101.370892 -372.04523)
		(width 0.13462)
		(layer "F.Cu")
		(net "USB2_MB_BMC_USB8042_DN")
	)
	(segment
		(start 101.370892 -370.37645)
		(end 101.256592 -370.49075)
		(width 0.13462)
		(layer "F.Cu")
		(net "USB2_MB_BMC_USB8042_DN")
	)
	(segment
		(start 100.807774 -383.32918)
		(end 99.97948 -384.157474)
		(width 0.13462)
		(layer "F.Cu")
		(net "USB2_MB_BMC_USB8042_DN")
	)
	(segment
		(start 101.370892 -372.04523)
		(end 101.370892 -373.181372)
		(width 0.13462)
		(layer "F.Cu")
		(net "USB2_MB_BMC_USB8042_DN")
	)
	(segment
		(start 96.167448 -362.750862)
		(end 96.328992 -362.750862)
		(width 0.13462)
		(layer "F.Cu")
		(net "USB2_MB_BMC_USB8042_DN")
	)
	(segment
		(start 9.67486 -371.78234)
		(end 9.67486 -370.926868)
		(width 0.13462)
		(layer "F.Cu")
		(net "USB2_MB_BMC_USB8042_DN")
	)
	(segment
		(start 5.437378 -387.872986)
		(end 4.557268 -387.872986)
		(width 0.13462)
		(layer "F.Cu")
		(net "USB2_MB_BMC_USB8042_DN")
	)
	(segment
		(start 4.276852 -387.873748)
		(end 3.424428 -387.873748)
		(width 0.13462)
		(layer "F.Cu")
		(net "USB2_MB_BMC_USB8042_DN")
	)
	(segment
		(start 101.370892 -371.00891)
		(end 101.370892 -371.41277)
		(width 0.13462)
		(layer "F.Cu")
		(net "USB2_MB_BMC_USB8042_DN")
	)
	(segment
		(start 3.424428 -387.873748)
		(end 2.989072 -387.438392)
		(width 0.13462)
		(layer "F.Cu")
		(net "USB2_MB_BMC_USB8042_DN")
	)
	(segment
		(start 95.881698 -362.303568)
		(end 95.881698 -362.465112)
		(width 0.13462)
		(layer "F.Cu")
		(net "USB2_MB_BMC_USB8042_DN")
	)
	(segment
		(start 4.557268 -387.872986)
		(end 4.276852 -387.873748)
		(width 0.13462)
		(layer "F.Cu")
		(net "USB2_MB_BMC_USB8042_DN")
	)
	(segment
		(start 99.064318 -365.647732)
		(end 99.350068 -365.933482)
		(width 0.13462)
		(layer "F.Cu")
		(net "USB2_MB_BMC_USB8042_DN")
	)
	(via
		(at 16.317468 -364.28426)
		(size 0.4064)
		(drill 0.2032)
		(layers "F.Cu" "B.Cu")
		(net "USB2_MB_BMC_USB8042_DN")
	)
	(segment
		(start 7.375906 -380.512828)
		(end 7.375906 -380.336806)
		(width 0.1651)
		(layer "In9.Cu")
		(net "USB2_MB_BMC_USB8042_DN")
	)
	(segment
		(start 13.495782 -372.970806)
		(end 13.620242 -372.846346)
		(width 0.1651)
		(layer "In9.Cu")
		(net "USB2_MB_BMC_USB8042_DN")
	)
	(segment
		(start 9.768586 -377.944126)
		(end 10.079482 -377.63323)
		(width 0.1651)
		(layer "In9.Cu")
		(net "USB2_MB_BMC_USB8042_DN")
	)
	(segment
		(start 12.472162 -375.24055)
		(end 12.648184 -375.24055)
		(width 0.1651)
		(layer "In9.Cu")
		(net "USB2_MB_BMC_USB8042_DN")
	)
	(segment
		(start 9.66851 -371.77599)
		(end 9.96315 -372.07063)
		(width 0.1651)
		(layer "In9.Cu")
		(net "USB2_MB_BMC_USB8042_DN")
	)
	(segment
		(start 12.008866 -371.199918)
		(end 11.569446 -371.199918)
		(width 0.1651)
		(layer "In9.Cu")
		(net "USB2_MB_BMC_USB8042_DN")
	)
	(segment
		(start 13.620242 -374.268492)
		(end 13.620242 -373.534686)
		(width 0.1651)
		(layer "In9.Cu")
		(net "USB2_MB_BMC_USB8042_DN")
	)
	(segment
		(start 7.065264 -382.861566)
		(end 6.940804 -382.737106)
		(width 0.1651)
		(layer "In9.Cu")
		(net "USB2_MB_BMC_USB8042_DN")
	)
	(segment
		(start 10.877042 -376.83567)
		(end 11.053064 -376.83567)
		(width 0.1651)
		(layer "In9.Cu")
		(net "USB2_MB_BMC_USB8042_DN")
	)
	(segment
		(start 6.940804 -385.18465)
		(end 6.940804 -384.74523)
		(width 0.1651)
		(layer "In9.Cu")
		(net "USB2_MB_BMC_USB8042_DN")
	)
	(segment
		(start 8.660384 -379.22835)
		(end 8.971026 -378.917708)
		(width 0.1651)
		(layer "In9.Cu")
		(net "USB2_MB_BMC_USB8042_DN")
	)
	(segment
		(start 6.186678 -386.583174)
		(end 6.497828 -386.272024)
		(width 0.1651)
		(layer "In9.Cu")
		(net "USB2_MB_BMC_USB8042_DN")
	)
	(segment
		(start 7.065264 -383.49301)
		(end 7.065264 -382.861566)
		(width 0.1651)
		(layer "In9.Cu")
		(net "USB2_MB_BMC_USB8042_DN")
	)
	(segment
		(start 10.079482 -377.63323)
		(end 10.255504 -377.63323)
		(width 0.1651)
		(layer "In9.Cu")
		(net "USB2_MB_BMC_USB8042_DN")
	)
	(segment
		(start 8.971026 -378.741686)
		(end 9.281922 -378.43079)
		(width 0.1651)
		(layer "In9.Cu")
		(net "USB2_MB_BMC_USB8042_DN")
	)
	(segment
		(start 11.674602 -376.03811)
		(end 11.850624 -376.03811)
		(width 0.1651)
		(layer "In9.Cu")
		(net "USB2_MB_BMC_USB8042_DN")
	)
	(segment
		(start 12.161266 -375.727468)
		(end 12.161266 -375.551446)
		(width 0.1651)
		(layer "In9.Cu")
		(net "USB2_MB_BMC_USB8042_DN")
	)
	(segment
		(start 13.620242 -371.884194)
		(end 12.811506 -371.075458)
		(width 0.1651)
		(layer "In9.Cu")
		(net "USB2_MB_BMC_USB8042_DN")
	)
	(segment
		(start 12.648184 -375.24055)
		(end 13.620242 -374.268492)
		(width 0.1651)
		(layer "In9.Cu")
		(net "USB2_MB_BMC_USB8042_DN")
	)
	(segment
		(start 7.065264 -380.82347)
		(end 7.375906 -380.512828)
		(width 0.1651)
		(layer "In9.Cu")
		(net "USB2_MB_BMC_USB8042_DN")
	)
	(segment
		(start 12.811506 -371.075458)
		(end 12.133326 -371.075458)
		(width 0.1651)
		(layer "In9.Cu")
		(net "USB2_MB_BMC_USB8042_DN")
	)
	(segment
		(start 6.940804 -384.05689)
		(end 6.940804 -383.61747)
		(width 0.1651)
		(layer "In9.Cu")
		(net "USB2_MB_BMC_USB8042_DN")
	)
	(segment
		(start 12.133326 -371.075458)
		(end 12.008866 -371.199918)
		(width 0.1651)
		(layer "In9.Cu")
		(net "USB2_MB_BMC_USB8042_DN")
	)
	(segment
		(start 8.173466 -379.539246)
		(end 8.484362 -379.22835)
		(width 0.1651)
		(layer "In9.Cu")
		(net "USB2_MB_BMC_USB8042_DN")
	)
	(segment
		(start 6.940804 -383.61747)
		(end 7.065264 -383.49301)
		(width 0.1651)
		(layer "In9.Cu")
		(net "USB2_MB_BMC_USB8042_DN")
	)
	(segment
		(start 6.186678 -386.759196)
		(end 6.186678 -386.583174)
		(width 0.1651)
		(layer "In9.Cu")
		(net "USB2_MB_BMC_USB8042_DN")
	)
	(segment
		(start 6.497828 -386.272024)
		(end 6.67385 -386.272024)
		(width 0.1651)
		(layer "In9.Cu")
		(net "USB2_MB_BMC_USB8042_DN")
	)
	(segment
		(start 3.97256 -387.266434)
		(end 5.67944 -387.266434)
		(width 0.1651)
		(layer "In9.Cu")
		(net "USB2_MB_BMC_USB8042_DN")
	)
	(segment
		(start 10.255504 -377.63323)
		(end 10.566146 -377.322588)
		(width 0.1651)
		(layer "In9.Cu")
		(net "USB2_MB_BMC_USB8042_DN")
	)
	(segment
		(start 11.363706 -376.525028)
		(end 11.363706 -376.349006)
		(width 0.1651)
		(layer "In9.Cu")
		(net "USB2_MB_BMC_USB8042_DN")
	)
	(segment
		(start 11.363706 -376.349006)
		(end 11.674602 -376.03811)
		(width 0.1651)
		(layer "In9.Cu")
		(net "USB2_MB_BMC_USB8042_DN")
	)
	(segment
		(start 7.065264 -384.18135)
		(end 6.940804 -384.05689)
		(width 0.1651)
		(layer "In9.Cu")
		(net "USB2_MB_BMC_USB8042_DN")
	)
	(segment
		(start 11.850624 -376.03811)
		(end 12.161266 -375.727468)
		(width 0.1651)
		(layer "In9.Cu")
		(net "USB2_MB_BMC_USB8042_DN")
	)
	(segment
		(start 7.862824 -380.02591)
		(end 8.173466 -379.715268)
		(width 0.1651)
		(layer "In9.Cu")
		(net "USB2_MB_BMC_USB8042_DN")
	)
	(segment
		(start 7.686802 -380.02591)
		(end 7.862824 -380.02591)
		(width 0.1651)
		(layer "In9.Cu")
		(net "USB2_MB_BMC_USB8042_DN")
	)
	(segment
		(start 11.444986 -371.075458)
		(end 10.116058 -371.075458)
		(width 0.1651)
		(layer "In9.Cu")
		(net "USB2_MB_BMC_USB8042_DN")
	)
	(segment
		(start 8.971026 -378.917708)
		(end 8.971026 -378.741686)
		(width 0.1651)
		(layer "In9.Cu")
		(net "USB2_MB_BMC_USB8042_DN")
	)
	(segment
		(start 2.335784 -387.819392)
		(end 3.419602 -387.819392)
		(width 0.1651)
		(layer "In9.Cu")
		(net "USB2_MB_BMC_USB8042_DN")
	)
	(segment
		(start 7.065264 -382.173226)
		(end 7.065264 -380.82347)
		(width 0.1651)
		(layer "In9.Cu")
		(net "USB2_MB_BMC_USB8042_DN")
	)
	(segment
		(start 10.566146 -377.322588)
		(end 10.566146 -377.146566)
		(width 0.1651)
		(layer "In9.Cu")
		(net "USB2_MB_BMC_USB8042_DN")
	)
	(segment
		(start 10.116058 -371.075458)
		(end 9.66851 -371.523006)
		(width 0.1651)
		(layer "In9.Cu")
		(net "USB2_MB_BMC_USB8042_DN")
	)
	(segment
		(start 13.620242 -372.846346)
		(end 13.620242 -371.884194)
		(width 0.1651)
		(layer "In9.Cu")
		(net "USB2_MB_BMC_USB8042_DN")
	)
	(segment
		(start 6.940804 -382.737106)
		(end 6.940804 -382.297686)
		(width 0.1651)
		(layer "In9.Cu")
		(net "USB2_MB_BMC_USB8042_DN")
	)
	(segment
		(start 7.065264 -384.62077)
		(end 7.065264 -384.18135)
		(width 0.1651)
		(layer "In9.Cu")
		(net "USB2_MB_BMC_USB8042_DN")
	)
	(segment
		(start 9.281922 -378.43079)
		(end 9.457944 -378.43079)
		(width 0.1651)
		(layer "In9.Cu")
		(net "USB2_MB_BMC_USB8042_DN")
	)
	(segment
		(start 9.66851 -371.523006)
		(end 9.66851 -371.77599)
		(width 0.1651)
		(layer "In9.Cu")
		(net "USB2_MB_BMC_USB8042_DN")
	)
	(segment
		(start 12.161266 -375.551446)
		(end 12.472162 -375.24055)
		(width 0.1651)
		(layer "In9.Cu")
		(net "USB2_MB_BMC_USB8042_DN")
	)
	(segment
		(start 3.419602 -387.819392)
		(end 3.97256 -387.266434)
		(width 0.1651)
		(layer "In9.Cu")
		(net "USB2_MB_BMC_USB8042_DN")
	)
	(segment
		(start 6.940804 -382.297686)
		(end 7.065264 -382.173226)
		(width 0.1651)
		(layer "In9.Cu")
		(net "USB2_MB_BMC_USB8042_DN")
	)
	(segment
		(start 8.173466 -379.715268)
		(end 8.173466 -379.539246)
		(width 0.1651)
		(layer "In9.Cu")
		(net "USB2_MB_BMC_USB8042_DN")
	)
	(segment
		(start 2.027682 -387.51129)
		(end 2.335784 -387.819392)
		(width 0.1651)
		(layer "In9.Cu")
		(net "USB2_MB_BMC_USB8042_DN")
	)
	(segment
		(start 9.768586 -378.120148)
		(end 9.768586 -377.944126)
		(width 0.1651)
		(layer "In9.Cu")
		(net "USB2_MB_BMC_USB8042_DN")
	)
	(segment
		(start 10.566146 -377.146566)
		(end 10.877042 -376.83567)
		(width 0.1651)
		(layer "In9.Cu")
		(net "USB2_MB_BMC_USB8042_DN")
	)
	(segment
		(start 7.065264 -385.88061)
		(end 7.065264 -385.30911)
		(width 0.1651)
		(layer "In9.Cu")
		(net "USB2_MB_BMC_USB8042_DN")
	)
	(segment
		(start 6.940804 -384.74523)
		(end 7.065264 -384.62077)
		(width 0.1651)
		(layer "In9.Cu")
		(net "USB2_MB_BMC_USB8042_DN")
	)
	(segment
		(start 13.495782 -373.410226)
		(end 13.495782 -372.970806)
		(width 0.1651)
		(layer "In9.Cu")
		(net "USB2_MB_BMC_USB8042_DN")
	)
	(segment
		(start 11.053064 -376.83567)
		(end 11.363706 -376.525028)
		(width 0.1651)
		(layer "In9.Cu")
		(net "USB2_MB_BMC_USB8042_DN")
	)
	(segment
		(start 13.620242 -373.534686)
		(end 13.495782 -373.410226)
		(width 0.1651)
		(layer "In9.Cu")
		(net "USB2_MB_BMC_USB8042_DN")
	)
	(segment
		(start 5.67944 -387.266434)
		(end 6.186678 -386.759196)
		(width 0.1651)
		(layer "In9.Cu")
		(net "USB2_MB_BMC_USB8042_DN")
	)
	(segment
		(start 7.375906 -380.336806)
		(end 7.686802 -380.02591)
		(width 0.1651)
		(layer "In9.Cu")
		(net "USB2_MB_BMC_USB8042_DN")
	)
	(segment
		(start 9.457944 -378.43079)
		(end 9.768586 -378.120148)
		(width 0.1651)
		(layer "In9.Cu")
		(net "USB2_MB_BMC_USB8042_DN")
	)
	(segment
		(start 11.569446 -371.199918)
		(end 11.444986 -371.075458)
		(width 0.1651)
		(layer "In9.Cu")
		(net "USB2_MB_BMC_USB8042_DN")
	)
	(segment
		(start 6.67385 -386.272024)
		(end 7.065264 -385.88061)
		(width 0.1651)
		(layer "In9.Cu")
		(net "USB2_MB_BMC_USB8042_DN")
	)
	(segment
		(start 8.484362 -379.22835)
		(end 8.660384 -379.22835)
		(width 0.1651)
		(layer "In9.Cu")
		(net "USB2_MB_BMC_USB8042_DN")
	)
	(segment
		(start 7.065264 -385.30911)
		(end 6.940804 -385.18465)
		(width 0.1651)
		(layer "In9.Cu")
		(net "USB2_MB_BMC_USB8042_DN")
	)
	(segment
		(start 102.527608 -381.566674)
		(end 102.527608 -373.96801)
		(width 0.13462)
		(layer "F.Cu")
		(net "USB2_MB_BMC_USB8042_DP")
	)
	(segment
		(start 102.527608 -373.96801)
		(end 101.645212 -373.085614)
		(width 0.13462)
		(layer "F.Cu")
		(net "USB2_MB_BMC_USB8042_DP")
	)
	(segment
		(start 9.40054 -370.813076)
		(end 9.40054 -371.76964)
		(width 0.13462)
		(layer "F.Cu")
		(net "USB2_MB_BMC_USB8042_DP")
	)
	(segment
		(start 2.992374 -388.445248)
		(end 2.618486 -388.073392)
		(width 0.13462)
		(layer "F.Cu")
		(net "USB2_MB_BMC_USB8042_DP")
	)
	(segment
		(start 3.302254 -388.135368)
		(end 2.992374 -388.445248)
		(width 0.13462)
		(layer "F.Cu")
		(net "USB2_MB_BMC_USB8042_DP")
	)
	(segment
		(start 101.829362 -384.405124)
		(end 101.829362 -384.089148)
		(width 0.13462)
		(layer "F.Cu")
		(net "USB2_MB_BMC_USB8042_DP")
	)
	(segment
		(start 5.566664 -388.246874)
		(end 5.454396 -388.134606)
		(width 0.13462)
		(layer "F.Cu")
		(net "USB2_MB_BMC_USB8042_DP")
	)
	(segment
		(start 101.069394 -383.024888)
		(end 102.527608 -381.566674)
		(width 0.13462)
		(layer "F.Cu")
		(net "USB2_MB_BMC_USB8042_DP")
	)
	(segment
		(start 57.029096 -359.193846)
		(end 53.066696 -359.193846)
		(width 0.13462)
		(layer "F.Cu")
		(net "USB2_MB_BMC_USB8042_DP")
	)
	(segment
		(start 4.27736 -388.135368)
		(end 3.302254 -388.135368)
		(width 0.13462)
		(layer "F.Cu")
		(net "USB2_MB_BMC_USB8042_DP")
	)
	(segment
		(start 94.194122 -360.22788)
		(end 58.06313 -360.22788)
		(width 0.13462)
		(layer "F.Cu")
		(net "USB2_MB_BMC_USB8042_DP")
	)
	(segment
		(start 5.780024 -388.246874)
		(end 5.566664 -388.246874)
		(width 0.13462)
		(layer "F.Cu")
		(net "USB2_MB_BMC_USB8042_DP")
	)
	(segment
		(start 101.069394 -383.32918)
		(end 101.069394 -383.024888)
		(width 0.13462)
		(layer "F.Cu")
		(net "USB2_MB_BMC_USB8042_DP")
	)
	(segment
		(start 101.645212 -373.085614)
		(end 101.645212 -367.67897)
		(width 0.13462)
		(layer "F.Cu")
		(net "USB2_MB_BMC_USB8042_DP")
	)
	(segment
		(start 2.618486 -388.073392)
		(end 2.32918 -388.073392)
		(width 0.13462)
		(layer "F.Cu")
		(net "USB2_MB_BMC_USB8042_DP")
	)
	(segment
		(start 52.340002 -359.92054)
		(end 20.990052 -359.92054)
		(width 0.13462)
		(layer "F.Cu")
		(net "USB2_MB_BMC_USB8042_DP")
	)
	(segment
		(start 5.454396 -388.134606)
		(end 4.557776 -388.134606)
		(width 0.13462)
		(layer "F.Cu")
		(net "USB2_MB_BMC_USB8042_DP")
	)
	(segment
		(start 9.40054 -371.76964)
		(end 9.09955 -372.07063)
		(width 0.13462)
		(layer "F.Cu")
		(net "USB2_MB_BMC_USB8042_DP")
	)
	(segment
		(start 58.06313 -360.22788)
		(end 57.029096 -359.193846)
		(width 0.13462)
		(layer "F.Cu")
		(net "USB2_MB_BMC_USB8042_DP")
	)
	(segment
		(start 53.066696 -359.193846)
		(end 52.340002 -359.92054)
		(width 0.13462)
		(layer "F.Cu")
		(net "USB2_MB_BMC_USB8042_DP")
	)
	(segment
		(start 2.32918 -388.073392)
		(end 2.027682 -388.37489)
		(width 0.13462)
		(layer "F.Cu")
		(net "USB2_MB_BMC_USB8042_DP")
	)
	(segment
		(start 101.829362 -384.089148)
		(end 101.069394 -383.32918)
		(width 0.13462)
		(layer "F.Cu")
		(net "USB2_MB_BMC_USB8042_DP")
	)
	(segment
		(start 4.557776 -388.134606)
		(end 4.27736 -388.135368)
		(width 0.13462)
		(layer "F.Cu")
		(net "USB2_MB_BMC_USB8042_DP")
	)
	(segment
		(start 20.293076 -359.92054)
		(end 9.40054 -370.813076)
		(width 0.13462)
		(layer "F.Cu")
		(net "USB2_MB_BMC_USB8042_DP")
	)
	(segment
		(start 20.990052 -359.92054)
		(end 20.293076 -359.92054)
		(width 0.13462)
		(layer "F.Cu")
		(net "USB2_MB_BMC_USB8042_DP")
	)
	(segment
		(start 101.645212 -367.67897)
		(end 94.194122 -360.22788)
		(width 0.13462)
		(layer "F.Cu")
		(net "USB2_MB_BMC_USB8042_DP")
	)
	(via
		(at 20.990052 -359.92054)
		(size 0.4064)
		(drill 0.2032)
		(layers "F.Cu" "B.Cu")
		(net "USB2_MB_BMC_USB8042_DP")
	)
	(segment
		(start 2.027682 -388.37489)
		(end 2.30886 -388.093712)
		(width 0.1651)
		(layer "In9.Cu")
		(net "USB2_MB_BMC_USB8042_DP")
	)
	(segment
		(start 9.39419 -371.409214)
		(end 9.39419 -371.77599)
		(width 0.1651)
		(layer "In9.Cu")
		(net "USB2_MB_BMC_USB8042_DP")
	)
	(segment
		(start 7.339584 -380.937262)
		(end 13.894562 -374.382284)
		(width 0.1651)
		(layer "In9.Cu")
		(net "USB2_MB_BMC_USB8042_DP")
	)
	(segment
		(start 9.39419 -371.77599)
		(end 9.09955 -372.07063)
		(width 0.1651)
		(layer "In9.Cu")
		(net "USB2_MB_BMC_USB8042_DP")
	)
	(segment
		(start 7.339584 -385.994402)
		(end 7.339584 -380.937262)
		(width 0.1651)
		(layer "In9.Cu")
		(net "USB2_MB_BMC_USB8042_DP")
	)
	(segment
		(start 13.894562 -371.770402)
		(end 12.925298 -370.801138)
		(width 0.1651)
		(layer "In9.Cu")
		(net "USB2_MB_BMC_USB8042_DP")
	)
	(segment
		(start 4.086352 -387.540754)
		(end 5.793232 -387.540754)
		(width 0.1651)
		(layer "In9.Cu")
		(net "USB2_MB_BMC_USB8042_DP")
	)
	(segment
		(start 2.30886 -388.093712)
		(end 3.533394 -388.093712)
		(width 0.1651)
		(layer "In9.Cu")
		(net "USB2_MB_BMC_USB8042_DP")
	)
	(segment
		(start 10.002266 -370.801138)
		(end 9.39419 -371.409214)
		(width 0.1651)
		(layer "In9.Cu")
		(net "USB2_MB_BMC_USB8042_DP")
	)
	(segment
		(start 13.894562 -374.382284)
		(end 13.894562 -371.770402)
		(width 0.1651)
		(layer "In9.Cu")
		(net "USB2_MB_BMC_USB8042_DP")
	)
	(segment
		(start 3.533394 -388.093712)
		(end 4.086352 -387.540754)
		(width 0.1651)
		(layer "In9.Cu")
		(net "USB2_MB_BMC_USB8042_DP")
	)
	(segment
		(start 12.925298 -370.801138)
		(end 10.002266 -370.801138)
		(width 0.1651)
		(layer "In9.Cu")
		(net "USB2_MB_BMC_USB8042_DP")
	)
	(segment
		(start 5.793232 -387.540754)
		(end 7.339584 -385.994402)
		(width 0.1651)
		(layer "In9.Cu")
		(net "USB2_MB_BMC_USB8042_DP")
	)
	(segment
		(start 13.930122 -390.896856)
		(end 15.44574 -390.896856)
		(width 0.13208)
		(layer "F.Cu")
		(net "BIC_USB_8042_HUB_PWRCTL3")
	)
	(segment
		(start 15.44574 -390.896856)
		(end 15.649194 -391.10031)
		(width 0.13208)
		(layer "F.Cu")
		(net "BIC_USB_8042_HUB_PWRCTL3")
	)
	(segment
		(start 15.831312 -392.321034)
		(end 15.649194 -392.138916)
		(width 0.13208)
		(layer "F.Cu")
		(net "BIC_USB_8042_HUB_PWRCTL3")
	)
	(segment
		(start 15.649194 -392.138916)
		(end 15.649194 -391.10031)
		(width 0.13208)
		(layer "F.Cu")
		(net "BIC_USB_8042_HUB_PWRCTL3")
	)
	(via
		(at 15.649194 -391.10031)
		(size 0.762)
		(drill 0.381)
		(layers "F.Cu" "B.Cu")
		(net "BIC_USB_8042_HUB_PWRCTL3")
	)
	(segment
		(start 4.140454 -370.232686)
		(end 4.140454 -372.010686)
		(width 0.508)
		(layer "F.Cu")
		(net "P3V3_USB_HUB")
	)
	(segment
		(start 15.429738 -395.19606)
		(end 15.429738 -395.17701)
		(width 0.3048)
		(layer "F.Cu")
		(net "P3V3_USB_HUB")
	)
	(segment
		(start 15.243302 -394.990574)
		(end 15.243302 -394.53058)
		(width 0.3048)
		(layer "F.Cu")
		(net "P3V3_USB_HUB")
	)
	(segment
		(start 15.429738 -395.17701)
		(end 15.243302 -394.990574)
		(width 0.3048)
		(layer "F.Cu")
		(net "P3V3_USB_HUB")
	)
	(segment
		(start 4.141216 -372.011448)
		(end 4.141216 -372.921784)
		(width 0.508)
		(layer "F.Cu")
		(net "P3V3_USB_HUB")
	)
	(segment
		(start 4.140454 -372.010686)
		(end 4.141216 -372.011448)
		(width 0.508)
		(layer "F.Cu")
		(net "P3V3_USB_HUB")
	)
	(via
		(at 4.141216 -372.921784)
		(size 0.508)
		(drill 0.254)
		(layers "F.Cu" "B.Cu")
		(net "P3V3_USB_HUB")
	)
	(via
		(at 1.648206 -381.338836)
		(size 0.508)
		(drill 0.254)
		(layers "F.Cu" "B.Cu")
		(net "P3V3_USB_HUB")
	)
	(via
		(at 15.429738 -395.19606)
		(size 0.508)
		(drill 0.254)
		(layers "F.Cu" "B.Cu")
		(net "P3V3_USB_HUB")
	)
	(segment
		(start 1.494028 -382.157986)
		(end 1.494028 -385.148074)
		(width 0.3556)
		(layer "B.Cu")
		(net "P3V3_USB_HUB")
	)
	(segment
		(start 2.314702 -389.821166)
		(end 2.314702 -390.430766)
		(width 0.3556)
		(layer "B.Cu")
		(net "P3V3_USB_HUB")
	)
	(segment
		(start 14.878812 -394.645134)
		(end 15.429738 -395.19606)
		(width 0.3556)
		(layer "B.Cu")
		(net "P3V3_USB_HUB")
	)
	(segment
		(start 2.704592 -386.358638)
		(end 2.704592 -389.431276)
		(width 0.3556)
		(layer "B.Cu")
		(net "P3V3_USB_HUB")
	)
	(segment
		(start 2.704592 -389.431276)
		(end 2.314702 -389.821166)
		(width 0.3556)
		(layer "B.Cu")
		(net "P3V3_USB_HUB")
	)
	(segment
		(start 1.494028 -385.148074)
		(end 2.704592 -386.358638)
		(width 0.3556)
		(layer "B.Cu")
		(net "P3V3_USB_HUB")
	)
	(segment
		(start 2.314702 -390.430766)
		(end 4.27736 -392.393424)
		(width 0.3556)
		(layer "B.Cu")
		(net "P3V3_USB_HUB")
	)
	(segment
		(start 12.811252 -394.645134)
		(end 14.878812 -394.645134)
		(width 0.3556)
		(layer "B.Cu")
		(net "P3V3_USB_HUB")
	)
	(segment
		(start 10.559542 -392.393424)
		(end 12.811252 -394.645134)
		(width 0.3556)
		(layer "B.Cu")
		(net "P3V3_USB_HUB")
	)
	(segment
		(start 4.27736 -392.393424)
		(end 10.559542 -392.393424)
		(width 0.3556)
		(layer "B.Cu")
		(net "P3V3_USB_HUB")
	)
	(segment
		(start 4.141216 -372.921784)
		(end 4.141216 -377.94565)
		(width 0.508)
		(layer "In9.Cu")
		(net "P3V3_USB_HUB")
	)
	(segment
		(start 2.464054 -381.338836)
		(end 1.648206 -381.338836)
		(width 0.508)
		(layer "In9.Cu")
		(net "P3V3_USB_HUB")
	)
	(segment
		(start 3.319526 -378.76734)
		(end 3.319526 -380.483364)
		(width 0.508)
		(layer "In9.Cu")
		(net "P3V3_USB_HUB")
	)
	(segment
		(start 4.141216 -377.94565)
		(end 3.319526 -378.76734)
		(width 0.508)
		(layer "In9.Cu")
		(net "P3V3_USB_HUB")
	)
	(segment
		(start 3.319526 -380.483364)
		(end 2.464054 -381.338836)
		(width 0.508)
		(layer "In9.Cu")
		(net "P3V3_USB_HUB")
	)
	(segment
		(start 14.140688 -392.36904)
		(end 12.930124 -391.158476)
		(width 0.13208)
		(layer "F.Cu")
		(net "BIC_USB_8042_HUB_PWRCTL2")
	)
	(segment
		(start 12.930124 -391.158476)
		(end 12.930124 -390.896856)
		(width 0.13208)
		(layer "F.Cu")
		(net "BIC_USB_8042_HUB_PWRCTL2")
	)
	(segment
		(start 16.424656 -393.728702)
		(end 16.445738 -393.728702)
		(width 0.13208)
		(layer "F.Cu")
		(net "BIC_USB_8042_HUB_PWRCTL2")
	)
	(segment
		(start 14.629892 -392.36904)
		(end 15.628366 -393.367514)
		(width 0.13208)
		(layer "F.Cu")
		(net "BIC_USB_8042_HUB_PWRCTL2")
	)
	(segment
		(start 16.063468 -393.367514)
		(end 16.424656 -393.728702)
		(width 0.13208)
		(layer "F.Cu")
		(net "BIC_USB_8042_HUB_PWRCTL2")
	)
	(segment
		(start 15.628366 -393.367514)
		(end 16.063468 -393.367514)
		(width 0.13208)
		(layer "F.Cu")
		(net "BIC_USB_8042_HUB_PWRCTL2")
	)
	(segment
		(start 14.629892 -392.36904)
		(end 14.140688 -392.36904)
		(width 0.13208)
		(layer "F.Cu")
		(net "BIC_USB_8042_HUB_PWRCTL2")
	)
	(via
		(at 14.629892 -392.36904)
		(size 0.762)
		(drill 0.381)
		(layers "F.Cu" "B.Cu")
		(net "BIC_USB_8042_HUB_PWRCTL2")
	)
	(segment
		(start 3.65125 -393.064492)
		(end 3.65125 -392.020806)
		(width 0.13208)
		(layer "F.Cu")
		(net "BIC_USB_8042_HUB_TEST")
	)
	(segment
		(start 3.65125 -392.020806)
		(end 4.08432 -391.587736)
		(width 0.13208)
		(layer "F.Cu")
		(net "BIC_USB_8042_HUB_TEST")
	)
	(segment
		(start 4.08432 -391.587736)
		(end 5.425186 -390.24687)
		(width 0.13208)
		(layer "F.Cu")
		(net "BIC_USB_8042_HUB_TEST")
	)
	(segment
		(start 5.425186 -390.24687)
		(end 5.780024 -390.24687)
		(width 0.13208)
		(layer "F.Cu")
		(net "BIC_USB_8042_HUB_TEST")
	)
	(via
		(at 4.08432 -391.587736)
		(size 0.762)
		(drill 0.381)
		(layers "F.Cu" "B.Cu")
		(net "BIC_USB_8042_HUB_TEST")
	)
	(segment
		(start 5.439918 -389.746744)
		(end 5.780024 -389.746744)
		(width 0.13208)
		(layer "F.Cu")
		(net "BIC_USB_8042_HUB_GRSTZ")
	)
	(segment
		(start 2.756408 -391.591038)
		(end 2.756408 -392.527282)
		(width 0.13208)
		(layer "F.Cu")
		(net "BIC_USB_8042_HUB_GRSTZ")
	)
	(segment
		(start 4.987036 -390.199626)
		(end 5.439918 -389.746744)
		(width 0.13208)
		(layer "F.Cu")
		(net "BIC_USB_8042_HUB_GRSTZ")
	)
	(segment
		(start 1.66624 -393.074144)
		(end 2.107184 -393.074144)
		(width 0.13208)
		(layer "F.Cu")
		(net "BIC_USB_8042_HUB_GRSTZ")
	)
	(segment
		(start 4.181602 -390.199626)
		(end 2.79019 -391.591038)
		(width 0.13208)
		(layer "F.Cu")
		(net "BIC_USB_8042_HUB_GRSTZ")
	)
	(segment
		(start 2.756408 -392.527282)
		(end 2.633218 -392.650472)
		(width 0.13208)
		(layer "F.Cu")
		(net "BIC_USB_8042_HUB_GRSTZ")
	)
	(segment
		(start 2.107184 -393.074144)
		(end 2.122424 -393.089384)
		(width 0.13208)
		(layer "F.Cu")
		(net "BIC_USB_8042_HUB_GRSTZ")
	)
	(segment
		(start 2.633218 -392.650472)
		(end 2.633218 -393.06627)
		(width 0.13208)
		(layer "F.Cu")
		(net "BIC_USB_8042_HUB_GRSTZ")
	)
	(segment
		(start 2.610104 -393.089384)
		(end 2.633218 -393.06627)
		(width 0.13208)
		(layer "F.Cu")
		(net "BIC_USB_8042_HUB_GRSTZ")
	)
	(segment
		(start 4.181602 -390.199626)
		(end 4.987036 -390.199626)
		(width 0.13208)
		(layer "F.Cu")
		(net "BIC_USB_8042_HUB_GRSTZ")
	)
	(segment
		(start 2.122424 -393.089384)
		(end 2.610104 -393.089384)
		(width 0.13208)
		(layer "F.Cu")
		(net "BIC_USB_8042_HUB_GRSTZ")
	)
	(segment
		(start 2.79019 -391.591038)
		(end 2.756408 -391.591038)
		(width 0.13208)
		(layer "F.Cu")
		(net "BIC_USB_8042_HUB_GRSTZ")
	)
	(via
		(at 4.181602 -390.199626)
		(size 0.762)
		(drill 0.381)
		(layers "F.Cu" "B.Cu")
		(net "BIC_USB_8042_HUB_GRSTZ")
	)
	(segment
		(start 13.275056 -392.478006)
		(end 14.252956 -393.455906)
		(width 0.13208)
		(layer "F.Cu")
		(net "BIC_USB_8042_HUB_FULLPWRMGMTZ")
	)
	(segment
		(start 13.275056 -392.478006)
		(end 12.895326 -392.478006)
		(width 0.13208)
		(layer "F.Cu")
		(net "BIC_USB_8042_HUB_FULLPWRMGMTZ")
	)
	(segment
		(start 15.243302 -393.73048)
		(end 14.252956 -393.73048)
		(width 0.13208)
		(layer "F.Cu")
		(net "BIC_USB_8042_HUB_FULLPWRMGMTZ")
	)
	(segment
		(start 10.430002 -391.226802)
		(end 10.430002 -390.896856)
		(width 0.13208)
		(layer "F.Cu")
		(net "BIC_USB_8042_HUB_FULLPWRMGMTZ")
	)
	(segment
		(start 11.888724 -391.471404)
		(end 10.674604 -391.471404)
		(width 0.13208)
		(layer "F.Cu")
		(net "BIC_USB_8042_HUB_FULLPWRMGMTZ")
	)
	(segment
		(start 12.895326 -392.478006)
		(end 11.888724 -391.471404)
		(width 0.13208)
		(layer "F.Cu")
		(net "BIC_USB_8042_HUB_FULLPWRMGMTZ")
	)
	(segment
		(start 14.252956 -393.455906)
		(end 14.252956 -393.73048)
		(width 0.13208)
		(layer "F.Cu")
		(net "BIC_USB_8042_HUB_FULLPWRMGMTZ")
	)
	(segment
		(start 10.674604 -391.471404)
		(end 10.430002 -391.226802)
		(width 0.13208)
		(layer "F.Cu")
		(net "BIC_USB_8042_HUB_FULLPWRMGMTZ")
	)
	(via
		(at 13.275056 -392.478006)
		(size 0.762)
		(drill 0.381)
		(layers "F.Cu" "B.Cu")
		(net "BIC_USB_8042_HUB_FULLPWRMGMTZ")
	)
	(segment
		(start 11.396472 -391.84834)
		(end 10.16 -391.84834)
		(width 0.13208)
		(layer "F.Cu")
		(net "BIC_USB_8042_HUB_GANGED")
	)
	(segment
		(start 10.16 -391.84834)
		(end 9.430004 -391.118344)
		(width 0.13208)
		(layer "F.Cu")
		(net "BIC_USB_8042_HUB_GANGED")
	)
	(segment
		(start 11.891772 -392.34364)
		(end 11.396472 -391.84834)
		(width 0.13208)
		(layer "F.Cu")
		(net "BIC_USB_8042_HUB_GANGED")
	)
	(segment
		(start 13.220192 -393.67206)
		(end 11.891772 -392.34364)
		(width 0.13208)
		(layer "F.Cu")
		(net "BIC_USB_8042_HUB_GANGED")
	)
	(segment
		(start 13.220192 -393.730734)
		(end 13.220192 -393.67206)
		(width 0.13208)
		(layer "F.Cu")
		(net "BIC_USB_8042_HUB_GANGED")
	)
	(segment
		(start 9.430004 -391.118344)
		(end 9.430004 -390.896856)
		(width 0.13208)
		(layer "F.Cu")
		(net "BIC_USB_8042_HUB_GANGED")
	)
	(via
		(at 11.891772 -392.34364)
		(size 0.762)
		(drill 0.381)
		(layers "F.Cu" "B.Cu")
		(net "BIC_USB_8042_HUB_GANGED")
	)
	(segment
		(start 5.207 -382.556766)
		(end 5.396992 -382.746758)
		(width 0.13208)
		(layer "F.Cu")
		(net "BIC_USB_8042_HUB_R1")
	)
	(segment
		(start 6.114796 -380.115826)
		(end 5.207 -381.023622)
		(width 0.13208)
		(layer "F.Cu")
		(net "BIC_USB_8042_HUB_R1")
	)
	(segment
		(start 6.521196 -379.709426)
		(end 6.114796 -380.115826)
		(width 0.13208)
		(layer "F.Cu")
		(net "BIC_USB_8042_HUB_R1")
	)
	(segment
		(start 5.207 -381.023622)
		(end 5.207 -382.556766)
		(width 0.13208)
		(layer "F.Cu")
		(net "BIC_USB_8042_HUB_R1")
	)
	(segment
		(start 6.521196 -378.933964)
		(end 6.521196 -379.709426)
		(width 0.13208)
		(layer "F.Cu")
		(net "BIC_USB_8042_HUB_R1")
	)
	(segment
		(start 5.396992 -382.746758)
		(end 5.780024 -382.746758)
		(width 0.13208)
		(layer "F.Cu")
		(net "BIC_USB_8042_HUB_R1")
	)
	(via
		(at 6.114796 -380.115826)
		(size 0.762)
		(drill 0.381)
		(layers "F.Cu" "B.Cu")
		(net "BIC_USB_8042_HUB_R1")
	)
	(segment
		(start 293.226744 -440.14136)
		(end 293.226744 -438.155842)
		(width 0.1397)
		(layer "In9.Cu")
		(net "TDR_DIFF_100_IN3_DIN")
	)
	(segment
		(start 232.988866 -440.14136)
		(end 232.988866 -439.16346)
		(width 0.1397)
		(layer "In9.Cu")
		(net "TDR_DIFF_100_IN3_DIN")
	)
	(segment
		(start 265.581384 -441.033916)
		(end 265.454384 -440.906916)
		(width 0.1397)
		(layer "In9.Cu")
		(net "TDR_DIFF_100_IN3_DIN")
	)
	(segment
		(start 269.421864 -438.155842)
		(end 269.10157 -437.835548)
		(width 0.1397)
		(layer "In9.Cu")
		(net "TDR_DIFF_100_IN3_DIN")
	)
	(segment
		(start 247.270524 -440.906916)
		(end 247.143524 -441.033916)
		(width 0.1397)
		(layer "In9.Cu")
		(net "TDR_DIFF_100_IN3_DIN")
	)
	(segment
		(start 293.226744 -438.155842)
		(end 292.90645 -437.835548)
		(width 0.1397)
		(layer "In9.Cu")
		(net "TDR_DIFF_100_IN3_DIN")
	)
	(segment
		(start 263.140444 -440.906916)
		(end 263.013444 -441.033916)
		(width 0.1397)
		(layer "In9.Cu")
		(net "TDR_DIFF_100_IN3_DIN")
	)
	(segment
		(start 271.395698 -437.835548)
		(end 271.075404 -438.155842)
		(width 0.1397)
		(layer "In9.Cu")
		(net "TDR_DIFF_100_IN3_DIN")
	)
	(segment
		(start 259.045964 -441.033916)
		(end 257.646424 -441.033916)
		(width 0.1397)
		(layer "In9.Cu")
		(net "TDR_DIFF_100_IN3_DIN")
	)
	(segment
		(start 259.172964 -440.906916)
		(end 259.045964 -441.033916)
		(width 0.1397)
		(layer "In9.Cu")
		(net "TDR_DIFF_100_IN3_DIN")
	)
	(segment
		(start 249.584464 -438.155842)
		(end 249.26417 -437.835548)
		(width 0.1397)
		(layer "In9.Cu")
		(net "TDR_DIFF_100_IN3_DIN")
	)
	(segment
		(start 239.335564 -438.155842)
		(end 239.335564 -440.871864)
		(width 0.1397)
		(layer "In9.Cu")
		(net "TDR_DIFF_100_IN3_DIN")
	)
	(segment
		(start 263.460738 -437.835548)
		(end 263.140444 -438.155842)
		(width 0.1397)
		(layer "In9.Cu")
		(net "TDR_DIFF_100_IN3_DIN")
	)
	(segment
		(start 267.107924 -438.155842)
		(end 267.107924 -440.906916)
		(width 0.1397)
		(layer "In9.Cu")
		(net "TDR_DIFF_100_IN3_DIN")
	)
	(segment
		(start 243.176044 -441.033916)
		(end 241.776504 -441.033916)
		(width 0.1397)
		(layer "In9.Cu")
		(net "TDR_DIFF_100_IN3_DIN")
	)
	(segment
		(start 269.421864 -440.906916)
		(end 269.421864 -438.155842)
		(width 0.1397)
		(layer "In9.Cu")
		(net "TDR_DIFF_100_IN3_DIN")
	)
	(segment
		(start 293.353744 -440.26836)
		(end 293.226744 -440.14136)
		(width 0.1397)
		(layer "In9.Cu")
		(net "TDR_DIFF_100_IN3_DIN")
	)
	(segment
		(start 263.013444 -441.033916)
		(end 261.613904 -441.033916)
		(width 0.1397)
		(layer "In9.Cu")
		(net "TDR_DIFF_100_IN3_DIN")
	)
	(segment
		(start 275.042884 -438.155842)
		(end 275.042884 -440.906916)
		(width 0.1397)
		(layer "In9.Cu")
		(net "TDR_DIFF_100_IN3_DIN")
	)
	(segment
		(start 235.368084 -438.155842)
		(end 235.368084 -440.14136)
		(width 0.1397)
		(layer "In9.Cu")
		(net "TDR_DIFF_100_IN3_DIN")
	)
	(segment
		(start 274.915884 -441.033916)
		(end 273.516344 -441.033916)
		(width 0.1397)
		(layer "In9.Cu")
		(net "TDR_DIFF_100_IN3_DIN")
	)
	(segment
		(start 290.785804 -441.033916)
		(end 289.386264 -441.033916)
		(width 0.1397)
		(layer "In9.Cu")
		(net "TDR_DIFF_100_IN3_DIN")
	)
	(segment
		(start 251.238004 -438.155842)
		(end 251.238004 -440.906916)
		(width 0.1397)
		(layer "In9.Cu")
		(net "TDR_DIFF_100_IN3_DIN")
	)
	(segment
		(start 267.428218 -437.835548)
		(end 267.107924 -438.155842)
		(width 0.1397)
		(layer "In9.Cu")
		(net "TDR_DIFF_100_IN3_DIN")
	)
	(segment
		(start 247.143524 -441.033916)
		(end 245.743984 -441.033916)
		(width 0.1397)
		(layer "In9.Cu")
		(net "TDR_DIFF_100_IN3_DIN")
	)
	(segment
		(start 253.678944 -441.033916)
		(end 253.551944 -440.906916)
		(width 0.1397)
		(layer "In9.Cu")
		(net "TDR_DIFF_100_IN3_DIN")
	)
	(segment
		(start 245.29669 -437.835548)
		(end 243.623338 -437.835548)
		(width 0.1397)
		(layer "In9.Cu")
		(net "TDR_DIFF_100_IN3_DIN")
	)
	(segment
		(start 279.010364 -440.906916)
		(end 278.883364 -441.033916)
		(width 0.1397)
		(layer "In9.Cu")
		(net "TDR_DIFF_100_IN3_DIN")
	)
	(segment
		(start 283.298138 -437.835548)
		(end 282.977844 -438.155842)
		(width 0.1397)
		(layer "In9.Cu")
		(net "TDR_DIFF_100_IN3_DIN")
	)
	(segment
		(start 251.111004 -441.033916)
		(end 249.711464 -441.033916)
		(width 0.1397)
		(layer "In9.Cu")
		(net "TDR_DIFF_100_IN3_DIN")
	)
	(segment
		(start 257.19913 -437.835548)
		(end 255.525778 -437.835548)
		(width 0.1397)
		(layer "In9.Cu")
		(net "TDR_DIFF_100_IN3_DIN")
	)
	(segment
		(start 255.205484 -440.906916)
		(end 255.078484 -441.033916)
		(width 0.1397)
		(layer "In9.Cu")
		(net "TDR_DIFF_100_IN3_DIN")
	)
	(segment
		(start 261.486904 -440.906916)
		(end 261.486904 -438.155842)
		(width 0.1397)
		(layer "In9.Cu")
		(net "TDR_DIFF_100_IN3_DIN")
	)
	(segment
		(start 281.324304 -438.155842)
		(end 281.00401 -437.835548)
		(width 0.1397)
		(layer "In9.Cu")
		(net "TDR_DIFF_100_IN3_DIN")
	)
	(segment
		(start 247.270524 -438.155842)
		(end 247.270524 -440.906916)
		(width 0.1397)
		(layer "In9.Cu")
		(net "TDR_DIFF_100_IN3_DIN")
	)
	(segment
		(start 285.291784 -440.906916)
		(end 285.291784 -438.155842)
		(width 0.1397)
		(layer "In9.Cu")
		(net "TDR_DIFF_100_IN3_DIN")
	)
	(segment
		(start 291.233098 -437.835548)
		(end 290.912804 -438.155842)
		(width 0.1397)
		(layer "In9.Cu")
		(net "TDR_DIFF_100_IN3_DIN")
	)
	(segment
		(start 284.97149 -437.835548)
		(end 283.298138 -437.835548)
		(width 0.1397)
		(layer "In9.Cu")
		(net "TDR_DIFF_100_IN3_DIN")
	)
	(segment
		(start 237.682024 -440.871864)
		(end 237.682024 -438.155842)
		(width 0.1397)
		(layer "In9.Cu")
		(net "TDR_DIFF_100_IN3_DIN")
	)
	(segment
		(start 241.649504 -438.155842)
		(end 241.32921 -437.835548)
		(width 0.1397)
		(layer "In9.Cu")
		(net "TDR_DIFF_100_IN3_DIN")
	)
	(segment
		(start 297.009566 -439.16346)
		(end 297.009566 -440.137804)
		(width 0.1397)
		(layer "In9.Cu")
		(net "TDR_DIFF_100_IN3_DIN")
	)
	(segment
		(start 279.330658 -437.835548)
		(end 279.010364 -438.155842)
		(width 0.1397)
		(layer "In9.Cu")
		(net "TDR_DIFF_100_IN3_DIN")
	)
	(segment
		(start 270.948404 -441.033916)
		(end 269.548864 -441.033916)
		(width 0.1397)
		(layer "In9.Cu")
		(net "TDR_DIFF_100_IN3_DIN")
	)
	(segment
		(start 237.682024 -438.155842)
		(end 237.36173 -437.835548)
		(width 0.1397)
		(layer "In9.Cu")
		(net "TDR_DIFF_100_IN3_DIN")
	)
	(segment
		(start 292.90645 -437.835548)
		(end 291.233098 -437.835548)
		(width 0.1397)
		(layer "In9.Cu")
		(net "TDR_DIFF_100_IN3_DIN")
	)
	(segment
		(start 281.324304 -440.906916)
		(end 281.324304 -438.155842)
		(width 0.1397)
		(layer "In9.Cu")
		(net "TDR_DIFF_100_IN3_DIN")
	)
	(segment
		(start 259.172964 -438.155842)
		(end 259.172964 -440.906916)
		(width 0.1397)
		(layer "In9.Cu")
		(net "TDR_DIFF_100_IN3_DIN")
	)
	(segment
		(start 261.486904 -438.155842)
		(end 261.16661 -437.835548)
		(width 0.1397)
		(layer "In9.Cu")
		(net "TDR_DIFF_100_IN3_DIN")
	)
	(segment
		(start 255.525778 -437.835548)
		(end 255.205484 -438.155842)
		(width 0.1397)
		(layer "In9.Cu")
		(net "TDR_DIFF_100_IN3_DIN")
	)
	(segment
		(start 285.291784 -438.155842)
		(end 284.97149 -437.835548)
		(width 0.1397)
		(layer "In9.Cu")
		(net "TDR_DIFF_100_IN3_DIN")
	)
	(segment
		(start 267.107924 -440.906916)
		(end 266.980924 -441.033916)
		(width 0.1397)
		(layer "In9.Cu")
		(net "TDR_DIFF_100_IN3_DIN")
	)
	(segment
		(start 265.454384 -440.906916)
		(end 265.454384 -438.155842)
		(width 0.1397)
		(layer "In9.Cu")
		(net "TDR_DIFF_100_IN3_DIN")
	)
	(segment
		(start 255.205484 -438.155842)
		(end 255.205484 -440.906916)
		(width 0.1397)
		(layer "In9.Cu")
		(net "TDR_DIFF_100_IN3_DIN")
	)
	(segment
		(start 245.743984 -441.033916)
		(end 245.616984 -440.906916)
		(width 0.1397)
		(layer "In9.Cu")
		(net "TDR_DIFF_100_IN3_DIN")
	)
	(segment
		(start 288.93897 -437.835548)
		(end 287.265618 -437.835548)
		(width 0.1397)
		(layer "In9.Cu")
		(net "TDR_DIFF_100_IN3_DIN")
	)
	(segment
		(start 287.265618 -437.835548)
		(end 286.945324 -438.155842)
		(width 0.1397)
		(layer "In9.Cu")
		(net "TDR_DIFF_100_IN3_DIN")
	)
	(segment
		(start 273.516344 -441.033916)
		(end 273.389344 -440.906916)
		(width 0.1397)
		(layer "In9.Cu")
		(net "TDR_DIFF_100_IN3_DIN")
	)
	(segment
		(start 282.977844 -440.906916)
		(end 282.850844 -441.033916)
		(width 0.1397)
		(layer "In9.Cu")
		(net "TDR_DIFF_100_IN3_DIN")
	)
	(segment
		(start 235.688378 -437.835548)
		(end 235.368084 -438.155842)
		(width 0.1397)
		(layer "In9.Cu")
		(net "TDR_DIFF_100_IN3_DIN")
	)
	(segment
		(start 273.389344 -440.906916)
		(end 273.389344 -438.155842)
		(width 0.1397)
		(layer "In9.Cu")
		(net "TDR_DIFF_100_IN3_DIN")
	)
	(segment
		(start 278.883364 -441.033916)
		(end 277.483824 -441.033916)
		(width 0.1397)
		(layer "In9.Cu")
		(net "TDR_DIFF_100_IN3_DIN")
	)
	(segment
		(start 243.303044 -440.906916)
		(end 243.176044 -441.033916)
		(width 0.1397)
		(layer "In9.Cu")
		(net "TDR_DIFF_100_IN3_DIN")
	)
	(segment
		(start 249.26417 -437.835548)
		(end 247.590818 -437.835548)
		(width 0.1397)
		(layer "In9.Cu")
		(net "TDR_DIFF_100_IN3_DIN")
	)
	(segment
		(start 296.87901 -440.26836)
		(end 293.353744 -440.26836)
		(width 0.1397)
		(layer "In9.Cu")
		(net "TDR_DIFF_100_IN3_DIN")
	)
	(segment
		(start 235.241084 -440.26836)
		(end 233.115866 -440.26836)
		(width 0.1397)
		(layer "In9.Cu")
		(net "TDR_DIFF_100_IN3_DIN")
	)
	(segment
		(start 273.389344 -438.155842)
		(end 273.06905 -437.835548)
		(width 0.1397)
		(layer "In9.Cu")
		(net "TDR_DIFF_100_IN3_DIN")
	)
	(segment
		(start 239.208564 -440.998864)
		(end 237.809024 -440.998864)
		(width 0.1397)
		(layer "In9.Cu")
		(net "TDR_DIFF_100_IN3_DIN")
	)
	(segment
		(start 233.115866 -440.26836)
		(end 232.988866 -440.14136)
		(width 0.1397)
		(layer "In9.Cu")
		(net "TDR_DIFF_100_IN3_DIN")
	)
	(segment
		(start 290.912804 -438.155842)
		(end 290.912804 -440.906916)
		(width 0.1397)
		(layer "In9.Cu")
		(net "TDR_DIFF_100_IN3_DIN")
	)
	(segment
		(start 281.00401 -437.835548)
		(end 279.330658 -437.835548)
		(width 0.1397)
		(layer "In9.Cu")
		(net "TDR_DIFF_100_IN3_DIN")
	)
	(segment
		(start 297.009566 -440.137804)
		(end 296.87901 -440.26836)
		(width 0.1397)
		(layer "In9.Cu")
		(net "TDR_DIFF_100_IN3_DIN")
	)
	(segment
		(start 235.368084 -440.14136)
		(end 235.241084 -440.26836)
		(width 0.1397)
		(layer "In9.Cu")
		(net "TDR_DIFF_100_IN3_DIN")
	)
	(segment
		(start 290.912804 -440.906916)
		(end 290.785804 -441.033916)
		(width 0.1397)
		(layer "In9.Cu")
		(net "TDR_DIFF_100_IN3_DIN")
	)
	(segment
		(start 289.259264 -438.155842)
		(end 288.93897 -437.835548)
		(width 0.1397)
		(layer "In9.Cu")
		(net "TDR_DIFF_100_IN3_DIN")
	)
	(segment
		(start 237.36173 -437.835548)
		(end 235.688378 -437.835548)
		(width 0.1397)
		(layer "In9.Cu")
		(net "TDR_DIFF_100_IN3_DIN")
	)
	(segment
		(start 241.32921 -437.835548)
		(end 239.655858 -437.835548)
		(width 0.1397)
		(layer "In9.Cu")
		(net "TDR_DIFF_100_IN3_DIN")
	)
	(segment
		(start 239.655858 -437.835548)
		(end 239.335564 -438.155842)
		(width 0.1397)
		(layer "In9.Cu")
		(net "TDR_DIFF_100_IN3_DIN")
	)
	(segment
		(start 245.616984 -440.906916)
		(end 245.616984 -438.155842)
		(width 0.1397)
		(layer "In9.Cu")
		(net "TDR_DIFF_100_IN3_DIN")
	)
	(segment
		(start 241.776504 -441.033916)
		(end 241.649504 -440.906916)
		(width 0.1397)
		(layer "In9.Cu")
		(net "TDR_DIFF_100_IN3_DIN")
	)
	(segment
		(start 261.613904 -441.033916)
		(end 261.486904 -440.906916)
		(width 0.1397)
		(layer "In9.Cu")
		(net "TDR_DIFF_100_IN3_DIN")
	)
	(segment
		(start 275.042884 -440.906916)
		(end 274.915884 -441.033916)
		(width 0.1397)
		(layer "In9.Cu")
		(net "TDR_DIFF_100_IN3_DIN")
	)
	(segment
		(start 269.10157 -437.835548)
		(end 267.428218 -437.835548)
		(width 0.1397)
		(layer "In9.Cu")
		(net "TDR_DIFF_100_IN3_DIN")
	)
	(segment
		(start 273.06905 -437.835548)
		(end 271.395698 -437.835548)
		(width 0.1397)
		(layer "In9.Cu")
		(net "TDR_DIFF_100_IN3_DIN")
	)
	(segment
		(start 257.646424 -441.033916)
		(end 257.519424 -440.906916)
		(width 0.1397)
		(layer "In9.Cu")
		(net "TDR_DIFF_100_IN3_DIN")
	)
	(segment
		(start 253.23165 -437.835548)
		(end 251.558298 -437.835548)
		(width 0.1397)
		(layer "In9.Cu")
		(net "TDR_DIFF_100_IN3_DIN")
	)
	(segment
		(start 243.623338 -437.835548)
		(end 243.303044 -438.155842)
		(width 0.1397)
		(layer "In9.Cu")
		(net "TDR_DIFF_100_IN3_DIN")
	)
	(segment
		(start 251.558298 -437.835548)
		(end 251.238004 -438.155842)
		(width 0.1397)
		(layer "In9.Cu")
		(net "TDR_DIFF_100_IN3_DIN")
	)
	(segment
		(start 253.551944 -440.906916)
		(end 253.551944 -438.155842)
		(width 0.1397)
		(layer "In9.Cu")
		(net "TDR_DIFF_100_IN3_DIN")
	)
	(segment
		(start 277.483824 -441.033916)
		(end 277.356824 -440.906916)
		(width 0.1397)
		(layer "In9.Cu")
		(net "TDR_DIFF_100_IN3_DIN")
	)
	(segment
		(start 257.519424 -438.155842)
		(end 257.19913 -437.835548)
		(width 0.1397)
		(layer "In9.Cu")
		(net "TDR_DIFF_100_IN3_DIN")
	)
	(segment
		(start 289.386264 -441.033916)
		(end 289.259264 -440.906916)
		(width 0.1397)
		(layer "In9.Cu")
		(net "TDR_DIFF_100_IN3_DIN")
	)
	(segment
		(start 266.980924 -441.033916)
		(end 265.581384 -441.033916)
		(width 0.1397)
		(layer "In9.Cu")
		(net "TDR_DIFF_100_IN3_DIN")
	)
	(segment
		(start 245.616984 -438.155842)
		(end 245.29669 -437.835548)
		(width 0.1397)
		(layer "In9.Cu")
		(net "TDR_DIFF_100_IN3_DIN")
	)
	(segment
		(start 249.584464 -440.906916)
		(end 249.584464 -438.155842)
		(width 0.1397)
		(layer "In9.Cu")
		(net "TDR_DIFF_100_IN3_DIN")
	)
	(segment
		(start 261.16661 -437.835548)
		(end 259.493258 -437.835548)
		(width 0.1397)
		(layer "In9.Cu")
		(net "TDR_DIFF_100_IN3_DIN")
	)
	(segment
		(start 277.03653 -437.835548)
		(end 275.363178 -437.835548)
		(width 0.1397)
		(layer "In9.Cu")
		(net "TDR_DIFF_100_IN3_DIN")
	)
	(segment
		(start 286.818324 -441.033916)
		(end 285.418784 -441.033916)
		(width 0.1397)
		(layer "In9.Cu")
		(net "TDR_DIFF_100_IN3_DIN")
	)
	(segment
		(start 282.977844 -438.155842)
		(end 282.977844 -440.906916)
		(width 0.1397)
		(layer "In9.Cu")
		(net "TDR_DIFF_100_IN3_DIN")
	)
	(segment
		(start 265.13409 -437.835548)
		(end 263.460738 -437.835548)
		(width 0.1397)
		(layer "In9.Cu")
		(net "TDR_DIFF_100_IN3_DIN")
	)
	(segment
		(start 259.493258 -437.835548)
		(end 259.172964 -438.155842)
		(width 0.1397)
		(layer "In9.Cu")
		(net "TDR_DIFF_100_IN3_DIN")
	)
	(segment
		(start 277.356824 -438.155842)
		(end 277.03653 -437.835548)
		(width 0.1397)
		(layer "In9.Cu")
		(net "TDR_DIFF_100_IN3_DIN")
	)
	(segment
		(start 239.335564 -440.871864)
		(end 239.208564 -440.998864)
		(width 0.1397)
		(layer "In9.Cu")
		(net "TDR_DIFF_100_IN3_DIN")
	)
	(segment
		(start 257.519424 -440.906916)
		(end 257.519424 -438.155842)
		(width 0.1397)
		(layer "In9.Cu")
		(net "TDR_DIFF_100_IN3_DIN")
	)
	(segment
		(start 277.356824 -440.906916)
		(end 277.356824 -438.155842)
		(width 0.1397)
		(layer "In9.Cu")
		(net "TDR_DIFF_100_IN3_DIN")
	)
	(segment
		(start 237.809024 -440.998864)
		(end 237.682024 -440.871864)
		(width 0.1397)
		(layer "In9.Cu")
		(net "TDR_DIFF_100_IN3_DIN")
	)
	(segment
		(start 286.945324 -440.906916)
		(end 286.818324 -441.033916)
		(width 0.1397)
		(layer "In9.Cu")
		(net "TDR_DIFF_100_IN3_DIN")
	)
	(segment
		(start 281.451304 -441.033916)
		(end 281.324304 -440.906916)
		(width 0.1397)
		(layer "In9.Cu")
		(net "TDR_DIFF_100_IN3_DIN")
	)
	(segment
		(start 289.259264 -440.906916)
		(end 289.259264 -438.155842)
		(width 0.1397)
		(layer "In9.Cu")
		(net "TDR_DIFF_100_IN3_DIN")
	)
	(segment
		(start 241.649504 -440.906916)
		(end 241.649504 -438.155842)
		(width 0.1397)
		(layer "In9.Cu")
		(net "TDR_DIFF_100_IN3_DIN")
	)
	(segment
		(start 265.454384 -438.155842)
		(end 265.13409 -437.835548)
		(width 0.1397)
		(layer "In9.Cu")
		(net "TDR_DIFF_100_IN3_DIN")
	)
	(segment
		(start 255.078484 -441.033916)
		(end 253.678944 -441.033916)
		(width 0.1397)
		(layer "In9.Cu")
		(net "TDR_DIFF_100_IN3_DIN")
	)
	(segment
		(start 263.140444 -438.155842)
		(end 263.140444 -440.906916)
		(width 0.1397)
		(layer "In9.Cu")
		(net "TDR_DIFF_100_IN3_DIN")
	)
	(segment
		(start 243.303044 -438.155842)
		(end 243.303044 -440.906916)
		(width 0.1397)
		(layer "In9.Cu")
		(net "TDR_DIFF_100_IN3_DIN")
	)
	(segment
		(start 271.075404 -440.906916)
		(end 270.948404 -441.033916)
		(width 0.1397)
		(layer "In9.Cu")
		(net "TDR_DIFF_100_IN3_DIN")
	)
	(segment
		(start 269.548864 -441.033916)
		(end 269.421864 -440.906916)
		(width 0.1397)
		(layer "In9.Cu")
		(net "TDR_DIFF_100_IN3_DIN")
	)
	(segment
		(start 279.010364 -438.155842)
		(end 279.010364 -440.906916)
		(width 0.1397)
		(layer "In9.Cu")
		(net "TDR_DIFF_100_IN3_DIN")
	)
	(segment
		(start 282.850844 -441.033916)
		(end 281.451304 -441.033916)
		(width 0.1397)
		(layer "In9.Cu")
		(net "TDR_DIFF_100_IN3_DIN")
	)
	(segment
		(start 249.711464 -441.033916)
		(end 249.584464 -440.906916)
		(width 0.1397)
		(layer "In9.Cu")
		(net "TDR_DIFF_100_IN3_DIN")
	)
	(segment
		(start 286.945324 -438.155842)
		(end 286.945324 -440.906916)
		(width 0.1397)
		(layer "In9.Cu")
		(net "TDR_DIFF_100_IN3_DIN")
	)
	(segment
		(start 271.075404 -438.155842)
		(end 271.075404 -440.906916)
		(width 0.1397)
		(layer "In9.Cu")
		(net "TDR_DIFF_100_IN3_DIN")
	)
	(segment
		(start 253.551944 -438.155842)
		(end 253.23165 -437.835548)
		(width 0.1397)
		(layer "In9.Cu")
		(net "TDR_DIFF_100_IN3_DIN")
	)
	(segment
		(start 285.418784 -441.033916)
		(end 285.291784 -440.906916)
		(width 0.1397)
		(layer "In9.Cu")
		(net "TDR_DIFF_100_IN3_DIN")
	)
	(segment
		(start 251.238004 -440.906916)
		(end 251.111004 -441.033916)
		(width 0.1397)
		(layer "In9.Cu")
		(net "TDR_DIFF_100_IN3_DIN")
	)
	(segment
		(start 247.590818 -437.835548)
		(end 247.270524 -438.155842)
		(width 0.1397)
		(layer "In9.Cu")
		(net "TDR_DIFF_100_IN3_DIN")
	)
	(segment
		(start 275.363178 -437.835548)
		(end 275.042884 -438.155842)
		(width 0.1397)
		(layer "In9.Cu")
		(net "TDR_DIFF_100_IN3_DIN")
	)
	(segment
		(start 286.940752 -447.08191)
		(end 287.034986 -446.987676)
		(width 0.1143)
		(layer "B.Cu")
		(net "TDR_DIFF_100_BOT_DIN")
	)
	(segment
		(start 243.392706 -444.218822)
		(end 243.709952 -443.901576)
		(width 0.1143)
		(layer "B.Cu")
		(net "TDR_DIFF_100_BOT_DIN")
	)
	(segment
		(start 296.992802 -446.162684)
		(end 296.992802 -445.151764)
		(width 0.1143)
		(layer "B.Cu")
		(net "TDR_DIFF_100_BOT_DIN")
	)
	(segment
		(start 265.68908 -447.08191)
		(end 267.103352 -447.08191)
		(width 0.1143)
		(layer "B.Cu")
		(net "TDR_DIFF_100_BOT_DIN")
	)
	(segment
		(start 275.132546 -446.987676)
		(end 275.132546 -444.218822)
		(width 0.1143)
		(layer "B.Cu")
		(net "TDR_DIFF_100_BOT_DIN")
	)
	(segment
		(start 273.529806 -446.987676)
		(end 273.62404 -447.08191)
		(width 0.1143)
		(layer "B.Cu")
		(net "TDR_DIFF_100_BOT_DIN")
	)
	(segment
		(start 289.399726 -444.238126)
		(end 289.399726 -446.987676)
		(width 0.1143)
		(layer "B.Cu")
		(net "TDR_DIFF_100_BOT_DIN")
	)
	(segment
		(start 253.692406 -444.218822)
		(end 253.692406 -446.987676)
		(width 0.1143)
		(layer "B.Cu")
		(net "TDR_DIFF_100_BOT_DIN")
	)
	(segment
		(start 239.425226 -444.218822)
		(end 239.742472 -443.901576)
		(width 0.1143)
		(layer "B.Cu")
		(net "TDR_DIFF_100_BOT_DIN")
	)
	(segment
		(start 261.7216 -447.08191)
		(end 263.135872 -447.08191)
		(width 0.1143)
		(layer "B.Cu")
		(net "TDR_DIFF_100_BOT_DIN")
	)
	(segment
		(start 281.14752 -443.901576)
		(end 281.464766 -444.218822)
		(width 0.1143)
		(layer "B.Cu")
		(net "TDR_DIFF_100_BOT_DIN")
	)
	(segment
		(start 253.78664 -447.08191)
		(end 255.200912 -447.08191)
		(width 0.1143)
		(layer "B.Cu")
		(net "TDR_DIFF_100_BOT_DIN")
	)
	(segment
		(start 259.168392 -447.08191)
		(end 259.262626 -446.987676)
		(width 0.1143)
		(layer "B.Cu")
		(net "TDR_DIFF_100_BOT_DIN")
	)
	(segment
		(start 273.529806 -444.218822)
		(end 273.529806 -446.987676)
		(width 0.1143)
		(layer "B.Cu")
		(net "TDR_DIFF_100_BOT_DIN")
	)
	(segment
		(start 235.457746 -444.246254)
		(end 235.802424 -443.901576)
		(width 0.1143)
		(layer "B.Cu")
		(net "TDR_DIFF_100_BOT_DIN")
	)
	(segment
		(start 289.49396 -447.08191)
		(end 290.908232 -447.08191)
		(width 0.1143)
		(layer "B.Cu")
		(net "TDR_DIFF_100_BOT_DIN")
	)
	(segment
		(start 232.959402 -445.151764)
		(end 232.959402 -446.142364)
		(width 0.1143)
		(layer "B.Cu")
		(net "TDR_DIFF_100_BOT_DIN")
	)
	(segment
		(start 247.677432 -443.901576)
		(end 249.40768 -443.901576)
		(width 0.1143)
		(layer "B.Cu")
		(net "TDR_DIFF_100_BOT_DIN")
	)
	(segment
		(start 293.354506 -446.122552)
		(end 293.463218 -446.231264)
		(width 0.1143)
		(layer "B.Cu")
		(net "TDR_DIFF_100_BOT_DIN")
	)
	(segment
		(start 253.37516 -443.901576)
		(end 253.692406 -444.218822)
		(width 0.1143)
		(layer "B.Cu")
		(net "TDR_DIFF_100_BOT_DIN")
	)
	(segment
		(start 283.067506 -444.218822)
		(end 283.384752 -443.901576)
		(width 0.1143)
		(layer "B.Cu")
		(net "TDR_DIFF_100_BOT_DIN")
	)
	(segment
		(start 271.165066 -444.225934)
		(end 271.489424 -443.901576)
		(width 0.1143)
		(layer "B.Cu")
		(net "TDR_DIFF_100_BOT_DIN")
	)
	(segment
		(start 277.18004 -443.901576)
		(end 277.497286 -444.218822)
		(width 0.1143)
		(layer "B.Cu")
		(net "TDR_DIFF_100_BOT_DIN")
	)
	(segment
		(start 261.31012 -443.901576)
		(end 261.627366 -444.218822)
		(width 0.1143)
		(layer "B.Cu")
		(net "TDR_DIFF_100_BOT_DIN")
	)
	(segment
		(start 263.564624 -443.901576)
		(end 265.2776 -443.901576)
		(width 0.1143)
		(layer "B.Cu")
		(net "TDR_DIFF_100_BOT_DIN")
	)
	(segment
		(start 239.330992 -447.08191)
		(end 239.425226 -446.987676)
		(width 0.1143)
		(layer "B.Cu")
		(net "TDR_DIFF_100_BOT_DIN")
	)
	(segment
		(start 235.354876 -446.2399)
		(end 235.457746 -446.13703)
		(width 0.1143)
		(layer "B.Cu")
		(net "TDR_DIFF_100_BOT_DIN")
	)
	(segment
		(start 283.067506 -446.987676)
		(end 283.067506 -444.218822)
		(width 0.1143)
		(layer "B.Cu")
		(net "TDR_DIFF_100_BOT_DIN")
	)
	(segment
		(start 257.75412 -447.08191)
		(end 259.168392 -447.08191)
		(width 0.1143)
		(layer "B.Cu")
		(net "TDR_DIFF_100_BOT_DIN")
	)
	(segment
		(start 247.360186 -444.218822)
		(end 247.677432 -443.901576)
		(width 0.1143)
		(layer "B.Cu")
		(net "TDR_DIFF_100_BOT_DIN")
	)
	(segment
		(start 243.392706 -446.987676)
		(end 243.392706 -444.218822)
		(width 0.1143)
		(layer "B.Cu")
		(net "TDR_DIFF_100_BOT_DIN")
	)
	(segment
		(start 285.432246 -446.987676)
		(end 285.52648 -447.08191)
		(width 0.1143)
		(layer "B.Cu")
		(net "TDR_DIFF_100_BOT_DIN")
	)
	(segment
		(start 287.352232 -443.901576)
		(end 289.063176 -443.901576)
		(width 0.1143)
		(layer "B.Cu")
		(net "TDR_DIFF_100_BOT_DIN")
	)
	(segment
		(start 259.262626 -444.218822)
		(end 259.579872 -443.901576)
		(width 0.1143)
		(layer "B.Cu")
		(net "TDR_DIFF_100_BOT_DIN")
	)
	(segment
		(start 277.497286 -446.987676)
		(end 277.59152 -447.08191)
		(width 0.1143)
		(layer "B.Cu")
		(net "TDR_DIFF_100_BOT_DIN")
	)
	(segment
		(start 283.384752 -443.901576)
		(end 285.115 -443.901576)
		(width 0.1143)
		(layer "B.Cu")
		(net "TDR_DIFF_100_BOT_DIN")
	)
	(segment
		(start 273.21256 -443.901576)
		(end 273.529806 -444.218822)
		(width 0.1143)
		(layer "B.Cu")
		(net "TDR_DIFF_100_BOT_DIN")
	)
	(segment
		(start 257.659886 -444.218822)
		(end 257.659886 -446.987676)
		(width 0.1143)
		(layer "B.Cu")
		(net "TDR_DIFF_100_BOT_DIN")
	)
	(segment
		(start 271.165066 -446.987676)
		(end 271.165066 -444.225934)
		(width 0.1143)
		(layer "B.Cu")
		(net "TDR_DIFF_100_BOT_DIN")
	)
	(segment
		(start 289.063176 -443.901576)
		(end 289.399726 -444.238126)
		(width 0.1143)
		(layer "B.Cu")
		(net "TDR_DIFF_100_BOT_DIN")
	)
	(segment
		(start 267.103352 -447.08191)
		(end 267.197586 -446.987676)
		(width 0.1143)
		(layer "B.Cu")
		(net "TDR_DIFF_100_BOT_DIN")
	)
	(segment
		(start 267.552424 -443.901576)
		(end 269.24508 -443.901576)
		(width 0.1143)
		(layer "B.Cu")
		(net "TDR_DIFF_100_BOT_DIN")
	)
	(segment
		(start 253.692406 -446.987676)
		(end 253.78664 -447.08191)
		(width 0.1143)
		(layer "B.Cu")
		(net "TDR_DIFF_100_BOT_DIN")
	)
	(segment
		(start 263.135872 -447.08191)
		(end 263.230106 -446.987676)
		(width 0.1143)
		(layer "B.Cu")
		(net "TDR_DIFF_100_BOT_DIN")
	)
	(segment
		(start 245.757446 -446.987676)
		(end 245.85168 -447.08191)
		(width 0.1143)
		(layer "B.Cu")
		(net "TDR_DIFF_100_BOT_DIN")
	)
	(segment
		(start 239.742472 -443.901576)
		(end 241.47272 -443.901576)
		(width 0.1143)
		(layer "B.Cu")
		(net "TDR_DIFF_100_BOT_DIN")
	)
	(segment
		(start 291.325046 -443.914276)
		(end 293.01313 -443.914276)
		(width 0.1143)
		(layer "B.Cu")
		(net "TDR_DIFF_100_BOT_DIN")
	)
	(segment
		(start 279.100026 -446.987676)
		(end 279.100026 -444.241174)
		(width 0.1143)
		(layer "B.Cu")
		(net "TDR_DIFF_100_BOT_DIN")
	)
	(segment
		(start 237.50524 -443.901576)
		(end 237.822486 -444.218822)
		(width 0.1143)
		(layer "B.Cu")
		(net "TDR_DIFF_100_BOT_DIN")
	)
	(segment
		(start 267.197586 -444.256414)
		(end 267.552424 -443.901576)
		(width 0.1143)
		(layer "B.Cu")
		(net "TDR_DIFF_100_BOT_DIN")
	)
	(segment
		(start 287.034986 -444.218822)
		(end 287.352232 -443.901576)
		(width 0.1143)
		(layer "B.Cu")
		(net "TDR_DIFF_100_BOT_DIN")
	)
	(segment
		(start 296.924222 -446.231264)
		(end 296.992802 -446.162684)
		(width 0.1143)
		(layer "B.Cu")
		(net "TDR_DIFF_100_BOT_DIN")
	)
	(segment
		(start 269.562326 -444.218822)
		(end 269.562326 -446.987676)
		(width 0.1143)
		(layer "B.Cu")
		(net "TDR_DIFF_100_BOT_DIN")
	)
	(segment
		(start 255.639824 -443.901576)
		(end 257.34264 -443.901576)
		(width 0.1143)
		(layer "B.Cu")
		(net "TDR_DIFF_100_BOT_DIN")
	)
	(segment
		(start 243.709952 -443.901576)
		(end 245.4402 -443.901576)
		(width 0.1143)
		(layer "B.Cu")
		(net "TDR_DIFF_100_BOT_DIN")
	)
	(segment
		(start 265.2776 -443.901576)
		(end 265.594846 -444.218822)
		(width 0.1143)
		(layer "B.Cu")
		(net "TDR_DIFF_100_BOT_DIN")
	)
	(segment
		(start 290.908232 -447.08191)
		(end 291.002466 -446.987676)
		(width 0.1143)
		(layer "B.Cu")
		(net "TDR_DIFF_100_BOT_DIN")
	)
	(segment
		(start 269.65656 -447.08191)
		(end 271.070832 -447.08191)
		(width 0.1143)
		(layer "B.Cu")
		(net "TDR_DIFF_100_BOT_DIN")
	)
	(segment
		(start 241.8842 -447.08191)
		(end 243.298472 -447.08191)
		(width 0.1143)
		(layer "B.Cu")
		(net "TDR_DIFF_100_BOT_DIN")
	)
	(segment
		(start 241.789966 -444.218822)
		(end 241.789966 -446.987676)
		(width 0.1143)
		(layer "B.Cu")
		(net "TDR_DIFF_100_BOT_DIN")
	)
	(segment
		(start 267.197586 -446.987676)
		(end 267.197586 -444.256414)
		(width 0.1143)
		(layer "B.Cu")
		(net "TDR_DIFF_100_BOT_DIN")
	)
	(segment
		(start 289.399726 -446.987676)
		(end 289.49396 -447.08191)
		(width 0.1143)
		(layer "B.Cu")
		(net "TDR_DIFF_100_BOT_DIN")
	)
	(segment
		(start 265.594846 -444.218822)
		(end 265.594846 -446.987676)
		(width 0.1143)
		(layer "B.Cu")
		(net "TDR_DIFF_100_BOT_DIN")
	)
	(segment
		(start 271.489424 -443.901576)
		(end 273.21256 -443.901576)
		(width 0.1143)
		(layer "B.Cu")
		(net "TDR_DIFF_100_BOT_DIN")
	)
	(segment
		(start 291.002466 -446.987676)
		(end 291.002466 -444.236856)
		(width 0.1143)
		(layer "B.Cu")
		(net "TDR_DIFF_100_BOT_DIN")
	)
	(segment
		(start 265.594846 -446.987676)
		(end 265.68908 -447.08191)
		(width 0.1143)
		(layer "B.Cu")
		(net "TDR_DIFF_100_BOT_DIN")
	)
	(segment
		(start 257.34264 -443.901576)
		(end 257.659886 -444.218822)
		(width 0.1143)
		(layer "B.Cu")
		(net "TDR_DIFF_100_BOT_DIN")
	)
	(segment
		(start 279.439624 -443.901576)
		(end 281.14752 -443.901576)
		(width 0.1143)
		(layer "B.Cu")
		(net "TDR_DIFF_100_BOT_DIN")
	)
	(segment
		(start 245.85168 -447.08191)
		(end 247.265952 -447.08191)
		(width 0.1143)
		(layer "B.Cu")
		(net "TDR_DIFF_100_BOT_DIN")
	)
	(segment
		(start 235.802424 -443.901576)
		(end 237.50524 -443.901576)
		(width 0.1143)
		(layer "B.Cu")
		(net "TDR_DIFF_100_BOT_DIN")
	)
	(segment
		(start 251.233432 -447.08191)
		(end 251.327666 -446.987676)
		(width 0.1143)
		(layer "B.Cu")
		(net "TDR_DIFF_100_BOT_DIN")
	)
	(segment
		(start 245.757446 -444.218822)
		(end 245.757446 -446.987676)
		(width 0.1143)
		(layer "B.Cu")
		(net "TDR_DIFF_100_BOT_DIN")
	)
	(segment
		(start 263.230106 -444.236094)
		(end 263.564624 -443.901576)
		(width 0.1143)
		(layer "B.Cu")
		(net "TDR_DIFF_100_BOT_DIN")
	)
	(segment
		(start 287.034986 -446.987676)
		(end 287.034986 -444.218822)
		(width 0.1143)
		(layer "B.Cu")
		(net "TDR_DIFF_100_BOT_DIN")
	)
	(segment
		(start 269.562326 -446.987676)
		(end 269.65656 -447.08191)
		(width 0.1143)
		(layer "B.Cu")
		(net "TDR_DIFF_100_BOT_DIN")
	)
	(segment
		(start 285.432246 -444.218822)
		(end 285.432246 -446.987676)
		(width 0.1143)
		(layer "B.Cu")
		(net "TDR_DIFF_100_BOT_DIN")
	)
	(segment
		(start 249.40768 -443.901576)
		(end 249.724926 -444.218822)
		(width 0.1143)
		(layer "B.Cu")
		(net "TDR_DIFF_100_BOT_DIN")
	)
	(segment
		(start 241.789966 -446.987676)
		(end 241.8842 -447.08191)
		(width 0.1143)
		(layer "B.Cu")
		(net "TDR_DIFF_100_BOT_DIN")
	)
	(segment
		(start 243.298472 -447.08191)
		(end 243.392706 -446.987676)
		(width 0.1143)
		(layer "B.Cu")
		(net "TDR_DIFF_100_BOT_DIN")
	)
	(segment
		(start 249.724926 -446.987676)
		(end 249.81916 -447.08191)
		(width 0.1143)
		(layer "B.Cu")
		(net "TDR_DIFF_100_BOT_DIN")
	)
	(segment
		(start 273.62404 -447.08191)
		(end 275.038312 -447.08191)
		(width 0.1143)
		(layer "B.Cu")
		(net "TDR_DIFF_100_BOT_DIN")
	)
	(segment
		(start 259.262626 -446.987676)
		(end 259.262626 -444.218822)
		(width 0.1143)
		(layer "B.Cu")
		(net "TDR_DIFF_100_BOT_DIN")
	)
	(segment
		(start 275.132546 -444.218822)
		(end 275.449792 -443.901576)
		(width 0.1143)
		(layer "B.Cu")
		(net "TDR_DIFF_100_BOT_DIN")
	)
	(segment
		(start 249.81916 -447.08191)
		(end 251.233432 -447.08191)
		(width 0.1143)
		(layer "B.Cu")
		(net "TDR_DIFF_100_BOT_DIN")
	)
	(segment
		(start 281.464766 -446.987676)
		(end 281.559 -447.08191)
		(width 0.1143)
		(layer "B.Cu")
		(net "TDR_DIFF_100_BOT_DIN")
	)
	(segment
		(start 291.002466 -444.236856)
		(end 291.325046 -443.914276)
		(width 0.1143)
		(layer "B.Cu")
		(net "TDR_DIFF_100_BOT_DIN")
	)
	(segment
		(start 251.327666 -444.251334)
		(end 251.677424 -443.901576)
		(width 0.1143)
		(layer "B.Cu")
		(net "TDR_DIFF_100_BOT_DIN")
	)
	(segment
		(start 285.52648 -447.08191)
		(end 286.940752 -447.08191)
		(width 0.1143)
		(layer "B.Cu")
		(net "TDR_DIFF_100_BOT_DIN")
	)
	(segment
		(start 293.354506 -444.255652)
		(end 293.354506 -446.122552)
		(width 0.1143)
		(layer "B.Cu")
		(net "TDR_DIFF_100_BOT_DIN")
	)
	(segment
		(start 257.659886 -446.987676)
		(end 257.75412 -447.08191)
		(width 0.1143)
		(layer "B.Cu")
		(net "TDR_DIFF_100_BOT_DIN")
	)
	(segment
		(start 271.070832 -447.08191)
		(end 271.165066 -446.987676)
		(width 0.1143)
		(layer "B.Cu")
		(net "TDR_DIFF_100_BOT_DIN")
	)
	(segment
		(start 235.457746 -446.13703)
		(end 235.457746 -444.246254)
		(width 0.1143)
		(layer "B.Cu")
		(net "TDR_DIFF_100_BOT_DIN")
	)
	(segment
		(start 279.005792 -447.08191)
		(end 279.100026 -446.987676)
		(width 0.1143)
		(layer "B.Cu")
		(net "TDR_DIFF_100_BOT_DIN")
	)
	(segment
		(start 277.59152 -447.08191)
		(end 279.005792 -447.08191)
		(width 0.1143)
		(layer "B.Cu")
		(net "TDR_DIFF_100_BOT_DIN")
	)
	(segment
		(start 281.559 -447.08191)
		(end 282.973272 -447.08191)
		(width 0.1143)
		(layer "B.Cu")
		(net "TDR_DIFF_100_BOT_DIN")
	)
	(segment
		(start 263.230106 -446.987676)
		(end 263.230106 -444.236094)
		(width 0.1143)
		(layer "B.Cu")
		(net "TDR_DIFF_100_BOT_DIN")
	)
	(segment
		(start 275.038312 -447.08191)
		(end 275.132546 -446.987676)
		(width 0.1143)
		(layer "B.Cu")
		(net "TDR_DIFF_100_BOT_DIN")
	)
	(segment
		(start 255.295146 -446.987676)
		(end 255.295146 -444.246254)
		(width 0.1143)
		(layer "B.Cu")
		(net "TDR_DIFF_100_BOT_DIN")
	)
	(segment
		(start 255.295146 -444.246254)
		(end 255.639824 -443.901576)
		(width 0.1143)
		(layer "B.Cu")
		(net "TDR_DIFF_100_BOT_DIN")
	)
	(segment
		(start 237.822486 -446.987676)
		(end 237.91672 -447.08191)
		(width 0.1143)
		(layer "B.Cu")
		(net "TDR_DIFF_100_BOT_DIN")
	)
	(segment
		(start 247.265952 -447.08191)
		(end 247.360186 -446.987676)
		(width 0.1143)
		(layer "B.Cu")
		(net "TDR_DIFF_100_BOT_DIN")
	)
	(segment
		(start 259.579872 -443.901576)
		(end 261.31012 -443.901576)
		(width 0.1143)
		(layer "B.Cu")
		(net "TDR_DIFF_100_BOT_DIN")
	)
	(segment
		(start 245.4402 -443.901576)
		(end 245.757446 -444.218822)
		(width 0.1143)
		(layer "B.Cu")
		(net "TDR_DIFF_100_BOT_DIN")
	)
	(segment
		(start 261.627366 -446.987676)
		(end 261.7216 -447.08191)
		(width 0.1143)
		(layer "B.Cu")
		(net "TDR_DIFF_100_BOT_DIN")
	)
	(segment
		(start 233.056938 -446.2399)
		(end 235.354876 -446.2399)
		(width 0.1143)
		(layer "B.Cu")
		(net "TDR_DIFF_100_BOT_DIN")
	)
	(segment
		(start 269.24508 -443.901576)
		(end 269.562326 -444.218822)
		(width 0.1143)
		(layer "B.Cu")
		(net "TDR_DIFF_100_BOT_DIN")
	)
	(segment
		(start 293.01313 -443.914276)
		(end 293.354506 -444.255652)
		(width 0.1143)
		(layer "B.Cu")
		(net "TDR_DIFF_100_BOT_DIN")
	)
	(segment
		(start 277.497286 -444.218822)
		(end 277.497286 -446.987676)
		(width 0.1143)
		(layer "B.Cu")
		(net "TDR_DIFF_100_BOT_DIN")
	)
	(segment
		(start 255.200912 -447.08191)
		(end 255.295146 -446.987676)
		(width 0.1143)
		(layer "B.Cu")
		(net "TDR_DIFF_100_BOT_DIN")
	)
	(segment
		(start 251.677424 -443.901576)
		(end 253.37516 -443.901576)
		(width 0.1143)
		(layer "B.Cu")
		(net "TDR_DIFF_100_BOT_DIN")
	)
	(segment
		(start 261.627366 -444.218822)
		(end 261.627366 -446.987676)
		(width 0.1143)
		(layer "B.Cu")
		(net "TDR_DIFF_100_BOT_DIN")
	)
	(segment
		(start 251.327666 -446.987676)
		(end 251.327666 -444.251334)
		(width 0.1143)
		(layer "B.Cu")
		(net "TDR_DIFF_100_BOT_DIN")
	)
	(segment
		(start 285.115 -443.901576)
		(end 285.432246 -444.218822)
		(width 0.1143)
		(layer "B.Cu")
		(net "TDR_DIFF_100_BOT_DIN")
	)
	(segment
		(start 282.973272 -447.08191)
		(end 283.067506 -446.987676)
		(width 0.1143)
		(layer "B.Cu")
		(net "TDR_DIFF_100_BOT_DIN")
	)
	(segment
		(start 247.360186 -446.987676)
		(end 247.360186 -444.218822)
		(width 0.1143)
		(layer "B.Cu")
		(net "TDR_DIFF_100_BOT_DIN")
	)
	(segment
		(start 239.425226 -446.987676)
		(end 239.425226 -444.218822)
		(width 0.1143)
		(layer "B.Cu")
		(net "TDR_DIFF_100_BOT_DIN")
	)
	(segment
		(start 241.47272 -443.901576)
		(end 241.789966 -444.218822)
		(width 0.1143)
		(layer "B.Cu")
		(net "TDR_DIFF_100_BOT_DIN")
	)
	(segment
		(start 275.449792 -443.901576)
		(end 277.18004 -443.901576)
		(width 0.1143)
		(layer "B.Cu")
		(net "TDR_DIFF_100_BOT_DIN")
	)
	(segment
		(start 293.463218 -446.231264)
		(end 296.924222 -446.231264)
		(width 0.1143)
		(layer "B.Cu")
		(net "TDR_DIFF_100_BOT_DIN")
	)
	(segment
		(start 237.91672 -447.08191)
		(end 239.330992 -447.08191)
		(width 0.1143)
		(layer "B.Cu")
		(net "TDR_DIFF_100_BOT_DIN")
	)
	(segment
		(start 249.724926 -444.218822)
		(end 249.724926 -446.987676)
		(width 0.1143)
		(layer "B.Cu")
		(net "TDR_DIFF_100_BOT_DIN")
	)
	(segment
		(start 279.100026 -444.241174)
		(end 279.439624 -443.901576)
		(width 0.1143)
		(layer "B.Cu")
		(net "TDR_DIFF_100_BOT_DIN")
	)
	(segment
		(start 232.959402 -446.142364)
		(end 233.056938 -446.2399)
		(width 0.1143)
		(layer "B.Cu")
		(net "TDR_DIFF_100_BOT_DIN")
	)
	(segment
		(start 281.464766 -444.218822)
		(end 281.464766 -446.987676)
		(width 0.1143)
		(layer "B.Cu")
		(net "TDR_DIFF_100_BOT_DIN")
	)
	(segment
		(start 237.822486 -444.218822)
		(end 237.822486 -446.987676)
		(width 0.1143)
		(layer "B.Cu")
		(net "TDR_DIFF_100_BOT_DIN")
	)
	(segment
		(start 176.250092 -444.080138)
		(end 176.123092 -443.953138)
		(width 0.1397)
		(layer "In13.Cu")
		(net "TDR_DIFF_100_IN5_DIP")
	)
	(segment
		(start 176.123092 -443.953138)
		(end 174.723552 -443.953138)
		(width 0.1397)
		(layer "In13.Cu")
		(net "TDR_DIFF_100_IN5_DIP")
	)
	(segment
		(start 164.220652 -443.953138)
		(end 162.821112 -443.953138)
		(width 0.1397)
		(layer "In13.Cu")
		(net "TDR_DIFF_100_IN5_DIP")
	)
	(segment
		(start 170.308778 -447.148966)
		(end 168.635426 -447.148966)
		(width 0.1397)
		(layer "In13.Cu")
		(net "TDR_DIFF_100_IN5_DIP")
	)
	(segment
		(start 196.087492 -444.080138)
		(end 195.960492 -443.953138)
		(width 0.1397)
		(layer "In13.Cu")
		(net "TDR_DIFF_100_IN5_DIP")
	)
	(segment
		(start 166.661592 -444.080138)
		(end 166.661592 -446.79362)
		(width 0.1397)
		(layer "In13.Cu")
		(net "TDR_DIFF_100_IN5_DIP")
	)
	(segment
		(start 210.303872 -446.828672)
		(end 209.983578 -447.148966)
		(width 0.1397)
		(layer "In13.Cu")
		(net "TDR_DIFF_100_IN5_DIP")
	)
	(segment
		(start 186.498992 -446.828672)
		(end 186.178698 -447.148966)
		(width 0.1397)
		(layer "In13.Cu")
		(net "TDR_DIFF_100_IN5_DIP")
	)
	(segment
		(start 178.564032 -446.828672)
		(end 178.243738 -447.148966)
		(width 0.1397)
		(layer "In13.Cu")
		(net "TDR_DIFF_100_IN5_DIP")
	)
	(segment
		(start 204.342746 -447.148966)
		(end 204.022452 -446.828672)
		(width 0.1397)
		(layer "In13.Cu")
		(net "TDR_DIFF_100_IN5_DIP")
	)
	(segment
		(start 172.602906 -447.148966)
		(end 172.282612 -446.828672)
		(width 0.1397)
		(layer "In13.Cu")
		(net "TDR_DIFF_100_IN5_DIP")
	)
	(segment
		(start 207.989932 -444.080138)
		(end 207.862932 -443.953138)
		(width 0.1397)
		(layer "In13.Cu")
		(net "TDR_DIFF_100_IN5_DIP")
	)
	(segment
		(start 206.463392 -443.953138)
		(end 206.336392 -444.080138)
		(width 0.1397)
		(layer "In13.Cu")
		(net "TDR_DIFF_100_IN5_DIP")
	)
	(segment
		(start 172.282612 -446.828672)
		(end 172.282612 -444.080138)
		(width 0.1397)
		(layer "In13.Cu")
		(net "TDR_DIFF_100_IN5_DIP")
	)
	(segment
		(start 186.178698 -447.148966)
		(end 184.505346 -447.148966)
		(width 0.1397)
		(layer "In13.Cu")
		(net "TDR_DIFF_100_IN5_DIP")
	)
	(segment
		(start 180.090572 -443.953138)
		(end 178.691032 -443.953138)
		(width 0.1397)
		(layer "In13.Cu")
		(net "TDR_DIFF_100_IN5_DIP")
	)
	(segment
		(start 219.892372 -444.080138)
		(end 219.765372 -443.953138)
		(width 0.1397)
		(layer "In13.Cu")
		(net "TDR_DIFF_100_IN5_DIP")
	)
	(segment
		(start 206.336392 -446.828672)
		(end 206.016098 -447.148966)
		(width 0.1397)
		(layer "In13.Cu")
		(net "TDR_DIFF_100_IN5_DIP")
	)
	(segment
		(start 211.830412 -443.953138)
		(end 210.430872 -443.953138)
		(width 0.1397)
		(layer "In13.Cu")
		(net "TDR_DIFF_100_IN5_DIP")
	)
	(segment
		(start 194.560952 -443.953138)
		(end 194.433952 -444.080138)
		(width 0.1397)
		(layer "In13.Cu")
		(net "TDR_DIFF_100_IN5_DIP")
	)
	(segment
		(start 176.250092 -446.828672)
		(end 176.250092 -444.080138)
		(width 0.1397)
		(layer "In13.Cu")
		(net "TDR_DIFF_100_IN5_DIP")
	)
	(segment
		(start 168.635426 -447.148966)
		(end 168.315132 -446.828672)
		(width 0.1397)
		(layer "In13.Cu")
		(net "TDR_DIFF_100_IN5_DIP")
	)
	(segment
		(start 160.111694 -446.38341)
		(end 159.984694 -446.51041)
		(width 0.1397)
		(layer "In13.Cu")
		(net "TDR_DIFF_100_IN5_DIP")
	)
	(segment
		(start 190.466472 -446.828672)
		(end 190.146178 -447.148966)
		(width 0.1397)
		(layer "In13.Cu")
		(net "TDR_DIFF_100_IN5_DIP")
	)
	(segment
		(start 164.347652 -444.080138)
		(end 164.220652 -443.953138)
		(width 0.1397)
		(layer "In13.Cu")
		(net "TDR_DIFF_100_IN5_DIP")
	)
	(segment
		(start 208.310226 -447.148966)
		(end 207.989932 -446.828672)
		(width 0.1397)
		(layer "In13.Cu")
		(net "TDR_DIFF_100_IN5_DIP")
	)
	(segment
		(start 184.185052 -444.080138)
		(end 184.058052 -443.953138)
		(width 0.1397)
		(layer "In13.Cu")
		(net "TDR_DIFF_100_IN5_DIP")
	)
	(segment
		(start 164.347652 -446.79362)
		(end 164.347652 -444.080138)
		(width 0.1397)
		(layer "In13.Cu")
		(net "TDR_DIFF_100_IN5_DIP")
	)
	(segment
		(start 213.951058 -447.148966)
		(end 212.277706 -447.148966)
		(width 0.1397)
		(layer "In13.Cu")
		(net "TDR_DIFF_100_IN5_DIP")
	)
	(segment
		(start 214.271352 -446.828672)
		(end 213.951058 -447.148966)
		(width 0.1397)
		(layer "In13.Cu")
		(net "TDR_DIFF_100_IN5_DIP")
	)
	(segment
		(start 168.315132 -446.828672)
		(end 168.315132 -444.080138)
		(width 0.1397)
		(layer "In13.Cu")
		(net "TDR_DIFF_100_IN5_DIP")
	)
	(segment
		(start 207.862932 -443.953138)
		(end 206.463392 -443.953138)
		(width 0.1397)
		(layer "In13.Cu")
		(net "TDR_DIFF_100_IN5_DIP")
	)
	(segment
		(start 196.087492 -446.828672)
		(end 196.087492 -444.080138)
		(width 0.1397)
		(layer "In13.Cu")
		(net "TDR_DIFF_100_IN5_DIP")
	)
	(segment
		(start 174.276258 -447.148966)
		(end 172.602906 -447.148966)
		(width 0.1397)
		(layer "In13.Cu")
		(net "TDR_DIFF_100_IN5_DIP")
	)
	(segment
		(start 192.120012 -444.080138)
		(end 191.993012 -443.953138)
		(width 0.1397)
		(layer "In13.Cu")
		(net "TDR_DIFF_100_IN5_DIP")
	)
	(segment
		(start 182.211218 -447.148966)
		(end 180.537866 -447.148966)
		(width 0.1397)
		(layer "In13.Cu")
		(net "TDR_DIFF_100_IN5_DIP")
	)
	(segment
		(start 191.993012 -443.953138)
		(end 190.593472 -443.953138)
		(width 0.1397)
		(layer "In13.Cu")
		(net "TDR_DIFF_100_IN5_DIP")
	)
	(segment
		(start 194.113658 -447.148966)
		(end 192.440306 -447.148966)
		(width 0.1397)
		(layer "In13.Cu")
		(net "TDR_DIFF_100_IN5_DIP")
	)
	(segment
		(start 170.756072 -443.953138)
		(end 170.629072 -444.080138)
		(width 0.1397)
		(layer "In13.Cu")
		(net "TDR_DIFF_100_IN5_DIP")
	)
	(segment
		(start 188.152532 -446.828672)
		(end 188.152532 -444.080138)
		(width 0.1397)
		(layer "In13.Cu")
		(net "TDR_DIFF_100_IN5_DIP")
	)
	(segment
		(start 174.596552 -444.080138)
		(end 174.596552 -446.828672)
		(width 0.1397)
		(layer "In13.Cu")
		(net "TDR_DIFF_100_IN5_DIP")
	)
	(segment
		(start 174.723552 -443.953138)
		(end 174.596552 -444.080138)
		(width 0.1397)
		(layer "In13.Cu")
		(net "TDR_DIFF_100_IN5_DIP")
	)
	(segment
		(start 195.960492 -443.953138)
		(end 194.560952 -443.953138)
		(width 0.1397)
		(layer "In13.Cu")
		(net "TDR_DIFF_100_IN5_DIP")
	)
	(segment
		(start 211.957412 -444.080138)
		(end 211.830412 -443.953138)
		(width 0.1397)
		(layer "In13.Cu")
		(net "TDR_DIFF_100_IN5_DIP")
	)
	(segment
		(start 209.983578 -447.148966)
		(end 208.310226 -447.148966)
		(width 0.1397)
		(layer "In13.Cu")
		(net "TDR_DIFF_100_IN5_DIP")
	)
	(segment
		(start 224.005394 -446.490598)
		(end 223.898206 -446.38341)
		(width 0.1397)
		(layer "In13.Cu")
		(net "TDR_DIFF_100_IN5_DIP")
	)
	(segment
		(start 190.146178 -447.148966)
		(end 188.472826 -447.148966)
		(width 0.1397)
		(layer "In13.Cu")
		(net "TDR_DIFF_100_IN5_DIP")
	)
	(segment
		(start 182.531512 -446.828672)
		(end 182.211218 -447.148966)
		(width 0.1397)
		(layer "In13.Cu")
		(net "TDR_DIFF_100_IN5_DIP")
	)
	(segment
		(start 188.152532 -444.080138)
		(end 188.025532 -443.953138)
		(width 0.1397)
		(layer "In13.Cu")
		(net "TDR_DIFF_100_IN5_DIP")
	)
	(segment
		(start 220.212666 -446.38341)
		(end 219.892372 -446.063116)
		(width 0.1397)
		(layer "In13.Cu")
		(net "TDR_DIFF_100_IN5_DIP")
	)
	(segment
		(start 168.315132 -444.080138)
		(end 168.188132 -443.953138)
		(width 0.1397)
		(layer "In13.Cu")
		(net "TDR_DIFF_100_IN5_DIP")
	)
	(segment
		(start 215.924892 -446.828672)
		(end 215.924892 -444.080138)
		(width 0.1397)
		(layer "In13.Cu")
		(net "TDR_DIFF_100_IN5_DIP")
	)
	(segment
		(start 180.537866 -447.148966)
		(end 180.217572 -446.828672)
		(width 0.1397)
		(layer "In13.Cu")
		(net "TDR_DIFF_100_IN5_DIP")
	)
	(segment
		(start 202.495912 -443.953138)
		(end 202.368912 -444.080138)
		(width 0.1397)
		(layer "In13.Cu")
		(net "TDR_DIFF_100_IN5_DIP")
	)
	(segment
		(start 190.466472 -444.080138)
		(end 190.466472 -446.828672)
		(width 0.1397)
		(layer "In13.Cu")
		(net "TDR_DIFF_100_IN5_DIP")
	)
	(segment
		(start 162.694112 -446.063116)
		(end 162.373818 -446.38341)
		(width 0.1397)
		(layer "In13.Cu")
		(net "TDR_DIFF_100_IN5_DIP")
	)
	(segment
		(start 202.368912 -446.828672)
		(end 202.048618 -447.148966)
		(width 0.1397)
		(layer "In13.Cu")
		(net "TDR_DIFF_100_IN5_DIP")
	)
	(segment
		(start 202.368912 -444.080138)
		(end 202.368912 -446.828672)
		(width 0.1397)
		(layer "In13.Cu")
		(net "TDR_DIFF_100_IN5_DIP")
	)
	(segment
		(start 214.271352 -444.080138)
		(end 214.271352 -446.828672)
		(width 0.1397)
		(layer "In13.Cu")
		(net "TDR_DIFF_100_IN5_DIP")
	)
	(segment
		(start 216.245186 -447.148966)
		(end 215.924892 -446.828672)
		(width 0.1397)
		(layer "In13.Cu")
		(net "TDR_DIFF_100_IN5_DIP")
	)
	(segment
		(start 204.022452 -446.828672)
		(end 204.022452 -444.080138)
		(width 0.1397)
		(layer "In13.Cu")
		(net "TDR_DIFF_100_IN5_DIP")
	)
	(segment
		(start 162.821112 -443.953138)
		(end 162.694112 -444.080138)
		(width 0.1397)
		(layer "In13.Cu")
		(net "TDR_DIFF_100_IN5_DIP")
	)
	(segment
		(start 188.025532 -443.953138)
		(end 186.625992 -443.953138)
		(width 0.1397)
		(layer "In13.Cu")
		(net "TDR_DIFF_100_IN5_DIP")
	)
	(segment
		(start 178.243738 -447.148966)
		(end 176.570386 -447.148966)
		(width 0.1397)
		(layer "In13.Cu")
		(net "TDR_DIFF_100_IN5_DIP")
	)
	(segment
		(start 176.570386 -447.148966)
		(end 176.250092 -446.828672)
		(width 0.1397)
		(layer "In13.Cu")
		(net "TDR_DIFF_100_IN5_DIP")
	)
	(segment
		(start 168.188132 -443.953138)
		(end 166.788592 -443.953138)
		(width 0.1397)
		(layer "In13.Cu")
		(net "TDR_DIFF_100_IN5_DIP")
	)
	(segment
		(start 184.505346 -447.148966)
		(end 184.185052 -446.828672)
		(width 0.1397)
		(layer "In13.Cu")
		(net "TDR_DIFF_100_IN5_DIP")
	)
	(segment
		(start 212.277706 -447.148966)
		(end 211.957412 -446.828672)
		(width 0.1397)
		(layer "In13.Cu")
		(net "TDR_DIFF_100_IN5_DIP")
	)
	(segment
		(start 164.667946 -447.113914)
		(end 164.347652 -446.79362)
		(width 0.1397)
		(layer "In13.Cu")
		(net "TDR_DIFF_100_IN5_DIP")
	)
	(segment
		(start 215.924892 -444.080138)
		(end 215.797892 -443.953138)
		(width 0.1397)
		(layer "In13.Cu")
		(net "TDR_DIFF_100_IN5_DIP")
	)
	(segment
		(start 218.238832 -444.080138)
		(end 218.238832 -446.828672)
		(width 0.1397)
		(layer "In13.Cu")
		(net "TDR_DIFF_100_IN5_DIP")
	)
	(segment
		(start 186.498992 -444.080138)
		(end 186.498992 -446.828672)
		(width 0.1397)
		(layer "In13.Cu")
		(net "TDR_DIFF_100_IN5_DIP")
	)
	(segment
		(start 200.054972 -444.080138)
		(end 199.927972 -443.953138)
		(width 0.1397)
		(layer "In13.Cu")
		(net "TDR_DIFF_100_IN5_DIP")
	)
	(segment
		(start 217.918538 -447.148966)
		(end 216.245186 -447.148966)
		(width 0.1397)
		(layer "In13.Cu")
		(net "TDR_DIFF_100_IN5_DIP")
	)
	(segment
		(start 192.440306 -447.148966)
		(end 192.120012 -446.828672)
		(width 0.1397)
		(layer "In13.Cu")
		(net "TDR_DIFF_100_IN5_DIP")
	)
	(segment
		(start 194.433952 -444.080138)
		(end 194.433952 -446.828672)
		(width 0.1397)
		(layer "In13.Cu")
		(net "TDR_DIFF_100_IN5_DIP")
	)
	(segment
		(start 219.765372 -443.953138)
		(end 218.365832 -443.953138)
		(width 0.1397)
		(layer "In13.Cu")
		(net "TDR_DIFF_100_IN5_DIP")
	)
	(segment
		(start 170.629072 -446.828672)
		(end 170.308778 -447.148966)
		(width 0.1397)
		(layer "In13.Cu")
		(net "TDR_DIFF_100_IN5_DIP")
	)
	(segment
		(start 162.694112 -444.080138)
		(end 162.694112 -446.063116)
		(width 0.1397)
		(layer "In13.Cu")
		(net "TDR_DIFF_100_IN5_DIP")
	)
	(segment
		(start 178.691032 -443.953138)
		(end 178.564032 -444.080138)
		(width 0.1397)
		(layer "In13.Cu")
		(net "TDR_DIFF_100_IN5_DIP")
	)
	(segment
		(start 198.081138 -447.148966)
		(end 196.407786 -447.148966)
		(width 0.1397)
		(layer "In13.Cu")
		(net "TDR_DIFF_100_IN5_DIP")
	)
	(segment
		(start 206.336392 -444.080138)
		(end 206.336392 -446.828672)
		(width 0.1397)
		(layer "In13.Cu")
		(net "TDR_DIFF_100_IN5_DIP")
	)
	(segment
		(start 166.788592 -443.953138)
		(end 166.661592 -444.080138)
		(width 0.1397)
		(layer "In13.Cu")
		(net "TDR_DIFF_100_IN5_DIP")
	)
	(segment
		(start 192.120012 -446.828672)
		(end 192.120012 -444.080138)
		(width 0.1397)
		(layer "In13.Cu")
		(net "TDR_DIFF_100_IN5_DIP")
	)
	(segment
		(start 170.629072 -444.080138)
		(end 170.629072 -446.828672)
		(width 0.1397)
		(layer "In13.Cu")
		(net "TDR_DIFF_100_IN5_DIP")
	)
	(segment
		(start 166.661592 -446.79362)
		(end 166.341298 -447.113914)
		(width 0.1397)
		(layer "In13.Cu")
		(net "TDR_DIFF_100_IN5_DIP")
	)
	(segment
		(start 219.892372 -446.063116)
		(end 219.892372 -444.080138)
		(width 0.1397)
		(layer "In13.Cu")
		(net "TDR_DIFF_100_IN5_DIP")
	)
	(segment
		(start 166.341298 -447.113914)
		(end 164.667946 -447.113914)
		(width 0.1397)
		(layer "In13.Cu")
		(net "TDR_DIFF_100_IN5_DIP")
	)
	(segment
		(start 184.058052 -443.953138)
		(end 182.658512 -443.953138)
		(width 0.1397)
		(layer "In13.Cu")
		(net "TDR_DIFF_100_IN5_DIP")
	)
	(segment
		(start 200.375266 -447.148966)
		(end 200.054972 -446.828672)
		(width 0.1397)
		(layer "In13.Cu")
		(net "TDR_DIFF_100_IN5_DIP")
	)
	(segment
		(start 198.528432 -443.953138)
		(end 198.401432 -444.080138)
		(width 0.1397)
		(layer "In13.Cu")
		(net "TDR_DIFF_100_IN5_DIP")
	)
	(segment
		(start 200.054972 -446.828672)
		(end 200.054972 -444.080138)
		(width 0.1397)
		(layer "In13.Cu")
		(net "TDR_DIFF_100_IN5_DIP")
	)
	(segment
		(start 172.155612 -443.953138)
		(end 170.756072 -443.953138)
		(width 0.1397)
		(layer "In13.Cu")
		(net "TDR_DIFF_100_IN5_DIP")
	)
	(segment
		(start 159.984694 -446.51041)
		(end 159.984694 -447.48831)
		(width 0.1397)
		(layer "In13.Cu")
		(net "TDR_DIFF_100_IN5_DIP")
	)
	(segment
		(start 210.430872 -443.953138)
		(end 210.303872 -444.080138)
		(width 0.1397)
		(layer "In13.Cu")
		(net "TDR_DIFF_100_IN5_DIP")
	)
	(segment
		(start 196.407786 -447.148966)
		(end 196.087492 -446.828672)
		(width 0.1397)
		(layer "In13.Cu")
		(net "TDR_DIFF_100_IN5_DIP")
	)
	(segment
		(start 199.927972 -443.953138)
		(end 198.528432 -443.953138)
		(width 0.1397)
		(layer "In13.Cu")
		(net "TDR_DIFF_100_IN5_DIP")
	)
	(segment
		(start 174.596552 -446.828672)
		(end 174.276258 -447.148966)
		(width 0.1397)
		(layer "In13.Cu")
		(net "TDR_DIFF_100_IN5_DIP")
	)
	(segment
		(start 214.398352 -443.953138)
		(end 214.271352 -444.080138)
		(width 0.1397)
		(layer "In13.Cu")
		(net "TDR_DIFF_100_IN5_DIP")
	)
	(segment
		(start 206.016098 -447.148966)
		(end 204.342746 -447.148966)
		(width 0.1397)
		(layer "In13.Cu")
		(net "TDR_DIFF_100_IN5_DIP")
	)
	(segment
		(start 180.217572 -444.080138)
		(end 180.090572 -443.953138)
		(width 0.1397)
		(layer "In13.Cu")
		(net "TDR_DIFF_100_IN5_DIP")
	)
	(segment
		(start 203.895452 -443.953138)
		(end 202.495912 -443.953138)
		(width 0.1397)
		(layer "In13.Cu")
		(net "TDR_DIFF_100_IN5_DIP")
	)
	(segment
		(start 211.957412 -446.828672)
		(end 211.957412 -444.080138)
		(width 0.1397)
		(layer "In13.Cu")
		(net "TDR_DIFF_100_IN5_DIP")
	)
	(segment
		(start 198.401432 -444.080138)
		(end 198.401432 -446.828672)
		(width 0.1397)
		(layer "In13.Cu")
		(net "TDR_DIFF_100_IN5_DIP")
	)
	(segment
		(start 223.898206 -446.38341)
		(end 220.212666 -446.38341)
		(width 0.1397)
		(layer "In13.Cu")
		(net "TDR_DIFF_100_IN5_DIP")
	)
	(segment
		(start 218.365832 -443.953138)
		(end 218.238832 -444.080138)
		(width 0.1397)
		(layer "In13.Cu")
		(net "TDR_DIFF_100_IN5_DIP")
	)
	(segment
		(start 224.005394 -447.48831)
		(end 224.005394 -446.490598)
		(width 0.1397)
		(layer "In13.Cu")
		(net "TDR_DIFF_100_IN5_DIP")
	)
	(segment
		(start 207.989932 -446.828672)
		(end 207.989932 -444.080138)
		(width 0.1397)
		(layer "In13.Cu")
		(net "TDR_DIFF_100_IN5_DIP")
	)
	(segment
		(start 182.658512 -443.953138)
		(end 182.531512 -444.080138)
		(width 0.1397)
		(layer "In13.Cu")
		(net "TDR_DIFF_100_IN5_DIP")
	)
	(segment
		(start 190.593472 -443.953138)
		(end 190.466472 -444.080138)
		(width 0.1397)
		(layer "In13.Cu")
		(net "TDR_DIFF_100_IN5_DIP")
	)
	(segment
		(start 210.303872 -444.080138)
		(end 210.303872 -446.828672)
		(width 0.1397)
		(layer "In13.Cu")
		(net "TDR_DIFF_100_IN5_DIP")
	)
	(segment
		(start 180.217572 -446.828672)
		(end 180.217572 -444.080138)
		(width 0.1397)
		(layer "In13.Cu")
		(net "TDR_DIFF_100_IN5_DIP")
	)
	(segment
		(start 218.238832 -446.828672)
		(end 217.918538 -447.148966)
		(width 0.1397)
		(layer "In13.Cu")
		(net "TDR_DIFF_100_IN5_DIP")
	)
	(segment
		(start 194.433952 -446.828672)
		(end 194.113658 -447.148966)
		(width 0.1397)
		(layer "In13.Cu")
		(net "TDR_DIFF_100_IN5_DIP")
	)
	(segment
		(start 182.531512 -444.080138)
		(end 182.531512 -446.828672)
		(width 0.1397)
		(layer "In13.Cu")
		(net "TDR_DIFF_100_IN5_DIP")
	)
	(segment
		(start 162.373818 -446.38341)
		(end 160.111694 -446.38341)
		(width 0.1397)
		(layer "In13.Cu")
		(net "TDR_DIFF_100_IN5_DIP")
	)
	(segment
		(start 178.564032 -444.080138)
		(end 178.564032 -446.828672)
		(width 0.1397)
		(layer "In13.Cu")
		(net "TDR_DIFF_100_IN5_DIP")
	)
	(segment
		(start 172.282612 -444.080138)
		(end 172.155612 -443.953138)
		(width 0.1397)
		(layer "In13.Cu")
		(net "TDR_DIFF_100_IN5_DIP")
	)
	(segment
		(start 184.185052 -446.828672)
		(end 184.185052 -444.080138)
		(width 0.1397)
		(layer "In13.Cu")
		(net "TDR_DIFF_100_IN5_DIP")
	)
	(segment
		(start 188.472826 -447.148966)
		(end 188.152532 -446.828672)
		(width 0.1397)
		(layer "In13.Cu")
		(net "TDR_DIFF_100_IN5_DIP")
	)
	(segment
		(start 215.797892 -443.953138)
		(end 214.398352 -443.953138)
		(width 0.1397)
		(layer "In13.Cu")
		(net "TDR_DIFF_100_IN5_DIP")
	)
	(segment
		(start 202.048618 -447.148966)
		(end 200.375266 -447.148966)
		(width 0.1397)
		(layer "In13.Cu")
		(net "TDR_DIFF_100_IN5_DIP")
	)
	(segment
		(start 186.625992 -443.953138)
		(end 186.498992 -444.080138)
		(width 0.1397)
		(layer "In13.Cu")
		(net "TDR_DIFF_100_IN5_DIP")
	)
	(segment
		(start 204.022452 -444.080138)
		(end 203.895452 -443.953138)
		(width 0.1397)
		(layer "In13.Cu")
		(net "TDR_DIFF_100_IN5_DIP")
	)
	(segment
		(start 198.401432 -446.828672)
		(end 198.081138 -447.148966)
		(width 0.1397)
		(layer "In13.Cu")
		(net "TDR_DIFF_100_IN5_DIP")
	)
	(segment
		(start 241.639598 -441.364116)
		(end 241.319304 -441.043822)
		(width 0.1397)
		(layer "In9.Cu")
		(net "TDR_DIFF_100_IN3_DIP")
	)
	(segment
		(start 232.988866 -440.72556)
		(end 232.988866 -441.70346)
		(width 0.1397)
		(layer "In9.Cu")
		(net "TDR_DIFF_100_IN3_DIP")
	)
	(segment
		(start 251.568204 -438.292748)
		(end 251.568204 -441.043822)
		(width 0.1397)
		(layer "In9.Cu")
		(net "TDR_DIFF_100_IN3_DIP")
	)
	(segment
		(start 239.665764 -438.292748)
		(end 239.665764 -441.00877)
		(width 0.1397)
		(layer "In9.Cu")
		(net "TDR_DIFF_100_IN3_DIP")
	)
	(segment
		(start 251.24791 -441.364116)
		(end 249.574558 -441.364116)
		(width 0.1397)
		(layer "In9.Cu")
		(net "TDR_DIFF_100_IN3_DIP")
	)
	(segment
		(start 265.444478 -441.364116)
		(end 265.124184 -441.043822)
		(width 0.1397)
		(layer "In9.Cu")
		(net "TDR_DIFF_100_IN3_DIP")
	)
	(segment
		(start 290.92271 -441.364116)
		(end 289.249358 -441.364116)
		(width 0.1397)
		(layer "In9.Cu")
		(net "TDR_DIFF_100_IN3_DIP")
	)
	(segment
		(start 280.994104 -441.043822)
		(end 280.994104 -438.292748)
		(width 0.1397)
		(layer "In9.Cu")
		(net "TDR_DIFF_100_IN3_DIP")
	)
	(segment
		(start 259.630164 -438.165748)
		(end 259.503164 -438.292748)
		(width 0.1397)
		(layer "In9.Cu")
		(net "TDR_DIFF_100_IN3_DIP")
	)
	(segment
		(start 263.470644 -438.292748)
		(end 263.470644 -441.043822)
		(width 0.1397)
		(layer "In9.Cu")
		(net "TDR_DIFF_100_IN3_DIP")
	)
	(segment
		(start 253.094744 -438.165748)
		(end 251.695204 -438.165748)
		(width 0.1397)
		(layer "In9.Cu")
		(net "TDR_DIFF_100_IN3_DIP")
	)
	(segment
		(start 296.902378 -440.59856)
		(end 293.216838 -440.59856)
		(width 0.1397)
		(layer "In9.Cu")
		(net "TDR_DIFF_100_IN3_DIP")
	)
	(segment
		(start 257.509518 -441.364116)
		(end 257.189224 -441.043822)
		(width 0.1397)
		(layer "In9.Cu")
		(net "TDR_DIFF_100_IN3_DIP")
	)
	(segment
		(start 287.275524 -438.292748)
		(end 287.275524 -441.043822)
		(width 0.1397)
		(layer "In9.Cu")
		(net "TDR_DIFF_100_IN3_DIP")
	)
	(segment
		(start 279.02027 -441.364116)
		(end 277.346918 -441.364116)
		(width 0.1397)
		(layer "In9.Cu")
		(net "TDR_DIFF_100_IN3_DIP")
	)
	(segment
		(start 279.340564 -438.292748)
		(end 279.340564 -441.043822)
		(width 0.1397)
		(layer "In9.Cu")
		(net "TDR_DIFF_100_IN3_DIP")
	)
	(segment
		(start 241.192304 -438.165748)
		(end 239.792764 -438.165748)
		(width 0.1397)
		(layer "In9.Cu")
		(net "TDR_DIFF_100_IN3_DIP")
	)
	(segment
		(start 261.156704 -438.292748)
		(end 261.029704 -438.165748)
		(width 0.1397)
		(layer "In9.Cu")
		(net "TDR_DIFF_100_IN3_DIP")
	)
	(segment
		(start 257.189224 -438.292748)
		(end 257.062224 -438.165748)
		(width 0.1397)
		(layer "In9.Cu")
		(net "TDR_DIFF_100_IN3_DIP")
	)
	(segment
		(start 275.373084 -438.292748)
		(end 275.373084 -441.043822)
		(width 0.1397)
		(layer "In9.Cu")
		(net "TDR_DIFF_100_IN3_DIP")
	)
	(segment
		(start 265.124184 -441.043822)
		(end 265.124184 -438.292748)
		(width 0.1397)
		(layer "In9.Cu")
		(net "TDR_DIFF_100_IN3_DIP")
	)
	(segment
		(start 292.896544 -440.278266)
		(end 292.896544 -438.292748)
		(width 0.1397)
		(layer "In9.Cu")
		(net "TDR_DIFF_100_IN3_DIP")
	)
	(segment
		(start 261.476998 -441.364116)
		(end 261.156704 -441.043822)
		(width 0.1397)
		(layer "In9.Cu")
		(net "TDR_DIFF_100_IN3_DIP")
	)
	(segment
		(start 245.607078 -441.364116)
		(end 245.286784 -441.043822)
		(width 0.1397)
		(layer "In9.Cu")
		(net "TDR_DIFF_100_IN3_DIP")
	)
	(segment
		(start 253.542038 -441.364116)
		(end 253.221744 -441.043822)
		(width 0.1397)
		(layer "In9.Cu")
		(net "TDR_DIFF_100_IN3_DIP")
	)
	(segment
		(start 279.340564 -441.043822)
		(end 279.02027 -441.364116)
		(width 0.1397)
		(layer "In9.Cu")
		(net "TDR_DIFF_100_IN3_DIP")
	)
	(segment
		(start 241.319304 -438.292748)
		(end 241.192304 -438.165748)
		(width 0.1397)
		(layer "In9.Cu")
		(net "TDR_DIFF_100_IN3_DIP")
	)
	(segment
		(start 284.961584 -441.043822)
		(end 284.961584 -438.292748)
		(width 0.1397)
		(layer "In9.Cu")
		(net "TDR_DIFF_100_IN3_DIP")
	)
	(segment
		(start 275.373084 -441.043822)
		(end 275.05279 -441.364116)
		(width 0.1397)
		(layer "In9.Cu")
		(net "TDR_DIFF_100_IN3_DIP")
	)
	(segment
		(start 245.159784 -438.165748)
		(end 243.760244 -438.165748)
		(width 0.1397)
		(layer "In9.Cu")
		(net "TDR_DIFF_100_IN3_DIP")
	)
	(segment
		(start 292.896544 -438.292748)
		(end 292.769544 -438.165748)
		(width 0.1397)
		(layer "In9.Cu")
		(net "TDR_DIFF_100_IN3_DIP")
	)
	(segment
		(start 251.568204 -441.043822)
		(end 251.24791 -441.364116)
		(width 0.1397)
		(layer "In9.Cu")
		(net "TDR_DIFF_100_IN3_DIP")
	)
	(segment
		(start 275.500084 -438.165748)
		(end 275.373084 -438.292748)
		(width 0.1397)
		(layer "In9.Cu")
		(net "TDR_DIFF_100_IN3_DIP")
	)
	(segment
		(start 277.346918 -441.364116)
		(end 277.026624 -441.043822)
		(width 0.1397)
		(layer "In9.Cu")
		(net "TDR_DIFF_100_IN3_DIP")
	)
	(segment
		(start 247.600724 -441.043822)
		(end 247.28043 -441.364116)
		(width 0.1397)
		(layer "In9.Cu")
		(net "TDR_DIFF_100_IN3_DIP")
	)
	(segment
		(start 291.370004 -438.165748)
		(end 291.243004 -438.292748)
		(width 0.1397)
		(layer "In9.Cu")
		(net "TDR_DIFF_100_IN3_DIP")
	)
	(segment
		(start 255.535684 -441.043822)
		(end 255.21539 -441.364116)
		(width 0.1397)
		(layer "In9.Cu")
		(net "TDR_DIFF_100_IN3_DIP")
	)
	(segment
		(start 259.18287 -441.364116)
		(end 257.509518 -441.364116)
		(width 0.1397)
		(layer "In9.Cu")
		(net "TDR_DIFF_100_IN3_DIP")
	)
	(segment
		(start 237.224824 -438.165748)
		(end 235.825284 -438.165748)
		(width 0.1397)
		(layer "In9.Cu")
		(net "TDR_DIFF_100_IN3_DIP")
	)
	(segment
		(start 267.438124 -441.043822)
		(end 267.11783 -441.364116)
		(width 0.1397)
		(layer "In9.Cu")
		(net "TDR_DIFF_100_IN3_DIP")
	)
	(segment
		(start 249.574558 -441.364116)
		(end 249.254264 -441.043822)
		(width 0.1397)
		(layer "In9.Cu")
		(net "TDR_DIFF_100_IN3_DIP")
	)
	(segment
		(start 239.665764 -441.00877)
		(end 239.34547 -441.329064)
		(width 0.1397)
		(layer "In9.Cu")
		(net "TDR_DIFF_100_IN3_DIP")
	)
	(segment
		(start 237.672118 -441.329064)
		(end 237.351824 -441.00877)
		(width 0.1397)
		(layer "In9.Cu")
		(net "TDR_DIFF_100_IN3_DIP")
	)
	(segment
		(start 264.997184 -438.165748)
		(end 263.597644 -438.165748)
		(width 0.1397)
		(layer "In9.Cu")
		(net "TDR_DIFF_100_IN3_DIP")
	)
	(segment
		(start 263.597644 -438.165748)
		(end 263.470644 -438.292748)
		(width 0.1397)
		(layer "In9.Cu")
		(net "TDR_DIFF_100_IN3_DIP")
	)
	(segment
		(start 281.314398 -441.364116)
		(end 280.994104 -441.043822)
		(width 0.1397)
		(layer "In9.Cu")
		(net "TDR_DIFF_100_IN3_DIP")
	)
	(segment
		(start 245.286784 -441.043822)
		(end 245.286784 -438.292748)
		(width 0.1397)
		(layer "In9.Cu")
		(net "TDR_DIFF_100_IN3_DIP")
	)
	(segment
		(start 263.470644 -441.043822)
		(end 263.15035 -441.364116)
		(width 0.1397)
		(layer "In9.Cu")
		(net "TDR_DIFF_100_IN3_DIP")
	)
	(segment
		(start 293.216838 -440.59856)
		(end 292.896544 -440.278266)
		(width 0.1397)
		(layer "In9.Cu")
		(net "TDR_DIFF_100_IN3_DIP")
	)
	(segment
		(start 284.834584 -438.165748)
		(end 283.435044 -438.165748)
		(width 0.1397)
		(layer "In9.Cu")
		(net "TDR_DIFF_100_IN3_DIP")
	)
	(segment
		(start 239.792764 -438.165748)
		(end 239.665764 -438.292748)
		(width 0.1397)
		(layer "In9.Cu")
		(net "TDR_DIFF_100_IN3_DIP")
	)
	(segment
		(start 235.698284 -438.292748)
		(end 235.698284 -440.278266)
		(width 0.1397)
		(layer "In9.Cu")
		(net "TDR_DIFF_100_IN3_DIP")
	)
	(segment
		(start 243.633244 -438.292748)
		(end 243.633244 -441.043822)
		(width 0.1397)
		(layer "In9.Cu")
		(net "TDR_DIFF_100_IN3_DIP")
	)
	(segment
		(start 247.600724 -438.292748)
		(end 247.600724 -441.043822)
		(width 0.1397)
		(layer "In9.Cu")
		(net "TDR_DIFF_100_IN3_DIP")
	)
	(segment
		(start 237.351824 -441.00877)
		(end 237.351824 -438.292748)
		(width 0.1397)
		(layer "In9.Cu")
		(net "TDR_DIFF_100_IN3_DIP")
	)
	(segment
		(start 287.402524 -438.165748)
		(end 287.275524 -438.292748)
		(width 0.1397)
		(layer "In9.Cu")
		(net "TDR_DIFF_100_IN3_DIP")
	)
	(segment
		(start 292.769544 -438.165748)
		(end 291.370004 -438.165748)
		(width 0.1397)
		(layer "In9.Cu")
		(net "TDR_DIFF_100_IN3_DIP")
	)
	(segment
		(start 259.503164 -438.292748)
		(end 259.503164 -441.043822)
		(width 0.1397)
		(layer "In9.Cu")
		(net "TDR_DIFF_100_IN3_DIP")
	)
	(segment
		(start 241.319304 -441.043822)
		(end 241.319304 -438.292748)
		(width 0.1397)
		(layer "In9.Cu")
		(net "TDR_DIFF_100_IN3_DIP")
	)
	(segment
		(start 297.009566 -440.705748)
		(end 296.902378 -440.59856)
		(width 0.1397)
		(layer "In9.Cu")
		(net "TDR_DIFF_100_IN3_DIP")
	)
	(segment
		(start 243.31295 -441.364116)
		(end 241.639598 -441.364116)
		(width 0.1397)
		(layer "In9.Cu")
		(net "TDR_DIFF_100_IN3_DIP")
	)
	(segment
		(start 287.275524 -441.043822)
		(end 286.95523 -441.364116)
		(width 0.1397)
		(layer "In9.Cu")
		(net "TDR_DIFF_100_IN3_DIP")
	)
	(segment
		(start 273.379438 -441.364116)
		(end 273.059144 -441.043822)
		(width 0.1397)
		(layer "In9.Cu")
		(net "TDR_DIFF_100_IN3_DIP")
	)
	(segment
		(start 288.929064 -438.292748)
		(end 288.802064 -438.165748)
		(width 0.1397)
		(layer "In9.Cu")
		(net "TDR_DIFF_100_IN3_DIP")
	)
	(segment
		(start 255.662684 -438.165748)
		(end 255.535684 -438.292748)
		(width 0.1397)
		(layer "In9.Cu")
		(net "TDR_DIFF_100_IN3_DIP")
	)
	(segment
		(start 269.091664 -441.043822)
		(end 269.091664 -438.292748)
		(width 0.1397)
		(layer "In9.Cu")
		(net "TDR_DIFF_100_IN3_DIP")
	)
	(segment
		(start 269.091664 -438.292748)
		(end 268.964664 -438.165748)
		(width 0.1397)
		(layer "In9.Cu")
		(net "TDR_DIFF_100_IN3_DIP")
	)
	(segment
		(start 245.286784 -438.292748)
		(end 245.159784 -438.165748)
		(width 0.1397)
		(layer "In9.Cu")
		(net "TDR_DIFF_100_IN3_DIP")
	)
	(segment
		(start 271.08531 -441.364116)
		(end 269.411958 -441.364116)
		(width 0.1397)
		(layer "In9.Cu")
		(net "TDR_DIFF_100_IN3_DIP")
	)
	(segment
		(start 285.281878 -441.364116)
		(end 284.961584 -441.043822)
		(width 0.1397)
		(layer "In9.Cu")
		(net "TDR_DIFF_100_IN3_DIP")
	)
	(segment
		(start 249.127264 -438.165748)
		(end 247.727724 -438.165748)
		(width 0.1397)
		(layer "In9.Cu")
		(net "TDR_DIFF_100_IN3_DIP")
	)
	(segment
		(start 267.438124 -438.292748)
		(end 267.438124 -441.043822)
		(width 0.1397)
		(layer "In9.Cu")
		(net "TDR_DIFF_100_IN3_DIP")
	)
	(segment
		(start 275.05279 -441.364116)
		(end 273.379438 -441.364116)
		(width 0.1397)
		(layer "In9.Cu")
		(net "TDR_DIFF_100_IN3_DIP")
	)
	(segment
		(start 277.026624 -441.043822)
		(end 277.026624 -438.292748)
		(width 0.1397)
		(layer "In9.Cu")
		(net "TDR_DIFF_100_IN3_DIP")
	)
	(segment
		(start 271.405604 -441.043822)
		(end 271.08531 -441.364116)
		(width 0.1397)
		(layer "In9.Cu")
		(net "TDR_DIFF_100_IN3_DIP")
	)
	(segment
		(start 243.760244 -438.165748)
		(end 243.633244 -438.292748)
		(width 0.1397)
		(layer "In9.Cu")
		(net "TDR_DIFF_100_IN3_DIP")
	)
	(segment
		(start 251.695204 -438.165748)
		(end 251.568204 -438.292748)
		(width 0.1397)
		(layer "In9.Cu")
		(net "TDR_DIFF_100_IN3_DIP")
	)
	(segment
		(start 255.535684 -438.292748)
		(end 255.535684 -441.043822)
		(width 0.1397)
		(layer "In9.Cu")
		(net "TDR_DIFF_100_IN3_DIP")
	)
	(segment
		(start 247.28043 -441.364116)
		(end 245.607078 -441.364116)
		(width 0.1397)
		(layer "In9.Cu")
		(net "TDR_DIFF_100_IN3_DIP")
	)
	(segment
		(start 265.124184 -438.292748)
		(end 264.997184 -438.165748)
		(width 0.1397)
		(layer "In9.Cu")
		(net "TDR_DIFF_100_IN3_DIP")
	)
	(segment
		(start 297.009566 -441.70346)
		(end 297.009566 -440.705748)
		(width 0.1397)
		(layer "In9.Cu")
		(net "TDR_DIFF_100_IN3_DIP")
	)
	(segment
		(start 268.964664 -438.165748)
		(end 267.565124 -438.165748)
		(width 0.1397)
		(layer "In9.Cu")
		(net "TDR_DIFF_100_IN3_DIP")
	)
	(segment
		(start 273.059144 -441.043822)
		(end 273.059144 -438.292748)
		(width 0.1397)
		(layer "In9.Cu")
		(net "TDR_DIFF_100_IN3_DIP")
	)
	(segment
		(start 286.95523 -441.364116)
		(end 285.281878 -441.364116)
		(width 0.1397)
		(layer "In9.Cu")
		(net "TDR_DIFF_100_IN3_DIP")
	)
	(segment
		(start 259.503164 -441.043822)
		(end 259.18287 -441.364116)
		(width 0.1397)
		(layer "In9.Cu")
		(net "TDR_DIFF_100_IN3_DIP")
	)
	(segment
		(start 291.243004 -441.043822)
		(end 290.92271 -441.364116)
		(width 0.1397)
		(layer "In9.Cu")
		(net "TDR_DIFF_100_IN3_DIP")
	)
	(segment
		(start 253.221744 -441.043822)
		(end 253.221744 -438.292748)
		(width 0.1397)
		(layer "In9.Cu")
		(net "TDR_DIFF_100_IN3_DIP")
	)
	(segment
		(start 283.308044 -441.043822)
		(end 282.98775 -441.364116)
		(width 0.1397)
		(layer "In9.Cu")
		(net "TDR_DIFF_100_IN3_DIP")
	)
	(segment
		(start 249.254264 -441.043822)
		(end 249.254264 -438.292748)
		(width 0.1397)
		(layer "In9.Cu")
		(net "TDR_DIFF_100_IN3_DIP")
	)
	(segment
		(start 255.21539 -441.364116)
		(end 253.542038 -441.364116)
		(width 0.1397)
		(layer "In9.Cu")
		(net "TDR_DIFF_100_IN3_DIP")
	)
	(segment
		(start 280.994104 -438.292748)
		(end 280.867104 -438.165748)
		(width 0.1397)
		(layer "In9.Cu")
		(net "TDR_DIFF_100_IN3_DIP")
	)
	(segment
		(start 272.932144 -438.165748)
		(end 271.532604 -438.165748)
		(width 0.1397)
		(layer "In9.Cu")
		(net "TDR_DIFF_100_IN3_DIP")
	)
	(segment
		(start 279.467564 -438.165748)
		(end 279.340564 -438.292748)
		(width 0.1397)
		(layer "In9.Cu")
		(net "TDR_DIFF_100_IN3_DIP")
	)
	(segment
		(start 271.532604 -438.165748)
		(end 271.405604 -438.292748)
		(width 0.1397)
		(layer "In9.Cu")
		(net "TDR_DIFF_100_IN3_DIP")
	)
	(segment
		(start 273.059144 -438.292748)
		(end 272.932144 -438.165748)
		(width 0.1397)
		(layer "In9.Cu")
		(net "TDR_DIFF_100_IN3_DIP")
	)
	(segment
		(start 261.156704 -441.043822)
		(end 261.156704 -438.292748)
		(width 0.1397)
		(layer "In9.Cu")
		(net "TDR_DIFF_100_IN3_DIP")
	)
	(segment
		(start 261.029704 -438.165748)
		(end 259.630164 -438.165748)
		(width 0.1397)
		(layer "In9.Cu")
		(net "TDR_DIFF_100_IN3_DIP")
	)
	(segment
		(start 257.189224 -441.043822)
		(end 257.189224 -438.292748)
		(width 0.1397)
		(layer "In9.Cu")
		(net "TDR_DIFF_100_IN3_DIP")
	)
	(segment
		(start 263.15035 -441.364116)
		(end 261.476998 -441.364116)
		(width 0.1397)
		(layer "In9.Cu")
		(net "TDR_DIFF_100_IN3_DIP")
	)
	(segment
		(start 276.899624 -438.165748)
		(end 275.500084 -438.165748)
		(width 0.1397)
		(layer "In9.Cu")
		(net "TDR_DIFF_100_IN3_DIP")
	)
	(segment
		(start 280.867104 -438.165748)
		(end 279.467564 -438.165748)
		(width 0.1397)
		(layer "In9.Cu")
		(net "TDR_DIFF_100_IN3_DIP")
	)
	(segment
		(start 269.411958 -441.364116)
		(end 269.091664 -441.043822)
		(width 0.1397)
		(layer "In9.Cu")
		(net "TDR_DIFF_100_IN3_DIP")
	)
	(segment
		(start 289.249358 -441.364116)
		(end 288.929064 -441.043822)
		(width 0.1397)
		(layer "In9.Cu")
		(net "TDR_DIFF_100_IN3_DIP")
	)
	(segment
		(start 288.802064 -438.165748)
		(end 287.402524 -438.165748)
		(width 0.1397)
		(layer "In9.Cu")
		(net "TDR_DIFF_100_IN3_DIP")
	)
	(segment
		(start 239.34547 -441.329064)
		(end 237.672118 -441.329064)
		(width 0.1397)
		(layer "In9.Cu")
		(net "TDR_DIFF_100_IN3_DIP")
	)
	(segment
		(start 235.37799 -440.59856)
		(end 233.115866 -440.59856)
		(width 0.1397)
		(layer "In9.Cu")
		(net "TDR_DIFF_100_IN3_DIP")
	)
	(segment
		(start 284.961584 -438.292748)
		(end 284.834584 -438.165748)
		(width 0.1397)
		(layer "In9.Cu")
		(net "TDR_DIFF_100_IN3_DIP")
	)
	(segment
		(start 267.565124 -438.165748)
		(end 267.438124 -438.292748)
		(width 0.1397)
		(layer "In9.Cu")
		(net "TDR_DIFF_100_IN3_DIP")
	)
	(segment
		(start 291.243004 -438.292748)
		(end 291.243004 -441.043822)
		(width 0.1397)
		(layer "In9.Cu")
		(net "TDR_DIFF_100_IN3_DIP")
	)
	(segment
		(start 247.727724 -438.165748)
		(end 247.600724 -438.292748)
		(width 0.1397)
		(layer "In9.Cu")
		(net "TDR_DIFF_100_IN3_DIP")
	)
	(segment
		(start 283.435044 -438.165748)
		(end 283.308044 -438.292748)
		(width 0.1397)
		(layer "In9.Cu")
		(net "TDR_DIFF_100_IN3_DIP")
	)
	(segment
		(start 282.98775 -441.364116)
		(end 281.314398 -441.364116)
		(width 0.1397)
		(layer "In9.Cu")
		(net "TDR_DIFF_100_IN3_DIP")
	)
	(segment
		(start 233.115866 -440.59856)
		(end 232.988866 -440.72556)
		(width 0.1397)
		(layer "In9.Cu")
		(net "TDR_DIFF_100_IN3_DIP")
	)
	(segment
		(start 277.026624 -438.292748)
		(end 276.899624 -438.165748)
		(width 0.1397)
		(layer "In9.Cu")
		(net "TDR_DIFF_100_IN3_DIP")
	)
	(segment
		(start 249.254264 -438.292748)
		(end 249.127264 -438.165748)
		(width 0.1397)
		(layer "In9.Cu")
		(net "TDR_DIFF_100_IN3_DIP")
	)
	(segment
		(start 288.929064 -441.043822)
		(end 288.929064 -438.292748)
		(width 0.1397)
		(layer "In9.Cu")
		(net "TDR_DIFF_100_IN3_DIP")
	)
	(segment
		(start 237.351824 -438.292748)
		(end 237.224824 -438.165748)
		(width 0.1397)
		(layer "In9.Cu")
		(net "TDR_DIFF_100_IN3_DIP")
	)
	(segment
		(start 257.062224 -438.165748)
		(end 255.662684 -438.165748)
		(width 0.1397)
		(layer "In9.Cu")
		(net "TDR_DIFF_100_IN3_DIP")
	)
	(segment
		(start 253.221744 -438.292748)
		(end 253.094744 -438.165748)
		(width 0.1397)
		(layer "In9.Cu")
		(net "TDR_DIFF_100_IN3_DIP")
	)
	(segment
		(start 235.698284 -440.278266)
		(end 235.37799 -440.59856)
		(width 0.1397)
		(layer "In9.Cu")
		(net "TDR_DIFF_100_IN3_DIP")
	)
	(segment
		(start 243.633244 -441.043822)
		(end 243.31295 -441.364116)
		(width 0.1397)
		(layer "In9.Cu")
		(net "TDR_DIFF_100_IN3_DIP")
	)
	(segment
		(start 283.308044 -438.292748)
		(end 283.308044 -441.043822)
		(width 0.1397)
		(layer "In9.Cu")
		(net "TDR_DIFF_100_IN3_DIP")
	)
	(segment
		(start 267.11783 -441.364116)
		(end 265.444478 -441.364116)
		(width 0.1397)
		(layer "In9.Cu")
		(net "TDR_DIFF_100_IN3_DIP")
	)
	(segment
		(start 271.405604 -438.292748)
		(end 271.405604 -441.043822)
		(width 0.1397)
		(layer "In9.Cu")
		(net "TDR_DIFF_100_IN3_DIP")
	)
	(segment
		(start 235.825284 -438.165748)
		(end 235.698284 -438.292748)
		(width 0.1397)
		(layer "In9.Cu")
		(net "TDR_DIFF_100_IN3_DIP")
	)
	(segment
		(start 213.941152 -443.943232)
		(end 213.941152 -446.691766)
		(width 0.1397)
		(layer "In13.Cu")
		(net "TDR_DIFF_100_IN5_DIN")
	)
	(segment
		(start 162.236912 -446.05321)
		(end 160.111694 -446.05321)
		(width 0.1397)
		(layer "In13.Cu")
		(net "TDR_DIFF_100_IN5_DIN")
	)
	(segment
		(start 198.391526 -443.622938)
		(end 198.071232 -443.943232)
		(width 0.1397)
		(layer "In13.Cu")
		(net "TDR_DIFF_100_IN5_DIN")
	)
	(segment
		(start 182.521606 -443.622938)
		(end 182.201312 -443.943232)
		(width 0.1397)
		(layer "In13.Cu")
		(net "TDR_DIFF_100_IN5_DIN")
	)
	(segment
		(start 206.326486 -443.622938)
		(end 206.006192 -443.943232)
		(width 0.1397)
		(layer "In13.Cu")
		(net "TDR_DIFF_100_IN5_DIN")
	)
	(segment
		(start 164.677852 -446.656714)
		(end 164.677852 -443.943232)
		(width 0.1397)
		(layer "In13.Cu")
		(net "TDR_DIFF_100_IN5_DIN")
	)
	(segment
		(start 168.325038 -443.622938)
		(end 166.651686 -443.622938)
		(width 0.1397)
		(layer "In13.Cu")
		(net "TDR_DIFF_100_IN5_DIN")
	)
	(segment
		(start 186.168792 -446.691766)
		(end 186.041792 -446.818766)
		(width 0.1397)
		(layer "In13.Cu")
		(net "TDR_DIFF_100_IN5_DIN")
	)
	(segment
		(start 216.382092 -446.818766)
		(end 216.255092 -446.691766)
		(width 0.1397)
		(layer "In13.Cu")
		(net "TDR_DIFF_100_IN5_DIN")
	)
	(segment
		(start 164.804852 -446.783714)
		(end 164.677852 -446.656714)
		(width 0.1397)
		(layer "In13.Cu")
		(net "TDR_DIFF_100_IN5_DIN")
	)
	(segment
		(start 180.547772 -443.943232)
		(end 180.227478 -443.622938)
		(width 0.1397)
		(layer "In13.Cu")
		(net "TDR_DIFF_100_IN5_DIN")
	)
	(segment
		(start 162.684206 -443.622938)
		(end 162.363912 -443.943232)
		(width 0.1397)
		(layer "In13.Cu")
		(net "TDR_DIFF_100_IN5_DIN")
	)
	(segment
		(start 190.136272 -443.943232)
		(end 190.136272 -446.691766)
		(width 0.1397)
		(layer "In13.Cu")
		(net "TDR_DIFF_100_IN5_DIN")
	)
	(segment
		(start 174.139352 -446.818766)
		(end 172.739812 -446.818766)
		(width 0.1397)
		(layer "In13.Cu")
		(net "TDR_DIFF_100_IN5_DIN")
	)
	(segment
		(start 209.973672 -443.943232)
		(end 209.973672 -446.691766)
		(width 0.1397)
		(layer "In13.Cu")
		(net "TDR_DIFF_100_IN5_DIN")
	)
	(segment
		(start 217.781632 -446.818766)
		(end 216.382092 -446.818766)
		(width 0.1397)
		(layer "In13.Cu")
		(net "TDR_DIFF_100_IN5_DIN")
	)
	(segment
		(start 190.136272 -446.691766)
		(end 190.009272 -446.818766)
		(width 0.1397)
		(layer "In13.Cu")
		(net "TDR_DIFF_100_IN5_DIN")
	)
	(segment
		(start 205.879192 -446.818766)
		(end 204.479652 -446.818766)
		(width 0.1397)
		(layer "In13.Cu")
		(net "TDR_DIFF_100_IN5_DIN")
	)
	(segment
		(start 166.651686 -443.622938)
		(end 166.331392 -443.943232)
		(width 0.1397)
		(layer "In13.Cu")
		(net "TDR_DIFF_100_IN5_DIN")
	)
	(segment
		(start 176.580292 -443.943232)
		(end 176.259998 -443.622938)
		(width 0.1397)
		(layer "In13.Cu")
		(net "TDR_DIFF_100_IN5_DIN")
	)
	(segment
		(start 198.071232 -446.691766)
		(end 197.944232 -446.818766)
		(width 0.1397)
		(layer "In13.Cu")
		(net "TDR_DIFF_100_IN5_DIN")
	)
	(segment
		(start 223.874838 -446.05321)
		(end 220.349572 -446.05321)
		(width 0.1397)
		(layer "In13.Cu")
		(net "TDR_DIFF_100_IN5_DIN")
	)
	(segment
		(start 182.201312 -443.943232)
		(end 182.201312 -446.691766)
		(width 0.1397)
		(layer "In13.Cu")
		(net "TDR_DIFF_100_IN5_DIN")
	)
	(segment
		(start 196.097398 -443.622938)
		(end 194.424046 -443.622938)
		(width 0.1397)
		(layer "In13.Cu")
		(net "TDR_DIFF_100_IN5_DIN")
	)
	(segment
		(start 180.547772 -446.691766)
		(end 180.547772 -443.943232)
		(width 0.1397)
		(layer "In13.Cu")
		(net "TDR_DIFF_100_IN5_DIN")
	)
	(segment
		(start 209.973672 -446.691766)
		(end 209.846672 -446.818766)
		(width 0.1397)
		(layer "In13.Cu")
		(net "TDR_DIFF_100_IN5_DIN")
	)
	(segment
		(start 178.554126 -443.622938)
		(end 178.233832 -443.943232)
		(width 0.1397)
		(layer "In13.Cu")
		(net "TDR_DIFF_100_IN5_DIN")
	)
	(segment
		(start 192.450212 -446.691766)
		(end 192.450212 -443.943232)
		(width 0.1397)
		(layer "In13.Cu")
		(net "TDR_DIFF_100_IN5_DIN")
	)
	(segment
		(start 193.976752 -446.818766)
		(end 192.577212 -446.818766)
		(width 0.1397)
		(layer "In13.Cu")
		(net "TDR_DIFF_100_IN5_DIN")
	)
	(segment
		(start 224.005394 -444.94831)
		(end 224.005394 -445.922654)
		(width 0.1397)
		(layer "In13.Cu")
		(net "TDR_DIFF_100_IN5_DIN")
	)
	(segment
		(start 180.227478 -443.622938)
		(end 178.554126 -443.622938)
		(width 0.1397)
		(layer "In13.Cu")
		(net "TDR_DIFF_100_IN5_DIN")
	)
	(segment
		(start 197.944232 -446.818766)
		(end 196.544692 -446.818766)
		(width 0.1397)
		(layer "In13.Cu")
		(net "TDR_DIFF_100_IN5_DIN")
	)
	(segment
		(start 216.255092 -443.943232)
		(end 215.934798 -443.622938)
		(width 0.1397)
		(layer "In13.Cu")
		(net "TDR_DIFF_100_IN5_DIN")
	)
	(segment
		(start 166.204392 -446.783714)
		(end 164.804852 -446.783714)
		(width 0.1397)
		(layer "In13.Cu")
		(net "TDR_DIFF_100_IN5_DIN")
	)
	(segment
		(start 204.352652 -443.943232)
		(end 204.032358 -443.622938)
		(width 0.1397)
		(layer "In13.Cu")
		(net "TDR_DIFF_100_IN5_DIN")
	)
	(segment
		(start 174.586646 -443.622938)
		(end 174.266352 -443.943232)
		(width 0.1397)
		(layer "In13.Cu")
		(net "TDR_DIFF_100_IN5_DIN")
	)
	(segment
		(start 172.739812 -446.818766)
		(end 172.612812 -446.691766)
		(width 0.1397)
		(layer "In13.Cu")
		(net "TDR_DIFF_100_IN5_DIN")
	)
	(segment
		(start 184.642252 -446.818766)
		(end 184.515252 -446.691766)
		(width 0.1397)
		(layer "In13.Cu")
		(net "TDR_DIFF_100_IN5_DIN")
	)
	(segment
		(start 176.259998 -443.622938)
		(end 174.586646 -443.622938)
		(width 0.1397)
		(layer "In13.Cu")
		(net "TDR_DIFF_100_IN5_DIN")
	)
	(segment
		(start 174.266352 -443.943232)
		(end 174.266352 -446.691766)
		(width 0.1397)
		(layer "In13.Cu")
		(net "TDR_DIFF_100_IN5_DIN")
	)
	(segment
		(start 188.609732 -446.818766)
		(end 188.482732 -446.691766)
		(width 0.1397)
		(layer "In13.Cu")
		(net "TDR_DIFF_100_IN5_DIN")
	)
	(segment
		(start 202.359006 -443.622938)
		(end 202.038712 -443.943232)
		(width 0.1397)
		(layer "In13.Cu")
		(net "TDR_DIFF_100_IN5_DIN")
	)
	(segment
		(start 184.194958 -443.622938)
		(end 182.521606 -443.622938)
		(width 0.1397)
		(layer "In13.Cu")
		(net "TDR_DIFF_100_IN5_DIN")
	)
	(segment
		(start 201.911712 -446.818766)
		(end 200.512172 -446.818766)
		(width 0.1397)
		(layer "In13.Cu")
		(net "TDR_DIFF_100_IN5_DIN")
	)
	(segment
		(start 186.168792 -443.943232)
		(end 186.168792 -446.691766)
		(width 0.1397)
		(layer "In13.Cu")
		(net "TDR_DIFF_100_IN5_DIN")
	)
	(segment
		(start 206.006192 -446.691766)
		(end 205.879192 -446.818766)
		(width 0.1397)
		(layer "In13.Cu")
		(net "TDR_DIFF_100_IN5_DIN")
	)
	(segment
		(start 192.450212 -443.943232)
		(end 192.129918 -443.622938)
		(width 0.1397)
		(layer "In13.Cu")
		(net "TDR_DIFF_100_IN5_DIN")
	)
	(segment
		(start 200.385172 -446.691766)
		(end 200.385172 -443.943232)
		(width 0.1397)
		(layer "In13.Cu")
		(net "TDR_DIFF_100_IN5_DIN")
	)
	(segment
		(start 186.489086 -443.622938)
		(end 186.168792 -443.943232)
		(width 0.1397)
		(layer "In13.Cu")
		(net "TDR_DIFF_100_IN5_DIN")
	)
	(segment
		(start 168.772332 -446.818766)
		(end 168.645332 -446.691766)
		(width 0.1397)
		(layer "In13.Cu")
		(net "TDR_DIFF_100_IN5_DIN")
	)
	(segment
		(start 194.103752 -443.943232)
		(end 194.103752 -446.691766)
		(width 0.1397)
		(layer "In13.Cu")
		(net "TDR_DIFF_100_IN5_DIN")
	)
	(segment
		(start 217.908632 -443.943232)
		(end 217.908632 -446.691766)
		(width 0.1397)
		(layer "In13.Cu")
		(net "TDR_DIFF_100_IN5_DIN")
	)
	(segment
		(start 159.984694 -445.92621)
		(end 159.984694 -444.94831)
		(width 0.1397)
		(layer "In13.Cu")
		(net "TDR_DIFF_100_IN5_DIN")
	)
	(segment
		(start 168.645332 -446.691766)
		(end 168.645332 -443.943232)
		(width 0.1397)
		(layer "In13.Cu")
		(net "TDR_DIFF_100_IN5_DIN")
	)
	(segment
		(start 216.255092 -446.691766)
		(end 216.255092 -443.943232)
		(width 0.1397)
		(layer "In13.Cu")
		(net "TDR_DIFF_100_IN5_DIN")
	)
	(segment
		(start 194.424046 -443.622938)
		(end 194.103752 -443.943232)
		(width 0.1397)
		(layer "In13.Cu")
		(net "TDR_DIFF_100_IN5_DIN")
	)
	(segment
		(start 200.385172 -443.943232)
		(end 200.064878 -443.622938)
		(width 0.1397)
		(layer "In13.Cu")
		(net "TDR_DIFF_100_IN5_DIN")
	)
	(segment
		(start 220.349572 -446.05321)
		(end 220.222572 -445.92621)
		(width 0.1397)
		(layer "In13.Cu")
		(net "TDR_DIFF_100_IN5_DIN")
	)
	(segment
		(start 178.233832 -446.691766)
		(end 178.106832 -446.818766)
		(width 0.1397)
		(layer "In13.Cu")
		(net "TDR_DIFF_100_IN5_DIN")
	)
	(segment
		(start 170.298872 -446.691766)
		(end 170.171872 -446.818766)
		(width 0.1397)
		(layer "In13.Cu")
		(net "TDR_DIFF_100_IN5_DIN")
	)
	(segment
		(start 170.619166 -443.622938)
		(end 170.298872 -443.943232)
		(width 0.1397)
		(layer "In13.Cu")
		(net "TDR_DIFF_100_IN5_DIN")
	)
	(segment
		(start 190.456566 -443.622938)
		(end 190.136272 -443.943232)
		(width 0.1397)
		(layer "In13.Cu")
		(net "TDR_DIFF_100_IN5_DIN")
	)
	(segment
		(start 219.902278 -443.622938)
		(end 218.228926 -443.622938)
		(width 0.1397)
		(layer "In13.Cu")
		(net "TDR_DIFF_100_IN5_DIN")
	)
	(segment
		(start 224.005394 -445.922654)
		(end 223.874838 -446.05321)
		(width 0.1397)
		(layer "In13.Cu")
		(net "TDR_DIFF_100_IN5_DIN")
	)
	(segment
		(start 214.261446 -443.622938)
		(end 213.941152 -443.943232)
		(width 0.1397)
		(layer "In13.Cu")
		(net "TDR_DIFF_100_IN5_DIN")
	)
	(segment
		(start 200.512172 -446.818766)
		(end 200.385172 -446.691766)
		(width 0.1397)
		(layer "In13.Cu")
		(net "TDR_DIFF_100_IN5_DIN")
	)
	(segment
		(start 192.577212 -446.818766)
		(end 192.450212 -446.691766)
		(width 0.1397)
		(layer "In13.Cu")
		(net "TDR_DIFF_100_IN5_DIN")
	)
	(segment
		(start 202.038712 -446.691766)
		(end 201.911712 -446.818766)
		(width 0.1397)
		(layer "In13.Cu")
		(net "TDR_DIFF_100_IN5_DIN")
	)
	(segment
		(start 164.677852 -443.943232)
		(end 164.357558 -443.622938)
		(width 0.1397)
		(layer "In13.Cu")
		(net "TDR_DIFF_100_IN5_DIN")
	)
	(segment
		(start 168.645332 -443.943232)
		(end 168.325038 -443.622938)
		(width 0.1397)
		(layer "In13.Cu")
		(net "TDR_DIFF_100_IN5_DIN")
	)
	(segment
		(start 198.071232 -443.943232)
		(end 198.071232 -446.691766)
		(width 0.1397)
		(layer "In13.Cu")
		(net "TDR_DIFF_100_IN5_DIN")
	)
	(segment
		(start 190.009272 -446.818766)
		(end 188.609732 -446.818766)
		(width 0.1397)
		(layer "In13.Cu")
		(net "TDR_DIFF_100_IN5_DIN")
	)
	(segment
		(start 184.515252 -446.691766)
		(end 184.515252 -443.943232)
		(width 0.1397)
		(layer "In13.Cu")
		(net "TDR_DIFF_100_IN5_DIN")
	)
	(segment
		(start 217.908632 -446.691766)
		(end 217.781632 -446.818766)
		(width 0.1397)
		(layer "In13.Cu")
		(net "TDR_DIFF_100_IN5_DIN")
	)
	(segment
		(start 178.106832 -446.818766)
		(end 176.707292 -446.818766)
		(width 0.1397)
		(layer "In13.Cu")
		(net "TDR_DIFF_100_IN5_DIN")
	)
	(segment
		(start 209.846672 -446.818766)
		(end 208.447132 -446.818766)
		(width 0.1397)
		(layer "In13.Cu")
		(net "TDR_DIFF_100_IN5_DIN")
	)
	(segment
		(start 176.707292 -446.818766)
		(end 176.580292 -446.691766)
		(width 0.1397)
		(layer "In13.Cu")
		(net "TDR_DIFF_100_IN5_DIN")
	)
	(segment
		(start 208.320132 -443.943232)
		(end 207.999838 -443.622938)
		(width 0.1397)
		(layer "In13.Cu")
		(net "TDR_DIFF_100_IN5_DIN")
	)
	(segment
		(start 218.228926 -443.622938)
		(end 217.908632 -443.943232)
		(width 0.1397)
		(layer "In13.Cu")
		(net "TDR_DIFF_100_IN5_DIN")
	)
	(segment
		(start 208.320132 -446.691766)
		(end 208.320132 -443.943232)
		(width 0.1397)
		(layer "In13.Cu")
		(net "TDR_DIFF_100_IN5_DIN")
	)
	(segment
		(start 188.162438 -443.622938)
		(end 186.489086 -443.622938)
		(width 0.1397)
		(layer "In13.Cu")
		(net "TDR_DIFF_100_IN5_DIN")
	)
	(segment
		(start 212.287612 -446.691766)
		(end 212.287612 -443.943232)
		(width 0.1397)
		(layer "In13.Cu")
		(net "TDR_DIFF_100_IN5_DIN")
	)
	(segment
		(start 160.111694 -446.05321)
		(end 159.984694 -445.92621)
		(width 0.1397)
		(layer "In13.Cu")
		(net "TDR_DIFF_100_IN5_DIN")
	)
	(segment
		(start 172.612812 -446.691766)
		(end 172.612812 -443.943232)
		(width 0.1397)
		(layer "In13.Cu")
		(net "TDR_DIFF_100_IN5_DIN")
	)
	(segment
		(start 202.038712 -443.943232)
		(end 202.038712 -446.691766)
		(width 0.1397)
		(layer "In13.Cu")
		(net "TDR_DIFF_100_IN5_DIN")
	)
	(segment
		(start 204.479652 -446.818766)
		(end 204.352652 -446.691766)
		(width 0.1397)
		(layer "In13.Cu")
		(net "TDR_DIFF_100_IN5_DIN")
	)
	(segment
		(start 162.363912 -443.943232)
		(end 162.363912 -445.92621)
		(width 0.1397)
		(layer "In13.Cu")
		(net "TDR_DIFF_100_IN5_DIN")
	)
	(segment
		(start 170.171872 -446.818766)
		(end 168.772332 -446.818766)
		(width 0.1397)
		(layer "In13.Cu")
		(net "TDR_DIFF_100_IN5_DIN")
	)
	(segment
		(start 220.222572 -445.92621)
		(end 220.222572 -443.943232)
		(width 0.1397)
		(layer "In13.Cu")
		(net "TDR_DIFF_100_IN5_DIN")
	)
	(segment
		(start 213.814152 -446.818766)
		(end 212.414612 -446.818766)
		(width 0.1397)
		(layer "In13.Cu")
		(net "TDR_DIFF_100_IN5_DIN")
	)
	(segment
		(start 188.482732 -446.691766)
		(end 188.482732 -443.943232)
		(width 0.1397)
		(layer "In13.Cu")
		(net "TDR_DIFF_100_IN5_DIN")
	)
	(segment
		(start 184.515252 -443.943232)
		(end 184.194958 -443.622938)
		(width 0.1397)
		(layer "In13.Cu")
		(net "TDR_DIFF_100_IN5_DIN")
	)
	(segment
		(start 196.544692 -446.818766)
		(end 196.417692 -446.691766)
		(width 0.1397)
		(layer "In13.Cu")
		(net "TDR_DIFF_100_IN5_DIN")
	)
	(segment
		(start 207.999838 -443.622938)
		(end 206.326486 -443.622938)
		(width 0.1397)
		(layer "In13.Cu")
		(net "TDR_DIFF_100_IN5_DIN")
	)
	(segment
		(start 174.266352 -446.691766)
		(end 174.139352 -446.818766)
		(width 0.1397)
		(layer "In13.Cu")
		(net "TDR_DIFF_100_IN5_DIN")
	)
	(segment
		(start 162.363912 -445.92621)
		(end 162.236912 -446.05321)
		(width 0.1397)
		(layer "In13.Cu")
		(net "TDR_DIFF_100_IN5_DIN")
	)
	(segment
		(start 170.298872 -443.943232)
		(end 170.298872 -446.691766)
		(width 0.1397)
		(layer "In13.Cu")
		(net "TDR_DIFF_100_IN5_DIN")
	)
	(segment
		(start 166.331392 -446.656714)
		(end 166.204392 -446.783714)
		(width 0.1397)
		(layer "In13.Cu")
		(net "TDR_DIFF_100_IN5_DIN")
	)
	(segment
		(start 200.064878 -443.622938)
		(end 198.391526 -443.622938)
		(width 0.1397)
		(layer "In13.Cu")
		(net "TDR_DIFF_100_IN5_DIN")
	)
	(segment
		(start 182.074312 -446.818766)
		(end 180.674772 -446.818766)
		(width 0.1397)
		(layer "In13.Cu")
		(net "TDR_DIFF_100_IN5_DIN")
	)
	(segment
		(start 178.233832 -443.943232)
		(end 178.233832 -446.691766)
		(width 0.1397)
		(layer "In13.Cu")
		(net "TDR_DIFF_100_IN5_DIN")
	)
	(segment
		(start 182.201312 -446.691766)
		(end 182.074312 -446.818766)
		(width 0.1397)
		(layer "In13.Cu")
		(net "TDR_DIFF_100_IN5_DIN")
	)
	(segment
		(start 210.293966 -443.622938)
		(end 209.973672 -443.943232)
		(width 0.1397)
		(layer "In13.Cu")
		(net "TDR_DIFF_100_IN5_DIN")
	)
	(segment
		(start 211.967318 -443.622938)
		(end 210.293966 -443.622938)
		(width 0.1397)
		(layer "In13.Cu")
		(net "TDR_DIFF_100_IN5_DIN")
	)
	(segment
		(start 206.006192 -443.943232)
		(end 206.006192 -446.691766)
		(width 0.1397)
		(layer "In13.Cu")
		(net "TDR_DIFF_100_IN5_DIN")
	)
	(segment
		(start 164.357558 -443.622938)
		(end 162.684206 -443.622938)
		(width 0.1397)
		(layer "In13.Cu")
		(net "TDR_DIFF_100_IN5_DIN")
	)
	(segment
		(start 180.674772 -446.818766)
		(end 180.547772 -446.691766)
		(width 0.1397)
		(layer "In13.Cu")
		(net "TDR_DIFF_100_IN5_DIN")
	)
	(segment
		(start 188.482732 -443.943232)
		(end 188.162438 -443.622938)
		(width 0.1397)
		(layer "In13.Cu")
		(net "TDR_DIFF_100_IN5_DIN")
	)
	(segment
		(start 166.331392 -443.943232)
		(end 166.331392 -446.656714)
		(width 0.1397)
		(layer "In13.Cu")
		(net "TDR_DIFF_100_IN5_DIN")
	)
	(segment
		(start 186.041792 -446.818766)
		(end 184.642252 -446.818766)
		(width 0.1397)
		(layer "In13.Cu")
		(net "TDR_DIFF_100_IN5_DIN")
	)
	(segment
		(start 172.292518 -443.622938)
		(end 170.619166 -443.622938)
		(width 0.1397)
		(layer "In13.Cu")
		(net "TDR_DIFF_100_IN5_DIN")
	)
	(segment
		(start 194.103752 -446.691766)
		(end 193.976752 -446.818766)
		(width 0.1397)
		(layer "In13.Cu")
		(net "TDR_DIFF_100_IN5_DIN")
	)
	(segment
		(start 212.287612 -443.943232)
		(end 211.967318 -443.622938)
		(width 0.1397)
		(layer "In13.Cu")
		(net "TDR_DIFF_100_IN5_DIN")
	)
	(segment
		(start 212.414612 -446.818766)
		(end 212.287612 -446.691766)
		(width 0.1397)
		(layer "In13.Cu")
		(net "TDR_DIFF_100_IN5_DIN")
	)
	(segment
		(start 176.580292 -446.691766)
		(end 176.580292 -443.943232)
		(width 0.1397)
		(layer "In13.Cu")
		(net "TDR_DIFF_100_IN5_DIN")
	)
	(segment
		(start 196.417692 -443.943232)
		(end 196.097398 -443.622938)
		(width 0.1397)
		(layer "In13.Cu")
		(net "TDR_DIFF_100_IN5_DIN")
	)
	(segment
		(start 208.447132 -446.818766)
		(end 208.320132 -446.691766)
		(width 0.1397)
		(layer "In13.Cu")
		(net "TDR_DIFF_100_IN5_DIN")
	)
	(segment
		(start 196.417692 -446.691766)
		(end 196.417692 -443.943232)
		(width 0.1397)
		(layer "In13.Cu")
		(net "TDR_DIFF_100_IN5_DIN")
	)
	(segment
		(start 213.941152 -446.691766)
		(end 213.814152 -446.818766)
		(width 0.1397)
		(layer "In13.Cu")
		(net "TDR_DIFF_100_IN5_DIN")
	)
	(segment
		(start 204.032358 -443.622938)
		(end 202.359006 -443.622938)
		(width 0.1397)
		(layer "In13.Cu")
		(net "TDR_DIFF_100_IN5_DIN")
	)
	(segment
		(start 220.222572 -443.943232)
		(end 219.902278 -443.622938)
		(width 0.1397)
		(layer "In13.Cu")
		(net "TDR_DIFF_100_IN5_DIN")
	)
	(segment
		(start 192.129918 -443.622938)
		(end 190.456566 -443.622938)
		(width 0.1397)
		(layer "In13.Cu")
		(net "TDR_DIFF_100_IN5_DIN")
	)
	(segment
		(start 172.612812 -443.943232)
		(end 172.292518 -443.622938)
		(width 0.1397)
		(layer "In13.Cu")
		(net "TDR_DIFF_100_IN5_DIN")
	)
	(segment
		(start 215.934798 -443.622938)
		(end 214.261446 -443.622938)
		(width 0.1397)
		(layer "In13.Cu")
		(net "TDR_DIFF_100_IN5_DIN")
	)
	(segment
		(start 204.352652 -446.691766)
		(end 204.352652 -443.943232)
		(width 0.1397)
		(layer "In13.Cu")
		(net "TDR_DIFF_100_IN5_DIN")
	)
	(segment
		(start 284.78226 -450.112384)
		(end 283.38272 -450.112384)
		(width 0.1397)
		(layer "In5.Cu")
		(net "TDR_DIFF_100_IN1_DIN")
	)
	(segment
		(start 237.619794 -453.27316)
		(end 237.2995 -452.952866)
		(width 0.1397)
		(layer "In5.Cu")
		(net "TDR_DIFF_100_IN1_DIN")
	)
	(segment
		(start 243.260626 -453.308212)
		(end 241.587274 -453.308212)
		(width 0.1397)
		(layer "In5.Cu")
		(net "TDR_DIFF_100_IN1_DIN")
	)
	(segment
		(start 279.28824 -452.987918)
		(end 278.967946 -453.308212)
		(width 0.1397)
		(layer "In5.Cu")
		(net "TDR_DIFF_100_IN1_DIN")
	)
	(segment
		(start 235.64596 -450.239384)
		(end 235.64596 -452.222362)
		(width 0.1397)
		(layer "In5.Cu")
		(net "TDR_DIFF_100_IN1_DIN")
	)
	(segment
		(start 253.16942 -452.987918)
		(end 253.16942 -450.239384)
		(width 0.1397)
		(layer "In5.Cu")
		(net "TDR_DIFF_100_IN1_DIN")
	)
	(segment
		(start 296.957242 -453.647556)
		(end 296.957242 -452.649844)
		(width 0.1397)
		(layer "In5.Cu")
		(net "TDR_DIFF_100_IN1_DIN")
	)
	(segment
		(start 279.41524 -450.112384)
		(end 279.28824 -450.239384)
		(width 0.1397)
		(layer "In5.Cu")
		(net "TDR_DIFF_100_IN1_DIN")
	)
	(segment
		(start 275.44776 -450.112384)
		(end 275.32076 -450.239384)
		(width 0.1397)
		(layer "In5.Cu")
		(net "TDR_DIFF_100_IN1_DIN")
	)
	(segment
		(start 282.935426 -453.308212)
		(end 281.262074 -453.308212)
		(width 0.1397)
		(layer "In5.Cu")
		(net "TDR_DIFF_100_IN1_DIN")
	)
	(segment
		(start 253.16942 -450.239384)
		(end 253.04242 -450.112384)
		(width 0.1397)
		(layer "In5.Cu")
		(net "TDR_DIFF_100_IN1_DIN")
	)
	(segment
		(start 296.850054 -452.542656)
		(end 293.164514 -452.542656)
		(width 0.1397)
		(layer "In5.Cu")
		(net "TDR_DIFF_100_IN1_DIN")
	)
	(segment
		(start 267.065506 -453.308212)
		(end 265.392154 -453.308212)
		(width 0.1397)
		(layer "In5.Cu")
		(net "TDR_DIFF_100_IN1_DIN")
	)
	(segment
		(start 275.000466 -453.308212)
		(end 273.327114 -453.308212)
		(width 0.1397)
		(layer "In5.Cu")
		(net "TDR_DIFF_100_IN1_DIN")
	)
	(segment
		(start 243.58092 -450.239384)
		(end 243.58092 -452.987918)
		(width 0.1397)
		(layer "In5.Cu")
		(net "TDR_DIFF_100_IN1_DIN")
	)
	(segment
		(start 255.48336 -450.239384)
		(end 255.48336 -452.987918)
		(width 0.1397)
		(layer "In5.Cu")
		(net "TDR_DIFF_100_IN1_DIN")
	)
	(segment
		(start 271.48028 -450.112384)
		(end 271.35328 -450.239384)
		(width 0.1397)
		(layer "In5.Cu")
		(net "TDR_DIFF_100_IN1_DIN")
	)
	(segment
		(start 271.35328 -452.987918)
		(end 271.032986 -453.308212)
		(width 0.1397)
		(layer "In5.Cu")
		(net "TDR_DIFF_100_IN1_DIN")
	)
	(segment
		(start 260.97738 -450.112384)
		(end 259.57784 -450.112384)
		(width 0.1397)
		(layer "In5.Cu")
		(net "TDR_DIFF_100_IN1_DIN")
	)
	(segment
		(start 245.23446 -452.987918)
		(end 245.23446 -450.239384)
		(width 0.1397)
		(layer "In5.Cu")
		(net "TDR_DIFF_100_IN1_DIN")
	)
	(segment
		(start 235.77296 -450.112384)
		(end 235.64596 -450.239384)
		(width 0.1397)
		(layer "In5.Cu")
		(net "TDR_DIFF_100_IN1_DIN")
	)
	(segment
		(start 284.90926 -452.987918)
		(end 284.90926 -450.239384)
		(width 0.1397)
		(layer "In5.Cu")
		(net "TDR_DIFF_100_IN1_DIN")
	)
	(segment
		(start 273.00682 -452.987918)
		(end 273.00682 -450.239384)
		(width 0.1397)
		(layer "In5.Cu")
		(net "TDR_DIFF_100_IN1_DIN")
	)
	(segment
		(start 290.870386 -453.308212)
		(end 289.197034 -453.308212)
		(width 0.1397)
		(layer "In5.Cu")
		(net "TDR_DIFF_100_IN1_DIN")
	)
	(segment
		(start 255.61036 -450.112384)
		(end 255.48336 -450.239384)
		(width 0.1397)
		(layer "In5.Cu")
		(net "TDR_DIFF_100_IN1_DIN")
	)
	(segment
		(start 245.554754 -453.308212)
		(end 245.23446 -452.987918)
		(width 0.1397)
		(layer "In5.Cu")
		(net "TDR_DIFF_100_IN1_DIN")
	)
	(segment
		(start 245.10746 -450.112384)
		(end 243.70792 -450.112384)
		(width 0.1397)
		(layer "In5.Cu")
		(net "TDR_DIFF_100_IN1_DIN")
	)
	(segment
		(start 241.13998 -450.112384)
		(end 239.74044 -450.112384)
		(width 0.1397)
		(layer "In5.Cu")
		(net "TDR_DIFF_100_IN1_DIN")
	)
	(segment
		(start 288.74974 -450.112384)
		(end 287.3502 -450.112384)
		(width 0.1397)
		(layer "In5.Cu")
		(net "TDR_DIFF_100_IN1_DIN")
	)
	(segment
		(start 249.20194 -450.239384)
		(end 249.07494 -450.112384)
		(width 0.1397)
		(layer "In5.Cu")
		(net "TDR_DIFF_100_IN1_DIN")
	)
	(segment
		(start 291.31768 -450.112384)
		(end 291.19068 -450.239384)
		(width 0.1397)
		(layer "In5.Cu")
		(net "TDR_DIFF_100_IN1_DIN")
	)
	(segment
		(start 255.163066 -453.308212)
		(end 253.489714 -453.308212)
		(width 0.1397)
		(layer "In5.Cu")
		(net "TDR_DIFF_100_IN1_DIN")
	)
	(segment
		(start 253.489714 -453.308212)
		(end 253.16942 -452.987918)
		(width 0.1397)
		(layer "In5.Cu")
		(net "TDR_DIFF_100_IN1_DIN")
	)
	(segment
		(start 263.41832 -450.239384)
		(end 263.41832 -452.987918)
		(width 0.1397)
		(layer "In5.Cu")
		(net "TDR_DIFF_100_IN1_DIN")
	)
	(segment
		(start 267.3858 -450.239384)
		(end 267.3858 -452.987918)
		(width 0.1397)
		(layer "In5.Cu")
		(net "TDR_DIFF_100_IN1_DIN")
	)
	(segment
		(start 265.07186 -452.987918)
		(end 265.07186 -450.239384)
		(width 0.1397)
		(layer "In5.Cu")
		(net "TDR_DIFF_100_IN1_DIN")
	)
	(segment
		(start 247.6754 -450.112384)
		(end 247.5484 -450.239384)
		(width 0.1397)
		(layer "In5.Cu")
		(net "TDR_DIFF_100_IN1_DIN")
	)
	(segment
		(start 261.10438 -452.987918)
		(end 261.10438 -450.239384)
		(width 0.1397)
		(layer "In5.Cu")
		(net "TDR_DIFF_100_IN1_DIN")
	)
	(segment
		(start 235.325666 -452.542656)
		(end 233.063542 -452.542656)
		(width 0.1397)
		(layer "In5.Cu")
		(net "TDR_DIFF_100_IN1_DIN")
	)
	(segment
		(start 280.81478 -450.112384)
		(end 279.41524 -450.112384)
		(width 0.1397)
		(layer "In5.Cu")
		(net "TDR_DIFF_100_IN1_DIN")
	)
	(segment
		(start 249.522234 -453.308212)
		(end 249.20194 -452.987918)
		(width 0.1397)
		(layer "In5.Cu")
		(net "TDR_DIFF_100_IN1_DIN")
	)
	(segment
		(start 239.61344 -452.952866)
		(end 239.293146 -453.27316)
		(width 0.1397)
		(layer "In5.Cu")
		(net "TDR_DIFF_100_IN1_DIN")
	)
	(segment
		(start 243.58092 -452.987918)
		(end 243.260626 -453.308212)
		(width 0.1397)
		(layer "In5.Cu")
		(net "TDR_DIFF_100_IN1_DIN")
	)
	(segment
		(start 237.2995 -450.239384)
		(end 237.1725 -450.112384)
		(width 0.1397)
		(layer "In5.Cu")
		(net "TDR_DIFF_100_IN1_DIN")
	)
	(segment
		(start 283.25572 -450.239384)
		(end 283.25572 -452.987918)
		(width 0.1397)
		(layer "In5.Cu")
		(net "TDR_DIFF_100_IN1_DIN")
	)
	(segment
		(start 280.94178 -450.239384)
		(end 280.81478 -450.112384)
		(width 0.1397)
		(layer "In5.Cu")
		(net "TDR_DIFF_100_IN1_DIN")
	)
	(segment
		(start 243.70792 -450.112384)
		(end 243.58092 -450.239384)
		(width 0.1397)
		(layer "In5.Cu")
		(net "TDR_DIFF_100_IN1_DIN")
	)
	(segment
		(start 241.26698 -450.239384)
		(end 241.13998 -450.112384)
		(width 0.1397)
		(layer "In5.Cu")
		(net "TDR_DIFF_100_IN1_DIN")
	)
	(segment
		(start 277.294594 -453.308212)
		(end 276.9743 -452.987918)
		(width 0.1397)
		(layer "In5.Cu")
		(net "TDR_DIFF_100_IN1_DIN")
	)
	(segment
		(start 268.91234 -450.112384)
		(end 267.5128 -450.112384)
		(width 0.1397)
		(layer "In5.Cu")
		(net "TDR_DIFF_100_IN1_DIN")
	)
	(segment
		(start 247.5484 -450.239384)
		(end 247.5484 -452.987918)
		(width 0.1397)
		(layer "In5.Cu")
		(net "TDR_DIFF_100_IN1_DIN")
	)
	(segment
		(start 251.51588 -450.239384)
		(end 251.51588 -452.987918)
		(width 0.1397)
		(layer "In5.Cu")
		(net "TDR_DIFF_100_IN1_DIN")
	)
	(segment
		(start 261.424674 -453.308212)
		(end 261.10438 -452.987918)
		(width 0.1397)
		(layer "In5.Cu")
		(net "TDR_DIFF_100_IN1_DIN")
	)
	(segment
		(start 287.3502 -450.112384)
		(end 287.2232 -450.239384)
		(width 0.1397)
		(layer "In5.Cu")
		(net "TDR_DIFF_100_IN1_DIN")
	)
	(segment
		(start 264.94486 -450.112384)
		(end 263.54532 -450.112384)
		(width 0.1397)
		(layer "In5.Cu")
		(net "TDR_DIFF_100_IN1_DIN")
	)
	(segment
		(start 251.64288 -450.112384)
		(end 251.51588 -450.239384)
		(width 0.1397)
		(layer "In5.Cu")
		(net "TDR_DIFF_100_IN1_DIN")
	)
	(segment
		(start 241.26698 -452.987918)
		(end 241.26698 -450.239384)
		(width 0.1397)
		(layer "In5.Cu")
		(net "TDR_DIFF_100_IN1_DIN")
	)
	(segment
		(start 269.359634 -453.308212)
		(end 269.03934 -452.987918)
		(width 0.1397)
		(layer "In5.Cu")
		(net "TDR_DIFF_100_IN1_DIN")
	)
	(segment
		(start 292.71722 -450.112384)
		(end 291.31768 -450.112384)
		(width 0.1397)
		(layer "In5.Cu")
		(net "TDR_DIFF_100_IN1_DIN")
	)
	(segment
		(start 249.20194 -452.987918)
		(end 249.20194 -450.239384)
		(width 0.1397)
		(layer "In5.Cu")
		(net "TDR_DIFF_100_IN1_DIN")
	)
	(segment
		(start 291.19068 -452.987918)
		(end 290.870386 -453.308212)
		(width 0.1397)
		(layer "In5.Cu")
		(net "TDR_DIFF_100_IN1_DIN")
	)
	(segment
		(start 239.293146 -453.27316)
		(end 237.619794 -453.27316)
		(width 0.1397)
		(layer "In5.Cu")
		(net "TDR_DIFF_100_IN1_DIN")
	)
	(segment
		(start 265.392154 -453.308212)
		(end 265.07186 -452.987918)
		(width 0.1397)
		(layer "In5.Cu")
		(net "TDR_DIFF_100_IN1_DIN")
	)
	(segment
		(start 235.64596 -452.222362)
		(end 235.325666 -452.542656)
		(width 0.1397)
		(layer "In5.Cu")
		(net "TDR_DIFF_100_IN1_DIN")
	)
	(segment
		(start 247.228106 -453.308212)
		(end 245.554754 -453.308212)
		(width 0.1397)
		(layer "In5.Cu")
		(net "TDR_DIFF_100_IN1_DIN")
	)
	(segment
		(start 245.23446 -450.239384)
		(end 245.10746 -450.112384)
		(width 0.1397)
		(layer "In5.Cu")
		(net "TDR_DIFF_100_IN1_DIN")
	)
	(segment
		(start 288.87674 -452.987918)
		(end 288.87674 -450.239384)
		(width 0.1397)
		(layer "In5.Cu")
		(net "TDR_DIFF_100_IN1_DIN")
	)
	(segment
		(start 288.87674 -450.239384)
		(end 288.74974 -450.112384)
		(width 0.1397)
		(layer "In5.Cu")
		(net "TDR_DIFF_100_IN1_DIN")
	)
	(segment
		(start 285.229554 -453.308212)
		(end 284.90926 -452.987918)
		(width 0.1397)
		(layer "In5.Cu")
		(net "TDR_DIFF_100_IN1_DIN")
	)
	(segment
		(start 283.25572 -452.987918)
		(end 282.935426 -453.308212)
		(width 0.1397)
		(layer "In5.Cu")
		(net "TDR_DIFF_100_IN1_DIN")
	)
	(segment
		(start 287.2232 -452.987918)
		(end 286.902906 -453.308212)
		(width 0.1397)
		(layer "In5.Cu")
		(net "TDR_DIFF_100_IN1_DIN")
	)
	(segment
		(start 257.0099 -450.112384)
		(end 255.61036 -450.112384)
		(width 0.1397)
		(layer "In5.Cu")
		(net "TDR_DIFF_100_IN1_DIN")
	)
	(segment
		(start 289.197034 -453.308212)
		(end 288.87674 -452.987918)
		(width 0.1397)
		(layer "In5.Cu")
		(net "TDR_DIFF_100_IN1_DIN")
	)
	(segment
		(start 259.45084 -450.239384)
		(end 259.45084 -452.987918)
		(width 0.1397)
		(layer "In5.Cu")
		(net "TDR_DIFF_100_IN1_DIN")
	)
	(segment
		(start 263.098026 -453.308212)
		(end 261.424674 -453.308212)
		(width 0.1397)
		(layer "In5.Cu")
		(net "TDR_DIFF_100_IN1_DIN")
	)
	(segment
		(start 276.9743 -450.239384)
		(end 276.8473 -450.112384)
		(width 0.1397)
		(layer "In5.Cu")
		(net "TDR_DIFF_100_IN1_DIN")
	)
	(segment
		(start 287.2232 -450.239384)
		(end 287.2232 -452.987918)
		(width 0.1397)
		(layer "In5.Cu")
		(net "TDR_DIFF_100_IN1_DIN")
	)
	(segment
		(start 279.28824 -450.239384)
		(end 279.28824 -452.987918)
		(width 0.1397)
		(layer "In5.Cu")
		(net "TDR_DIFF_100_IN1_DIN")
	)
	(segment
		(start 263.41832 -452.987918)
		(end 263.098026 -453.308212)
		(width 0.1397)
		(layer "In5.Cu")
		(net "TDR_DIFF_100_IN1_DIN")
	)
	(segment
		(start 284.90926 -450.239384)
		(end 284.78226 -450.112384)
		(width 0.1397)
		(layer "In5.Cu")
		(net "TDR_DIFF_100_IN1_DIN")
	)
	(segment
		(start 275.32076 -450.239384)
		(end 275.32076 -452.987918)
		(width 0.1397)
		(layer "In5.Cu")
		(net "TDR_DIFF_100_IN1_DIN")
	)
	(segment
		(start 296.957242 -452.649844)
		(end 296.850054 -452.542656)
		(width 0.1397)
		(layer "In5.Cu")
		(net "TDR_DIFF_100_IN1_DIN")
	)
	(segment
		(start 257.457194 -453.308212)
		(end 257.1369 -452.987918)
		(width 0.1397)
		(layer "In5.Cu")
		(net "TDR_DIFF_100_IN1_DIN")
	)
	(segment
		(start 280.94178 -452.987918)
		(end 280.94178 -450.239384)
		(width 0.1397)
		(layer "In5.Cu")
		(net "TDR_DIFF_100_IN1_DIN")
	)
	(segment
		(start 276.9743 -452.987918)
		(end 276.9743 -450.239384)
		(width 0.1397)
		(layer "In5.Cu")
		(net "TDR_DIFF_100_IN1_DIN")
	)
	(segment
		(start 292.84422 -452.222362)
		(end 292.84422 -450.239384)
		(width 0.1397)
		(layer "In5.Cu")
		(net "TDR_DIFF_100_IN1_DIN")
	)
	(segment
		(start 257.1369 -452.987918)
		(end 257.1369 -450.239384)
		(width 0.1397)
		(layer "In5.Cu")
		(net "TDR_DIFF_100_IN1_DIN")
	)
	(segment
		(start 259.45084 -452.987918)
		(end 259.130546 -453.308212)
		(width 0.1397)
		(layer "In5.Cu")
		(net "TDR_DIFF_100_IN1_DIN")
	)
	(segment
		(start 251.51588 -452.987918)
		(end 251.195586 -453.308212)
		(width 0.1397)
		(layer "In5.Cu")
		(net "TDR_DIFF_100_IN1_DIN")
	)
	(segment
		(start 272.87982 -450.112384)
		(end 271.48028 -450.112384)
		(width 0.1397)
		(layer "In5.Cu")
		(net "TDR_DIFF_100_IN1_DIN")
	)
	(segment
		(start 265.07186 -450.239384)
		(end 264.94486 -450.112384)
		(width 0.1397)
		(layer "In5.Cu")
		(net "TDR_DIFF_100_IN1_DIN")
	)
	(segment
		(start 292.84422 -450.239384)
		(end 292.71722 -450.112384)
		(width 0.1397)
		(layer "In5.Cu")
		(net "TDR_DIFF_100_IN1_DIN")
	)
	(segment
		(start 232.936542 -452.669656)
		(end 232.936542 -453.647556)
		(width 0.1397)
		(layer "In5.Cu")
		(net "TDR_DIFF_100_IN1_DIN")
	)
	(segment
		(start 273.00682 -450.239384)
		(end 272.87982 -450.112384)
		(width 0.1397)
		(layer "In5.Cu")
		(net "TDR_DIFF_100_IN1_DIN")
	)
	(segment
		(start 247.5484 -452.987918)
		(end 247.228106 -453.308212)
		(width 0.1397)
		(layer "In5.Cu")
		(net "TDR_DIFF_100_IN1_DIN")
	)
	(segment
		(start 255.48336 -452.987918)
		(end 255.163066 -453.308212)
		(width 0.1397)
		(layer "In5.Cu")
		(net "TDR_DIFF_100_IN1_DIN")
	)
	(segment
		(start 267.5128 -450.112384)
		(end 267.3858 -450.239384)
		(width 0.1397)
		(layer "In5.Cu")
		(net "TDR_DIFF_100_IN1_DIN")
	)
	(segment
		(start 269.03934 -452.987918)
		(end 269.03934 -450.239384)
		(width 0.1397)
		(layer "In5.Cu")
		(net "TDR_DIFF_100_IN1_DIN")
	)
	(segment
		(start 237.1725 -450.112384)
		(end 235.77296 -450.112384)
		(width 0.1397)
		(layer "In5.Cu")
		(net "TDR_DIFF_100_IN1_DIN")
	)
	(segment
		(start 237.2995 -452.952866)
		(end 237.2995 -450.239384)
		(width 0.1397)
		(layer "In5.Cu")
		(net "TDR_DIFF_100_IN1_DIN")
	)
	(segment
		(start 261.10438 -450.239384)
		(end 260.97738 -450.112384)
		(width 0.1397)
		(layer "In5.Cu")
		(net "TDR_DIFF_100_IN1_DIN")
	)
	(segment
		(start 271.032986 -453.308212)
		(end 269.359634 -453.308212)
		(width 0.1397)
		(layer "In5.Cu")
		(net "TDR_DIFF_100_IN1_DIN")
	)
	(segment
		(start 263.54532 -450.112384)
		(end 263.41832 -450.239384)
		(width 0.1397)
		(layer "In5.Cu")
		(net "TDR_DIFF_100_IN1_DIN")
	)
	(segment
		(start 259.130546 -453.308212)
		(end 257.457194 -453.308212)
		(width 0.1397)
		(layer "In5.Cu")
		(net "TDR_DIFF_100_IN1_DIN")
	)
	(segment
		(start 239.74044 -450.112384)
		(end 239.61344 -450.239384)
		(width 0.1397)
		(layer "In5.Cu")
		(net "TDR_DIFF_100_IN1_DIN")
	)
	(segment
		(start 273.327114 -453.308212)
		(end 273.00682 -452.987918)
		(width 0.1397)
		(layer "In5.Cu")
		(net "TDR_DIFF_100_IN1_DIN")
	)
	(segment
		(start 269.03934 -450.239384)
		(end 268.91234 -450.112384)
		(width 0.1397)
		(layer "In5.Cu")
		(net "TDR_DIFF_100_IN1_DIN")
	)
	(segment
		(start 271.35328 -450.239384)
		(end 271.35328 -452.987918)
		(width 0.1397)
		(layer "In5.Cu")
		(net "TDR_DIFF_100_IN1_DIN")
	)
	(segment
		(start 233.063542 -452.542656)
		(end 232.936542 -452.669656)
		(width 0.1397)
		(layer "In5.Cu")
		(net "TDR_DIFF_100_IN1_DIN")
	)
	(segment
		(start 253.04242 -450.112384)
		(end 251.64288 -450.112384)
		(width 0.1397)
		(layer "In5.Cu")
		(net "TDR_DIFF_100_IN1_DIN")
	)
	(segment
		(start 241.587274 -453.308212)
		(end 241.26698 -452.987918)
		(width 0.1397)
		(layer "In5.Cu")
		(net "TDR_DIFF_100_IN1_DIN")
	)
	(segment
		(start 249.07494 -450.112384)
		(end 247.6754 -450.112384)
		(width 0.1397)
		(layer "In5.Cu")
		(net "TDR_DIFF_100_IN1_DIN")
	)
	(segment
		(start 291.19068 -450.239384)
		(end 291.19068 -452.987918)
		(width 0.1397)
		(layer "In5.Cu")
		(net "TDR_DIFF_100_IN1_DIN")
	)
	(segment
		(start 239.61344 -450.239384)
		(end 239.61344 -452.952866)
		(width 0.1397)
		(layer "In5.Cu")
		(net "TDR_DIFF_100_IN1_DIN")
	)
	(segment
		(start 259.57784 -450.112384)
		(end 259.45084 -450.239384)
		(width 0.1397)
		(layer "In5.Cu")
		(net "TDR_DIFF_100_IN1_DIN")
	)
	(segment
		(start 276.8473 -450.112384)
		(end 275.44776 -450.112384)
		(width 0.1397)
		(layer "In5.Cu")
		(net "TDR_DIFF_100_IN1_DIN")
	)
	(segment
		(start 278.967946 -453.308212)
		(end 277.294594 -453.308212)
		(width 0.1397)
		(layer "In5.Cu")
		(net "TDR_DIFF_100_IN1_DIN")
	)
	(segment
		(start 281.262074 -453.308212)
		(end 280.94178 -452.987918)
		(width 0.1397)
		(layer "In5.Cu")
		(net "TDR_DIFF_100_IN1_DIN")
	)
	(segment
		(start 257.1369 -450.239384)
		(end 257.0099 -450.112384)
		(width 0.1397)
		(layer "In5.Cu")
		(net "TDR_DIFF_100_IN1_DIN")
	)
	(segment
		(start 283.38272 -450.112384)
		(end 283.25572 -450.239384)
		(width 0.1397)
		(layer "In5.Cu")
		(net "TDR_DIFF_100_IN1_DIN")
	)
	(segment
		(start 267.3858 -452.987918)
		(end 267.065506 -453.308212)
		(width 0.1397)
		(layer "In5.Cu")
		(net "TDR_DIFF_100_IN1_DIN")
	)
	(segment
		(start 275.32076 -452.987918)
		(end 275.000466 -453.308212)
		(width 0.1397)
		(layer "In5.Cu")
		(net "TDR_DIFF_100_IN1_DIN")
	)
	(segment
		(start 251.195586 -453.308212)
		(end 249.522234 -453.308212)
		(width 0.1397)
		(layer "In5.Cu")
		(net "TDR_DIFF_100_IN1_DIN")
	)
	(segment
		(start 286.902906 -453.308212)
		(end 285.229554 -453.308212)
		(width 0.1397)
		(layer "In5.Cu")
		(net "TDR_DIFF_100_IN1_DIN")
	)
	(segment
		(start 293.164514 -452.542656)
		(end 292.84422 -452.222362)
		(width 0.1397)
		(layer "In5.Cu")
		(net "TDR_DIFF_100_IN1_DIN")
	)
	(segment
		(start 186.070748 -455.901552)
		(end 186.070748 -458.650086)
		(width 0.1397)
		(layer "In15.Cu")
		(net "TDR_DIFF_100_IN6_DIN")
	)
	(segment
		(start 182.423562 -455.581258)
		(end 182.103268 -455.901552)
		(width 0.1397)
		(layer "In15.Cu")
		(net "TDR_DIFF_100_IN6_DIN")
	)
	(segment
		(start 218.130882 -455.581258)
		(end 217.810588 -455.901552)
		(width 0.1397)
		(layer "In15.Cu")
		(net "TDR_DIFF_100_IN6_DIN")
	)
	(segment
		(start 182.103268 -455.901552)
		(end 182.103268 -458.650086)
		(width 0.1397)
		(layer "In15.Cu")
		(net "TDR_DIFF_100_IN6_DIN")
	)
	(segment
		(start 223.776794 -458.01153)
		(end 220.251528 -458.01153)
		(width 0.1397)
		(layer "In15.Cu")
		(net "TDR_DIFF_100_IN6_DIN")
	)
	(segment
		(start 172.514768 -455.901552)
		(end 172.194474 -455.581258)
		(width 0.1397)
		(layer "In15.Cu")
		(net "TDR_DIFF_100_IN6_DIN")
	)
	(segment
		(start 170.200828 -455.901552)
		(end 170.200828 -458.650086)
		(width 0.1397)
		(layer "In15.Cu")
		(net "TDR_DIFF_100_IN6_DIN")
	)
	(segment
		(start 201.940668 -455.901552)
		(end 201.940668 -458.650086)
		(width 0.1397)
		(layer "In15.Cu")
		(net "TDR_DIFF_100_IN6_DIN")
	)
	(segment
		(start 190.038228 -455.901552)
		(end 190.038228 -458.650086)
		(width 0.1397)
		(layer "In15.Cu")
		(net "TDR_DIFF_100_IN6_DIN")
	)
	(segment
		(start 166.106348 -458.742034)
		(end 164.706808 -458.742034)
		(width 0.1397)
		(layer "In15.Cu")
		(net "TDR_DIFF_100_IN6_DIN")
	)
	(segment
		(start 194.005708 -455.901552)
		(end 194.005708 -458.650086)
		(width 0.1397)
		(layer "In15.Cu")
		(net "TDR_DIFF_100_IN6_DIN")
	)
	(segment
		(start 166.233348 -455.901552)
		(end 166.233348 -458.615034)
		(width 0.1397)
		(layer "In15.Cu")
		(net "TDR_DIFF_100_IN6_DIN")
	)
	(segment
		(start 200.287128 -458.650086)
		(end 200.287128 -455.901552)
		(width 0.1397)
		(layer "In15.Cu")
		(net "TDR_DIFF_100_IN6_DIN")
	)
	(segment
		(start 192.352168 -455.901552)
		(end 192.031874 -455.581258)
		(width 0.1397)
		(layer "In15.Cu")
		(net "TDR_DIFF_100_IN6_DIN")
	)
	(segment
		(start 210.195922 -455.581258)
		(end 209.875628 -455.901552)
		(width 0.1397)
		(layer "In15.Cu")
		(net "TDR_DIFF_100_IN6_DIN")
	)
	(segment
		(start 186.070748 -458.650086)
		(end 185.943748 -458.777086)
		(width 0.1397)
		(layer "In15.Cu")
		(net "TDR_DIFF_100_IN6_DIN")
	)
	(segment
		(start 181.976268 -458.777086)
		(end 180.576728 -458.777086)
		(width 0.1397)
		(layer "In15.Cu")
		(net "TDR_DIFF_100_IN6_DIN")
	)
	(segment
		(start 182.103268 -458.650086)
		(end 181.976268 -458.777086)
		(width 0.1397)
		(layer "In15.Cu")
		(net "TDR_DIFF_100_IN6_DIN")
	)
	(segment
		(start 192.479168 -458.777086)
		(end 192.352168 -458.650086)
		(width 0.1397)
		(layer "In15.Cu")
		(net "TDR_DIFF_100_IN6_DIN")
	)
	(segment
		(start 174.168308 -455.901552)
		(end 174.168308 -458.650086)
		(width 0.1397)
		(layer "In15.Cu")
		(net "TDR_DIFF_100_IN6_DIN")
	)
	(segment
		(start 217.810588 -455.901552)
		(end 217.810588 -458.650086)
		(width 0.1397)
		(layer "In15.Cu")
		(net "TDR_DIFF_100_IN6_DIN")
	)
	(segment
		(start 162.265868 -455.901552)
		(end 162.265868 -457.88453)
		(width 0.1397)
		(layer "In15.Cu")
		(net "TDR_DIFF_100_IN6_DIN")
	)
	(segment
		(start 220.124528 -457.88453)
		(end 220.124528 -455.901552)
		(width 0.1397)
		(layer "In15.Cu")
		(net "TDR_DIFF_100_IN6_DIN")
	)
	(segment
		(start 166.233348 -458.615034)
		(end 166.106348 -458.742034)
		(width 0.1397)
		(layer "In15.Cu")
		(net "TDR_DIFF_100_IN6_DIN")
	)
	(segment
		(start 164.706808 -458.742034)
		(end 164.579808 -458.615034)
		(width 0.1397)
		(layer "In15.Cu")
		(net "TDR_DIFF_100_IN6_DIN")
	)
	(segment
		(start 164.259514 -455.581258)
		(end 162.586162 -455.581258)
		(width 0.1397)
		(layer "In15.Cu")
		(net "TDR_DIFF_100_IN6_DIN")
	)
	(segment
		(start 208.222088 -458.650086)
		(end 208.222088 -455.901552)
		(width 0.1397)
		(layer "In15.Cu")
		(net "TDR_DIFF_100_IN6_DIN")
	)
	(segment
		(start 166.553642 -455.581258)
		(end 166.233348 -455.901552)
		(width 0.1397)
		(layer "In15.Cu")
		(net "TDR_DIFF_100_IN6_DIN")
	)
	(segment
		(start 172.514768 -458.650086)
		(end 172.514768 -455.901552)
		(width 0.1397)
		(layer "In15.Cu")
		(net "TDR_DIFF_100_IN6_DIN")
	)
	(segment
		(start 178.456082 -455.581258)
		(end 178.135788 -455.901552)
		(width 0.1397)
		(layer "In15.Cu")
		(net "TDR_DIFF_100_IN6_DIN")
	)
	(segment
		(start 207.901794 -455.581258)
		(end 206.228442 -455.581258)
		(width 0.1397)
		(layer "In15.Cu")
		(net "TDR_DIFF_100_IN6_DIN")
	)
	(segment
		(start 168.226994 -455.581258)
		(end 166.553642 -455.581258)
		(width 0.1397)
		(layer "In15.Cu")
		(net "TDR_DIFF_100_IN6_DIN")
	)
	(segment
		(start 184.417208 -458.650086)
		(end 184.417208 -455.901552)
		(width 0.1397)
		(layer "In15.Cu")
		(net "TDR_DIFF_100_IN6_DIN")
	)
	(segment
		(start 204.381608 -458.777086)
		(end 204.254608 -458.650086)
		(width 0.1397)
		(layer "In15.Cu")
		(net "TDR_DIFF_100_IN6_DIN")
	)
	(segment
		(start 194.326002 -455.581258)
		(end 194.005708 -455.901552)
		(width 0.1397)
		(layer "In15.Cu")
		(net "TDR_DIFF_100_IN6_DIN")
	)
	(segment
		(start 196.319648 -458.650086)
		(end 196.319648 -455.901552)
		(width 0.1397)
		(layer "In15.Cu")
		(net "TDR_DIFF_100_IN6_DIN")
	)
	(segment
		(start 174.168308 -458.650086)
		(end 174.041308 -458.777086)
		(width 0.1397)
		(layer "In15.Cu")
		(net "TDR_DIFF_100_IN6_DIN")
	)
	(segment
		(start 196.446648 -458.777086)
		(end 196.319648 -458.650086)
		(width 0.1397)
		(layer "In15.Cu")
		(net "TDR_DIFF_100_IN6_DIN")
	)
	(segment
		(start 214.163402 -455.581258)
		(end 213.843108 -455.901552)
		(width 0.1397)
		(layer "In15.Cu")
		(net "TDR_DIFF_100_IN6_DIN")
	)
	(segment
		(start 186.391042 -455.581258)
		(end 186.070748 -455.901552)
		(width 0.1397)
		(layer "In15.Cu")
		(net "TDR_DIFF_100_IN6_DIN")
	)
	(segment
		(start 178.008788 -458.777086)
		(end 176.609248 -458.777086)
		(width 0.1397)
		(layer "In15.Cu")
		(net "TDR_DIFF_100_IN6_DIN")
	)
	(segment
		(start 196.319648 -455.901552)
		(end 195.999354 -455.581258)
		(width 0.1397)
		(layer "In15.Cu")
		(net "TDR_DIFF_100_IN6_DIN")
	)
	(segment
		(start 185.943748 -458.777086)
		(end 184.544208 -458.777086)
		(width 0.1397)
		(layer "In15.Cu")
		(net "TDR_DIFF_100_IN6_DIN")
	)
	(segment
		(start 209.875628 -458.650086)
		(end 209.748628 -458.777086)
		(width 0.1397)
		(layer "In15.Cu")
		(net "TDR_DIFF_100_IN6_DIN")
	)
	(segment
		(start 188.384688 -458.650086)
		(end 188.384688 -455.901552)
		(width 0.1397)
		(layer "In15.Cu")
		(net "TDR_DIFF_100_IN6_DIN")
	)
	(segment
		(start 176.161954 -455.581258)
		(end 174.488602 -455.581258)
		(width 0.1397)
		(layer "In15.Cu")
		(net "TDR_DIFF_100_IN6_DIN")
	)
	(segment
		(start 164.579808 -455.901552)
		(end 164.259514 -455.581258)
		(width 0.1397)
		(layer "In15.Cu")
		(net "TDR_DIFF_100_IN6_DIN")
	)
	(segment
		(start 168.547288 -455.901552)
		(end 168.226994 -455.581258)
		(width 0.1397)
		(layer "In15.Cu")
		(net "TDR_DIFF_100_IN6_DIN")
	)
	(segment
		(start 205.908148 -455.901552)
		(end 205.908148 -458.650086)
		(width 0.1397)
		(layer "In15.Cu")
		(net "TDR_DIFF_100_IN6_DIN")
	)
	(segment
		(start 208.349088 -458.777086)
		(end 208.222088 -458.650086)
		(width 0.1397)
		(layer "In15.Cu")
		(net "TDR_DIFF_100_IN6_DIN")
	)
	(segment
		(start 223.90735 -456.90663)
		(end 223.90735 -457.880974)
		(width 0.1397)
		(layer "In15.Cu")
		(net "TDR_DIFF_100_IN6_DIN")
	)
	(segment
		(start 212.316568 -458.777086)
		(end 212.189568 -458.650086)
		(width 0.1397)
		(layer "In15.Cu")
		(net "TDR_DIFF_100_IN6_DIN")
	)
	(segment
		(start 162.586162 -455.581258)
		(end 162.265868 -455.901552)
		(width 0.1397)
		(layer "In15.Cu")
		(net "TDR_DIFF_100_IN6_DIN")
	)
	(segment
		(start 176.482248 -455.901552)
		(end 176.161954 -455.581258)
		(width 0.1397)
		(layer "In15.Cu")
		(net "TDR_DIFF_100_IN6_DIN")
	)
	(segment
		(start 170.521122 -455.581258)
		(end 170.200828 -455.901552)
		(width 0.1397)
		(layer "In15.Cu")
		(net "TDR_DIFF_100_IN6_DIN")
	)
	(segment
		(start 180.576728 -458.777086)
		(end 180.449728 -458.650086)
		(width 0.1397)
		(layer "In15.Cu")
		(net "TDR_DIFF_100_IN6_DIN")
	)
	(segment
		(start 208.222088 -455.901552)
		(end 207.901794 -455.581258)
		(width 0.1397)
		(layer "In15.Cu")
		(net "TDR_DIFF_100_IN6_DIN")
	)
	(segment
		(start 202.260962 -455.581258)
		(end 201.940668 -455.901552)
		(width 0.1397)
		(layer "In15.Cu")
		(net "TDR_DIFF_100_IN6_DIN")
	)
	(segment
		(start 168.674288 -458.777086)
		(end 168.547288 -458.650086)
		(width 0.1397)
		(layer "In15.Cu")
		(net "TDR_DIFF_100_IN6_DIN")
	)
	(segment
		(start 217.810588 -458.650086)
		(end 217.683588 -458.777086)
		(width 0.1397)
		(layer "In15.Cu")
		(net "TDR_DIFF_100_IN6_DIN")
	)
	(segment
		(start 220.124528 -455.901552)
		(end 219.804234 -455.581258)
		(width 0.1397)
		(layer "In15.Cu")
		(net "TDR_DIFF_100_IN6_DIN")
	)
	(segment
		(start 176.609248 -458.777086)
		(end 176.482248 -458.650086)
		(width 0.1397)
		(layer "In15.Cu")
		(net "TDR_DIFF_100_IN6_DIN")
	)
	(segment
		(start 216.157048 -458.650086)
		(end 216.157048 -455.901552)
		(width 0.1397)
		(layer "In15.Cu")
		(net "TDR_DIFF_100_IN6_DIN")
	)
	(segment
		(start 180.449728 -458.650086)
		(end 180.449728 -455.901552)
		(width 0.1397)
		(layer "In15.Cu")
		(net "TDR_DIFF_100_IN6_DIN")
	)
	(segment
		(start 170.200828 -458.650086)
		(end 170.073828 -458.777086)
		(width 0.1397)
		(layer "In15.Cu")
		(net "TDR_DIFF_100_IN6_DIN")
	)
	(segment
		(start 162.265868 -457.88453)
		(end 162.138868 -458.01153)
		(width 0.1397)
		(layer "In15.Cu")
		(net "TDR_DIFF_100_IN6_DIN")
	)
	(segment
		(start 212.189568 -458.650086)
		(end 212.189568 -455.901552)
		(width 0.1397)
		(layer "In15.Cu")
		(net "TDR_DIFF_100_IN6_DIN")
	)
	(segment
		(start 205.781148 -458.777086)
		(end 204.381608 -458.777086)
		(width 0.1397)
		(layer "In15.Cu")
		(net "TDR_DIFF_100_IN6_DIN")
	)
	(segment
		(start 216.157048 -455.901552)
		(end 215.836754 -455.581258)
		(width 0.1397)
		(layer "In15.Cu")
		(net "TDR_DIFF_100_IN6_DIN")
	)
	(segment
		(start 192.031874 -455.581258)
		(end 190.358522 -455.581258)
		(width 0.1397)
		(layer "In15.Cu")
		(net "TDR_DIFF_100_IN6_DIN")
	)
	(segment
		(start 190.038228 -458.650086)
		(end 189.911228 -458.777086)
		(width 0.1397)
		(layer "In15.Cu")
		(net "TDR_DIFF_100_IN6_DIN")
	)
	(segment
		(start 220.251528 -458.01153)
		(end 220.124528 -457.88453)
		(width 0.1397)
		(layer "In15.Cu")
		(net "TDR_DIFF_100_IN6_DIN")
	)
	(segment
		(start 189.911228 -458.777086)
		(end 188.511688 -458.777086)
		(width 0.1397)
		(layer "In15.Cu")
		(net "TDR_DIFF_100_IN6_DIN")
	)
	(segment
		(start 188.511688 -458.777086)
		(end 188.384688 -458.650086)
		(width 0.1397)
		(layer "In15.Cu")
		(net "TDR_DIFF_100_IN6_DIN")
	)
	(segment
		(start 192.352168 -458.650086)
		(end 192.352168 -455.901552)
		(width 0.1397)
		(layer "In15.Cu")
		(net "TDR_DIFF_100_IN6_DIN")
	)
	(segment
		(start 197.973188 -455.901552)
		(end 197.973188 -458.650086)
		(width 0.1397)
		(layer "In15.Cu")
		(net "TDR_DIFF_100_IN6_DIN")
	)
	(segment
		(start 159.88665 -457.88453)
		(end 159.88665 -456.90663)
		(width 0.1397)
		(layer "In15.Cu")
		(net "TDR_DIFF_100_IN6_DIN")
	)
	(segment
		(start 197.846188 -458.777086)
		(end 196.446648 -458.777086)
		(width 0.1397)
		(layer "In15.Cu")
		(net "TDR_DIFF_100_IN6_DIN")
	)
	(segment
		(start 172.194474 -455.581258)
		(end 170.521122 -455.581258)
		(width 0.1397)
		(layer "In15.Cu")
		(net "TDR_DIFF_100_IN6_DIN")
	)
	(segment
		(start 200.287128 -455.901552)
		(end 199.966834 -455.581258)
		(width 0.1397)
		(layer "In15.Cu")
		(net "TDR_DIFF_100_IN6_DIN")
	)
	(segment
		(start 201.940668 -458.650086)
		(end 201.813668 -458.777086)
		(width 0.1397)
		(layer "In15.Cu")
		(net "TDR_DIFF_100_IN6_DIN")
	)
	(segment
		(start 178.135788 -455.901552)
		(end 178.135788 -458.650086)
		(width 0.1397)
		(layer "In15.Cu")
		(net "TDR_DIFF_100_IN6_DIN")
	)
	(segment
		(start 194.005708 -458.650086)
		(end 193.878708 -458.777086)
		(width 0.1397)
		(layer "In15.Cu")
		(net "TDR_DIFF_100_IN6_DIN")
	)
	(segment
		(start 197.973188 -458.650086)
		(end 197.846188 -458.777086)
		(width 0.1397)
		(layer "In15.Cu")
		(net "TDR_DIFF_100_IN6_DIN")
	)
	(segment
		(start 184.544208 -458.777086)
		(end 184.417208 -458.650086)
		(width 0.1397)
		(layer "In15.Cu")
		(net "TDR_DIFF_100_IN6_DIN")
	)
	(segment
		(start 184.417208 -455.901552)
		(end 184.096914 -455.581258)
		(width 0.1397)
		(layer "In15.Cu")
		(net "TDR_DIFF_100_IN6_DIN")
	)
	(segment
		(start 198.293482 -455.581258)
		(end 197.973188 -455.901552)
		(width 0.1397)
		(layer "In15.Cu")
		(net "TDR_DIFF_100_IN6_DIN")
	)
	(segment
		(start 160.01365 -458.01153)
		(end 159.88665 -457.88453)
		(width 0.1397)
		(layer "In15.Cu")
		(net "TDR_DIFF_100_IN6_DIN")
	)
	(segment
		(start 162.138868 -458.01153)
		(end 160.01365 -458.01153)
		(width 0.1397)
		(layer "In15.Cu")
		(net "TDR_DIFF_100_IN6_DIN")
	)
	(segment
		(start 215.836754 -455.581258)
		(end 214.163402 -455.581258)
		(width 0.1397)
		(layer "In15.Cu")
		(net "TDR_DIFF_100_IN6_DIN")
	)
	(segment
		(start 203.934314 -455.581258)
		(end 202.260962 -455.581258)
		(width 0.1397)
		(layer "In15.Cu")
		(net "TDR_DIFF_100_IN6_DIN")
	)
	(segment
		(start 212.189568 -455.901552)
		(end 211.869274 -455.581258)
		(width 0.1397)
		(layer "In15.Cu")
		(net "TDR_DIFF_100_IN6_DIN")
	)
	(segment
		(start 188.384688 -455.901552)
		(end 188.064394 -455.581258)
		(width 0.1397)
		(layer "In15.Cu")
		(net "TDR_DIFF_100_IN6_DIN")
	)
	(segment
		(start 174.488602 -455.581258)
		(end 174.168308 -455.901552)
		(width 0.1397)
		(layer "In15.Cu")
		(net "TDR_DIFF_100_IN6_DIN")
	)
	(segment
		(start 188.064394 -455.581258)
		(end 186.391042 -455.581258)
		(width 0.1397)
		(layer "In15.Cu")
		(net "TDR_DIFF_100_IN6_DIN")
	)
	(segment
		(start 219.804234 -455.581258)
		(end 218.130882 -455.581258)
		(width 0.1397)
		(layer "In15.Cu")
		(net "TDR_DIFF_100_IN6_DIN")
	)
	(segment
		(start 206.228442 -455.581258)
		(end 205.908148 -455.901552)
		(width 0.1397)
		(layer "In15.Cu")
		(net "TDR_DIFF_100_IN6_DIN")
	)
	(segment
		(start 180.449728 -455.901552)
		(end 180.129434 -455.581258)
		(width 0.1397)
		(layer "In15.Cu")
		(net "TDR_DIFF_100_IN6_DIN")
	)
	(segment
		(start 195.999354 -455.581258)
		(end 194.326002 -455.581258)
		(width 0.1397)
		(layer "In15.Cu")
		(net "TDR_DIFF_100_IN6_DIN")
	)
	(segment
		(start 213.843108 -458.650086)
		(end 213.716108 -458.777086)
		(width 0.1397)
		(layer "In15.Cu")
		(net "TDR_DIFF_100_IN6_DIN")
	)
	(segment
		(start 205.908148 -458.650086)
		(end 205.781148 -458.777086)
		(width 0.1397)
		(layer "In15.Cu")
		(net "TDR_DIFF_100_IN6_DIN")
	)
	(segment
		(start 170.073828 -458.777086)
		(end 168.674288 -458.777086)
		(width 0.1397)
		(layer "In15.Cu")
		(net "TDR_DIFF_100_IN6_DIN")
	)
	(segment
		(start 204.254608 -458.650086)
		(end 204.254608 -455.901552)
		(width 0.1397)
		(layer "In15.Cu")
		(net "TDR_DIFF_100_IN6_DIN")
	)
	(segment
		(start 200.414128 -458.777086)
		(end 200.287128 -458.650086)
		(width 0.1397)
		(layer "In15.Cu")
		(net "TDR_DIFF_100_IN6_DIN")
	)
	(segment
		(start 184.096914 -455.581258)
		(end 182.423562 -455.581258)
		(width 0.1397)
		(layer "In15.Cu")
		(net "TDR_DIFF_100_IN6_DIN")
	)
	(segment
		(start 201.813668 -458.777086)
		(end 200.414128 -458.777086)
		(width 0.1397)
		(layer "In15.Cu")
		(net "TDR_DIFF_100_IN6_DIN")
	)
	(segment
		(start 164.579808 -458.615034)
		(end 164.579808 -455.901552)
		(width 0.1397)
		(layer "In15.Cu")
		(net "TDR_DIFF_100_IN6_DIN")
	)
	(segment
		(start 178.135788 -458.650086)
		(end 178.008788 -458.777086)
		(width 0.1397)
		(layer "In15.Cu")
		(net "TDR_DIFF_100_IN6_DIN")
	)
	(segment
		(start 176.482248 -458.650086)
		(end 176.482248 -455.901552)
		(width 0.1397)
		(layer "In15.Cu")
		(net "TDR_DIFF_100_IN6_DIN")
	)
	(segment
		(start 209.748628 -458.777086)
		(end 208.349088 -458.777086)
		(width 0.1397)
		(layer "In15.Cu")
		(net "TDR_DIFF_100_IN6_DIN")
	)
	(segment
		(start 213.716108 -458.777086)
		(end 212.316568 -458.777086)
		(width 0.1397)
		(layer "In15.Cu")
		(net "TDR_DIFF_100_IN6_DIN")
	)
	(segment
		(start 190.358522 -455.581258)
		(end 190.038228 -455.901552)
		(width 0.1397)
		(layer "In15.Cu")
		(net "TDR_DIFF_100_IN6_DIN")
	)
	(segment
		(start 216.284048 -458.777086)
		(end 216.157048 -458.650086)
		(width 0.1397)
		(layer "In15.Cu")
		(net "TDR_DIFF_100_IN6_DIN")
	)
	(segment
		(start 223.90735 -457.880974)
		(end 223.776794 -458.01153)
		(width 0.1397)
		(layer "In15.Cu")
		(net "TDR_DIFF_100_IN6_DIN")
	)
	(segment
		(start 193.878708 -458.777086)
		(end 192.479168 -458.777086)
		(width 0.1397)
		(layer "In15.Cu")
		(net "TDR_DIFF_100_IN6_DIN")
	)
	(segment
		(start 217.683588 -458.777086)
		(end 216.284048 -458.777086)
		(width 0.1397)
		(layer "In15.Cu")
		(net "TDR_DIFF_100_IN6_DIN")
	)
	(segment
		(start 204.254608 -455.901552)
		(end 203.934314 -455.581258)
		(width 0.1397)
		(layer "In15.Cu")
		(net "TDR_DIFF_100_IN6_DIN")
	)
	(segment
		(start 211.869274 -455.581258)
		(end 210.195922 -455.581258)
		(width 0.1397)
		(layer "In15.Cu")
		(net "TDR_DIFF_100_IN6_DIN")
	)
	(segment
		(start 209.875628 -455.901552)
		(end 209.875628 -458.650086)
		(width 0.1397)
		(layer "In15.Cu")
		(net "TDR_DIFF_100_IN6_DIN")
	)
	(segment
		(start 213.843108 -455.901552)
		(end 213.843108 -458.650086)
		(width 0.1397)
		(layer "In15.Cu")
		(net "TDR_DIFF_100_IN6_DIN")
	)
	(segment
		(start 174.041308 -458.777086)
		(end 172.641768 -458.777086)
		(width 0.1397)
		(layer "In15.Cu")
		(net "TDR_DIFF_100_IN6_DIN")
	)
	(segment
		(start 168.547288 -458.650086)
		(end 168.547288 -455.901552)
		(width 0.1397)
		(layer "In15.Cu")
		(net "TDR_DIFF_100_IN6_DIN")
	)
	(segment
		(start 172.641768 -458.777086)
		(end 172.514768 -458.650086)
		(width 0.1397)
		(layer "In15.Cu")
		(net "TDR_DIFF_100_IN6_DIN")
	)
	(segment
		(start 180.129434 -455.581258)
		(end 178.456082 -455.581258)
		(width 0.1397)
		(layer "In15.Cu")
		(net "TDR_DIFF_100_IN6_DIN")
	)
	(segment
		(start 199.966834 -455.581258)
		(end 198.293482 -455.581258)
		(width 0.1397)
		(layer "In15.Cu")
		(net "TDR_DIFF_100_IN6_DIN")
	)
	(segment
		(start 199.956928 -458.786992)
		(end 199.956928 -456.038458)
		(width 0.1397)
		(layer "In15.Cu")
		(net "TDR_DIFF_100_IN6_DIP")
	)
	(segment
		(start 213.853014 -459.107286)
		(end 212.179662 -459.107286)
		(width 0.1397)
		(layer "In15.Cu")
		(net "TDR_DIFF_100_IN6_DIP")
	)
	(segment
		(start 194.462908 -455.911458)
		(end 194.335908 -456.038458)
		(width 0.1397)
		(layer "In15.Cu")
		(net "TDR_DIFF_100_IN6_DIP")
	)
	(segment
		(start 174.498508 -458.786992)
		(end 174.178214 -459.107286)
		(width 0.1397)
		(layer "In15.Cu")
		(net "TDR_DIFF_100_IN6_DIP")
	)
	(segment
		(start 206.238348 -458.786992)
		(end 205.918054 -459.107286)
		(width 0.1397)
		(layer "In15.Cu")
		(net "TDR_DIFF_100_IN6_DIP")
	)
	(segment
		(start 166.243254 -459.072234)
		(end 164.569902 -459.072234)
		(width 0.1397)
		(layer "In15.Cu")
		(net "TDR_DIFF_100_IN6_DIP")
	)
	(segment
		(start 198.303388 -456.038458)
		(end 198.303388 -458.786992)
		(width 0.1397)
		(layer "In15.Cu")
		(net "TDR_DIFF_100_IN6_DIP")
	)
	(segment
		(start 162.723068 -455.911458)
		(end 162.596068 -456.038458)
		(width 0.1397)
		(layer "In15.Cu")
		(net "TDR_DIFF_100_IN6_DIP")
	)
	(segment
		(start 174.178214 -459.107286)
		(end 172.504862 -459.107286)
		(width 0.1397)
		(layer "In15.Cu")
		(net "TDR_DIFF_100_IN6_DIP")
	)
	(segment
		(start 195.989448 -456.038458)
		(end 195.862448 -455.911458)
		(width 0.1397)
		(layer "In15.Cu")
		(net "TDR_DIFF_100_IN6_DIP")
	)
	(segment
		(start 162.275774 -458.34173)
		(end 160.01365 -458.34173)
		(width 0.1397)
		(layer "In15.Cu")
		(net "TDR_DIFF_100_IN6_DIP")
	)
	(segment
		(start 164.122608 -455.911458)
		(end 162.723068 -455.911458)
		(width 0.1397)
		(layer "In15.Cu")
		(net "TDR_DIFF_100_IN6_DIP")
	)
	(segment
		(start 198.430388 -455.911458)
		(end 198.303388 -456.038458)
		(width 0.1397)
		(layer "In15.Cu")
		(net "TDR_DIFF_100_IN6_DIP")
	)
	(segment
		(start 209.885534 -459.107286)
		(end 208.212182 -459.107286)
		(width 0.1397)
		(layer "In15.Cu")
		(net "TDR_DIFF_100_IN6_DIP")
	)
	(segment
		(start 194.015614 -459.107286)
		(end 192.342262 -459.107286)
		(width 0.1397)
		(layer "In15.Cu")
		(net "TDR_DIFF_100_IN6_DIP")
	)
	(segment
		(start 182.433468 -456.038458)
		(end 182.433468 -458.786992)
		(width 0.1397)
		(layer "In15.Cu")
		(net "TDR_DIFF_100_IN6_DIP")
	)
	(segment
		(start 218.267788 -455.911458)
		(end 218.140788 -456.038458)
		(width 0.1397)
		(layer "In15.Cu")
		(net "TDR_DIFF_100_IN6_DIP")
	)
	(segment
		(start 198.303388 -458.786992)
		(end 197.983094 -459.107286)
		(width 0.1397)
		(layer "In15.Cu")
		(net "TDR_DIFF_100_IN6_DIP")
	)
	(segment
		(start 162.596068 -456.038458)
		(end 162.596068 -458.021436)
		(width 0.1397)
		(layer "In15.Cu")
		(net "TDR_DIFF_100_IN6_DIP")
	)
	(segment
		(start 176.152048 -456.038458)
		(end 176.025048 -455.911458)
		(width 0.1397)
		(layer "In15.Cu")
		(net "TDR_DIFF_100_IN6_DIP")
	)
	(segment
		(start 170.531028 -456.038458)
		(end 170.531028 -458.786992)
		(width 0.1397)
		(layer "In15.Cu")
		(net "TDR_DIFF_100_IN6_DIP")
	)
	(segment
		(start 207.891888 -458.786992)
		(end 207.891888 -456.038458)
		(width 0.1397)
		(layer "In15.Cu")
		(net "TDR_DIFF_100_IN6_DIP")
	)
	(segment
		(start 212.179662 -459.107286)
		(end 211.859368 -458.786992)
		(width 0.1397)
		(layer "In15.Cu")
		(net "TDR_DIFF_100_IN6_DIP")
	)
	(segment
		(start 214.173308 -458.786992)
		(end 213.853014 -459.107286)
		(width 0.1397)
		(layer "In15.Cu")
		(net "TDR_DIFF_100_IN6_DIP")
	)
	(segment
		(start 201.950574 -459.107286)
		(end 200.277222 -459.107286)
		(width 0.1397)
		(layer "In15.Cu")
		(net "TDR_DIFF_100_IN6_DIP")
	)
	(segment
		(start 190.368428 -458.786992)
		(end 190.048134 -459.107286)
		(width 0.1397)
		(layer "In15.Cu")
		(net "TDR_DIFF_100_IN6_DIP")
	)
	(segment
		(start 182.113174 -459.107286)
		(end 180.439822 -459.107286)
		(width 0.1397)
		(layer "In15.Cu")
		(net "TDR_DIFF_100_IN6_DIP")
	)
	(segment
		(start 176.025048 -455.911458)
		(end 174.625508 -455.911458)
		(width 0.1397)
		(layer "In15.Cu")
		(net "TDR_DIFF_100_IN6_DIP")
	)
	(segment
		(start 217.820494 -459.107286)
		(end 216.147142 -459.107286)
		(width 0.1397)
		(layer "In15.Cu")
		(net "TDR_DIFF_100_IN6_DIP")
	)
	(segment
		(start 178.145694 -459.107286)
		(end 176.472342 -459.107286)
		(width 0.1397)
		(layer "In15.Cu")
		(net "TDR_DIFF_100_IN6_DIP")
	)
	(segment
		(start 182.433468 -458.786992)
		(end 182.113174 -459.107286)
		(width 0.1397)
		(layer "In15.Cu")
		(net "TDR_DIFF_100_IN6_DIP")
	)
	(segment
		(start 219.794328 -456.038458)
		(end 219.667328 -455.911458)
		(width 0.1397)
		(layer "In15.Cu")
		(net "TDR_DIFF_100_IN6_DIP")
	)
	(segment
		(start 203.797408 -455.911458)
		(end 202.397868 -455.911458)
		(width 0.1397)
		(layer "In15.Cu")
		(net "TDR_DIFF_100_IN6_DIP")
	)
	(segment
		(start 205.918054 -459.107286)
		(end 204.244702 -459.107286)
		(width 0.1397)
		(layer "In15.Cu")
		(net "TDR_DIFF_100_IN6_DIP")
	)
	(segment
		(start 223.800162 -458.34173)
		(end 220.114622 -458.34173)
		(width 0.1397)
		(layer "In15.Cu")
		(net "TDR_DIFF_100_IN6_DIP")
	)
	(segment
		(start 170.210734 -459.107286)
		(end 168.537382 -459.107286)
		(width 0.1397)
		(layer "In15.Cu")
		(net "TDR_DIFF_100_IN6_DIP")
	)
	(segment
		(start 187.927488 -455.911458)
		(end 186.527948 -455.911458)
		(width 0.1397)
		(layer "In15.Cu")
		(net "TDR_DIFF_100_IN6_DIP")
	)
	(segment
		(start 192.021968 -458.786992)
		(end 192.021968 -456.038458)
		(width 0.1397)
		(layer "In15.Cu")
		(net "TDR_DIFF_100_IN6_DIP")
	)
	(segment
		(start 208.212182 -459.107286)
		(end 207.891888 -458.786992)
		(width 0.1397)
		(layer "In15.Cu")
		(net "TDR_DIFF_100_IN6_DIP")
	)
	(segment
		(start 210.332828 -455.911458)
		(end 210.205828 -456.038458)
		(width 0.1397)
		(layer "In15.Cu")
		(net "TDR_DIFF_100_IN6_DIP")
	)
	(segment
		(start 164.249608 -458.75194)
		(end 164.249608 -456.038458)
		(width 0.1397)
		(layer "In15.Cu")
		(net "TDR_DIFF_100_IN6_DIP")
	)
	(segment
		(start 162.596068 -458.021436)
		(end 162.275774 -458.34173)
		(width 0.1397)
		(layer "In15.Cu")
		(net "TDR_DIFF_100_IN6_DIP")
	)
	(segment
		(start 214.300308 -455.911458)
		(end 214.173308 -456.038458)
		(width 0.1397)
		(layer "In15.Cu")
		(net "TDR_DIFF_100_IN6_DIP")
	)
	(segment
		(start 211.859368 -458.786992)
		(end 211.859368 -456.038458)
		(width 0.1397)
		(layer "In15.Cu")
		(net "TDR_DIFF_100_IN6_DIP")
	)
	(segment
		(start 160.01365 -458.34173)
		(end 159.88665 -458.46873)
		(width 0.1397)
		(layer "In15.Cu")
		(net "TDR_DIFF_100_IN6_DIP")
	)
	(segment
		(start 172.184568 -458.786992)
		(end 172.184568 -456.038458)
		(width 0.1397)
		(layer "In15.Cu")
		(net "TDR_DIFF_100_IN6_DIP")
	)
	(segment
		(start 216.147142 -459.107286)
		(end 215.826848 -458.786992)
		(width 0.1397)
		(layer "In15.Cu")
		(net "TDR_DIFF_100_IN6_DIP")
	)
	(segment
		(start 174.625508 -455.911458)
		(end 174.498508 -456.038458)
		(width 0.1397)
		(layer "In15.Cu")
		(net "TDR_DIFF_100_IN6_DIP")
	)
	(segment
		(start 191.894968 -455.911458)
		(end 190.495428 -455.911458)
		(width 0.1397)
		(layer "In15.Cu")
		(net "TDR_DIFF_100_IN6_DIP")
	)
	(segment
		(start 207.891888 -456.038458)
		(end 207.764888 -455.911458)
		(width 0.1397)
		(layer "In15.Cu")
		(net "TDR_DIFF_100_IN6_DIP")
	)
	(segment
		(start 184.087008 -458.786992)
		(end 184.087008 -456.038458)
		(width 0.1397)
		(layer "In15.Cu")
		(net "TDR_DIFF_100_IN6_DIP")
	)
	(segment
		(start 204.244702 -459.107286)
		(end 203.924408 -458.786992)
		(width 0.1397)
		(layer "In15.Cu")
		(net "TDR_DIFF_100_IN6_DIP")
	)
	(segment
		(start 210.205828 -458.786992)
		(end 209.885534 -459.107286)
		(width 0.1397)
		(layer "In15.Cu")
		(net "TDR_DIFF_100_IN6_DIP")
	)
	(segment
		(start 219.794328 -458.021436)
		(end 219.794328 -456.038458)
		(width 0.1397)
		(layer "In15.Cu")
		(net "TDR_DIFF_100_IN6_DIP")
	)
	(segment
		(start 180.119528 -458.786992)
		(end 180.119528 -456.038458)
		(width 0.1397)
		(layer "In15.Cu")
		(net "TDR_DIFF_100_IN6_DIP")
	)
	(segment
		(start 182.560468 -455.911458)
		(end 182.433468 -456.038458)
		(width 0.1397)
		(layer "In15.Cu")
		(net "TDR_DIFF_100_IN6_DIP")
	)
	(segment
		(start 200.277222 -459.107286)
		(end 199.956928 -458.786992)
		(width 0.1397)
		(layer "In15.Cu")
		(net "TDR_DIFF_100_IN6_DIP")
	)
	(segment
		(start 203.924408 -458.786992)
		(end 203.924408 -456.038458)
		(width 0.1397)
		(layer "In15.Cu")
		(net "TDR_DIFF_100_IN6_DIP")
	)
	(segment
		(start 184.087008 -456.038458)
		(end 183.960008 -455.911458)
		(width 0.1397)
		(layer "In15.Cu")
		(net "TDR_DIFF_100_IN6_DIP")
	)
	(segment
		(start 214.173308 -456.038458)
		(end 214.173308 -458.786992)
		(width 0.1397)
		(layer "In15.Cu")
		(net "TDR_DIFF_100_IN6_DIP")
	)
	(segment
		(start 176.472342 -459.107286)
		(end 176.152048 -458.786992)
		(width 0.1397)
		(layer "In15.Cu")
		(net "TDR_DIFF_100_IN6_DIP")
	)
	(segment
		(start 170.658028 -455.911458)
		(end 170.531028 -456.038458)
		(width 0.1397)
		(layer "In15.Cu")
		(net "TDR_DIFF_100_IN6_DIP")
	)
	(segment
		(start 199.829928 -455.911458)
		(end 198.430388 -455.911458)
		(width 0.1397)
		(layer "In15.Cu")
		(net "TDR_DIFF_100_IN6_DIP")
	)
	(segment
		(start 218.140788 -458.786992)
		(end 217.820494 -459.107286)
		(width 0.1397)
		(layer "In15.Cu")
		(net "TDR_DIFF_100_IN6_DIP")
	)
	(segment
		(start 188.054488 -456.038458)
		(end 187.927488 -455.911458)
		(width 0.1397)
		(layer "In15.Cu")
		(net "TDR_DIFF_100_IN6_DIP")
	)
	(segment
		(start 203.924408 -456.038458)
		(end 203.797408 -455.911458)
		(width 0.1397)
		(layer "In15.Cu")
		(net "TDR_DIFF_100_IN6_DIP")
	)
	(segment
		(start 195.989448 -458.786992)
		(end 195.989448 -456.038458)
		(width 0.1397)
		(layer "In15.Cu")
		(net "TDR_DIFF_100_IN6_DIP")
	)
	(segment
		(start 190.368428 -456.038458)
		(end 190.368428 -458.786992)
		(width 0.1397)
		(layer "In15.Cu")
		(net "TDR_DIFF_100_IN6_DIP")
	)
	(segment
		(start 172.184568 -456.038458)
		(end 172.057568 -455.911458)
		(width 0.1397)
		(layer "In15.Cu")
		(net "TDR_DIFF_100_IN6_DIP")
	)
	(segment
		(start 168.537382 -459.107286)
		(end 168.217088 -458.786992)
		(width 0.1397)
		(layer "In15.Cu")
		(net "TDR_DIFF_100_IN6_DIP")
	)
	(segment
		(start 215.826848 -456.038458)
		(end 215.699848 -455.911458)
		(width 0.1397)
		(layer "In15.Cu")
		(net "TDR_DIFF_100_IN6_DIP")
	)
	(segment
		(start 186.527948 -455.911458)
		(end 186.400948 -456.038458)
		(width 0.1397)
		(layer "In15.Cu")
		(net "TDR_DIFF_100_IN6_DIP")
	)
	(segment
		(start 223.90735 -458.448918)
		(end 223.800162 -458.34173)
		(width 0.1397)
		(layer "In15.Cu")
		(net "TDR_DIFF_100_IN6_DIP")
	)
	(segment
		(start 172.057568 -455.911458)
		(end 170.658028 -455.911458)
		(width 0.1397)
		(layer "In15.Cu")
		(net "TDR_DIFF_100_IN6_DIP")
	)
	(segment
		(start 183.960008 -455.911458)
		(end 182.560468 -455.911458)
		(width 0.1397)
		(layer "In15.Cu")
		(net "TDR_DIFF_100_IN6_DIP")
	)
	(segment
		(start 194.335908 -456.038458)
		(end 194.335908 -458.786992)
		(width 0.1397)
		(layer "In15.Cu")
		(net "TDR_DIFF_100_IN6_DIP")
	)
	(segment
		(start 206.365348 -455.911458)
		(end 206.238348 -456.038458)
		(width 0.1397)
		(layer "In15.Cu")
		(net "TDR_DIFF_100_IN6_DIP")
	)
	(segment
		(start 195.862448 -455.911458)
		(end 194.462908 -455.911458)
		(width 0.1397)
		(layer "In15.Cu")
		(net "TDR_DIFF_100_IN6_DIP")
	)
	(segment
		(start 215.826848 -458.786992)
		(end 215.826848 -456.038458)
		(width 0.1397)
		(layer "In15.Cu")
		(net "TDR_DIFF_100_IN6_DIP")
	)
	(segment
		(start 199.956928 -456.038458)
		(end 199.829928 -455.911458)
		(width 0.1397)
		(layer "In15.Cu")
		(net "TDR_DIFF_100_IN6_DIP")
	)
	(segment
		(start 164.249608 -456.038458)
		(end 164.122608 -455.911458)
		(width 0.1397)
		(layer "In15.Cu")
		(net "TDR_DIFF_100_IN6_DIP")
	)
	(segment
		(start 211.732368 -455.911458)
		(end 210.332828 -455.911458)
		(width 0.1397)
		(layer "In15.Cu")
		(net "TDR_DIFF_100_IN6_DIP")
	)
	(segment
		(start 180.119528 -456.038458)
		(end 179.992528 -455.911458)
		(width 0.1397)
		(layer "In15.Cu")
		(net "TDR_DIFF_100_IN6_DIP")
	)
	(segment
		(start 166.690548 -455.911458)
		(end 166.563548 -456.038458)
		(width 0.1397)
		(layer "In15.Cu")
		(net "TDR_DIFF_100_IN6_DIP")
	)
	(segment
		(start 188.054488 -458.786992)
		(end 188.054488 -456.038458)
		(width 0.1397)
		(layer "In15.Cu")
		(net "TDR_DIFF_100_IN6_DIP")
	)
	(segment
		(start 176.152048 -458.786992)
		(end 176.152048 -456.038458)
		(width 0.1397)
		(layer "In15.Cu")
		(net "TDR_DIFF_100_IN6_DIP")
	)
	(segment
		(start 168.217088 -458.786992)
		(end 168.217088 -456.038458)
		(width 0.1397)
		(layer "In15.Cu")
		(net "TDR_DIFF_100_IN6_DIP")
	)
	(segment
		(start 190.048134 -459.107286)
		(end 188.374782 -459.107286)
		(width 0.1397)
		(layer "In15.Cu")
		(net "TDR_DIFF_100_IN6_DIP")
	)
	(segment
		(start 168.090088 -455.911458)
		(end 166.690548 -455.911458)
		(width 0.1397)
		(layer "In15.Cu")
		(net "TDR_DIFF_100_IN6_DIP")
	)
	(segment
		(start 202.270868 -456.038458)
		(end 202.270868 -458.786992)
		(width 0.1397)
		(layer "In15.Cu")
		(net "TDR_DIFF_100_IN6_DIP")
	)
	(segment
		(start 202.270868 -458.786992)
		(end 201.950574 -459.107286)
		(width 0.1397)
		(layer "In15.Cu")
		(net "TDR_DIFF_100_IN6_DIP")
	)
	(segment
		(start 218.140788 -456.038458)
		(end 218.140788 -458.786992)
		(width 0.1397)
		(layer "In15.Cu")
		(net "TDR_DIFF_100_IN6_DIP")
	)
	(segment
		(start 211.859368 -456.038458)
		(end 211.732368 -455.911458)
		(width 0.1397)
		(layer "In15.Cu")
		(net "TDR_DIFF_100_IN6_DIP")
	)
	(segment
		(start 192.021968 -456.038458)
		(end 191.894968 -455.911458)
		(width 0.1397)
		(layer "In15.Cu")
		(net "TDR_DIFF_100_IN6_DIP")
	)
	(segment
		(start 186.400948 -456.038458)
		(end 186.400948 -458.786992)
		(width 0.1397)
		(layer "In15.Cu")
		(net "TDR_DIFF_100_IN6_DIP")
	)
	(segment
		(start 178.465988 -456.038458)
		(end 178.465988 -458.786992)
		(width 0.1397)
		(layer "In15.Cu")
		(net "TDR_DIFF_100_IN6_DIP")
	)
	(segment
		(start 174.498508 -456.038458)
		(end 174.498508 -458.786992)
		(width 0.1397)
		(layer "In15.Cu")
		(net "TDR_DIFF_100_IN6_DIP")
	)
	(segment
		(start 179.992528 -455.911458)
		(end 178.592988 -455.911458)
		(width 0.1397)
		(layer "In15.Cu")
		(net "TDR_DIFF_100_IN6_DIP")
	)
	(segment
		(start 219.667328 -455.911458)
		(end 218.267788 -455.911458)
		(width 0.1397)
		(layer "In15.Cu")
		(net "TDR_DIFF_100_IN6_DIP")
	)
	(segment
		(start 190.495428 -455.911458)
		(end 190.368428 -456.038458)
		(width 0.1397)
		(layer "In15.Cu")
		(net "TDR_DIFF_100_IN6_DIP")
	)
	(segment
		(start 178.465988 -458.786992)
		(end 178.145694 -459.107286)
		(width 0.1397)
		(layer "In15.Cu")
		(net "TDR_DIFF_100_IN6_DIP")
	)
	(segment
		(start 223.90735 -459.44663)
		(end 223.90735 -458.448918)
		(width 0.1397)
		(layer "In15.Cu")
		(net "TDR_DIFF_100_IN6_DIP")
	)
	(segment
		(start 188.374782 -459.107286)
		(end 188.054488 -458.786992)
		(width 0.1397)
		(layer "In15.Cu")
		(net "TDR_DIFF_100_IN6_DIP")
	)
	(segment
		(start 170.531028 -458.786992)
		(end 170.210734 -459.107286)
		(width 0.1397)
		(layer "In15.Cu")
		(net "TDR_DIFF_100_IN6_DIP")
	)
	(segment
		(start 159.88665 -458.46873)
		(end 159.88665 -459.44663)
		(width 0.1397)
		(layer "In15.Cu")
		(net "TDR_DIFF_100_IN6_DIP")
	)
	(segment
		(start 186.080654 -459.107286)
		(end 184.407302 -459.107286)
		(width 0.1397)
		(layer "In15.Cu")
		(net "TDR_DIFF_100_IN6_DIP")
	)
	(segment
		(start 206.238348 -456.038458)
		(end 206.238348 -458.786992)
		(width 0.1397)
		(layer "In15.Cu")
		(net "TDR_DIFF_100_IN6_DIP")
	)
	(segment
		(start 184.407302 -459.107286)
		(end 184.087008 -458.786992)
		(width 0.1397)
		(layer "In15.Cu")
		(net "TDR_DIFF_100_IN6_DIP")
	)
	(segment
		(start 168.217088 -456.038458)
		(end 168.090088 -455.911458)
		(width 0.1397)
		(layer "In15.Cu")
		(net "TDR_DIFF_100_IN6_DIP")
	)
	(segment
		(start 207.764888 -455.911458)
		(end 206.365348 -455.911458)
		(width 0.1397)
		(layer "In15.Cu")
		(net "TDR_DIFF_100_IN6_DIP")
	)
	(segment
		(start 178.592988 -455.911458)
		(end 178.465988 -456.038458)
		(width 0.1397)
		(layer "In15.Cu")
		(net "TDR_DIFF_100_IN6_DIP")
	)
	(segment
		(start 210.205828 -456.038458)
		(end 210.205828 -458.786992)
		(width 0.1397)
		(layer "In15.Cu")
		(net "TDR_DIFF_100_IN6_DIP")
	)
	(segment
		(start 194.335908 -458.786992)
		(end 194.015614 -459.107286)
		(width 0.1397)
		(layer "In15.Cu")
		(net "TDR_DIFF_100_IN6_DIP")
	)
	(segment
		(start 172.504862 -459.107286)
		(end 172.184568 -458.786992)
		(width 0.1397)
		(layer "In15.Cu")
		(net "TDR_DIFF_100_IN6_DIP")
	)
	(segment
		(start 166.563548 -458.75194)
		(end 166.243254 -459.072234)
		(width 0.1397)
		(layer "In15.Cu")
		(net "TDR_DIFF_100_IN6_DIP")
	)
	(segment
		(start 197.983094 -459.107286)
		(end 196.309742 -459.107286)
		(width 0.1397)
		(layer "In15.Cu")
		(net "TDR_DIFF_100_IN6_DIP")
	)
	(segment
		(start 215.699848 -455.911458)
		(end 214.300308 -455.911458)
		(width 0.1397)
		(layer "In15.Cu")
		(net "TDR_DIFF_100_IN6_DIP")
	)
	(segment
		(start 166.563548 -456.038458)
		(end 166.563548 -458.75194)
		(width 0.1397)
		(layer "In15.Cu")
		(net "TDR_DIFF_100_IN6_DIP")
	)
	(segment
		(start 180.439822 -459.107286)
		(end 180.119528 -458.786992)
		(width 0.1397)
		(layer "In15.Cu")
		(net "TDR_DIFF_100_IN6_DIP")
	)
	(segment
		(start 186.400948 -458.786992)
		(end 186.080654 -459.107286)
		(width 0.1397)
		(layer "In15.Cu")
		(net "TDR_DIFF_100_IN6_DIP")
	)
	(segment
		(start 196.309742 -459.107286)
		(end 195.989448 -458.786992)
		(width 0.1397)
		(layer "In15.Cu")
		(net "TDR_DIFF_100_IN6_DIP")
	)
	(segment
		(start 202.397868 -455.911458)
		(end 202.270868 -456.038458)
		(width 0.1397)
		(layer "In15.Cu")
		(net "TDR_DIFF_100_IN6_DIP")
	)
	(segment
		(start 192.342262 -459.107286)
		(end 192.021968 -458.786992)
		(width 0.1397)
		(layer "In15.Cu")
		(net "TDR_DIFF_100_IN6_DIP")
	)
	(segment
		(start 164.569902 -459.072234)
		(end 164.249608 -458.75194)
		(width 0.1397)
		(layer "In15.Cu")
		(net "TDR_DIFF_100_IN6_DIP")
	)
	(segment
		(start 220.114622 -458.34173)
		(end 219.794328 -458.021436)
		(width 0.1397)
		(layer "In15.Cu")
		(net "TDR_DIFF_100_IN6_DIP")
	)
	(segment
		(start 172.254418 -449.63588)
		(end 170.581066 -449.63588)
		(width 0.1397)
		(layer "In7.Cu")
		(net "TDR_DIFF_100_IN2_DIN")
	)
	(segment
		(start 194.065652 -452.704708)
		(end 193.938652 -452.831708)
		(width 0.1397)
		(layer "In7.Cu")
		(net "TDR_DIFF_100_IN2_DIN")
	)
	(segment
		(start 172.574712 -452.704708)
		(end 172.574712 -449.956174)
		(width 0.1397)
		(layer "In7.Cu")
		(net "TDR_DIFF_100_IN2_DIN")
	)
	(segment
		(start 174.228252 -452.704708)
		(end 174.101252 -452.831708)
		(width 0.1397)
		(layer "In7.Cu")
		(net "TDR_DIFF_100_IN2_DIN")
	)
	(segment
		(start 182.163212 -452.704708)
		(end 182.036212 -452.831708)
		(width 0.1397)
		(layer "In7.Cu")
		(net "TDR_DIFF_100_IN2_DIN")
	)
	(segment
		(start 205.968092 -449.956174)
		(end 205.968092 -452.704708)
		(width 0.1397)
		(layer "In7.Cu")
		(net "TDR_DIFF_100_IN2_DIN")
	)
	(segment
		(start 209.935572 -449.956174)
		(end 209.935572 -452.704708)
		(width 0.1397)
		(layer "In7.Cu")
		(net "TDR_DIFF_100_IN2_DIN")
	)
	(segment
		(start 162.325812 -451.939152)
		(end 162.198812 -452.066152)
		(width 0.1397)
		(layer "In7.Cu")
		(net "TDR_DIFF_100_IN2_DIN")
	)
	(segment
		(start 168.734232 -452.831708)
		(end 168.607232 -452.704708)
		(width 0.1397)
		(layer "In7.Cu")
		(net "TDR_DIFF_100_IN2_DIN")
	)
	(segment
		(start 196.379592 -452.704708)
		(end 196.379592 -449.956174)
		(width 0.1397)
		(layer "In7.Cu")
		(net "TDR_DIFF_100_IN2_DIN")
	)
	(segment
		(start 184.477152 -452.704708)
		(end 184.477152 -449.956174)
		(width 0.1397)
		(layer "In7.Cu")
		(net "TDR_DIFF_100_IN2_DIN")
	)
	(segment
		(start 220.184472 -449.956174)
		(end 219.864178 -449.63588)
		(width 0.1397)
		(layer "In7.Cu")
		(net "TDR_DIFF_100_IN2_DIN")
	)
	(segment
		(start 180.509672 -452.704708)
		(end 180.509672 -449.956174)
		(width 0.1397)
		(layer "In7.Cu")
		(net "TDR_DIFF_100_IN2_DIN")
	)
	(segment
		(start 180.636672 -452.831708)
		(end 180.509672 -452.704708)
		(width 0.1397)
		(layer "In7.Cu")
		(net "TDR_DIFF_100_IN2_DIN")
	)
	(segment
		(start 176.542192 -449.956174)
		(end 176.221898 -449.63588)
		(width 0.1397)
		(layer "In7.Cu")
		(net "TDR_DIFF_100_IN2_DIN")
	)
	(segment
		(start 206.288386 -449.63588)
		(end 205.968092 -449.956174)
		(width 0.1397)
		(layer "In7.Cu")
		(net "TDR_DIFF_100_IN2_DIN")
	)
	(segment
		(start 164.319458 -449.63588)
		(end 162.646106 -449.63588)
		(width 0.1397)
		(layer "In7.Cu")
		(net "TDR_DIFF_100_IN2_DIN")
	)
	(segment
		(start 192.091818 -449.63588)
		(end 190.418466 -449.63588)
		(width 0.1397)
		(layer "In7.Cu")
		(net "TDR_DIFF_100_IN2_DIN")
	)
	(segment
		(start 196.379592 -449.956174)
		(end 196.059298 -449.63588)
		(width 0.1397)
		(layer "In7.Cu")
		(net "TDR_DIFF_100_IN2_DIN")
	)
	(segment
		(start 211.929218 -449.63588)
		(end 210.255866 -449.63588)
		(width 0.1397)
		(layer "In7.Cu")
		(net "TDR_DIFF_100_IN2_DIN")
	)
	(segment
		(start 202.000612 -449.956174)
		(end 202.000612 -452.704708)
		(width 0.1397)
		(layer "In7.Cu")
		(net "TDR_DIFF_100_IN2_DIN")
	)
	(segment
		(start 204.441552 -452.831708)
		(end 204.314552 -452.704708)
		(width 0.1397)
		(layer "In7.Cu")
		(net "TDR_DIFF_100_IN2_DIN")
	)
	(segment
		(start 168.607232 -449.956174)
		(end 168.286938 -449.63588)
		(width 0.1397)
		(layer "In7.Cu")
		(net "TDR_DIFF_100_IN2_DIN")
	)
	(segment
		(start 215.896698 -449.63588)
		(end 214.223346 -449.63588)
		(width 0.1397)
		(layer "In7.Cu")
		(net "TDR_DIFF_100_IN2_DIN")
	)
	(segment
		(start 164.639752 -452.669656)
		(end 164.639752 -449.956174)
		(width 0.1397)
		(layer "In7.Cu")
		(net "TDR_DIFF_100_IN2_DIN")
	)
	(segment
		(start 189.971172 -452.831708)
		(end 188.571632 -452.831708)
		(width 0.1397)
		(layer "In7.Cu")
		(net "TDR_DIFF_100_IN2_DIN")
	)
	(segment
		(start 201.873612 -452.831708)
		(end 200.474072 -452.831708)
		(width 0.1397)
		(layer "In7.Cu")
		(net "TDR_DIFF_100_IN2_DIN")
	)
	(segment
		(start 192.539112 -452.831708)
		(end 192.412112 -452.704708)
		(width 0.1397)
		(layer "In7.Cu")
		(net "TDR_DIFF_100_IN2_DIN")
	)
	(segment
		(start 174.228252 -449.956174)
		(end 174.228252 -452.704708)
		(width 0.1397)
		(layer "In7.Cu")
		(net "TDR_DIFF_100_IN2_DIN")
	)
	(segment
		(start 202.000612 -452.704708)
		(end 201.873612 -452.831708)
		(width 0.1397)
		(layer "In7.Cu")
		(net "TDR_DIFF_100_IN2_DIN")
	)
	(segment
		(start 216.216992 -449.956174)
		(end 215.896698 -449.63588)
		(width 0.1397)
		(layer "In7.Cu")
		(net "TDR_DIFF_100_IN2_DIN")
	)
	(segment
		(start 168.286938 -449.63588)
		(end 166.613586 -449.63588)
		(width 0.1397)
		(layer "In7.Cu")
		(net "TDR_DIFF_100_IN2_DIN")
	)
	(segment
		(start 220.184472 -451.939152)
		(end 220.184472 -449.956174)
		(width 0.1397)
		(layer "In7.Cu")
		(net "TDR_DIFF_100_IN2_DIN")
	)
	(segment
		(start 186.450986 -449.63588)
		(end 186.130692 -449.956174)
		(width 0.1397)
		(layer "In7.Cu")
		(net "TDR_DIFF_100_IN2_DIN")
	)
	(segment
		(start 223.967294 -450.961252)
		(end 223.967294 -451.935596)
		(width 0.1397)
		(layer "In7.Cu")
		(net "TDR_DIFF_100_IN2_DIN")
	)
	(segment
		(start 172.701712 -452.831708)
		(end 172.574712 -452.704708)
		(width 0.1397)
		(layer "In7.Cu")
		(net "TDR_DIFF_100_IN2_DIN")
	)
	(segment
		(start 188.124338 -449.63588)
		(end 186.450986 -449.63588)
		(width 0.1397)
		(layer "In7.Cu")
		(net "TDR_DIFF_100_IN2_DIN")
	)
	(segment
		(start 220.311472 -452.066152)
		(end 220.184472 -451.939152)
		(width 0.1397)
		(layer "In7.Cu")
		(net "TDR_DIFF_100_IN2_DIN")
	)
	(segment
		(start 190.098172 -449.956174)
		(end 190.098172 -452.704708)
		(width 0.1397)
		(layer "In7.Cu")
		(net "TDR_DIFF_100_IN2_DIN")
	)
	(segment
		(start 198.353426 -449.63588)
		(end 198.033132 -449.956174)
		(width 0.1397)
		(layer "In7.Cu")
		(net "TDR_DIFF_100_IN2_DIN")
	)
	(segment
		(start 166.293292 -449.956174)
		(end 166.293292 -452.669656)
		(width 0.1397)
		(layer "In7.Cu")
		(net "TDR_DIFF_100_IN2_DIN")
	)
	(segment
		(start 200.347072 -449.956174)
		(end 200.026778 -449.63588)
		(width 0.1397)
		(layer "In7.Cu")
		(net "TDR_DIFF_100_IN2_DIN")
	)
	(segment
		(start 213.776052 -452.831708)
		(end 212.376512 -452.831708)
		(width 0.1397)
		(layer "In7.Cu")
		(net "TDR_DIFF_100_IN2_DIN")
	)
	(segment
		(start 197.906132 -452.831708)
		(end 196.506592 -452.831708)
		(width 0.1397)
		(layer "In7.Cu")
		(net "TDR_DIFF_100_IN2_DIN")
	)
	(segment
		(start 164.639752 -449.956174)
		(end 164.319458 -449.63588)
		(width 0.1397)
		(layer "In7.Cu")
		(net "TDR_DIFF_100_IN2_DIN")
	)
	(segment
		(start 178.195732 -449.956174)
		(end 178.195732 -452.704708)
		(width 0.1397)
		(layer "In7.Cu")
		(net "TDR_DIFF_100_IN2_DIN")
	)
	(segment
		(start 213.903052 -452.704708)
		(end 213.776052 -452.831708)
		(width 0.1397)
		(layer "In7.Cu")
		(net "TDR_DIFF_100_IN2_DIN")
	)
	(segment
		(start 219.864178 -449.63588)
		(end 218.190826 -449.63588)
		(width 0.1397)
		(layer "In7.Cu")
		(net "TDR_DIFF_100_IN2_DIN")
	)
	(segment
		(start 208.409032 -452.831708)
		(end 208.282032 -452.704708)
		(width 0.1397)
		(layer "In7.Cu")
		(net "TDR_DIFF_100_IN2_DIN")
	)
	(segment
		(start 188.444632 -449.956174)
		(end 188.124338 -449.63588)
		(width 0.1397)
		(layer "In7.Cu")
		(net "TDR_DIFF_100_IN2_DIN")
	)
	(segment
		(start 214.223346 -449.63588)
		(end 213.903052 -449.956174)
		(width 0.1397)
		(layer "In7.Cu")
		(net "TDR_DIFF_100_IN2_DIN")
	)
	(segment
		(start 217.870532 -452.704708)
		(end 217.743532 -452.831708)
		(width 0.1397)
		(layer "In7.Cu")
		(net "TDR_DIFF_100_IN2_DIN")
	)
	(segment
		(start 217.743532 -452.831708)
		(end 216.343992 -452.831708)
		(width 0.1397)
		(layer "In7.Cu")
		(net "TDR_DIFF_100_IN2_DIN")
	)
	(segment
		(start 170.133772 -452.831708)
		(end 168.734232 -452.831708)
		(width 0.1397)
		(layer "In7.Cu")
		(net "TDR_DIFF_100_IN2_DIN")
	)
	(segment
		(start 184.477152 -449.956174)
		(end 184.156858 -449.63588)
		(width 0.1397)
		(layer "In7.Cu")
		(net "TDR_DIFF_100_IN2_DIN")
	)
	(segment
		(start 162.198812 -452.066152)
		(end 160.073594 -452.066152)
		(width 0.1397)
		(layer "In7.Cu")
		(net "TDR_DIFF_100_IN2_DIN")
	)
	(segment
		(start 216.343992 -452.831708)
		(end 216.216992 -452.704708)
		(width 0.1397)
		(layer "In7.Cu")
		(net "TDR_DIFF_100_IN2_DIN")
	)
	(segment
		(start 166.613586 -449.63588)
		(end 166.293292 -449.956174)
		(width 0.1397)
		(layer "In7.Cu")
		(net "TDR_DIFF_100_IN2_DIN")
	)
	(segment
		(start 186.130692 -449.956174)
		(end 186.130692 -452.704708)
		(width 0.1397)
		(layer "In7.Cu")
		(net "TDR_DIFF_100_IN2_DIN")
	)
	(segment
		(start 184.156858 -449.63588)
		(end 182.483506 -449.63588)
		(width 0.1397)
		(layer "In7.Cu")
		(net "TDR_DIFF_100_IN2_DIN")
	)
	(segment
		(start 212.249512 -449.956174)
		(end 211.929218 -449.63588)
		(width 0.1397)
		(layer "In7.Cu")
		(net "TDR_DIFF_100_IN2_DIN")
	)
	(segment
		(start 178.195732 -452.704708)
		(end 178.068732 -452.831708)
		(width 0.1397)
		(layer "In7.Cu")
		(net "TDR_DIFF_100_IN2_DIN")
	)
	(segment
		(start 204.314552 -449.956174)
		(end 203.994258 -449.63588)
		(width 0.1397)
		(layer "In7.Cu")
		(net "TDR_DIFF_100_IN2_DIN")
	)
	(segment
		(start 198.033132 -449.956174)
		(end 198.033132 -452.704708)
		(width 0.1397)
		(layer "In7.Cu")
		(net "TDR_DIFF_100_IN2_DIN")
	)
	(segment
		(start 192.412112 -452.704708)
		(end 192.412112 -449.956174)
		(width 0.1397)
		(layer "In7.Cu")
		(net "TDR_DIFF_100_IN2_DIN")
	)
	(segment
		(start 170.260772 -452.704708)
		(end 170.133772 -452.831708)
		(width 0.1397)
		(layer "In7.Cu")
		(net "TDR_DIFF_100_IN2_DIN")
	)
	(segment
		(start 182.163212 -449.956174)
		(end 182.163212 -452.704708)
		(width 0.1397)
		(layer "In7.Cu")
		(net "TDR_DIFF_100_IN2_DIN")
	)
	(segment
		(start 198.033132 -452.704708)
		(end 197.906132 -452.831708)
		(width 0.1397)
		(layer "In7.Cu")
		(net "TDR_DIFF_100_IN2_DIN")
	)
	(segment
		(start 205.968092 -452.704708)
		(end 205.841092 -452.831708)
		(width 0.1397)
		(layer "In7.Cu")
		(net "TDR_DIFF_100_IN2_DIN")
	)
	(segment
		(start 162.325812 -449.956174)
		(end 162.325812 -451.939152)
		(width 0.1397)
		(layer "In7.Cu")
		(net "TDR_DIFF_100_IN2_DIN")
	)
	(segment
		(start 160.073594 -452.066152)
		(end 159.946594 -451.939152)
		(width 0.1397)
		(layer "In7.Cu")
		(net "TDR_DIFF_100_IN2_DIN")
	)
	(segment
		(start 205.841092 -452.831708)
		(end 204.441552 -452.831708)
		(width 0.1397)
		(layer "In7.Cu")
		(net "TDR_DIFF_100_IN2_DIN")
	)
	(segment
		(start 192.412112 -449.956174)
		(end 192.091818 -449.63588)
		(width 0.1397)
		(layer "In7.Cu")
		(net "TDR_DIFF_100_IN2_DIN")
	)
	(segment
		(start 208.282032 -452.704708)
		(end 208.282032 -449.956174)
		(width 0.1397)
		(layer "In7.Cu")
		(net "TDR_DIFF_100_IN2_DIN")
	)
	(segment
		(start 184.604152 -452.831708)
		(end 184.477152 -452.704708)
		(width 0.1397)
		(layer "In7.Cu")
		(net "TDR_DIFF_100_IN2_DIN")
	)
	(segment
		(start 209.808572 -452.831708)
		(end 208.409032 -452.831708)
		(width 0.1397)
		(layer "In7.Cu")
		(net "TDR_DIFF_100_IN2_DIN")
	)
	(segment
		(start 194.385946 -449.63588)
		(end 194.065652 -449.956174)
		(width 0.1397)
		(layer "In7.Cu")
		(net "TDR_DIFF_100_IN2_DIN")
	)
	(segment
		(start 223.967294 -451.935596)
		(end 223.836738 -452.066152)
		(width 0.1397)
		(layer "In7.Cu")
		(net "TDR_DIFF_100_IN2_DIN")
	)
	(segment
		(start 168.607232 -452.704708)
		(end 168.607232 -449.956174)
		(width 0.1397)
		(layer "In7.Cu")
		(net "TDR_DIFF_100_IN2_DIN")
	)
	(segment
		(start 166.166292 -452.796656)
		(end 164.766752 -452.796656)
		(width 0.1397)
		(layer "In7.Cu")
		(net "TDR_DIFF_100_IN2_DIN")
	)
	(segment
		(start 193.938652 -452.831708)
		(end 192.539112 -452.831708)
		(width 0.1397)
		(layer "In7.Cu")
		(net "TDR_DIFF_100_IN2_DIN")
	)
	(segment
		(start 204.314552 -452.704708)
		(end 204.314552 -449.956174)
		(width 0.1397)
		(layer "In7.Cu")
		(net "TDR_DIFF_100_IN2_DIN")
	)
	(segment
		(start 188.444632 -452.704708)
		(end 188.444632 -449.956174)
		(width 0.1397)
		(layer "In7.Cu")
		(net "TDR_DIFF_100_IN2_DIN")
	)
	(segment
		(start 164.766752 -452.796656)
		(end 164.639752 -452.669656)
		(width 0.1397)
		(layer "In7.Cu")
		(net "TDR_DIFF_100_IN2_DIN")
	)
	(segment
		(start 212.376512 -452.831708)
		(end 212.249512 -452.704708)
		(width 0.1397)
		(layer "In7.Cu")
		(net "TDR_DIFF_100_IN2_DIN")
	)
	(segment
		(start 182.483506 -449.63588)
		(end 182.163212 -449.956174)
		(width 0.1397)
		(layer "In7.Cu")
		(net "TDR_DIFF_100_IN2_DIN")
	)
	(segment
		(start 196.506592 -452.831708)
		(end 196.379592 -452.704708)
		(width 0.1397)
		(layer "In7.Cu")
		(net "TDR_DIFF_100_IN2_DIN")
	)
	(segment
		(start 213.903052 -449.956174)
		(end 213.903052 -452.704708)
		(width 0.1397)
		(layer "In7.Cu")
		(net "TDR_DIFF_100_IN2_DIN")
	)
	(segment
		(start 207.961738 -449.63588)
		(end 206.288386 -449.63588)
		(width 0.1397)
		(layer "In7.Cu")
		(net "TDR_DIFF_100_IN2_DIN")
	)
	(segment
		(start 159.946594 -451.939152)
		(end 159.946594 -450.961252)
		(width 0.1397)
		(layer "In7.Cu")
		(net "TDR_DIFF_100_IN2_DIN")
	)
	(segment
		(start 178.068732 -452.831708)
		(end 176.669192 -452.831708)
		(width 0.1397)
		(layer "In7.Cu")
		(net "TDR_DIFF_100_IN2_DIN")
	)
	(segment
		(start 186.130692 -452.704708)
		(end 186.003692 -452.831708)
		(width 0.1397)
		(layer "In7.Cu")
		(net "TDR_DIFF_100_IN2_DIN")
	)
	(segment
		(start 202.320906 -449.63588)
		(end 202.000612 -449.956174)
		(width 0.1397)
		(layer "In7.Cu")
		(net "TDR_DIFF_100_IN2_DIN")
	)
	(segment
		(start 212.249512 -452.704708)
		(end 212.249512 -449.956174)
		(width 0.1397)
		(layer "In7.Cu")
		(net "TDR_DIFF_100_IN2_DIN")
	)
	(segment
		(start 176.221898 -449.63588)
		(end 174.548546 -449.63588)
		(width 0.1397)
		(layer "In7.Cu")
		(net "TDR_DIFF_100_IN2_DIN")
	)
	(segment
		(start 172.574712 -449.956174)
		(end 172.254418 -449.63588)
		(width 0.1397)
		(layer "In7.Cu")
		(net "TDR_DIFF_100_IN2_DIN")
	)
	(segment
		(start 217.870532 -449.956174)
		(end 217.870532 -452.704708)
		(width 0.1397)
		(layer "In7.Cu")
		(net "TDR_DIFF_100_IN2_DIN")
	)
	(segment
		(start 216.216992 -452.704708)
		(end 216.216992 -449.956174)
		(width 0.1397)
		(layer "In7.Cu")
		(net "TDR_DIFF_100_IN2_DIN")
	)
	(segment
		(start 200.026778 -449.63588)
		(end 198.353426 -449.63588)
		(width 0.1397)
		(layer "In7.Cu")
		(net "TDR_DIFF_100_IN2_DIN")
	)
	(segment
		(start 209.935572 -452.704708)
		(end 209.808572 -452.831708)
		(width 0.1397)
		(layer "In7.Cu")
		(net "TDR_DIFF_100_IN2_DIN")
	)
	(segment
		(start 174.101252 -452.831708)
		(end 172.701712 -452.831708)
		(width 0.1397)
		(layer "In7.Cu")
		(net "TDR_DIFF_100_IN2_DIN")
	)
	(segment
		(start 196.059298 -449.63588)
		(end 194.385946 -449.63588)
		(width 0.1397)
		(layer "In7.Cu")
		(net "TDR_DIFF_100_IN2_DIN")
	)
	(segment
		(start 180.509672 -449.956174)
		(end 180.189378 -449.63588)
		(width 0.1397)
		(layer "In7.Cu")
		(net "TDR_DIFF_100_IN2_DIN")
	)
	(segment
		(start 194.065652 -449.956174)
		(end 194.065652 -452.704708)
		(width 0.1397)
		(layer "In7.Cu")
		(net "TDR_DIFF_100_IN2_DIN")
	)
	(segment
		(start 180.189378 -449.63588)
		(end 178.516026 -449.63588)
		(width 0.1397)
		(layer "In7.Cu")
		(net "TDR_DIFF_100_IN2_DIN")
	)
	(segment
		(start 170.581066 -449.63588)
		(end 170.260772 -449.956174)
		(width 0.1397)
		(layer "In7.Cu")
		(net "TDR_DIFF_100_IN2_DIN")
	)
	(segment
		(start 210.255866 -449.63588)
		(end 209.935572 -449.956174)
		(width 0.1397)
		(layer "In7.Cu")
		(net "TDR_DIFF_100_IN2_DIN")
	)
	(segment
		(start 166.293292 -452.669656)
		(end 166.166292 -452.796656)
		(width 0.1397)
		(layer "In7.Cu")
		(net "TDR_DIFF_100_IN2_DIN")
	)
	(segment
		(start 176.669192 -452.831708)
		(end 176.542192 -452.704708)
		(width 0.1397)
		(layer "In7.Cu")
		(net "TDR_DIFF_100_IN2_DIN")
	)
	(segment
		(start 170.260772 -449.956174)
		(end 170.260772 -452.704708)
		(width 0.1397)
		(layer "In7.Cu")
		(net "TDR_DIFF_100_IN2_DIN")
	)
	(segment
		(start 200.347072 -452.704708)
		(end 200.347072 -449.956174)
		(width 0.1397)
		(layer "In7.Cu")
		(net "TDR_DIFF_100_IN2_DIN")
	)
	(segment
		(start 190.098172 -452.704708)
		(end 189.971172 -452.831708)
		(width 0.1397)
		(layer "In7.Cu")
		(net "TDR_DIFF_100_IN2_DIN")
	)
	(segment
		(start 182.036212 -452.831708)
		(end 180.636672 -452.831708)
		(width 0.1397)
		(layer "In7.Cu")
		(net "TDR_DIFF_100_IN2_DIN")
	)
	(segment
		(start 218.190826 -449.63588)
		(end 217.870532 -449.956174)
		(width 0.1397)
		(layer "In7.Cu")
		(net "TDR_DIFF_100_IN2_DIN")
	)
	(segment
		(start 200.474072 -452.831708)
		(end 200.347072 -452.704708)
		(width 0.1397)
		(layer "In7.Cu")
		(net "TDR_DIFF_100_IN2_DIN")
	)
	(segment
		(start 188.571632 -452.831708)
		(end 188.444632 -452.704708)
		(width 0.1397)
		(layer "In7.Cu")
		(net "TDR_DIFF_100_IN2_DIN")
	)
	(segment
		(start 190.418466 -449.63588)
		(end 190.098172 -449.956174)
		(width 0.1397)
		(layer "In7.Cu")
		(net "TDR_DIFF_100_IN2_DIN")
	)
	(segment
		(start 203.994258 -449.63588)
		(end 202.320906 -449.63588)
		(width 0.1397)
		(layer "In7.Cu")
		(net "TDR_DIFF_100_IN2_DIN")
	)
	(segment
		(start 223.836738 -452.066152)
		(end 220.311472 -452.066152)
		(width 0.1397)
		(layer "In7.Cu")
		(net "TDR_DIFF_100_IN2_DIN")
	)
	(segment
		(start 162.646106 -449.63588)
		(end 162.325812 -449.956174)
		(width 0.1397)
		(layer "In7.Cu")
		(net "TDR_DIFF_100_IN2_DIN")
	)
	(segment
		(start 174.548546 -449.63588)
		(end 174.228252 -449.956174)
		(width 0.1397)
		(layer "In7.Cu")
		(net "TDR_DIFF_100_IN2_DIN")
	)
	(segment
		(start 178.516026 -449.63588)
		(end 178.195732 -449.956174)
		(width 0.1397)
		(layer "In7.Cu")
		(net "TDR_DIFF_100_IN2_DIN")
	)
	(segment
		(start 208.282032 -449.956174)
		(end 207.961738 -449.63588)
		(width 0.1397)
		(layer "In7.Cu")
		(net "TDR_DIFF_100_IN2_DIN")
	)
	(segment
		(start 176.542192 -452.704708)
		(end 176.542192 -449.956174)
		(width 0.1397)
		(layer "In7.Cu")
		(net "TDR_DIFF_100_IN2_DIN")
	)
	(segment
		(start 186.003692 -452.831708)
		(end 184.604152 -452.831708)
		(width 0.1397)
		(layer "In7.Cu")
		(net "TDR_DIFF_100_IN2_DIN")
	)
	(segment
		(start 210.530186 -438.21223)
		(end 210.530186 -440.978544)
		(width 0.1143)
		(layer "F.Cu")
		(net "TDR_DIFF_100_TOP_DIN")
	)
	(segment
		(start 180.298852 -438.117996)
		(end 178.88458 -438.117996)
		(width 0.1143)
		(layer "F.Cu")
		(net "TDR_DIFF_100_TOP_DIN")
	)
	(segment
		(start 160.142682 -440.432444)
		(end 160.041082 -440.534044)
		(width 0.1143)
		(layer "F.Cu")
		(net "TDR_DIFF_100_TOP_DIN")
	)
	(segment
		(start 182.85206 -438.117996)
		(end 182.757826 -438.21223)
		(width 0.1143)
		(layer "F.Cu")
		(net "TDR_DIFF_100_TOP_DIN")
	)
	(segment
		(start 218.55938 -438.117996)
		(end 218.465146 -438.21223)
		(width 0.1143)
		(layer "F.Cu")
		(net "TDR_DIFF_100_TOP_DIN")
	)
	(segment
		(start 192.201292 -438.117996)
		(end 190.78702 -438.117996)
		(width 0.1143)
		(layer "F.Cu")
		(net "TDR_DIFF_100_TOP_DIN")
	)
	(segment
		(start 218.465146 -438.21223)
		(end 218.465146 -440.978544)
		(width 0.1143)
		(layer "F.Cu")
		(net "TDR_DIFF_100_TOP_DIN")
	)
	(segment
		(start 182.44058 -441.29579)
		(end 180.710332 -441.29579)
		(width 0.1143)
		(layer "F.Cu")
		(net "TDR_DIFF_100_TOP_DIN")
	)
	(segment
		(start 170.855386 -440.978544)
		(end 170.53814 -441.29579)
		(width 0.1143)
		(layer "F.Cu")
		(net "TDR_DIFF_100_TOP_DIN")
	)
	(segment
		(start 162.920426 -440.04992)
		(end 162.537902 -440.432444)
		(width 0.1143)
		(layer "F.Cu")
		(net "TDR_DIFF_100_TOP_DIN")
	)
	(segment
		(start 168.396412 -438.117996)
		(end 166.98214 -438.117996)
		(width 0.1143)
		(layer "F.Cu")
		(net "TDR_DIFF_100_TOP_DIN")
	)
	(segment
		(start 214.497666 -440.978544)
		(end 214.18042 -441.29579)
		(width 0.1143)
		(layer "F.Cu")
		(net "TDR_DIFF_100_TOP_DIN")
	)
	(segment
		(start 184.677812 -441.29579)
		(end 184.360566 -440.978544)
		(width 0.1143)
		(layer "F.Cu")
		(net "TDR_DIFF_100_TOP_DIN")
	)
	(segment
		(start 206.65694 -438.117996)
		(end 206.562706 -438.21223)
		(width 0.1143)
		(layer "F.Cu")
		(net "TDR_DIFF_100_TOP_DIN")
	)
	(segment
		(start 176.331372 -438.117996)
		(end 174.9171 -438.117996)
		(width 0.1143)
		(layer "F.Cu")
		(net "TDR_DIFF_100_TOP_DIN")
	)
	(segment
		(start 196.580252 -441.29579)
		(end 196.263006 -440.978544)
		(width 0.1143)
		(layer "F.Cu")
		(net "TDR_DIFF_100_TOP_DIN")
	)
	(segment
		(start 184.266332 -438.117996)
		(end 182.85206 -438.117996)
		(width 0.1143)
		(layer "F.Cu")
		(net "TDR_DIFF_100_TOP_DIN")
	)
	(segment
		(start 168.490646 -440.978544)
		(end 168.490646 -438.21223)
		(width 0.1143)
		(layer "F.Cu")
		(net "TDR_DIFF_100_TOP_DIN")
	)
	(segment
		(start 163.01466 -438.117996)
		(end 162.920426 -438.21223)
		(width 0.1143)
		(layer "F.Cu")
		(net "TDR_DIFF_100_TOP_DIN")
	)
	(segment
		(start 178.88458 -438.117996)
		(end 178.790346 -438.21223)
		(width 0.1143)
		(layer "F.Cu")
		(net "TDR_DIFF_100_TOP_DIN")
	)
	(segment
		(start 172.775372 -441.29579)
		(end 172.458126 -440.978544)
		(width 0.1143)
		(layer "F.Cu")
		(net "TDR_DIFF_100_TOP_DIN")
	)
	(segment
		(start 208.071212 -438.117996)
		(end 206.65694 -438.117996)
		(width 0.1143)
		(layer "F.Cu")
		(net "TDR_DIFF_100_TOP_DIN")
	)
	(segment
		(start 210.62442 -438.117996)
		(end 210.530186 -438.21223)
		(width 0.1143)
		(layer "F.Cu")
		(net "TDR_DIFF_100_TOP_DIN")
	)
	(segment
		(start 212.038692 -438.117996)
		(end 210.62442 -438.117996)
		(width 0.1143)
		(layer "F.Cu")
		(net "TDR_DIFF_100_TOP_DIN")
	)
	(segment
		(start 176.425606 -438.21223)
		(end 176.331372 -438.117996)
		(width 0.1143)
		(layer "F.Cu")
		(net "TDR_DIFF_100_TOP_DIN")
	)
	(segment
		(start 182.757826 -438.21223)
		(end 182.757826 -440.978544)
		(width 0.1143)
		(layer "F.Cu")
		(net "TDR_DIFF_100_TOP_DIN")
	)
	(segment
		(start 214.18042 -441.29579)
		(end 212.450172 -441.29579)
		(width 0.1143)
		(layer "F.Cu")
		(net "TDR_DIFF_100_TOP_DIN")
	)
	(segment
		(start 188.328046 -438.21223)
		(end 188.233812 -438.117996)
		(width 0.1143)
		(layer "F.Cu")
		(net "TDR_DIFF_100_TOP_DIN")
	)
	(segment
		(start 186.725306 -438.21223)
		(end 186.725306 -440.978544)
		(width 0.1143)
		(layer "F.Cu")
		(net "TDR_DIFF_100_TOP_DIN")
	)
	(segment
		(start 190.692786 -438.21223)
		(end 190.692786 -440.978544)
		(width 0.1143)
		(layer "F.Cu")
		(net "TDR_DIFF_100_TOP_DIN")
	)
	(segment
		(start 172.458126 -438.21223)
		(end 172.363892 -438.117996)
		(width 0.1143)
		(layer "F.Cu")
		(net "TDR_DIFF_100_TOP_DIN")
	)
	(segment
		(start 204.197966 -438.21223)
		(end 204.103732 -438.117996)
		(width 0.1143)
		(layer "F.Cu")
		(net "TDR_DIFF_100_TOP_DIN")
	)
	(segment
		(start 184.360566 -438.21223)
		(end 184.266332 -438.117996)
		(width 0.1143)
		(layer "F.Cu")
		(net "TDR_DIFF_100_TOP_DIN")
	)
	(segment
		(start 214.5919 -438.117996)
		(end 214.497666 -438.21223)
		(width 0.1143)
		(layer "F.Cu")
		(net "TDR_DIFF_100_TOP_DIN")
	)
	(segment
		(start 174.50562 -441.29579)
		(end 172.775372 -441.29579)
		(width 0.1143)
		(layer "F.Cu")
		(net "TDR_DIFF_100_TOP_DIN")
	)
	(segment
		(start 178.4731 -441.29579)
		(end 176.742852 -441.29579)
		(width 0.1143)
		(layer "F.Cu")
		(net "TDR_DIFF_100_TOP_DIN")
	)
	(segment
		(start 174.9171 -438.117996)
		(end 174.822866 -438.21223)
		(width 0.1143)
		(layer "F.Cu")
		(net "TDR_DIFF_100_TOP_DIN")
	)
	(segment
		(start 200.136252 -438.117996)
		(end 198.72198 -438.117996)
		(width 0.1143)
		(layer "F.Cu")
		(net "TDR_DIFF_100_TOP_DIN")
	)
	(segment
		(start 198.72198 -438.117996)
		(end 198.627746 -438.21223)
		(width 0.1143)
		(layer "F.Cu")
		(net "TDR_DIFF_100_TOP_DIN")
	)
	(segment
		(start 216.100406 -440.978544)
		(end 216.100406 -438.21223)
		(width 0.1143)
		(layer "F.Cu")
		(net "TDR_DIFF_100_TOP_DIN")
	)
	(segment
		(start 178.790346 -438.21223)
		(end 178.790346 -440.978544)
		(width 0.1143)
		(layer "F.Cu")
		(net "TDR_DIFF_100_TOP_DIN")
	)
	(segment
		(start 224.002854 -440.432444)
		(end 223.990154 -440.445144)
		(width 0.1143)
		(layer "F.Cu")
		(net "TDR_DIFF_100_TOP_DIN")
	)
	(segment
		(start 194.34302 -441.29579)
		(end 192.612772 -441.29579)
		(width 0.1143)
		(layer "F.Cu")
		(net "TDR_DIFF_100_TOP_DIN")
	)
	(segment
		(start 170.855386 -438.21223)
		(end 170.855386 -440.978544)
		(width 0.1143)
		(layer "F.Cu")
		(net "TDR_DIFF_100_TOP_DIN")
	)
	(segment
		(start 224.074482 -440.49442)
		(end 224.012506 -440.432444)
		(width 0.1143)
		(layer "F.Cu")
		(net "TDR_DIFF_100_TOP_DIN")
	)
	(segment
		(start 194.7545 -438.117996)
		(end 194.660266 -438.21223)
		(width 0.1143)
		(layer "F.Cu")
		(net "TDR_DIFF_100_TOP_DIN")
	)
	(segment
		(start 202.595226 -438.21223)
		(end 202.595226 -440.978544)
		(width 0.1143)
		(layer "F.Cu")
		(net "TDR_DIFF_100_TOP_DIN")
	)
	(segment
		(start 206.562706 -440.978544)
		(end 206.24546 -441.29579)
		(width 0.1143)
		(layer "F.Cu")
		(net "TDR_DIFF_100_TOP_DIN")
	)
	(segment
		(start 196.168772 -438.117996)
		(end 194.7545 -438.117996)
		(width 0.1143)
		(layer "F.Cu")
		(net "TDR_DIFF_100_TOP_DIN")
	)
	(segment
		(start 166.887906 -440.978544)
		(end 166.57066 -441.29579)
		(width 0.1143)
		(layer "F.Cu")
		(net "TDR_DIFF_100_TOP_DIN")
	)
	(segment
		(start 176.742852 -441.29579)
		(end 176.425606 -440.978544)
		(width 0.1143)
		(layer "F.Cu")
		(net "TDR_DIFF_100_TOP_DIN")
	)
	(segment
		(start 224.012506 -440.432444)
		(end 224.002854 -440.432444)
		(width 0.1143)
		(layer "F.Cu")
		(net "TDR_DIFF_100_TOP_DIN")
	)
	(segment
		(start 216.006172 -438.117996)
		(end 214.5919 -438.117996)
		(width 0.1143)
		(layer "F.Cu")
		(net "TDR_DIFF_100_TOP_DIN")
	)
	(segment
		(start 200.230486 -438.21223)
		(end 200.136252 -438.117996)
		(width 0.1143)
		(layer "F.Cu")
		(net "TDR_DIFF_100_TOP_DIN")
	)
	(segment
		(start 223.990154 -440.445144)
		(end 220.385132 -440.445144)
		(width 0.1143)
		(layer "F.Cu")
		(net "TDR_DIFF_100_TOP_DIN")
	)
	(segment
		(start 162.537902 -440.432444)
		(end 160.142682 -440.432444)
		(width 0.1143)
		(layer "F.Cu")
		(net "TDR_DIFF_100_TOP_DIN")
	)
	(segment
		(start 216.100406 -438.21223)
		(end 216.006172 -438.117996)
		(width 0.1143)
		(layer "F.Cu")
		(net "TDR_DIFF_100_TOP_DIN")
	)
	(segment
		(start 190.692786 -440.978544)
		(end 190.37554 -441.29579)
		(width 0.1143)
		(layer "F.Cu")
		(net "TDR_DIFF_100_TOP_DIN")
	)
	(segment
		(start 204.103732 -438.117996)
		(end 202.68946 -438.117996)
		(width 0.1143)
		(layer "F.Cu")
		(net "TDR_DIFF_100_TOP_DIN")
	)
	(segment
		(start 186.81954 -438.117996)
		(end 186.725306 -438.21223)
		(width 0.1143)
		(layer "F.Cu")
		(net "TDR_DIFF_100_TOP_DIN")
	)
	(segment
		(start 200.547732 -441.29579)
		(end 200.230486 -440.978544)
		(width 0.1143)
		(layer "F.Cu")
		(net "TDR_DIFF_100_TOP_DIN")
	)
	(segment
		(start 206.24546 -441.29579)
		(end 204.515212 -441.29579)
		(width 0.1143)
		(layer "F.Cu")
		(net "TDR_DIFF_100_TOP_DIN")
	)
	(segment
		(start 204.515212 -441.29579)
		(end 204.197966 -440.978544)
		(width 0.1143)
		(layer "F.Cu")
		(net "TDR_DIFF_100_TOP_DIN")
	)
	(segment
		(start 178.790346 -440.978544)
		(end 178.4731 -441.29579)
		(width 0.1143)
		(layer "F.Cu")
		(net "TDR_DIFF_100_TOP_DIN")
	)
	(segment
		(start 166.98214 -438.117996)
		(end 166.887906 -438.21223)
		(width 0.1143)
		(layer "F.Cu")
		(net "TDR_DIFF_100_TOP_DIN")
	)
	(segment
		(start 206.562706 -438.21223)
		(end 206.562706 -440.978544)
		(width 0.1143)
		(layer "F.Cu")
		(net "TDR_DIFF_100_TOP_DIN")
	)
	(segment
		(start 170.53814 -441.29579)
		(end 168.807892 -441.29579)
		(width 0.1143)
		(layer "F.Cu")
		(net "TDR_DIFF_100_TOP_DIN")
	)
	(segment
		(start 160.041082 -440.534044)
		(end 160.041082 -441.524644)
		(width 0.1143)
		(layer "F.Cu")
		(net "TDR_DIFF_100_TOP_DIN")
	)
	(segment
		(start 164.428932 -438.117996)
		(end 163.01466 -438.117996)
		(width 0.1143)
		(layer "F.Cu")
		(net "TDR_DIFF_100_TOP_DIN")
	)
	(segment
		(start 164.523166 -438.21223)
		(end 164.428932 -438.117996)
		(width 0.1143)
		(layer "F.Cu")
		(net "TDR_DIFF_100_TOP_DIN")
	)
	(segment
		(start 182.757826 -440.978544)
		(end 182.44058 -441.29579)
		(width 0.1143)
		(layer "F.Cu")
		(net "TDR_DIFF_100_TOP_DIN")
	)
	(segment
		(start 204.197966 -440.978544)
		(end 204.197966 -438.21223)
		(width 0.1143)
		(layer "F.Cu")
		(net "TDR_DIFF_100_TOP_DIN")
	)
	(segment
		(start 216.417652 -441.29579)
		(end 216.100406 -440.978544)
		(width 0.1143)
		(layer "F.Cu")
		(net "TDR_DIFF_100_TOP_DIN")
	)
	(segment
		(start 192.295526 -438.21223)
		(end 192.201292 -438.117996)
		(width 0.1143)
		(layer "F.Cu")
		(net "TDR_DIFF_100_TOP_DIN")
	)
	(segment
		(start 210.21294 -441.29579)
		(end 208.482692 -441.29579)
		(width 0.1143)
		(layer "F.Cu")
		(net "TDR_DIFF_100_TOP_DIN")
	)
	(segment
		(start 176.425606 -440.978544)
		(end 176.425606 -438.21223)
		(width 0.1143)
		(layer "F.Cu")
		(net "TDR_DIFF_100_TOP_DIN")
	)
	(segment
		(start 212.450172 -441.29579)
		(end 212.132926 -440.978544)
		(width 0.1143)
		(layer "F.Cu")
		(net "TDR_DIFF_100_TOP_DIN")
	)
	(segment
		(start 190.37554 -441.29579)
		(end 188.645292 -441.29579)
		(width 0.1143)
		(layer "F.Cu")
		(net "TDR_DIFF_100_TOP_DIN")
	)
	(segment
		(start 162.920426 -438.21223)
		(end 162.920426 -440.04992)
		(width 0.1143)
		(layer "F.Cu")
		(net "TDR_DIFF_100_TOP_DIN")
	)
	(segment
		(start 166.887906 -438.21223)
		(end 166.887906 -440.978544)
		(width 0.1143)
		(layer "F.Cu")
		(net "TDR_DIFF_100_TOP_DIN")
	)
	(segment
		(start 200.230486 -440.978544)
		(end 200.230486 -438.21223)
		(width 0.1143)
		(layer "F.Cu")
		(net "TDR_DIFF_100_TOP_DIN")
	)
	(segment
		(start 198.627746 -438.21223)
		(end 198.627746 -440.978544)
		(width 0.1143)
		(layer "F.Cu")
		(net "TDR_DIFF_100_TOP_DIN")
	)
	(segment
		(start 180.710332 -441.29579)
		(end 180.393086 -440.978544)
		(width 0.1143)
		(layer "F.Cu")
		(net "TDR_DIFF_100_TOP_DIN")
	)
	(segment
		(start 224.074482 -441.524644)
		(end 224.074482 -440.49442)
		(width 0.1143)
		(layer "F.Cu")
		(net "TDR_DIFF_100_TOP_DIN")
	)
	(segment
		(start 168.490646 -438.21223)
		(end 168.396412 -438.117996)
		(width 0.1143)
		(layer "F.Cu")
		(net "TDR_DIFF_100_TOP_DIN")
	)
	(segment
		(start 180.393086 -438.21223)
		(end 180.298852 -438.117996)
		(width 0.1143)
		(layer "F.Cu")
		(net "TDR_DIFF_100_TOP_DIN")
	)
	(segment
		(start 164.523166 -440.978544)
		(end 164.523166 -438.21223)
		(width 0.1143)
		(layer "F.Cu")
		(net "TDR_DIFF_100_TOP_DIN")
	)
	(segment
		(start 212.132926 -438.21223)
		(end 212.038692 -438.117996)
		(width 0.1143)
		(layer "F.Cu")
		(net "TDR_DIFF_100_TOP_DIN")
	)
	(segment
		(start 196.263006 -440.978544)
		(end 196.263006 -438.21223)
		(width 0.1143)
		(layer "F.Cu")
		(net "TDR_DIFF_100_TOP_DIN")
	)
	(segment
		(start 186.725306 -440.978544)
		(end 186.40806 -441.29579)
		(width 0.1143)
		(layer "F.Cu")
		(net "TDR_DIFF_100_TOP_DIN")
	)
	(segment
		(start 208.165446 -438.21223)
		(end 208.071212 -438.117996)
		(width 0.1143)
		(layer "F.Cu")
		(net "TDR_DIFF_100_TOP_DIN")
	)
	(segment
		(start 220.385132 -440.445144)
		(end 220.067886 -440.127898)
		(width 0.1143)
		(layer "F.Cu")
		(net "TDR_DIFF_100_TOP_DIN")
	)
	(segment
		(start 220.067886 -438.21223)
		(end 219.973652 -438.117996)
		(width 0.1143)
		(layer "F.Cu")
		(net "TDR_DIFF_100_TOP_DIN")
	)
	(segment
		(start 210.530186 -440.978544)
		(end 210.21294 -441.29579)
		(width 0.1143)
		(layer "F.Cu")
		(net "TDR_DIFF_100_TOP_DIN")
	)
	(segment
		(start 208.165446 -440.978544)
		(end 208.165446 -438.21223)
		(width 0.1143)
		(layer "F.Cu")
		(net "TDR_DIFF_100_TOP_DIN")
	)
	(segment
		(start 194.660266 -440.978544)
		(end 194.34302 -441.29579)
		(width 0.1143)
		(layer "F.Cu")
		(net "TDR_DIFF_100_TOP_DIN")
	)
	(segment
		(start 168.807892 -441.29579)
		(end 168.490646 -440.978544)
		(width 0.1143)
		(layer "F.Cu")
		(net "TDR_DIFF_100_TOP_DIN")
	)
	(segment
		(start 192.612772 -441.29579)
		(end 192.295526 -440.978544)
		(width 0.1143)
		(layer "F.Cu")
		(net "TDR_DIFF_100_TOP_DIN")
	)
	(segment
		(start 219.973652 -438.117996)
		(end 218.55938 -438.117996)
		(width 0.1143)
		(layer "F.Cu")
		(net "TDR_DIFF_100_TOP_DIN")
	)
	(segment
		(start 188.233812 -438.117996)
		(end 186.81954 -438.117996)
		(width 0.1143)
		(layer "F.Cu")
		(net "TDR_DIFF_100_TOP_DIN")
	)
	(segment
		(start 202.68946 -438.117996)
		(end 202.595226 -438.21223)
		(width 0.1143)
		(layer "F.Cu")
		(net "TDR_DIFF_100_TOP_DIN")
	)
	(segment
		(start 212.132926 -440.978544)
		(end 212.132926 -438.21223)
		(width 0.1143)
		(layer "F.Cu")
		(net "TDR_DIFF_100_TOP_DIN")
	)
	(segment
		(start 180.393086 -440.978544)
		(end 180.393086 -438.21223)
		(width 0.1143)
		(layer "F.Cu")
		(net "TDR_DIFF_100_TOP_DIN")
	)
	(segment
		(start 218.465146 -440.978544)
		(end 218.1479 -441.29579)
		(width 0.1143)
		(layer "F.Cu")
		(net "TDR_DIFF_100_TOP_DIN")
	)
	(segment
		(start 220.067886 -440.127898)
		(end 220.067886 -438.21223)
		(width 0.1143)
		(layer "F.Cu")
		(net "TDR_DIFF_100_TOP_DIN")
	)
	(segment
		(start 194.660266 -438.21223)
		(end 194.660266 -440.978544)
		(width 0.1143)
		(layer "F.Cu")
		(net "TDR_DIFF_100_TOP_DIN")
	)
	(segment
		(start 164.840412 -441.29579)
		(end 164.523166 -440.978544)
		(width 0.1143)
		(layer "F.Cu")
		(net "TDR_DIFF_100_TOP_DIN")
	)
	(segment
		(start 172.363892 -438.117996)
		(end 170.94962 -438.117996)
		(width 0.1143)
		(layer "F.Cu")
		(net "TDR_DIFF_100_TOP_DIN")
	)
	(segment
		(start 198.627746 -440.978544)
		(end 198.3105 -441.29579)
		(width 0.1143)
		(layer "F.Cu")
		(net "TDR_DIFF_100_TOP_DIN")
	)
	(segment
		(start 218.1479 -441.29579)
		(end 216.417652 -441.29579)
		(width 0.1143)
		(layer "F.Cu")
		(net "TDR_DIFF_100_TOP_DIN")
	)
	(segment
		(start 174.822866 -440.978544)
		(end 174.50562 -441.29579)
		(width 0.1143)
		(layer "F.Cu")
		(net "TDR_DIFF_100_TOP_DIN")
	)
	(segment
		(start 202.27798 -441.29579)
		(end 200.547732 -441.29579)
		(width 0.1143)
		(layer "F.Cu")
		(net "TDR_DIFF_100_TOP_DIN")
	)
	(segment
		(start 196.263006 -438.21223)
		(end 196.168772 -438.117996)
		(width 0.1143)
		(layer "F.Cu")
		(net "TDR_DIFF_100_TOP_DIN")
	)
	(segment
		(start 198.3105 -441.29579)
		(end 196.580252 -441.29579)
		(width 0.1143)
		(layer "F.Cu")
		(net "TDR_DIFF_100_TOP_DIN")
	)
	(segment
		(start 170.94962 -438.117996)
		(end 170.855386 -438.21223)
		(width 0.1143)
		(layer "F.Cu")
		(net "TDR_DIFF_100_TOP_DIN")
	)
	(segment
		(start 166.57066 -441.29579)
		(end 164.840412 -441.29579)
		(width 0.1143)
		(layer "F.Cu")
		(net "TDR_DIFF_100_TOP_DIN")
	)
	(segment
		(start 192.295526 -440.978544)
		(end 192.295526 -438.21223)
		(width 0.1143)
		(layer "F.Cu")
		(net "TDR_DIFF_100_TOP_DIN")
	)
	(segment
		(start 188.645292 -441.29579)
		(end 188.328046 -440.978544)
		(width 0.1143)
		(layer "F.Cu")
		(net "TDR_DIFF_100_TOP_DIN")
	)
	(segment
		(start 184.360566 -440.978544)
		(end 184.360566 -438.21223)
		(width 0.1143)
		(layer "F.Cu")
		(net "TDR_DIFF_100_TOP_DIN")
	)
	(segment
		(start 202.595226 -440.978544)
		(end 202.27798 -441.29579)
		(width 0.1143)
		(layer "F.Cu")
		(net "TDR_DIFF_100_TOP_DIN")
	)
	(segment
		(start 208.482692 -441.29579)
		(end 208.165446 -440.978544)
		(width 0.1143)
		(layer "F.Cu")
		(net "TDR_DIFF_100_TOP_DIN")
	)
	(segment
		(start 172.458126 -440.978544)
		(end 172.458126 -438.21223)
		(width 0.1143)
		(layer "F.Cu")
		(net "TDR_DIFF_100_TOP_DIN")
	)
	(segment
		(start 174.822866 -438.21223)
		(end 174.822866 -440.978544)
		(width 0.1143)
		(layer "F.Cu")
		(net "TDR_DIFF_100_TOP_DIN")
	)
	(segment
		(start 188.328046 -440.978544)
		(end 188.328046 -438.21223)
		(width 0.1143)
		(layer "F.Cu")
		(net "TDR_DIFF_100_TOP_DIN")
	)
	(segment
		(start 214.497666 -438.21223)
		(end 214.497666 -440.978544)
		(width 0.1143)
		(layer "F.Cu")
		(net "TDR_DIFF_100_TOP_DIN")
	)
	(segment
		(start 186.40806 -441.29579)
		(end 184.677812 -441.29579)
		(width 0.1143)
		(layer "F.Cu")
		(net "TDR_DIFF_100_TOP_DIN")
	)
	(segment
		(start 190.78702 -438.117996)
		(end 190.692786 -438.21223)
		(width 0.1143)
		(layer "F.Cu")
		(net "TDR_DIFF_100_TOP_DIN")
	)
	(segment
		(start 218.096846 -438.059576)
		(end 218.096846 -440.82589)
		(width 0.1143)
		(layer "F.Cu")
		(net "TDR_DIFF_100_TOP_DIP")
	)
	(segment
		(start 224.074482 -439.995564)
		(end 223.993202 -440.076844)
		(width 0.1143)
		(layer "F.Cu")
		(net "TDR_DIFF_100_TOP_DIP")
	)
	(segment
		(start 178.731926 -437.749696)
		(end 178.422046 -438.059576)
		(width 0.1143)
		(layer "F.Cu")
		(net "TDR_DIFF_100_TOP_DIP")
	)
	(segment
		(start 220.436186 -438.059576)
		(end 220.126306 -437.749696)
		(width 0.1143)
		(layer "F.Cu")
		(net "TDR_DIFF_100_TOP_DIP")
	)
	(segment
		(start 166.829486 -437.749696)
		(end 166.519606 -438.059576)
		(width 0.1143)
		(layer "F.Cu")
		(net "TDR_DIFF_100_TOP_DIP")
	)
	(segment
		(start 186.357006 -438.059576)
		(end 186.357006 -440.82589)
		(width 0.1143)
		(layer "F.Cu")
		(net "TDR_DIFF_100_TOP_DIP")
	)
	(segment
		(start 186.357006 -440.82589)
		(end 186.255406 -440.92749)
		(width 0.1143)
		(layer "F.Cu")
		(net "TDR_DIFF_100_TOP_DIP")
	)
	(segment
		(start 188.696346 -440.82589)
		(end 188.696346 -438.059576)
		(width 0.1143)
		(layer "F.Cu")
		(net "TDR_DIFF_100_TOP_DIP")
	)
	(segment
		(start 200.598786 -440.82589)
		(end 200.598786 -438.059576)
		(width 0.1143)
		(layer "F.Cu")
		(net "TDR_DIFF_100_TOP_DIP")
	)
	(segment
		(start 168.549066 -437.749696)
		(end 166.829486 -437.749696)
		(width 0.1143)
		(layer "F.Cu")
		(net "TDR_DIFF_100_TOP_DIP")
	)
	(segment
		(start 206.092806 -440.92749)
		(end 204.667866 -440.92749)
		(width 0.1143)
		(layer "F.Cu")
		(net "TDR_DIFF_100_TOP_DIP")
	)
	(segment
		(start 174.764446 -437.749696)
		(end 174.454566 -438.059576)
		(width 0.1143)
		(layer "F.Cu")
		(net "TDR_DIFF_100_TOP_DIP")
	)
	(segment
		(start 166.519606 -440.82589)
		(end 166.418006 -440.92749)
		(width 0.1143)
		(layer "F.Cu")
		(net "TDR_DIFF_100_TOP_DIP")
	)
	(segment
		(start 214.027766 -440.92749)
		(end 212.602826 -440.92749)
		(width 0.1143)
		(layer "F.Cu")
		(net "TDR_DIFF_100_TOP_DIP")
	)
	(segment
		(start 162.862006 -437.749696)
		(end 162.552126 -438.059576)
		(width 0.1143)
		(layer "F.Cu")
		(net "TDR_DIFF_100_TOP_DIP")
	)
	(segment
		(start 198.259446 -438.059576)
		(end 198.259446 -440.82589)
		(width 0.1143)
		(layer "F.Cu")
		(net "TDR_DIFF_100_TOP_DIP")
	)
	(segment
		(start 206.194406 -440.82589)
		(end 206.092806 -440.92749)
		(width 0.1143)
		(layer "F.Cu")
		(net "TDR_DIFF_100_TOP_DIP")
	)
	(segment
		(start 174.454566 -438.059576)
		(end 174.454566 -440.82589)
		(width 0.1143)
		(layer "F.Cu")
		(net "TDR_DIFF_100_TOP_DIP")
	)
	(segment
		(start 190.222886 -440.92749)
		(end 188.797946 -440.92749)
		(width 0.1143)
		(layer "F.Cu")
		(net "TDR_DIFF_100_TOP_DIP")
	)
	(segment
		(start 166.418006 -440.92749)
		(end 164.993066 -440.92749)
		(width 0.1143)
		(layer "F.Cu")
		(net "TDR_DIFF_100_TOP_DIP")
	)
	(segment
		(start 218.406726 -437.749696)
		(end 218.096846 -438.059576)
		(width 0.1143)
		(layer "F.Cu")
		(net "TDR_DIFF_100_TOP_DIP")
	)
	(segment
		(start 214.439246 -437.749696)
		(end 214.129366 -438.059576)
		(width 0.1143)
		(layer "F.Cu")
		(net "TDR_DIFF_100_TOP_DIP")
	)
	(segment
		(start 166.519606 -438.059576)
		(end 166.519606 -440.82589)
		(width 0.1143)
		(layer "F.Cu")
		(net "TDR_DIFF_100_TOP_DIP")
	)
	(segment
		(start 198.569326 -437.749696)
		(end 198.259446 -438.059576)
		(width 0.1143)
		(layer "F.Cu")
		(net "TDR_DIFF_100_TOP_DIP")
	)
	(segment
		(start 220.126306 -437.749696)
		(end 218.406726 -437.749696)
		(width 0.1143)
		(layer "F.Cu")
		(net "TDR_DIFF_100_TOP_DIP")
	)
	(segment
		(start 204.256386 -437.749696)
		(end 202.536806 -437.749696)
		(width 0.1143)
		(layer "F.Cu")
		(net "TDR_DIFF_100_TOP_DIP")
	)
	(segment
		(start 178.320446 -440.92749)
		(end 176.895506 -440.92749)
		(width 0.1143)
		(layer "F.Cu")
		(net "TDR_DIFF_100_TOP_DIP")
	)
	(segment
		(start 172.928026 -440.92749)
		(end 172.826426 -440.82589)
		(width 0.1143)
		(layer "F.Cu")
		(net "TDR_DIFF_100_TOP_DIP")
	)
	(segment
		(start 172.516546 -437.749696)
		(end 170.796966 -437.749696)
		(width 0.1143)
		(layer "F.Cu")
		(net "TDR_DIFF_100_TOP_DIP")
	)
	(segment
		(start 160.129982 -440.064144)
		(end 160.041082 -439.975244)
		(width 0.1143)
		(layer "F.Cu")
		(net "TDR_DIFF_100_TOP_DIP")
	)
	(segment
		(start 164.581586 -437.749696)
		(end 162.862006 -437.749696)
		(width 0.1143)
		(layer "F.Cu")
		(net "TDR_DIFF_100_TOP_DIP")
	)
	(segment
		(start 206.504286 -437.749696)
		(end 206.194406 -438.059576)
		(width 0.1143)
		(layer "F.Cu")
		(net "TDR_DIFF_100_TOP_DIP")
	)
	(segment
		(start 184.830466 -440.92749)
		(end 184.728866 -440.82589)
		(width 0.1143)
		(layer "F.Cu")
		(net "TDR_DIFF_100_TOP_DIP")
	)
	(segment
		(start 190.324486 -438.059576)
		(end 190.324486 -440.82589)
		(width 0.1143)
		(layer "F.Cu")
		(net "TDR_DIFF_100_TOP_DIP")
	)
	(segment
		(start 180.862986 -440.92749)
		(end 180.761386 -440.82589)
		(width 0.1143)
		(layer "F.Cu")
		(net "TDR_DIFF_100_TOP_DIP")
	)
	(segment
		(start 208.533746 -438.059576)
		(end 208.223866 -437.749696)
		(width 0.1143)
		(layer "F.Cu")
		(net "TDR_DIFF_100_TOP_DIP")
	)
	(segment
		(start 176.895506 -440.92749)
		(end 176.793906 -440.82589)
		(width 0.1143)
		(layer "F.Cu")
		(net "TDR_DIFF_100_TOP_DIP")
	)
	(segment
		(start 168.858946 -438.059576)
		(end 168.549066 -437.749696)
		(width 0.1143)
		(layer "F.Cu")
		(net "TDR_DIFF_100_TOP_DIP")
	)
	(segment
		(start 162.385248 -440.064144)
		(end 160.129982 -440.064144)
		(width 0.1143)
		(layer "F.Cu")
		(net "TDR_DIFF_100_TOP_DIP")
	)
	(segment
		(start 223.993202 -440.076844)
		(end 220.537786 -440.076844)
		(width 0.1143)
		(layer "F.Cu")
		(net "TDR_DIFF_100_TOP_DIP")
	)
	(segment
		(start 220.537786 -440.076844)
		(end 220.436186 -439.975244)
		(width 0.1143)
		(layer "F.Cu")
		(net "TDR_DIFF_100_TOP_DIP")
	)
	(segment
		(start 212.501226 -440.82589)
		(end 212.501226 -438.059576)
		(width 0.1143)
		(layer "F.Cu")
		(net "TDR_DIFF_100_TOP_DIP")
	)
	(segment
		(start 216.468706 -438.059576)
		(end 216.158826 -437.749696)
		(width 0.1143)
		(layer "F.Cu")
		(net "TDR_DIFF_100_TOP_DIP")
	)
	(segment
		(start 196.732906 -440.92749)
		(end 196.631306 -440.82589)
		(width 0.1143)
		(layer "F.Cu")
		(net "TDR_DIFF_100_TOP_DIP")
	)
	(segment
		(start 168.960546 -440.92749)
		(end 168.858946 -440.82589)
		(width 0.1143)
		(layer "F.Cu")
		(net "TDR_DIFF_100_TOP_DIP")
	)
	(segment
		(start 196.631306 -440.82589)
		(end 196.631306 -438.059576)
		(width 0.1143)
		(layer "F.Cu")
		(net "TDR_DIFF_100_TOP_DIP")
	)
	(segment
		(start 164.891466 -438.059576)
		(end 164.581586 -437.749696)
		(width 0.1143)
		(layer "F.Cu")
		(net "TDR_DIFF_100_TOP_DIP")
	)
	(segment
		(start 164.891466 -440.82589)
		(end 164.891466 -438.059576)
		(width 0.1143)
		(layer "F.Cu")
		(net "TDR_DIFF_100_TOP_DIP")
	)
	(segment
		(start 172.826426 -438.059576)
		(end 172.516546 -437.749696)
		(width 0.1143)
		(layer "F.Cu")
		(net "TDR_DIFF_100_TOP_DIP")
	)
	(segment
		(start 176.793906 -438.059576)
		(end 176.484026 -437.749696)
		(width 0.1143)
		(layer "F.Cu")
		(net "TDR_DIFF_100_TOP_DIP")
	)
	(segment
		(start 174.454566 -440.82589)
		(end 174.352966 -440.92749)
		(width 0.1143)
		(layer "F.Cu")
		(net "TDR_DIFF_100_TOP_DIP")
	)
	(segment
		(start 214.129366 -438.059576)
		(end 214.129366 -440.82589)
		(width 0.1143)
		(layer "F.Cu")
		(net "TDR_DIFF_100_TOP_DIP")
	)
	(segment
		(start 184.728866 -440.82589)
		(end 184.728866 -438.059576)
		(width 0.1143)
		(layer "F.Cu")
		(net "TDR_DIFF_100_TOP_DIP")
	)
	(segment
		(start 210.161886 -440.82589)
		(end 210.060286 -440.92749)
		(width 0.1143)
		(layer "F.Cu")
		(net "TDR_DIFF_100_TOP_DIP")
	)
	(segment
		(start 200.700386 -440.92749)
		(end 200.598786 -440.82589)
		(width 0.1143)
		(layer "F.Cu")
		(net "TDR_DIFF_100_TOP_DIP")
	)
	(segment
		(start 196.321426 -437.749696)
		(end 194.601846 -437.749696)
		(width 0.1143)
		(layer "F.Cu")
		(net "TDR_DIFF_100_TOP_DIP")
	)
	(segment
		(start 190.634366 -437.749696)
		(end 190.324486 -438.059576)
		(width 0.1143)
		(layer "F.Cu")
		(net "TDR_DIFF_100_TOP_DIP")
	)
	(segment
		(start 200.288906 -437.749696)
		(end 198.569326 -437.749696)
		(width 0.1143)
		(layer "F.Cu")
		(net "TDR_DIFF_100_TOP_DIP")
	)
	(segment
		(start 176.793906 -440.82589)
		(end 176.793906 -438.059576)
		(width 0.1143)
		(layer "F.Cu")
		(net "TDR_DIFF_100_TOP_DIP")
	)
	(segment
		(start 208.223866 -437.749696)
		(end 206.504286 -437.749696)
		(width 0.1143)
		(layer "F.Cu")
		(net "TDR_DIFF_100_TOP_DIP")
	)
	(segment
		(start 220.436186 -439.975244)
		(end 220.436186 -438.059576)
		(width 0.1143)
		(layer "F.Cu")
		(net "TDR_DIFF_100_TOP_DIP")
	)
	(segment
		(start 204.667866 -440.92749)
		(end 204.566266 -440.82589)
		(width 0.1143)
		(layer "F.Cu")
		(net "TDR_DIFF_100_TOP_DIP")
	)
	(segment
		(start 200.598786 -438.059576)
		(end 200.288906 -437.749696)
		(width 0.1143)
		(layer "F.Cu")
		(net "TDR_DIFF_100_TOP_DIP")
	)
	(segment
		(start 164.993066 -440.92749)
		(end 164.891466 -440.82589)
		(width 0.1143)
		(layer "F.Cu")
		(net "TDR_DIFF_100_TOP_DIP")
	)
	(segment
		(start 180.451506 -437.749696)
		(end 178.731926 -437.749696)
		(width 0.1143)
		(layer "F.Cu")
		(net "TDR_DIFF_100_TOP_DIP")
	)
	(segment
		(start 202.125326 -440.92749)
		(end 200.700386 -440.92749)
		(width 0.1143)
		(layer "F.Cu")
		(net "TDR_DIFF_100_TOP_DIP")
	)
	(segment
		(start 190.324486 -440.82589)
		(end 190.222886 -440.92749)
		(width 0.1143)
		(layer "F.Cu")
		(net "TDR_DIFF_100_TOP_DIP")
	)
	(segment
		(start 182.389526 -438.059576)
		(end 182.389526 -440.82589)
		(width 0.1143)
		(layer "F.Cu")
		(net "TDR_DIFF_100_TOP_DIP")
	)
	(segment
		(start 178.422046 -438.059576)
		(end 178.422046 -440.82589)
		(width 0.1143)
		(layer "F.Cu")
		(net "TDR_DIFF_100_TOP_DIP")
	)
	(segment
		(start 192.765426 -440.92749)
		(end 192.663826 -440.82589)
		(width 0.1143)
		(layer "F.Cu")
		(net "TDR_DIFF_100_TOP_DIP")
	)
	(segment
		(start 188.386466 -437.749696)
		(end 186.666886 -437.749696)
		(width 0.1143)
		(layer "F.Cu")
		(net "TDR_DIFF_100_TOP_DIP")
	)
	(segment
		(start 194.291966 -438.059576)
		(end 194.291966 -440.82589)
		(width 0.1143)
		(layer "F.Cu")
		(net "TDR_DIFF_100_TOP_DIP")
	)
	(segment
		(start 162.552126 -438.059576)
		(end 162.552126 -439.897266)
		(width 0.1143)
		(layer "F.Cu")
		(net "TDR_DIFF_100_TOP_DIP")
	)
	(segment
		(start 194.601846 -437.749696)
		(end 194.291966 -438.059576)
		(width 0.1143)
		(layer "F.Cu")
		(net "TDR_DIFF_100_TOP_DIP")
	)
	(segment
		(start 198.157846 -440.92749)
		(end 196.732906 -440.92749)
		(width 0.1143)
		(layer "F.Cu")
		(net "TDR_DIFF_100_TOP_DIP")
	)
	(segment
		(start 160.041082 -439.975244)
		(end 160.041082 -438.984644)
		(width 0.1143)
		(layer "F.Cu")
		(net "TDR_DIFF_100_TOP_DIP")
	)
	(segment
		(start 208.635346 -440.92749)
		(end 208.533746 -440.82589)
		(width 0.1143)
		(layer "F.Cu")
		(net "TDR_DIFF_100_TOP_DIP")
	)
	(segment
		(start 198.259446 -440.82589)
		(end 198.157846 -440.92749)
		(width 0.1143)
		(layer "F.Cu")
		(net "TDR_DIFF_100_TOP_DIP")
	)
	(segment
		(start 212.501226 -438.059576)
		(end 212.191346 -437.749696)
		(width 0.1143)
		(layer "F.Cu")
		(net "TDR_DIFF_100_TOP_DIP")
	)
	(segment
		(start 178.422046 -440.82589)
		(end 178.320446 -440.92749)
		(width 0.1143)
		(layer "F.Cu")
		(net "TDR_DIFF_100_TOP_DIP")
	)
	(segment
		(start 206.194406 -438.059576)
		(end 206.194406 -440.82589)
		(width 0.1143)
		(layer "F.Cu")
		(net "TDR_DIFF_100_TOP_DIP")
	)
	(segment
		(start 204.566266 -438.059576)
		(end 204.256386 -437.749696)
		(width 0.1143)
		(layer "F.Cu")
		(net "TDR_DIFF_100_TOP_DIP")
	)
	(segment
		(start 174.352966 -440.92749)
		(end 172.928026 -440.92749)
		(width 0.1143)
		(layer "F.Cu")
		(net "TDR_DIFF_100_TOP_DIP")
	)
	(segment
		(start 202.226926 -438.059576)
		(end 202.226926 -440.82589)
		(width 0.1143)
		(layer "F.Cu")
		(net "TDR_DIFF_100_TOP_DIP")
	)
	(segment
		(start 214.129366 -440.82589)
		(end 214.027766 -440.92749)
		(width 0.1143)
		(layer "F.Cu")
		(net "TDR_DIFF_100_TOP_DIP")
	)
	(segment
		(start 216.570306 -440.92749)
		(end 216.468706 -440.82589)
		(width 0.1143)
		(layer "F.Cu")
		(net "TDR_DIFF_100_TOP_DIP")
	)
	(segment
		(start 224.074482 -438.984644)
		(end 224.074482 -439.995564)
		(width 0.1143)
		(layer "F.Cu")
		(net "TDR_DIFF_100_TOP_DIP")
	)
	(segment
		(start 204.566266 -440.82589)
		(end 204.566266 -438.059576)
		(width 0.1143)
		(layer "F.Cu")
		(net "TDR_DIFF_100_TOP_DIP")
	)
	(segment
		(start 182.287926 -440.92749)
		(end 180.862986 -440.92749)
		(width 0.1143)
		(layer "F.Cu")
		(net "TDR_DIFF_100_TOP_DIP")
	)
	(segment
		(start 182.699406 -437.749696)
		(end 182.389526 -438.059576)
		(width 0.1143)
		(layer "F.Cu")
		(net "TDR_DIFF_100_TOP_DIP")
	)
	(segment
		(start 208.533746 -440.82589)
		(end 208.533746 -438.059576)
		(width 0.1143)
		(layer "F.Cu")
		(net "TDR_DIFF_100_TOP_DIP")
	)
	(segment
		(start 216.158826 -437.749696)
		(end 214.439246 -437.749696)
		(width 0.1143)
		(layer "F.Cu")
		(net "TDR_DIFF_100_TOP_DIP")
	)
	(segment
		(start 176.484026 -437.749696)
		(end 174.764446 -437.749696)
		(width 0.1143)
		(layer "F.Cu")
		(net "TDR_DIFF_100_TOP_DIP")
	)
	(segment
		(start 202.226926 -440.82589)
		(end 202.125326 -440.92749)
		(width 0.1143)
		(layer "F.Cu")
		(net "TDR_DIFF_100_TOP_DIP")
	)
	(segment
		(start 210.471766 -437.749696)
		(end 210.161886 -438.059576)
		(width 0.1143)
		(layer "F.Cu")
		(net "TDR_DIFF_100_TOP_DIP")
	)
	(segment
		(start 192.353946 -437.749696)
		(end 190.634366 -437.749696)
		(width 0.1143)
		(layer "F.Cu")
		(net "TDR_DIFF_100_TOP_DIP")
	)
	(segment
		(start 180.761386 -438.059576)
		(end 180.451506 -437.749696)
		(width 0.1143)
		(layer "F.Cu")
		(net "TDR_DIFF_100_TOP_DIP")
	)
	(segment
		(start 184.418986 -437.749696)
		(end 182.699406 -437.749696)
		(width 0.1143)
		(layer "F.Cu")
		(net "TDR_DIFF_100_TOP_DIP")
	)
	(segment
		(start 180.761386 -440.82589)
		(end 180.761386 -438.059576)
		(width 0.1143)
		(layer "F.Cu")
		(net "TDR_DIFF_100_TOP_DIP")
	)
	(segment
		(start 184.728866 -438.059576)
		(end 184.418986 -437.749696)
		(width 0.1143)
		(layer "F.Cu")
		(net "TDR_DIFF_100_TOP_DIP")
	)
	(segment
		(start 182.389526 -440.82589)
		(end 182.287926 -440.92749)
		(width 0.1143)
		(layer "F.Cu")
		(net "TDR_DIFF_100_TOP_DIP")
	)
	(segment
		(start 170.796966 -437.749696)
		(end 170.487086 -438.059576)
		(width 0.1143)
		(layer "F.Cu")
		(net "TDR_DIFF_100_TOP_DIP")
	)
	(segment
		(start 194.291966 -440.82589)
		(end 194.190366 -440.92749)
		(width 0.1143)
		(layer "F.Cu")
		(net "TDR_DIFF_100_TOP_DIP")
	)
	(segment
		(start 162.552126 -439.897266)
		(end 162.385248 -440.064144)
		(width 0.1143)
		(layer "F.Cu")
		(net "TDR_DIFF_100_TOP_DIP")
	)
	(segment
		(start 192.663826 -440.82589)
		(end 192.663826 -438.059576)
		(width 0.1143)
		(layer "F.Cu")
		(net "TDR_DIFF_100_TOP_DIP")
	)
	(segment
		(start 210.161886 -438.059576)
		(end 210.161886 -440.82589)
		(width 0.1143)
		(layer "F.Cu")
		(net "TDR_DIFF_100_TOP_DIP")
	)
	(segment
		(start 212.191346 -437.749696)
		(end 210.471766 -437.749696)
		(width 0.1143)
		(layer "F.Cu")
		(net "TDR_DIFF_100_TOP_DIP")
	)
	(segment
		(start 210.060286 -440.92749)
		(end 208.635346 -440.92749)
		(width 0.1143)
		(layer "F.Cu")
		(net "TDR_DIFF_100_TOP_DIP")
	)
	(segment
		(start 202.536806 -437.749696)
		(end 202.226926 -438.059576)
		(width 0.1143)
		(layer "F.Cu")
		(net "TDR_DIFF_100_TOP_DIP")
	)
	(segment
		(start 168.858946 -440.82589)
		(end 168.858946 -438.059576)
		(width 0.1143)
		(layer "F.Cu")
		(net "TDR_DIFF_100_TOP_DIP")
	)
	(segment
		(start 196.631306 -438.059576)
		(end 196.321426 -437.749696)
		(width 0.1143)
		(layer "F.Cu")
		(net "TDR_DIFF_100_TOP_DIP")
	)
	(segment
		(start 186.255406 -440.92749)
		(end 184.830466 -440.92749)
		(width 0.1143)
		(layer "F.Cu")
		(net "TDR_DIFF_100_TOP_DIP")
	)
	(segment
		(start 192.663826 -438.059576)
		(end 192.353946 -437.749696)
		(width 0.1143)
		(layer "F.Cu")
		(net "TDR_DIFF_100_TOP_DIP")
	)
	(segment
		(start 170.487086 -438.059576)
		(end 170.487086 -440.82589)
		(width 0.1143)
		(layer "F.Cu")
		(net "TDR_DIFF_100_TOP_DIP")
	)
	(segment
		(start 188.696346 -438.059576)
		(end 188.386466 -437.749696)
		(width 0.1143)
		(layer "F.Cu")
		(net "TDR_DIFF_100_TOP_DIP")
	)
	(segment
		(start 218.096846 -440.82589)
		(end 217.995246 -440.92749)
		(width 0.1143)
		(layer "F.Cu")
		(net "TDR_DIFF_100_TOP_DIP")
	)
	(segment
		(start 170.385486 -440.92749)
		(end 168.960546 -440.92749)
		(width 0.1143)
		(layer "F.Cu")
		(net "TDR_DIFF_100_TOP_DIP")
	)
	(segment
		(start 186.666886 -437.749696)
		(end 186.357006 -438.059576)
		(width 0.1143)
		(layer "F.Cu")
		(net "TDR_DIFF_100_TOP_DIP")
	)
	(segment
		(start 172.826426 -440.82589)
		(end 172.826426 -438.059576)
		(width 0.1143)
		(layer "F.Cu")
		(net "TDR_DIFF_100_TOP_DIP")
	)
	(segment
		(start 216.468706 -440.82589)
		(end 216.468706 -438.059576)
		(width 0.1143)
		(layer "F.Cu")
		(net "TDR_DIFF_100_TOP_DIP")
	)
	(segment
		(start 194.190366 -440.92749)
		(end 192.765426 -440.92749)
		(width 0.1143)
		(layer "F.Cu")
		(net "TDR_DIFF_100_TOP_DIP")
	)
	(segment
		(start 188.797946 -440.92749)
		(end 188.696346 -440.82589)
		(width 0.1143)
		(layer "F.Cu")
		(net "TDR_DIFF_100_TOP_DIP")
	)
	(segment
		(start 212.602826 -440.92749)
		(end 212.501226 -440.82589)
		(width 0.1143)
		(layer "F.Cu")
		(net "TDR_DIFF_100_TOP_DIP")
	)
	(segment
		(start 170.487086 -440.82589)
		(end 170.385486 -440.92749)
		(width 0.1143)
		(layer "F.Cu")
		(net "TDR_DIFF_100_TOP_DIP")
	)
	(segment
		(start 217.995246 -440.92749)
		(end 216.570306 -440.92749)
		(width 0.1143)
		(layer "F.Cu")
		(net "TDR_DIFF_100_TOP_DIP")
	)
	(segment
		(start 251.695966 -447.14033)
		(end 251.695966 -444.403988)
		(width 0.1143)
		(layer "B.Cu")
		(net "TDR_DIFF_100_BOT_DIP")
	)
	(segment
		(start 279.592278 -444.269876)
		(end 280.994866 -444.269876)
		(width 0.1143)
		(layer "B.Cu")
		(net "TDR_DIFF_100_BOT_DIP")
	)
	(segment
		(start 255.663446 -447.14033)
		(end 255.663446 -444.398908)
		(width 0.1143)
		(layer "B.Cu")
		(net "TDR_DIFF_100_BOT_DIP")
	)
	(segment
		(start 255.792478 -444.269876)
		(end 257.189986 -444.269876)
		(width 0.1143)
		(layer "B.Cu")
		(net "TDR_DIFF_100_BOT_DIP")
	)
	(segment
		(start 239.793526 -444.371476)
		(end 239.895126 -444.269876)
		(width 0.1143)
		(layer "B.Cu")
		(net "TDR_DIFF_100_BOT_DIP")
	)
	(segment
		(start 249.356626 -447.14033)
		(end 249.666506 -447.45021)
		(width 0.1143)
		(layer "B.Cu")
		(net "TDR_DIFF_100_BOT_DIP")
	)
	(segment
		(start 263.598406 -447.14033)
		(end 263.598406 -444.388748)
		(width 0.1143)
		(layer "B.Cu")
		(net "TDR_DIFF_100_BOT_DIP")
	)
	(segment
		(start 273.059906 -444.269876)
		(end 273.161506 -444.371476)
		(width 0.1143)
		(layer "B.Cu")
		(net "TDR_DIFF_100_BOT_DIP")
	)
	(segment
		(start 291.4777 -444.282576)
		(end 292.860476 -444.282576)
		(width 0.1143)
		(layer "B.Cu")
		(net "TDR_DIFF_100_BOT_DIP")
	)
	(segment
		(start 296.992802 -446.66154)
		(end 296.992802 -447.691764)
		(width 0.1143)
		(layer "B.Cu")
		(net "TDR_DIFF_100_BOT_DIP")
	)
	(segment
		(start 257.601466 -447.45021)
		(end 259.321046 -447.45021)
		(width 0.1143)
		(layer "B.Cu")
		(net "TDR_DIFF_100_BOT_DIP")
	)
	(segment
		(start 267.565886 -444.409068)
		(end 267.705078 -444.269876)
		(width 0.1143)
		(layer "B.Cu")
		(net "TDR_DIFF_100_BOT_DIP")
	)
	(segment
		(start 271.533366 -447.14033)
		(end 271.533366 -444.378588)
		(width 0.1143)
		(layer "B.Cu")
		(net "TDR_DIFF_100_BOT_DIP")
	)
	(segment
		(start 237.764066 -447.45021)
		(end 239.483646 -447.45021)
		(width 0.1143)
		(layer "B.Cu")
		(net "TDR_DIFF_100_BOT_DIP")
	)
	(segment
		(start 280.994866 -444.269876)
		(end 281.096466 -444.371476)
		(width 0.1143)
		(layer "B.Cu")
		(net "TDR_DIFF_100_BOT_DIP")
	)
	(segment
		(start 243.761006 -447.14033)
		(end 243.761006 -444.371476)
		(width 0.1143)
		(layer "B.Cu")
		(net "TDR_DIFF_100_BOT_DIP")
	)
	(segment
		(start 289.031426 -444.39078)
		(end 289.031426 -447.14033)
		(width 0.1143)
		(layer "B.Cu")
		(net "TDR_DIFF_100_BOT_DIP")
	)
	(segment
		(start 245.285006 -444.269876)
		(end 245.389146 -444.374016)
		(width 0.1143)
		(layer "B.Cu")
		(net "TDR_DIFF_100_BOT_DIP")
	)
	(segment
		(start 271.223486 -447.45021)
		(end 271.533366 -447.14033)
		(width 0.1143)
		(layer "B.Cu")
		(net "TDR_DIFF_100_BOT_DIP")
	)
	(segment
		(start 269.194026 -447.14033)
		(end 269.503906 -447.45021)
		(width 0.1143)
		(layer "B.Cu")
		(net "TDR_DIFF_100_BOT_DIP")
	)
	(segment
		(start 287.504886 -444.269876)
		(end 288.910522 -444.269876)
		(width 0.1143)
		(layer "B.Cu")
		(net "TDR_DIFF_100_BOT_DIP")
	)
	(segment
		(start 257.291586 -447.14033)
		(end 257.601466 -447.45021)
		(width 0.1143)
		(layer "B.Cu")
		(net "TDR_DIFF_100_BOT_DIP")
	)
	(segment
		(start 291.060886 -447.45021)
		(end 291.370766 -447.14033)
		(width 0.1143)
		(layer "B.Cu")
		(net "TDR_DIFF_100_BOT_DIP")
	)
	(segment
		(start 265.536426 -447.45021)
		(end 267.256006 -447.45021)
		(width 0.1143)
		(layer "B.Cu")
		(net "TDR_DIFF_100_BOT_DIP")
	)
	(segment
		(start 261.259066 -447.14033)
		(end 261.568946 -447.45021)
		(width 0.1143)
		(layer "B.Cu")
		(net "TDR_DIFF_100_BOT_DIP")
	)
	(segment
		(start 235.955078 -444.269876)
		(end 237.352586 -444.269876)
		(width 0.1143)
		(layer "B.Cu")
		(net "TDR_DIFF_100_BOT_DIP")
	)
	(segment
		(start 245.699026 -447.45021)
		(end 247.418606 -447.45021)
		(width 0.1143)
		(layer "B.Cu")
		(net "TDR_DIFF_100_BOT_DIP")
	)
	(segment
		(start 253.633986 -447.45021)
		(end 255.353566 -447.45021)
		(width 0.1143)
		(layer "B.Cu")
		(net "TDR_DIFF_100_BOT_DIP")
	)
	(segment
		(start 255.663446 -444.398908)
		(end 255.792478 -444.269876)
		(width 0.1143)
		(layer "B.Cu")
		(net "TDR_DIFF_100_BOT_DIP")
	)
	(segment
		(start 291.370766 -444.38951)
		(end 291.4777 -444.282576)
		(width 0.1143)
		(layer "B.Cu")
		(net "TDR_DIFF_100_BOT_DIP")
	)
	(segment
		(start 263.717278 -444.269876)
		(end 265.124946 -444.269876)
		(width 0.1143)
		(layer "B.Cu")
		(net "TDR_DIFF_100_BOT_DIP")
	)
	(segment
		(start 233.061002 -446.6082)
		(end 235.50753 -446.6082)
		(width 0.1143)
		(layer "B.Cu")
		(net "TDR_DIFF_100_BOT_DIP")
	)
	(segment
		(start 277.128986 -444.374016)
		(end 277.128986 -447.14033)
		(width 0.1143)
		(layer "B.Cu")
		(net "TDR_DIFF_100_BOT_DIP")
	)
	(segment
		(start 261.154926 -444.269876)
		(end 261.259066 -444.374016)
		(width 0.1143)
		(layer "B.Cu")
		(net "TDR_DIFF_100_BOT_DIP")
	)
	(segment
		(start 269.194026 -444.371476)
		(end 269.194026 -447.14033)
		(width 0.1143)
		(layer "B.Cu")
		(net "TDR_DIFF_100_BOT_DIP")
	)
	(segment
		(start 247.728486 -444.371476)
		(end 247.830086 -444.269876)
		(width 0.1143)
		(layer "B.Cu")
		(net "TDR_DIFF_100_BOT_DIP")
	)
	(segment
		(start 289.341306 -447.45021)
		(end 291.060886 -447.45021)
		(width 0.1143)
		(layer "B.Cu")
		(net "TDR_DIFF_100_BOT_DIP")
	)
	(segment
		(start 241.421666 -444.374016)
		(end 241.421666 -447.14033)
		(width 0.1143)
		(layer "B.Cu")
		(net "TDR_DIFF_100_BOT_DIP")
	)
	(segment
		(start 243.862606 -444.269876)
		(end 245.285006 -444.269876)
		(width 0.1143)
		(layer "B.Cu")
		(net "TDR_DIFF_100_BOT_DIP")
	)
	(segment
		(start 251.386086 -447.45021)
		(end 251.695966 -447.14033)
		(width 0.1143)
		(layer "B.Cu")
		(net "TDR_DIFF_100_BOT_DIP")
	)
	(segment
		(start 281.406346 -447.45021)
		(end 283.125926 -447.45021)
		(width 0.1143)
		(layer "B.Cu")
		(net "TDR_DIFF_100_BOT_DIP")
	)
	(segment
		(start 275.602446 -444.269876)
		(end 277.024846 -444.269876)
		(width 0.1143)
		(layer "B.Cu")
		(net "TDR_DIFF_100_BOT_DIP")
	)
	(segment
		(start 253.324106 -444.371476)
		(end 253.324106 -447.14033)
		(width 0.1143)
		(layer "B.Cu")
		(net "TDR_DIFF_100_BOT_DIP")
	)
	(segment
		(start 259.321046 -447.45021)
		(end 259.630926 -447.14033)
		(width 0.1143)
		(layer "B.Cu")
		(net "TDR_DIFF_100_BOT_DIP")
	)
	(segment
		(start 267.705078 -444.269876)
		(end 269.092426 -444.269876)
		(width 0.1143)
		(layer "B.Cu")
		(net "TDR_DIFF_100_BOT_DIP")
	)
	(segment
		(start 269.503906 -447.45021)
		(end 271.223486 -447.45021)
		(width 0.1143)
		(layer "B.Cu")
		(net "TDR_DIFF_100_BOT_DIP")
	)
	(segment
		(start 251.695966 -444.403988)
		(end 251.830078 -444.269876)
		(width 0.1143)
		(layer "B.Cu")
		(net "TDR_DIFF_100_BOT_DIP")
	)
	(segment
		(start 249.252486 -444.269876)
		(end 249.356626 -444.374016)
		(width 0.1143)
		(layer "B.Cu")
		(net "TDR_DIFF_100_BOT_DIP")
	)
	(segment
		(start 285.063946 -447.14033)
		(end 285.373826 -447.45021)
		(width 0.1143)
		(layer "B.Cu")
		(net "TDR_DIFF_100_BOT_DIP")
	)
	(segment
		(start 296.930826 -446.599564)
		(end 296.992802 -446.66154)
		(width 0.1143)
		(layer "B.Cu")
		(net "TDR_DIFF_100_BOT_DIP")
	)
	(segment
		(start 273.161506 -447.14033)
		(end 273.471386 -447.45021)
		(width 0.1143)
		(layer "B.Cu")
		(net "TDR_DIFF_100_BOT_DIP")
	)
	(segment
		(start 285.063946 -444.371476)
		(end 285.063946 -447.14033)
		(width 0.1143)
		(layer "B.Cu")
		(net "TDR_DIFF_100_BOT_DIP")
	)
	(segment
		(start 235.50753 -446.6082)
		(end 235.826046 -446.289684)
		(width 0.1143)
		(layer "B.Cu")
		(net "TDR_DIFF_100_BOT_DIP")
	)
	(segment
		(start 232.959402 -447.691764)
		(end 232.959402 -446.7098)
		(width 0.1143)
		(layer "B.Cu")
		(net "TDR_DIFF_100_BOT_DIP")
	)
	(segment
		(start 267.565886 -447.14033)
		(end 267.565886 -444.409068)
		(width 0.1143)
		(layer "B.Cu")
		(net "TDR_DIFF_100_BOT_DIP")
	)
	(segment
		(start 275.500846 -447.14033)
		(end 275.500846 -444.371476)
		(width 0.1143)
		(layer "B.Cu")
		(net "TDR_DIFF_100_BOT_DIP")
	)
	(segment
		(start 271.533366 -444.378588)
		(end 271.642078 -444.269876)
		(width 0.1143)
		(layer "B.Cu")
		(net "TDR_DIFF_100_BOT_DIP")
	)
	(segment
		(start 235.826046 -446.289684)
		(end 235.826046 -444.398908)
		(width 0.1143)
		(layer "B.Cu")
		(net "TDR_DIFF_100_BOT_DIP")
	)
	(segment
		(start 265.124946 -444.269876)
		(end 265.226546 -444.371476)
		(width 0.1143)
		(layer "B.Cu")
		(net "TDR_DIFF_100_BOT_DIP")
	)
	(segment
		(start 281.096466 -447.14033)
		(end 281.406346 -447.45021)
		(width 0.1143)
		(layer "B.Cu")
		(net "TDR_DIFF_100_BOT_DIP")
	)
	(segment
		(start 237.454186 -447.14033)
		(end 237.764066 -447.45021)
		(width 0.1143)
		(layer "B.Cu")
		(net "TDR_DIFF_100_BOT_DIP")
	)
	(segment
		(start 273.471386 -447.45021)
		(end 275.190966 -447.45021)
		(width 0.1143)
		(layer "B.Cu")
		(net "TDR_DIFF_100_BOT_DIP")
	)
	(segment
		(start 267.256006 -447.45021)
		(end 267.565886 -447.14033)
		(width 0.1143)
		(layer "B.Cu")
		(net "TDR_DIFF_100_BOT_DIP")
	)
	(segment
		(start 265.226546 -447.14033)
		(end 265.536426 -447.45021)
		(width 0.1143)
		(layer "B.Cu")
		(net "TDR_DIFF_100_BOT_DIP")
	)
	(segment
		(start 249.666506 -447.45021)
		(end 251.386086 -447.45021)
		(width 0.1143)
		(layer "B.Cu")
		(net "TDR_DIFF_100_BOT_DIP")
	)
	(segment
		(start 257.291586 -444.371476)
		(end 257.291586 -447.14033)
		(width 0.1143)
		(layer "B.Cu")
		(net "TDR_DIFF_100_BOT_DIP")
	)
	(segment
		(start 261.568946 -447.45021)
		(end 263.288526 -447.45021)
		(width 0.1143)
		(layer "B.Cu")
		(net "TDR_DIFF_100_BOT_DIP")
	)
	(segment
		(start 235.826046 -444.398908)
		(end 235.955078 -444.269876)
		(width 0.1143)
		(layer "B.Cu")
		(net "TDR_DIFF_100_BOT_DIP")
	)
	(segment
		(start 232.959402 -446.7098)
		(end 233.061002 -446.6082)
		(width 0.1143)
		(layer "B.Cu")
		(net "TDR_DIFF_100_BOT_DIP")
	)
	(segment
		(start 271.642078 -444.269876)
		(end 273.059906 -444.269876)
		(width 0.1143)
		(layer "B.Cu")
		(net "TDR_DIFF_100_BOT_DIP")
	)
	(segment
		(start 279.468326 -447.14033)
		(end 279.468326 -444.393828)
		(width 0.1143)
		(layer "B.Cu")
		(net "TDR_DIFF_100_BOT_DIP")
	)
	(segment
		(start 259.732526 -444.269876)
		(end 261.154926 -444.269876)
		(width 0.1143)
		(layer "B.Cu")
		(net "TDR_DIFF_100_BOT_DIP")
	)
	(segment
		(start 243.451126 -447.45021)
		(end 243.761006 -447.14033)
		(width 0.1143)
		(layer "B.Cu")
		(net "TDR_DIFF_100_BOT_DIP")
	)
	(segment
		(start 259.630926 -447.14033)
		(end 259.630926 -444.371476)
		(width 0.1143)
		(layer "B.Cu")
		(net "TDR_DIFF_100_BOT_DIP")
	)
	(segment
		(start 283.435806 -447.14033)
		(end 283.435806 -444.371476)
		(width 0.1143)
		(layer "B.Cu")
		(net "TDR_DIFF_100_BOT_DIP")
	)
	(segment
		(start 251.830078 -444.269876)
		(end 253.222506 -444.269876)
		(width 0.1143)
		(layer "B.Cu")
		(net "TDR_DIFF_100_BOT_DIP")
	)
	(segment
		(start 283.537406 -444.269876)
		(end 284.962346 -444.269876)
		(width 0.1143)
		(layer "B.Cu")
		(net "TDR_DIFF_100_BOT_DIP")
	)
	(segment
		(start 283.435806 -444.371476)
		(end 283.537406 -444.269876)
		(width 0.1143)
		(layer "B.Cu")
		(net "TDR_DIFF_100_BOT_DIP")
	)
	(segment
		(start 285.373826 -447.45021)
		(end 287.093406 -447.45021)
		(width 0.1143)
		(layer "B.Cu")
		(net "TDR_DIFF_100_BOT_DIP")
	)
	(segment
		(start 263.288526 -447.45021)
		(end 263.598406 -447.14033)
		(width 0.1143)
		(layer "B.Cu")
		(net "TDR_DIFF_100_BOT_DIP")
	)
	(segment
		(start 247.728486 -447.14033)
		(end 247.728486 -444.371476)
		(width 0.1143)
		(layer "B.Cu")
		(net "TDR_DIFF_100_BOT_DIP")
	)
	(segment
		(start 293.310564 -446.599564)
		(end 296.930826 -446.599564)
		(width 0.1143)
		(layer "B.Cu")
		(net "TDR_DIFF_100_BOT_DIP")
	)
	(segment
		(start 239.895126 -444.269876)
		(end 241.317526 -444.269876)
		(width 0.1143)
		(layer "B.Cu")
		(net "TDR_DIFF_100_BOT_DIP")
	)
	(segment
		(start 287.403286 -447.14033)
		(end 287.403286 -444.371476)
		(width 0.1143)
		(layer "B.Cu")
		(net "TDR_DIFF_100_BOT_DIP")
	)
	(segment
		(start 292.986206 -444.408306)
		(end 292.986206 -446.275206)
		(width 0.1143)
		(layer "B.Cu")
		(net "TDR_DIFF_100_BOT_DIP")
	)
	(segment
		(start 241.317526 -444.269876)
		(end 241.421666 -444.374016)
		(width 0.1143)
		(layer "B.Cu")
		(net "TDR_DIFF_100_BOT_DIP")
	)
	(segment
		(start 243.761006 -444.371476)
		(end 243.862606 -444.269876)
		(width 0.1143)
		(layer "B.Cu")
		(net "TDR_DIFF_100_BOT_DIP")
	)
	(segment
		(start 291.370766 -447.14033)
		(end 291.370766 -444.38951)
		(width 0.1143)
		(layer "B.Cu")
		(net "TDR_DIFF_100_BOT_DIP")
	)
	(segment
		(start 237.454186 -444.371476)
		(end 237.454186 -447.14033)
		(width 0.1143)
		(layer "B.Cu")
		(net "TDR_DIFF_100_BOT_DIP")
	)
	(segment
		(start 287.403286 -444.371476)
		(end 287.504886 -444.269876)
		(width 0.1143)
		(layer "B.Cu")
		(net "TDR_DIFF_100_BOT_DIP")
	)
	(segment
		(start 279.468326 -444.393828)
		(end 279.592278 -444.269876)
		(width 0.1143)
		(layer "B.Cu")
		(net "TDR_DIFF_100_BOT_DIP")
	)
	(segment
		(start 241.421666 -447.14033)
		(end 241.731546 -447.45021)
		(width 0.1143)
		(layer "B.Cu")
		(net "TDR_DIFF_100_BOT_DIP")
	)
	(segment
		(start 289.031426 -447.14033)
		(end 289.341306 -447.45021)
		(width 0.1143)
		(layer "B.Cu")
		(net "TDR_DIFF_100_BOT_DIP")
	)
	(segment
		(start 288.910522 -444.269876)
		(end 289.031426 -444.39078)
		(width 0.1143)
		(layer "B.Cu")
		(net "TDR_DIFF_100_BOT_DIP")
	)
	(segment
		(start 279.158446 -447.45021)
		(end 279.468326 -447.14033)
		(width 0.1143)
		(layer "B.Cu")
		(net "TDR_DIFF_100_BOT_DIP")
	)
	(segment
		(start 245.389146 -447.14033)
		(end 245.699026 -447.45021)
		(width 0.1143)
		(layer "B.Cu")
		(net "TDR_DIFF_100_BOT_DIP")
	)
	(segment
		(start 287.093406 -447.45021)
		(end 287.403286 -447.14033)
		(width 0.1143)
		(layer "B.Cu")
		(net "TDR_DIFF_100_BOT_DIP")
	)
	(segment
		(start 253.324106 -447.14033)
		(end 253.633986 -447.45021)
		(width 0.1143)
		(layer "B.Cu")
		(net "TDR_DIFF_100_BOT_DIP")
	)
	(segment
		(start 257.189986 -444.269876)
		(end 257.291586 -444.371476)
		(width 0.1143)
		(layer "B.Cu")
		(net "TDR_DIFF_100_BOT_DIP")
	)
	(segment
		(start 265.226546 -444.371476)
		(end 265.226546 -447.14033)
		(width 0.1143)
		(layer "B.Cu")
		(net "TDR_DIFF_100_BOT_DIP")
	)
	(segment
		(start 263.598406 -444.388748)
		(end 263.717278 -444.269876)
		(width 0.1143)
		(layer "B.Cu")
		(net "TDR_DIFF_100_BOT_DIP")
	)
	(segment
		(start 239.483646 -447.45021)
		(end 239.793526 -447.14033)
		(width 0.1143)
		(layer "B.Cu")
		(net "TDR_DIFF_100_BOT_DIP")
	)
	(segment
		(start 275.500846 -444.371476)
		(end 275.602446 -444.269876)
		(width 0.1143)
		(layer "B.Cu")
		(net "TDR_DIFF_100_BOT_DIP")
	)
	(segment
		(start 277.438866 -447.45021)
		(end 279.158446 -447.45021)
		(width 0.1143)
		(layer "B.Cu")
		(net "TDR_DIFF_100_BOT_DIP")
	)
	(segment
		(start 261.259066 -444.374016)
		(end 261.259066 -447.14033)
		(width 0.1143)
		(layer "B.Cu")
		(net "TDR_DIFF_100_BOT_DIP")
	)
	(segment
		(start 273.161506 -444.371476)
		(end 273.161506 -447.14033)
		(width 0.1143)
		(layer "B.Cu")
		(net "TDR_DIFF_100_BOT_DIP")
	)
	(segment
		(start 255.353566 -447.45021)
		(end 255.663446 -447.14033)
		(width 0.1143)
		(layer "B.Cu")
		(net "TDR_DIFF_100_BOT_DIP")
	)
	(segment
		(start 253.222506 -444.269876)
		(end 253.324106 -444.371476)
		(width 0.1143)
		(layer "B.Cu")
		(net "TDR_DIFF_100_BOT_DIP")
	)
	(segment
		(start 277.128986 -447.14033)
		(end 277.438866 -447.45021)
		(width 0.1143)
		(layer "B.Cu")
		(net "TDR_DIFF_100_BOT_DIP")
	)
	(segment
		(start 281.096466 -444.371476)
		(end 281.096466 -447.14033)
		(width 0.1143)
		(layer "B.Cu")
		(net "TDR_DIFF_100_BOT_DIP")
	)
	(segment
		(start 277.024846 -444.269876)
		(end 277.128986 -444.374016)
		(width 0.1143)
		(layer "B.Cu")
		(net "TDR_DIFF_100_BOT_DIP")
	)
	(segment
		(start 247.830086 -444.269876)
		(end 249.252486 -444.269876)
		(width 0.1143)
		(layer "B.Cu")
		(net "TDR_DIFF_100_BOT_DIP")
	)
	(segment
		(start 239.793526 -447.14033)
		(end 239.793526 -444.371476)
		(width 0.1143)
		(layer "B.Cu")
		(net "TDR_DIFF_100_BOT_DIP")
	)
	(segment
		(start 245.389146 -444.374016)
		(end 245.389146 -447.14033)
		(width 0.1143)
		(layer "B.Cu")
		(net "TDR_DIFF_100_BOT_DIP")
	)
	(segment
		(start 249.356626 -444.374016)
		(end 249.356626 -447.14033)
		(width 0.1143)
		(layer "B.Cu")
		(net "TDR_DIFF_100_BOT_DIP")
	)
	(segment
		(start 284.962346 -444.269876)
		(end 285.063946 -444.371476)
		(width 0.1143)
		(layer "B.Cu")
		(net "TDR_DIFF_100_BOT_DIP")
	)
	(segment
		(start 275.190966 -447.45021)
		(end 275.500846 -447.14033)
		(width 0.1143)
		(layer "B.Cu")
		(net "TDR_DIFF_100_BOT_DIP")
	)
	(segment
		(start 292.860476 -444.282576)
		(end 292.986206 -444.408306)
		(width 0.1143)
		(layer "B.Cu")
		(net "TDR_DIFF_100_BOT_DIP")
	)
	(segment
		(start 292.986206 -446.275206)
		(end 293.310564 -446.599564)
		(width 0.1143)
		(layer "B.Cu")
		(net "TDR_DIFF_100_BOT_DIP")
	)
	(segment
		(start 259.630926 -444.371476)
		(end 259.732526 -444.269876)
		(width 0.1143)
		(layer "B.Cu")
		(net "TDR_DIFF_100_BOT_DIP")
	)
	(segment
		(start 237.352586 -444.269876)
		(end 237.454186 -444.371476)
		(width 0.1143)
		(layer "B.Cu")
		(net "TDR_DIFF_100_BOT_DIP")
	)
	(segment
		(start 269.092426 -444.269876)
		(end 269.194026 -444.371476)
		(width 0.1143)
		(layer "B.Cu")
		(net "TDR_DIFF_100_BOT_DIP")
	)
	(segment
		(start 241.731546 -447.45021)
		(end 243.451126 -447.45021)
		(width 0.1143)
		(layer "B.Cu")
		(net "TDR_DIFF_100_BOT_DIP")
	)
	(segment
		(start 283.125926 -447.45021)
		(end 283.435806 -447.14033)
		(width 0.1143)
		(layer "B.Cu")
		(net "TDR_DIFF_100_BOT_DIP")
	)
	(segment
		(start 247.418606 -447.45021)
		(end 247.728486 -447.14033)
		(width 0.1143)
		(layer "B.Cu")
		(net "TDR_DIFF_100_BOT_DIP")
	)
	(segment
		(start 237.309406 -449.779644)
		(end 235.636054 -449.779644)
		(width 0.1397)
		(layer "In5.Cu")
		(net "TDR_DIFF_100_IN1_DIP")
	)
	(segment
		(start 281.27198 -452.851012)
		(end 281.27198 -450.099938)
		(width 0.1397)
		(layer "In5.Cu")
		(net "TDR_DIFF_100_IN1_DIP")
	)
	(segment
		(start 286.893 -452.851012)
		(end 286.766 -452.978012)
		(width 0.1397)
		(layer "In5.Cu")
		(net "TDR_DIFF_100_IN1_DIP")
	)
	(segment
		(start 273.33702 -450.099938)
		(end 273.016726 -449.779644)
		(width 0.1397)
		(layer "In5.Cu")
		(net "TDR_DIFF_100_IN1_DIP")
	)
	(segment
		(start 237.6297 -452.81596)
		(end 237.6297 -450.099938)
		(width 0.1397)
		(layer "In5.Cu")
		(net "TDR_DIFF_100_IN1_DIP")
	)
	(segment
		(start 261.43458 -450.099938)
		(end 261.114286 -449.779644)
		(width 0.1397)
		(layer "In5.Cu")
		(net "TDR_DIFF_100_IN1_DIP")
	)
	(segment
		(start 288.886646 -449.779644)
		(end 287.213294 -449.779644)
		(width 0.1397)
		(layer "In5.Cu")
		(net "TDR_DIFF_100_IN1_DIP")
	)
	(segment
		(start 237.6297 -450.099938)
		(end 237.309406 -449.779644)
		(width 0.1397)
		(layer "In5.Cu")
		(net "TDR_DIFF_100_IN1_DIP")
	)
	(segment
		(start 277.3045 -450.099938)
		(end 276.984206 -449.779644)
		(width 0.1397)
		(layer "In5.Cu")
		(net "TDR_DIFF_100_IN1_DIP")
	)
	(segment
		(start 283.245814 -449.779644)
		(end 282.92552 -450.099938)
		(width 0.1397)
		(layer "In5.Cu")
		(net "TDR_DIFF_100_IN1_DIP")
	)
	(segment
		(start 239.603534 -449.779644)
		(end 239.28324 -450.099938)
		(width 0.1397)
		(layer "In5.Cu")
		(net "TDR_DIFF_100_IN1_DIP")
	)
	(segment
		(start 261.43458 -452.851012)
		(end 261.43458 -450.099938)
		(width 0.1397)
		(layer "In5.Cu")
		(net "TDR_DIFF_100_IN1_DIP")
	)
	(segment
		(start 286.766 -452.978012)
		(end 285.36646 -452.978012)
		(width 0.1397)
		(layer "In5.Cu")
		(net "TDR_DIFF_100_IN1_DIP")
	)
	(segment
		(start 293.30142 -452.212456)
		(end 293.17442 -452.085456)
		(width 0.1397)
		(layer "In5.Cu")
		(net "TDR_DIFF_100_IN1_DIP")
	)
	(segment
		(start 241.72418 -452.978012)
		(end 241.59718 -452.851012)
		(width 0.1397)
		(layer "In5.Cu")
		(net "TDR_DIFF_100_IN1_DIP")
	)
	(segment
		(start 273.016726 -449.779644)
		(end 271.343374 -449.779644)
		(width 0.1397)
		(layer "In5.Cu")
		(net "TDR_DIFF_100_IN1_DIP")
	)
	(segment
		(start 279.278334 -449.779644)
		(end 278.95804 -450.099938)
		(width 0.1397)
		(layer "In5.Cu")
		(net "TDR_DIFF_100_IN1_DIP")
	)
	(segment
		(start 273.33702 -452.851012)
		(end 273.33702 -450.099938)
		(width 0.1397)
		(layer "In5.Cu")
		(net "TDR_DIFF_100_IN1_DIP")
	)
	(segment
		(start 281.39898 -452.978012)
		(end 281.27198 -452.851012)
		(width 0.1397)
		(layer "In5.Cu")
		(net "TDR_DIFF_100_IN1_DIP")
	)
	(segment
		(start 289.20694 -450.099938)
		(end 288.886646 -449.779644)
		(width 0.1397)
		(layer "In5.Cu")
		(net "TDR_DIFF_100_IN1_DIP")
	)
	(segment
		(start 296.957242 -451.107556)
		(end 296.957242 -452.0819)
		(width 0.1397)
		(layer "In5.Cu")
		(net "TDR_DIFF_100_IN1_DIP")
	)
	(segment
		(start 255.15316 -452.851012)
		(end 255.02616 -452.978012)
		(width 0.1397)
		(layer "In5.Cu")
		(net "TDR_DIFF_100_IN1_DIP")
	)
	(segment
		(start 247.538494 -449.779644)
		(end 247.2182 -450.099938)
		(width 0.1397)
		(layer "In5.Cu")
		(net "TDR_DIFF_100_IN1_DIP")
	)
	(segment
		(start 267.0556 -452.851012)
		(end 266.9286 -452.978012)
		(width 0.1397)
		(layer "In5.Cu")
		(net "TDR_DIFF_100_IN1_DIP")
	)
	(segment
		(start 277.3045 -452.851012)
		(end 277.3045 -450.099938)
		(width 0.1397)
		(layer "In5.Cu")
		(net "TDR_DIFF_100_IN1_DIP")
	)
	(segment
		(start 245.244366 -449.779644)
		(end 243.571014 -449.779644)
		(width 0.1397)
		(layer "In5.Cu")
		(net "TDR_DIFF_100_IN1_DIP")
	)
	(segment
		(start 293.17442 -450.099938)
		(end 292.854126 -449.779644)
		(width 0.1397)
		(layer "In5.Cu")
		(net "TDR_DIFF_100_IN1_DIP")
	)
	(segment
		(start 255.02616 -452.978012)
		(end 253.62662 -452.978012)
		(width 0.1397)
		(layer "In5.Cu")
		(net "TDR_DIFF_100_IN1_DIP")
	)
	(segment
		(start 263.08812 -450.099938)
		(end 263.08812 -452.851012)
		(width 0.1397)
		(layer "In5.Cu")
		(net "TDR_DIFF_100_IN1_DIP")
	)
	(segment
		(start 276.984206 -449.779644)
		(end 275.310854 -449.779644)
		(width 0.1397)
		(layer "In5.Cu")
		(net "TDR_DIFF_100_IN1_DIP")
	)
	(segment
		(start 290.86048 -452.851012)
		(end 290.73348 -452.978012)
		(width 0.1397)
		(layer "In5.Cu")
		(net "TDR_DIFF_100_IN1_DIP")
	)
	(segment
		(start 278.95804 -450.099938)
		(end 278.95804 -452.851012)
		(width 0.1397)
		(layer "In5.Cu")
		(net "TDR_DIFF_100_IN1_DIP")
	)
	(segment
		(start 243.25072 -450.099938)
		(end 243.25072 -452.851012)
		(width 0.1397)
		(layer "In5.Cu")
		(net "TDR_DIFF_100_IN1_DIP")
	)
	(segment
		(start 253.62662 -452.978012)
		(end 253.49962 -452.851012)
		(width 0.1397)
		(layer "In5.Cu")
		(net "TDR_DIFF_100_IN1_DIP")
	)
	(segment
		(start 282.79852 -452.978012)
		(end 281.39898 -452.978012)
		(width 0.1397)
		(layer "In5.Cu")
		(net "TDR_DIFF_100_IN1_DIP")
	)
	(segment
		(start 269.49654 -452.978012)
		(end 269.36954 -452.851012)
		(width 0.1397)
		(layer "In5.Cu")
		(net "TDR_DIFF_100_IN1_DIP")
	)
	(segment
		(start 233.063542 -452.212456)
		(end 232.936542 -452.085456)
		(width 0.1397)
		(layer "In5.Cu")
		(net "TDR_DIFF_100_IN1_DIP")
	)
	(segment
		(start 274.99056 -452.851012)
		(end 274.86356 -452.978012)
		(width 0.1397)
		(layer "In5.Cu")
		(net "TDR_DIFF_100_IN1_DIP")
	)
	(segment
		(start 251.18568 -450.099938)
		(end 251.18568 -452.851012)
		(width 0.1397)
		(layer "In5.Cu")
		(net "TDR_DIFF_100_IN1_DIP")
	)
	(segment
		(start 267.375894 -449.779644)
		(end 267.0556 -450.099938)
		(width 0.1397)
		(layer "In5.Cu")
		(net "TDR_DIFF_100_IN1_DIP")
	)
	(segment
		(start 247.2182 -450.099938)
		(end 247.2182 -452.851012)
		(width 0.1397)
		(layer "In5.Cu")
		(net "TDR_DIFF_100_IN1_DIP")
	)
	(segment
		(start 245.56466 -450.099938)
		(end 245.244366 -449.779644)
		(width 0.1397)
		(layer "In5.Cu")
		(net "TDR_DIFF_100_IN1_DIP")
	)
	(segment
		(start 265.081766 -449.779644)
		(end 263.408414 -449.779644)
		(width 0.1397)
		(layer "In5.Cu")
		(net "TDR_DIFF_100_IN1_DIP")
	)
	(segment
		(start 280.951686 -449.779644)
		(end 279.278334 -449.779644)
		(width 0.1397)
		(layer "In5.Cu")
		(net "TDR_DIFF_100_IN1_DIP")
	)
	(segment
		(start 262.96112 -452.978012)
		(end 261.56158 -452.978012)
		(width 0.1397)
		(layer "In5.Cu")
		(net "TDR_DIFF_100_IN1_DIP")
	)
	(segment
		(start 243.12372 -452.978012)
		(end 241.72418 -452.978012)
		(width 0.1397)
		(layer "In5.Cu")
		(net "TDR_DIFF_100_IN1_DIP")
	)
	(segment
		(start 245.56466 -452.851012)
		(end 245.56466 -450.099938)
		(width 0.1397)
		(layer "In5.Cu")
		(net "TDR_DIFF_100_IN1_DIP")
	)
	(segment
		(start 243.571014 -449.779644)
		(end 243.25072 -450.099938)
		(width 0.1397)
		(layer "In5.Cu")
		(net "TDR_DIFF_100_IN1_DIP")
	)
	(segment
		(start 249.211846 -449.779644)
		(end 247.538494 -449.779644)
		(width 0.1397)
		(layer "In5.Cu")
		(net "TDR_DIFF_100_IN1_DIP")
	)
	(segment
		(start 259.12064 -452.851012)
		(end 258.99364 -452.978012)
		(width 0.1397)
		(layer "In5.Cu")
		(net "TDR_DIFF_100_IN1_DIP")
	)
	(segment
		(start 275.310854 -449.779644)
		(end 274.99056 -450.099938)
		(width 0.1397)
		(layer "In5.Cu")
		(net "TDR_DIFF_100_IN1_DIP")
	)
	(segment
		(start 257.146806 -449.779644)
		(end 255.473454 -449.779644)
		(width 0.1397)
		(layer "In5.Cu")
		(net "TDR_DIFF_100_IN1_DIP")
	)
	(segment
		(start 287.213294 -449.779644)
		(end 286.893 -450.099938)
		(width 0.1397)
		(layer "In5.Cu")
		(net "TDR_DIFF_100_IN1_DIP")
	)
	(segment
		(start 289.20694 -452.851012)
		(end 289.20694 -450.099938)
		(width 0.1397)
		(layer "In5.Cu")
		(net "TDR_DIFF_100_IN1_DIP")
	)
	(segment
		(start 274.99056 -450.099938)
		(end 274.99056 -452.851012)
		(width 0.1397)
		(layer "In5.Cu")
		(net "TDR_DIFF_100_IN1_DIP")
	)
	(segment
		(start 265.40206 -452.851012)
		(end 265.40206 -450.099938)
		(width 0.1397)
		(layer "In5.Cu")
		(net "TDR_DIFF_100_IN1_DIP")
	)
	(segment
		(start 296.826686 -452.212456)
		(end 293.30142 -452.212456)
		(width 0.1397)
		(layer "In5.Cu")
		(net "TDR_DIFF_100_IN1_DIP")
	)
	(segment
		(start 273.46402 -452.978012)
		(end 273.33702 -452.851012)
		(width 0.1397)
		(layer "In5.Cu")
		(net "TDR_DIFF_100_IN1_DIP")
	)
	(segment
		(start 286.893 -450.099938)
		(end 286.893 -452.851012)
		(width 0.1397)
		(layer "In5.Cu")
		(net "TDR_DIFF_100_IN1_DIP")
	)
	(segment
		(start 285.23946 -452.851012)
		(end 285.23946 -450.099938)
		(width 0.1397)
		(layer "In5.Cu")
		(net "TDR_DIFF_100_IN1_DIP")
	)
	(segment
		(start 251.505974 -449.779644)
		(end 251.18568 -450.099938)
		(width 0.1397)
		(layer "In5.Cu")
		(net "TDR_DIFF_100_IN1_DIP")
	)
	(segment
		(start 239.15624 -452.94296)
		(end 237.7567 -452.94296)
		(width 0.1397)
		(layer "In5.Cu")
		(net "TDR_DIFF_100_IN1_DIP")
	)
	(segment
		(start 290.86048 -450.099938)
		(end 290.86048 -452.851012)
		(width 0.1397)
		(layer "In5.Cu")
		(net "TDR_DIFF_100_IN1_DIP")
	)
	(segment
		(start 284.919166 -449.779644)
		(end 283.245814 -449.779644)
		(width 0.1397)
		(layer "In5.Cu")
		(net "TDR_DIFF_100_IN1_DIP")
	)
	(segment
		(start 257.4671 -452.851012)
		(end 257.4671 -450.099938)
		(width 0.1397)
		(layer "In5.Cu")
		(net "TDR_DIFF_100_IN1_DIP")
	)
	(segment
		(start 269.36954 -452.851012)
		(end 269.36954 -450.099938)
		(width 0.1397)
		(layer "In5.Cu")
		(net "TDR_DIFF_100_IN1_DIP")
	)
	(segment
		(start 292.854126 -449.779644)
		(end 291.180774 -449.779644)
		(width 0.1397)
		(layer "In5.Cu")
		(net "TDR_DIFF_100_IN1_DIP")
	)
	(segment
		(start 296.957242 -452.0819)
		(end 296.826686 -452.212456)
		(width 0.1397)
		(layer "In5.Cu")
		(net "TDR_DIFF_100_IN1_DIP")
	)
	(segment
		(start 253.179326 -449.779644)
		(end 251.505974 -449.779644)
		(width 0.1397)
		(layer "In5.Cu")
		(net "TDR_DIFF_100_IN1_DIP")
	)
	(segment
		(start 241.59718 -452.851012)
		(end 241.59718 -450.099938)
		(width 0.1397)
		(layer "In5.Cu")
		(net "TDR_DIFF_100_IN1_DIP")
	)
	(segment
		(start 285.23946 -450.099938)
		(end 284.919166 -449.779644)
		(width 0.1397)
		(layer "In5.Cu")
		(net "TDR_DIFF_100_IN1_DIP")
	)
	(segment
		(start 289.33394 -452.978012)
		(end 289.20694 -452.851012)
		(width 0.1397)
		(layer "In5.Cu")
		(net "TDR_DIFF_100_IN1_DIP")
	)
	(segment
		(start 235.31576 -452.085456)
		(end 235.18876 -452.212456)
		(width 0.1397)
		(layer "In5.Cu")
		(net "TDR_DIFF_100_IN1_DIP")
	)
	(segment
		(start 281.27198 -450.099938)
		(end 280.951686 -449.779644)
		(width 0.1397)
		(layer "In5.Cu")
		(net "TDR_DIFF_100_IN1_DIP")
	)
	(segment
		(start 282.92552 -450.099938)
		(end 282.92552 -452.851012)
		(width 0.1397)
		(layer "In5.Cu")
		(net "TDR_DIFF_100_IN1_DIP")
	)
	(segment
		(start 263.08812 -452.851012)
		(end 262.96112 -452.978012)
		(width 0.1397)
		(layer "In5.Cu")
		(net "TDR_DIFF_100_IN1_DIP")
	)
	(segment
		(start 239.28324 -452.81596)
		(end 239.15624 -452.94296)
		(width 0.1397)
		(layer "In5.Cu")
		(net "TDR_DIFF_100_IN1_DIP")
	)
	(segment
		(start 241.276886 -449.779644)
		(end 239.603534 -449.779644)
		(width 0.1397)
		(layer "In5.Cu")
		(net "TDR_DIFF_100_IN1_DIP")
	)
	(segment
		(start 232.936542 -452.085456)
		(end 232.936542 -451.107556)
		(width 0.1397)
		(layer "In5.Cu")
		(net "TDR_DIFF_100_IN1_DIP")
	)
	(segment
		(start 241.59718 -450.099938)
		(end 241.276886 -449.779644)
		(width 0.1397)
		(layer "In5.Cu")
		(net "TDR_DIFF_100_IN1_DIP")
	)
	(segment
		(start 291.180774 -449.779644)
		(end 290.86048 -450.099938)
		(width 0.1397)
		(layer "In5.Cu")
		(net "TDR_DIFF_100_IN1_DIP")
	)
	(segment
		(start 282.92552 -452.851012)
		(end 282.79852 -452.978012)
		(width 0.1397)
		(layer "In5.Cu")
		(net "TDR_DIFF_100_IN1_DIP")
	)
	(segment
		(start 251.18568 -452.851012)
		(end 251.05868 -452.978012)
		(width 0.1397)
		(layer "In5.Cu")
		(net "TDR_DIFF_100_IN1_DIP")
	)
	(segment
		(start 293.17442 -452.085456)
		(end 293.17442 -450.099938)
		(width 0.1397)
		(layer "In5.Cu")
		(net "TDR_DIFF_100_IN1_DIP")
	)
	(segment
		(start 255.473454 -449.779644)
		(end 255.15316 -450.099938)
		(width 0.1397)
		(layer "In5.Cu")
		(net "TDR_DIFF_100_IN1_DIP")
	)
	(segment
		(start 265.40206 -450.099938)
		(end 265.081766 -449.779644)
		(width 0.1397)
		(layer "In5.Cu")
		(net "TDR_DIFF_100_IN1_DIP")
	)
	(segment
		(start 290.73348 -452.978012)
		(end 289.33394 -452.978012)
		(width 0.1397)
		(layer "In5.Cu")
		(net "TDR_DIFF_100_IN1_DIP")
	)
	(segment
		(start 259.12064 -450.099938)
		(end 259.12064 -452.851012)
		(width 0.1397)
		(layer "In5.Cu")
		(net "TDR_DIFF_100_IN1_DIP")
	)
	(segment
		(start 271.02308 -452.851012)
		(end 270.89608 -452.978012)
		(width 0.1397)
		(layer "In5.Cu")
		(net "TDR_DIFF_100_IN1_DIP")
	)
	(segment
		(start 271.02308 -450.099938)
		(end 271.02308 -452.851012)
		(width 0.1397)
		(layer "In5.Cu")
		(net "TDR_DIFF_100_IN1_DIP")
	)
	(segment
		(start 251.05868 -452.978012)
		(end 249.65914 -452.978012)
		(width 0.1397)
		(layer "In5.Cu")
		(net "TDR_DIFF_100_IN1_DIP")
	)
	(segment
		(start 239.28324 -450.099938)
		(end 239.28324 -452.81596)
		(width 0.1397)
		(layer "In5.Cu")
		(net "TDR_DIFF_100_IN1_DIP")
	)
	(segment
		(start 235.18876 -452.212456)
		(end 233.063542 -452.212456)
		(width 0.1397)
		(layer "In5.Cu")
		(net "TDR_DIFF_100_IN1_DIP")
	)
	(segment
		(start 278.95804 -452.851012)
		(end 278.83104 -452.978012)
		(width 0.1397)
		(layer "In5.Cu")
		(net "TDR_DIFF_100_IN1_DIP")
	)
	(segment
		(start 278.83104 -452.978012)
		(end 277.4315 -452.978012)
		(width 0.1397)
		(layer "In5.Cu")
		(net "TDR_DIFF_100_IN1_DIP")
	)
	(segment
		(start 269.36954 -450.099938)
		(end 269.049246 -449.779644)
		(width 0.1397)
		(layer "In5.Cu")
		(net "TDR_DIFF_100_IN1_DIP")
	)
	(segment
		(start 257.5941 -452.978012)
		(end 257.4671 -452.851012)
		(width 0.1397)
		(layer "In5.Cu")
		(net "TDR_DIFF_100_IN1_DIP")
	)
	(segment
		(start 285.36646 -452.978012)
		(end 285.23946 -452.851012)
		(width 0.1397)
		(layer "In5.Cu")
		(net "TDR_DIFF_100_IN1_DIP")
	)
	(segment
		(start 265.52906 -452.978012)
		(end 265.40206 -452.851012)
		(width 0.1397)
		(layer "In5.Cu")
		(net "TDR_DIFF_100_IN1_DIP")
	)
	(segment
		(start 258.99364 -452.978012)
		(end 257.5941 -452.978012)
		(width 0.1397)
		(layer "In5.Cu")
		(net "TDR_DIFF_100_IN1_DIP")
	)
	(segment
		(start 277.4315 -452.978012)
		(end 277.3045 -452.851012)
		(width 0.1397)
		(layer "In5.Cu")
		(net "TDR_DIFF_100_IN1_DIP")
	)
	(segment
		(start 249.53214 -450.099938)
		(end 249.211846 -449.779644)
		(width 0.1397)
		(layer "In5.Cu")
		(net "TDR_DIFF_100_IN1_DIP")
	)
	(segment
		(start 235.31576 -450.099938)
		(end 235.31576 -452.085456)
		(width 0.1397)
		(layer "In5.Cu")
		(net "TDR_DIFF_100_IN1_DIP")
	)
	(segment
		(start 245.69166 -452.978012)
		(end 245.56466 -452.851012)
		(width 0.1397)
		(layer "In5.Cu")
		(net "TDR_DIFF_100_IN1_DIP")
	)
	(segment
		(start 274.86356 -452.978012)
		(end 273.46402 -452.978012)
		(width 0.1397)
		(layer "In5.Cu")
		(net "TDR_DIFF_100_IN1_DIP")
	)
	(segment
		(start 249.53214 -452.851012)
		(end 249.53214 -450.099938)
		(width 0.1397)
		(layer "In5.Cu")
		(net "TDR_DIFF_100_IN1_DIP")
	)
	(segment
		(start 271.343374 -449.779644)
		(end 271.02308 -450.099938)
		(width 0.1397)
		(layer "In5.Cu")
		(net "TDR_DIFF_100_IN1_DIP")
	)
	(segment
		(start 259.440934 -449.779644)
		(end 259.12064 -450.099938)
		(width 0.1397)
		(layer "In5.Cu")
		(net "TDR_DIFF_100_IN1_DIP")
	)
	(segment
		(start 247.2182 -452.851012)
		(end 247.0912 -452.978012)
		(width 0.1397)
		(layer "In5.Cu")
		(net "TDR_DIFF_100_IN1_DIP")
	)
	(segment
		(start 261.56158 -452.978012)
		(end 261.43458 -452.851012)
		(width 0.1397)
		(layer "In5.Cu")
		(net "TDR_DIFF_100_IN1_DIP")
	)
	(segment
		(start 253.49962 -452.851012)
		(end 253.49962 -450.099938)
		(width 0.1397)
		(layer "In5.Cu")
		(net "TDR_DIFF_100_IN1_DIP")
	)
	(segment
		(start 255.15316 -450.099938)
		(end 255.15316 -452.851012)
		(width 0.1397)
		(layer "In5.Cu")
		(net "TDR_DIFF_100_IN1_DIP")
	)
	(segment
		(start 266.9286 -452.978012)
		(end 265.52906 -452.978012)
		(width 0.1397)
		(layer "In5.Cu")
		(net "TDR_DIFF_100_IN1_DIP")
	)
	(segment
		(start 235.636054 -449.779644)
		(end 235.31576 -450.099938)
		(width 0.1397)
		(layer "In5.Cu")
		(net "TDR_DIFF_100_IN1_DIP")
	)
	(segment
		(start 267.0556 -450.099938)
		(end 267.0556 -452.851012)
		(width 0.1397)
		(layer "In5.Cu")
		(net "TDR_DIFF_100_IN1_DIP")
	)
	(segment
		(start 247.0912 -452.978012)
		(end 245.69166 -452.978012)
		(width 0.1397)
		(layer "In5.Cu")
		(net "TDR_DIFF_100_IN1_DIP")
	)
	(segment
		(start 237.7567 -452.94296)
		(end 237.6297 -452.81596)
		(width 0.1397)
		(layer "In5.Cu")
		(net "TDR_DIFF_100_IN1_DIP")
	)
	(segment
		(start 263.408414 -449.779644)
		(end 263.08812 -450.099938)
		(width 0.1397)
		(layer "In5.Cu")
		(net "TDR_DIFF_100_IN1_DIP")
	)
	(segment
		(start 270.89608 -452.978012)
		(end 269.49654 -452.978012)
		(width 0.1397)
		(layer "In5.Cu")
		(net "TDR_DIFF_100_IN1_DIP")
	)
	(segment
		(start 261.114286 -449.779644)
		(end 259.440934 -449.779644)
		(width 0.1397)
		(layer "In5.Cu")
		(net "TDR_DIFF_100_IN1_DIP")
	)
	(segment
		(start 269.049246 -449.779644)
		(end 267.375894 -449.779644)
		(width 0.1397)
		(layer "In5.Cu")
		(net "TDR_DIFF_100_IN1_DIP")
	)
	(segment
		(start 257.4671 -450.099938)
		(end 257.146806 -449.779644)
		(width 0.1397)
		(layer "In5.Cu")
		(net "TDR_DIFF_100_IN1_DIP")
	)
	(segment
		(start 253.49962 -450.099938)
		(end 253.179326 -449.779644)
		(width 0.1397)
		(layer "In5.Cu")
		(net "TDR_DIFF_100_IN1_DIP")
	)
	(segment
		(start 249.65914 -452.978012)
		(end 249.53214 -452.851012)
		(width 0.1397)
		(layer "In5.Cu")
		(net "TDR_DIFF_100_IN1_DIP")
	)
	(segment
		(start 243.25072 -452.851012)
		(end 243.12372 -452.978012)
		(width 0.1397)
		(layer "In5.Cu")
		(net "TDR_DIFF_100_IN1_DIP")
	)
	(segment
		(start 273.360642 -456.302872)
		(end 273.040348 -455.982578)
		(width 0.1397)
		(layer "In11.Cu")
		(net "TDR_DIFF_100_IN4_DIP")
	)
	(segment
		(start 259.144262 -459.053946)
		(end 259.017262 -459.180946)
		(width 0.1397)
		(layer "In11.Cu")
		(net "TDR_DIFF_100_IN4_DIP")
	)
	(segment
		(start 278.854662 -459.180946)
		(end 277.455122 -459.180946)
		(width 0.1397)
		(layer "In11.Cu")
		(net "TDR_DIFF_100_IN4_DIP")
	)
	(segment
		(start 293.198042 -456.302872)
		(end 292.877748 -455.982578)
		(width 0.1397)
		(layer "In11.Cu")
		(net "TDR_DIFF_100_IN4_DIP")
	)
	(segment
		(start 296.850308 -458.41539)
		(end 293.325042 -458.41539)
		(width 0.1397)
		(layer "In11.Cu")
		(net "TDR_DIFF_100_IN4_DIP")
	)
	(segment
		(start 247.241822 -456.302872)
		(end 247.241822 -459.053946)
		(width 0.1397)
		(layer "In11.Cu")
		(net "TDR_DIFF_100_IN4_DIP")
	)
	(segment
		(start 282.822142 -459.180946)
		(end 281.422602 -459.180946)
		(width 0.1397)
		(layer "In11.Cu")
		(net "TDR_DIFF_100_IN4_DIP")
	)
	(segment
		(start 278.981662 -456.302872)
		(end 278.981662 -459.053946)
		(width 0.1397)
		(layer "In11.Cu")
		(net "TDR_DIFF_100_IN4_DIP")
	)
	(segment
		(start 270.919702 -459.180946)
		(end 269.520162 -459.180946)
		(width 0.1397)
		(layer "In11.Cu")
		(net "TDR_DIFF_100_IN4_DIP")
	)
	(segment
		(start 289.357562 -459.180946)
		(end 289.230562 -459.053946)
		(width 0.1397)
		(layer "In11.Cu")
		(net "TDR_DIFF_100_IN4_DIP")
	)
	(segment
		(start 247.114822 -459.180946)
		(end 245.715282 -459.180946)
		(width 0.1397)
		(layer "In11.Cu")
		(net "TDR_DIFF_100_IN4_DIP")
	)
	(segment
		(start 296.980864 -458.284834)
		(end 296.850308 -458.41539)
		(width 0.1397)
		(layer "In11.Cu")
		(net "TDR_DIFF_100_IN4_DIP")
	)
	(segment
		(start 253.523242 -456.302872)
		(end 253.202948 -455.982578)
		(width 0.1397)
		(layer "In11.Cu")
		(net "TDR_DIFF_100_IN4_DIP")
	)
	(segment
		(start 255.176782 -456.302872)
		(end 255.176782 -459.053946)
		(width 0.1397)
		(layer "In11.Cu")
		(net "TDR_DIFF_100_IN4_DIP")
	)
	(segment
		(start 259.464556 -455.982578)
		(end 259.144262 -456.302872)
		(width 0.1397)
		(layer "In11.Cu")
		(net "TDR_DIFF_100_IN4_DIP")
	)
	(segment
		(start 284.942788 -455.982578)
		(end 283.269436 -455.982578)
		(width 0.1397)
		(layer "In11.Cu")
		(net "TDR_DIFF_100_IN4_DIP")
	)
	(segment
		(start 282.949142 -456.302872)
		(end 282.949142 -459.053946)
		(width 0.1397)
		(layer "In11.Cu")
		(net "TDR_DIFF_100_IN4_DIP")
	)
	(segment
		(start 274.887182 -459.180946)
		(end 273.487642 -459.180946)
		(width 0.1397)
		(layer "In11.Cu")
		(net "TDR_DIFF_100_IN4_DIP")
	)
	(segment
		(start 257.617722 -459.180946)
		(end 257.490722 -459.053946)
		(width 0.1397)
		(layer "In11.Cu")
		(net "TDR_DIFF_100_IN4_DIP")
	)
	(segment
		(start 265.552682 -459.180946)
		(end 265.425682 -459.053946)
		(width 0.1397)
		(layer "In11.Cu")
		(net "TDR_DIFF_100_IN4_DIP")
	)
	(segment
		(start 245.588282 -456.302872)
		(end 245.267988 -455.982578)
		(width 0.1397)
		(layer "In11.Cu")
		(net "TDR_DIFF_100_IN4_DIP")
	)
	(segment
		(start 286.916622 -459.053946)
		(end 286.789622 -459.180946)
		(width 0.1397)
		(layer "In11.Cu")
		(net "TDR_DIFF_100_IN4_DIP")
	)
	(segment
		(start 249.555762 -459.053946)
		(end 249.555762 -456.302872)
		(width 0.1397)
		(layer "In11.Cu")
		(net "TDR_DIFF_100_IN4_DIP")
	)
	(segment
		(start 279.301956 -455.982578)
		(end 278.981662 -456.302872)
		(width 0.1397)
		(layer "In11.Cu")
		(net "TDR_DIFF_100_IN4_DIP")
	)
	(segment
		(start 232.960164 -458.28839)
		(end 232.960164 -457.31049)
		(width 0.1397)
		(layer "In11.Cu")
		(net "TDR_DIFF_100_IN4_DIP")
	)
	(segment
		(start 245.588282 -459.053946)
		(end 245.588282 -456.302872)
		(width 0.1397)
		(layer "In11.Cu")
		(net "TDR_DIFF_100_IN4_DIP")
	)
	(segment
		(start 275.334476 -455.982578)
		(end 275.014182 -456.302872)
		(width 0.1397)
		(layer "In11.Cu")
		(net "TDR_DIFF_100_IN4_DIP")
	)
	(segment
		(start 251.209302 -456.302872)
		(end 251.209302 -459.053946)
		(width 0.1397)
		(layer "In11.Cu")
		(net "TDR_DIFF_100_IN4_DIP")
	)
	(segment
		(start 285.390082 -459.180946)
		(end 285.263082 -459.053946)
		(width 0.1397)
		(layer "In11.Cu")
		(net "TDR_DIFF_100_IN4_DIP")
	)
	(segment
		(start 281.295602 -459.053946)
		(end 281.295602 -456.302872)
		(width 0.1397)
		(layer "In11.Cu")
		(net "TDR_DIFF_100_IN4_DIP")
	)
	(segment
		(start 235.212382 -458.41539)
		(end 233.087164 -458.41539)
		(width 0.1397)
		(layer "In11.Cu")
		(net "TDR_DIFF_100_IN4_DIP")
	)
	(segment
		(start 243.594636 -455.982578)
		(end 243.274342 -456.302872)
		(width 0.1397)
		(layer "In11.Cu")
		(net "TDR_DIFF_100_IN4_DIP")
	)
	(segment
		(start 289.230562 -456.302872)
		(end 288.910268 -455.982578)
		(width 0.1397)
		(layer "In11.Cu")
		(net "TDR_DIFF_100_IN4_DIP")
	)
	(segment
		(start 263.432036 -455.982578)
		(end 263.111742 -456.302872)
		(width 0.1397)
		(layer "In11.Cu")
		(net "TDR_DIFF_100_IN4_DIP")
	)
	(segment
		(start 243.147342 -459.180946)
		(end 241.747802 -459.180946)
		(width 0.1397)
		(layer "In11.Cu")
		(net "TDR_DIFF_100_IN4_DIP")
	)
	(segment
		(start 291.204396 -455.982578)
		(end 290.884102 -456.302872)
		(width 0.1397)
		(layer "In11.Cu")
		(net "TDR_DIFF_100_IN4_DIP")
	)
	(segment
		(start 280.975308 -455.982578)
		(end 279.301956 -455.982578)
		(width 0.1397)
		(layer "In11.Cu")
		(net "TDR_DIFF_100_IN4_DIP")
	)
	(segment
		(start 275.014182 -456.302872)
		(end 275.014182 -459.053946)
		(width 0.1397)
		(layer "In11.Cu")
		(net "TDR_DIFF_100_IN4_DIP")
	)
	(segment
		(start 282.949142 -459.053946)
		(end 282.822142 -459.180946)
		(width 0.1397)
		(layer "In11.Cu")
		(net "TDR_DIFF_100_IN4_DIP")
	)
	(segment
		(start 237.653322 -459.018894)
		(end 237.653322 -456.302872)
		(width 0.1397)
		(layer "In11.Cu")
		(net "TDR_DIFF_100_IN4_DIP")
	)
	(segment
		(start 255.176782 -459.053946)
		(end 255.049782 -459.180946)
		(width 0.1397)
		(layer "In11.Cu")
		(net "TDR_DIFF_100_IN4_DIP")
	)
	(segment
		(start 277.455122 -459.180946)
		(end 277.328122 -459.053946)
		(width 0.1397)
		(layer "In11.Cu")
		(net "TDR_DIFF_100_IN4_DIP")
	)
	(segment
		(start 247.562116 -455.982578)
		(end 247.241822 -456.302872)
		(width 0.1397)
		(layer "In11.Cu")
		(net "TDR_DIFF_100_IN4_DIP")
	)
	(segment
		(start 239.306862 -459.018894)
		(end 239.179862 -459.145894)
		(width 0.1397)
		(layer "In11.Cu")
		(net "TDR_DIFF_100_IN4_DIP")
	)
	(segment
		(start 235.339382 -458.28839)
		(end 235.212382 -458.41539)
		(width 0.1397)
		(layer "In11.Cu")
		(net "TDR_DIFF_100_IN4_DIP")
	)
	(segment
		(start 237.780322 -459.145894)
		(end 237.653322 -459.018894)
		(width 0.1397)
		(layer "In11.Cu")
		(net "TDR_DIFF_100_IN4_DIP")
	)
	(segment
		(start 257.490722 -459.053946)
		(end 257.490722 -456.302872)
		(width 0.1397)
		(layer "In11.Cu")
		(net "TDR_DIFF_100_IN4_DIP")
	)
	(segment
		(start 241.620802 -459.053946)
		(end 241.620802 -456.302872)
		(width 0.1397)
		(layer "In11.Cu")
		(net "TDR_DIFF_100_IN4_DIP")
	)
	(segment
		(start 290.757102 -459.180946)
		(end 289.357562 -459.180946)
		(width 0.1397)
		(layer "In11.Cu")
		(net "TDR_DIFF_100_IN4_DIP")
	)
	(segment
		(start 245.267988 -455.982578)
		(end 243.594636 -455.982578)
		(width 0.1397)
		(layer "In11.Cu")
		(net "TDR_DIFF_100_IN4_DIP")
	)
	(segment
		(start 249.682762 -459.180946)
		(end 249.555762 -459.053946)
		(width 0.1397)
		(layer "In11.Cu")
		(net "TDR_DIFF_100_IN4_DIP")
	)
	(segment
		(start 237.653322 -456.302872)
		(end 237.333028 -455.982578)
		(width 0.1397)
		(layer "In11.Cu")
		(net "TDR_DIFF_100_IN4_DIP")
	)
	(segment
		(start 263.111742 -459.053946)
		(end 262.984742 -459.180946)
		(width 0.1397)
		(layer "In11.Cu")
		(net "TDR_DIFF_100_IN4_DIP")
	)
	(segment
		(start 247.241822 -459.053946)
		(end 247.114822 -459.180946)
		(width 0.1397)
		(layer "In11.Cu")
		(net "TDR_DIFF_100_IN4_DIP")
	)
	(segment
		(start 261.585202 -459.180946)
		(end 261.458202 -459.053946)
		(width 0.1397)
		(layer "In11.Cu")
		(net "TDR_DIFF_100_IN4_DIP")
	)
	(segment
		(start 239.306862 -456.302872)
		(end 239.306862 -459.018894)
		(width 0.1397)
		(layer "In11.Cu")
		(net "TDR_DIFF_100_IN4_DIP")
	)
	(segment
		(start 287.236916 -455.982578)
		(end 286.916622 -456.302872)
		(width 0.1397)
		(layer "In11.Cu")
		(net "TDR_DIFF_100_IN4_DIP")
	)
	(segment
		(start 285.263082 -459.053946)
		(end 285.263082 -456.302872)
		(width 0.1397)
		(layer "In11.Cu")
		(net "TDR_DIFF_100_IN4_DIP")
	)
	(segment
		(start 269.393162 -456.302872)
		(end 269.072868 -455.982578)
		(width 0.1397)
		(layer "In11.Cu")
		(net "TDR_DIFF_100_IN4_DIP")
	)
	(segment
		(start 261.137908 -455.982578)
		(end 259.464556 -455.982578)
		(width 0.1397)
		(layer "In11.Cu")
		(net "TDR_DIFF_100_IN4_DIP")
	)
	(segment
		(start 259.144262 -456.302872)
		(end 259.144262 -459.053946)
		(width 0.1397)
		(layer "In11.Cu")
		(net "TDR_DIFF_100_IN4_DIP")
	)
	(segment
		(start 286.789622 -459.180946)
		(end 285.390082 -459.180946)
		(width 0.1397)
		(layer "In11.Cu")
		(net "TDR_DIFF_100_IN4_DIP")
	)
	(segment
		(start 235.339382 -456.302872)
		(end 235.339382 -458.28839)
		(width 0.1397)
		(layer "In11.Cu")
		(net "TDR_DIFF_100_IN4_DIP")
	)
	(segment
		(start 289.230562 -459.053946)
		(end 289.230562 -456.302872)
		(width 0.1397)
		(layer "In11.Cu")
		(net "TDR_DIFF_100_IN4_DIP")
	)
	(segment
		(start 261.458202 -456.302872)
		(end 261.137908 -455.982578)
		(width 0.1397)
		(layer "In11.Cu")
		(net "TDR_DIFF_100_IN4_DIP")
	)
	(segment
		(start 267.079222 -459.053946)
		(end 266.952222 -459.180946)
		(width 0.1397)
		(layer "In11.Cu")
		(net "TDR_DIFF_100_IN4_DIP")
	)
	(segment
		(start 277.007828 -455.982578)
		(end 275.334476 -455.982578)
		(width 0.1397)
		(layer "In11.Cu")
		(net "TDR_DIFF_100_IN4_DIP")
	)
	(segment
		(start 263.111742 -456.302872)
		(end 263.111742 -459.053946)
		(width 0.1397)
		(layer "In11.Cu")
		(net "TDR_DIFF_100_IN4_DIP")
	)
	(segment
		(start 249.235468 -455.982578)
		(end 247.562116 -455.982578)
		(width 0.1397)
		(layer "In11.Cu")
		(net "TDR_DIFF_100_IN4_DIP")
	)
	(segment
		(start 290.884102 -456.302872)
		(end 290.884102 -459.053946)
		(width 0.1397)
		(layer "In11.Cu")
		(net "TDR_DIFF_100_IN4_DIP")
	)
	(segment
		(start 255.049782 -459.180946)
		(end 253.650242 -459.180946)
		(width 0.1397)
		(layer "In11.Cu")
		(net "TDR_DIFF_100_IN4_DIP")
	)
	(segment
		(start 273.360642 -459.053946)
		(end 273.360642 -456.302872)
		(width 0.1397)
		(layer "In11.Cu")
		(net "TDR_DIFF_100_IN4_DIP")
	)
	(segment
		(start 296.980864 -457.31049)
		(end 296.980864 -458.284834)
		(width 0.1397)
		(layer "In11.Cu")
		(net "TDR_DIFF_100_IN4_DIP")
	)
	(segment
		(start 267.079222 -456.302872)
		(end 267.079222 -459.053946)
		(width 0.1397)
		(layer "In11.Cu")
		(net "TDR_DIFF_100_IN4_DIP")
	)
	(segment
		(start 243.274342 -456.302872)
		(end 243.274342 -459.053946)
		(width 0.1397)
		(layer "In11.Cu")
		(net "TDR_DIFF_100_IN4_DIP")
	)
	(segment
		(start 285.263082 -456.302872)
		(end 284.942788 -455.982578)
		(width 0.1397)
		(layer "In11.Cu")
		(net "TDR_DIFF_100_IN4_DIP")
	)
	(segment
		(start 286.916622 -456.302872)
		(end 286.916622 -459.053946)
		(width 0.1397)
		(layer "In11.Cu")
		(net "TDR_DIFF_100_IN4_DIP")
	)
	(segment
		(start 277.328122 -459.053946)
		(end 277.328122 -456.302872)
		(width 0.1397)
		(layer "In11.Cu")
		(net "TDR_DIFF_100_IN4_DIP")
	)
	(segment
		(start 251.082302 -459.180946)
		(end 249.682762 -459.180946)
		(width 0.1397)
		(layer "In11.Cu")
		(net "TDR_DIFF_100_IN4_DIP")
	)
	(segment
		(start 261.458202 -459.053946)
		(end 261.458202 -456.302872)
		(width 0.1397)
		(layer "In11.Cu")
		(net "TDR_DIFF_100_IN4_DIP")
	)
	(segment
		(start 265.425682 -459.053946)
		(end 265.425682 -456.302872)
		(width 0.1397)
		(layer "In11.Cu")
		(net "TDR_DIFF_100_IN4_DIP")
	)
	(segment
		(start 255.497076 -455.982578)
		(end 255.176782 -456.302872)
		(width 0.1397)
		(layer "In11.Cu")
		(net "TDR_DIFF_100_IN4_DIP")
	)
	(segment
		(start 241.747802 -459.180946)
		(end 241.620802 -459.053946)
		(width 0.1397)
		(layer "In11.Cu")
		(net "TDR_DIFF_100_IN4_DIP")
	)
	(segment
		(start 235.659676 -455.982578)
		(end 235.339382 -456.302872)
		(width 0.1397)
		(layer "In11.Cu")
		(net "TDR_DIFF_100_IN4_DIP")
	)
	(segment
		(start 290.884102 -459.053946)
		(end 290.757102 -459.180946)
		(width 0.1397)
		(layer "In11.Cu")
		(net "TDR_DIFF_100_IN4_DIP")
	)
	(segment
		(start 245.715282 -459.180946)
		(end 245.588282 -459.053946)
		(width 0.1397)
		(layer "In11.Cu")
		(net "TDR_DIFF_100_IN4_DIP")
	)
	(segment
		(start 293.325042 -458.41539)
		(end 293.198042 -458.28839)
		(width 0.1397)
		(layer "In11.Cu")
		(net "TDR_DIFF_100_IN4_DIP")
	)
	(segment
		(start 288.910268 -455.982578)
		(end 287.236916 -455.982578)
		(width 0.1397)
		(layer "In11.Cu")
		(net "TDR_DIFF_100_IN4_DIP")
	)
	(segment
		(start 278.981662 -459.053946)
		(end 278.854662 -459.180946)
		(width 0.1397)
		(layer "In11.Cu")
		(net "TDR_DIFF_100_IN4_DIP")
	)
	(segment
		(start 273.040348 -455.982578)
		(end 271.366996 -455.982578)
		(width 0.1397)
		(layer "In11.Cu")
		(net "TDR_DIFF_100_IN4_DIP")
	)
	(segment
		(start 259.017262 -459.180946)
		(end 257.617722 -459.180946)
		(width 0.1397)
		(layer "In11.Cu")
		(net "TDR_DIFF_100_IN4_DIP")
	)
	(segment
		(start 283.269436 -455.982578)
		(end 282.949142 -456.302872)
		(width 0.1397)
		(layer "In11.Cu")
		(net "TDR_DIFF_100_IN4_DIP")
	)
	(segment
		(start 243.274342 -459.053946)
		(end 243.147342 -459.180946)
		(width 0.1397)
		(layer "In11.Cu")
		(net "TDR_DIFF_100_IN4_DIP")
	)
	(segment
		(start 251.209302 -459.053946)
		(end 251.082302 -459.180946)
		(width 0.1397)
		(layer "In11.Cu")
		(net "TDR_DIFF_100_IN4_DIP")
	)
	(segment
		(start 237.333028 -455.982578)
		(end 235.659676 -455.982578)
		(width 0.1397)
		(layer "In11.Cu")
		(net "TDR_DIFF_100_IN4_DIP")
	)
	(segment
		(start 266.952222 -459.180946)
		(end 265.552682 -459.180946)
		(width 0.1397)
		(layer "In11.Cu")
		(net "TDR_DIFF_100_IN4_DIP")
	)
	(segment
		(start 257.170428 -455.982578)
		(end 255.497076 -455.982578)
		(width 0.1397)
		(layer "In11.Cu")
		(net "TDR_DIFF_100_IN4_DIP")
	)
	(segment
		(start 269.393162 -459.053946)
		(end 269.393162 -456.302872)
		(width 0.1397)
		(layer "In11.Cu")
		(net "TDR_DIFF_100_IN4_DIP")
	)
	(segment
		(start 271.046702 -459.053946)
		(end 270.919702 -459.180946)
		(width 0.1397)
		(layer "In11.Cu")
		(net "TDR_DIFF_100_IN4_DIP")
	)
	(segment
		(start 277.328122 -456.302872)
		(end 277.007828 -455.982578)
		(width 0.1397)
		(layer "In11.Cu")
		(net "TDR_DIFF_100_IN4_DIP")
	)
	(segment
		(start 293.198042 -458.28839)
		(end 293.198042 -456.302872)
		(width 0.1397)
		(layer "In11.Cu")
		(net "TDR_DIFF_100_IN4_DIP")
	)
	(segment
		(start 253.523242 -459.053946)
		(end 253.523242 -456.302872)
		(width 0.1397)
		(layer "In11.Cu")
		(net "TDR_DIFF_100_IN4_DIP")
	)
	(segment
		(start 253.202948 -455.982578)
		(end 251.529596 -455.982578)
		(width 0.1397)
		(layer "In11.Cu")
		(net "TDR_DIFF_100_IN4_DIP")
	)
	(segment
		(start 241.620802 -456.302872)
		(end 241.300508 -455.982578)
		(width 0.1397)
		(layer "In11.Cu")
		(net "TDR_DIFF_100_IN4_DIP")
	)
	(segment
		(start 271.046702 -456.302872)
		(end 271.046702 -459.053946)
		(width 0.1397)
		(layer "In11.Cu")
		(net "TDR_DIFF_100_IN4_DIP")
	)
	(segment
		(start 262.984742 -459.180946)
		(end 261.585202 -459.180946)
		(width 0.1397)
		(layer "In11.Cu")
		(net "TDR_DIFF_100_IN4_DIP")
	)
	(segment
		(start 253.650242 -459.180946)
		(end 253.523242 -459.053946)
		(width 0.1397)
		(layer "In11.Cu")
		(net "TDR_DIFF_100_IN4_DIP")
	)
	(segment
		(start 269.520162 -459.180946)
		(end 269.393162 -459.053946)
		(width 0.1397)
		(layer "In11.Cu")
		(net "TDR_DIFF_100_IN4_DIP")
	)
	(segment
		(start 273.487642 -459.180946)
		(end 273.360642 -459.053946)
		(width 0.1397)
		(layer "In11.Cu")
		(net "TDR_DIFF_100_IN4_DIP")
	)
	(segment
		(start 269.072868 -455.982578)
		(end 267.399516 -455.982578)
		(width 0.1397)
		(layer "In11.Cu")
		(net "TDR_DIFF_100_IN4_DIP")
	)
	(segment
		(start 257.490722 -456.302872)
		(end 257.170428 -455.982578)
		(width 0.1397)
		(layer "In11.Cu")
		(net "TDR_DIFF_100_IN4_DIP")
	)
	(segment
		(start 265.105388 -455.982578)
		(end 263.432036 -455.982578)
		(width 0.1397)
		(layer "In11.Cu")
		(net "TDR_DIFF_100_IN4_DIP")
	)
	(segment
		(start 239.627156 -455.982578)
		(end 239.306862 -456.302872)
		(width 0.1397)
		(layer "In11.Cu")
		(net "TDR_DIFF_100_IN4_DIP")
	)
	(segment
		(start 292.877748 -455.982578)
		(end 291.204396 -455.982578)
		(width 0.1397)
		(layer "In11.Cu")
		(net "TDR_DIFF_100_IN4_DIP")
	)
	(segment
		(start 239.179862 -459.145894)
		(end 237.780322 -459.145894)
		(width 0.1397)
		(layer "In11.Cu")
		(net "TDR_DIFF_100_IN4_DIP")
	)
	(segment
		(start 265.425682 -456.302872)
		(end 265.105388 -455.982578)
		(width 0.1397)
		(layer "In11.Cu")
		(net "TDR_DIFF_100_IN4_DIP")
	)
	(segment
		(start 241.300508 -455.982578)
		(end 239.627156 -455.982578)
		(width 0.1397)
		(layer "In11.Cu")
		(net "TDR_DIFF_100_IN4_DIP")
	)
	(segment
		(start 281.422602 -459.180946)
		(end 281.295602 -459.053946)
		(width 0.1397)
		(layer "In11.Cu")
		(net "TDR_DIFF_100_IN4_DIP")
	)
	(segment
		(start 275.014182 -459.053946)
		(end 274.887182 -459.180946)
		(width 0.1397)
		(layer "In11.Cu")
		(net "TDR_DIFF_100_IN4_DIP")
	)
	(segment
		(start 251.529596 -455.982578)
		(end 251.209302 -456.302872)
		(width 0.1397)
		(layer "In11.Cu")
		(net "TDR_DIFF_100_IN4_DIP")
	)
	(segment
		(start 267.399516 -455.982578)
		(end 267.079222 -456.302872)
		(width 0.1397)
		(layer "In11.Cu")
		(net "TDR_DIFF_100_IN4_DIP")
	)
	(segment
		(start 271.366996 -455.982578)
		(end 271.046702 -456.302872)
		(width 0.1397)
		(layer "In11.Cu")
		(net "TDR_DIFF_100_IN4_DIP")
	)
	(segment
		(start 233.087164 -458.41539)
		(end 232.960164 -458.28839)
		(width 0.1397)
		(layer "In11.Cu")
		(net "TDR_DIFF_100_IN4_DIP")
	)
	(segment
		(start 281.295602 -456.302872)
		(end 280.975308 -455.982578)
		(width 0.1397)
		(layer "In11.Cu")
		(net "TDR_DIFF_100_IN4_DIP")
	)
	(segment
		(start 249.555762 -456.302872)
		(end 249.235468 -455.982578)
		(width 0.1397)
		(layer "In11.Cu")
		(net "TDR_DIFF_100_IN4_DIP")
	)
	(segment
		(start 184.019952 -449.96608)
		(end 182.620412 -449.96608)
		(width 0.1397)
		(layer "In7.Cu")
		(net "TDR_DIFF_100_IN2_DIP")
	)
	(segment
		(start 198.363332 -452.841614)
		(end 198.043038 -453.161908)
		(width 0.1397)
		(layer "In7.Cu")
		(net "TDR_DIFF_100_IN2_DIP")
	)
	(segment
		(start 178.525932 -450.09308)
		(end 178.525932 -452.841614)
		(width 0.1397)
		(layer "In7.Cu")
		(net "TDR_DIFF_100_IN2_DIP")
	)
	(segment
		(start 172.244512 -450.09308)
		(end 172.117512 -449.96608)
		(width 0.1397)
		(layer "In7.Cu")
		(net "TDR_DIFF_100_IN2_DIP")
	)
	(segment
		(start 214.233252 -450.09308)
		(end 214.233252 -452.841614)
		(width 0.1397)
		(layer "In7.Cu")
		(net "TDR_DIFF_100_IN2_DIP")
	)
	(segment
		(start 196.369686 -453.161908)
		(end 196.049392 -452.841614)
		(width 0.1397)
		(layer "In7.Cu")
		(net "TDR_DIFF_100_IN2_DIP")
	)
	(segment
		(start 190.428372 -450.09308)
		(end 190.428372 -452.841614)
		(width 0.1397)
		(layer "In7.Cu")
		(net "TDR_DIFF_100_IN2_DIP")
	)
	(segment
		(start 210.392772 -449.96608)
		(end 210.265772 -450.09308)
		(width 0.1397)
		(layer "In7.Cu")
		(net "TDR_DIFF_100_IN2_DIP")
	)
	(segment
		(start 162.783012 -449.96608)
		(end 162.656012 -450.09308)
		(width 0.1397)
		(layer "In7.Cu")
		(net "TDR_DIFF_100_IN2_DIP")
	)
	(segment
		(start 192.081912 -450.09308)
		(end 191.954912 -449.96608)
		(width 0.1397)
		(layer "In7.Cu")
		(net "TDR_DIFF_100_IN2_DIP")
	)
	(segment
		(start 178.652932 -449.96608)
		(end 178.525932 -450.09308)
		(width 0.1397)
		(layer "In7.Cu")
		(net "TDR_DIFF_100_IN2_DIP")
	)
	(segment
		(start 170.717972 -449.96608)
		(end 170.590972 -450.09308)
		(width 0.1397)
		(layer "In7.Cu")
		(net "TDR_DIFF_100_IN2_DIP")
	)
	(segment
		(start 186.140598 -453.161908)
		(end 184.467246 -453.161908)
		(width 0.1397)
		(layer "In7.Cu")
		(net "TDR_DIFF_100_IN2_DIP")
	)
	(segment
		(start 207.951832 -450.09308)
		(end 207.824832 -449.96608)
		(width 0.1397)
		(layer "In7.Cu")
		(net "TDR_DIFF_100_IN2_DIP")
	)
	(segment
		(start 188.434726 -453.161908)
		(end 188.114432 -452.841614)
		(width 0.1397)
		(layer "In7.Cu")
		(net "TDR_DIFF_100_IN2_DIP")
	)
	(segment
		(start 209.945478 -453.161908)
		(end 208.272126 -453.161908)
		(width 0.1397)
		(layer "In7.Cu")
		(net "TDR_DIFF_100_IN2_DIP")
	)
	(segment
		(start 214.360252 -449.96608)
		(end 214.233252 -450.09308)
		(width 0.1397)
		(layer "In7.Cu")
		(net "TDR_DIFF_100_IN2_DIP")
	)
	(segment
		(start 186.460892 -452.841614)
		(end 186.140598 -453.161908)
		(width 0.1397)
		(layer "In7.Cu")
		(net "TDR_DIFF_100_IN2_DIP")
	)
	(segment
		(start 184.146952 -452.841614)
		(end 184.146952 -450.09308)
		(width 0.1397)
		(layer "In7.Cu")
		(net "TDR_DIFF_100_IN2_DIP")
	)
	(segment
		(start 170.270678 -453.161908)
		(end 168.597326 -453.161908)
		(width 0.1397)
		(layer "In7.Cu")
		(net "TDR_DIFF_100_IN2_DIP")
	)
	(segment
		(start 211.919312 -452.841614)
		(end 211.919312 -450.09308)
		(width 0.1397)
		(layer "In7.Cu")
		(net "TDR_DIFF_100_IN2_DIP")
	)
	(segment
		(start 166.750492 -449.96608)
		(end 166.623492 -450.09308)
		(width 0.1397)
		(layer "In7.Cu")
		(net "TDR_DIFF_100_IN2_DIP")
	)
	(segment
		(start 206.298292 -450.09308)
		(end 206.298292 -452.841614)
		(width 0.1397)
		(layer "In7.Cu")
		(net "TDR_DIFF_100_IN2_DIP")
	)
	(segment
		(start 194.395852 -452.841614)
		(end 194.075558 -453.161908)
		(width 0.1397)
		(layer "In7.Cu")
		(net "TDR_DIFF_100_IN2_DIP")
	)
	(segment
		(start 164.309552 -450.09308)
		(end 164.182552 -449.96608)
		(width 0.1397)
		(layer "In7.Cu")
		(net "TDR_DIFF_100_IN2_DIP")
	)
	(segment
		(start 211.919312 -450.09308)
		(end 211.792312 -449.96608)
		(width 0.1397)
		(layer "In7.Cu")
		(net "TDR_DIFF_100_IN2_DIP")
	)
	(segment
		(start 192.081912 -452.841614)
		(end 192.081912 -450.09308)
		(width 0.1397)
		(layer "In7.Cu")
		(net "TDR_DIFF_100_IN2_DIP")
	)
	(segment
		(start 190.555372 -449.96608)
		(end 190.428372 -450.09308)
		(width 0.1397)
		(layer "In7.Cu")
		(net "TDR_DIFF_100_IN2_DIP")
	)
	(segment
		(start 174.558452 -452.841614)
		(end 174.238158 -453.161908)
		(width 0.1397)
		(layer "In7.Cu")
		(net "TDR_DIFF_100_IN2_DIP")
	)
	(segment
		(start 160.073594 -452.396352)
		(end 159.946594 -452.523352)
		(width 0.1397)
		(layer "In7.Cu")
		(net "TDR_DIFF_100_IN2_DIP")
	)
	(segment
		(start 214.233252 -452.841614)
		(end 213.912958 -453.161908)
		(width 0.1397)
		(layer "In7.Cu")
		(net "TDR_DIFF_100_IN2_DIP")
	)
	(segment
		(start 204.304646 -453.161908)
		(end 203.984352 -452.841614)
		(width 0.1397)
		(layer "In7.Cu")
		(net "TDR_DIFF_100_IN2_DIP")
	)
	(segment
		(start 218.200732 -450.09308)
		(end 218.200732 -452.841614)
		(width 0.1397)
		(layer "In7.Cu")
		(net "TDR_DIFF_100_IN2_DIP")
	)
	(segment
		(start 202.010518 -453.161908)
		(end 200.337166 -453.161908)
		(width 0.1397)
		(layer "In7.Cu")
		(net "TDR_DIFF_100_IN2_DIP")
	)
	(segment
		(start 168.277032 -452.841614)
		(end 168.277032 -450.09308)
		(width 0.1397)
		(layer "In7.Cu")
		(net "TDR_DIFF_100_IN2_DIP")
	)
	(segment
		(start 162.656012 -450.09308)
		(end 162.656012 -452.076058)
		(width 0.1397)
		(layer "In7.Cu")
		(net "TDR_DIFF_100_IN2_DIP")
	)
	(segment
		(start 219.854272 -450.09308)
		(end 219.727272 -449.96608)
		(width 0.1397)
		(layer "In7.Cu")
		(net "TDR_DIFF_100_IN2_DIP")
	)
	(segment
		(start 215.886792 -450.09308)
		(end 215.759792 -449.96608)
		(width 0.1397)
		(layer "In7.Cu")
		(net "TDR_DIFF_100_IN2_DIP")
	)
	(segment
		(start 210.265772 -450.09308)
		(end 210.265772 -452.841614)
		(width 0.1397)
		(layer "In7.Cu")
		(net "TDR_DIFF_100_IN2_DIP")
	)
	(segment
		(start 210.265772 -452.841614)
		(end 209.945478 -453.161908)
		(width 0.1397)
		(layer "In7.Cu")
		(net "TDR_DIFF_100_IN2_DIP")
	)
	(segment
		(start 200.016872 -450.09308)
		(end 199.889872 -449.96608)
		(width 0.1397)
		(layer "In7.Cu")
		(net "TDR_DIFF_100_IN2_DIP")
	)
	(segment
		(start 176.211992 -452.841614)
		(end 176.211992 -450.09308)
		(width 0.1397)
		(layer "In7.Cu")
		(net "TDR_DIFF_100_IN2_DIP")
	)
	(segment
		(start 223.967294 -452.50354)
		(end 223.860106 -452.396352)
		(width 0.1397)
		(layer "In7.Cu")
		(net "TDR_DIFF_100_IN2_DIP")
	)
	(segment
		(start 216.207086 -453.161908)
		(end 215.886792 -452.841614)
		(width 0.1397)
		(layer "In7.Cu")
		(net "TDR_DIFF_100_IN2_DIP")
	)
	(segment
		(start 172.244512 -452.841614)
		(end 172.244512 -450.09308)
		(width 0.1397)
		(layer "In7.Cu")
		(net "TDR_DIFF_100_IN2_DIP")
	)
	(segment
		(start 178.205638 -453.161908)
		(end 176.532286 -453.161908)
		(width 0.1397)
		(layer "In7.Cu")
		(net "TDR_DIFF_100_IN2_DIP")
	)
	(segment
		(start 198.363332 -450.09308)
		(end 198.363332 -452.841614)
		(width 0.1397)
		(layer "In7.Cu")
		(net "TDR_DIFF_100_IN2_DIP")
	)
	(segment
		(start 174.238158 -453.161908)
		(end 172.564806 -453.161908)
		(width 0.1397)
		(layer "In7.Cu")
		(net "TDR_DIFF_100_IN2_DIP")
	)
	(segment
		(start 205.977998 -453.161908)
		(end 204.304646 -453.161908)
		(width 0.1397)
		(layer "In7.Cu")
		(net "TDR_DIFF_100_IN2_DIP")
	)
	(segment
		(start 213.912958 -453.161908)
		(end 212.239606 -453.161908)
		(width 0.1397)
		(layer "In7.Cu")
		(net "TDR_DIFF_100_IN2_DIP")
	)
	(segment
		(start 188.114432 -452.841614)
		(end 188.114432 -450.09308)
		(width 0.1397)
		(layer "In7.Cu")
		(net "TDR_DIFF_100_IN2_DIP")
	)
	(segment
		(start 215.886792 -452.841614)
		(end 215.886792 -450.09308)
		(width 0.1397)
		(layer "In7.Cu")
		(net "TDR_DIFF_100_IN2_DIP")
	)
	(segment
		(start 182.493412 -452.841614)
		(end 182.173118 -453.161908)
		(width 0.1397)
		(layer "In7.Cu")
		(net "TDR_DIFF_100_IN2_DIP")
	)
	(segment
		(start 199.889872 -449.96608)
		(end 198.490332 -449.96608)
		(width 0.1397)
		(layer "In7.Cu")
		(net "TDR_DIFF_100_IN2_DIP")
	)
	(segment
		(start 180.499766 -453.161908)
		(end 180.179472 -452.841614)
		(width 0.1397)
		(layer "In7.Cu")
		(net "TDR_DIFF_100_IN2_DIP")
	)
	(segment
		(start 180.052472 -449.96608)
		(end 178.652932 -449.96608)
		(width 0.1397)
		(layer "In7.Cu")
		(net "TDR_DIFF_100_IN2_DIP")
	)
	(segment
		(start 164.182552 -449.96608)
		(end 162.783012 -449.96608)
		(width 0.1397)
		(layer "In7.Cu")
		(net "TDR_DIFF_100_IN2_DIP")
	)
	(segment
		(start 202.330812 -450.09308)
		(end 202.330812 -452.841614)
		(width 0.1397)
		(layer "In7.Cu")
		(net "TDR_DIFF_100_IN2_DIP")
	)
	(segment
		(start 176.084992 -449.96608)
		(end 174.685452 -449.96608)
		(width 0.1397)
		(layer "In7.Cu")
		(net "TDR_DIFF_100_IN2_DIP")
	)
	(segment
		(start 215.759792 -449.96608)
		(end 214.360252 -449.96608)
		(width 0.1397)
		(layer "In7.Cu")
		(net "TDR_DIFF_100_IN2_DIP")
	)
	(segment
		(start 207.824832 -449.96608)
		(end 206.425292 -449.96608)
		(width 0.1397)
		(layer "In7.Cu")
		(net "TDR_DIFF_100_IN2_DIP")
	)
	(segment
		(start 182.173118 -453.161908)
		(end 180.499766 -453.161908)
		(width 0.1397)
		(layer "In7.Cu")
		(net "TDR_DIFF_100_IN2_DIP")
	)
	(segment
		(start 202.457812 -449.96608)
		(end 202.330812 -450.09308)
		(width 0.1397)
		(layer "In7.Cu")
		(net "TDR_DIFF_100_IN2_DIP")
	)
	(segment
		(start 203.857352 -449.96608)
		(end 202.457812 -449.96608)
		(width 0.1397)
		(layer "In7.Cu")
		(net "TDR_DIFF_100_IN2_DIP")
	)
	(segment
		(start 178.525932 -452.841614)
		(end 178.205638 -453.161908)
		(width 0.1397)
		(layer "In7.Cu")
		(net "TDR_DIFF_100_IN2_DIP")
	)
	(segment
		(start 200.016872 -452.841614)
		(end 200.016872 -450.09308)
		(width 0.1397)
		(layer "In7.Cu")
		(net "TDR_DIFF_100_IN2_DIP")
	)
	(segment
		(start 219.854272 -452.076058)
		(end 219.854272 -450.09308)
		(width 0.1397)
		(layer "In7.Cu")
		(net "TDR_DIFF_100_IN2_DIP")
	)
	(segment
		(start 168.277032 -450.09308)
		(end 168.150032 -449.96608)
		(width 0.1397)
		(layer "In7.Cu")
		(net "TDR_DIFF_100_IN2_DIP")
	)
	(segment
		(start 182.493412 -450.09308)
		(end 182.493412 -452.841614)
		(width 0.1397)
		(layer "In7.Cu")
		(net "TDR_DIFF_100_IN2_DIP")
	)
	(segment
		(start 164.309552 -452.806562)
		(end 164.309552 -450.09308)
		(width 0.1397)
		(layer "In7.Cu")
		(net "TDR_DIFF_100_IN2_DIP")
	)
	(segment
		(start 174.685452 -449.96608)
		(end 174.558452 -450.09308)
		(width 0.1397)
		(layer "In7.Cu")
		(net "TDR_DIFF_100_IN2_DIP")
	)
	(segment
		(start 168.597326 -453.161908)
		(end 168.277032 -452.841614)
		(width 0.1397)
		(layer "In7.Cu")
		(net "TDR_DIFF_100_IN2_DIP")
	)
	(segment
		(start 207.951832 -452.841614)
		(end 207.951832 -450.09308)
		(width 0.1397)
		(layer "In7.Cu")
		(net "TDR_DIFF_100_IN2_DIP")
	)
	(segment
		(start 206.298292 -452.841614)
		(end 205.977998 -453.161908)
		(width 0.1397)
		(layer "In7.Cu")
		(net "TDR_DIFF_100_IN2_DIP")
	)
	(segment
		(start 170.590972 -452.841614)
		(end 170.270678 -453.161908)
		(width 0.1397)
		(layer "In7.Cu")
		(net "TDR_DIFF_100_IN2_DIP")
	)
	(segment
		(start 203.984352 -450.09308)
		(end 203.857352 -449.96608)
		(width 0.1397)
		(layer "In7.Cu")
		(net "TDR_DIFF_100_IN2_DIP")
	)
	(segment
		(start 180.179472 -452.841614)
		(end 180.179472 -450.09308)
		(width 0.1397)
		(layer "In7.Cu")
		(net "TDR_DIFF_100_IN2_DIP")
	)
	(segment
		(start 194.522852 -449.96608)
		(end 194.395852 -450.09308)
		(width 0.1397)
		(layer "In7.Cu")
		(net "TDR_DIFF_100_IN2_DIP")
	)
	(segment
		(start 182.620412 -449.96608)
		(end 182.493412 -450.09308)
		(width 0.1397)
		(layer "In7.Cu")
		(net "TDR_DIFF_100_IN2_DIP")
	)
	(segment
		(start 186.587892 -449.96608)
		(end 186.460892 -450.09308)
		(width 0.1397)
		(layer "In7.Cu")
		(net "TDR_DIFF_100_IN2_DIP")
	)
	(segment
		(start 172.564806 -453.161908)
		(end 172.244512 -452.841614)
		(width 0.1397)
		(layer "In7.Cu")
		(net "TDR_DIFF_100_IN2_DIP")
	)
	(segment
		(start 191.954912 -449.96608)
		(end 190.555372 -449.96608)
		(width 0.1397)
		(layer "In7.Cu")
		(net "TDR_DIFF_100_IN2_DIP")
	)
	(segment
		(start 223.967294 -453.501252)
		(end 223.967294 -452.50354)
		(width 0.1397)
		(layer "In7.Cu")
		(net "TDR_DIFF_100_IN2_DIP")
	)
	(segment
		(start 198.490332 -449.96608)
		(end 198.363332 -450.09308)
		(width 0.1397)
		(layer "In7.Cu")
		(net "TDR_DIFF_100_IN2_DIP")
	)
	(segment
		(start 194.395852 -450.09308)
		(end 194.395852 -452.841614)
		(width 0.1397)
		(layer "In7.Cu")
		(net "TDR_DIFF_100_IN2_DIP")
	)
	(segment
		(start 166.303198 -453.126856)
		(end 164.629846 -453.126856)
		(width 0.1397)
		(layer "In7.Cu")
		(net "TDR_DIFF_100_IN2_DIP")
	)
	(segment
		(start 162.656012 -452.076058)
		(end 162.335718 -452.396352)
		(width 0.1397)
		(layer "In7.Cu")
		(net "TDR_DIFF_100_IN2_DIP")
	)
	(segment
		(start 172.117512 -449.96608)
		(end 170.717972 -449.96608)
		(width 0.1397)
		(layer "In7.Cu")
		(net "TDR_DIFF_100_IN2_DIP")
	)
	(segment
		(start 176.211992 -450.09308)
		(end 176.084992 -449.96608)
		(width 0.1397)
		(layer "In7.Cu")
		(net "TDR_DIFF_100_IN2_DIP")
	)
	(segment
		(start 166.623492 -452.806562)
		(end 166.303198 -453.126856)
		(width 0.1397)
		(layer "In7.Cu")
		(net "TDR_DIFF_100_IN2_DIP")
	)
	(segment
		(start 188.114432 -450.09308)
		(end 187.987432 -449.96608)
		(width 0.1397)
		(layer "In7.Cu")
		(net "TDR_DIFF_100_IN2_DIP")
	)
	(segment
		(start 162.335718 -452.396352)
		(end 160.073594 -452.396352)
		(width 0.1397)
		(layer "In7.Cu")
		(net "TDR_DIFF_100_IN2_DIP")
	)
	(segment
		(start 212.239606 -453.161908)
		(end 211.919312 -452.841614)
		(width 0.1397)
		(layer "In7.Cu")
		(net "TDR_DIFF_100_IN2_DIP")
	)
	(segment
		(start 198.043038 -453.161908)
		(end 196.369686 -453.161908)
		(width 0.1397)
		(layer "In7.Cu")
		(net "TDR_DIFF_100_IN2_DIP")
	)
	(segment
		(start 220.174566 -452.396352)
		(end 219.854272 -452.076058)
		(width 0.1397)
		(layer "In7.Cu")
		(net "TDR_DIFF_100_IN2_DIP")
	)
	(segment
		(start 192.402206 -453.161908)
		(end 192.081912 -452.841614)
		(width 0.1397)
		(layer "In7.Cu")
		(net "TDR_DIFF_100_IN2_DIP")
	)
	(segment
		(start 186.460892 -450.09308)
		(end 186.460892 -452.841614)
		(width 0.1397)
		(layer "In7.Cu")
		(net "TDR_DIFF_100_IN2_DIP")
	)
	(segment
		(start 218.327732 -449.96608)
		(end 218.200732 -450.09308)
		(width 0.1397)
		(layer "In7.Cu")
		(net "TDR_DIFF_100_IN2_DIP")
	)
	(segment
		(start 217.880438 -453.161908)
		(end 216.207086 -453.161908)
		(width 0.1397)
		(layer "In7.Cu")
		(net "TDR_DIFF_100_IN2_DIP")
	)
	(segment
		(start 166.623492 -450.09308)
		(end 166.623492 -452.806562)
		(width 0.1397)
		(layer "In7.Cu")
		(net "TDR_DIFF_100_IN2_DIP")
	)
	(segment
		(start 208.272126 -453.161908)
		(end 207.951832 -452.841614)
		(width 0.1397)
		(layer "In7.Cu")
		(net "TDR_DIFF_100_IN2_DIP")
	)
	(segment
		(start 196.049392 -452.841614)
		(end 196.049392 -450.09308)
		(width 0.1397)
		(layer "In7.Cu")
		(net "TDR_DIFF_100_IN2_DIP")
	)
	(segment
		(start 176.532286 -453.161908)
		(end 176.211992 -452.841614)
		(width 0.1397)
		(layer "In7.Cu")
		(net "TDR_DIFF_100_IN2_DIP")
	)
	(segment
		(start 211.792312 -449.96608)
		(end 210.392772 -449.96608)
		(width 0.1397)
		(layer "In7.Cu")
		(net "TDR_DIFF_100_IN2_DIP")
	)
	(segment
		(start 200.337166 -453.161908)
		(end 200.016872 -452.841614)
		(width 0.1397)
		(layer "In7.Cu")
		(net "TDR_DIFF_100_IN2_DIP")
	)
	(segment
		(start 194.075558 -453.161908)
		(end 192.402206 -453.161908)
		(width 0.1397)
		(layer "In7.Cu")
		(net "TDR_DIFF_100_IN2_DIP")
	)
	(segment
		(start 168.150032 -449.96608)
		(end 166.750492 -449.96608)
		(width 0.1397)
		(layer "In7.Cu")
		(net "TDR_DIFF_100_IN2_DIP")
	)
	(segment
		(start 190.428372 -452.841614)
		(end 190.108078 -453.161908)
		(width 0.1397)
		(layer "In7.Cu")
		(net "TDR_DIFF_100_IN2_DIP")
	)
	(segment
		(start 174.558452 -450.09308)
		(end 174.558452 -452.841614)
		(width 0.1397)
		(layer "In7.Cu")
		(net "TDR_DIFF_100_IN2_DIP")
	)
	(segment
		(start 184.467246 -453.161908)
		(end 184.146952 -452.841614)
		(width 0.1397)
		(layer "In7.Cu")
		(net "TDR_DIFF_100_IN2_DIP")
	)
	(segment
		(start 170.590972 -450.09308)
		(end 170.590972 -452.841614)
		(width 0.1397)
		(layer "In7.Cu")
		(net "TDR_DIFF_100_IN2_DIP")
	)
	(segment
		(start 218.200732 -452.841614)
		(end 217.880438 -453.161908)
		(width 0.1397)
		(layer "In7.Cu")
		(net "TDR_DIFF_100_IN2_DIP")
	)
	(segment
		(start 195.922392 -449.96608)
		(end 194.522852 -449.96608)
		(width 0.1397)
		(layer "In7.Cu")
		(net "TDR_DIFF_100_IN2_DIP")
	)
	(segment
		(start 206.425292 -449.96608)
		(end 206.298292 -450.09308)
		(width 0.1397)
		(layer "In7.Cu")
		(net "TDR_DIFF_100_IN2_DIP")
	)
	(segment
		(start 187.987432 -449.96608)
		(end 186.587892 -449.96608)
		(width 0.1397)
		(layer "In7.Cu")
		(net "TDR_DIFF_100_IN2_DIP")
	)
	(segment
		(start 196.049392 -450.09308)
		(end 195.922392 -449.96608)
		(width 0.1397)
		(layer "In7.Cu")
		(net "TDR_DIFF_100_IN2_DIP")
	)
	(segment
		(start 190.108078 -453.161908)
		(end 188.434726 -453.161908)
		(width 0.1397)
		(layer "In7.Cu")
		(net "TDR_DIFF_100_IN2_DIP")
	)
	(segment
		(start 219.727272 -449.96608)
		(end 218.327732 -449.96608)
		(width 0.1397)
		(layer "In7.Cu")
		(net "TDR_DIFF_100_IN2_DIP")
	)
	(segment
		(start 159.946594 -452.523352)
		(end 159.946594 -453.501252)
		(width 0.1397)
		(layer "In7.Cu")
		(net "TDR_DIFF_100_IN2_DIP")
	)
	(segment
		(start 203.984352 -452.841614)
		(end 203.984352 -450.09308)
		(width 0.1397)
		(layer "In7.Cu")
		(net "TDR_DIFF_100_IN2_DIP")
	)
	(segment
		(start 202.330812 -452.841614)
		(end 202.010518 -453.161908)
		(width 0.1397)
		(layer "In7.Cu")
		(net "TDR_DIFF_100_IN2_DIP")
	)
	(segment
		(start 223.860106 -452.396352)
		(end 220.174566 -452.396352)
		(width 0.1397)
		(layer "In7.Cu")
		(net "TDR_DIFF_100_IN2_DIP")
	)
	(segment
		(start 180.179472 -450.09308)
		(end 180.052472 -449.96608)
		(width 0.1397)
		(layer "In7.Cu")
		(net "TDR_DIFF_100_IN2_DIP")
	)
	(segment
		(start 184.146952 -450.09308)
		(end 184.019952 -449.96608)
		(width 0.1397)
		(layer "In7.Cu")
		(net "TDR_DIFF_100_IN2_DIP")
	)
	(segment
		(start 164.629846 -453.126856)
		(end 164.309552 -452.806562)
		(width 0.1397)
		(layer "In7.Cu")
		(net "TDR_DIFF_100_IN2_DIP")
	)
	(segment
		(start 292.867842 -458.425296)
		(end 292.867842 -456.442318)
		(width 0.1397)
		(layer "In11.Cu")
		(net "TDR_DIFF_100_IN4_DIN")
	)
	(segment
		(start 235.349288 -458.74559)
		(end 233.087164 -458.74559)
		(width 0.1397)
		(layer "In11.Cu")
		(net "TDR_DIFF_100_IN4_DIN")
	)
	(segment
		(start 245.258082 -456.442318)
		(end 245.131082 -456.315318)
		(width 0.1397)
		(layer "In11.Cu")
		(net "TDR_DIFF_100_IN4_DIN")
	)
	(segment
		(start 285.253176 -459.511146)
		(end 284.932882 -459.190852)
		(width 0.1397)
		(layer "In11.Cu")
		(net "TDR_DIFF_100_IN4_DIN")
	)
	(segment
		(start 291.341302 -456.315318)
		(end 291.214302 -456.442318)
		(width 0.1397)
		(layer "In11.Cu")
		(net "TDR_DIFF_100_IN4_DIN")
	)
	(segment
		(start 261.001002 -456.315318)
		(end 259.601462 -456.315318)
		(width 0.1397)
		(layer "In11.Cu")
		(net "TDR_DIFF_100_IN4_DIN")
	)
	(segment
		(start 261.448296 -459.511146)
		(end 261.128002 -459.190852)
		(width 0.1397)
		(layer "In11.Cu")
		(net "TDR_DIFF_100_IN4_DIN")
	)
	(segment
		(start 267.409422 -459.190852)
		(end 267.089128 -459.511146)
		(width 0.1397)
		(layer "In11.Cu")
		(net "TDR_DIFF_100_IN4_DIN")
	)
	(segment
		(start 255.506982 -459.190852)
		(end 255.186688 -459.511146)
		(width 0.1397)
		(layer "In11.Cu")
		(net "TDR_DIFF_100_IN4_DIN")
	)
	(segment
		(start 282.959048 -459.511146)
		(end 281.285696 -459.511146)
		(width 0.1397)
		(layer "In11.Cu")
		(net "TDR_DIFF_100_IN4_DIN")
	)
	(segment
		(start 279.311862 -456.442318)
		(end 279.311862 -459.190852)
		(width 0.1397)
		(layer "In11.Cu")
		(net "TDR_DIFF_100_IN4_DIN")
	)
	(segment
		(start 288.900362 -456.442318)
		(end 288.773362 -456.315318)
		(width 0.1397)
		(layer "In11.Cu")
		(net "TDR_DIFF_100_IN4_DIN")
	)
	(segment
		(start 245.578376 -459.511146)
		(end 245.258082 -459.190852)
		(width 0.1397)
		(layer "In11.Cu")
		(net "TDR_DIFF_100_IN4_DIN")
	)
	(segment
		(start 287.373822 -456.315318)
		(end 287.246822 -456.442318)
		(width 0.1397)
		(layer "In11.Cu")
		(net "TDR_DIFF_100_IN4_DIN")
	)
	(segment
		(start 293.188136 -458.74559)
		(end 292.867842 -458.425296)
		(width 0.1397)
		(layer "In11.Cu")
		(net "TDR_DIFF_100_IN4_DIN")
	)
	(segment
		(start 269.062962 -459.190852)
		(end 269.062962 -456.442318)
		(width 0.1397)
		(layer "In11.Cu")
		(net "TDR_DIFF_100_IN4_DIN")
	)
	(segment
		(start 275.471382 -456.315318)
		(end 275.344382 -456.442318)
		(width 0.1397)
		(layer "In11.Cu")
		(net "TDR_DIFF_100_IN4_DIN")
	)
	(segment
		(start 264.968482 -456.315318)
		(end 263.568942 -456.315318)
		(width 0.1397)
		(layer "In11.Cu")
		(net "TDR_DIFF_100_IN4_DIN")
	)
	(segment
		(start 288.900362 -459.190852)
		(end 288.900362 -456.442318)
		(width 0.1397)
		(layer "In11.Cu")
		(net "TDR_DIFF_100_IN4_DIN")
	)
	(segment
		(start 276.997922 -459.190852)
		(end 276.997922 -456.442318)
		(width 0.1397)
		(layer "In11.Cu")
		(net "TDR_DIFF_100_IN4_DIN")
	)
	(segment
		(start 259.474462 -459.190852)
		(end 259.154168 -459.511146)
		(width 0.1397)
		(layer "In11.Cu")
		(net "TDR_DIFF_100_IN4_DIN")
	)
	(segment
		(start 247.699022 -456.315318)
		(end 247.572022 -456.442318)
		(width 0.1397)
		(layer "In11.Cu")
		(net "TDR_DIFF_100_IN4_DIN")
	)
	(segment
		(start 255.186688 -459.511146)
		(end 253.513336 -459.511146)
		(width 0.1397)
		(layer "In11.Cu")
		(net "TDR_DIFF_100_IN4_DIN")
	)
	(segment
		(start 279.438862 -456.315318)
		(end 279.311862 -456.442318)
		(width 0.1397)
		(layer "In11.Cu")
		(net "TDR_DIFF_100_IN4_DIN")
	)
	(segment
		(start 251.666502 -456.315318)
		(end 251.539502 -456.442318)
		(width 0.1397)
		(layer "In11.Cu")
		(net "TDR_DIFF_100_IN4_DIN")
	)
	(segment
		(start 257.033522 -456.315318)
		(end 255.633982 -456.315318)
		(width 0.1397)
		(layer "In11.Cu")
		(net "TDR_DIFF_100_IN4_DIN")
	)
	(segment
		(start 296.980864 -458.852778)
		(end 296.873676 -458.74559)
		(width 0.1397)
		(layer "In11.Cu")
		(net "TDR_DIFF_100_IN4_DIN")
	)
	(segment
		(start 253.193042 -456.442318)
		(end 253.066042 -456.315318)
		(width 0.1397)
		(layer "In11.Cu")
		(net "TDR_DIFF_100_IN4_DIN")
	)
	(segment
		(start 290.894008 -459.511146)
		(end 289.220656 -459.511146)
		(width 0.1397)
		(layer "In11.Cu")
		(net "TDR_DIFF_100_IN4_DIN")
	)
	(segment
		(start 253.066042 -456.315318)
		(end 251.666502 -456.315318)
		(width 0.1397)
		(layer "In11.Cu")
		(net "TDR_DIFF_100_IN4_DIN")
	)
	(segment
		(start 281.285696 -459.511146)
		(end 280.965402 -459.190852)
		(width 0.1397)
		(layer "In11.Cu")
		(net "TDR_DIFF_100_IN4_DIN")
	)
	(segment
		(start 247.572022 -456.442318)
		(end 247.572022 -459.190852)
		(width 0.1397)
		(layer "In11.Cu")
		(net "TDR_DIFF_100_IN4_DIN")
	)
	(segment
		(start 255.633982 -456.315318)
		(end 255.506982 -456.442318)
		(width 0.1397)
		(layer "In11.Cu")
		(net "TDR_DIFF_100_IN4_DIN")
	)
	(segment
		(start 251.539502 -459.190852)
		(end 251.219208 -459.511146)
		(width 0.1397)
		(layer "In11.Cu")
		(net "TDR_DIFF_100_IN4_DIN")
	)
	(segment
		(start 249.225562 -456.442318)
		(end 249.098562 -456.315318)
		(width 0.1397)
		(layer "In11.Cu")
		(net "TDR_DIFF_100_IN4_DIN")
	)
	(segment
		(start 261.128002 -459.190852)
		(end 261.128002 -456.442318)
		(width 0.1397)
		(layer "In11.Cu")
		(net "TDR_DIFF_100_IN4_DIN")
	)
	(segment
		(start 257.160522 -456.442318)
		(end 257.033522 -456.315318)
		(width 0.1397)
		(layer "In11.Cu")
		(net "TDR_DIFF_100_IN4_DIN")
	)
	(segment
		(start 283.406342 -456.315318)
		(end 283.279342 -456.442318)
		(width 0.1397)
		(layer "In11.Cu")
		(net "TDR_DIFF_100_IN4_DIN")
	)
	(segment
		(start 249.545856 -459.511146)
		(end 249.225562 -459.190852)
		(width 0.1397)
		(layer "In11.Cu")
		(net "TDR_DIFF_100_IN4_DIN")
	)
	(segment
		(start 289.220656 -459.511146)
		(end 288.900362 -459.190852)
		(width 0.1397)
		(layer "In11.Cu")
		(net "TDR_DIFF_100_IN4_DIN")
	)
	(segment
		(start 251.219208 -459.511146)
		(end 249.545856 -459.511146)
		(width 0.1397)
		(layer "In11.Cu")
		(net "TDR_DIFF_100_IN4_DIN")
	)
	(segment
		(start 237.196122 -456.315318)
		(end 235.796582 -456.315318)
		(width 0.1397)
		(layer "In11.Cu")
		(net "TDR_DIFF_100_IN4_DIN")
	)
	(segment
		(start 233.087164 -458.74559)
		(end 232.960164 -458.87259)
		(width 0.1397)
		(layer "In11.Cu")
		(net "TDR_DIFF_100_IN4_DIN")
	)
	(segment
		(start 251.539502 -456.442318)
		(end 251.539502 -459.190852)
		(width 0.1397)
		(layer "In11.Cu")
		(net "TDR_DIFF_100_IN4_DIN")
	)
	(segment
		(start 269.062962 -456.442318)
		(end 268.935962 -456.315318)
		(width 0.1397)
		(layer "In11.Cu")
		(net "TDR_DIFF_100_IN4_DIN")
	)
	(segment
		(start 287.246822 -459.190852)
		(end 286.926528 -459.511146)
		(width 0.1397)
		(layer "In11.Cu")
		(net "TDR_DIFF_100_IN4_DIN")
	)
	(segment
		(start 273.030442 -456.442318)
		(end 272.903442 -456.315318)
		(width 0.1397)
		(layer "In11.Cu")
		(net "TDR_DIFF_100_IN4_DIN")
	)
	(segment
		(start 241.290602 -459.190852)
		(end 241.290602 -456.442318)
		(width 0.1397)
		(layer "In11.Cu")
		(net "TDR_DIFF_100_IN4_DIN")
	)
	(segment
		(start 275.344382 -459.190852)
		(end 275.024088 -459.511146)
		(width 0.1397)
		(layer "In11.Cu")
		(net "TDR_DIFF_100_IN4_DIN")
	)
	(segment
		(start 237.323122 -459.1558)
		(end 237.323122 -456.442318)
		(width 0.1397)
		(layer "In11.Cu")
		(net "TDR_DIFF_100_IN4_DIN")
	)
	(segment
		(start 278.991568 -459.511146)
		(end 277.318216 -459.511146)
		(width 0.1397)
		(layer "In11.Cu")
		(net "TDR_DIFF_100_IN4_DIN")
	)
	(segment
		(start 253.193042 -459.190852)
		(end 253.193042 -456.442318)
		(width 0.1397)
		(layer "In11.Cu")
		(net "TDR_DIFF_100_IN4_DIN")
	)
	(segment
		(start 245.258082 -459.190852)
		(end 245.258082 -456.442318)
		(width 0.1397)
		(layer "In11.Cu")
		(net "TDR_DIFF_100_IN4_DIN")
	)
	(segment
		(start 263.441942 -456.442318)
		(end 263.441942 -459.190852)
		(width 0.1397)
		(layer "In11.Cu")
		(net "TDR_DIFF_100_IN4_DIN")
	)
	(segment
		(start 232.960164 -458.87259)
		(end 232.960164 -459.85049)
		(width 0.1397)
		(layer "In11.Cu")
		(net "TDR_DIFF_100_IN4_DIN")
	)
	(segment
		(start 291.214302 -456.442318)
		(end 291.214302 -459.190852)
		(width 0.1397)
		(layer "In11.Cu")
		(net "TDR_DIFF_100_IN4_DIN")
	)
	(segment
		(start 267.409422 -456.442318)
		(end 267.409422 -459.190852)
		(width 0.1397)
		(layer "In11.Cu")
		(net "TDR_DIFF_100_IN4_DIN")
	)
	(segment
		(start 253.513336 -459.511146)
		(end 253.193042 -459.190852)
		(width 0.1397)
		(layer "In11.Cu")
		(net "TDR_DIFF_100_IN4_DIN")
	)
	(segment
		(start 271.376902 -456.442318)
		(end 271.376902 -459.190852)
		(width 0.1397)
		(layer "In11.Cu")
		(net "TDR_DIFF_100_IN4_DIN")
	)
	(segment
		(start 249.225562 -459.190852)
		(end 249.225562 -456.442318)
		(width 0.1397)
		(layer "In11.Cu")
		(net "TDR_DIFF_100_IN4_DIN")
	)
	(segment
		(start 267.089128 -459.511146)
		(end 265.415776 -459.511146)
		(width 0.1397)
		(layer "In11.Cu")
		(net "TDR_DIFF_100_IN4_DIN")
	)
	(segment
		(start 280.965402 -459.190852)
		(end 280.965402 -456.442318)
		(width 0.1397)
		(layer "In11.Cu")
		(net "TDR_DIFF_100_IN4_DIN")
	)
	(segment
		(start 241.163602 -456.315318)
		(end 239.764062 -456.315318)
		(width 0.1397)
		(layer "In11.Cu")
		(net "TDR_DIFF_100_IN4_DIN")
	)
	(segment
		(start 259.154168 -459.511146)
		(end 257.480816 -459.511146)
		(width 0.1397)
		(layer "In11.Cu")
		(net "TDR_DIFF_100_IN4_DIN")
	)
	(segment
		(start 237.643416 -459.476094)
		(end 237.323122 -459.1558)
		(width 0.1397)
		(layer "In11.Cu")
		(net "TDR_DIFF_100_IN4_DIN")
	)
	(segment
		(start 292.740842 -456.315318)
		(end 291.341302 -456.315318)
		(width 0.1397)
		(layer "In11.Cu")
		(net "TDR_DIFF_100_IN4_DIN")
	)
	(segment
		(start 286.926528 -459.511146)
		(end 285.253176 -459.511146)
		(width 0.1397)
		(layer "In11.Cu")
		(net "TDR_DIFF_100_IN4_DIN")
	)
	(segment
		(start 271.503902 -456.315318)
		(end 271.376902 -456.442318)
		(width 0.1397)
		(layer "In11.Cu")
		(net "TDR_DIFF_100_IN4_DIN")
	)
	(segment
		(start 273.350736 -459.511146)
		(end 273.030442 -459.190852)
		(width 0.1397)
		(layer "In11.Cu")
		(net "TDR_DIFF_100_IN4_DIN")
	)
	(segment
		(start 273.030442 -459.190852)
		(end 273.030442 -456.442318)
		(width 0.1397)
		(layer "In11.Cu")
		(net "TDR_DIFF_100_IN4_DIN")
	)
	(segment
		(start 272.903442 -456.315318)
		(end 271.503902 -456.315318)
		(width 0.1397)
		(layer "In11.Cu")
		(net "TDR_DIFF_100_IN4_DIN")
	)
	(segment
		(start 284.805882 -456.315318)
		(end 283.406342 -456.315318)
		(width 0.1397)
		(layer "In11.Cu")
		(net "TDR_DIFF_100_IN4_DIN")
	)
	(segment
		(start 235.669582 -458.425296)
		(end 235.349288 -458.74559)
		(width 0.1397)
		(layer "In11.Cu")
		(net "TDR_DIFF_100_IN4_DIN")
	)
	(segment
		(start 235.669582 -456.442318)
		(end 235.669582 -458.425296)
		(width 0.1397)
		(layer "In11.Cu")
		(net "TDR_DIFF_100_IN4_DIN")
	)
	(segment
		(start 239.764062 -456.315318)
		(end 239.637062 -456.442318)
		(width 0.1397)
		(layer "In11.Cu")
		(net "TDR_DIFF_100_IN4_DIN")
	)
	(segment
		(start 239.637062 -456.442318)
		(end 239.637062 -459.1558)
		(width 0.1397)
		(layer "In11.Cu")
		(net "TDR_DIFF_100_IN4_DIN")
	)
	(segment
		(start 261.128002 -456.442318)
		(end 261.001002 -456.315318)
		(width 0.1397)
		(layer "In11.Cu")
		(net "TDR_DIFF_100_IN4_DIN")
	)
	(segment
		(start 263.441942 -459.190852)
		(end 263.121648 -459.511146)
		(width 0.1397)
		(layer "In11.Cu")
		(net "TDR_DIFF_100_IN4_DIN")
	)
	(segment
		(start 241.610896 -459.511146)
		(end 241.290602 -459.190852)
		(width 0.1397)
		(layer "In11.Cu")
		(net "TDR_DIFF_100_IN4_DIN")
	)
	(segment
		(start 237.323122 -456.442318)
		(end 237.196122 -456.315318)
		(width 0.1397)
		(layer "In11.Cu")
		(net "TDR_DIFF_100_IN4_DIN")
	)
	(segment
		(start 269.383256 -459.511146)
		(end 269.062962 -459.190852)
		(width 0.1397)
		(layer "In11.Cu")
		(net "TDR_DIFF_100_IN4_DIN")
	)
	(segment
		(start 276.997922 -456.442318)
		(end 276.870922 -456.315318)
		(width 0.1397)
		(layer "In11.Cu")
		(net "TDR_DIFF_100_IN4_DIN")
	)
	(segment
		(start 265.095482 -459.190852)
		(end 265.095482 -456.442318)
		(width 0.1397)
		(layer "In11.Cu")
		(net "TDR_DIFF_100_IN4_DIN")
	)
	(segment
		(start 239.637062 -459.1558)
		(end 239.316768 -459.476094)
		(width 0.1397)
		(layer "In11.Cu")
		(net "TDR_DIFF_100_IN4_DIN")
	)
	(segment
		(start 283.279342 -459.190852)
		(end 282.959048 -459.511146)
		(width 0.1397)
		(layer "In11.Cu")
		(net "TDR_DIFF_100_IN4_DIN")
	)
	(segment
		(start 245.131082 -456.315318)
		(end 243.731542 -456.315318)
		(width 0.1397)
		(layer "In11.Cu")
		(net "TDR_DIFF_100_IN4_DIN")
	)
	(segment
		(start 247.572022 -459.190852)
		(end 247.251728 -459.511146)
		(width 0.1397)
		(layer "In11.Cu")
		(net "TDR_DIFF_100_IN4_DIN")
	)
	(segment
		(start 259.601462 -456.315318)
		(end 259.474462 -456.442318)
		(width 0.1397)
		(layer "In11.Cu")
		(net "TDR_DIFF_100_IN4_DIN")
	)
	(segment
		(start 265.415776 -459.511146)
		(end 265.095482 -459.190852)
		(width 0.1397)
		(layer "In11.Cu")
		(net "TDR_DIFF_100_IN4_DIN")
	)
	(segment
		(start 257.480816 -459.511146)
		(end 257.160522 -459.190852)
		(width 0.1397)
		(layer "In11.Cu")
		(net "TDR_DIFF_100_IN4_DIN")
	)
	(segment
		(start 284.932882 -459.190852)
		(end 284.932882 -456.442318)
		(width 0.1397)
		(layer "In11.Cu")
		(net "TDR_DIFF_100_IN4_DIN")
	)
	(segment
		(start 275.024088 -459.511146)
		(end 273.350736 -459.511146)
		(width 0.1397)
		(layer "In11.Cu")
		(net "TDR_DIFF_100_IN4_DIN")
	)
	(segment
		(start 296.980864 -459.85049)
		(end 296.980864 -458.852778)
		(width 0.1397)
		(layer "In11.Cu")
		(net "TDR_DIFF_100_IN4_DIN")
	)
	(segment
		(start 268.935962 -456.315318)
		(end 267.536422 -456.315318)
		(width 0.1397)
		(layer "In11.Cu")
		(net "TDR_DIFF_100_IN4_DIN")
	)
	(segment
		(start 279.311862 -459.190852)
		(end 278.991568 -459.511146)
		(width 0.1397)
		(layer "In11.Cu")
		(net "TDR_DIFF_100_IN4_DIN")
	)
	(segment
		(start 255.506982 -456.442318)
		(end 255.506982 -459.190852)
		(width 0.1397)
		(layer "In11.Cu")
		(net "TDR_DIFF_100_IN4_DIN")
	)
	(segment
		(start 259.474462 -456.442318)
		(end 259.474462 -459.190852)
		(width 0.1397)
		(layer "In11.Cu")
		(net "TDR_DIFF_100_IN4_DIN")
	)
	(segment
		(start 276.870922 -456.315318)
		(end 275.471382 -456.315318)
		(width 0.1397)
		(layer "In11.Cu")
		(net "TDR_DIFF_100_IN4_DIN")
	)
	(segment
		(start 235.796582 -456.315318)
		(end 235.669582 -456.442318)
		(width 0.1397)
		(layer "In11.Cu")
		(net "TDR_DIFF_100_IN4_DIN")
	)
	(segment
		(start 284.932882 -456.442318)
		(end 284.805882 -456.315318)
		(width 0.1397)
		(layer "In11.Cu")
		(net "TDR_DIFF_100_IN4_DIN")
	)
	(segment
		(start 263.121648 -459.511146)
		(end 261.448296 -459.511146)
		(width 0.1397)
		(layer "In11.Cu")
		(net "TDR_DIFF_100_IN4_DIN")
	)
	(segment
		(start 247.251728 -459.511146)
		(end 245.578376 -459.511146)
		(width 0.1397)
		(layer "In11.Cu")
		(net "TDR_DIFF_100_IN4_DIN")
	)
	(segment
		(start 257.160522 -459.190852)
		(end 257.160522 -456.442318)
		(width 0.1397)
		(layer "In11.Cu")
		(net "TDR_DIFF_100_IN4_DIN")
	)
	(segment
		(start 267.536422 -456.315318)
		(end 267.409422 -456.442318)
		(width 0.1397)
		(layer "In11.Cu")
		(net "TDR_DIFF_100_IN4_DIN")
	)
	(segment
		(start 243.604542 -459.190852)
		(end 243.284248 -459.511146)
		(width 0.1397)
		(layer "In11.Cu")
		(net "TDR_DIFF_100_IN4_DIN")
	)
	(segment
		(start 249.098562 -456.315318)
		(end 247.699022 -456.315318)
		(width 0.1397)
		(layer "In11.Cu")
		(net "TDR_DIFF_100_IN4_DIN")
	)
	(segment
		(start 291.214302 -459.190852)
		(end 290.894008 -459.511146)
		(width 0.1397)
		(layer "In11.Cu")
		(net "TDR_DIFF_100_IN4_DIN")
	)
	(segment
		(start 243.731542 -456.315318)
		(end 243.604542 -456.442318)
		(width 0.1397)
		(layer "In11.Cu")
		(net "TDR_DIFF_100_IN4_DIN")
	)
	(segment
		(start 288.773362 -456.315318)
		(end 287.373822 -456.315318)
		(width 0.1397)
		(layer "In11.Cu")
		(net "TDR_DIFF_100_IN4_DIN")
	)
	(segment
		(start 241.290602 -456.442318)
		(end 241.163602 -456.315318)
		(width 0.1397)
		(layer "In11.Cu")
		(net "TDR_DIFF_100_IN4_DIN")
	)
	(segment
		(start 280.965402 -456.442318)
		(end 280.838402 -456.315318)
		(width 0.1397)
		(layer "In11.Cu")
		(net "TDR_DIFF_100_IN4_DIN")
	)
	(segment
		(start 263.568942 -456.315318)
		(end 263.441942 -456.442318)
		(width 0.1397)
		(layer "In11.Cu")
		(net "TDR_DIFF_100_IN4_DIN")
	)
	(segment
		(start 277.318216 -459.511146)
		(end 276.997922 -459.190852)
		(width 0.1397)
		(layer "In11.Cu")
		(net "TDR_DIFF_100_IN4_DIN")
	)
	(segment
		(start 265.095482 -456.442318)
		(end 264.968482 -456.315318)
		(width 0.1397)
		(layer "In11.Cu")
		(net "TDR_DIFF_100_IN4_DIN")
	)
	(segment
		(start 275.344382 -456.442318)
		(end 275.344382 -459.190852)
		(width 0.1397)
		(layer "In11.Cu")
		(net "TDR_DIFF_100_IN4_DIN")
	)
	(segment
		(start 239.316768 -459.476094)
		(end 237.643416 -459.476094)
		(width 0.1397)
		(layer "In11.Cu")
		(net "TDR_DIFF_100_IN4_DIN")
	)
	(segment
		(start 296.873676 -458.74559)
		(end 293.188136 -458.74559)
		(width 0.1397)
		(layer "In11.Cu")
		(net "TDR_DIFF_100_IN4_DIN")
	)
	(segment
		(start 280.838402 -456.315318)
		(end 279.438862 -456.315318)
		(width 0.1397)
		(layer "In11.Cu")
		(net "TDR_DIFF_100_IN4_DIN")
	)
	(segment
		(start 243.604542 -456.442318)
		(end 243.604542 -459.190852)
		(width 0.1397)
		(layer "In11.Cu")
		(net "TDR_DIFF_100_IN4_DIN")
	)
	(segment
		(start 287.246822 -456.442318)
		(end 287.246822 -459.190852)
		(width 0.1397)
		(layer "In11.Cu")
		(net "TDR_DIFF_100_IN4_DIN")
	)
	(segment
		(start 271.376902 -459.190852)
		(end 271.056608 -459.511146)
		(width 0.1397)
		(layer "In11.Cu")
		(net "TDR_DIFF_100_IN4_DIN")
	)
	(segment
		(start 271.056608 -459.511146)
		(end 269.383256 -459.511146)
		(width 0.1397)
		(layer "In11.Cu")
		(net "TDR_DIFF_100_IN4_DIN")
	)
	(segment
		(start 243.284248 -459.511146)
		(end 241.610896 -459.511146)
		(width 0.1397)
		(layer "In11.Cu")
		(net "TDR_DIFF_100_IN4_DIN")
	)
	(segment
		(start 292.867842 -456.442318)
		(end 292.740842 -456.315318)
		(width 0.1397)
		(layer "In11.Cu")
		(net "TDR_DIFF_100_IN4_DIN")
	)
	(segment
		(start 283.279342 -456.442318)
		(end 283.279342 -459.190852)
		(width 0.1397)
		(layer "In11.Cu")
		(net "TDR_DIFF_100_IN4_DIN")
	)
	(segment
		(start 317.830708 -303.635918)
		(end 317.957708 -303.508918)
		(width 0.13208)
		(layer "F.Cu")
		(net "SMB_PEX2_SLAVE1_SCL")
	)
	(segment
		(start 300.874938 -308.724808)
		(end 300.399958 -309.199788)
		(width 0.13208)
		(layer "F.Cu")
		(net "SMB_PEX2_SLAVE1_SCL")
	)
	(segment
		(start 317.830708 -304.5079)
		(end 317.830708 -303.635918)
		(width 0.13208)
		(layer "F.Cu")
		(net "SMB_PEX2_SLAVE1_SCL")
	)
	(segment
		(start 317.957708 -303.508918)
		(end 318.276224 -303.508918)
		(width 0.13208)
		(layer "F.Cu")
		(net "SMB_PEX2_SLAVE1_SCL")
	)
	(segment
		(start 300.399958 -309.199788)
		(end 300.399704 -309.199788)
		(width 0.13208)
		(layer "F.Cu")
		(net "SMB_PEX2_SLAVE1_SCL")
	)
	(via
		(at 300.874938 -308.724808)
		(size 0.4064)
		(drill 0.2032)
		(layers "F.Cu" "B.Cu")
		(net "SMB_PEX2_SLAVE1_SCL")
	)
	(via
		(at 318.276224 -303.508918)
		(size 0.508)
		(drill 0.254)
		(layers "F.Cu" "B.Cu")
		(net "SMB_PEX2_SLAVE1_SCL")
	)
	(segment
		(start 300.942756 -308.724808)
		(end 300.874938 -308.724808)
		(width 0.15494)
		(layer "In15.Cu")
		(net "SMB_PEX2_SLAVE1_SCL")
	)
	(segment
		(start 318.276224 -303.041304)
		(end 317.706248 -302.471328)
		(width 0.15494)
		(layer "In15.Cu")
		(net "SMB_PEX2_SLAVE1_SCL")
	)
	(segment
		(start 301.374556 -308.293008)
		(end 300.942756 -308.724808)
		(width 0.15494)
		(layer "In15.Cu")
		(net "SMB_PEX2_SLAVE1_SCL")
	)
	(segment
		(start 318.276224 -303.508918)
		(end 318.276224 -303.041304)
		(width 0.15494)
		(layer "In15.Cu")
		(net "SMB_PEX2_SLAVE1_SCL")
	)
	(segment
		(start 304.122582 -308.03977)
		(end 303.869344 -308.293008)
		(width 0.15494)
		(layer "In15.Cu")
		(net "SMB_PEX2_SLAVE1_SCL")
	)
	(segment
		(start 304.122582 -302.734218)
		(end 304.122582 -308.03977)
		(width 0.15494)
		(layer "In15.Cu")
		(net "SMB_PEX2_SLAVE1_SCL")
	)
	(segment
		(start 317.706248 -302.471328)
		(end 304.385472 -302.471328)
		(width 0.15494)
		(layer "In15.Cu")
		(net "SMB_PEX2_SLAVE1_SCL")
	)
	(segment
		(start 304.385472 -302.471328)
		(end 304.122582 -302.734218)
		(width 0.15494)
		(layer "In15.Cu")
		(net "SMB_PEX2_SLAVE1_SCL")
	)
	(segment
		(start 303.869344 -308.293008)
		(end 301.374556 -308.293008)
		(width 0.15494)
		(layer "In15.Cu")
		(net "SMB_PEX2_SLAVE1_SCL")
	)
	(segment
		(start 320.2432 -302.538384)
		(end 320.2432 -303.203864)
		(width 0.13208)
		(layer "F.Cu")
		(net "SMB_PEX2_SLAVE1_SDA")
	)
	(segment
		(start 320.2432 -303.203864)
		(end 320.235834 -303.21123)
		(width 0.13208)
		(layer "F.Cu")
		(net "SMB_PEX2_SLAVE1_SDA")
	)
	(segment
		(start 304.199798 -308.249828)
		(end 303.724818 -307.774848)
		(width 0.13208)
		(layer "F.Cu")
		(net "SMB_PEX2_SLAVE1_SDA")
	)
	(via
		(at 303.724818 -307.774848)
		(size 0.4064)
		(drill 0.2032)
		(layers "F.Cu" "B.Cu")
		(net "SMB_PEX2_SLAVE1_SDA")
	)
	(via
		(at 320.2432 -302.538384)
		(size 0.508)
		(drill 0.254)
		(layers "F.Cu" "B.Cu")
		(net "SMB_PEX2_SLAVE1_SDA")
	)
	(segment
		(start 304.52441 -300.637448)
		(end 304.202084 -300.959774)
		(width 0.15494)
		(layer "In15.Cu")
		(net "SMB_PEX2_SLAVE1_SDA")
	)
	(segment
		(start 318.478408 -302.538384)
		(end 316.577472 -300.637448)
		(width 0.15494)
		(layer "In15.Cu")
		(net "SMB_PEX2_SLAVE1_SDA")
	)
	(segment
		(start 304.202084 -301.38751)
		(end 304.062384 -301.52721)
		(width 0.15494)
		(layer "In15.Cu")
		(net "SMB_PEX2_SLAVE1_SDA")
	)
	(segment
		(start 304.202084 -300.959774)
		(end 304.202084 -301.38751)
		(width 0.15494)
		(layer "In15.Cu")
		(net "SMB_PEX2_SLAVE1_SDA")
	)
	(segment
		(start 303.230534 -307.497226)
		(end 303.508156 -307.774848)
		(width 0.15494)
		(layer "In15.Cu")
		(net "SMB_PEX2_SLAVE1_SDA")
	)
	(segment
		(start 303.508156 -307.774848)
		(end 303.724818 -307.774848)
		(width 0.15494)
		(layer "In15.Cu")
		(net "SMB_PEX2_SLAVE1_SDA")
	)
	(segment
		(start 320.2432 -302.538384)
		(end 318.478408 -302.538384)
		(width 0.15494)
		(layer "In15.Cu")
		(net "SMB_PEX2_SLAVE1_SDA")
	)
	(segment
		(start 303.230534 -302.268636)
		(end 303.230534 -307.497226)
		(width 0.15494)
		(layer "In15.Cu")
		(net "SMB_PEX2_SLAVE1_SDA")
	)
	(segment
		(start 303.234344 -301.927514)
		(end 303.234344 -302.264826)
		(width 0.15494)
		(layer "In15.Cu")
		(net "SMB_PEX2_SLAVE1_SDA")
	)
	(segment
		(start 316.577472 -300.637448)
		(end 304.52441 -300.637448)
		(width 0.15494)
		(layer "In15.Cu")
		(net "SMB_PEX2_SLAVE1_SDA")
	)
	(segment
		(start 304.062384 -301.52721)
		(end 303.634648 -301.52721)
		(width 0.15494)
		(layer "In15.Cu")
		(net "SMB_PEX2_SLAVE1_SDA")
	)
	(segment
		(start 303.634648 -301.52721)
		(end 303.234344 -301.927514)
		(width 0.15494)
		(layer "In15.Cu")
		(net "SMB_PEX2_SLAVE1_SDA")
	)
	(segment
		(start 303.234344 -302.264826)
		(end 303.230534 -302.268636)
		(width 0.15494)
		(layer "In15.Cu")
		(net "SMB_PEX2_SLAVE1_SDA")
	)
	(segment
		(start 420.299896 -308.249828)
		(end 419.824916 -307.774848)
		(width 0.13208)
		(layer "F.Cu")
		(net "SMB_PEX3_SLAVE1_SDA")
	)
	(segment
		(start 435.093364 -311.725564)
		(end 435.093364 -312.379614)
		(width 0.13208)
		(layer "F.Cu")
		(net "SMB_PEX3_SLAVE1_SDA")
	)
	(via
		(at 419.824916 -307.774848)
		(size 0.4064)
		(drill 0.2032)
		(layers "F.Cu" "B.Cu")
		(net "SMB_PEX3_SLAVE1_SDA")
	)
	(via
		(at 435.093364 -312.379614)
		(size 0.508)
		(drill 0.254)
		(layers "F.Cu" "B.Cu")
		(net "SMB_PEX3_SLAVE1_SDA")
	)
	(segment
		(start 420.300404 -307.29936)
		(end 422.5036 -307.29936)
		(width 0.15494)
		(layer "In11.Cu")
		(net "SMB_PEX3_SLAVE1_SDA")
	)
	(segment
		(start 435.222142 -310.837834)
		(end 437.66867 -310.837834)
		(width 0.15494)
		(layer "In11.Cu")
		(net "SMB_PEX3_SLAVE1_SDA")
	)
	(segment
		(start 437.797448 -311.148476)
		(end 437.66867 -311.277254)
		(width 0.15494)
		(layer "In11.Cu")
		(net "SMB_PEX3_SLAVE1_SDA")
	)
	(segment
		(start 433.233576 -307.721)
		(end 435.093364 -309.580788)
		(width 0.15494)
		(layer "In11.Cu")
		(net "SMB_PEX3_SLAVE1_SDA")
	)
	(segment
		(start 419.824916 -307.774848)
		(end 420.300404 -307.29936)
		(width 0.15494)
		(layer "In11.Cu")
		(net "SMB_PEX3_SLAVE1_SDA")
	)
	(segment
		(start 437.66867 -310.837834)
		(end 437.797448 -310.966612)
		(width 0.15494)
		(layer "In11.Cu")
		(net "SMB_PEX3_SLAVE1_SDA")
	)
	(segment
		(start 435.222142 -311.277254)
		(end 435.093364 -311.406032)
		(width 0.15494)
		(layer "In11.Cu")
		(net "SMB_PEX3_SLAVE1_SDA")
	)
	(segment
		(start 422.92524 -307.721)
		(end 433.233576 -307.721)
		(width 0.15494)
		(layer "In11.Cu")
		(net "SMB_PEX3_SLAVE1_SDA")
	)
	(segment
		(start 437.66867 -311.277254)
		(end 435.222142 -311.277254)
		(width 0.15494)
		(layer "In11.Cu")
		(net "SMB_PEX3_SLAVE1_SDA")
	)
	(segment
		(start 435.093364 -309.580788)
		(end 435.093364 -310.709056)
		(width 0.15494)
		(layer "In11.Cu")
		(net "SMB_PEX3_SLAVE1_SDA")
	)
	(segment
		(start 437.797448 -310.966612)
		(end 437.797448 -311.148476)
		(width 0.15494)
		(layer "In11.Cu")
		(net "SMB_PEX3_SLAVE1_SDA")
	)
	(segment
		(start 422.5036 -307.29936)
		(end 422.92524 -307.721)
		(width 0.15494)
		(layer "In11.Cu")
		(net "SMB_PEX3_SLAVE1_SDA")
	)
	(segment
		(start 435.093364 -310.709056)
		(end 435.222142 -310.837834)
		(width 0.15494)
		(layer "In11.Cu")
		(net "SMB_PEX3_SLAVE1_SDA")
	)
	(segment
		(start 435.093364 -311.406032)
		(end 435.093364 -312.379614)
		(width 0.15494)
		(layer "In11.Cu")
		(net "SMB_PEX3_SLAVE1_SDA")
	)
	(segment
		(start 434.02123 -311.72785)
		(end 434.02123 -312.320432)
		(width 0.13208)
		(layer "F.Cu")
		(net "SMB_PEX3_SLAVE1_SCL")
	)
	(segment
		(start 416.500056 -309.199788)
		(end 416.499802 -309.199788)
		(width 0.13208)
		(layer "F.Cu")
		(net "SMB_PEX3_SLAVE1_SCL")
	)
	(segment
		(start 434.02123 -312.320432)
		(end 434.54955 -312.848752)
		(width 0.13208)
		(layer "F.Cu")
		(net "SMB_PEX3_SLAVE1_SCL")
	)
	(segment
		(start 416.975036 -308.724808)
		(end 416.500056 -309.199788)
		(width 0.13208)
		(layer "F.Cu")
		(net "SMB_PEX3_SLAVE1_SCL")
	)
	(via
		(at 416.975036 -308.724808)
		(size 0.4064)
		(drill 0.2032)
		(layers "F.Cu" "B.Cu")
		(net "SMB_PEX3_SLAVE1_SCL")
	)
	(via
		(at 434.54955 -312.848752)
		(size 0.508)
		(drill 0.254)
		(layers "F.Cu" "B.Cu")
		(net "SMB_PEX3_SLAVE1_SCL")
	)
	(segment
		(start 434.54955 -309.904638)
		(end 434.54955 -312.848752)
		(width 0.15494)
		(layer "In11.Cu")
		(net "SMB_PEX3_SLAVE1_SCL")
	)
	(segment
		(start 422.960546 -308.7624)
		(end 433.407312 -308.7624)
		(width 0.15494)
		(layer "In11.Cu")
		(net "SMB_PEX3_SLAVE1_SCL")
	)
	(segment
		(start 416.975036 -308.724808)
		(end 417.48583 -308.214014)
		(width 0.15494)
		(layer "In11.Cu")
		(net "SMB_PEX3_SLAVE1_SCL")
	)
	(segment
		(start 422.41216 -308.214014)
		(end 422.960546 -308.7624)
		(width 0.15494)
		(layer "In11.Cu")
		(net "SMB_PEX3_SLAVE1_SCL")
	)
	(segment
		(start 433.407312 -308.7624)
		(end 434.54955 -309.904638)
		(width 0.15494)
		(layer "In11.Cu")
		(net "SMB_PEX3_SLAVE1_SCL")
	)
	(segment
		(start 417.48583 -308.214014)
		(end 422.41216 -308.214014)
		(width 0.15494)
		(layer "In11.Cu")
		(net "SMB_PEX3_SLAVE1_SCL")
	)
	(segment
		(start 184.29986 -309.199788)
		(end 184.300114 -309.199788)
		(width 0.13208)
		(layer "F.Cu")
		(net "SMB_PEX1_SLAVE1_SCL")
	)
	(segment
		(start 201.578718 -301.908464)
		(end 201.970386 -301.908464)
		(width 0.13208)
		(layer "F.Cu")
		(net "SMB_PEX1_SLAVE1_SCL")
	)
	(segment
		(start 201.311256 -302.175926)
		(end 201.578718 -301.908464)
		(width 0.13208)
		(layer "F.Cu")
		(net "SMB_PEX1_SLAVE1_SCL")
	)
	(segment
		(start 201.265028 -302.682656)
		(end 201.311256 -302.636428)
		(width 0.13208)
		(layer "F.Cu")
		(net "SMB_PEX1_SLAVE1_SCL")
	)
	(segment
		(start 184.300114 -309.199788)
		(end 184.775094 -308.724808)
		(width 0.13208)
		(layer "F.Cu")
		(net "SMB_PEX1_SLAVE1_SCL")
	)
	(segment
		(start 201.311256 -302.636428)
		(end 201.311256 -302.175926)
		(width 0.13208)
		(layer "F.Cu")
		(net "SMB_PEX1_SLAVE1_SCL")
	)
	(via
		(at 184.775094 -308.724808)
		(size 0.4064)
		(drill 0.2032)
		(layers "F.Cu" "B.Cu")
		(net "SMB_PEX1_SLAVE1_SCL")
	)
	(via
		(at 201.265028 -302.682656)
		(size 0.508)
		(drill 0.254)
		(layers "F.Cu" "B.Cu")
		(net "SMB_PEX1_SLAVE1_SCL")
	)
	(segment
		(start 200.020174 -303.428654)
		(end 195.920614 -303.428654)
		(width 0.15494)
		(layer "In5.Cu")
		(net "SMB_PEX1_SLAVE1_SCL")
	)
	(segment
		(start 186.067192 -309.277512)
		(end 185.327798 -309.277512)
		(width 0.15494)
		(layer "In5.Cu")
		(net "SMB_PEX1_SLAVE1_SCL")
	)
	(segment
		(start 195.224908 -304.12436)
		(end 195.224908 -311.4802)
		(width 0.15494)
		(layer "In5.Cu")
		(net "SMB_PEX1_SLAVE1_SCL")
	)
	(segment
		(start 200.958958 -302.988726)
		(end 200.460102 -302.988726)
		(width 0.15494)
		(layer "In5.Cu")
		(net "SMB_PEX1_SLAVE1_SCL")
	)
	(segment
		(start 200.460102 -302.988726)
		(end 200.020174 -303.428654)
		(width 0.15494)
		(layer "In5.Cu")
		(net "SMB_PEX1_SLAVE1_SCL")
	)
	(segment
		(start 201.265028 -302.682656)
		(end 200.958958 -302.988726)
		(width 0.15494)
		(layer "In5.Cu")
		(net "SMB_PEX1_SLAVE1_SCL")
	)
	(segment
		(start 186.7154 -311.4802)
		(end 186.7154 -309.92572)
		(width 0.15494)
		(layer "In5.Cu")
		(net "SMB_PEX1_SLAVE1_SCL")
	)
	(segment
		(start 195.920614 -303.428654)
		(end 195.224908 -304.12436)
		(width 0.15494)
		(layer "In5.Cu")
		(net "SMB_PEX1_SLAVE1_SCL")
	)
	(segment
		(start 195.097908 -311.6072)
		(end 186.8424 -311.6072)
		(width 0.15494)
		(layer "In5.Cu")
		(net "SMB_PEX1_SLAVE1_SCL")
	)
	(segment
		(start 185.327798 -309.277512)
		(end 184.775094 -308.724808)
		(width 0.15494)
		(layer "In5.Cu")
		(net "SMB_PEX1_SLAVE1_SCL")
	)
	(segment
		(start 186.8424 -311.6072)
		(end 186.7154 -311.4802)
		(width 0.15494)
		(layer "In5.Cu")
		(net "SMB_PEX1_SLAVE1_SCL")
	)
	(segment
		(start 186.7154 -309.92572)
		(end 186.067192 -309.277512)
		(width 0.15494)
		(layer "In5.Cu")
		(net "SMB_PEX1_SLAVE1_SCL")
	)
	(segment
		(start 195.224908 -311.4802)
		(end 195.097908 -311.6072)
		(width 0.15494)
		(layer "In5.Cu")
		(net "SMB_PEX1_SLAVE1_SCL")
	)
	(segment
		(start 188.099954 -308.249828)
		(end 187.624974 -307.774848)
		(width 0.13208)
		(layer "F.Cu")
		(net "SMB_PEX1_SLAVE1_SDA")
	)
	(segment
		(start 204.255878 -303.050448)
		(end 204.332332 -303.050448)
		(width 0.13208)
		(layer "F.Cu")
		(net "SMB_PEX1_SLAVE1_SDA")
	)
	(segment
		(start 203.792582 -303.513744)
		(end 204.255878 -303.050448)
		(width 0.13208)
		(layer "F.Cu")
		(net "SMB_PEX1_SLAVE1_SDA")
	)
	(via
		(at 204.332332 -303.050448)
		(size 0.508)
		(drill 0.254)
		(layers "F.Cu" "B.Cu")
		(net "SMB_PEX1_SLAVE1_SDA")
	)
	(via
		(at 187.624974 -307.774848)
		(size 0.4064)
		(drill 0.2032)
		(layers "F.Cu" "B.Cu")
		(net "SMB_PEX1_SLAVE1_SDA")
	)
	(segment
		(start 194.896232 -302.521874)
		(end 200.009506 -302.521874)
		(width 0.15494)
		(layer "In5.Cu")
		(net "SMB_PEX1_SLAVE1_SDA")
	)
	(segment
		(start 200.487534 -302.043846)
		(end 202.066652 -302.043846)
		(width 0.15494)
		(layer "In5.Cu")
		(net "SMB_PEX1_SLAVE1_SDA")
	)
	(segment
		(start 187.624974 -308.036976)
		(end 188.10097 -308.512972)
		(width 0.15494)
		(layer "In5.Cu")
		(net "SMB_PEX1_SLAVE1_SDA")
	)
	(segment
		(start 188.10097 -308.512972)
		(end 188.10097 -309.5244)
		(width 0.15494)
		(layer "In5.Cu")
		(net "SMB_PEX1_SLAVE1_SDA")
	)
	(segment
		(start 187.624974 -307.774848)
		(end 187.624974 -308.036976)
		(width 0.15494)
		(layer "In5.Cu")
		(net "SMB_PEX1_SLAVE1_SDA")
	)
	(segment
		(start 194.3354 -303.082706)
		(end 194.896232 -302.521874)
		(width 0.15494)
		(layer "In5.Cu")
		(net "SMB_PEX1_SLAVE1_SDA")
	)
	(segment
		(start 203.725018 -302.104298)
		(end 204.08773 -302.46701)
		(width 0.15494)
		(layer "In5.Cu")
		(net "SMB_PEX1_SLAVE1_SDA")
	)
	(segment
		(start 194.3354 -309.5244)
		(end 194.3354 -303.082706)
		(width 0.15494)
		(layer "In5.Cu")
		(net "SMB_PEX1_SLAVE1_SDA")
	)
	(segment
		(start 203.076302 -302.32731)
		(end 203.299314 -302.104298)
		(width 0.15494)
		(layer "In5.Cu")
		(net "SMB_PEX1_SLAVE1_SDA")
	)
	(segment
		(start 202.066652 -302.043846)
		(end 202.350116 -302.32731)
		(width 0.15494)
		(layer "In5.Cu")
		(net "SMB_PEX1_SLAVE1_SDA")
	)
	(segment
		(start 204.08773 -302.46701)
		(end 204.08773 -302.805846)
		(width 0.15494)
		(layer "In5.Cu")
		(net "SMB_PEX1_SLAVE1_SDA")
	)
	(segment
		(start 188.22797 -309.6514)
		(end 194.2084 -309.6514)
		(width 0.15494)
		(layer "In5.Cu")
		(net "SMB_PEX1_SLAVE1_SDA")
	)
	(segment
		(start 202.350116 -302.32731)
		(end 203.076302 -302.32731)
		(width 0.15494)
		(layer "In5.Cu")
		(net "SMB_PEX1_SLAVE1_SDA")
	)
	(segment
		(start 204.08773 -302.805846)
		(end 204.332332 -303.050448)
		(width 0.15494)
		(layer "In5.Cu")
		(net "SMB_PEX1_SLAVE1_SDA")
	)
	(segment
		(start 203.299314 -302.104298)
		(end 203.725018 -302.104298)
		(width 0.15494)
		(layer "In5.Cu")
		(net "SMB_PEX1_SLAVE1_SDA")
	)
	(segment
		(start 188.10097 -309.5244)
		(end 188.22797 -309.6514)
		(width 0.15494)
		(layer "In5.Cu")
		(net "SMB_PEX1_SLAVE1_SDA")
	)
	(segment
		(start 200.009506 -302.521874)
		(end 200.487534 -302.043846)
		(width 0.15494)
		(layer "In5.Cu")
		(net "SMB_PEX1_SLAVE1_SDA")
	)
	(segment
		(start 194.2084 -309.6514)
		(end 194.3354 -309.5244)
		(width 0.15494)
		(layer "In5.Cu")
		(net "SMB_PEX1_SLAVE1_SDA")
	)
	(segment
		(start 252.434344 -212.934296)
		(end 252.789436 -212.934296)
		(width 0.13208)
		(layer "F.Cu")
		(net "PWRGD_P1V2_AUX")
	)
	(segment
		(start 251.384562 -211.884514)
		(end 252.434344 -212.934296)
		(width 0.13208)
		(layer "F.Cu")
		(net "PWRGD_P1V2_AUX")
	)
	(segment
		(start 251.384562 -211.11464)
		(end 251.384562 -211.884514)
		(width 0.13208)
		(layer "F.Cu")
		(net "PWRGD_P1V2_AUX")
	)
	(segment
		(start 250.133612 -210.606386)
		(end 250.133612 -209.590386)
		(width 0.13208)
		(layer "F.Cu")
		(net "PWRGD_P1V2_AUX")
	)
	(segment
		(start 250.133612 -210.606386)
		(end 250.876308 -210.606386)
		(width 0.13208)
		(layer "F.Cu")
		(net "PWRGD_P1V2_AUX")
	)
	(segment
		(start 250.876308 -210.606386)
		(end 251.384562 -211.11464)
		(width 0.13208)
		(layer "F.Cu")
		(net "PWRGD_P1V2_AUX")
	)
	(via
		(at 250.876308 -210.606386)
		(size 0.508)
		(drill 0.254)
		(layers "F.Cu" "B.Cu")
		(net "PWRGD_P1V2_AUX")
	)
	(segment
		(start 250.876562 -212.638386)
		(end 250.133612 -212.638386)
		(width 0.13208)
		(layer "F.Cu")
		(net "P1V2_AUX_ADJ")
	)
	(segment
		(start 252.789436 -213.434168)
		(end 251.672344 -213.434168)
		(width 0.13208)
		(layer "F.Cu")
		(net "P1V2_AUX_ADJ")
	)
	(segment
		(start 251.672344 -213.434168)
		(end 250.876562 -212.638386)
		(width 0.13208)
		(layer "F.Cu")
		(net "P1V2_AUX_ADJ")
	)
	(segment
		(start 250.133612 -211.622386)
		(end 250.133612 -212.638386)
		(width 0.13208)
		(layer "F.Cu")
		(net "P1V2_AUX_ADJ")
	)
	(via
		(at 250.876562 -212.638386)
		(size 0.508)
		(drill 0.254)
		(layers "F.Cu" "B.Cu")
		(net "P1V2_AUX_ADJ")
	)
	(segment
		(start 247.273064 -210.288378)
		(end 247.27154 -211.276946)
		(width 0.13208)
		(layer "F.Cu")
		(net "HSC_TYPE_ADC_R")
	)
	(segment
		(start 247.27154 -211.276946)
		(end 247.27154 -212.087714)
		(width 0.13208)
		(layer "F.Cu")
		(net "HSC_TYPE_ADC_R")
	)
	(segment
		(start 235.867448 -219.504006)
		(end 235.467652 -219.10421)
		(width 0.13208)
		(layer "F.Cu")
		(net "HSC_TYPE_ADC_R")
	)
	(via
		(at 247.27154 -212.087714)
		(size 0.508)
		(drill 0.254)
		(layers "F.Cu" "B.Cu")
		(net "HSC_TYPE_ADC_R")
	)
	(via
		(at 235.867448 -219.504006)
		(size 0.4572)
		(drill 0.254)
		(layers "F.Cu" "B.Cu")
		(net "HSC_TYPE_ADC_R")
	)
	(via
		(at 229.660958 -345.42857)
		(size 0.508)
		(drill 0.254)
		(layers "F.Cu" "B.Cu")
		(net "HSC_TYPE_ADC_R")
	)
	(segment
		(start 251.19203 -345.117674)
		(end 252.423168 -346.348812)
		(width 0.13208)
		(layer "B.Cu")
		(net "HSC_TYPE_ADC_R")
	)
	(segment
		(start 254.996696 -350.844104)
		(end 252.984 -352.8568)
		(width 0.13208)
		(layer "B.Cu")
		(net "HSC_TYPE_ADC_R")
	)
	(segment
		(start 252.984 -352.8568)
		(end 252.41885 -352.8568)
		(width 0.13208)
		(layer "B.Cu")
		(net "HSC_TYPE_ADC_R")
	)
	(segment
		(start 230.160322 -344.929206)
		(end 229.660958 -345.42857)
		(width 0.13208)
		(layer "B.Cu")
		(net "HSC_TYPE_ADC_R")
	)
	(segment
		(start 254.996696 -347.503496)
		(end 254.996696 -350.844104)
		(width 0.13208)
		(layer "B.Cu")
		(net "HSC_TYPE_ADC_R")
	)
	(segment
		(start 249.52579 -344.929206)
		(end 230.160322 -344.929206)
		(width 0.13208)
		(layer "B.Cu")
		(net "HSC_TYPE_ADC_R")
	)
	(segment
		(start 250.272296 -345.117674)
		(end 251.19203 -345.117674)
		(width 0.13208)
		(layer "B.Cu")
		(net "HSC_TYPE_ADC_R")
	)
	(segment
		(start 249.714258 -345.117674)
		(end 249.52579 -344.929206)
		(width 0.13208)
		(layer "B.Cu")
		(net "HSC_TYPE_ADC_R")
	)
	(segment
		(start 253.842012 -346.348812)
		(end 254.996696 -347.503496)
		(width 0.13208)
		(layer "B.Cu")
		(net "HSC_TYPE_ADC_R")
	)
	(segment
		(start 250.272296 -345.117674)
		(end 249.714258 -345.117674)
		(width 0.13208)
		(layer "B.Cu")
		(net "HSC_TYPE_ADC_R")
	)
	(segment
		(start 252.423168 -346.348812)
		(end 253.842012 -346.348812)
		(width 0.13208)
		(layer "B.Cu")
		(net "HSC_TYPE_ADC_R")
	)
	(segment
		(start 233.613706 -310.320182)
		(end 233.613706 -330.201524)
		(width 0.15494)
		(layer "In5.Cu")
		(net "HSC_TYPE_ADC_R")
	)
	(segment
		(start 231.46512 -223.69272)
		(end 231.46512 -230.962454)
		(width 0.15494)
		(layer "In5.Cu")
		(net "HSC_TYPE_ADC_R")
	)
	(segment
		(start 233.613706 -249.819922)
		(end 233.613706 -281.590242)
		(width 0.15494)
		(layer "In5.Cu")
		(net "HSC_TYPE_ADC_R")
	)
	(segment
		(start 229.028752 -245.234968)
		(end 233.613706 -249.819922)
		(width 0.15494)
		(layer "In5.Cu")
		(net "HSC_TYPE_ADC_R")
	)
	(segment
		(start 234.787186 -219.902278)
		(end 234.666536 -220.022928)
		(width 0.0889)
		(layer "In5.Cu")
		(net "HSC_TYPE_ADC_R")
	)
	(segment
		(start 233.62793 -310.305958)
		(end 233.613706 -310.320182)
		(width 0.15494)
		(layer "In5.Cu")
		(net "HSC_TYPE_ADC_R")
	)
	(segment
		(start 229.028752 -239.701578)
		(end 229.028752 -245.234968)
		(width 0.15494)
		(layer "In5.Cu")
		(net "HSC_TYPE_ADC_R")
	)
	(segment
		(start 231.46512 -222.443294)
		(end 231.46512 -223.69272)
		(width 0.0889)
		(layer "In5.Cu")
		(net "HSC_TYPE_ADC_R")
	)
	(segment
		(start 230.94696 -231.480614)
		(end 229.60584 -231.480614)
		(width 0.15494)
		(layer "In5.Cu")
		(net "HSC_TYPE_ADC_R")
	)
	(segment
		(start 233.613706 -281.590242)
		(end 233.62793 -281.604466)
		(width 0.15494)
		(layer "In5.Cu")
		(net "HSC_TYPE_ADC_R")
	)
	(segment
		(start 229.84206 -333.97317)
		(end 229.84206 -345.247468)
		(width 0.15494)
		(layer "In5.Cu")
		(net "HSC_TYPE_ADC_R")
	)
	(segment
		(start 231.46512 -230.962454)
		(end 230.94696 -231.480614)
		(width 0.15494)
		(layer "In5.Cu")
		(net "HSC_TYPE_ADC_R")
	)
	(segment
		(start 229.2604 -237.582964)
		(end 229.54488 -237.867444)
		(width 0.15494)
		(layer "In5.Cu")
		(net "HSC_TYPE_ADC_R")
	)
	(segment
		(start 233.613706 -330.201524)
		(end 229.84206 -333.97317)
		(width 0.15494)
		(layer "In5.Cu")
		(net "HSC_TYPE_ADC_R")
	)
	(segment
		(start 229.2604 -231.826054)
		(end 229.2604 -237.582964)
		(width 0.15494)
		(layer "In5.Cu")
		(net "HSC_TYPE_ADC_R")
	)
	(segment
		(start 231.603042 -222.305372)
		(end 231.46512 -222.443294)
		(width 0.0889)
		(layer "In5.Cu")
		(net "HSC_TYPE_ADC_R")
	)
	(segment
		(start 234.666536 -222.094806)
		(end 234.45597 -222.305372)
		(width 0.0889)
		(layer "In5.Cu")
		(net "HSC_TYPE_ADC_R")
	)
	(segment
		(start 229.84206 -345.247468)
		(end 229.660958 -345.42857)
		(width 0.15494)
		(layer "In5.Cu")
		(net "HSC_TYPE_ADC_R")
	)
	(segment
		(start 229.54488 -239.18545)
		(end 229.028752 -239.701578)
		(width 0.15494)
		(layer "In5.Cu")
		(net "HSC_TYPE_ADC_R")
	)
	(segment
		(start 233.62793 -281.604466)
		(end 233.62793 -310.305958)
		(width 0.15494)
		(layer "In5.Cu")
		(net "HSC_TYPE_ADC_R")
	)
	(segment
		(start 234.666536 -220.022928)
		(end 234.666536 -222.094806)
		(width 0.0889)
		(layer "In5.Cu")
		(net "HSC_TYPE_ADC_R")
	)
	(segment
		(start 229.60584 -231.480614)
		(end 229.2604 -231.826054)
		(width 0.15494)
		(layer "In5.Cu")
		(net "HSC_TYPE_ADC_R")
	)
	(segment
		(start 235.867448 -219.504006)
		(end 235.469176 -219.902278)
		(width 0.0889)
		(layer "In5.Cu")
		(net "HSC_TYPE_ADC_R")
	)
	(segment
		(start 234.45597 -222.305372)
		(end 231.603042 -222.305372)
		(width 0.0889)
		(layer "In5.Cu")
		(net "HSC_TYPE_ADC_R")
	)
	(segment
		(start 229.54488 -237.867444)
		(end 229.54488 -239.18545)
		(width 0.15494)
		(layer "In5.Cu")
		(net "HSC_TYPE_ADC_R")
	)
	(segment
		(start 235.469176 -219.902278)
		(end 234.787186 -219.902278)
		(width 0.0889)
		(layer "In5.Cu")
		(net "HSC_TYPE_ADC_R")
	)
	(segment
		(start 245.003574 -216.35466)
		(end 245.003574 -217.728038)
		(width 0.15494)
		(layer "In15.Cu")
		(net "HSC_TYPE_ADC_R")
	)
	(segment
		(start 239.025938 -220.543374)
		(end 237.98657 -219.504006)
		(width 0.15494)
		(layer "In15.Cu")
		(net "HSC_TYPE_ADC_R")
	)
	(segment
		(start 247.27154 -212.087714)
		(end 246.89054 -212.468714)
		(width 0.15494)
		(layer "In15.Cu")
		(net "HSC_TYPE_ADC_R")
	)
	(segment
		(start 243.0526 -219.679012)
		(end 242.425728 -219.679012)
		(width 0.15494)
		(layer "In15.Cu")
		(net "HSC_TYPE_ADC_R")
	)
	(segment
		(start 245.003574 -217.728038)
		(end 243.0526 -219.679012)
		(width 0.15494)
		(layer "In15.Cu")
		(net "HSC_TYPE_ADC_R")
	)
	(segment
		(start 237.98657 -219.504006)
		(end 235.867448 -219.504006)
		(width 0.15494)
		(layer "In15.Cu")
		(net "HSC_TYPE_ADC_R")
	)
	(segment
		(start 246.89054 -214.467694)
		(end 245.003574 -216.35466)
		(width 0.15494)
		(layer "In15.Cu")
		(net "HSC_TYPE_ADC_R")
	)
	(segment
		(start 242.425728 -219.679012)
		(end 241.561366 -220.543374)
		(width 0.15494)
		(layer "In15.Cu")
		(net "HSC_TYPE_ADC_R")
	)
	(segment
		(start 246.89054 -212.468714)
		(end 246.89054 -214.467694)
		(width 0.15494)
		(layer "In15.Cu")
		(net "HSC_TYPE_ADC_R")
	)
	(segment
		(start 241.561366 -220.543374)
		(end 239.025938 -220.543374)
		(width 0.15494)
		(layer "In15.Cu")
		(net "HSC_TYPE_ADC_R")
	)
	(segment
		(start 457.211684 -364.085378)
		(end 457.211684 -365.143034)
		(width 0.13208)
		(layer "F.Cu")
		(net "GPU_3V3IO_RSVD4_ISO_R")
	)
	(segment
		(start 334.09382 -214.387176)
		(end 333.694024 -213.98738)
		(width 0.13208)
		(layer "F.Cu")
		(net "GPU_3V3IO_RSVD4_ISO_R")
	)
	(segment
		(start 457.410566 -363.886496)
		(end 457.211684 -364.085378)
		(width 0.13208)
		(layer "F.Cu")
		(net "GPU_3V3IO_RSVD4_ISO_R")
	)
	(segment
		(start 460.299308 -363.886496)
		(end 457.410566 -363.886496)
		(width 0.13208)
		(layer "F.Cu")
		(net "GPU_3V3IO_RSVD4_ISO_R")
	)
	(via
		(at 333.694024 -213.98738)
		(size 0.4572)
		(drill 0.254)
		(layers "F.Cu" "B.Cu")
		(net "GPU_3V3IO_RSVD4_ISO_R")
	)
	(via
		(at 386.830316 -228.079554)
		(size 0.508)
		(drill 0.254)
		(layers "F.Cu" "B.Cu")
		(net "GPU_3V3IO_RSVD4_ISO_R")
	)
	(via
		(at 353.197414 -228.621844)
		(size 0.508)
		(drill 0.254)
		(layers "F.Cu" "B.Cu")
		(net "GPU_3V3IO_RSVD4_ISO_R")
	)
	(via
		(at 460.299308 -363.886496)
		(size 0.508)
		(drill 0.254)
		(layers "F.Cu" "B.Cu")
		(net "GPU_3V3IO_RSVD4_ISO_R")
	)
	(segment
		(start 443.248796 -304.862738)
		(end 442.242956 -305.868578)
		(width 0.13208)
		(layer "B.Cu")
		(net "GPU_3V3IO_RSVD4_ISO_R")
	)
	(segment
		(start 394.654024 -249.79503)
		(end 416.551618 -249.79503)
		(width 0.13208)
		(layer "B.Cu")
		(net "GPU_3V3IO_RSVD4_ISO_R")
	)
	(segment
		(start 445.779144 -256.969514)
		(end 445.779144 -282.868878)
		(width 0.13208)
		(layer "B.Cu")
		(net "GPU_3V3IO_RSVD4_ISO_R")
	)
	(segment
		(start 449.625974 -322.892166)
		(end 457.179172 -322.892166)
		(width 0.13208)
		(layer "B.Cu")
		(net "GPU_3V3IO_RSVD4_ISO_R")
	)
	(segment
		(start 442.087 -248.896378)
		(end 444.707264 -248.896378)
		(width 0.13208)
		(layer "B.Cu")
		(net "GPU_3V3IO_RSVD4_ISO_R")
	)
	(segment
		(start 460.299308 -363.375194)
		(end 460.299308 -363.886496)
		(width 0.13208)
		(layer "B.Cu")
		(net "GPU_3V3IO_RSVD4_ISO_R")
	)
	(segment
		(start 391.474452 -246.615458)
		(end 394.654024 -249.79503)
		(width 0.13208)
		(layer "B.Cu")
		(net "GPU_3V3IO_RSVD4_ISO_R")
	)
	(segment
		(start 444.707264 -248.896378)
		(end 445.9986 -250.187714)
		(width 0.13208)
		(layer "B.Cu")
		(net "GPU_3V3IO_RSVD4_ISO_R")
	)
	(segment
		(start 416.551618 -249.79503)
		(end 417.213034 -250.456446)
		(width 0.13208)
		(layer "B.Cu")
		(net "GPU_3V3IO_RSVD4_ISO_R")
	)
	(segment
		(start 450.54012 -250.187714)
		(end 452.71309 -252.360684)
		(width 0.13208)
		(layer "B.Cu")
		(net "GPU_3V3IO_RSVD4_ISO_R")
	)
	(segment
		(start 442.242956 -305.868578)
		(end 442.242956 -308.308756)
		(width 0.13208)
		(layer "B.Cu")
		(net "GPU_3V3IO_RSVD4_ISO_R")
	)
	(segment
		(start 443.248796 -285.399226)
		(end 443.248796 -304.862738)
		(width 0.13208)
		(layer "B.Cu")
		(net "GPU_3V3IO_RSVD4_ISO_R")
	)
	(segment
		(start 448.954906 -253.793752)
		(end 445.779144 -256.969514)
		(width 0.13208)
		(layer "B.Cu")
		(net "GPU_3V3IO_RSVD4_ISO_R")
	)
	(segment
		(start 440.526932 -250.456446)
		(end 442.087 -248.896378)
		(width 0.13208)
		(layer "B.Cu")
		(net "GPU_3V3IO_RSVD4_ISO_R")
	)
	(segment
		(start 386.957062 -228.079554)
		(end 391.474452 -232.596944)
		(width 0.13208)
		(layer "B.Cu")
		(net "GPU_3V3IO_RSVD4_ISO_R")
	)
	(segment
		(start 391.474452 -232.596944)
		(end 391.474452 -246.615458)
		(width 0.13208)
		(layer "B.Cu")
		(net "GPU_3V3IO_RSVD4_ISO_R")
	)
	(segment
		(start 465.360258 -331.073252)
		(end 465.360258 -358.314244)
		(width 0.13208)
		(layer "B.Cu")
		(net "GPU_3V3IO_RSVD4_ISO_R")
	)
	(segment
		(start 452.243444 -253.793752)
		(end 448.954906 -253.793752)
		(width 0.13208)
		(layer "B.Cu")
		(net "GPU_3V3IO_RSVD4_ISO_R")
	)
	(segment
		(start 441.017914 -309.533798)
		(end 441.017914 -314.284106)
		(width 0.13208)
		(layer "B.Cu")
		(net "GPU_3V3IO_RSVD4_ISO_R")
	)
	(segment
		(start 417.213034 -250.456446)
		(end 440.526932 -250.456446)
		(width 0.13208)
		(layer "B.Cu")
		(net "GPU_3V3IO_RSVD4_ISO_R")
	)
	(segment
		(start 386.830316 -228.079554)
		(end 386.957062 -228.079554)
		(width 0.13208)
		(layer "B.Cu")
		(net "GPU_3V3IO_RSVD4_ISO_R")
	)
	(segment
		(start 452.71309 -252.360684)
		(end 452.71309 -253.324106)
		(width 0.13208)
		(layer "B.Cu")
		(net "GPU_3V3IO_RSVD4_ISO_R")
	)
	(segment
		(start 441.017914 -314.284106)
		(end 449.625974 -322.892166)
		(width 0.13208)
		(layer "B.Cu")
		(net "GPU_3V3IO_RSVD4_ISO_R")
	)
	(segment
		(start 442.242956 -308.308756)
		(end 441.017914 -309.533798)
		(width 0.13208)
		(layer "B.Cu")
		(net "GPU_3V3IO_RSVD4_ISO_R")
	)
	(segment
		(start 445.9986 -250.187714)
		(end 450.54012 -250.187714)
		(width 0.13208)
		(layer "B.Cu")
		(net "GPU_3V3IO_RSVD4_ISO_R")
	)
	(segment
		(start 457.179172 -322.892166)
		(end 465.360258 -331.073252)
		(width 0.13208)
		(layer "B.Cu")
		(net "GPU_3V3IO_RSVD4_ISO_R")
	)
	(segment
		(start 452.71309 -253.324106)
		(end 452.243444 -253.793752)
		(width 0.13208)
		(layer "B.Cu")
		(net "GPU_3V3IO_RSVD4_ISO_R")
	)
	(segment
		(start 465.360258 -358.314244)
		(end 460.299308 -363.375194)
		(width 0.13208)
		(layer "B.Cu")
		(net "GPU_3V3IO_RSVD4_ISO_R")
	)
	(segment
		(start 445.779144 -282.868878)
		(end 443.248796 -285.399226)
		(width 0.13208)
		(layer "B.Cu")
		(net "GPU_3V3IO_RSVD4_ISO_R")
	)
	(segment
		(start 363.65815 -232.785666)
		(end 363.65815 -227.430584)
		(width 0.15494)
		(layer "In5.Cu")
		(net "GPU_3V3IO_RSVD4_ISO_R")
	)
	(segment
		(start 366.614456 -224.474278)
		(end 369.010438 -224.474278)
		(width 0.15494)
		(layer "In5.Cu")
		(net "GPU_3V3IO_RSVD4_ISO_R")
	)
	(segment
		(start 357.675942 -232.620312)
		(end 358.179878 -233.124248)
		(width 0.15494)
		(layer "In5.Cu")
		(net "GPU_3V3IO_RSVD4_ISO_R")
	)
	(segment
		(start 356.364286 -229.676706)
		(end 357.675942 -230.988362)
		(width 0.15494)
		(layer "In5.Cu")
		(net "GPU_3V3IO_RSVD4_ISO_R")
	)
	(segment
		(start 369.990878 -219.58173)
		(end 371.889782 -217.682826)
		(width 0.15494)
		(layer "In5.Cu")
		(net "GPU_3V3IO_RSVD4_ISO_R")
	)
	(segment
		(start 363.319568 -233.124248)
		(end 363.65815 -232.785666)
		(width 0.15494)
		(layer "In5.Cu")
		(net "GPU_3V3IO_RSVD4_ISO_R")
	)
	(segment
		(start 371.889782 -217.682826)
		(end 378.716794 -217.682826)
		(width 0.15494)
		(layer "In5.Cu")
		(net "GPU_3V3IO_RSVD4_ISO_R")
	)
	(segment
		(start 378.716794 -217.682826)
		(end 386.830316 -225.796348)
		(width 0.15494)
		(layer "In5.Cu")
		(net "GPU_3V3IO_RSVD4_ISO_R")
	)
	(segment
		(start 357.675942 -230.988362)
		(end 357.675942 -232.620312)
		(width 0.15494)
		(layer "In5.Cu")
		(net "GPU_3V3IO_RSVD4_ISO_R")
	)
	(segment
		(start 386.830316 -225.796348)
		(end 386.830316 -228.079554)
		(width 0.15494)
		(layer "In5.Cu")
		(net "GPU_3V3IO_RSVD4_ISO_R")
	)
	(segment
		(start 358.179878 -233.124248)
		(end 363.319568 -233.124248)
		(width 0.15494)
		(layer "In5.Cu")
		(net "GPU_3V3IO_RSVD4_ISO_R")
	)
	(segment
		(start 369.010438 -224.474278)
		(end 369.990878 -223.493838)
		(width 0.15494)
		(layer "In5.Cu")
		(net "GPU_3V3IO_RSVD4_ISO_R")
	)
	(segment
		(start 363.65815 -227.430584)
		(end 366.614456 -224.474278)
		(width 0.15494)
		(layer "In5.Cu")
		(net "GPU_3V3IO_RSVD4_ISO_R")
	)
	(segment
		(start 353.197414 -228.621844)
		(end 354.252276 -229.676706)
		(width 0.15494)
		(layer "In5.Cu")
		(net "GPU_3V3IO_RSVD4_ISO_R")
	)
	(segment
		(start 369.990878 -223.493838)
		(end 369.990878 -219.58173)
		(width 0.15494)
		(layer "In5.Cu")
		(net "GPU_3V3IO_RSVD4_ISO_R")
	)
	(segment
		(start 354.252276 -229.676706)
		(end 356.364286 -229.676706)
		(width 0.15494)
		(layer "In5.Cu")
		(net "GPU_3V3IO_RSVD4_ISO_R")
	)
	(segment
		(start 339.344508 -232.777792)
		(end 350.52127 -232.777792)
		(width 0.15494)
		(layer "In11.Cu")
		(net "GPU_3V3IO_RSVD4_ISO_R")
	)
	(segment
		(start 353.197414 -230.101648)
		(end 353.197414 -228.621844)
		(width 0.15494)
		(layer "In11.Cu")
		(net "GPU_3V3IO_RSVD4_ISO_R")
	)
	(segment
		(start 335.696052 -215.390476)
		(end 335.696052 -227.29952)
		(width 0.0889)
		(layer "In11.Cu")
		(net "GPU_3V3IO_RSVD4_ISO_R")
	)
	(segment
		(start 333.694024 -213.98738)
		(end 334.892904 -215.18626)
		(width 0.0889)
		(layer "In11.Cu")
		(net "GPU_3V3IO_RSVD4_ISO_R")
	)
	(segment
		(start 335.696052 -229.129336)
		(end 339.344508 -232.777792)
		(width 0.15494)
		(layer "In11.Cu")
		(net "GPU_3V3IO_RSVD4_ISO_R")
	)
	(segment
		(start 335.696052 -227.29952)
		(end 335.696052 -229.129336)
		(width 0.15494)
		(layer "In11.Cu")
		(net "GPU_3V3IO_RSVD4_ISO_R")
	)
	(segment
		(start 350.52127 -232.777792)
		(end 353.197414 -230.101648)
		(width 0.15494)
		(layer "In11.Cu")
		(net "GPU_3V3IO_RSVD4_ISO_R")
	)
	(segment
		(start 335.491836 -215.18626)
		(end 335.696052 -215.390476)
		(width 0.0889)
		(layer "In11.Cu")
		(net "GPU_3V3IO_RSVD4_ISO_R")
	)
	(segment
		(start 334.892904 -215.18626)
		(end 335.491836 -215.18626)
		(width 0.0889)
		(layer "In11.Cu")
		(net "GPU_3V3IO_RSVD4_ISO_R")
	)
	(segment
		(start 405.754078 -371.693948)
		(end 405.754078 -371.008148)
		(width 0.13208)
		(layer "F.Cu")
		(net "GPU_3V3IO_RSVD4_ISO")
	)
	(segment
		(start 457.211684 -365.943134)
		(end 458.185266 -365.943134)
		(width 0.13208)
		(layer "F.Cu")
		(net "GPU_3V3IO_RSVD4_ISO")
	)
	(segment
		(start 456.03541 -363.462824)
		(end 456.22464 -363.652054)
		(width 0.13208)
		(layer "F.Cu")
		(net "GPU_3V3IO_RSVD4_ISO")
	)
	(segment
		(start 456.512676 -365.943134)
		(end 457.211684 -365.943134)
		(width 0.13208)
		(layer "F.Cu")
		(net "GPU_3V3IO_RSVD4_ISO")
	)
	(segment
		(start 454.055988 -362.805726)
		(end 454.713086 -363.462824)
		(width 0.13208)
		(layer "F.Cu")
		(net "GPU_3V3IO_RSVD4_ISO")
	)
	(segment
		(start 456.22464 -365.655098)
		(end 456.512676 -365.943134)
		(width 0.13208)
		(layer "F.Cu")
		(net "GPU_3V3IO_RSVD4_ISO")
	)
	(segment
		(start 459.076044 -365.94161)
		(end 459.077822 -365.943388)
		(width 0.13208)
		(layer "F.Cu")
		(net "GPU_3V3IO_RSVD4_ISO")
	)
	(segment
		(start 450.135752 -362.805726)
		(end 454.055988 -362.805726)
		(width 0.13208)
		(layer "F.Cu")
		(net "GPU_3V3IO_RSVD4_ISO")
	)
	(segment
		(start 454.713086 -363.462824)
		(end 456.03541 -363.462824)
		(width 0.13208)
		(layer "F.Cu")
		(net "GPU_3V3IO_RSVD4_ISO")
	)
	(segment
		(start 456.22464 -363.652054)
		(end 456.22464 -365.655098)
		(width 0.13208)
		(layer "F.Cu")
		(net "GPU_3V3IO_RSVD4_ISO")
	)
	(segment
		(start 458.185266 -365.943134)
		(end 458.18679 -365.94161)
		(width 0.13208)
		(layer "F.Cu")
		(net "GPU_3V3IO_RSVD4_ISO")
	)
	(segment
		(start 458.18679 -365.94161)
		(end 459.076044 -365.94161)
		(width 0.13208)
		(layer "F.Cu")
		(net "GPU_3V3IO_RSVD4_ISO")
	)
	(via
		(at 450.135752 -362.805726)
		(size 0.508)
		(drill 0.254)
		(layers "F.Cu" "B.Cu")
		(net "GPU_3V3IO_RSVD4_ISO")
	)
	(via
		(at 405.754078 -371.008148)
		(size 0.508)
		(drill 0.254)
		(layers "F.Cu" "B.Cu")
		(net "GPU_3V3IO_RSVD4_ISO")
	)
	(segment
		(start 450.135752 -362.805726)
		(end 449.832984 -362.502958)
		(width 0.13208)
		(layer "B.Cu")
		(net "GPU_3V3IO_RSVD4_ISO")
	)
	(segment
		(start 449.832984 -362.502958)
		(end 412.824168 -362.502958)
		(width 0.13208)
		(layer "B.Cu")
		(net "GPU_3V3IO_RSVD4_ISO")
	)
	(segment
		(start 412.824168 -362.502958)
		(end 408.11704 -367.210086)
		(width 0.13208)
		(layer "B.Cu")
		(net "GPU_3V3IO_RSVD4_ISO")
	)
	(segment
		(start 407.275284 -370.377974)
		(end 405.754078 -371.008148)
		(width 0.13208)
		(layer "B.Cu")
		(net "GPU_3V3IO_RSVD4_ISO")
	)
	(segment
		(start 408.11704 -367.210086)
		(end 408.11704 -369.536218)
		(width 0.13208)
		(layer "B.Cu")
		(net "GPU_3V3IO_RSVD4_ISO")
	)
	(segment
		(start 408.11704 -369.536218)
		(end 407.275284 -370.377974)
		(width 0.13208)
		(layer "B.Cu")
		(net "GPU_3V3IO_RSVD4_ISO")
	)
	(segment
		(start 336.493866 -214.387176)
		(end 336.09407 -213.98738)
		(width 0.13208)
		(layer "F.Cu")
		(net "GPU_3V3IO_RSVD3_ISO_R")
	)
	(segment
		(start 457.914502 -371.85981)
		(end 457.180442 -372.59387)
		(width 0.13208)
		(layer "F.Cu")
		(net "GPU_3V3IO_RSVD3_ISO_R")
	)
	(segment
		(start 457.180442 -372.59387)
		(end 457.180442 -373.319294)
		(width 0.13208)
		(layer "F.Cu")
		(net "GPU_3V3IO_RSVD3_ISO_R")
	)
	(via
		(at 386.811774 -228.862636)
		(size 0.508)
		(drill 0.254)
		(layers "F.Cu" "B.Cu")
		(net "GPU_3V3IO_RSVD3_ISO_R")
	)
	(via
		(at 352.426016 -228.582474)
		(size 0.508)
		(drill 0.254)
		(layers "F.Cu" "B.Cu")
		(net "GPU_3V3IO_RSVD3_ISO_R")
	)
	(via
		(at 457.914502 -371.85981)
		(size 0.508)
		(drill 0.254)
		(layers "F.Cu" "B.Cu")
		(net "GPU_3V3IO_RSVD3_ISO_R")
	)
	(via
		(at 336.09407 -213.98738)
		(size 0.4572)
		(drill 0.254)
		(layers "F.Cu" "B.Cu")
		(net "GPU_3V3IO_RSVD3_ISO_R")
	)
	(segment
		(start 442.92774 -304.740056)
		(end 441.896754 -305.771042)
		(width 0.13208)
		(layer "B.Cu")
		(net "GPU_3V3IO_RSVD3_ISO_R")
	)
	(segment
		(start 417.072572 -250.795028)
		(end 440.667394 -250.795028)
		(width 0.13208)
		(layer "B.Cu")
		(net "GPU_3V3IO_RSVD3_ISO_R")
	)
	(segment
		(start 449.508118 -323.176646)
		(end 456.781662 -323.176646)
		(width 0.13208)
		(layer "B.Cu")
		(net "GPU_3V3IO_RSVD3_ISO_R")
	)
	(segment
		(start 394.513562 -250.133612)
		(end 416.411156 -250.133612)
		(width 0.13208)
		(layer "B.Cu")
		(net "GPU_3V3IO_RSVD3_ISO_R")
	)
	(segment
		(start 448.846956 -253.499366)
		(end 445.494664 -256.851658)
		(width 0.13208)
		(layer "B.Cu")
		(net "GPU_3V3IO_RSVD3_ISO_R")
	)
	(segment
		(start 441.896754 -308.230016)
		(end 440.72429 -309.40248)
		(width 0.13208)
		(layer "B.Cu")
		(net "GPU_3V3IO_RSVD3_ISO_R")
	)
	(segment
		(start 442.265308 -249.197114)
		(end 444.581788 -249.197114)
		(width 0.13208)
		(layer "B.Cu")
		(net "GPU_3V3IO_RSVD3_ISO_R")
	)
	(segment
		(start 459.661768 -370.112544)
		(end 457.914502 -371.85981)
		(width 0.13208)
		(layer "B.Cu")
		(net "GPU_3V3IO_RSVD3_ISO_R")
	)
	(segment
		(start 459.661768 -363.391704)
		(end 459.661768 -370.112544)
		(width 0.13208)
		(layer "B.Cu")
		(net "GPU_3V3IO_RSVD3_ISO_R")
	)
	(segment
		(start 451.974458 -253.499366)
		(end 448.846956 -253.499366)
		(width 0.13208)
		(layer "B.Cu")
		(net "GPU_3V3IO_RSVD3_ISO_R")
	)
	(segment
		(start 391.13587 -246.75592)
		(end 394.513562 -250.133612)
		(width 0.13208)
		(layer "B.Cu")
		(net "GPU_3V3IO_RSVD3_ISO_R")
	)
	(segment
		(start 445.494664 -256.851658)
		(end 445.494664 -282.751022)
		(width 0.13208)
		(layer "B.Cu")
		(net "GPU_3V3IO_RSVD3_ISO_R")
	)
	(segment
		(start 440.72429 -314.392818)
		(end 449.508118 -323.176646)
		(width 0.13208)
		(layer "B.Cu")
		(net "GPU_3V3IO_RSVD3_ISO_R")
	)
	(segment
		(start 456.781662 -323.176646)
		(end 464.78952 -331.184504)
		(width 0.13208)
		(layer "B.Cu")
		(net "GPU_3V3IO_RSVD3_ISO_R")
	)
	(segment
		(start 442.92774 -285.317946)
		(end 442.92774 -304.740056)
		(width 0.13208)
		(layer "B.Cu")
		(net "GPU_3V3IO_RSVD3_ISO_R")
	)
	(segment
		(start 445.494664 -282.751022)
		(end 442.92774 -285.317946)
		(width 0.13208)
		(layer "B.Cu")
		(net "GPU_3V3IO_RSVD3_ISO_R")
	)
	(segment
		(start 444.581788 -249.197114)
		(end 445.856868 -250.472194)
		(width 0.13208)
		(layer "B.Cu")
		(net "GPU_3V3IO_RSVD3_ISO_R")
	)
	(segment
		(start 464.78952 -331.184504)
		(end 464.78952 -358.263952)
		(width 0.13208)
		(layer "B.Cu")
		(net "GPU_3V3IO_RSVD3_ISO_R")
	)
	(segment
		(start 440.667394 -250.795028)
		(end 442.265308 -249.197114)
		(width 0.13208)
		(layer "B.Cu")
		(net "GPU_3V3IO_RSVD3_ISO_R")
	)
	(segment
		(start 452.42861 -252.47854)
		(end 452.42861 -253.045214)
		(width 0.13208)
		(layer "B.Cu")
		(net "GPU_3V3IO_RSVD3_ISO_R")
	)
	(segment
		(start 416.411156 -250.133612)
		(end 417.072572 -250.795028)
		(width 0.13208)
		(layer "B.Cu")
		(net "GPU_3V3IO_RSVD3_ISO_R")
	)
	(segment
		(start 391.13587 -232.777792)
		(end 391.13587 -246.75592)
		(width 0.13208)
		(layer "B.Cu")
		(net "GPU_3V3IO_RSVD3_ISO_R")
	)
	(segment
		(start 450.422264 -250.472194)
		(end 452.42861 -252.47854)
		(width 0.13208)
		(layer "B.Cu")
		(net "GPU_3V3IO_RSVD3_ISO_R")
	)
	(segment
		(start 445.856868 -250.472194)
		(end 450.422264 -250.472194)
		(width 0.13208)
		(layer "B.Cu")
		(net "GPU_3V3IO_RSVD3_ISO_R")
	)
	(segment
		(start 441.896754 -305.771042)
		(end 441.896754 -308.230016)
		(width 0.13208)
		(layer "B.Cu")
		(net "GPU_3V3IO_RSVD3_ISO_R")
	)
	(segment
		(start 464.78952 -358.263952)
		(end 459.661768 -363.391704)
		(width 0.13208)
		(layer "B.Cu")
		(net "GPU_3V3IO_RSVD3_ISO_R")
	)
	(segment
		(start 452.42861 -253.045214)
		(end 451.974458 -253.499366)
		(width 0.13208)
		(layer "B.Cu")
		(net "GPU_3V3IO_RSVD3_ISO_R")
	)
	(segment
		(start 440.72429 -309.40248)
		(end 440.72429 -314.392818)
		(width 0.13208)
		(layer "B.Cu")
		(net "GPU_3V3IO_RSVD3_ISO_R")
	)
	(segment
		(start 386.811774 -228.862636)
		(end 387.220714 -228.862636)
		(width 0.13208)
		(layer "B.Cu")
		(net "GPU_3V3IO_RSVD3_ISO_R")
	)
	(segment
		(start 387.220714 -228.862636)
		(end 391.13587 -232.777792)
		(width 0.13208)
		(layer "B.Cu")
		(net "GPU_3V3IO_RSVD3_ISO_R")
	)
	(segment
		(start 364.051596 -227.543868)
		(end 364.051596 -232.91927)
		(width 0.15494)
		(layer "In5.Cu")
		(net "GPU_3V3IO_RSVD3_ISO_R")
	)
	(segment
		(start 378.541026 -218.040966)
		(end 372.038372 -218.040966)
		(width 0.15494)
		(layer "In5.Cu")
		(net "GPU_3V3IO_RSVD3_ISO_R")
	)
	(segment
		(start 370.349018 -223.666812)
		(end 369.183412 -224.832418)
		(width 0.15494)
		(layer "In5.Cu")
		(net "GPU_3V3IO_RSVD3_ISO_R")
	)
	(segment
		(start 356.277926 -230.133144)
		(end 353.976686 -230.133144)
		(width 0.15494)
		(layer "In5.Cu")
		(net "GPU_3V3IO_RSVD3_ISO_R")
	)
	(segment
		(start 353.976686 -230.133144)
		(end 352.426016 -228.582474)
		(width 0.15494)
		(layer "In5.Cu")
		(net "GPU_3V3IO_RSVD3_ISO_R")
	)
	(segment
		(start 358.053894 -233.54919)
		(end 357.298498 -232.793794)
		(width 0.15494)
		(layer "In5.Cu")
		(net "GPU_3V3IO_RSVD3_ISO_R")
	)
	(segment
		(start 357.298498 -231.153716)
		(end 356.277926 -230.133144)
		(width 0.15494)
		(layer "In5.Cu")
		(net "GPU_3V3IO_RSVD3_ISO_R")
	)
	(segment
		(start 363.421676 -233.54919)
		(end 358.053894 -233.54919)
		(width 0.15494)
		(layer "In5.Cu")
		(net "GPU_3V3IO_RSVD3_ISO_R")
	)
	(segment
		(start 364.051596 -232.91927)
		(end 363.421676 -233.54919)
		(width 0.15494)
		(layer "In5.Cu")
		(net "GPU_3V3IO_RSVD3_ISO_R")
	)
	(segment
		(start 357.298498 -232.793794)
		(end 357.298498 -231.153716)
		(width 0.15494)
		(layer "In5.Cu")
		(net "GPU_3V3IO_RSVD3_ISO_R")
	)
	(segment
		(start 386.811774 -228.862636)
		(end 386.330444 -228.381306)
		(width 0.15494)
		(layer "In5.Cu")
		(net "GPU_3V3IO_RSVD3_ISO_R")
	)
	(segment
		(start 366.763046 -224.832418)
		(end 364.051596 -227.543868)
		(width 0.15494)
		(layer "In5.Cu")
		(net "GPU_3V3IO_RSVD3_ISO_R")
	)
	(segment
		(start 369.183412 -224.832418)
		(end 366.763046 -224.832418)
		(width 0.15494)
		(layer "In5.Cu")
		(net "GPU_3V3IO_RSVD3_ISO_R")
	)
	(segment
		(start 370.349018 -219.73032)
		(end 370.349018 -223.666812)
		(width 0.15494)
		(layer "In5.Cu")
		(net "GPU_3V3IO_RSVD3_ISO_R")
	)
	(segment
		(start 386.330444 -225.830384)
		(end 378.541026 -218.040966)
		(width 0.15494)
		(layer "In5.Cu")
		(net "GPU_3V3IO_RSVD3_ISO_R")
	)
	(segment
		(start 372.038372 -218.040966)
		(end 370.349018 -219.73032)
		(width 0.15494)
		(layer "In5.Cu")
		(net "GPU_3V3IO_RSVD3_ISO_R")
	)
	(segment
		(start 386.330444 -228.381306)
		(end 386.330444 -225.830384)
		(width 0.15494)
		(layer "In5.Cu")
		(net "GPU_3V3IO_RSVD3_ISO_R")
	)
	(segment
		(start 336.794094 -229.354126)
		(end 339.603842 -232.163874)
		(width 0.15494)
		(layer "In11.Cu")
		(net "GPU_3V3IO_RSVD3_ISO_R")
	)
	(segment
		(start 339.603842 -232.163874)
		(end 350.45015 -232.163874)
		(width 0.15494)
		(layer "In11.Cu")
		(net "GPU_3V3IO_RSVD3_ISO_R")
	)
	(segment
		(start 350.45015 -232.163874)
		(end 351.528634 -231.08539)
		(width 0.15494)
		(layer "In11.Cu")
		(net "GPU_3V3IO_RSVD3_ISO_R")
	)
	(segment
		(start 336.794094 -228.267768)
		(end 336.794094 -229.354126)
		(width 0.15494)
		(layer "In11.Cu")
		(net "GPU_3V3IO_RSVD3_ISO_R")
	)
	(segment
		(start 336.493104 -227.29952)
		(end 336.493104 -227.966778)
		(width 0.15494)
		(layer "In11.Cu")
		(net "GPU_3V3IO_RSVD3_ISO_R")
	)
	(segment
		(start 351.528634 -229.479856)
		(end 352.426016 -228.582474)
		(width 0.15494)
		(layer "In11.Cu")
		(net "GPU_3V3IO_RSVD3_ISO_R")
	)
	(segment
		(start 351.528634 -231.08539)
		(end 351.528634 -229.479856)
		(width 0.15494)
		(layer "In11.Cu")
		(net "GPU_3V3IO_RSVD3_ISO_R")
	)
	(segment
		(start 336.09407 -213.98738)
		(end 336.493104 -214.386414)
		(width 0.0889)
		(layer "In11.Cu")
		(net "GPU_3V3IO_RSVD3_ISO_R")
	)
	(segment
		(start 336.493104 -227.966778)
		(end 336.794094 -228.267768)
		(width 0.15494)
		(layer "In11.Cu")
		(net "GPU_3V3IO_RSVD3_ISO_R")
	)
	(segment
		(start 336.493104 -214.386414)
		(end 336.493104 -227.29952)
		(width 0.0889)
		(layer "In11.Cu")
		(net "GPU_3V3IO_RSVD3_ISO_R")
	)
	(segment
		(start 457.180442 -374.119394)
		(end 455.9554 -372.894352)
		(width 0.13208)
		(layer "F.Cu")
		(net "GPU_3V3IO_RSVD3_ISO")
	)
	(segment
		(start 455.224388 -371.0432)
		(end 453.37857 -371.0432)
		(width 0.13208)
		(layer "F.Cu")
		(net "GPU_3V3IO_RSVD3_ISO")
	)
	(segment
		(start 453.37857 -371.0432)
		(end 452.89597 -371.5258)
		(width 0.13208)
		(layer "F.Cu")
		(net "GPU_3V3IO_RSVD3_ISO")
	)
	(segment
		(start 458.155548 -374.11787)
		(end 458.157326 -374.119648)
		(width 0.13208)
		(layer "F.Cu")
		(net "GPU_3V3IO_RSVD3_ISO")
	)
	(segment
		(start 458.157326 -374.119648)
		(end 459.04658 -374.119648)
		(width 0.13208)
		(layer "F.Cu")
		(net "GPU_3V3IO_RSVD3_ISO")
	)
	(segment
		(start 455.9554 -372.894352)
		(end 455.9554 -371.774212)
		(width 0.13208)
		(layer "F.Cu")
		(net "GPU_3V3IO_RSVD3_ISO")
	)
	(segment
		(start 455.9554 -371.774212)
		(end 455.224388 -371.0432)
		(width 0.13208)
		(layer "F.Cu")
		(net "GPU_3V3IO_RSVD3_ISO")
	)
	(segment
		(start 457.181966 -374.11787)
		(end 458.155548 -374.11787)
		(width 0.13208)
		(layer "F.Cu")
		(net "GPU_3V3IO_RSVD3_ISO")
	)
	(segment
		(start 457.180442 -374.119394)
		(end 457.181966 -374.11787)
		(width 0.13208)
		(layer "F.Cu")
		(net "GPU_3V3IO_RSVD3_ISO")
	)
	(segment
		(start 452.89597 -374.129808)
		(end 452.89597 -371.5258)
		(width 0.13208)
		(layer "F.Cu")
		(net "GPU_3V3IO_RSVD3_ISO")
	)
	(via
		(at 455.9554 -371.774212)
		(size 0.762)
		(drill 0.381)
		(layers "F.Cu" "B.Cu")
		(net "GPU_3V3IO_RSVD3_ISO")
	)
	(segment
		(start 457.186284 -366.913922)
		(end 456.024996 -366.913922)
		(width 0.13208)
		(layer "F.Cu")
		(net "GPU_3V3IO_RSVD4_N")
	)
	(segment
		(start 406.899872 -369.174268)
		(end 407.254202 -369.528598)
		(width 0.13208)
		(layer "F.Cu")
		(net "GPU_3V3IO_RSVD4_N")
	)
	(segment
		(start 406.50414 -369.894104)
		(end 407.254202 -369.894104)
		(width 0.13208)
		(layer "F.Cu")
		(net "GPU_3V3IO_RSVD4_N")
	)
	(segment
		(start 407.254202 -369.528598)
		(end 407.254202 -369.894104)
		(width 0.13208)
		(layer "F.Cu")
		(net "GPU_3V3IO_RSVD4_N")
	)
	(via
		(at 406.899872 -369.174268)
		(size 0.508)
		(drill 0.254)
		(layers "F.Cu" "B.Cu")
		(net "GPU_3V3IO_RSVD4_N")
	)
	(via
		(at 456.024996 -366.913922)
		(size 0.508)
		(drill 0.254)
		(layers "F.Cu" "B.Cu")
		(net "GPU_3V3IO_RSVD4_N")
	)
	(segment
		(start 453.518016 -365.463328)
		(end 454.96861 -366.913922)
		(width 0.13208)
		(layer "B.Cu")
		(net "GPU_3V3IO_RSVD4_N")
	)
	(segment
		(start 407.15438 -368.91976)
		(end 407.15438 -366.965484)
		(width 0.13208)
		(layer "B.Cu")
		(net "GPU_3V3IO_RSVD4_N")
	)
	(segment
		(start 454.96861 -366.913922)
		(end 456.024996 -366.913922)
		(width 0.13208)
		(layer "B.Cu")
		(net "GPU_3V3IO_RSVD4_N")
	)
	(segment
		(start 412.470346 -361.649518)
		(end 450.832474 -361.649518)
		(width 0.13208)
		(layer "B.Cu")
		(net "GPU_3V3IO_RSVD4_N")
	)
	(segment
		(start 453.518016 -364.33506)
		(end 453.518016 -365.463328)
		(width 0.13208)
		(layer "B.Cu")
		(net "GPU_3V3IO_RSVD4_N")
	)
	(segment
		(start 450.832474 -361.649518)
		(end 453.518016 -364.33506)
		(width 0.13208)
		(layer "B.Cu")
		(net "GPU_3V3IO_RSVD4_N")
	)
	(segment
		(start 407.15438 -366.965484)
		(end 412.470346 -361.649518)
		(width 0.13208)
		(layer "B.Cu")
		(net "GPU_3V3IO_RSVD4_N")
	)
	(segment
		(start 406.899872 -369.174268)
		(end 407.15438 -368.91976)
		(width 0.13208)
		(layer "B.Cu")
		(net "GPU_3V3IO_RSVD4_N")
	)
	(segment
		(start 456.795886 -375.449338)
		(end 455.967338 -375.449338)
		(width 0.13208)
		(layer "F.Cu")
		(net "GPU_3V3IO_RSVD3_N")
	)
	(segment
		(start 455.39787 -374.87987)
		(end 454.695814 -374.87987)
		(width 0.13208)
		(layer "F.Cu")
		(net "GPU_3V3IO_RSVD3_N")
	)
	(segment
		(start 457.155042 -375.090182)
		(end 456.795886 -375.449338)
		(width 0.13208)
		(layer "F.Cu")
		(net "GPU_3V3IO_RSVD3_N")
	)
	(segment
		(start 454.695814 -375.629932)
		(end 454.695814 -374.87987)
		(width 0.13208)
		(layer "F.Cu")
		(net "GPU_3V3IO_RSVD3_N")
	)
	(segment
		(start 455.967338 -375.449338)
		(end 455.39787 -374.87987)
		(width 0.13208)
		(layer "F.Cu")
		(net "GPU_3V3IO_RSVD3_N")
	)
	(via
		(at 455.967338 -375.449338)
		(size 0.762)
		(drill 0.381)
		(layers "F.Cu" "B.Cu")
		(net "GPU_3V3IO_RSVD3_N")
	)
	(segment
		(start 68.200016 -309.199788)
		(end 68.199762 -309.199788)
		(width 0.13208)
		(layer "F.Cu")
		(net "SMB_PEX0_SLAVE1_SCL")
	)
	(segment
		(start 68.674996 -308.724808)
		(end 68.200016 -309.199788)
		(width 0.13208)
		(layer "F.Cu")
		(net "SMB_PEX0_SLAVE1_SCL")
	)
	(segment
		(start 85.89645 -302.48733)
		(end 85.217508 -301.808388)
		(width 0.13208)
		(layer "F.Cu")
		(net "SMB_PEX0_SLAVE1_SCL")
	)
	(segment
		(start 85.933788 -302.48733)
		(end 85.89645 -302.48733)
		(width 0.13208)
		(layer "F.Cu")
		(net "SMB_PEX0_SLAVE1_SCL")
	)
	(via
		(at 68.674996 -308.724808)
		(size 0.4064)
		(drill 0.2032)
		(layers "F.Cu" "B.Cu")
		(net "SMB_PEX0_SLAVE1_SCL")
	)
	(via
		(at 85.217508 -301.808388)
		(size 0.508)
		(drill 0.254)
		(layers "F.Cu" "B.Cu")
		(net "SMB_PEX0_SLAVE1_SCL")
	)
	(segment
		(start 84.52612 -306.8066)
		(end 85.564218 -306.376578)
		(width 0.15494)
		(layer "In5.Cu")
		(net "SMB_PEX0_SLAVE1_SCL")
	)
	(segment
		(start 70.612 -309.771796)
		(end 70.612 -312.2676)
		(width 0.15494)
		(layer "In5.Cu")
		(net "SMB_PEX0_SLAVE1_SCL")
	)
	(segment
		(start 92.164662 -302.679354)
		(end 91.825826 -302.340518)
		(width 0.15494)
		(layer "In5.Cu")
		(net "SMB_PEX0_SLAVE1_SCL")
	)
	(segment
		(start 91.825826 -302.340518)
		(end 85.749638 -302.340518)
		(width 0.15494)
		(layer "In5.Cu")
		(net "SMB_PEX0_SLAVE1_SCL")
	)
	(segment
		(start 69.061584 -309.111396)
		(end 69.9516 -309.111396)
		(width 0.15494)
		(layer "In5.Cu")
		(net "SMB_PEX0_SLAVE1_SCL")
	)
	(segment
		(start 69.9516 -309.111396)
		(end 70.612 -309.771796)
		(width 0.15494)
		(layer "In5.Cu")
		(net "SMB_PEX0_SLAVE1_SCL")
	)
	(segment
		(start 81.2038 -306.8066)
		(end 84.52612 -306.8066)
		(width 0.15494)
		(layer "In5.Cu")
		(net "SMB_PEX0_SLAVE1_SCL")
	)
	(segment
		(start 81.0768 -306.9336)
		(end 81.2038 -306.8066)
		(width 0.15494)
		(layer "In5.Cu")
		(net "SMB_PEX0_SLAVE1_SCL")
	)
	(segment
		(start 68.674996 -308.724808)
		(end 69.061584 -309.111396)
		(width 0.15494)
		(layer "In5.Cu")
		(net "SMB_PEX0_SLAVE1_SCL")
	)
	(segment
		(start 92.164662 -303.86909)
		(end 92.164662 -302.679354)
		(width 0.15494)
		(layer "In5.Cu")
		(net "SMB_PEX0_SLAVE1_SCL")
	)
	(segment
		(start 85.749638 -302.340518)
		(end 85.217508 -301.808388)
		(width 0.15494)
		(layer "In5.Cu")
		(net "SMB_PEX0_SLAVE1_SCL")
	)
	(segment
		(start 80.645 -312.4962)
		(end 81.0768 -312.0644)
		(width 0.15494)
		(layer "In5.Cu")
		(net "SMB_PEX0_SLAVE1_SCL")
	)
	(segment
		(start 81.0768 -312.0644)
		(end 81.0768 -306.9336)
		(width 0.15494)
		(layer "In5.Cu")
		(net "SMB_PEX0_SLAVE1_SCL")
	)
	(segment
		(start 91.52255 -305.513994)
		(end 91.52255 -304.511202)
		(width 0.15494)
		(layer "In5.Cu")
		(net "SMB_PEX0_SLAVE1_SCL")
	)
	(segment
		(start 91.262454 -305.77409)
		(end 91.52255 -305.513994)
		(width 0.15494)
		(layer "In5.Cu")
		(net "SMB_PEX0_SLAVE1_SCL")
	)
	(segment
		(start 91.52255 -304.511202)
		(end 92.164662 -303.86909)
		(width 0.15494)
		(layer "In5.Cu")
		(net "SMB_PEX0_SLAVE1_SCL")
	)
	(segment
		(start 70.8406 -312.4962)
		(end 80.645 -312.4962)
		(width 0.15494)
		(layer "In5.Cu")
		(net "SMB_PEX0_SLAVE1_SCL")
	)
	(segment
		(start 86.166706 -305.77409)
		(end 91.262454 -305.77409)
		(width 0.15494)
		(layer "In5.Cu")
		(net "SMB_PEX0_SLAVE1_SCL")
	)
	(segment
		(start 85.564218 -306.376578)
		(end 86.166706 -305.77409)
		(width 0.15494)
		(layer "In5.Cu")
		(net "SMB_PEX0_SLAVE1_SCL")
	)
	(segment
		(start 70.612 -312.2676)
		(end 70.8406 -312.4962)
		(width 0.15494)
		(layer "In5.Cu")
		(net "SMB_PEX0_SLAVE1_SCL")
	)
	(segment
		(start 71.999856 -308.249828)
		(end 71.524876 -307.774848)
		(width 0.13208)
		(layer "F.Cu")
		(net "SMB_PEX0_SLAVE1_SDA")
	)
	(segment
		(start 90.305636 -302.363378)
		(end 90.002868 -302.666146)
		(width 0.13208)
		(layer "F.Cu")
		(net "SMB_PEX0_SLAVE1_SDA")
	)
	(segment
		(start 91.096592 -302.363378)
		(end 90.305636 -302.363378)
		(width 0.13208)
		(layer "F.Cu")
		(net "SMB_PEX0_SLAVE1_SDA")
	)
	(segment
		(start 91.572842 -302.839628)
		(end 91.096592 -302.363378)
		(width 0.13208)
		(layer "F.Cu")
		(net "SMB_PEX0_SLAVE1_SDA")
	)
	(via
		(at 71.524876 -307.774848)
		(size 0.4064)
		(drill 0.2032)
		(layers "F.Cu" "B.Cu")
		(net "SMB_PEX0_SLAVE1_SDA")
	)
	(via
		(at 91.572842 -302.839628)
		(size 0.508)
		(drill 0.254)
		(layers "F.Cu" "B.Cu")
		(net "SMB_PEX0_SLAVE1_SDA")
	)
	(segment
		(start 91.02598 -303.576736)
		(end 91.1606 -303.442116)
		(width 0.15494)
		(layer "In5.Cu")
		(net "SMB_PEX0_SLAVE1_SDA")
	)
	(segment
		(start 85.659722 -303.293526)
		(end 85.794342 -303.428146)
		(width 0.15494)
		(layer "In5.Cu")
		(net "SMB_PEX0_SLAVE1_SDA")
	)
	(segment
		(start 87.602568 -304.029364)
		(end 87.784432 -304.029364)
		(width 0.15494)
		(layer "In5.Cu")
		(net "SMB_PEX0_SLAVE1_SDA")
	)
	(segment
		(start 88.31326 -303.442116)
		(end 88.44788 -303.576736)
		(width 0.15494)
		(layer "In5.Cu")
		(net "SMB_PEX0_SLAVE1_SDA")
	)
	(segment
		(start 87.47379 -303.900586)
		(end 87.602568 -304.029364)
		(width 0.15494)
		(layer "In5.Cu")
		(net "SMB_PEX0_SLAVE1_SDA")
	)
	(segment
		(start 90.12936 -303.442116)
		(end 90.37574 -303.442116)
		(width 0.15494)
		(layer "In5.Cu")
		(net "SMB_PEX0_SLAVE1_SDA")
	)
	(segment
		(start 89.3445 -303.442116)
		(end 89.47912 -303.576736)
		(width 0.15494)
		(layer "In5.Cu")
		(net "SMB_PEX0_SLAVE1_SDA")
	)
	(segment
		(start 86.175342 -303.293526)
		(end 86.175342 -302.942498)
		(width 0.15494)
		(layer "In5.Cu")
		(net "SMB_PEX0_SLAVE1_SDA")
	)
	(segment
		(start 72.4408 -309.667148)
		(end 72.4408 -310.226202)
		(width 0.15494)
		(layer "In5.Cu")
		(net "SMB_PEX0_SLAVE1_SDA")
	)
	(segment
		(start 71.524876 -307.774848)
		(end 71.524876 -308.10581)
		(width 0.15494)
		(layer "In5.Cu")
		(net "SMB_PEX0_SLAVE1_SDA")
	)
	(segment
		(start 84.714334 -303.875694)
		(end 84.896198 -303.875694)
		(width 0.15494)
		(layer "In5.Cu")
		(net "SMB_PEX0_SLAVE1_SDA")
	)
	(segment
		(start 91.572842 -303.314862)
		(end 91.572842 -302.839628)
		(width 0.15494)
		(layer "In5.Cu")
		(net "SMB_PEX0_SLAVE1_SDA")
	)
	(segment
		(start 87.91321 -303.569116)
		(end 88.04021 -303.442116)
		(width 0.15494)
		(layer "In5.Cu")
		(net "SMB_PEX0_SLAVE1_SDA")
	)
	(segment
		(start 87.346536 -302.807878)
		(end 87.47379 -302.935132)
		(width 0.15494)
		(layer "In5.Cu")
		(net "SMB_PEX0_SLAVE1_SDA")
	)
	(segment
		(start 85.659722 -302.942498)
		(end 85.659722 -303.293526)
		(width 0.15494)
		(layer "In5.Cu")
		(net "SMB_PEX0_SLAVE1_SDA")
	)
	(segment
		(start 90.64498 -304.50155)
		(end 90.89136 -304.50155)
		(width 0.15494)
		(layer "In5.Cu")
		(net "SMB_PEX0_SLAVE1_SDA")
	)
	(segment
		(start 83.950302 -305.096164)
		(end 83.950302 -304.9143)
		(width 0.15494)
		(layer "In5.Cu")
		(net "SMB_PEX0_SLAVE1_SDA")
	)
	(segment
		(start 85.344 -305.224942)
		(end 84.07908 -305.224942)
		(width 0.15494)
		(layer "In5.Cu")
		(net "SMB_PEX0_SLAVE1_SDA")
	)
	(segment
		(start 83.950302 -302.573436)
		(end 84.15782 -302.365918)
		(width 0.15494)
		(layer "In5.Cu")
		(net "SMB_PEX0_SLAVE1_SDA")
	)
	(segment
		(start 85.024976 -302.984916)
		(end 85.202014 -302.807878)
		(width 0.15494)
		(layer "In5.Cu")
		(net "SMB_PEX0_SLAVE1_SDA")
	)
	(segment
		(start 88.9635 -304.36693)
		(end 88.9635 -303.576736)
		(width 0.15494)
		(layer "In5.Cu")
		(net "SMB_PEX0_SLAVE1_SDA")
	)
	(segment
		(start 84.456778 -302.365918)
		(end 84.585556 -302.494696)
		(width 0.15494)
		(layer "In5.Cu")
		(net "SMB_PEX0_SLAVE1_SDA")
	)
	(segment
		(start 84.15782 -302.365918)
		(end 84.456778 -302.365918)
		(width 0.15494)
		(layer "In5.Cu")
		(net "SMB_PEX0_SLAVE1_SDA")
	)
	(segment
		(start 90.51036 -304.36693)
		(end 90.64498 -304.50155)
		(width 0.15494)
		(layer "In5.Cu")
		(net "SMB_PEX0_SLAVE1_SDA")
	)
	(segment
		(start 91.1606 -303.442116)
		(end 91.445588 -303.442116)
		(width 0.15494)
		(layer "In5.Cu")
		(net "SMB_PEX0_SLAVE1_SDA")
	)
	(segment
		(start 89.86012 -304.50155)
		(end 89.99474 -304.36693)
		(width 0.15494)
		(layer "In5.Cu")
		(net "SMB_PEX0_SLAVE1_SDA")
	)
	(segment
		(start 89.09812 -303.442116)
		(end 89.3445 -303.442116)
		(width 0.15494)
		(layer "In5.Cu")
		(net "SMB_PEX0_SLAVE1_SDA")
	)
	(segment
		(start 83.950302 -305.79314)
		(end 84.07908 -305.664362)
		(width 0.15494)
		(layer "In5.Cu")
		(net "SMB_PEX0_SLAVE1_SDA")
	)
	(segment
		(start 85.024976 -303.746916)
		(end 85.024976 -302.984916)
		(width 0.15494)
		(layer "In5.Cu")
		(net "SMB_PEX0_SLAVE1_SDA")
	)
	(segment
		(start 85.344 -304.346102)
		(end 84.07908 -304.346102)
		(width 0.15494)
		(layer "In5.Cu")
		(net "SMB_PEX0_SLAVE1_SDA")
	)
	(segment
		(start 84.07908 -304.785522)
		(end 85.344 -304.785522)
		(width 0.15494)
		(layer "In5.Cu")
		(net "SMB_PEX0_SLAVE1_SDA")
	)
	(segment
		(start 78.892146 -310.5912)
		(end 79.0702 -310.413146)
		(width 0.15494)
		(layer "In5.Cu")
		(net "SMB_PEX0_SLAVE1_SDA")
	)
	(segment
		(start 88.44788 -304.36693)
		(end 88.5825 -304.50155)
		(width 0.15494)
		(layer "In5.Cu")
		(net "SMB_PEX0_SLAVE1_SDA")
	)
	(segment
		(start 88.44788 -303.576736)
		(end 88.44788 -304.36693)
		(width 0.15494)
		(layer "In5.Cu")
		(net "SMB_PEX0_SLAVE1_SDA")
	)
	(segment
		(start 88.5825 -304.50155)
		(end 88.82888 -304.50155)
		(width 0.15494)
		(layer "In5.Cu")
		(net "SMB_PEX0_SLAVE1_SDA")
	)
	(segment
		(start 79.1972 -305.79314)
		(end 83.950302 -305.79314)
		(width 0.15494)
		(layer "In5.Cu")
		(net "SMB_PEX0_SLAVE1_SDA")
	)
	(segment
		(start 90.37574 -303.442116)
		(end 90.51036 -303.576736)
		(width 0.15494)
		(layer "In5.Cu")
		(net "SMB_PEX0_SLAVE1_SDA")
	)
	(segment
		(start 79.0702 -305.92014)
		(end 79.1972 -305.79314)
		(width 0.15494)
		(layer "In5.Cu")
		(net "SMB_PEX0_SLAVE1_SDA")
	)
	(segment
		(start 85.525102 -302.807878)
		(end 85.659722 -302.942498)
		(width 0.15494)
		(layer "In5.Cu")
		(net "SMB_PEX0_SLAVE1_SDA")
	)
	(segment
		(start 72.4408 -310.226202)
		(end 72.805798 -310.5912)
		(width 0.15494)
		(layer "In5.Cu")
		(net "SMB_PEX0_SLAVE1_SDA")
	)
	(segment
		(start 85.794342 -303.428146)
		(end 86.040722 -303.428146)
		(width 0.15494)
		(layer "In5.Cu")
		(net "SMB_PEX0_SLAVE1_SDA")
	)
	(segment
		(start 87.784432 -304.029364)
		(end 87.91321 -303.900586)
		(width 0.15494)
		(layer "In5.Cu")
		(net "SMB_PEX0_SLAVE1_SDA")
	)
	(segment
		(start 85.202014 -302.807878)
		(end 85.525102 -302.807878)
		(width 0.15494)
		(layer "In5.Cu")
		(net "SMB_PEX0_SLAVE1_SDA")
	)
	(segment
		(start 91.445588 -303.442116)
		(end 91.572842 -303.314862)
		(width 0.15494)
		(layer "In5.Cu")
		(net "SMB_PEX0_SLAVE1_SDA")
	)
	(segment
		(start 72.805798 -310.5912)
		(end 78.892146 -310.5912)
		(width 0.15494)
		(layer "In5.Cu")
		(net "SMB_PEX0_SLAVE1_SDA")
	)
	(segment
		(start 84.585556 -303.746916)
		(end 84.714334 -303.875694)
		(width 0.15494)
		(layer "In5.Cu")
		(net "SMB_PEX0_SLAVE1_SDA")
	)
	(segment
		(start 85.344 -304.785522)
		(end 85.473794 -304.655728)
		(width 0.15494)
		(layer "In5.Cu")
		(net "SMB_PEX0_SLAVE1_SDA")
	)
	(segment
		(start 86.175342 -302.942498)
		(end 86.309962 -302.807878)
		(width 0.15494)
		(layer "In5.Cu")
		(net "SMB_PEX0_SLAVE1_SDA")
	)
	(segment
		(start 85.344 -305.664362)
		(end 85.473794 -305.534568)
		(width 0.15494)
		(layer "In5.Cu")
		(net "SMB_PEX0_SLAVE1_SDA")
	)
	(segment
		(start 88.82888 -304.50155)
		(end 88.9635 -304.36693)
		(width 0.15494)
		(layer "In5.Cu")
		(net "SMB_PEX0_SLAVE1_SDA")
	)
	(segment
		(start 83.950302 -304.9143)
		(end 84.07908 -304.785522)
		(width 0.15494)
		(layer "In5.Cu")
		(net "SMB_PEX0_SLAVE1_SDA")
	)
	(segment
		(start 84.896198 -303.875694)
		(end 85.024976 -303.746916)
		(width 0.15494)
		(layer "In5.Cu")
		(net "SMB_PEX0_SLAVE1_SDA")
	)
	(segment
		(start 86.309962 -302.807878)
		(end 87.346536 -302.807878)
		(width 0.15494)
		(layer "In5.Cu")
		(net "SMB_PEX0_SLAVE1_SDA")
	)
	(segment
		(start 89.47912 -304.36693)
		(end 89.61374 -304.50155)
		(width 0.15494)
		(layer "In5.Cu")
		(net "SMB_PEX0_SLAVE1_SDA")
	)
	(segment
		(start 89.99474 -304.36693)
		(end 89.99474 -303.576736)
		(width 0.15494)
		(layer "In5.Cu")
		(net "SMB_PEX0_SLAVE1_SDA")
	)
	(segment
		(start 84.07908 -305.664362)
		(end 85.344 -305.664362)
		(width 0.15494)
		(layer "In5.Cu")
		(net "SMB_PEX0_SLAVE1_SDA")
	)
	(segment
		(start 84.585556 -302.494696)
		(end 84.585556 -303.746916)
		(width 0.15494)
		(layer "In5.Cu")
		(net "SMB_PEX0_SLAVE1_SDA")
	)
	(segment
		(start 86.040722 -303.428146)
		(end 86.175342 -303.293526)
		(width 0.15494)
		(layer "In5.Cu")
		(net "SMB_PEX0_SLAVE1_SDA")
	)
	(segment
		(start 89.99474 -303.576736)
		(end 90.12936 -303.442116)
		(width 0.15494)
		(layer "In5.Cu")
		(net "SMB_PEX0_SLAVE1_SDA")
	)
	(segment
		(start 88.9635 -303.576736)
		(end 89.09812 -303.442116)
		(width 0.15494)
		(layer "In5.Cu")
		(net "SMB_PEX0_SLAVE1_SDA")
	)
	(segment
		(start 89.61374 -304.50155)
		(end 89.86012 -304.50155)
		(width 0.15494)
		(layer "In5.Cu")
		(net "SMB_PEX0_SLAVE1_SDA")
	)
	(segment
		(start 87.91321 -303.900586)
		(end 87.91321 -303.569116)
		(width 0.15494)
		(layer "In5.Cu")
		(net "SMB_PEX0_SLAVE1_SDA")
	)
	(segment
		(start 72.018652 -308.599586)
		(end 72.018652 -309.245)
		(width 0.15494)
		(layer "In5.Cu")
		(net "SMB_PEX0_SLAVE1_SDA")
	)
	(segment
		(start 85.473794 -305.534568)
		(end 85.473794 -305.354736)
		(width 0.15494)
		(layer "In5.Cu")
		(net "SMB_PEX0_SLAVE1_SDA")
	)
	(segment
		(start 85.473794 -304.475896)
		(end 85.344 -304.346102)
		(width 0.15494)
		(layer "In5.Cu")
		(net "SMB_PEX0_SLAVE1_SDA")
	)
	(segment
		(start 84.07908 -305.224942)
		(end 83.950302 -305.096164)
		(width 0.15494)
		(layer "In5.Cu")
		(net "SMB_PEX0_SLAVE1_SDA")
	)
	(segment
		(start 84.07908 -304.346102)
		(end 83.950302 -304.217324)
		(width 0.15494)
		(layer "In5.Cu")
		(net "SMB_PEX0_SLAVE1_SDA")
	)
	(segment
		(start 90.51036 -303.576736)
		(end 90.51036 -304.36693)
		(width 0.15494)
		(layer "In5.Cu")
		(net "SMB_PEX0_SLAVE1_SDA")
	)
	(segment
		(start 71.524876 -308.10581)
		(end 72.018652 -308.599586)
		(width 0.15494)
		(layer "In5.Cu")
		(net "SMB_PEX0_SLAVE1_SDA")
	)
	(segment
		(start 83.950302 -304.217324)
		(end 83.950302 -302.573436)
		(width 0.15494)
		(layer "In5.Cu")
		(net "SMB_PEX0_SLAVE1_SDA")
	)
	(segment
		(start 87.47379 -302.935132)
		(end 87.47379 -303.900586)
		(width 0.15494)
		(layer "In5.Cu")
		(net "SMB_PEX0_SLAVE1_SDA")
	)
	(segment
		(start 85.473794 -304.655728)
		(end 85.473794 -304.475896)
		(width 0.15494)
		(layer "In5.Cu")
		(net "SMB_PEX0_SLAVE1_SDA")
	)
	(segment
		(start 79.0702 -310.413146)
		(end 79.0702 -305.92014)
		(width 0.15494)
		(layer "In5.Cu")
		(net "SMB_PEX0_SLAVE1_SDA")
	)
	(segment
		(start 89.47912 -303.576736)
		(end 89.47912 -304.36693)
		(width 0.15494)
		(layer "In5.Cu")
		(net "SMB_PEX0_SLAVE1_SDA")
	)
	(segment
		(start 85.473794 -305.354736)
		(end 85.344 -305.224942)
		(width 0.15494)
		(layer "In5.Cu")
		(net "SMB_PEX0_SLAVE1_SDA")
	)
	(segment
		(start 88.04021 -303.442116)
		(end 88.31326 -303.442116)
		(width 0.15494)
		(layer "In5.Cu")
		(net "SMB_PEX0_SLAVE1_SDA")
	)
	(segment
		(start 91.02598 -304.36693)
		(end 91.02598 -303.576736)
		(width 0.15494)
		(layer "In5.Cu")
		(net "SMB_PEX0_SLAVE1_SDA")
	)
	(segment
		(start 90.89136 -304.50155)
		(end 91.02598 -304.36693)
		(width 0.15494)
		(layer "In5.Cu")
		(net "SMB_PEX0_SLAVE1_SDA")
	)
	(segment
		(start 72.018652 -309.245)
		(end 72.4408 -309.667148)
		(width 0.15494)
		(layer "In5.Cu")
		(net "SMB_PEX0_SLAVE1_SDA")
	)
	(segment
		(start 181.196234 -189.986158)
		(end 180.7083 -189.498224)
		(width 0.13208)
		(layer "F.Cu")
		(net "SPI_BIC1_LS01_EN")
	)
	(segment
		(start 184.691274 -188.895736)
		(end 185.350658 -188.895736)
		(width 0.13208)
		(layer "F.Cu")
		(net "SPI_BIC1_LS01_EN")
	)
	(segment
		(start 183.600852 -189.986158)
		(end 184.691274 -188.895736)
		(width 0.13208)
		(layer "F.Cu")
		(net "SPI_BIC1_LS01_EN")
	)
	(segment
		(start 180.7083 -189.498224)
		(end 180.7083 -187.431426)
		(width 0.13208)
		(layer "F.Cu")
		(net "SPI_BIC1_LS01_EN")
	)
	(segment
		(start 181.764178 -189.986158)
		(end 183.600852 -189.986158)
		(width 0.13208)
		(layer "F.Cu")
		(net "SPI_BIC1_LS01_EN")
	)
	(segment
		(start 180.7083 -187.431426)
		(end 181.593998 -186.545728)
		(width 0.13208)
		(layer "F.Cu")
		(net "SPI_BIC1_LS01_EN")
	)
	(segment
		(start 181.764178 -189.986158)
		(end 181.196234 -189.986158)
		(width 0.13208)
		(layer "F.Cu")
		(net "SPI_BIC1_LS01_EN")
	)
	(via
		(at 181.764178 -189.986158)
		(size 0.762)
		(drill 0.381)
		(layers "F.Cu" "B.Cu")
		(net "SPI_BIC1_LS01_EN")
	)
	(via
		(at 291.255196 -197.715886)
		(size 0.6604)
		(drill 0.3302)
		(layers "F.Cu" "B.Cu")
		(net "SPI_BIC1_LS23_EN")
	)
	(segment
		(start 292.779704 -197.715886)
		(end 292.971982 -197.908164)
		(width 0.13208)
		(layer "B.Cu")
		(net "SPI_BIC1_LS23_EN")
	)
	(segment
		(start 292.971982 -197.908164)
		(end 292.971982 -198.849742)
		(width 0.13208)
		(layer "B.Cu")
		(net "SPI_BIC1_LS23_EN")
	)
	(segment
		(start 289.462718 -198.860156)
		(end 290.606988 -197.715886)
		(width 0.13208)
		(layer "B.Cu")
		(net "SPI_BIC1_LS23_EN")
	)
	(segment
		(start 290.606988 -197.715886)
		(end 291.255196 -197.715886)
		(width 0.13208)
		(layer "B.Cu")
		(net "SPI_BIC1_LS23_EN")
	)
	(segment
		(start 291.255196 -197.715886)
		(end 292.779704 -197.715886)
		(width 0.13208)
		(layer "B.Cu")
		(net "SPI_BIC1_LS23_EN")
	)
	(segment
		(start 262.46836 -349.746824)
		(end 263.731248 -349.746824)
		(width 0.13208)
		(layer "F.Cu")
		(net "A_HSC_LOW_DRAIN")
	)
	(segment
		(start 263.904984 -349.573088)
		(end 263.904984 -348.397068)
		(width 0.13208)
		(layer "F.Cu")
		(net "A_HSC_LOW_DRAIN")
	)
	(segment
		(start 263.731248 -349.746824)
		(end 263.904984 -349.573088)
		(width 0.13208)
		(layer "F.Cu")
		(net "A_HSC_LOW_DRAIN")
	)
	(via
		(at 263.904984 -349.573088)
		(size 0.762)
		(drill 0.381)
		(layers "F.Cu" "B.Cu")
		(net "A_HSC_LOW_DRAIN")
	)
	(segment
		(start 257.569462 -349.695008)
		(end 257.569462 -350.720152)
		(width 0.13208)
		(layer "F.Cu")
		(net "A_HSC_LOW_GATE")
	)
	(segment
		(start 258.90982 -350.722438)
		(end 260.44271 -350.722438)
		(width 0.13208)
		(layer "F.Cu")
		(net "A_HSC_LOW_GATE")
	)
	(segment
		(start 264.608056 -342.807544)
		(end 264.608056 -344.073988)
		(width 0.13208)
		(layer "F.Cu")
		(net "A_HSC_LOW_GATE")
	)
	(segment
		(start 264.299192 -341.154766)
		(end 265.015726 -341.154766)
		(width 0.13208)
		(layer "F.Cu")
		(net "A_HSC_LOW_GATE")
	)
	(segment
		(start 262.94842 -340.92134)
		(end 262.94842 -341.101172)
		(width 0.13208)
		(layer "F.Cu")
		(net "A_HSC_LOW_GATE")
	)
	(segment
		(start 268.632432 -334.16367)
		(end 268.632432 -339.59673)
		(width 0.13208)
		(layer "F.Cu")
		(net "A_HSC_LOW_GATE")
	)
	(segment
		(start 268.632432 -339.59673)
		(end 267.624052 -340.60511)
		(width 0.13208)
		(layer "F.Cu")
		(net "A_HSC_LOW_GATE")
	)
	(segment
		(start 265.462258 -341.953342)
		(end 264.608056 -342.807544)
		(width 0.13208)
		(layer "F.Cu")
		(net "A_HSC_LOW_GATE")
	)
	(segment
		(start 262.94842 -341.101172)
		(end 263.340088 -341.49284)
		(width 0.13208)
		(layer "F.Cu")
		(net "A_HSC_LOW_GATE")
	)
	(segment
		(start 267.624052 -340.60511)
		(end 263.26465 -340.60511)
		(width 0.13208)
		(layer "F.Cu")
		(net "A_HSC_LOW_GATE")
	)
	(segment
		(start 260.44271 -350.722438)
		(end 260.468364 -350.696784)
		(width 0.13208)
		(layer "F.Cu")
		(net "A_HSC_LOW_GATE")
	)
	(segment
		(start 265.462258 -341.601298)
		(end 265.462258 -341.953342)
		(width 0.13208)
		(layer "F.Cu")
		(net "A_HSC_LOW_GATE")
	)
	(segment
		(start 263.961118 -341.49284)
		(end 264.299192 -341.154766)
		(width 0.13208)
		(layer "F.Cu")
		(net "A_HSC_LOW_GATE")
	)
	(segment
		(start 257.571748 -350.722438)
		(end 258.90982 -350.722438)
		(width 0.13208)
		(layer "F.Cu")
		(net "A_HSC_LOW_GATE")
	)
	(segment
		(start 257.569462 -350.720152)
		(end 257.571748 -350.722438)
		(width 0.13208)
		(layer "F.Cu")
		(net "A_HSC_LOW_GATE")
	)
	(segment
		(start 264.608056 -344.073988)
		(end 264.885424 -344.351356)
		(width 0.13208)
		(layer "F.Cu")
		(net "A_HSC_LOW_GATE")
	)
	(segment
		(start 265.015726 -341.154766)
		(end 265.462258 -341.601298)
		(width 0.13208)
		(layer "F.Cu")
		(net "A_HSC_LOW_GATE")
	)
	(segment
		(start 261.01675 -351.24517)
		(end 260.468364 -350.696784)
		(width 0.13208)
		(layer "F.Cu")
		(net "A_HSC_LOW_GATE")
	)
	(segment
		(start 268.620748 -333.104744)
		(end 268.620748 -334.151986)
		(width 0.13208)
		(layer "F.Cu")
		(net "A_HSC_LOW_GATE")
	)
	(segment
		(start 268.620748 -334.151986)
		(end 268.632432 -334.16367)
		(width 0.13208)
		(layer "F.Cu")
		(net "A_HSC_LOW_GATE")
	)
	(segment
		(start 264.885424 -350.109028)
		(end 263.749282 -351.24517)
		(width 0.13208)
		(layer "F.Cu")
		(net "A_HSC_LOW_GATE")
	)
	(segment
		(start 263.749282 -351.24517)
		(end 261.01675 -351.24517)
		(width 0.13208)
		(layer "F.Cu")
		(net "A_HSC_LOW_GATE")
	)
	(segment
		(start 263.26465 -340.60511)
		(end 262.94842 -340.92134)
		(width 0.13208)
		(layer "F.Cu")
		(net "A_HSC_LOW_GATE")
	)
	(segment
		(start 263.340088 -341.49284)
		(end 263.622282 -341.49284)
		(width 0.13208)
		(layer "F.Cu")
		(net "A_HSC_LOW_GATE")
	)
	(segment
		(start 264.885424 -344.351356)
		(end 264.885424 -350.109028)
		(width 0.13208)
		(layer "F.Cu")
		(net "A_HSC_LOW_GATE")
	)
	(segment
		(start 263.622282 -341.49284)
		(end 263.961118 -341.49284)
		(width 0.13208)
		(layer "F.Cu")
		(net "A_HSC_LOW_GATE")
	)
	(via
		(at 258.90982 -350.722438)
		(size 0.762)
		(drill 0.381)
		(layers "F.Cu" "B.Cu")
		(net "A_HSC_LOW_GATE")
	)
	(segment
		(start 257.565144 -346.337382)
		(end 257.599434 -346.303092)
		(width 0.13208)
		(layer "F.Cu")
		(net "A_HSC_HIGH")
	)
	(segment
		(start 260.176264 -343.851738)
		(end 260.635242 -343.39276)
		(width 0.13208)
		(layer "F.Cu")
		(net "A_HSC_HIGH")
	)
	(segment
		(start 258.891278 -346.303092)
		(end 260.176264 -345.018106)
		(width 0.13208)
		(layer "F.Cu")
		(net "A_HSC_HIGH")
	)
	(segment
		(start 260.635242 -343.39276)
		(end 261.002526 -343.39276)
		(width 0.13208)
		(layer "F.Cu")
		(net "A_HSC_HIGH")
	)
	(segment
		(start 257.599434 -346.303092)
		(end 258.891278 -346.303092)
		(width 0.13208)
		(layer "F.Cu")
		(net "A_HSC_HIGH")
	)
	(segment
		(start 260.176264 -345.018106)
		(end 260.176264 -343.851738)
		(width 0.13208)
		(layer "F.Cu")
		(net "A_HSC_HIGH")
	)
	(via
		(at 260.176264 -345.018106)
		(size 0.762)
		(drill 0.381)
		(layers "F.Cu" "B.Cu")
		(net "A_HSC_HIGH")
	)
	(segment
		(start 334.89392 -212.786976)
		(end 334.494124 -212.38718)
		(width 0.13208)
		(layer "F.Cu")
		(net "GPU_3V3IO_RSVD1_ISO_R")
	)
	(segment
		(start 404.846282 -366.409478)
		(end 405.58466 -366.409478)
		(width 0.13208)
		(layer "F.Cu")
		(net "GPU_3V3IO_RSVD1_ISO_R")
	)
	(segment
		(start 382.013206 -220.324172)
		(end 384.228848 -220.324172)
		(width 0.13208)
		(layer "F.Cu")
		(net "GPU_3V3IO_RSVD1_ISO_R")
	)
	(segment
		(start 369.257834 -218.27617)
		(end 379.965204 -218.27617)
		(width 0.13208)
		(layer "F.Cu")
		(net "GPU_3V3IO_RSVD1_ISO_R")
	)
	(segment
		(start 379.965204 -218.27617)
		(end 382.013206 -220.324172)
		(width 0.13208)
		(layer "F.Cu")
		(net "GPU_3V3IO_RSVD1_ISO_R")
	)
	(segment
		(start 367.976404 -219.5576)
		(end 369.257834 -218.27617)
		(width 0.13208)
		(layer "F.Cu")
		(net "GPU_3V3IO_RSVD1_ISO_R")
	)
	(via
		(at 367.976404 -219.5576)
		(size 0.508)
		(drill 0.254)
		(layers "F.Cu" "B.Cu")
		(net "GPU_3V3IO_RSVD1_ISO_R")
	)
	(via
		(at 384.228848 -220.324172)
		(size 0.508)
		(drill 0.254)
		(layers "F.Cu" "B.Cu")
		(net "GPU_3V3IO_RSVD1_ISO_R")
	)
	(via
		(at 405.58466 -366.409478)
		(size 0.508)
		(drill 0.254)
		(layers "F.Cu" "B.Cu")
		(net "GPU_3V3IO_RSVD1_ISO_R")
	)
	(via
		(at 334.494124 -212.38718)
		(size 0.4572)
		(drill 0.254)
		(layers "F.Cu" "B.Cu")
		(net "GPU_3V3IO_RSVD1_ISO_R")
	)
	(segment
		(start 383.9718 -224.0026)
		(end 385.604258 -224.0026)
		(width 0.13208)
		(layer "B.Cu")
		(net "GPU_3V3IO_RSVD1_ISO_R")
	)
	(segment
		(start 383.75463 -220.79839)
		(end 383.75463 -223.78543)
		(width 0.13208)
		(layer "B.Cu")
		(net "GPU_3V3IO_RSVD1_ISO_R")
	)
	(segment
		(start 444.449962 -249.496072)
		(end 445.772286 -250.818396)
		(width 0.13208)
		(layer "B.Cu")
		(net "GPU_3V3IO_RSVD1_ISO_R")
	)
	(segment
		(start 412.234634 -361.080558)
		(end 406.905714 -366.409478)
		(width 0.13208)
		(layer "B.Cu")
		(net "GPU_3V3IO_RSVD1_ISO_R")
	)
	(segment
		(start 387.2357 -229.964742)
		(end 387.685788 -229.964742)
		(width 0.13208)
		(layer "B.Cu")
		(net "GPU_3V3IO_RSVD1_ISO_R")
	)
	(segment
		(start 456.584304 -323.461126)
		(end 464.452208 -331.32903)
		(width 0.13208)
		(layer "B.Cu")
		(net "GPU_3V3IO_RSVD1_ISO_R")
	)
	(segment
		(start 451.209664 -252.91796)
		(end 450.912738 -253.214886)
		(width 0.13208)
		(layer "B.Cu")
		(net "GPU_3V3IO_RSVD1_ISO_R")
	)
	(segment
		(start 440.369706 -310.024526)
		(end 440.369706 -314.44057)
		(width 0.13208)
		(layer "B.Cu")
		(net "GPU_3V3IO_RSVD1_ISO_R")
	)
	(segment
		(start 406.905714 -366.409478)
		(end 405.58466 -366.409478)
		(width 0.13208)
		(layer "B.Cu")
		(net "GPU_3V3IO_RSVD1_ISO_R")
	)
	(segment
		(start 442.627004 -285.216346)
		(end 442.627004 -304.5714)
		(width 0.13208)
		(layer "B.Cu")
		(net "GPU_3V3IO_RSVD1_ISO_R")
	)
	(segment
		(start 385.604258 -224.0026)
		(end 386.339334 -224.737676)
		(width 0.13208)
		(layer "B.Cu")
		(net "GPU_3V3IO_RSVD1_ISO_R")
	)
	(segment
		(start 390.766046 -246.851678)
		(end 394.402056 -250.487688)
		(width 0.13208)
		(layer "B.Cu")
		(net "GPU_3V3IO_RSVD1_ISO_R")
	)
	(segment
		(start 384.228848 -220.324172)
		(end 383.75463 -220.79839)
		(width 0.13208)
		(layer "B.Cu")
		(net "GPU_3V3IO_RSVD1_ISO_R")
	)
	(segment
		(start 440.841892 -251.133102)
		(end 442.478922 -249.496072)
		(width 0.13208)
		(layer "B.Cu")
		(net "GPU_3V3IO_RSVD1_ISO_R")
	)
	(segment
		(start 439.078624 -307.12791)
		(end 439.078624 -308.733444)
		(width 0.13208)
		(layer "B.Cu")
		(net "GPU_3V3IO_RSVD1_ISO_R")
	)
	(segment
		(start 441.408566 -305.789838)
		(end 440.416696 -305.789838)
		(width 0.13208)
		(layer "B.Cu")
		(net "GPU_3V3IO_RSVD1_ISO_R")
	)
	(segment
		(start 461.506316 -361.080558)
		(end 412.234634 -361.080558)
		(width 0.13208)
		(layer "B.Cu")
		(net "GPU_3V3IO_RSVD1_ISO_R")
	)
	(segment
		(start 390.766046 -233.045)
		(end 390.766046 -246.851678)
		(width 0.13208)
		(layer "B.Cu")
		(net "GPU_3V3IO_RSVD1_ISO_R")
	)
	(segment
		(start 450.36613 -250.818396)
		(end 451.209664 -251.66193)
		(width 0.13208)
		(layer "B.Cu")
		(net "GPU_3V3IO_RSVD1_ISO_R")
	)
	(segment
		(start 386.339334 -224.737676)
		(end 386.339334 -229.068376)
		(width 0.13208)
		(layer "B.Cu")
		(net "GPU_3V3IO_RSVD1_ISO_R")
	)
	(segment
		(start 442.478922 -249.496072)
		(end 444.449962 -249.496072)
		(width 0.13208)
		(layer "B.Cu")
		(net "GPU_3V3IO_RSVD1_ISO_R")
	)
	(segment
		(start 416.284156 -250.487688)
		(end 416.92957 -251.133102)
		(width 0.13208)
		(layer "B.Cu")
		(net "GPU_3V3IO_RSVD1_ISO_R")
	)
	(segment
		(start 464.452208 -358.134666)
		(end 461.506316 -361.080558)
		(width 0.13208)
		(layer "B.Cu")
		(net "GPU_3V3IO_RSVD1_ISO_R")
	)
	(segment
		(start 387.685788 -229.964742)
		(end 390.766046 -233.045)
		(width 0.13208)
		(layer "B.Cu")
		(net "GPU_3V3IO_RSVD1_ISO_R")
	)
	(segment
		(start 445.210184 -282.633166)
		(end 442.627004 -285.216346)
		(width 0.13208)
		(layer "B.Cu")
		(net "GPU_3V3IO_RSVD1_ISO_R")
	)
	(segment
		(start 448.7291 -253.214886)
		(end 445.210184 -256.733802)
		(width 0.13208)
		(layer "B.Cu")
		(net "GPU_3V3IO_RSVD1_ISO_R")
	)
	(segment
		(start 464.452208 -331.32903)
		(end 464.452208 -358.134666)
		(width 0.13208)
		(layer "B.Cu")
		(net "GPU_3V3IO_RSVD1_ISO_R")
	)
	(segment
		(start 439.078624 -308.733444)
		(end 440.369706 -310.024526)
		(width 0.13208)
		(layer "B.Cu")
		(net "GPU_3V3IO_RSVD1_ISO_R")
	)
	(segment
		(start 383.75463 -223.78543)
		(end 383.9718 -224.0026)
		(width 0.13208)
		(layer "B.Cu")
		(net "GPU_3V3IO_RSVD1_ISO_R")
	)
	(segment
		(start 449.390262 -323.461126)
		(end 456.584304 -323.461126)
		(width 0.13208)
		(layer "B.Cu")
		(net "GPU_3V3IO_RSVD1_ISO_R")
	)
	(segment
		(start 442.627004 -304.5714)
		(end 441.408566 -305.789838)
		(width 0.13208)
		(layer "B.Cu")
		(net "GPU_3V3IO_RSVD1_ISO_R")
	)
	(segment
		(start 445.210184 -256.733802)
		(end 445.210184 -282.633166)
		(width 0.13208)
		(layer "B.Cu")
		(net "GPU_3V3IO_RSVD1_ISO_R")
	)
	(segment
		(start 451.209664 -251.66193)
		(end 451.209664 -252.91796)
		(width 0.13208)
		(layer "B.Cu")
		(net "GPU_3V3IO_RSVD1_ISO_R")
	)
	(segment
		(start 394.402056 -250.487688)
		(end 416.284156 -250.487688)
		(width 0.13208)
		(layer "B.Cu")
		(net "GPU_3V3IO_RSVD1_ISO_R")
	)
	(segment
		(start 440.369706 -314.44057)
		(end 449.390262 -323.461126)
		(width 0.13208)
		(layer "B.Cu")
		(net "GPU_3V3IO_RSVD1_ISO_R")
	)
	(segment
		(start 416.92957 -251.133102)
		(end 440.841892 -251.133102)
		(width 0.13208)
		(layer "B.Cu")
		(net "GPU_3V3IO_RSVD1_ISO_R")
	)
	(segment
		(start 450.912738 -253.214886)
		(end 448.7291 -253.214886)
		(width 0.13208)
		(layer "B.Cu")
		(net "GPU_3V3IO_RSVD1_ISO_R")
	)
	(segment
		(start 445.772286 -250.818396)
		(end 450.36613 -250.818396)
		(width 0.13208)
		(layer "B.Cu")
		(net "GPU_3V3IO_RSVD1_ISO_R")
	)
	(segment
		(start 386.339334 -229.068376)
		(end 387.2357 -229.964742)
		(width 0.13208)
		(layer "B.Cu")
		(net "GPU_3V3IO_RSVD1_ISO_R")
	)
	(segment
		(start 440.416696 -305.789838)
		(end 439.078624 -307.12791)
		(width 0.13208)
		(layer "B.Cu")
		(net "GPU_3V3IO_RSVD1_ISO_R")
	)
	(segment
		(start 343.60358 -214.389462)
		(end 342.94699 -214.389462)
		(width 0.0889)
		(layer "In13.Cu")
		(net "GPU_3V3IO_RSVD1_ISO_R")
	)
	(segment
		(start 359.776776 -210.823556)
		(end 356.058216 -210.823556)
		(width 0.15494)
		(layer "In13.Cu")
		(net "GPU_3V3IO_RSVD1_ISO_R")
	)
	(segment
		(start 343.694004 -214.299038)
		(end 343.60358 -214.389462)
		(width 0.0889)
		(layer "In13.Cu")
		(net "GPU_3V3IO_RSVD1_ISO_R")
	)
	(segment
		(start 367.976404 -219.5576)
		(end 367.14303 -218.724226)
		(width 0.15494)
		(layer "In13.Cu")
		(net "GPU_3V3IO_RSVD1_ISO_R")
	)
	(segment
		(start 353.293934 -213.587838)
		(end 343.870534 -213.587838)
		(width 0.0889)
		(layer "In13.Cu")
		(net "GPU_3V3IO_RSVD1_ISO_R")
	)
	(segment
		(start 337.295744 -212.17636)
		(end 337.295744 -212.551772)
		(width 0.0889)
		(layer "In13.Cu")
		(net "GPU_3V3IO_RSVD1_ISO_R")
	)
	(segment
		(start 356.058216 -210.823556)
		(end 353.293934 -213.587838)
		(width 0.15494)
		(layer "In13.Cu")
		(net "GPU_3V3IO_RSVD1_ISO_R")
	)
	(segment
		(start 363.09427 -209.015584)
		(end 362.712254 -209.3976)
		(width 0.15494)
		(layer "In13.Cu")
		(net "GPU_3V3IO_RSVD1_ISO_R")
	)
	(segment
		(start 337.48472 -211.987384)
		(end 337.295744 -212.17636)
		(width 0.0889)
		(layer "In13.Cu")
		(net "GPU_3V3IO_RSVD1_ISO_R")
	)
	(segment
		(start 361.202732 -209.3976)
		(end 359.776776 -210.823556)
		(width 0.15494)
		(layer "In13.Cu")
		(net "GPU_3V3IO_RSVD1_ISO_R")
	)
	(segment
		(start 342.137492 -212.168994)
		(end 341.955882 -211.987384)
		(width 0.0889)
		(layer "In13.Cu")
		(net "GPU_3V3IO_RSVD1_ISO_R")
	)
	(segment
		(start 367.14303 -211.515452)
		(end 364.643162 -209.015584)
		(width 0.15494)
		(layer "In13.Cu")
		(net "GPU_3V3IO_RSVD1_ISO_R")
	)
	(segment
		(start 362.712254 -209.3976)
		(end 361.202732 -209.3976)
		(width 0.15494)
		(layer "In13.Cu")
		(net "GPU_3V3IO_RSVD1_ISO_R")
	)
	(segment
		(start 342.94699 -214.389462)
		(end 342.137492 -213.579964)
		(width 0.0889)
		(layer "In13.Cu")
		(net "GPU_3V3IO_RSVD1_ISO_R")
	)
	(segment
		(start 342.137492 -213.579964)
		(end 342.137492 -212.168994)
		(width 0.0889)
		(layer "In13.Cu")
		(net "GPU_3V3IO_RSVD1_ISO_R")
	)
	(segment
		(start 337.06181 -212.785706)
		(end 334.89265 -212.785706)
		(width 0.0889)
		(layer "In13.Cu")
		(net "GPU_3V3IO_RSVD1_ISO_R")
	)
	(segment
		(start 337.295744 -212.551772)
		(end 337.06181 -212.785706)
		(width 0.0889)
		(layer "In13.Cu")
		(net "GPU_3V3IO_RSVD1_ISO_R")
	)
	(segment
		(start 343.694004 -213.764368)
		(end 343.694004 -214.299038)
		(width 0.0889)
		(layer "In13.Cu")
		(net "GPU_3V3IO_RSVD1_ISO_R")
	)
	(segment
		(start 364.643162 -209.015584)
		(end 363.09427 -209.015584)
		(width 0.15494)
		(layer "In13.Cu")
		(net "GPU_3V3IO_RSVD1_ISO_R")
	)
	(segment
		(start 334.89265 -212.785706)
		(end 334.494124 -212.38718)
		(width 0.0889)
		(layer "In13.Cu")
		(net "GPU_3V3IO_RSVD1_ISO_R")
	)
	(segment
		(start 343.870534 -213.587838)
		(end 343.694004 -213.764368)
		(width 0.0889)
		(layer "In13.Cu")
		(net "GPU_3V3IO_RSVD1_ISO_R")
	)
	(segment
		(start 367.14303 -218.724226)
		(end 367.14303 -211.515452)
		(width 0.15494)
		(layer "In13.Cu")
		(net "GPU_3V3IO_RSVD1_ISO_R")
	)
	(segment
		(start 341.955882 -211.987384)
		(end 337.48472 -211.987384)
		(width 0.0889)
		(layer "In13.Cu")
		(net "GPU_3V3IO_RSVD1_ISO_R")
	)
	(segment
		(start 256.853436 -343.302336)
		(end 255.476756 -343.302336)
		(width 0.13208)
		(layer "F.Cu")
		(net "A_HSC_LOW")
	)
	(segment
		(start 262.278622 -341.20963)
		(end 261.908798 -340.839806)
		(width 0.13208)
		(layer "F.Cu")
		(net "A_HSC_LOW")
	)
	(segment
		(start 257.573018 -347.68409)
		(end 257.570732 -347.686376)
		(width 0.13208)
		(layer "F.Cu")
		(net "A_HSC_LOW")
	)
	(segment
		(start 263.622282 -343.39276)
		(end 262.603996 -343.39276)
		(width 0.13208)
		(layer "F.Cu")
		(net "A_HSC_LOW")
	)
	(segment
		(start 257.523488 -342.632284)
		(end 256.853436 -343.302336)
		(width 0.13208)
		(layer "F.Cu")
		(net "A_HSC_LOW")
	)
	(segment
		(start 255.784604 -348.167706)
		(end 257.089402 -348.167706)
		(width 0.13208)
		(layer "F.Cu")
		(net "A_HSC_LOW")
	)
	(segment
		(start 261.908798 -340.839806)
		(end 257.890264 -340.839806)
		(width 0.13208)
		(layer "F.Cu")
		(net "A_HSC_LOW")
	)
	(segment
		(start 257.570732 -347.686376)
		(end 257.570732 -348.674436)
		(width 0.13208)
		(layer "F.Cu")
		(net "A_HSC_LOW")
	)
	(segment
		(start 257.364484 -341.819738)
		(end 257.523488 -341.978742)
		(width 0.13208)
		(layer "F.Cu")
		(net "A_HSC_LOW")
	)
	(segment
		(start 262.603996 -343.39276)
		(end 262.278622 -343.067386)
		(width 0.13208)
		(layer "F.Cu")
		(net "A_HSC_LOW")
	)
	(segment
		(start 255.422908 -347.80601)
		(end 255.784604 -348.167706)
		(width 0.13208)
		(layer "F.Cu")
		(net "A_HSC_LOW")
	)
	(segment
		(start 262.278622 -343.067386)
		(end 262.278622 -341.20963)
		(width 0.13208)
		(layer "F.Cu")
		(net "A_HSC_LOW")
	)
	(segment
		(start 255.476756 -343.302336)
		(end 255.422908 -343.356184)
		(width 0.13208)
		(layer "F.Cu")
		(net "A_HSC_LOW")
	)
	(segment
		(start 257.523488 -341.978742)
		(end 257.523488 -342.632284)
		(width 0.13208)
		(layer "F.Cu")
		(net "A_HSC_LOW")
	)
	(segment
		(start 257.364484 -341.365586)
		(end 257.364484 -341.819738)
		(width 0.13208)
		(layer "F.Cu")
		(net "A_HSC_LOW")
	)
	(segment
		(start 255.422908 -343.356184)
		(end 255.422908 -347.80601)
		(width 0.13208)
		(layer "F.Cu")
		(net "A_HSC_LOW")
	)
	(segment
		(start 257.089402 -348.167706)
		(end 257.570732 -347.686376)
		(width 0.13208)
		(layer "F.Cu")
		(net "A_HSC_LOW")
	)
	(segment
		(start 257.890264 -340.839806)
		(end 257.364484 -341.365586)
		(width 0.13208)
		(layer "F.Cu")
		(net "A_HSC_LOW")
	)
	(via
		(at 255.476756 -343.302336)
		(size 0.762)
		(drill 0.381)
		(layers "F.Cu" "B.Cu")
		(net "A_HSC_LOW")
	)
	(segment
		(start 452.927212 -365.953548)
		(end 452.927212 -365.1377)
		(width 0.13208)
		(layer "F.Cu")
		(net "GPU_3V3IO_RSVD1_ISO")
	)
	(segment
		(start 403.287484 -370.219478)
		(end 403.287484 -369.425474)
		(width 0.13208)
		(layer "F.Cu")
		(net "GPU_3V3IO_RSVD1_ISO")
	)
	(segment
		(start 404.47214 -365.534956)
		(end 404.861268 -365.534956)
		(width 0.13208)
		(layer "F.Cu")
		(net "GPU_3V3IO_RSVD1_ISO")
	)
	(segment
		(start 403.287484 -370.219478)
		(end 404.626826 -370.219478)
		(width 0.13208)
		(layer "F.Cu")
		(net "GPU_3V3IO_RSVD1_ISO")
	)
	(segment
		(start 404.046182 -365.960914)
		(end 404.47214 -365.534956)
		(width 0.13208)
		(layer "F.Cu")
		(net "GPU_3V3IO_RSVD1_ISO")
	)
	(segment
		(start 404.046182 -366.409478)
		(end 404.046182 -365.960914)
		(width 0.13208)
		(layer "F.Cu")
		(net "GPU_3V3IO_RSVD1_ISO")
	)
	(segment
		(start 403.287484 -369.425474)
		(end 404.039578 -368.67338)
		(width 0.13208)
		(layer "F.Cu")
		(net "GPU_3V3IO_RSVD1_ISO")
	)
	(segment
		(start 404.039578 -367.407952)
		(end 404.039578 -366.416082)
		(width 0.13208)
		(layer "F.Cu")
		(net "GPU_3V3IO_RSVD1_ISO")
	)
	(segment
		(start 404.039578 -366.416082)
		(end 404.046182 -366.409478)
		(width 0.13208)
		(layer "F.Cu")
		(net "GPU_3V3IO_RSVD1_ISO")
	)
	(segment
		(start 404.039578 -368.67338)
		(end 404.039578 -367.407952)
		(width 0.13208)
		(layer "F.Cu")
		(net "GPU_3V3IO_RSVD1_ISO")
	)
	(via
		(at 404.626826 -370.219478)
		(size 0.508)
		(drill 0.254)
		(layers "F.Cu" "B.Cu")
		(net "GPU_3V3IO_RSVD1_ISO")
	)
	(via
		(at 404.039578 -368.67338)
		(size 0.762)
		(drill 0.381)
		(layers "F.Cu" "B.Cu")
		(net "GPU_3V3IO_RSVD1_ISO")
	)
	(via
		(at 452.927212 -365.1377)
		(size 0.508)
		(drill 0.254)
		(layers "F.Cu" "B.Cu")
		(net "GPU_3V3IO_RSVD1_ISO")
	)
	(segment
		(start 450.60997 -361.933998)
		(end 452.927212 -364.25124)
		(width 0.13208)
		(layer "B.Cu")
		(net "GPU_3V3IO_RSVD1_ISO")
	)
	(segment
		(start 407.48458 -369.296188)
		(end 407.48458 -367.03762)
		(width 0.13208)
		(layer "B.Cu")
		(net "GPU_3V3IO_RSVD1_ISO")
	)
	(segment
		(start 404.626826 -370.219478)
		(end 404.843742 -370.002562)
		(width 0.13208)
		(layer "B.Cu")
		(net "GPU_3V3IO_RSVD1_ISO")
	)
	(segment
		(start 407.48458 -367.03762)
		(end 412.588202 -361.933998)
		(width 0.13208)
		(layer "B.Cu")
		(net "GPU_3V3IO_RSVD1_ISO")
	)
	(segment
		(start 407.15311 -369.627658)
		(end 407.48458 -369.296188)
		(width 0.13208)
		(layer "B.Cu")
		(net "GPU_3V3IO_RSVD1_ISO")
	)
	(segment
		(start 412.588202 -361.933998)
		(end 450.60997 -361.933998)
		(width 0.13208)
		(layer "B.Cu")
		(net "GPU_3V3IO_RSVD1_ISO")
	)
	(segment
		(start 406.247854 -370.002562)
		(end 407.15311 -369.627658)
		(width 0.13208)
		(layer "B.Cu")
		(net "GPU_3V3IO_RSVD1_ISO")
	)
	(segment
		(start 452.927212 -364.25124)
		(end 452.927212 -365.1377)
		(width 0.13208)
		(layer "B.Cu")
		(net "GPU_3V3IO_RSVD1_ISO")
	)
	(segment
		(start 404.843742 -370.002562)
		(end 406.247854 -370.002562)
		(width 0.13208)
		(layer "B.Cu")
		(net "GPU_3V3IO_RSVD1_ISO")
	)
	(segment
		(start 454.08723 -365.19231)
		(end 454.08723 -366.464596)
		(width 0.13208)
		(layer "F.Cu")
		(net "GPU_3V3IO_RSVD1_N")
	)
	(segment
		(start 454.326244 -366.70361)
		(end 454.727056 -366.70361)
		(width 0.13208)
		(layer "F.Cu")
		(net "GPU_3V3IO_RSVD1_N")
	)
	(segment
		(start 454.727056 -367.453672)
		(end 454.727056 -366.70361)
		(width 0.13208)
		(layer "F.Cu")
		(net "GPU_3V3IO_RSVD1_N")
	)
	(segment
		(start 454.08723 -366.464596)
		(end 454.326244 -366.70361)
		(width 0.13208)
		(layer "F.Cu")
		(net "GPU_3V3IO_RSVD1_N")
	)
	(segment
		(start 406.484582 -367.42624)
		(end 406.484582 -368.063272)
		(width 0.13208)
		(layer "F.Cu")
		(net "GPU_3V3IO_RSVD1_N")
	)
	(via
		(at 406.484582 -368.063272)
		(size 0.508)
		(drill 0.254)
		(layers "F.Cu" "B.Cu")
		(net "GPU_3V3IO_RSVD1_N")
	)
	(via
		(at 454.08723 -365.19231)
		(size 0.508)
		(drill 0.254)
		(layers "F.Cu" "B.Cu")
		(net "GPU_3V3IO_RSVD1_N")
	)
	(segment
		(start 406.484582 -368.063272)
		(end 406.484582 -367.232946)
		(width 0.13208)
		(layer "B.Cu")
		(net "GPU_3V3IO_RSVD1_N")
	)
	(segment
		(start 406.484582 -367.232946)
		(end 412.35249 -361.365038)
		(width 0.13208)
		(layer "B.Cu")
		(net "GPU_3V3IO_RSVD1_N")
	)
	(segment
		(start 451.10019 -361.365038)
		(end 454.08723 -364.352078)
		(width 0.13208)
		(layer "B.Cu")
		(net "GPU_3V3IO_RSVD1_N")
	)
	(segment
		(start 412.35249 -361.365038)
		(end 451.10019 -361.365038)
		(width 0.13208)
		(layer "B.Cu")
		(net "GPU_3V3IO_RSVD1_N")
	)
	(segment
		(start 454.08723 -364.352078)
		(end 454.08723 -365.19231)
		(width 0.13208)
		(layer "B.Cu")
		(net "GPU_3V3IO_RSVD1_N")
	)
	(segment
		(start 126.880112 -167.752014)
		(end 126.880112 -167.092122)
		(width 0.13208)
		(layer "F.Cu")
		(net "NIC0_CLK_EN_BUF_R_N")
	)
	(segment
		(start 126.880112 -167.092122)
		(end 126.880112 -166.427404)
		(width 0.13208)
		(layer "F.Cu")
		(net "NIC0_CLK_EN_BUF_R_N")
	)
	(segment
		(start 126.880112 -166.427404)
		(end 126.89967 -166.407846)
		(width 0.13208)
		(layer "F.Cu")
		(net "NIC0_CLK_EN_BUF_R_N")
	)
	(segment
		(start 133.471158 -175.400462)
		(end 133.221222 -175.880522)
		(width 0.13208)
		(layer "F.Cu")
		(net "NIC0_CLK_EN_BUF_R_N")
	)
	(via
		(at 133.221222 -175.880522)
		(size 0.4572)
		(drill 0.254)
		(layers "F.Cu" "B.Cu")
		(net "NIC0_CLK_EN_BUF_R_N")
	)
	(via
		(at 126.880112 -167.092122)
		(size 0.508)
		(drill 0.254)
		(layers "F.Cu" "B.Cu")
		(net "NIC0_CLK_EN_BUF_R_N")
	)
	(segment
		(start 127.957072 -166.015162)
		(end 135.931148 -166.015162)
		(width 0.15494)
		(layer "In11.Cu")
		(net "NIC0_CLK_EN_BUF_R_N")
	)
	(segment
		(start 137.406634 -170.726354)
		(end 133.221222 -174.911766)
		(width 0.15494)
		(layer "In11.Cu")
		(net "NIC0_CLK_EN_BUF_R_N")
	)
	(segment
		(start 137.406634 -167.490648)
		(end 137.406634 -170.726354)
		(width 0.15494)
		(layer "In11.Cu")
		(net "NIC0_CLK_EN_BUF_R_N")
	)
	(segment
		(start 126.880112 -167.092122)
		(end 127.957072 -166.015162)
		(width 0.15494)
		(layer "In11.Cu")
		(net "NIC0_CLK_EN_BUF_R_N")
	)
	(segment
		(start 133.221222 -174.911766)
		(end 133.221222 -175.880522)
		(width 0.15494)
		(layer "In11.Cu")
		(net "NIC0_CLK_EN_BUF_R_N")
	)
	(segment
		(start 135.931148 -166.015162)
		(end 137.406634 -167.490648)
		(width 0.15494)
		(layer "In11.Cu")
		(net "NIC0_CLK_EN_BUF_R_N")
	)
	(segment
		(start 181.203854 -180.327046)
		(end 181.203854 -179.569618)
		(width 0.13208)
		(layer "F.Cu")
		(net "NIC2_CLK_EN_BUF_R_N")
	)
	(segment
		(start 181.203854 -179.569618)
		(end 181.199028 -179.564792)
		(width 0.13208)
		(layer "F.Cu")
		(net "NIC2_CLK_EN_BUF_R_N")
	)
	(segment
		(start 180.389784 -180.154072)
		(end 180.562758 -180.327046)
		(width 0.13208)
		(layer "F.Cu")
		(net "NIC2_CLK_EN_BUF_R_N")
	)
	(segment
		(start 180.562758 -180.327046)
		(end 181.203854 -180.327046)
		(width 0.13208)
		(layer "F.Cu")
		(net "NIC2_CLK_EN_BUF_R_N")
	)
	(segment
		(start 180.389784 -179.720748)
		(end 180.389784 -180.154072)
		(width 0.13208)
		(layer "F.Cu")
		(net "NIC2_CLK_EN_BUF_R_N")
	)
	(segment
		(start 179.61864 -180.162962)
		(end 179.94757 -180.162962)
		(width 0.13208)
		(layer "F.Cu")
		(net "NIC2_CLK_EN_BUF_R_N")
	)
	(segment
		(start 181.199028 -179.564792)
		(end 181.199028 -179.149248)
		(width 0.13208)
		(layer "F.Cu")
		(net "NIC2_CLK_EN_BUF_R_N")
	)
	(segment
		(start 134.49173 -176.515014)
		(end 134.971028 -175.900334)
		(width 0.0889)
		(layer "F.Cu")
		(net "NIC2_CLK_EN_BUF_R_N")
	)
	(segment
		(start 179.94757 -180.162962)
		(end 180.389784 -179.720748)
		(width 0.13208)
		(layer "F.Cu")
		(net "NIC2_CLK_EN_BUF_R_N")
	)
	(segment
		(start 134.491222 -176.515522)
		(end 134.49173 -176.515014)
		(width 0.0889)
		(layer "F.Cu")
		(net "NIC2_CLK_EN_BUF_R_N")
	)
	(via
		(at 134.491222 -176.515522)
		(size 0.4572)
		(drill 0.254)
		(layers "F.Cu" "B.Cu")
		(net "NIC2_CLK_EN_BUF_R_N")
	)
	(via
		(at 180.389784 -179.720748)
		(size 0.508)
		(drill 0.254)
		(layers "F.Cu" "B.Cu")
		(net "NIC2_CLK_EN_BUF_R_N")
	)
	(via
		(at 181.203854 -180.327046)
		(size 0.762)
		(drill 0.381)
		(layers "F.Cu" "B.Cu")
		(net "NIC2_CLK_EN_BUF_R_N")
	)
	(segment
		(start 178.303682 -179.720748)
		(end 174.020734 -175.4378)
		(width 0.15494)
		(layer "In13.Cu")
		(net "NIC2_CLK_EN_BUF_R_N")
	)
	(segment
		(start 168.477946 -175.4378)
		(end 167.512746 -174.4726)
		(width 0.15494)
		(layer "In13.Cu")
		(net "NIC2_CLK_EN_BUF_R_N")
	)
	(segment
		(start 149.2377 -174.4726)
		(end 145.6055 -170.8404)
		(width 0.15494)
		(layer "In13.Cu")
		(net "NIC2_CLK_EN_BUF_R_N")
	)
	(segment
		(start 180.389784 -179.720748)
		(end 178.303682 -179.720748)
		(width 0.15494)
		(layer "In13.Cu")
		(net "NIC2_CLK_EN_BUF_R_N")
	)
	(segment
		(start 135.802624 -176.515522)
		(end 134.491222 -176.515522)
		(width 0.15494)
		(layer "In13.Cu")
		(net "NIC2_CLK_EN_BUF_R_N")
	)
	(segment
		(start 174.020734 -175.4378)
		(end 168.477946 -175.4378)
		(width 0.15494)
		(layer "In13.Cu")
		(net "NIC2_CLK_EN_BUF_R_N")
	)
	(segment
		(start 167.512746 -174.4726)
		(end 149.2377 -174.4726)
		(width 0.15494)
		(layer "In13.Cu")
		(net "NIC2_CLK_EN_BUF_R_N")
	)
	(segment
		(start 145.6055 -170.8404)
		(end 141.477746 -170.8404)
		(width 0.15494)
		(layer "In13.Cu")
		(net "NIC2_CLK_EN_BUF_R_N")
	)
	(segment
		(start 141.477746 -170.8404)
		(end 135.802624 -176.515522)
		(width 0.15494)
		(layer "In13.Cu")
		(net "NIC2_CLK_EN_BUF_R_N")
	)
	(segment
		(start 134.471156 -175.400462)
		(end 134.355332 -175.448468)
		(width 0.0889)
		(layer "F.Cu")
		(net "NIC1_CLK_EN_BUF_R_N")
	)
	(segment
		(start 121.611898 -166.248588)
		(end 121.611898 -165.838124)
		(width 0.13208)
		(layer "F.Cu")
		(net "NIC1_CLK_EN_BUF_R_N")
	)
	(segment
		(start 134.355332 -175.448468)
		(end 133.923278 -175.880522)
		(width 0.0889)
		(layer "F.Cu")
		(net "NIC1_CLK_EN_BUF_R_N")
	)
	(segment
		(start 133.923278 -175.880522)
		(end 133.856222 -175.880522)
		(width 0.0889)
		(layer "F.Cu")
		(net "NIC1_CLK_EN_BUF_R_N")
	)
	(segment
		(start 121.611898 -164.849048)
		(end 121.611898 -165.838124)
		(width 0.13208)
		(layer "F.Cu")
		(net "NIC1_CLK_EN_BUF_R_N")
	)
	(segment
		(start 121.623074 -164.837872)
		(end 121.611898 -164.849048)
		(width 0.13208)
		(layer "F.Cu")
		(net "NIC1_CLK_EN_BUF_R_N")
	)
	(segment
		(start 122.362468 -166.999158)
		(end 121.611898 -166.248588)
		(width 0.13208)
		(layer "F.Cu")
		(net "NIC1_CLK_EN_BUF_R_N")
	)
	(via
		(at 133.856222 -175.880522)
		(size 0.4572)
		(drill 0.254)
		(layers "F.Cu" "B.Cu")
		(net "NIC1_CLK_EN_BUF_R_N")
	)
	(via
		(at 122.362468 -166.999158)
		(size 0.508)
		(drill 0.254)
		(layers "F.Cu" "B.Cu")
		(net "NIC1_CLK_EN_BUF_R_N")
	)
	(segment
		(start 123.755658 -165.605968)
		(end 136.090914 -165.605968)
		(width 0.15494)
		(layer "In11.Cu")
		(net "NIC1_CLK_EN_BUF_R_N")
	)
	(segment
		(start 122.362468 -166.999158)
		(end 123.755658 -165.605968)
		(width 0.15494)
		(layer "In11.Cu")
		(net "NIC1_CLK_EN_BUF_R_N")
	)
	(segment
		(start 136.090914 -165.605968)
		(end 137.781792 -167.296846)
		(width 0.15494)
		(layer "In11.Cu")
		(net "NIC1_CLK_EN_BUF_R_N")
	)
	(segment
		(start 133.856222 -174.78883)
		(end 133.856222 -175.880522)
		(width 0.15494)
		(layer "In11.Cu")
		(net "NIC1_CLK_EN_BUF_R_N")
	)
	(segment
		(start 137.781792 -170.86326)
		(end 133.856222 -174.78883)
		(width 0.15494)
		(layer "In11.Cu")
		(net "NIC1_CLK_EN_BUF_R_N")
	)
	(segment
		(start 137.781792 -167.296846)
		(end 137.781792 -170.86326)
		(width 0.15494)
		(layer "In11.Cu")
		(net "NIC1_CLK_EN_BUF_R_N")
	)
	(segment
		(start 364.857792 -393.60094)
		(end 364.225586 -394.233146)
		(width 0.13208)
		(layer "F.Cu")
		(net "MB_3V3IO_RSVD1_ISO_R")
	)
	(segment
		(start 366.548162 -387.909054)
		(end 366.538764 -387.918452)
		(width 0.13208)
		(layer "F.Cu")
		(net "MB_3V3IO_RSVD1_ISO_R")
	)
	(segment
		(start 366.538764 -387.918452)
		(end 366.538764 -391.919968)
		(width 0.13208)
		(layer "F.Cu")
		(net "MB_3V3IO_RSVD1_ISO_R")
	)
	(segment
		(start 366.538764 -391.919968)
		(end 364.857792 -393.60094)
		(width 0.13208)
		(layer "F.Cu")
		(net "MB_3V3IO_RSVD1_ISO_R")
	)
	(segment
		(start 359.957624 -394.233146)
		(end 358.542844 -392.818366)
		(width 0.13208)
		(layer "F.Cu")
		(net "MB_3V3IO_RSVD1_ISO_R")
	)
	(segment
		(start 364.225586 -394.233146)
		(end 359.957624 -394.233146)
		(width 0.13208)
		(layer "F.Cu")
		(net "MB_3V3IO_RSVD1_ISO_R")
	)
	(segment
		(start 338.893912 -216.786968)
		(end 338.494116 -216.387172)
		(width 0.13208)
		(layer "F.Cu")
		(net "MB_3V3IO_RSVD1_ISO_R")
	)
	(via
		(at 338.494116 -216.387172)
		(size 0.4572)
		(drill 0.254)
		(layers "F.Cu" "B.Cu")
		(net "MB_3V3IO_RSVD1_ISO_R")
	)
	(via
		(at 364.857792 -393.60094)
		(size 0.762)
		(drill 0.381)
		(layers "F.Cu" "B.Cu")
		(net "MB_3V3IO_RSVD1_ISO_R")
	)
	(via
		(at 359.990136 -231.396286)
		(size 0.508)
		(drill 0.254)
		(layers "F.Cu" "B.Cu")
		(net "MB_3V3IO_RSVD1_ISO_R")
	)
	(via
		(at 366.548162 -387.909054)
		(size 0.508)
		(drill 0.254)
		(layers "F.Cu" "B.Cu")
		(net "MB_3V3IO_RSVD1_ISO_R")
	)
	(via
		(at 393.320016 -232.585006)
		(size 0.508)
		(drill 0.254)
		(layers "F.Cu" "B.Cu")
		(net "MB_3V3IO_RSVD1_ISO_R")
	)
	(segment
		(start 442.541406 -306.076096)
		(end 442.541406 -309.002938)
		(width 0.13208)
		(layer "B.Cu")
		(net "MB_3V3IO_RSVD1_ISO_R")
	)
	(segment
		(start 452.99757 -253.441962)
		(end 452.3613 -254.078232)
		(width 0.13208)
		(layer "B.Cu")
		(net "MB_3V3IO_RSVD1_ISO_R")
	)
	(segment
		(start 452.99757 -252.242828)
		(end 452.99757 -253.441962)
		(width 0.13208)
		(layer "B.Cu")
		(net "MB_3V3IO_RSVD1_ISO_R")
	)
	(segment
		(start 393.320016 -235.023406)
		(end 391.758932 -236.58449)
		(width 0.13208)
		(layer "B.Cu")
		(net "MB_3V3IO_RSVD1_ISO_R")
	)
	(segment
		(start 442.714888 -315.578744)
		(end 449.74383 -322.607686)
		(width 0.13208)
		(layer "B.Cu")
		(net "MB_3V3IO_RSVD1_ISO_R")
	)
	(segment
		(start 394.769594 -249.50801)
		(end 416.620706 -249.50801)
		(width 0.13208)
		(layer "B.Cu")
		(net "MB_3V3IO_RSVD1_ISO_R")
	)
	(segment
		(start 449.072762 -254.078232)
		(end 446.063624 -257.08737)
		(width 0.13208)
		(layer "B.Cu")
		(net "MB_3V3IO_RSVD1_ISO_R")
	)
	(segment
		(start 443.534546 -305.082956)
		(end 442.541406 -306.076096)
		(width 0.13208)
		(layer "B.Cu")
		(net "MB_3V3IO_RSVD1_ISO_R")
	)
	(segment
		(start 408.252676 -390.570212)
		(end 405.591518 -387.909054)
		(width 0.13208)
		(layer "B.Cu")
		(net "MB_3V3IO_RSVD1_ISO_R")
	)
	(segment
		(start 393.320016 -232.585006)
		(end 393.320016 -235.023406)
		(width 0.13208)
		(layer "B.Cu")
		(net "MB_3V3IO_RSVD1_ISO_R")
	)
	(segment
		(start 417.808918 -248.319798)
		(end 449.07454 -248.319798)
		(width 0.13208)
		(layer "B.Cu")
		(net "MB_3V3IO_RSVD1_ISO_R")
	)
	(segment
		(start 457.297028 -322.607686)
		(end 465.644738 -330.955396)
		(width 0.13208)
		(layer "B.Cu")
		(net "MB_3V3IO_RSVD1_ISO_R")
	)
	(segment
		(start 449.74383 -322.607686)
		(end 457.297028 -322.607686)
		(width 0.13208)
		(layer "B.Cu")
		(net "MB_3V3IO_RSVD1_ISO_R")
	)
	(segment
		(start 449.07454 -248.319798)
		(end 452.99757 -252.242828)
		(width 0.13208)
		(layer "B.Cu")
		(net "MB_3V3IO_RSVD1_ISO_R")
	)
	(segment
		(start 446.063624 -282.986734)
		(end 443.534546 -285.515812)
		(width 0.13208)
		(layer "B.Cu")
		(net "MB_3V3IO_RSVD1_ISO_R")
	)
	(segment
		(start 442.541406 -309.002938)
		(end 442.714888 -309.17642)
		(width 0.13208)
		(layer "B.Cu")
		(net "MB_3V3IO_RSVD1_ISO_R")
	)
	(segment
		(start 391.758932 -246.497348)
		(end 394.769594 -249.50801)
		(width 0.13208)
		(layer "B.Cu")
		(net "MB_3V3IO_RSVD1_ISO_R")
	)
	(segment
		(start 452.3613 -254.078232)
		(end 449.072762 -254.078232)
		(width 0.13208)
		(layer "B.Cu")
		(net "MB_3V3IO_RSVD1_ISO_R")
	)
	(segment
		(start 465.644738 -369.99545)
		(end 445.069976 -390.570212)
		(width 0.13208)
		(layer "B.Cu")
		(net "MB_3V3IO_RSVD1_ISO_R")
	)
	(segment
		(start 465.644738 -330.955396)
		(end 465.644738 -369.99545)
		(width 0.13208)
		(layer "B.Cu")
		(net "MB_3V3IO_RSVD1_ISO_R")
	)
	(segment
		(start 443.534546 -285.515812)
		(end 443.534546 -305.082956)
		(width 0.13208)
		(layer "B.Cu")
		(net "MB_3V3IO_RSVD1_ISO_R")
	)
	(segment
		(start 446.063624 -257.08737)
		(end 446.063624 -282.986734)
		(width 0.13208)
		(layer "B.Cu")
		(net "MB_3V3IO_RSVD1_ISO_R")
	)
	(segment
		(start 416.620706 -249.50801)
		(end 417.808918 -248.319798)
		(width 0.13208)
		(layer "B.Cu")
		(net "MB_3V3IO_RSVD1_ISO_R")
	)
	(segment
		(start 445.069976 -390.570212)
		(end 408.252676 -390.570212)
		(width 0.13208)
		(layer "B.Cu")
		(net "MB_3V3IO_RSVD1_ISO_R")
	)
	(segment
		(start 442.714888 -309.17642)
		(end 442.714888 -315.578744)
		(width 0.13208)
		(layer "B.Cu")
		(net "MB_3V3IO_RSVD1_ISO_R")
	)
	(segment
		(start 405.591518 -387.909054)
		(end 366.548162 -387.909054)
		(width 0.13208)
		(layer "B.Cu")
		(net "MB_3V3IO_RSVD1_ISO_R")
	)
	(segment
		(start 391.758932 -236.58449)
		(end 391.758932 -246.497348)
		(width 0.13208)
		(layer "B.Cu")
		(net "MB_3V3IO_RSVD1_ISO_R")
	)
	(segment
		(start 381.714248 -216.531952)
		(end 389.333486 -224.15119)
		(width 0.15494)
		(layer "In5.Cu")
		(net "MB_3V3IO_RSVD1_ISO_R")
	)
	(segment
		(start 389.333486 -231.145334)
		(end 390.773158 -232.585006)
		(width 0.15494)
		(layer "In5.Cu")
		(net "MB_3V3IO_RSVD1_ISO_R")
	)
	(segment
		(start 366.168686 -223.399858)
		(end 368.564668 -223.399858)
		(width 0.15494)
		(layer "In5.Cu")
		(net "MB_3V3IO_RSVD1_ISO_R")
	)
	(segment
		(start 368.900202 -223.064324)
		(end 368.900202 -218.980004)
		(width 0.15494)
		(layer "In5.Cu")
		(net "MB_3V3IO_RSVD1_ISO_R")
	)
	(segment
		(start 368.564668 -223.399858)
		(end 368.900202 -223.064324)
		(width 0.15494)
		(layer "In5.Cu")
		(net "MB_3V3IO_RSVD1_ISO_R")
	)
	(segment
		(start 360.738166 -228.830378)
		(end 366.168686 -223.399858)
		(width 0.15494)
		(layer "In5.Cu")
		(net "MB_3V3IO_RSVD1_ISO_R")
	)
	(segment
		(start 360.738166 -230.648256)
		(end 360.738166 -228.830378)
		(width 0.15494)
		(layer "In5.Cu")
		(net "MB_3V3IO_RSVD1_ISO_R")
	)
	(segment
		(start 368.900202 -218.980004)
		(end 371.348254 -216.531952)
		(width 0.15494)
		(layer "In5.Cu")
		(net "MB_3V3IO_RSVD1_ISO_R")
	)
	(segment
		(start 390.773158 -232.585006)
		(end 393.320016 -232.585006)
		(width 0.15494)
		(layer "In5.Cu")
		(net "MB_3V3IO_RSVD1_ISO_R")
	)
	(segment
		(start 371.348254 -216.531952)
		(end 381.714248 -216.531952)
		(width 0.15494)
		(layer "In5.Cu")
		(net "MB_3V3IO_RSVD1_ISO_R")
	)
	(segment
		(start 389.333486 -224.15119)
		(end 389.333486 -231.145334)
		(width 0.15494)
		(layer "In5.Cu")
		(net "MB_3V3IO_RSVD1_ISO_R")
	)
	(segment
		(start 359.990136 -231.396286)
		(end 360.738166 -230.648256)
		(width 0.15494)
		(layer "In5.Cu")
		(net "MB_3V3IO_RSVD1_ISO_R")
	)
	(segment
		(start 352.174048 -219.837508)
		(end 351.79635 -219.45981)
		(width 0.15494)
		(layer "In13.Cu")
		(net "MB_3V3IO_RSVD1_ISO_R")
	)
	(segment
		(start 347.309694 -219.45981)
		(end 346.892626 -219.042742)
		(width 0.15494)
		(layer "In13.Cu")
		(net "MB_3V3IO_RSVD1_ISO_R")
	)
	(segment
		(start 340.326218 -216.784682)
		(end 338.891626 -216.784682)
		(width 0.0889)
		(layer "In13.Cu")
		(net "MB_3V3IO_RSVD1_ISO_R")
	)
	(segment
		(start 346.892626 -218.531186)
		(end 346.750894 -218.389454)
		(width 0.0889)
		(layer "In13.Cu")
		(net "MB_3V3IO_RSVD1_ISO_R")
	)
	(segment
		(start 342.781128 -218.389454)
		(end 341.978996 -217.587322)
		(width 0.0889)
		(layer "In13.Cu")
		(net "MB_3V3IO_RSVD1_ISO_R")
	)
	(segment
		(start 340.699852 -217.587322)
		(end 340.491318 -217.378788)
		(width 0.0889)
		(layer "In13.Cu")
		(net "MB_3V3IO_RSVD1_ISO_R")
	)
	(segment
		(start 346.750894 -218.389454)
		(end 342.781128 -218.389454)
		(width 0.0889)
		(layer "In13.Cu")
		(net "MB_3V3IO_RSVD1_ISO_R")
	)
	(segment
		(start 340.491318 -217.378788)
		(end 340.491318 -216.949782)
		(width 0.0889)
		(layer "In13.Cu")
		(net "MB_3V3IO_RSVD1_ISO_R")
	)
	(segment
		(start 360.55681 -230.829612)
		(end 360.55681 -229.259384)
		(width 0.15494)
		(layer "In13.Cu")
		(net "MB_3V3IO_RSVD1_ISO_R")
	)
	(segment
		(start 346.892626 -219.042742)
		(end 346.892626 -218.531186)
		(width 0.0889)
		(layer "In13.Cu")
		(net "MB_3V3IO_RSVD1_ISO_R")
	)
	(segment
		(start 355.023166 -219.837508)
		(end 352.174048 -219.837508)
		(width 0.15494)
		(layer "In13.Cu")
		(net "MB_3V3IO_RSVD1_ISO_R")
	)
	(segment
		(start 338.891626 -216.784682)
		(end 338.494116 -216.387172)
		(width 0.0889)
		(layer "In13.Cu")
		(net "MB_3V3IO_RSVD1_ISO_R")
	)
	(segment
		(start 359.990136 -231.396286)
		(end 360.55681 -230.829612)
		(width 0.15494)
		(layer "In13.Cu")
		(net "MB_3V3IO_RSVD1_ISO_R")
	)
	(segment
		(start 357.809546 -226.51212)
		(end 357.809546 -222.623888)
		(width 0.15494)
		(layer "In13.Cu")
		(net "MB_3V3IO_RSVD1_ISO_R")
	)
	(segment
		(start 360.55681 -229.259384)
		(end 357.809546 -226.51212)
		(width 0.15494)
		(layer "In13.Cu")
		(net "MB_3V3IO_RSVD1_ISO_R")
	)
	(segment
		(start 341.978996 -217.587322)
		(end 340.699852 -217.587322)
		(width 0.0889)
		(layer "In13.Cu")
		(net "MB_3V3IO_RSVD1_ISO_R")
	)
	(segment
		(start 351.79635 -219.45981)
		(end 347.309694 -219.45981)
		(width 0.15494)
		(layer "In13.Cu")
		(net "MB_3V3IO_RSVD1_ISO_R")
	)
	(segment
		(start 357.809546 -222.623888)
		(end 355.023166 -219.837508)
		(width 0.15494)
		(layer "In13.Cu")
		(net "MB_3V3IO_RSVD1_ISO_R")
	)
	(segment
		(start 340.491318 -216.949782)
		(end 340.326218 -216.784682)
		(width 0.0889)
		(layer "In13.Cu")
		(net "MB_3V3IO_RSVD1_ISO_R")
	)
	(segment
		(start 132.931662 -192.736724)
		(end 131.770628 -191.57569)
		(width 0.13208)
		(layer "F.Cu")
		(net "NIC6_CLK_EN_BUF_R_N")
	)
	(segment
		(start 131.770628 -191.57569)
		(end 131.770628 -191.55537)
		(width 0.13208)
		(layer "F.Cu")
		(net "NIC6_CLK_EN_BUF_R_N")
	)
	(segment
		(start 133.247892 -190.676022)
		(end 132.930392 -190.358522)
		(width 0.13208)
		(layer "F.Cu")
		(net "NIC6_CLK_EN_BUF_R_N")
	)
	(segment
		(start 132.930392 -190.358522)
		(end 131.770628 -190.358522)
		(width 0.13208)
		(layer "F.Cu")
		(net "NIC6_CLK_EN_BUF_R_N")
	)
	(segment
		(start 131.770628 -191.55537)
		(end 131.770628 -190.358522)
		(width 0.13208)
		(layer "F.Cu")
		(net "NIC6_CLK_EN_BUF_R_N")
	)
	(segment
		(start 133.247892 -191.360298)
		(end 133.247892 -190.676022)
		(width 0.13208)
		(layer "F.Cu")
		(net "NIC6_CLK_EN_BUF_R_N")
	)
	(segment
		(start 133.177026 -192.736724)
		(end 132.931662 -192.736724)
		(width 0.13208)
		(layer "F.Cu")
		(net "NIC6_CLK_EN_BUF_R_N")
	)
	(segment
		(start 134.493254 -178.812444)
		(end 134.493254 -178.465988)
		(width 0.0889)
		(layer "F.Cu")
		(net "NIC6_CLK_EN_BUF_R_N")
	)
	(segment
		(start 134.971028 -179.400454)
		(end 134.892796 -179.211986)
		(width 0.0889)
		(layer "F.Cu")
		(net "NIC6_CLK_EN_BUF_R_N")
	)
	(segment
		(start 134.892796 -179.211986)
		(end 134.493254 -178.812444)
		(width 0.0889)
		(layer "F.Cu")
		(net "NIC6_CLK_EN_BUF_R_N")
	)
	(via
		(at 131.770628 -191.55537)
		(size 0.762)
		(drill 0.381)
		(layers "F.Cu" "B.Cu")
		(net "NIC6_CLK_EN_BUF_R_N")
	)
	(via
		(at 133.247892 -191.360298)
		(size 0.508)
		(drill 0.254)
		(layers "F.Cu" "B.Cu")
		(net "NIC6_CLK_EN_BUF_R_N")
	)
	(via
		(at 134.493254 -178.465988)
		(size 0.4572)
		(drill 0.254)
		(layers "F.Cu" "B.Cu")
		(net "NIC6_CLK_EN_BUF_R_N")
	)
	(segment
		(start 128.1684 -190.7794)
		(end 127.0508 -189.6618)
		(width 0.15494)
		(layer "In5.Cu")
		(net "NIC6_CLK_EN_BUF_R_N")
	)
	(segment
		(start 131.851146 -190.7794)
		(end 128.1684 -190.7794)
		(width 0.15494)
		(layer "In5.Cu")
		(net "NIC6_CLK_EN_BUF_R_N")
	)
	(segment
		(start 127.0508 -189.6618)
		(end 127.0508 -188.23051)
		(width 0.15494)
		(layer "In5.Cu")
		(net "NIC6_CLK_EN_BUF_R_N")
	)
	(segment
		(start 134.97179 -178.944524)
		(end 134.493254 -178.465988)
		(width 0.15494)
		(layer "In5.Cu")
		(net "NIC6_CLK_EN_BUF_R_N")
	)
	(segment
		(start 132.432044 -191.360298)
		(end 131.851146 -190.7794)
		(width 0.15494)
		(layer "In5.Cu")
		(net "NIC6_CLK_EN_BUF_R_N")
	)
	(segment
		(start 127.0508 -188.23051)
		(end 134.97179 -180.30952)
		(width 0.15494)
		(layer "In5.Cu")
		(net "NIC6_CLK_EN_BUF_R_N")
	)
	(segment
		(start 134.97179 -180.30952)
		(end 134.97179 -178.944524)
		(width 0.15494)
		(layer "In5.Cu")
		(net "NIC6_CLK_EN_BUF_R_N")
	)
	(segment
		(start 133.247892 -191.360298)
		(end 132.432044 -191.360298)
		(width 0.15494)
		(layer "In5.Cu")
		(net "NIC6_CLK_EN_BUF_R_N")
	)
	(segment
		(start 129.310384 -192.75171)
		(end 130.421634 -192.75171)
		(width 0.13208)
		(layer "F.Cu")
		(net "NIC7_CLK_EN_BUF_R_N")
	)
	(segment
		(start 134.471156 -179.900326)
		(end 133.781546 -179.422552)
		(width 0.0889)
		(layer "F.Cu")
		(net "NIC7_CLK_EN_BUF_R_N")
	)
	(segment
		(start 130.421634 -192.75171)
		(end 130.430016 -192.743328)
		(width 0.13208)
		(layer "F.Cu")
		(net "NIC7_CLK_EN_BUF_R_N")
	)
	(segment
		(start 130.430016 -192.743328)
		(end 130.430016 -191.974216)
		(width 0.13208)
		(layer "F.Cu")
		(net "NIC7_CLK_EN_BUF_R_N")
	)
	(via
		(at 133.781546 -179.422552)
		(size 0.49022)
		(drill 0.254)
		(layers "F.Cu" "B.Cu")
		(net "NIC7_CLK_EN_BUF_R_N")
	)
	(via
		(at 130.430016 -191.974216)
		(size 0.508)
		(drill 0.254)
		(layers "F.Cu" "B.Cu")
		(net "NIC7_CLK_EN_BUF_R_N")
	)
	(segment
		(start 126.69266 -188.068966)
		(end 133.781546 -180.98008)
		(width 0.15494)
		(layer "In5.Cu")
		(net "NIC7_CLK_EN_BUF_R_N")
	)
	(segment
		(start 126.69266 -190.881254)
		(end 126.69266 -188.068966)
		(width 0.15494)
		(layer "In5.Cu")
		(net "NIC7_CLK_EN_BUF_R_N")
	)
	(segment
		(start 133.781546 -180.98008)
		(end 133.781546 -179.422552)
		(width 0.15494)
		(layer "In5.Cu")
		(net "NIC7_CLK_EN_BUF_R_N")
	)
	(segment
		(start 127.785622 -191.974216)
		(end 126.69266 -190.881254)
		(width 0.15494)
		(layer "In5.Cu")
		(net "NIC7_CLK_EN_BUF_R_N")
	)
	(segment
		(start 130.430016 -191.974216)
		(end 127.785622 -191.974216)
		(width 0.15494)
		(layer "In5.Cu")
		(net "NIC7_CLK_EN_BUF_R_N")
	)
	(segment
		(start 359.515156 -399.675858)
		(end 358.417876 -398.578578)
		(width 0.13208)
		(layer "F.Cu")
		(net "MB_3V3IO_RSVD3_ISO_R")
	)
	(segment
		(start 337.293966 -216.786968)
		(end 336.89417 -216.387172)
		(width 0.13208)
		(layer "F.Cu")
		(net "MB_3V3IO_RSVD3_ISO_R")
	)
	(segment
		(start 362.072174 -399.675858)
		(end 359.515156 -399.675858)
		(width 0.13208)
		(layer "F.Cu")
		(net "MB_3V3IO_RSVD3_ISO_R")
	)
	(segment
		(start 367.31829 -397.416782)
		(end 366.927892 -397.80718)
		(width 0.13208)
		(layer "F.Cu")
		(net "MB_3V3IO_RSVD3_ISO_R")
	)
	(segment
		(start 367.31829 -388.842504)
		(end 367.31829 -397.416782)
		(width 0.13208)
		(layer "F.Cu")
		(net "MB_3V3IO_RSVD3_ISO_R")
	)
	(segment
		(start 362.637832 -399.1102)
		(end 362.072174 -399.675858)
		(width 0.13208)
		(layer "F.Cu")
		(net "MB_3V3IO_RSVD3_ISO_R")
	)
	(segment
		(start 365.624872 -399.1102)
		(end 362.637832 -399.1102)
		(width 0.13208)
		(layer "F.Cu")
		(net "MB_3V3IO_RSVD3_ISO_R")
	)
	(segment
		(start 366.927892 -397.80718)
		(end 365.624872 -399.1102)
		(width 0.13208)
		(layer "F.Cu")
		(net "MB_3V3IO_RSVD3_ISO_R")
	)
	(via
		(at 367.31829 -388.842504)
		(size 0.508)
		(drill 0.254)
		(layers "F.Cu" "B.Cu")
		(net "MB_3V3IO_RSVD3_ISO_R")
	)
	(via
		(at 393.351766 -235.670344)
		(size 0.508)
		(drill 0.254)
		(layers "F.Cu" "B.Cu")
		(net "MB_3V3IO_RSVD3_ISO_R")
	)
	(via
		(at 336.89417 -216.387172)
		(size 0.4572)
		(drill 0.254)
		(layers "F.Cu" "B.Cu")
		(net "MB_3V3IO_RSVD3_ISO_R")
	)
	(via
		(at 366.927892 -397.80718)
		(size 0.762)
		(drill 0.381)
		(layers "F.Cu" "B.Cu")
		(net "MB_3V3IO_RSVD3_ISO_R")
	)
	(via
		(at 362.22559 -231.211374)
		(size 0.508)
		(drill 0.254)
		(layers "F.Cu" "B.Cu")
		(net "MB_3V3IO_RSVD3_ISO_R")
	)
	(segment
		(start 449.190618 -254.362712)
		(end 446.348104 -257.205226)
		(width 0.13208)
		(layer "B.Cu")
		(net "MB_3V3IO_RSVD3_ISO_R")
	)
	(segment
		(start 449.861686 -322.323206)
		(end 457.414884 -322.323206)
		(width 0.13208)
		(layer "B.Cu")
		(net "MB_3V3IO_RSVD3_ISO_R")
	)
	(segment
		(start 407.520648 -390.854692)
		(end 406.94864 -390.282684)
		(width 0.13208)
		(layer "B.Cu")
		(net "MB_3V3IO_RSVD3_ISO_R")
	)
	(segment
		(start 394.887704 -249.22353)
		(end 416.50285 -249.22353)
		(width 0.13208)
		(layer "B.Cu")
		(net "MB_3V3IO_RSVD3_ISO_R")
	)
	(segment
		(start 446.348104 -283.10459)
		(end 443.825122 -285.627572)
		(width 0.13208)
		(layer "B.Cu")
		(net "MB_3V3IO_RSVD3_ISO_R")
	)
	(segment
		(start 406.94864 -390.282684)
		(end 405.040846 -390.282684)
		(width 0.13208)
		(layer "B.Cu")
		(net "MB_3V3IO_RSVD3_ISO_R")
	)
	(segment
		(start 443.825122 -305.24196)
		(end 442.887862 -306.17922)
		(width 0.13208)
		(layer "B.Cu")
		(net "MB_3V3IO_RSVD3_ISO_R")
	)
	(segment
		(start 465.929218 -330.83754)
		(end 465.929218 -370.19611)
		(width 0.13208)
		(layer "B.Cu")
		(net "MB_3V3IO_RSVD3_ISO_R")
	)
	(segment
		(start 416.50285 -249.22353)
		(end 417.702238 -248.024142)
		(width 0.13208)
		(layer "B.Cu")
		(net "MB_3V3IO_RSVD3_ISO_R")
	)
	(segment
		(start 417.702238 -248.024142)
		(end 449.18122 -248.024142)
		(width 0.13208)
		(layer "B.Cu")
		(net "MB_3V3IO_RSVD3_ISO_R")
	)
	(segment
		(start 465.929218 -370.19611)
		(end 445.270636 -390.854692)
		(width 0.13208)
		(layer "B.Cu")
		(net "MB_3V3IO_RSVD3_ISO_R")
	)
	(segment
		(start 452.479156 -254.362712)
		(end 449.190618 -254.362712)
		(width 0.13208)
		(layer "B.Cu")
		(net "MB_3V3IO_RSVD3_ISO_R")
	)
	(segment
		(start 449.18122 -248.024142)
		(end 453.28205 -252.124972)
		(width 0.13208)
		(layer "B.Cu")
		(net "MB_3V3IO_RSVD3_ISO_R")
	)
	(segment
		(start 442.887862 -306.17922)
		(end 442.887862 -308.887622)
		(width 0.13208)
		(layer "B.Cu")
		(net "MB_3V3IO_RSVD3_ISO_R")
	)
	(segment
		(start 446.348104 -257.205226)
		(end 446.348104 -283.10459)
		(width 0.13208)
		(layer "B.Cu")
		(net "MB_3V3IO_RSVD3_ISO_R")
	)
	(segment
		(start 443.053216 -309.052976)
		(end 443.053216 -315.514736)
		(width 0.13208)
		(layer "B.Cu")
		(net "MB_3V3IO_RSVD3_ISO_R")
	)
	(segment
		(start 443.825122 -285.627572)
		(end 443.825122 -305.24196)
		(width 0.13208)
		(layer "B.Cu")
		(net "MB_3V3IO_RSVD3_ISO_R")
	)
	(segment
		(start 442.887862 -308.887622)
		(end 443.053216 -309.052976)
		(width 0.13208)
		(layer "B.Cu")
		(net "MB_3V3IO_RSVD3_ISO_R")
	)
	(segment
		(start 443.053216 -315.514736)
		(end 449.861686 -322.323206)
		(width 0.13208)
		(layer "B.Cu")
		(net "MB_3V3IO_RSVD3_ISO_R")
	)
	(segment
		(start 403.600666 -388.842504)
		(end 367.31829 -388.842504)
		(width 0.13208)
		(layer "B.Cu")
		(net "MB_3V3IO_RSVD3_ISO_R")
	)
	(segment
		(start 392.043412 -236.978698)
		(end 392.043412 -246.379238)
		(width 0.13208)
		(layer "B.Cu")
		(net "MB_3V3IO_RSVD3_ISO_R")
	)
	(segment
		(start 393.351766 -235.670344)
		(end 392.043412 -236.978698)
		(width 0.13208)
		(layer "B.Cu")
		(net "MB_3V3IO_RSVD3_ISO_R")
	)
	(segment
		(start 457.414884 -322.323206)
		(end 465.929218 -330.83754)
		(width 0.13208)
		(layer "B.Cu")
		(net "MB_3V3IO_RSVD3_ISO_R")
	)
	(segment
		(start 453.28205 -252.124972)
		(end 453.28205 -253.559818)
		(width 0.13208)
		(layer "B.Cu")
		(net "MB_3V3IO_RSVD3_ISO_R")
	)
	(segment
		(start 405.040846 -390.282684)
		(end 403.600666 -388.842504)
		(width 0.13208)
		(layer "B.Cu")
		(net "MB_3V3IO_RSVD3_ISO_R")
	)
	(segment
		(start 392.043412 -246.379238)
		(end 394.887704 -249.22353)
		(width 0.13208)
		(layer "B.Cu")
		(net "MB_3V3IO_RSVD3_ISO_R")
	)
	(segment
		(start 453.28205 -253.559818)
		(end 452.479156 -254.362712)
		(width 0.13208)
		(layer "B.Cu")
		(net "MB_3V3IO_RSVD3_ISO_R")
	)
	(segment
		(start 445.270636 -390.854692)
		(end 407.520648 -390.854692)
		(width 0.13208)
		(layer "B.Cu")
		(net "MB_3V3IO_RSVD3_ISO_R")
	)
	(segment
		(start 388.966202 -231.28478)
		(end 393.351766 -235.670344)
		(width 0.15494)
		(layer "In5.Cu")
		(net "MB_3V3IO_RSVD3_ISO_R")
	)
	(segment
		(start 368.713258 -223.757998)
		(end 369.25885 -223.212406)
		(width 0.15494)
		(layer "In5.Cu")
		(net "MB_3V3IO_RSVD3_ISO_R")
	)
	(segment
		(start 366.317276 -223.757998)
		(end 368.713258 -223.757998)
		(width 0.15494)
		(layer "In5.Cu")
		(net "MB_3V3IO_RSVD3_ISO_R")
	)
	(segment
		(start 362.22559 -231.211374)
		(end 362.22559 -227.849684)
		(width 0.15494)
		(layer "In5.Cu")
		(net "MB_3V3IO_RSVD3_ISO_R")
	)
	(segment
		(start 388.966202 -224.303336)
		(end 388.966202 -231.28478)
		(width 0.15494)
		(layer "In5.Cu")
		(net "MB_3V3IO_RSVD3_ISO_R")
	)
	(segment
		(start 369.25885 -219.140786)
		(end 371.5004 -216.899236)
		(width 0.15494)
		(layer "In5.Cu")
		(net "MB_3V3IO_RSVD3_ISO_R")
	)
	(segment
		(start 381.562102 -216.899236)
		(end 388.966202 -224.303336)
		(width 0.15494)
		(layer "In5.Cu")
		(net "MB_3V3IO_RSVD3_ISO_R")
	)
	(segment
		(start 362.22559 -227.849684)
		(end 366.317276 -223.757998)
		(width 0.15494)
		(layer "In5.Cu")
		(net "MB_3V3IO_RSVD3_ISO_R")
	)
	(segment
		(start 369.25885 -223.212406)
		(end 369.25885 -219.140786)
		(width 0.15494)
		(layer "In5.Cu")
		(net "MB_3V3IO_RSVD3_ISO_R")
	)
	(segment
		(start 371.5004 -216.899236)
		(end 381.562102 -216.899236)
		(width 0.15494)
		(layer "In5.Cu")
		(net "MB_3V3IO_RSVD3_ISO_R")
	)
	(segment
		(start 358.227122 -220.610176)
		(end 356.100888 -218.483942)
		(width 0.15494)
		(layer "In13.Cu")
		(net "MB_3V3IO_RSVD3_ISO_R")
	)
	(segment
		(start 359.612438 -224.229676)
		(end 358.227122 -222.84436)
		(width 0.15494)
		(layer "In13.Cu")
		(net "MB_3V3IO_RSVD3_ISO_R")
	)
	(segment
		(start 342.950038 -217.58656)
		(end 342.14816 -216.784682)
		(width 0.0889)
		(layer "In13.Cu")
		(net "MB_3V3IO_RSVD3_ISO_R")
	)
	(segment
		(start 354.126038 -218.483942)
		(end 353.413822 -219.196158)
		(width 0.15494)
		(layer "In13.Cu")
		(net "MB_3V3IO_RSVD3_ISO_R")
	)
	(segment
		(start 347.569536 -217.58656)
		(end 342.950038 -217.58656)
		(width 0.0889)
		(layer "In13.Cu")
		(net "MB_3V3IO_RSVD3_ISO_R")
	)
	(segment
		(start 347.69171 -217.708734)
		(end 347.569536 -217.58656)
		(width 0.0889)
		(layer "In13.Cu")
		(net "MB_3V3IO_RSVD3_ISO_R")
	)
	(segment
		(start 362.22559 -231.211374)
		(end 362.22559 -228.33838)
		(width 0.15494)
		(layer "In13.Cu")
		(net "MB_3V3IO_RSVD3_ISO_R")
	)
	(segment
		(start 353.413822 -219.196158)
		(end 347.904054 -219.196158)
		(width 0.15494)
		(layer "In13.Cu")
		(net "MB_3V3IO_RSVD3_ISO_R")
	)
	(segment
		(start 337.524598 -215.985852)
		(end 337.123278 -216.387172)
		(width 0.0889)
		(layer "In13.Cu")
		(net "MB_3V3IO_RSVD3_ISO_R")
	)
	(segment
		(start 340.491572 -216.194386)
		(end 340.283038 -215.985852)
		(width 0.0889)
		(layer "In13.Cu")
		(net "MB_3V3IO_RSVD3_ISO_R")
	)
	(segment
		(start 342.14816 -216.784682)
		(end 340.708234 -216.784682)
		(width 0.0889)
		(layer "In13.Cu")
		(net "MB_3V3IO_RSVD3_ISO_R")
	)
	(segment
		(start 337.123278 -216.387172)
		(end 336.89417 -216.387172)
		(width 0.0889)
		(layer "In13.Cu")
		(net "MB_3V3IO_RSVD3_ISO_R")
	)
	(segment
		(start 347.904054 -219.196158)
		(end 347.69171 -218.983814)
		(width 0.15494)
		(layer "In13.Cu")
		(net "MB_3V3IO_RSVD3_ISO_R")
	)
	(segment
		(start 340.708234 -216.784682)
		(end 340.491572 -216.56802)
		(width 0.0889)
		(layer "In13.Cu")
		(net "MB_3V3IO_RSVD3_ISO_R")
	)
	(segment
		(start 340.283038 -215.985852)
		(end 337.524598 -215.985852)
		(width 0.0889)
		(layer "In13.Cu")
		(net "MB_3V3IO_RSVD3_ISO_R")
	)
	(segment
		(start 362.22559 -228.33838)
		(end 359.612438 -225.725228)
		(width 0.15494)
		(layer "In13.Cu")
		(net "MB_3V3IO_RSVD3_ISO_R")
	)
	(segment
		(start 359.612438 -225.725228)
		(end 359.612438 -224.229676)
		(width 0.15494)
		(layer "In13.Cu")
		(net "MB_3V3IO_RSVD3_ISO_R")
	)
	(segment
		(start 356.100888 -218.483942)
		(end 354.126038 -218.483942)
		(width 0.15494)
		(layer "In13.Cu")
		(net "MB_3V3IO_RSVD3_ISO_R")
	)
	(segment
		(start 347.69171 -218.983814)
		(end 347.69171 -217.708734)
		(width 0.0889)
		(layer "In13.Cu")
		(net "MB_3V3IO_RSVD3_ISO_R")
	)
	(segment
		(start 358.227122 -222.84436)
		(end 358.227122 -220.610176)
		(width 0.15494)
		(layer "In13.Cu")
		(net "MB_3V3IO_RSVD3_ISO_R")
	)
	(segment
		(start 340.491572 -216.56802)
		(end 340.491572 -216.194386)
		(width 0.0889)
		(layer "In13.Cu")
		(net "MB_3V3IO_RSVD3_ISO_R")
	)
	(segment
		(start 146.12493 -188.847476)
		(end 146.12493 -189.46368)
		(width 0.13208)
		(layer "F.Cu")
		(net "NIC5_CLK_EN_BUF_R_N")
	)
	(segment
		(start 134.971028 -178.400456)
		(end 134.971028 -178.344068)
		(width 0.13208)
		(layer "F.Cu")
		(net "NIC5_CLK_EN_BUF_R_N")
	)
	(segment
		(start 144.93113 -188.752988)
		(end 146.124676 -188.752988)
		(width 0.13208)
		(layer "F.Cu")
		(net "NIC5_CLK_EN_BUF_R_N")
	)
	(segment
		(start 134.971028 -178.344068)
		(end 134.491222 -177.864262)
		(width 0.13208)
		(layer "F.Cu")
		(net "NIC5_CLK_EN_BUF_R_N")
	)
	(segment
		(start 146.12493 -189.46368)
		(end 145.739612 -189.848998)
		(width 0.13208)
		(layer "F.Cu")
		(net "NIC5_CLK_EN_BUF_R_N")
	)
	(segment
		(start 146.12493 -188.753242)
		(end 146.12493 -188.847476)
		(width 0.13208)
		(layer "F.Cu")
		(net "NIC5_CLK_EN_BUF_R_N")
	)
	(segment
		(start 145.924016 -190.578486)
		(end 145.739612 -190.394082)
		(width 0.13208)
		(layer "F.Cu")
		(net "NIC5_CLK_EN_BUF_R_N")
	)
	(segment
		(start 146.124676 -188.752988)
		(end 146.12493 -188.753242)
		(width 0.13208)
		(layer "F.Cu")
		(net "NIC5_CLK_EN_BUF_R_N")
	)
	(segment
		(start 134.491222 -177.864262)
		(end 134.491222 -177.785522)
		(width 0.13208)
		(layer "F.Cu")
		(net "NIC5_CLK_EN_BUF_R_N")
	)
	(segment
		(start 145.739612 -190.394082)
		(end 145.739612 -189.848998)
		(width 0.13208)
		(layer "F.Cu")
		(net "NIC5_CLK_EN_BUF_R_N")
	)
	(via
		(at 134.491222 -177.785522)
		(size 0.4572)
		(drill 0.254)
		(layers "F.Cu" "B.Cu")
		(net "NIC5_CLK_EN_BUF_R_N")
	)
	(via
		(at 146.12493 -188.847476)
		(size 0.762)
		(drill 0.381)
		(layers "F.Cu" "B.Cu")
		(net "NIC5_CLK_EN_BUF_R_N")
	)
	(via
		(at 145.739612 -189.848998)
		(size 0.508)
		(drill 0.254)
		(layers "F.Cu" "B.Cu")
		(net "NIC5_CLK_EN_BUF_R_N")
	)
	(segment
		(start 134.609078 -177.785522)
		(end 134.491222 -177.785522)
		(width 0.15494)
		(layer "In11.Cu")
		(net "NIC5_CLK_EN_BUF_R_N")
	)
	(segment
		(start 142.984474 -172.83176)
		(end 139.56284 -172.83176)
		(width 0.15494)
		(layer "In11.Cu")
		(net "NIC5_CLK_EN_BUF_R_N")
	)
	(segment
		(start 144.904968 -174.752254)
		(end 142.984474 -172.83176)
		(width 0.15494)
		(layer "In11.Cu")
		(net "NIC5_CLK_EN_BUF_R_N")
	)
	(segment
		(start 139.56284 -172.83176)
		(end 134.609078 -177.785522)
		(width 0.15494)
		(layer "In11.Cu")
		(net "NIC5_CLK_EN_BUF_R_N")
	)
	(segment
		(start 145.739612 -189.848998)
		(end 144.904968 -189.014354)
		(width 0.15494)
		(layer "In11.Cu")
		(net "NIC5_CLK_EN_BUF_R_N")
	)
	(segment
		(start 144.904968 -189.014354)
		(end 144.904968 -174.752254)
		(width 0.15494)
		(layer "In11.Cu")
		(net "NIC5_CLK_EN_BUF_R_N")
	)
	(segment
		(start 183.508142 -176.360836)
		(end 183.508142 -176.204372)
		(width 0.13208)
		(layer "F.Cu")
		(net "NIC3_CLK_EN_BUF_R_N")
	)
	(segment
		(start 134.971028 -176.900332)
		(end 134.491222 -177.150522)
		(width 0.13208)
		(layer "F.Cu")
		(net "NIC3_CLK_EN_BUF_R_N")
	)
	(segment
		(start 182.94604 -176.922938)
		(end 183.508142 -176.360836)
		(width 0.13208)
		(layer "F.Cu")
		(net "NIC3_CLK_EN_BUF_R_N")
	)
	(segment
		(start 184.148476 -175.41875)
		(end 184.148476 -176.089056)
		(width 0.13208)
		(layer "F.Cu")
		(net "NIC3_CLK_EN_BUF_R_N")
	)
	(segment
		(start 182.972456 -175.668686)
		(end 183.222392 -175.41875)
		(width 0.13208)
		(layer "F.Cu")
		(net "NIC3_CLK_EN_BUF_R_N")
	)
	(segment
		(start 184.148476 -176.089056)
		(end 184.03316 -176.204372)
		(width 0.13208)
		(layer "F.Cu")
		(net "NIC3_CLK_EN_BUF_R_N")
	)
	(segment
		(start 184.03316 -176.204372)
		(end 183.508142 -176.204372)
		(width 0.13208)
		(layer "F.Cu")
		(net "NIC3_CLK_EN_BUF_R_N")
	)
	(segment
		(start 183.222392 -175.41875)
		(end 184.148476 -175.41875)
		(width 0.13208)
		(layer "F.Cu")
		(net "NIC3_CLK_EN_BUF_R_N")
	)
	(via
		(at 134.491222 -177.150522)
		(size 0.4572)
		(drill 0.254)
		(layers "F.Cu" "B.Cu")
		(net "NIC3_CLK_EN_BUF_R_N")
	)
	(via
		(at 184.148476 -175.41875)
		(size 0.762)
		(drill 0.381)
		(layers "F.Cu" "B.Cu")
		(net "NIC3_CLK_EN_BUF_R_N")
	)
	(via
		(at 183.508142 -176.204372)
		(size 0.508)
		(drill 0.254)
		(layers "F.Cu" "B.Cu")
		(net "NIC3_CLK_EN_BUF_R_N")
	)
	(segment
		(start 181.12867 -176.900586)
		(end 180.640228 -177.389028)
		(width 0.15494)
		(layer "In13.Cu")
		(net "NIC3_CLK_EN_BUF_R_N")
	)
	(segment
		(start 141.623796 -171.278804)
		(end 135.752078 -177.150522)
		(width 0.15494)
		(layer "In13.Cu")
		(net "NIC3_CLK_EN_BUF_R_N")
	)
	(segment
		(start 168.3004 -175.8696)
		(end 167.293544 -174.862744)
		(width 0.15494)
		(layer "In13.Cu")
		(net "NIC3_CLK_EN_BUF_R_N")
	)
	(segment
		(start 173.863 -175.8696)
		(end 168.3004 -175.8696)
		(width 0.15494)
		(layer "In13.Cu")
		(net "NIC3_CLK_EN_BUF_R_N")
	)
	(segment
		(start 178.373532 -180.380132)
		(end 173.863 -175.8696)
		(width 0.15494)
		(layer "In13.Cu")
		(net "NIC3_CLK_EN_BUF_R_N")
	)
	(segment
		(start 180.821076 -180.380132)
		(end 178.373532 -180.380132)
		(width 0.15494)
		(layer "In13.Cu")
		(net "NIC3_CLK_EN_BUF_R_N")
	)
	(segment
		(start 135.752078 -177.150522)
		(end 134.491222 -177.150522)
		(width 0.15494)
		(layer "In13.Cu")
		(net "NIC3_CLK_EN_BUF_R_N")
	)
	(segment
		(start 149.04847 -174.862744)
		(end 145.46453 -171.278804)
		(width 0.15494)
		(layer "In13.Cu")
		(net "NIC3_CLK_EN_BUF_R_N")
	)
	(segment
		(start 180.640228 -177.389028)
		(end 180.640228 -178.538378)
		(width 0.15494)
		(layer "In13.Cu")
		(net "NIC3_CLK_EN_BUF_R_N")
	)
	(segment
		(start 181.167532 -179.065682)
		(end 181.167532 -180.033676)
		(width 0.15494)
		(layer "In13.Cu")
		(net "NIC3_CLK_EN_BUF_R_N")
	)
	(segment
		(start 182.811928 -176.900586)
		(end 181.12867 -176.900586)
		(width 0.15494)
		(layer "In13.Cu")
		(net "NIC3_CLK_EN_BUF_R_N")
	)
	(segment
		(start 145.46453 -171.278804)
		(end 141.623796 -171.278804)
		(width 0.15494)
		(layer "In13.Cu")
		(net "NIC3_CLK_EN_BUF_R_N")
	)
	(segment
		(start 181.167532 -180.033676)
		(end 180.821076 -180.380132)
		(width 0.15494)
		(layer "In13.Cu")
		(net "NIC3_CLK_EN_BUF_R_N")
	)
	(segment
		(start 183.508142 -176.204372)
		(end 182.811928 -176.900586)
		(width 0.15494)
		(layer "In13.Cu")
		(net "NIC3_CLK_EN_BUF_R_N")
	)
	(segment
		(start 167.293544 -174.862744)
		(end 149.04847 -174.862744)
		(width 0.15494)
		(layer "In13.Cu")
		(net "NIC3_CLK_EN_BUF_R_N")
	)
	(segment
		(start 180.640228 -178.538378)
		(end 181.167532 -179.065682)
		(width 0.15494)
		(layer "In13.Cu")
		(net "NIC3_CLK_EN_BUF_R_N")
	)
	(segment
		(start 361.178856 -380.995682)
		(end 361.544108 -380.63043)
		(width 0.13208)
		(layer "F.Cu")
		(net "MB_3V3IO_RSVD4_ISO_R")
	)
	(segment
		(start 334.09382 -215.987122)
		(end 333.694024 -215.587326)
		(width 0.13208)
		(layer "F.Cu")
		(net "MB_3V3IO_RSVD4_ISO_R")
	)
	(segment
		(start 361.178856 -381.714502)
		(end 361.178856 -380.995682)
		(width 0.13208)
		(layer "F.Cu")
		(net "MB_3V3IO_RSVD4_ISO_R")
	)
	(via
		(at 393.348464 -236.626908)
		(size 0.508)
		(drill 0.254)
		(layers "F.Cu" "B.Cu")
		(net "MB_3V3IO_RSVD4_ISO_R")
	)
	(via
		(at 362.980986 -230.779066)
		(size 0.508)
		(drill 0.254)
		(layers "F.Cu" "B.Cu")
		(net "MB_3V3IO_RSVD4_ISO_R")
	)
	(via
		(at 361.178856 -381.714502)
		(size 0.508)
		(drill 0.254)
		(layers "F.Cu" "B.Cu")
		(net "MB_3V3IO_RSVD4_ISO_R")
	)
	(via
		(at 333.694024 -215.587326)
		(size 0.4572)
		(drill 0.254)
		(layers "F.Cu" "B.Cu")
		(net "MB_3V3IO_RSVD4_ISO_R")
	)
	(segment
		(start 447.5099 -259.339842)
		(end 447.5099 -260.010656)
		(width 0.13208)
		(layer "B.Cu")
		(net "MB_3V3IO_RSVD4_ISO_R")
	)
	(segment
		(start 367.0173 -389.341106)
		(end 365.193072 -387.516878)
		(width 0.13208)
		(layer "B.Cu")
		(net "MB_3V3IO_RSVD4_ISO_R")
	)
	(segment
		(start 449.979542 -322.038726)
		(end 457.53274 -322.038726)
		(width 0.13208)
		(layer "B.Cu")
		(net "MB_3V3IO_RSVD4_ISO_R")
	)
	(segment
		(start 446.632584 -283.222446)
		(end 444.155576 -285.699454)
		(width 0.13208)
		(layer "B.Cu")
		(net "MB_3V3IO_RSVD4_ISO_R")
	)
	(segment
		(start 401.711414 -389.341106)
		(end 367.0173 -389.341106)
		(width 0.13208)
		(layer "B.Cu")
		(net "MB_3V3IO_RSVD4_ISO_R")
	)
	(segment
		(start 446.632584 -257.323082)
		(end 446.632584 -258.462526)
		(width 0.13208)
		(layer "B.Cu")
		(net "MB_3V3IO_RSVD4_ISO_R")
	)
	(segment
		(start 447.5099 -260.010656)
		(end 446.632584 -260.887972)
		(width 0.13208)
		(layer "B.Cu")
		(net "MB_3V3IO_RSVD4_ISO_R")
	)
	(segment
		(start 444.155576 -305.464718)
		(end 443.173612 -306.446682)
		(width 0.13208)
		(layer "B.Cu")
		(net "MB_3V3IO_RSVD4_ISO_R")
	)
	(segment
		(start 392.327892 -246.261128)
		(end 395.005814 -248.93905)
		(width 0.13208)
		(layer "B.Cu")
		(net "MB_3V3IO_RSVD4_ISO_R")
	)
	(segment
		(start 453.56653 -252.007116)
		(end 453.56653 -253.677674)
		(width 0.13208)
		(layer "B.Cu")
		(net "MB_3V3IO_RSVD4_ISO_R")
	)
	(segment
		(start 443.988444 -392.738864)
		(end 405.109172 -392.738864)
		(width 0.13208)
		(layer "B.Cu")
		(net "MB_3V3IO_RSVD4_ISO_R")
	)
	(segment
		(start 405.109172 -392.738864)
		(end 401.711414 -389.341106)
		(width 0.13208)
		(layer "B.Cu")
		(net "MB_3V3IO_RSVD4_ISO_R")
	)
	(segment
		(start 392.327892 -237.64748)
		(end 392.327892 -246.261128)
		(width 0.13208)
		(layer "B.Cu")
		(net "MB_3V3IO_RSVD4_ISO_R")
	)
	(segment
		(start 365.193072 -384.425698)
		(end 362.481876 -381.714502)
		(width 0.13208)
		(layer "B.Cu")
		(net "MB_3V3IO_RSVD4_ISO_R")
	)
	(segment
		(start 395.005814 -248.93905)
		(end 416.384994 -248.93905)
		(width 0.13208)
		(layer "B.Cu")
		(net "MB_3V3IO_RSVD4_ISO_R")
	)
	(segment
		(start 443.364112 -315.423296)
		(end 449.979542 -322.038726)
		(width 0.13208)
		(layer "B.Cu")
		(net "MB_3V3IO_RSVD4_ISO_R")
	)
	(segment
		(start 417.63061 -247.693434)
		(end 449.252848 -247.693434)
		(width 0.13208)
		(layer "B.Cu")
		(net "MB_3V3IO_RSVD4_ISO_R")
	)
	(segment
		(start 365.193072 -387.516878)
		(end 365.193072 -384.425698)
		(width 0.13208)
		(layer "B.Cu")
		(net "MB_3V3IO_RSVD4_ISO_R")
	)
	(segment
		(start 449.252848 -247.693434)
		(end 453.56653 -252.007116)
		(width 0.13208)
		(layer "B.Cu")
		(net "MB_3V3IO_RSVD4_ISO_R")
	)
	(segment
		(start 446.632584 -258.462526)
		(end 447.5099 -259.339842)
		(width 0.13208)
		(layer "B.Cu")
		(net "MB_3V3IO_RSVD4_ISO_R")
	)
	(segment
		(start 457.53274 -322.038726)
		(end 466.213698 -330.719684)
		(width 0.13208)
		(layer "B.Cu")
		(net "MB_3V3IO_RSVD4_ISO_R")
	)
	(segment
		(start 466.213698 -330.719684)
		(end 466.213698 -370.51361)
		(width 0.13208)
		(layer "B.Cu")
		(net "MB_3V3IO_RSVD4_ISO_R")
	)
	(segment
		(start 362.481876 -381.714502)
		(end 361.178856 -381.714502)
		(width 0.13208)
		(layer "B.Cu")
		(net "MB_3V3IO_RSVD4_ISO_R")
	)
	(segment
		(start 446.632584 -260.887972)
		(end 446.632584 -283.222446)
		(width 0.13208)
		(layer "B.Cu")
		(net "MB_3V3IO_RSVD4_ISO_R")
	)
	(segment
		(start 444.155576 -285.699454)
		(end 444.155576 -305.464718)
		(width 0.13208)
		(layer "B.Cu")
		(net "MB_3V3IO_RSVD4_ISO_R")
	)
	(segment
		(start 452.597012 -254.647192)
		(end 449.308474 -254.647192)
		(width 0.13208)
		(layer "B.Cu")
		(net "MB_3V3IO_RSVD4_ISO_R")
	)
	(segment
		(start 443.173612 -306.446682)
		(end 443.173612 -308.752748)
		(width 0.13208)
		(layer "B.Cu")
		(net "MB_3V3IO_RSVD4_ISO_R")
	)
	(segment
		(start 443.173612 -308.752748)
		(end 443.364112 -308.943248)
		(width 0.13208)
		(layer "B.Cu")
		(net "MB_3V3IO_RSVD4_ISO_R")
	)
	(segment
		(start 393.348464 -236.626908)
		(end 392.327892 -237.64748)
		(width 0.13208)
		(layer "B.Cu")
		(net "MB_3V3IO_RSVD4_ISO_R")
	)
	(segment
		(start 416.384994 -248.93905)
		(end 417.63061 -247.693434)
		(width 0.13208)
		(layer "B.Cu")
		(net "MB_3V3IO_RSVD4_ISO_R")
	)
	(segment
		(start 449.308474 -254.647192)
		(end 446.632584 -257.323082)
		(width 0.13208)
		(layer "B.Cu")
		(net "MB_3V3IO_RSVD4_ISO_R")
	)
	(segment
		(start 453.56653 -253.677674)
		(end 452.597012 -254.647192)
		(width 0.13208)
		(layer "B.Cu")
		(net "MB_3V3IO_RSVD4_ISO_R")
	)
	(segment
		(start 466.213698 -370.51361)
		(end 443.988444 -392.738864)
		(width 0.13208)
		(layer "B.Cu")
		(net "MB_3V3IO_RSVD4_ISO_R")
	)
	(segment
		(start 443.364112 -308.943248)
		(end 443.364112 -315.423296)
		(width 0.13208)
		(layer "B.Cu")
		(net "MB_3V3IO_RSVD4_ISO_R")
	)
	(segment
		(start 362.980986 -230.779066)
		(end 362.980986 -227.601018)
		(width 0.15494)
		(layer "In5.Cu")
		(net "MB_3V3IO_RSVD4_ISO_R")
	)
	(segment
		(start 366.465866 -224.116138)
		(end 368.861848 -224.116138)
		(width 0.15494)
		(layer "In5.Cu")
		(net "MB_3V3IO_RSVD4_ISO_R")
	)
	(segment
		(start 368.861848 -224.116138)
		(end 369.6208 -223.357186)
		(width 0.15494)
		(layer "In5.Cu")
		(net "MB_3V3IO_RSVD4_ISO_R")
	)
	(segment
		(start 362.980986 -227.601018)
		(end 366.465866 -224.116138)
		(width 0.15494)
		(layer "In5.Cu")
		(net "MB_3V3IO_RSVD4_ISO_R")
	)
	(segment
		(start 379.068584 -217.294206)
		(end 388.571232 -226.796854)
		(width 0.15494)
		(layer "In5.Cu")
		(net "MB_3V3IO_RSVD4_ISO_R")
	)
	(segment
		(start 369.6208 -223.357186)
		(end 369.6208 -219.337636)
		(width 0.15494)
		(layer "In5.Cu")
		(net "MB_3V3IO_RSVD4_ISO_R")
	)
	(segment
		(start 388.571232 -231.849676)
		(end 393.348464 -236.626908)
		(width 0.15494)
		(layer "In5.Cu")
		(net "MB_3V3IO_RSVD4_ISO_R")
	)
	(segment
		(start 371.66423 -217.294206)
		(end 379.068584 -217.294206)
		(width 0.15494)
		(layer "In5.Cu")
		(net "MB_3V3IO_RSVD4_ISO_R")
	)
	(segment
		(start 369.6208 -219.337636)
		(end 371.66423 -217.294206)
		(width 0.15494)
		(layer "In5.Cu")
		(net "MB_3V3IO_RSVD4_ISO_R")
	)
	(segment
		(start 388.571232 -226.796854)
		(end 388.571232 -231.849676)
		(width 0.15494)
		(layer "In5.Cu")
		(net "MB_3V3IO_RSVD4_ISO_R")
	)
	(segment
		(start 334.09255 -215.985852)
		(end 333.694024 -215.587326)
		(width 0.0889)
		(layer "In13.Cu")
		(net "MB_3V3IO_RSVD4_ISO_R")
	)
	(segment
		(start 362.619036 -225.284284)
		(end 362.619036 -220.994732)
		(width 0.15494)
		(layer "In13.Cu")
		(net "MB_3V3IO_RSVD4_ISO_R")
	)
	(segment
		(start 362.980986 -225.646234)
		(end 362.619036 -225.284284)
		(width 0.15494)
		(layer "In13.Cu")
		(net "MB_3V3IO_RSVD4_ISO_R")
	)
	(segment
		(start 354.094796 -217.917268)
		(end 353.62261 -218.389454)
		(width 0.15494)
		(layer "In13.Cu")
		(net "MB_3V3IO_RSVD4_ISO_R")
	)
	(segment
		(start 359.541572 -217.917268)
		(end 354.094796 -217.917268)
		(width 0.15494)
		(layer "In13.Cu")
		(net "MB_3V3IO_RSVD4_ISO_R")
	)
	(segment
		(start 337.509104 -215.186768)
		(end 337.295998 -215.399874)
		(width 0.0889)
		(layer "In13.Cu")
		(net "MB_3V3IO_RSVD4_ISO_R")
	)
	(segment
		(start 337.158584 -215.985852)
		(end 334.09255 -215.985852)
		(width 0.0889)
		(layer "In13.Cu")
		(net "MB_3V3IO_RSVD4_ISO_R")
	)
	(segment
		(start 340.680548 -215.985852)
		(end 340.495382 -215.800686)
		(width 0.0889)
		(layer "In13.Cu")
		(net "MB_3V3IO_RSVD4_ISO_R")
	)
	(segment
		(start 362.619036 -220.994732)
		(end 359.541572 -217.917268)
		(width 0.15494)
		(layer "In13.Cu")
		(net "MB_3V3IO_RSVD4_ISO_R")
	)
	(segment
		(start 337.295998 -215.848438)
		(end 337.158584 -215.985852)
		(width 0.0889)
		(layer "In13.Cu")
		(net "MB_3V3IO_RSVD4_ISO_R")
	)
	(segment
		(start 340.495382 -215.418924)
		(end 340.263226 -215.186768)
		(width 0.0889)
		(layer "In13.Cu")
		(net "MB_3V3IO_RSVD4_ISO_R")
	)
	(segment
		(start 343.016586 -216.78773)
		(end 342.214708 -215.985852)
		(width 0.0889)
		(layer "In13.Cu")
		(net "MB_3V3IO_RSVD4_ISO_R")
	)
	(segment
		(start 348.496128 -218.229688)
		(end 348.496128 -216.910412)
		(width 0.0889)
		(layer "In13.Cu")
		(net "MB_3V3IO_RSVD4_ISO_R")
	)
	(segment
		(start 340.263226 -215.186768)
		(end 337.509104 -215.186768)
		(width 0.0889)
		(layer "In13.Cu")
		(net "MB_3V3IO_RSVD4_ISO_R")
	)
	(segment
		(start 337.295998 -215.399874)
		(end 337.295998 -215.848438)
		(width 0.0889)
		(layer "In13.Cu")
		(net "MB_3V3IO_RSVD4_ISO_R")
	)
	(segment
		(start 348.655894 -218.389454)
		(end 348.496128 -218.229688)
		(width 0.0889)
		(layer "In13.Cu")
		(net "MB_3V3IO_RSVD4_ISO_R")
	)
	(segment
		(start 342.214708 -215.985852)
		(end 340.680548 -215.985852)
		(width 0.0889)
		(layer "In13.Cu")
		(net "MB_3V3IO_RSVD4_ISO_R")
	)
	(segment
		(start 348.496128 -216.910412)
		(end 348.373446 -216.78773)
		(width 0.0889)
		(layer "In13.Cu")
		(net "MB_3V3IO_RSVD4_ISO_R")
	)
	(segment
		(start 340.495382 -215.800686)
		(end 340.495382 -215.418924)
		(width 0.0889)
		(layer "In13.Cu")
		(net "MB_3V3IO_RSVD4_ISO_R")
	)
	(segment
		(start 362.980986 -230.779066)
		(end 362.980986 -225.646234)
		(width 0.15494)
		(layer "In13.Cu")
		(net "MB_3V3IO_RSVD4_ISO_R")
	)
	(segment
		(start 353.62261 -218.389454)
		(end 348.655894 -218.389454)
		(width 0.0889)
		(layer "In13.Cu")
		(net "MB_3V3IO_RSVD4_ISO_R")
	)
	(segment
		(start 348.373446 -216.78773)
		(end 343.016586 -216.78773)
		(width 0.0889)
		(layer "In13.Cu")
		(net "MB_3V3IO_RSVD4_ISO_R")
	)
	(segment
		(start 143.347948 -192.526666)
		(end 143.365728 -192.544446)
		(width 0.13208)
		(layer "F.Cu")
		(net "NIC4_CLK_EN_BUF_R_N")
	)
	(segment
		(start 135.471154 -178.400456)
		(end 136.166098 -178.400456)
		(width 0.13208)
		(layer "F.Cu")
		(net "NIC4_CLK_EN_BUF_R_N")
	)
	(segment
		(start 143.365728 -192.544446)
		(end 144.389856 -192.544446)
		(width 0.13208)
		(layer "F.Cu")
		(net "NIC4_CLK_EN_BUF_R_N")
	)
	(segment
		(start 143.347948 -191.767968)
		(end 143.347948 -192.526666)
		(width 0.13208)
		(layer "F.Cu")
		(net "NIC4_CLK_EN_BUF_R_N")
	)
	(via
		(at 136.166098 -178.400456)
		(size 0.508)
		(drill 0.254)
		(layers "F.Cu" "B.Cu")
		(net "NIC4_CLK_EN_BUF_R_N")
	)
	(via
		(at 143.347948 -192.526666)
		(size 0.508)
		(drill 0.254)
		(layers "F.Cu" "B.Cu")
		(net "NIC4_CLK_EN_BUF_R_N")
	)
	(segment
		(start 143.347948 -189.619382)
		(end 144.543018 -188.424312)
		(width 0.15494)
		(layer "In11.Cu")
		(net "NIC4_CLK_EN_BUF_R_N")
	)
	(segment
		(start 144.543018 -188.424312)
		(end 144.543018 -174.902368)
		(width 0.15494)
		(layer "In11.Cu")
		(net "NIC4_CLK_EN_BUF_R_N")
	)
	(segment
		(start 144.543018 -174.902368)
		(end 142.83436 -173.19371)
		(width 0.15494)
		(layer "In11.Cu")
		(net "NIC4_CLK_EN_BUF_R_N")
	)
	(segment
		(start 136.166098 -176.787556)
		(end 136.166098 -178.400456)
		(width 0.15494)
		(layer "In11.Cu")
		(net "NIC4_CLK_EN_BUF_R_N")
	)
	(segment
		(start 142.83436 -173.19371)
		(end 139.759944 -173.19371)
		(width 0.15494)
		(layer "In11.Cu")
		(net "NIC4_CLK_EN_BUF_R_N")
	)
	(segment
		(start 139.759944 -173.19371)
		(end 136.166098 -176.787556)
		(width 0.15494)
		(layer "In11.Cu")
		(net "NIC4_CLK_EN_BUF_R_N")
	)
	(segment
		(start 143.347948 -192.526666)
		(end 143.347948 -189.619382)
		(width 0.15494)
		(layer "In11.Cu")
		(net "NIC4_CLK_EN_BUF_R_N")
	)
	(segment
		(start 360.366056 -385.268216)
		(end 359.837736 -384.739896)
		(width 0.13208)
		(layer "F.Cu")
		(net "MB_3V3IO_RSVD4_ISO")
	)
	(segment
		(start 362.342684 -379.655324)
		(end 362.342684 -378.76607)
		(width 0.13208)
		(layer "F.Cu")
		(net "MB_3V3IO_RSVD4_ISO")
	)
	(segment
		(start 359.392728 -384.739896)
		(end 359.837736 -384.739896)
		(width 0.13208)
		(layer "F.Cu")
		(net "MB_3V3IO_RSVD4_ISO")
	)
	(segment
		(start 362.354622 -381.838708)
		(end 361.93984 -382.25349)
		(width 0.13208)
		(layer "F.Cu")
		(net "MB_3V3IO_RSVD4_ISO")
	)
	(segment
		(start 362.354622 -384.914902)
		(end 362.001308 -385.268216)
		(width 0.13208)
		(layer "F.Cu")
		(net "MB_3V3IO_RSVD4_ISO")
	)
	(segment
		(start 359.050082 -384.39725)
		(end 359.392728 -384.739896)
		(width 0.13208)
		(layer "F.Cu")
		(net "MB_3V3IO_RSVD4_ISO")
	)
	(segment
		(start 362.342684 -378.76607)
		(end 362.344462 -378.764292)
		(width 0.13208)
		(layer "F.Cu")
		(net "MB_3V3IO_RSVD4_ISO")
	)
	(segment
		(start 359.853992 -382.25349)
		(end 359.050082 -383.0574)
		(width 0.13208)
		(layer "F.Cu")
		(net "MB_3V3IO_RSVD4_ISO")
	)
	(segment
		(start 362.344208 -380.63043)
		(end 362.344208 -379.656848)
		(width 0.13208)
		(layer "F.Cu")
		(net "MB_3V3IO_RSVD4_ISO")
	)
	(segment
		(start 361.93984 -382.25349)
		(end 359.853992 -382.25349)
		(width 0.13208)
		(layer "F.Cu")
		(net "MB_3V3IO_RSVD4_ISO")
	)
	(segment
		(start 362.354622 -380.640844)
		(end 362.354622 -381.838708)
		(width 0.13208)
		(layer "F.Cu")
		(net "MB_3V3IO_RSVD4_ISO")
	)
	(segment
		(start 362.001308 -385.268216)
		(end 360.366056 -385.268216)
		(width 0.13208)
		(layer "F.Cu")
		(net "MB_3V3IO_RSVD4_ISO")
	)
	(segment
		(start 362.344208 -380.63043)
		(end 362.354622 -380.640844)
		(width 0.13208)
		(layer "F.Cu")
		(net "MB_3V3IO_RSVD4_ISO")
	)
	(segment
		(start 359.050082 -383.0574)
		(end 359.050082 -384.39725)
		(width 0.13208)
		(layer "F.Cu")
		(net "MB_3V3IO_RSVD4_ISO")
	)
	(segment
		(start 362.344208 -379.656848)
		(end 362.342684 -379.655324)
		(width 0.13208)
		(layer "F.Cu")
		(net "MB_3V3IO_RSVD4_ISO")
	)
	(via
		(at 362.354622 -381.838708)
		(size 0.762)
		(drill 0.381)
		(layers "F.Cu" "B.Cu")
		(net "MB_3V3IO_RSVD4_ISO")
	)
	(segment
		(start 362.732574 -397.250412)
		(end 362.732574 -398.58315)
		(width 0.13208)
		(layer "F.Cu")
		(net "MB_3V3IO_RSVD3_ISO")
	)
	(segment
		(start 358.417876 -397.778478)
		(end 357.444294 -397.778478)
		(width 0.13208)
		(layer "F.Cu")
		(net "MB_3V3IO_RSVD3_ISO")
	)
	(segment
		(start 357.444294 -397.778478)
		(end 357.44277 -397.780002)
		(width 0.13208)
		(layer "F.Cu")
		(net "MB_3V3IO_RSVD3_ISO")
	)
	(segment
		(start 356.553516 -397.780002)
		(end 356.551738 -397.778224)
		(width 0.13208)
		(layer "F.Cu")
		(net "MB_3V3IO_RSVD3_ISO")
	)
	(segment
		(start 358.859074 -397.33728)
		(end 359.654348 -397.33728)
		(width 0.13208)
		(layer "F.Cu")
		(net "MB_3V3IO_RSVD3_ISO")
	)
	(segment
		(start 359.654348 -398.193006)
		(end 359.654348 -397.33728)
		(width 0.13208)
		(layer "F.Cu")
		(net "MB_3V3IO_RSVD3_ISO")
	)
	(segment
		(start 359.650538 -398.649444)
		(end 359.650538 -398.196816)
		(width 0.13208)
		(layer "F.Cu")
		(net "MB_3V3IO_RSVD3_ISO")
	)
	(segment
		(start 362.732574 -398.58315)
		(end 362.021882 -399.293842)
		(width 0.13208)
		(layer "F.Cu")
		(net "MB_3V3IO_RSVD3_ISO")
	)
	(segment
		(start 359.650538 -398.196816)
		(end 359.654348 -398.193006)
		(width 0.13208)
		(layer "F.Cu")
		(net "MB_3V3IO_RSVD3_ISO")
	)
	(segment
		(start 357.44277 -397.780002)
		(end 356.553516 -397.780002)
		(width 0.13208)
		(layer "F.Cu")
		(net "MB_3V3IO_RSVD3_ISO")
	)
	(segment
		(start 358.417876 -397.778478)
		(end 358.859074 -397.33728)
		(width 0.13208)
		(layer "F.Cu")
		(net "MB_3V3IO_RSVD3_ISO")
	)
	(segment
		(start 362.021882 -399.293842)
		(end 360.294936 -399.293842)
		(width 0.13208)
		(layer "F.Cu")
		(net "MB_3V3IO_RSVD3_ISO")
	)
	(segment
		(start 360.294936 -399.293842)
		(end 359.650538 -398.649444)
		(width 0.13208)
		(layer "F.Cu")
		(net "MB_3V3IO_RSVD3_ISO")
	)
	(via
		(at 359.654348 -397.33728)
		(size 0.762)
		(drill 0.381)
		(layers "F.Cu" "B.Cu")
		(net "MB_3V3IO_RSVD3_ISO")
	)
	(segment
		(start 359.745026 -392.018266)
		(end 358.542844 -392.018266)
		(width 0.13208)
		(layer "F.Cu")
		(net "MB_3V3IO_RSVD1_ISO")
	)
	(segment
		(start 359.813606 -392.086846)
		(end 359.745026 -392.018266)
		(width 0.13208)
		(layer "F.Cu")
		(net "MB_3V3IO_RSVD1_ISO")
	)
	(segment
		(start 357.56596 -392.018012)
		(end 357.567738 -392.01979)
		(width 0.13208)
		(layer "F.Cu")
		(net "MB_3V3IO_RSVD1_ISO")
	)
	(segment
		(start 357.569262 -392.018266)
		(end 357.567738 -392.01979)
		(width 0.13208)
		(layer "F.Cu")
		(net "MB_3V3IO_RSVD1_ISO")
	)
	(segment
		(start 362.827316 -392.007852)
		(end 362.827316 -393.355068)
		(width 0.13208)
		(layer "F.Cu")
		(net "MB_3V3IO_RSVD1_ISO")
	)
	(segment
		(start 362.25734 -393.925044)
		(end 360.491532 -393.925044)
		(width 0.13208)
		(layer "F.Cu")
		(net "MB_3V3IO_RSVD1_ISO")
	)
	(segment
		(start 356.676706 -392.018012)
		(end 357.56596 -392.018012)
		(width 0.13208)
		(layer "F.Cu")
		(net "MB_3V3IO_RSVD1_ISO")
	)
	(segment
		(start 362.827316 -393.355068)
		(end 362.25734 -393.925044)
		(width 0.13208)
		(layer "F.Cu")
		(net "MB_3V3IO_RSVD1_ISO")
	)
	(segment
		(start 358.542844 -392.018266)
		(end 357.569262 -392.018266)
		(width 0.13208)
		(layer "F.Cu")
		(net "MB_3V3IO_RSVD1_ISO")
	)
	(segment
		(start 360.491532 -393.925044)
		(end 359.813606 -393.247118)
		(width 0.13208)
		(layer "F.Cu")
		(net "MB_3V3IO_RSVD1_ISO")
	)
	(segment
		(start 359.813606 -393.247118)
		(end 359.813606 -392.086846)
		(width 0.13208)
		(layer "F.Cu")
		(net "MB_3V3IO_RSVD1_ISO")
	)
	(via
		(at 359.745026 -392.018266)
		(size 0.762)
		(drill 0.381)
		(layers "F.Cu" "B.Cu")
		(net "MB_3V3IO_RSVD1_ISO")
	)
	(segment
		(start 359.764584 -390.696958)
		(end 360.325416 -391.25779)
		(width 0.13208)
		(layer "F.Cu")
		(net "MB_3V3IO_RSVD1_N")
	)
	(segment
		(start 359.764584 -390.688322)
		(end 359.764584 -390.696958)
		(width 0.13208)
		(layer "F.Cu")
		(net "MB_3V3IO_RSVD1_N")
	)
	(segment
		(start 358.9274 -390.688322)
		(end 359.764584 -390.688322)
		(width 0.13208)
		(layer "F.Cu")
		(net "MB_3V3IO_RSVD1_N")
	)
	(segment
		(start 358.568244 -391.047478)
		(end 358.9274 -390.688322)
		(width 0.13208)
		(layer "F.Cu")
		(net "MB_3V3IO_RSVD1_N")
	)
	(segment
		(start 361.027472 -391.25779)
		(end 361.027472 -390.507728)
		(width 0.13208)
		(layer "F.Cu")
		(net "MB_3V3IO_RSVD1_N")
	)
	(segment
		(start 360.325416 -391.25779)
		(end 361.027472 -391.25779)
		(width 0.13208)
		(layer "F.Cu")
		(net "MB_3V3IO_RSVD1_N")
	)
	(via
		(at 359.764584 -390.688322)
		(size 0.762)
		(drill 0.381)
		(layers "F.Cu" "B.Cu")
		(net "MB_3V3IO_RSVD1_N")
	)
	(segment
		(start 360.512106 -395.329664)
		(end 359.471214 -395.329664)
		(width 0.13208)
		(layer "F.Cu")
		(net "MB_3V3IO_RSVD3_N")
	)
	(segment
		(start 360.93273 -395.750288)
		(end 360.512106 -395.329664)
		(width 0.13208)
		(layer "F.Cu")
		(net "MB_3V3IO_RSVD3_N")
	)
	(segment
		(start 360.93273 -396.50035)
		(end 360.93273 -395.750288)
		(width 0.13208)
		(layer "F.Cu")
		(net "MB_3V3IO_RSVD3_N")
	)
	(segment
		(start 358.837738 -395.329664)
		(end 359.471214 -395.329664)
		(width 0.13208)
		(layer "F.Cu")
		(net "MB_3V3IO_RSVD3_N")
	)
	(segment
		(start 358.443276 -396.80769)
		(end 358.443276 -395.724126)
		(width 0.13208)
		(layer "F.Cu")
		(net "MB_3V3IO_RSVD3_N")
	)
	(segment
		(start 358.443276 -395.724126)
		(end 358.837738 -395.329664)
		(width 0.13208)
		(layer "F.Cu")
		(net "MB_3V3IO_RSVD3_N")
	)
	(via
		(at 359.471214 -395.329664)
		(size 0.762)
		(drill 0.381)
		(layers "F.Cu" "B.Cu")
		(net "MB_3V3IO_RSVD3_N")
	)
	(segment
		(start 363.854746 -383.115058)
		(end 363.104684 -383.115058)
		(width 0.13208)
		(layer "F.Cu")
		(net "MB_3V3IO_RSVD4_N")
	)
	(segment
		(start 363.104684 -383.115058)
		(end 363.104684 -382.413002)
		(width 0.13208)
		(layer "F.Cu")
		(net "MB_3V3IO_RSVD4_N")
	)
	(segment
		(start 363.674152 -381.841756)
		(end 363.674152 -381.014986)
		(width 0.13208)
		(layer "F.Cu")
		(net "MB_3V3IO_RSVD4_N")
	)
	(segment
		(start 363.104684 -382.413002)
		(end 363.674152 -381.843534)
		(width 0.13208)
		(layer "F.Cu")
		(net "MB_3V3IO_RSVD4_N")
	)
	(segment
		(start 363.674152 -381.014986)
		(end 363.314996 -380.65583)
		(width 0.13208)
		(layer "F.Cu")
		(net "MB_3V3IO_RSVD4_N")
	)
	(segment
		(start 363.674152 -381.843534)
		(end 363.674152 -381.841756)
		(width 0.13208)
		(layer "F.Cu")
		(net "MB_3V3IO_RSVD4_N")
	)
	(via
		(at 363.674152 -381.841756)
		(size 0.762)
		(drill 0.381)
		(layers "F.Cu" "B.Cu")
		(net "MB_3V3IO_RSVD4_N")
	)
	(segment
		(start 363.097064 -386.172964)
		(end 363.096556 -386.172456)
		(width 0.13208)
		(layer "F.Cu")
		(net "MB_3V3IO_RSVD4")
	)
	(segment
		(start 363.096556 -386.172456)
		(end 363.096556 -384.92303)
		(width 0.13208)
		(layer "F.Cu")
		(net "MB_3V3IO_RSVD4")
	)
	(segment
		(start 363.097064 -387.954266)
		(end 363.115098 -387.9723)
		(width 0.13208)
		(layer "F.Cu")
		(net "MB_3V3IO_RSVD4")
	)
	(segment
		(start 363.104684 -384.914902)
		(end 363.104684 -384.332226)
		(width 0.13208)
		(layer "F.Cu")
		(net "MB_3V3IO_RSVD4")
	)
	(segment
		(start 361.07624 -383.929128)
		(end 359.848404 -383.929128)
		(width 0.13208)
		(layer "F.Cu")
		(net "MB_3V3IO_RSVD4")
	)
	(segment
		(start 363.097064 -387.160008)
		(end 363.097064 -387.954266)
		(width 0.13208)
		(layer "F.Cu")
		(net "MB_3V3IO_RSVD4")
	)
	(segment
		(start 359.848404 -383.929128)
		(end 359.837736 -383.939796)
		(width 0.13208)
		(layer "F.Cu")
		(net "MB_3V3IO_RSVD4")
	)
	(segment
		(start 363.104684 -384.332226)
		(end 362.701586 -383.929128)
		(width 0.13208)
		(layer "F.Cu")
		(net "MB_3V3IO_RSVD4")
	)
	(segment
		(start 362.701586 -383.929128)
		(end 361.07624 -383.929128)
		(width 0.13208)
		(layer "F.Cu")
		(net "MB_3V3IO_RSVD4")
	)
	(segment
		(start 363.096556 -384.92303)
		(end 363.104684 -384.914902)
		(width 0.13208)
		(layer "F.Cu")
		(net "MB_3V3IO_RSVD4")
	)
	(segment
		(start 363.097064 -387.160008)
		(end 363.097064 -386.172964)
		(width 0.13208)
		(layer "F.Cu")
		(net "MB_3V3IO_RSVD4")
	)
	(via
		(at 363.115098 -387.9723)
		(size 0.508)
		(drill 0.254)
		(layers "F.Cu" "B.Cu")
		(net "MB_3V3IO_RSVD4")
	)
	(via
		(at 361.07624 -383.929128)
		(size 0.762)
		(drill 0.381)
		(layers "F.Cu" "B.Cu")
		(net "MB_3V3IO_RSVD4")
	)
	(segment
		(start 363.115098 -387.9723)
		(end 365.916718 -390.77392)
		(width 0.13208)
		(layer "B.Cu")
		(net "MB_3V3IO_RSVD4")
	)
	(segment
		(start 391.262108 -390.77392)
		(end 394.62329 -394.135102)
		(width 0.13208)
		(layer "B.Cu")
		(net "MB_3V3IO_RSVD4")
	)
	(segment
		(start 394.62329 -400.82343)
		(end 395.29004 -401.49018)
		(width 0.13208)
		(layer "B.Cu")
		(net "MB_3V3IO_RSVD4")
	)
	(segment
		(start 365.916718 -390.77392)
		(end 391.262108 -390.77392)
		(width 0.13208)
		(layer "B.Cu")
		(net "MB_3V3IO_RSVD4")
	)
	(segment
		(start 394.62329 -394.135102)
		(end 394.62329 -400.82343)
		(width 0.13208)
		(layer "B.Cu")
		(net "MB_3V3IO_RSVD4")
	)
	(segment
		(start 361.649518 -398.649444)
		(end 362.137452 -398.16151)
		(width 0.13208)
		(layer "F.Cu")
		(net "MB_3V3IO_RSVD3")
	)
	(segment
		(start 364.947454 -397.025622)
		(end 365.798862 -397.025622)
		(width 0.13208)
		(layer "F.Cu")
		(net "MB_3V3IO_RSVD3")
	)
	(segment
		(start 362.732574 -396.50035)
		(end 363.434122 -396.50035)
		(width 0.13208)
		(layer "F.Cu")
		(net "MB_3V3IO_RSVD3")
	)
	(segment
		(start 363.96041 -397.025622)
		(end 363.959902 -397.02613)
		(width 0.13208)
		(layer "F.Cu")
		(net "MB_3V3IO_RSVD3")
	)
	(segment
		(start 362.137452 -398.16151)
		(end 362.137452 -396.951454)
		(width 0.13208)
		(layer "F.Cu")
		(net "MB_3V3IO_RSVD3")
	)
	(segment
		(start 362.58246 -396.506446)
		(end 362.726478 -396.506446)
		(width 0.13208)
		(layer "F.Cu")
		(net "MB_3V3IO_RSVD3")
	)
	(segment
		(start 360.450638 -398.649444)
		(end 361.649518 -398.649444)
		(width 0.13208)
		(layer "F.Cu")
		(net "MB_3V3IO_RSVD3")
	)
	(segment
		(start 362.137452 -396.951454)
		(end 362.58246 -396.506446)
		(width 0.13208)
		(layer "F.Cu")
		(net "MB_3V3IO_RSVD3")
	)
	(segment
		(start 363.434122 -396.50035)
		(end 363.959902 -397.02613)
		(width 0.13208)
		(layer "F.Cu")
		(net "MB_3V3IO_RSVD3")
	)
	(segment
		(start 362.726478 -396.506446)
		(end 362.732574 -396.50035)
		(width 0.13208)
		(layer "F.Cu")
		(net "MB_3V3IO_RSVD3")
	)
	(segment
		(start 364.947454 -397.025622)
		(end 363.96041 -397.025622)
		(width 0.13208)
		(layer "F.Cu")
		(net "MB_3V3IO_RSVD3")
	)
	(via
		(at 361.649518 -398.649444)
		(size 0.762)
		(drill 0.381)
		(layers "F.Cu" "B.Cu")
		(net "MB_3V3IO_RSVD3")
	)
	(via
		(at 365.798862 -397.025622)
		(size 0.508)
		(drill 0.254)
		(layers "F.Cu" "B.Cu")
		(net "MB_3V3IO_RSVD3")
	)
	(segment
		(start 365.798862 -397.025622)
		(end 369.807236 -393.017248)
		(width 0.13208)
		(layer "B.Cu")
		(net "MB_3V3IO_RSVD3")
	)
	(segment
		(start 393.7889 -407.491184)
		(end 393.089892 -408.190192)
		(width 0.13208)
		(layer "B.Cu")
		(net "MB_3V3IO_RSVD3")
	)
	(segment
		(start 393.7889 -394.48105)
		(end 393.7889 -407.491184)
		(width 0.13208)
		(layer "B.Cu")
		(net "MB_3V3IO_RSVD3")
	)
	(segment
		(start 392.325098 -393.017248)
		(end 393.7889 -394.48105)
		(width 0.13208)
		(layer "B.Cu")
		(net "MB_3V3IO_RSVD3")
	)
	(segment
		(start 369.807236 -393.017248)
		(end 392.325098 -393.017248)
		(width 0.13208)
		(layer "B.Cu")
		(net "MB_3V3IO_RSVD3")
	)
	(segment
		(start 129.243582 -194.45351)
		(end 129.243582 -194.065906)
		(width 0.13208)
		(layer "F.Cu")
		(net "NIC7_CLK_EN_BUF_N")
	)
	(segment
		(start 130.532378 -194.807586)
		(end 130.71729 -194.992498)
		(width 0.13208)
		(layer "F.Cu")
		(net "NIC7_CLK_EN_BUF_N")
	)
	(segment
		(start 129.597658 -194.807586)
		(end 130.532378 -194.807586)
		(width 0.13208)
		(layer "F.Cu")
		(net "NIC7_CLK_EN_BUF_N")
	)
	(segment
		(start 129.243582 -194.065906)
		(end 129.76606 -193.543428)
		(width 0.13208)
		(layer "F.Cu")
		(net "NIC7_CLK_EN_BUF_N")
	)
	(segment
		(start 129.76606 -193.543428)
		(end 130.430016 -193.543428)
		(width 0.13208)
		(layer "F.Cu")
		(net "NIC7_CLK_EN_BUF_N")
	)
	(segment
		(start 130.71729 -194.992498)
		(end 130.71729 -195.391786)
		(width 0.13208)
		(layer "F.Cu")
		(net "NIC7_CLK_EN_BUF_N")
	)
	(segment
		(start 129.243582 -194.45351)
		(end 129.597658 -194.807586)
		(width 0.13208)
		(layer "F.Cu")
		(net "NIC7_CLK_EN_BUF_N")
	)
	(via
		(at 129.243582 -194.45351)
		(size 0.762)
		(drill 0.381)
		(layers "F.Cu" "B.Cu")
		(net "NIC7_CLK_EN_BUF_N")
	)
	(segment
		(start 362.610908 -391.25779)
		(end 362.827316 -391.25779)
		(width 0.13208)
		(layer "F.Cu")
		(net "MB_3V3IO_RSVD1")
	)
	(segment
		(start 361.841542 -393.281154)
		(end 362.281978 -392.840718)
		(width 0.13208)
		(layer "F.Cu")
		(net "MB_3V3IO_RSVD1")
	)
	(segment
		(start 361.841542 -393.281154)
		(end 360.647742 -393.281154)
		(width 0.13208)
		(layer "F.Cu")
		(net "MB_3V3IO_RSVD1")
	)
	(segment
		(start 362.281978 -391.58672)
		(end 362.610908 -391.25779)
		(width 0.13208)
		(layer "F.Cu")
		(net "MB_3V3IO_RSVD1")
	)
	(segment
		(start 364.08487 -391.265918)
		(end 362.835444 -391.265918)
		(width 0.13208)
		(layer "F.Cu")
		(net "MB_3V3IO_RSVD1")
	)
	(segment
		(start 364.085378 -391.26541)
		(end 364.08487 -391.265918)
		(width 0.13208)
		(layer "F.Cu")
		(net "MB_3V3IO_RSVD1")
	)
	(segment
		(start 365.072422 -391.26541)
		(end 364.085378 -391.26541)
		(width 0.13208)
		(layer "F.Cu")
		(net "MB_3V3IO_RSVD1")
	)
	(segment
		(start 365.072422 -391.26541)
		(end 366.05083 -391.26541)
		(width 0.13208)
		(layer "F.Cu")
		(net "MB_3V3IO_RSVD1")
	)
	(segment
		(start 362.835444 -391.265918)
		(end 362.827316 -391.25779)
		(width 0.13208)
		(layer "F.Cu")
		(net "MB_3V3IO_RSVD1")
	)
	(segment
		(start 360.647742 -393.281154)
		(end 360.613706 -393.247118)
		(width 0.13208)
		(layer "F.Cu")
		(net "MB_3V3IO_RSVD1")
	)
	(segment
		(start 362.281978 -392.840718)
		(end 362.281978 -391.58672)
		(width 0.13208)
		(layer "F.Cu")
		(net "MB_3V3IO_RSVD1")
	)
	(via
		(at 361.841542 -393.281154)
		(size 0.762)
		(drill 0.381)
		(layers "F.Cu" "B.Cu")
		(net "MB_3V3IO_RSVD1")
	)
	(via
		(at 366.05083 -391.26541)
		(size 0.508)
		(drill 0.254)
		(layers "F.Cu" "B.Cu")
		(net "MB_3V3IO_RSVD1")
	)
	(segment
		(start 391.17397 -391.26541)
		(end 394.213588 -394.305028)
		(width 0.13208)
		(layer "B.Cu")
		(net "MB_3V3IO_RSVD1")
	)
	(segment
		(start 394.213588 -410.966412)
		(end 393.089892 -412.090108)
		(width 0.13208)
		(layer "B.Cu")
		(net "MB_3V3IO_RSVD1")
	)
	(segment
		(start 366.05083 -391.26541)
		(end 391.17397 -391.26541)
		(width 0.13208)
		(layer "B.Cu")
		(net "MB_3V3IO_RSVD1")
	)
	(segment
		(start 394.213588 -394.305028)
		(end 394.213588 -410.966412)
		(width 0.13208)
		(layer "B.Cu")
		(net "MB_3V3IO_RSVD1")
	)
	(segment
		(start 132.173726 -195.913756)
		(end 133.535166 -195.913756)
		(width 0.13208)
		(layer "F.Cu")
		(net "NIC6_CLK_EN_BUF_N")
	)
	(segment
		(start 133.65734 -194.017138)
		(end 133.65734 -195.075302)
		(width 0.13208)
		(layer "F.Cu")
		(net "NIC6_CLK_EN_BUF_N")
	)
	(segment
		(start 133.177026 -193.536824)
		(end 133.65734 -194.017138)
		(width 0.13208)
		(layer "F.Cu")
		(net "NIC6_CLK_EN_BUF_N")
	)
	(segment
		(start 133.65734 -195.791582)
		(end 133.65734 -195.075302)
		(width 0.13208)
		(layer "F.Cu")
		(net "NIC6_CLK_EN_BUF_N")
	)
	(segment
		(start 133.535166 -195.913756)
		(end 133.65734 -195.791582)
		(width 0.13208)
		(layer "F.Cu")
		(net "NIC6_CLK_EN_BUF_N")
	)
	(segment
		(start 132.017262 -195.391786)
		(end 132.017262 -195.757292)
		(width 0.13208)
		(layer "F.Cu")
		(net "NIC6_CLK_EN_BUF_N")
	)
	(segment
		(start 132.017262 -195.757292)
		(end 132.173726 -195.913756)
		(width 0.13208)
		(layer "F.Cu")
		(net "NIC6_CLK_EN_BUF_N")
	)
	(via
		(at 133.65734 -195.075302)
		(size 0.762)
		(drill 0.381)
		(layers "F.Cu" "B.Cu")
		(net "NIC6_CLK_EN_BUF_N")
	)
	(segment
		(start 142.705328 -189.128146)
		(end 143.406368 -189.128146)
		(width 0.13208)
		(layer "F.Cu")
		(net "NIC5_CLK_EN_BUF_N")
	)
	(segment
		(start 143.530066 -187.70219)
		(end 143.67383 -187.558426)
		(width 0.13208)
		(layer "F.Cu")
		(net "NIC5_CLK_EN_BUF_N")
	)
	(segment
		(start 144.13103 -188.752988)
		(end 144.13103 -187.558426)
		(width 0.13208)
		(layer "F.Cu")
		(net "NIC5_CLK_EN_BUF_N")
	)
	(segment
		(start 143.530066 -189.004448)
		(end 143.530066 -187.70219)
		(width 0.13208)
		(layer "F.Cu")
		(net "NIC5_CLK_EN_BUF_N")
	)
	(segment
		(start 143.406368 -189.128146)
		(end 143.530066 -189.004448)
		(width 0.13208)
		(layer "F.Cu")
		(net "NIC5_CLK_EN_BUF_N")
	)
	(segment
		(start 143.67383 -187.558426)
		(end 144.13103 -187.558426)
		(width 0.13208)
		(layer "F.Cu")
		(net "NIC5_CLK_EN_BUF_N")
	)
	(via
		(at 144.13103 -187.558426)
		(size 0.762)
		(drill 0.381)
		(layers "F.Cu" "B.Cu")
		(net "NIC5_CLK_EN_BUF_N")
	)
	(segment
		(start 142.436088 -191.879728)
		(end 141.308836 -191.879728)
		(width 0.13208)
		(layer "F.Cu")
		(net "NIC4_CLK_EN_BUF_N")
	)
	(segment
		(start 141.308836 -191.879728)
		(end 141.308836 -191.386968)
		(width 0.13208)
		(layer "F.Cu")
		(net "NIC4_CLK_EN_BUF_N")
	)
	(segment
		(start 143.385794 -190.659512)
		(end 143.1544 -190.428118)
		(width 0.13208)
		(layer "F.Cu")
		(net "NIC4_CLK_EN_BUF_N")
	)
	(segment
		(start 143.1544 -190.428118)
		(end 142.705328 -190.428118)
		(width 0.13208)
		(layer "F.Cu")
		(net "NIC4_CLK_EN_BUF_N")
	)
	(segment
		(start 143.385794 -191.013842)
		(end 143.385794 -190.659512)
		(width 0.13208)
		(layer "F.Cu")
		(net "NIC4_CLK_EN_BUF_N")
	)
	(segment
		(start 141.408912 -191.286892)
		(end 143.112744 -191.286892)
		(width 0.13208)
		(layer "F.Cu")
		(net "NIC4_CLK_EN_BUF_N")
	)
	(segment
		(start 143.112744 -191.286892)
		(end 143.385794 -191.013842)
		(width 0.13208)
		(layer "F.Cu")
		(net "NIC4_CLK_EN_BUF_N")
	)
	(segment
		(start 142.547848 -191.767968)
		(end 142.436088 -191.879728)
		(width 0.13208)
		(layer "F.Cu")
		(net "NIC4_CLK_EN_BUF_N")
	)
	(segment
		(start 141.308836 -191.386968)
		(end 141.408912 -191.286892)
		(width 0.13208)
		(layer "F.Cu")
		(net "NIC4_CLK_EN_BUF_N")
	)
	(via
		(at 141.308836 -191.879728)
		(size 0.762)
		(drill 0.381)
		(layers "F.Cu" "B.Cu")
		(net "NIC4_CLK_EN_BUF_N")
	)
	(segment
		(start 180.305202 -176.873408)
		(end 180.116734 -177.061876)
		(width 0.13208)
		(layer "F.Cu")
		(net "NIC3_CLK_EN_BUF_N")
	)
	(segment
		(start 182.172356 -175.668686)
		(end 180.781452 -175.668686)
		(width 0.13208)
		(layer "F.Cu")
		(net "NIC3_CLK_EN_BUF_N")
	)
	(segment
		(start 180.116734 -177.061876)
		(end 179.746402 -177.061876)
		(width 0.13208)
		(layer "F.Cu")
		(net "NIC3_CLK_EN_BUF_N")
	)
	(segment
		(start 180.305202 -176.144936)
		(end 180.305202 -176.873408)
		(width 0.13208)
		(layer "F.Cu")
		(net "NIC3_CLK_EN_BUF_N")
	)
	(segment
		(start 180.781452 -175.668686)
		(end 180.305202 -176.144936)
		(width 0.13208)
		(layer "F.Cu")
		(net "NIC3_CLK_EN_BUF_N")
	)
	(via
		(at 180.781452 -175.668686)
		(size 0.762)
		(drill 0.381)
		(layers "F.Cu" "B.Cu")
		(net "NIC3_CLK_EN_BUF_N")
	)
	(segment
		(start 178.156362 -179.232814)
		(end 177.615088 -179.774088)
		(width 0.13208)
		(layer "F.Cu")
		(net "NIC2_CLK_EN_BUF_N")
	)
	(segment
		(start 179.746402 -178.361848)
		(end 180.207158 -178.361848)
		(width 0.13208)
		(layer "F.Cu")
		(net "NIC2_CLK_EN_BUF_N")
	)
	(segment
		(start 180.007514 -179.232814)
		(end 178.156362 -179.232814)
		(width 0.13208)
		(layer "F.Cu")
		(net "NIC2_CLK_EN_BUF_N")
	)
	(segment
		(start 178.003962 -180.162962)
		(end 177.615088 -179.774088)
		(width 0.13208)
		(layer "F.Cu")
		(net "NIC2_CLK_EN_BUF_N")
	)
	(segment
		(start 178.81854 -180.162962)
		(end 178.003962 -180.162962)
		(width 0.13208)
		(layer "F.Cu")
		(net "NIC2_CLK_EN_BUF_N")
	)
	(segment
		(start 180.315108 -178.469798)
		(end 180.315108 -178.92522)
		(width 0.13208)
		(layer "F.Cu")
		(net "NIC2_CLK_EN_BUF_N")
	)
	(segment
		(start 180.207158 -178.361848)
		(end 180.315108 -178.469798)
		(width 0.13208)
		(layer "F.Cu")
		(net "NIC2_CLK_EN_BUF_N")
	)
	(segment
		(start 180.315108 -178.92522)
		(end 180.007514 -179.232814)
		(width 0.13208)
		(layer "F.Cu")
		(net "NIC2_CLK_EN_BUF_N")
	)
	(via
		(at 177.615088 -179.774088)
		(size 0.762)
		(drill 0.381)
		(layers "F.Cu" "B.Cu")
		(net "NIC2_CLK_EN_BUF_N")
	)
	(segment
		(start 122.827542 -165.838124)
		(end 122.411998 -165.838124)
		(width 0.13208)
		(layer "F.Cu")
		(net "NIC1_CLK_EN_BUF_N")
	)
	(segment
		(start 123.602242 -166.483538)
		(end 122.960638 -165.841934)
		(width 0.13208)
		(layer "F.Cu")
		(net "NIC1_CLK_EN_BUF_N")
	)
	(segment
		(start 123.602242 -166.483538)
		(end 124.14631 -167.027606)
		(width 0.13208)
		(layer "F.Cu")
		(net "NIC1_CLK_EN_BUF_N")
	)
	(segment
		(start 122.960638 -165.841934)
		(end 122.831352 -165.841934)
		(width 0.13208)
		(layer "F.Cu")
		(net "NIC1_CLK_EN_BUF_N")
	)
	(segment
		(start 124.14631 -167.027606)
		(end 124.14631 -168.484804)
		(width 0.13208)
		(layer "F.Cu")
		(net "NIC1_CLK_EN_BUF_N")
	)
	(segment
		(start 122.831352 -165.841934)
		(end 122.827542 -165.838124)
		(width 0.13208)
		(layer "F.Cu")
		(net "NIC1_CLK_EN_BUF_N")
	)
	(via
		(at 123.602242 -166.483538)
		(size 0.762)
		(drill 0.381)
		(layers "F.Cu" "B.Cu")
		(net "NIC1_CLK_EN_BUF_N")
	)
	(segment
		(start 125.446282 -168.094406)
		(end 125.446282 -168.484804)
		(width 0.13208)
		(layer "F.Cu")
		(net "NIC0_CLK_EN_BUF_N")
	)
	(segment
		(start 126.812802 -169.069258)
		(end 126.812802 -168.434258)
		(width 0.13208)
		(layer "F.Cu")
		(net "NIC0_CLK_EN_BUF_N")
	)
	(segment
		(start 127.680212 -168.201848)
		(end 127.680212 -167.752014)
		(width 0.13208)
		(layer "F.Cu")
		(net "NIC0_CLK_EN_BUF_N")
	)
	(segment
		(start 126.284736 -167.906192)
		(end 125.634496 -167.906192)
		(width 0.13208)
		(layer "F.Cu")
		(net "NIC0_CLK_EN_BUF_N")
	)
	(segment
		(start 126.812802 -168.434258)
		(end 126.284736 -167.906192)
		(width 0.13208)
		(layer "F.Cu")
		(net "NIC0_CLK_EN_BUF_N")
	)
	(segment
		(start 126.812802 -169.069258)
		(end 127.680212 -168.201848)
		(width 0.13208)
		(layer "F.Cu")
		(net "NIC0_CLK_EN_BUF_N")
	)
	(segment
		(start 125.634496 -167.906192)
		(end 125.446282 -168.094406)
		(width 0.13208)
		(layer "F.Cu")
		(net "NIC0_CLK_EN_BUF_N")
	)
	(via
		(at 126.812802 -169.069258)
		(size 0.762)
		(drill 0.381)
		(layers "F.Cu" "B.Cu")
		(net "NIC0_CLK_EN_BUF_N")
	)
	(segment
		(start 266.294362 -366.930432)
		(end 265.240008 -366.930432)
		(width 0.508)
		(layer "F.Cu")
		(net "HS_GATE2_R_4")
	)
	(via
		(at 266.294362 -366.930432)
		(size 0.508)
		(drill 0.254)
		(layers "F.Cu" "B.Cu")
		(net "HS_GATE2_R_4")
	)
	(via
		(at 265.485372 -366.927384)
		(size 0.6604)
		(drill 0.3302)
		(layers "F.Cu" "B.Cu")
		(net "HS_GATE2_R_4")
	)
	(segment
		(start 266.294362 -366.930432)
		(end 265.48842 -366.930432)
		(width 0.508)
		(layer "B.Cu")
		(net "HS_GATE2_R_4")
	)
	(segment
		(start 265.485372 -366.927384)
		(end 264.18413 -366.927384)
		(width 0.508)
		(layer "B.Cu")
		(net "HS_GATE2_R_4")
	)
	(segment
		(start 265.48842 -366.930432)
		(end 265.485372 -366.927384)
		(width 0.508)
		(layer "B.Cu")
		(net "HS_GATE2_R_4")
	)
	(segment
		(start 243.577872 -349.400114)
		(end 241.90579 -349.400114)
		(width 0.254)
		(layer "F.Cu")
		(net "P12V_HSC_GATE2")
	)
	(via
		(at 241.81689 -355.910642)
		(size 0.6604)
		(drill 0.3302)
		(layers "F.Cu" "B.Cu")
		(net "P12V_HSC_GATE2")
	)
	(via
		(at 241.14379 -349.400114)
		(size 0.508)
		(drill 0.254)
		(layers "F.Cu" "B.Cu")
		(net "P12V_HSC_GATE2")
	)
	(via
		(at 241.90579 -349.400114)
		(size 0.508)
		(drill 0.254)
		(layers "F.Cu" "B.Cu")
		(net "P12V_HSC_GATE2")
	)
	(segment
		(start 267.884656 -367.178844)
		(end 269.099792 -365.963708)
		(width 0.4572)
		(layer "B.Cu")
		(net "P12V_HSC_GATE2")
	)
	(segment
		(start 241.81689 -355.910642)
		(end 241.184938 -355.27869)
		(width 0.4572)
		(layer "B.Cu")
		(net "P12V_HSC_GATE2")
	)
	(segment
		(start 263.669526 -367.73866)
		(end 266.465558 -367.73866)
		(width 0.4572)
		(layer "B.Cu")
		(net "P12V_HSC_GATE2")
	)
	(segment
		(start 255.890522 -366.906048)
		(end 255.097534 -367.699036)
		(width 0.4572)
		(layer "B.Cu")
		(net "P12V_HSC_GATE2")
	)
	(segment
		(start 249.97156 -366.83696)
		(end 249.119136 -367.689384)
		(width 0.4572)
		(layer "B.Cu")
		(net "P12V_HSC_GATE2")
	)
	(segment
		(start 241.81689 -355.910642)
		(end 242.638834 -356.732586)
		(width 0.4572)
		(layer "B.Cu")
		(net "P12V_HSC_GATE2")
	)
	(segment
		(start 242.64239 -358.807512)
		(end 242.080542 -359.36936)
		(width 0.4572)
		(layer "B.Cu")
		(net "P12V_HSC_GATE2")
	)
	(segment
		(start 250.76404 -367.452148)
		(end 250.76404 -366.860328)
		(width 0.4572)
		(layer "B.Cu")
		(net "P12V_HSC_GATE2")
	)
	(segment
		(start 241.184938 -352.29419)
		(end 240.530126 -351.639378)
		(width 0.4572)
		(layer "B.Cu")
		(net "P12V_HSC_GATE2")
	)
	(segment
		(start 261.781036 -367.719102)
		(end 262.572754 -366.927384)
		(width 0.4572)
		(layer "B.Cu")
		(net "P12V_HSC_GATE2")
	)
	(segment
		(start 241.14379 -349.400114)
		(end 241.90579 -349.400114)
		(width 0.4572)
		(layer "B.Cu")
		(net "P12V_HSC_GATE2")
	)
	(segment
		(start 235.360718 -360.466386)
		(end 235.360718 -366.32134)
		(width 0.4572)
		(layer "B.Cu")
		(net "P12V_HSC_GATE2")
	)
	(segment
		(start 242.638834 -357.543862)
		(end 242.64239 -357.547418)
		(width 0.4572)
		(layer "B.Cu")
		(net "P12V_HSC_GATE2")
	)
	(segment
		(start 245.105682 -367.369852)
		(end 245.105682 -366.896396)
		(width 0.4572)
		(layer "B.Cu")
		(net "P12V_HSC_GATE2")
	)
	(segment
		(start 250.76404 -366.860328)
		(end 250.740672 -366.83696)
		(width 0.4572)
		(layer "B.Cu")
		(net "P12V_HSC_GATE2")
	)
	(segment
		(start 256.864866 -366.906048)
		(end 255.890522 -366.906048)
		(width 0.4572)
		(layer "B.Cu")
		(net "P12V_HSC_GATE2")
	)
	(segment
		(start 235.360718 -366.32134)
		(end 236.659674 -367.620296)
		(width 0.4572)
		(layer "B.Cu")
		(net "P12V_HSC_GATE2")
	)
	(segment
		(start 236.457744 -359.36936)
		(end 235.360718 -360.466386)
		(width 0.4572)
		(layer "B.Cu")
		(net "P12V_HSC_GATE2")
	)
	(segment
		(start 251.010928 -367.699036)
		(end 250.76404 -367.452148)
		(width 0.4572)
		(layer "B.Cu")
		(net "P12V_HSC_GATE2")
	)
	(segment
		(start 245.425214 -367.689384)
		(end 245.105682 -367.369852)
		(width 0.4572)
		(layer "B.Cu")
		(net "P12V_HSC_GATE2")
	)
	(segment
		(start 241.184938 -355.27869)
		(end 241.184938 -352.29419)
		(width 0.4572)
		(layer "B.Cu")
		(net "P12V_HSC_GATE2")
	)
	(segment
		(start 267.025374 -367.178844)
		(end 267.087858 -367.178844)
		(width 0.4572)
		(layer "B.Cu")
		(net "P12V_HSC_GATE2")
	)
	(segment
		(start 269.099792 -365.963708)
		(end 269.099792 -365.379254)
		(width 0.4572)
		(layer "B.Cu")
		(net "P12V_HSC_GATE2")
	)
	(segment
		(start 242.638834 -356.732586)
		(end 242.638834 -357.543862)
		(width 0.4572)
		(layer "B.Cu")
		(net "P12V_HSC_GATE2")
	)
	(segment
		(start 266.465558 -367.73866)
		(end 267.025374 -367.178844)
		(width 0.4572)
		(layer "B.Cu")
		(net "P12V_HSC_GATE2")
	)
	(segment
		(start 242.080542 -359.36936)
		(end 236.457744 -359.36936)
		(width 0.4572)
		(layer "B.Cu")
		(net "P12V_HSC_GATE2")
	)
	(segment
		(start 242.64239 -357.547418)
		(end 242.64239 -358.807512)
		(width 0.4572)
		(layer "B.Cu")
		(net "P12V_HSC_GATE2")
	)
	(segment
		(start 249.119136 -367.689384)
		(end 245.425214 -367.689384)
		(width 0.4572)
		(layer "B.Cu")
		(net "P12V_HSC_GATE2")
	)
	(segment
		(start 255.097534 -367.699036)
		(end 251.010928 -367.699036)
		(width 0.4572)
		(layer "B.Cu")
		(net "P12V_HSC_GATE2")
	)
	(segment
		(start 262.572754 -366.927384)
		(end 263.38403 -366.927384)
		(width 0.4572)
		(layer "B.Cu")
		(net "P12V_HSC_GATE2")
	)
	(segment
		(start 240.530126 -351.639378)
		(end 240.530126 -350.013778)
		(width 0.4572)
		(layer "B.Cu")
		(net "P12V_HSC_GATE2")
	)
	(segment
		(start 243.155724 -366.896396)
		(end 245.105682 -366.896396)
		(width 0.4572)
		(layer "B.Cu")
		(net "P12V_HSC_GATE2")
	)
	(segment
		(start 267.087858 -367.178844)
		(end 267.884656 -367.178844)
		(width 0.4572)
		(layer "B.Cu")
		(net "P12V_HSC_GATE2")
	)
	(segment
		(start 250.740672 -366.83696)
		(end 249.97156 -366.83696)
		(width 0.4572)
		(layer "B.Cu")
		(net "P12V_HSC_GATE2")
	)
	(segment
		(start 256.864866 -367.344452)
		(end 257.239516 -367.719102)
		(width 0.4572)
		(layer "B.Cu")
		(net "P12V_HSC_GATE2")
	)
	(segment
		(start 256.864866 -366.906048)
		(end 256.864866 -367.344452)
		(width 0.4572)
		(layer "B.Cu")
		(net "P12V_HSC_GATE2")
	)
	(segment
		(start 263.38403 -367.453164)
		(end 263.669526 -367.73866)
		(width 0.4572)
		(layer "B.Cu")
		(net "P12V_HSC_GATE2")
	)
	(segment
		(start 242.431824 -367.620296)
		(end 243.155724 -366.896396)
		(width 0.4572)
		(layer "B.Cu")
		(net "P12V_HSC_GATE2")
	)
	(segment
		(start 240.530126 -350.013778)
		(end 241.14379 -349.400114)
		(width 0.4572)
		(layer "B.Cu")
		(net "P12V_HSC_GATE2")
	)
	(segment
		(start 236.659674 -367.620296)
		(end 242.431824 -367.620296)
		(width 0.4572)
		(layer "B.Cu")
		(net "P12V_HSC_GATE2")
	)
	(segment
		(start 263.38403 -366.927384)
		(end 263.38403 -367.453164)
		(width 0.4572)
		(layer "B.Cu")
		(net "P12V_HSC_GATE2")
	)
	(segment
		(start 257.239516 -367.719102)
		(end 261.781036 -367.719102)
		(width 0.4572)
		(layer "B.Cu")
		(net "P12V_HSC_GATE2")
	)
	(segment
		(start 258.259326 -378.417328)
		(end 258.538218 -378.69622)
		(width 0.254)
		(layer "F.Cu")
		(net "P12V_HSC_SENSE2_R2_P")
	)
	(segment
		(start 258.538218 -378.69622)
		(end 258.538218 -379.170438)
		(width 0.254)
		(layer "F.Cu")
		(net "P12V_HSC_SENSE2_R2_P")
	)
	(via
		(at 236.514386 -351.339658)
		(size 0.508)
		(drill 0.254)
		(layers "F.Cu" "B.Cu")
		(net "P12V_HSC_SENSE2_R2_P")
	)
	(via
		(at 258.259326 -378.417328)
		(size 0.508)
		(drill 0.254)
		(layers "F.Cu" "B.Cu")
		(net "P12V_HSC_SENSE2_R2_P")
	)
	(via
		(at 236.514386 -357.130858)
		(size 0.762)
		(drill 0.254)
		(layers "F.Cu" "B.Cu")
		(net "P12V_HSC_SENSE2_R2_P")
	)
	(segment
		(start 237.231936 -357.130858)
		(end 236.514386 -357.130858)
		(width 0.254)
		(layer "B.Cu")
		(net "P12V_HSC_SENSE2_R2_P")
	)
	(segment
		(start 235.38688 -351.349056)
		(end 235.917232 -351.349056)
		(width 0.254)
		(layer "B.Cu")
		(net "P12V_HSC_SENSE2_R2_P")
	)
	(segment
		(start 235.92663 -351.339658)
		(end 236.514386 -351.339658)
		(width 0.254)
		(layer "B.Cu")
		(net "P12V_HSC_SENSE2_R2_P")
	)
	(segment
		(start 235.917232 -351.349056)
		(end 235.92663 -351.339658)
		(width 0.254)
		(layer "B.Cu")
		(net "P12V_HSC_SENSE2_R2_P")
	)
	(segment
		(start 237.484666 -352.309938)
		(end 236.514386 -351.339658)
		(width 0.254)
		(layer "In5.Cu")
		(net "P12V_HSC_SENSE2_R2_P")
	)
	(segment
		(start 237.484666 -356.160578)
		(end 237.484666 -352.309938)
		(width 0.254)
		(layer "In5.Cu")
		(net "P12V_HSC_SENSE2_R2_P")
	)
	(segment
		(start 236.514386 -357.130858)
		(end 237.484666 -356.160578)
		(width 0.254)
		(layer "In5.Cu")
		(net "P12V_HSC_SENSE2_R2_P")
	)
	(segment
		(start 258.259326 -378.417328)
		(end 258.492752 -378.183394)
		(width 0.254)
		(layer "In9.Cu")
		(net "P12V_HSC_SENSE2_R2_P")
	)
	(segment
		(start 234.721908 -369.624102)
		(end 234.721908 -361.43057)
		(width 0.254)
		(layer "In9.Cu")
		(net "P12V_HSC_SENSE2_R2_P")
	)
	(segment
		(start 237.21695 -357.833422)
		(end 236.514386 -357.130858)
		(width 0.254)
		(layer "In9.Cu")
		(net "P12V_HSC_SENSE2_R2_P")
	)
	(segment
		(start 237.21695 -358.935528)
		(end 237.21695 -357.833422)
		(width 0.254)
		(layer "In9.Cu")
		(net "P12V_HSC_SENSE2_R2_P")
	)
	(segment
		(start 237.776004 -377.424696)
		(end 235.548424 -375.197116)
		(width 0.254)
		(layer "In9.Cu")
		(net "P12V_HSC_SENSE2_R2_P")
	)
	(segment
		(start 258.492752 -378.183394)
		(end 258.492752 -377.848368)
		(width 0.254)
		(layer "In9.Cu")
		(net "P12V_HSC_SENSE2_R2_P")
	)
	(segment
		(start 258.06908 -377.424696)
		(end 237.776004 -377.424696)
		(width 0.254)
		(layer "In9.Cu")
		(net "P12V_HSC_SENSE2_R2_P")
	)
	(segment
		(start 235.548424 -375.197116)
		(end 235.548424 -373.796052)
		(width 0.254)
		(layer "In9.Cu")
		(net "P12V_HSC_SENSE2_R2_P")
	)
	(segment
		(start 233.769408 -370.576602)
		(end 234.721908 -369.624102)
		(width 0.254)
		(layer "In9.Cu")
		(net "P12V_HSC_SENSE2_R2_P")
	)
	(segment
		(start 258.492752 -377.848368)
		(end 258.06908 -377.424696)
		(width 0.254)
		(layer "In9.Cu")
		(net "P12V_HSC_SENSE2_R2_P")
	)
	(segment
		(start 234.721908 -361.43057)
		(end 237.21695 -358.935528)
		(width 0.254)
		(layer "In9.Cu")
		(net "P12V_HSC_SENSE2_R2_P")
	)
	(segment
		(start 235.548424 -373.796052)
		(end 233.769408 -372.017036)
		(width 0.254)
		(layer "In9.Cu")
		(net "P12V_HSC_SENSE2_R2_P")
	)
	(segment
		(start 233.769408 -372.017036)
		(end 233.769408 -370.576602)
		(width 0.254)
		(layer "In9.Cu")
		(net "P12V_HSC_SENSE2_R2_P")
	)
	(segment
		(start 279.232106 -386.498592)
		(end 279.232106 -388.528306)
		(width 0.13208)
		(layer "F.Cu")
		(net "LTC4282_T_CRIT_N")
	)
	(segment
		(start 279.232106 -388.528306)
		(end 279.756108 -389.052308)
		(width 0.13208)
		(layer "F.Cu")
		(net "LTC4282_T_CRIT_N")
	)
	(via
		(at 279.756108 -389.052308)
		(size 0.508)
		(drill 0.254)
		(layers "F.Cu" "B.Cu")
		(net "LTC4282_T_CRIT_N")
	)
	(via
		(at 279.756108 -385.6228)
		(size 0.6604)
		(drill 0.3302)
		(layers "F.Cu" "B.Cu")
		(net "LTC4282_T_CRIT_N")
	)
	(segment
		(start 279.756108 -384.40995)
		(end 279.74925 -384.403092)
		(width 0.13208)
		(layer "B.Cu")
		(net "LTC4282_T_CRIT_N")
	)
	(segment
		(start 279.756108 -385.6228)
		(end 279.756108 -384.40995)
		(width 0.13208)
		(layer "B.Cu")
		(net "LTC4282_T_CRIT_N")
	)
	(segment
		(start 279.756108 -385.6228)
		(end 279.756108 -389.052308)
		(width 0.13208)
		(layer "B.Cu")
		(net "LTC4282_T_CRIT_N")
	)
	(via
		(at 266.939776 -365.251238)
		(size 0.6604)
		(drill 0.3302)
		(layers "F.Cu" "B.Cu")
		(net "P12V_HSC_GATE_RC")
	)
	(segment
		(start 268.102334 -365.379)
		(end 268.068298 -365.413036)
		(width 0.381)
		(layer "B.Cu")
		(net "P12V_HSC_GATE_RC")
	)
	(segment
		(start 268.068298 -365.413036)
		(end 267.717016 -365.413036)
		(width 0.381)
		(layer "B.Cu")
		(net "P12V_HSC_GATE_RC")
	)
	(segment
		(start 267.087858 -365.832644)
		(end 267.087858 -366.378744)
		(width 0.381)
		(layer "B.Cu")
		(net "P12V_HSC_GATE_RC")
	)
	(segment
		(start 266.939776 -365.251238)
		(end 266.939776 -365.684562)
		(width 0.381)
		(layer "B.Cu")
		(net "P12V_HSC_GATE_RC")
	)
	(segment
		(start 267.555218 -365.251238)
		(end 266.939776 -365.251238)
		(width 0.381)
		(layer "B.Cu")
		(net "P12V_HSC_GATE_RC")
	)
	(segment
		(start 266.939776 -365.684562)
		(end 267.087858 -365.832644)
		(width 0.381)
		(layer "B.Cu")
		(net "P12V_HSC_GATE_RC")
	)
	(segment
		(start 267.717016 -365.413036)
		(end 267.555218 -365.251238)
		(width 0.381)
		(layer "B.Cu")
		(net "P12V_HSC_GATE_RC")
	)
	(segment
		(start 258.538218 -377.820174)
		(end 258.538218 -377.616974)
		(width 0.254)
		(layer "F.Cu")
		(net "P12V_HSC_SENSE2_R2_N")
	)
	(segment
		(start 259.085842 -378.367798)
		(end 258.538218 -377.820174)
		(width 0.254)
		(layer "F.Cu")
		(net "P12V_HSC_SENSE2_R2_N")
	)
	(via
		(at 236.514386 -353.270058)
		(size 0.762)
		(drill 0.254)
		(layers "F.Cu" "B.Cu")
		(net "P12V_HSC_SENSE2_R2_N")
	)
	(via
		(at 259.085842 -378.367798)
		(size 0.508)
		(drill 0.254)
		(layers "F.Cu" "B.Cu")
		(net "P12V_HSC_SENSE2_R2_N")
	)
	(via
		(at 236.514386 -355.200458)
		(size 0.508)
		(drill 0.254)
		(layers "F.Cu" "B.Cu")
		(net "P12V_HSC_SENSE2_R2_N")
	)
	(segment
		(start 235.400596 -353.273614)
		(end 235.404152 -353.270058)
		(width 0.254)
		(layer "B.Cu")
		(net "P12V_HSC_SENSE2_R2_N")
	)
	(segment
		(start 237.231936 -355.200458)
		(end 236.514386 -355.200458)
		(width 0.254)
		(layer "B.Cu")
		(net "P12V_HSC_SENSE2_R2_N")
	)
	(segment
		(start 235.404152 -353.270058)
		(end 236.514386 -353.270058)
		(width 0.254)
		(layer "B.Cu")
		(net "P12V_HSC_SENSE2_R2_N")
	)
	(segment
		(start 237.103666 -354.611178)
		(end 236.514386 -355.200458)
		(width 0.254)
		(layer "In5.Cu")
		(net "P12V_HSC_SENSE2_R2_N")
	)
	(segment
		(start 236.514386 -353.270058)
		(end 237.103666 -353.859338)
		(width 0.254)
		(layer "In5.Cu")
		(net "P12V_HSC_SENSE2_R2_N")
	)
	(segment
		(start 237.103666 -353.859338)
		(end 237.103666 -354.611178)
		(width 0.254)
		(layer "In5.Cu")
		(net "P12V_HSC_SENSE2_R2_N")
	)
	(segment
		(start 237.59795 -356.284022)
		(end 236.514386 -355.200458)
		(width 0.254)
		(layer "In9.Cu")
		(net "P12V_HSC_SENSE2_R2_N")
	)
	(segment
		(start 258.873752 -377.69038)
		(end 258.227068 -377.043696)
		(width 0.254)
		(layer "In9.Cu")
		(net "P12V_HSC_SENSE2_R2_N")
	)
	(segment
		(start 235.929424 -375.039128)
		(end 235.929424 -373.638064)
		(width 0.254)
		(layer "In9.Cu")
		(net "P12V_HSC_SENSE2_R2_N")
	)
	(segment
		(start 258.227068 -377.043696)
		(end 237.933992 -377.043696)
		(width 0.254)
		(layer "In9.Cu")
		(net "P12V_HSC_SENSE2_R2_N")
	)
	(segment
		(start 237.59795 -359.093516)
		(end 237.59795 -356.284022)
		(width 0.254)
		(layer "In9.Cu")
		(net "P12V_HSC_SENSE2_R2_N")
	)
	(segment
		(start 258.873752 -378.002292)
		(end 258.873752 -377.69038)
		(width 0.254)
		(layer "In9.Cu")
		(net "P12V_HSC_SENSE2_R2_N")
	)
	(segment
		(start 235.102908 -361.588558)
		(end 237.59795 -359.093516)
		(width 0.254)
		(layer "In9.Cu")
		(net "P12V_HSC_SENSE2_R2_N")
	)
	(segment
		(start 234.150408 -370.73459)
		(end 235.102908 -369.78209)
		(width 0.254)
		(layer "In9.Cu")
		(net "P12V_HSC_SENSE2_R2_N")
	)
	(segment
		(start 258.874006 -378.155962)
		(end 258.873752 -378.002292)
		(width 0.254)
		(layer "In9.Cu")
		(net "P12V_HSC_SENSE2_R2_N")
	)
	(segment
		(start 259.085842 -378.367798)
		(end 258.874006 -378.155962)
		(width 0.254)
		(layer "In9.Cu")
		(net "P12V_HSC_SENSE2_R2_N")
	)
	(segment
		(start 234.150408 -371.859048)
		(end 234.150408 -370.73459)
		(width 0.254)
		(layer "In9.Cu")
		(net "P12V_HSC_SENSE2_R2_N")
	)
	(segment
		(start 235.102908 -369.78209)
		(end 235.102908 -361.588558)
		(width 0.254)
		(layer "In9.Cu")
		(net "P12V_HSC_SENSE2_R2_N")
	)
	(segment
		(start 237.933992 -377.043696)
		(end 235.929424 -375.039128)
		(width 0.254)
		(layer "In9.Cu")
		(net "P12V_HSC_SENSE2_R2_N")
	)
	(segment
		(start 235.929424 -373.638064)
		(end 234.150408 -371.859048)
		(width 0.254)
		(layer "In9.Cu")
		(net "P12V_HSC_SENSE2_R2_N")
	)
	(segment
		(start 243.577872 -350.400112)
		(end 241.913918 -350.400112)
		(width 0.254)
		(layer "F.Cu")
		(net "P12V_HSC_GATE1")
	)
	(via
		(at 243.48059 -352.916998)
		(size 0.6604)
		(drill 0.3302)
		(layers "F.Cu" "B.Cu")
		(net "P12V_HSC_GATE1")
	)
	(via
		(at 241.165126 -350.400112)
		(size 0.508)
		(drill 0.254)
		(layers "F.Cu" "B.Cu")
		(net "P12V_HSC_GATE1")
	)
	(via
		(at 241.913918 -350.400112)
		(size 0.508)
		(drill 0.254)
		(layers "F.Cu" "B.Cu")
		(net "P12V_HSC_GATE1")
	)
	(segment
		(start 242.42776 -360.20756)
		(end 243.48059 -359.15473)
		(width 0.4572)
		(layer "B.Cu")
		(net "P12V_HSC_GATE1")
	)
	(segment
		(start 243.48059 -359.15473)
		(end 243.48059 -352.916998)
		(width 0.4572)
		(layer "B.Cu")
		(net "P12V_HSC_GATE1")
	)
	(segment
		(start 236.124496 -365.733584)
		(end 236.124496 -361.028742)
		(width 0.4572)
		(layer "B.Cu")
		(net "P12V_HSC_GATE1")
	)
	(segment
		(start 242.565428 -350.400112)
		(end 241.913918 -350.400112)
		(width 0.4572)
		(layer "B.Cu")
		(net "P12V_HSC_GATE1")
	)
	(segment
		(start 236.124496 -361.028742)
		(end 236.945678 -360.20756)
		(width 0.4572)
		(layer "B.Cu")
		(net "P12V_HSC_GATE1")
	)
	(segment
		(start 243.48059 -352.916998)
		(end 243.48059 -351.315274)
		(width 0.4572)
		(layer "B.Cu")
		(net "P12V_HSC_GATE1")
	)
	(segment
		(start 236.945678 -360.20756)
		(end 242.42776 -360.20756)
		(width 0.4572)
		(layer "B.Cu")
		(net "P12V_HSC_GATE1")
	)
	(segment
		(start 243.48059 -351.315274)
		(end 242.565428 -350.400112)
		(width 0.4572)
		(layer "B.Cu")
		(net "P12V_HSC_GATE1")
	)
	(segment
		(start 238.490252 -366.750854)
		(end 237.141766 -366.750854)
		(width 0.4572)
		(layer "B.Cu")
		(net "P12V_HSC_GATE1")
	)
	(segment
		(start 237.141766 -366.750854)
		(end 236.124496 -365.733584)
		(width 0.4572)
		(layer "B.Cu")
		(net "P12V_HSC_GATE1")
	)
	(segment
		(start 241.165126 -350.400112)
		(end 241.913918 -350.400112)
		(width 0.4572)
		(layer "B.Cu")
		(net "P12V_HSC_GATE1")
	)
	(segment
		(start 78.223364 -238.6076)
		(end 73.173336 -238.6076)
		(width 0.13208)
		(layer "F.Cu")
		(net "UART_PEX0_CLI_BUF_R1_TX")
	)
	(segment
		(start 73.12533 -238.655606)
		(end 71.7296 -238.655606)
		(width 0.13208)
		(layer "F.Cu")
		(net "UART_PEX0_CLI_BUF_R1_TX")
	)
	(segment
		(start 73.173336 -238.6076)
		(end 73.12533 -238.655606)
		(width 0.13208)
		(layer "F.Cu")
		(net "UART_PEX0_CLI_BUF_R1_TX")
	)
	(via
		(at 73.173336 -238.6076)
		(size 0.762)
		(drill 0.381)
		(layers "F.Cu" "B.Cu")
		(net "UART_PEX0_CLI_BUF_R1_TX")
	)
	(segment
		(start 80.889348 -218.1606)
		(end 72.843136 -218.1606)
		(width 0.13208)
		(layer "F.Cu")
		(net "UART_PEX3_CLI_R1_RX")
	)
	(segment
		(start 71.218806 -218.1606)
		(end 71.247 -218.132406)
		(width 0.13208)
		(layer "F.Cu")
		(net "UART_PEX3_CLI_R1_RX")
	)
	(segment
		(start 72.843136 -218.1606)
		(end 71.218806 -218.1606)
		(width 0.13208)
		(layer "F.Cu")
		(net "UART_PEX3_CLI_R1_RX")
	)
	(via
		(at 72.843136 -218.1606)
		(size 0.762)
		(drill 0.381)
		(layers "F.Cu" "B.Cu")
		(net "UART_PEX3_CLI_R1_RX")
	)
	(segment
		(start 60.467748 -227.1268)
		(end 71.2724 -227.1268)
		(width 0.13208)
		(layer "F.Cu")
		(net "UART_PEX1_CLI_R1_RX")
	)
	(segment
		(start 71.2724 -227.1268)
		(end 72.666606 -227.1268)
		(width 0.13208)
		(layer "F.Cu")
		(net "UART_PEX1_CLI_R1_RX")
	)
	(segment
		(start 72.666606 -227.1268)
		(end 72.7202 -227.073206)
		(width 0.13208)
		(layer "F.Cu")
		(net "UART_PEX1_CLI_R1_RX")
	)
	(via
		(at 71.2724 -227.1268)
		(size 0.762)
		(drill 0.381)
		(layers "F.Cu" "B.Cu")
		(net "UART_PEX1_CLI_R1_RX")
	)
	(segment
		(start 72.697594 -229.6668)
		(end 72.7202 -229.689406)
		(width 0.13208)
		(layer "F.Cu")
		(net "UART_PEX1_CLI_BUF_R1_TX")
	)
	(segment
		(start 57.547764 -229.6668)
		(end 70.993 -229.6668)
		(width 0.13208)
		(layer "F.Cu")
		(net "UART_PEX1_CLI_BUF_R1_TX")
	)
	(segment
		(start 70.993 -229.6668)
		(end 72.697594 -229.6668)
		(width 0.13208)
		(layer "F.Cu")
		(net "UART_PEX1_CLI_BUF_R1_TX")
	)
	(via
		(at 70.993 -229.6668)
		(size 0.762)
		(drill 0.381)
		(layers "F.Cu" "B.Cu")
		(net "UART_PEX1_CLI_BUF_R1_TX")
	)
	(segment
		(start 60.467748 -210.0326)
		(end 62.3062 -210.0326)
		(width 0.13208)
		(layer "F.Cu")
		(net "UART_PEX2_CLI_R1_RX")
	)
	(segment
		(start 62.3062 -210.0326)
		(end 62.562994 -209.775806)
		(width 0.13208)
		(layer "F.Cu")
		(net "UART_PEX2_CLI_R1_RX")
	)
	(segment
		(start 62.562994 -208.026)
		(end 62.562994 -207.3402)
		(width 0.13208)
		(layer "F.Cu")
		(net "UART_PEX2_CLI_R1_RX")
	)
	(segment
		(start 62.562994 -209.775806)
		(end 62.562994 -208.026)
		(width 0.13208)
		(layer "F.Cu")
		(net "UART_PEX2_CLI_R1_RX")
	)
	(via
		(at 62.562994 -208.026)
		(size 0.508)
		(drill 0.254)
		(layers "F.Cu" "B.Cu")
		(net "UART_PEX2_CLI_R1_RX")
	)
	(segment
		(start 73.017634 -220.7006)
		(end 71.244206 -220.7006)
		(width 0.13208)
		(layer "F.Cu")
		(net "UART_PEX3_CLI_BUF_R1_TX")
	)
	(segment
		(start 77.969364 -220.7006)
		(end 73.017634 -220.7006)
		(width 0.13208)
		(layer "F.Cu")
		(net "UART_PEX3_CLI_BUF_R1_TX")
	)
	(segment
		(start 71.244206 -220.7006)
		(end 71.247 -220.697806)
		(width 0.13208)
		(layer "F.Cu")
		(net "UART_PEX3_CLI_BUF_R1_TX")
	)
	(via
		(at 73.017634 -220.7006)
		(size 0.762)
		(drill 0.381)
		(layers "F.Cu" "B.Cu")
		(net "UART_PEX3_CLI_BUF_R1_TX")
	)
	(segment
		(start 60.5536 -212.5726)
		(end 60.579 -212.5472)
		(width 0.13208)
		(layer "F.Cu")
		(net "UART_PEX2_CLI_BUF_R1_TX")
	)
	(segment
		(start 60.579 -212.5472)
		(end 62.308994 -212.5472)
		(width 0.13208)
		(layer "F.Cu")
		(net "UART_PEX2_CLI_BUF_R1_TX")
	)
	(segment
		(start 57.547764 -212.5726)
		(end 60.5536 -212.5726)
		(width 0.13208)
		(layer "F.Cu")
		(net "UART_PEX2_CLI_BUF_R1_TX")
	)
	(via
		(at 60.5536 -212.5726)
		(size 0.508)
		(drill 0.254)
		(layers "F.Cu" "B.Cu")
		(net "UART_PEX2_CLI_BUF_R1_TX")
	)
	(segment
		(start 81.143348 -236.0676)
		(end 73.29932 -236.0676)
		(width 0.13208)
		(layer "F.Cu")
		(net "UART_PEX0_CLI_R1_RX")
	)
	(segment
		(start 71.7042 -236.090206)
		(end 73.276714 -236.090206)
		(width 0.13208)
		(layer "F.Cu")
		(net "UART_PEX0_CLI_R1_RX")
	)
	(segment
		(start 73.276714 -236.090206)
		(end 73.29932 -236.0676)
		(width 0.13208)
		(layer "F.Cu")
		(net "UART_PEX0_CLI_R1_RX")
	)
	(via
		(at 73.29932 -236.0676)
		(size 0.762)
		(drill 0.381)
		(layers "F.Cu" "B.Cu")
		(net "UART_PEX0_CLI_R1_RX")
	)
	(segment
		(start 399.28038 -243.206778)
		(end 399.28038 -246.144288)
		(width 0.13208)
		(layer "F.Cu")
		(net "UART_PEX1_SDB_R1_RX")
	)
	(segment
		(start 398.403318 -242.329716)
		(end 399.28038 -243.206778)
		(width 0.13208)
		(layer "F.Cu")
		(net "UART_PEX1_SDB_R1_RX")
	)
	(segment
		(start 394.789406 -242.9764)
		(end 395.43609 -242.329716)
		(width 0.13208)
		(layer "F.Cu")
		(net "UART_PEX1_SDB_R1_RX")
	)
	(segment
		(start 398.943068 -246.4816)
		(end 397.195548 -246.4816)
		(width 0.13208)
		(layer "F.Cu")
		(net "UART_PEX1_SDB_R1_RX")
	)
	(segment
		(start 399.28038 -246.144288)
		(end 398.943068 -246.4816)
		(width 0.13208)
		(layer "F.Cu")
		(net "UART_PEX1_SDB_R1_RX")
	)
	(segment
		(start 395.43609 -242.329716)
		(end 396.95374 -242.329716)
		(width 0.13208)
		(layer "F.Cu")
		(net "UART_PEX1_SDB_R1_RX")
	)
	(segment
		(start 396.95374 -242.329716)
		(end 398.403318 -242.329716)
		(width 0.13208)
		(layer "F.Cu")
		(net "UART_PEX1_SDB_R1_RX")
	)
	(via
		(at 396.95374 -242.329716)
		(size 0.762)
		(drill 0.381)
		(layers "F.Cu" "B.Cu")
		(net "UART_PEX1_SDB_R1_RX")
	)
	(segment
		(start 417.662614 -239.302544)
		(end 418.689536 -239.302544)
		(width 0.13208)
		(layer "F.Cu")
		(net "UART_PEX2_SDB_R1_RX")
	)
	(segment
		(start 415.18332 -239.29848)
		(end 417.65855 -239.29848)
		(width 0.13208)
		(layer "F.Cu")
		(net "UART_PEX2_SDB_R1_RX")
	)
	(segment
		(start 417.65855 -239.29848)
		(end 417.662614 -239.302544)
		(width 0.13208)
		(layer "F.Cu")
		(net "UART_PEX2_SDB_R1_RX")
	)
	(via
		(at 417.65855 -239.29848)
		(size 0.508)
		(drill 0.254)
		(layers "F.Cu" "B.Cu")
		(net "UART_PEX2_SDB_R1_RX")
	)
	(segment
		(start 412.263336 -241.83848)
		(end 415.993834 -241.83848)
		(width 0.13208)
		(layer "F.Cu")
		(net "UART_PEX2_SDB_BUF_R1_TX")
	)
	(segment
		(start 415.995104 -241.83975)
		(end 416.758374 -241.83975)
		(width 0.13208)
		(layer "F.Cu")
		(net "UART_PEX2_SDB_BUF_R1_TX")
	)
	(segment
		(start 415.993834 -241.83848)
		(end 415.995104 -241.83975)
		(width 0.13208)
		(layer "F.Cu")
		(net "UART_PEX2_SDB_BUF_R1_TX")
	)
	(via
		(at 415.993834 -241.83848)
		(size 0.508)
		(drill 0.254)
		(layers "F.Cu" "B.Cu")
		(net "UART_PEX2_SDB_BUF_R1_TX")
	)
	(segment
		(start 417.762436 -230.956866)
		(end 418.789358 -230.956866)
		(width 0.13208)
		(layer "F.Cu")
		(net "UART_PEX3_SDB_R1_RX")
	)
	(segment
		(start 402.533104 -230.278432)
		(end 412.701232 -230.278432)
		(width 0.13208)
		(layer "F.Cu")
		(net "UART_PEX3_SDB_R1_RX")
	)
	(segment
		(start 412.701232 -230.278432)
		(end 413.375602 -230.952802)
		(width 0.13208)
		(layer "F.Cu")
		(net "UART_PEX3_SDB_R1_RX")
	)
	(segment
		(start 413.375602 -230.952802)
		(end 417.758372 -230.952802)
		(width 0.13208)
		(layer "F.Cu")
		(net "UART_PEX3_SDB_R1_RX")
	)
	(segment
		(start 417.758372 -230.952802)
		(end 417.762436 -230.956866)
		(width 0.13208)
		(layer "F.Cu")
		(net "UART_PEX3_SDB_R1_RX")
	)
	(via
		(at 417.758372 -230.952802)
		(size 0.508)
		(drill 0.254)
		(layers "F.Cu" "B.Cu")
		(net "UART_PEX3_SDB_R1_RX")
	)
	(segment
		(start 412.407862 -223.863662)
		(end 413.961072 -223.863662)
		(width 0.13208)
		(layer "F.Cu")
		(net "UART_PEX0_SDB_BUF_R1_TX")
	)
	(segment
		(start 416.73145 -224.768156)
		(end 416.73145 -224.027746)
		(width 0.13208)
		(layer "F.Cu")
		(net "UART_PEX0_SDB_BUF_R1_TX")
	)
	(segment
		(start 416.262312 -225.237294)
		(end 416.73145 -224.768156)
		(width 0.13208)
		(layer "F.Cu")
		(net "UART_PEX0_SDB_BUF_R1_TX")
	)
	(segment
		(start 413.961072 -223.863662)
		(end 415.334704 -225.237294)
		(width 0.13208)
		(layer "F.Cu")
		(net "UART_PEX0_SDB_BUF_R1_TX")
	)
	(segment
		(start 415.334704 -225.237294)
		(end 416.262312 -225.237294)
		(width 0.13208)
		(layer "F.Cu")
		(net "UART_PEX0_SDB_BUF_R1_TX")
	)
	(via
		(at 415.334704 -225.237294)
		(size 0.508)
		(drill 0.254)
		(layers "F.Cu" "B.Cu")
		(net "UART_PEX0_SDB_BUF_R1_TX")
	)
	(segment
		(start 415.327846 -221.323662)
		(end 417.716208 -221.323662)
		(width 0.13208)
		(layer "F.Cu")
		(net "UART_PEX0_SDB_R1_RX")
	)
	(segment
		(start 418.23513 -221.323662)
		(end 418.237162 -221.32163)
		(width 0.13208)
		(layer "F.Cu")
		(net "UART_PEX0_SDB_R1_RX")
	)
	(segment
		(start 417.716208 -221.323662)
		(end 418.23513 -221.323662)
		(width 0.13208)
		(layer "F.Cu")
		(net "UART_PEX0_SDB_R1_RX")
	)
	(segment
		(start 418.237162 -221.32163)
		(end 418.65296 -221.32163)
		(width 0.13208)
		(layer "F.Cu")
		(net "UART_PEX0_SDB_R1_RX")
	)
	(via
		(at 417.716208 -221.323662)
		(size 0.508)
		(drill 0.254)
		(layers "F.Cu" "B.Cu")
		(net "UART_PEX0_SDB_R1_RX")
	)
	(segment
		(start 391.507218 -245.753128)
		(end 390.56437 -245.753128)
		(width 0.13208)
		(layer "F.Cu")
		(net "UART_PEX1_SDB_BUF_R1_TX")
	)
	(segment
		(start 389.946134 -247.443498)
		(end 391.524236 -249.0216)
		(width 0.13208)
		(layer "F.Cu")
		(net "UART_PEX1_SDB_BUF_R1_TX")
	)
	(segment
		(start 390.56437 -245.753128)
		(end 389.946134 -246.371364)
		(width 0.13208)
		(layer "F.Cu")
		(net "UART_PEX1_SDB_BUF_R1_TX")
	)
	(segment
		(start 392.067288 -246.313198)
		(end 391.507218 -245.753128)
		(width 0.13208)
		(layer "F.Cu")
		(net "UART_PEX1_SDB_BUF_R1_TX")
	)
	(segment
		(start 389.946134 -246.371364)
		(end 389.946134 -246.842788)
		(width 0.13208)
		(layer "F.Cu")
		(net "UART_PEX1_SDB_BUF_R1_TX")
	)
	(segment
		(start 389.946134 -246.842788)
		(end 389.946134 -247.443498)
		(width 0.13208)
		(layer "F.Cu")
		(net "UART_PEX1_SDB_BUF_R1_TX")
	)
	(segment
		(start 391.524236 -249.0216)
		(end 394.275564 -249.0216)
		(width 0.13208)
		(layer "F.Cu")
		(net "UART_PEX1_SDB_BUF_R1_TX")
	)
	(via
		(at 389.946134 -246.842788)
		(size 0.762)
		(drill 0.381)
		(layers "F.Cu" "B.Cu")
		(net "UART_PEX1_SDB_BUF_R1_TX")
	)
	(segment
		(start 412.385256 -233.492802)
		(end 415.29 -233.492802)
		(width 0.13208)
		(layer "F.Cu")
		(net "UART_PEX3_SDB_BUF_R1_TX")
	)
	(segment
		(start 411.710886 -232.818432)
		(end 412.385256 -233.492802)
		(width 0.13208)
		(layer "F.Cu")
		(net "UART_PEX3_SDB_BUF_R1_TX")
	)
	(segment
		(start 399.61312 -232.818432)
		(end 411.710886 -232.818432)
		(width 0.13208)
		(layer "F.Cu")
		(net "UART_PEX3_SDB_BUF_R1_TX")
	)
	(segment
		(start 415.803588 -232.979214)
		(end 416.819842 -232.979214)
		(width 0.13208)
		(layer "F.Cu")
		(net "UART_PEX3_SDB_BUF_R1_TX")
	)
	(segment
		(start 415.29 -233.492802)
		(end 415.803588 -232.979214)
		(width 0.13208)
		(layer "F.Cu")
		(net "UART_PEX3_SDB_BUF_R1_TX")
	)
	(via
		(at 415.29 -233.492802)
		(size 0.508)
		(drill 0.254)
		(layers "F.Cu" "B.Cu")
		(net "UART_PEX3_SDB_BUF_R1_TX")
	)
	(segment
		(start 240.76279 -355.715824)
		(end 242.255294 -355.715824)
		(width 0.254)
		(layer "F.Cu")
		(net "P12V_HSC_SENSE1_N")
	)
	(segment
		(start 240.15319 -356.873048)
		(end 240.15319 -356.325424)
		(width 0.254)
		(layer "F.Cu")
		(net "P12V_HSC_SENSE1_N")
	)
	(segment
		(start 240.15319 -356.325424)
		(end 240.76279 -355.715824)
		(width 0.254)
		(layer "F.Cu")
		(net "P12V_HSC_SENSE1_N")
	)
	(segment
		(start 238.168434 -377.987306)
		(end 238.485934 -378.304806)
		(width 0.254)
		(layer "F.Cu")
		(net "P12V_HSC_SENSE1_N")
	)
	(segment
		(start 239.07496 -378.304806)
		(end 239.416844 -377.962922)
		(width 0.254)
		(layer "F.Cu")
		(net "P12V_HSC_SENSE1_N")
	)
	(segment
		(start 238.485934 -378.304806)
		(end 239.07496 -378.304806)
		(width 0.254)
		(layer "F.Cu")
		(net "P12V_HSC_SENSE1_N")
	)
	(segment
		(start 239.416844 -377.962922)
		(end 239.416844 -375.163588)
		(width 0.254)
		(layer "F.Cu")
		(net "P12V_HSC_SENSE1_N")
	)
	(segment
		(start 242.571016 -355.400102)
		(end 243.577872 -355.400102)
		(width 0.254)
		(layer "F.Cu")
		(net "P12V_HSC_SENSE1_N")
	)
	(segment
		(start 239.83569 -357.190548)
		(end 240.15319 -356.873048)
		(width 0.254)
		(layer "F.Cu")
		(net "P12V_HSC_SENSE1_N")
	)
	(segment
		(start 242.255294 -355.715824)
		(end 242.571016 -355.400102)
		(width 0.254)
		(layer "F.Cu")
		(net "P12V_HSC_SENSE1_N")
	)
	(via
		(at 239.83569 -357.190548)
		(size 0.508)
		(drill 0.254)
		(layers "F.Cu" "B.Cu")
		(net "P12V_HSC_SENSE1_N")
	)
	(via
		(at 238.168434 -377.987306)
		(size 0.508)
		(drill 0.254)
		(layers "F.Cu" "B.Cu")
		(net "P12V_HSC_SENSE1_N")
	)
	(segment
		(start 238.765588 -349.104458)
		(end 239.075468 -349.414338)
		(width 0.254)
		(layer "B.Cu")
		(net "P12V_HSC_SENSE1_N")
	)
	(segment
		(start 240.15319 -356.082854)
		(end 240.15319 -356.873048)
		(width 0.254)
		(layer "B.Cu")
		(net "P12V_HSC_SENSE1_N")
	)
	(segment
		(start 238.02848 -349.473012)
		(end 238.397034 -349.104458)
		(width 0.254)
		(layer "B.Cu")
		(net "P12V_HSC_SENSE1_N")
	)
	(segment
		(start 238.397034 -349.104458)
		(end 238.765588 -349.104458)
		(width 0.254)
		(layer "B.Cu")
		(net "P12V_HSC_SENSE1_N")
	)
	(segment
		(start 239.631982 -355.561646)
		(end 240.15319 -356.082854)
		(width 0.254)
		(layer "B.Cu")
		(net "P12V_HSC_SENSE1_N")
	)
	(segment
		(start 239.075468 -349.414338)
		(end 239.075468 -354.052632)
		(width 0.254)
		(layer "B.Cu")
		(net "P12V_HSC_SENSE1_N")
	)
	(segment
		(start 240.15319 -356.873048)
		(end 239.83569 -357.190548)
		(width 0.254)
		(layer "B.Cu")
		(net "P12V_HSC_SENSE1_N")
	)
	(segment
		(start 239.075468 -354.052632)
		(end 239.631982 -354.609146)
		(width 0.254)
		(layer "B.Cu")
		(net "P12V_HSC_SENSE1_N")
	)
	(segment
		(start 239.631982 -354.609146)
		(end 239.631982 -355.561646)
		(width 0.254)
		(layer "B.Cu")
		(net "P12V_HSC_SENSE1_N")
	)
	(segment
		(start 243.485924 -357.96093)
		(end 242.448588 -358.998266)
		(width 0.254)
		(layer "In5.Cu")
		(net "P12V_HSC_SENSE1_N")
	)
	(segment
		(start 237.685326 -358.998266)
		(end 235.071412 -361.61218)
		(width 0.254)
		(layer "In5.Cu")
		(net "P12V_HSC_SENSE1_N")
	)
	(segment
		(start 240.15319 -356.873048)
		(end 240.15319 -356.301548)
		(width 0.254)
		(layer "In5.Cu")
		(net "P12V_HSC_SENSE1_N")
	)
	(segment
		(start 243.485924 -356.120192)
		(end 243.485924 -357.96093)
		(width 0.254)
		(layer "In5.Cu")
		(net "P12V_HSC_SENSE1_N")
	)
	(segment
		(start 243.068856 -355.703124)
		(end 243.485924 -356.120192)
		(width 0.254)
		(layer "In5.Cu")
		(net "P12V_HSC_SENSE1_N")
	)
	(segment
		(start 237.850934 -378.304806)
		(end 238.168434 -377.987306)
		(width 0.254)
		(layer "In5.Cu")
		(net "P12V_HSC_SENSE1_N")
	)
	(segment
		(start 234.155234 -375.980706)
		(end 236.479334 -378.304806)
		(width 0.254)
		(layer "In5.Cu")
		(net "P12V_HSC_SENSE1_N")
	)
	(segment
		(start 234.155234 -370.725954)
		(end 234.155234 -375.980706)
		(width 0.254)
		(layer "In5.Cu")
		(net "P12V_HSC_SENSE1_N")
	)
	(segment
		(start 235.071412 -369.809776)
		(end 234.155234 -370.725954)
		(width 0.254)
		(layer "In5.Cu")
		(net "P12V_HSC_SENSE1_N")
	)
	(segment
		(start 235.071412 -361.61218)
		(end 235.071412 -369.809776)
		(width 0.254)
		(layer "In5.Cu")
		(net "P12V_HSC_SENSE1_N")
	)
	(segment
		(start 240.751614 -355.703124)
		(end 243.068856 -355.703124)
		(width 0.254)
		(layer "In5.Cu")
		(net "P12V_HSC_SENSE1_N")
	)
	(segment
		(start 239.83569 -357.190548)
		(end 240.15319 -356.873048)
		(width 0.254)
		(layer "In5.Cu")
		(net "P12V_HSC_SENSE1_N")
	)
	(segment
		(start 236.479334 -378.304806)
		(end 237.850934 -378.304806)
		(width 0.254)
		(layer "In5.Cu")
		(net "P12V_HSC_SENSE1_N")
	)
	(segment
		(start 240.15319 -356.301548)
		(end 240.751614 -355.703124)
		(width 0.254)
		(layer "In5.Cu")
		(net "P12V_HSC_SENSE1_N")
	)
	(segment
		(start 242.448588 -358.998266)
		(end 237.685326 -358.998266)
		(width 0.254)
		(layer "In5.Cu")
		(net "P12V_HSC_SENSE1_N")
	)
	(segment
		(start 247.018048 -353.900232)
		(end 248.955306 -353.900232)
		(width 0.13208)
		(layer "F.Cu")
		(net "MB0_P12V_STBY_PWRGD")
	)
	(via
		(at 250.0884 -352.2472)
		(size 0.6604)
		(drill 0.3302)
		(layers "F.Cu" "B.Cu")
		(net "MB0_P12V_STBY_PWRGD")
	)
	(via
		(at 248.955306 -353.900232)
		(size 0.508)
		(drill 0.254)
		(layers "F.Cu" "B.Cu")
		(net "MB0_P12V_STBY_PWRGD")
	)
	(segment
		(start 250.0884 -352.2472)
		(end 251.21235 -352.2472)
		(width 0.13208)
		(layer "B.Cu")
		(net "MB0_P12V_STBY_PWRGD")
	)
	(segment
		(start 248.955306 -353.900232)
		(end 248.197116 -353.142042)
		(width 0.13208)
		(layer "B.Cu")
		(net "MB0_P12V_STBY_PWRGD")
	)
	(segment
		(start 249.246136 -351.404936)
		(end 250.0884 -352.2472)
		(width 0.13208)
		(layer "B.Cu")
		(net "MB0_P12V_STBY_PWRGD")
	)
	(segment
		(start 248.197116 -351.662238)
		(end 248.454418 -351.404936)
		(width 0.13208)
		(layer "B.Cu")
		(net "MB0_P12V_STBY_PWRGD")
	)
	(segment
		(start 248.197116 -353.142042)
		(end 248.197116 -351.662238)
		(width 0.13208)
		(layer "B.Cu")
		(net "MB0_P12V_STBY_PWRGD")
	)
	(segment
		(start 248.454418 -351.404936)
		(end 249.246136 -351.404936)
		(width 0.13208)
		(layer "B.Cu")
		(net "MB0_P12V_STBY_PWRGD")
	)
	(segment
		(start 251.21235 -352.2472)
		(end 251.61875 -351.8408)
		(width 0.13208)
		(layer "B.Cu")
		(net "MB0_P12V_STBY_PWRGD")
	)
	(segment
		(start 243.577872 -351.40011)
		(end 241.950494 -351.40011)
		(width 0.254)
		(layer "F.Cu")
		(net "P12V_HSC_ADC_P")
	)
	(via
		(at 238.647986 -356.165658)
		(size 0.508)
		(drill 0.254)
		(layers "F.Cu" "B.Cu")
		(net "P12V_HSC_ADC_P")
	)
	(via
		(at 236.524546 -348.475554)
		(size 0.762)
		(drill 0.254)
		(layers "F.Cu" "B.Cu")
		(net "P12V_HSC_ADC_P")
	)
	(via
		(at 241.950494 -351.40011)
		(size 0.508)
		(drill 0.254)
		(layers "F.Cu" "B.Cu")
		(net "P12V_HSC_ADC_P")
	)
	(segment
		(start 238.032036 -356.165658)
		(end 238.647986 -356.165658)
		(width 0.254)
		(layer "B.Cu")
		(net "P12V_HSC_ADC_P")
	)
	(segment
		(start 236.524546 -348.475554)
		(end 237.209584 -348.475554)
		(width 0.254)
		(layer "B.Cu")
		(net "P12V_HSC_ADC_P")
	)
	(segment
		(start 238.032036 -357.130858)
		(end 238.032036 -356.165658)
		(width 0.254)
		(layer "B.Cu")
		(net "P12V_HSC_ADC_P")
	)
	(segment
		(start 236.783626 -348.734634)
		(end 238.948468 -348.734634)
		(width 0.254)
		(layer "In5.Cu")
		(net "P12V_HSC_ADC_P")
	)
	(segment
		(start 236.524546 -348.475554)
		(end 236.783626 -348.734634)
		(width 0.254)
		(layer "In5.Cu")
		(net "P12V_HSC_ADC_P")
	)
	(segment
		(start 239.967262 -355.36378)
		(end 239.457484 -355.873558)
		(width 0.254)
		(layer "In5.Cu")
		(net "P12V_HSC_ADC_P")
	)
	(segment
		(start 238.948468 -348.734634)
		(end 239.967262 -349.753428)
		(width 0.254)
		(layer "In5.Cu")
		(net "P12V_HSC_ADC_P")
	)
	(segment
		(start 238.940086 -355.873558)
		(end 238.647986 -356.165658)
		(width 0.254)
		(layer "In5.Cu")
		(net "P12V_HSC_ADC_P")
	)
	(segment
		(start 239.457484 -355.873558)
		(end 238.940086 -355.873558)
		(width 0.254)
		(layer "In5.Cu")
		(net "P12V_HSC_ADC_P")
	)
	(segment
		(start 239.967262 -349.753428)
		(end 239.967262 -355.36378)
		(width 0.254)
		(layer "In5.Cu")
		(net "P12V_HSC_ADC_P")
	)
	(segment
		(start 241.950494 -351.40011)
		(end 242.271804 -351.697544)
		(width 0.254)
		(layer "In7.Cu")
		(net "P12V_HSC_ADC_P")
	)
	(segment
		(start 242.798092 -351.676462)
		(end 243.485416 -352.363786)
		(width 0.254)
		(layer "In7.Cu")
		(net "P12V_HSC_ADC_P")
	)
	(segment
		(start 238.940086 -355.873558)
		(end 238.647986 -356.165658)
		(width 0.254)
		(layer "In7.Cu")
		(net "P12V_HSC_ADC_P")
	)
	(segment
		(start 243.485416 -352.363786)
		(end 243.485416 -354.810314)
		(width 0.254)
		(layer "In7.Cu")
		(net "P12V_HSC_ADC_P")
	)
	(segment
		(start 242.271804 -351.697544)
		(end 242.272566 -351.69729)
		(width 0.254)
		(layer "In7.Cu")
		(net "P12V_HSC_ADC_P")
	)
	(segment
		(start 242.422172 -355.873558)
		(end 238.940086 -355.873558)
		(width 0.254)
		(layer "In7.Cu")
		(net "P12V_HSC_ADC_P")
	)
	(segment
		(start 242.631214 -351.683066)
		(end 242.798092 -351.676462)
		(width 0.254)
		(layer "In7.Cu")
		(net "P12V_HSC_ADC_P")
	)
	(segment
		(start 242.272566 -351.69729)
		(end 242.631214 -351.683066)
		(width 0.254)
		(layer "In7.Cu")
		(net "P12V_HSC_ADC_P")
	)
	(segment
		(start 243.485416 -354.810314)
		(end 242.422172 -355.873558)
		(width 0.254)
		(layer "In7.Cu")
		(net "P12V_HSC_ADC_P")
	)
	(segment
		(start 260.661912 -347.103192)
		(end 258.891278 -347.103192)
		(width 0.13208)
		(layer "F.Cu")
		(net "HSC_CSOUT")
	)
	(segment
		(start 247.018048 -352.89998)
		(end 248.943368 -352.89998)
		(width 0.13208)
		(layer "F.Cu")
		(net "HSC_CSOUT")
	)
	(segment
		(start 256.772918 -347.68409)
		(end 255.9939 -347.68409)
		(width 0.13208)
		(layer "F.Cu")
		(net "HSC_CSOUT")
	)
	(segment
		(start 257.34264 -335.472024)
		(end 258.401566 -334.413098)
		(width 0.13208)
		(layer "F.Cu")
		(net "HSC_CSOUT")
	)
	(segment
		(start 261.052818 -346.712286)
		(end 260.661912 -347.103192)
		(width 0.13208)
		(layer "F.Cu")
		(net "HSC_CSOUT")
	)
	(segment
		(start 263.097264 -345.76893)
		(end 263.095232 -345.766898)
		(width 0.13208)
		(layer "F.Cu")
		(net "HSC_CSOUT")
	)
	(segment
		(start 263.097264 -346.712286)
		(end 261.052818 -346.712286)
		(width 0.13208)
		(layer "F.Cu")
		(net "HSC_CSOUT")
	)
	(segment
		(start 256.772918 -347.68409)
		(end 257.353816 -347.103192)
		(width 0.13208)
		(layer "F.Cu")
		(net "HSC_CSOUT")
	)
	(segment
		(start 257.353816 -347.103192)
		(end 258.891278 -347.103192)
		(width 0.13208)
		(layer "F.Cu")
		(net "HSC_CSOUT")
	)
	(segment
		(start 263.097264 -346.712286)
		(end 263.097264 -345.76893)
		(width 0.13208)
		(layer "F.Cu")
		(net "HSC_CSOUT")
	)
	(segment
		(start 251.587254 -335.472024)
		(end 257.34264 -335.472024)
		(width 0.13208)
		(layer "F.Cu")
		(net "HSC_CSOUT")
	)
	(via
		(at 251.587254 -335.472024)
		(size 0.508)
		(drill 0.254)
		(layers "F.Cu" "B.Cu")
		(net "HSC_CSOUT")
	)
	(via
		(at 248.943368 -352.89998)
		(size 0.508)
		(drill 0.254)
		(layers "F.Cu" "B.Cu")
		(net "HSC_CSOUT")
	)
	(via
		(at 253.66599 -353.03841)
		(size 0.6604)
		(drill 0.3302)
		(layers "F.Cu" "B.Cu")
		(net "HSC_CSOUT")
	)
	(via
		(at 255.9939 -347.68409)
		(size 0.508)
		(drill 0.254)
		(layers "F.Cu" "B.Cu")
		(net "HSC_CSOUT")
	)
	(segment
		(start 252.12675 -353.6188)
		(end 251.61875 -354.1268)
		(width 0.13208)
		(layer "B.Cu")
		(net "HSC_CSOUT")
	)
	(segment
		(start 250.170188 -354.1268)
		(end 248.943368 -352.89998)
		(width 0.13208)
		(layer "B.Cu")
		(net "HSC_CSOUT")
	)
	(segment
		(start 255.53416 -351.17024)
		(end 253.66599 -353.03841)
		(width 0.13208)
		(layer "B.Cu")
		(net "HSC_CSOUT")
	)
	(segment
		(start 253.0856 -353.6188)
		(end 252.12675 -353.6188)
		(width 0.13208)
		(layer "B.Cu")
		(net "HSC_CSOUT")
	)
	(segment
		(start 251.61875 -354.1268)
		(end 250.170188 -354.1268)
		(width 0.13208)
		(layer "B.Cu")
		(net "HSC_CSOUT")
	)
	(segment
		(start 255.53416 -348.14383)
		(end 255.53416 -351.17024)
		(width 0.13208)
		(layer "B.Cu")
		(net "HSC_CSOUT")
	)
	(segment
		(start 253.66599 -353.03841)
		(end 253.0856 -353.6188)
		(width 0.13208)
		(layer "B.Cu")
		(net "HSC_CSOUT")
	)
	(segment
		(start 255.9939 -347.68409)
		(end 255.53416 -348.14383)
		(width 0.13208)
		(layer "B.Cu")
		(net "HSC_CSOUT")
	)
	(segment
		(start 251.017024 -342.707214)
		(end 251.017024 -336.05089)
		(width 0.15494)
		(layer "In5.Cu")
		(net "HSC_CSOUT")
	)
	(segment
		(start 251.587254 -335.48066)
		(end 251.587254 -335.472024)
		(width 0.15494)
		(layer "In5.Cu")
		(net "HSC_CSOUT")
	)
	(segment
		(start 251.017024 -336.05089)
		(end 251.587254 -335.48066)
		(width 0.15494)
		(layer "In5.Cu")
		(net "HSC_CSOUT")
	)
	(segment
		(start 255.9939 -347.68409)
		(end 251.017024 -342.707214)
		(width 0.15494)
		(layer "In5.Cu")
		(net "HSC_CSOUT")
	)
	(segment
		(start 336.1436 -266.2682)
		(end 337.5914 -264.8204)
		(width 0.13208)
		(layer "F.Cu")
		(net "SMB_SML1_PMBUS_HSC_SDA")
	)
	(segment
		(start 267.463524 -329.465178)
		(end 330.858622 -329.465178)
		(width 0.13208)
		(layer "F.Cu")
		(net "SMB_SML1_PMBUS_HSC_SDA")
	)
	(segment
		(start 332.3336 -266.2682)
		(end 336.1436 -266.2682)
		(width 0.13208)
		(layer "F.Cu")
		(net "SMB_SML1_PMBUS_HSC_SDA")
	)
	(segment
		(start 247.018048 -349.899986)
		(end 248.971562 -349.899986)
		(width 0.13208)
		(layer "F.Cu")
		(net "SMB_SML1_PMBUS_HSC_SDA")
	)
	(segment
		(start 327.584816 -280.059384)
		(end 331.724 -275.9202)
		(width 0.13208)
		(layer "F.Cu")
		(net "SMB_SML1_PMBUS_HSC_SDA")
	)
	(segment
		(start 331.0382 -317.0936)
		(end 327.584816 -313.640216)
		(width 0.13208)
		(layer "F.Cu")
		(net "SMB_SML1_PMBUS_HSC_SDA")
	)
	(segment
		(start 331.724 -275.9202)
		(end 331.724 -266.8778)
		(width 0.13208)
		(layer "F.Cu")
		(net "SMB_SML1_PMBUS_HSC_SDA")
	)
	(segment
		(start 331.724 -266.8778)
		(end 332.3336 -266.2682)
		(width 0.13208)
		(layer "F.Cu")
		(net "SMB_SML1_PMBUS_HSC_SDA")
	)
	(segment
		(start 327.584816 -313.640216)
		(end 327.584816 -280.059384)
		(width 0.13208)
		(layer "F.Cu")
		(net "SMB_SML1_PMBUS_HSC_SDA")
	)
	(segment
		(start 337.5914 -264.8204)
		(end 337.5914 -259.5118)
		(width 0.13208)
		(layer "F.Cu")
		(net "SMB_SML1_PMBUS_HSC_SDA")
	)
	(segment
		(start 331.0382 -325.509382)
		(end 331.0382 -317.0936)
		(width 0.13208)
		(layer "F.Cu")
		(net "SMB_SML1_PMBUS_HSC_SDA")
	)
	(segment
		(start 351.087182 -251.6886)
		(end 351.323148 -251.924566)
		(width 0.13208)
		(layer "F.Cu")
		(net "SMB_SML1_PMBUS_HSC_SDA")
	)
	(segment
		(start 266.700508 -328.702162)
		(end 267.463524 -329.465178)
		(width 0.13208)
		(layer "F.Cu")
		(net "SMB_SML1_PMBUS_HSC_SDA")
	)
	(segment
		(start 330.858622 -329.465178)
		(end 332.327758 -327.996042)
		(width 0.13208)
		(layer "F.Cu")
		(net "SMB_SML1_PMBUS_HSC_SDA")
	)
	(segment
		(start 332.327758 -326.79894)
		(end 331.0382 -325.509382)
		(width 0.13208)
		(layer "F.Cu")
		(net "SMB_SML1_PMBUS_HSC_SDA")
	)
	(segment
		(start 337.5914 -259.5118)
		(end 345.4146 -251.6886)
		(width 0.13208)
		(layer "F.Cu")
		(net "SMB_SML1_PMBUS_HSC_SDA")
	)
	(segment
		(start 345.4146 -251.6886)
		(end 351.087182 -251.6886)
		(width 0.13208)
		(layer "F.Cu")
		(net "SMB_SML1_PMBUS_HSC_SDA")
	)
	(segment
		(start 332.327758 -327.996042)
		(end 332.327758 -326.79894)
		(width 0.13208)
		(layer "F.Cu")
		(net "SMB_SML1_PMBUS_HSC_SDA")
	)
	(segment
		(start 266.700508 -328.493882)
		(end 266.700508 -328.702162)
		(width 0.13208)
		(layer "F.Cu")
		(net "SMB_SML1_PMBUS_HSC_SDA")
	)
	(via
		(at 253.817882 -349.8596)
		(size 0.508)
		(drill 0.254)
		(layers "F.Cu" "B.Cu")
		(net "SMB_SML1_PMBUS_HSC_SDA")
	)
	(via
		(at 266.700508 -328.493882)
		(size 0.508)
		(drill 0.254)
		(layers "F.Cu" "B.Cu")
		(net "SMB_SML1_PMBUS_HSC_SDA")
	)
	(via
		(at 351.323148 -251.924566)
		(size 0.508)
		(drill 0.254)
		(layers "F.Cu" "B.Cu")
		(net "SMB_SML1_PMBUS_HSC_SDA")
	)
	(via
		(at 248.971562 -349.899986)
		(size 0.508)
		(drill 0.254)
		(layers "F.Cu" "B.Cu")
		(net "SMB_SML1_PMBUS_HSC_SDA")
	)
	(segment
		(start 253.777496 -349.899986)
		(end 253.817882 -349.8596)
		(width 0.13208)
		(layer "B.Cu")
		(net "SMB_SML1_PMBUS_HSC_SDA")
	)
	(segment
		(start 248.971562 -349.899986)
		(end 253.777496 -349.899986)
		(width 0.13208)
		(layer "B.Cu")
		(net "SMB_SML1_PMBUS_HSC_SDA")
	)
	(segment
		(start 351.323148 -251.924566)
		(end 353.302316 -249.945398)
		(width 0.13208)
		(layer "B.Cu")
		(net "SMB_SML1_PMBUS_HSC_SDA")
	)
	(segment
		(start 353.302316 -249.945398)
		(end 354.188268 -249.945398)
		(width 0.13208)
		(layer "B.Cu")
		(net "SMB_SML1_PMBUS_HSC_SDA")
	)
	(segment
		(start 254.165354 -346.137738)
		(end 254.294132 -346.266516)
		(width 0.15494)
		(layer "In15.Cu")
		(net "SMB_SML1_PMBUS_HSC_SDA")
	)
	(segment
		(start 253.376684 -346.137738)
		(end 254.165354 -346.137738)
		(width 0.15494)
		(layer "In15.Cu")
		(net "SMB_SML1_PMBUS_HSC_SDA")
	)
	(segment
		(start 254.294132 -336.802984)
		(end 254.294132 -344.6907)
		(width 0.15494)
		(layer "In15.Cu")
		(net "SMB_SML1_PMBUS_HSC_SDA")
	)
	(segment
		(start 253.376684 -345.698318)
		(end 253.247906 -345.827096)
		(width 0.15494)
		(layer "In15.Cu")
		(net "SMB_SML1_PMBUS_HSC_SDA")
	)
	(segment
		(start 253.376684 -344.819478)
		(end 253.247906 -344.948256)
		(width 0.15494)
		(layer "In15.Cu")
		(net "SMB_SML1_PMBUS_HSC_SDA")
	)
	(segment
		(start 254.294132 -344.6907)
		(end 254.165354 -344.819478)
		(width 0.15494)
		(layer "In15.Cu")
		(net "SMB_SML1_PMBUS_HSC_SDA")
	)
	(segment
		(start 253.247906 -345.13012)
		(end 253.376684 -345.258898)
		(width 0.15494)
		(layer "In15.Cu")
		(net "SMB_SML1_PMBUS_HSC_SDA")
	)
	(segment
		(start 254.165354 -345.258898)
		(end 254.294132 -345.387676)
		(width 0.15494)
		(layer "In15.Cu")
		(net "SMB_SML1_PMBUS_HSC_SDA")
	)
	(segment
		(start 266.700508 -328.493882)
		(end 262.603234 -328.493882)
		(width 0.15494)
		(layer "In15.Cu")
		(net "SMB_SML1_PMBUS_HSC_SDA")
	)
	(segment
		(start 254.165354 -345.698318)
		(end 253.376684 -345.698318)
		(width 0.15494)
		(layer "In15.Cu")
		(net "SMB_SML1_PMBUS_HSC_SDA")
	)
	(segment
		(start 254.165354 -344.819478)
		(end 253.376684 -344.819478)
		(width 0.15494)
		(layer "In15.Cu")
		(net "SMB_SML1_PMBUS_HSC_SDA")
	)
	(segment
		(start 253.247906 -344.948256)
		(end 253.247906 -345.13012)
		(width 0.15494)
		(layer "In15.Cu")
		(net "SMB_SML1_PMBUS_HSC_SDA")
	)
	(segment
		(start 254.294132 -346.266516)
		(end 254.294132 -349.38335)
		(width 0.15494)
		(layer "In15.Cu")
		(net "SMB_SML1_PMBUS_HSC_SDA")
	)
	(segment
		(start 254.294132 -345.56954)
		(end 254.165354 -345.698318)
		(width 0.15494)
		(layer "In15.Cu")
		(net "SMB_SML1_PMBUS_HSC_SDA")
	)
	(segment
		(start 253.247906 -346.00896)
		(end 253.376684 -346.137738)
		(width 0.15494)
		(layer "In15.Cu")
		(net "SMB_SML1_PMBUS_HSC_SDA")
	)
	(segment
		(start 253.376684 -345.258898)
		(end 254.165354 -345.258898)
		(width 0.15494)
		(layer "In15.Cu")
		(net "SMB_SML1_PMBUS_HSC_SDA")
	)
	(segment
		(start 253.247906 -345.827096)
		(end 253.247906 -346.00896)
		(width 0.15494)
		(layer "In15.Cu")
		(net "SMB_SML1_PMBUS_HSC_SDA")
	)
	(segment
		(start 254.294132 -345.387676)
		(end 254.294132 -345.56954)
		(width 0.15494)
		(layer "In15.Cu")
		(net "SMB_SML1_PMBUS_HSC_SDA")
	)
	(segment
		(start 254.294132 -349.38335)
		(end 253.817882 -349.8596)
		(width 0.15494)
		(layer "In15.Cu")
		(net "SMB_SML1_PMBUS_HSC_SDA")
	)
	(segment
		(start 262.603234 -328.493882)
		(end 254.294132 -336.802984)
		(width 0.15494)
		(layer "In15.Cu")
		(net "SMB_SML1_PMBUS_HSC_SDA")
	)
	(via
		(at 241.979704 -371.865906)
		(size 0.508)
		(drill 0.254)
		(layers "F.Cu" "B.Cu")
		(net "P12V_STBY_R1")
	)
	(via
		(at 236.332014 -371.865906)
		(size 0.508)
		(drill 0.254)
		(layers "F.Cu" "B.Cu")
		(net "P12V_STBY_R1")
	)
	(via
		(at 236.332014 -372.627906)
		(size 0.508)
		(drill 0.254)
		(layers "F.Cu" "B.Cu")
		(net "P12V_STBY_R1")
	)
	(via
		(at 241.979704 -370.341906)
		(size 0.508)
		(drill 0.254)
		(layers "F.Cu" "B.Cu")
		(net "P12V_STBY_R1")
	)
	(via
		(at 236.332014 -369.579906)
		(size 0.508)
		(drill 0.254)
		(layers "F.Cu" "B.Cu")
		(net "P12V_STBY_R1")
	)
	(via
		(at 241.979704 -369.579906)
		(size 0.508)
		(drill 0.254)
		(layers "F.Cu" "B.Cu")
		(net "P12V_STBY_R1")
	)
	(via
		(at 241.979704 -371.103906)
		(size 0.508)
		(drill 0.254)
		(layers "F.Cu" "B.Cu")
		(net "P12V_STBY_R1")
	)
	(via
		(at 236.332014 -370.341906)
		(size 0.508)
		(drill 0.254)
		(layers "F.Cu" "B.Cu")
		(net "P12V_STBY_R1")
	)
	(via
		(at 237.351824 -375.779284)
		(size 0.6604)
		(drill 0.3302)
		(layers "F.Cu" "B.Cu")
		(net "P12V_STBY_R1")
	)
	(via
		(at 241.979704 -372.627906)
		(size 0.508)
		(drill 0.254)
		(layers "F.Cu" "B.Cu")
		(net "P12V_STBY_R1")
	)
	(via
		(at 236.332014 -371.103906)
		(size 0.508)
		(drill 0.254)
		(layers "F.Cu" "B.Cu")
		(net "P12V_STBY_R1")
	)
	(segment
		(start 248.279412 -348.899988)
		(end 247.018048 -348.899988)
		(width 0.13208)
		(layer "F.Cu")
		(net "IRQ_SML1_PMBUS_ALERT_N")
	)
	(segment
		(start 250.303792 -349.311214)
		(end 249.417078 -348.4245)
		(width 0.13208)
		(layer "F.Cu")
		(net "IRQ_SML1_PMBUS_ALERT_N")
	)
	(segment
		(start 248.7549 -348.4245)
		(end 248.279412 -348.899988)
		(width 0.13208)
		(layer "F.Cu")
		(net "IRQ_SML1_PMBUS_ALERT_N")
	)
	(segment
		(start 250.303792 -355.160834)
		(end 250.303792 -349.311214)
		(width 0.13208)
		(layer "F.Cu")
		(net "IRQ_SML1_PMBUS_ALERT_N")
	)
	(segment
		(start 249.417078 -348.4245)
		(end 248.7549 -348.4245)
		(width 0.13208)
		(layer "F.Cu")
		(net "IRQ_SML1_PMBUS_ALERT_N")
	)
	(via
		(at 250.303792 -355.160834)
		(size 0.508)
		(drill 0.254)
		(layers "F.Cu" "B.Cu")
		(net "IRQ_SML1_PMBUS_ALERT_N")
	)
	(segment
		(start 250.303792 -355.160834)
		(end 251.611384 -355.160834)
		(width 0.13208)
		(layer "B.Cu")
		(net "IRQ_SML1_PMBUS_ALERT_N")
	)
	(segment
		(start 248.94159 -377.616974)
		(end 248.94159 -377.820174)
		(width 0.254)
		(layer "F.Cu")
		(net "P12V_HSC_SENSE2_R1_N")
	)
	(segment
		(start 248.94159 -377.820174)
		(end 249.489214 -378.367798)
		(width 0.254)
		(layer "F.Cu")
		(net "P12V_HSC_SENSE2_R1_N")
	)
	(via
		(at 236.514386 -352.304858)
		(size 0.508)
		(drill 0.254)
		(layers "F.Cu" "B.Cu")
		(net "P12V_HSC_SENSE2_R1_N")
	)
	(via
		(at 236.514386 -354.235258)
		(size 0.508)
		(drill 0.254)
		(layers "F.Cu" "B.Cu")
		(net "P12V_HSC_SENSE2_R1_N")
	)
	(via
		(at 249.489214 -378.367798)
		(size 0.508)
		(drill 0.254)
		(layers "F.Cu" "B.Cu")
		(net "P12V_HSC_SENSE2_R1_N")
	)
	(segment
		(start 235.943902 -352.307906)
		(end 235.94695 -352.304858)
		(width 0.254)
		(layer "B.Cu")
		(net "P12V_HSC_SENSE2_R1_N")
	)
	(segment
		(start 237.231936 -354.235258)
		(end 236.514386 -354.235258)
		(width 0.254)
		(layer "B.Cu")
		(net "P12V_HSC_SENSE2_R1_N")
	)
	(segment
		(start 235.94695 -352.304858)
		(end 236.514386 -352.304858)
		(width 0.254)
		(layer "B.Cu")
		(net "P12V_HSC_SENSE2_R1_N")
	)
	(segment
		(start 235.393484 -352.307906)
		(end 235.943902 -352.307906)
		(width 0.254)
		(layer "B.Cu")
		(net "P12V_HSC_SENSE2_R1_N")
	)
	(segment
		(start 236.514386 -352.304858)
		(end 235.928916 -352.890328)
		(width 0.254)
		(layer "In5.Cu")
		(net "P12V_HSC_SENSE2_R1_N")
	)
	(segment
		(start 235.928916 -353.649788)
		(end 236.514386 -354.235258)
		(width 0.254)
		(layer "In5.Cu")
		(net "P12V_HSC_SENSE2_R1_N")
	)
	(segment
		(start 235.928916 -352.890328)
		(end 235.928916 -353.649788)
		(width 0.254)
		(layer "In5.Cu")
		(net "P12V_HSC_SENSE2_R1_N")
	)
	(segment
		(start 235.083858 -361.450128)
		(end 238.007398 -358.526588)
		(width 0.254)
		(layer "In7.Cu")
		(net "P12V_HSC_SENSE2_R1_N")
	)
	(segment
		(start 238.007398 -358.526588)
		(end 238.007398 -355.72827)
		(width 0.254)
		(layer "In7.Cu")
		(net "P12V_HSC_SENSE2_R1_N")
	)
	(segment
		(start 235.083858 -369.805458)
		(end 235.083858 -361.450128)
		(width 0.254)
		(layer "In7.Cu")
		(net "P12V_HSC_SENSE2_R1_N")
	)
	(segment
		(start 249.291602 -377.603004)
		(end 248.722896 -377.034298)
		(width 0.254)
		(layer "In7.Cu")
		(net "P12V_HSC_SENSE2_R1_N")
	)
	(segment
		(start 235.535724 -377.034298)
		(end 234.147106 -375.64568)
		(width 0.254)
		(layer "In7.Cu")
		(net "P12V_HSC_SENSE2_R1_N")
	)
	(segment
		(start 248.722896 -377.034298)
		(end 235.535724 -377.034298)
		(width 0.254)
		(layer "In7.Cu")
		(net "P12V_HSC_SENSE2_R1_N")
	)
	(segment
		(start 234.147106 -370.74221)
		(end 235.083858 -369.805458)
		(width 0.254)
		(layer "In7.Cu")
		(net "P12V_HSC_SENSE2_R1_N")
	)
	(segment
		(start 234.147106 -375.64568)
		(end 234.147106 -370.74221)
		(width 0.254)
		(layer "In7.Cu")
		(net "P12V_HSC_SENSE2_R1_N")
	)
	(segment
		(start 249.489214 -378.367798)
		(end 249.291602 -378.170186)
		(width 0.254)
		(layer "In7.Cu")
		(net "P12V_HSC_SENSE2_R1_N")
	)
	(segment
		(start 238.007398 -355.72827)
		(end 236.514386 -354.235258)
		(width 0.254)
		(layer "In7.Cu")
		(net "P12V_HSC_SENSE2_R1_N")
	)
	(segment
		(start 249.291602 -378.170186)
		(end 249.291602 -377.603004)
		(width 0.254)
		(layer "In7.Cu")
		(net "P12V_HSC_SENSE2_R1_N")
	)
	(segment
		(start 240.53419 -356.483412)
		(end 240.53419 -356.873048)
		(width 0.254)
		(layer "F.Cu")
		(net "P12V_HSC_SENSE1_P")
	)
	(segment
		(start 240.920778 -356.096824)
		(end 240.53419 -356.483412)
		(width 0.254)
		(layer "F.Cu")
		(net "P12V_HSC_SENSE1_P")
	)
	(segment
		(start 239.08766 -378.685806)
		(end 238.485934 -378.685806)
		(width 0.254)
		(layer "F.Cu")
		(net "P12V_HSC_SENSE1_P")
	)
	(segment
		(start 242.198652 -356.096824)
		(end 240.920778 -356.096824)
		(width 0.254)
		(layer "F.Cu")
		(net "P12V_HSC_SENSE1_P")
	)
	(segment
		(start 240.53419 -356.873048)
		(end 240.85169 -357.190548)
		(width 0.254)
		(layer "F.Cu")
		(net "P12V_HSC_SENSE1_P")
	)
	(segment
		(start 239.416844 -379.01499)
		(end 239.08766 -378.685806)
		(width 0.254)
		(layer "F.Cu")
		(net "P12V_HSC_SENSE1_P")
	)
	(segment
		(start 239.416844 -380.563628)
		(end 239.416844 -379.01499)
		(width 0.254)
		(layer "F.Cu")
		(net "P12V_HSC_SENSE1_P")
	)
	(segment
		(start 242.503198 -356.4001)
		(end 242.198652 -356.096824)
		(width 0.254)
		(layer "F.Cu")
		(net "P12V_HSC_SENSE1_P")
	)
	(segment
		(start 238.485934 -378.685806)
		(end 238.168434 -379.003306)
		(width 0.254)
		(layer "F.Cu")
		(net "P12V_HSC_SENSE1_P")
	)
	(segment
		(start 243.577872 -356.4001)
		(end 242.503198 -356.4001)
		(width 0.254)
		(layer "F.Cu")
		(net "P12V_HSC_SENSE1_P")
	)
	(via
		(at 240.85169 -357.190548)
		(size 0.508)
		(drill 0.254)
		(layers "F.Cu" "B.Cu")
		(net "P12V_HSC_SENSE1_P")
	)
	(via
		(at 238.168434 -379.003306)
		(size 0.508)
		(drill 0.254)
		(layers "F.Cu" "B.Cu")
		(net "P12V_HSC_SENSE1_P")
	)
	(segment
		(start 238.009684 -348.475554)
		(end 238.257588 -348.723458)
		(width 0.254)
		(layer "B.Cu")
		(net "P12V_HSC_SENSE1_P")
	)
	(segment
		(start 239.456468 -349.25635)
		(end 239.456468 -353.894644)
		(width 0.254)
		(layer "B.Cu")
		(net "P12V_HSC_SENSE1_P")
	)
	(segment
		(start 238.923576 -348.723458)
		(end 239.456468 -349.25635)
		(width 0.254)
		(layer "B.Cu")
		(net "P12V_HSC_SENSE1_P")
	)
	(segment
		(start 239.456468 -353.894644)
		(end 240.012982 -354.451158)
		(width 0.254)
		(layer "B.Cu")
		(net "P12V_HSC_SENSE1_P")
	)
	(segment
		(start 240.53419 -355.924866)
		(end 240.53419 -356.873048)
		(width 0.254)
		(layer "B.Cu")
		(net "P12V_HSC_SENSE1_P")
	)
	(segment
		(start 240.012982 -355.403658)
		(end 240.53419 -355.924866)
		(width 0.254)
		(layer "B.Cu")
		(net "P12V_HSC_SENSE1_P")
	)
	(segment
		(start 240.53419 -356.873048)
		(end 240.85169 -357.190548)
		(width 0.254)
		(layer "B.Cu")
		(net "P12V_HSC_SENSE1_P")
	)
	(segment
		(start 238.257588 -348.723458)
		(end 238.923576 -348.723458)
		(width 0.254)
		(layer "B.Cu")
		(net "P12V_HSC_SENSE1_P")
	)
	(segment
		(start 240.012982 -354.451158)
		(end 240.012982 -355.403658)
		(width 0.254)
		(layer "B.Cu")
		(net "P12V_HSC_SENSE1_P")
	)
	(segment
		(start 237.850934 -378.685806)
		(end 236.321346 -378.685806)
		(width 0.254)
		(layer "In5.Cu")
		(net "P12V_HSC_SENSE1_P")
	)
	(segment
		(start 237.527338 -358.617266)
		(end 242.2906 -358.617266)
		(width 0.254)
		(layer "In5.Cu")
		(net "P12V_HSC_SENSE1_P")
	)
	(segment
		(start 233.774234 -376.138694)
		(end 233.774234 -370.567966)
		(width 0.254)
		(layer "In5.Cu")
		(net "P12V_HSC_SENSE1_P")
	)
	(segment
		(start 240.53419 -356.873048)
		(end 240.85169 -357.190548)
		(width 0.254)
		(layer "In5.Cu")
		(net "P12V_HSC_SENSE1_P")
	)
	(segment
		(start 240.53419 -356.459536)
		(end 240.53419 -356.873048)
		(width 0.254)
		(layer "In5.Cu")
		(net "P12V_HSC_SENSE1_P")
	)
	(segment
		(start 236.321346 -378.685806)
		(end 233.774234 -376.138694)
		(width 0.254)
		(layer "In5.Cu")
		(net "P12V_HSC_SENSE1_P")
	)
	(segment
		(start 238.168434 -379.003306)
		(end 237.850934 -378.685806)
		(width 0.254)
		(layer "In5.Cu")
		(net "P12V_HSC_SENSE1_P")
	)
	(segment
		(start 242.910868 -356.084124)
		(end 240.909602 -356.084124)
		(width 0.254)
		(layer "In5.Cu")
		(net "P12V_HSC_SENSE1_P")
	)
	(segment
		(start 243.104924 -357.802942)
		(end 243.104924 -356.27818)
		(width 0.254)
		(layer "In5.Cu")
		(net "P12V_HSC_SENSE1_P")
	)
	(segment
		(start 242.2906 -358.617266)
		(end 243.104924 -357.802942)
		(width 0.254)
		(layer "In5.Cu")
		(net "P12V_HSC_SENSE1_P")
	)
	(segment
		(start 234.690412 -369.651788)
		(end 234.690412 -361.454192)
		(width 0.254)
		(layer "In5.Cu")
		(net "P12V_HSC_SENSE1_P")
	)
	(segment
		(start 243.104924 -356.27818)
		(end 242.910868 -356.084124)
		(width 0.254)
		(layer "In5.Cu")
		(net "P12V_HSC_SENSE1_P")
	)
	(segment
		(start 240.909602 -356.084124)
		(end 240.53419 -356.459536)
		(width 0.254)
		(layer "In5.Cu")
		(net "P12V_HSC_SENSE1_P")
	)
	(segment
		(start 233.774234 -370.567966)
		(end 234.690412 -369.651788)
		(width 0.254)
		(layer "In5.Cu")
		(net "P12V_HSC_SENSE1_P")
	)
	(segment
		(start 234.690412 -361.454192)
		(end 237.527338 -358.617266)
		(width 0.254)
		(layer "In5.Cu")
		(net "P12V_HSC_SENSE1_P")
	)
	(segment
		(start 243.577872 -352.400108)
		(end 241.989864 -352.400108)
		(width 0.254)
		(layer "F.Cu")
		(net "P12V_HSC_ADC_N")
	)
	(via
		(at 236.508798 -349.473012)
		(size 0.508)
		(drill 0.254)
		(layers "F.Cu" "B.Cu")
		(net "P12V_HSC_ADC_N")
	)
	(via
		(at 241.989864 -352.400108)
		(size 0.508)
		(drill 0.254)
		(layers "F.Cu" "B.Cu")
		(net "P12V_HSC_ADC_N")
	)
	(via
		(at 238.647986 -355.200458)
		(size 0.762)
		(drill 0.254)
		(layers "F.Cu" "B.Cu")
		(net "P12V_HSC_ADC_N")
	)
	(segment
		(start 237.22838 -349.473012)
		(end 236.508798 -349.473012)
		(width 0.254)
		(layer "B.Cu")
		(net "P12V_HSC_ADC_N")
	)
	(segment
		(start 238.032036 -355.200458)
		(end 238.647986 -355.200458)
		(width 0.254)
		(layer "B.Cu")
		(net "P12V_HSC_ADC_N")
	)
	(segment
		(start 238.032036 -355.200458)
		(end 238.032036 -354.235258)
		(width 0.254)
		(layer "B.Cu")
		(net "P12V_HSC_ADC_N")
	)
	(segment
		(start 238.940086 -355.492558)
		(end 238.647986 -355.200458)
		(width 0.254)
		(layer "In5.Cu")
		(net "P12V_HSC_ADC_N")
	)
	(segment
		(start 239.586262 -349.911416)
		(end 239.586262 -355.205792)
		(width 0.254)
		(layer "In5.Cu")
		(net "P12V_HSC_ADC_N")
	)
	(segment
		(start 236.866176 -349.115634)
		(end 238.79048 -349.115634)
		(width 0.254)
		(layer "In5.Cu")
		(net "P12V_HSC_ADC_N")
	)
	(segment
		(start 236.508798 -349.473012)
		(end 236.866176 -349.115634)
		(width 0.254)
		(layer "In5.Cu")
		(net "P12V_HSC_ADC_N")
	)
	(segment
		(start 239.299496 -355.492558)
		(end 238.940086 -355.492558)
		(width 0.254)
		(layer "In5.Cu")
		(net "P12V_HSC_ADC_N")
	)
	(segment
		(start 239.586262 -355.205792)
		(end 239.299496 -355.492558)
		(width 0.254)
		(layer "In5.Cu")
		(net "P12V_HSC_ADC_N")
	)
	(segment
		(start 238.79048 -349.115634)
		(end 239.586262 -349.911416)
		(width 0.254)
		(layer "In5.Cu")
		(net "P12V_HSC_ADC_N")
	)
	(segment
		(start 238.647986 -355.200458)
		(end 238.940086 -355.492558)
		(width 0.254)
		(layer "In7.Cu")
		(net "P12V_HSC_ADC_N")
	)
	(segment
		(start 243.104416 -354.652326)
		(end 243.104416 -352.521774)
		(width 0.254)
		(layer "In7.Cu")
		(net "P12V_HSC_ADC_N")
	)
	(segment
		(start 238.940086 -355.492558)
		(end 242.264184 -355.492558)
		(width 0.254)
		(layer "In7.Cu")
		(net "P12V_HSC_ADC_N")
	)
	(segment
		(start 242.264184 -355.492558)
		(end 243.104416 -354.652326)
		(width 0.254)
		(layer "In7.Cu")
		(net "P12V_HSC_ADC_N")
	)
	(segment
		(start 242.287552 -352.078036)
		(end 241.989864 -352.400108)
		(width 0.254)
		(layer "In7.Cu")
		(net "P12V_HSC_ADC_N")
	)
	(segment
		(start 243.104416 -352.521774)
		(end 242.646454 -352.063812)
		(width 0.254)
		(layer "In7.Cu")
		(net "P12V_HSC_ADC_N")
	)
	(segment
		(start 242.646454 -352.063812)
		(end 242.287552 -352.078036)
		(width 0.254)
		(layer "In7.Cu")
		(net "P12V_HSC_ADC_N")
	)
	(segment
		(start 247.018048 -354.90023)
		(end 248.931938 -354.90023)
		(width 0.13208)
		(layer "F.Cu")
		(net "P12V_HSC_EN")
	)
	(via
		(at 248.931938 -354.90023)
		(size 0.508)
		(drill 0.254)
		(layers "F.Cu" "B.Cu")
		(net "P12V_HSC_EN")
	)
	(via
		(at 247.620028 -353.58832)
		(size 0.6604)
		(drill 0.3302)
		(layers "F.Cu" "B.Cu")
		(net "P12V_HSC_EN")
	)
	(segment
		(start 249.682 -349.4024)
		(end 248.3104 -349.4024)
		(width 0.13208)
		(layer "B.Cu")
		(net "P12V_HSC_EN")
	)
	(segment
		(start 251.61875 -348.8436)
		(end 250.2408 -348.8436)
		(width 0.13208)
		(layer "B.Cu")
		(net "P12V_HSC_EN")
	)
	(segment
		(start 250.2408 -348.8436)
		(end 249.682 -349.4024)
		(width 0.13208)
		(layer "B.Cu")
		(net "P12V_HSC_EN")
	)
	(segment
		(start 248.3104 -349.4024)
		(end 247.620028 -350.092772)
		(width 0.13208)
		(layer "B.Cu")
		(net "P12V_HSC_EN")
	)
	(segment
		(start 248.931938 -354.90023)
		(end 247.620028 -353.58832)
		(width 0.13208)
		(layer "B.Cu")
		(net "P12V_HSC_EN")
	)
	(segment
		(start 247.620028 -350.092772)
		(end 247.620028 -353.58832)
		(width 0.13208)
		(layer "B.Cu")
		(net "P12V_HSC_EN")
	)
	(segment
		(start 249.645932 -349.583756)
		(end 249.645932 -354.973382)
		(width 0.13208)
		(layer "F.Cu")
		(net "IRQ_HSC_FAULT_R_N")
	)
	(segment
		(start 248.962164 -348.899988)
		(end 249.645932 -349.583756)
		(width 0.13208)
		(layer "F.Cu")
		(net "IRQ_HSC_FAULT_R_N")
	)
	(segment
		(start 248.719086 -355.900228)
		(end 247.018048 -355.900228)
		(width 0.13208)
		(layer "F.Cu")
		(net "IRQ_HSC_FAULT_R_N")
	)
	(segment
		(start 249.645932 -354.973382)
		(end 248.719086 -355.900228)
		(width 0.13208)
		(layer "F.Cu")
		(net "IRQ_HSC_FAULT_R_N")
	)
	(via
		(at 248.962164 -348.899988)
		(size 0.508)
		(drill 0.254)
		(layers "F.Cu" "B.Cu")
		(net "IRQ_HSC_FAULT_R_N")
	)
	(via
		(at 250.488958 -347.390212)
		(size 0.6604)
		(drill 0.3302)
		(layers "F.Cu" "B.Cu")
		(net "IRQ_HSC_FAULT_R_N")
	)
	(segment
		(start 250.488958 -348.014798)
		(end 250.488958 -347.390212)
		(width 0.13208)
		(layer "B.Cu")
		(net "IRQ_HSC_FAULT_R_N")
	)
	(segment
		(start 250.488958 -347.390212)
		(end 251.232162 -347.390212)
		(width 0.13208)
		(layer "B.Cu")
		(net "IRQ_HSC_FAULT_R_N")
	)
	(segment
		(start 248.962164 -348.899988)
		(end 249.603768 -348.899988)
		(width 0.13208)
		(layer "B.Cu")
		(net "IRQ_HSC_FAULT_R_N")
	)
	(segment
		(start 249.603768 -348.899988)
		(end 250.488958 -348.014798)
		(width 0.13208)
		(layer "B.Cu")
		(net "IRQ_HSC_FAULT_R_N")
	)
	(segment
		(start 251.232162 -347.390212)
		(end 251.61875 -347.7768)
		(width 0.13208)
		(layer "B.Cu")
		(net "IRQ_HSC_FAULT_R_N")
	)
	(segment
		(start 254.499872 -217.782902)
		(end 254.175768 -217.458798)
		(width 0.13208)
		(layer "F.Cu")
		(net "HSC_D_OC_BIC_N")
	)
	(segment
		(start 249.655584 -217.458798)
		(end 249.614182 -217.5002)
		(width 0.13208)
		(layer "F.Cu")
		(net "HSC_D_OC_BIC_N")
	)
	(segment
		(start 262.217408 -217.782902)
		(end 254.499872 -217.782902)
		(width 0.13208)
		(layer "F.Cu")
		(net "HSC_D_OC_BIC_N")
	)
	(segment
		(start 254.175768 -217.458798)
		(end 249.655584 -217.458798)
		(width 0.13208)
		(layer "F.Cu")
		(net "HSC_D_OC_BIC_N")
	)
	(segment
		(start 263.635236 -216.365074)
		(end 262.217408 -217.782902)
		(width 0.13208)
		(layer "F.Cu")
		(net "HSC_D_OC_BIC_N")
	)
	(segment
		(start 249.614182 -217.5002)
		(end 249.3518 -217.5002)
		(width 0.13208)
		(layer "F.Cu")
		(net "HSC_D_OC_BIC_N")
	)
	(segment
		(start 263.635236 -215.194388)
		(end 263.635236 -216.365074)
		(width 0.13208)
		(layer "F.Cu")
		(net "HSC_D_OC_BIC_N")
	)
	(segment
		(start 262.398002 -215.194388)
		(end 263.635236 -215.194388)
		(width 0.13208)
		(layer "F.Cu")
		(net "HSC_D_OC_BIC_N")
	)
	(segment
		(start 224.267776 -224.704148)
		(end 223.86798 -225.103944)
		(width 0.13208)
		(layer "F.Cu")
		(net "HSC_D_OC_BIC_N")
	)
	(via
		(at 249.3518 -217.5002)
		(size 0.508)
		(drill 0.254)
		(layers "F.Cu" "B.Cu")
		(net "HSC_D_OC_BIC_N")
	)
	(via
		(at 263.635236 -215.194388)
		(size 0.762)
		(drill 0.381)
		(layers "F.Cu" "B.Cu")
		(net "HSC_D_OC_BIC_N")
	)
	(via
		(at 223.86798 -225.103944)
		(size 0.4572)
		(drill 0.254)
		(layers "F.Cu" "B.Cu")
		(net "HSC_D_OC_BIC_N")
	)
	(segment
		(start 224.283524 -224.6884)
		(end 223.86798 -225.103944)
		(width 0.15494)
		(layer "In15.Cu")
		(net "HSC_D_OC_BIC_N")
	)
	(segment
		(start 237.744762 -224.08896)
		(end 237.176564 -224.08896)
		(width 0.15494)
		(layer "In15.Cu")
		(net "HSC_D_OC_BIC_N")
	)
	(segment
		(start 225.94697 -224.6884)
		(end 224.283524 -224.6884)
		(width 0.15494)
		(layer "In15.Cu")
		(net "HSC_D_OC_BIC_N")
	)
	(segment
		(start 249.3518 -217.5002)
		(end 249.2248 -217.6272)
		(width 0.15494)
		(layer "In15.Cu")
		(net "HSC_D_OC_BIC_N")
	)
	(segment
		(start 249.2248 -217.6272)
		(end 246.117872 -217.6272)
		(width 0.15494)
		(layer "In15.Cu")
		(net "HSC_D_OC_BIC_N")
	)
	(segment
		(start 246.117872 -217.6272)
		(end 242.180872 -221.5642)
		(width 0.15494)
		(layer "In15.Cu")
		(net "HSC_D_OC_BIC_N")
	)
	(segment
		(start 235.884466 -225.72726)
		(end 226.98583 -225.72726)
		(width 0.15494)
		(layer "In15.Cu")
		(net "HSC_D_OC_BIC_N")
	)
	(segment
		(start 236.471714 -224.79381)
		(end 236.226858 -225.384868)
		(width 0.15494)
		(layer "In15.Cu")
		(net "HSC_D_OC_BIC_N")
	)
	(segment
		(start 242.180872 -221.5642)
		(end 240.269522 -221.5642)
		(width 0.15494)
		(layer "In15.Cu")
		(net "HSC_D_OC_BIC_N")
	)
	(segment
		(start 240.269522 -221.5642)
		(end 237.744762 -224.08896)
		(width 0.15494)
		(layer "In15.Cu")
		(net "HSC_D_OC_BIC_N")
	)
	(segment
		(start 226.98583 -225.72726)
		(end 225.94697 -224.6884)
		(width 0.15494)
		(layer "In15.Cu")
		(net "HSC_D_OC_BIC_N")
	)
	(segment
		(start 237.176564 -224.08896)
		(end 236.471714 -224.79381)
		(width 0.15494)
		(layer "In15.Cu")
		(net "HSC_D_OC_BIC_N")
	)
	(segment
		(start 236.226858 -225.384868)
		(end 235.884466 -225.72726)
		(width 0.15494)
		(layer "In15.Cu")
		(net "HSC_D_OC_BIC_N")
	)
	(segment
		(start 354.871274 -251.206)
		(end 345.0844 -251.206)
		(width 0.13208)
		(layer "F.Cu")
		(net "SMB_SML1_PMBUS_HSC_SCL")
	)
	(segment
		(start 330.610972 -328.9808)
		(end 267.869162 -328.9808)
		(width 0.13208)
		(layer "F.Cu")
		(net "SMB_SML1_PMBUS_HSC_SCL")
	)
	(segment
		(start 345.0844 -251.206)
		(end 337.105752 -259.184648)
		(width 0.13208)
		(layer "F.Cu")
		(net "SMB_SML1_PMBUS_HSC_SCL")
	)
	(segment
		(start 330.561442 -317.455042)
		(end 330.561442 -325.709788)
		(width 0.13208)
		(layer "F.Cu")
		(net "SMB_SML1_PMBUS_HSC_SCL")
	)
	(segment
		(start 331.8256 -326.973946)
		(end 331.8256 -327.766172)
		(width 0.13208)
		(layer "F.Cu")
		(net "SMB_SML1_PMBUS_HSC_SCL")
	)
	(segment
		(start 327.126092 -279.883108)
		(end 327.126092 -314.019692)
		(width 0.13208)
		(layer "F.Cu")
		(net "SMB_SML1_PMBUS_HSC_SCL")
	)
	(segment
		(start 355.308916 -250.768358)
		(end 354.871274 -251.206)
		(width 0.13208)
		(layer "F.Cu")
		(net "SMB_SML1_PMBUS_HSC_SCL")
	)
	(segment
		(start 337.105752 -259.184648)
		(end 337.105752 -264.645648)
		(width 0.13208)
		(layer "F.Cu")
		(net "SMB_SML1_PMBUS_HSC_SCL")
	)
	(segment
		(start 332.105 -265.811)
		(end 331.270864 -266.645136)
		(width 0.13208)
		(layer "F.Cu")
		(net "SMB_SML1_PMBUS_HSC_SCL")
	)
	(segment
		(start 267.869162 -328.9808)
		(end 267.37564 -328.487278)
		(width 0.13208)
		(layer "F.Cu")
		(net "SMB_SML1_PMBUS_HSC_SCL")
	)
	(segment
		(start 330.561442 -325.709788)
		(end 331.8256 -326.973946)
		(width 0.13208)
		(layer "F.Cu")
		(net "SMB_SML1_PMBUS_HSC_SCL")
	)
	(segment
		(start 335.9404 -265.811)
		(end 332.105 -265.811)
		(width 0.13208)
		(layer "F.Cu")
		(net "SMB_SML1_PMBUS_HSC_SCL")
	)
	(segment
		(start 327.126092 -314.019692)
		(end 330.561442 -317.455042)
		(width 0.13208)
		(layer "F.Cu")
		(net "SMB_SML1_PMBUS_HSC_SCL")
	)
	(segment
		(start 247.018048 -350.899984)
		(end 248.955306 -350.899984)
		(width 0.13208)
		(layer "F.Cu")
		(net "SMB_SML1_PMBUS_HSC_SCL")
	)
	(segment
		(start 331.8256 -327.766172)
		(end 330.610972 -328.9808)
		(width 0.13208)
		(layer "F.Cu")
		(net "SMB_SML1_PMBUS_HSC_SCL")
	)
	(segment
		(start 337.105752 -264.645648)
		(end 335.9404 -265.811)
		(width 0.13208)
		(layer "F.Cu")
		(net "SMB_SML1_PMBUS_HSC_SCL")
	)
	(segment
		(start 331.270864 -275.738336)
		(end 327.126092 -279.883108)
		(width 0.13208)
		(layer "F.Cu")
		(net "SMB_SML1_PMBUS_HSC_SCL")
	)
	(segment
		(start 331.270864 -266.645136)
		(end 331.270864 -275.738336)
		(width 0.13208)
		(layer "F.Cu")
		(net "SMB_SML1_PMBUS_HSC_SCL")
	)
	(via
		(at 355.308916 -250.768358)
		(size 0.508)
		(drill 0.254)
		(layers "F.Cu" "B.Cu")
		(net "SMB_SML1_PMBUS_HSC_SCL")
	)
	(via
		(at 249.7836 -350.899984)
		(size 0.6604)
		(drill 0.3302)
		(layers "F.Cu" "B.Cu")
		(net "SMB_SML1_PMBUS_HSC_SCL")
	)
	(via
		(at 253.339854 -350.8248)
		(size 0.508)
		(drill 0.254)
		(layers "F.Cu" "B.Cu")
		(net "SMB_SML1_PMBUS_HSC_SCL")
	)
	(via
		(at 248.955306 -350.899984)
		(size 0.508)
		(drill 0.254)
		(layers "F.Cu" "B.Cu")
		(net "SMB_SML1_PMBUS_HSC_SCL")
	)
	(via
		(at 267.37564 -328.487278)
		(size 0.508)
		(drill 0.254)
		(layers "F.Cu" "B.Cu")
		(net "SMB_SML1_PMBUS_HSC_SCL")
	)
	(segment
		(start 355.821234 -251.911866)
		(end 357.545132 -251.911866)
		(width 0.13208)
		(layer "B.Cu")
		(net "SMB_SML1_PMBUS_HSC_SCL")
	)
	(segment
		(start 248.955306 -350.899984)
		(end 249.7836 -350.899984)
		(width 0.13208)
		(layer "B.Cu")
		(net "SMB_SML1_PMBUS_HSC_SCL")
	)
	(segment
		(start 249.7836 -350.899984)
		(end 253.26467 -350.899984)
		(width 0.13208)
		(layer "B.Cu")
		(net "SMB_SML1_PMBUS_HSC_SCL")
	)
	(segment
		(start 355.308916 -251.399548)
		(end 355.821234 -251.911866)
		(width 0.13208)
		(layer "B.Cu")
		(net "SMB_SML1_PMBUS_HSC_SCL")
	)
	(segment
		(start 357.545132 -251.911866)
		(end 357.81996 -252.186694)
		(width 0.13208)
		(layer "B.Cu")
		(net "SMB_SML1_PMBUS_HSC_SCL")
	)
	(segment
		(start 355.308916 -250.768358)
		(end 355.308916 -251.399548)
		(width 0.13208)
		(layer "B.Cu")
		(net "SMB_SML1_PMBUS_HSC_SCL")
	)
	(segment
		(start 253.26467 -350.899984)
		(end 253.339854 -350.8248)
		(width 0.13208)
		(layer "B.Cu")
		(net "SMB_SML1_PMBUS_HSC_SCL")
	)
	(segment
		(start 253.339854 -350.8248)
		(end 254.113792 -350.8248)
		(width 0.15494)
		(layer "In15.Cu")
		(net "SMB_SML1_PMBUS_HSC_SCL")
	)
	(segment
		(start 254.753872 -350.18472)
		(end 254.753872 -336.993484)
		(width 0.15494)
		(layer "In15.Cu")
		(net "SMB_SML1_PMBUS_HSC_SCL")
	)
	(segment
		(start 262.436356 -329.311)
		(end 266.817094 -329.311)
		(width 0.15494)
		(layer "In15.Cu")
		(net "SMB_SML1_PMBUS_HSC_SCL")
	)
	(segment
		(start 254.753872 -336.993484)
		(end 262.436356 -329.311)
		(width 0.15494)
		(layer "In15.Cu")
		(net "SMB_SML1_PMBUS_HSC_SCL")
	)
	(segment
		(start 267.37564 -328.752454)
		(end 267.37564 -328.487278)
		(width 0.15494)
		(layer "In15.Cu")
		(net "SMB_SML1_PMBUS_HSC_SCL")
	)
	(segment
		(start 254.113792 -350.8248)
		(end 254.753872 -350.18472)
		(width 0.15494)
		(layer "In15.Cu")
		(net "SMB_SML1_PMBUS_HSC_SCL")
	)
	(segment
		(start 266.817094 -329.311)
		(end 267.37564 -328.752454)
		(width 0.15494)
		(layer "In15.Cu")
		(net "SMB_SML1_PMBUS_HSC_SCL")
	)
	(segment
		(start 243.577872 -354.400104)
		(end 241.90833 -354.400104)
		(width 0.254)
		(layer "F.Cu")
		(net "P12V_HSC_SENSE2_P")
	)
	(via
		(at 233.74477 -351.349056)
		(size 0.508)
		(drill 0.254)
		(layers "F.Cu" "B.Cu")
		(net "P12V_HSC_SENSE2_P")
	)
	(via
		(at 241.90833 -354.400104)
		(size 0.508)
		(drill 0.254)
		(layers "F.Cu" "B.Cu")
		(net "P12V_HSC_SENSE2_P")
	)
	(segment
		(start 234.58678 -351.349056)
		(end 233.74477 -351.349056)
		(width 0.254)
		(layer "B.Cu")
		(net "P12V_HSC_SENSE2_P")
	)
	(segment
		(start 234.58678 -351.349056)
		(end 234.579922 -351.342198)
		(width 0.254)
		(layer "B.Cu")
		(net "P12V_HSC_SENSE2_P")
	)
	(segment
		(start 234.579922 -351.342198)
		(end 234.579922 -350.370394)
		(width 0.254)
		(layer "B.Cu")
		(net "P12V_HSC_SENSE2_P")
	)
	(segment
		(start 241.90833 -354.400104)
		(end 242.227354 -354.099876)
		(width 0.254)
		(layer "In5.Cu")
		(net "P12V_HSC_SENSE2_P")
	)
	(segment
		(start 234.069128 -351.673414)
		(end 233.74477 -351.349056)
		(width 0.254)
		(layer "In5.Cu")
		(net "P12V_HSC_SENSE2_P")
	)
	(segment
		(start 242.58651 -354.110798)
		(end 243.016024 -354.110798)
		(width 0.254)
		(layer "In5.Cu")
		(net "P12V_HSC_SENSE2_P")
	)
	(segment
		(start 243.016024 -354.110798)
		(end 243.441982 -353.68484)
		(width 0.254)
		(layer "In5.Cu")
		(net "P12V_HSC_SENSE2_P")
	)
	(segment
		(start 242.227354 -354.099876)
		(end 242.58651 -354.110798)
		(width 0.254)
		(layer "In5.Cu")
		(net "P12V_HSC_SENSE2_P")
	)
	(segment
		(start 234.43946 -351.673414)
		(end 234.069128 -351.673414)
		(width 0.254)
		(layer "In5.Cu")
		(net "P12V_HSC_SENSE2_P")
	)
	(segment
		(start 234.625896 -351.486978)
		(end 234.43946 -351.673414)
		(width 0.254)
		(layer "In5.Cu")
		(net "P12V_HSC_SENSE2_P")
	)
	(segment
		(start 237.058708 -346.164408)
		(end 234.625896 -348.59722)
		(width 0.254)
		(layer "In5.Cu")
		(net "P12V_HSC_SENSE2_P")
	)
	(segment
		(start 234.625896 -348.59722)
		(end 234.625896 -351.486978)
		(width 0.254)
		(layer "In5.Cu")
		(net "P12V_HSC_SENSE2_P")
	)
	(segment
		(start 243.441982 -353.68484)
		(end 243.441982 -346.83573)
		(width 0.254)
		(layer "In5.Cu")
		(net "P12V_HSC_SENSE2_P")
	)
	(segment
		(start 242.77066 -346.164408)
		(end 237.058708 -346.164408)
		(width 0.254)
		(layer "In5.Cu")
		(net "P12V_HSC_SENSE2_P")
	)
	(segment
		(start 243.441982 -346.83573)
		(end 242.77066 -346.164408)
		(width 0.254)
		(layer "In5.Cu")
		(net "P12V_HSC_SENSE2_P")
	)
	(segment
		(start 243.577872 -353.400106)
		(end 241.938556 -353.400106)
		(width 0.254)
		(layer "F.Cu")
		(net "P12V_HSC_SENSE2_N")
	)
	(via
		(at 233.77144 -352.307906)
		(size 0.762)
		(drill 0.254)
		(layers "F.Cu" "B.Cu")
		(net "P12V_HSC_SENSE2_N")
	)
	(via
		(at 241.938556 -353.400106)
		(size 0.508)
		(drill 0.254)
		(layers "F.Cu" "B.Cu")
		(net "P12V_HSC_SENSE2_N")
	)
	(segment
		(start 234.593384 -352.307906)
		(end 234.593384 -353.266502)
		(width 0.254)
		(layer "B.Cu")
		(net "P12V_HSC_SENSE2_N")
	)
	(segment
		(start 234.593384 -352.307906)
		(end 233.77144 -352.307906)
		(width 0.254)
		(layer "B.Cu")
		(net "P12V_HSC_SENSE2_N")
	)
	(segment
		(start 234.593384 -353.266502)
		(end 234.600496 -353.273614)
		(width 0.254)
		(layer "B.Cu")
		(net "P12V_HSC_SENSE2_N")
	)
	(segment
		(start 235.006896 -348.755208)
		(end 237.216696 -346.545408)
		(width 0.254)
		(layer "In5.Cu")
		(net "P12V_HSC_SENSE2_N")
	)
	(segment
		(start 235.006896 -351.644966)
		(end 235.006896 -348.755208)
		(width 0.254)
		(layer "In5.Cu")
		(net "P12V_HSC_SENSE2_N")
	)
	(segment
		(start 242.238784 -353.718876)
		(end 241.938556 -353.400106)
		(width 0.254)
		(layer "In5.Cu")
		(net "P12V_HSC_SENSE2_N")
	)
	(segment
		(start 243.060982 -346.993718)
		(end 243.060982 -353.526852)
		(width 0.254)
		(layer "In5.Cu")
		(net "P12V_HSC_SENSE2_N")
	)
	(segment
		(start 234.024932 -352.054414)
		(end 234.597448 -352.054414)
		(width 0.254)
		(layer "In5.Cu")
		(net "P12V_HSC_SENSE2_N")
	)
	(segment
		(start 242.858036 -353.729798)
		(end 242.598194 -353.729798)
		(width 0.254)
		(layer "In5.Cu")
		(net "P12V_HSC_SENSE2_N")
	)
	(segment
		(start 242.612672 -346.545408)
		(end 243.060982 -346.993718)
		(width 0.254)
		(layer "In5.Cu")
		(net "P12V_HSC_SENSE2_N")
	)
	(segment
		(start 237.216696 -346.545408)
		(end 242.612672 -346.545408)
		(width 0.254)
		(layer "In5.Cu")
		(net "P12V_HSC_SENSE2_N")
	)
	(segment
		(start 234.597448 -352.054414)
		(end 235.006896 -351.644966)
		(width 0.254)
		(layer "In5.Cu")
		(net "P12V_HSC_SENSE2_N")
	)
	(segment
		(start 243.060982 -353.526852)
		(end 242.858036 -353.729798)
		(width 0.254)
		(layer "In5.Cu")
		(net "P12V_HSC_SENSE2_N")
	)
	(segment
		(start 242.598194 -353.729798)
		(end 242.238784 -353.718876)
		(width 0.254)
		(layer "In5.Cu")
		(net "P12V_HSC_SENSE2_N")
	)
	(segment
		(start 233.77144 -352.307906)
		(end 234.024932 -352.054414)
		(width 0.254)
		(layer "In5.Cu")
		(net "P12V_HSC_SENSE2_N")
	)
	(segment
		(start 325.406766 -215.42883)
		(end 324.293484 -215.42883)
		(width 0.13208)
		(layer "F.Cu")
		(net "HSC_D_OC_FPGA_N")
	)
	(segment
		(start 336.493866 -219.987114)
		(end 336.09407 -220.38691)
		(width 0.13208)
		(layer "F.Cu")
		(net "HSC_D_OC_FPGA_N")
	)
	(segment
		(start 325.88835 -215.46947)
		(end 325.447406 -215.46947)
		(width 0.13208)
		(layer "F.Cu")
		(net "HSC_D_OC_FPGA_N")
	)
	(segment
		(start 325.447406 -215.46947)
		(end 325.406766 -215.42883)
		(width 0.13208)
		(layer "F.Cu")
		(net "HSC_D_OC_FPGA_N")
	)
	(via
		(at 336.09407 -220.38691)
		(size 0.4572)
		(drill 0.254)
		(layers "F.Cu" "B.Cu")
		(net "HSC_D_OC_FPGA_N")
	)
	(via
		(at 325.88835 -215.46947)
		(size 0.508)
		(drill 0.254)
		(layers "F.Cu" "B.Cu")
		(net "HSC_D_OC_FPGA_N")
	)
	(segment
		(start 327.2282 -216.102946)
		(end 326.822054 -215.6968)
		(width 0.15494)
		(layer "In15.Cu")
		(net "HSC_D_OC_FPGA_N")
	)
	(segment
		(start 331.90053 -217.648282)
		(end 329.952604 -217.648282)
		(width 0.15494)
		(layer "In15.Cu")
		(net "HSC_D_OC_FPGA_N")
	)
	(segment
		(start 329.952604 -217.648282)
		(end 329.671934 -217.367612)
		(width 0.15494)
		(layer "In15.Cu")
		(net "HSC_D_OC_FPGA_N")
	)
	(segment
		(start 336.09407 -220.38691)
		(end 335.116424 -219.409264)
		(width 0.15494)
		(layer "In15.Cu")
		(net "HSC_D_OC_FPGA_N")
	)
	(segment
		(start 326.11568 -215.6968)
		(end 325.88835 -215.46947)
		(width 0.15494)
		(layer "In15.Cu")
		(net "HSC_D_OC_FPGA_N")
	)
	(segment
		(start 327.2282 -216.4588)
		(end 327.2282 -216.102946)
		(width 0.15494)
		(layer "In15.Cu")
		(net "HSC_D_OC_FPGA_N")
	)
	(segment
		(start 329.671934 -217.367612)
		(end 328.137012 -217.367612)
		(width 0.15494)
		(layer "In15.Cu")
		(net "HSC_D_OC_FPGA_N")
	)
	(segment
		(start 333.661512 -219.409264)
		(end 331.90053 -217.648282)
		(width 0.15494)
		(layer "In15.Cu")
		(net "HSC_D_OC_FPGA_N")
	)
	(segment
		(start 335.116424 -219.409264)
		(end 333.661512 -219.409264)
		(width 0.15494)
		(layer "In15.Cu")
		(net "HSC_D_OC_FPGA_N")
	)
	(segment
		(start 328.137012 -217.367612)
		(end 327.2282 -216.4588)
		(width 0.15494)
		(layer "In15.Cu")
		(net "HSC_D_OC_FPGA_N")
	)
	(segment
		(start 326.822054 -215.6968)
		(end 326.11568 -215.6968)
		(width 0.15494)
		(layer "In15.Cu")
		(net "HSC_D_OC_FPGA_N")
	)
	(via
		(at 260.385052 -371.815106)
		(size 0.508)
		(drill 0.254)
		(layers "F.Cu" "B.Cu")
		(net "P12V_STBY_R2")
	)
	(via
		(at 260.385052 -372.577106)
		(size 0.508)
		(drill 0.254)
		(layers "F.Cu" "B.Cu")
		(net "P12V_STBY_R2")
	)
	(via
		(at 242.884452 -372.653306)
		(size 0.508)
		(drill 0.254)
		(layers "F.Cu" "B.Cu")
		(net "P12V_STBY_R2")
	)
	(via
		(at 254.644652 -370.316506)
		(size 0.508)
		(drill 0.254)
		(layers "F.Cu" "B.Cu")
		(net "P12V_STBY_R2")
	)
	(via
		(at 242.884452 -373.355108)
		(size 0.508)
		(drill 0.254)
		(layers "F.Cu" "B.Cu")
		(net "P12V_STBY_R2")
	)
	(via
		(at 260.385052 -370.291106)
		(size 0.508)
		(drill 0.254)
		(layers "F.Cu" "B.Cu")
		(net "P12V_STBY_R2")
	)
	(via
		(at 248.802652 -373.329708)
		(size 0.508)
		(drill 0.254)
		(layers "F.Cu" "B.Cu")
		(net "P12V_STBY_R2")
	)
	(via
		(at 243.318538 -377.106688)
		(size 0.6604)
		(drill 0.3302)
		(layers "F.Cu" "B.Cu")
		(net "P12V_STBY_R2")
	)
	(via
		(at 260.385052 -369.529106)
		(size 0.508)
		(drill 0.254)
		(layers "F.Cu" "B.Cu")
		(net "P12V_STBY_R2")
	)
	(via
		(at 254.644652 -372.602506)
		(size 0.508)
		(drill 0.254)
		(layers "F.Cu" "B.Cu")
		(net "P12V_STBY_R2")
	)
	(via
		(at 248.802652 -371.865906)
		(size 0.508)
		(drill 0.254)
		(layers "F.Cu" "B.Cu")
		(net "P12V_STBY_R2")
	)
	(via
		(at 254.644652 -371.078506)
		(size 0.508)
		(drill 0.254)
		(layers "F.Cu" "B.Cu")
		(net "P12V_STBY_R2")
	)
	(via
		(at 248.802652 -372.627906)
		(size 0.508)
		(drill 0.254)
		(layers "F.Cu" "B.Cu")
		(net "P12V_STBY_R2")
	)
	(via
		(at 260.385052 -373.278908)
		(size 0.508)
		(drill 0.254)
		(layers "F.Cu" "B.Cu")
		(net "P12V_STBY_R2")
	)
	(via
		(at 242.884452 -370.367306)
		(size 0.508)
		(drill 0.254)
		(layers "F.Cu" "B.Cu")
		(net "P12V_STBY_R2")
	)
	(via
		(at 248.802652 -371.103906)
		(size 0.508)
		(drill 0.254)
		(layers "F.Cu" "B.Cu")
		(net "P12V_STBY_R2")
	)
	(via
		(at 242.884452 -371.129306)
		(size 0.508)
		(drill 0.254)
		(layers "F.Cu" "B.Cu")
		(net "P12V_STBY_R2")
	)
	(via
		(at 242.884452 -371.891306)
		(size 0.508)
		(drill 0.254)
		(layers "F.Cu" "B.Cu")
		(net "P12V_STBY_R2")
	)
	(via
		(at 254.644652 -371.840506)
		(size 0.508)
		(drill 0.254)
		(layers "F.Cu" "B.Cu")
		(net "P12V_STBY_R2")
	)
	(via
		(at 248.802652 -370.341906)
		(size 0.508)
		(drill 0.254)
		(layers "F.Cu" "B.Cu")
		(net "P12V_STBY_R2")
	)
	(via
		(at 260.385052 -371.053106)
		(size 0.508)
		(drill 0.254)
		(layers "F.Cu" "B.Cu")
		(net "P12V_STBY_R2")
	)
	(via
		(at 254.644652 -369.554506)
		(size 0.508)
		(drill 0.254)
		(layers "F.Cu" "B.Cu")
		(net "P12V_STBY_R2")
	)
	(via
		(at 242.884452 -369.605306)
		(size 0.508)
		(drill 0.254)
		(layers "F.Cu" "B.Cu")
		(net "P12V_STBY_R2")
	)
	(via
		(at 248.802652 -369.579906)
		(size 0.508)
		(drill 0.254)
		(layers "F.Cu" "B.Cu")
		(net "P12V_STBY_R2")
	)
	(via
		(at 254.644652 -373.304308)
		(size 0.508)
		(drill 0.254)
		(layers "F.Cu" "B.Cu")
		(net "P12V_STBY_R2")
	)
	(segment
		(start 248.74982 -351.900236)
		(end 248.918984 -352.0694)
		(width 0.13208)
		(layer "F.Cu")
		(net "HSC_TYPE_ADC")
	)
	(segment
		(start 247.018048 -351.900236)
		(end 248.74982 -351.900236)
		(width 0.13208)
		(layer "F.Cu")
		(net "HSC_TYPE_ADC")
	)
	(via
		(at 248.918984 -352.0694)
		(size 0.508)
		(drill 0.254)
		(layers "F.Cu" "B.Cu")
		(net "HSC_TYPE_ADC")
	)
	(segment
		(start 249.706384 -352.8568)
		(end 251.61875 -352.8568)
		(width 0.13208)
		(layer "B.Cu")
		(net "HSC_TYPE_ADC")
	)
	(segment
		(start 248.918984 -352.0694)
		(end 249.706384 -352.8568)
		(width 0.13208)
		(layer "B.Cu")
		(net "HSC_TYPE_ADC")
	)
	(segment
		(start 248.94159 -378.671328)
		(end 248.68759 -378.417328)
		(width 0.254)
		(layer "F.Cu")
		(net "P12V_HSC_SENSE2_R1_P")
	)
	(segment
		(start 248.94159 -379.170438)
		(end 248.94159 -378.671328)
		(width 0.254)
		(layer "F.Cu")
		(net "P12V_HSC_SENSE2_R1_P")
	)
	(segment
		(start 248.68759 -378.417328)
		(end 248.662698 -378.417328)
		(width 0.254)
		(layer "F.Cu")
		(net "P12V_HSC_SENSE2_R1_P")
	)
	(via
		(at 236.514386 -356.165658)
		(size 0.508)
		(drill 0.254)
		(layers "F.Cu" "B.Cu")
		(net "P12V_HSC_SENSE2_R1_P")
	)
	(via
		(at 248.662698 -378.417328)
		(size 0.508)
		(drill 0.254)
		(layers "F.Cu" "B.Cu")
		(net "P12V_HSC_SENSE2_R1_P")
	)
	(via
		(at 236.514386 -350.374458)
		(size 0.762)
		(drill 0.254)
		(layers "F.Cu" "B.Cu")
		(net "P12V_HSC_SENSE2_R1_P")
	)
	(segment
		(start 235.862876 -350.370394)
		(end 235.86694 -350.374458)
		(width 0.254)
		(layer "B.Cu")
		(net "P12V_HSC_SENSE2_R1_P")
	)
	(segment
		(start 235.380022 -350.370394)
		(end 235.862876 -350.370394)
		(width 0.254)
		(layer "B.Cu")
		(net "P12V_HSC_SENSE2_R1_P")
	)
	(segment
		(start 237.231936 -356.165658)
		(end 236.514386 -356.165658)
		(width 0.254)
		(layer "B.Cu")
		(net "P12V_HSC_SENSE2_R1_P")
	)
	(segment
		(start 235.86694 -350.374458)
		(end 236.514386 -350.374458)
		(width 0.254)
		(layer "B.Cu")
		(net "P12V_HSC_SENSE2_R1_P")
	)
	(segment
		(start 236.514386 -350.374458)
		(end 235.547916 -351.340928)
		(width 0.254)
		(layer "In5.Cu")
		(net "P12V_HSC_SENSE2_R1_P")
	)
	(segment
		(start 235.547916 -355.199188)
		(end 236.514386 -356.165658)
		(width 0.254)
		(layer "In5.Cu")
		(net "P12V_HSC_SENSE2_R1_P")
	)
	(segment
		(start 235.547916 -351.340928)
		(end 235.547916 -355.199188)
		(width 0.254)
		(layer "In5.Cu")
		(net "P12V_HSC_SENSE2_R1_P")
	)
	(segment
		(start 248.564908 -377.415298)
		(end 235.377736 -377.415298)
		(width 0.254)
		(layer "In7.Cu")
		(net "P12V_HSC_SENSE2_R1_P")
	)
	(segment
		(start 237.626398 -357.27767)
		(end 236.514386 -356.165658)
		(width 0.254)
		(layer "In7.Cu")
		(net "P12V_HSC_SENSE2_R1_P")
	)
	(segment
		(start 235.377736 -377.415298)
		(end 233.766106 -375.803668)
		(width 0.254)
		(layer "In7.Cu")
		(net "P12V_HSC_SENSE2_R1_P")
	)
	(segment
		(start 248.87428 -377.72467)
		(end 248.564908 -377.415298)
		(width 0.254)
		(layer "In7.Cu")
		(net "P12V_HSC_SENSE2_R1_P")
	)
	(segment
		(start 248.662698 -378.417328)
		(end 248.87428 -378.205746)
		(width 0.254)
		(layer "In7.Cu")
		(net "P12V_HSC_SENSE2_R1_P")
	)
	(segment
		(start 237.626398 -358.3686)
		(end 237.626398 -357.27767)
		(width 0.254)
		(layer "In7.Cu")
		(net "P12V_HSC_SENSE2_R1_P")
	)
	(segment
		(start 234.702858 -369.64747)
		(end 234.702858 -361.29214)
		(width 0.254)
		(layer "In7.Cu")
		(net "P12V_HSC_SENSE2_R1_P")
	)
	(segment
		(start 248.87428 -378.205746)
		(end 248.87428 -377.72467)
		(width 0.254)
		(layer "In7.Cu")
		(net "P12V_HSC_SENSE2_R1_P")
	)
	(segment
		(start 234.702858 -361.29214)
		(end 237.626398 -358.3686)
		(width 0.254)
		(layer "In7.Cu")
		(net "P12V_HSC_SENSE2_R1_P")
	)
	(segment
		(start 233.766106 -375.803668)
		(end 233.766106 -370.584222)
		(width 0.254)
		(layer "In7.Cu")
		(net "P12V_HSC_SENSE2_R1_P")
	)
	(segment
		(start 233.766106 -370.584222)
		(end 234.702858 -369.64747)
		(width 0.254)
		(layer "In7.Cu")
		(net "P12V_HSC_SENSE2_R1_P")
	)
	(segment
		(start 71.7296 -237.855506)
		(end 70.799706 -237.855506)
		(width 0.13208)
		(layer "F.Cu")
		(net "UART_PEX0_CLI_BUF_R_TX")
	)
	(segment
		(start 109.3724 -202.5396)
		(end 108.5342 -203.3778)
		(width 0.13208)
		(layer "F.Cu")
		(net "UART_PEX0_CLI_BUF_R_TX")
	)
	(segment
		(start 108.5342 -203.3778)
		(end 106.22915 -203.3778)
		(width 0.13208)
		(layer "F.Cu")
		(net "UART_PEX0_CLI_BUF_R_TX")
	)
	(segment
		(start 106.22915 -203.3778)
		(end 105.7148 -202.86345)
		(width 0.13208)
		(layer "F.Cu")
		(net "UART_PEX0_CLI_BUF_R_TX")
	)
	(via
		(at 70.799706 -237.855506)
		(size 0.508)
		(drill 0.254)
		(layers "F.Cu" "B.Cu")
		(net "UART_PEX0_CLI_BUF_R_TX")
	)
	(via
		(at 71.5772 -236.0676)
		(size 0.6604)
		(drill 0.3302)
		(layers "F.Cu" "B.Cu")
		(net "UART_PEX0_CLI_BUF_R_TX")
	)
	(via
		(at 131.496308 -209.9564)
		(size 0.508)
		(drill 0.254)
		(layers "F.Cu" "B.Cu")
		(net "UART_PEX0_CLI_BUF_R_TX")
	)
	(via
		(at 109.3724 -202.5396)
		(size 0.508)
		(drill 0.254)
		(layers "F.Cu" "B.Cu")
		(net "UART_PEX0_CLI_BUF_R_TX")
	)
	(segment
		(start 71.5772 -236.0676)
		(end 71.5772 -237.078012)
		(width 0.13208)
		(layer "B.Cu")
		(net "UART_PEX0_CLI_BUF_R_TX")
	)
	(segment
		(start 109.3724 -201.3204)
		(end 107.213146 -199.161146)
		(width 0.13208)
		(layer "B.Cu")
		(net "UART_PEX0_CLI_BUF_R_TX")
	)
	(segment
		(start 129.929128 -210.938872)
		(end 129.321814 -210.938872)
		(width 0.13208)
		(layer "B.Cu")
		(net "UART_PEX0_CLI_BUF_R_TX")
	)
	(segment
		(start 130.9116 -209.9564)
		(end 129.929128 -210.938872)
		(width 0.13208)
		(layer "B.Cu")
		(net "UART_PEX0_CLI_BUF_R_TX")
	)
	(segment
		(start 69.2658 -230.8352)
		(end 71.5772 -233.1466)
		(width 0.13208)
		(layer "B.Cu")
		(net "UART_PEX0_CLI_BUF_R_TX")
	)
	(segment
		(start 109.3724 -202.5396)
		(end 109.3724 -201.3204)
		(width 0.13208)
		(layer "B.Cu")
		(net "UART_PEX0_CLI_BUF_R_TX")
	)
	(segment
		(start 71.5772 -233.1466)
		(end 71.5772 -236.0676)
		(width 0.13208)
		(layer "B.Cu")
		(net "UART_PEX0_CLI_BUF_R_TX")
	)
	(segment
		(start 132.620766 -211.080858)
		(end 131.496308 -209.9564)
		(width 0.13208)
		(layer "B.Cu")
		(net "UART_PEX0_CLI_BUF_R_TX")
	)
	(segment
		(start 71.491602 -223.9772)
		(end 69.2658 -226.203002)
		(width 0.13208)
		(layer "B.Cu")
		(net "UART_PEX0_CLI_BUF_R_TX")
	)
	(segment
		(start 102.774496 -200.137776)
		(end 102.774496 -203.971906)
		(width 0.13208)
		(layer "B.Cu")
		(net "UART_PEX0_CLI_BUF_R_TX")
	)
	(segment
		(start 131.496308 -209.9564)
		(end 130.9116 -209.9564)
		(width 0.13208)
		(layer "B.Cu")
		(net "UART_PEX0_CLI_BUF_R_TX")
	)
	(segment
		(start 105.892854 -199.161146)
		(end 105.2068 -199.8472)
		(width 0.13208)
		(layer "B.Cu")
		(net "UART_PEX0_CLI_BUF_R_TX")
	)
	(segment
		(start 107.213146 -199.161146)
		(end 105.892854 -199.161146)
		(width 0.13208)
		(layer "B.Cu")
		(net "UART_PEX0_CLI_BUF_R_TX")
	)
	(segment
		(start 71.5772 -237.078012)
		(end 70.799706 -237.855506)
		(width 0.13208)
		(layer "B.Cu")
		(net "UART_PEX0_CLI_BUF_R_TX")
	)
	(segment
		(start 105.2068 -199.8472)
		(end 103.065072 -199.8472)
		(width 0.13208)
		(layer "B.Cu")
		(net "UART_PEX0_CLI_BUF_R_TX")
	)
	(segment
		(start 103.065072 -199.8472)
		(end 102.774496 -200.137776)
		(width 0.13208)
		(layer "B.Cu")
		(net "UART_PEX0_CLI_BUF_R_TX")
	)
	(segment
		(start 76.012802 -223.9772)
		(end 71.491602 -223.9772)
		(width 0.13208)
		(layer "B.Cu")
		(net "UART_PEX0_CLI_BUF_R_TX")
	)
	(segment
		(start 98.390202 -208.3562)
		(end 91.633802 -208.3562)
		(width 0.13208)
		(layer "B.Cu")
		(net "UART_PEX0_CLI_BUF_R_TX")
	)
	(segment
		(start 69.2658 -226.203002)
		(end 69.2658 -230.8352)
		(width 0.13208)
		(layer "B.Cu")
		(net "UART_PEX0_CLI_BUF_R_TX")
	)
	(segment
		(start 102.774496 -203.971906)
		(end 98.390202 -208.3562)
		(width 0.13208)
		(layer "B.Cu")
		(net "UART_PEX0_CLI_BUF_R_TX")
	)
	(segment
		(start 91.633802 -208.3562)
		(end 76.012802 -223.9772)
		(width 0.13208)
		(layer "B.Cu")
		(net "UART_PEX0_CLI_BUF_R_TX")
	)
	(segment
		(start 109.3724 -202.5396)
		(end 109.3724 -203.2762)
		(width 0.15494)
		(layer "In13.Cu")
		(net "UART_PEX0_CLI_BUF_R_TX")
	)
	(segment
		(start 118.3894 -203.9366)
		(end 119.7356 -205.2828)
		(width 0.15494)
		(layer "In13.Cu")
		(net "UART_PEX0_CLI_BUF_R_TX")
	)
	(segment
		(start 109.3724 -203.2762)
		(end 110.0328 -203.9366)
		(width 0.15494)
		(layer "In13.Cu")
		(net "UART_PEX0_CLI_BUF_R_TX")
	)
	(segment
		(start 110.0328 -203.9366)
		(end 118.3894 -203.9366)
		(width 0.15494)
		(layer "In13.Cu")
		(net "UART_PEX0_CLI_BUF_R_TX")
	)
	(segment
		(start 123.396248 -205.285848)
		(end 128.1938 -210.0834)
		(width 0.15494)
		(layer "In13.Cu")
		(net "UART_PEX0_CLI_BUF_R_TX")
	)
	(segment
		(start 119.7356 -205.2828)
		(end 119.94896 -205.2828)
		(width 0.15494)
		(layer "In13.Cu")
		(net "UART_PEX0_CLI_BUF_R_TX")
	)
	(segment
		(start 123.115324 -205.285848)
		(end 123.396248 -205.285848)
		(width 0.15494)
		(layer "In13.Cu")
		(net "UART_PEX0_CLI_BUF_R_TX")
	)
	(segment
		(start 119.9515 -205.28534)
		(end 123.114816 -205.28534)
		(width 0.15494)
		(layer "In13.Cu")
		(net "UART_PEX0_CLI_BUF_R_TX")
	)
	(segment
		(start 123.114816 -205.28534)
		(end 123.115324 -205.285848)
		(width 0.15494)
		(layer "In13.Cu")
		(net "UART_PEX0_CLI_BUF_R_TX")
	)
	(segment
		(start 128.1938 -210.0834)
		(end 131.369308 -210.0834)
		(width 0.15494)
		(layer "In13.Cu")
		(net "UART_PEX0_CLI_BUF_R_TX")
	)
	(segment
		(start 131.369308 -210.0834)
		(end 131.496308 -209.9564)
		(width 0.15494)
		(layer "In13.Cu")
		(net "UART_PEX0_CLI_BUF_R_TX")
	)
	(segment
		(start 119.94896 -205.2828)
		(end 119.9515 -205.28534)
		(width 0.15494)
		(layer "In13.Cu")
		(net "UART_PEX0_CLI_BUF_R_TX")
	)
	(segment
		(start 97.182178 -194.183)
		(end 95.875094 -194.183)
		(width 0.13208)
		(layer "F.Cu")
		(net "UART_PEX3_CLI_CP2108_RX")
	)
	(segment
		(start 98.668332 -196.001132)
		(end 97.182178 -194.514978)
		(width 0.13208)
		(layer "F.Cu")
		(net "UART_PEX3_CLI_CP2108_RX")
	)
	(segment
		(start 99.25812 -196.001132)
		(end 98.668332 -196.001132)
		(width 0.13208)
		(layer "F.Cu")
		(net "UART_PEX3_CLI_CP2108_RX")
	)
	(segment
		(start 97.182178 -194.514978)
		(end 97.182178 -194.183)
		(width 0.13208)
		(layer "F.Cu")
		(net "UART_PEX3_CLI_CP2108_RX")
	)
	(via
		(at 97.182178 -194.183)
		(size 0.762)
		(drill 0.381)
		(layers "F.Cu" "B.Cu")
		(net "UART_PEX3_CLI_CP2108_RX")
	)
	(segment
		(start 107.74045 -200.50125)
		(end 108.204 -200.50125)
		(width 0.13208)
		(layer "F.Cu")
		(net "UART_PEX1_CLI_BUF_R_TX")
	)
	(segment
		(start 106.9848 -199.7456)
		(end 107.74045 -200.50125)
		(width 0.13208)
		(layer "F.Cu")
		(net "UART_PEX1_CLI_BUF_R_TX")
	)
	(segment
		(start 72.278494 -228.4476)
		(end 69.9516 -228.4476)
		(width 0.13208)
		(layer "F.Cu")
		(net "UART_PEX1_CLI_BUF_R_TX")
	)
	(segment
		(start 72.7202 -228.889306)
		(end 72.278494 -228.4476)
		(width 0.13208)
		(layer "F.Cu")
		(net "UART_PEX1_CLI_BUF_R_TX")
	)
	(via
		(at 69.9516 -227.1268)
		(size 0.6604)
		(drill 0.3302)
		(layers "F.Cu" "B.Cu")
		(net "UART_PEX1_CLI_BUF_R_TX")
	)
	(via
		(at 106.9848 -199.7456)
		(size 0.508)
		(drill 0.254)
		(layers "F.Cu" "B.Cu")
		(net "UART_PEX1_CLI_BUF_R_TX")
	)
	(via
		(at 69.9516 -228.4476)
		(size 0.508)
		(drill 0.254)
		(layers "F.Cu" "B.Cu")
		(net "UART_PEX1_CLI_BUF_R_TX")
	)
	(segment
		(start 128.451356 -212.238844)
		(end 129.321814 -212.238844)
		(width 0.13208)
		(layer "B.Cu")
		(net "UART_PEX1_CLI_BUF_R_TX")
	)
	(segment
		(start 132.21081 -212.8012)
		(end 132.630164 -212.381846)
		(width 0.13208)
		(layer "B.Cu")
		(net "UART_PEX1_CLI_BUF_R_TX")
	)
	(segment
		(start 69.9516 -226.2886)
		(end 70.7898 -225.4504)
		(width 0.13208)
		(layer "B.Cu")
		(net "UART_PEX1_CLI_BUF_R_TX")
	)
	(segment
		(start 130.5052 -212.8012)
		(end 132.21081 -212.8012)
		(width 0.13208)
		(layer "B.Cu")
		(net "UART_PEX1_CLI_BUF_R_TX")
	)
	(segment
		(start 108.8136 -203.3778)
		(end 112.2934 -206.8576)
		(width 0.13208)
		(layer "B.Cu")
		(net "UART_PEX1_CLI_BUF_R_TX")
	)
	(segment
		(start 70.7898 -225.4504)
		(end 75.311 -225.4504)
		(width 0.13208)
		(layer "B.Cu")
		(net "UART_PEX1_CLI_BUF_R_TX")
	)
	(segment
		(start 98.6536 -208.7626)
		(end 106.9848 -200.4314)
		(width 0.13208)
		(layer "B.Cu")
		(net "UART_PEX1_CLI_BUF_R_TX")
	)
	(segment
		(start 106.9848 -199.7456)
		(end 108.8136 -201.5744)
		(width 0.13208)
		(layer "B.Cu")
		(net "UART_PEX1_CLI_BUF_R_TX")
	)
	(segment
		(start 121.4628 -213.0552)
		(end 127.635 -213.0552)
		(width 0.13208)
		(layer "B.Cu")
		(net "UART_PEX1_CLI_BUF_R_TX")
	)
	(segment
		(start 127.635 -213.0552)
		(end 128.451356 -212.238844)
		(width 0.13208)
		(layer "B.Cu")
		(net "UART_PEX1_CLI_BUF_R_TX")
	)
	(segment
		(start 91.9988 -208.7626)
		(end 98.6536 -208.7626)
		(width 0.13208)
		(layer "B.Cu")
		(net "UART_PEX1_CLI_BUF_R_TX")
	)
	(segment
		(start 115.2652 -206.8576)
		(end 121.4628 -213.0552)
		(width 0.13208)
		(layer "B.Cu")
		(net "UART_PEX1_CLI_BUF_R_TX")
	)
	(segment
		(start 129.321814 -212.238844)
		(end 129.942844 -212.238844)
		(width 0.13208)
		(layer "B.Cu")
		(net "UART_PEX1_CLI_BUF_R_TX")
	)
	(segment
		(start 106.9848 -200.4314)
		(end 106.9848 -199.7456)
		(width 0.13208)
		(layer "B.Cu")
		(net "UART_PEX1_CLI_BUF_R_TX")
	)
	(segment
		(start 69.9516 -227.1268)
		(end 69.9516 -226.2886)
		(width 0.13208)
		(layer "B.Cu")
		(net "UART_PEX1_CLI_BUF_R_TX")
	)
	(segment
		(start 129.942844 -212.238844)
		(end 130.5052 -212.8012)
		(width 0.13208)
		(layer "B.Cu")
		(net "UART_PEX1_CLI_BUF_R_TX")
	)
	(segment
		(start 108.8136 -201.5744)
		(end 108.8136 -203.3778)
		(width 0.13208)
		(layer "B.Cu")
		(net "UART_PEX1_CLI_BUF_R_TX")
	)
	(segment
		(start 69.9516 -228.4476)
		(end 69.9516 -227.1268)
		(width 0.13208)
		(layer "B.Cu")
		(net "UART_PEX1_CLI_BUF_R_TX")
	)
	(segment
		(start 75.311 -225.4504)
		(end 91.9988 -208.7626)
		(width 0.13208)
		(layer "B.Cu")
		(net "UART_PEX1_CLI_BUF_R_TX")
	)
	(segment
		(start 112.2934 -206.8576)
		(end 115.2652 -206.8576)
		(width 0.13208)
		(layer "B.Cu")
		(net "UART_PEX1_CLI_BUF_R_TX")
	)
	(segment
		(start 97.4852 -199.3392)
		(end 98.171 -198.6534)
		(width 0.13208)
		(layer "F.Cu")
		(net "UART_PEX3_CLI_CP2108_TX")
	)
	(segment
		(start 99.25812 -197.501256)
		(end 98.962464 -197.501256)
		(width 0.13208)
		(layer "F.Cu")
		(net "UART_PEX3_CLI_CP2108_TX")
	)
	(segment
		(start 95.87865 -199.7456)
		(end 96.28505 -199.3392)
		(width 0.13208)
		(layer "F.Cu")
		(net "UART_PEX3_CLI_CP2108_TX")
	)
	(segment
		(start 96.28505 -199.3392)
		(end 97.4852 -199.3392)
		(width 0.13208)
		(layer "F.Cu")
		(net "UART_PEX3_CLI_CP2108_TX")
	)
	(segment
		(start 98.962464 -197.501256)
		(end 98.171 -198.29272)
		(width 0.13208)
		(layer "F.Cu")
		(net "UART_PEX3_CLI_CP2108_TX")
	)
	(segment
		(start 98.171 -198.29272)
		(end 98.171 -198.6534)
		(width 0.13208)
		(layer "F.Cu")
		(net "UART_PEX3_CLI_CP2108_TX")
	)
	(via
		(at 98.171 -198.6534)
		(size 0.762)
		(drill 0.381)
		(layers "F.Cu" "B.Cu")
		(net "UART_PEX3_CLI_CP2108_TX")
	)
	(segment
		(start 104.5972 -199.8218)
		(end 103.458264 -198.682864)
		(width 0.13208)
		(layer "F.Cu")
		(net "UART_PEX0_CLI_CP2108_RX")
	)
	(segment
		(start 104.6734 -201.651362)
		(end 104.5972 -201.575162)
		(width 0.13208)
		(layer "F.Cu")
		(net "UART_PEX0_CLI_CP2108_RX")
	)
	(segment
		(start 103.458264 -198.682864)
		(end 103.458264 -198.20128)
		(width 0.13208)
		(layer "F.Cu")
		(net "UART_PEX0_CLI_CP2108_RX")
	)
	(segment
		(start 104.5972 -200.8886)
		(end 104.5972 -199.8218)
		(width 0.13208)
		(layer "F.Cu")
		(net "UART_PEX0_CLI_CP2108_RX")
	)
	(segment
		(start 104.6734 -202.066906)
		(end 104.6734 -201.651362)
		(width 0.13208)
		(layer "F.Cu")
		(net "UART_PEX0_CLI_CP2108_RX")
	)
	(segment
		(start 104.5972 -201.575162)
		(end 104.5972 -200.8886)
		(width 0.13208)
		(layer "F.Cu")
		(net "UART_PEX0_CLI_CP2108_RX")
	)
	(via
		(at 104.5972 -200.8886)
		(size 0.762)
		(drill 0.381)
		(layers "F.Cu" "B.Cu")
		(net "UART_PEX0_CLI_CP2108_RX")
	)
	(segment
		(start 97.6884 -190.50127)
		(end 96.31172 -190.50127)
		(width 0.13208)
		(layer "F.Cu")
		(net "UART_PEX2_CLI_CP2108_TX")
	)
	(segment
		(start 99.25812 -190.50127)
		(end 97.6884 -190.50127)
		(width 0.13208)
		(layer "F.Cu")
		(net "UART_PEX2_CLI_CP2108_TX")
	)
	(segment
		(start 96.31172 -190.50127)
		(end 96.31045 -190.5)
		(width 0.13208)
		(layer "F.Cu")
		(net "UART_PEX2_CLI_CP2108_TX")
	)
	(via
		(at 97.6884 -190.50127)
		(size 0.762)
		(drill 0.381)
		(layers "F.Cu" "B.Cu")
		(net "UART_PEX2_CLI_CP2108_TX")
	)
	(segment
		(start 109.219746 -198.628)
		(end 108.483654 -198.628)
		(width 0.13208)
		(layer "F.Cu")
		(net "UART_PEX1_CLI_CP2108_TX")
	)
	(segment
		(start 108.204 -198.907654)
		(end 108.204 -199.70115)
		(width 0.13208)
		(layer "F.Cu")
		(net "UART_PEX1_CLI_CP2108_TX")
	)
	(segment
		(start 109.6264 -197.501256)
		(end 109.6264 -198.221346)
		(width 0.13208)
		(layer "F.Cu")
		(net "UART_PEX1_CLI_CP2108_TX")
	)
	(segment
		(start 108.15828 -197.501256)
		(end 109.6264 -197.501256)
		(width 0.13208)
		(layer "F.Cu")
		(net "UART_PEX1_CLI_CP2108_TX")
	)
	(segment
		(start 109.6264 -198.221346)
		(end 109.219746 -198.628)
		(width 0.13208)
		(layer "F.Cu")
		(net "UART_PEX1_CLI_CP2108_TX")
	)
	(segment
		(start 108.483654 -198.628)
		(end 108.204 -198.907654)
		(width 0.13208)
		(layer "F.Cu")
		(net "UART_PEX1_CLI_CP2108_TX")
	)
	(via
		(at 109.6264 -197.501256)
		(size 0.762)
		(drill 0.381)
		(layers "F.Cu" "B.Cu")
		(net "UART_PEX1_CLI_CP2108_TX")
	)
	(segment
		(start 94.1324 -197.7898)
		(end 94.1324 -198.79945)
		(width 0.13208)
		(layer "F.Cu")
		(net "UART_PEX3_CLI_BUF_R_TX")
	)
	(segment
		(start 70.906894 -219.5576)
		(end 69.9516 -219.5576)
		(width 0.13208)
		(layer "F.Cu")
		(net "UART_PEX3_CLI_BUF_R_TX")
	)
	(segment
		(start 94.1324 -198.79945)
		(end 95.07855 -199.7456)
		(width 0.13208)
		(layer "F.Cu")
		(net "UART_PEX3_CLI_BUF_R_TX")
	)
	(segment
		(start 71.247 -219.897706)
		(end 70.906894 -219.5576)
		(width 0.13208)
		(layer "F.Cu")
		(net "UART_PEX3_CLI_BUF_R_TX")
	)
	(segment
		(start 92.9259 -196.5833)
		(end 94.1324 -197.7898)
		(width 0.13208)
		(layer "F.Cu")
		(net "UART_PEX3_CLI_BUF_R_TX")
	)
	(via
		(at 108.2802 -202.5396)
		(size 0.508)
		(drill 0.254)
		(layers "F.Cu" "B.Cu")
		(net "UART_PEX3_CLI_BUF_R_TX")
	)
	(via
		(at 92.9259 -196.5833)
		(size 0.508)
		(drill 0.254)
		(layers "F.Cu" "B.Cu")
		(net "UART_PEX3_CLI_BUF_R_TX")
	)
	(via
		(at 69.9516 -219.5576)
		(size 0.508)
		(drill 0.254)
		(layers "F.Cu" "B.Cu")
		(net "UART_PEX3_CLI_BUF_R_TX")
	)
	(via
		(at 71.10603 -218.40317)
		(size 0.6604)
		(drill 0.3302)
		(layers "F.Cu" "B.Cu")
		(net "UART_PEX3_CLI_BUF_R_TX")
	)
	(segment
		(start 112.7252 -208.5848)
		(end 113.9952 -208.5848)
		(width 0.13208)
		(layer "B.Cu")
		(net "UART_PEX3_CLI_BUF_R_TX")
	)
	(segment
		(start 125.2474 -216.4842)
		(end 127.7874 -216.4842)
		(width 0.13208)
		(layer "B.Cu")
		(net "UART_PEX3_CLI_BUF_R_TX")
	)
	(segment
		(start 132.427472 -215.744806)
		(end 132.539486 -215.85682)
		(width 0.13208)
		(layer "B.Cu")
		(net "UART_PEX3_CLI_BUF_R_TX")
	)
	(segment
		(start 121.3104 -215.9)
		(end 124.6632 -215.9)
		(width 0.13208)
		(layer "B.Cu")
		(net "UART_PEX3_CLI_BUF_R_TX")
	)
	(segment
		(start 113.9952 -208.5848)
		(end 121.3104 -215.9)
		(width 0.13208)
		(layer "B.Cu")
		(net "UART_PEX3_CLI_BUF_R_TX")
	)
	(segment
		(start 71.10603 -218.40317)
		(end 69.9516 -219.5576)
		(width 0.13208)
		(layer "B.Cu")
		(net "UART_PEX3_CLI_BUF_R_TX")
	)
	(segment
		(start 108.2802 -204.1398)
		(end 112.7252 -208.5848)
		(width 0.13208)
		(layer "B.Cu")
		(net "UART_PEX3_CLI_BUF_R_TX")
	)
	(segment
		(start 128.526794 -215.744806)
		(end 128.986534 -215.744806)
		(width 0.13208)
		(layer "B.Cu")
		(net "UART_PEX3_CLI_BUF_R_TX")
	)
	(segment
		(start 124.6632 -215.9)
		(end 125.2474 -216.4842)
		(width 0.13208)
		(layer "B.Cu")
		(net "UART_PEX3_CLI_BUF_R_TX")
	)
	(segment
		(start 128.986534 -215.744806)
		(end 132.427472 -215.744806)
		(width 0.13208)
		(layer "B.Cu")
		(net "UART_PEX3_CLI_BUF_R_TX")
	)
	(segment
		(start 92.9259 -196.5833)
		(end 71.10603 -218.40317)
		(width 0.13208)
		(layer "B.Cu")
		(net "UART_PEX3_CLI_BUF_R_TX")
	)
	(segment
		(start 127.7874 -216.4842)
		(end 128.526794 -215.744806)
		(width 0.13208)
		(layer "B.Cu")
		(net "UART_PEX3_CLI_BUF_R_TX")
	)
	(segment
		(start 108.2802 -202.5396)
		(end 108.2802 -204.1398)
		(width 0.13208)
		(layer "B.Cu")
		(net "UART_PEX3_CLI_BUF_R_TX")
	)
	(segment
		(start 103.0351 -196.5833)
		(end 108.2802 -201.8284)
		(width 0.15494)
		(layer "In7.Cu")
		(net "UART_PEX3_CLI_BUF_R_TX")
	)
	(segment
		(start 92.9259 -196.5833)
		(end 103.0351 -196.5833)
		(width 0.15494)
		(layer "In7.Cu")
		(net "UART_PEX3_CLI_BUF_R_TX")
	)
	(segment
		(start 108.2802 -201.8284)
		(end 108.2802 -202.5396)
		(width 0.15494)
		(layer "In7.Cu")
		(net "UART_PEX3_CLI_BUF_R_TX")
	)
	(segment
		(start 98.510344 -190.001144)
		(end 99.25812 -190.001144)
		(width 0.13208)
		(layer "F.Cu")
		(net "UART_PEX2_CLI_CP2108_RX")
	)
	(segment
		(start 96.306894 -189.3062)
		(end 96.611694 -189.0014)
		(width 0.13208)
		(layer "F.Cu")
		(net "UART_PEX2_CLI_CP2108_RX")
	)
	(segment
		(start 97.5106 -189.0014)
		(end 98.510344 -190.001144)
		(width 0.13208)
		(layer "F.Cu")
		(net "UART_PEX2_CLI_CP2108_RX")
	)
	(segment
		(start 96.611694 -189.0014)
		(end 97.5106 -189.0014)
		(width 0.13208)
		(layer "F.Cu")
		(net "UART_PEX2_CLI_CP2108_RX")
	)
	(via
		(at 97.5106 -189.0014)
		(size 0.762)
		(drill 0.381)
		(layers "F.Cu" "B.Cu")
		(net "UART_PEX2_CLI_CP2108_RX")
	)
	(segment
		(start 106.426 -200.4822)
		(end 106.7816 -200.8378)
		(width 0.13208)
		(layer "F.Cu")
		(net "UART_PEX1_CLI_CP2108_RX")
	)
	(segment
		(start 106.7816 -200.8378)
		(end 106.7816 -202.066906)
		(width 0.13208)
		(layer "F.Cu")
		(net "UART_PEX1_CLI_CP2108_RX")
	)
	(segment
		(start 107.458256 -198.865744)
		(end 107.272582 -199.051418)
		(width 0.13208)
		(layer "F.Cu")
		(net "UART_PEX1_CLI_CP2108_RX")
	)
	(segment
		(start 106.688636 -199.051418)
		(end 106.426 -199.314054)
		(width 0.13208)
		(layer "F.Cu")
		(net "UART_PEX1_CLI_CP2108_RX")
	)
	(segment
		(start 106.426 -199.314054)
		(end 106.426 -200.4822)
		(width 0.13208)
		(layer "F.Cu")
		(net "UART_PEX1_CLI_CP2108_RX")
	)
	(segment
		(start 107.272582 -199.051418)
		(end 106.688636 -199.051418)
		(width 0.13208)
		(layer "F.Cu")
		(net "UART_PEX1_CLI_CP2108_RX")
	)
	(segment
		(start 107.458256 -198.20128)
		(end 107.458256 -198.865744)
		(width 0.13208)
		(layer "F.Cu")
		(net "UART_PEX1_CLI_CP2108_RX")
	)
	(via
		(at 106.7816 -200.8378)
		(size 0.762)
		(drill 0.381)
		(layers "F.Cu" "B.Cu")
		(net "UART_PEX1_CLI_CP2108_RX")
	)
	(segment
		(start 63.109094 -212.5472)
		(end 64.0334 -212.5472)
		(width 0.13208)
		(layer "F.Cu")
		(net "UART_PEX2_CLI_BUF_R_TX")
	)
	(segment
		(start 95.51035 -190.5)
		(end 94.5642 -190.5)
		(width 0.13208)
		(layer "F.Cu")
		(net "UART_PEX2_CLI_BUF_R_TX")
	)
	(via
		(at 94.5642 -190.5)
		(size 0.508)
		(drill 0.254)
		(layers "F.Cu" "B.Cu")
		(net "UART_PEX2_CLI_BUF_R_TX")
	)
	(via
		(at 121.8438 -215.2904)
		(size 0.508)
		(drill 0.254)
		(layers "F.Cu" "B.Cu")
		(net "UART_PEX2_CLI_BUF_R_TX")
	)
	(via
		(at 64.0334 -212.5472)
		(size 0.508)
		(drill 0.254)
		(layers "F.Cu" "B.Cu")
		(net "UART_PEX2_CLI_BUF_R_TX")
	)
	(via
		(at 92.2274 -190.5)
		(size 0.6604)
		(drill 0.3302)
		(layers "F.Cu" "B.Cu")
		(net "UART_PEX2_CLI_BUF_R_TX")
	)
	(segment
		(start 131.813554 -213.524846)
		(end 132.630164 -213.524846)
		(width 0.13208)
		(layer "B.Cu")
		(net "UART_PEX2_CLI_BUF_R_TX")
	)
	(segment
		(start 128.084834 -214.444834)
		(end 128.986534 -214.444834)
		(width 0.13208)
		(layer "B.Cu")
		(net "UART_PEX2_CLI_BUF_R_TX")
	)
	(segment
		(start 86.0806 -190.5)
		(end 64.0334 -212.5472)
		(width 0.13208)
		(layer "B.Cu")
		(net "UART_PEX2_CLI_BUF_R_TX")
	)
	(segment
		(start 92.2274 -190.5)
		(end 86.0806 -190.5)
		(width 0.13208)
		(layer "B.Cu")
		(net "UART_PEX2_CLI_BUF_R_TX")
	)
	(segment
		(start 121.8438 -215.2904)
		(end 123.5964 -213.5378)
		(width 0.13208)
		(layer "B.Cu")
		(net "UART_PEX2_CLI_BUF_R_TX")
	)
	(segment
		(start 128.986534 -214.444834)
		(end 130.893566 -214.444834)
		(width 0.13208)
		(layer "B.Cu")
		(net "UART_PEX2_CLI_BUF_R_TX")
	)
	(segment
		(start 127.1778 -213.5378)
		(end 128.084834 -214.444834)
		(width 0.13208)
		(layer "B.Cu")
		(net "UART_PEX2_CLI_BUF_R_TX")
	)
	(segment
		(start 94.5642 -190.5)
		(end 92.2274 -190.5)
		(width 0.13208)
		(layer "B.Cu")
		(net "UART_PEX2_CLI_BUF_R_TX")
	)
	(segment
		(start 130.893566 -214.444834)
		(end 131.813554 -213.524846)
		(width 0.13208)
		(layer "B.Cu")
		(net "UART_PEX2_CLI_BUF_R_TX")
	)
	(segment
		(start 123.5964 -213.5378)
		(end 127.1778 -213.5378)
		(width 0.13208)
		(layer "B.Cu")
		(net "UART_PEX2_CLI_BUF_R_TX")
	)
	(segment
		(start 110.916466 -201.315066)
		(end 116.586 -206.9846)
		(width 0.15494)
		(layer "In7.Cu")
		(net "UART_PEX2_CLI_BUF_R_TX")
	)
	(segment
		(start 108.3056 -190.5)
		(end 110.916466 -193.110866)
		(width 0.15494)
		(layer "In7.Cu")
		(net "UART_PEX2_CLI_BUF_R_TX")
	)
	(segment
		(start 120.5738 -215.2904)
		(end 121.8438 -215.2904)
		(width 0.15494)
		(layer "In7.Cu")
		(net "UART_PEX2_CLI_BUF_R_TX")
	)
	(segment
		(start 116.586 -211.3026)
		(end 120.5738 -215.2904)
		(width 0.15494)
		(layer "In7.Cu")
		(net "UART_PEX2_CLI_BUF_R_TX")
	)
	(segment
		(start 110.916466 -193.110866)
		(end 110.916466 -201.315066)
		(width 0.15494)
		(layer "In7.Cu")
		(net "UART_PEX2_CLI_BUF_R_TX")
	)
	(segment
		(start 94.5642 -190.5)
		(end 108.3056 -190.5)
		(width 0.15494)
		(layer "In7.Cu")
		(net "UART_PEX2_CLI_BUF_R_TX")
	)
	(segment
		(start 116.586 -206.9846)
		(end 116.586 -211.3026)
		(width 0.15494)
		(layer "In7.Cu")
		(net "UART_PEX2_CLI_BUF_R_TX")
	)
	(segment
		(start 105.7148 -199.8218)
		(end 105.2322 -199.8218)
		(width 0.13208)
		(layer "F.Cu")
		(net "UART_PEX0_CLI_CP2108_TX")
	)
	(segment
		(start 103.958136 -198.547736)
		(end 103.958136 -198.20128)
		(width 0.13208)
		(layer "F.Cu")
		(net "UART_PEX0_CLI_CP2108_TX")
	)
	(segment
		(start 105.7148 -199.8218)
		(end 105.7148 -202.06335)
		(width 0.13208)
		(layer "F.Cu")
		(net "UART_PEX0_CLI_CP2108_TX")
	)
	(segment
		(start 105.2322 -199.8218)
		(end 103.958136 -198.547736)
		(width 0.13208)
		(layer "F.Cu")
		(net "UART_PEX0_CLI_CP2108_TX")
	)
	(via
		(at 105.7148 -199.8218)
		(size 0.762)
		(drill 0.381)
		(layers "F.Cu" "B.Cu")
		(net "UART_PEX0_CLI_CP2108_TX")
	)
	(segment
		(start 238.887 -82.604102)
		(end 238.590074 -82.307176)
		(width 0.13462)
		(layer "F.Cu")
		(net "USB2_CP2108_CLI_DN")
	)
	(segment
		(start 238.324898 -83.951318)
		(end 238.324898 -83.494626)
		(width 0.13462)
		(layer "F.Cu")
		(net "USB2_CP2108_CLI_DN")
	)
	(segment
		(start 99.497642 -199.7837)
		(end 99.0981 -200.183242)
		(width 0.13462)
		(layer "F.Cu")
		(net "USB2_CP2108_CLI_DN")
	)
	(segment
		(start 238.324898 -83.494626)
		(end 238.887 -82.932524)
		(width 0.13462)
		(layer "F.Cu")
		(net "USB2_CP2108_CLI_DN")
	)
	(segment
		(start 238.887 -82.932524)
		(end 238.887 -82.604102)
		(width 0.13462)
		(layer "F.Cu")
		(net "USB2_CP2108_CLI_DN")
	)
	(segment
		(start 99.0981 -201.06386)
		(end 98.80981 -201.35215)
		(width 0.13462)
		(layer "F.Cu")
		(net "USB2_CP2108_CLI_DN")
	)
	(segment
		(start 100.45827 -198.527416)
		(end 100.57638 -198.645526)
		(width 0.13462)
		(layer "F.Cu")
		(net "USB2_CP2108_CLI_DN")
	)
	(segment
		(start 100.45827 -198.20128)
		(end 100.45827 -198.527416)
		(width 0.13462)
		(layer "F.Cu")
		(net "USB2_CP2108_CLI_DN")
	)
	(segment
		(start 100.57638 -199.136508)
		(end 99.929188 -199.7837)
		(width 0.13462)
		(layer "F.Cu")
		(net "USB2_CP2108_CLI_DN")
	)
	(segment
		(start 100.57638 -198.645526)
		(end 100.57638 -199.136508)
		(width 0.13462)
		(layer "F.Cu")
		(net "USB2_CP2108_CLI_DN")
	)
	(segment
		(start 99.0981 -200.183242)
		(end 99.0981 -201.06386)
		(width 0.13462)
		(layer "F.Cu")
		(net "USB2_CP2108_CLI_DN")
	)
	(segment
		(start 99.929188 -199.7837)
		(end 99.497642 -199.7837)
		(width 0.13462)
		(layer "F.Cu")
		(net "USB2_CP2108_CLI_DN")
	)
	(segment
		(start 139.08405 -86.83244)
		(end 139.19835 -86.71814)
		(width 0.1651)
		(layer "In9.Cu")
		(net "USB2_CP2108_CLI_DN")
	)
	(segment
		(start 214.43315 -85.79104)
		(end 214.92845 -85.79104)
		(width 0.1651)
		(layer "In9.Cu")
		(net "USB2_CP2108_CLI_DN")
	)
	(segment
		(start 238.880904 -82.016346)
		(end 238.590074 -82.307176)
		(width 0.1651)
		(layer "In9.Cu")
		(net "USB2_CP2108_CLI_DN")
	)
	(segment
		(start 91.50604 -194.98945)
		(end 91.50604 -194.49415)
		(width 0.1651)
		(layer "In9.Cu")
		(net "USB2_CP2108_CLI_DN")
	)
	(segment
		(start 91.39174 -194.37985)
		(end 91.39174 -189.80404)
		(width 0.1651)
		(layer "In9.Cu")
		(net "USB2_CP2108_CLI_DN")
	)
	(segment
		(start 237.21695 -81.65084)
		(end 237.71225 -81.65084)
		(width 0.1651)
		(layer "In9.Cu")
		(net "USB2_CP2108_CLI_DN")
	)
	(segment
		(start 91.50604 -194.49415)
		(end 91.39174 -194.37985)
		(width 0.1651)
		(layer "In9.Cu")
		(net "USB2_CP2108_CLI_DN")
	)
	(segment
		(start 211.88045 -85.67674)
		(end 211.99475 -85.79104)
		(width 0.1651)
		(layer "In9.Cu")
		(net "USB2_CP2108_CLI_DN")
	)
	(segment
		(start 121.94794 -108.42244)
		(end 121.94794 -106.11104)
		(width 0.1651)
		(layer "In9.Cu")
		(net "USB2_CP2108_CLI_DN")
	)
	(segment
		(start 234.93095 -80.97774)
		(end 235.84916 -80.97774)
		(width 0.1651)
		(layer "In9.Cu")
		(net "USB2_CP2108_CLI_DN")
	)
	(segment
		(start 141.86535 -86.71814)
		(end 142.36065 -86.71814)
		(width 0.1651)
		(layer "In9.Cu")
		(net "USB2_CP2108_CLI_DN")
	)
	(segment
		(start 98.77044 -202.20686)
		(end 93.33484 -202.20686)
		(width 0.1651)
		(layer "In9.Cu")
		(net "USB2_CP2108_CLI_DN")
	)
	(segment
		(start 213.70925 -85.79104)
		(end 213.82355 -85.67674)
		(width 0.1651)
		(layer "In9.Cu")
		(net "USB2_CP2108_CLI_DN")
	)
	(segment
		(start 111.356394 -119.013986)
		(end 111.518192 -119.013986)
		(width 0.1651)
		(layer "In9.Cu")
		(net "USB2_CP2108_CLI_DN")
	)
	(segment
		(start 91.50604 -195.71335)
		(end 91.39174 -195.59905)
		(width 0.1651)
		(layer "In9.Cu")
		(net "USB2_CP2108_CLI_DN")
	)
	(segment
		(start 108.769658 -121.600722)
		(end 108.931202 -121.600722)
		(width 0.1651)
		(layer "In9.Cu")
		(net "USB2_CP2108_CLI_DN")
	)
	(segment
		(start 111.868712 -118.501668)
		(end 121.94794 -108.42244)
		(width 0.1651)
		(layer "In9.Cu")
		(net "USB2_CP2108_CLI_DN")
	)
	(segment
		(start 107.22864 -123.14174)
		(end 108.769658 -121.600722)
		(width 0.1651)
		(layer "In9.Cu")
		(net "USB2_CP2108_CLI_DN")
	)
	(segment
		(start 94.82074 -174.56404)
		(end 102.56774 -166.81704)
		(width 0.1651)
		(layer "In9.Cu")
		(net "USB2_CP2108_CLI_DN")
	)
	(segment
		(start 210.66125 -85.67674)
		(end 210.77555 -85.79104)
		(width 0.1651)
		(layer "In9.Cu")
		(net "USB2_CP2108_CLI_DN")
	)
	(segment
		(start 139.92225 -86.71814)
		(end 140.03655 -86.83244)
		(width 0.1651)
		(layer "In9.Cu")
		(net "USB2_CP2108_CLI_DN")
	)
	(segment
		(start 91.39174 -195.10375)
		(end 91.50604 -194.98945)
		(width 0.1651)
		(layer "In9.Cu")
		(net "USB2_CP2108_CLI_DN")
	)
	(segment
		(start 132.56514 -95.49384)
		(end 132.56514 -88.55964)
		(width 0.1651)
		(layer "In9.Cu")
		(net "USB2_CP2108_CLI_DN")
	)
	(segment
		(start 93.33484 -202.20686)
		(end 91.39174 -200.26376)
		(width 0.1651)
		(layer "In9.Cu")
		(net "USB2_CP2108_CLI_DN")
	)
	(segment
		(start 91.39174 -197.54215)
		(end 91.50604 -197.42785)
		(width 0.1651)
		(layer "In9.Cu")
		(net "USB2_CP2108_CLI_DN")
	)
	(segment
		(start 138.58875 -86.83244)
		(end 139.08405 -86.83244)
		(width 0.1651)
		(layer "In9.Cu")
		(net "USB2_CP2108_CLI_DN")
	)
	(segment
		(start 194.80784 -87.86114)
		(end 195.51904 -87.14994)
		(width 0.1651)
		(layer "In9.Cu")
		(net "USB2_CP2108_CLI_DN")
	)
	(segment
		(start 104.84104 -123.14174)
		(end 107.22864 -123.14174)
		(width 0.1651)
		(layer "In9.Cu")
		(net "USB2_CP2108_CLI_DN")
	)
	(segment
		(start 110.655862 -119.876316)
		(end 111.006382 -119.525796)
		(width 0.1651)
		(layer "In9.Cu")
		(net "USB2_CP2108_CLI_DN")
	)
	(segment
		(start 141.75105 -86.83244)
		(end 141.86535 -86.71814)
		(width 0.1651)
		(layer "In9.Cu")
		(net "USB2_CP2108_CLI_DN")
	)
	(segment
		(start 237.71225 -81.65084)
		(end 237.82655 -81.53654)
		(width 0.1651)
		(layer "In9.Cu")
		(net "USB2_CP2108_CLI_DN")
	)
	(segment
		(start 110.144052 -120.388126)
		(end 110.144052 -120.226328)
		(width 0.1651)
		(layer "In9.Cu")
		(net "USB2_CP2108_CLI_DN")
	)
	(segment
		(start 236.40796 -81.53654)
		(end 237.10265 -81.53654)
		(width 0.1651)
		(layer "In9.Cu")
		(net "USB2_CP2108_CLI_DN")
	)
	(segment
		(start 91.50604 -196.93255)
		(end 91.39174 -196.81825)
		(width 0.1651)
		(layer "In9.Cu")
		(net "USB2_CP2108_CLI_DN")
	)
	(segment
		(start 212.60435 -85.67674)
		(end 213.09965 -85.67674)
		(width 0.1651)
		(layer "In9.Cu")
		(net "USB2_CP2108_CLI_DN")
	)
	(segment
		(start 213.09965 -85.67674)
		(end 213.21395 -85.79104)
		(width 0.1651)
		(layer "In9.Cu")
		(net "USB2_CP2108_CLI_DN")
	)
	(segment
		(start 146.44116 -87.86114)
		(end 194.80784 -87.86114)
		(width 0.1651)
		(layer "In9.Cu")
		(net "USB2_CP2108_CLI_DN")
	)
	(segment
		(start 98.80981 -201.35215)
		(end 99.10064 -201.64298)
		(width 0.1651)
		(layer "In9.Cu")
		(net "USB2_CP2108_CLI_DN")
	)
	(segment
		(start 138.47445 -86.71814)
		(end 138.58875 -86.83244)
		(width 0.1651)
		(layer "In9.Cu")
		(net "USB2_CP2108_CLI_DN")
	)
	(segment
		(start 142.97025 -86.83244)
		(end 143.08455 -86.71814)
		(width 0.1651)
		(layer "In9.Cu")
		(net "USB2_CP2108_CLI_DN")
	)
	(segment
		(start 140.03655 -86.83244)
		(end 140.53185 -86.83244)
		(width 0.1651)
		(layer "In9.Cu")
		(net "USB2_CP2108_CLI_DN")
	)
	(segment
		(start 143.08455 -86.71814)
		(end 145.29816 -86.71814)
		(width 0.1651)
		(layer "In9.Cu")
		(net "USB2_CP2108_CLI_DN")
	)
	(segment
		(start 238.880904 -81.66354)
		(end 238.880904 -82.016346)
		(width 0.1651)
		(layer "In9.Cu")
		(net "USB2_CP2108_CLI_DN")
	)
	(segment
		(start 91.39174 -196.81825)
		(end 91.39174 -196.32295)
		(width 0.1651)
		(layer "In9.Cu")
		(net "USB2_CP2108_CLI_DN")
	)
	(segment
		(start 237.10265 -81.53654)
		(end 237.21695 -81.65084)
		(width 0.1651)
		(layer "In9.Cu")
		(net "USB2_CP2108_CLI_DN")
	)
	(segment
		(start 234.20705 -80.97774)
		(end 234.32135 -81.09204)
		(width 0.1651)
		(layer "In9.Cu")
		(net "USB2_CP2108_CLI_DN")
	)
	(segment
		(start 94.82074 -186.37504)
		(end 94.82074 -174.56404)
		(width 0.1651)
		(layer "In9.Cu")
		(net "USB2_CP2108_CLI_DN")
	)
	(segment
		(start 91.39174 -189.80404)
		(end 94.82074 -186.37504)
		(width 0.1651)
		(layer "In9.Cu")
		(net "USB2_CP2108_CLI_DN")
	)
	(segment
		(start 139.19835 -86.71814)
		(end 139.92225 -86.71814)
		(width 0.1651)
		(layer "In9.Cu")
		(net "USB2_CP2108_CLI_DN")
	)
	(segment
		(start 231.64165 -80.97774)
		(end 231.75595 -81.09204)
		(width 0.1651)
		(layer "In9.Cu")
		(net "USB2_CP2108_CLI_DN")
	)
	(segment
		(start 213.21395 -85.79104)
		(end 213.70925 -85.79104)
		(width 0.1651)
		(layer "In9.Cu")
		(net "USB2_CP2108_CLI_DN")
	)
	(segment
		(start 111.868712 -118.663466)
		(end 111.868712 -118.501668)
		(width 0.1651)
		(layer "In9.Cu")
		(net "USB2_CP2108_CLI_DN")
	)
	(segment
		(start 214.92845 -85.79104)
		(end 215.04275 -85.67674)
		(width 0.1651)
		(layer "In9.Cu")
		(net "USB2_CP2108_CLI_DN")
	)
	(segment
		(start 110.494064 -119.876316)
		(end 110.655862 -119.876316)
		(width 0.1651)
		(layer "In9.Cu")
		(net "USB2_CP2108_CLI_DN")
	)
	(segment
		(start 132.56514 -88.55964)
		(end 134.40664 -86.71814)
		(width 0.1651)
		(layer "In9.Cu")
		(net "USB2_CP2108_CLI_DN")
	)
	(segment
		(start 219.69476 -85.67674)
		(end 220.05036 -86.03234)
		(width 0.1651)
		(layer "In9.Cu")
		(net "USB2_CP2108_CLI_DN")
	)
	(segment
		(start 99.10064 -201.64298)
		(end 99.10064 -201.87666)
		(width 0.1651)
		(layer "In9.Cu")
		(net "USB2_CP2108_CLI_DN")
	)
	(segment
		(start 211.99475 -85.79104)
		(end 212.49005 -85.79104)
		(width 0.1651)
		(layer "In9.Cu")
		(net "USB2_CP2108_CLI_DN")
	)
	(segment
		(start 140.64615 -86.71814)
		(end 141.14145 -86.71814)
		(width 0.1651)
		(layer "In9.Cu")
		(net "USB2_CP2108_CLI_DN")
	)
	(segment
		(start 234.81665 -81.09204)
		(end 234.93095 -80.97774)
		(width 0.1651)
		(layer "In9.Cu")
		(net "USB2_CP2108_CLI_DN")
	)
	(segment
		(start 109.793532 -120.738646)
		(end 110.144052 -120.388126)
		(width 0.1651)
		(layer "In9.Cu")
		(net "USB2_CP2108_CLI_DN")
	)
	(segment
		(start 232.36555 -80.97774)
		(end 234.20705 -80.97774)
		(width 0.1651)
		(layer "In9.Cu")
		(net "USB2_CP2108_CLI_DN")
	)
	(segment
		(start 205.06944 -87.14994)
		(end 206.54264 -85.67674)
		(width 0.1651)
		(layer "In9.Cu")
		(net "USB2_CP2108_CLI_DN")
	)
	(segment
		(start 111.006382 -119.525796)
		(end 111.006382 -119.363998)
		(width 0.1651)
		(layer "In9.Cu")
		(net "USB2_CP2108_CLI_DN")
	)
	(segment
		(start 121.94794 -106.11104)
		(end 132.56514 -95.49384)
		(width 0.1651)
		(layer "In9.Cu")
		(net "USB2_CP2108_CLI_DN")
	)
	(segment
		(start 230.72344 -80.97774)
		(end 231.64165 -80.97774)
		(width 0.1651)
		(layer "In9.Cu")
		(net "USB2_CP2108_CLI_DN")
	)
	(segment
		(start 102.56774 -166.81704)
		(end 102.56774 -125.41504)
		(width 0.1651)
		(layer "In9.Cu")
		(net "USB2_CP2108_CLI_DN")
	)
	(segment
		(start 91.39174 -195.59905)
		(end 91.39174 -195.10375)
		(width 0.1651)
		(layer "In9.Cu")
		(net "USB2_CP2108_CLI_DN")
	)
	(segment
		(start 215.04275 -85.67674)
		(end 219.69476 -85.67674)
		(width 0.1651)
		(layer "In9.Cu")
		(net "USB2_CP2108_CLI_DN")
	)
	(segment
		(start 91.39174 -196.32295)
		(end 91.50604 -196.20865)
		(width 0.1651)
		(layer "In9.Cu")
		(net "USB2_CP2108_CLI_DN")
	)
	(segment
		(start 142.36065 -86.71814)
		(end 142.47495 -86.83244)
		(width 0.1651)
		(layer "In9.Cu")
		(net "USB2_CP2108_CLI_DN")
	)
	(segment
		(start 214.31885 -85.67674)
		(end 214.43315 -85.79104)
		(width 0.1651)
		(layer "In9.Cu")
		(net "USB2_CP2108_CLI_DN")
	)
	(segment
		(start 211.38515 -85.67674)
		(end 211.88045 -85.67674)
		(width 0.1651)
		(layer "In9.Cu")
		(net "USB2_CP2108_CLI_DN")
	)
	(segment
		(start 237.82655 -81.53654)
		(end 238.753904 -81.53654)
		(width 0.1651)
		(layer "In9.Cu")
		(net "USB2_CP2108_CLI_DN")
	)
	(segment
		(start 109.631734 -120.738646)
		(end 109.793532 -120.738646)
		(width 0.1651)
		(layer "In9.Cu")
		(net "USB2_CP2108_CLI_DN")
	)
	(segment
		(start 206.54264 -85.67674)
		(end 210.66125 -85.67674)
		(width 0.1651)
		(layer "In9.Cu")
		(net "USB2_CP2108_CLI_DN")
	)
	(segment
		(start 110.144052 -120.226328)
		(end 110.494064 -119.876316)
		(width 0.1651)
		(layer "In9.Cu")
		(net "USB2_CP2108_CLI_DN")
	)
	(segment
		(start 235.84916 -80.97774)
		(end 236.40796 -81.53654)
		(width 0.1651)
		(layer "In9.Cu")
		(net "USB2_CP2108_CLI_DN")
	)
	(segment
		(start 91.39174 -198.03745)
		(end 91.39174 -197.54215)
		(width 0.1651)
		(layer "In9.Cu")
		(net "USB2_CP2108_CLI_DN")
	)
	(segment
		(start 220.05036 -86.03234)
		(end 225.66884 -86.03234)
		(width 0.1651)
		(layer "In9.Cu")
		(net "USB2_CP2108_CLI_DN")
	)
	(segment
		(start 134.40664 -86.71814)
		(end 138.47445 -86.71814)
		(width 0.1651)
		(layer "In9.Cu")
		(net "USB2_CP2108_CLI_DN")
	)
	(segment
		(start 91.50604 -198.15175)
		(end 91.39174 -198.03745)
		(width 0.1651)
		(layer "In9.Cu")
		(net "USB2_CP2108_CLI_DN")
	)
	(segment
		(start 102.56774 -125.41504)
		(end 104.84104 -123.14174)
		(width 0.1651)
		(layer "In9.Cu")
		(net "USB2_CP2108_CLI_DN")
	)
	(segment
		(start 91.50604 -196.20865)
		(end 91.50604 -195.71335)
		(width 0.1651)
		(layer "In9.Cu")
		(net "USB2_CP2108_CLI_DN")
	)
	(segment
		(start 142.47495 -86.83244)
		(end 142.97025 -86.83244)
		(width 0.1651)
		(layer "In9.Cu")
		(net "USB2_CP2108_CLI_DN")
	)
	(segment
		(start 111.518192 -119.013986)
		(end 111.868712 -118.663466)
		(width 0.1651)
		(layer "In9.Cu")
		(net "USB2_CP2108_CLI_DN")
	)
	(segment
		(start 91.50604 -198.64705)
		(end 91.50604 -198.15175)
		(width 0.1651)
		(layer "In9.Cu")
		(net "USB2_CP2108_CLI_DN")
	)
	(segment
		(start 213.82355 -85.67674)
		(end 214.31885 -85.67674)
		(width 0.1651)
		(layer "In9.Cu")
		(net "USB2_CP2108_CLI_DN")
	)
	(segment
		(start 210.77555 -85.79104)
		(end 211.27085 -85.79104)
		(width 0.1651)
		(layer "In9.Cu")
		(net "USB2_CP2108_CLI_DN")
	)
	(segment
		(start 108.931202 -121.600722)
		(end 109.281722 -121.250202)
		(width 0.1651)
		(layer "In9.Cu")
		(net "USB2_CP2108_CLI_DN")
	)
	(segment
		(start 212.49005 -85.79104)
		(end 212.60435 -85.67674)
		(width 0.1651)
		(layer "In9.Cu")
		(net "USB2_CP2108_CLI_DN")
	)
	(segment
		(start 141.14145 -86.71814)
		(end 141.25575 -86.83244)
		(width 0.1651)
		(layer "In9.Cu")
		(net "USB2_CP2108_CLI_DN")
	)
	(segment
		(start 231.75595 -81.09204)
		(end 232.25125 -81.09204)
		(width 0.1651)
		(layer "In9.Cu")
		(net "USB2_CP2108_CLI_DN")
	)
	(segment
		(start 195.51904 -87.14994)
		(end 205.06944 -87.14994)
		(width 0.1651)
		(layer "In9.Cu")
		(net "USB2_CP2108_CLI_DN")
	)
	(segment
		(start 145.29816 -86.71814)
		(end 146.44116 -87.86114)
		(width 0.1651)
		(layer "In9.Cu")
		(net "USB2_CP2108_CLI_DN")
	)
	(segment
		(start 109.281722 -121.250202)
		(end 109.281722 -121.088658)
		(width 0.1651)
		(layer "In9.Cu")
		(net "USB2_CP2108_CLI_DN")
	)
	(segment
		(start 211.27085 -85.79104)
		(end 211.38515 -85.67674)
		(width 0.1651)
		(layer "In9.Cu")
		(net "USB2_CP2108_CLI_DN")
	)
	(segment
		(start 141.25575 -86.83244)
		(end 141.75105 -86.83244)
		(width 0.1651)
		(layer "In9.Cu")
		(net "USB2_CP2108_CLI_DN")
	)
	(segment
		(start 140.53185 -86.83244)
		(end 140.64615 -86.71814)
		(width 0.1651)
		(layer "In9.Cu")
		(net "USB2_CP2108_CLI_DN")
	)
	(segment
		(start 99.10064 -201.87666)
		(end 98.77044 -202.20686)
		(width 0.1651)
		(layer "In9.Cu")
		(net "USB2_CP2108_CLI_DN")
	)
	(segment
		(start 109.281722 -121.088658)
		(end 109.631734 -120.738646)
		(width 0.1651)
		(layer "In9.Cu")
		(net "USB2_CP2108_CLI_DN")
	)
	(segment
		(start 111.006382 -119.363998)
		(end 111.356394 -119.013986)
		(width 0.1651)
		(layer "In9.Cu")
		(net "USB2_CP2108_CLI_DN")
	)
	(segment
		(start 225.66884 -86.03234)
		(end 230.72344 -80.97774)
		(width 0.1651)
		(layer "In9.Cu")
		(net "USB2_CP2108_CLI_DN")
	)
	(segment
		(start 238.753904 -81.53654)
		(end 238.880904 -81.66354)
		(width 0.1651)
		(layer "In9.Cu")
		(net "USB2_CP2108_CLI_DN")
	)
	(segment
		(start 91.39174 -200.26376)
		(end 91.39174 -198.76135)
		(width 0.1651)
		(layer "In9.Cu")
		(net "USB2_CP2108_CLI_DN")
	)
	(segment
		(start 91.39174 -198.76135)
		(end 91.50604 -198.64705)
		(width 0.1651)
		(layer "In9.Cu")
		(net "USB2_CP2108_CLI_DN")
	)
	(segment
		(start 234.32135 -81.09204)
		(end 234.81665 -81.09204)
		(width 0.1651)
		(layer "In9.Cu")
		(net "USB2_CP2108_CLI_DN")
	)
	(segment
		(start 232.25125 -81.09204)
		(end 232.36555 -80.97774)
		(width 0.1651)
		(layer "In9.Cu")
		(net "USB2_CP2108_CLI_DN")
	)
	(segment
		(start 91.50604 -197.42785)
		(end 91.50604 -196.93255)
		(width 0.1651)
		(layer "In9.Cu")
		(net "USB2_CP2108_CLI_DN")
	)
	(segment
		(start 100.8507 -199.2503)
		(end 100.04298 -200.05802)
		(width 0.13462)
		(layer "F.Cu")
		(net "USB2_CP2108_CLI_DP")
	)
	(segment
		(start 100.04298 -200.05802)
		(end 99.611434 -200.05802)
		(width 0.13462)
		(layer "F.Cu")
		(net "USB2_CP2108_CLI_DP")
	)
	(segment
		(start 99.37242 -201.05116)
		(end 99.67341 -201.35215)
		(width 0.13462)
		(layer "F.Cu")
		(net "USB2_CP2108_CLI_DP")
	)
	(segment
		(start 239.16132 -82.92592)
		(end 239.16132 -82.59953)
		(width 0.13462)
		(layer "F.Cu")
		(net "USB2_CP2108_CLI_DP")
	)
	(segment
		(start 100.958142 -198.533258)
		(end 100.8507 -198.6407)
		(width 0.13462)
		(layer "F.Cu")
		(net "USB2_CP2108_CLI_DP")
	)
	(segment
		(start 239.721898 -83.951318)
		(end 239.721898 -83.486498)
		(width 0.13462)
		(layer "F.Cu")
		(net "USB2_CP2108_CLI_DP")
	)
	(segment
		(start 239.721898 -83.486498)
		(end 239.16132 -82.92592)
		(width 0.13462)
		(layer "F.Cu")
		(net "USB2_CP2108_CLI_DP")
	)
	(segment
		(start 239.16132 -82.59953)
		(end 239.453674 -82.307176)
		(width 0.13462)
		(layer "F.Cu")
		(net "USB2_CP2108_CLI_DP")
	)
	(segment
		(start 100.958142 -198.20128)
		(end 100.958142 -198.533258)
		(width 0.13462)
		(layer "F.Cu")
		(net "USB2_CP2108_CLI_DP")
	)
	(segment
		(start 99.37242 -200.297034)
		(end 99.37242 -201.05116)
		(width 0.13462)
		(layer "F.Cu")
		(net "USB2_CP2108_CLI_DP")
	)
	(segment
		(start 99.611434 -200.05802)
		(end 99.37242 -200.297034)
		(width 0.13462)
		(layer "F.Cu")
		(net "USB2_CP2108_CLI_DP")
	)
	(segment
		(start 100.8507 -198.6407)
		(end 100.8507 -199.2503)
		(width 0.13462)
		(layer "F.Cu")
		(net "USB2_CP2108_CLI_DP")
	)
	(segment
		(start 132.2832 -88.4428)
		(end 132.2832 -95.377)
		(width 0.1651)
		(layer "In9.Cu")
		(net "USB2_CP2108_CLI_DP")
	)
	(segment
		(start 194.691 -87.5792)
		(end 146.558 -87.5792)
		(width 0.1651)
		(layer "In9.Cu")
		(net "USB2_CP2108_CLI_DP")
	)
	(segment
		(start 239.453674 -82.307176)
		(end 239.162844 -82.016346)
		(width 0.1651)
		(layer "In9.Cu")
		(net "USB2_CP2108_CLI_DP")
	)
	(segment
		(start 99.38258 -201.64298)
		(end 99.67341 -201.35215)
		(width 0.1651)
		(layer "In9.Cu")
		(net "USB2_CP2108_CLI_DP")
	)
	(segment
		(start 107.1118 -122.8598)
		(end 104.7242 -122.8598)
		(width 0.1651)
		(layer "In9.Cu")
		(net "USB2_CP2108_CLI_DP")
	)
	(segment
		(start 146.558 -87.5792)
		(end 145.415 -86.4362)
		(width 0.1651)
		(layer "In9.Cu")
		(net "USB2_CP2108_CLI_DP")
	)
	(segment
		(start 134.2898 -86.4362)
		(end 132.2832 -88.4428)
		(width 0.1651)
		(layer "In9.Cu")
		(net "USB2_CP2108_CLI_DP")
	)
	(segment
		(start 102.2858 -166.7002)
		(end 94.5388 -174.4472)
		(width 0.1651)
		(layer "In9.Cu")
		(net "USB2_CP2108_CLI_DP")
	)
	(segment
		(start 235.966 -80.6958)
		(end 230.6066 -80.6958)
		(width 0.1651)
		(layer "In9.Cu")
		(net "USB2_CP2108_CLI_DP")
	)
	(segment
		(start 121.666 -105.9942)
		(end 121.666 -108.3056)
		(width 0.1651)
		(layer "In9.Cu")
		(net "USB2_CP2108_CLI_DP")
	)
	(segment
		(start 206.4258 -85.3948)
		(end 204.9526 -86.868)
		(width 0.1651)
		(layer "In9.Cu")
		(net "USB2_CP2108_CLI_DP")
	)
	(segment
		(start 145.415 -86.4362)
		(end 134.2898 -86.4362)
		(width 0.1651)
		(layer "In9.Cu")
		(net "USB2_CP2108_CLI_DP")
	)
	(segment
		(start 195.4022 -86.868)
		(end 194.691 -87.5792)
		(width 0.1651)
		(layer "In9.Cu")
		(net "USB2_CP2108_CLI_DP")
	)
	(segment
		(start 91.1098 -200.3806)
		(end 93.218 -202.4888)
		(width 0.1651)
		(layer "In9.Cu")
		(net "USB2_CP2108_CLI_DP")
	)
	(segment
		(start 225.552 -85.7504)
		(end 220.1672 -85.7504)
		(width 0.1651)
		(layer "In9.Cu")
		(net "USB2_CP2108_CLI_DP")
	)
	(segment
		(start 239.162844 -82.016346)
		(end 239.162844 -81.5467)
		(width 0.1651)
		(layer "In9.Cu")
		(net "USB2_CP2108_CLI_DP")
	)
	(segment
		(start 219.8116 -85.3948)
		(end 206.4258 -85.3948)
		(width 0.1651)
		(layer "In9.Cu")
		(net "USB2_CP2108_CLI_DP")
	)
	(segment
		(start 99.38258 -201.9935)
		(end 99.38258 -201.64298)
		(width 0.1651)
		(layer "In9.Cu")
		(net "USB2_CP2108_CLI_DP")
	)
	(segment
		(start 94.5388 -186.2582)
		(end 91.1098 -189.6872)
		(width 0.1651)
		(layer "In9.Cu")
		(net "USB2_CP2108_CLI_DP")
	)
	(segment
		(start 238.870744 -81.2546)
		(end 236.5248 -81.2546)
		(width 0.1651)
		(layer "In9.Cu")
		(net "USB2_CP2108_CLI_DP")
	)
	(segment
		(start 98.88728 -202.4888)
		(end 99.38258 -201.9935)
		(width 0.1651)
		(layer "In9.Cu")
		(net "USB2_CP2108_CLI_DP")
	)
	(segment
		(start 104.7242 -122.8598)
		(end 102.2858 -125.2982)
		(width 0.1651)
		(layer "In9.Cu")
		(net "USB2_CP2108_CLI_DP")
	)
	(segment
		(start 230.6066 -80.6958)
		(end 225.552 -85.7504)
		(width 0.1651)
		(layer "In9.Cu")
		(net "USB2_CP2108_CLI_DP")
	)
	(segment
		(start 93.218 -202.4888)
		(end 98.88728 -202.4888)
		(width 0.1651)
		(layer "In9.Cu")
		(net "USB2_CP2108_CLI_DP")
	)
	(segment
		(start 204.9526 -86.868)
		(end 195.4022 -86.868)
		(width 0.1651)
		(layer "In9.Cu")
		(net "USB2_CP2108_CLI_DP")
	)
	(segment
		(start 91.1098 -189.6872)
		(end 91.1098 -200.3806)
		(width 0.1651)
		(layer "In9.Cu")
		(net "USB2_CP2108_CLI_DP")
	)
	(segment
		(start 236.5248 -81.2546)
		(end 235.966 -80.6958)
		(width 0.1651)
		(layer "In9.Cu")
		(net "USB2_CP2108_CLI_DP")
	)
	(segment
		(start 102.2858 -125.2982)
		(end 102.2858 -166.7002)
		(width 0.1651)
		(layer "In9.Cu")
		(net "USB2_CP2108_CLI_DP")
	)
	(segment
		(start 121.666 -108.3056)
		(end 107.1118 -122.8598)
		(width 0.1651)
		(layer "In9.Cu")
		(net "USB2_CP2108_CLI_DP")
	)
	(segment
		(start 220.1672 -85.7504)
		(end 219.8116 -85.3948)
		(width 0.1651)
		(layer "In9.Cu")
		(net "USB2_CP2108_CLI_DP")
	)
	(segment
		(start 94.5388 -174.4472)
		(end 94.5388 -186.2582)
		(width 0.1651)
		(layer "In9.Cu")
		(net "USB2_CP2108_CLI_DP")
	)
	(segment
		(start 239.162844 -81.5467)
		(end 238.870744 -81.2546)
		(width 0.1651)
		(layer "In9.Cu")
		(net "USB2_CP2108_CLI_DP")
	)
	(segment
		(start 132.2832 -95.377)
		(end 121.666 -105.9942)
		(width 0.1651)
		(layer "In9.Cu")
		(net "USB2_CP2108_CLI_DP")
	)
	(segment
		(start 445.311784 -223.320102)
		(end 446.501266 -223.320102)
		(width 0.13208)
		(layer "F.Cu")
		(net "UART_PEX2_SDB_CP2108_RX")
	)
	(segment
		(start 447.92392 -223.681544)
		(end 447.379344 -223.681544)
		(width 0.13208)
		(layer "F.Cu")
		(net "UART_PEX2_SDB_CP2108_RX")
	)
	(segment
		(start 445.308228 -223.316546)
		(end 445.311784 -223.320102)
		(width 0.13208)
		(layer "F.Cu")
		(net "UART_PEX2_SDB_CP2108_RX")
	)
	(segment
		(start 447.379344 -223.681544)
		(end 447.017902 -223.320102)
		(width 0.13208)
		(layer "F.Cu")
		(net "UART_PEX2_SDB_CP2108_RX")
	)
	(segment
		(start 447.017902 -223.320102)
		(end 446.501266 -223.320102)
		(width 0.13208)
		(layer "F.Cu")
		(net "UART_PEX2_SDB_CP2108_RX")
	)
	(via
		(at 446.501266 -223.320102)
		(size 0.762)
		(drill 0.381)
		(layers "F.Cu" "B.Cu")
		(net "UART_PEX2_SDB_CP2108_RX")
	)
	(segment
		(start 456.826874 -231.18445)
		(end 456.82408 -231.181656)
		(width 0.13208)
		(layer "F.Cu")
		(net "UART_PEX1_SDB_CP2108_TX")
	)
	(segment
		(start 459.6638 -231.18445)
		(end 458.3684 -231.18445)
		(width 0.13208)
		(layer "F.Cu")
		(net "UART_PEX1_SDB_CP2108_TX")
	)
	(segment
		(start 458.3684 -231.18445)
		(end 456.826874 -231.18445)
		(width 0.13208)
		(layer "F.Cu")
		(net "UART_PEX1_SDB_CP2108_TX")
	)
	(via
		(at 458.3684 -231.18445)
		(size 0.762)
		(drill 0.381)
		(layers "F.Cu" "B.Cu")
		(net "UART_PEX1_SDB_CP2108_TX")
	)
	(segment
		(start 99.06635 -198.9836)
		(end 97.3328 -200.71715)
		(width 0.13208)
		(layer "F.Cu")
		(net "RST_CP2108_CLI_R_N")
	)
	(segment
		(start 99.958144 -198.491856)
		(end 99.4664 -198.9836)
		(width 0.13208)
		(layer "F.Cu")
		(net "RST_CP2108_CLI_R_N")
	)
	(segment
		(start 99.958144 -198.20128)
		(end 99.958144 -198.491856)
		(width 0.13208)
		(layer "F.Cu")
		(net "RST_CP2108_CLI_R_N")
	)
	(segment
		(start 96.167194 -200.71715)
		(end 97.3328 -200.71715)
		(width 0.13208)
		(layer "F.Cu")
		(net "RST_CP2108_CLI_R_N")
	)
	(segment
		(start 95.177356 -200.709276)
		(end 96.131888 -200.709276)
		(width 0.13208)
		(layer "F.Cu")
		(net "RST_CP2108_CLI_R_N")
	)
	(segment
		(start 96.15932 -200.709276)
		(end 96.167194 -200.71715)
		(width 0.13208)
		(layer "F.Cu")
		(net "RST_CP2108_CLI_R_N")
	)
	(segment
		(start 96.131888 -200.709276)
		(end 96.15932 -200.709276)
		(width 0.13208)
		(layer "F.Cu")
		(net "RST_CP2108_CLI_R_N")
	)
	(segment
		(start 99.4664 -198.9836)
		(end 99.06635 -198.9836)
		(width 0.13208)
		(layer "F.Cu")
		(net "RST_CP2108_CLI_R_N")
	)
	(via
		(at 97.3328 -200.71715)
		(size 0.762)
		(drill 0.381)
		(layers "F.Cu" "B.Cu")
		(net "RST_CP2108_CLI_R_N")
	)
	(segment
		(start 455.542396 -234.354116)
		(end 454.602596 -233.414316)
		(width 0.13208)
		(layer "F.Cu")
		(net "UART_PEX0_SDB_CP2108_TX")
	)
	(segment
		(start 455.542396 -234.800394)
		(end 455.542396 -234.354116)
		(width 0.13208)
		(layer "F.Cu")
		(net "UART_PEX0_SDB_CP2108_TX")
	)
	(segment
		(start 453.953372 -232.765092)
		(end 453.000618 -232.765092)
		(width 0.13208)
		(layer "F.Cu")
		(net "UART_PEX0_SDB_CP2108_TX")
	)
	(segment
		(start 453.000618 -232.765092)
		(end 452.623936 -232.38841)
		(width 0.13208)
		(layer "F.Cu")
		(net "UART_PEX0_SDB_CP2108_TX")
	)
	(segment
		(start 454.602596 -233.414316)
		(end 453.953372 -232.765092)
		(width 0.13208)
		(layer "F.Cu")
		(net "UART_PEX0_SDB_CP2108_TX")
	)
	(segment
		(start 452.623936 -232.38841)
		(end 452.623936 -231.88168)
		(width 0.13208)
		(layer "F.Cu")
		(net "UART_PEX0_SDB_CP2108_TX")
	)
	(via
		(at 454.602596 -233.414316)
		(size 0.762)
		(drill 0.381)
		(layers "F.Cu" "B.Cu")
		(net "UART_PEX0_SDB_CP2108_TX")
	)
	(segment
		(start 456.532996 -233.75747)
		(end 456.532996 -234.790996)
		(width 0.13208)
		(layer "F.Cu")
		(net "UART_PEX1_SDB_CP2108_RX")
	)
	(segment
		(start 456.124056 -231.88168)
		(end 456.124056 -233.34853)
		(width 0.13208)
		(layer "F.Cu")
		(net "UART_PEX1_SDB_CP2108_RX")
	)
	(segment
		(start 456.124056 -233.34853)
		(end 456.532996 -233.75747)
		(width 0.13208)
		(layer "F.Cu")
		(net "UART_PEX1_SDB_CP2108_RX")
	)
	(via
		(at 456.124056 -233.34853)
		(size 0.762)
		(drill 0.381)
		(layers "F.Cu" "B.Cu")
		(net "UART_PEX1_SDB_CP2108_RX")
	)
	(segment
		(start 446.34785 -237.5154)
		(end 446.34785 -236.4994)
		(width 0.13208)
		(layer "F.Cu")
		(net "RST_CP2108_SDB_R_N")
	)
	(segment
		(start 447.3956 -232.4862)
		(end 448.3354 -232.4862)
		(width 0.13208)
		(layer "F.Cu")
		(net "RST_CP2108_SDB_R_N")
	)
	(segment
		(start 446.34785 -236.4994)
		(end 446.34785 -235.2548)
		(width 0.13208)
		(layer "F.Cu")
		(net "RST_CP2108_SDB_R_N")
	)
	(segment
		(start 448.623944 -232.197656)
		(end 448.623944 -231.88168)
		(width 0.13208)
		(layer "F.Cu")
		(net "RST_CP2108_SDB_R_N")
	)
	(segment
		(start 446.34785 -235.2548)
		(end 446.34785 -233.53395)
		(width 0.13208)
		(layer "F.Cu")
		(net "RST_CP2108_SDB_R_N")
	)
	(segment
		(start 448.3354 -232.4862)
		(end 448.623944 -232.197656)
		(width 0.13208)
		(layer "F.Cu")
		(net "RST_CP2108_SDB_R_N")
	)
	(segment
		(start 446.34785 -233.53395)
		(end 447.3956 -232.4862)
		(width 0.13208)
		(layer "F.Cu")
		(net "RST_CP2108_SDB_R_N")
	)
	(via
		(at 446.34785 -235.2548)
		(size 0.762)
		(drill 0.381)
		(layers "F.Cu" "B.Cu")
		(net "RST_CP2108_SDB_R_N")
	)
	(segment
		(start 454.542398 -234.823508)
		(end 454.542398 -234.374944)
		(width 0.13208)
		(layer "F.Cu")
		(net "UART_PEX0_SDB_CP2108_RX")
	)
	(segment
		(start 452.124064 -231.88168)
		(end 452.124064 -232.86974)
		(width 0.13208)
		(layer "F.Cu")
		(net "UART_PEX0_SDB_CP2108_RX")
	)
	(segment
		(start 452.124064 -232.86974)
		(end 452.718678 -233.464354)
		(width 0.13208)
		(layer "F.Cu")
		(net "UART_PEX0_SDB_CP2108_RX")
	)
	(segment
		(start 453.631808 -233.464354)
		(end 452.718678 -233.464354)
		(width 0.13208)
		(layer "F.Cu")
		(net "UART_PEX0_SDB_CP2108_RX")
	)
	(segment
		(start 454.542398 -234.374944)
		(end 453.631808 -233.464354)
		(width 0.13208)
		(layer "F.Cu")
		(net "UART_PEX0_SDB_CP2108_RX")
	)
	(via
		(at 452.718678 -233.464354)
		(size 0.762)
		(drill 0.381)
		(layers "F.Cu" "B.Cu")
		(net "UART_PEX0_SDB_CP2108_RX")
	)
	(segment
		(start 449.047616 -234.331256)
		(end 449.342256 -234.625896)
		(width 0.13462)
		(layer "F.Cu")
		(net "USB2_CP2108_SDB_DP")
	)
	(segment
		(start 234.61853 -80.024224)
		(end 234.75569 -79.887064)
		(width 0.13462)
		(layer "F.Cu")
		(net "USB2_CP2108_SDB_DP")
	)
	(segment
		(start 449.623942 -232.224834)
		(end 449.511166 -232.33761)
		(width 0.13462)
		(layer "F.Cu")
		(net "USB2_CP2108_SDB_DP")
	)
	(segment
		(start 235.29671 -80.024224)
		(end 235.70057 -80.024224)
		(width 0.13462)
		(layer "F.Cu")
		(net "USB2_CP2108_SDB_DP")
	)
	(segment
		(start 234.75569 -79.887064)
		(end 235.15955 -79.887064)
		(width 0.13462)
		(layer "F.Cu")
		(net "USB2_CP2108_SDB_DP")
	)
	(segment
		(start 233.871008 -81.699608)
		(end 233.871008 -82.118708)
		(width 0.13462)
		(layer "F.Cu")
		(net "USB2_CP2108_SDB_DP")
	)
	(segment
		(start 233.288332 -81.116932)
		(end 233.871008 -81.699608)
		(width 0.13462)
		(layer "F.Cu")
		(net "USB2_CP2108_SDB_DP")
	)
	(segment
		(start 234.21467 -80.024224)
		(end 234.61853 -80.024224)
		(width 0.13462)
		(layer "F.Cu")
		(net "USB2_CP2108_SDB_DP")
	)
	(segment
		(start 236.24159 -79.887064)
		(end 236.37875 -80.024224)
		(width 0.13462)
		(layer "F.Cu")
		(net "USB2_CP2108_SDB_DP")
	)
	(segment
		(start 234.07751 -79.887064)
		(end 234.21467 -80.024224)
		(width 0.13462)
		(layer "F.Cu")
		(net "USB2_CP2108_SDB_DP")
	)
	(segment
		(start 237.701328 -79.887064)
		(end 237.998 -80.183736)
		(width 0.13462)
		(layer "F.Cu")
		(net "USB2_CP2108_SDB_DP")
	)
	(segment
		(start 233.288332 -80.20558)
		(end 233.606848 -79.887064)
		(width 0.13462)
		(layer "F.Cu")
		(net "USB2_CP2108_SDB_DP")
	)
	(segment
		(start 235.83773 -79.887064)
		(end 236.24159 -79.887064)
		(width 0.13462)
		(layer "F.Cu")
		(net "USB2_CP2108_SDB_DP")
	)
	(segment
		(start 233.288332 -80.704944)
		(end 233.288332 -81.116932)
		(width 0.13462)
		(layer "F.Cu")
		(net "USB2_CP2108_SDB_DP")
	)
	(segment
		(start 449.511166 -233.452416)
		(end 449.047616 -233.915966)
		(width 0.13462)
		(layer "F.Cu")
		(net "USB2_CP2108_SDB_DP")
	)
	(segment
		(start 236.91977 -79.887064)
		(end 237.701328 -79.887064)
		(width 0.13462)
		(layer "F.Cu")
		(net "USB2_CP2108_SDB_DP")
	)
	(segment
		(start 449.623942 -231.88168)
		(end 449.623942 -232.224834)
		(width 0.13462)
		(layer "F.Cu")
		(net "USB2_CP2108_SDB_DP")
	)
	(segment
		(start 449.047616 -233.915966)
		(end 449.047616 -234.331256)
		(width 0.13462)
		(layer "F.Cu")
		(net "USB2_CP2108_SDB_DP")
	)
	(segment
		(start 236.78261 -80.024224)
		(end 236.91977 -79.887064)
		(width 0.13462)
		(layer "F.Cu")
		(net "USB2_CP2108_SDB_DP")
	)
	(segment
		(start 233.288332 -80.704944)
		(end 233.288332 -80.20558)
		(width 0.13462)
		(layer "F.Cu")
		(net "USB2_CP2108_SDB_DP")
	)
	(segment
		(start 233.606848 -79.887064)
		(end 234.07751 -79.887064)
		(width 0.13462)
		(layer "F.Cu")
		(net "USB2_CP2108_SDB_DP")
	)
	(segment
		(start 449.511166 -232.33761)
		(end 449.511166 -233.452416)
		(width 0.13462)
		(layer "F.Cu")
		(net "USB2_CP2108_SDB_DP")
	)
	(segment
		(start 235.15955 -79.887064)
		(end 235.29671 -80.024224)
		(width 0.13462)
		(layer "F.Cu")
		(net "USB2_CP2108_SDB_DP")
	)
	(segment
		(start 235.70057 -80.024224)
		(end 235.83773 -79.887064)
		(width 0.13462)
		(layer "F.Cu")
		(net "USB2_CP2108_SDB_DP")
	)
	(segment
		(start 236.37875 -80.024224)
		(end 236.78261 -80.024224)
		(width 0.13462)
		(layer "F.Cu")
		(net "USB2_CP2108_SDB_DP")
	)
	(via
		(at 237.998 -80.183736)
		(size 0.508)
		(drill 0.254)
		(layers "F.Cu" "B.Cu")
		(net "USB2_CP2108_SDB_DP")
	)
	(via
		(at 233.288332 -80.704944)
		(size 0.4064)
		(drill 0.2032)
		(layers "F.Cu" "B.Cu")
		(net "USB2_CP2108_SDB_DP")
	)
	(via
		(at 449.342256 -234.625896)
		(size 0.508)
		(drill 0.254)
		(layers "F.Cu" "B.Cu")
		(net "USB2_CP2108_SDB_DP")
	)
	(segment
		(start 244.5004 -73.634854)
		(end 248.277634 -69.85762)
		(width 0.13462)
		(layer "B.Cu")
		(net "USB2_CP2108_SDB_DP")
	)
	(segment
		(start 444.55588 -201.623168)
		(end 444.55588 -210.436968)
		(width 0.13462)
		(layer "B.Cu")
		(net "USB2_CP2108_SDB_DP")
	)
	(segment
		(start 446.6082 -235.761784)
		(end 447.216276 -236.36986)
		(width 0.13462)
		(layer "B.Cu")
		(net "USB2_CP2108_SDB_DP")
	)
	(segment
		(start 244.5004 -75.1586)
		(end 244.5004 -73.634854)
		(width 0.13462)
		(layer "B.Cu")
		(net "USB2_CP2108_SDB_DP")
	)
	(segment
		(start 374.869202 -167.815006)
		(end 375.272808 -167.4114)
		(width 0.13462)
		(layer "B.Cu")
		(net "USB2_CP2108_SDB_DP")
	)
	(segment
		(start 410.745432 -167.81272)
		(end 444.55588 -201.623168)
		(width 0.13462)
		(layer "B.Cu")
		(net "USB2_CP2108_SDB_DP")
	)
	(segment
		(start 285.60522 -82.423)
		(end 287.827212 -84.644992)
		(width 0.13462)
		(layer "B.Cu")
		(net "USB2_CP2108_SDB_DP")
	)
	(segment
		(start 260.890766 -69.85762)
		(end 263.964166 -72.93102)
		(width 0.13462)
		(layer "B.Cu")
		(net "USB2_CP2108_SDB_DP")
	)
	(segment
		(start 239.776254 -79.882746)
		(end 244.5004 -75.1586)
		(width 0.13462)
		(layer "B.Cu")
		(net "USB2_CP2108_SDB_DP")
	)
	(segment
		(start 446.6082 -212.489288)
		(end 446.6082 -235.761784)
		(width 0.13462)
		(layer "B.Cu")
		(net "USB2_CP2108_SDB_DP")
	)
	(segment
		(start 274.312634 -76.9366)
		(end 279.799034 -82.423)
		(width 0.13462)
		(layer "B.Cu")
		(net "USB2_CP2108_SDB_DP")
	)
	(segment
		(start 347.218 -143.517112)
		(end 347.218 -160.120838)
		(width 0.13462)
		(layer "B.Cu")
		(net "USB2_CP2108_SDB_DP")
	)
	(segment
		(start 375.272808 -167.4114)
		(end 406.846532 -167.4114)
		(width 0.13462)
		(layer "B.Cu")
		(net "USB2_CP2108_SDB_DP")
	)
	(segment
		(start 248.277634 -69.85762)
		(end 260.890766 -69.85762)
		(width 0.13462)
		(layer "B.Cu")
		(net "USB2_CP2108_SDB_DP")
	)
	(segment
		(start 351.560384 -164.463222)
		(end 366.596168 -164.463222)
		(width 0.13462)
		(layer "B.Cu")
		(net "USB2_CP2108_SDB_DP")
	)
	(segment
		(start 271.627346 -76.9366)
		(end 274.312634 -76.9366)
		(width 0.13462)
		(layer "B.Cu")
		(net "USB2_CP2108_SDB_DP")
	)
	(segment
		(start 267.621766 -72.93102)
		(end 271.627346 -76.9366)
		(width 0.13462)
		(layer "B.Cu")
		(net "USB2_CP2108_SDB_DP")
	)
	(segment
		(start 447.216276 -236.36986)
		(end 448.53479 -236.36986)
		(width 0.13462)
		(layer "B.Cu")
		(net "USB2_CP2108_SDB_DP")
	)
	(segment
		(start 366.596168 -164.463222)
		(end 369.947952 -167.815006)
		(width 0.13462)
		(layer "B.Cu")
		(net "USB2_CP2108_SDB_DP")
	)
	(segment
		(start 297.974766 -128.88722)
		(end 316.357508 -128.88722)
		(width 0.13462)
		(layer "B.Cu")
		(net "USB2_CP2108_SDB_DP")
	)
	(segment
		(start 316.357508 -128.88722)
		(end 321.475608 -134.00532)
		(width 0.13462)
		(layer "B.Cu")
		(net "USB2_CP2108_SDB_DP")
	)
	(segment
		(start 263.964166 -72.93102)
		(end 267.621766 -72.93102)
		(width 0.13462)
		(layer "B.Cu")
		(net "USB2_CP2108_SDB_DP")
	)
	(segment
		(start 321.475608 -134.00532)
		(end 337.706208 -134.00532)
		(width 0.13462)
		(layer "B.Cu")
		(net "USB2_CP2108_SDB_DP")
	)
	(segment
		(start 337.706208 -134.00532)
		(end 347.218 -143.517112)
		(width 0.13462)
		(layer "B.Cu")
		(net "USB2_CP2108_SDB_DP")
	)
	(segment
		(start 406.846532 -167.4114)
		(end 407.247852 -167.81272)
		(width 0.13462)
		(layer "B.Cu")
		(net "USB2_CP2108_SDB_DP")
	)
	(segment
		(start 238.29899 -79.882746)
		(end 239.776254 -79.882746)
		(width 0.13462)
		(layer "B.Cu")
		(net "USB2_CP2108_SDB_DP")
	)
	(segment
		(start 287.827212 -84.644992)
		(end 287.827212 -91.822524)
		(width 0.13462)
		(layer "B.Cu")
		(net "USB2_CP2108_SDB_DP")
	)
	(segment
		(start 369.947952 -167.815006)
		(end 374.869202 -167.815006)
		(width 0.13462)
		(layer "B.Cu")
		(net "USB2_CP2108_SDB_DP")
	)
	(segment
		(start 448.53479 -236.36986)
		(end 449.0466 -235.85805)
		(width 0.13462)
		(layer "B.Cu")
		(net "USB2_CP2108_SDB_DP")
	)
	(segment
		(start 444.55588 -210.436968)
		(end 446.6082 -212.489288)
		(width 0.13462)
		(layer "B.Cu")
		(net "USB2_CP2108_SDB_DP")
	)
	(segment
		(start 449.0466 -235.85805)
		(end 449.0466 -234.921552)
		(width 0.13462)
		(layer "B.Cu")
		(net "USB2_CP2108_SDB_DP")
	)
	(segment
		(start 237.998 -80.183736)
		(end 238.29899 -79.882746)
		(width 0.13462)
		(layer "B.Cu")
		(net "USB2_CP2108_SDB_DP")
	)
	(segment
		(start 449.0466 -234.921552)
		(end 449.342256 -234.625896)
		(width 0.13462)
		(layer "B.Cu")
		(net "USB2_CP2108_SDB_DP")
	)
	(segment
		(start 292.1254 -96.120712)
		(end 292.1254 -123.037854)
		(width 0.13462)
		(layer "B.Cu")
		(net "USB2_CP2108_SDB_DP")
	)
	(segment
		(start 279.799034 -82.423)
		(end 285.60522 -82.423)
		(width 0.13462)
		(layer "B.Cu")
		(net "USB2_CP2108_SDB_DP")
	)
	(segment
		(start 287.827212 -91.822524)
		(end 292.1254 -96.120712)
		(width 0.13462)
		(layer "B.Cu")
		(net "USB2_CP2108_SDB_DP")
	)
	(segment
		(start 407.247852 -167.81272)
		(end 410.745432 -167.81272)
		(width 0.13462)
		(layer "B.Cu")
		(net "USB2_CP2108_SDB_DP")
	)
	(segment
		(start 292.1254 -123.037854)
		(end 297.974766 -128.88722)
		(width 0.13462)
		(layer "B.Cu")
		(net "USB2_CP2108_SDB_DP")
	)
	(segment
		(start 347.218 -160.120838)
		(end 351.560384 -164.463222)
		(width 0.13462)
		(layer "B.Cu")
		(net "USB2_CP2108_SDB_DP")
	)
	(segment
		(start 445.313054 -224.705418)
		(end 446.510156 -224.705418)
		(width 0.13208)
		(layer "F.Cu")
		(net "UART_PEX2_SDB_CP2108_TX")
	)
	(segment
		(start 447.033904 -224.18167)
		(end 447.92392 -224.18167)
		(width 0.13208)
		(layer "F.Cu")
		(net "UART_PEX2_SDB_CP2108_TX")
	)
	(segment
		(start 445.308482 -224.700846)
		(end 445.313054 -224.705418)
		(width 0.13208)
		(layer "F.Cu")
		(net "UART_PEX2_SDB_CP2108_TX")
	)
	(segment
		(start 446.510156 -224.705418)
		(end 447.033904 -224.18167)
		(width 0.13208)
		(layer "F.Cu")
		(net "UART_PEX2_SDB_CP2108_TX")
	)
	(via
		(at 446.510156 -224.705418)
		(size 0.762)
		(drill 0.381)
		(layers "F.Cu" "B.Cu")
		(net "UART_PEX2_SDB_CP2108_TX")
	)
	(segment
		(start 446.510156 -227.908866)
		(end 446.514982 -227.90404)
		(width 0.13208)
		(layer "F.Cu")
		(net "UART_PEX3_SDB_CP2108_RX")
	)
	(segment
		(start 446.514982 -228.631496)
		(end 447.565018 -229.681532)
		(width 0.13208)
		(layer "F.Cu")
		(net "UART_PEX3_SDB_CP2108_RX")
	)
	(segment
		(start 445.322198 -227.908866)
		(end 446.510156 -227.908866)
		(width 0.13208)
		(layer "F.Cu")
		(net "UART_PEX3_SDB_CP2108_RX")
	)
	(segment
		(start 446.514982 -227.90404)
		(end 446.514982 -228.631496)
		(width 0.13208)
		(layer "F.Cu")
		(net "UART_PEX3_SDB_CP2108_RX")
	)
	(segment
		(start 447.565018 -229.681532)
		(end 447.92392 -229.681532)
		(width 0.13208)
		(layer "F.Cu")
		(net "UART_PEX3_SDB_CP2108_RX")
	)
	(via
		(at 446.514982 -227.90404)
		(size 0.762)
		(drill 0.381)
		(layers "F.Cu" "B.Cu")
		(net "UART_PEX3_SDB_CP2108_RX")
	)
	(segment
		(start 445.94526 -232.524554)
		(end 445.113918 -232.524554)
		(width 0.13208)
		(layer "F.Cu")
		(net "UART_PEX3_SDB_CP2108_TX")
	)
	(segment
		(start 447.92392 -231.181656)
		(end 447.288158 -231.181656)
		(width 0.13208)
		(layer "F.Cu")
		(net "UART_PEX3_SDB_CP2108_TX")
	)
	(segment
		(start 446.48247 -231.987344)
		(end 445.94526 -232.524554)
		(width 0.13208)
		(layer "F.Cu")
		(net "UART_PEX3_SDB_CP2108_TX")
	)
	(segment
		(start 447.288158 -231.181656)
		(end 446.48247 -231.987344)
		(width 0.13208)
		(layer "F.Cu")
		(net "UART_PEX3_SDB_CP2108_TX")
	)
	(via
		(at 446.48247 -231.987344)
		(size 0.762)
		(drill 0.381)
		(layers "F.Cu" "B.Cu")
		(net "UART_PEX3_SDB_CP2108_TX")
	)
	(segment
		(start 237.705392 -79.612744)
		(end 237.998 -79.320136)
		(width 0.13462)
		(layer "F.Cu")
		(net "USB2_CP2108_SDB_DN")
	)
	(segment
		(start 449.12407 -231.88168)
		(end 449.12407 -232.224834)
		(width 0.13462)
		(layer "F.Cu")
		(net "USB2_CP2108_SDB_DN")
	)
	(segment
		(start 236.49432 -79.612744)
		(end 233.493056 -79.612744)
		(width 0.13462)
		(layer "F.Cu")
		(net "USB2_CP2108_SDB_DN")
	)
	(segment
		(start 449.236846 -232.33761)
		(end 449.236846 -233.338624)
		(width 0.13462)
		(layer "F.Cu")
		(net "USB2_CP2108_SDB_DN")
	)
	(segment
		(start 233.493056 -79.612744)
		(end 233.014012 -80.091788)
		(width 0.13462)
		(layer "F.Cu")
		(net "USB2_CP2108_SDB_DN")
	)
	(segment
		(start 448.773296 -233.802174)
		(end 448.773296 -234.331256)
		(width 0.13462)
		(layer "F.Cu")
		(net "USB2_CP2108_SDB_DN")
	)
	(segment
		(start 236.49432 -79.612744)
		(end 237.705392 -79.612744)
		(width 0.13462)
		(layer "F.Cu")
		(net "USB2_CP2108_SDB_DN")
	)
	(segment
		(start 449.236846 -233.338624)
		(end 448.773296 -233.802174)
		(width 0.13462)
		(layer "F.Cu")
		(net "USB2_CP2108_SDB_DN")
	)
	(segment
		(start 232.46969 -81.664048)
		(end 232.46969 -82.118708)
		(width 0.13462)
		(layer "F.Cu")
		(net "USB2_CP2108_SDB_DN")
	)
	(segment
		(start 449.12407 -232.224834)
		(end 449.236846 -232.33761)
		(width 0.13462)
		(layer "F.Cu")
		(net "USB2_CP2108_SDB_DN")
	)
	(segment
		(start 448.773296 -234.331256)
		(end 448.478656 -234.625896)
		(width 0.13462)
		(layer "F.Cu")
		(net "USB2_CP2108_SDB_DN")
	)
	(segment
		(start 233.014012 -80.091788)
		(end 233.014012 -81.119726)
		(width 0.13462)
		(layer "F.Cu")
		(net "USB2_CP2108_SDB_DN")
	)
	(segment
		(start 233.014012 -81.119726)
		(end 232.46969 -81.664048)
		(width 0.13462)
		(layer "F.Cu")
		(net "USB2_CP2108_SDB_DN")
	)
	(via
		(at 237.998 -79.320136)
		(size 0.508)
		(drill 0.254)
		(layers "F.Cu" "B.Cu")
		(net "USB2_CP2108_SDB_DN")
	)
	(via
		(at 448.478656 -234.625896)
		(size 0.508)
		(drill 0.254)
		(layers "F.Cu" "B.Cu")
		(net "USB2_CP2108_SDB_DN")
	)
	(via
		(at 236.49432 -79.612744)
		(size 0.4064)
		(drill 0.2032)
		(layers "F.Cu" "B.Cu")
		(net "USB2_CP2108_SDB_DN")
	)
	(segment
		(start 446.88252 -231.71785)
		(end 447.01968 -231.58069)
		(width 0.13462)
		(layer "B.Cu")
		(net "USB2_CP2108_SDB_DN")
	)
	(segment
		(start 370.061744 -167.540686)
		(end 366.70996 -164.188902)
		(width 0.13462)
		(layer "B.Cu")
		(net "USB2_CP2108_SDB_DN")
	)
	(segment
		(start 444.8302 -201.509376)
		(end 410.859224 -167.5384)
		(width 0.13462)
		(layer "B.Cu")
		(net "USB2_CP2108_SDB_DN")
	)
	(segment
		(start 447.01968 -232.25887)
		(end 446.88252 -232.12171)
		(width 0.13462)
		(layer "B.Cu")
		(net "USB2_CP2108_SDB_DN")
	)
	(segment
		(start 375.159016 -167.13708)
		(end 374.75541 -167.540686)
		(width 0.13462)
		(layer "B.Cu")
		(net "USB2_CP2108_SDB_DN")
	)
	(segment
		(start 374.75541 -167.540686)
		(end 370.061744 -167.540686)
		(width 0.13462)
		(layer "B.Cu")
		(net "USB2_CP2108_SDB_DN")
	)
	(segment
		(start 347.49232 -143.40332)
		(end 337.82 -133.731)
		(width 0.13462)
		(layer "B.Cu")
		(net "USB2_CP2108_SDB_DN")
	)
	(segment
		(start 271.741138 -76.66228)
		(end 267.735558 -72.6567)
		(width 0.13462)
		(layer "B.Cu")
		(net "USB2_CP2108_SDB_DN")
	)
	(segment
		(start 447.01968 -230.49865)
		(end 447.01968 -230.09479)
		(width 0.13462)
		(layer "B.Cu")
		(net "USB2_CP2108_SDB_DN")
	)
	(segment
		(start 264.077958 -72.6567)
		(end 261.004558 -69.5833)
		(width 0.13462)
		(layer "B.Cu")
		(net "USB2_CP2108_SDB_DN")
	)
	(segment
		(start 446.88252 -232.79989)
		(end 447.01968 -232.66273)
		(width 0.13462)
		(layer "B.Cu")
		(net "USB2_CP2108_SDB_DN")
	)
	(segment
		(start 298.088558 -128.6129)
		(end 292.39972 -122.924062)
		(width 0.13462)
		(layer "B.Cu")
		(net "USB2_CP2108_SDB_DN")
	)
	(segment
		(start 448.478656 -234.625896)
		(end 448.77228 -234.91952)
		(width 0.13462)
		(layer "B.Cu")
		(net "USB2_CP2108_SDB_DN")
	)
	(segment
		(start 244.22608 -75.044808)
		(end 239.662462 -79.608426)
		(width 0.13462)
		(layer "B.Cu")
		(net "USB2_CP2108_SDB_DN")
	)
	(segment
		(start 239.662462 -79.608426)
		(end 238.28629 -79.608426)
		(width 0.13462)
		(layer "B.Cu")
		(net "USB2_CP2108_SDB_DN")
	)
	(segment
		(start 406.960324 -167.13708)
		(end 375.159016 -167.13708)
		(width 0.13462)
		(layer "B.Cu")
		(net "USB2_CP2108_SDB_DN")
	)
	(segment
		(start 446.88252 -235.647992)
		(end 446.88252 -232.79989)
		(width 0.13462)
		(layer "B.Cu")
		(net "USB2_CP2108_SDB_DN")
	)
	(segment
		(start 285.719012 -82.14868)
		(end 279.912826 -82.14868)
		(width 0.13462)
		(layer "B.Cu")
		(net "USB2_CP2108_SDB_DN")
	)
	(segment
		(start 447.01968 -230.09479)
		(end 446.88252 -229.95763)
		(width 0.13462)
		(layer "B.Cu")
		(net "USB2_CP2108_SDB_DN")
	)
	(segment
		(start 351.674176 -164.188902)
		(end 347.49232 -160.007046)
		(width 0.13462)
		(layer "B.Cu")
		(net "USB2_CP2108_SDB_DN")
	)
	(segment
		(start 288.101532 -91.708732)
		(end 288.101532 -84.5312)
		(width 0.13462)
		(layer "B.Cu")
		(net "USB2_CP2108_SDB_DN")
	)
	(segment
		(start 261.004558 -69.5833)
		(end 248.163842 -69.5833)
		(width 0.13462)
		(layer "B.Cu")
		(net "USB2_CP2108_SDB_DN")
	)
	(segment
		(start 446.88252 -232.12171)
		(end 446.88252 -231.71785)
		(width 0.13462)
		(layer "B.Cu")
		(net "USB2_CP2108_SDB_DN")
	)
	(segment
		(start 288.101532 -84.5312)
		(end 285.719012 -82.14868)
		(width 0.13462)
		(layer "B.Cu")
		(net "USB2_CP2108_SDB_DN")
	)
	(segment
		(start 248.163842 -69.5833)
		(end 244.22608 -73.521062)
		(width 0.13462)
		(layer "B.Cu")
		(net "USB2_CP2108_SDB_DN")
	)
	(segment
		(start 444.8302 -210.323176)
		(end 444.8302 -201.509376)
		(width 0.13462)
		(layer "B.Cu")
		(net "USB2_CP2108_SDB_DN")
	)
	(segment
		(start 274.426426 -76.66228)
		(end 271.741138 -76.66228)
		(width 0.13462)
		(layer "B.Cu")
		(net "USB2_CP2108_SDB_DN")
	)
	(segment
		(start 448.77228 -234.91952)
		(end 448.77228 -235.744258)
		(width 0.13462)
		(layer "B.Cu")
		(net "USB2_CP2108_SDB_DN")
	)
	(segment
		(start 446.88252 -231.03967)
		(end 446.88252 -230.63581)
		(width 0.13462)
		(layer "B.Cu")
		(net "USB2_CP2108_SDB_DN")
	)
	(segment
		(start 337.82 -133.731)
		(end 321.5894 -133.731)
		(width 0.13462)
		(layer "B.Cu")
		(net "USB2_CP2108_SDB_DN")
	)
	(segment
		(start 448.420998 -236.09554)
		(end 447.330068 -236.09554)
		(width 0.13462)
		(layer "B.Cu")
		(net "USB2_CP2108_SDB_DN")
	)
	(segment
		(start 447.01968 -232.66273)
		(end 447.01968 -232.25887)
		(width 0.13462)
		(layer "B.Cu")
		(net "USB2_CP2108_SDB_DN")
	)
	(segment
		(start 244.22608 -73.521062)
		(end 244.22608 -75.044808)
		(width 0.13462)
		(layer "B.Cu")
		(net "USB2_CP2108_SDB_DN")
	)
	(segment
		(start 448.77228 -235.744258)
		(end 448.420998 -236.09554)
		(width 0.13462)
		(layer "B.Cu")
		(net "USB2_CP2108_SDB_DN")
	)
	(segment
		(start 446.88252 -212.375496)
		(end 444.8302 -210.323176)
		(width 0.13462)
		(layer "B.Cu")
		(net "USB2_CP2108_SDB_DN")
	)
	(segment
		(start 447.330068 -236.09554)
		(end 446.88252 -235.647992)
		(width 0.13462)
		(layer "B.Cu")
		(net "USB2_CP2108_SDB_DN")
	)
	(segment
		(start 447.01968 -231.58069)
		(end 447.01968 -231.17683)
		(width 0.13462)
		(layer "B.Cu")
		(net "USB2_CP2108_SDB_DN")
	)
	(segment
		(start 238.28629 -79.608426)
		(end 237.998 -79.320136)
		(width 0.13462)
		(layer "B.Cu")
		(net "USB2_CP2108_SDB_DN")
	)
	(segment
		(start 410.859224 -167.5384)
		(end 407.361644 -167.5384)
		(width 0.13462)
		(layer "B.Cu")
		(net "USB2_CP2108_SDB_DN")
	)
	(segment
		(start 446.88252 -229.95763)
		(end 446.88252 -212.375496)
		(width 0.13462)
		(layer "B.Cu")
		(net "USB2_CP2108_SDB_DN")
	)
	(segment
		(start 316.4713 -128.6129)
		(end 298.088558 -128.6129)
		(width 0.13462)
		(layer "B.Cu")
		(net "USB2_CP2108_SDB_DN")
	)
	(segment
		(start 446.88252 -230.63581)
		(end 447.01968 -230.49865)
		(width 0.13462)
		(layer "B.Cu")
		(net "USB2_CP2108_SDB_DN")
	)
	(segment
		(start 366.70996 -164.188902)
		(end 351.674176 -164.188902)
		(width 0.13462)
		(layer "B.Cu")
		(net "USB2_CP2108_SDB_DN")
	)
	(segment
		(start 292.39972 -96.00692)
		(end 288.101532 -91.708732)
		(width 0.13462)
		(layer "B.Cu")
		(net "USB2_CP2108_SDB_DN")
	)
	(segment
		(start 321.5894 -133.731)
		(end 316.4713 -128.6129)
		(width 0.13462)
		(layer "B.Cu")
		(net "USB2_CP2108_SDB_DN")
	)
	(segment
		(start 292.39972 -122.924062)
		(end 292.39972 -96.00692)
		(width 0.13462)
		(layer "B.Cu")
		(net "USB2_CP2108_SDB_DN")
	)
	(segment
		(start 407.361644 -167.5384)
		(end 406.960324 -167.13708)
		(width 0.13462)
		(layer "B.Cu")
		(net "USB2_CP2108_SDB_DN")
	)
	(segment
		(start 279.912826 -82.14868)
		(end 274.426426 -76.66228)
		(width 0.13462)
		(layer "B.Cu")
		(net "USB2_CP2108_SDB_DN")
	)
	(segment
		(start 447.01968 -231.17683)
		(end 446.88252 -231.03967)
		(width 0.13462)
		(layer "B.Cu")
		(net "USB2_CP2108_SDB_DN")
	)
	(segment
		(start 267.735558 -72.6567)
		(end 264.077958 -72.6567)
		(width 0.13462)
		(layer "B.Cu")
		(net "USB2_CP2108_SDB_DN")
	)
	(segment
		(start 347.49232 -160.007046)
		(end 347.49232 -143.40332)
		(width 0.13462)
		(layer "B.Cu")
		(net "USB2_CP2108_SDB_DN")
	)
	(segment
		(start 204.614526 -366.145826)
		(end 204.468476 -366.291876)
		(width 0.13208)
		(layer "F.Cu")
		(net "HSC_P12V_MP5990_EN")
	)
	(segment
		(start 204.468476 -366.291876)
		(end 204.468476 -366.719612)
		(width 0.13208)
		(layer "F.Cu")
		(net "HSC_P12V_MP5990_EN")
	)
	(segment
		(start 204.614526 -365.470186)
		(end 204.614526 -366.145826)
		(width 0.13208)
		(layer "F.Cu")
		(net "HSC_P12V_MP5990_EN")
	)
	(segment
		(start 204.030326 -364.885986)
		(end 204.614526 -365.470186)
		(width 0.13208)
		(layer "F.Cu")
		(net "HSC_P12V_MP5990_EN")
	)
	(via
		(at 204.614526 -366.145826)
		(size 0.508)
		(drill 0.254)
		(layers "F.Cu" "B.Cu")
		(net "HSC_P12V_MP5990_EN")
	)
	(segment
		(start 278.58212 -391.198608)
		(end 278.58212 -389.9916)
		(width 0.13208)
		(layer "F.Cu")
		(net "LTC4282_ALERT1_R_N")
	)
	(via
		(at 278.58212 -389.9916)
		(size 0.508)
		(drill 0.254)
		(layers "F.Cu" "B.Cu")
		(net "LTC4282_ALERT1_R_N")
	)
	(segment
		(start 278.110442 -390.463278)
		(end 278.58212 -389.9916)
		(width 0.13208)
		(layer "B.Cu")
		(net "LTC4282_ALERT1_R_N")
	)
	(segment
		(start 277.33371 -390.463278)
		(end 278.110442 -390.463278)
		(width 0.13208)
		(layer "B.Cu")
		(net "LTC4282_ALERT1_R_N")
	)
	(segment
		(start 279.048718 -392.730482)
		(end 278.405082 -392.730482)
		(width 0.13208)
		(layer "F.Cu")
		(net "SMB_LTC4282_TEMP_SDA")
	)
	(segment
		(start 278.405082 -392.730482)
		(end 277.93188 -392.25728)
		(width 0.13208)
		(layer "F.Cu")
		(net "SMB_LTC4282_TEMP_SDA")
	)
	(segment
		(start 251.336302 -278.850344)
		(end 251.336302 -278.811482)
		(width 0.13208)
		(layer "F.Cu")
		(net "SMB_LTC4282_TEMP_SDA")
	)
	(segment
		(start 250.709938 -279.476708)
		(end 251.336302 -278.850344)
		(width 0.13208)
		(layer "F.Cu")
		(net "SMB_LTC4282_TEMP_SDA")
	)
	(segment
		(start 277.93188 -392.25728)
		(end 277.93188 -391.198608)
		(width 0.13208)
		(layer "F.Cu")
		(net "SMB_LTC4282_TEMP_SDA")
	)
	(via
		(at 231.42829 -341.77224)
		(size 0.508)
		(drill 0.254)
		(layers "F.Cu" "B.Cu")
		(net "SMB_LTC4282_TEMP_SDA")
	)
	(via
		(at 279.048718 -392.730482)
		(size 0.508)
		(drill 0.254)
		(layers "F.Cu" "B.Cu")
		(net "SMB_LTC4282_TEMP_SDA")
	)
	(via
		(at 251.336302 -278.811482)
		(size 0.508)
		(drill 0.254)
		(layers "F.Cu" "B.Cu")
		(net "SMB_LTC4282_TEMP_SDA")
	)
	(segment
		(start 248.434606 -278.877014)
		(end 248.434606 -306.282344)
		(width 0.15494)
		(layer "In5.Cu")
		(net "SMB_LTC4282_TEMP_SDA")
	)
	(segment
		(start 231.42829 -339.715602)
		(end 231.42829 -341.77224)
		(width 0.15494)
		(layer "In5.Cu")
		(net "SMB_LTC4282_TEMP_SDA")
	)
	(segment
		(start 244.209316 -321.494658)
		(end 231.9274 -333.776574)
		(width 0.15494)
		(layer "In5.Cu")
		(net "SMB_LTC4282_TEMP_SDA")
	)
	(segment
		(start 231.9274 -333.776574)
		(end 231.9274 -339.216492)
		(width 0.15494)
		(layer "In5.Cu")
		(net "SMB_LTC4282_TEMP_SDA")
	)
	(segment
		(start 248.434606 -306.282344)
		(end 247.511316 -307.205634)
		(width 0.15494)
		(layer "In5.Cu")
		(net "SMB_LTC4282_TEMP_SDA")
	)
	(segment
		(start 247.511316 -307.205634)
		(end 247.511316 -313.52236)
		(width 0.15494)
		(layer "In5.Cu")
		(net "SMB_LTC4282_TEMP_SDA")
	)
	(segment
		(start 247.511316 -313.52236)
		(end 244.209316 -321.494658)
		(width 0.15494)
		(layer "In5.Cu")
		(net "SMB_LTC4282_TEMP_SDA")
	)
	(segment
		(start 231.9274 -339.216492)
		(end 231.42829 -339.715602)
		(width 0.15494)
		(layer "In5.Cu")
		(net "SMB_LTC4282_TEMP_SDA")
	)
	(segment
		(start 251.336302 -278.811482)
		(end 250.85548 -278.33066)
		(width 0.15494)
		(layer "In5.Cu")
		(net "SMB_LTC4282_TEMP_SDA")
	)
	(segment
		(start 250.85548 -278.33066)
		(end 248.98096 -278.33066)
		(width 0.15494)
		(layer "In5.Cu")
		(net "SMB_LTC4282_TEMP_SDA")
	)
	(segment
		(start 248.98096 -278.33066)
		(end 248.434606 -278.877014)
		(width 0.15494)
		(layer "In5.Cu")
		(net "SMB_LTC4282_TEMP_SDA")
	)
	(segment
		(start 263.677654 -344.065606)
		(end 265.573002 -345.960954)
		(width 0.15494)
		(layer "In9.Cu")
		(net "SMB_LTC4282_TEMP_SDA")
	)
	(segment
		(start 231.965754 -341.234776)
		(end 232.987342 -341.234776)
		(width 0.15494)
		(layer "In9.Cu")
		(net "SMB_LTC4282_TEMP_SDA")
	)
	(segment
		(start 232.987342 -341.234776)
		(end 235.818172 -344.065606)
		(width 0.15494)
		(layer "In9.Cu")
		(net "SMB_LTC4282_TEMP_SDA")
	)
	(segment
		(start 231.42829 -341.77224)
		(end 231.965754 -341.234776)
		(width 0.15494)
		(layer "In9.Cu")
		(net "SMB_LTC4282_TEMP_SDA")
	)
	(segment
		(start 235.818172 -344.065606)
		(end 263.677654 -344.065606)
		(width 0.15494)
		(layer "In9.Cu")
		(net "SMB_LTC4282_TEMP_SDA")
	)
	(segment
		(start 281.412696 -390.366504)
		(end 279.048718 -392.730482)
		(width 0.15494)
		(layer "In9.Cu")
		(net "SMB_LTC4282_TEMP_SDA")
	)
	(segment
		(start 265.573002 -355.614224)
		(end 281.412696 -371.453918)
		(width 0.15494)
		(layer "In9.Cu")
		(net "SMB_LTC4282_TEMP_SDA")
	)
	(segment
		(start 281.412696 -371.453918)
		(end 281.412696 -390.366504)
		(width 0.15494)
		(layer "In9.Cu")
		(net "SMB_LTC4282_TEMP_SDA")
	)
	(segment
		(start 265.573002 -345.960954)
		(end 265.573002 -355.614224)
		(width 0.15494)
		(layer "In9.Cu")
		(net "SMB_LTC4282_TEMP_SDA")
	)
	(segment
		(start 277.281894 -392.725656)
		(end 277.24735 -392.7602)
		(width 0.13208)
		(layer "F.Cu")
		(net "SMB_LTC4282_TEMP_SCL")
	)
	(segment
		(start 250.60783 -281.55011)
		(end 250.70054 -281.4574)
		(width 0.13208)
		(layer "F.Cu")
		(net "SMB_LTC4282_TEMP_SCL")
	)
	(segment
		(start 277.281894 -391.198608)
		(end 277.281894 -392.725656)
		(width 0.13208)
		(layer "F.Cu")
		(net "SMB_LTC4282_TEMP_SCL")
	)
	(segment
		(start 250.70054 -281.4574)
		(end 250.70054 -280.573988)
		(width 0.13208)
		(layer "F.Cu")
		(net "SMB_LTC4282_TEMP_SCL")
	)
	(via
		(at 232.164382 -341.785702)
		(size 0.508)
		(drill 0.254)
		(layers "F.Cu" "B.Cu")
		(net "SMB_LTC4282_TEMP_SCL")
	)
	(via
		(at 250.60783 -281.55011)
		(size 0.508)
		(drill 0.254)
		(layers "F.Cu" "B.Cu")
		(net "SMB_LTC4282_TEMP_SCL")
	)
	(via
		(at 277.24735 -392.7602)
		(size 0.508)
		(drill 0.254)
		(layers "F.Cu" "B.Cu")
		(net "SMB_LTC4282_TEMP_SCL")
	)
	(segment
		(start 232.41 -333.944468)
		(end 244.599206 -321.755262)
		(width 0.15494)
		(layer "In5.Cu")
		(net "SMB_LTC4282_TEMP_SCL")
	)
	(segment
		(start 232.164382 -341.785702)
		(end 232.164382 -339.675216)
		(width 0.15494)
		(layer "In5.Cu")
		(net "SMB_LTC4282_TEMP_SCL")
	)
	(segment
		(start 248.894346 -283.263594)
		(end 250.60783 -281.55011)
		(width 0.15494)
		(layer "In5.Cu")
		(net "SMB_LTC4282_TEMP_SCL")
	)
	(segment
		(start 247.971056 -307.396388)
		(end 248.894346 -306.473098)
		(width 0.15494)
		(layer "In5.Cu")
		(net "SMB_LTC4282_TEMP_SCL")
	)
	(segment
		(start 232.41 -339.429598)
		(end 232.41 -333.944468)
		(width 0.15494)
		(layer "In5.Cu")
		(net "SMB_LTC4282_TEMP_SCL")
	)
	(segment
		(start 244.599206 -321.755262)
		(end 247.971056 -313.61507)
		(width 0.15494)
		(layer "In5.Cu")
		(net "SMB_LTC4282_TEMP_SCL")
	)
	(segment
		(start 232.164382 -339.675216)
		(end 232.41 -339.429598)
		(width 0.15494)
		(layer "In5.Cu")
		(net "SMB_LTC4282_TEMP_SCL")
	)
	(segment
		(start 248.894346 -306.473098)
		(end 248.894346 -283.263594)
		(width 0.15494)
		(layer "In5.Cu")
		(net "SMB_LTC4282_TEMP_SCL")
	)
	(segment
		(start 247.971056 -313.61507)
		(end 247.971056 -307.396388)
		(width 0.15494)
		(layer "In5.Cu")
		(net "SMB_LTC4282_TEMP_SCL")
	)
	(segment
		(start 274.912328 -367.506504)
		(end 275.040852 -367.635028)
		(width 0.15494)
		(layer "In9.Cu")
		(net "SMB_LTC4282_TEMP_SCL")
	)
	(segment
		(start 276.284436 -368.878612)
		(end 276.466808 -368.878612)
		(width 0.15494)
		(layer "In9.Cu")
		(net "SMB_LTC4282_TEMP_SCL")
	)
	(segment
		(start 275.451824 -366.345216)
		(end 275.580348 -366.47374)
		(width 0.15494)
		(layer "In9.Cu")
		(net "SMB_LTC4282_TEMP_SCL")
	)
	(segment
		(start 232.729278 -341.785702)
		(end 235.527596 -344.58402)
		(width 0.15494)
		(layer "In9.Cu")
		(net "SMB_LTC4282_TEMP_SCL")
	)
	(segment
		(start 264.911332 -355.804724)
		(end 274.958556 -365.851948)
		(width 0.15494)
		(layer "In9.Cu")
		(net "SMB_LTC4282_TEMP_SCL")
	)
	(segment
		(start 276.513036 -367.5888)
		(end 276.695408 -367.5888)
		(width 0.15494)
		(layer "In9.Cu")
		(net "SMB_LTC4282_TEMP_SCL")
	)
	(segment
		(start 274.958556 -365.851948)
		(end 274.958556 -366.03432)
		(width 0.15494)
		(layer "In9.Cu")
		(net "SMB_LTC4282_TEMP_SCL")
	)
	(segment
		(start 274.958556 -366.03432)
		(end 274.290536 -366.70234)
		(width 0.15494)
		(layer "In9.Cu")
		(net "SMB_LTC4282_TEMP_SCL")
	)
	(segment
		(start 277.445724 -368.339116)
		(end 277.445724 -368.521488)
		(width 0.15494)
		(layer "In9.Cu")
		(net "SMB_LTC4282_TEMP_SCL")
	)
	(segment
		(start 263.372092 -344.58402)
		(end 264.911332 -346.12326)
		(width 0.15494)
		(layer "In9.Cu")
		(net "SMB_LTC4282_TEMP_SCL")
	)
	(segment
		(start 277.445724 -368.521488)
		(end 276.777704 -369.189508)
		(width 0.15494)
		(layer "In9.Cu")
		(net "SMB_LTC4282_TEMP_SCL")
	)
	(segment
		(start 276.823932 -367.899696)
		(end 276.155912 -368.567716)
		(width 0.15494)
		(layer "In9.Cu")
		(net "SMB_LTC4282_TEMP_SCL")
	)
	(segment
		(start 275.662644 -368.25682)
		(end 275.845016 -368.25682)
		(width 0.15494)
		(layer "In9.Cu")
		(net "SMB_LTC4282_TEMP_SCL")
	)
	(segment
		(start 277.134828 -368.210592)
		(end 277.3172 -368.210592)
		(width 0.15494)
		(layer "In9.Cu")
		(net "SMB_LTC4282_TEMP_SCL")
	)
	(segment
		(start 280.748232 -389.405368)
		(end 277.3934 -392.7602)
		(width 0.15494)
		(layer "In9.Cu")
		(net "SMB_LTC4282_TEMP_SCL")
	)
	(segment
		(start 280.748232 -371.641624)
		(end 280.748232 -389.405368)
		(width 0.15494)
		(layer "In9.Cu")
		(net "SMB_LTC4282_TEMP_SCL")
	)
	(segment
		(start 276.823932 -367.717324)
		(end 276.823932 -367.899696)
		(width 0.15494)
		(layer "In9.Cu")
		(net "SMB_LTC4282_TEMP_SCL")
	)
	(segment
		(start 275.040852 -367.635028)
		(end 275.223224 -367.635028)
		(width 0.15494)
		(layer "In9.Cu")
		(net "SMB_LTC4282_TEMP_SCL")
	)
	(segment
		(start 275.891244 -366.967008)
		(end 276.073616 -366.967008)
		(width 0.15494)
		(layer "In9.Cu")
		(net "SMB_LTC4282_TEMP_SCL")
	)
	(segment
		(start 275.53412 -367.945924)
		(end 275.53412 -368.128296)
		(width 0.15494)
		(layer "In9.Cu")
		(net "SMB_LTC4282_TEMP_SCL")
	)
	(segment
		(start 275.269452 -366.345216)
		(end 275.451824 -366.345216)
		(width 0.15494)
		(layer "In9.Cu")
		(net "SMB_LTC4282_TEMP_SCL")
	)
	(segment
		(start 275.580348 -366.656112)
		(end 274.912328 -367.324132)
		(width 0.15494)
		(layer "In9.Cu")
		(net "SMB_LTC4282_TEMP_SCL")
	)
	(segment
		(start 274.41906 -367.013236)
		(end 274.601432 -367.013236)
		(width 0.15494)
		(layer "In9.Cu")
		(net "SMB_LTC4282_TEMP_SCL")
	)
	(segment
		(start 275.845016 -368.25682)
		(end 276.513036 -367.5888)
		(width 0.15494)
		(layer "In9.Cu")
		(net "SMB_LTC4282_TEMP_SCL")
	)
	(segment
		(start 276.777704 -369.189508)
		(end 276.777704 -369.37188)
		(width 0.15494)
		(layer "In9.Cu")
		(net "SMB_LTC4282_TEMP_SCL")
	)
	(segment
		(start 276.155912 -368.750088)
		(end 276.284436 -368.878612)
		(width 0.15494)
		(layer "In9.Cu")
		(net "SMB_LTC4282_TEMP_SCL")
	)
	(segment
		(start 274.290536 -366.884712)
		(end 274.41906 -367.013236)
		(width 0.15494)
		(layer "In9.Cu")
		(net "SMB_LTC4282_TEMP_SCL")
	)
	(segment
		(start 275.580348 -366.47374)
		(end 275.580348 -366.656112)
		(width 0.15494)
		(layer "In9.Cu")
		(net "SMB_LTC4282_TEMP_SCL")
	)
	(segment
		(start 276.20214 -367.277904)
		(end 275.53412 -367.945924)
		(width 0.15494)
		(layer "In9.Cu")
		(net "SMB_LTC4282_TEMP_SCL")
	)
	(segment
		(start 274.290536 -366.70234)
		(end 274.290536 -366.884712)
		(width 0.15494)
		(layer "In9.Cu")
		(net "SMB_LTC4282_TEMP_SCL")
	)
	(segment
		(start 277.3172 -368.210592)
		(end 277.445724 -368.339116)
		(width 0.15494)
		(layer "In9.Cu")
		(net "SMB_LTC4282_TEMP_SCL")
	)
	(segment
		(start 275.53412 -368.128296)
		(end 275.662644 -368.25682)
		(width 0.15494)
		(layer "In9.Cu")
		(net "SMB_LTC4282_TEMP_SCL")
	)
	(segment
		(start 277.75662 -368.832384)
		(end 277.938992 -368.832384)
		(width 0.15494)
		(layer "In9.Cu")
		(net "SMB_LTC4282_TEMP_SCL")
	)
	(segment
		(start 276.155912 -368.567716)
		(end 276.155912 -368.750088)
		(width 0.15494)
		(layer "In9.Cu")
		(net "SMB_LTC4282_TEMP_SCL")
	)
	(segment
		(start 275.223224 -367.635028)
		(end 275.891244 -366.967008)
		(width 0.15494)
		(layer "In9.Cu")
		(net "SMB_LTC4282_TEMP_SCL")
	)
	(segment
		(start 276.466808 -368.878612)
		(end 277.134828 -368.210592)
		(width 0.15494)
		(layer "In9.Cu")
		(net "SMB_LTC4282_TEMP_SCL")
	)
	(segment
		(start 276.20214 -367.095532)
		(end 276.20214 -367.277904)
		(width 0.15494)
		(layer "In9.Cu")
		(net "SMB_LTC4282_TEMP_SCL")
	)
	(segment
		(start 276.695408 -367.5888)
		(end 276.823932 -367.717324)
		(width 0.15494)
		(layer "In9.Cu")
		(net "SMB_LTC4282_TEMP_SCL")
	)
	(segment
		(start 232.164382 -341.785702)
		(end 232.729278 -341.785702)
		(width 0.15494)
		(layer "In9.Cu")
		(net "SMB_LTC4282_TEMP_SCL")
	)
	(segment
		(start 277.0886 -369.500404)
		(end 277.75662 -368.832384)
		(width 0.15494)
		(layer "In9.Cu")
		(net "SMB_LTC4282_TEMP_SCL")
	)
	(segment
		(start 277.3934 -392.7602)
		(end 277.24735 -392.7602)
		(width 0.15494)
		(layer "In9.Cu")
		(net "SMB_LTC4282_TEMP_SCL")
	)
	(segment
		(start 276.906228 -369.500404)
		(end 277.0886 -369.500404)
		(width 0.15494)
		(layer "In9.Cu")
		(net "SMB_LTC4282_TEMP_SCL")
	)
	(segment
		(start 235.527596 -344.58402)
		(end 263.372092 -344.58402)
		(width 0.15494)
		(layer "In9.Cu")
		(net "SMB_LTC4282_TEMP_SCL")
	)
	(segment
		(start 264.911332 -346.12326)
		(end 264.911332 -355.804724)
		(width 0.15494)
		(layer "In9.Cu")
		(net "SMB_LTC4282_TEMP_SCL")
	)
	(segment
		(start 274.601432 -367.013236)
		(end 275.269452 -366.345216)
		(width 0.15494)
		(layer "In9.Cu")
		(net "SMB_LTC4282_TEMP_SCL")
	)
	(segment
		(start 276.073616 -366.967008)
		(end 276.20214 -367.095532)
		(width 0.15494)
		(layer "In9.Cu")
		(net "SMB_LTC4282_TEMP_SCL")
	)
	(segment
		(start 276.777704 -369.37188)
		(end 276.906228 -369.500404)
		(width 0.15494)
		(layer "In9.Cu")
		(net "SMB_LTC4282_TEMP_SCL")
	)
	(segment
		(start 277.938992 -368.832384)
		(end 280.748232 -371.641624)
		(width 0.15494)
		(layer "In9.Cu")
		(net "SMB_LTC4282_TEMP_SCL")
	)
	(segment
		(start 274.912328 -367.324132)
		(end 274.912328 -367.506504)
		(width 0.15494)
		(layer "In9.Cu")
		(net "SMB_LTC4282_TEMP_SCL")
	)
	(segment
		(start 278.58212 -386.498592)
		(end 278.58212 -387.7818)
		(width 0.254)
		(layer "F.Cu")
		(net "LTC4282_TEMP_D-")
	)
	(segment
		(start 271.490694 -368.632994)
		(end 270.176244 -369.947444)
		(width 0.254)
		(layer "F.Cu")
		(net "LTC4282_TEMP_D-")
	)
	(segment
		(start 270.176244 -369.947444)
		(end 269.59814 -369.947444)
		(width 0.254)
		(layer "F.Cu")
		(net "LTC4282_TEMP_D-")
	)
	(via
		(at 278.58212 -387.7818)
		(size 0.508)
		(drill 0.254)
		(layers "F.Cu" "B.Cu")
		(net "LTC4282_TEMP_D-")
	)
	(via
		(at 271.490694 -368.632994)
		(size 0.508)
		(drill 0.254)
		(layers "F.Cu" "B.Cu")
		(net "LTC4282_TEMP_D-")
	)
	(segment
		(start 278.257 -386.334)
		(end 278.257 -387.45668)
		(width 0.13208)
		(layer "B.Cu")
		(net "LTC4282_TEMP_D-")
	)
	(segment
		(start 278.257 -387.45668)
		(end 278.58212 -387.7818)
		(width 0.13208)
		(layer "B.Cu")
		(net "LTC4282_TEMP_D-")
	)
	(segment
		(start 271.490694 -368.632994)
		(end 273.952208 -368.632994)
		(width 0.254)
		(layer "In9.Cu")
		(net "LTC4282_TEMP_D-")
	)
	(segment
		(start 279.17521 -373.855996)
		(end 279.17521 -387.18871)
		(width 0.254)
		(layer "In9.Cu")
		(net "LTC4282_TEMP_D-")
	)
	(segment
		(start 279.17521 -387.18871)
		(end 278.58212 -387.7818)
		(width 0.254)
		(layer "In9.Cu")
		(net "LTC4282_TEMP_D-")
	)
	(segment
		(start 273.952208 -368.632994)
		(end 279.17521 -373.855996)
		(width 0.254)
		(layer "In9.Cu")
		(net "LTC4282_TEMP_D-")
	)
	(segment
		(start 277.248366 -388.294372)
		(end 277.248366 -388.236714)
		(width 0.254)
		(layer "F.Cu")
		(net "LTC4282_TEMP_D+")
	)
	(segment
		(start 277.93188 -387.5532)
		(end 277.93188 -386.498592)
		(width 0.254)
		(layer "F.Cu")
		(net "LTC4282_TEMP_D+")
	)
	(segment
		(start 277.248366 -388.236714)
		(end 277.93188 -387.5532)
		(width 0.254)
		(layer "F.Cu")
		(net "LTC4282_TEMP_D+")
	)
	(segment
		(start 270.83004 -367.167414)
		(end 271.689068 -367.167414)
		(width 0.254)
		(layer "F.Cu")
		(net "LTC4282_TEMP_D+")
	)
	(via
		(at 277.248366 -388.294372)
		(size 0.508)
		(drill 0.254)
		(layers "F.Cu" "B.Cu")
		(net "LTC4282_TEMP_D+")
	)
	(via
		(at 271.689068 -367.167414)
		(size 0.508)
		(drill 0.254)
		(layers "F.Cu" "B.Cu")
		(net "LTC4282_TEMP_D+")
	)
	(segment
		(start 276.7838 -387.829806)
		(end 276.7838 -386.334)
		(width 0.13208)
		(layer "B.Cu")
		(net "LTC4282_TEMP_D+")
	)
	(segment
		(start 277.248366 -388.294372)
		(end 276.7838 -387.829806)
		(width 0.13208)
		(layer "B.Cu")
		(net "LTC4282_TEMP_D+")
	)
	(segment
		(start 277.248366 -388.294372)
		(end 277.33752 -388.383526)
		(width 0.254)
		(layer "In9.Cu")
		(net "LTC4282_TEMP_D+")
	)
	(segment
		(start 277.33752 -388.383526)
		(end 278.784558 -388.383526)
		(width 0.254)
		(layer "In9.Cu")
		(net "LTC4282_TEMP_D+")
	)
	(segment
		(start 279.55621 -373.698008)
		(end 273.025616 -367.167414)
		(width 0.254)
		(layer "In9.Cu")
		(net "LTC4282_TEMP_D+")
	)
	(segment
		(start 278.784558 -388.383526)
		(end 279.55621 -387.611874)
		(width 0.254)
		(layer "In9.Cu")
		(net "LTC4282_TEMP_D+")
	)
	(segment
		(start 279.55621 -387.611874)
		(end 279.55621 -373.698008)
		(width 0.254)
		(layer "In9.Cu")
		(net "LTC4282_TEMP_D+")
	)
	(segment
		(start 273.025616 -367.167414)
		(end 271.689068 -367.167414)
		(width 0.254)
		(layer "In9.Cu")
		(net "LTC4282_TEMP_D+")
	)
	(segment
		(start 267.511276 -369.949222)
		(end 268.770862 -369.949222)
		(width 0.13208)
		(layer "F.Cu")
		(net "LTC4282_TEMP_R_D-")
	)
	(segment
		(start 267.511276 -368.527584)
		(end 267.511276 -369.949222)
		(width 0.13208)
		(layer "F.Cu")
		(net "LTC4282_TEMP_R_D-")
	)
	(segment
		(start 268.770862 -369.949222)
		(end 268.77264 -369.947444)
		(width 0.13208)
		(layer "F.Cu")
		(net "LTC4282_TEMP_R_D-")
	)
	(segment
		(start 268.77264 -369.947444)
		(end 268.79804 -369.947444)
		(width 0.13208)
		(layer "F.Cu")
		(net "LTC4282_TEMP_R_D-")
	)
	(via
		(at 267.511276 -369.949222)
		(size 0.762)
		(drill 0.381)
		(layers "F.Cu" "B.Cu")
		(net "LTC4282_TEMP_R_D-")
	)
	(segment
		(start 269.411196 -368.527584)
		(end 268.705838 -368.527584)
		(width 0.13208)
		(layer "F.Cu")
		(net "LTC4282_TEMP_R_D+")
	)
	(segment
		(start 268.461236 -368.282982)
		(end 268.461236 -366.527588)
		(width 0.13208)
		(layer "F.Cu")
		(net "LTC4282_TEMP_R_D+")
	)
	(segment
		(start 270.83004 -366.367314)
		(end 270.83004 -365.572548)
		(width 0.13208)
		(layer "F.Cu")
		(net "LTC4282_TEMP_R_D+")
	)
	(segment
		(start 268.461236 -365.808514)
		(end 268.461236 -366.527588)
		(width 0.13208)
		(layer "F.Cu")
		(net "LTC4282_TEMP_R_D+")
	)
	(segment
		(start 270.83004 -365.572548)
		(end 270.491712 -365.23422)
		(width 0.13208)
		(layer "F.Cu")
		(net "LTC4282_TEMP_R_D+")
	)
	(segment
		(start 269.03553 -365.23422)
		(end 268.461236 -365.808514)
		(width 0.13208)
		(layer "F.Cu")
		(net "LTC4282_TEMP_R_D+")
	)
	(segment
		(start 269.761462 -365.23422)
		(end 269.03553 -365.23422)
		(width 0.13208)
		(layer "F.Cu")
		(net "LTC4282_TEMP_R_D+")
	)
	(segment
		(start 270.491712 -365.23422)
		(end 269.761462 -365.23422)
		(width 0.13208)
		(layer "F.Cu")
		(net "LTC4282_TEMP_R_D+")
	)
	(segment
		(start 268.705838 -368.527584)
		(end 268.461236 -368.282982)
		(width 0.13208)
		(layer "F.Cu")
		(net "LTC4282_TEMP_R_D+")
	)
	(via
		(at 269.761462 -365.23422)
		(size 0.762)
		(drill 0.381)
		(layers "F.Cu" "B.Cu")
		(net "LTC4282_TEMP_R_D+")
	)
	(segment
		(start 247.718072 -366.875568)
		(end 248.649236 -366.875568)
		(width 0.508)
		(layer "F.Cu")
		(net "HS_GATE2_R_1")
	)
	(via
		(at 247.346724 -366.875568)
		(size 0.6604)
		(drill 0.3302)
		(layers "F.Cu" "B.Cu")
		(net "HS_GATE2_R_1")
	)
	(via
		(at 248.649236 -366.875568)
		(size 0.508)
		(drill 0.254)
		(layers "F.Cu" "B.Cu")
		(net "HS_GATE2_R_1")
	)
	(segment
		(start 247.346724 -366.875568)
		(end 245.970552 -366.875568)
		(width 0.508)
		(layer "B.Cu")
		(net "HS_GATE2_R_1")
	)
	(segment
		(start 245.970552 -366.875568)
		(end 245.949724 -366.896396)
		(width 0.508)
		(layer "B.Cu")
		(net "HS_GATE2_R_1")
	)
	(segment
		(start 245.949724 -366.896396)
		(end 245.905782 -366.896396)
		(width 0.508)
		(layer "B.Cu")
		(net "HS_GATE2_R_1")
	)
	(segment
		(start 248.649236 -366.875568)
		(end 247.346724 -366.875568)
		(width 0.508)
		(layer "B.Cu")
		(net "HS_GATE2_R_1")
	)
	(segment
		(start 241.98453 -366.811306)
		(end 241.07394 -366.811306)
		(width 0.508)
		(layer "F.Cu")
		(net "HS_GATE1_R_1")
	)
	(via
		(at 241.98453 -366.811306)
		(size 0.508)
		(drill 0.254)
		(layers "F.Cu" "B.Cu")
		(net "HS_GATE1_R_1")
	)
	(via
		(at 240.642394 -366.750854)
		(size 0.6604)
		(drill 0.3302)
		(layers "F.Cu" "B.Cu")
		(net "HS_GATE1_R_1")
	)
	(segment
		(start 241.98453 -366.811306)
		(end 241.924078 -366.750854)
		(width 0.508)
		(layer "B.Cu")
		(net "HS_GATE1_R_1")
	)
	(segment
		(start 241.924078 -366.750854)
		(end 240.642394 -366.750854)
		(width 0.508)
		(layer "B.Cu")
		(net "HS_GATE1_R_1")
	)
	(segment
		(start 240.642394 -366.750854)
		(end 239.290352 -366.750854)
		(width 0.508)
		(layer "B.Cu")
		(net "HS_GATE1_R_1")
	)
	(segment
		(start 259.426964 -366.900968)
		(end 260.50621 -366.900968)
		(width 0.508)
		(layer "F.Cu")
		(net "HS_GATE2_R_3")
	)
	(via
		(at 260.50621 -366.900968)
		(size 0.508)
		(drill 0.254)
		(layers "F.Cu" "B.Cu")
		(net "HS_GATE2_R_3")
	)
	(via
		(at 259.129784 -366.900968)
		(size 0.6604)
		(drill 0.3302)
		(layers "F.Cu" "B.Cu")
		(net "HS_GATE2_R_3")
	)
	(segment
		(start 259.129784 -366.900968)
		(end 257.70967 -366.900968)
		(width 0.508)
		(layer "B.Cu")
		(net "HS_GATE2_R_3")
	)
	(segment
		(start 260.50621 -366.900968)
		(end 259.129784 -366.900968)
		(width 0.508)
		(layer "B.Cu")
		(net "HS_GATE2_R_3")
	)
	(segment
		(start 257.70459 -366.906048)
		(end 257.664966 -366.906048)
		(width 0.508)
		(layer "B.Cu")
		(net "HS_GATE2_R_3")
	)
	(segment
		(start 257.70967 -366.900968)
		(end 257.70459 -366.906048)
		(width 0.508)
		(layer "B.Cu")
		(net "HS_GATE2_R_3")
	)
	(segment
		(start 253.576836 -366.875568)
		(end 254.557276 -366.875568)
		(width 0.508)
		(layer "F.Cu")
		(net "HS_GATE2_R_2")
	)
	(via
		(at 252.728476 -366.83696)
		(size 0.6604)
		(drill 0.3302)
		(layers "F.Cu" "B.Cu")
		(net "HS_GATE2_R_2")
	)
	(via
		(at 254.557276 -366.875568)
		(size 0.508)
		(drill 0.254)
		(layers "F.Cu" "B.Cu")
		(net "HS_GATE2_R_2")
	)
	(segment
		(start 254.518668 -366.83696)
		(end 252.728476 -366.83696)
		(width 0.508)
		(layer "B.Cu")
		(net "HS_GATE2_R_2")
	)
	(segment
		(start 254.557276 -366.875568)
		(end 254.518668 -366.83696)
		(width 0.508)
		(layer "B.Cu")
		(net "HS_GATE2_R_2")
	)
	(segment
		(start 252.728476 -366.83696)
		(end 251.540772 -366.83696)
		(width 0.508)
		(layer "B.Cu")
		(net "HS_GATE2_R_2")
	)
	(segment
		(start 355.375972 -258.99491)
		(end 355.96576 -258.99491)
		(width 0.13208)
		(layer "F.Cu")
		(net "P0V8_PEX2_SVID")
	)
	(segment
		(start 355.96576 -258.99491)
		(end 356.16261 -259.19176)
		(width 0.13208)
		(layer "F.Cu")
		(net "P0V8_PEX2_SVID")
	)
	(segment
		(start 355.375972 -259.39496)
		(end 355.95941 -259.39496)
		(width 0.13208)
		(layer "F.Cu")
		(net "P0V8_PEX2_SVID")
	)
	(segment
		(start 355.95941 -259.39496)
		(end 356.16261 -259.19176)
		(width 0.13208)
		(layer "F.Cu")
		(net "P0V8_PEX2_SVID")
	)
	(via
		(at 356.16261 -259.19176)
		(size 0.508)
		(drill 0.254)
		(layers "F.Cu" "B.Cu")
		(net "P0V8_PEX2_SVID")
	)
	(via
		(at 356.313486 -260.142736)
		(size 0.6604)
		(drill 0.3302)
		(layers "F.Cu" "B.Cu")
		(net "P0V8_PEX2_SVID")
	)
	(segment
		(start 356.313486 -260.142736)
		(end 356.331266 -260.160516)
		(width 0.13208)
		(layer "B.Cu")
		(net "P0V8_PEX2_SVID")
	)
	(segment
		(start 356.331266 -260.160516)
		(end 357.487474 -260.160516)
		(width 0.13208)
		(layer "B.Cu")
		(net "P0V8_PEX2_SVID")
	)
	(segment
		(start 356.16261 -259.99186)
		(end 356.313486 -260.142736)
		(width 0.13208)
		(layer "B.Cu")
		(net "P0V8_PEX2_SVID")
	)
	(segment
		(start 357.487474 -260.160516)
		(end 357.487474 -261.179818)
		(width 0.13208)
		(layer "B.Cu")
		(net "P0V8_PEX2_SVID")
	)
	(segment
		(start 356.16261 -259.19176)
		(end 356.16261 -259.99186)
		(width 0.13208)
		(layer "B.Cu")
		(net "P0V8_PEX2_SVID")
	)
	(segment
		(start 123.175776 -259.39496)
		(end 123.759214 -259.39496)
		(width 0.13208)
		(layer "F.Cu")
		(net "P0V8_PEX0_SVID")
	)
	(segment
		(start 123.175776 -258.99491)
		(end 123.765564 -258.99491)
		(width 0.13208)
		(layer "F.Cu")
		(net "P0V8_PEX0_SVID")
	)
	(segment
		(start 123.759214 -259.39496)
		(end 123.962414 -259.19176)
		(width 0.13208)
		(layer "F.Cu")
		(net "P0V8_PEX0_SVID")
	)
	(segment
		(start 123.765564 -258.99491)
		(end 123.962414 -259.19176)
		(width 0.13208)
		(layer "F.Cu")
		(net "P0V8_PEX0_SVID")
	)
	(via
		(at 124.153676 -260.116574)
		(size 0.6604)
		(drill 0.3302)
		(layers "F.Cu" "B.Cu")
		(net "P0V8_PEX0_SVID")
	)
	(via
		(at 123.962414 -259.19176)
		(size 0.508)
		(drill 0.254)
		(layers "F.Cu" "B.Cu")
		(net "P0V8_PEX0_SVID")
	)
	(segment
		(start 124.175012 -260.13791)
		(end 124.153676 -260.116574)
		(width 0.13208)
		(layer "B.Cu")
		(net "P0V8_PEX0_SVID")
	)
	(segment
		(start 123.962414 -259.19176)
		(end 123.962414 -259.925312)
		(width 0.13208)
		(layer "B.Cu")
		(net "P0V8_PEX0_SVID")
	)
	(segment
		(start 125.310138 -261.15391)
		(end 125.313186 -261.150862)
		(width 0.13208)
		(layer "B.Cu")
		(net "P0V8_PEX0_SVID")
	)
	(segment
		(start 125.313186 -260.13791)
		(end 124.175012 -260.13791)
		(width 0.13208)
		(layer "B.Cu")
		(net "P0V8_PEX0_SVID")
	)
	(segment
		(start 123.962414 -259.925312)
		(end 124.153676 -260.116574)
		(width 0.13208)
		(layer "B.Cu")
		(net "P0V8_PEX0_SVID")
	)
	(segment
		(start 125.313186 -261.150862)
		(end 125.313186 -260.13791)
		(width 0.13208)
		(layer "B.Cu")
		(net "P0V8_PEX0_SVID")
	)
	(segment
		(start 241.5794 -214.324946)
		(end 241.5794 -213.78545)
		(width 0.2032)
		(layer "F.Cu")
		(net "P1V8_PLL0_PEX1_SCALED")
	)
	(segment
		(start 238.451136 -213.614)
		(end 238.781336 -213.9442)
		(width 0.2032)
		(layer "F.Cu")
		(net "P1V8_PLL0_PEX1_SCALED")
	)
	(segment
		(start 240.5888 -213.78545)
		(end 241.5794 -213.78545)
		(width 0.2032)
		(layer "F.Cu")
		(net "P1V8_PLL0_PEX1_SCALED")
	)
	(segment
		(start 240.43005 -213.9442)
		(end 240.5888 -213.78545)
		(width 0.2032)
		(layer "F.Cu")
		(net "P1V8_PLL0_PEX1_SCALED")
	)
	(segment
		(start 243.3828 -214.299546)
		(end 243.128546 -214.5538)
		(width 0.2032)
		(layer "F.Cu")
		(net "P1V8_PLL0_PEX1_SCALED")
	)
	(segment
		(start 238.0488 -213.614)
		(end 238.451136 -213.614)
		(width 0.2032)
		(layer "F.Cu")
		(net "P1V8_PLL0_PEX1_SCALED")
	)
	(segment
		(start 238.781336 -213.9442)
		(end 240.43005 -213.9442)
		(width 0.2032)
		(layer "F.Cu")
		(net "P1V8_PLL0_PEX1_SCALED")
	)
	(segment
		(start 243.3828 -213.78545)
		(end 243.3828 -214.299546)
		(width 0.2032)
		(layer "F.Cu")
		(net "P1V8_PLL0_PEX1_SCALED")
	)
	(segment
		(start 241.808254 -214.5538)
		(end 241.5794 -214.324946)
		(width 0.2032)
		(layer "F.Cu")
		(net "P1V8_PLL0_PEX1_SCALED")
	)
	(segment
		(start 234.667552 -215.104218)
		(end 235.067348 -214.704422)
		(width 0.2032)
		(layer "F.Cu")
		(net "P1V8_PLL0_PEX1_SCALED")
	)
	(segment
		(start 243.128546 -214.5538)
		(end 241.808254 -214.5538)
		(width 0.2032)
		(layer "F.Cu")
		(net "P1V8_PLL0_PEX1_SCALED")
	)
	(via
		(at 239.619028 -212.19033)
		(size 0.6604)
		(drill 0.3302)
		(layers "F.Cu" "B.Cu")
		(net "P1V8_PLL0_PEX1_SCALED")
	)
	(via
		(at 235.067348 -214.704422)
		(size 0.4572)
		(drill 0.254)
		(layers "F.Cu" "B.Cu")
		(net "P1V8_PLL0_PEX1_SCALED")
	)
	(via
		(at 238.0488 -213.614)
		(size 0.508)
		(drill 0.254)
		(layers "F.Cu" "B.Cu")
		(net "P1V8_PLL0_PEX1_SCALED")
	)
	(segment
		(start 238.61014 -212.419946)
		(end 238.32312 -212.706966)
		(width 0.13208)
		(layer "B.Cu")
		(net "P1V8_PLL0_PEX1_SCALED")
	)
	(segment
		(start 238.055912 -213.614)
		(end 238.0488 -213.614)
		(width 0.13208)
		(layer "B.Cu")
		(net "P1V8_PLL0_PEX1_SCALED")
	)
	(segment
		(start 239.389412 -212.419946)
		(end 238.61014 -212.419946)
		(width 0.13208)
		(layer "B.Cu")
		(net "P1V8_PLL0_PEX1_SCALED")
	)
	(segment
		(start 239.619028 -212.19033)
		(end 239.389412 -212.419946)
		(width 0.13208)
		(layer "B.Cu")
		(net "P1V8_PLL0_PEX1_SCALED")
	)
	(segment
		(start 238.32312 -212.706966)
		(end 238.32312 -213.346792)
		(width 0.13208)
		(layer "B.Cu")
		(net "P1V8_PLL0_PEX1_SCALED")
	)
	(segment
		(start 238.32312 -213.346792)
		(end 238.055912 -213.614)
		(width 0.13208)
		(layer "B.Cu")
		(net "P1V8_PLL0_PEX1_SCALED")
	)
	(segment
		(start 238.0488 -214.1728)
		(end 237.3376 -214.884)
		(width 0.2032)
		(layer "In5.Cu")
		(net "P1V8_PLL0_PEX1_SCALED")
	)
	(segment
		(start 238.0488 -213.614)
		(end 238.0488 -214.1728)
		(width 0.2032)
		(layer "In5.Cu")
		(net "P1V8_PLL0_PEX1_SCALED")
	)
	(segment
		(start 236.7534 -214.884)
		(end 236.4486 -214.5792)
		(width 0.2032)
		(layer "In5.Cu")
		(net "P1V8_PLL0_PEX1_SCALED")
	)
	(segment
		(start 237.3376 -214.884)
		(end 236.7534 -214.884)
		(width 0.2032)
		(layer "In5.Cu")
		(net "P1V8_PLL0_PEX1_SCALED")
	)
	(segment
		(start 236.4486 -214.5792)
		(end 235.19257 -214.5792)
		(width 0.2032)
		(layer "In5.Cu")
		(net "P1V8_PLL0_PEX1_SCALED")
	)
	(segment
		(start 235.19257 -214.5792)
		(end 235.067348 -214.704422)
		(width 0.2032)
		(layer "In5.Cu")
		(net "P1V8_PLL0_PEX1_SCALED")
	)
	(segment
		(start 349.293942 -213.587076)
		(end 349.693738 -213.18728)
		(width 0.13208)
		(layer "F.Cu")
		(net "PWRGD_PEX3_P1V8_PLL_R")
	)
	(via
		(at 349.693738 -213.18728)
		(size 0.4572)
		(drill 0.254)
		(layers "F.Cu" "B.Cu")
		(net "PWRGD_PEX3_P1V8_PLL_R")
	)
	(via
		(at 355.567488 -214.657686)
		(size 0.508)
		(drill 0.254)
		(layers "F.Cu" "B.Cu")
		(net "PWRGD_PEX3_P1V8_PLL_R")
	)
	(via
		(at 352.116898 -212.471)
		(size 0.6604)
		(drill 0.3302)
		(layers "F.Cu" "B.Cu")
		(net "PWRGD_PEX3_P1V8_PLL_R")
	)
	(via
		(at 375.075958 -210.217004)
		(size 0.508)
		(drill 0.254)
		(layers "F.Cu" "B.Cu")
		(net "PWRGD_PEX3_P1V8_PLL_R")
	)
	(via
		(at 459.235556 -250.147328)
		(size 0.508)
		(drill 0.254)
		(layers "F.Cu" "B.Cu")
		(net "PWRGD_PEX3_P1V8_PLL_R")
	)
	(segment
		(start 350.410018 -212.471)
		(end 352.116898 -212.471)
		(width 0.13208)
		(layer "B.Cu")
		(net "PWRGD_PEX3_P1V8_PLL_R")
	)
	(segment
		(start 352.116898 -212.471)
		(end 352.830892 -212.471)
		(width 0.13208)
		(layer "B.Cu")
		(net "PWRGD_PEX3_P1V8_PLL_R")
	)
	(segment
		(start 352.830892 -212.471)
		(end 355.017578 -214.657686)
		(width 0.13208)
		(layer "B.Cu")
		(net "PWRGD_PEX3_P1V8_PLL_R")
	)
	(segment
		(start 349.693738 -213.18728)
		(end 350.410018 -212.471)
		(width 0.13208)
		(layer "B.Cu")
		(net "PWRGD_PEX3_P1V8_PLL_R")
	)
	(segment
		(start 355.017578 -214.657686)
		(end 355.567488 -214.657686)
		(width 0.13208)
		(layer "B.Cu")
		(net "PWRGD_PEX3_P1V8_PLL_R")
	)
	(segment
		(start 365.487966 -216.547446)
		(end 365.104172 -216.163652)
		(width 0.15494)
		(layer "In13.Cu")
		(net "PWRGD_PEX3_P1V8_PLL_R")
	)
	(segment
		(start 369.4938 -227.202746)
		(end 369.4938 -228.55174)
		(width 0.15494)
		(layer "In13.Cu")
		(net "PWRGD_PEX3_P1V8_PLL_R")
	)
	(segment
		(start 361.31373 -216.163652)
		(end 360.028744 -214.878666)
		(width 0.15494)
		(layer "In13.Cu")
		(net "PWRGD_PEX3_P1V8_PLL_R")
	)
	(segment
		(start 363.146848 -219.900246)
		(end 365.487966 -217.559128)
		(width 0.15494)
		(layer "In13.Cu")
		(net "PWRGD_PEX3_P1V8_PLL_R")
	)
	(segment
		(start 355.788468 -214.878666)
		(end 355.567488 -214.657686)
		(width 0.15494)
		(layer "In13.Cu")
		(net "PWRGD_PEX3_P1V8_PLL_R")
	)
	(segment
		(start 363.760512 -225.7806)
		(end 363.146848 -225.166936)
		(width 0.15494)
		(layer "In13.Cu")
		(net "PWRGD_PEX3_P1V8_PLL_R")
	)
	(segment
		(start 363.760512 -229.691946)
		(end 363.760512 -225.7806)
		(width 0.15494)
		(layer "In13.Cu")
		(net "PWRGD_PEX3_P1V8_PLL_R")
	)
	(segment
		(start 375.02465 -210.268312)
		(end 375.02465 -214.467186)
		(width 0.15494)
		(layer "In13.Cu")
		(net "PWRGD_PEX3_P1V8_PLL_R")
	)
	(segment
		(start 364.499398 -230.430832)
		(end 363.760512 -229.691946)
		(width 0.15494)
		(layer "In13.Cu")
		(net "PWRGD_PEX3_P1V8_PLL_R")
	)
	(segment
		(start 367.614708 -230.430832)
		(end 364.499398 -230.430832)
		(width 0.15494)
		(layer "In13.Cu")
		(net "PWRGD_PEX3_P1V8_PLL_R")
	)
	(segment
		(start 369.4938 -228.55174)
		(end 367.614708 -230.430832)
		(width 0.15494)
		(layer "In13.Cu")
		(net "PWRGD_PEX3_P1V8_PLL_R")
	)
	(segment
		(start 368.173 -225.881946)
		(end 369.4938 -227.202746)
		(width 0.15494)
		(layer "In13.Cu")
		(net "PWRGD_PEX3_P1V8_PLL_R")
	)
	(segment
		(start 363.146848 -225.166936)
		(end 363.146848 -219.900246)
		(width 0.15494)
		(layer "In13.Cu")
		(net "PWRGD_PEX3_P1V8_PLL_R")
	)
	(segment
		(start 365.104172 -216.163652)
		(end 361.31373 -216.163652)
		(width 0.15494)
		(layer "In13.Cu")
		(net "PWRGD_PEX3_P1V8_PLL_R")
	)
	(segment
		(start 375.02465 -214.467186)
		(end 368.173 -221.318836)
		(width 0.15494)
		(layer "In13.Cu")
		(net "PWRGD_PEX3_P1V8_PLL_R")
	)
	(segment
		(start 368.173 -221.318836)
		(end 368.173 -225.881946)
		(width 0.15494)
		(layer "In13.Cu")
		(net "PWRGD_PEX3_P1V8_PLL_R")
	)
	(segment
		(start 375.075958 -210.217004)
		(end 375.02465 -210.268312)
		(width 0.15494)
		(layer "In13.Cu")
		(net "PWRGD_PEX3_P1V8_PLL_R")
	)
	(segment
		(start 360.028744 -214.878666)
		(end 355.788468 -214.878666)
		(width 0.15494)
		(layer "In13.Cu")
		(net "PWRGD_PEX3_P1V8_PLL_R")
	)
	(segment
		(start 365.487966 -217.559128)
		(end 365.487966 -216.547446)
		(width 0.15494)
		(layer "In13.Cu")
		(net "PWRGD_PEX3_P1V8_PLL_R")
	)
	(segment
		(start 383.972054 -240.690146)
		(end 384.48107 -240.18113)
		(width 0.15494)
		(layer "In15.Cu")
		(net "PWRGD_PEX3_P1V8_PLL_R")
	)
	(segment
		(start 377.31446 -241.195352)
		(end 377.84024 -241.195352)
		(width 0.15494)
		(layer "In15.Cu")
		(net "PWRGD_PEX3_P1V8_PLL_R")
	)
	(segment
		(start 376.178064 -233.388154)
		(end 376.178064 -238.865156)
		(width 0.15494)
		(layer "In15.Cu")
		(net "PWRGD_PEX3_P1V8_PLL_R")
	)
	(segment
		(start 376.550682 -240.431574)
		(end 377.31446 -241.195352)
		(width 0.15494)
		(layer "In15.Cu")
		(net "PWRGD_PEX3_P1V8_PLL_R")
	)
	(segment
		(start 394.214604 -242.99418)
		(end 395.089888 -243.869464)
		(width 0.15494)
		(layer "In15.Cu")
		(net "PWRGD_PEX3_P1V8_PLL_R")
	)
	(segment
		(start 415.55035 -243.869464)
		(end 416.288982 -243.130832)
		(width 0.15494)
		(layer "In15.Cu")
		(net "PWRGD_PEX3_P1V8_PLL_R")
	)
	(segment
		(start 382.269238 -240.72977)
		(end 383.878836 -240.72977)
		(width 0.15494)
		(layer "In15.Cu")
		(net "PWRGD_PEX3_P1V8_PLL_R")
	)
	(segment
		(start 383.927858 -240.719864)
		(end 383.972054 -240.690146)
		(width 0.15494)
		(layer "In15.Cu")
		(net "PWRGD_PEX3_P1V8_PLL_R")
	)
	(segment
		(start 383.878836 -240.72977)
		(end 383.927858 -240.719864)
		(width 0.15494)
		(layer "In15.Cu")
		(net "PWRGD_PEX3_P1V8_PLL_R")
	)
	(segment
		(start 376.178064 -238.865156)
		(end 376.550682 -239.237774)
		(width 0.15494)
		(layer "In15.Cu")
		(net "PWRGD_PEX3_P1V8_PLL_R")
	)
	(segment
		(start 460.462122 -249.979434)
		(end 460.294228 -250.147328)
		(width 0.15494)
		(layer "In15.Cu")
		(net "PWRGD_PEX3_P1V8_PLL_R")
	)
	(segment
		(start 460.462122 -242.18011)
		(end 460.462122 -249.979434)
		(width 0.15494)
		(layer "In15.Cu")
		(net "PWRGD_PEX3_P1V8_PLL_R")
	)
	(segment
		(start 440.781948 -243.130832)
		(end 444.52032 -239.39246)
		(width 0.15494)
		(layer "In15.Cu")
		(net "PWRGD_PEX3_P1V8_PLL_R")
	)
	(segment
		(start 377.84024 -241.195352)
		(end 379.439932 -242.795044)
		(width 0.15494)
		(layer "In15.Cu")
		(net "PWRGD_PEX3_P1V8_PLL_R")
	)
	(segment
		(start 392.28649 -242.99418)
		(end 394.214604 -242.99418)
		(width 0.15494)
		(layer "In15.Cu")
		(net "PWRGD_PEX3_P1V8_PLL_R")
	)
	(segment
		(start 395.089888 -243.869464)
		(end 415.55035 -243.869464)
		(width 0.15494)
		(layer "In15.Cu")
		(net "PWRGD_PEX3_P1V8_PLL_R")
	)
	(segment
		(start 377.406408 -217.554302)
		(end 377.406408 -232.15981)
		(width 0.15494)
		(layer "In15.Cu")
		(net "PWRGD_PEX3_P1V8_PLL_R")
	)
	(segment
		(start 384.48107 -240.18113)
		(end 389.47344 -240.18113)
		(width 0.15494)
		(layer "In15.Cu")
		(net "PWRGD_PEX3_P1V8_PLL_R")
	)
	(segment
		(start 375.075958 -215.223852)
		(end 377.406408 -217.554302)
		(width 0.15494)
		(layer "In15.Cu")
		(net "PWRGD_PEX3_P1V8_PLL_R")
	)
	(segment
		(start 460.294228 -250.147328)
		(end 459.235556 -250.147328)
		(width 0.15494)
		(layer "In15.Cu")
		(net "PWRGD_PEX3_P1V8_PLL_R")
	)
	(segment
		(start 444.52032 -239.39246)
		(end 457.674472 -239.39246)
		(width 0.15494)
		(layer "In15.Cu")
		(net "PWRGD_PEX3_P1V8_PLL_R")
	)
	(segment
		(start 377.406408 -232.15981)
		(end 376.178064 -233.388154)
		(width 0.15494)
		(layer "In15.Cu")
		(net "PWRGD_PEX3_P1V8_PLL_R")
	)
	(segment
		(start 375.075958 -210.217004)
		(end 375.075958 -215.223852)
		(width 0.15494)
		(layer "In15.Cu")
		(net "PWRGD_PEX3_P1V8_PLL_R")
	)
	(segment
		(start 376.550682 -239.237774)
		(end 376.550682 -240.431574)
		(width 0.15494)
		(layer "In15.Cu")
		(net "PWRGD_PEX3_P1V8_PLL_R")
	)
	(segment
		(start 380.203964 -242.795044)
		(end 382.269238 -240.72977)
		(width 0.15494)
		(layer "In15.Cu")
		(net "PWRGD_PEX3_P1V8_PLL_R")
	)
	(segment
		(start 379.439932 -242.795044)
		(end 380.203964 -242.795044)
		(width 0.15494)
		(layer "In15.Cu")
		(net "PWRGD_PEX3_P1V8_PLL_R")
	)
	(segment
		(start 416.288982 -243.130832)
		(end 440.781948 -243.130832)
		(width 0.15494)
		(layer "In15.Cu")
		(net "PWRGD_PEX3_P1V8_PLL_R")
	)
	(segment
		(start 389.47344 -240.18113)
		(end 392.28649 -242.99418)
		(width 0.15494)
		(layer "In15.Cu")
		(net "PWRGD_PEX3_P1V8_PLL_R")
	)
	(segment
		(start 457.674472 -239.39246)
		(end 460.462122 -242.18011)
		(width 0.15494)
		(layer "In15.Cu")
		(net "PWRGD_PEX3_P1V8_PLL_R")
	)
	(segment
		(start 351.180654 -211.700364)
		(end 352.52787 -211.700364)
		(width 0.13208)
		(layer "F.Cu")
		(net "PWRGD_PEX2_P1V8_PLL_R")
	)
	(segment
		(start 352.723196 -211.505038)
		(end 354.57257 -211.505038)
		(width 0.13208)
		(layer "F.Cu")
		(net "PWRGD_PEX2_P1V8_PLL_R")
	)
	(segment
		(start 304.299366 -246.104664)
		(end 325.074788 -246.104664)
		(width 0.13208)
		(layer "F.Cu")
		(net "PWRGD_PEX2_P1V8_PLL_R")
	)
	(segment
		(start 303.431702 -245.237)
		(end 304.299366 -246.104664)
		(width 0.13208)
		(layer "F.Cu")
		(net "PWRGD_PEX2_P1V8_PLL_R")
	)
	(segment
		(start 263.525254 -245.237)
		(end 303.431702 -245.237)
		(width 0.13208)
		(layer "F.Cu")
		(net "PWRGD_PEX2_P1V8_PLL_R")
	)
	(segment
		(start 352.52787 -211.700364)
		(end 352.723196 -211.505038)
		(width 0.13208)
		(layer "F.Cu")
		(net "PWRGD_PEX2_P1V8_PLL_R")
	)
	(segment
		(start 350.893888 -211.98713)
		(end 351.180654 -211.700364)
		(width 0.13208)
		(layer "F.Cu")
		(net "PWRGD_PEX2_P1V8_PLL_R")
	)
	(segment
		(start 326.050656 -246.104664)
		(end 325.074788 -246.104664)
		(width 0.13208)
		(layer "F.Cu")
		(net "PWRGD_PEX2_P1V8_PLL_R")
	)
	(segment
		(start 327.861168 -244.294152)
		(end 326.050656 -246.104664)
		(width 0.13208)
		(layer "F.Cu")
		(net "PWRGD_PEX2_P1V8_PLL_R")
	)
	(segment
		(start 262.47598 -242.314476)
		(end 262.822944 -242.66144)
		(width 0.13208)
		(layer "F.Cu")
		(net "PWRGD_PEX2_P1V8_PLL_R")
	)
	(segment
		(start 262.822944 -244.53469)
		(end 263.525254 -245.237)
		(width 0.13208)
		(layer "F.Cu")
		(net "PWRGD_PEX2_P1V8_PLL_R")
	)
	(segment
		(start 262.822944 -242.66144)
		(end 262.822944 -244.53469)
		(width 0.13208)
		(layer "F.Cu")
		(net "PWRGD_PEX2_P1V8_PLL_R")
	)
	(segment
		(start 327.861168 -244.186202)
		(end 327.861168 -244.294152)
		(width 0.13208)
		(layer "F.Cu")
		(net "PWRGD_PEX2_P1V8_PLL_R")
	)
	(via
		(at 325.074788 -246.104664)
		(size 0.762)
		(drill 0.381)
		(layers "F.Cu" "B.Cu")
		(net "PWRGD_PEX2_P1V8_PLL_R")
	)
	(via
		(at 327.861168 -244.186202)
		(size 0.508)
		(drill 0.254)
		(layers "F.Cu" "B.Cu")
		(net "PWRGD_PEX2_P1V8_PLL_R")
	)
	(via
		(at 262.47598 -242.314476)
		(size 0.508)
		(drill 0.254)
		(layers "F.Cu" "B.Cu")
		(net "PWRGD_PEX2_P1V8_PLL_R")
	)
	(via
		(at 354.57257 -211.505038)
		(size 0.508)
		(drill 0.254)
		(layers "F.Cu" "B.Cu")
		(net "PWRGD_PEX2_P1V8_PLL_R")
	)
	(segment
		(start 355.11994 -209.677)
		(end 357.360474 -209.677)
		(width 0.15494)
		(layer "In9.Cu")
		(net "PWRGD_PEX2_P1V8_PLL_R")
	)
	(segment
		(start 328.031094 -242.907058)
		(end 328.031094 -243.941854)
		(width 0.15494)
		(layer "In9.Cu")
		(net "PWRGD_PEX2_P1V8_PLL_R")
	)
	(segment
		(start 330.835 -235.368338)
		(end 330.835 -235.965746)
		(width 0.15494)
		(layer "In9.Cu")
		(net "PWRGD_PEX2_P1V8_PLL_R")
	)
	(segment
		(start 339.757258 -231.3178)
		(end 335.439258 -235.6358)
		(width 0.15494)
		(layer "In9.Cu")
		(net "PWRGD_PEX2_P1V8_PLL_R")
	)
	(segment
		(start 354.57257 -210.22437)
		(end 355.11994 -209.677)
		(width 0.15494)
		(layer "In9.Cu")
		(net "PWRGD_PEX2_P1V8_PLL_R")
	)
	(segment
		(start 341.937594 -230.756968)
		(end 341.376762 -231.3178)
		(width 0.15494)
		(layer "In9.Cu")
		(net "PWRGD_PEX2_P1V8_PLL_R")
	)
	(segment
		(start 335.439258 -235.6358)
		(end 333.520796 -235.6358)
		(width 0.15494)
		(layer "In9.Cu")
		(net "PWRGD_PEX2_P1V8_PLL_R")
	)
	(segment
		(start 356.459282 -229.1334)
		(end 355.612192 -229.1334)
		(width 0.15494)
		(layer "In9.Cu")
		(net "PWRGD_PEX2_P1V8_PLL_R")
	)
	(segment
		(start 341.376762 -231.3178)
		(end 339.757258 -231.3178)
		(width 0.15494)
		(layer "In9.Cu")
		(net "PWRGD_PEX2_P1V8_PLL_R")
	)
	(segment
		(start 333.126334 -235.241338)
		(end 330.962 -235.241338)
		(width 0.15494)
		(layer "In9.Cu")
		(net "PWRGD_PEX2_P1V8_PLL_R")
	)
	(segment
		(start 328.5236 -238.277146)
		(end 328.5236 -242.414552)
		(width 0.15494)
		(layer "In9.Cu")
		(net "PWRGD_PEX2_P1V8_PLL_R")
	)
	(segment
		(start 333.520796 -235.6358)
		(end 333.126334 -235.241338)
		(width 0.15494)
		(layer "In9.Cu")
		(net "PWRGD_PEX2_P1V8_PLL_R")
	)
	(segment
		(start 330.835 -235.965746)
		(end 328.5236 -238.277146)
		(width 0.15494)
		(layer "In9.Cu")
		(net "PWRGD_PEX2_P1V8_PLL_R")
	)
	(segment
		(start 357.643938 -209.960464)
		(end 357.643938 -227.948744)
		(width 0.15494)
		(layer "In9.Cu")
		(net "PWRGD_PEX2_P1V8_PLL_R")
	)
	(segment
		(start 328.5236 -242.414552)
		(end 328.031094 -242.907058)
		(width 0.15494)
		(layer "In9.Cu")
		(net "PWRGD_PEX2_P1V8_PLL_R")
	)
	(segment
		(start 327.861168 -244.11178)
		(end 327.861168 -244.186202)
		(width 0.15494)
		(layer "In9.Cu")
		(net "PWRGD_PEX2_P1V8_PLL_R")
	)
	(segment
		(start 354.57257 -211.505038)
		(end 354.57257 -210.22437)
		(width 0.15494)
		(layer "In9.Cu")
		(net "PWRGD_PEX2_P1V8_PLL_R")
	)
	(segment
		(start 357.360474 -209.677)
		(end 357.643938 -209.960464)
		(width 0.15494)
		(layer "In9.Cu")
		(net "PWRGD_PEX2_P1V8_PLL_R")
	)
	(segment
		(start 330.962 -235.241338)
		(end 330.835 -235.368338)
		(width 0.15494)
		(layer "In9.Cu")
		(net "PWRGD_PEX2_P1V8_PLL_R")
	)
	(segment
		(start 345.467432 -230.756968)
		(end 341.937594 -230.756968)
		(width 0.15494)
		(layer "In9.Cu")
		(net "PWRGD_PEX2_P1V8_PLL_R")
	)
	(segment
		(start 355.612192 -229.1334)
		(end 354.240592 -230.505)
		(width 0.15494)
		(layer "In9.Cu")
		(net "PWRGD_PEX2_P1V8_PLL_R")
	)
	(segment
		(start 354.240592 -230.505)
		(end 345.7194 -230.505)
		(width 0.15494)
		(layer "In9.Cu")
		(net "PWRGD_PEX2_P1V8_PLL_R")
	)
	(segment
		(start 328.031094 -243.941854)
		(end 327.861168 -244.11178)
		(width 0.15494)
		(layer "In9.Cu")
		(net "PWRGD_PEX2_P1V8_PLL_R")
	)
	(segment
		(start 345.7194 -230.505)
		(end 345.467432 -230.756968)
		(width 0.15494)
		(layer "In9.Cu")
		(net "PWRGD_PEX2_P1V8_PLL_R")
	)
	(segment
		(start 357.643938 -227.948744)
		(end 356.459282 -229.1334)
		(width 0.15494)
		(layer "In9.Cu")
		(net "PWRGD_PEX2_P1V8_PLL_R")
	)
	(segment
		(start 349.293942 -215.187022)
		(end 349.693738 -214.787226)
		(width 0.13208)
		(layer "F.Cu")
		(net "PWRGD_PEX1_P1V8_PLL_R")
	)
	(via
		(at 349.693738 -214.787226)
		(size 0.4572)
		(drill 0.254)
		(layers "F.Cu" "B.Cu")
		(net "PWRGD_PEX1_P1V8_PLL_R")
	)
	(via
		(at 257.425444 -190.696342)
		(size 0.508)
		(drill 0.254)
		(layers "F.Cu" "B.Cu")
		(net "PWRGD_PEX1_P1V8_PLL_R")
	)
	(via
		(at 150.305516 -243.072666)
		(size 0.508)
		(drill 0.254)
		(layers "F.Cu" "B.Cu")
		(net "PWRGD_PEX1_P1V8_PLL_R")
	)
	(via
		(at 245.396258 -197.201028)
		(size 0.508)
		(drill 0.254)
		(layers "F.Cu" "B.Cu")
		(net "PWRGD_PEX1_P1V8_PLL_R")
	)
	(segment
		(start 241.28349 -189.164722)
		(end 238.780828 -186.66206)
		(width 0.13208)
		(layer "B.Cu")
		(net "PWRGD_PEX1_P1V8_PLL_R")
	)
	(segment
		(start 243.691664 -198.905622)
		(end 242.960398 -198.905622)
		(width 0.13208)
		(layer "B.Cu")
		(net "PWRGD_PEX1_P1V8_PLL_R")
	)
	(segment
		(start 158.050484 -237.043214)
		(end 152.402286 -237.043214)
		(width 0.13208)
		(layer "B.Cu")
		(net "PWRGD_PEX1_P1V8_PLL_R")
	)
	(segment
		(start 241.28349 -196.180202)
		(end 241.28349 -189.164722)
		(width 0.13208)
		(layer "B.Cu")
		(net "PWRGD_PEX1_P1V8_PLL_R")
	)
	(segment
		(start 207.748378 -190.42507)
		(end 204.587094 -190.42507)
		(width 0.13208)
		(layer "B.Cu")
		(net "PWRGD_PEX1_P1V8_PLL_R")
	)
	(segment
		(start 242.960398 -198.905622)
		(end 242.571524 -198.744586)
		(width 0.13208)
		(layer "B.Cu")
		(net "PWRGD_PEX1_P1V8_PLL_R")
	)
	(segment
		(start 152.402286 -237.043214)
		(end 151.858726 -237.586774)
		(width 0.13208)
		(layer "B.Cu")
		(net "PWRGD_PEX1_P1V8_PLL_R")
	)
	(segment
		(start 185.991246 -206.743808)
		(end 185.691018 -207.044036)
		(width 0.13208)
		(layer "B.Cu")
		(net "PWRGD_PEX1_P1V8_PLL_R")
	)
	(segment
		(start 242.073938 -198.247)
		(end 242.073938 -196.97065)
		(width 0.13208)
		(layer "B.Cu")
		(net "PWRGD_PEX1_P1V8_PLL_R")
	)
	(segment
		(start 150.305516 -242.13693)
		(end 150.305516 -243.072666)
		(width 0.13208)
		(layer "B.Cu")
		(net "PWRGD_PEX1_P1V8_PLL_R")
	)
	(segment
		(start 220.757242 -188.366654)
		(end 209.806794 -188.366654)
		(width 0.13208)
		(layer "B.Cu")
		(net "PWRGD_PEX1_P1V8_PLL_R")
	)
	(segment
		(start 238.780828 -186.66206)
		(end 222.461836 -186.66206)
		(width 0.13208)
		(layer "B.Cu")
		(net "PWRGD_PEX1_P1V8_PLL_R")
	)
	(segment
		(start 242.073938 -196.97065)
		(end 241.28349 -196.180202)
		(width 0.13208)
		(layer "B.Cu")
		(net "PWRGD_PEX1_P1V8_PLL_R")
	)
	(segment
		(start 209.806794 -188.366654)
		(end 207.748378 -190.42507)
		(width 0.13208)
		(layer "B.Cu")
		(net "PWRGD_PEX1_P1V8_PLL_R")
	)
	(segment
		(start 222.461836 -186.66206)
		(end 220.757242 -188.366654)
		(width 0.13208)
		(layer "B.Cu")
		(net "PWRGD_PEX1_P1V8_PLL_R")
	)
	(segment
		(start 188.268356 -206.743808)
		(end 185.991246 -206.743808)
		(width 0.13208)
		(layer "B.Cu")
		(net "PWRGD_PEX1_P1V8_PLL_R")
	)
	(segment
		(start 185.691018 -207.044036)
		(end 185.691018 -209.40268)
		(width 0.13208)
		(layer "B.Cu")
		(net "PWRGD_PEX1_P1V8_PLL_R")
	)
	(segment
		(start 245.396258 -197.201028)
		(end 243.691664 -198.905622)
		(width 0.13208)
		(layer "B.Cu")
		(net "PWRGD_PEX1_P1V8_PLL_R")
	)
	(segment
		(start 204.587094 -190.42507)
		(end 188.268356 -206.743808)
		(width 0.13208)
		(layer "B.Cu")
		(net "PWRGD_PEX1_P1V8_PLL_R")
	)
	(segment
		(start 151.858726 -240.58372)
		(end 150.305516 -242.13693)
		(width 0.13208)
		(layer "B.Cu")
		(net "PWRGD_PEX1_P1V8_PLL_R")
	)
	(segment
		(start 185.691018 -209.40268)
		(end 158.050484 -237.043214)
		(width 0.13208)
		(layer "B.Cu")
		(net "PWRGD_PEX1_P1V8_PLL_R")
	)
	(segment
		(start 151.858726 -237.586774)
		(end 151.858726 -240.58372)
		(width 0.13208)
		(layer "B.Cu")
		(net "PWRGD_PEX1_P1V8_PLL_R")
	)
	(segment
		(start 242.571524 -198.744586)
		(end 242.073938 -198.247)
		(width 0.13208)
		(layer "B.Cu")
		(net "PWRGD_PEX1_P1V8_PLL_R")
	)
	(segment
		(start 326.177148 -209.24774)
		(end 325.772018 -209.65287)
		(width 0.15494)
		(layer "In13.Cu")
		(net "PWRGD_PEX1_P1V8_PLL_R")
	)
	(segment
		(start 341.192104 -212.786214)
		(end 337.51647 -212.786214)
		(width 0.0889)
		(layer "In13.Cu")
		(net "PWRGD_PEX1_P1V8_PLL_R")
	)
	(segment
		(start 349.693738 -214.787226)
		(end 349.296228 -214.389716)
		(width 0.0889)
		(layer "In13.Cu")
		(net "PWRGD_PEX1_P1V8_PLL_R")
	)
	(segment
		(start 331.613764 -211.217764)
		(end 329.64374 -209.24774)
		(width 0.15494)
		(layer "In13.Cu")
		(net "PWRGD_PEX1_P1V8_PLL_R")
	)
	(segment
		(start 344.492072 -215.014302)
		(end 344.320622 -215.185752)
		(width 0.0889)
		(layer "In13.Cu")
		(net "PWRGD_PEX1_P1V8_PLL_R")
	)
	(segment
		(start 280.994104 -209.41157)
		(end 264.485628 -192.903094)
		(width 0.15494)
		(layer "In13.Cu")
		(net "PWRGD_PEX1_P1V8_PLL_R")
	)
	(segment
		(start 259.29463 -192.903094)
		(end 257.425444 -191.033908)
		(width 0.15494)
		(layer "In13.Cu")
		(net "PWRGD_PEX1_P1V8_PLL_R")
	)
	(segment
		(start 344.320622 -215.185752)
		(end 342.937592 -215.185752)
		(width 0.0889)
		(layer "In13.Cu")
		(net "PWRGD_PEX1_P1V8_PLL_R")
	)
	(segment
		(start 337.51647 -212.786214)
		(end 337.295744 -213.00694)
		(width 0.0889)
		(layer "In13.Cu")
		(net "PWRGD_PEX1_P1V8_PLL_R")
	)
	(segment
		(start 342.937592 -215.185752)
		(end 342.141556 -214.389716)
		(width 0.0889)
		(layer "In13.Cu")
		(net "PWRGD_PEX1_P1V8_PLL_R")
	)
	(segment
		(start 337.295744 -213.00694)
		(end 337.295744 -213.436454)
		(width 0.0889)
		(layer "In13.Cu")
		(net "PWRGD_PEX1_P1V8_PLL_R")
	)
	(segment
		(start 349.296228 -214.389716)
		(end 344.564716 -214.389716)
		(width 0.0889)
		(layer "In13.Cu")
		(net "PWRGD_PEX1_P1V8_PLL_R")
	)
	(segment
		(start 344.492072 -214.46236)
		(end 344.492072 -215.014302)
		(width 0.0889)
		(layer "In13.Cu")
		(net "PWRGD_PEX1_P1V8_PLL_R")
	)
	(segment
		(start 264.485628 -192.903094)
		(end 259.29463 -192.903094)
		(width 0.15494)
		(layer "In13.Cu")
		(net "PWRGD_PEX1_P1V8_PLL_R")
	)
	(segment
		(start 325.772018 -209.65287)
		(end 325.370698 -209.65287)
		(width 0.15494)
		(layer "In13.Cu")
		(net "PWRGD_PEX1_P1V8_PLL_R")
	)
	(segment
		(start 329.64374 -209.24774)
		(end 326.177148 -209.24774)
		(width 0.15494)
		(layer "In13.Cu")
		(net "PWRGD_PEX1_P1V8_PLL_R")
	)
	(segment
		(start 325.370698 -209.65287)
		(end 325.129398 -209.41157)
		(width 0.15494)
		(layer "In13.Cu")
		(net "PWRGD_PEX1_P1V8_PLL_R")
	)
	(segment
		(start 341.294212 -214.272622)
		(end 341.294212 -212.888322)
		(width 0.0889)
		(layer "In13.Cu")
		(net "PWRGD_PEX1_P1V8_PLL_R")
	)
	(segment
		(start 331.613764 -212.630766)
		(end 331.613764 -211.217764)
		(width 0.15494)
		(layer "In13.Cu")
		(net "PWRGD_PEX1_P1V8_PLL_R")
	)
	(segment
		(start 333.88046 -213.585806)
		(end 333.575914 -213.28126)
		(width 0.15494)
		(layer "In13.Cu")
		(net "PWRGD_PEX1_P1V8_PLL_R")
	)
	(segment
		(start 332.264258 -213.28126)
		(end 331.613764 -212.630766)
		(width 0.15494)
		(layer "In13.Cu")
		(net "PWRGD_PEX1_P1V8_PLL_R")
	)
	(segment
		(start 337.146392 -213.585806)
		(end 333.88046 -213.585806)
		(width 0.0889)
		(layer "In13.Cu")
		(net "PWRGD_PEX1_P1V8_PLL_R")
	)
	(segment
		(start 341.294212 -212.888322)
		(end 341.192104 -212.786214)
		(width 0.0889)
		(layer "In13.Cu")
		(net "PWRGD_PEX1_P1V8_PLL_R")
	)
	(segment
		(start 337.295744 -213.436454)
		(end 337.146392 -213.585806)
		(width 0.0889)
		(layer "In13.Cu")
		(net "PWRGD_PEX1_P1V8_PLL_R")
	)
	(segment
		(start 333.575914 -213.28126)
		(end 332.264258 -213.28126)
		(width 0.15494)
		(layer "In13.Cu")
		(net "PWRGD_PEX1_P1V8_PLL_R")
	)
	(segment
		(start 344.564716 -214.389716)
		(end 344.492072 -214.46236)
		(width 0.0889)
		(layer "In13.Cu")
		(net "PWRGD_PEX1_P1V8_PLL_R")
	)
	(segment
		(start 342.141556 -214.389716)
		(end 341.411306 -214.389716)
		(width 0.0889)
		(layer "In13.Cu")
		(net "PWRGD_PEX1_P1V8_PLL_R")
	)
	(segment
		(start 341.411306 -214.389716)
		(end 341.294212 -214.272622)
		(width 0.0889)
		(layer "In13.Cu")
		(net "PWRGD_PEX1_P1V8_PLL_R")
	)
	(segment
		(start 257.425444 -191.033908)
		(end 257.425444 -190.696342)
		(width 0.15494)
		(layer "In13.Cu")
		(net "PWRGD_PEX1_P1V8_PLL_R")
	)
	(segment
		(start 325.129398 -209.41157)
		(end 280.994104 -209.41157)
		(width 0.15494)
		(layer "In13.Cu")
		(net "PWRGD_PEX1_P1V8_PLL_R")
	)
	(segment
		(start 255.527556 -192.260982)
		(end 255.527556 -197.532244)
		(width 0.15494)
		(layer "In15.Cu")
		(net "PWRGD_PEX1_P1V8_PLL_R")
	)
	(segment
		(start 257.425444 -190.696342)
		(end 257.092196 -190.696342)
		(width 0.15494)
		(layer "In15.Cu")
		(net "PWRGD_PEX1_P1V8_PLL_R")
	)
	(segment
		(start 247.491504 -197.201028)
		(end 245.396258 -197.201028)
		(width 0.15494)
		(layer "In15.Cu")
		(net "PWRGD_PEX1_P1V8_PLL_R")
	)
	(segment
		(start 249.35942 -199.068944)
		(end 247.491504 -197.201028)
		(width 0.15494)
		(layer "In15.Cu")
		(net "PWRGD_PEX1_P1V8_PLL_R")
	)
	(segment
		(start 257.092196 -190.696342)
		(end 255.527556 -192.260982)
		(width 0.15494)
		(layer "In15.Cu")
		(net "PWRGD_PEX1_P1V8_PLL_R")
	)
	(segment
		(start 249.35942 -199.451468)
		(end 249.35942 -199.068944)
		(width 0.15494)
		(layer "In15.Cu")
		(net "PWRGD_PEX1_P1V8_PLL_R")
	)
	(segment
		(start 250.414282 -200.50633)
		(end 249.35942 -199.451468)
		(width 0.15494)
		(layer "In15.Cu")
		(net "PWRGD_PEX1_P1V8_PLL_R")
	)
	(segment
		(start 255.527556 -197.532244)
		(end 252.55347 -200.50633)
		(width 0.15494)
		(layer "In15.Cu")
		(net "PWRGD_PEX1_P1V8_PLL_R")
	)
	(segment
		(start 252.55347 -200.50633)
		(end 250.414282 -200.50633)
		(width 0.15494)
		(layer "In15.Cu")
		(net "PWRGD_PEX1_P1V8_PLL_R")
	)
	(via
		(at 148.870162 -244.298978)
		(size 0.508)
		(drill 0.254)
		(layers "F.Cu" "B.Cu")
		(net "PWRGD_PEX1_P1V8_PLL")
	)
	(segment
		(start 148.114766 -244.298978)
		(end 148.114004 -244.298216)
		(width 0.381)
		(layer "B.Cu")
		(net "PWRGD_PEX1_P1V8_PLL")
	)
	(segment
		(start 148.114004 -244.298216)
		(end 147.56765 -244.298216)
		(width 0.381)
		(layer "B.Cu")
		(net "PWRGD_PEX1_P1V8_PLL")
	)
	(segment
		(start 148.870162 -244.298978)
		(end 148.114766 -244.298978)
		(width 0.381)
		(layer "B.Cu")
		(net "PWRGD_PEX1_P1V8_PLL")
	)
	(segment
		(start 150.394162 -241.210084)
		(end 151.605234 -241.210084)
		(width 0.381)
		(layer "F.Cu")
		(net "P1V8_PLL_PEX1_ADJ")
	)
	(via
		(at 151.605234 -241.210084)
		(size 0.762)
		(drill 0.381)
		(layers "F.Cu" "B.Cu")
		(net "P1V8_PLL_PEX1_ADJ")
	)
	(via
		(at 144.933162 -243.130578)
		(size 0.508)
		(drill 0.254)
		(layers "F.Cu" "B.Cu")
		(net "PEX1_P1V8_PLL_EN")
	)
	(segment
		(start 144.685512 -242.882928)
		(end 144.933162 -243.130578)
		(width 0.254)
		(layer "B.Cu")
		(net "PEX1_P1V8_PLL_EN")
	)
	(segment
		(start 143.790162 -242.882928)
		(end 144.685512 -242.882928)
		(width 0.254)
		(layer "B.Cu")
		(net "PEX1_P1V8_PLL_EN")
	)
	(segment
		(start 19.73834 -212.231478)
		(end 19.062446 -212.231478)
		(width 0.254)
		(layer "F.Cu")
		(net "P1V8_PLL_PEX0_ADJ")
	)
	(segment
		(start 19.947382 -212.44052)
		(end 19.73834 -212.231478)
		(width 0.254)
		(layer "F.Cu")
		(net "P1V8_PLL_PEX0_ADJ")
	)
	(segment
		(start 19.732752 -215.230202)
		(end 19.947382 -215.015572)
		(width 0.254)
		(layer "F.Cu")
		(net "P1V8_PLL_PEX0_ADJ")
	)
	(segment
		(start 19.947382 -215.015572)
		(end 19.947382 -212.44052)
		(width 0.254)
		(layer "F.Cu")
		(net "P1V8_PLL_PEX0_ADJ")
	)
	(via
		(at 19.732752 -215.230202)
		(size 0.762)
		(drill 0.381)
		(layers "F.Cu" "B.Cu")
		(net "P1V8_PLL_PEX0_ADJ")
	)
	(via
		(at 17.538446 -215.320372)
		(size 0.508)
		(drill 0.254)
		(layers "F.Cu" "B.Cu")
		(net "PWRGD_PEX0_P1V8_PLL")
	)
	(segment
		(start 16.753078 -215.320372)
		(end 16.729964 -215.297258)
		(width 0.381)
		(layer "B.Cu")
		(net "PWRGD_PEX0_P1V8_PLL")
	)
	(segment
		(start 17.538446 -215.320372)
		(end 16.753078 -215.320372)
		(width 0.381)
		(layer "B.Cu")
		(net "PWRGD_PEX0_P1V8_PLL")
	)
	(segment
		(start 16.729964 -215.297258)
		(end 16.18361 -215.297258)
		(width 0.381)
		(layer "B.Cu")
		(net "PWRGD_PEX0_P1V8_PLL")
	)
	(via
		(at 13.601446 -214.151972)
		(size 0.508)
		(drill 0.254)
		(layers "F.Cu" "B.Cu")
		(net "PEX0_P1V8_PLL_EN")
	)
	(segment
		(start 13.353796 -213.904322)
		(end 13.601446 -214.151972)
		(width 0.254)
		(layer "B.Cu")
		(net "PEX0_P1V8_PLL_EN")
	)
	(segment
		(start 12.458446 -213.904322)
		(end 13.353796 -213.904322)
		(width 0.254)
		(layer "B.Cu")
		(net "PEX0_P1V8_PLL_EN")
	)
	(segment
		(start 239.317276 -226.368864)
		(end 238.608362 -226.368864)
		(width 0.2032)
		(layer "F.Cu")
		(net "P1V8_PLL0_PEX3_SCALED")
	)
	(segment
		(start 238.61903 -225.426524)
		(end 238.61903 -224.48266)
		(width 0.2032)
		(layer "F.Cu")
		(net "P1V8_PLL0_PEX3_SCALED")
	)
	(segment
		(start 238.619538 -225.427032)
		(end 238.61903 -225.426524)
		(width 0.2032)
		(layer "F.Cu")
		(net "P1V8_PLL0_PEX3_SCALED")
	)
	(segment
		(start 238.437166 -221.536514)
		(end 238.437166 -222.096584)
		(width 0.2032)
		(layer "F.Cu")
		(net "P1V8_PLL0_PEX3_SCALED")
	)
	(segment
		(start 238.619538 -226.357688)
		(end 238.619538 -225.427032)
		(width 0.2032)
		(layer "F.Cu")
		(net "P1V8_PLL0_PEX3_SCALED")
	)
	(segment
		(start 236.74832 -219.847668)
		(end 238.437166 -221.536514)
		(width 0.2032)
		(layer "F.Cu")
		(net "P1V8_PLL0_PEX3_SCALED")
	)
	(segment
		(start 236.562392 -219.39885)
		(end 236.74832 -219.847668)
		(width 0.2032)
		(layer "F.Cu")
		(net "P1V8_PLL0_PEX3_SCALED")
	)
	(segment
		(start 235.467652 -218.30411)
		(end 236.562392 -219.39885)
		(width 0.2032)
		(layer "F.Cu")
		(net "P1V8_PLL0_PEX3_SCALED")
	)
	(segment
		(start 238.608362 -226.368864)
		(end 238.619538 -226.357688)
		(width 0.2032)
		(layer "F.Cu")
		(net "P1V8_PLL0_PEX3_SCALED")
	)
	(via
		(at 239.317276 -226.368864)
		(size 0.508)
		(drill 0.254)
		(layers "F.Cu" "B.Cu")
		(net "P1V8_PLL0_PEX3_SCALED")
	)
	(via
		(at 238.437166 -222.096584)
		(size 0.762)
		(drill 0.254)
		(layers "F.Cu" "B.Cu")
		(net "P1V8_PLL0_PEX3_SCALED")
	)
	(segment
		(start 238.581184 -225.247708)
		(end 238.581184 -222.240602)
		(width 0.2032)
		(layer "In5.Cu")
		(net "P1V8_PLL0_PEX3_SCALED")
	)
	(segment
		(start 239.317276 -225.9838)
		(end 238.581184 -225.247708)
		(width 0.2032)
		(layer "In5.Cu")
		(net "P1V8_PLL0_PEX3_SCALED")
	)
	(segment
		(start 238.581184 -222.240602)
		(end 238.437166 -222.096584)
		(width 0.2032)
		(layer "In5.Cu")
		(net "P1V8_PLL0_PEX3_SCALED")
	)
	(segment
		(start 239.317276 -226.368864)
		(end 239.317276 -225.9838)
		(width 0.2032)
		(layer "In5.Cu")
		(net "P1V8_PLL0_PEX3_SCALED")
	)
	(segment
		(start 236.909864 -227.337366)
		(end 236.011974 -227.337366)
		(width 0.2032)
		(layer "F.Cu")
		(net "P1V8_PLL0_PEX2_SCALED")
	)
	(segment
		(start 237.900464 -227.337366)
		(end 236.909864 -227.337366)
		(width 0.2032)
		(layer "F.Cu")
		(net "P1V8_PLL0_PEX2_SCALED")
	)
	(segment
		(start 238.891064 -227.33762)
		(end 237.900718 -227.33762)
		(width 0.2032)
		(layer "F.Cu")
		(net "P1V8_PLL0_PEX2_SCALED")
	)
	(segment
		(start 234.667552 -218.30411)
		(end 235.067348 -217.904314)
		(width 0.2032)
		(layer "F.Cu")
		(net "P1V8_PLL0_PEX2_SCALED")
	)
	(segment
		(start 237.900718 -227.33762)
		(end 237.900464 -227.337366)
		(width 0.2032)
		(layer "F.Cu")
		(net "P1V8_PLL0_PEX2_SCALED")
	)
	(via
		(at 235.067348 -217.904314)
		(size 0.4572)
		(drill 0.254)
		(layers "F.Cu" "B.Cu")
		(net "P1V8_PLL0_PEX2_SCALED")
	)
	(via
		(at 236.011974 -227.337366)
		(size 0.508)
		(drill 0.254)
		(layers "F.Cu" "B.Cu")
		(net "P1V8_PLL0_PEX2_SCALED")
	)
	(segment
		(start 236.011974 -225.69551)
		(end 236.011974 -227.337366)
		(width 0.2032)
		(layer "In13.Cu")
		(net "P1V8_PLL0_PEX2_SCALED")
	)
	(segment
		(start 236.757972 -224.919032)
		(end 236.460538 -225.216466)
		(width 0.2032)
		(layer "In13.Cu")
		(net "P1V8_PLL0_PEX2_SCALED")
	)
	(segment
		(start 238.093758 -220.930724)
		(end 239.17275 -220.930724)
		(width 0.2032)
		(layer "In13.Cu")
		(net "P1V8_PLL0_PEX2_SCALED")
	)
	(segment
		(start 235.067348 -217.904314)
		(end 238.093758 -220.930724)
		(width 0.2032)
		(layer "In13.Cu")
		(net "P1V8_PLL0_PEX2_SCALED")
	)
	(segment
		(start 239.17275 -220.930724)
		(end 239.37595 -221.133924)
		(width 0.2032)
		(layer "In13.Cu")
		(net "P1V8_PLL0_PEX2_SCALED")
	)
	(segment
		(start 237.959392 -224.735136)
		(end 236.972348 -224.735136)
		(width 0.2032)
		(layer "In13.Cu")
		(net "P1V8_PLL0_PEX2_SCALED")
	)
	(segment
		(start 236.460538 -225.216466)
		(end 236.460538 -225.246946)
		(width 0.2032)
		(layer "In13.Cu")
		(net "P1V8_PLL0_PEX2_SCALED")
	)
	(segment
		(start 239.37595 -223.318578)
		(end 237.959392 -224.735136)
		(width 0.2032)
		(layer "In13.Cu")
		(net "P1V8_PLL0_PEX2_SCALED")
	)
	(segment
		(start 236.460538 -225.246946)
		(end 236.011974 -225.69551)
		(width 0.2032)
		(layer "In13.Cu")
		(net "P1V8_PLL0_PEX2_SCALED")
	)
	(segment
		(start 236.788452 -224.919032)
		(end 236.757972 -224.919032)
		(width 0.2032)
		(layer "In13.Cu")
		(net "P1V8_PLL0_PEX2_SCALED")
	)
	(segment
		(start 239.37595 -221.133924)
		(end 239.37595 -223.318578)
		(width 0.2032)
		(layer "In13.Cu")
		(net "P1V8_PLL0_PEX2_SCALED")
	)
	(segment
		(start 236.972348 -224.735136)
		(end 236.788452 -224.919032)
		(width 0.2032)
		(layer "In13.Cu")
		(net "P1V8_PLL0_PEX2_SCALED")
	)
	(segment
		(start 236.414818 -215.104218)
		(end 235.467652 -215.104218)
		(width 0.2032)
		(layer "F.Cu")
		(net "P1V8_PLL0_PEX0_SCALED")
	)
	(segment
		(start 242.316 -216.00795)
		(end 243.3066 -216.00795)
		(width 0.2032)
		(layer "F.Cu")
		(net "P1V8_PLL0_PEX0_SCALED")
	)
	(segment
		(start 240.4618 -216.5096)
		(end 240.0554 -216.5096)
		(width 0.2032)
		(layer "F.Cu")
		(net "P1V8_PLL0_PEX0_SCALED")
	)
	(segment
		(start 240.0554 -216.5096)
		(end 238.716566 -215.170766)
		(width 0.2032)
		(layer "F.Cu")
		(net "P1V8_PLL0_PEX0_SCALED")
	)
	(segment
		(start 241.3254 -216.00795)
		(end 240.96345 -216.00795)
		(width 0.2032)
		(layer "F.Cu")
		(net "P1V8_PLL0_PEX0_SCALED")
	)
	(segment
		(start 237.758224 -215.265)
		(end 236.5756 -215.265)
		(width 0.2032)
		(layer "F.Cu")
		(net "P1V8_PLL0_PEX0_SCALED")
	)
	(segment
		(start 238.716566 -215.170766)
		(end 237.852458 -215.170766)
		(width 0.2032)
		(layer "F.Cu")
		(net "P1V8_PLL0_PEX0_SCALED")
	)
	(segment
		(start 236.5756 -215.265)
		(end 236.414818 -215.104218)
		(width 0.2032)
		(layer "F.Cu")
		(net "P1V8_PLL0_PEX0_SCALED")
	)
	(segment
		(start 241.3254 -216.00795)
		(end 242.316 -216.00795)
		(width 0.2032)
		(layer "F.Cu")
		(net "P1V8_PLL0_PEX0_SCALED")
	)
	(segment
		(start 237.852458 -215.170766)
		(end 237.758224 -215.265)
		(width 0.2032)
		(layer "F.Cu")
		(net "P1V8_PLL0_PEX0_SCALED")
	)
	(segment
		(start 240.96345 -216.00795)
		(end 240.4618 -216.5096)
		(width 0.2032)
		(layer "F.Cu")
		(net "P1V8_PLL0_PEX0_SCALED")
	)
	(via
		(at 240.0554 -216.5096)
		(size 0.762)
		(drill 0.381)
		(layers "F.Cu" "B.Cu")
		(net "P1V8_PLL0_PEX0_SCALED")
	)
	(via
		(at 457.800202 -251.37364)
		(size 0.508)
		(drill 0.254)
		(layers "F.Cu" "B.Cu")
		(net "PWRGD_PEX3_P1V8_PLL")
	)
	(segment
		(start 457.800202 -251.37364)
		(end 457.800202 -250.79325)
		(width 0.381)
		(layer "B.Cu")
		(net "PWRGD_PEX3_P1V8_PLL")
	)
	(segment
		(start 457.673456 -250.666504)
		(end 457.673456 -250.20524)
		(width 0.381)
		(layer "B.Cu")
		(net "PWRGD_PEX3_P1V8_PLL")
	)
	(segment
		(start 457.800202 -250.79325)
		(end 457.673456 -250.666504)
		(width 0.381)
		(layer "B.Cu")
		(net "PWRGD_PEX3_P1V8_PLL")
	)
	(via
		(at 261.040626 -243.540788)
		(size 0.508)
		(drill 0.254)
		(layers "F.Cu" "B.Cu")
		(net "PWRGD_PEX2_P1V8_PLL")
	)
	(segment
		(start 261.040626 -242.960398)
		(end 260.91388 -242.833652)
		(width 0.381)
		(layer "B.Cu")
		(net "PWRGD_PEX2_P1V8_PLL")
	)
	(segment
		(start 260.91388 -242.833652)
		(end 260.91388 -242.372388)
		(width 0.381)
		(layer "B.Cu")
		(net "PWRGD_PEX2_P1V8_PLL")
	)
	(segment
		(start 261.040626 -243.540788)
		(end 261.040626 -242.960398)
		(width 0.381)
		(layer "B.Cu")
		(net "PWRGD_PEX2_P1V8_PLL")
	)
	(via
		(at 453.863202 -250.20524)
		(size 0.508)
		(drill 0.254)
		(layers "F.Cu" "B.Cu")
		(net "PEX3_P1V8_PLL_EN")
	)
	(segment
		(start 454.444354 -251.292868)
		(end 454.444354 -251.238004)
		(width 0.254)
		(layer "B.Cu")
		(net "PEX3_P1V8_PLL_EN")
	)
	(segment
		(start 453.863202 -250.656852)
		(end 453.863202 -250.20524)
		(width 0.254)
		(layer "B.Cu")
		(net "PEX3_P1V8_PLL_EN")
	)
	(segment
		(start 454.507346 -251.35586)
		(end 454.444354 -251.292868)
		(width 0.254)
		(layer "B.Cu")
		(net "PEX3_P1V8_PLL_EN")
	)
	(segment
		(start 454.444354 -251.238004)
		(end 453.863202 -250.656852)
		(width 0.254)
		(layer "B.Cu")
		(net "PEX3_P1V8_PLL_EN")
	)
	(segment
		(start 459.324202 -247.20169)
		(end 460.530956 -247.20169)
		(width 0.381)
		(layer "F.Cu")
		(net "P1V8_PLL_PEX3_ADJ")
	)
	(via
		(at 460.530956 -247.20169)
		(size 0.762)
		(drill 0.381)
		(layers "F.Cu" "B.Cu")
		(net "P1V8_PLL_PEX3_ADJ")
	)
	(segment
		(start 350.893888 -213.587076)
		(end 351.293684 -213.18728)
		(width 0.13208)
		(layer "F.Cu")
		(net "PWRGD_PEX0_P1V8_PLL_R")
	)
	(via
		(at 175.374046 -206.859124)
		(size 0.508)
		(drill 0.254)
		(layers "F.Cu" "B.Cu")
		(net "PWRGD_PEX0_P1V8_PLL_R")
	)
	(via
		(at 18.9738 -214.09406)
		(size 0.508)
		(drill 0.254)
		(layers "F.Cu" "B.Cu")
		(net "PWRGD_PEX0_P1V8_PLL_R")
	)
	(via
		(at 206.641192 -206.756)
		(size 0.508)
		(drill 0.254)
		(layers "F.Cu" "B.Cu")
		(net "PWRGD_PEX0_P1V8_PLL_R")
	)
	(via
		(at 351.293684 -213.18728)
		(size 0.4572)
		(drill 0.254)
		(layers "F.Cu" "B.Cu")
		(net "PWRGD_PEX0_P1V8_PLL_R")
	)
	(segment
		(start 175.47717 -206.756)
		(end 175.374046 -206.859124)
		(width 0.15494)
		(layer "In13.Cu")
		(net "PWRGD_PEX0_P1V8_PLL_R")
	)
	(segment
		(start 206.641192 -206.756)
		(end 175.47717 -206.756)
		(width 0.15494)
		(layer "In13.Cu")
		(net "PWRGD_PEX0_P1V8_PLL_R")
	)
	(segment
		(start 134.41172 -204.99832)
		(end 135.9662 -206.5528)
		(width 0.15494)
		(layer "In15.Cu")
		(net "PWRGD_PEX0_P1V8_PLL_R")
	)
	(segment
		(start 149.051264 -206.044038)
		(end 174.55896 -206.044038)
		(width 0.15494)
		(layer "In15.Cu")
		(net "PWRGD_PEX0_P1V8_PLL_R")
	)
	(segment
		(start 243.127784 -203.746608)
		(end 243.835936 -203.038456)
		(width 0.15494)
		(layer "In15.Cu")
		(net "PWRGD_PEX0_P1V8_PLL_R")
	)
	(segment
		(start 136.5504 -208.0768)
		(end 139.7508 -208.0768)
		(width 0.15494)
		(layer "In15.Cu")
		(net "PWRGD_PEX0_P1V8_PLL_R")
	)
	(segment
		(start 216.51849 -205.89113)
		(end 217.86723 -207.23987)
		(width 0.15494)
		(layer "In15.Cu")
		(net "PWRGD_PEX0_P1V8_PLL_R")
	)
	(segment
		(start 336.018632 -200.305162)
		(end 336.841846 -201.128376)
		(width 0.15494)
		(layer "In15.Cu")
		(net "PWRGD_PEX0_P1V8_PLL_R")
	)
	(segment
		(start 347.707712 -204.940662)
		(end 348.807024 -206.039974)
		(width 0.15494)
		(layer "In15.Cu")
		(net "PWRGD_PEX0_P1V8_PLL_R")
	)
	(segment
		(start 262.509 -200.787)
		(end 264.2362 -202.5142)
		(width 0.15494)
		(layer "In15.Cu")
		(net "PWRGD_PEX0_P1V8_PLL_R")
	)
	(segment
		(start 208.1022 -207.254602)
		(end 208.214468 -207.36687)
		(width 0.15494)
		(layer "In15.Cu")
		(net "PWRGD_PEX0_P1V8_PLL_R")
	)
	(segment
		(start 344.15222 -203.00569)
		(end 345.16187 -204.01534)
		(width 0.15494)
		(layer "In15.Cu")
		(net "PWRGD_PEX0_P1V8_PLL_R")
	)
	(segment
		(start 140.9954 -209.3214)
		(end 142.8496 -209.3214)
		(width 0.15494)
		(layer "In15.Cu")
		(net "PWRGD_PEX0_P1V8_PLL_R")
	)
	(segment
		(start 18.9738 -214.09406)
		(end 20.94103 -216.06129)
		(width 0.15494)
		(layer "In15.Cu")
		(net "PWRGD_PEX0_P1V8_PLL_R")
	)
	(segment
		(start 345.16187 -204.01534)
		(end 345.16187 -204.3684)
		(width 0.15494)
		(layer "In15.Cu")
		(net "PWRGD_PEX0_P1V8_PLL_R")
	)
	(segment
		(start 243.127784 -205.871064)
		(end 243.127784 -203.746608)
		(width 0.15494)
		(layer "In15.Cu")
		(net "PWRGD_PEX0_P1V8_PLL_R")
	)
	(segment
		(start 215.187784 -205.89113)
		(end 216.51849 -205.89113)
		(width 0.15494)
		(layer "In15.Cu")
		(net "PWRGD_PEX0_P1V8_PLL_R")
	)
	(segment
		(start 20.993862 -209.331814)
		(end 20.993862 -205.657196)
		(width 0.15494)
		(layer "In15.Cu")
		(net "PWRGD_PEX0_P1V8_PLL_R")
	)
	(segment
		(start 325.83247 -200.124314)
		(end 326.564244 -199.39254)
		(width 0.15494)
		(layer "In15.Cu")
		(net "PWRGD_PEX0_P1V8_PLL_R")
	)
	(segment
		(start 233.880406 -207.535526)
		(end 234.405932 -207.01)
		(width 0.15494)
		(layer "In15.Cu")
		(net "PWRGD_PEX0_P1V8_PLL_R")
	)
	(segment
		(start 340.81466 -202.46213)
		(end 341.35822 -203.00569)
		(width 0.15494)
		(layer "In15.Cu")
		(net "PWRGD_PEX0_P1V8_PLL_R")
	)
	(segment
		(start 266.030456 -201.7522)
		(end 267.377672 -201.7522)
		(width 0.15494)
		(layer "In15.Cu")
		(net "PWRGD_PEX0_P1V8_PLL_R")
	)
	(segment
		(start 328.67219 -199.39254)
		(end 328.75474 -199.30999)
		(width 0.15494)
		(layer "In15.Cu")
		(net "PWRGD_PEX0_P1V8_PLL_R")
	)
	(segment
		(start 220.59265 -206.85887)
		(end 228.271324 -206.85887)
		(width 0.15494)
		(layer "In15.Cu")
		(net "PWRGD_PEX0_P1V8_PLL_R")
	)
	(segment
		(start 207.139794 -207.254602)
		(end 208.1022 -207.254602)
		(width 0.15494)
		(layer "In15.Cu")
		(net "PWRGD_PEX0_P1V8_PLL_R")
	)
	(segment
		(start 23.079456 -211.417408)
		(end 20.993862 -209.331814)
		(width 0.15494)
		(layer "In15.Cu")
		(net "PWRGD_PEX0_P1V8_PLL_R")
	)
	(segment
		(start 243.835936 -203.038456)
		(end 243.835936 -202.340464)
		(width 0.15494)
		(layer "In15.Cu")
		(net "PWRGD_PEX0_P1V8_PLL_R")
	)
	(segment
		(start 340.262718 -202.612752)
		(end 340.41334 -202.46213)
		(width 0.15494)
		(layer "In15.Cu")
		(net "PWRGD_PEX0_P1V8_PLL_R")
	)
	(segment
		(start 337.789012 -201.128376)
		(end 339.328506 -202.66787)
		(width 0.15494)
		(layer "In15.Cu")
		(net "PWRGD_PEX0_P1V8_PLL_R")
	)
	(segment
		(start 269.156942 -199.97293)
		(end 323.637402 -199.97293)
		(width 0.15494)
		(layer "In15.Cu")
		(net "PWRGD_PEX0_P1V8_PLL_R")
	)
	(segment
		(start 257.353054 -200.787)
		(end 262.509 -200.787)
		(width 0.15494)
		(layer "In15.Cu")
		(net "PWRGD_PEX0_P1V8_PLL_R")
	)
	(segment
		(start 213.712044 -207.36687)
		(end 215.187784 -205.89113)
		(width 0.15494)
		(layer "In15.Cu")
		(net "PWRGD_PEX0_P1V8_PLL_R")
	)
	(segment
		(start 249.266456 -202.13701)
		(end 253.71171 -202.13701)
		(width 0.15494)
		(layer "In15.Cu")
		(net "PWRGD_PEX0_P1V8_PLL_R")
	)
	(segment
		(start 265.568938 -201.943462)
		(end 266.030456 -201.7522)
		(width 0.15494)
		(layer "In15.Cu")
		(net "PWRGD_PEX0_P1V8_PLL_R")
	)
	(segment
		(start 345.734132 -204.940662)
		(end 347.707712 -204.940662)
		(width 0.15494)
		(layer "In15.Cu")
		(net "PWRGD_PEX0_P1V8_PLL_R")
	)
	(segment
		(start 208.214468 -207.36687)
		(end 213.712044 -207.36687)
		(width 0.15494)
		(layer "In15.Cu")
		(net "PWRGD_PEX0_P1V8_PLL_R")
	)
	(segment
		(start 114.931698 -201.285094)
		(end 119.75084 -201.285094)
		(width 0.15494)
		(layer "In15.Cu")
		(net "PWRGD_PEX0_P1V8_PLL_R")
	)
	(segment
		(start 135.9662 -206.5528)
		(end 135.9662 -207.4926)
		(width 0.15494)
		(layer "In15.Cu")
		(net "PWRGD_PEX0_P1V8_PLL_R")
	)
	(segment
		(start 94.922848 -192.840102)
		(end 106.486706 -192.840102)
		(width 0.15494)
		(layer "In15.Cu")
		(net "PWRGD_PEX0_P1V8_PLL_R")
	)
	(segment
		(start 119.75084 -201.285094)
		(end 123.464066 -204.99832)
		(width 0.15494)
		(layer "In15.Cu")
		(net "PWRGD_PEX0_P1V8_PLL_R")
	)
	(segment
		(start 256.082546 -202.6412)
		(end 256.87782 -201.845926)
		(width 0.15494)
		(layer "In15.Cu")
		(net "PWRGD_PEX0_P1V8_PLL_R")
	)
	(segment
		(start 146.87804 -205.29296)
		(end 148.300186 -205.29296)
		(width 0.15494)
		(layer "In15.Cu")
		(net "PWRGD_PEX0_P1V8_PLL_R")
	)
	(segment
		(start 341.35822 -203.00569)
		(end 344.15222 -203.00569)
		(width 0.15494)
		(layer "In15.Cu")
		(net "PWRGD_PEX0_P1V8_PLL_R")
	)
	(segment
		(start 220.21165 -207.23987)
		(end 220.59265 -206.85887)
		(width 0.15494)
		(layer "In15.Cu")
		(net "PWRGD_PEX0_P1V8_PLL_R")
	)
	(segment
		(start 256.87782 -201.262234)
		(end 257.353054 -200.787)
		(width 0.15494)
		(layer "In15.Cu")
		(net "PWRGD_PEX0_P1V8_PLL_R")
	)
	(segment
		(start 323.78904 -200.124314)
		(end 325.83247 -200.124314)
		(width 0.15494)
		(layer "In15.Cu")
		(net "PWRGD_PEX0_P1V8_PLL_R")
	)
	(segment
		(start 256.87782 -201.845926)
		(end 256.87782 -201.262234)
		(width 0.15494)
		(layer "In15.Cu")
		(net "PWRGD_PEX0_P1V8_PLL_R")
	)
	(segment
		(start 228.271324 -206.85887)
		(end 228.94798 -207.535526)
		(width 0.15494)
		(layer "In15.Cu")
		(net "PWRGD_PEX0_P1V8_PLL_R")
	)
	(segment
		(start 264.9982 -202.5142)
		(end 265.568938 -201.943462)
		(width 0.15494)
		(layer "In15.Cu")
		(net "PWRGD_PEX0_P1V8_PLL_R")
	)
	(segment
		(start 228.94798 -207.535526)
		(end 233.880406 -207.535526)
		(width 0.15494)
		(layer "In15.Cu")
		(net "PWRGD_PEX0_P1V8_PLL_R")
	)
	(segment
		(start 336.841846 -201.128376)
		(end 337.789012 -201.128376)
		(width 0.15494)
		(layer "In15.Cu")
		(net "PWRGD_PEX0_P1V8_PLL_R")
	)
	(segment
		(start 267.377672 -201.7522)
		(end 269.156942 -199.97293)
		(width 0.15494)
		(layer "In15.Cu")
		(net "PWRGD_PEX0_P1V8_PLL_R")
	)
	(segment
		(start 174.55896 -206.044038)
		(end 175.374046 -206.859124)
		(width 0.15494)
		(layer "In15.Cu")
		(net "PWRGD_PEX0_P1V8_PLL_R")
	)
	(segment
		(start 254.2159 -202.6412)
		(end 256.082546 -202.6412)
		(width 0.15494)
		(layer "In15.Cu")
		(net "PWRGD_PEX0_P1V8_PLL_R")
	)
	(segment
		(start 22.355048 -216.06129)
		(end 23.079456 -215.336882)
		(width 0.15494)
		(layer "In15.Cu")
		(net "PWRGD_PEX0_P1V8_PLL_R")
	)
	(segment
		(start 340.41334 -202.46213)
		(end 340.81466 -202.46213)
		(width 0.15494)
		(layer "In15.Cu")
		(net "PWRGD_PEX0_P1V8_PLL_R")
	)
	(segment
		(start 351.293684 -211.363814)
		(end 351.293684 -213.18728)
		(width 0.15494)
		(layer "In15.Cu")
		(net "PWRGD_PEX0_P1V8_PLL_R")
	)
	(segment
		(start 123.464066 -204.99832)
		(end 134.41172 -204.99832)
		(width 0.15494)
		(layer "In15.Cu")
		(net "PWRGD_PEX0_P1V8_PLL_R")
	)
	(segment
		(start 135.9662 -207.4926)
		(end 136.5504 -208.0768)
		(width 0.15494)
		(layer "In15.Cu")
		(net "PWRGD_PEX0_P1V8_PLL_R")
	)
	(segment
		(start 245.146576 -201.029824)
		(end 246.851424 -201.029824)
		(width 0.15494)
		(layer "In15.Cu")
		(net "PWRGD_PEX0_P1V8_PLL_R")
	)
	(segment
		(start 345.16187 -204.3684)
		(end 345.734132 -204.940662)
		(width 0.15494)
		(layer "In15.Cu")
		(net "PWRGD_PEX0_P1V8_PLL_R")
	)
	(segment
		(start 336.018632 -199.952102)
		(end 336.018632 -200.305162)
		(width 0.15494)
		(layer "In15.Cu")
		(net "PWRGD_PEX0_P1V8_PLL_R")
	)
	(segment
		(start 328.75474 -199.30999)
		(end 335.37652 -199.30999)
		(width 0.15494)
		(layer "In15.Cu")
		(net "PWRGD_PEX0_P1V8_PLL_R")
	)
	(segment
		(start 20.94103 -216.06129)
		(end 22.355048 -216.06129)
		(width 0.15494)
		(layer "In15.Cu")
		(net "PWRGD_PEX0_P1V8_PLL_R")
	)
	(segment
		(start 335.37652 -199.30999)
		(end 336.018632 -199.952102)
		(width 0.15494)
		(layer "In15.Cu")
		(net "PWRGD_PEX0_P1V8_PLL_R")
	)
	(segment
		(start 323.637402 -199.97293)
		(end 323.78904 -200.124314)
		(width 0.15494)
		(layer "In15.Cu")
		(net "PWRGD_PEX0_P1V8_PLL_R")
	)
	(segment
		(start 23.079456 -215.336882)
		(end 23.079456 -211.417408)
		(width 0.15494)
		(layer "In15.Cu")
		(net "PWRGD_PEX0_P1V8_PLL_R")
	)
	(segment
		(start 339.328506 -202.66787)
		(end 340.207346 -202.66787)
		(width 0.15494)
		(layer "In15.Cu")
		(net "PWRGD_PEX0_P1V8_PLL_R")
	)
	(segment
		(start 36.176966 -190.474092)
		(end 92.556838 -190.474092)
		(width 0.15494)
		(layer "In15.Cu")
		(net "PWRGD_PEX0_P1V8_PLL_R")
	)
	(segment
		(start 92.556838 -190.474092)
		(end 94.922848 -192.840102)
		(width 0.15494)
		(layer "In15.Cu")
		(net "PWRGD_PEX0_P1V8_PLL_R")
	)
	(segment
		(start 246.851424 -201.029824)
		(end 247.5484 -201.7268)
		(width 0.15494)
		(layer "In15.Cu")
		(net "PWRGD_PEX0_P1V8_PLL_R")
	)
	(segment
		(start 340.207346 -202.66787)
		(end 340.262718 -202.612752)
		(width 0.15494)
		(layer "In15.Cu")
		(net "PWRGD_PEX0_P1V8_PLL_R")
	)
	(segment
		(start 253.71171 -202.13701)
		(end 254.2159 -202.6412)
		(width 0.15494)
		(layer "In15.Cu")
		(net "PWRGD_PEX0_P1V8_PLL_R")
	)
	(segment
		(start 248.856246 -201.7268)
		(end 249.266456 -202.13701)
		(width 0.15494)
		(layer "In15.Cu")
		(net "PWRGD_PEX0_P1V8_PLL_R")
	)
	(segment
		(start 326.564244 -199.39254)
		(end 328.67219 -199.39254)
		(width 0.15494)
		(layer "In15.Cu")
		(net "PWRGD_PEX0_P1V8_PLL_R")
	)
	(segment
		(start 241.988848 -207.01)
		(end 243.127784 -205.871064)
		(width 0.15494)
		(layer "In15.Cu")
		(net "PWRGD_PEX0_P1V8_PLL_R")
	)
	(segment
		(start 348.807024 -206.039974)
		(end 348.807024 -208.877154)
		(width 0.15494)
		(layer "In15.Cu")
		(net "PWRGD_PEX0_P1V8_PLL_R")
	)
	(segment
		(start 206.641192 -206.756)
		(end 207.139794 -207.254602)
		(width 0.15494)
		(layer "In15.Cu")
		(net "PWRGD_PEX0_P1V8_PLL_R")
	)
	(segment
		(start 243.835936 -202.340464)
		(end 245.146576 -201.029824)
		(width 0.15494)
		(layer "In15.Cu")
		(net "PWRGD_PEX0_P1V8_PLL_R")
	)
	(segment
		(start 217.86723 -207.23987)
		(end 220.21165 -207.23987)
		(width 0.15494)
		(layer "In15.Cu")
		(net "PWRGD_PEX0_P1V8_PLL_R")
	)
	(segment
		(start 247.5484 -201.7268)
		(end 248.856246 -201.7268)
		(width 0.15494)
		(layer "In15.Cu")
		(net "PWRGD_PEX0_P1V8_PLL_R")
	)
	(segment
		(start 148.300186 -205.29296)
		(end 149.051264 -206.044038)
		(width 0.15494)
		(layer "In15.Cu")
		(net "PWRGD_PEX0_P1V8_PLL_R")
	)
	(segment
		(start 106.486706 -192.840102)
		(end 114.931698 -201.285094)
		(width 0.15494)
		(layer "In15.Cu")
		(net "PWRGD_PEX0_P1V8_PLL_R")
	)
	(segment
		(start 20.993862 -205.657196)
		(end 36.176966 -190.474092)
		(width 0.15494)
		(layer "In15.Cu")
		(net "PWRGD_PEX0_P1V8_PLL_R")
	)
	(segment
		(start 264.2362 -202.5142)
		(end 264.9982 -202.5142)
		(width 0.15494)
		(layer "In15.Cu")
		(net "PWRGD_PEX0_P1V8_PLL_R")
	)
	(segment
		(start 142.8496 -209.3214)
		(end 146.87804 -205.29296)
		(width 0.15494)
		(layer "In15.Cu")
		(net "PWRGD_PEX0_P1V8_PLL_R")
	)
	(segment
		(start 348.807024 -208.877154)
		(end 351.293684 -211.363814)
		(width 0.15494)
		(layer "In15.Cu")
		(net "PWRGD_PEX0_P1V8_PLL_R")
	)
	(segment
		(start 234.405932 -207.01)
		(end 241.988848 -207.01)
		(width 0.15494)
		(layer "In15.Cu")
		(net "PWRGD_PEX0_P1V8_PLL_R")
	)
	(segment
		(start 139.7508 -208.0768)
		(end 140.9954 -209.3214)
		(width 0.15494)
		(layer "In15.Cu")
		(net "PWRGD_PEX0_P1V8_PLL_R")
	)
	(via
		(at 257.103626 -242.372388)
		(size 0.508)
		(drill 0.254)
		(layers "F.Cu" "B.Cu")
		(net "PEX2_P1V8_PLL_EN")
	)
	(segment
		(start 256.855976 -242.124738)
		(end 257.103626 -242.372388)
		(width 0.254)
		(layer "B.Cu")
		(net "PEX2_P1V8_PLL_EN")
	)
	(segment
		(start 255.960626 -242.124738)
		(end 256.855976 -242.124738)
		(width 0.254)
		(layer "B.Cu")
		(net "PEX2_P1V8_PLL_EN")
	)
	(segment
		(start 262.564626 -240.451894)
		(end 263.761728 -240.451894)
		(width 0.381)
		(layer "F.Cu")
		(net "P1V8_PLL_PEX2_ADJ")
	)
	(via
		(at 263.761728 -240.451894)
		(size 0.762)
		(drill 0.381)
		(layers "F.Cu" "B.Cu")
		(net "P1V8_PLL_PEX2_ADJ")
	)
	(via
		(at 249.878342 -392.704574)
		(size 0.508)
		(drill 0.254)
		(layers "F.Cu" "B.Cu")
		(net "P12V_STBY_FUSE")
	)
	(via
		(at 281.2288 -365.484156)
		(size 0.6604)
		(drill 0.3302)
		(layers "F.Cu" "B.Cu")
		(net "P12V_STBY_FUSE")
	)
	(via
		(at 246.772938 -392.704574)
		(size 0.508)
		(drill 0.254)
		(layers "F.Cu" "B.Cu")
		(net "P12V_STBY_FUSE")
	)
	(via
		(at 248.296938 -392.704574)
		(size 0.508)
		(drill 0.254)
		(layers "F.Cu" "B.Cu")
		(net "P12V_STBY_FUSE")
	)
	(via
		(at 249.116342 -392.704574)
		(size 0.508)
		(drill 0.254)
		(layers "F.Cu" "B.Cu")
		(net "P12V_STBY_FUSE")
	)
	(via
		(at 247.534938 -392.704574)
		(size 0.508)
		(drill 0.254)
		(layers "F.Cu" "B.Cu")
		(net "P12V_STBY_FUSE")
	)
	(via
		(at 203.02982 -359.85704)
		(size 0.6604)
		(drill 0.3302)
		(layers "F.Cu" "B.Cu")
		(net "P12V_STBY_FUSE")
	)
	(via
		(at 250.640342 -392.704574)
		(size 0.508)
		(drill 0.254)
		(layers "F.Cu" "B.Cu")
		(net "P12V_STBY_FUSE")
	)
	(segment
		(start 250.98502 -392.359896)
		(end 250.640342 -392.704574)
		(width 0.254)
		(layer "B.Cu")
		(net "P12V_STBY_FUSE")
	)
	(segment
		(start 280.425652 -398.54632)
		(end 277.450804 -398.54632)
		(width 0.254)
		(layer "B.Cu")
		(net "P12V_STBY_FUSE")
	)
	(segment
		(start 264.490708 -349.853504)
		(end 264.490708 -355.714808)
		(width 0.254)
		(layer "B.Cu")
		(net "P12V_STBY_FUSE")
	)
	(segment
		(start 203.02982 -359.85704)
		(end 203.02982 -357.042466)
		(width 0.254)
		(layer "B.Cu")
		(net "P12V_STBY_FUSE")
	)
	(segment
		(start 203.02982 -357.042466)
		(end 203.98613 -356.086156)
		(width 0.254)
		(layer "B.Cu")
		(net "P12V_STBY_FUSE")
	)
	(segment
		(start 203.127864 -352.63963)
		(end 203.127864 -348.767908)
		(width 0.254)
		(layer "B.Cu")
		(net "P12V_STBY_FUSE")
	)
	(segment
		(start 203.98613 -356.086156)
		(end 203.98613 -353.497896)
		(width 0.254)
		(layer "B.Cu")
		(net "P12V_STBY_FUSE")
	)
	(segment
		(start 260.383782 -392.359896)
		(end 250.98502 -392.359896)
		(width 0.254)
		(layer "B.Cu")
		(net "P12V_STBY_FUSE")
	)
	(segment
		(start 281.2288 -364.0836)
		(end 281.2288 -365.484156)
		(width 0.254)
		(layer "B.Cu")
		(net "P12V_STBY_FUSE")
	)
	(segment
		(start 278.335232 -361.190032)
		(end 281.2288 -364.0836)
		(width 0.254)
		(layer "B.Cu")
		(net "P12V_STBY_FUSE")
	)
	(segment
		(start 275.36394 -392.284204)
		(end 270.451326 -387.37159)
		(width 0.254)
		(layer "B.Cu")
		(net "P12V_STBY_FUSE")
	)
	(segment
		(start 223.453706 -343.926922)
		(end 251.403104 -343.926922)
		(width 0.254)
		(layer "B.Cu")
		(net "P12V_STBY_FUSE")
	)
	(segment
		(start 277.450804 -398.54632)
		(end 275.36394 -396.459456)
		(width 0.254)
		(layer "B.Cu")
		(net "P12V_STBY_FUSE")
	)
	(segment
		(start 203.98613 -353.497896)
		(end 203.127864 -352.63963)
		(width 0.254)
		(layer "B.Cu")
		(net "P12V_STBY_FUSE")
	)
	(segment
		(start 221.867222 -342.340438)
		(end 223.453706 -343.926922)
		(width 0.254)
		(layer "B.Cu")
		(net "P12V_STBY_FUSE")
	)
	(segment
		(start 252.521466 -345.045284)
		(end 259.682488 -345.045284)
		(width 0.254)
		(layer "B.Cu")
		(net "P12V_STBY_FUSE")
	)
	(segment
		(start 275.36394 -396.459456)
		(end 275.36394 -392.284204)
		(width 0.254)
		(layer "B.Cu")
		(net "P12V_STBY_FUSE")
	)
	(segment
		(start 270.451326 -387.37159)
		(end 265.372088 -387.37159)
		(width 0.254)
		(layer "B.Cu")
		(net "P12V_STBY_FUSE")
	)
	(segment
		(start 281.2288 -397.743172)
		(end 280.425652 -398.54632)
		(width 0.254)
		(layer "B.Cu")
		(net "P12V_STBY_FUSE")
	)
	(segment
		(start 251.403104 -343.926922)
		(end 252.521466 -345.045284)
		(width 0.254)
		(layer "B.Cu")
		(net "P12V_STBY_FUSE")
	)
	(segment
		(start 281.2288 -365.484156)
		(end 281.2288 -397.743172)
		(width 0.254)
		(layer "B.Cu")
		(net "P12V_STBY_FUSE")
	)
	(segment
		(start 269.965932 -361.190032)
		(end 278.335232 -361.190032)
		(width 0.254)
		(layer "B.Cu")
		(net "P12V_STBY_FUSE")
	)
	(segment
		(start 203.02982 -361.045252)
		(end 203.02982 -359.85704)
		(width 0.254)
		(layer "B.Cu")
		(net "P12V_STBY_FUSE")
	)
	(segment
		(start 203.973176 -361.988608)
		(end 203.02982 -361.045252)
		(width 0.254)
		(layer "B.Cu")
		(net "P12V_STBY_FUSE")
	)
	(segment
		(start 209.555334 -342.340438)
		(end 221.867222 -342.340438)
		(width 0.254)
		(layer "B.Cu")
		(net "P12V_STBY_FUSE")
	)
	(segment
		(start 203.127864 -348.767908)
		(end 209.555334 -342.340438)
		(width 0.254)
		(layer "B.Cu")
		(net "P12V_STBY_FUSE")
	)
	(segment
		(start 264.490708 -355.714808)
		(end 269.965932 -361.190032)
		(width 0.254)
		(layer "B.Cu")
		(net "P12V_STBY_FUSE")
	)
	(segment
		(start 265.372088 -387.37159)
		(end 260.383782 -392.359896)
		(width 0.254)
		(layer "B.Cu")
		(net "P12V_STBY_FUSE")
	)
	(segment
		(start 259.682488 -345.045284)
		(end 264.490708 -349.853504)
		(width 0.254)
		(layer "B.Cu")
		(net "P12V_STBY_FUSE")
	)
	(segment
		(start 218.247468 -256.373376)
		(end 218.247468 -257.23088)
		(width 0.4572)
		(layer "F.Cu")
		(net "P1V25_SERDES_VDDPLL_PEX1_C10")
	)
	(segment
		(start 218.4146 -255.484884)
		(end 217.70213 -254.772414)
		(width 0.4572)
		(layer "F.Cu")
		(net "P1V25_SERDES_VDDPLL_PEX1_C10")
	)
	(segment
		(start 217.70213 -254.772414)
		(end 217.70213 -252.598174)
		(width 0.4572)
		(layer "F.Cu")
		(net "P1V25_SERDES_VDDPLL_PEX1_C10")
	)
	(segment
		(start 218.247468 -257.23088)
		(end 217.902536 -257.575812)
		(width 0.4572)
		(layer "F.Cu")
		(net "P1V25_SERDES_VDDPLL_PEX1_C10")
	)
	(segment
		(start 218.4146 -256.206244)
		(end 218.4146 -255.484884)
		(width 0.4572)
		(layer "F.Cu")
		(net "P1V25_SERDES_VDDPLL_PEX1_C10")
	)
	(segment
		(start 217.70213 -252.598174)
		(end 218.247468 -252.052836)
		(width 0.4572)
		(layer "F.Cu")
		(net "P1V25_SERDES_VDDPLL_PEX1_C10")
	)
	(segment
		(start 218.4146 -256.206244)
		(end 218.247468 -256.373376)
		(width 0.4572)
		(layer "F.Cu")
		(net "P1V25_SERDES_VDDPLL_PEX1_C10")
	)
	(via
		(at 218.4146 -256.206244)
		(size 0.762)
		(drill 0.381)
		(layers "F.Cu" "B.Cu")
		(net "P1V25_SERDES_VDDPLL_PEX1_C10")
	)
	(segment
		(start 229.16515 -257.368802)
		(end 229.738936 -256.795016)
		(width 0.4572)
		(layer "F.Cu")
		(net "P1V25_SERDES_VDDPLL_PEX1_C9")
	)
	(segment
		(start 229.738936 -256.795016)
		(end 229.738936 -256.242566)
		(width 0.4572)
		(layer "F.Cu")
		(net "P1V25_SERDES_VDDPLL_PEX1_C9")
	)
	(segment
		(start 229.738936 -256.242566)
		(end 228.783134 -255.286764)
		(width 0.4572)
		(layer "F.Cu")
		(net "P1V25_SERDES_VDDPLL_PEX1_C9")
	)
	(segment
		(start 229.16515 -257.975862)
		(end 229.16515 -257.368802)
		(width 0.4572)
		(layer "F.Cu")
		(net "P1V25_SERDES_VDDPLL_PEX1_C9")
	)
	(segment
		(start 228.783134 -255.286764)
		(end 228.783134 -254.92202)
		(width 0.4572)
		(layer "F.Cu")
		(net "P1V25_SERDES_VDDPLL_PEX1_C9")
	)
	(via
		(at 229.738936 -256.795016)
		(size 0.762)
		(drill 0.381)
		(layers "F.Cu" "B.Cu")
		(net "P1V25_SERDES_VDDPLL_PEX1_C9")
	)
	(segment
		(start 227.13315 -256.3495)
		(end 227.13315 -257.456686)
		(width 0.4572)
		(layer "F.Cu")
		(net "P1V25_SERDES_VDDPLL_PEX1_C7")
	)
	(segment
		(start 226.331272 -255.319022)
		(end 227.13315 -256.1209)
		(width 0.4572)
		(layer "F.Cu")
		(net "P1V25_SERDES_VDDPLL_PEX1_C7")
	)
	(segment
		(start 227.13315 -257.456686)
		(end 226.977702 -257.612134)
		(width 0.4572)
		(layer "F.Cu")
		(net "P1V25_SERDES_VDDPLL_PEX1_C7")
	)
	(segment
		(start 227.13315 -256.1209)
		(end 227.13315 -256.3495)
		(width 0.4572)
		(layer "F.Cu")
		(net "P1V25_SERDES_VDDPLL_PEX1_C7")
	)
	(segment
		(start 226.331272 -254.92202)
		(end 226.331272 -255.319022)
		(width 0.4572)
		(layer "F.Cu")
		(net "P1V25_SERDES_VDDPLL_PEX1_C7")
	)
	(via
		(at 227.13315 -256.3495)
		(size 0.762)
		(drill 0.381)
		(layers "F.Cu" "B.Cu")
		(net "P1V25_SERDES_VDDPLL_PEX1_C7")
	)
	(via
		(at 128.530604 -323.479668)
		(size 0.6604)
		(drill 0.3302)
		(layers "F.Cu" "B.Cu")
		(net "P0V8_SERDES_VDDA_PEX1_C1")
	)
	(segment
		(start 128.531112 -323.47916)
		(end 128.530604 -323.479668)
		(width 0.4572)
		(layer "B.Cu")
		(net "P0V8_SERDES_VDDA_PEX1_C1")
	)
	(segment
		(start 128.531112 -322.289424)
		(end 128.531112 -323.47916)
		(width 0.4572)
		(layer "B.Cu")
		(net "P0V8_SERDES_VDDA_PEX1_C1")
	)
	(segment
		(start 128.454912 -322.213224)
		(end 128.531112 -322.289424)
		(width 0.4572)
		(layer "B.Cu")
		(net "P0V8_SERDES_VDDA_PEX1_C1")
	)
	(segment
		(start 128.530604 -324.87489)
		(end 128.530604 -323.479668)
		(width 0.4572)
		(layer "B.Cu")
		(net "P0V8_SERDES_VDDA_PEX1_C1")
	)
	(segment
		(start 231.501696 -256.077974)
		(end 230.767636 -255.343914)
		(width 0.4572)
		(layer "F.Cu")
		(net "P1V25_SERDES_VDDPLL_PEX1_C4")
	)
	(segment
		(start 230.767636 -255.343914)
		(end 230.620062 -255.343914)
		(width 0.4572)
		(layer "F.Cu")
		(net "P1V25_SERDES_VDDPLL_PEX1_C4")
	)
	(segment
		(start 230.18877 -257.572764)
		(end 230.678736 -257.082798)
		(width 0.4572)
		(layer "F.Cu")
		(net "P1V25_SERDES_VDDPLL_PEX1_C4")
	)
	(segment
		(start 231.483408 -257.082798)
		(end 231.501696 -257.06451)
		(width 0.4572)
		(layer "F.Cu")
		(net "P1V25_SERDES_VDDPLL_PEX1_C4")
	)
	(segment
		(start 231.501696 -257.06451)
		(end 231.501696 -256.077974)
		(width 0.4572)
		(layer "F.Cu")
		(net "P1V25_SERDES_VDDPLL_PEX1_C4")
	)
	(segment
		(start 230.18877 -257.989324)
		(end 230.18877 -257.572764)
		(width 0.4572)
		(layer "F.Cu")
		(net "P1V25_SERDES_VDDPLL_PEX1_C4")
	)
	(segment
		(start 230.678736 -257.082798)
		(end 231.483408 -257.082798)
		(width 0.4572)
		(layer "F.Cu")
		(net "P1V25_SERDES_VDDPLL_PEX1_C4")
	)
	(via
		(at 231.483408 -257.082798)
		(size 0.762)
		(drill 0.381)
		(layers "F.Cu" "B.Cu")
		(net "P1V25_SERDES_VDDPLL_PEX1_C4")
	)
	(via
		(at 120.046496 -323.038978)
		(size 0.6604)
		(drill 0.3302)
		(layers "F.Cu" "B.Cu")
		(net "P0V8_SERDES_VDDA_PEX1_C7")
	)
	(segment
		(start 120.03786 -323.047614)
		(end 120.046496 -323.038978)
		(width 0.4572)
		(layer "B.Cu")
		(net "P0V8_SERDES_VDDA_PEX1_C7")
	)
	(segment
		(start 120.038368 -323.03085)
		(end 120.046496 -323.038978)
		(width 0.4572)
		(layer "B.Cu")
		(net "P0V8_SERDES_VDDA_PEX1_C7")
	)
	(segment
		(start 120.038368 -321.788028)
		(end 120.038368 -323.03085)
		(width 0.4572)
		(layer "B.Cu")
		(net "P0V8_SERDES_VDDA_PEX1_C7")
	)
	(segment
		(start 120.03786 -324.449694)
		(end 120.03786 -323.047614)
		(width 0.4572)
		(layer "B.Cu")
		(net "P0V8_SERDES_VDDA_PEX1_C7")
	)
	(segment
		(start 219.457778 -257.575812)
		(end 219.930472 -257.103118)
		(width 0.4572)
		(layer "F.Cu")
		(net "P1V25_SERDES_VDDPLL_PEX1_C11")
	)
	(segment
		(start 218.570556 -253.48057)
		(end 219.99829 -252.052836)
		(width 0.4572)
		(layer "F.Cu")
		(net "P1V25_SERDES_VDDPLL_PEX1_C11")
	)
	(segment
		(start 218.570556 -254.175514)
		(end 218.570556 -253.48057)
		(width 0.4572)
		(layer "F.Cu")
		(net "P1V25_SERDES_VDDPLL_PEX1_C11")
	)
	(segment
		(start 219.930472 -257.103118)
		(end 219.930472 -256.04978)
		(width 0.4572)
		(layer "F.Cu")
		(net "P1V25_SERDES_VDDPLL_PEX1_C11")
	)
	(segment
		(start 218.570556 -254.689864)
		(end 218.570556 -254.175514)
		(width 0.4572)
		(layer "F.Cu")
		(net "P1V25_SERDES_VDDPLL_PEX1_C11")
	)
	(segment
		(start 219.930472 -256.04978)
		(end 218.570556 -254.689864)
		(width 0.4572)
		(layer "F.Cu")
		(net "P1V25_SERDES_VDDPLL_PEX1_C11")
	)
	(via
		(at 218.570556 -254.175514)
		(size 0.762)
		(drill 0.381)
		(layers "F.Cu" "B.Cu")
		(net "P1V25_SERDES_VDDPLL_PEX1_C11")
	)
	(segment
		(start 223.287844 -256.97434)
		(end 223.889316 -257.575812)
		(width 0.4572)
		(layer "F.Cu")
		(net "P1V25_SERDES_VDDPLL_PEX1_C2")
	)
	(segment
		(start 223.287844 -256.108962)
		(end 223.287844 -256.31394)
		(width 0.4572)
		(layer "F.Cu")
		(net "P1V25_SERDES_VDDPLL_PEX1_C2")
	)
	(segment
		(start 223.287844 -256.31394)
		(end 223.287844 -256.97434)
		(width 0.4572)
		(layer "F.Cu")
		(net "P1V25_SERDES_VDDPLL_PEX1_C2")
	)
	(segment
		(start 222.574866 -255.395984)
		(end 223.287844 -256.108962)
		(width 0.4572)
		(layer "F.Cu")
		(net "P1V25_SERDES_VDDPLL_PEX1_C2")
	)
	(segment
		(start 222.574866 -254.92202)
		(end 222.574866 -255.395984)
		(width 0.4572)
		(layer "F.Cu")
		(net "P1V25_SERDES_VDDPLL_PEX1_C2")
	)
	(via
		(at 223.287844 -256.31394)
		(size 0.762)
		(drill 0.381)
		(layers "F.Cu" "B.Cu")
		(net "P1V25_SERDES_VDDPLL_PEX1_C2")
	)
	(segment
		(start 220.709236 -256.355596)
		(end 220.709236 -255.705864)
		(width 0.4572)
		(layer "F.Cu")
		(net "P1V25_SERDES_VDDPLL_PEX1_C0")
	)
	(segment
		(start 220.709236 -255.705864)
		(end 220.077792 -255.07442)
		(width 0.4572)
		(layer "F.Cu")
		(net "P1V25_SERDES_VDDPLL_PEX1_C0")
	)
	(segment
		(start 220.709236 -257.203194)
		(end 220.709236 -256.355596)
		(width 0.4572)
		(layer "F.Cu")
		(net "P1V25_SERDES_VDDPLL_PEX1_C0")
	)
	(segment
		(start 220.077792 -255.07442)
		(end 220.077792 -254.92202)
		(width 0.4572)
		(layer "F.Cu")
		(net "P1V25_SERDES_VDDPLL_PEX1_C0")
	)
	(segment
		(start 221.081854 -257.575812)
		(end 220.709236 -257.203194)
		(width 0.4572)
		(layer "F.Cu")
		(net "P1V25_SERDES_VDDPLL_PEX1_C0")
	)
	(via
		(at 220.709236 -256.355596)
		(size 0.762)
		(drill 0.381)
		(layers "F.Cu" "B.Cu")
		(net "P1V25_SERDES_VDDPLL_PEX1_C0")
	)
	(via
		(at 130.016504 -323.109082)
		(size 0.6604)
		(drill 0.3302)
		(layers "F.Cu" "B.Cu")
		(net "P0V8_SERDES_VDDA_PEX1_C11")
	)
	(segment
		(start 131.859274 -322.23456)
		(end 131.69138 -322.402454)
		(width 0.4572)
		(layer "B.Cu")
		(net "P0V8_SERDES_VDDA_PEX1_C11")
	)
	(segment
		(start 130.016504 -322.793868)
		(end 130.016504 -323.109082)
		(width 0.4572)
		(layer "B.Cu")
		(net "P0V8_SERDES_VDDA_PEX1_C11")
	)
	(segment
		(start 130.016504 -323.109082)
		(end 130.016504 -324.57263)
		(width 0.4572)
		(layer "B.Cu")
		(net "P0V8_SERDES_VDDA_PEX1_C11")
	)
	(segment
		(start 131.69138 -322.402454)
		(end 130.407918 -322.402454)
		(width 0.4572)
		(layer "B.Cu")
		(net "P0V8_SERDES_VDDA_PEX1_C11")
	)
	(segment
		(start 130.407918 -322.402454)
		(end 130.016504 -322.793868)
		(width 0.4572)
		(layer "B.Cu")
		(net "P0V8_SERDES_VDDA_PEX1_C11")
	)
	(via
		(at 127.084836 -323.381878)
		(size 0.6604)
		(drill 0.3302)
		(layers "F.Cu" "B.Cu")
		(net "P0V8_SERDES_VDDA_PEX1_C2")
	)
	(segment
		(start 127.0762 -324.87489)
		(end 127.0762 -323.390514)
		(width 0.4572)
		(layer "B.Cu")
		(net "P0V8_SERDES_VDDA_PEX1_C2")
	)
	(segment
		(start 127.0762 -323.390514)
		(end 127.084836 -323.381878)
		(width 0.4572)
		(layer "B.Cu")
		(net "P0V8_SERDES_VDDA_PEX1_C2")
	)
	(segment
		(start 127.076708 -322.213224)
		(end 127.076708 -323.37375)
		(width 0.4572)
		(layer "B.Cu")
		(net "P0V8_SERDES_VDDA_PEX1_C2")
	)
	(segment
		(start 127.076708 -323.37375)
		(end 127.084836 -323.381878)
		(width 0.4572)
		(layer "B.Cu")
		(net "P0V8_SERDES_VDDA_PEX1_C2")
	)
	(via
		(at 122.81789 -323.011546)
		(size 0.6604)
		(drill 0.3302)
		(layers "F.Cu" "B.Cu")
		(net "P0V8_SERDES_VDDA_PEX1_C9")
	)
	(segment
		(start 122.809762 -323.003418)
		(end 122.81789 -323.011546)
		(width 0.4572)
		(layer "B.Cu")
		(net "P0V8_SERDES_VDDA_PEX1_C9")
	)
	(segment
		(start 122.809254 -324.449694)
		(end 122.809254 -323.020182)
		(width 0.4572)
		(layer "B.Cu")
		(net "P0V8_SERDES_VDDA_PEX1_C9")
	)
	(segment
		(start 122.809254 -323.020182)
		(end 122.81789 -323.011546)
		(width 0.4572)
		(layer "B.Cu")
		(net "P0V8_SERDES_VDDA_PEX1_C9")
	)
	(segment
		(start 122.809762 -321.788028)
		(end 122.809762 -323.003418)
		(width 0.4572)
		(layer "B.Cu")
		(net "P0V8_SERDES_VDDA_PEX1_C9")
	)
	(via
		(at 133.530848 -323.339968)
		(size 0.508)
		(drill 0.254)
		(layers "F.Cu" "B.Cu")
		(net "P0V8_SERDES_VDDA_PEX1_C5")
	)
	(segment
		(start 133.530848 -323.339968)
		(end 133.530848 -322.502276)
		(width 0.4572)
		(layer "B.Cu")
		(net "P0V8_SERDES_VDDA_PEX1_C5")
	)
	(segment
		(start 133.530848 -323.824092)
		(end 133.530848 -323.339968)
		(width 0.4572)
		(layer "B.Cu")
		(net "P0V8_SERDES_VDDA_PEX1_C5")
	)
	(segment
		(start 132.78231 -324.57263)
		(end 133.530848 -323.824092)
		(width 0.4572)
		(layer "B.Cu")
		(net "P0V8_SERDES_VDDA_PEX1_C5")
	)
	(segment
		(start 133.530848 -322.502276)
		(end 133.78815 -322.244974)
		(width 0.4572)
		(layer "B.Cu")
		(net "P0V8_SERDES_VDDA_PEX1_C5")
	)
	(via
		(at 118.619778 -323.066156)
		(size 0.6604)
		(drill 0.3302)
		(layers "F.Cu" "B.Cu")
		(net "P0V8_SERDES_VDDA_PEX1_C6")
	)
	(segment
		(start 118.611142 -324.449694)
		(end 118.611142 -323.074792)
		(width 0.4572)
		(layer "B.Cu")
		(net "P0V8_SERDES_VDDA_PEX1_C6")
	)
	(segment
		(start 118.611142 -323.074792)
		(end 118.619778 -323.066156)
		(width 0.4572)
		(layer "B.Cu")
		(net "P0V8_SERDES_VDDA_PEX1_C6")
	)
	(segment
		(start 118.61165 -323.058028)
		(end 118.619778 -323.066156)
		(width 0.4572)
		(layer "B.Cu")
		(net "P0V8_SERDES_VDDA_PEX1_C6")
	)
	(segment
		(start 118.61165 -321.796156)
		(end 118.61165 -323.058028)
		(width 0.4572)
		(layer "B.Cu")
		(net "P0V8_SERDES_VDDA_PEX1_C6")
	)
	(via
		(at 124.244862 -322.984114)
		(size 0.6604)
		(drill 0.3302)
		(layers "F.Cu" "B.Cu")
		(net "P0V8_SERDES_VDDA_PEX1_C3")
	)
	(segment
		(start 124.236734 -321.788028)
		(end 124.236734 -322.975986)
		(width 0.4572)
		(layer "B.Cu")
		(net "P0V8_SERDES_VDDA_PEX1_C3")
	)
	(segment
		(start 124.236226 -322.99275)
		(end 124.244862 -322.984114)
		(width 0.4572)
		(layer "B.Cu")
		(net "P0V8_SERDES_VDDA_PEX1_C3")
	)
	(segment
		(start 124.236734 -322.975986)
		(end 124.244862 -322.984114)
		(width 0.4572)
		(layer "B.Cu")
		(net "P0V8_SERDES_VDDA_PEX1_C3")
	)
	(segment
		(start 124.236226 -324.449694)
		(end 124.236226 -322.99275)
		(width 0.4572)
		(layer "B.Cu")
		(net "P0V8_SERDES_VDDA_PEX1_C3")
	)
	(segment
		(start 227.581206 -254.92202)
		(end 227.581206 -255.3335)
		(width 0.4572)
		(layer "F.Cu")
		(net "P1V25_SERDES_VDDPLL_PEX1_C8")
	)
	(segment
		(start 227.581206 -255.3335)
		(end 228.425502 -256.177796)
		(width 0.4572)
		(layer "F.Cu")
		(net "P1V25_SERDES_VDDPLL_PEX1_C8")
	)
	(segment
		(start 228.425502 -256.336038)
		(end 228.425502 -256.640838)
		(width 0.4572)
		(layer "F.Cu")
		(net "P1V25_SERDES_VDDPLL_PEX1_C8")
	)
	(segment
		(start 228.425502 -256.177796)
		(end 228.425502 -256.336038)
		(width 0.4572)
		(layer "F.Cu")
		(net "P1V25_SERDES_VDDPLL_PEX1_C8")
	)
	(segment
		(start 228.103684 -256.962656)
		(end 228.103684 -257.59791)
		(width 0.4572)
		(layer "F.Cu")
		(net "P1V25_SERDES_VDDPLL_PEX1_C8")
	)
	(segment
		(start 228.425502 -256.640838)
		(end 228.103684 -256.962656)
		(width 0.4572)
		(layer "F.Cu")
		(net "P1V25_SERDES_VDDPLL_PEX1_C8")
	)
	(via
		(at 228.425502 -256.336038)
		(size 0.762)
		(drill 0.381)
		(layers "F.Cu" "B.Cu")
		(net "P1V25_SERDES_VDDPLL_PEX1_C8")
	)
	(via
		(at 131.718304 -323.343016)
		(size 0.508)
		(drill 0.254)
		(layers "F.Cu" "B.Cu")
		(net "P0V8_SERDES_VDDA_PEX1_C10")
	)
	(segment
		(start 131.718304 -323.343016)
		(end 131.402328 -323.658992)
		(width 0.4572)
		(layer "B.Cu")
		(net "P0V8_SERDES_VDDA_PEX1_C10")
	)
	(segment
		(start 131.402328 -323.658992)
		(end 131.402328 -324.57263)
		(width 0.4572)
		(layer "B.Cu")
		(net "P0V8_SERDES_VDDA_PEX1_C10")
	)
	(segment
		(start 132.826506 -322.234814)
		(end 131.718304 -323.343016)
		(width 0.4572)
		(layer "B.Cu")
		(net "P0V8_SERDES_VDDA_PEX1_C10")
	)
	(via
		(at 135.334248 -323.384926)
		(size 0.6604)
		(drill 0.3302)
		(layers "F.Cu" "B.Cu")
		(net "P0V8_SERDES_VDDA_PEX1_C4")
	)
	(segment
		(start 134.735062 -322.251578)
		(end 135.334248 -322.850764)
		(width 0.4572)
		(layer "B.Cu")
		(net "P0V8_SERDES_VDDA_PEX1_C4")
	)
	(segment
		(start 135.334248 -322.850764)
		(end 135.334248 -323.384926)
		(width 0.4572)
		(layer "B.Cu")
		(net "P0V8_SERDES_VDDA_PEX1_C4")
	)
	(segment
		(start 135.334248 -323.384926)
		(end 134.146544 -324.57263)
		(width 0.4572)
		(layer "B.Cu")
		(net "P0V8_SERDES_VDDA_PEX1_C4")
	)
	(via
		(at 125.704854 -323.363082)
		(size 0.6604)
		(drill 0.3302)
		(layers "F.Cu" "B.Cu")
		(net "P0V8_SERDES_VDDA_PEX1_C0")
	)
	(segment
		(start 125.704346 -324.87489)
		(end 125.704346 -323.36359)
		(width 0.4572)
		(layer "B.Cu")
		(net "P0V8_SERDES_VDDA_PEX1_C0")
	)
	(segment
		(start 125.704854 -323.363082)
		(end 125.704854 -322.213224)
		(width 0.4572)
		(layer "B.Cu")
		(net "P0V8_SERDES_VDDA_PEX1_C0")
	)
	(segment
		(start 125.704346 -323.36359)
		(end 125.704854 -323.363082)
		(width 0.4572)
		(layer "B.Cu")
		(net "P0V8_SERDES_VDDA_PEX1_C0")
	)
	(segment
		(start 221.996508 -257.080004)
		(end 221.996508 -256.387346)
		(width 0.4572)
		(layer "F.Cu")
		(net "P1V25_SERDES_VDDPLL_PEX1_C1")
	)
	(segment
		(start 222.492316 -257.575812)
		(end 221.996508 -257.080004)
		(width 0.4572)
		(layer "F.Cu")
		(net "P1V25_SERDES_VDDPLL_PEX1_C1")
	)
	(segment
		(start 221.459806 -255.850644)
		(end 221.459806 -255.04902)
		(width 0.4572)
		(layer "F.Cu")
		(net "P1V25_SERDES_VDDPLL_PEX1_C1")
	)
	(segment
		(start 221.459806 -255.04902)
		(end 221.332806 -254.92202)
		(width 0.4572)
		(layer "F.Cu")
		(net "P1V25_SERDES_VDDPLL_PEX1_C1")
	)
	(segment
		(start 221.996508 -256.387346)
		(end 221.459806 -255.850644)
		(width 0.4572)
		(layer "F.Cu")
		(net "P1V25_SERDES_VDDPLL_PEX1_C1")
	)
	(via
		(at 221.996508 -256.387346)
		(size 0.762)
		(drill 0.381)
		(layers "F.Cu" "B.Cu")
		(net "P1V25_SERDES_VDDPLL_PEX1_C1")
	)
	(segment
		(start 225.09988 -255.346708)
		(end 225.857308 -256.104136)
		(width 0.4572)
		(layer "F.Cu")
		(net "P1V25_SERDES_VDDPLL_PEX1_C6")
	)
	(segment
		(start 225.09988 -254.92202)
		(end 225.09988 -255.346708)
		(width 0.4572)
		(layer "F.Cu")
		(net "P1V25_SERDES_VDDPLL_PEX1_C6")
	)
	(segment
		(start 225.857308 -256.332736)
		(end 225.857308 -257.54711)
		(width 0.4572)
		(layer "F.Cu")
		(net "P1V25_SERDES_VDDPLL_PEX1_C6")
	)
	(segment
		(start 225.857308 -257.54711)
		(end 225.828606 -257.575812)
		(width 0.4572)
		(layer "F.Cu")
		(net "P1V25_SERDES_VDDPLL_PEX1_C6")
	)
	(segment
		(start 225.857308 -256.104136)
		(end 225.857308 -256.332736)
		(width 0.4572)
		(layer "F.Cu")
		(net "P1V25_SERDES_VDDPLL_PEX1_C6")
	)
	(via
		(at 225.857308 -256.332736)
		(size 0.762)
		(drill 0.381)
		(layers "F.Cu" "B.Cu")
		(net "P1V25_SERDES_VDDPLL_PEX1_C6")
	)
	(segment
		(start 216.531952 -257.575812)
		(end 217.446352 -256.661412)
		(width 0.4572)
		(layer "F.Cu")
		(net "P1V25_SERDES_VDDPLL_PEX1_C5")
	)
	(segment
		(start 216.437718 -252.052836)
		(end 216.604596 -252.219714)
		(width 0.4572)
		(layer "F.Cu")
		(net "P1V25_SERDES_VDDPLL_PEX1_C5")
	)
	(segment
		(start 216.604596 -252.219714)
		(end 216.604596 -254.260858)
		(width 0.4572)
		(layer "F.Cu")
		(net "P1V25_SERDES_VDDPLL_PEX1_C5")
	)
	(segment
		(start 217.446352 -255.457198)
		(end 216.604596 -254.615442)
		(width 0.4572)
		(layer "F.Cu")
		(net "P1V25_SERDES_VDDPLL_PEX1_C5")
	)
	(segment
		(start 216.604596 -254.615442)
		(end 216.604596 -254.260858)
		(width 0.4572)
		(layer "F.Cu")
		(net "P1V25_SERDES_VDDPLL_PEX1_C5")
	)
	(segment
		(start 217.446352 -256.661412)
		(end 217.446352 -255.457198)
		(width 0.4572)
		(layer "F.Cu")
		(net "P1V25_SERDES_VDDPLL_PEX1_C5")
	)
	(via
		(at 216.604596 -254.260858)
		(size 0.762)
		(drill 0.381)
		(layers "F.Cu" "B.Cu")
		(net "P1V25_SERDES_VDDPLL_PEX1_C5")
	)
	(via
		(at 121.445782 -323.038978)
		(size 0.6604)
		(drill 0.3302)
		(layers "F.Cu" "B.Cu")
		(net "P0V8_SERDES_VDDA_PEX1_C8")
	)
	(segment
		(start 121.437146 -323.047614)
		(end 121.445782 -323.038978)
		(width 0.4572)
		(layer "B.Cu")
		(net "P0V8_SERDES_VDDA_PEX1_C8")
	)
	(segment
		(start 121.437146 -324.449694)
		(end 121.437146 -323.047614)
		(width 0.4572)
		(layer "B.Cu")
		(net "P0V8_SERDES_VDDA_PEX1_C8")
	)
	(segment
		(start 121.437654 -323.03085)
		(end 121.445782 -323.038978)
		(width 0.4572)
		(layer "B.Cu")
		(net "P0V8_SERDES_VDDA_PEX1_C8")
	)
	(segment
		(start 121.437654 -321.788028)
		(end 121.437654 -323.03085)
		(width 0.4572)
		(layer "B.Cu")
		(net "P0V8_SERDES_VDDA_PEX1_C8")
	)
	(segment
		(start 223.844612 -254.92202)
		(end 223.844612 -255.354328)
		(width 0.4572)
		(layer "F.Cu")
		(net "P1V25_SERDES_VDDPLL_PEX1_C3")
	)
	(segment
		(start 223.844612 -255.354328)
		(end 224.56394 -256.073656)
		(width 0.4572)
		(layer "F.Cu")
		(net "P1V25_SERDES_VDDPLL_PEX1_C3")
	)
	(segment
		(start 224.56394 -256.073656)
		(end 224.56394 -256.353056)
		(width 0.4572)
		(layer "F.Cu")
		(net "P1V25_SERDES_VDDPLL_PEX1_C3")
	)
	(segment
		(start 224.56394 -256.353056)
		(end 224.84334 -256.632456)
		(width 0.4572)
		(layer "F.Cu")
		(net "P1V25_SERDES_VDDPLL_PEX1_C3")
	)
	(segment
		(start 224.84334 -256.632456)
		(end 224.84334 -257.575812)
		(width 0.4572)
		(layer "F.Cu")
		(net "P1V25_SERDES_VDDPLL_PEX1_C3")
	)
	(via
		(at 224.56394 -256.353056)
		(size 0.762)
		(drill 0.381)
		(layers "F.Cu" "B.Cu")
		(net "P1V25_SERDES_VDDPLL_PEX1_C3")
	)
	(via
		(at 348.750128 -324.755764)
		(size 0.6604)
		(drill 0.3302)
		(layers "F.Cu" "B.Cu")
		(net "P0V8_SERDES_VDDA_PEX2_C3")
	)
	(segment
		(start 348.750128 -324.755764)
		(end 348.750128 -323.770498)
		(width 0.4572)
		(layer "B.Cu")
		(net "P0V8_SERDES_VDDA_PEX2_C3")
	)
	(segment
		(start 348.750128 -326.197722)
		(end 348.750128 -324.755764)
		(width 0.4572)
		(layer "B.Cu")
		(net "P0V8_SERDES_VDDA_PEX2_C3")
	)
	(segment
		(start 348.750128 -323.770498)
		(end 348.526608 -323.546978)
		(width 0.4572)
		(layer "B.Cu")
		(net "P0V8_SERDES_VDDA_PEX2_C3")
	)
	(segment
		(start 240.86439 -255.840484)
		(end 240.86439 -254.872998)
		(width 0.4572)
		(layer "F.Cu")
		(net "P1V25_SERDES_VDDPLL_PEX2_C5")
	)
	(segment
		(start 241.550698 -257.575812)
		(end 241.398806 -257.42392)
		(width 0.4572)
		(layer "F.Cu")
		(net "P1V25_SERDES_VDDPLL_PEX2_C5")
	)
	(segment
		(start 241.398806 -256.3749)
		(end 240.86439 -255.840484)
		(width 0.4572)
		(layer "F.Cu")
		(net "P1V25_SERDES_VDDPLL_PEX2_C5")
	)
	(segment
		(start 241.398806 -257.42392)
		(end 241.398806 -256.3749)
		(width 0.4572)
		(layer "F.Cu")
		(net "P1V25_SERDES_VDDPLL_PEX2_C5")
	)
	(via
		(at 241.398806 -256.3749)
		(size 0.762)
		(drill 0.381)
		(layers "F.Cu" "B.Cu")
		(net "P1V25_SERDES_VDDPLL_PEX2_C5")
	)
	(via
		(at 331.92847 -325.00443)
		(size 0.6604)
		(drill 0.3302)
		(layers "F.Cu" "B.Cu")
		(net "P0V8_SERDES_VDDA_PEX2_C10")
	)
	(segment
		(start 333.912972 -325.172578)
		(end 333.912972 -323.558916)
		(width 0.4572)
		(layer "B.Cu")
		(net "P0V8_SERDES_VDDA_PEX2_C10")
	)
	(segment
		(start 331.92847 -325.00443)
		(end 333.744824 -325.00443)
		(width 0.4572)
		(layer "B.Cu")
		(net "P0V8_SERDES_VDDA_PEX2_C10")
	)
	(segment
		(start 333.744824 -325.00443)
		(end 333.912972 -325.172578)
		(width 0.4572)
		(layer "B.Cu")
		(net "P0V8_SERDES_VDDA_PEX2_C10")
	)
	(segment
		(start 333.912972 -323.558916)
		(end 333.909416 -323.55536)
		(width 0.4572)
		(layer "B.Cu")
		(net "P0V8_SERDES_VDDA_PEX2_C10")
	)
	(segment
		(start 240.072164 -256.334006)
		(end 240.072164 -257.508502)
		(width 0.4572)
		(layer "F.Cu")
		(net "P1V25_SERDES_VDDPLL_PEX2_C3")
	)
	(segment
		(start 240.072164 -257.508502)
		(end 240.139474 -257.575812)
		(width 0.4572)
		(layer "F.Cu")
		(net "P1V25_SERDES_VDDPLL_PEX2_C3")
	)
	(segment
		(start 239.333024 -255.594866)
		(end 240.072164 -256.334006)
		(width 0.4572)
		(layer "F.Cu")
		(net "P1V25_SERDES_VDDPLL_PEX2_C3")
	)
	(segment
		(start 239.333024 -254.92202)
		(end 239.333024 -255.594866)
		(width 0.4572)
		(layer "F.Cu")
		(net "P1V25_SERDES_VDDPLL_PEX2_C3")
	)
	(via
		(at 240.072164 -256.334006)
		(size 0.762)
		(drill 0.381)
		(layers "F.Cu" "B.Cu")
		(net "P1V25_SERDES_VDDPLL_PEX2_C3")
	)
	(segment
		(start 244.12194 -254.833882)
		(end 244.12194 -255.427226)
		(width 0.4572)
		(layer "F.Cu")
		(net "P1V25_SERDES_VDDPLL_PEX2_C7")
	)
	(segment
		(start 244.05463 -255.494536)
		(end 244.05463 -256.271014)
		(width 0.4572)
		(layer "F.Cu")
		(net "P1V25_SERDES_VDDPLL_PEX2_C7")
	)
	(segment
		(start 244.05463 -256.841498)
		(end 244.811042 -257.59791)
		(width 0.4572)
		(layer "F.Cu")
		(net "P1V25_SERDES_VDDPLL_PEX2_C7")
	)
	(segment
		(start 244.12194 -255.427226)
		(end 244.05463 -255.494536)
		(width 0.4572)
		(layer "F.Cu")
		(net "P1V25_SERDES_VDDPLL_PEX2_C7")
	)
	(segment
		(start 244.05463 -256.271014)
		(end 244.05463 -256.841498)
		(width 0.4572)
		(layer "F.Cu")
		(net "P1V25_SERDES_VDDPLL_PEX2_C7")
	)
	(via
		(at 244.05463 -256.271014)
		(size 0.762)
		(drill 0.381)
		(layers "F.Cu" "B.Cu")
		(net "P1V25_SERDES_VDDPLL_PEX2_C7")
	)
	(via
		(at 344.641424 -324.830948)
		(size 0.6604)
		(drill 0.3302)
		(layers "F.Cu" "B.Cu")
		(net "P0V8_SERDES_VDDA_PEX2_C2")
	)
	(segment
		(start 344.641424 -324.830948)
		(end 344.641424 -323.55536)
		(width 0.4572)
		(layer "B.Cu")
		(net "P0V8_SERDES_VDDA_PEX2_C2")
	)
	(segment
		(start 344.645234 -326.208898)
		(end 344.641424 -326.205088)
		(width 0.4572)
		(layer "B.Cu")
		(net "P0V8_SERDES_VDDA_PEX2_C2")
	)
	(segment
		(start 344.641424 -326.205088)
		(end 344.641424 -324.830948)
		(width 0.4572)
		(layer "B.Cu")
		(net "P0V8_SERDES_VDDA_PEX2_C2")
	)
	(via
		(at 347.428312 -324.830948)
		(size 0.6604)
		(drill 0.3302)
		(layers "F.Cu" "B.Cu")
		(net "P0V8_SERDES_VDDA_PEX2_C6")
	)
	(segment
		(start 347.390974 -326.208898)
		(end 347.428312 -326.17156)
		(width 0.4572)
		(layer "B.Cu")
		(net "P0V8_SERDES_VDDA_PEX2_C6")
	)
	(segment
		(start 347.428312 -324.830948)
		(end 347.428312 -323.55536)
		(width 0.4572)
		(layer "B.Cu")
		(net "P0V8_SERDES_VDDA_PEX2_C6")
	)
	(segment
		(start 347.428312 -326.17156)
		(end 347.428312 -324.830948)
		(width 0.4572)
		(layer "B.Cu")
		(net "P0V8_SERDES_VDDA_PEX2_C6")
	)
	(segment
		(start 233.800904 -255.572768)
		(end 233.800904 -254.92202)
		(width 0.4572)
		(layer "F.Cu")
		(net "P1V25_SERDES_VDDPLL_PEX2_C9")
	)
	(segment
		(start 234.152694 -257.575812)
		(end 234.588304 -257.140202)
		(width 0.4572)
		(layer "F.Cu")
		(net "P1V25_SERDES_VDDPLL_PEX2_C9")
	)
	(segment
		(start 234.588304 -256.360168)
		(end 233.800904 -255.572768)
		(width 0.4572)
		(layer "F.Cu")
		(net "P1V25_SERDES_VDDPLL_PEX2_C9")
	)
	(segment
		(start 234.588304 -257.140202)
		(end 234.588304 -256.360168)
		(width 0.4572)
		(layer "F.Cu")
		(net "P1V25_SERDES_VDDPLL_PEX2_C9")
	)
	(via
		(at 234.588304 -256.360168)
		(size 0.762)
		(drill 0.381)
		(layers "F.Cu" "B.Cu")
		(net "P1V25_SERDES_VDDPLL_PEX2_C9")
	)
	(segment
		(start 235.196126 -255.524762)
		(end 235.196126 -254.92202)
		(width 0.4572)
		(layer "F.Cu")
		(net "P1V25_SERDES_VDDPLL_PEX2_C0")
	)
	(segment
		(start 235.707936 -257.575812)
		(end 235.983526 -257.300222)
		(width 0.4572)
		(layer "F.Cu")
		(net "P1V25_SERDES_VDDPLL_PEX2_C0")
	)
	(segment
		(start 235.983526 -256.312162)
		(end 235.196126 -255.524762)
		(width 0.4572)
		(layer "F.Cu")
		(net "P1V25_SERDES_VDDPLL_PEX2_C0")
	)
	(segment
		(start 235.983526 -257.300222)
		(end 235.983526 -256.312162)
		(width 0.4572)
		(layer "F.Cu")
		(net "P1V25_SERDES_VDDPLL_PEX2_C0")
	)
	(via
		(at 235.983526 -256.312162)
		(size 0.762)
		(drill 0.381)
		(layers "F.Cu" "B.Cu")
		(net "P1V25_SERDES_VDDPLL_PEX2_C0")
	)
	(segment
		(start 248.924572 -255.307592)
		(end 248.698766 -255.081786)
		(width 0.4572)
		(layer "F.Cu")
		(net "P1V25_SERDES_VDDPLL_PEX2_C11")
	)
	(segment
		(start 247.817386 -257.553968)
		(end 248.83364 -256.537714)
		(width 0.4572)
		(layer "F.Cu")
		(net "P1V25_SERDES_VDDPLL_PEX2_C11")
	)
	(segment
		(start 247.817386 -257.6449)
		(end 247.817386 -257.553968)
		(width 0.4572)
		(layer "F.Cu")
		(net "P1V25_SERDES_VDDPLL_PEX2_C11")
	)
	(segment
		(start 248.924572 -256.537714)
		(end 248.924572 -255.307592)
		(width 0.4572)
		(layer "F.Cu")
		(net "P1V25_SERDES_VDDPLL_PEX2_C11")
	)
	(segment
		(start 248.83364 -256.537714)
		(end 248.924572 -256.537714)
		(width 0.4572)
		(layer "F.Cu")
		(net "P1V25_SERDES_VDDPLL_PEX2_C11")
	)
	(via
		(at 248.924572 -256.537714)
		(size 0.762)
		(drill 0.381)
		(layers "F.Cu" "B.Cu")
		(net "P1V25_SERDES_VDDPLL_PEX2_C11")
	)
	(via
		(at 337.541362 -324.824852)
		(size 0.6604)
		(drill 0.3302)
		(layers "F.Cu" "B.Cu")
		(net "P0V8_SERDES_VDDA_PEX2_C8")
	)
	(segment
		(start 337.541362 -325.330312)
		(end 336.662776 -326.208898)
		(width 0.4572)
		(layer "B.Cu")
		(net "P0V8_SERDES_VDDA_PEX2_C8")
	)
	(segment
		(start 337.541362 -324.824852)
		(end 337.541362 -325.330312)
		(width 0.4572)
		(layer "B.Cu")
		(net "P0V8_SERDES_VDDA_PEX2_C8")
	)
	(segment
		(start 337.541362 -324.42531)
		(end 337.541362 -324.824852)
		(width 0.4572)
		(layer "B.Cu")
		(net "P0V8_SERDES_VDDA_PEX2_C8")
	)
	(segment
		(start 336.671412 -323.55536)
		(end 337.541362 -324.42531)
		(width 0.4572)
		(layer "B.Cu")
		(net "P0V8_SERDES_VDDA_PEX2_C8")
	)
	(via
		(at 113.346484 -323.03339)
		(size 0.6604)
		(drill 0.3302)
		(layers "F.Cu" "B.Cu")
		(net "P0V8_SERDES_VDDA_PEX0_C7")
	)
	(segment
		(start 113.346484 -323.03339)
		(end 113.346484 -321.771518)
		(width 0.4572)
		(layer "B.Cu")
		(net "P0V8_SERDES_VDDA_PEX0_C7")
	)
	(segment
		(start 113.346484 -324.41642)
		(end 113.346484 -323.03339)
		(width 0.4572)
		(layer "B.Cu")
		(net "P0V8_SERDES_VDDA_PEX0_C7")
	)
	(segment
		(start 113.337848 -324.425056)
		(end 113.346484 -324.41642)
		(width 0.4572)
		(layer "B.Cu")
		(net "P0V8_SERDES_VDDA_PEX0_C7")
	)
	(segment
		(start 233.299762 -257.05816)
		(end 233.299762 -256.387854)
		(width 0.4572)
		(layer "F.Cu")
		(net "P1V25_SERDES_VDDPLL_PEX2_C1")
	)
	(segment
		(start 232.78211 -257.575812)
		(end 233.299762 -257.05816)
		(width 0.4572)
		(layer "F.Cu")
		(net "P1V25_SERDES_VDDPLL_PEX2_C1")
	)
	(segment
		(start 232.092754 -255.227836)
		(end 232.092754 -255.17602)
		(width 0.4572)
		(layer "F.Cu")
		(net "P1V25_SERDES_VDDPLL_PEX2_C1")
	)
	(segment
		(start 233.299762 -256.387854)
		(end 233.252772 -256.387854)
		(width 0.4572)
		(layer "F.Cu")
		(net "P1V25_SERDES_VDDPLL_PEX2_C1")
	)
	(segment
		(start 233.252772 -256.387854)
		(end 232.092754 -255.227836)
		(width 0.4572)
		(layer "F.Cu")
		(net "P1V25_SERDES_VDDPLL_PEX2_C1")
	)
	(via
		(at 233.299762 -256.387854)
		(size 0.762)
		(drill 0.381)
		(layers "F.Cu" "B.Cu")
		(net "P1V25_SERDES_VDDPLL_PEX2_C1")
	)
	(via
		(at 114.649758 -323.04736)
		(size 0.6604)
		(drill 0.3302)
		(layers "F.Cu" "B.Cu")
		(net "P0V8_SERDES_VDDA_PEX0_C6")
	)
	(segment
		(start 114.649758 -323.04736)
		(end 114.649758 -321.785488)
		(width 0.4572)
		(layer "B.Cu")
		(net "P0V8_SERDES_VDDA_PEX0_C6")
	)
	(segment
		(start 114.641122 -324.439026)
		(end 114.649758 -324.43039)
		(width 0.4572)
		(layer "B.Cu")
		(net "P0V8_SERDES_VDDA_PEX0_C6")
	)
	(segment
		(start 114.649758 -324.43039)
		(end 114.649758 -323.04736)
		(width 0.4572)
		(layer "B.Cu")
		(net "P0V8_SERDES_VDDA_PEX0_C6")
	)
	(segment
		(start 238.751364 -257.566922)
		(end 238.751364 -256.332736)
		(width 0.4572)
		(layer "F.Cu")
		(net "P1V25_SERDES_VDDPLL_PEX2_C2")
	)
	(segment
		(start 238.751364 -256.332736)
		(end 237.963964 -255.545336)
		(width 0.4572)
		(layer "F.Cu")
		(net "P1V25_SERDES_VDDPLL_PEX2_C2")
	)
	(segment
		(start 237.963964 -255.545336)
		(end 237.963964 -254.92202)
		(width 0.4572)
		(layer "F.Cu")
		(net "P1V25_SERDES_VDDPLL_PEX2_C2")
	)
	(segment
		(start 238.742474 -257.575812)
		(end 238.751364 -257.566922)
		(width 0.4572)
		(layer "F.Cu")
		(net "P1V25_SERDES_VDDPLL_PEX2_C2")
	)
	(via
		(at 238.751364 -256.332736)
		(size 0.762)
		(drill 0.381)
		(layers "F.Cu" "B.Cu")
		(net "P1V25_SERDES_VDDPLL_PEX2_C2")
	)
	(via
		(at 106.89082 -323.509132)
		(size 0.6604)
		(drill 0.3302)
		(layers "F.Cu" "B.Cu")
		(net "P0V8_SERDES_VDDA_PEX0_C9")
	)
	(segment
		(start 108.146342 -322.478654)
		(end 107.657392 -322.967604)
		(width 0.4572)
		(layer "B.Cu")
		(net "P0V8_SERDES_VDDA_PEX0_C9")
	)
	(segment
		(start 107.657392 -322.967604)
		(end 107.131358 -322.967604)
		(width 0.4572)
		(layer "B.Cu")
		(net "P0V8_SERDES_VDDA_PEX0_C9")
	)
	(segment
		(start 106.89082 -323.208142)
		(end 106.89082 -323.509132)
		(width 0.4572)
		(layer "B.Cu")
		(net "P0V8_SERDES_VDDA_PEX0_C9")
	)
	(segment
		(start 107.354624 -324.411594)
		(end 108.171996 -324.411594)
		(width 0.4572)
		(layer "B.Cu")
		(net "P0V8_SERDES_VDDA_PEX0_C9")
	)
	(segment
		(start 106.89082 -323.94779)
		(end 107.354624 -324.411594)
		(width 0.4572)
		(layer "B.Cu")
		(net "P0V8_SERDES_VDDA_PEX0_C9")
	)
	(segment
		(start 106.89082 -323.509132)
		(end 106.89082 -323.94779)
		(width 0.4572)
		(layer "B.Cu")
		(net "P0V8_SERDES_VDDA_PEX0_C9")
	)
	(segment
		(start 108.146342 -322.210938)
		(end 108.146342 -322.478654)
		(width 0.4572)
		(layer "B.Cu")
		(net "P0V8_SERDES_VDDA_PEX0_C9")
	)
	(segment
		(start 107.131358 -322.967604)
		(end 106.89082 -323.208142)
		(width 0.4572)
		(layer "B.Cu")
		(net "P0V8_SERDES_VDDA_PEX0_C9")
	)
	(via
		(at 339.581744 -324.707504)
		(size 0.6604)
		(drill 0.3302)
		(layers "F.Cu" "B.Cu")
		(net "P0V8_SERDES_VDDA_PEX2_C1")
	)
	(segment
		(start 339.581744 -324.707504)
		(end 339.581744 -323.80936)
		(width 0.4572)
		(layer "B.Cu")
		(net "P0V8_SERDES_VDDA_PEX2_C1")
	)
	(segment
		(start 339.581744 -325.938896)
		(end 339.581744 -324.707504)
		(width 0.4572)
		(layer "B.Cu")
		(net "P0V8_SERDES_VDDA_PEX2_C1")
	)
	(segment
		(start 339.311742 -326.208898)
		(end 339.581744 -325.938896)
		(width 0.4572)
		(layer "B.Cu")
		(net "P0V8_SERDES_VDDA_PEX2_C1")
	)
	(segment
		(start 339.581744 -323.80936)
		(end 339.327744 -323.55536)
		(width 0.4572)
		(layer "B.Cu")
		(net "P0V8_SERDES_VDDA_PEX2_C1")
	)
	(segment
		(start 115.720368 -318.921638)
		(end 115.727226 -318.91478)
		(width 0.4572)
		(layer "F.Cu")
		(net "P0V8_SERDES_VDDA_PEX0_C10")
	)
	(segment
		(start 115.720368 -320.083434)
		(end 115.720368 -318.921638)
		(width 0.4572)
		(layer "F.Cu")
		(net "P0V8_SERDES_VDDA_PEX0_C10")
	)
	(via
		(at 338.558378 -324.756272)
		(size 0.6604)
		(drill 0.3302)
		(layers "F.Cu" "B.Cu")
		(net "P0V8_SERDES_VDDA_PEX2_C11")
	)
	(segment
		(start 338.558378 -324.14591)
		(end 338.558378 -324.756272)
		(width 0.4572)
		(layer "B.Cu")
		(net "P0V8_SERDES_VDDA_PEX2_C11")
	)
	(segment
		(start 338.558378 -325.621396)
		(end 337.970876 -326.208898)
		(width 0.4572)
		(layer "B.Cu")
		(net "P0V8_SERDES_VDDA_PEX2_C11")
	)
	(segment
		(start 338.558378 -324.756272)
		(end 338.558378 -325.621396)
		(width 0.4572)
		(layer "B.Cu")
		(net "P0V8_SERDES_VDDA_PEX2_C11")
	)
	(segment
		(start 337.967828 -323.55536)
		(end 338.558378 -324.14591)
		(width 0.4572)
		(layer "B.Cu")
		(net "P0V8_SERDES_VDDA_PEX2_C11")
	)
	(segment
		(start 117.119654 -319.46469)
		(end 116.985796 -319.330832)
		(width 0.4572)
		(layer "F.Cu")
		(net "P0V8_SERDES_VDDA_PEX0_C11")
	)
	(segment
		(start 116.985796 -319.330832)
		(end 116.985796 -318.915034)
		(width 0.4572)
		(layer "F.Cu")
		(net "P0V8_SERDES_VDDA_PEX0_C11")
	)
	(segment
		(start 117.119654 -320.083434)
		(end 117.119654 -319.46469)
		(width 0.4572)
		(layer "F.Cu")
		(net "P0V8_SERDES_VDDA_PEX0_C11")
	)
	(via
		(at 343.324942 -324.7898)
		(size 0.6604)
		(drill 0.3302)
		(layers "F.Cu" "B.Cu")
		(net "P0V8_SERDES_VDDA_PEX2_C5")
	)
	(segment
		(start 343.324942 -326.207628)
		(end 343.324942 -324.7898)
		(width 0.4572)
		(layer "B.Cu")
		(net "P0V8_SERDES_VDDA_PEX2_C5")
	)
	(segment
		(start 343.324942 -324.7898)
		(end 343.324942 -323.55536)
		(width 0.4572)
		(layer "B.Cu")
		(net "P0V8_SERDES_VDDA_PEX2_C5")
	)
	(segment
		(start 343.323672 -326.208898)
		(end 343.324942 -326.207628)
		(width 0.4572)
		(layer "B.Cu")
		(net "P0V8_SERDES_VDDA_PEX2_C5")
	)
	(via
		(at 109.502956 -323.266054)
		(size 0.508)
		(drill 0.254)
		(layers "F.Cu" "B.Cu")
		(net "P0V8_SERDES_VDDA_PEX0_C8")
	)
	(segment
		(start 109.502956 -324.48754)
		(end 109.502956 -323.266054)
		(width 0.4572)
		(layer "B.Cu")
		(net "P0V8_SERDES_VDDA_PEX0_C8")
	)
	(segment
		(start 109.641894 -322.645024)
		(end 109.641894 -322.210938)
		(width 0.4572)
		(layer "B.Cu")
		(net "P0V8_SERDES_VDDA_PEX0_C8")
	)
	(segment
		(start 109.502956 -322.783962)
		(end 109.641894 -322.645024)
		(width 0.4572)
		(layer "B.Cu")
		(net "P0V8_SERDES_VDDA_PEX0_C8")
	)
	(segment
		(start 109.502956 -323.266054)
		(end 109.502956 -322.783962)
		(width 0.4572)
		(layer "B.Cu")
		(net "P0V8_SERDES_VDDA_PEX0_C8")
	)
	(segment
		(start 236.58195 -255.586484)
		(end 236.58195 -254.92202)
		(width 0.4572)
		(layer "F.Cu")
		(net "P1V25_SERDES_VDDPLL_PEX2_C8")
	)
	(segment
		(start 237.36935 -256.373884)
		(end 236.58195 -255.586484)
		(width 0.4572)
		(layer "F.Cu")
		(net "P1V25_SERDES_VDDPLL_PEX2_C8")
	)
	(segment
		(start 237.332012 -257.575812)
		(end 237.36935 -257.538474)
		(width 0.4572)
		(layer "F.Cu")
		(net "P1V25_SERDES_VDDPLL_PEX2_C8")
	)
	(segment
		(start 237.36935 -257.538474)
		(end 237.36935 -256.373884)
		(width 0.4572)
		(layer "F.Cu")
		(net "P1V25_SERDES_VDDPLL_PEX2_C8")
	)
	(via
		(at 237.36935 -256.373884)
		(size 0.762)
		(drill 0.381)
		(layers "F.Cu" "B.Cu")
		(net "P1V25_SERDES_VDDPLL_PEX2_C8")
	)
	(segment
		(start 247.16232 -256.041398)
		(end 246.836692 -256.367026)
		(width 0.4572)
		(layer "F.Cu")
		(net "P1V25_SERDES_VDDPLL_PEX2_C6")
	)
	(segment
		(start 246.836692 -257.629914)
		(end 246.82704 -257.639566)
		(width 0.4572)
		(layer "F.Cu")
		(net "P1V25_SERDES_VDDPLL_PEX2_C6")
	)
	(segment
		(start 246.836692 -256.367026)
		(end 246.836692 -257.629914)
		(width 0.4572)
		(layer "F.Cu")
		(net "P1V25_SERDES_VDDPLL_PEX2_C6")
	)
	(segment
		(start 247.16232 -254.877824)
		(end 247.16232 -256.041398)
		(width 0.4572)
		(layer "F.Cu")
		(net "P1V25_SERDES_VDDPLL_PEX2_C6")
	)
	(via
		(at 246.836692 -256.367026)
		(size 0.762)
		(drill 0.381)
		(layers "F.Cu" "B.Cu")
		(net "P1V25_SERDES_VDDPLL_PEX2_C6")
	)
	(segment
		(start 242.716304 -254.989838)
		(end 242.716304 -256.370582)
		(width 0.4572)
		(layer "F.Cu")
		(net "P1V25_SERDES_VDDPLL_PEX2_C10")
	)
	(segment
		(start 242.61191 -254.885444)
		(end 242.716304 -254.989838)
		(width 0.4572)
		(layer "F.Cu")
		(net "P1V25_SERDES_VDDPLL_PEX2_C10")
	)
	(segment
		(start 242.716304 -257.395472)
		(end 242.535964 -257.575812)
		(width 0.4572)
		(layer "F.Cu")
		(net "P1V25_SERDES_VDDPLL_PEX2_C10")
	)
	(segment
		(start 242.716304 -256.370582)
		(end 242.716304 -257.395472)
		(width 0.4572)
		(layer "F.Cu")
		(net "P1V25_SERDES_VDDPLL_PEX2_C10")
	)
	(via
		(at 242.716304 -256.370582)
		(size 0.762)
		(drill 0.381)
		(layers "F.Cu" "B.Cu")
		(net "P1V25_SERDES_VDDPLL_PEX2_C10")
	)
	(via
		(at 346.026232 -324.830948)
		(size 0.6604)
		(drill 0.3302)
		(layers "F.Cu" "B.Cu")
		(net "P0V8_SERDES_VDDA_PEX2_C7")
	)
	(segment
		(start 346.026232 -326.198992)
		(end 346.026232 -324.830948)
		(width 0.4572)
		(layer "B.Cu")
		(net "P0V8_SERDES_VDDA_PEX2_C7")
	)
	(segment
		(start 346.026232 -324.830948)
		(end 346.026232 -323.55536)
		(width 0.4572)
		(layer "B.Cu")
		(net "P0V8_SERDES_VDDA_PEX2_C7")
	)
	(segment
		(start 346.016326 -326.208898)
		(end 346.026232 -326.198992)
		(width 0.4572)
		(layer "B.Cu")
		(net "P0V8_SERDES_VDDA_PEX2_C7")
	)
	(segment
		(start 245.482364 -257.3401)
		(end 245.77675 -257.634486)
		(width 0.4572)
		(layer "F.Cu")
		(net "P1V25_SERDES_VDDPLL_PEX2_C4")
	)
	(segment
		(start 245.482364 -256.346452)
		(end 245.482364 -255.040638)
		(width 0.4572)
		(layer "F.Cu")
		(net "P1V25_SERDES_VDDPLL_PEX2_C4")
	)
	(segment
		(start 245.482364 -256.346452)
		(end 245.482364 -257.3401)
		(width 0.4572)
		(layer "F.Cu")
		(net "P1V25_SERDES_VDDPLL_PEX2_C4")
	)
	(segment
		(start 245.482364 -255.040638)
		(end 245.625112 -254.89789)
		(width 0.4572)
		(layer "F.Cu")
		(net "P1V25_SERDES_VDDPLL_PEX2_C4")
	)
	(via
		(at 245.482364 -256.346452)
		(size 0.762)
		(drill 0.381)
		(layers "F.Cu" "B.Cu")
		(net "P1V25_SERDES_VDDPLL_PEX2_C4")
	)
	(via
		(at 341.975948 -324.7898)
		(size 0.6604)
		(drill 0.3302)
		(layers "F.Cu" "B.Cu")
		(net "P0V8_SERDES_VDDA_PEX2_C4")
	)
	(segment
		(start 341.978234 -326.208898)
		(end 341.975948 -326.206612)
		(width 0.4572)
		(layer "B.Cu")
		(net "P0V8_SERDES_VDDA_PEX2_C4")
	)
	(segment
		(start 341.975948 -324.7898)
		(end 341.975948 -323.55536)
		(width 0.4572)
		(layer "B.Cu")
		(net "P0V8_SERDES_VDDA_PEX2_C4")
	)
	(segment
		(start 341.975948 -326.206612)
		(end 341.975948 -324.7898)
		(width 0.4572)
		(layer "B.Cu")
		(net "P0V8_SERDES_VDDA_PEX2_C4")
	)
	(via
		(at 336.521044 -324.856348)
		(size 0.508)
		(drill 0.254)
		(layers "F.Cu" "B.Cu")
		(net "P0V8_SERDES_VDDA_PEX2_C0")
	)
	(segment
		(start 336.283554 -325.158608)
		(end 336.521044 -324.921118)
		(width 0.4572)
		(layer "B.Cu")
		(net "P0V8_SERDES_VDDA_PEX2_C0")
	)
	(segment
		(start 336.521044 -324.856348)
		(end 336.521044 -324.47738)
		(width 0.4572)
		(layer "B.Cu")
		(net "P0V8_SERDES_VDDA_PEX2_C0")
	)
	(segment
		(start 335.298288 -325.158608)
		(end 336.283554 -325.158608)
		(width 0.4572)
		(layer "B.Cu")
		(net "P0V8_SERDES_VDDA_PEX2_C0")
	)
	(segment
		(start 336.521044 -324.921118)
		(end 336.521044 -324.856348)
		(width 0.4572)
		(layer "B.Cu")
		(net "P0V8_SERDES_VDDA_PEX2_C0")
	)
	(segment
		(start 336.521044 -324.47738)
		(end 335.599024 -323.55536)
		(width 0.4572)
		(layer "B.Cu")
		(net "P0V8_SERDES_VDDA_PEX2_C0")
	)
	(segment
		(start 335.599024 -323.55536)
		(end 335.279746 -323.55536)
		(width 0.4572)
		(layer "B.Cu")
		(net "P0V8_SERDES_VDDA_PEX2_C0")
	)
	(via
		(at 340.671404 -324.762368)
		(size 0.6604)
		(drill 0.3302)
		(layers "F.Cu" "B.Cu")
		(net "P0V8_SERDES_VDDA_PEX2_C9")
	)
	(segment
		(start 340.671404 -324.762368)
		(end 340.671404 -323.55536)
		(width 0.4572)
		(layer "B.Cu")
		(net "P0V8_SERDES_VDDA_PEX2_C9")
	)
	(segment
		(start 340.671404 -326.186292)
		(end 340.671404 -324.762368)
		(width 0.4572)
		(layer "B.Cu")
		(net "P0V8_SERDES_VDDA_PEX2_C9")
	)
	(segment
		(start 340.648798 -326.208898)
		(end 340.671404 -326.186292)
		(width 0.4572)
		(layer "B.Cu")
		(net "P0V8_SERDES_VDDA_PEX2_C9")
	)
	(via
		(at 367.629694 -323.398388)
		(size 0.6604)
		(drill 0.3302)
		(layers "F.Cu" "B.Cu")
		(net "P0V8_SERDES_VDDA_PEX3_C5")
	)
	(segment
		(start 366.316768 -323.427344)
		(end 367.600738 -323.427344)
		(width 0.4572)
		(layer "B.Cu")
		(net "P0V8_SERDES_VDDA_PEX3_C5")
	)
	(segment
		(start 367.629694 -323.398388)
		(end 367.629694 -322.659756)
		(width 0.4572)
		(layer "B.Cu")
		(net "P0V8_SERDES_VDDA_PEX3_C5")
	)
	(segment
		(start 367.600738 -323.427344)
		(end 367.629694 -323.398388)
		(width 0.4572)
		(layer "B.Cu")
		(net "P0V8_SERDES_VDDA_PEX3_C5")
	)
	(segment
		(start 367.629694 -322.659756)
		(end 367.215928 -322.24599)
		(width 0.4572)
		(layer "B.Cu")
		(net "P0V8_SERDES_VDDA_PEX3_C5")
	)
	(segment
		(start 367.215928 -322.24599)
		(end 366.872774 -322.24599)
		(width 0.4572)
		(layer "B.Cu")
		(net "P0V8_SERDES_VDDA_PEX3_C5")
	)
	(segment
		(start 453.17283 -257.043682)
		(end 453.510142 -256.70637)
		(width 0.4572)
		(layer "F.Cu")
		(net "P1V25_SERDES_VDDPLL_PEX3_C1")
	)
	(segment
		(start 453.17283 -257.931158)
		(end 453.17283 -257.043682)
		(width 0.4572)
		(layer "F.Cu")
		(net "P1V25_SERDES_VDDPLL_PEX3_C1")
	)
	(segment
		(start 453.842882 -256.37363)
		(end 453.842882 -255.334516)
		(width 0.4572)
		(layer "F.Cu")
		(net "P1V25_SERDES_VDDPLL_PEX3_C1")
	)
	(segment
		(start 453.842882 -255.334516)
		(end 453.841866 -255.3335)
		(width 0.4572)
		(layer "F.Cu")
		(net "P1V25_SERDES_VDDPLL_PEX3_C1")
	)
	(segment
		(start 453.510142 -256.70637)
		(end 453.842882 -256.37363)
		(width 0.4572)
		(layer "F.Cu")
		(net "P1V25_SERDES_VDDPLL_PEX3_C1")
	)
	(via
		(at 453.510142 -256.70637)
		(size 0.762)
		(drill 0.381)
		(layers "F.Cu" "B.Cu")
		(net "P1V25_SERDES_VDDPLL_PEX3_C1")
	)
	(segment
		(start 361.058968 -322.573904)
		(end 361.912408 -323.427344)
		(width 0.4572)
		(layer "B.Cu")
		(net "P0V8_SERDES_VDDA_PEX3_C11")
	)
	(segment
		(start 360.882692 -322.573904)
		(end 361.058968 -322.573904)
		(width 0.4572)
		(layer "B.Cu")
		(net "P0V8_SERDES_VDDA_PEX3_C11")
	)
	(segment
		(start 360.540554 -322.231766)
		(end 360.882692 -322.573904)
		(width 0.4572)
		(layer "B.Cu")
		(net "P0V8_SERDES_VDDA_PEX3_C11")
	)
	(segment
		(start 457.817728 -257.931158)
		(end 457.817728 -256.694686)
		(width 0.4572)
		(layer "F.Cu")
		(net "P1V25_SERDES_VDDPLL_PEX3_C4")
	)
	(segment
		(start 458.15504 -255.233932)
		(end 457.817728 -255.571244)
		(width 0.4572)
		(layer "F.Cu")
		(net "P1V25_SERDES_VDDPLL_PEX3_C4")
	)
	(segment
		(start 458.219048 -255.233932)
		(end 458.15504 -255.233932)
		(width 0.4572)
		(layer "F.Cu")
		(net "P1V25_SERDES_VDDPLL_PEX3_C4")
	)
	(segment
		(start 457.817728 -255.571244)
		(end 457.817728 -256.694686)
		(width 0.4572)
		(layer "F.Cu")
		(net "P1V25_SERDES_VDDPLL_PEX3_C4")
	)
	(via
		(at 457.817728 -256.694686)
		(size 0.762)
		(drill 0.381)
		(layers "F.Cu" "B.Cu")
		(net "P1V25_SERDES_VDDPLL_PEX3_C4")
	)
	(segment
		(start 451.622668 -257.146298)
		(end 451.622668 -257.931158)
		(width 0.4572)
		(layer "F.Cu")
		(net "P1V25_SERDES_VDDPLL_PEX3_C9")
	)
	(segment
		(start 452.457058 -255.349248)
		(end 452.457058 -256.311908)
		(width 0.4572)
		(layer "F.Cu")
		(net "P1V25_SERDES_VDDPLL_PEX3_C9")
	)
	(segment
		(start 452.472806 -255.3335)
		(end 452.457058 -255.349248)
		(width 0.4572)
		(layer "F.Cu")
		(net "P1V25_SERDES_VDDPLL_PEX3_C9")
	)
	(segment
		(start 452.059294 -256.709672)
		(end 451.622668 -257.146298)
		(width 0.4572)
		(layer "F.Cu")
		(net "P1V25_SERDES_VDDPLL_PEX3_C9")
	)
	(segment
		(start 452.457058 -256.311908)
		(end 452.059294 -256.709672)
		(width 0.4572)
		(layer "F.Cu")
		(net "P1V25_SERDES_VDDPLL_PEX3_C9")
	)
	(via
		(at 452.059294 -256.709672)
		(size 0.762)
		(drill 0.381)
		(layers "F.Cu" "B.Cu")
		(net "P1V25_SERDES_VDDPLL_PEX3_C9")
	)
	(via
		(at 358.918764 -323.316346)
		(size 0.508)
		(drill 0.254)
		(layers "F.Cu" "B.Cu")
		(net "P0V8_SERDES_VDDA_PEX3_C8")
	)
	(segment
		(start 359.455974 -322.779136)
		(end 358.918764 -323.316346)
		(width 0.4572)
		(layer "B.Cu")
		(net "P0V8_SERDES_VDDA_PEX3_C8")
	)
	(segment
		(start 359.455974 -322.24599)
		(end 359.455974 -322.779136)
		(width 0.4572)
		(layer "B.Cu")
		(net "P0V8_SERDES_VDDA_PEX3_C8")
	)
	(segment
		(start 360.24312 -323.427344)
		(end 359.029762 -323.427344)
		(width 0.4572)
		(layer "B.Cu")
		(net "P0V8_SERDES_VDDA_PEX3_C8")
	)
	(segment
		(start 359.029762 -323.427344)
		(end 358.918764 -323.316346)
		(width 0.4572)
		(layer "B.Cu")
		(net "P0V8_SERDES_VDDA_PEX3_C8")
	)
	(segment
		(start 448.343274 -257.931158)
		(end 448.343274 -257.201162)
		(width 0.4572)
		(layer "F.Cu")
		(net "P1V25_SERDES_VDDPLL_PEX3_C0")
	)
	(segment
		(start 448.343274 -257.201162)
		(end 448.851782 -256.692654)
		(width 0.4572)
		(layer "F.Cu")
		(net "P1V25_SERDES_VDDPLL_PEX3_C0")
	)
	(segment
		(start 448.851782 -256.692654)
		(end 449.704968 -255.839468)
		(width 0.4572)
		(layer "F.Cu")
		(net "P1V25_SERDES_VDDPLL_PEX3_C0")
	)
	(segment
		(start 449.704968 -255.839468)
		(end 449.704968 -255.3335)
		(width 0.4572)
		(layer "F.Cu")
		(net "P1V25_SERDES_VDDPLL_PEX3_C0")
	)
	(via
		(at 448.851782 -256.692654)
		(size 0.762)
		(drill 0.381)
		(layers "F.Cu" "B.Cu")
		(net "P1V25_SERDES_VDDPLL_PEX3_C0")
	)
	(via
		(at 356.886764 -323.316346)
		(size 0.508)
		(drill 0.254)
		(layers "F.Cu" "B.Cu")
		(net "P0V8_SERDES_VDDA_PEX3_C9")
	)
	(segment
		(start 356.886764 -323.316346)
		(end 356.886764 -324.049644)
		(width 0.4572)
		(layer "B.Cu")
		(net "P0V8_SERDES_VDDA_PEX3_C9")
	)
	(segment
		(start 357.356664 -322.24599)
		(end 356.886764 -322.71589)
		(width 0.4572)
		(layer "B.Cu")
		(net "P0V8_SERDES_VDDA_PEX3_C9")
	)
	(segment
		(start 356.886764 -322.71589)
		(end 356.886764 -323.316346)
		(width 0.4572)
		(layer "B.Cu")
		(net "P0V8_SERDES_VDDA_PEX3_C9")
	)
	(segment
		(start 356.886764 -324.049644)
		(end 357.436928 -324.599808)
		(width 0.4572)
		(layer "B.Cu")
		(net "P0V8_SERDES_VDDA_PEX3_C9")
	)
	(segment
		(start 451.057518 -256.058416)
		(end 450.412612 -256.703322)
		(width 0.4572)
		(layer "F.Cu")
		(net "P1V25_SERDES_VDDPLL_PEX3_C8")
	)
	(segment
		(start 451.090792 -255.3335)
		(end 451.057518 -255.366774)
		(width 0.4572)
		(layer "F.Cu")
		(net "P1V25_SERDES_VDDPLL_PEX3_C8")
	)
	(segment
		(start 450.412612 -256.703322)
		(end 450.085968 -257.029966)
		(width 0.4572)
		(layer "F.Cu")
		(net "P1V25_SERDES_VDDPLL_PEX3_C8")
	)
	(segment
		(start 450.085968 -257.029966)
		(end 450.085968 -257.931158)
		(width 0.4572)
		(layer "F.Cu")
		(net "P1V25_SERDES_VDDPLL_PEX3_C8")
	)
	(segment
		(start 451.057518 -255.366774)
		(end 451.057518 -256.058416)
		(width 0.4572)
		(layer "F.Cu")
		(net "P1V25_SERDES_VDDPLL_PEX3_C8")
	)
	(via
		(at 450.412612 -256.703322)
		(size 0.762)
		(drill 0.381)
		(layers "F.Cu" "B.Cu")
		(net "P1V25_SERDES_VDDPLL_PEX3_C8")
	)
	(segment
		(start 461.76311 -255.233932)
		(end 460.425038 -256.572004)
		(width 0.4572)
		(layer "F.Cu")
		(net "P1V25_SERDES_VDDPLL_PEX3_C10")
	)
	(segment
		(start 460.425038 -257.82143)
		(end 460.31531 -257.931158)
		(width 0.4572)
		(layer "F.Cu")
		(net "P1V25_SERDES_VDDPLL_PEX3_C10")
	)
	(segment
		(start 460.425038 -256.723896)
		(end 460.425038 -257.82143)
		(width 0.4572)
		(layer "F.Cu")
		(net "P1V25_SERDES_VDDPLL_PEX3_C10")
	)
	(segment
		(start 460.425038 -256.572004)
		(end 460.425038 -256.723896)
		(width 0.4572)
		(layer "F.Cu")
		(net "P1V25_SERDES_VDDPLL_PEX3_C10")
	)
	(via
		(at 460.425038 -256.723896)
		(size 0.762)
		(drill 0.381)
		(layers "F.Cu" "B.Cu")
		(net "P1V25_SERDES_VDDPLL_PEX3_C10")
	)
	(segment
		(start 459.152752 -256.696464)
		(end 459.152752 -257.77063)
		(width 0.4572)
		(layer "F.Cu")
		(net "P1V25_SERDES_VDDPLL_PEX3_C5")
	)
	(segment
		(start 459.152752 -257.77063)
		(end 459.31328 -257.931158)
		(width 0.4572)
		(layer "F.Cu")
		(net "P1V25_SERDES_VDDPLL_PEX3_C5")
	)
	(segment
		(start 459.152752 -256.198878)
		(end 459.152752 -256.696464)
		(width 0.4572)
		(layer "F.Cu")
		(net "P1V25_SERDES_VDDPLL_PEX3_C5")
	)
	(segment
		(start 460.027782 -255.233932)
		(end 460.027782 -255.323848)
		(width 0.4572)
		(layer "F.Cu")
		(net "P1V25_SERDES_VDDPLL_PEX3_C5")
	)
	(segment
		(start 460.027782 -255.323848)
		(end 459.152752 -256.198878)
		(width 0.4572)
		(layer "F.Cu")
		(net "P1V25_SERDES_VDDPLL_PEX3_C5")
	)
	(via
		(at 459.152752 -256.696464)
		(size 0.762)
		(drill 0.381)
		(layers "F.Cu" "B.Cu")
		(net "P1V25_SERDES_VDDPLL_PEX3_C5")
	)
	(segment
		(start 454.86828 -256.726944)
		(end 454.66889 -256.926334)
		(width 0.4572)
		(layer "F.Cu")
		(net "P1V25_SERDES_VDDPLL_PEX3_C2")
	)
	(segment
		(start 455.238612 -256.356612)
		(end 454.86828 -256.726944)
		(width 0.4572)
		(layer "F.Cu")
		(net "P1V25_SERDES_VDDPLL_PEX3_C2")
	)
	(segment
		(start 455.238612 -255.3335)
		(end 455.238612 -256.356612)
		(width 0.4572)
		(layer "F.Cu")
		(net "P1V25_SERDES_VDDPLL_PEX3_C2")
	)
	(segment
		(start 454.66889 -256.926334)
		(end 454.66889 -257.931158)
		(width 0.4572)
		(layer "F.Cu")
		(net "P1V25_SERDES_VDDPLL_PEX3_C2")
	)
	(via
		(at 454.86828 -256.726944)
		(size 0.762)
		(drill 0.381)
		(layers "F.Cu" "B.Cu")
		(net "P1V25_SERDES_VDDPLL_PEX3_C2")
	)
	(via
		(at 353.383088 -322.81368)
		(size 0.6604)
		(drill 0.3302)
		(layers "F.Cu" "B.Cu")
		(net "P0V8_SERDES_VDDA_PEX3_C6")
	)
	(segment
		(start 353.383088 -322.81368)
		(end 353.383088 -321.551808)
		(width 0.4572)
		(layer "B.Cu")
		(net "P0V8_SERDES_VDDA_PEX3_C6")
	)
	(segment
		(start 353.383088 -324.046596)
		(end 353.383088 -322.81368)
		(width 0.4572)
		(layer "B.Cu")
		(net "P0V8_SERDES_VDDA_PEX3_C6")
	)
	(segment
		(start 353.224338 -324.205346)
		(end 353.383088 -324.046596)
		(width 0.4572)
		(layer "B.Cu")
		(net "P0V8_SERDES_VDDA_PEX3_C6")
	)
	(segment
		(start 446.855596 -255.3335)
		(end 446.03924 -256.149856)
		(width 0.4572)
		(layer "F.Cu")
		(net "P1V25_SERDES_VDDPLL_PEX3_C6")
	)
	(segment
		(start 446.03924 -256.149856)
		(end 446.03924 -256.7305)
		(width 0.4572)
		(layer "F.Cu")
		(net "P1V25_SERDES_VDDPLL_PEX3_C6")
	)
	(segment
		(start 446.03924 -257.87096)
		(end 446.099438 -257.931158)
		(width 0.4572)
		(layer "F.Cu")
		(net "P1V25_SERDES_VDDPLL_PEX3_C6")
	)
	(segment
		(start 446.03924 -256.7305)
		(end 446.03924 -257.87096)
		(width 0.4572)
		(layer "F.Cu")
		(net "P1V25_SERDES_VDDPLL_PEX3_C6")
	)
	(via
		(at 446.03924 -256.7305)
		(size 0.762)
		(drill 0.381)
		(layers "F.Cu" "B.Cu")
		(net "P1V25_SERDES_VDDPLL_PEX3_C6")
	)
	(segment
		(start 456.334876 -256.69113)
		(end 456.60056 -256.425446)
		(width 0.4572)
		(layer "F.Cu")
		(net "P1V25_SERDES_VDDPLL_PEX3_C3")
	)
	(segment
		(start 456.271376 -257.931158)
		(end 456.271376 -256.75463)
		(width 0.4572)
		(layer "F.Cu")
		(net "P1V25_SERDES_VDDPLL_PEX3_C3")
	)
	(segment
		(start 456.271376 -256.75463)
		(end 456.334876 -256.69113)
		(width 0.4572)
		(layer "F.Cu")
		(net "P1V25_SERDES_VDDPLL_PEX3_C3")
	)
	(segment
		(start 456.60056 -255.35382)
		(end 456.62088 -255.3335)
		(width 0.4572)
		(layer "F.Cu")
		(net "P1V25_SERDES_VDDPLL_PEX3_C3")
	)
	(segment
		(start 456.60056 -256.425446)
		(end 456.60056 -255.35382)
		(width 0.4572)
		(layer "F.Cu")
		(net "P1V25_SERDES_VDDPLL_PEX3_C3")
	)
	(via
		(at 456.334876 -256.69113)
		(size 0.762)
		(drill 0.381)
		(layers "F.Cu" "B.Cu")
		(net "P1V25_SERDES_VDDPLL_PEX3_C3")
	)
	(segment
		(start 463.502756 -255.24333)
		(end 463.489802 -255.24333)
		(width 0.4572)
		(layer "F.Cu")
		(net "P1V25_SERDES_VDDPLL_PEX3_C11")
	)
	(segment
		(start 462.009236 -256.723896)
		(end 462.009236 -257.251962)
		(width 0.4572)
		(layer "F.Cu")
		(net "P1V25_SERDES_VDDPLL_PEX3_C11")
	)
	(segment
		(start 462.009236 -257.251962)
		(end 461.33004 -257.931158)
		(width 0.4572)
		(layer "F.Cu")
		(net "P1V25_SERDES_VDDPLL_PEX3_C11")
	)
	(segment
		(start 463.489802 -255.24333)
		(end 462.009236 -256.723896)
		(width 0.4572)
		(layer "F.Cu")
		(net "P1V25_SERDES_VDDPLL_PEX3_C11")
	)
	(via
		(at 462.009236 -256.723896)
		(size 0.762)
		(drill 0.381)
		(layers "F.Cu" "B.Cu")
		(net "P1V25_SERDES_VDDPLL_PEX3_C11")
	)
	(via
		(at 357.902764 -323.316346)
		(size 0.508)
		(drill 0.254)
		(layers "F.Cu" "B.Cu")
		(net "P0V8_SERDES_VDDA_PEX3_C2")
	)
	(segment
		(start 358.440736 -322.778374)
		(end 357.902764 -323.316346)
		(width 0.4572)
		(layer "B.Cu")
		(net "P0V8_SERDES_VDDA_PEX3_C2")
	)
	(segment
		(start 358.747568 -324.602348)
		(end 358.747568 -324.402958)
		(width 0.4572)
		(layer "B.Cu")
		(net "P0V8_SERDES_VDDA_PEX3_C2")
	)
	(segment
		(start 357.902764 -323.558154)
		(end 357.902764 -323.316346)
		(width 0.4572)
		(layer "B.Cu")
		(net "P0V8_SERDES_VDDA_PEX3_C2")
	)
	(segment
		(start 358.747568 -324.402958)
		(end 357.902764 -323.558154)
		(width 0.4572)
		(layer "B.Cu")
		(net "P0V8_SERDES_VDDA_PEX3_C2")
	)
	(segment
		(start 358.440736 -322.24599)
		(end 358.440736 -322.778374)
		(width 0.4572)
		(layer "B.Cu")
		(net "P0V8_SERDES_VDDA_PEX3_C2")
	)
	(via
		(at 352.074988 -322.822316)
		(size 0.6604)
		(drill 0.3302)
		(layers "F.Cu" "B.Cu")
		(net "P0V8_SERDES_VDDA_PEX3_C0")
	)
	(segment
		(start 351.916238 -324.213982)
		(end 352.074988 -324.055232)
		(width 0.4572)
		(layer "B.Cu")
		(net "P0V8_SERDES_VDDA_PEX3_C0")
	)
	(segment
		(start 352.074988 -322.822316)
		(end 352.074988 -321.560444)
		(width 0.4572)
		(layer "B.Cu")
		(net "P0V8_SERDES_VDDA_PEX3_C0")
	)
	(segment
		(start 352.074988 -324.055232)
		(end 352.074988 -322.822316)
		(width 0.4572)
		(layer "B.Cu")
		(net "P0V8_SERDES_VDDA_PEX3_C0")
	)
	(via
		(at 350.757744 -322.808092)
		(size 0.6604)
		(drill 0.3302)
		(layers "F.Cu" "B.Cu")
		(net "P0V8_SERDES_VDDA_PEX3_C1")
	)
	(segment
		(start 350.598994 -324.199758)
		(end 350.757744 -324.041008)
		(width 0.4572)
		(layer "B.Cu")
		(net "P0V8_SERDES_VDDA_PEX3_C1")
	)
	(segment
		(start 350.757744 -324.041008)
		(end 350.757744 -322.808092)
		(width 0.4572)
		(layer "B.Cu")
		(net "P0V8_SERDES_VDDA_PEX3_C1")
	)
	(segment
		(start 350.757744 -322.808092)
		(end 350.757744 -321.54622)
		(width 0.4572)
		(layer "B.Cu")
		(net "P0V8_SERDES_VDDA_PEX3_C1")
	)
	(segment
		(start 365.864394 -322.24599)
		(end 365.864394 -322.370704)
		(width 0.4572)
		(layer "B.Cu")
		(net "P0V8_SERDES_VDDA_PEX3_C4")
	)
	(segment
		(start 365.864394 -322.370704)
		(end 364.807754 -323.427344)
		(width 0.4572)
		(layer "B.Cu")
		(net "P0V8_SERDES_VDDA_PEX3_C4")
	)
	(segment
		(start 364.855506 -322.25234)
		(end 364.506764 -322.601082)
		(width 0.4572)
		(layer "B.Cu")
		(net "P0V8_SERDES_VDDA_PEX3_C10")
	)
	(segment
		(start 364.506764 -322.601082)
		(end 364.131606 -322.601082)
		(width 0.4572)
		(layer "B.Cu")
		(net "P0V8_SERDES_VDDA_PEX3_C10")
	)
	(segment
		(start 364.131606 -322.601082)
		(end 363.305344 -323.427344)
		(width 0.4572)
		(layer "B.Cu")
		(net "P0V8_SERDES_VDDA_PEX3_C10")
	)
	(segment
		(start 448.309746 -255.869948)
		(end 448.309746 -255.3335)
		(width 0.4572)
		(layer "F.Cu")
		(net "P1V25_SERDES_VDDPLL_PEX3_C7")
	)
	(segment
		(start 447.163698 -257.015996)
		(end 447.48323 -256.696464)
		(width 0.4572)
		(layer "F.Cu")
		(net "P1V25_SERDES_VDDPLL_PEX3_C7")
	)
	(segment
		(start 447.48323 -256.696464)
		(end 448.309746 -255.869948)
		(width 0.4572)
		(layer "F.Cu")
		(net "P1V25_SERDES_VDDPLL_PEX3_C7")
	)
	(segment
		(start 447.163698 -257.931158)
		(end 447.163698 -257.015996)
		(width 0.4572)
		(layer "F.Cu")
		(net "P1V25_SERDES_VDDPLL_PEX3_C7")
	)
	(via
		(at 447.48323 -256.696464)
		(size 0.762)
		(drill 0.381)
		(layers "F.Cu" "B.Cu")
		(net "P1V25_SERDES_VDDPLL_PEX3_C7")
	)
	(via
		(at 355.962712 -322.813172)
		(size 0.6604)
		(drill 0.3302)
		(layers "F.Cu" "B.Cu")
		(net "P0V8_SERDES_VDDA_PEX3_C3")
	)
	(segment
		(start 355.803962 -324.573646)
		(end 355.803962 -323.811646)
		(width 0.4572)
		(layer "B.Cu")
		(net "P0V8_SERDES_VDDA_PEX3_C3")
	)
	(segment
		(start 355.962712 -323.652896)
		(end 355.962712 -322.813172)
		(width 0.4572)
		(layer "B.Cu")
		(net "P0V8_SERDES_VDDA_PEX3_C3")
	)
	(segment
		(start 355.962712 -322.813172)
		(end 355.962712 -321.5513)
		(width 0.4572)
		(layer "B.Cu")
		(net "P0V8_SERDES_VDDA_PEX3_C3")
	)
	(segment
		(start 355.803962 -323.811646)
		(end 355.962712 -323.652896)
		(width 0.4572)
		(layer "B.Cu")
		(net "P0V8_SERDES_VDDA_PEX3_C3")
	)
	(via
		(at 354.659184 -322.813172)
		(size 0.6604)
		(drill 0.3302)
		(layers "F.Cu" "B.Cu")
		(net "P0V8_SERDES_VDDA_PEX3_C7")
	)
	(segment
		(start 354.659184 -322.813172)
		(end 354.659184 -321.5513)
		(width 0.4572)
		(layer "B.Cu")
		(net "P0V8_SERDES_VDDA_PEX3_C7")
	)
	(segment
		(start 354.500434 -324.204838)
		(end 354.659184 -324.046088)
		(width 0.4572)
		(layer "B.Cu")
		(net "P0V8_SERDES_VDDA_PEX3_C7")
	)
	(segment
		(start 354.659184 -324.046088)
		(end 354.659184 -322.813172)
		(width 0.4572)
		(layer "B.Cu")
		(net "P0V8_SERDES_VDDA_PEX3_C7")
	)
	(segment
		(start 2.766314 -254.598424)
		(end 2.718054 -254.646684)
		(width 0.4572)
		(layer "F.Cu")
		(net "P1V25_SERDES_VDDPLL_PEX0_C7")
	)
	(segment
		(start 2.766314 -253.549658)
		(end 2.766314 -254.598424)
		(width 0.4572)
		(layer "F.Cu")
		(net "P1V25_SERDES_VDDPLL_PEX0_C7")
	)
	(segment
		(start 3.686302 -252.62967)
		(end 2.908046 -253.407926)
		(width 0.4572)
		(layer "F.Cu")
		(net "P1V25_SERDES_VDDPLL_PEX0_C7")
	)
	(segment
		(start 2.908046 -253.407926)
		(end 2.766314 -253.549658)
		(width 0.4572)
		(layer "F.Cu")
		(net "P1V25_SERDES_VDDPLL_PEX0_C7")
	)
	(segment
		(start 3.686302 -252.049026)
		(end 3.686302 -252.62967)
		(width 0.4572)
		(layer "F.Cu")
		(net "P1V25_SERDES_VDDPLL_PEX0_C7")
	)
	(via
		(at 2.908046 -253.407926)
		(size 0.762)
		(drill 0.381)
		(layers "F.Cu" "B.Cu")
		(net "P1V25_SERDES_VDDPLL_PEX0_C7")
	)
	(segment
		(start 10.244836 -253.44247)
		(end 10.615168 -253.072138)
		(width 0.4572)
		(layer "F.Cu")
		(net "P1V25_SERDES_VDDPLL_PEX0_C2")
	)
	(segment
		(start 10.045446 -254.646684)
		(end 10.045446 -253.64186)
		(width 0.4572)
		(layer "F.Cu")
		(net "P1V25_SERDES_VDDPLL_PEX0_C2")
	)
	(segment
		(start 10.045446 -253.64186)
		(end 10.244836 -253.44247)
		(width 0.4572)
		(layer "F.Cu")
		(net "P1V25_SERDES_VDDPLL_PEX0_C2")
	)
	(segment
		(start 10.615168 -253.072138)
		(end 10.615168 -252.049026)
		(width 0.4572)
		(layer "F.Cu")
		(net "P1V25_SERDES_VDDPLL_PEX0_C2")
	)
	(via
		(at 10.244836 -253.44247)
		(size 0.762)
		(drill 0.381)
		(layers "F.Cu" "B.Cu")
		(net "P1V25_SERDES_VDDPLL_PEX0_C2")
	)
	(segment
		(start 14.532356 -254.489204)
		(end 14.532356 -253.462536)
		(width 0.4572)
		(layer "F.Cu")
		(net "P1V25_SERDES_VDDPLL_PEX0_C10")
	)
	(segment
		(start 14.708886 -252.012704)
		(end 14.708886 -253.286006)
		(width 0.4572)
		(layer "F.Cu")
		(net "P1V25_SERDES_VDDPLL_PEX0_C10")
	)
	(segment
		(start 14.708886 -253.286006)
		(end 14.532356 -253.462536)
		(width 0.4572)
		(layer "F.Cu")
		(net "P1V25_SERDES_VDDPLL_PEX0_C10")
	)
	(segment
		(start 14.689836 -254.646684)
		(end 14.532356 -254.489204)
		(width 0.4572)
		(layer "F.Cu")
		(net "P1V25_SERDES_VDDPLL_PEX0_C10")
	)
	(via
		(at 14.532356 -253.462536)
		(size 0.762)
		(drill 0.381)
		(layers "F.Cu" "B.Cu")
		(net "P1V25_SERDES_VDDPLL_PEX0_C10")
	)
	(segment
		(start 3.71983 -253.916688)
		(end 3.71983 -254.646684)
		(width 0.4572)
		(layer "F.Cu")
		(net "P1V25_SERDES_VDDPLL_PEX0_C8")
	)
	(segment
		(start 5.081524 -252.049026)
		(end 5.081524 -252.554994)
		(width 0.4572)
		(layer "F.Cu")
		(net "P1V25_SERDES_VDDPLL_PEX0_C8")
	)
	(segment
		(start 5.081524 -252.554994)
		(end 4.228338 -253.40818)
		(width 0.4572)
		(layer "F.Cu")
		(net "P1V25_SERDES_VDDPLL_PEX0_C8")
	)
	(segment
		(start 4.228338 -253.40818)
		(end 3.71983 -253.916688)
		(width 0.4572)
		(layer "F.Cu")
		(net "P1V25_SERDES_VDDPLL_PEX0_C8")
	)
	(via
		(at 4.228338 -253.40818)
		(size 0.762)
		(drill 0.381)
		(layers "F.Cu" "B.Cu")
		(net "P1V25_SERDES_VDDPLL_PEX0_C8")
	)
	(segment
		(start 5.462524 -254.646684)
		(end 5.462524 -253.745492)
		(width 0.4572)
		(layer "F.Cu")
		(net "P1V25_SERDES_VDDPLL_PEX0_C9")
	)
	(segment
		(start 6.434074 -252.0823)
		(end 6.467348 -252.049026)
		(width 0.4572)
		(layer "F.Cu")
		(net "P1V25_SERDES_VDDPLL_PEX0_C9")
	)
	(segment
		(start 6.434074 -252.773942)
		(end 6.434074 -252.0823)
		(width 0.4572)
		(layer "F.Cu")
		(net "P1V25_SERDES_VDDPLL_PEX0_C9")
	)
	(segment
		(start 5.789168 -253.418848)
		(end 6.434074 -252.773942)
		(width 0.4572)
		(layer "F.Cu")
		(net "P1V25_SERDES_VDDPLL_PEX0_C9")
	)
	(segment
		(start 5.462524 -253.745492)
		(end 5.789168 -253.418848)
		(width 0.4572)
		(layer "F.Cu")
		(net "P1V25_SERDES_VDDPLL_PEX0_C9")
	)
	(via
		(at 5.789168 -253.418848)
		(size 0.762)
		(drill 0.381)
		(layers "F.Cu" "B.Cu")
		(net "P1V25_SERDES_VDDPLL_PEX0_C9")
	)
	(segment
		(start 15.63497 -248.487184)
		(end 15.801594 -248.653808)
		(width 0.4572)
		(layer "F.Cu")
		(net "P1V25_SERDES_VDDPLL_PEX0_C5")
	)
	(segment
		(start 15.801594 -254.536956)
		(end 15.801594 -253.464568)
		(width 0.4572)
		(layer "F.Cu")
		(net "P1V25_SERDES_VDDPLL_PEX0_C5")
	)
	(segment
		(start 15.691866 -254.646684)
		(end 15.801594 -254.536956)
		(width 0.4572)
		(layer "F.Cu")
		(net "P1V25_SERDES_VDDPLL_PEX0_C5")
	)
	(segment
		(start 15.801594 -248.653808)
		(end 15.801594 -253.464568)
		(width 0.4572)
		(layer "F.Cu")
		(net "P1V25_SERDES_VDDPLL_PEX0_C5")
	)
	(via
		(at 15.801594 -253.464568)
		(size 0.762)
		(drill 0.381)
		(layers "F.Cu" "B.Cu")
		(net "P1V25_SERDES_VDDPLL_PEX0_C5")
	)
	(segment
		(start 17.358868 -251.971556)
		(end 17.358868 -253.412498)
		(width 0.4572)
		(layer "F.Cu")
		(net "P1V25_SERDES_VDDPLL_PEX0_C4")
	)
	(segment
		(start 16.706596 -254.646684)
		(end 17.385792 -253.967488)
		(width 0.4572)
		(layer "F.Cu")
		(net "P1V25_SERDES_VDDPLL_PEX0_C4")
	)
	(segment
		(start 17.385792 -253.967488)
		(end 17.385792 -253.439422)
		(width 0.4572)
		(layer "F.Cu")
		(net "P1V25_SERDES_VDDPLL_PEX0_C4")
	)
	(segment
		(start 17.358868 -253.412498)
		(end 17.385792 -253.439422)
		(width 0.4572)
		(layer "F.Cu")
		(net "P1V25_SERDES_VDDPLL_PEX0_C4")
	)
	(via
		(at 17.385792 -253.439422)
		(size 0.762)
		(drill 0.381)
		(layers "F.Cu" "B.Cu")
		(net "P1V25_SERDES_VDDPLL_PEX0_C4")
	)
	(segment
		(start 7.43585 -253.425198)
		(end 7.833614 -253.027434)
		(width 0.4572)
		(layer "F.Cu")
		(net "P1V25_SERDES_VDDPLL_PEX0_C0")
	)
	(segment
		(start 7.833614 -253.027434)
		(end 7.833614 -252.064774)
		(width 0.4572)
		(layer "F.Cu")
		(net "P1V25_SERDES_VDDPLL_PEX0_C0")
	)
	(segment
		(start 6.999224 -253.861824)
		(end 7.43585 -253.425198)
		(width 0.4572)
		(layer "F.Cu")
		(net "P1V25_SERDES_VDDPLL_PEX0_C0")
	)
	(segment
		(start 7.833614 -252.064774)
		(end 7.849362 -252.049026)
		(width 0.4572)
		(layer "F.Cu")
		(net "P1V25_SERDES_VDDPLL_PEX0_C0")
	)
	(segment
		(start 6.999224 -254.646684)
		(end 6.999224 -253.861824)
		(width 0.4572)
		(layer "F.Cu")
		(net "P1V25_SERDES_VDDPLL_PEX0_C0")
	)
	(via
		(at 7.43585 -253.425198)
		(size 0.762)
		(drill 0.381)
		(layers "F.Cu" "B.Cu")
		(net "P1V25_SERDES_VDDPLL_PEX0_C0")
	)
	(segment
		(start 1.62179 -254.122682)
		(end 1.62179 -253.415038)
		(width 0.4572)
		(layer "F.Cu")
		(net "P1V25_SERDES_VDDPLL_PEX0_C6")
	)
	(segment
		(start 1.729994 -254.230886)
		(end 1.62179 -254.122682)
		(width 0.4572)
		(layer "F.Cu")
		(net "P1V25_SERDES_VDDPLL_PEX0_C6")
	)
	(segment
		(start 1.729994 -254.646684)
		(end 1.729994 -254.230886)
		(width 0.4572)
		(layer "F.Cu")
		(net "P1V25_SERDES_VDDPLL_PEX0_C6")
	)
	(segment
		(start 1.62179 -252.659388)
		(end 2.232152 -252.049026)
		(width 0.4572)
		(layer "F.Cu")
		(net "P1V25_SERDES_VDDPLL_PEX0_C6")
	)
	(segment
		(start 1.62179 -253.415038)
		(end 1.62179 -252.659388)
		(width 0.4572)
		(layer "F.Cu")
		(net "P1V25_SERDES_VDDPLL_PEX0_C6")
	)
	(via
		(at 1.62179 -253.415038)
		(size 0.762)
		(drill 0.381)
		(layers "F.Cu" "B.Cu")
		(net "P1V25_SERDES_VDDPLL_PEX0_C6")
	)
	(segment
		(start 11.997436 -252.049026)
		(end 11.977116 -252.069346)
		(width 0.4572)
		(layer "F.Cu")
		(net "P1V25_SERDES_VDDPLL_PEX0_C3")
	)
	(segment
		(start 11.977116 -253.140972)
		(end 11.711432 -253.406656)
		(width 0.4572)
		(layer "F.Cu")
		(net "P1V25_SERDES_VDDPLL_PEX0_C3")
	)
	(segment
		(start 11.647932 -253.470156)
		(end 11.647932 -254.646684)
		(width 0.4572)
		(layer "F.Cu")
		(net "P1V25_SERDES_VDDPLL_PEX0_C3")
	)
	(segment
		(start 11.711432 -253.406656)
		(end 11.647932 -253.470156)
		(width 0.4572)
		(layer "F.Cu")
		(net "P1V25_SERDES_VDDPLL_PEX0_C3")
	)
	(segment
		(start 11.977116 -252.069346)
		(end 11.977116 -253.140972)
		(width 0.4572)
		(layer "F.Cu")
		(net "P1V25_SERDES_VDDPLL_PEX0_C3")
	)
	(via
		(at 11.711432 -253.406656)
		(size 0.762)
		(drill 0.381)
		(layers "F.Cu" "B.Cu")
		(net "P1V25_SERDES_VDDPLL_PEX0_C3")
	)
	(segment
		(start 13.194284 -248.82856)
		(end 13.194284 -253.410212)
		(width 0.4572)
		(layer "F.Cu")
		(net "P1V25_SERDES_VDDPLL_PEX0_C11")
	)
	(segment
		(start 13.194284 -253.410212)
		(end 13.194284 -254.646684)
		(width 0.4572)
		(layer "F.Cu")
		(net "P1V25_SERDES_VDDPLL_PEX0_C11")
	)
	(segment
		(start 12.852908 -248.487184)
		(end 13.194284 -248.82856)
		(width 0.4572)
		(layer "F.Cu")
		(net "P1V25_SERDES_VDDPLL_PEX0_C11")
	)
	(via
		(at 13.194284 -253.410212)
		(size 0.762)
		(drill 0.381)
		(layers "F.Cu" "B.Cu")
		(net "P1V25_SERDES_VDDPLL_PEX0_C11")
	)
	(via
		(at 117.265958 -323.058028)
		(size 0.6604)
		(drill 0.3302)
		(layers "F.Cu" "B.Cu")
		(net "P0V8_SERDES_VDDA_PEX0_C0")
	)
	(segment
		(start 117.265958 -324.441058)
		(end 117.265958 -323.058028)
		(width 0.4572)
		(layer "B.Cu")
		(net "P0V8_SERDES_VDDA_PEX0_C0")
	)
	(segment
		(start 117.257322 -324.449694)
		(end 117.265958 -324.441058)
		(width 0.4572)
		(layer "B.Cu")
		(net "P0V8_SERDES_VDDA_PEX0_C0")
	)
	(segment
		(start 117.265958 -323.058028)
		(end 117.265958 -321.796156)
		(width 0.4572)
		(layer "B.Cu")
		(net "P0V8_SERDES_VDDA_PEX0_C0")
	)
	(segment
		(start 9.219438 -252.050042)
		(end 9.219438 -253.089156)
		(width 0.4572)
		(layer "F.Cu")
		(net "P1V25_SERDES_VDDPLL_PEX0_C1")
	)
	(segment
		(start 9.219438 -253.089156)
		(end 8.886698 -253.421896)
		(width 0.4572)
		(layer "F.Cu")
		(net "P1V25_SERDES_VDDPLL_PEX0_C1")
	)
	(segment
		(start 9.218422 -252.049026)
		(end 9.219438 -252.050042)
		(width 0.4572)
		(layer "F.Cu")
		(net "P1V25_SERDES_VDDPLL_PEX0_C1")
	)
	(segment
		(start 8.886698 -253.421896)
		(end 8.549386 -253.759208)
		(width 0.4572)
		(layer "F.Cu")
		(net "P1V25_SERDES_VDDPLL_PEX0_C1")
	)
	(segment
		(start 8.549386 -253.759208)
		(end 8.549386 -254.646684)
		(width 0.4572)
		(layer "F.Cu")
		(net "P1V25_SERDES_VDDPLL_PEX0_C1")
	)
	(via
		(at 8.886698 -253.421896)
		(size 0.762)
		(drill 0.381)
		(layers "F.Cu" "B.Cu")
		(net "P1V25_SERDES_VDDPLL_PEX0_C1")
	)
	(segment
		(start 117.175026 -309.349902)
		(end 117.175026 -307.867304)
		(width 0.4572)
		(layer "F.Cu")
		(net "P0V8_SERDES_VDDA_PEX0_C5")
	)
	(segment
		(start 115.83035 -309.349902)
		(end 115.83035 -307.882036)
		(width 0.4572)
		(layer "F.Cu")
		(net "P0V8_SERDES_VDDA_PEX0_C4")
	)
	(segment
		(start 115.83035 -307.882036)
		(end 115.815872 -307.867558)
		(width 0.4572)
		(layer "F.Cu")
		(net "P0V8_SERDES_VDDA_PEX0_C4")
	)
	(via
		(at 110.792514 -323.025262)
		(size 0.6604)
		(drill 0.3302)
		(layers "F.Cu" "B.Cu")
		(net "P0V8_SERDES_VDDA_PEX0_C3")
	)
	(segment
		(start 110.792514 -321.797426)
		(end 110.792514 -323.025262)
		(width 0.4572)
		(layer "B.Cu")
		(net "P0V8_SERDES_VDDA_PEX0_C3")
	)
	(segment
		(start 110.82655 -321.76339)
		(end 110.792514 -321.797426)
		(width 0.4572)
		(layer "B.Cu")
		(net "P0V8_SERDES_VDDA_PEX0_C3")
	)
	(segment
		(start 110.792514 -323.025262)
		(end 110.792514 -324.391528)
		(width 0.4572)
		(layer "B.Cu")
		(net "P0V8_SERDES_VDDA_PEX0_C3")
	)
	(segment
		(start 110.792514 -324.391528)
		(end 110.817914 -324.416928)
		(width 0.4572)
		(layer "B.Cu")
		(net "P0V8_SERDES_VDDA_PEX0_C3")
	)
	(via
		(at 112.06988 -323.031104)
		(size 0.6604)
		(drill 0.3302)
		(layers "F.Cu" "B.Cu")
		(net "P0V8_SERDES_VDDA_PEX0_C2")
	)
	(segment
		(start 112.06988 -321.799458)
		(end 112.06988 -323.031104)
		(width 0.4572)
		(layer "B.Cu")
		(net "P0V8_SERDES_VDDA_PEX0_C2")
	)
	(segment
		(start 112.06988 -323.031104)
		(end 112.06988 -324.372224)
		(width 0.4572)
		(layer "B.Cu")
		(net "P0V8_SERDES_VDDA_PEX0_C2")
	)
	(segment
		(start 112.06988 -324.372224)
		(end 112.025176 -324.416928)
		(width 0.4572)
		(layer "B.Cu")
		(net "P0V8_SERDES_VDDA_PEX0_C2")
	)
	(segment
		(start 112.033812 -321.76339)
		(end 112.06988 -321.799458)
		(width 0.4572)
		(layer "B.Cu")
		(net "P0V8_SERDES_VDDA_PEX0_C2")
	)
	(via
		(at 115.943888 -323.05244)
		(size 0.6604)
		(drill 0.3302)
		(layers "F.Cu" "B.Cu")
		(net "P0V8_SERDES_VDDA_PEX0_C1")
	)
	(segment
		(start 115.943888 -324.43547)
		(end 115.943888 -323.05244)
		(width 0.4572)
		(layer "B.Cu")
		(net "P0V8_SERDES_VDDA_PEX0_C1")
	)
	(segment
		(start 115.943888 -323.05244)
		(end 116.090954 -322.905374)
		(width 0.4572)
		(layer "B.Cu")
		(net "P0V8_SERDES_VDDA_PEX0_C1")
	)
	(segment
		(start 115.935252 -324.444106)
		(end 115.943888 -324.43547)
		(width 0.4572)
		(layer "B.Cu")
		(net "P0V8_SERDES_VDDA_PEX0_C1")
	)
	(segment
		(start 116.090954 -322.905374)
		(end 116.090954 -321.937634)
		(width 0.4572)
		(layer "B.Cu")
		(net "P0V8_SERDES_VDDA_PEX0_C1")
	)
	(segment
		(start 116.090954 -321.937634)
		(end 115.943888 -321.790568)
		(width 0.4572)
		(layer "B.Cu")
		(net "P0V8_SERDES_VDDA_PEX0_C1")
	)
	(segment
		(start 410.63037 -194.220846)
		(end 410.612082 -194.202558)
		(width 0.13208)
		(layer "F.Cu")
		(net "FPGA_PEX0_MODE_SEL1_ISO")
	)
	(segment
		(start 410.63037 -196.80682)
		(end 410.63037 -195.4022)
		(width 0.13208)
		(layer "F.Cu")
		(net "FPGA_PEX0_MODE_SEL1_ISO")
	)
	(segment
		(start 410.63037 -195.4022)
		(end 410.63037 -194.220846)
		(width 0.13208)
		(layer "F.Cu")
		(net "FPGA_PEX0_MODE_SEL1_ISO")
	)
	(via
		(at 410.63037 -195.4022)
		(size 0.762)
		(drill 0.381)
		(layers "F.Cu" "B.Cu")
		(net "FPGA_PEX0_MODE_SEL1_ISO")
	)
	(segment
		(start 415.0868 -197.585076)
		(end 415.0868 -198.374)
		(width 0.13208)
		(layer "F.Cu")
		(net "FPGA_PEX0_MODE_SEL1_D_N")
	)
	(segment
		(start 412.425896 -197.5612)
		(end 411.8864 -197.5612)
		(width 0.13208)
		(layer "F.Cu")
		(net "FPGA_PEX0_MODE_SEL1_D_N")
	)
	(segment
		(start 412.430214 -197.556882)
		(end 412.425896 -197.5612)
		(width 0.13208)
		(layer "F.Cu")
		(net "FPGA_PEX0_MODE_SEL1_D_N")
	)
	(segment
		(start 411.7594 -197.6882)
		(end 411.7594 -198.1708)
		(width 0.13208)
		(layer "F.Cu")
		(net "FPGA_PEX0_MODE_SEL1_D_N")
	)
	(segment
		(start 411.8864 -197.5612)
		(end 411.7594 -197.6882)
		(width 0.13208)
		(layer "F.Cu")
		(net "FPGA_PEX0_MODE_SEL1_D_N")
	)
	(segment
		(start 413.893 -198.7042)
		(end 413.6644 -198.7042)
		(width 0.13208)
		(layer "F.Cu")
		(net "FPGA_PEX0_MODE_SEL1_D_N")
	)
	(segment
		(start 411.895544 -198.306944)
		(end 412.430214 -198.306944)
		(width 0.13208)
		(layer "F.Cu")
		(net "FPGA_PEX0_MODE_SEL1_D_N")
	)
	(segment
		(start 414.7566 -198.7042)
		(end 413.893 -198.7042)
		(width 0.13208)
		(layer "F.Cu")
		(net "FPGA_PEX0_MODE_SEL1_D_N")
	)
	(segment
		(start 413.6644 -198.7042)
		(end 413.267144 -198.306944)
		(width 0.13208)
		(layer "F.Cu")
		(net "FPGA_PEX0_MODE_SEL1_D_N")
	)
	(segment
		(start 413.267144 -198.306944)
		(end 412.430214 -198.306944)
		(width 0.13208)
		(layer "F.Cu")
		(net "FPGA_PEX0_MODE_SEL1_D_N")
	)
	(segment
		(start 411.7594 -198.1708)
		(end 411.895544 -198.306944)
		(width 0.13208)
		(layer "F.Cu")
		(net "FPGA_PEX0_MODE_SEL1_D_N")
	)
	(segment
		(start 415.0868 -198.374)
		(end 414.7566 -198.7042)
		(width 0.13208)
		(layer "F.Cu")
		(net "FPGA_PEX0_MODE_SEL1_D_N")
	)
	(segment
		(start 415.057082 -197.555358)
		(end 415.0868 -197.585076)
		(width 0.13208)
		(layer "F.Cu")
		(net "FPGA_PEX0_MODE_SEL1_D_N")
	)
	(via
		(at 413.893 -198.7042)
		(size 0.762)
		(drill 0.381)
		(layers "F.Cu" "B.Cu")
		(net "FPGA_PEX0_MODE_SEL1_D_N")
	)
	(segment
		(start 356.997508 -208.233518)
		(end 356.972108 -208.258918)
		(width 0.13208)
		(layer "F.Cu")
		(net "FPGA_PEX3_MODE_SEL1")
	)
	(segment
		(start 346.093796 -215.987122)
		(end 346.493592 -215.587326)
		(width 0.13208)
		(layer "F.Cu")
		(net "FPGA_PEX3_MODE_SEL1")
	)
	(segment
		(start 357.588058 -208.233518)
		(end 356.997508 -208.233518)
		(width 0.13208)
		(layer "F.Cu")
		(net "FPGA_PEX3_MODE_SEL1")
	)
	(via
		(at 356.972108 -208.258918)
		(size 0.508)
		(drill 0.254)
		(layers "F.Cu" "B.Cu")
		(net "FPGA_PEX3_MODE_SEL1")
	)
	(via
		(at 346.493592 -215.587326)
		(size 0.4572)
		(drill 0.254)
		(layers "F.Cu" "B.Cu")
		(net "FPGA_PEX3_MODE_SEL1")
	)
	(segment
		(start 350.091248 -213.006432)
		(end 350.90608 -212.1916)
		(width 0.15494)
		(layer "In5.Cu")
		(net "FPGA_PEX3_MODE_SEL1")
	)
	(segment
		(start 351.3582 -212.1916)
		(end 354.66274 -208.88706)
		(width 0.15494)
		(layer "In5.Cu")
		(net "FPGA_PEX3_MODE_SEL1")
	)
	(segment
		(start 356.343966 -208.88706)
		(end 356.972108 -208.258918)
		(width 0.15494)
		(layer "In5.Cu")
		(net "FPGA_PEX3_MODE_SEL1")
	)
	(segment
		(start 349.86722 -215.19642)
		(end 350.091248 -214.972392)
		(width 0.0889)
		(layer "In5.Cu")
		(net "FPGA_PEX3_MODE_SEL1")
	)
	(segment
		(start 346.493592 -215.587326)
		(end 346.884498 -215.19642)
		(width 0.0889)
		(layer "In5.Cu")
		(net "FPGA_PEX3_MODE_SEL1")
	)
	(segment
		(start 346.884498 -215.19642)
		(end 349.86722 -215.19642)
		(width 0.0889)
		(layer "In5.Cu")
		(net "FPGA_PEX3_MODE_SEL1")
	)
	(segment
		(start 350.90608 -212.1916)
		(end 351.3582 -212.1916)
		(width 0.15494)
		(layer "In5.Cu")
		(net "FPGA_PEX3_MODE_SEL1")
	)
	(segment
		(start 354.66274 -208.88706)
		(end 356.343966 -208.88706)
		(width 0.15494)
		(layer "In5.Cu")
		(net "FPGA_PEX3_MODE_SEL1")
	)
	(segment
		(start 350.091248 -214.972392)
		(end 350.091248 -213.006432)
		(width 0.0889)
		(layer "In5.Cu")
		(net "FPGA_PEX3_MODE_SEL1")
	)
	(segment
		(start 365.380778 -218.902026)
		(end 362.886752 -218.902026)
		(width 0.13208)
		(layer "F.Cu")
		(net "FPGA_PEX3_MODE_SEL1_R")
	)
	(segment
		(start 359.818178 -208.56956)
		(end 359.482136 -208.233518)
		(width 0.13208)
		(layer "F.Cu")
		(net "FPGA_PEX3_MODE_SEL1_R")
	)
	(segment
		(start 410.52877 -207.945482)
		(end 409.934918 -207.945482)
		(width 0.13208)
		(layer "F.Cu")
		(net "FPGA_PEX3_MODE_SEL1_R")
	)
	(segment
		(start 359.482136 -208.233518)
		(end 358.388158 -208.233518)
		(width 0.13208)
		(layer "F.Cu")
		(net "FPGA_PEX3_MODE_SEL1_R")
	)
	(segment
		(start 362.886752 -218.902026)
		(end 359.818178 -215.833452)
		(width 0.13208)
		(layer "F.Cu")
		(net "FPGA_PEX3_MODE_SEL1_R")
	)
	(segment
		(start 409.934918 -207.945482)
		(end 407.126948 -210.753452)
		(width 0.13208)
		(layer "F.Cu")
		(net "FPGA_PEX3_MODE_SEL1_R")
	)
	(segment
		(start 400.464274 -217.416126)
		(end 366.866678 -217.416126)
		(width 0.13208)
		(layer "F.Cu")
		(net "FPGA_PEX3_MODE_SEL1_R")
	)
	(segment
		(start 407.126948 -210.753452)
		(end 400.464274 -217.416126)
		(width 0.13208)
		(layer "F.Cu")
		(net "FPGA_PEX3_MODE_SEL1_R")
	)
	(segment
		(start 366.866678 -217.416126)
		(end 365.380778 -218.902026)
		(width 0.13208)
		(layer "F.Cu")
		(net "FPGA_PEX3_MODE_SEL1_R")
	)
	(segment
		(start 359.818178 -215.833452)
		(end 359.818178 -208.56956)
		(width 0.13208)
		(layer "F.Cu")
		(net "FPGA_PEX3_MODE_SEL1_R")
	)
	(via
		(at 407.126948 -210.753452)
		(size 0.762)
		(drill 0.381)
		(layers "F.Cu" "B.Cu")
		(net "FPGA_PEX3_MODE_SEL1_R")
	)
	(segment
		(start 356.72649 -207.310482)
		(end 357.510842 -207.310482)
		(width 0.13208)
		(layer "F.Cu")
		(net "FPGA_PEX3_MODE_SEL2")
	)
	(segment
		(start 357.510842 -207.310482)
		(end 357.637842 -207.183482)
		(width 0.13208)
		(layer "F.Cu")
		(net "FPGA_PEX3_MODE_SEL2")
	)
	(segment
		(start 355.9302 -208.40319)
		(end 355.91242 -208.38541)
		(width 0.13208)
		(layer "F.Cu")
		(net "FPGA_PEX3_MODE_SEL2")
	)
	(segment
		(start 355.91242 -208.38541)
		(end 355.91242 -208.124552)
		(width 0.13208)
		(layer "F.Cu")
		(net "FPGA_PEX3_MODE_SEL2")
	)
	(segment
		(start 355.91242 -208.124552)
		(end 356.72649 -207.310482)
		(width 0.13208)
		(layer "F.Cu")
		(net "FPGA_PEX3_MODE_SEL2")
	)
	(segment
		(start 350.093788 -211.98713)
		(end 350.493584 -211.587334)
		(width 0.13208)
		(layer "F.Cu")
		(net "FPGA_PEX3_MODE_SEL2")
	)
	(via
		(at 355.9302 -208.40319)
		(size 0.508)
		(drill 0.254)
		(layers "F.Cu" "B.Cu")
		(net "FPGA_PEX3_MODE_SEL2")
	)
	(via
		(at 350.493584 -211.587334)
		(size 0.4572)
		(drill 0.254)
		(layers "F.Cu" "B.Cu")
		(net "FPGA_PEX3_MODE_SEL2")
	)
	(segment
		(start 351.455736 -211.587334)
		(end 350.493584 -211.587334)
		(width 0.15494)
		(layer "In5.Cu")
		(net "FPGA_PEX3_MODE_SEL2")
	)
	(segment
		(start 354.63988 -208.40319)
		(end 351.455736 -211.587334)
		(width 0.15494)
		(layer "In5.Cu")
		(net "FPGA_PEX3_MODE_SEL2")
	)
	(segment
		(start 355.9302 -208.40319)
		(end 354.63988 -208.40319)
		(width 0.15494)
		(layer "In5.Cu")
		(net "FPGA_PEX3_MODE_SEL2")
	)
	(segment
		(start 359.323386 -207.183482)
		(end 360.111548 -207.971644)
		(width 0.13208)
		(layer "F.Cu")
		(net "FPGA_PEX3_MODE_SEL2_R")
	)
	(segment
		(start 363.008418 -218.608656)
		(end 365.259112 -218.608656)
		(width 0.13208)
		(layer "F.Cu")
		(net "FPGA_PEX3_MODE_SEL2_R")
	)
	(segment
		(start 360.111548 -215.711786)
		(end 363.008418 -218.608656)
		(width 0.13208)
		(layer "F.Cu")
		(net "FPGA_PEX3_MODE_SEL2_R")
	)
	(segment
		(start 407.908252 -208.263744)
		(end 408.104086 -208.06791)
		(width 0.13208)
		(layer "F.Cu")
		(net "FPGA_PEX3_MODE_SEL2_R")
	)
	(segment
		(start 358.437942 -207.183482)
		(end 359.323386 -207.183482)
		(width 0.13208)
		(layer "F.Cu")
		(net "FPGA_PEX3_MODE_SEL2_R")
	)
	(segment
		(start 366.736122 -217.131646)
		(end 399.445988 -217.131646)
		(width 0.13208)
		(layer "F.Cu")
		(net "FPGA_PEX3_MODE_SEL2_R")
	)
	(segment
		(start 412.220918 -183.078882)
		(end 411.607 -183.6928)
		(width 0.13208)
		(layer "F.Cu")
		(net "FPGA_PEX3_MODE_SEL2_R")
	)
	(segment
		(start 407.908252 -208.669382)
		(end 407.908252 -208.263744)
		(width 0.13208)
		(layer "F.Cu")
		(net "FPGA_PEX3_MODE_SEL2_R")
	)
	(segment
		(start 413.29737 -183.078882)
		(end 412.220918 -183.078882)
		(width 0.13208)
		(layer "F.Cu")
		(net "FPGA_PEX3_MODE_SEL2_R")
	)
	(segment
		(start 399.445988 -217.131646)
		(end 407.908252 -208.669382)
		(width 0.13208)
		(layer "F.Cu")
		(net "FPGA_PEX3_MODE_SEL2_R")
	)
	(segment
		(start 360.111548 -207.971644)
		(end 360.111548 -215.711786)
		(width 0.13208)
		(layer "F.Cu")
		(net "FPGA_PEX3_MODE_SEL2_R")
	)
	(segment
		(start 365.259112 -218.608656)
		(end 366.736122 -217.131646)
		(width 0.13208)
		(layer "F.Cu")
		(net "FPGA_PEX3_MODE_SEL2_R")
	)
	(via
		(at 411.607 -183.6928)
		(size 0.508)
		(drill 0.254)
		(layers "F.Cu" "B.Cu")
		(net "FPGA_PEX3_MODE_SEL2_R")
	)
	(via
		(at 408.104086 -208.06791)
		(size 0.508)
		(drill 0.254)
		(layers "F.Cu" "B.Cu")
		(net "FPGA_PEX3_MODE_SEL2_R")
	)
	(segment
		(start 412.873952 -190.551562)
		(end 412.873952 -184.959752)
		(width 0.13208)
		(layer "B.Cu")
		(net "FPGA_PEX3_MODE_SEL2_R")
	)
	(segment
		(start 410.876242 -196.454776)
		(end 411.715966 -195.615052)
		(width 0.13208)
		(layer "B.Cu")
		(net "FPGA_PEX3_MODE_SEL2_R")
	)
	(segment
		(start 412.873952 -184.959752)
		(end 411.607 -183.6928)
		(width 0.13208)
		(layer "B.Cu")
		(net "FPGA_PEX3_MODE_SEL2_R")
	)
	(segment
		(start 411.715966 -195.615052)
		(end 411.715966 -191.709548)
		(width 0.13208)
		(layer "B.Cu")
		(net "FPGA_PEX3_MODE_SEL2_R")
	)
	(segment
		(start 408.104086 -208.06791)
		(end 409.489148 -208.06791)
		(width 0.13208)
		(layer "B.Cu")
		(net "FPGA_PEX3_MODE_SEL2_R")
	)
	(segment
		(start 411.715966 -191.709548)
		(end 412.873952 -190.551562)
		(width 0.13208)
		(layer "B.Cu")
		(net "FPGA_PEX3_MODE_SEL2_R")
	)
	(segment
		(start 410.876242 -206.680816)
		(end 410.876242 -196.454776)
		(width 0.13208)
		(layer "B.Cu")
		(net "FPGA_PEX3_MODE_SEL2_R")
	)
	(segment
		(start 409.489148 -208.06791)
		(end 410.876242 -206.680816)
		(width 0.13208)
		(layer "B.Cu")
		(net "FPGA_PEX3_MODE_SEL2_R")
	)
	(segment
		(start 361.312714 -215.213946)
		(end 361.312714 -206.25816)
		(width 0.13208)
		(layer "F.Cu")
		(net "FPGA_PEX2_MODE_SEL1_R")
	)
	(segment
		(start 411.834838 -192.202562)
		(end 412.627318 -191.410082)
		(width 0.13208)
		(layer "F.Cu")
		(net "FPGA_PEX2_MODE_SEL1_R")
	)
	(segment
		(start 366.175036 -215.993726)
		(end 364.761272 -217.40749)
		(width 0.13208)
		(layer "F.Cu")
		(net "FPGA_PEX2_MODE_SEL1_R")
	)
	(segment
		(start 407.225754 -202.441048)
		(end 407.468324 -202.198478)
		(width 0.13208)
		(layer "F.Cu")
		(net "FPGA_PEX2_MODE_SEL1_R")
	)
	(segment
		(start 350.311974 -203.34478)
		(end 349.762318 -203.894436)
		(width 0.13208)
		(layer "F.Cu")
		(net "FPGA_PEX2_MODE_SEL1_R")
	)
	(segment
		(start 407.225754 -202.441048)
		(end 406.139396 -203.527406)
		(width 0.13208)
		(layer "F.Cu")
		(net "FPGA_PEX2_MODE_SEL1_R")
	)
	(segment
		(start 407.468324 -193.985388)
		(end 409.25115 -192.202562)
		(width 0.13208)
		(layer "F.Cu")
		(net "FPGA_PEX2_MODE_SEL1_R")
	)
	(segment
		(start 358.399334 -203.34478)
		(end 350.311974 -203.34478)
		(width 0.13208)
		(layer "F.Cu")
		(net "FPGA_PEX2_MODE_SEL1_R")
	)
	(segment
		(start 349.762318 -203.894436)
		(end 349.762318 -204.831442)
		(width 0.13208)
		(layer "F.Cu")
		(net "FPGA_PEX2_MODE_SEL1_R")
	)
	(segment
		(start 407.468324 -202.198478)
		(end 407.468324 -193.985388)
		(width 0.13208)
		(layer "F.Cu")
		(net "FPGA_PEX2_MODE_SEL1_R")
	)
	(segment
		(start 364.761272 -217.40749)
		(end 363.506258 -217.40749)
		(width 0.13208)
		(layer "F.Cu")
		(net "FPGA_PEX2_MODE_SEL1_R")
	)
	(segment
		(start 406.139396 -208.739232)
		(end 398.884902 -215.993726)
		(width 0.13208)
		(layer "F.Cu")
		(net "FPGA_PEX2_MODE_SEL1_R")
	)
	(segment
		(start 398.884902 -215.993726)
		(end 366.175036 -215.993726)
		(width 0.13208)
		(layer "F.Cu")
		(net "FPGA_PEX2_MODE_SEL1_R")
	)
	(segment
		(start 363.506258 -217.40749)
		(end 361.312714 -215.213946)
		(width 0.13208)
		(layer "F.Cu")
		(net "FPGA_PEX2_MODE_SEL1_R")
	)
	(segment
		(start 406.139396 -203.527406)
		(end 406.139396 -208.739232)
		(width 0.13208)
		(layer "F.Cu")
		(net "FPGA_PEX2_MODE_SEL1_R")
	)
	(segment
		(start 361.312714 -206.25816)
		(end 358.399334 -203.34478)
		(width 0.13208)
		(layer "F.Cu")
		(net "FPGA_PEX2_MODE_SEL1_R")
	)
	(segment
		(start 412.627318 -191.410082)
		(end 413.37357 -191.410082)
		(width 0.13208)
		(layer "F.Cu")
		(net "FPGA_PEX2_MODE_SEL1_R")
	)
	(segment
		(start 409.25115 -192.202562)
		(end 411.834838 -192.202562)
		(width 0.13208)
		(layer "F.Cu")
		(net "FPGA_PEX2_MODE_SEL1_R")
	)
	(via
		(at 407.225754 -202.441048)
		(size 0.762)
		(drill 0.381)
		(layers "F.Cu" "B.Cu")
		(net "FPGA_PEX2_MODE_SEL1_R")
	)
	(segment
		(start 349.4024 -206.934308)
		(end 349.4024 -210.457542)
		(width 0.13208)
		(layer "F.Cu")
		(net "FPGA_PEX2_MODE_SEL1")
	)
	(segment
		(start 349.762318 -205.631542)
		(end 349.762318 -205.7146)
		(width 0.13208)
		(layer "F.Cu")
		(net "FPGA_PEX2_MODE_SEL1")
	)
	(segment
		(start 349.299022 -206.177896)
		(end 349.4024 -206.281274)
		(width 0.13208)
		(layer "F.Cu")
		(net "FPGA_PEX2_MODE_SEL1")
	)
	(segment
		(start 349.4024 -210.457542)
		(end 349.293942 -210.566)
		(width 0.13208)
		(layer "F.Cu")
		(net "FPGA_PEX2_MODE_SEL1")
	)
	(segment
		(start 349.4024 -206.281274)
		(end 349.4024 -206.934308)
		(width 0.13208)
		(layer "F.Cu")
		(net "FPGA_PEX2_MODE_SEL1")
	)
	(segment
		(start 349.293942 -210.566)
		(end 349.293942 -211.18703)
		(width 0.13208)
		(layer "F.Cu")
		(net "FPGA_PEX2_MODE_SEL1")
	)
	(segment
		(start 349.762318 -205.7146)
		(end 349.299022 -206.177896)
		(width 0.13208)
		(layer "F.Cu")
		(net "FPGA_PEX2_MODE_SEL1")
	)
	(via
		(at 349.4024 -206.934308)
		(size 0.762)
		(drill 0.381)
		(layers "F.Cu" "B.Cu")
		(net "FPGA_PEX2_MODE_SEL1")
	)
	(via
		(at 349.299022 -206.177896)
		(size 0.508)
		(drill 0.254)
		(layers "F.Cu" "B.Cu")
		(net "FPGA_PEX2_MODE_SEL1")
	)
	(segment
		(start 357.246682 -205.560168)
		(end 357.246682 -206.176118)
		(width 0.13208)
		(layer "F.Cu")
		(net "FPGA_PEX2_MODE_SEL2")
	)
	(segment
		(start 346.893896 -213.587076)
		(end 347.293692 -213.18728)
		(width 0.13208)
		(layer "F.Cu")
		(net "FPGA_PEX2_MODE_SEL2")
	)
	(via
		(at 347.293692 -213.18728)
		(size 0.4572)
		(drill 0.254)
		(layers "F.Cu" "B.Cu")
		(net "FPGA_PEX2_MODE_SEL2")
	)
	(via
		(at 357.246682 -206.176118)
		(size 0.508)
		(drill 0.254)
		(layers "F.Cu" "B.Cu")
		(net "FPGA_PEX2_MODE_SEL2")
	)
	(segment
		(start 349.291148 -212.206332)
		(end 349.6818 -211.81568)
		(width 0.15494)
		(layer "In5.Cu")
		(net "FPGA_PEX2_MODE_SEL2")
	)
	(segment
		(start 357.034084 -206.176118)
		(end 357.246682 -206.176118)
		(width 0.15494)
		(layer "In5.Cu")
		(net "FPGA_PEX2_MODE_SEL2")
	)
	(segment
		(start 355.96068 -207.249522)
		(end 357.034084 -206.176118)
		(width 0.15494)
		(layer "In5.Cu")
		(net "FPGA_PEX2_MODE_SEL2")
	)
	(segment
		(start 352.038158 -209.638646)
		(end 354.427282 -207.249522)
		(width 0.15494)
		(layer "In5.Cu")
		(net "FPGA_PEX2_MODE_SEL2")
	)
	(segment
		(start 347.293692 -213.18728)
		(end 347.695012 -212.78596)
		(width 0.0889)
		(layer "In5.Cu")
		(net "FPGA_PEX2_MODE_SEL2")
	)
	(segment
		(start 354.427282 -207.249522)
		(end 355.96068 -207.249522)
		(width 0.15494)
		(layer "In5.Cu")
		(net "FPGA_PEX2_MODE_SEL2")
	)
	(segment
		(start 349.291148 -212.582252)
		(end 349.291148 -212.206332)
		(width 0.0889)
		(layer "In5.Cu")
		(net "FPGA_PEX2_MODE_SEL2")
	)
	(segment
		(start 349.6818 -211.81568)
		(end 349.6818 -211.2518)
		(width 0.15494)
		(layer "In5.Cu")
		(net "FPGA_PEX2_MODE_SEL2")
	)
	(segment
		(start 349.6818 -211.2518)
		(end 351.294954 -209.638646)
		(width 0.15494)
		(layer "In5.Cu")
		(net "FPGA_PEX2_MODE_SEL2")
	)
	(segment
		(start 347.695012 -212.78596)
		(end 349.08744 -212.78596)
		(width 0.0889)
		(layer "In5.Cu")
		(net "FPGA_PEX2_MODE_SEL2")
	)
	(segment
		(start 349.08744 -212.78596)
		(end 349.291148 -212.582252)
		(width 0.0889)
		(layer "In5.Cu")
		(net "FPGA_PEX2_MODE_SEL2")
	)
	(segment
		(start 351.294954 -209.638646)
		(end 352.038158 -209.638646)
		(width 0.15494)
		(layer "In5.Cu")
		(net "FPGA_PEX2_MODE_SEL2")
	)
	(segment
		(start 366.613186 -216.847166)
		(end 365.139732 -218.32062)
		(width 0.13208)
		(layer "F.Cu")
		(net "FPGA_PEX2_MODE_SEL2_R")
	)
	(segment
		(start 363.127798 -218.32062)
		(end 360.399584 -215.592406)
		(width 0.13208)
		(layer "F.Cu")
		(net "FPGA_PEX2_MODE_SEL2_R")
	)
	(segment
		(start 409.960318 -204.364082)
		(end 409.414218 -204.910182)
		(width 0.13208)
		(layer "F.Cu")
		(net "FPGA_PEX2_MODE_SEL2_R")
	)
	(segment
		(start 399.323052 -216.847166)
		(end 366.613186 -216.847166)
		(width 0.13208)
		(layer "F.Cu")
		(net "FPGA_PEX2_MODE_SEL2_R")
	)
	(segment
		(start 410.50337 -204.364082)
		(end 409.960318 -204.364082)
		(width 0.13208)
		(layer "F.Cu")
		(net "FPGA_PEX2_MODE_SEL2_R")
	)
	(segment
		(start 360.399584 -215.592406)
		(end 360.399584 -206.877666)
		(width 0.13208)
		(layer "F.Cu")
		(net "FPGA_PEX2_MODE_SEL2_R")
	)
	(segment
		(start 360.399584 -206.877666)
		(end 358.281986 -204.760068)
		(width 0.13208)
		(layer "F.Cu")
		(net "FPGA_PEX2_MODE_SEL2_R")
	)
	(segment
		(start 409.414218 -204.910182)
		(end 408.119326 -204.910182)
		(width 0.13208)
		(layer "F.Cu")
		(net "FPGA_PEX2_MODE_SEL2_R")
	)
	(segment
		(start 408.119326 -204.910182)
		(end 407.407364 -205.622144)
		(width 0.13208)
		(layer "F.Cu")
		(net "FPGA_PEX2_MODE_SEL2_R")
	)
	(segment
		(start 358.281986 -204.760068)
		(end 357.246682 -204.760068)
		(width 0.13208)
		(layer "F.Cu")
		(net "FPGA_PEX2_MODE_SEL2_R")
	)
	(segment
		(start 407.407364 -205.622144)
		(end 407.407364 -207.466946)
		(width 0.13208)
		(layer "F.Cu")
		(net "FPGA_PEX2_MODE_SEL2_R")
	)
	(segment
		(start 407.407364 -208.762854)
		(end 399.323052 -216.847166)
		(width 0.13208)
		(layer "F.Cu")
		(net "FPGA_PEX2_MODE_SEL2_R")
	)
	(segment
		(start 407.407364 -207.466946)
		(end 407.407364 -208.762854)
		(width 0.13208)
		(layer "F.Cu")
		(net "FPGA_PEX2_MODE_SEL2_R")
	)
	(segment
		(start 365.139732 -218.32062)
		(end 363.127798 -218.32062)
		(width 0.13208)
		(layer "F.Cu")
		(net "FPGA_PEX2_MODE_SEL2_R")
	)
	(via
		(at 407.407364 -207.466946)
		(size 0.762)
		(drill 0.381)
		(layers "F.Cu" "B.Cu")
		(net "FPGA_PEX2_MODE_SEL2_R")
	)
	(segment
		(start 406.759156 -208.996026)
		(end 399.192496 -216.562686)
		(width 0.13208)
		(layer "F.Cu")
		(net "FPGA_PEX1_MODE_SEL1_R")
	)
	(segment
		(start 366.48263 -216.562686)
		(end 365.018066 -218.02725)
		(width 0.13208)
		(layer "F.Cu")
		(net "FPGA_PEX1_MODE_SEL1_R")
	)
	(segment
		(start 365.018066 -218.02725)
		(end 363.249464 -218.02725)
		(width 0.13208)
		(layer "F.Cu")
		(net "FPGA_PEX1_MODE_SEL1_R")
	)
	(segment
		(start 407.97226 -204.158596)
		(end 406.759156 -205.3717)
		(width 0.13208)
		(layer "F.Cu")
		(net "FPGA_PEX1_MODE_SEL1_R")
	)
	(segment
		(start 399.192496 -216.562686)
		(end 366.48263 -216.562686)
		(width 0.13208)
		(layer "F.Cu")
		(net "FPGA_PEX1_MODE_SEL1_R")
	)
	(segment
		(start 412.398718 -178.532282)
		(end 411.6324 -179.2986)
		(width 0.13208)
		(layer "F.Cu")
		(net "FPGA_PEX1_MODE_SEL1_R")
	)
	(segment
		(start 360.692954 -206.54645)
		(end 358.290622 -204.144118)
		(width 0.13208)
		(layer "F.Cu")
		(net "FPGA_PEX1_MODE_SEL1_R")
	)
	(segment
		(start 358.290622 -204.144118)
		(end 356.855268 -204.144118)
		(width 0.13208)
		(layer "F.Cu")
		(net "FPGA_PEX1_MODE_SEL1_R")
	)
	(segment
		(start 356.855268 -204.144118)
		(end 356.239318 -204.760068)
		(width 0.13208)
		(layer "F.Cu")
		(net "FPGA_PEX1_MODE_SEL1_R")
	)
	(segment
		(start 360.692954 -215.47074)
		(end 360.692954 -206.54645)
		(width 0.13208)
		(layer "F.Cu")
		(net "FPGA_PEX1_MODE_SEL1_R")
	)
	(segment
		(start 363.249464 -218.02725)
		(end 360.692954 -215.47074)
		(width 0.13208)
		(layer "F.Cu")
		(net "FPGA_PEX1_MODE_SEL1_R")
	)
	(segment
		(start 413.29737 -178.532282)
		(end 412.398718 -178.532282)
		(width 0.13208)
		(layer "F.Cu")
		(net "FPGA_PEX1_MODE_SEL1_R")
	)
	(segment
		(start 406.759156 -205.3717)
		(end 406.759156 -208.996026)
		(width 0.13208)
		(layer "F.Cu")
		(net "FPGA_PEX1_MODE_SEL1_R")
	)
	(via
		(at 407.97226 -204.158596)
		(size 0.508)
		(drill 0.254)
		(layers "F.Cu" "B.Cu")
		(net "FPGA_PEX1_MODE_SEL1_R")
	)
	(via
		(at 411.6324 -179.2986)
		(size 0.508)
		(drill 0.254)
		(layers "F.Cu" "B.Cu")
		(net "FPGA_PEX1_MODE_SEL1_R")
	)
	(segment
		(start 411.221428 -195.546726)
		(end 411.221428 -191.580262)
		(width 0.13208)
		(layer "B.Cu")
		(net "FPGA_PEX1_MODE_SEL1_R")
	)
	(segment
		(start 412.468568 -185.560716)
		(end 411.088078 -184.180226)
		(width 0.13208)
		(layer "B.Cu")
		(net "FPGA_PEX1_MODE_SEL1_R")
	)
	(segment
		(start 410.363162 -203.312014)
		(end 410.363162 -196.404992)
		(width 0.13208)
		(layer "B.Cu")
		(net "FPGA_PEX1_MODE_SEL1_R")
	)
	(segment
		(start 410.363162 -196.404992)
		(end 411.221428 -195.546726)
		(width 0.13208)
		(layer "B.Cu")
		(net "FPGA_PEX1_MODE_SEL1_R")
	)
	(segment
		(start 407.97226 -204.158596)
		(end 409.51658 -204.158596)
		(width 0.13208)
		(layer "B.Cu")
		(net "FPGA_PEX1_MODE_SEL1_R")
	)
	(segment
		(start 409.51658 -204.158596)
		(end 410.363162 -203.312014)
		(width 0.13208)
		(layer "B.Cu")
		(net "FPGA_PEX1_MODE_SEL1_R")
	)
	(segment
		(start 411.088078 -184.180226)
		(end 411.088078 -179.842922)
		(width 0.13208)
		(layer "B.Cu")
		(net "FPGA_PEX1_MODE_SEL1_R")
	)
	(segment
		(start 411.221428 -191.580262)
		(end 412.468568 -190.333122)
		(width 0.13208)
		(layer "B.Cu")
		(net "FPGA_PEX1_MODE_SEL1_R")
	)
	(segment
		(start 411.088078 -179.842922)
		(end 411.6324 -179.2986)
		(width 0.13208)
		(layer "B.Cu")
		(net "FPGA_PEX1_MODE_SEL1_R")
	)
	(segment
		(start 412.468568 -190.333122)
		(end 412.468568 -185.560716)
		(width 0.13208)
		(layer "B.Cu")
		(net "FPGA_PEX1_MODE_SEL1_R")
	)
	(segment
		(start 346.893896 -212.786976)
		(end 347.293692 -212.38718)
		(width 0.13208)
		(layer "F.Cu")
		(net "FPGA_PEX1_MODE_SEL1")
	)
	(segment
		(start 356.239318 -205.560168)
		(end 356.213918 -205.585568)
		(width 0.13208)
		(layer "F.Cu")
		(net "FPGA_PEX1_MODE_SEL1")
	)
	(segment
		(start 356.213918 -205.585568)
		(end 356.213918 -206.169768)
		(width 0.13208)
		(layer "F.Cu")
		(net "FPGA_PEX1_MODE_SEL1")
	)
	(via
		(at 347.293692 -212.38718)
		(size 0.4572)
		(drill 0.254)
		(layers "F.Cu" "B.Cu")
		(net "FPGA_PEX1_MODE_SEL1")
	)
	(via
		(at 356.213918 -206.169768)
		(size 0.508)
		(drill 0.254)
		(layers "F.Cu" "B.Cu")
		(net "FPGA_PEX1_MODE_SEL1")
	)
	(segment
		(start 347.696028 -211.984844)
		(end 347.293692 -212.38718)
		(width 0.0889)
		(layer "In5.Cu")
		(net "FPGA_PEX1_MODE_SEL1")
	)
	(segment
		(start 354.278692 -206.891382)
		(end 352.015044 -209.15503)
		(width 0.15494)
		(layer "In5.Cu")
		(net "FPGA_PEX1_MODE_SEL1")
	)
	(segment
		(start 349.075756 -211.984844)
		(end 347.696028 -211.984844)
		(width 0.0889)
		(layer "In5.Cu")
		(net "FPGA_PEX1_MODE_SEL1")
	)
	(segment
		(start 351.11817 -209.15503)
		(end 349.3262 -210.947)
		(width 0.15494)
		(layer "In5.Cu")
		(net "FPGA_PEX1_MODE_SEL1")
	)
	(segment
		(start 355.197156 -206.891382)
		(end 354.278692 -206.891382)
		(width 0.15494)
		(layer "In5.Cu")
		(net "FPGA_PEX1_MODE_SEL1")
	)
	(segment
		(start 349.3262 -210.947)
		(end 349.3262 -211.7344)
		(width 0.15494)
		(layer "In5.Cu")
		(net "FPGA_PEX1_MODE_SEL1")
	)
	(segment
		(start 349.3262 -211.7344)
		(end 349.075756 -211.984844)
		(width 0.15494)
		(layer "In5.Cu")
		(net "FPGA_PEX1_MODE_SEL1")
	)
	(segment
		(start 356.213918 -206.169768)
		(end 356.207568 -206.176118)
		(width 0.15494)
		(layer "In5.Cu")
		(net "FPGA_PEX1_MODE_SEL1")
	)
	(segment
		(start 355.91242 -206.176118)
		(end 355.197156 -206.891382)
		(width 0.15494)
		(layer "In5.Cu")
		(net "FPGA_PEX1_MODE_SEL1")
	)
	(segment
		(start 352.015044 -209.15503)
		(end 351.11817 -209.15503)
		(width 0.15494)
		(layer "In5.Cu")
		(net "FPGA_PEX1_MODE_SEL1")
	)
	(segment
		(start 356.207568 -206.176118)
		(end 355.91242 -206.176118)
		(width 0.15494)
		(layer "In5.Cu")
		(net "FPGA_PEX1_MODE_SEL1")
	)
	(segment
		(start 355.223318 -206.172816)
		(end 355.22662 -206.176118)
		(width 0.13208)
		(layer "F.Cu")
		(net "FPGA_PEX1_MODE_SEL2")
	)
	(segment
		(start 355.223318 -205.560168)
		(end 355.223318 -206.172816)
		(width 0.13208)
		(layer "F.Cu")
		(net "FPGA_PEX1_MODE_SEL2")
	)
	(segment
		(start 346.093796 -211.98713)
		(end 346.493592 -211.587334)
		(width 0.13208)
		(layer "F.Cu")
		(net "FPGA_PEX1_MODE_SEL2")
	)
	(via
		(at 346.493592 -211.587334)
		(size 0.4572)
		(drill 0.254)
		(layers "F.Cu" "B.Cu")
		(net "FPGA_PEX1_MODE_SEL2")
	)
	(via
		(at 355.22662 -206.176118)
		(size 0.508)
		(drill 0.254)
		(layers "F.Cu" "B.Cu")
		(net "FPGA_PEX1_MODE_SEL2")
	)
	(segment
		(start 350.915986 -208.671414)
		(end 351.833942 -208.671414)
		(width 0.15494)
		(layer "In5.Cu")
		(net "FPGA_PEX1_MODE_SEL2")
	)
	(segment
		(start 348.402656 -211.184744)
		(end 350.915986 -208.671414)
		(width 0.15494)
		(layer "In5.Cu")
		(net "FPGA_PEX1_MODE_SEL2")
	)
	(segment
		(start 351.833942 -208.671414)
		(end 354.329238 -206.176118)
		(width 0.15494)
		(layer "In5.Cu")
		(net "FPGA_PEX1_MODE_SEL2")
	)
	(segment
		(start 346.896182 -211.184744)
		(end 348.402656 -211.184744)
		(width 0.0889)
		(layer "In5.Cu")
		(net "FPGA_PEX1_MODE_SEL2")
	)
	(segment
		(start 354.329238 -206.176118)
		(end 355.22662 -206.176118)
		(width 0.15494)
		(layer "In5.Cu")
		(net "FPGA_PEX1_MODE_SEL2")
	)
	(segment
		(start 346.493592 -211.587334)
		(end 346.896182 -211.184744)
		(width 0.0889)
		(layer "In5.Cu")
		(net "FPGA_PEX1_MODE_SEL2")
	)
	(segment
		(start 361.024678 -215.333326)
		(end 361.024678 -206.421228)
		(width 0.13208)
		(layer "F.Cu")
		(net "FPGA_PEX1_MODE_SEL2_R")
	)
	(segment
		(start 361.024678 -206.421228)
		(end 358.41686 -203.81341)
		(width 0.13208)
		(layer "F.Cu")
		(net "FPGA_PEX1_MODE_SEL2_R")
	)
	(segment
		(start 406.427432 -204.556106)
		(end 406.427432 -208.858612)
		(width 0.13208)
		(layer "F.Cu")
		(net "FPGA_PEX1_MODE_SEL2_R")
	)
	(segment
		(start 355.640894 -203.81341)
		(end 355.223318 -204.230986)
		(width 0.13208)
		(layer "F.Cu")
		(net "FPGA_PEX1_MODE_SEL2_R")
	)
	(segment
		(start 358.41686 -203.81341)
		(end 355.640894 -203.81341)
		(width 0.13208)
		(layer "F.Cu")
		(net "FPGA_PEX1_MODE_SEL2_R")
	)
	(segment
		(start 408.8638 -201.1426)
		(end 409.223718 -200.782682)
		(width 0.13208)
		(layer "F.Cu")
		(net "FPGA_PEX1_MODE_SEL2_R")
	)
	(segment
		(start 407.05913 -203.924408)
		(end 406.427432 -204.556106)
		(width 0.13208)
		(layer "F.Cu")
		(net "FPGA_PEX1_MODE_SEL2_R")
	)
	(segment
		(start 407.05913 -203.924408)
		(end 407.941272 -203.042266)
		(width 0.13208)
		(layer "F.Cu")
		(net "FPGA_PEX1_MODE_SEL2_R")
	)
	(segment
		(start 364.880652 -217.695526)
		(end 363.386878 -217.695526)
		(width 0.13208)
		(layer "F.Cu")
		(net "FPGA_PEX1_MODE_SEL2_R")
	)
	(segment
		(start 409.223718 -200.782682)
		(end 410.57957 -200.782682)
		(width 0.13208)
		(layer "F.Cu")
		(net "FPGA_PEX1_MODE_SEL2_R")
	)
	(segment
		(start 406.427432 -208.858612)
		(end 399.007838 -216.278206)
		(width 0.13208)
		(layer "F.Cu")
		(net "FPGA_PEX1_MODE_SEL2_R")
	)
	(segment
		(start 407.941272 -201.37501)
		(end 408.173682 -201.1426)
		(width 0.13208)
		(layer "F.Cu")
		(net "FPGA_PEX1_MODE_SEL2_R")
	)
	(segment
		(start 355.223318 -204.230986)
		(end 355.223318 -204.760068)
		(width 0.13208)
		(layer "F.Cu")
		(net "FPGA_PEX1_MODE_SEL2_R")
	)
	(segment
		(start 363.386878 -217.695526)
		(end 361.024678 -215.333326)
		(width 0.13208)
		(layer "F.Cu")
		(net "FPGA_PEX1_MODE_SEL2_R")
	)
	(segment
		(start 399.007838 -216.278206)
		(end 366.297972 -216.278206)
		(width 0.13208)
		(layer "F.Cu")
		(net "FPGA_PEX1_MODE_SEL2_R")
	)
	(segment
		(start 407.941272 -203.042266)
		(end 407.941272 -201.37501)
		(width 0.13208)
		(layer "F.Cu")
		(net "FPGA_PEX1_MODE_SEL2_R")
	)
	(segment
		(start 366.297972 -216.278206)
		(end 364.880652 -217.695526)
		(width 0.13208)
		(layer "F.Cu")
		(net "FPGA_PEX1_MODE_SEL2_R")
	)
	(segment
		(start 408.173682 -201.1426)
		(end 408.8638 -201.1426)
		(width 0.13208)
		(layer "F.Cu")
		(net "FPGA_PEX1_MODE_SEL2_R")
	)
	(via
		(at 407.05913 -203.924408)
		(size 0.762)
		(drill 0.381)
		(layers "F.Cu" "B.Cu")
		(net "FPGA_PEX1_MODE_SEL2_R")
	)
	(segment
		(start 410.63037 -197.556882)
		(end 409.240482 -197.556882)
		(width 0.13208)
		(layer "F.Cu")
		(net "FPGA_PEX0_MODE_SEL1_R")
	)
	(segment
		(start 343.615518 -200.76795)
		(end 343.615518 -200.152)
		(width 0.13208)
		(layer "F.Cu")
		(net "FPGA_PEX0_MODE_SEL1_R")
	)
	(segment
		(start 409.240482 -197.556882)
		(end 408.813 -197.1294)
		(width 0.13208)
		(layer "F.Cu")
		(net "FPGA_PEX0_MODE_SEL1_R")
	)
	(via
		(at 343.615518 -200.152)
		(size 0.508)
		(drill 0.254)
		(layers "F.Cu" "B.Cu")
		(net "FPGA_PEX0_MODE_SEL1_R")
	)
	(via
		(at 373.583454 -187.77712)
		(size 0.508)
		(drill 0.254)
		(layers "F.Cu" "B.Cu")
		(net "FPGA_PEX0_MODE_SEL1_R")
	)
	(via
		(at 408.813 -197.1294)
		(size 0.508)
		(drill 0.254)
		(layers "F.Cu" "B.Cu")
		(net "FPGA_PEX0_MODE_SEL1_R")
	)
	(segment
		(start 378.97943 -193.591688)
		(end 382.413764 -190.157354)
		(width 0.13208)
		(layer "B.Cu")
		(net "FPGA_PEX0_MODE_SEL1_R")
	)
	(segment
		(start 408.610816 -196.927216)
		(end 408.813 -197.1294)
		(width 0.13208)
		(layer "B.Cu")
		(net "FPGA_PEX0_MODE_SEL1_R")
	)
	(segment
		(start 373.973852 -193.591688)
		(end 378.97943 -193.591688)
		(width 0.13208)
		(layer "B.Cu")
		(net "FPGA_PEX0_MODE_SEL1_R")
	)
	(segment
		(start 373.583454 -187.77712)
		(end 373.065802 -187.77712)
		(width 0.13208)
		(layer "B.Cu")
		(net "FPGA_PEX0_MODE_SEL1_R")
	)
	(segment
		(start 382.413764 -190.157354)
		(end 406.52827 -190.157354)
		(width 0.13208)
		(layer "B.Cu")
		(net "FPGA_PEX0_MODE_SEL1_R")
	)
	(segment
		(start 408.610816 -192.2399)
		(end 408.610816 -196.927216)
		(width 0.13208)
		(layer "B.Cu")
		(net "FPGA_PEX0_MODE_SEL1_R")
	)
	(segment
		(start 372.622064 -192.2399)
		(end 373.973852 -193.591688)
		(width 0.13208)
		(layer "B.Cu")
		(net "FPGA_PEX0_MODE_SEL1_R")
	)
	(segment
		(start 406.52827 -190.157354)
		(end 408.610816 -192.2399)
		(width 0.13208)
		(layer "B.Cu")
		(net "FPGA_PEX0_MODE_SEL1_R")
	)
	(segment
		(start 373.065802 -187.77712)
		(end 372.622064 -188.220858)
		(width 0.13208)
		(layer "B.Cu")
		(net "FPGA_PEX0_MODE_SEL1_R")
	)
	(segment
		(start 372.622064 -188.220858)
		(end 372.622064 -192.2399)
		(width 0.13208)
		(layer "B.Cu")
		(net "FPGA_PEX0_MODE_SEL1_R")
	)
	(segment
		(start 343.933272 -200.469754)
		(end 343.615518 -200.152)
		(width 0.15494)
		(layer "In13.Cu")
		(net "FPGA_PEX0_MODE_SEL1_R")
	)
	(segment
		(start 366.027208 -196.076316)
		(end 362.711492 -199.392032)
		(width 0.15494)
		(layer "In13.Cu")
		(net "FPGA_PEX0_MODE_SEL1_R")
	)
	(segment
		(start 371.823488 -187.77712)
		(end 366.027208 -193.5734)
		(width 0.15494)
		(layer "In13.Cu")
		(net "FPGA_PEX0_MODE_SEL1_R")
	)
	(segment
		(start 359.002838 -199.392032)
		(end 357.925116 -200.469754)
		(width 0.15494)
		(layer "In13.Cu")
		(net "FPGA_PEX0_MODE_SEL1_R")
	)
	(segment
		(start 373.583454 -187.77712)
		(end 371.823488 -187.77712)
		(width 0.15494)
		(layer "In13.Cu")
		(net "FPGA_PEX0_MODE_SEL1_R")
	)
	(segment
		(start 362.711492 -199.392032)
		(end 359.002838 -199.392032)
		(width 0.15494)
		(layer "In13.Cu")
		(net "FPGA_PEX0_MODE_SEL1_R")
	)
	(segment
		(start 357.925116 -200.469754)
		(end 343.933272 -200.469754)
		(width 0.15494)
		(layer "In13.Cu")
		(net "FPGA_PEX0_MODE_SEL1_R")
	)
	(segment
		(start 366.027208 -193.5734)
		(end 366.027208 -196.076316)
		(width 0.15494)
		(layer "In13.Cu")
		(net "FPGA_PEX0_MODE_SEL1_R")
	)
	(segment
		(start 345.29395 -211.18703)
		(end 345.29395 -210.566)
		(width 0.13208)
		(layer "F.Cu")
		(net "FPGA_PEX0_MODE_SEL1")
	)
	(segment
		(start 343.615518 -201.56805)
		(end 343.615518 -202.184)
		(width 0.13208)
		(layer "F.Cu")
		(net "FPGA_PEX0_MODE_SEL1")
	)
	(via
		(at 343.615518 -202.184)
		(size 0.508)
		(drill 0.254)
		(layers "F.Cu" "B.Cu")
		(net "FPGA_PEX0_MODE_SEL1")
	)
	(via
		(at 345.29395 -210.566)
		(size 0.4572)
		(drill 0.254)
		(layers "F.Cu" "B.Cu")
		(net "FPGA_PEX0_MODE_SEL1")
	)
	(segment
		(start 344.698828 -205.633828)
		(end 344.17 -205.105)
		(width 0.15494)
		(layer "In5.Cu")
		(net "FPGA_PEX0_MODE_SEL1")
	)
	(segment
		(start 343.615518 -202.213718)
		(end 343.615518 -202.184)
		(width 0.15494)
		(layer "In5.Cu")
		(net "FPGA_PEX0_MODE_SEL1")
	)
	(segment
		(start 344.17 -202.7682)
		(end 343.615518 -202.213718)
		(width 0.15494)
		(layer "In5.Cu")
		(net "FPGA_PEX0_MODE_SEL1")
	)
	(segment
		(start 345.29395 -210.566)
		(end 344.698828 -209.970878)
		(width 0.15494)
		(layer "In5.Cu")
		(net "FPGA_PEX0_MODE_SEL1")
	)
	(segment
		(start 344.698828 -209.970878)
		(end 344.698828 -205.633828)
		(width 0.15494)
		(layer "In5.Cu")
		(net "FPGA_PEX0_MODE_SEL1")
	)
	(segment
		(start 344.17 -205.105)
		(end 344.17 -202.7682)
		(width 0.15494)
		(layer "In5.Cu")
		(net "FPGA_PEX0_MODE_SEL1")
	)
	(segment
		(start 408.8892 -207.5942)
		(end 409.448 -207.5942)
		(width 0.13208)
		(layer "F.Cu")
		(net "FPGA_PEX3_MODE_SEL1_ISO")
	)
	(segment
		(start 408.503882 -206.318358)
		(end 408.5082 -206.322676)
		(width 0.13208)
		(layer "F.Cu")
		(net "FPGA_PEX3_MODE_SEL1_ISO")
	)
	(segment
		(start 409.448 -207.5942)
		(end 409.84678 -207.19542)
		(width 0.13208)
		(layer "F.Cu")
		(net "FPGA_PEX3_MODE_SEL1_ISO")
	)
	(segment
		(start 408.5082 -207.2132)
		(end 408.8892 -207.5942)
		(width 0.13208)
		(layer "F.Cu")
		(net "FPGA_PEX3_MODE_SEL1_ISO")
	)
	(segment
		(start 409.84678 -207.19542)
		(end 410.52877 -207.19542)
		(width 0.13208)
		(layer "F.Cu")
		(net "FPGA_PEX3_MODE_SEL1_ISO")
	)
	(segment
		(start 408.5082 -206.322676)
		(end 408.5082 -207.2132)
		(width 0.13208)
		(layer "F.Cu")
		(net "FPGA_PEX3_MODE_SEL1_ISO")
	)
	(via
		(at 408.8892 -207.5942)
		(size 0.762)
		(drill 0.381)
		(layers "F.Cu" "B.Cu")
		(net "FPGA_PEX3_MODE_SEL1_ISO")
	)
	(segment
		(start 412.328614 -208.695544)
		(end 412.809944 -208.695544)
		(width 0.13208)
		(layer "F.Cu")
		(net "FPGA_PEX3_MODE_SEL1_D_N")
	)
	(segment
		(start 411.6324 -208.0768)
		(end 411.763718 -207.945482)
		(width 0.13208)
		(layer "F.Cu")
		(net "FPGA_PEX3_MODE_SEL1_D_N")
	)
	(segment
		(start 412.328614 -208.695544)
		(end 412.312358 -208.7118)
		(width 0.13208)
		(layer "F.Cu")
		(net "FPGA_PEX3_MODE_SEL1_D_N")
	)
	(segment
		(start 412.809944 -208.695544)
		(end 412.877 -208.7626)
		(width 0.13208)
		(layer "F.Cu")
		(net "FPGA_PEX3_MODE_SEL1_D_N")
	)
	(segment
		(start 412.3944 -210.0326)
		(end 412.085282 -210.341718)
		(width 0.13208)
		(layer "F.Cu")
		(net "FPGA_PEX3_MODE_SEL1_D_N")
	)
	(segment
		(start 412.877 -210.0326)
		(end 412.3944 -210.0326)
		(width 0.13208)
		(layer "F.Cu")
		(net "FPGA_PEX3_MODE_SEL1_D_N")
	)
	(segment
		(start 411.734 -208.7118)
		(end 411.6324 -208.6102)
		(width 0.13208)
		(layer "F.Cu")
		(net "FPGA_PEX3_MODE_SEL1_D_N")
	)
	(segment
		(start 412.312358 -208.7118)
		(end 411.734 -208.7118)
		(width 0.13208)
		(layer "F.Cu")
		(net "FPGA_PEX3_MODE_SEL1_D_N")
	)
	(segment
		(start 411.763718 -207.945482)
		(end 412.328614 -207.945482)
		(width 0.13208)
		(layer "F.Cu")
		(net "FPGA_PEX3_MODE_SEL1_D_N")
	)
	(segment
		(start 412.877 -208.7626)
		(end 412.877 -210.0326)
		(width 0.13208)
		(layer "F.Cu")
		(net "FPGA_PEX3_MODE_SEL1_D_N")
	)
	(segment
		(start 412.085282 -210.341718)
		(end 411.372558 -210.341718)
		(width 0.13208)
		(layer "F.Cu")
		(net "FPGA_PEX3_MODE_SEL1_D_N")
	)
	(segment
		(start 411.6324 -208.6102)
		(end 411.6324 -208.0768)
		(width 0.13208)
		(layer "F.Cu")
		(net "FPGA_PEX3_MODE_SEL1_D_N")
	)
	(via
		(at 412.877 -210.0326)
		(size 0.762)
		(drill 0.381)
		(layers "F.Cu" "B.Cu")
		(net "FPGA_PEX3_MODE_SEL1_D_N")
	)
	(segment
		(start 410.00426 -182.32882)
		(end 410.000958 -182.325518)
		(width 0.13208)
		(layer "F.Cu")
		(net "FPGA_PEX3_MODE_SEL2_ISO")
	)
	(segment
		(start 411.607 -182.32882)
		(end 410.00426 -182.32882)
		(width 0.13208)
		(layer "F.Cu")
		(net "FPGA_PEX3_MODE_SEL2_ISO")
	)
	(segment
		(start 413.29737 -182.32882)
		(end 411.607 -182.32882)
		(width 0.13208)
		(layer "F.Cu")
		(net "FPGA_PEX3_MODE_SEL2_ISO")
	)
	(via
		(at 411.607 -182.32882)
		(size 0.762)
		(drill 0.381)
		(layers "F.Cu" "B.Cu")
		(net "FPGA_PEX3_MODE_SEL2_ISO")
	)
	(segment
		(start 412.246318 -186.787282)
		(end 411.5054 -187.5282)
		(width 0.13208)
		(layer "F.Cu")
		(net "FPGA_PEX0_MODE_SEL2_R")
	)
	(segment
		(start 342.624918 -200.76795)
		(end 342.624918 -200.152)
		(width 0.13208)
		(layer "F.Cu")
		(net "FPGA_PEX0_MODE_SEL2_R")
	)
	(segment
		(start 413.37357 -186.787282)
		(end 412.246318 -186.787282)
		(width 0.13208)
		(layer "F.Cu")
		(net "FPGA_PEX0_MODE_SEL2_R")
	)
	(via
		(at 342.624918 -200.152)
		(size 0.508)
		(drill 0.254)
		(layers "F.Cu" "B.Cu")
		(net "FPGA_PEX0_MODE_SEL2_R")
	)
	(via
		(at 411.5054 -187.5282)
		(size 0.508)
		(drill 0.254)
		(layers "F.Cu" "B.Cu")
		(net "FPGA_PEX0_MODE_SEL2_R")
	)
	(via
		(at 373.635524 -189.183772)
		(size 0.508)
		(drill 0.254)
		(layers "F.Cu" "B.Cu")
		(net "FPGA_PEX0_MODE_SEL2_R")
	)
	(segment
		(start 407.404824 -189.353698)
		(end 408.976068 -187.782454)
		(width 0.13208)
		(layer "B.Cu")
		(net "FPGA_PEX0_MODE_SEL2_R")
	)
	(segment
		(start 411.251146 -187.782454)
		(end 411.5054 -187.5282)
		(width 0.13208)
		(layer "B.Cu")
		(net "FPGA_PEX0_MODE_SEL2_R")
	)
	(segment
		(start 408.976068 -187.782454)
		(end 411.251146 -187.782454)
		(width 0.13208)
		(layer "B.Cu")
		(net "FPGA_PEX0_MODE_SEL2_R")
	)
	(segment
		(start 375.045986 -189.183772)
		(end 375.215912 -189.353698)
		(width 0.13208)
		(layer "B.Cu")
		(net "FPGA_PEX0_MODE_SEL2_R")
	)
	(segment
		(start 375.215912 -189.353698)
		(end 407.404824 -189.353698)
		(width 0.13208)
		(layer "B.Cu")
		(net "FPGA_PEX0_MODE_SEL2_R")
	)
	(segment
		(start 373.635524 -189.183772)
		(end 375.045986 -189.183772)
		(width 0.13208)
		(layer "B.Cu")
		(net "FPGA_PEX0_MODE_SEL2_R")
	)
	(segment
		(start 362.904532 -199.857868)
		(end 359.195878 -199.857868)
		(width 0.15494)
		(layer "In13.Cu")
		(net "FPGA_PEX0_MODE_SEL2_R")
	)
	(segment
		(start 359.195878 -199.857868)
		(end 358.118156 -200.93559)
		(width 0.15494)
		(layer "In13.Cu")
		(net "FPGA_PEX0_MODE_SEL2_R")
	)
	(segment
		(start 366.493044 -193.76644)
		(end 366.493044 -196.269356)
		(width 0.15494)
		(layer "In13.Cu")
		(net "FPGA_PEX0_MODE_SEL2_R")
	)
	(segment
		(start 371.075712 -189.183772)
		(end 366.493044 -193.76644)
		(width 0.15494)
		(layer "In13.Cu")
		(net "FPGA_PEX0_MODE_SEL2_R")
	)
	(segment
		(start 373.635524 -189.183772)
		(end 371.075712 -189.183772)
		(width 0.15494)
		(layer "In13.Cu")
		(net "FPGA_PEX0_MODE_SEL2_R")
	)
	(segment
		(start 366.493044 -196.269356)
		(end 362.904532 -199.857868)
		(width 0.15494)
		(layer "In13.Cu")
		(net "FPGA_PEX0_MODE_SEL2_R")
	)
	(segment
		(start 358.118156 -200.93559)
		(end 343.408508 -200.93559)
		(width 0.15494)
		(layer "In13.Cu")
		(net "FPGA_PEX0_MODE_SEL2_R")
	)
	(segment
		(start 343.408508 -200.93559)
		(end 342.624918 -200.152)
		(width 0.15494)
		(layer "In13.Cu")
		(net "FPGA_PEX0_MODE_SEL2_R")
	)
	(segment
		(start 414.3502 -183.261)
		(end 414.532318 -183.078882)
		(width 0.13208)
		(layer "F.Cu")
		(net "FPGA_PEX3_MODE_SEL2_D_N")
	)
	(segment
		(start 415.097214 -183.828944)
		(end 415.68751 -183.828944)
		(width 0.13208)
		(layer "F.Cu")
		(net "FPGA_PEX3_MODE_SEL2_D_N")
	)
	(segment
		(start 415.097214 -183.828944)
		(end 415.080958 -183.8452)
		(width 0.13208)
		(layer "F.Cu")
		(net "FPGA_PEX3_MODE_SEL2_D_N")
	)
	(segment
		(start 415.68751 -183.828944)
		(end 415.823654 -183.6928)
		(width 0.13208)
		(layer "F.Cu")
		(net "FPGA_PEX3_MODE_SEL2_D_N")
	)
	(segment
		(start 415.823654 -183.6928)
		(end 416.5854 -183.6928)
		(width 0.13208)
		(layer "F.Cu")
		(net "FPGA_PEX3_MODE_SEL2_D_N")
	)
	(segment
		(start 416.6108 -183.6928)
		(end 416.960558 -184.042558)
		(width 0.13208)
		(layer "F.Cu")
		(net "FPGA_PEX3_MODE_SEL2_D_N")
	)
	(segment
		(start 414.3502 -183.6928)
		(end 414.3502 -183.261)
		(width 0.13208)
		(layer "F.Cu")
		(net "FPGA_PEX3_MODE_SEL2_D_N")
	)
	(segment
		(start 416.5854 -183.6928)
		(end 416.6108 -183.6928)
		(width 0.13208)
		(layer "F.Cu")
		(net "FPGA_PEX3_MODE_SEL2_D_N")
	)
	(segment
		(start 414.5026 -183.8452)
		(end 414.3502 -183.6928)
		(width 0.13208)
		(layer "F.Cu")
		(net "FPGA_PEX3_MODE_SEL2_D_N")
	)
	(segment
		(start 415.080958 -183.8452)
		(end 414.5026 -183.8452)
		(width 0.13208)
		(layer "F.Cu")
		(net "FPGA_PEX3_MODE_SEL2_D_N")
	)
	(segment
		(start 416.960558 -184.042558)
		(end 416.960558 -184.941718)
		(width 0.13208)
		(layer "F.Cu")
		(net "FPGA_PEX3_MODE_SEL2_D_N")
	)
	(segment
		(start 414.532318 -183.078882)
		(end 415.097214 -183.078882)
		(width 0.13208)
		(layer "F.Cu")
		(net "FPGA_PEX3_MODE_SEL2_D_N")
	)
	(via
		(at 416.5854 -183.6928)
		(size 0.762)
		(drill 0.381)
		(layers "F.Cu" "B.Cu")
		(net "FPGA_PEX3_MODE_SEL2_D_N")
	)
	(segment
		(start 342.624918 -201.56805)
		(end 342.624918 -202.184)
		(width 0.13208)
		(layer "F.Cu")
		(net "FPGA_PEX0_MODE_SEL2")
	)
	(segment
		(start 344.49385 -214.387176)
		(end 344.893646 -213.98738)
		(width 0.13208)
		(layer "F.Cu")
		(net "FPGA_PEX0_MODE_SEL2")
	)
	(via
		(at 344.893646 -213.98738)
		(size 0.4572)
		(drill 0.254)
		(layers "F.Cu" "B.Cu")
		(net "FPGA_PEX0_MODE_SEL2")
	)
	(via
		(at 342.624918 -202.184)
		(size 0.508)
		(drill 0.254)
		(layers "F.Cu" "B.Cu")
		(net "FPGA_PEX0_MODE_SEL2")
	)
	(segment
		(start 343.167462 -203.190094)
		(end 343.167462 -205.194662)
		(width 0.15494)
		(layer "In5.Cu")
		(net "FPGA_PEX0_MODE_SEL2")
	)
	(segment
		(start 344.499946 -214.38108)
		(end 344.893646 -213.98738)
		(width 0.0889)
		(layer "In5.Cu")
		(net "FPGA_PEX0_MODE_SEL2")
	)
	(segment
		(start 343.69121 -211.40293)
		(end 343.69121 -212.04682)
		(width 0.15494)
		(layer "In5.Cu")
		(net "FPGA_PEX0_MODE_SEL2")
	)
	(segment
		(start 343.167462 -205.194662)
		(end 343.658698 -205.685898)
		(width 0.15494)
		(layer "In5.Cu")
		(net "FPGA_PEX0_MODE_SEL2")
	)
	(segment
		(start 343.69121 -214.18931)
		(end 343.88298 -214.38108)
		(width 0.0889)
		(layer "In5.Cu")
		(net "FPGA_PEX0_MODE_SEL2")
	)
	(segment
		(start 343.658698 -205.685898)
		(end 343.658698 -208.225898)
		(width 0.15494)
		(layer "In5.Cu")
		(net "FPGA_PEX0_MODE_SEL2")
	)
	(segment
		(start 343.88298 -214.38108)
		(end 344.499946 -214.38108)
		(width 0.0889)
		(layer "In5.Cu")
		(net "FPGA_PEX0_MODE_SEL2")
	)
	(segment
		(start 342.624918 -202.64755)
		(end 343.167462 -203.190094)
		(width 0.15494)
		(layer "In5.Cu")
		(net "FPGA_PEX0_MODE_SEL2")
	)
	(segment
		(start 342.624918 -202.184)
		(end 342.624918 -202.64755)
		(width 0.15494)
		(layer "In5.Cu")
		(net "FPGA_PEX0_MODE_SEL2")
	)
	(segment
		(start 343.658698 -208.225898)
		(end 344.1192 -208.6864)
		(width 0.15494)
		(layer "In5.Cu")
		(net "FPGA_PEX0_MODE_SEL2")
	)
	(segment
		(start 344.1192 -208.6864)
		(end 344.1192 -210.97494)
		(width 0.15494)
		(layer "In5.Cu")
		(net "FPGA_PEX0_MODE_SEL2")
	)
	(segment
		(start 344.1192 -210.97494)
		(end 343.69121 -211.40293)
		(width 0.15494)
		(layer "In5.Cu")
		(net "FPGA_PEX0_MODE_SEL2")
	)
	(segment
		(start 343.69121 -212.04682)
		(end 343.69121 -214.18931)
		(width 0.0889)
		(layer "In5.Cu")
		(net "FPGA_PEX0_MODE_SEL2")
	)
	(segment
		(start 410.650944 -190.66002)
		(end 410.637482 -190.646558)
		(width 0.13208)
		(layer "F.Cu")
		(net "FPGA_PEX2_MODE_SEL1_ISO")
	)
	(segment
		(start 411.9118 -190.66002)
		(end 410.650944 -190.66002)
		(width 0.13208)
		(layer "F.Cu")
		(net "FPGA_PEX2_MODE_SEL1_ISO")
	)
	(segment
		(start 413.37357 -190.66002)
		(end 411.9118 -190.66002)
		(width 0.13208)
		(layer "F.Cu")
		(net "FPGA_PEX2_MODE_SEL1_ISO")
	)
	(via
		(at 411.9118 -190.66002)
		(size 0.762)
		(drill 0.381)
		(layers "F.Cu" "B.Cu")
		(net "FPGA_PEX2_MODE_SEL1_ISO")
	)
	(segment
		(start 414.633918 -191.410082)
		(end 415.173414 -191.410082)
		(width 0.13208)
		(layer "F.Cu")
		(net "FPGA_PEX2_MODE_SEL1_D_N")
	)
	(segment
		(start 413.988758 -193.730118)
		(end 413.993076 -193.7258)
		(width 0.13208)
		(layer "F.Cu")
		(net "FPGA_PEX2_MODE_SEL1_D_N")
	)
	(segment
		(start 415.173414 -192.160144)
		(end 415.16427 -192.151)
		(width 0.13208)
		(layer "F.Cu")
		(net "FPGA_PEX2_MODE_SEL1_D_N")
	)
	(segment
		(start 415.16427 -192.151)
		(end 414.655 -192.151)
		(width 0.13208)
		(layer "F.Cu")
		(net "FPGA_PEX2_MODE_SEL1_D_N")
	)
	(segment
		(start 414.4772 -191.5668)
		(end 414.633918 -191.410082)
		(width 0.13208)
		(layer "F.Cu")
		(net "FPGA_PEX2_MODE_SEL1_D_N")
	)
	(segment
		(start 413.993076 -193.7258)
		(end 414.9344 -193.7258)
		(width 0.13208)
		(layer "F.Cu")
		(net "FPGA_PEX2_MODE_SEL1_D_N")
	)
	(segment
		(start 414.655 -192.151)
		(end 414.4772 -191.9732)
		(width 0.13208)
		(layer "F.Cu")
		(net "FPGA_PEX2_MODE_SEL1_D_N")
	)
	(segment
		(start 414.4772 -191.9732)
		(end 414.4772 -191.5668)
		(width 0.13208)
		(layer "F.Cu")
		(net "FPGA_PEX2_MODE_SEL1_D_N")
	)
	(segment
		(start 414.9344 -193.7258)
		(end 415.173414 -193.486786)
		(width 0.13208)
		(layer "F.Cu")
		(net "FPGA_PEX2_MODE_SEL1_D_N")
	)
	(segment
		(start 415.173414 -193.486786)
		(end 415.173414 -192.160144)
		(width 0.13208)
		(layer "F.Cu")
		(net "FPGA_PEX2_MODE_SEL1_D_N")
	)
	(via
		(at 415.173414 -193.486786)
		(size 0.762)
		(drill 0.381)
		(layers "F.Cu" "B.Cu")
		(net "FPGA_PEX2_MODE_SEL1_D_N")
	)
	(segment
		(start 410.50337 -203.61402)
		(end 410.024834 -203.61402)
		(width 0.13208)
		(layer "F.Cu")
		(net "FPGA_PEX2_MODE_SEL2_ISO")
	)
	(segment
		(start 410.024834 -203.61402)
		(end 409.473654 -204.1652)
		(width 0.13208)
		(layer "F.Cu")
		(net "FPGA_PEX2_MODE_SEL2_ISO")
	)
	(segment
		(start 408.529282 -203.906882)
		(end 408.529282 -202.762358)
		(width 0.13208)
		(layer "F.Cu")
		(net "FPGA_PEX2_MODE_SEL2_ISO")
	)
	(segment
		(start 409.473654 -204.1652)
		(end 408.7876 -204.1652)
		(width 0.13208)
		(layer "F.Cu")
		(net "FPGA_PEX2_MODE_SEL2_ISO")
	)
	(segment
		(start 408.7876 -204.1652)
		(end 408.529282 -203.906882)
		(width 0.13208)
		(layer "F.Cu")
		(net "FPGA_PEX2_MODE_SEL2_ISO")
	)
	(via
		(at 408.7876 -204.1652)
		(size 0.762)
		(drill 0.381)
		(layers "F.Cu" "B.Cu")
		(net "FPGA_PEX2_MODE_SEL2_ISO")
	)
	(segment
		(start 411.895544 -205.114144)
		(end 412.303214 -205.114144)
		(width 0.13208)
		(layer "F.Cu")
		(net "FPGA_PEX2_MODE_SEL2_D_N")
	)
	(segment
		(start 413.6136 -205.5876)
		(end 412.77667 -205.5876)
		(width 0.13208)
		(layer "F.Cu")
		(net "FPGA_PEX2_MODE_SEL2_D_N")
	)
	(segment
		(start 412.303214 -204.364082)
		(end 411.789118 -204.364082)
		(width 0.13208)
		(layer "F.Cu")
		(net "FPGA_PEX2_MODE_SEL2_D_N")
	)
	(segment
		(start 413.6136 -205.5876)
		(end 414.1216 -205.5876)
		(width 0.13208)
		(layer "F.Cu")
		(net "FPGA_PEX2_MODE_SEL2_D_N")
	)
	(segment
		(start 414.1216 -205.5876)
		(end 414.3756 -205.3336)
		(width 0.13208)
		(layer "F.Cu")
		(net "FPGA_PEX2_MODE_SEL2_D_N")
	)
	(segment
		(start 412.77667 -205.5876)
		(end 412.303214 -205.114144)
		(width 0.13208)
		(layer "F.Cu")
		(net "FPGA_PEX2_MODE_SEL2_D_N")
	)
	(segment
		(start 411.789118 -204.364082)
		(end 411.734 -204.4192)
		(width 0.13208)
		(layer "F.Cu")
		(net "FPGA_PEX2_MODE_SEL2_D_N")
	)
	(segment
		(start 411.734 -204.9526)
		(end 411.895544 -205.114144)
		(width 0.13208)
		(layer "F.Cu")
		(net "FPGA_PEX2_MODE_SEL2_D_N")
	)
	(segment
		(start 411.734 -204.4192)
		(end 411.734 -204.9526)
		(width 0.13208)
		(layer "F.Cu")
		(net "FPGA_PEX2_MODE_SEL2_D_N")
	)
	(segment
		(start 414.3756 -204.366876)
		(end 414.371282 -204.362558)
		(width 0.13208)
		(layer "F.Cu")
		(net "FPGA_PEX2_MODE_SEL2_D_N")
	)
	(segment
		(start 414.3756 -205.3336)
		(end 414.3756 -204.366876)
		(width 0.13208)
		(layer "F.Cu")
		(net "FPGA_PEX2_MODE_SEL2_D_N")
	)
	(via
		(at 413.6136 -205.5876)
		(size 0.762)
		(drill 0.381)
		(layers "F.Cu" "B.Cu")
		(net "FPGA_PEX2_MODE_SEL2_D_N")
	)
	(segment
		(start 410.00426 -177.78222)
		(end 410.000958 -177.778918)
		(width 0.13208)
		(layer "F.Cu")
		(net "FPGA_PEX1_MODE_SEL1_ISO")
	)
	(segment
		(start 413.29737 -177.78222)
		(end 411.6324 -177.78222)
		(width 0.13208)
		(layer "F.Cu")
		(net "FPGA_PEX1_MODE_SEL1_ISO")
	)
	(segment
		(start 411.6324 -177.78222)
		(end 410.00426 -177.78222)
		(width 0.13208)
		(layer "F.Cu")
		(net "FPGA_PEX1_MODE_SEL1_ISO")
	)
	(via
		(at 411.6324 -177.78222)
		(size 0.762)
		(drill 0.381)
		(layers "F.Cu" "B.Cu")
		(net "FPGA_PEX1_MODE_SEL1_ISO")
	)
	(segment
		(start 415.08807 -179.2732)
		(end 414.6042 -179.2732)
		(width 0.13208)
		(layer "F.Cu")
		(net "FPGA_PEX1_MODE_SEL1_D_N")
	)
	(segment
		(start 416.2298 -180.721)
		(end 415.10204 -180.721)
		(width 0.13208)
		(layer "F.Cu")
		(net "FPGA_PEX1_MODE_SEL1_D_N")
	)
	(segment
		(start 416.3822 -180.0606)
		(end 416.3822 -180.5686)
		(width 0.13208)
		(layer "F.Cu")
		(net "FPGA_PEX1_MODE_SEL1_D_N")
	)
	(segment
		(start 414.6042 -179.2732)
		(end 414.4264 -179.0954)
		(width 0.13208)
		(layer "F.Cu")
		(net "FPGA_PEX1_MODE_SEL1_D_N")
	)
	(segment
		(start 415.10204 -180.721)
		(end 415.080958 -180.699918)
		(width 0.13208)
		(layer "F.Cu")
		(net "FPGA_PEX1_MODE_SEL1_D_N")
	)
	(segment
		(start 414.4264 -179.0954)
		(end 414.4264 -178.6636)
		(width 0.13208)
		(layer "F.Cu")
		(net "FPGA_PEX1_MODE_SEL1_D_N")
	)
	(segment
		(start 414.4264 -178.6636)
		(end 414.557718 -178.532282)
		(width 0.13208)
		(layer "F.Cu")
		(net "FPGA_PEX1_MODE_SEL1_D_N")
	)
	(segment
		(start 416.137344 -179.282344)
		(end 416.3822 -179.5272)
		(width 0.13208)
		(layer "F.Cu")
		(net "FPGA_PEX1_MODE_SEL1_D_N")
	)
	(segment
		(start 415.097214 -179.282344)
		(end 415.08807 -179.2732)
		(width 0.13208)
		(layer "F.Cu")
		(net "FPGA_PEX1_MODE_SEL1_D_N")
	)
	(segment
		(start 416.3822 -179.5272)
		(end 416.3822 -180.0606)
		(width 0.13208)
		(layer "F.Cu")
		(net "FPGA_PEX1_MODE_SEL1_D_N")
	)
	(segment
		(start 416.3822 -180.5686)
		(end 416.2298 -180.721)
		(width 0.13208)
		(layer "F.Cu")
		(net "FPGA_PEX1_MODE_SEL1_D_N")
	)
	(segment
		(start 415.097214 -179.282344)
		(end 416.137344 -179.282344)
		(width 0.13208)
		(layer "F.Cu")
		(net "FPGA_PEX1_MODE_SEL1_D_N")
	)
	(segment
		(start 414.557718 -178.532282)
		(end 415.097214 -178.532282)
		(width 0.13208)
		(layer "F.Cu")
		(net "FPGA_PEX1_MODE_SEL1_D_N")
	)
	(via
		(at 416.3822 -180.0606)
		(size 0.762)
		(drill 0.381)
		(layers "F.Cu" "B.Cu")
		(net "FPGA_PEX1_MODE_SEL1_D_N")
	)
	(segment
		(start 408.6225 -200.1901)
		(end 408.305 -199.8726)
		(width 0.13208)
		(layer "F.Cu")
		(net "FPGA_PEX1_MODE_SEL2_ISO")
	)
	(segment
		(start 408.305 -199.25284)
		(end 408.554682 -199.003158)
		(width 0.13208)
		(layer "F.Cu")
		(net "FPGA_PEX1_MODE_SEL2_ISO")
	)
	(segment
		(start 408.305 -199.8726)
		(end 408.305 -199.25284)
		(width 0.13208)
		(layer "F.Cu")
		(net "FPGA_PEX1_MODE_SEL2_ISO")
	)
	(segment
		(start 409.74518 -200.03262)
		(end 410.57957 -200.03262)
		(width 0.13208)
		(layer "F.Cu")
		(net "FPGA_PEX1_MODE_SEL2_ISO")
	)
	(segment
		(start 408.6225 -200.1901)
		(end 409.5877 -200.1901)
		(width 0.13208)
		(layer "F.Cu")
		(net "FPGA_PEX1_MODE_SEL2_ISO")
	)
	(segment
		(start 409.5877 -200.1901)
		(end 409.74518 -200.03262)
		(width 0.13208)
		(layer "F.Cu")
		(net "FPGA_PEX1_MODE_SEL2_ISO")
	)
	(via
		(at 408.6225 -200.1901)
		(size 0.762)
		(drill 0.381)
		(layers "F.Cu" "B.Cu")
		(net "FPGA_PEX1_MODE_SEL2_ISO")
	)
	(segment
		(start 411.839918 -200.782682)
		(end 412.379414 -200.782682)
		(width 0.13208)
		(layer "F.Cu")
		(net "FPGA_PEX1_MODE_SEL2_D_N")
	)
	(segment
		(start 412.835344 -201.532744)
		(end 412.379414 -201.532744)
		(width 0.13208)
		(layer "F.Cu")
		(net "FPGA_PEX1_MODE_SEL2_D_N")
	)
	(segment
		(start 413.4104 -202.1078)
		(end 412.835344 -201.532744)
		(width 0.13208)
		(layer "F.Cu")
		(net "FPGA_PEX1_MODE_SEL2_D_N")
	)
	(segment
		(start 413.9438 -202.1078)
		(end 413.4104 -202.1078)
		(width 0.13208)
		(layer "F.Cu")
		(net "FPGA_PEX1_MODE_SEL2_D_N")
	)
	(segment
		(start 414.6804 -201.9046)
		(end 414.6804 -200.785476)
		(width 0.13208)
		(layer "F.Cu")
		(net "FPGA_PEX1_MODE_SEL2_D_N")
	)
	(segment
		(start 414.4772 -202.1078)
		(end 414.6804 -201.9046)
		(width 0.13208)
		(layer "F.Cu")
		(net "FPGA_PEX1_MODE_SEL2_D_N")
	)
	(segment
		(start 412.379414 -201.532744)
		(end 411.819344 -201.532744)
		(width 0.13208)
		(layer "F.Cu")
		(net "FPGA_PEX1_MODE_SEL2_D_N")
	)
	(segment
		(start 411.6832 -201.3966)
		(end 411.6832 -200.9394)
		(width 0.13208)
		(layer "F.Cu")
		(net "FPGA_PEX1_MODE_SEL2_D_N")
	)
	(segment
		(start 414.6804 -200.785476)
		(end 414.676082 -200.781158)
		(width 0.13208)
		(layer "F.Cu")
		(net "FPGA_PEX1_MODE_SEL2_D_N")
	)
	(segment
		(start 411.6832 -200.9394)
		(end 411.839918 -200.782682)
		(width 0.13208)
		(layer "F.Cu")
		(net "FPGA_PEX1_MODE_SEL2_D_N")
	)
	(segment
		(start 413.9438 -202.1078)
		(end 414.4772 -202.1078)
		(width 0.13208)
		(layer "F.Cu")
		(net "FPGA_PEX1_MODE_SEL2_D_N")
	)
	(segment
		(start 411.819344 -201.532744)
		(end 411.6832 -201.3966)
		(width 0.13208)
		(layer "F.Cu")
		(net "FPGA_PEX1_MODE_SEL2_D_N")
	)
	(via
		(at 413.9438 -202.1078)
		(size 0.762)
		(drill 0.381)
		(layers "F.Cu" "B.Cu")
		(net "FPGA_PEX1_MODE_SEL2_D_N")
	)
	(segment
		(start 413.37357 -186.03722)
		(end 411.7848 -186.03722)
		(width 0.13208)
		(layer "F.Cu")
		(net "FPGA_PEX0_MODE_SEL2_ISO")
	)
	(segment
		(start 411.7848 -186.03722)
		(end 410.08046 -186.03722)
		(width 0.13208)
		(layer "F.Cu")
		(net "FPGA_PEX0_MODE_SEL2_ISO")
	)
	(segment
		(start 410.08046 -186.03722)
		(end 410.077158 -186.033918)
		(width 0.13208)
		(layer "F.Cu")
		(net "FPGA_PEX0_MODE_SEL2_ISO")
	)
	(via
		(at 411.7848 -186.03722)
		(size 0.762)
		(drill 0.381)
		(layers "F.Cu" "B.Cu")
		(net "FPGA_PEX0_MODE_SEL2_ISO")
	)
	(segment
		(start 415.173414 -187.537344)
		(end 415.16427 -187.5282)
		(width 0.13208)
		(layer "F.Cu")
		(net "FPGA_PEX0_MODE_SEL2_D_N")
	)
	(segment
		(start 414.31464 -189.2046)
		(end 414.9852 -189.2046)
		(width 0.13208)
		(layer "F.Cu")
		(net "FPGA_PEX0_MODE_SEL2_D_N")
	)
	(segment
		(start 414.4518 -187.4012)
		(end 414.4518 -186.944)
		(width 0.13208)
		(layer "F.Cu")
		(net "FPGA_PEX0_MODE_SEL2_D_N")
	)
	(segment
		(start 414.9852 -189.2046)
		(end 415.3662 -188.8236)
		(width 0.13208)
		(layer "F.Cu")
		(net "FPGA_PEX0_MODE_SEL2_D_N")
	)
	(segment
		(start 414.4518 -186.944)
		(end 414.608518 -186.787282)
		(width 0.13208)
		(layer "F.Cu")
		(net "FPGA_PEX0_MODE_SEL2_D_N")
	)
	(segment
		(start 414.5788 -187.5282)
		(end 414.4518 -187.4012)
		(width 0.13208)
		(layer "F.Cu")
		(net "FPGA_PEX0_MODE_SEL2_D_N")
	)
	(segment
		(start 415.3662 -188.8236)
		(end 415.3662 -187.73013)
		(width 0.13208)
		(layer "F.Cu")
		(net "FPGA_PEX0_MODE_SEL2_D_N")
	)
	(segment
		(start 415.16427 -187.5282)
		(end 414.5788 -187.5282)
		(width 0.13208)
		(layer "F.Cu")
		(net "FPGA_PEX0_MODE_SEL2_D_N")
	)
	(segment
		(start 414.608518 -186.787282)
		(end 415.173414 -186.787282)
		(width 0.13208)
		(layer "F.Cu")
		(net "FPGA_PEX0_MODE_SEL2_D_N")
	)
	(segment
		(start 414.166558 -189.056518)
		(end 414.31464 -189.2046)
		(width 0.13208)
		(layer "F.Cu")
		(net "FPGA_PEX0_MODE_SEL2_D_N")
	)
	(segment
		(start 415.3662 -187.73013)
		(end 415.173414 -187.537344)
		(width 0.13208)
		(layer "F.Cu")
		(net "FPGA_PEX0_MODE_SEL2_D_N")
	)
	(via
		(at 415.3662 -188.8236)
		(size 0.762)
		(drill 0.381)
		(layers "F.Cu" "B.Cu")
		(net "FPGA_PEX0_MODE_SEL2_D_N")
	)
	(segment
		(start 305.149758 -304.449734)
		(end 304.674778 -304.924714)
		(width 0.249936)
		(layer "F.Cu")
		(net "Net_380")
	)
	(via
		(at 304.674778 -304.924714)
		(size 0.4064)
		(drill 0.2032)
		(layers "F.Cu" "B.Cu")
		(net "Net_380")
	)
	(segment
		(start 421.249856 -304.449734)
		(end 420.774876 -304.924714)
		(width 0.249936)
		(layer "F.Cu")
		(net "Net_389")
	)
	(via
		(at 420.774876 -304.924714)
		(size 0.4064)
		(drill 0.2032)
		(layers "F.Cu" "B.Cu")
		(net "Net_389")
	)
	(segment
		(start 72.949816 -304.449734)
		(end 72.474836 -304.924714)
		(width 0.249936)
		(layer "F.Cu")
		(net "Net_390")
	)
	(via
		(at 72.474836 -304.924714)
		(size 0.4064)
		(drill 0.2032)
		(layers "F.Cu" "B.Cu")
		(net "Net_390")
	)
	(segment
		(start 189.049914 -304.449734)
		(end 188.574934 -304.924714)
		(width 0.249936)
		(layer "F.Cu")
		(net "Net_391")
	)
	(via
		(at 188.574934 -304.924714)
		(size 0.4064)
		(drill 0.2032)
		(layers "F.Cu" "B.Cu")
		(net "Net_391")
	)
	(segment
		(start 435.02961 -301.02048)
		(end 435.02961 -301.879)
		(width 0.13208)
		(layer "F.Cu")
		(net "RST_PEX3_S3_PERST_R_N")
	)
	(segment
		(start 420.299896 -306.349908)
		(end 419.824916 -306.824888)
		(width 0.13208)
		(layer "F.Cu")
		(net "RST_PEX3_S3_PERST_R_N")
	)
	(via
		(at 419.824916 -306.824888)
		(size 0.4064)
		(drill 0.2032)
		(layers "F.Cu" "B.Cu")
		(net "RST_PEX3_S3_PERST_R_N")
	)
	(via
		(at 435.02961 -301.879)
		(size 0.508)
		(drill 0.254)
		(layers "F.Cu" "B.Cu")
		(net "RST_PEX3_S3_PERST_R_N")
	)
	(segment
		(start 434.99024 -301.879)
		(end 435.02961 -301.879)
		(width 0.13208)
		(layer "B.Cu")
		(net "RST_PEX3_S3_PERST_R_N")
	)
	(segment
		(start 421.995854 -304.3936)
		(end 422.258998 -304.130456)
		(width 0.13208)
		(layer "B.Cu")
		(net "RST_PEX3_S3_PERST_R_N")
	)
	(segment
		(start 419.824916 -306.824888)
		(end 420.28364 -306.366164)
		(width 0.13208)
		(layer "B.Cu")
		(net "RST_PEX3_S3_PERST_R_N")
	)
	(segment
		(start 422.258998 -303.729644)
		(end 423.423842 -302.5648)
		(width 0.13208)
		(layer "B.Cu")
		(net "RST_PEX3_S3_PERST_R_N")
	)
	(segment
		(start 434.30444 -302.5648)
		(end 434.99024 -301.879)
		(width 0.13208)
		(layer "B.Cu")
		(net "RST_PEX3_S3_PERST_R_N")
	)
	(segment
		(start 420.28364 -304.5714)
		(end 420.46144 -304.3936)
		(width 0.13208)
		(layer "B.Cu")
		(net "RST_PEX3_S3_PERST_R_N")
	)
	(segment
		(start 420.28364 -306.366164)
		(end 420.28364 -304.5714)
		(width 0.13208)
		(layer "B.Cu")
		(net "RST_PEX3_S3_PERST_R_N")
	)
	(segment
		(start 420.46144 -304.3936)
		(end 421.995854 -304.3936)
		(width 0.13208)
		(layer "B.Cu")
		(net "RST_PEX3_S3_PERST_R_N")
	)
	(segment
		(start 423.423842 -302.5648)
		(end 434.30444 -302.5648)
		(width 0.13208)
		(layer "B.Cu")
		(net "RST_PEX3_S3_PERST_R_N")
	)
	(segment
		(start 422.258998 -304.130456)
		(end 422.258998 -303.729644)
		(width 0.13208)
		(layer "B.Cu")
		(net "RST_PEX3_S3_PERST_R_N")
	)
	(segment
		(start 380.97206 -303.3141)
		(end 380.8349 -303.45126)
		(width 0.1143)
		(layer "F.Cu")
		(net "CLK_100M_DB800ZL_PEX3_S3_R_DN")
	)
	(segment
		(start 383.665222 -301.54118)
		(end 383.665222 -302.122332)
		(width 0.1143)
		(layer "F.Cu")
		(net "CLK_100M_DB800ZL_PEX3_S3_R_DN")
	)
	(segment
		(start 383.394204 -302.587152)
		(end 383.110232 -302.871378)
		(width 0.1143)
		(layer "F.Cu")
		(net "CLK_100M_DB800ZL_PEX3_S3_R_DN")
	)
	(segment
		(start 369.2398 -332.5114)
		(end 367.94313 -333.80807)
		(width 0.1143)
		(layer "F.Cu")
		(net "CLK_100M_DB800ZL_PEX3_S3_R_DN")
	)
	(segment
		(start 375.119646 -303.3141)
		(end 373.1895 -305.244246)
		(width 0.1143)
		(layer "F.Cu")
		(net "CLK_100M_DB800ZL_PEX3_S3_R_DN")
	)
	(segment
		(start 377.06554 -303.3141)
		(end 375.119646 -303.3141)
		(width 0.1143)
		(layer "F.Cu")
		(net "CLK_100M_DB800ZL_PEX3_S3_R_DN")
	)
	(segment
		(start 373.1895 -313.7535)
		(end 370.794788 -316.148212)
		(width 0.1143)
		(layer "F.Cu")
		(net "CLK_100M_DB800ZL_PEX3_S3_R_DN")
	)
	(segment
		(start 383.802382 -300.32706)
		(end 383.665222 -300.46422)
		(width 0.1143)
		(layer "F.Cu")
		(net "CLK_100M_DB800ZL_PEX3_S3_R_DN")
	)
	(segment
		(start 384.604514 -295.89984)
		(end 383.665222 -296.839132)
		(width 0.1143)
		(layer "F.Cu")
		(net "CLK_100M_DB800ZL_PEX3_S3_R_DN")
	)
	(segment
		(start 382.916176 -302.871378)
		(end 382.473454 -303.3141)
		(width 0.1143)
		(layer "F.Cu")
		(net "CLK_100M_DB800ZL_PEX3_S3_R_DN")
	)
	(segment
		(start 370.794788 -316.148212)
		(end 369.2398 -319.901316)
		(width 0.1143)
		(layer "F.Cu")
		(net "CLK_100M_DB800ZL_PEX3_S3_R_DN")
	)
	(segment
		(start 381.37338 -303.3141)
		(end 380.97206 -303.3141)
		(width 0.1143)
		(layer "F.Cu")
		(net "CLK_100M_DB800ZL_PEX3_S3_R_DN")
	)
	(segment
		(start 379.35662 -303.45126)
		(end 379.21946 -303.3141)
		(width 0.1143)
		(layer "F.Cu")
		(net "CLK_100M_DB800ZL_PEX3_S3_R_DN")
	)
	(segment
		(start 373.32666 -306.93614)
		(end 373.32666 -307.33746)
		(width 0.1143)
		(layer "F.Cu")
		(net "CLK_100M_DB800ZL_PEX3_S3_R_DN")
	)
	(segment
		(start 378.27966 -303.45126)
		(end 378.1425 -303.3141)
		(width 0.1143)
		(layer "F.Cu")
		(net "CLK_100M_DB800ZL_PEX3_S3_R_DN")
	)
	(segment
		(start 383.665222 -296.839132)
		(end 383.665222 -299.78858)
		(width 0.1143)
		(layer "F.Cu")
		(net "CLK_100M_DB800ZL_PEX3_S3_R_DN")
	)
	(segment
		(start 366.0648 -333.44612)
		(end 366.0648 -333.156052)
		(width 0.1143)
		(layer "F.Cu")
		(net "CLK_100M_DB800ZL_PEX3_S3_R_DN")
	)
	(segment
		(start 366.42675 -333.80807)
		(end 366.0648 -333.44612)
		(width 0.1143)
		(layer "F.Cu")
		(net "CLK_100M_DB800ZL_PEX3_S3_R_DN")
	)
	(segment
		(start 383.665222 -300.46422)
		(end 383.665222 -300.86554)
		(width 0.1143)
		(layer "F.Cu")
		(net "CLK_100M_DB800ZL_PEX3_S3_R_DN")
	)
	(segment
		(start 378.1425 -303.3141)
		(end 377.74118 -303.3141)
		(width 0.1143)
		(layer "F.Cu")
		(net "CLK_100M_DB800ZL_PEX3_S3_R_DN")
	)
	(segment
		(start 381.91186 -303.45126)
		(end 381.51054 -303.45126)
		(width 0.1143)
		(layer "F.Cu")
		(net "CLK_100M_DB800ZL_PEX3_S3_R_DN")
	)
	(segment
		(start 379.8951 -303.3141)
		(end 379.75794 -303.45126)
		(width 0.1143)
		(layer "F.Cu")
		(net "CLK_100M_DB800ZL_PEX3_S3_R_DN")
	)
	(segment
		(start 377.2027 -303.45126)
		(end 377.06554 -303.3141)
		(width 0.1143)
		(layer "F.Cu")
		(net "CLK_100M_DB800ZL_PEX3_S3_R_DN")
	)
	(segment
		(start 383.110232 -302.871378)
		(end 382.916176 -302.871378)
		(width 0.1143)
		(layer "F.Cu")
		(net "CLK_100M_DB800ZL_PEX3_S3_R_DN")
	)
	(segment
		(start 383.394204 -302.39335)
		(end 383.394204 -302.587152)
		(width 0.1143)
		(layer "F.Cu")
		(net "CLK_100M_DB800ZL_PEX3_S3_R_DN")
	)
	(segment
		(start 377.74118 -303.3141)
		(end 377.60402 -303.45126)
		(width 0.1143)
		(layer "F.Cu")
		(net "CLK_100M_DB800ZL_PEX3_S3_R_DN")
	)
	(segment
		(start 383.665222 -302.122332)
		(end 383.394204 -302.39335)
		(width 0.1143)
		(layer "F.Cu")
		(net "CLK_100M_DB800ZL_PEX3_S3_R_DN")
	)
	(segment
		(start 379.21946 -303.3141)
		(end 378.81814 -303.3141)
		(width 0.1143)
		(layer "F.Cu")
		(net "CLK_100M_DB800ZL_PEX3_S3_R_DN")
	)
	(segment
		(start 378.68098 -303.45126)
		(end 378.27966 -303.45126)
		(width 0.1143)
		(layer "F.Cu")
		(net "CLK_100M_DB800ZL_PEX3_S3_R_DN")
	)
	(segment
		(start 383.802382 -301.40402)
		(end 383.665222 -301.54118)
		(width 0.1143)
		(layer "F.Cu")
		(net "CLK_100M_DB800ZL_PEX3_S3_R_DN")
	)
	(segment
		(start 373.32666 -307.33746)
		(end 373.1895 -307.47462)
		(width 0.1143)
		(layer "F.Cu")
		(net "CLK_100M_DB800ZL_PEX3_S3_R_DN")
	)
	(segment
		(start 373.1895 -306.79898)
		(end 373.32666 -306.93614)
		(width 0.1143)
		(layer "F.Cu")
		(net "CLK_100M_DB800ZL_PEX3_S3_R_DN")
	)
	(segment
		(start 379.75794 -303.45126)
		(end 379.35662 -303.45126)
		(width 0.1143)
		(layer "F.Cu")
		(net "CLK_100M_DB800ZL_PEX3_S3_R_DN")
	)
	(segment
		(start 380.43358 -303.45126)
		(end 380.29642 -303.3141)
		(width 0.1143)
		(layer "F.Cu")
		(net "CLK_100M_DB800ZL_PEX3_S3_R_DN")
	)
	(segment
		(start 367.94313 -333.80807)
		(end 366.42675 -333.80807)
		(width 0.1143)
		(layer "F.Cu")
		(net "CLK_100M_DB800ZL_PEX3_S3_R_DN")
	)
	(segment
		(start 383.802382 -301.0027)
		(end 383.802382 -301.40402)
		(width 0.1143)
		(layer "F.Cu")
		(net "CLK_100M_DB800ZL_PEX3_S3_R_DN")
	)
	(segment
		(start 382.04902 -303.3141)
		(end 381.91186 -303.45126)
		(width 0.1143)
		(layer "F.Cu")
		(net "CLK_100M_DB800ZL_PEX3_S3_R_DN")
	)
	(segment
		(start 366.0648 -333.156052)
		(end 365.82604 -332.917292)
		(width 0.1143)
		(layer "F.Cu")
		(net "CLK_100M_DB800ZL_PEX3_S3_R_DN")
	)
	(segment
		(start 380.8349 -303.45126)
		(end 380.43358 -303.45126)
		(width 0.1143)
		(layer "F.Cu")
		(net "CLK_100M_DB800ZL_PEX3_S3_R_DN")
	)
	(segment
		(start 382.473454 -303.3141)
		(end 382.04902 -303.3141)
		(width 0.1143)
		(layer "F.Cu")
		(net "CLK_100M_DB800ZL_PEX3_S3_R_DN")
	)
	(segment
		(start 383.665222 -299.78858)
		(end 383.802382 -299.92574)
		(width 0.1143)
		(layer "F.Cu")
		(net "CLK_100M_DB800ZL_PEX3_S3_R_DN")
	)
	(segment
		(start 383.665222 -300.86554)
		(end 383.802382 -301.0027)
		(width 0.1143)
		(layer "F.Cu")
		(net "CLK_100M_DB800ZL_PEX3_S3_R_DN")
	)
	(segment
		(start 380.29642 -303.3141)
		(end 379.8951 -303.3141)
		(width 0.1143)
		(layer "F.Cu")
		(net "CLK_100M_DB800ZL_PEX3_S3_R_DN")
	)
	(segment
		(start 378.81814 -303.3141)
		(end 378.68098 -303.45126)
		(width 0.1143)
		(layer "F.Cu")
		(net "CLK_100M_DB800ZL_PEX3_S3_R_DN")
	)
	(segment
		(start 373.1895 -307.47462)
		(end 373.1895 -313.7535)
		(width 0.1143)
		(layer "F.Cu")
		(net "CLK_100M_DB800ZL_PEX3_S3_R_DN")
	)
	(segment
		(start 377.60402 -303.45126)
		(end 377.2027 -303.45126)
		(width 0.1143)
		(layer "F.Cu")
		(net "CLK_100M_DB800ZL_PEX3_S3_R_DN")
	)
	(segment
		(start 373.1895 -305.244246)
		(end 373.1895 -306.79898)
		(width 0.1143)
		(layer "F.Cu")
		(net "CLK_100M_DB800ZL_PEX3_S3_R_DN")
	)
	(segment
		(start 383.802382 -299.92574)
		(end 383.802382 -300.32706)
		(width 0.1143)
		(layer "F.Cu")
		(net "CLK_100M_DB800ZL_PEX3_S3_R_DN")
	)
	(segment
		(start 381.51054 -303.45126)
		(end 381.37338 -303.3141)
		(width 0.1143)
		(layer "F.Cu")
		(net "CLK_100M_DB800ZL_PEX3_S3_R_DN")
	)
	(segment
		(start 369.2398 -319.901316)
		(end 369.2398 -332.5114)
		(width 0.1143)
		(layer "F.Cu")
		(net "CLK_100M_DB800ZL_PEX3_S3_R_DN")
	)
	(segment
		(start 385.149852 -295.89984)
		(end 384.604514 -295.89984)
		(width 0.1143)
		(layer "F.Cu")
		(net "CLK_100M_DB800ZL_PEX3_S3_R_DN")
	)
	(via
		(at 365.82604 -332.917292)
		(size 0.508)
		(drill 0.254)
		(layers "F.Cu" "B.Cu")
		(net "CLK_100M_DB800ZL_PEX3_S3_R_DN")
	)
	(segment
		(start 266.035028 -338.63407)
		(end 264.62609 -339.575394)
		(width 0.1143)
		(layer "B.Cu")
		(net "CLK_100M_DB800ZL_PEX3_S3_R_DN")
	)
	(segment
		(start 193.679318 -339.268562)
		(end 166.315136 -339.268562)
		(width 0.1143)
		(layer "B.Cu")
		(net "CLK_100M_DB800ZL_PEX3_S3_R_DN")
	)
	(segment
		(start 225.73615 -339.575394)
		(end 220.805756 -334.645)
		(width 0.1143)
		(layer "B.Cu")
		(net "CLK_100M_DB800ZL_PEX3_S3_R_DN")
	)
	(segment
		(start 359.395522 -340.2584)
		(end 357.837232 -340.2584)
		(width 0.1143)
		(layer "B.Cu")
		(net "CLK_100M_DB800ZL_PEX3_S3_R_DN")
	)
	(segment
		(start 366.0775 -336.9056)
		(end 365.07801 -337.904836)
		(width 0.1143)
		(layer "B.Cu")
		(net "CLK_100M_DB800ZL_PEX3_S3_R_DN")
	)
	(segment
		(start 365.07801 -337.904836)
		(end 359.395522 -340.2584)
		(width 0.1143)
		(layer "B.Cu")
		(net "CLK_100M_DB800ZL_PEX3_S3_R_DN")
	)
	(segment
		(start 117.21846 -352.73488)
		(end 116.81714 -352.73488)
		(width 0.1143)
		(layer "B.Cu")
		(net "CLK_100M_DB800ZL_PEX3_S3_R_DN")
	)
	(segment
		(start 366.0775 -333.168752)
		(end 366.0775 -336.9056)
		(width 0.1143)
		(layer "B.Cu")
		(net "CLK_100M_DB800ZL_PEX3_S3_R_DN")
	)
	(segment
		(start 117.35562 -352.87204)
		(end 117.21846 -352.73488)
		(width 0.1143)
		(layer "B.Cu")
		(net "CLK_100M_DB800ZL_PEX3_S3_R_DN")
	)
	(segment
		(start 220.805756 -334.645)
		(end 198.30288 -334.645)
		(width 0.1143)
		(layer "B.Cu")
		(net "CLK_100M_DB800ZL_PEX3_S3_R_DN")
	)
	(segment
		(start 110.279434 -352.1329)
		(end 109.943138 -351.796604)
		(width 0.1143)
		(layer "B.Cu")
		(net "CLK_100M_DB800ZL_PEX3_S3_R_DN")
	)
	(segment
		(start 365.82604 -332.917292)
		(end 366.0775 -333.168752)
		(width 0.1143)
		(layer "B.Cu")
		(net "CLK_100M_DB800ZL_PEX3_S3_R_DN")
	)
	(segment
		(start 166.315136 -339.268562)
		(end 153.870152 -344.423492)
		(width 0.1143)
		(layer "B.Cu")
		(net "CLK_100M_DB800ZL_PEX3_S3_R_DN")
	)
	(segment
		(start 111.344202 -352.87204)
		(end 110.605062 -352.1329)
		(width 0.1143)
		(layer "B.Cu")
		(net "CLK_100M_DB800ZL_PEX3_S3_R_DN")
	)
	(segment
		(start 198.30288 -334.645)
		(end 193.679318 -339.268562)
		(width 0.1143)
		(layer "B.Cu")
		(net "CLK_100M_DB800ZL_PEX3_S3_R_DN")
	)
	(segment
		(start 118.29542 -352.73488)
		(end 117.8941 -352.73488)
		(width 0.1143)
		(layer "B.Cu")
		(net "CLK_100M_DB800ZL_PEX3_S3_R_DN")
	)
	(segment
		(start 357.837232 -340.2584)
		(end 353.915726 -338.63407)
		(width 0.1143)
		(layer "B.Cu")
		(net "CLK_100M_DB800ZL_PEX3_S3_R_DN")
	)
	(segment
		(start 117.75694 -352.87204)
		(end 117.35562 -352.87204)
		(width 0.1143)
		(layer "B.Cu")
		(net "CLK_100M_DB800ZL_PEX3_S3_R_DN")
	)
	(segment
		(start 116.81714 -352.73488)
		(end 116.67998 -352.87204)
		(width 0.1143)
		(layer "B.Cu")
		(net "CLK_100M_DB800ZL_PEX3_S3_R_DN")
	)
	(segment
		(start 110.605062 -352.1329)
		(end 110.279434 -352.1329)
		(width 0.1143)
		(layer "B.Cu")
		(net "CLK_100M_DB800ZL_PEX3_S3_R_DN")
	)
	(segment
		(start 353.915726 -338.63407)
		(end 266.035028 -338.63407)
		(width 0.1143)
		(layer "B.Cu")
		(net "CLK_100M_DB800ZL_PEX3_S3_R_DN")
	)
	(segment
		(start 118.43258 -352.87204)
		(end 118.29542 -352.73488)
		(width 0.1143)
		(layer "B.Cu")
		(net "CLK_100M_DB800ZL_PEX3_S3_R_DN")
	)
	(segment
		(start 153.870152 -344.423492)
		(end 145.421858 -352.87204)
		(width 0.1143)
		(layer "B.Cu")
		(net "CLK_100M_DB800ZL_PEX3_S3_R_DN")
	)
	(segment
		(start 117.8941 -352.73488)
		(end 117.75694 -352.87204)
		(width 0.1143)
		(layer "B.Cu")
		(net "CLK_100M_DB800ZL_PEX3_S3_R_DN")
	)
	(segment
		(start 116.67998 -352.87204)
		(end 111.344202 -352.87204)
		(width 0.1143)
		(layer "B.Cu")
		(net "CLK_100M_DB800ZL_PEX3_S3_R_DN")
	)
	(segment
		(start 264.62609 -339.575394)
		(end 225.73615 -339.575394)
		(width 0.1143)
		(layer "B.Cu")
		(net "CLK_100M_DB800ZL_PEX3_S3_R_DN")
	)
	(segment
		(start 145.421858 -352.87204)
		(end 118.43258 -352.87204)
		(width 0.1143)
		(layer "B.Cu")
		(net "CLK_100M_DB800ZL_PEX3_S3_R_DN")
	)
	(segment
		(start 384.5052 -295.4782)
		(end 383.296922 -296.686478)
		(width 0.1143)
		(layer "F.Cu")
		(net "CLK_100M_DB800ZL_PEX3_S3_R_DP")
	)
	(segment
		(start 386.099812 -295.89984)
		(end 385.678172 -295.4782)
		(width 0.1143)
		(layer "F.Cu")
		(net "CLK_100M_DB800ZL_PEX3_S3_R_DP")
	)
	(segment
		(start 368.8715 -331.281786)
		(end 368.73434 -331.418946)
		(width 0.1143)
		(layer "F.Cu")
		(net "CLK_100M_DB800ZL_PEX3_S3_R_DP")
	)
	(segment
		(start 372.8212 -313.600846)
		(end 370.482368 -315.939424)
		(width 0.1143)
		(layer "F.Cu")
		(net "CLK_100M_DB800ZL_PEX3_S3_R_DP")
	)
	(segment
		(start 368.73434 -331.820266)
		(end 368.8715 -331.957426)
		(width 0.1143)
		(layer "F.Cu")
		(net "CLK_100M_DB800ZL_PEX3_S3_R_DP")
	)
	(segment
		(start 366.4331 -333.173832)
		(end 366.68964 -332.917292)
		(width 0.1143)
		(layer "F.Cu")
		(net "CLK_100M_DB800ZL_PEX3_S3_R_DP")
	)
	(segment
		(start 368.8715 -331.957426)
		(end 368.8715 -332.358746)
		(width 0.1143)
		(layer "F.Cu")
		(net "CLK_100M_DB800ZL_PEX3_S3_R_DP")
	)
	(segment
		(start 370.482368 -315.939424)
		(end 368.8715 -319.82791)
		(width 0.1143)
		(layer "F.Cu")
		(net "CLK_100M_DB800ZL_PEX3_S3_R_DP")
	)
	(segment
		(start 366.579404 -333.43977)
		(end 366.4331 -333.293466)
		(width 0.1143)
		(layer "F.Cu")
		(net "CLK_100M_DB800ZL_PEX3_S3_R_DP")
	)
	(segment
		(start 383.296922 -301.969678)
		(end 382.3208 -302.9458)
		(width 0.1143)
		(layer "F.Cu")
		(net "CLK_100M_DB800ZL_PEX3_S3_R_DP")
	)
	(segment
		(start 385.678172 -295.4782)
		(end 384.5052 -295.4782)
		(width 0.1143)
		(layer "F.Cu")
		(net "CLK_100M_DB800ZL_PEX3_S3_R_DP")
	)
	(segment
		(start 366.4331 -333.293466)
		(end 366.4331 -333.173832)
		(width 0.1143)
		(layer "F.Cu")
		(net "CLK_100M_DB800ZL_PEX3_S3_R_DP")
	)
	(segment
		(start 368.8715 -319.82791)
		(end 368.8715 -331.281786)
		(width 0.1143)
		(layer "F.Cu")
		(net "CLK_100M_DB800ZL_PEX3_S3_R_DP")
	)
	(segment
		(start 368.73434 -331.418946)
		(end 368.73434 -331.820266)
		(width 0.1143)
		(layer "F.Cu")
		(net "CLK_100M_DB800ZL_PEX3_S3_R_DP")
	)
	(segment
		(start 368.8715 -332.358746)
		(end 367.790476 -333.43977)
		(width 0.1143)
		(layer "F.Cu")
		(net "CLK_100M_DB800ZL_PEX3_S3_R_DP")
	)
	(segment
		(start 382.3208 -302.9458)
		(end 374.966992 -302.9458)
		(width 0.1143)
		(layer "F.Cu")
		(net "CLK_100M_DB800ZL_PEX3_S3_R_DP")
	)
	(segment
		(start 374.966992 -302.9458)
		(end 372.8212 -305.091592)
		(width 0.1143)
		(layer "F.Cu")
		(net "CLK_100M_DB800ZL_PEX3_S3_R_DP")
	)
	(segment
		(start 383.296922 -296.686478)
		(end 383.296922 -301.969678)
		(width 0.1143)
		(layer "F.Cu")
		(net "CLK_100M_DB800ZL_PEX3_S3_R_DP")
	)
	(segment
		(start 372.8212 -305.091592)
		(end 372.8212 -313.600846)
		(width 0.1143)
		(layer "F.Cu")
		(net "CLK_100M_DB800ZL_PEX3_S3_R_DP")
	)
	(segment
		(start 367.790476 -333.43977)
		(end 366.579404 -333.43977)
		(width 0.1143)
		(layer "F.Cu")
		(net "CLK_100M_DB800ZL_PEX3_S3_R_DP")
	)
	(via
		(at 366.68964 -332.917292)
		(size 0.508)
		(drill 0.254)
		(layers "F.Cu" "B.Cu")
		(net "CLK_100M_DB800ZL_PEX3_S3_R_DP")
	)
	(segment
		(start 111.191548 -353.24034)
		(end 110.452408 -352.5012)
		(width 0.1143)
		(layer "B.Cu")
		(net "CLK_100M_DB800ZL_PEX3_S3_R_DP")
	)
	(segment
		(start 366.4458 -337.058254)
		(end 365.286798 -338.217256)
		(width 0.1143)
		(layer "B.Cu")
		(net "CLK_100M_DB800ZL_PEX3_S3_R_DP")
	)
	(segment
		(start 366.68964 -332.917292)
		(end 366.4458 -333.161132)
		(width 0.1143)
		(layer "B.Cu")
		(net "CLK_100M_DB800ZL_PEX3_S3_R_DP")
	)
	(segment
		(start 366.4458 -333.161132)
		(end 366.4458 -337.058254)
		(width 0.1143)
		(layer "B.Cu")
		(net "CLK_100M_DB800ZL_PEX3_S3_R_DP")
	)
	(segment
		(start 359.468928 -340.6267)
		(end 357.763826 -340.6267)
		(width 0.1143)
		(layer "B.Cu")
		(net "CLK_100M_DB800ZL_PEX3_S3_R_DP")
	)
	(segment
		(start 365.286798 -338.217256)
		(end 359.468928 -340.6267)
		(width 0.1143)
		(layer "B.Cu")
		(net "CLK_100M_DB800ZL_PEX3_S3_R_DP")
	)
	(segment
		(start 110.452408 -352.5012)
		(end 110.254542 -352.5012)
		(width 0.1143)
		(layer "B.Cu")
		(net "CLK_100M_DB800ZL_PEX3_S3_R_DP")
	)
	(segment
		(start 353.84232 -339.00237)
		(end 266.146788 -339.00237)
		(width 0.1143)
		(layer "B.Cu")
		(net "CLK_100M_DB800ZL_PEX3_S3_R_DP")
	)
	(segment
		(start 154.07894 -344.735912)
		(end 145.574512 -353.24034)
		(width 0.1143)
		(layer "B.Cu")
		(net "CLK_100M_DB800ZL_PEX3_S3_R_DP")
	)
	(segment
		(start 198.455534 -335.0133)
		(end 193.831972 -339.636862)
		(width 0.1143)
		(layer "B.Cu")
		(net "CLK_100M_DB800ZL_PEX3_S3_R_DP")
	)
	(segment
		(start 225.583496 -339.943694)
		(end 220.653102 -335.0133)
		(width 0.1143)
		(layer "B.Cu")
		(net "CLK_100M_DB800ZL_PEX3_S3_R_DP")
	)
	(segment
		(start 357.763826 -340.6267)
		(end 353.84232 -339.00237)
		(width 0.1143)
		(layer "B.Cu")
		(net "CLK_100M_DB800ZL_PEX3_S3_R_DP")
	)
	(segment
		(start 264.73785 -339.943694)
		(end 225.583496 -339.943694)
		(width 0.1143)
		(layer "B.Cu")
		(net "CLK_100M_DB800ZL_PEX3_S3_R_DP")
	)
	(segment
		(start 110.254542 -352.5012)
		(end 109.943138 -352.812604)
		(width 0.1143)
		(layer "B.Cu")
		(net "CLK_100M_DB800ZL_PEX3_S3_R_DP")
	)
	(segment
		(start 166.388542 -339.636862)
		(end 154.07894 -344.735912)
		(width 0.1143)
		(layer "B.Cu")
		(net "CLK_100M_DB800ZL_PEX3_S3_R_DP")
	)
	(segment
		(start 220.653102 -335.0133)
		(end 198.455534 -335.0133)
		(width 0.1143)
		(layer "B.Cu")
		(net "CLK_100M_DB800ZL_PEX3_S3_R_DP")
	)
	(segment
		(start 145.574512 -353.24034)
		(end 111.191548 -353.24034)
		(width 0.1143)
		(layer "B.Cu")
		(net "CLK_100M_DB800ZL_PEX3_S3_R_DP")
	)
	(segment
		(start 193.831972 -339.636862)
		(end 166.388542 -339.636862)
		(width 0.1143)
		(layer "B.Cu")
		(net "CLK_100M_DB800ZL_PEX3_S3_R_DP")
	)
	(segment
		(start 266.146788 -339.00237)
		(end 264.73785 -339.943694)
		(width 0.1143)
		(layer "B.Cu")
		(net "CLK_100M_DB800ZL_PEX3_S3_R_DP")
	)
	(segment
		(start 249.57786 -332.729586)
		(end 249.4407 -332.866746)
		(width 0.1143)
		(layer "F.Cu")
		(net "CLK_100M_DB800ZL_PEX2_S3_R_DN")
	)
	(segment
		(start 265.831828 -303.40046)
		(end 265.430508 -303.40046)
		(width 0.1143)
		(layer "F.Cu")
		(net "CLK_100M_DB800ZL_PEX2_S3_R_DN")
	)
	(segment
		(start 262.062468 -303.2633)
		(end 261.661148 -303.2633)
		(width 0.1143)
		(layer "F.Cu")
		(net "CLK_100M_DB800ZL_PEX2_S3_R_DN")
	)
	(segment
		(start 267.565124 -299.903388)
		(end 267.702284 -300.040548)
		(width 0.1143)
		(layer "F.Cu")
		(net "CLK_100M_DB800ZL_PEX2_S3_R_DN")
	)
	(segment
		(start 249.4407 -335.421986)
		(end 249.57786 -335.559146)
		(width 0.1143)
		(layer "F.Cu")
		(net "CLK_100M_DB800ZL_PEX2_S3_R_DN")
	)
	(segment
		(start 267.702284 -301.518828)
		(end 267.565124 -301.655988)
		(width 0.1143)
		(layer "F.Cu")
		(net "CLK_100M_DB800ZL_PEX2_S3_R_DN")
	)
	(segment
		(start 266.370308 -303.2633)
		(end 265.968988 -303.2633)
		(width 0.1143)
		(layer "F.Cu")
		(net "CLK_100M_DB800ZL_PEX2_S3_R_DN")
	)
	(segment
		(start 249.4407 -335.020666)
		(end 249.4407 -335.421986)
		(width 0.1143)
		(layer "F.Cu")
		(net "CLK_100M_DB800ZL_PEX2_S3_R_DN")
	)
	(segment
		(start 260.447028 -303.40046)
		(end 260.045708 -303.40046)
		(width 0.1143)
		(layer "F.Cu")
		(net "CLK_100M_DB800ZL_PEX2_S3_R_DN")
	)
	(segment
		(start 252.094238 -339.152484)
		(end 252.288294 -339.152484)
		(width 0.1143)
		(layer "F.Cu")
		(net "CLK_100M_DB800ZL_PEX2_S3_R_DN")
	)
	(segment
		(start 250.132342 -328.967846)
		(end 250.20651 -329.146916)
		(width 0.1143)
		(layer "F.Cu")
		(net "CLK_100M_DB800ZL_PEX2_S3_R_DN")
	)
	(segment
		(start 262.738108 -303.2633)
		(end 262.600948 -303.40046)
		(width 0.1143)
		(layer "F.Cu")
		(net "CLK_100M_DB800ZL_PEX2_S3_R_DN")
	)
	(segment
		(start 253.55042 -320.682112)
		(end 253.557532 -320.698876)
		(width 0.1143)
		(layer "F.Cu")
		(net "CLK_100M_DB800ZL_PEX2_S3_R_DN")
	)
	(segment
		(start 262.199628 -303.40046)
		(end 262.062468 -303.2633)
		(width 0.1143)
		(layer "F.Cu")
		(net "CLK_100M_DB800ZL_PEX2_S3_R_DN")
	)
	(segment
		(start 251.81052 -338.674964)
		(end 251.81052 -338.868766)
		(width 0.1143)
		(layer "F.Cu")
		(net "CLK_100M_DB800ZL_PEX2_S3_R_DN")
	)
	(segment
		(start 250.003056 -336.867246)
		(end 250.287028 -337.151472)
		(width 0.1143)
		(layer "F.Cu")
		(net "CLK_100M_DB800ZL_PEX2_S3_R_DN")
	)
	(segment
		(start 249.57786 -333.806546)
		(end 249.4407 -333.943706)
		(width 0.1143)
		(layer "F.Cu")
		(net "CLK_100M_DB800ZL_PEX2_S3_R_DN")
	)
	(segment
		(start 267.565124 -296.725848)
		(end 267.565124 -297.57878)
		(width 0.1143)
		(layer "F.Cu")
		(net "CLK_100M_DB800ZL_PEX2_S3_R_DN")
	)
	(segment
		(start 254.095758 -341.154004)
		(end 254.379476 -341.437722)
		(width 0.1143)
		(layer "F.Cu")
		(net "CLK_100M_DB800ZL_PEX2_S3_R_DN")
	)
	(segment
		(start 253.334012 -340.198456)
		(end 253.334012 -340.392258)
		(width 0.1143)
		(layer "F.Cu")
		(net "CLK_100M_DB800ZL_PEX2_S3_R_DN")
	)
	(segment
		(start 267.565124 -302.068484)
		(end 267.132054 -302.501554)
		(width 0.1143)
		(layer "F.Cu")
		(net "CLK_100M_DB800ZL_PEX2_S3_R_DN")
	)
	(segment
		(start 253.05004 -339.91423)
		(end 253.334012 -340.198456)
		(width 0.1143)
		(layer "F.Cu")
		(net "CLK_100M_DB800ZL_PEX2_S3_R_DN")
	)
	(segment
		(start 253.811786 -340.675976)
		(end 254.095758 -340.960202)
		(width 0.1143)
		(layer "F.Cu")
		(net "CLK_100M_DB800ZL_PEX2_S3_R_DN")
	)
	(segment
		(start 249.57786 -335.960466)
		(end 249.4407 -336.097626)
		(width 0.1143)
		(layer "F.Cu")
		(net "CLK_100M_DB800ZL_PEX2_S3_R_DN")
	)
	(segment
		(start 249.57786 -334.482186)
		(end 249.57786 -334.883506)
		(width 0.1143)
		(layer "F.Cu")
		(net "CLK_100M_DB800ZL_PEX2_S3_R_DN")
	)
	(segment
		(start 268.391132 -295.89984)
		(end 267.565124 -296.725848)
		(width 0.1143)
		(layer "F.Cu")
		(net "CLK_100M_DB800ZL_PEX2_S3_R_DN")
	)
	(segment
		(start 251.048774 -337.913218)
		(end 251.048774 -338.10702)
		(width 0.1143)
		(layer "F.Cu")
		(net "CLK_100M_DB800ZL_PEX2_S3_R_DN")
	)
	(segment
		(start 263.276588 -303.40046)
		(end 263.139428 -303.2633)
		(width 0.1143)
		(layer "F.Cu")
		(net "CLK_100M_DB800ZL_PEX2_S3_R_DN")
	)
	(segment
		(start 252.572266 -339.630512)
		(end 252.855984 -339.91423)
		(width 0.1143)
		(layer "F.Cu")
		(net "CLK_100M_DB800ZL_PEX2_S3_R_DN")
	)
	(segment
		(start 261.661148 -303.2633)
		(end 261.523988 -303.40046)
		(width 0.1143)
		(layer "F.Cu")
		(net "CLK_100M_DB800ZL_PEX2_S3_R_DN")
	)
	(segment
		(start 250.053094 -329.51801)
		(end 249.873516 -329.592178)
		(width 0.1143)
		(layer "F.Cu")
		(net "CLK_100M_DB800ZL_PEX2_S3_R_DN")
	)
	(segment
		(start 260.045708 -303.40046)
		(end 259.908548 -303.2633)
		(width 0.1143)
		(layer "F.Cu")
		(net "CLK_100M_DB800ZL_PEX2_S3_R_DN")
	)
	(segment
		(start 253.6698 -320.101214)
		(end 253.577344 -320.617088)
		(width 0.1143)
		(layer "F.Cu")
		(net "CLK_100M_DB800ZL_PEX2_S3_R_DN")
	)
	(segment
		(start 259.461 -303.2633)
		(end 257.543808 -305.180746)
		(width 0.1143)
		(layer "F.Cu")
		(net "CLK_100M_DB800ZL_PEX2_S3_R_DN")
	)
	(segment
		(start 254.379476 -341.437722)
		(end 256.129282 -341.437722)
		(width 0.1143)
		(layer "F.Cu")
		(net "CLK_100M_DB800ZL_PEX2_S3_R_DN")
	)
	(segment
		(start 265.293348 -303.2633)
		(end 264.892028 -303.2633)
		(width 0.1143)
		(layer "F.Cu")
		(net "CLK_100M_DB800ZL_PEX2_S3_R_DN")
	)
	(segment
		(start 259.908548 -303.2633)
		(end 259.461 -303.2633)
		(width 0.1143)
		(layer "F.Cu")
		(net "CLK_100M_DB800ZL_PEX2_S3_R_DN")
	)
	(segment
		(start 266.654026 -302.979582)
		(end 266.370308 -303.2633)
		(width 0.1143)
		(layer "F.Cu")
		(net "CLK_100M_DB800ZL_PEX2_S3_R_DN")
	)
	(segment
		(start 249.4407 -333.943706)
		(end 249.4407 -334.345026)
		(width 0.1143)
		(layer "F.Cu")
		(net "CLK_100M_DB800ZL_PEX2_S3_R_DN")
	)
	(segment
		(start 267.565124 -301.655988)
		(end 267.565124 -302.068484)
		(width 0.1143)
		(layer "F.Cu")
		(net "CLK_100M_DB800ZL_PEX2_S3_R_DN")
	)
	(segment
		(start 250.287028 -337.151472)
		(end 250.287028 -337.345274)
		(width 0.1143)
		(layer "F.Cu")
		(net "CLK_100M_DB800ZL_PEX2_S3_R_DN")
	)
	(segment
		(start 249.57786 -334.883506)
		(end 249.4407 -335.020666)
		(width 0.1143)
		(layer "F.Cu")
		(net "CLK_100M_DB800ZL_PEX2_S3_R_DN")
	)
	(segment
		(start 253.61773 -340.675976)
		(end 253.811786 -340.675976)
		(width 0.1143)
		(layer "F.Cu")
		(net "CLK_100M_DB800ZL_PEX2_S3_R_DN")
	)
	(segment
		(start 267.702284 -301.117508)
		(end 267.702284 -301.518828)
		(width 0.1143)
		(layer "F.Cu")
		(net "CLK_100M_DB800ZL_PEX2_S3_R_DN")
	)
	(segment
		(start 256.129282 -341.437722)
		(end 256.370582 -341.196422)
		(width 0.1143)
		(layer "F.Cu")
		(net "CLK_100M_DB800ZL_PEX2_S3_R_DN")
	)
	(segment
		(start 249.4407 -330.637388)
		(end 249.4407 -332.191106)
		(width 0.1143)
		(layer "F.Cu")
		(net "CLK_100M_DB800ZL_PEX2_S3_R_DN")
	)
	(segment
		(start 252.855984 -339.91423)
		(end 253.05004 -339.91423)
		(width 0.1143)
		(layer "F.Cu")
		(net "CLK_100M_DB800ZL_PEX2_S3_R_DN")
	)
	(segment
		(start 249.4407 -334.345026)
		(end 249.57786 -334.482186)
		(width 0.1143)
		(layer "F.Cu")
		(net "CLK_100M_DB800ZL_PEX2_S3_R_DN")
	)
	(segment
		(start 254.095758 -340.960202)
		(end 254.095758 -341.154004)
		(width 0.1143)
		(layer "F.Cu")
		(net "CLK_100M_DB800ZL_PEX2_S3_R_DN")
	)
	(segment
		(start 250.287028 -337.345274)
		(end 250.570746 -337.628992)
		(width 0.1143)
		(layer "F.Cu")
		(net "CLK_100M_DB800ZL_PEX2_S3_R_DN")
	)
	(segment
		(start 249.4407 -333.268066)
		(end 249.57786 -333.405226)
		(width 0.1143)
		(layer "F.Cu")
		(net "CLK_100M_DB800ZL_PEX2_S3_R_DN")
	)
	(segment
		(start 264.892028 -303.2633)
		(end 264.754868 -303.40046)
		(width 0.1143)
		(layer "F.Cu")
		(net "CLK_100M_DB800ZL_PEX2_S3_R_DN")
	)
	(segment
		(start 261.523988 -303.40046)
		(end 261.122668 -303.40046)
		(width 0.1143)
		(layer "F.Cu")
		(net "CLK_100M_DB800ZL_PEX2_S3_R_DN")
	)
	(segment
		(start 252.572266 -339.43671)
		(end 252.572266 -339.630512)
		(width 0.1143)
		(layer "F.Cu")
		(net "CLK_100M_DB800ZL_PEX2_S3_R_DN")
	)
	(segment
		(start 263.677908 -303.40046)
		(end 263.276588 -303.40046)
		(width 0.1143)
		(layer "F.Cu")
		(net "CLK_100M_DB800ZL_PEX2_S3_R_DN")
	)
	(segment
		(start 249.57786 -333.405226)
		(end 249.57786 -333.806546)
		(width 0.1143)
		(layer "F.Cu")
		(net "CLK_100M_DB800ZL_PEX2_S3_R_DN")
	)
	(segment
		(start 249.57786 -335.559146)
		(end 249.57786 -335.960466)
		(width 0.1143)
		(layer "F.Cu")
		(net "CLK_100M_DB800ZL_PEX2_S3_R_DN")
	)
	(segment
		(start 249.873516 -329.592178)
		(end 249.4407 -330.637388)
		(width 0.1143)
		(layer "F.Cu")
		(net "CLK_100M_DB800ZL_PEX2_S3_R_DN")
	)
	(segment
		(start 249.57786 -332.328266)
		(end 249.57786 -332.729586)
		(width 0.1143)
		(layer "F.Cu")
		(net "CLK_100M_DB800ZL_PEX2_S3_R_DN")
	)
	(segment
		(start 266.847828 -302.979582)
		(end 266.654026 -302.979582)
		(width 0.1143)
		(layer "F.Cu")
		(net "CLK_100M_DB800ZL_PEX2_S3_R_DN")
	)
	(segment
		(start 250.20651 -329.146916)
		(end 250.053094 -329.51801)
		(width 0.1143)
		(layer "F.Cu")
		(net "CLK_100M_DB800ZL_PEX2_S3_R_DN")
	)
	(segment
		(start 267.132054 -302.69561)
		(end 266.847828 -302.979582)
		(width 0.1143)
		(layer "F.Cu")
		(net "CLK_100M_DB800ZL_PEX2_S3_R_DN")
	)
	(segment
		(start 267.565124 -298.25442)
		(end 267.565124 -299.903388)
		(width 0.1143)
		(layer "F.Cu")
		(net "CLK_100M_DB800ZL_PEX2_S3_R_DN")
	)
	(segment
		(start 257.543808 -305.180746)
		(end 253.6698 -314.533026)
		(width 0.1143)
		(layer "F.Cu")
		(net "CLK_100M_DB800ZL_PEX2_S3_R_DN")
	)
	(segment
		(start 269.049754 -295.89984)
		(end 268.391132 -295.89984)
		(width 0.1143)
		(layer "F.Cu")
		(net "CLK_100M_DB800ZL_PEX2_S3_R_DN")
	)
	(segment
		(start 250.570746 -337.628992)
		(end 250.764802 -337.628992)
		(width 0.1143)
		(layer "F.Cu")
		(net "CLK_100M_DB800ZL_PEX2_S3_R_DN")
	)
	(segment
		(start 267.565124 -300.579028)
		(end 267.565124 -300.980348)
		(width 0.1143)
		(layer "F.Cu")
		(net "CLK_100M_DB800ZL_PEX2_S3_R_DN")
	)
	(segment
		(start 253.557532 -320.698876)
		(end 250.132342 -328.967846)
		(width 0.1143)
		(layer "F.Cu")
		(net "CLK_100M_DB800ZL_PEX2_S3_R_DN")
	)
	(segment
		(start 264.754868 -303.40046)
		(end 264.353548 -303.40046)
		(width 0.1143)
		(layer "F.Cu")
		(net "CLK_100M_DB800ZL_PEX2_S3_R_DN")
	)
	(segment
		(start 249.4407 -336.097626)
		(end 249.4407 -336.498946)
		(width 0.1143)
		(layer "F.Cu")
		(net "CLK_100M_DB800ZL_PEX2_S3_R_DN")
	)
	(segment
		(start 261.122668 -303.40046)
		(end 260.985508 -303.2633)
		(width 0.1143)
		(layer "F.Cu")
		(net "CLK_100M_DB800ZL_PEX2_S3_R_DN")
	)
	(segment
		(start 267.565124 -297.57878)
		(end 267.702284 -297.71594)
		(width 0.1143)
		(layer "F.Cu")
		(net "CLK_100M_DB800ZL_PEX2_S3_R_DN")
	)
	(segment
		(start 251.81052 -338.868766)
		(end 252.094238 -339.152484)
		(width 0.1143)
		(layer "F.Cu")
		(net "CLK_100M_DB800ZL_PEX2_S3_R_DN")
	)
	(segment
		(start 267.702284 -298.11726)
		(end 267.565124 -298.25442)
		(width 0.1143)
		(layer "F.Cu")
		(net "CLK_100M_DB800ZL_PEX2_S3_R_DN")
	)
	(segment
		(start 249.4407 -336.498946)
		(end 249.809 -336.867246)
		(width 0.1143)
		(layer "F.Cu")
		(net "CLK_100M_DB800ZL_PEX2_S3_R_DN")
	)
	(segment
		(start 267.565124 -300.980348)
		(end 267.702284 -301.117508)
		(width 0.1143)
		(layer "F.Cu")
		(net "CLK_100M_DB800ZL_PEX2_S3_R_DN")
	)
	(segment
		(start 260.584188 -303.2633)
		(end 260.447028 -303.40046)
		(width 0.1143)
		(layer "F.Cu")
		(net "CLK_100M_DB800ZL_PEX2_S3_R_DN")
	)
	(segment
		(start 264.353548 -303.40046)
		(end 264.216388 -303.2633)
		(width 0.1143)
		(layer "F.Cu")
		(net "CLK_100M_DB800ZL_PEX2_S3_R_DN")
	)
	(segment
		(start 253.334012 -340.392258)
		(end 253.61773 -340.675976)
		(width 0.1143)
		(layer "F.Cu")
		(net "CLK_100M_DB800ZL_PEX2_S3_R_DN")
	)
	(segment
		(start 249.809 -336.867246)
		(end 250.003056 -336.867246)
		(width 0.1143)
		(layer "F.Cu")
		(net "CLK_100M_DB800ZL_PEX2_S3_R_DN")
	)
	(segment
		(start 264.216388 -303.2633)
		(end 263.815068 -303.2633)
		(width 0.1143)
		(layer "F.Cu")
		(net "CLK_100M_DB800ZL_PEX2_S3_R_DN")
	)
	(segment
		(start 267.132054 -302.501554)
		(end 267.132054 -302.69561)
		(width 0.1143)
		(layer "F.Cu")
		(net "CLK_100M_DB800ZL_PEX2_S3_R_DN")
	)
	(segment
		(start 260.985508 -303.2633)
		(end 260.584188 -303.2633)
		(width 0.1143)
		(layer "F.Cu")
		(net "CLK_100M_DB800ZL_PEX2_S3_R_DN")
	)
	(segment
		(start 263.815068 -303.2633)
		(end 263.677908 -303.40046)
		(width 0.1143)
		(layer "F.Cu")
		(net "CLK_100M_DB800ZL_PEX2_S3_R_DN")
	)
	(segment
		(start 249.4407 -332.191106)
		(end 249.57786 -332.328266)
		(width 0.1143)
		(layer "F.Cu")
		(net "CLK_100M_DB800ZL_PEX2_S3_R_DN")
	)
	(segment
		(start 263.139428 -303.2633)
		(end 262.738108 -303.2633)
		(width 0.1143)
		(layer "F.Cu")
		(net "CLK_100M_DB800ZL_PEX2_S3_R_DN")
	)
	(segment
		(start 250.764802 -337.628992)
		(end 251.048774 -337.913218)
		(width 0.1143)
		(layer "F.Cu")
		(net "CLK_100M_DB800ZL_PEX2_S3_R_DN")
	)
	(segment
		(start 249.4407 -332.866746)
		(end 249.4407 -333.268066)
		(width 0.1143)
		(layer "F.Cu")
		(net "CLK_100M_DB800ZL_PEX2_S3_R_DN")
	)
	(segment
		(start 253.6698 -314.533026)
		(end 253.6698 -320.101214)
		(width 0.1143)
		(layer "F.Cu")
		(net "CLK_100M_DB800ZL_PEX2_S3_R_DN")
	)
	(segment
		(start 252.288294 -339.152484)
		(end 252.572266 -339.43671)
		(width 0.1143)
		(layer "F.Cu")
		(net "CLK_100M_DB800ZL_PEX2_S3_R_DN")
	)
	(segment
		(start 265.430508 -303.40046)
		(end 265.293348 -303.2633)
		(width 0.1143)
		(layer "F.Cu")
		(net "CLK_100M_DB800ZL_PEX2_S3_R_DN")
	)
	(segment
		(start 262.600948 -303.40046)
		(end 262.199628 -303.40046)
		(width 0.1143)
		(layer "F.Cu")
		(net "CLK_100M_DB800ZL_PEX2_S3_R_DN")
	)
	(segment
		(start 267.702284 -297.71594)
		(end 267.702284 -298.11726)
		(width 0.1143)
		(layer "F.Cu")
		(net "CLK_100M_DB800ZL_PEX2_S3_R_DN")
	)
	(segment
		(start 251.048774 -338.10702)
		(end 251.332492 -338.390738)
		(width 0.1143)
		(layer "F.Cu")
		(net "CLK_100M_DB800ZL_PEX2_S3_R_DN")
	)
	(segment
		(start 267.702284 -300.040548)
		(end 267.702284 -300.441868)
		(width 0.1143)
		(layer "F.Cu")
		(net "CLK_100M_DB800ZL_PEX2_S3_R_DN")
	)
	(segment
		(start 267.702284 -300.441868)
		(end 267.565124 -300.579028)
		(width 0.1143)
		(layer "F.Cu")
		(net "CLK_100M_DB800ZL_PEX2_S3_R_DN")
	)
	(segment
		(start 251.526548 -338.390738)
		(end 251.81052 -338.674964)
		(width 0.1143)
		(layer "F.Cu")
		(net "CLK_100M_DB800ZL_PEX2_S3_R_DN")
	)
	(segment
		(start 251.332492 -338.390738)
		(end 251.526548 -338.390738)
		(width 0.1143)
		(layer "F.Cu")
		(net "CLK_100M_DB800ZL_PEX2_S3_R_DN")
	)
	(segment
		(start 253.577344 -320.617088)
		(end 253.55042 -320.682112)
		(width 0.1143)
		(layer "F.Cu")
		(net "CLK_100M_DB800ZL_PEX2_S3_R_DN")
	)
	(segment
		(start 265.968988 -303.2633)
		(end 265.831828 -303.40046)
		(width 0.1143)
		(layer "F.Cu")
		(net "CLK_100M_DB800ZL_PEX2_S3_R_DN")
	)
	(via
		(at 256.370582 -341.196422)
		(size 0.508)
		(drill 0.254)
		(layers "F.Cu" "B.Cu")
		(net "CLK_100M_DB800ZL_PEX2_S3_R_DN")
	)
	(segment
		(start 148.48332 -353.51593)
		(end 148.79574 -353.25939)
		(width 0.1143)
		(layer "B.Cu")
		(net "CLK_100M_DB800ZL_PEX2_S3_R_DN")
	)
	(segment
		(start 146.790918 -355.082094)
		(end 146.809968 -354.889054)
		(width 0.1143)
		(layer "B.Cu")
		(net "CLK_100M_DB800ZL_PEX2_S3_R_DN")
	)
	(segment
		(start 160.709356 -343.661492)
		(end 160.70961 -343.661492)
		(width 0.1143)
		(layer "B.Cu")
		(net "CLK_100M_DB800ZL_PEX2_S3_R_DN")
	)
	(segment
		(start 146.809968 -354.889054)
		(end 147.122388 -354.632514)
		(width 0.1143)
		(layer "B.Cu")
		(net "CLK_100M_DB800ZL_PEX2_S3_R_DN")
	)
	(segment
		(start 256.129282 -341.437722)
		(end 256.370582 -341.196422)
		(width 0.1143)
		(layer "B.Cu")
		(net "CLK_100M_DB800ZL_PEX2_S3_R_DN")
	)
	(segment
		(start 164.337238 -341.235538)
		(end 166.58209 -340.30539)
		(width 0.1143)
		(layer "B.Cu")
		(net "CLK_100M_DB800ZL_PEX2_S3_R_DN")
	)
	(segment
		(start 199.079866 -335.6737)
		(end 220.319854 -335.6737)
		(width 0.1143)
		(layer "B.Cu")
		(net "CLK_100M_DB800ZL_PEX2_S3_R_DN")
	)
	(segment
		(start 148.79574 -353.25939)
		(end 148.98878 -353.27844)
		(width 0.1143)
		(layer "B.Cu")
		(net "CLK_100M_DB800ZL_PEX2_S3_R_DN")
	)
	(segment
		(start 108.519468 -361.1626)
		(end 113.65738 -356.024688)
		(width 0.1143)
		(layer "B.Cu")
		(net "CLK_100M_DB800ZL_PEX2_S3_R_DN")
	)
	(segment
		(start 113.65738 -356.024688)
		(end 145.642076 -356.024688)
		(width 0.1143)
		(layer "B.Cu")
		(net "CLK_100M_DB800ZL_PEX2_S3_R_DN")
	)
	(segment
		(start 106.223562 -359.124758)
		(end 105.893362 -359.454958)
		(width 0.1143)
		(layer "B.Cu")
		(net "CLK_100M_DB800ZL_PEX2_S3_R_DN")
	)
	(segment
		(start 148.46427 -353.70897)
		(end 148.48332 -353.51593)
		(width 0.1143)
		(layer "B.Cu")
		(net "CLK_100M_DB800ZL_PEX2_S3_R_DN")
	)
	(segment
		(start 149.300946 -353.022408)
		(end 149.319996 -352.829368)
		(width 0.1143)
		(layer "B.Cu")
		(net "CLK_100M_DB800ZL_PEX2_S3_R_DN")
	)
	(segment
		(start 105.893362 -359.454958)
		(end 105.893362 -360.553508)
		(width 0.1143)
		(layer "B.Cu")
		(net "CLK_100M_DB800ZL_PEX2_S3_R_DN")
	)
	(segment
		(start 149.825456 -352.591878)
		(end 160.709356 -343.661492)
		(width 0.1143)
		(layer "B.Cu")
		(net "CLK_100M_DB800ZL_PEX2_S3_R_DN")
	)
	(segment
		(start 147.122388 -354.632514)
		(end 147.315428 -354.651564)
		(width 0.1143)
		(layer "B.Cu")
		(net "CLK_100M_DB800ZL_PEX2_S3_R_DN")
	)
	(segment
		(start 194.448176 -340.30539)
		(end 199.079866 -335.6737)
		(width 0.1143)
		(layer "B.Cu")
		(net "CLK_100M_DB800ZL_PEX2_S3_R_DN")
	)
	(segment
		(start 149.632416 -352.572828)
		(end 149.825456 -352.591878)
		(width 0.1143)
		(layer "B.Cu")
		(net "CLK_100M_DB800ZL_PEX2_S3_R_DN")
	)
	(segment
		(start 146.478752 -355.338126)
		(end 146.790918 -355.082094)
		(width 0.1143)
		(layer "B.Cu")
		(net "CLK_100M_DB800ZL_PEX2_S3_R_DN")
	)
	(segment
		(start 148.152104 -353.965002)
		(end 148.46427 -353.70897)
		(width 0.1143)
		(layer "B.Cu")
		(net "CLK_100M_DB800ZL_PEX2_S3_R_DN")
	)
	(segment
		(start 220.319854 -335.6737)
		(end 225.349308 -340.703154)
		(width 0.1143)
		(layer "B.Cu")
		(net "CLK_100M_DB800ZL_PEX2_S3_R_DN")
	)
	(segment
		(start 145.642076 -356.024688)
		(end 145.954242 -355.768656)
		(width 0.1143)
		(layer "B.Cu")
		(net "CLK_100M_DB800ZL_PEX2_S3_R_DN")
	)
	(segment
		(start 254.189484 -340.703154)
		(end 254.924052 -341.437722)
		(width 0.1143)
		(layer "B.Cu")
		(net "CLK_100M_DB800ZL_PEX2_S3_R_DN")
	)
	(segment
		(start 145.954242 -355.768656)
		(end 145.973292 -355.575616)
		(width 0.1143)
		(layer "B.Cu")
		(net "CLK_100M_DB800ZL_PEX2_S3_R_DN")
	)
	(segment
		(start 147.959064 -353.945952)
		(end 148.152104 -353.965002)
		(width 0.1143)
		(layer "B.Cu")
		(net "CLK_100M_DB800ZL_PEX2_S3_R_DN")
	)
	(segment
		(start 146.285712 -355.319076)
		(end 146.478752 -355.338126)
		(width 0.1143)
		(layer "B.Cu")
		(net "CLK_100M_DB800ZL_PEX2_S3_R_DN")
	)
	(segment
		(start 225.349308 -340.703154)
		(end 254.189484 -340.703154)
		(width 0.1143)
		(layer "B.Cu")
		(net "CLK_100M_DB800ZL_PEX2_S3_R_DN")
	)
	(segment
		(start 160.70961 -343.661492)
		(end 160.72358 -343.650062)
		(width 0.1143)
		(layer "B.Cu")
		(net "CLK_100M_DB800ZL_PEX2_S3_R_DN")
	)
	(segment
		(start 106.502454 -361.1626)
		(end 108.519468 -361.1626)
		(width 0.1143)
		(layer "B.Cu")
		(net "CLK_100M_DB800ZL_PEX2_S3_R_DN")
	)
	(segment
		(start 147.315428 -354.651564)
		(end 147.627594 -354.395532)
		(width 0.1143)
		(layer "B.Cu")
		(net "CLK_100M_DB800ZL_PEX2_S3_R_DN")
	)
	(segment
		(start 149.319996 -352.829368)
		(end 149.632416 -352.572828)
		(width 0.1143)
		(layer "B.Cu")
		(net "CLK_100M_DB800ZL_PEX2_S3_R_DN")
	)
	(segment
		(start 160.72358 -343.650062)
		(end 164.337238 -341.235538)
		(width 0.1143)
		(layer "B.Cu")
		(net "CLK_100M_DB800ZL_PEX2_S3_R_DN")
	)
	(segment
		(start 147.627594 -354.395532)
		(end 147.646644 -354.202492)
		(width 0.1143)
		(layer "B.Cu")
		(net "CLK_100M_DB800ZL_PEX2_S3_R_DN")
	)
	(segment
		(start 147.646644 -354.202492)
		(end 147.959064 -353.945952)
		(width 0.1143)
		(layer "B.Cu")
		(net "CLK_100M_DB800ZL_PEX2_S3_R_DN")
	)
	(segment
		(start 254.924052 -341.437722)
		(end 256.129282 -341.437722)
		(width 0.1143)
		(layer "B.Cu")
		(net "CLK_100M_DB800ZL_PEX2_S3_R_DN")
	)
	(segment
		(start 105.893362 -360.553508)
		(end 106.502454 -361.1626)
		(width 0.1143)
		(layer "B.Cu")
		(net "CLK_100M_DB800ZL_PEX2_S3_R_DN")
	)
	(segment
		(start 166.58209 -340.30539)
		(end 194.448176 -340.30539)
		(width 0.1143)
		(layer "B.Cu")
		(net "CLK_100M_DB800ZL_PEX2_S3_R_DN")
	)
	(segment
		(start 145.973292 -355.575616)
		(end 146.285712 -355.319076)
		(width 0.1143)
		(layer "B.Cu")
		(net "CLK_100M_DB800ZL_PEX2_S3_R_DN")
	)
	(segment
		(start 148.98878 -353.27844)
		(end 149.300946 -353.022408)
		(width 0.1143)
		(layer "B.Cu")
		(net "CLK_100M_DB800ZL_PEX2_S3_R_DN")
	)
	(segment
		(start 259.308346 -302.895)
		(end 257.231388 -304.971958)
		(width 0.1143)
		(layer "F.Cu")
		(net "CLK_100M_DB800ZL_PEX2_S3_R_DP")
	)
	(segment
		(start 249.0724 -330.563982)
		(end 249.0724 -336.6516)
		(width 0.1143)
		(layer "F.Cu")
		(net "CLK_100M_DB800ZL_PEX2_S3_R_DP")
	)
	(segment
		(start 269.578074 -295.4782)
		(end 268.291818 -295.4782)
		(width 0.1143)
		(layer "F.Cu")
		(net "CLK_100M_DB800ZL_PEX2_S3_R_DP")
	)
	(segment
		(start 267.196824 -301.91583)
		(end 266.217654 -302.895)
		(width 0.1143)
		(layer "F.Cu")
		(net "CLK_100M_DB800ZL_PEX2_S3_R_DP")
	)
	(segment
		(start 256.116582 -341.806022)
		(end 256.370582 -342.060022)
		(width 0.1143)
		(layer "F.Cu")
		(net "CLK_100M_DB800ZL_PEX2_S3_R_DP")
	)
	(segment
		(start 267.196824 -296.573194)
		(end 267.196824 -301.91583)
		(width 0.1143)
		(layer "F.Cu")
		(net "CLK_100M_DB800ZL_PEX2_S3_R_DP")
	)
	(segment
		(start 253.3015 -320.068448)
		(end 253.214632 -320.552318)
		(width 0.1143)
		(layer "F.Cu")
		(net "CLK_100M_DB800ZL_PEX2_S3_R_DP")
	)
	(segment
		(start 266.217654 -302.895)
		(end 259.308346 -302.895)
		(width 0.1143)
		(layer "F.Cu")
		(net "CLK_100M_DB800ZL_PEX2_S3_R_DP")
	)
	(segment
		(start 253.214632 -320.552318)
		(end 253.217172 -320.557398)
		(width 0.1143)
		(layer "F.Cu")
		(net "CLK_100M_DB800ZL_PEX2_S3_R_DP")
	)
	(segment
		(start 253.3015 -314.45962)
		(end 253.3015 -320.068448)
		(width 0.1143)
		(layer "F.Cu")
		(net "CLK_100M_DB800ZL_PEX2_S3_R_DP")
	)
	(segment
		(start 249.0724 -336.6516)
		(end 254.226822 -341.806022)
		(width 0.1143)
		(layer "F.Cu")
		(net "CLK_100M_DB800ZL_PEX2_S3_R_DP")
	)
	(segment
		(start 254.226822 -341.806022)
		(end 256.116582 -341.806022)
		(width 0.1143)
		(layer "F.Cu")
		(net "CLK_100M_DB800ZL_PEX2_S3_R_DP")
	)
	(segment
		(start 269.999714 -295.89984)
		(end 269.578074 -295.4782)
		(width 0.1143)
		(layer "F.Cu")
		(net "CLK_100M_DB800ZL_PEX2_S3_R_DP")
	)
	(segment
		(start 257.231388 -304.971958)
		(end 253.3015 -314.45962)
		(width 0.1143)
		(layer "F.Cu")
		(net "CLK_100M_DB800ZL_PEX2_S3_R_DP")
	)
	(segment
		(start 253.217172 -320.557398)
		(end 249.0724 -330.563982)
		(width 0.1143)
		(layer "F.Cu")
		(net "CLK_100M_DB800ZL_PEX2_S3_R_DP")
	)
	(segment
		(start 268.291818 -295.4782)
		(end 267.196824 -296.573194)
		(width 0.1143)
		(layer "F.Cu")
		(net "CLK_100M_DB800ZL_PEX2_S3_R_DP")
	)
	(via
		(at 256.370582 -342.060022)
		(size 0.508)
		(drill 0.254)
		(layers "F.Cu" "B.Cu")
		(net "CLK_100M_DB800ZL_PEX2_S3_R_DP")
	)
	(segment
		(start 108.672122 -361.5309)
		(end 106.3498 -361.5309)
		(width 0.1143)
		(layer "B.Cu")
		(net "CLK_100M_DB800ZL_PEX2_S3_R_DP")
	)
	(segment
		(start 106.3498 -361.5309)
		(end 105.525062 -360.706162)
		(width 0.1143)
		(layer "B.Cu")
		(net "CLK_100M_DB800ZL_PEX2_S3_R_DP")
	)
	(segment
		(start 220.1672 -336.042)
		(end 199.23252 -336.042)
		(width 0.1143)
		(layer "B.Cu")
		(net "CLK_100M_DB800ZL_PEX2_S3_R_DP")
	)
	(segment
		(start 256.370582 -342.060022)
		(end 256.116582 -341.806022)
		(width 0.1143)
		(layer "B.Cu")
		(net "CLK_100M_DB800ZL_PEX2_S3_R_DP")
	)
	(segment
		(start 254.771398 -341.806022)
		(end 254.03683 -341.071454)
		(width 0.1143)
		(layer "B.Cu")
		(net "CLK_100M_DB800ZL_PEX2_S3_R_DP")
	)
	(segment
		(start 199.23252 -336.042)
		(end 194.60083 -340.67369)
		(width 0.1143)
		(layer "B.Cu")
		(net "CLK_100M_DB800ZL_PEX2_S3_R_DP")
	)
	(segment
		(start 160.94329 -343.94648)
		(end 160.94329 -343.946226)
		(width 0.1143)
		(layer "B.Cu")
		(net "CLK_100M_DB800ZL_PEX2_S3_R_DP")
	)
	(segment
		(start 105.525062 -360.706162)
		(end 105.525062 -359.442258)
		(width 0.1143)
		(layer "B.Cu")
		(net "CLK_100M_DB800ZL_PEX2_S3_R_DP")
	)
	(segment
		(start 113.810034 -356.392988)
		(end 108.672122 -361.5309)
		(width 0.1143)
		(layer "B.Cu")
		(net "CLK_100M_DB800ZL_PEX2_S3_R_DP")
	)
	(segment
		(start 254.03683 -341.071454)
		(end 225.196654 -341.071454)
		(width 0.1143)
		(layer "B.Cu")
		(net "CLK_100M_DB800ZL_PEX2_S3_R_DP")
	)
	(segment
		(start 194.60083 -340.67369)
		(end 166.655496 -340.67369)
		(width 0.1143)
		(layer "B.Cu")
		(net "CLK_100M_DB800ZL_PEX2_S3_R_DP")
	)
	(segment
		(start 160.94329 -343.946226)
		(end 145.773902 -356.392988)
		(width 0.1143)
		(layer "B.Cu")
		(net "CLK_100M_DB800ZL_PEX2_S3_R_DP")
	)
	(segment
		(start 225.196654 -341.071454)
		(end 220.1672 -336.042)
		(width 0.1143)
		(layer "B.Cu")
		(net "CLK_100M_DB800ZL_PEX2_S3_R_DP")
	)
	(segment
		(start 105.525062 -359.442258)
		(end 105.207562 -359.124758)
		(width 0.1143)
		(layer "B.Cu")
		(net "CLK_100M_DB800ZL_PEX2_S3_R_DP")
	)
	(segment
		(start 164.511736 -341.561928)
		(end 160.94329 -343.94648)
		(width 0.1143)
		(layer "B.Cu")
		(net "CLK_100M_DB800ZL_PEX2_S3_R_DP")
	)
	(segment
		(start 256.116582 -341.806022)
		(end 254.771398 -341.806022)
		(width 0.1143)
		(layer "B.Cu")
		(net "CLK_100M_DB800ZL_PEX2_S3_R_DP")
	)
	(segment
		(start 145.773902 -356.392988)
		(end 113.810034 -356.392988)
		(width 0.1143)
		(layer "B.Cu")
		(net "CLK_100M_DB800ZL_PEX2_S3_R_DP")
	)
	(segment
		(start 166.655496 -340.67369)
		(end 164.511736 -341.561928)
		(width 0.1143)
		(layer "B.Cu")
		(net "CLK_100M_DB800ZL_PEX2_S3_R_DP")
	)
	(segment
		(start 318.929512 -301.02048)
		(end 318.929512 -301.83963)
		(width 0.13208)
		(layer "F.Cu")
		(net "RST_PEX2_S3_PERST_R_N")
	)
	(segment
		(start 304.199798 -306.349908)
		(end 303.724818 -306.824888)
		(width 0.13208)
		(layer "F.Cu")
		(net "RST_PEX2_S3_PERST_R_N")
	)
	(via
		(at 318.929512 -301.83963)
		(size 0.508)
		(drill 0.254)
		(layers "F.Cu" "B.Cu")
		(net "RST_PEX2_S3_PERST_R_N")
	)
	(via
		(at 303.724818 -306.824888)
		(size 0.4064)
		(drill 0.2032)
		(layers "F.Cu" "B.Cu")
		(net "RST_PEX2_S3_PERST_R_N")
	)
	(segment
		(start 305.025044 -305.3588)
		(end 304.310542 -305.3588)
		(width 0.13208)
		(layer "B.Cu")
		(net "RST_PEX2_S3_PERST_R_N")
	)
	(segment
		(start 318.677544 -302.091598)
		(end 318.506856 -302.091598)
		(width 0.13208)
		(layer "B.Cu")
		(net "RST_PEX2_S3_PERST_R_N")
	)
	(segment
		(start 304.183542 -306.366164)
		(end 303.724818 -306.824888)
		(width 0.13208)
		(layer "B.Cu")
		(net "RST_PEX2_S3_PERST_R_N")
	)
	(segment
		(start 304.183542 -305.4858)
		(end 304.183542 -306.366164)
		(width 0.13208)
		(layer "B.Cu")
		(net "RST_PEX2_S3_PERST_R_N")
	)
	(segment
		(start 318.929512 -301.83963)
		(end 318.677544 -302.091598)
		(width 0.13208)
		(layer "B.Cu")
		(net "RST_PEX2_S3_PERST_R_N")
	)
	(segment
		(start 315.671454 -304.927)
		(end 305.456844 -304.927)
		(width 0.13208)
		(layer "B.Cu")
		(net "RST_PEX2_S3_PERST_R_N")
	)
	(segment
		(start 318.506856 -302.091598)
		(end 315.671454 -304.927)
		(width 0.13208)
		(layer "B.Cu")
		(net "RST_PEX2_S3_PERST_R_N")
	)
	(segment
		(start 305.456844 -304.927)
		(end 305.025044 -305.3588)
		(width 0.13208)
		(layer "B.Cu")
		(net "RST_PEX2_S3_PERST_R_N")
	)
	(segment
		(start 304.310542 -305.3588)
		(end 304.183542 -305.4858)
		(width 0.13208)
		(layer "B.Cu")
		(net "RST_PEX2_S3_PERST_R_N")
	)
	(segment
		(start 140.8303 -314.410852)
		(end 138.883136 -316.35827)
		(width 0.1143)
		(layer "F.Cu")
		(net "CLK_100M_DB800ZL_PEX1_S3_R_DN")
	)
	(segment
		(start 151.46528 -296.725848)
		(end 151.46528 -300.419008)
		(width 0.1143)
		(layer "F.Cu")
		(net "CLK_100M_DB800ZL_PEX1_S3_R_DN")
	)
	(segment
		(start 110.278672 -352.54438)
		(end 110.278672 -352.9457)
		(width 0.1143)
		(layer "F.Cu")
		(net "CLK_100M_DB800ZL_PEX1_S3_R_DN")
	)
	(segment
		(start 145.936208 -303.40046)
		(end 145.534888 -303.40046)
		(width 0.1143)
		(layer "F.Cu")
		(net "CLK_100M_DB800ZL_PEX1_S3_R_DN")
	)
	(segment
		(start 150.244048 -303.40046)
		(end 149.842728 -303.40046)
		(width 0.1143)
		(layer "F.Cu")
		(net "CLK_100M_DB800ZL_PEX1_S3_R_DN")
	)
	(segment
		(start 140.96746 -313.43981)
		(end 140.8303 -313.57697)
		(width 0.1143)
		(layer "F.Cu")
		(net "CLK_100M_DB800ZL_PEX1_S3_R_DN")
	)
	(segment
		(start 110.141512 -350.2533)
		(end 110.278672 -350.39046)
		(width 0.1143)
		(layer "F.Cu")
		(net "CLK_100M_DB800ZL_PEX1_S3_R_DN")
	)
	(segment
		(start 147.150328 -303.2633)
		(end 147.013168 -303.40046)
		(width 0.1143)
		(layer "F.Cu")
		(net "CLK_100M_DB800ZL_PEX1_S3_R_DN")
	)
	(segment
		(start 144.859248 -303.40046)
		(end 144.457928 -303.40046)
		(width 0.1143)
		(layer "F.Cu")
		(net "CLK_100M_DB800ZL_PEX1_S3_R_DN")
	)
	(segment
		(start 150.782528 -303.2633)
		(end 150.381208 -303.2633)
		(width 0.1143)
		(layer "F.Cu")
		(net "CLK_100M_DB800ZL_PEX1_S3_R_DN")
	)
	(segment
		(start 110.278672 -349.71482)
		(end 110.141512 -349.85198)
		(width 0.1143)
		(layer "F.Cu")
		(net "CLK_100M_DB800ZL_PEX1_S3_R_DN")
	)
	(segment
		(start 151.60244 -300.957488)
		(end 151.46528 -301.094648)
		(width 0.1143)
		(layer "F.Cu")
		(net "CLK_100M_DB800ZL_PEX1_S3_R_DN")
	)
	(segment
		(start 148.090128 -303.40046)
		(end 147.688808 -303.40046)
		(width 0.1143)
		(layer "F.Cu")
		(net "CLK_100M_DB800ZL_PEX1_S3_R_DN")
	)
	(segment
		(start 144.320768 -303.2633)
		(end 142.748 -303.2633)
		(width 0.1143)
		(layer "F.Cu")
		(net "CLK_100M_DB800ZL_PEX1_S3_R_DN")
	)
	(segment
		(start 149.842728 -303.40046)
		(end 149.705568 -303.2633)
		(width 0.1143)
		(layer "F.Cu")
		(net "CLK_100M_DB800ZL_PEX1_S3_R_DN")
	)
	(segment
		(start 151.46528 -302.580548)
		(end 150.782528 -303.2633)
		(width 0.1143)
		(layer "F.Cu")
		(net "CLK_100M_DB800ZL_PEX1_S3_R_DN")
	)
	(segment
		(start 109.776514 -356.46614)
		(end 107.869228 -358.373426)
		(width 0.1143)
		(layer "F.Cu")
		(net "CLK_100M_DB800ZL_PEX1_S3_R_DN")
	)
	(segment
		(start 151.46528 -301.094648)
		(end 151.46528 -301.495968)
		(width 0.1143)
		(layer "F.Cu")
		(net "CLK_100M_DB800ZL_PEX1_S3_R_DN")
	)
	(segment
		(start 114.324384 -340.719156)
		(end 111.515652 -340.719156)
		(width 0.1143)
		(layer "F.Cu")
		(net "CLK_100M_DB800ZL_PEX1_S3_R_DN")
	)
	(segment
		(start 140.96746 -312.35777)
		(end 140.8303 -312.49493)
		(width 0.1143)
		(layer "F.Cu")
		(net "CLK_100M_DB800ZL_PEX1_S3_R_DN")
	)
	(segment
		(start 105.937812 -359.182162)
		(end 103.161846 -359.182162)
		(width 0.1143)
		(layer "F.Cu")
		(net "CLK_100M_DB800ZL_PEX1_S3_R_DN")
	)
	(segment
		(start 149.304248 -303.2633)
		(end 149.167088 -303.40046)
		(width 0.1143)
		(layer "F.Cu")
		(net "CLK_100M_DB800ZL_PEX1_S3_R_DN")
	)
	(segment
		(start 147.013168 -303.40046)
		(end 146.611848 -303.40046)
		(width 0.1143)
		(layer "F.Cu")
		(net "CLK_100M_DB800ZL_PEX1_S3_R_DN")
	)
	(segment
		(start 146.073368 -303.2633)
		(end 145.936208 -303.40046)
		(width 0.1143)
		(layer "F.Cu")
		(net "CLK_100M_DB800ZL_PEX1_S3_R_DN")
	)
	(segment
		(start 152.291288 -295.89984)
		(end 151.46528 -296.725848)
		(width 0.1143)
		(layer "F.Cu")
		(net "CLK_100M_DB800ZL_PEX1_S3_R_DN")
	)
	(segment
		(start 147.688808 -303.40046)
		(end 147.551648 -303.2633)
		(width 0.1143)
		(layer "F.Cu")
		(net "CLK_100M_DB800ZL_PEX1_S3_R_DN")
	)
	(segment
		(start 110.141512 -353.08286)
		(end 110.141512 -353.48418)
		(width 0.1143)
		(layer "F.Cu")
		(net "CLK_100M_DB800ZL_PEX1_S3_R_DN")
	)
	(segment
		(start 110.141512 -349.85198)
		(end 110.141512 -350.2533)
		(width 0.1143)
		(layer "F.Cu")
		(net "CLK_100M_DB800ZL_PEX1_S3_R_DN")
	)
	(segment
		(start 138.883136 -316.35827)
		(end 137.522712 -319.642236)
		(width 0.1143)
		(layer "F.Cu")
		(net "CLK_100M_DB800ZL_PEX1_S3_R_DN")
	)
	(segment
		(start 102.8573 -359.486708)
		(end 102.8573 -359.749344)
		(width 0.1143)
		(layer "F.Cu")
		(net "CLK_100M_DB800ZL_PEX1_S3_R_DN")
	)
	(segment
		(start 149.167088 -303.40046)
		(end 148.765768 -303.40046)
		(width 0.1143)
		(layer "F.Cu")
		(net "CLK_100M_DB800ZL_PEX1_S3_R_DN")
	)
	(segment
		(start 140.96746 -313.03595)
		(end 140.96746 -313.43981)
		(width 0.1143)
		(layer "F.Cu")
		(net "CLK_100M_DB800ZL_PEX1_S3_R_DN")
	)
	(segment
		(start 110.278672 -353.62134)
		(end 110.278672 -354.02266)
		(width 0.1143)
		(layer "F.Cu")
		(net "CLK_100M_DB800ZL_PEX1_S3_R_DN")
	)
	(segment
		(start 110.141512 -355.585522)
		(end 109.776514 -356.46614)
		(width 0.1143)
		(layer "F.Cu")
		(net "CLK_100M_DB800ZL_PEX1_S3_R_DN")
	)
	(segment
		(start 137.522712 -323.087492)
		(end 123.827286 -336.783172)
		(width 0.1143)
		(layer "F.Cu")
		(net "CLK_100M_DB800ZL_PEX1_S3_R_DN")
	)
	(segment
		(start 110.141512 -352.40722)
		(end 110.278672 -352.54438)
		(width 0.1143)
		(layer "F.Cu")
		(net "CLK_100M_DB800ZL_PEX1_S3_R_DN")
	)
	(segment
		(start 140.8303 -305.181)
		(end 140.8303 -310.73471)
		(width 0.1143)
		(layer "F.Cu")
		(net "CLK_100M_DB800ZL_PEX1_S3_R_DN")
	)
	(segment
		(start 111.515652 -340.719156)
		(end 110.141512 -342.093296)
		(width 0.1143)
		(layer "F.Cu")
		(net "CLK_100M_DB800ZL_PEX1_S3_R_DN")
	)
	(segment
		(start 144.457928 -303.40046)
		(end 144.320768 -303.2633)
		(width 0.1143)
		(layer "F.Cu")
		(net "CLK_100M_DB800ZL_PEX1_S3_R_DN")
	)
	(segment
		(start 123.827286 -336.783172)
		(end 114.324384 -340.719156)
		(width 0.1143)
		(layer "F.Cu")
		(net "CLK_100M_DB800ZL_PEX1_S3_R_DN")
	)
	(segment
		(start 148.765768 -303.40046)
		(end 148.628608 -303.2633)
		(width 0.1143)
		(layer "F.Cu")
		(net "CLK_100M_DB800ZL_PEX1_S3_R_DN")
	)
	(segment
		(start 110.141512 -349.17634)
		(end 110.278672 -349.3135)
		(width 0.1143)
		(layer "F.Cu")
		(net "CLK_100M_DB800ZL_PEX1_S3_R_DN")
	)
	(segment
		(start 103.161846 -359.182162)
		(end 102.8573 -359.486708)
		(width 0.1143)
		(layer "F.Cu")
		(net "CLK_100M_DB800ZL_PEX1_S3_R_DN")
	)
	(segment
		(start 140.8303 -310.73471)
		(end 140.96746 -310.87187)
		(width 0.1143)
		(layer "F.Cu")
		(net "CLK_100M_DB800ZL_PEX1_S3_R_DN")
	)
	(segment
		(start 142.748 -303.2633)
		(end 140.8303 -305.181)
		(width 0.1143)
		(layer "F.Cu")
		(net "CLK_100M_DB800ZL_PEX1_S3_R_DN")
	)
	(segment
		(start 144.996408 -303.2633)
		(end 144.859248 -303.40046)
		(width 0.1143)
		(layer "F.Cu")
		(net "CLK_100M_DB800ZL_PEX1_S3_R_DN")
	)
	(segment
		(start 151.60244 -300.556168)
		(end 151.60244 -300.957488)
		(width 0.1143)
		(layer "F.Cu")
		(net "CLK_100M_DB800ZL_PEX1_S3_R_DN")
	)
	(segment
		(start 148.628608 -303.2633)
		(end 148.227288 -303.2633)
		(width 0.1143)
		(layer "F.Cu")
		(net "CLK_100M_DB800ZL_PEX1_S3_R_DN")
	)
	(segment
		(start 110.278672 -354.02266)
		(end 110.141512 -354.15982)
		(width 0.1143)
		(layer "F.Cu")
		(net "CLK_100M_DB800ZL_PEX1_S3_R_DN")
	)
	(segment
		(start 107.869228 -358.373426)
		(end 105.937812 -359.182162)
		(width 0.1143)
		(layer "F.Cu")
		(net "CLK_100M_DB800ZL_PEX1_S3_R_DN")
	)
	(segment
		(start 140.96746 -311.95391)
		(end 140.96746 -312.35777)
		(width 0.1143)
		(layer "F.Cu")
		(net "CLK_100M_DB800ZL_PEX1_S3_R_DN")
	)
	(segment
		(start 110.278672 -349.3135)
		(end 110.278672 -349.71482)
		(width 0.1143)
		(layer "F.Cu")
		(net "CLK_100M_DB800ZL_PEX1_S3_R_DN")
	)
	(segment
		(start 140.8303 -311.81675)
		(end 140.96746 -311.95391)
		(width 0.1143)
		(layer "F.Cu")
		(net "CLK_100M_DB800ZL_PEX1_S3_R_DN")
	)
	(segment
		(start 110.141512 -350.92894)
		(end 110.141512 -351.33026)
		(width 0.1143)
		(layer "F.Cu")
		(net "CLK_100M_DB800ZL_PEX1_S3_R_DN")
	)
	(segment
		(start 137.522712 -319.642236)
		(end 137.522712 -323.087492)
		(width 0.1143)
		(layer "F.Cu")
		(net "CLK_100M_DB800ZL_PEX1_S3_R_DN")
	)
	(segment
		(start 110.278672 -351.46742)
		(end 110.278672 -351.86874)
		(width 0.1143)
		(layer "F.Cu")
		(net "CLK_100M_DB800ZL_PEX1_S3_R_DN")
	)
	(segment
		(start 110.278672 -351.86874)
		(end 110.141512 -352.0059)
		(width 0.1143)
		(layer "F.Cu")
		(net "CLK_100M_DB800ZL_PEX1_S3_R_DN")
	)
	(segment
		(start 146.611848 -303.40046)
		(end 146.474688 -303.2633)
		(width 0.1143)
		(layer "F.Cu")
		(net "CLK_100M_DB800ZL_PEX1_S3_R_DN")
	)
	(segment
		(start 140.8303 -311.41289)
		(end 140.8303 -311.81675)
		(width 0.1143)
		(layer "F.Cu")
		(net "CLK_100M_DB800ZL_PEX1_S3_R_DN")
	)
	(segment
		(start 150.381208 -303.2633)
		(end 150.244048 -303.40046)
		(width 0.1143)
		(layer "F.Cu")
		(net "CLK_100M_DB800ZL_PEX1_S3_R_DN")
	)
	(segment
		(start 145.397728 -303.2633)
		(end 144.996408 -303.2633)
		(width 0.1143)
		(layer "F.Cu")
		(net "CLK_100M_DB800ZL_PEX1_S3_R_DN")
	)
	(segment
		(start 110.141512 -354.15982)
		(end 110.141512 -355.585522)
		(width 0.1143)
		(layer "F.Cu")
		(net "CLK_100M_DB800ZL_PEX1_S3_R_DN")
	)
	(segment
		(start 151.60244 -302.034448)
		(end 151.46528 -302.171608)
		(width 0.1143)
		(layer "F.Cu")
		(net "CLK_100M_DB800ZL_PEX1_S3_R_DN")
	)
	(segment
		(start 110.141512 -351.33026)
		(end 110.278672 -351.46742)
		(width 0.1143)
		(layer "F.Cu")
		(net "CLK_100M_DB800ZL_PEX1_S3_R_DN")
	)
	(segment
		(start 145.534888 -303.40046)
		(end 145.397728 -303.2633)
		(width 0.1143)
		(layer "F.Cu")
		(net "CLK_100M_DB800ZL_PEX1_S3_R_DN")
	)
	(segment
		(start 110.278672 -350.79178)
		(end 110.141512 -350.92894)
		(width 0.1143)
		(layer "F.Cu")
		(net "CLK_100M_DB800ZL_PEX1_S3_R_DN")
	)
	(segment
		(start 151.60244 -301.633128)
		(end 151.60244 -302.034448)
		(width 0.1143)
		(layer "F.Cu")
		(net "CLK_100M_DB800ZL_PEX1_S3_R_DN")
	)
	(segment
		(start 151.46528 -302.171608)
		(end 151.46528 -302.580548)
		(width 0.1143)
		(layer "F.Cu")
		(net "CLK_100M_DB800ZL_PEX1_S3_R_DN")
	)
	(segment
		(start 102.8573 -359.749344)
		(end 103.095806 -359.98785)
		(width 0.1143)
		(layer "F.Cu")
		(net "CLK_100M_DB800ZL_PEX1_S3_R_DN")
	)
	(segment
		(start 140.8303 -312.89879)
		(end 140.96746 -313.03595)
		(width 0.1143)
		(layer "F.Cu")
		(net "CLK_100M_DB800ZL_PEX1_S3_R_DN")
	)
	(segment
		(start 152.94991 -295.89984)
		(end 152.291288 -295.89984)
		(width 0.1143)
		(layer "F.Cu")
		(net "CLK_100M_DB800ZL_PEX1_S3_R_DN")
	)
	(segment
		(start 149.705568 -303.2633)
		(end 149.304248 -303.2633)
		(width 0.1143)
		(layer "F.Cu")
		(net "CLK_100M_DB800ZL_PEX1_S3_R_DN")
	)
	(segment
		(start 146.474688 -303.2633)
		(end 146.073368 -303.2633)
		(width 0.1143)
		(layer "F.Cu")
		(net "CLK_100M_DB800ZL_PEX1_S3_R_DN")
	)
	(segment
		(start 140.8303 -313.57697)
		(end 140.8303 -314.410852)
		(width 0.1143)
		(layer "F.Cu")
		(net "CLK_100M_DB800ZL_PEX1_S3_R_DN")
	)
	(segment
		(start 110.278672 -352.9457)
		(end 110.141512 -353.08286)
		(width 0.1143)
		(layer "F.Cu")
		(net "CLK_100M_DB800ZL_PEX1_S3_R_DN")
	)
	(segment
		(start 110.278672 -350.39046)
		(end 110.278672 -350.79178)
		(width 0.1143)
		(layer "F.Cu")
		(net "CLK_100M_DB800ZL_PEX1_S3_R_DN")
	)
	(segment
		(start 140.96746 -311.27573)
		(end 140.8303 -311.41289)
		(width 0.1143)
		(layer "F.Cu")
		(net "CLK_100M_DB800ZL_PEX1_S3_R_DN")
	)
	(segment
		(start 110.141512 -342.093296)
		(end 110.141512 -349.17634)
		(width 0.1143)
		(layer "F.Cu")
		(net "CLK_100M_DB800ZL_PEX1_S3_R_DN")
	)
	(segment
		(start 110.141512 -352.0059)
		(end 110.141512 -352.40722)
		(width 0.1143)
		(layer "F.Cu")
		(net "CLK_100M_DB800ZL_PEX1_S3_R_DN")
	)
	(segment
		(start 151.46528 -300.419008)
		(end 151.60244 -300.556168)
		(width 0.1143)
		(layer "F.Cu")
		(net "CLK_100M_DB800ZL_PEX1_S3_R_DN")
	)
	(segment
		(start 140.8303 -312.49493)
		(end 140.8303 -312.89879)
		(width 0.1143)
		(layer "F.Cu")
		(net "CLK_100M_DB800ZL_PEX1_S3_R_DN")
	)
	(segment
		(start 147.551648 -303.2633)
		(end 147.150328 -303.2633)
		(width 0.1143)
		(layer "F.Cu")
		(net "CLK_100M_DB800ZL_PEX1_S3_R_DN")
	)
	(segment
		(start 151.46528 -301.495968)
		(end 151.60244 -301.633128)
		(width 0.1143)
		(layer "F.Cu")
		(net "CLK_100M_DB800ZL_PEX1_S3_R_DN")
	)
	(segment
		(start 148.227288 -303.2633)
		(end 148.090128 -303.40046)
		(width 0.1143)
		(layer "F.Cu")
		(net "CLK_100M_DB800ZL_PEX1_S3_R_DN")
	)
	(segment
		(start 110.141512 -353.48418)
		(end 110.278672 -353.62134)
		(width 0.1143)
		(layer "F.Cu")
		(net "CLK_100M_DB800ZL_PEX1_S3_R_DN")
	)
	(segment
		(start 140.96746 -310.87187)
		(end 140.96746 -311.27573)
		(width 0.1143)
		(layer "F.Cu")
		(net "CLK_100M_DB800ZL_PEX1_S3_R_DN")
	)
	(via
		(at 103.095806 -359.98785)
		(size 0.508)
		(drill 0.254)
		(layers "F.Cu" "B.Cu")
		(net "CLK_100M_DB800ZL_PEX1_S3_R_DN")
	)
	(segment
		(start 102.8573 -359.749344)
		(end 103.095806 -359.98785)
		(width 0.1143)
		(layer "B.Cu")
		(net "CLK_100M_DB800ZL_PEX1_S3_R_DN")
	)
	(segment
		(start 103.172006 -358.323134)
		(end 102.8573 -358.63784)
		(width 0.1143)
		(layer "B.Cu")
		(net "CLK_100M_DB800ZL_PEX1_S3_R_DN")
	)
	(segment
		(start 102.8573 -358.63784)
		(end 102.8573 -359.749344)
		(width 0.1143)
		(layer "B.Cu")
		(net "CLK_100M_DB800ZL_PEX1_S3_R_DN")
	)
	(segment
		(start 138.570716 -316.149482)
		(end 137.154412 -319.56883)
		(width 0.1143)
		(layer "F.Cu")
		(net "CLK_100M_DB800ZL_PEX1_S3_R_DP")
	)
	(segment
		(start 150.629874 -302.895)
		(end 142.595346 -302.895)
		(width 0.1143)
		(layer "F.Cu")
		(net "CLK_100M_DB800ZL_PEX1_S3_R_DP")
	)
	(segment
		(start 123.618498 -336.470752)
		(end 114.250978 -340.350856)
		(width 0.1143)
		(layer "F.Cu")
		(net "CLK_100M_DB800ZL_PEX1_S3_R_DP")
	)
	(segment
		(start 137.154412 -322.934838)
		(end 123.618498 -336.470752)
		(width 0.1143)
		(layer "F.Cu")
		(net "CLK_100M_DB800ZL_PEX1_S3_R_DP")
	)
	(segment
		(start 109.464094 -356.257352)
		(end 107.659932 -358.061514)
		(width 0.1143)
		(layer "F.Cu")
		(net "CLK_100M_DB800ZL_PEX1_S3_R_DP")
	)
	(segment
		(start 102.489 -359.731056)
		(end 102.232206 -359.98785)
		(width 0.1143)
		(layer "F.Cu")
		(net "CLK_100M_DB800ZL_PEX1_S3_R_DP")
	)
	(segment
		(start 153.42743 -295.4274)
		(end 152.242774 -295.4274)
		(width 0.1143)
		(layer "F.Cu")
		(net "CLK_100M_DB800ZL_PEX1_S3_R_DP")
	)
	(segment
		(start 109.773212 -355.512116)
		(end 109.464094 -356.257352)
		(width 0.1143)
		(layer "F.Cu")
		(net "CLK_100M_DB800ZL_PEX1_S3_R_DP")
	)
	(segment
		(start 153.89987 -295.89984)
		(end 153.42743 -295.4274)
		(width 0.1143)
		(layer "F.Cu")
		(net "CLK_100M_DB800ZL_PEX1_S3_R_DP")
	)
	(segment
		(start 151.09698 -296.573194)
		(end 151.09698 -302.427894)
		(width 0.1143)
		(layer "F.Cu")
		(net "CLK_100M_DB800ZL_PEX1_S3_R_DP")
	)
	(segment
		(start 140.462 -314.258198)
		(end 138.570716 -316.149482)
		(width 0.1143)
		(layer "F.Cu")
		(net "CLK_100M_DB800ZL_PEX1_S3_R_DP")
	)
	(segment
		(start 103.009192 -358.813862)
		(end 102.489 -359.334054)
		(width 0.1143)
		(layer "F.Cu")
		(net "CLK_100M_DB800ZL_PEX1_S3_R_DP")
	)
	(segment
		(start 105.863644 -358.813862)
		(end 103.009192 -358.813862)
		(width 0.1143)
		(layer "F.Cu")
		(net "CLK_100M_DB800ZL_PEX1_S3_R_DP")
	)
	(segment
		(start 109.773212 -341.940642)
		(end 109.773212 -355.512116)
		(width 0.1143)
		(layer "F.Cu")
		(net "CLK_100M_DB800ZL_PEX1_S3_R_DP")
	)
	(segment
		(start 137.154412 -319.56883)
		(end 137.154412 -322.934838)
		(width 0.1143)
		(layer "F.Cu")
		(net "CLK_100M_DB800ZL_PEX1_S3_R_DP")
	)
	(segment
		(start 111.362998 -340.350856)
		(end 109.773212 -341.940642)
		(width 0.1143)
		(layer "F.Cu")
		(net "CLK_100M_DB800ZL_PEX1_S3_R_DP")
	)
	(segment
		(start 102.489 -359.334054)
		(end 102.489 -359.731056)
		(width 0.1143)
		(layer "F.Cu")
		(net "CLK_100M_DB800ZL_PEX1_S3_R_DP")
	)
	(segment
		(start 151.09698 -302.427894)
		(end 150.629874 -302.895)
		(width 0.1143)
		(layer "F.Cu")
		(net "CLK_100M_DB800ZL_PEX1_S3_R_DP")
	)
	(segment
		(start 142.595346 -302.895)
		(end 140.462 -305.028346)
		(width 0.1143)
		(layer "F.Cu")
		(net "CLK_100M_DB800ZL_PEX1_S3_R_DP")
	)
	(segment
		(start 140.462 -305.028346)
		(end 140.462 -314.258198)
		(width 0.1143)
		(layer "F.Cu")
		(net "CLK_100M_DB800ZL_PEX1_S3_R_DP")
	)
	(segment
		(start 114.250978 -340.350856)
		(end 111.362998 -340.350856)
		(width 0.1143)
		(layer "F.Cu")
		(net "CLK_100M_DB800ZL_PEX1_S3_R_DP")
	)
	(segment
		(start 107.659932 -358.061514)
		(end 105.863644 -358.813862)
		(width 0.1143)
		(layer "F.Cu")
		(net "CLK_100M_DB800ZL_PEX1_S3_R_DP")
	)
	(segment
		(start 152.242774 -295.4274)
		(end 151.09698 -296.573194)
		(width 0.1143)
		(layer "F.Cu")
		(net "CLK_100M_DB800ZL_PEX1_S3_R_DP")
	)
	(via
		(at 102.232206 -359.98785)
		(size 0.508)
		(drill 0.254)
		(layers "F.Cu" "B.Cu")
		(net "CLK_100M_DB800ZL_PEX1_S3_R_DP")
	)
	(segment
		(start 102.489 -359.731056)
		(end 102.232206 -359.98785)
		(width 0.1143)
		(layer "B.Cu")
		(net "CLK_100M_DB800ZL_PEX1_S3_R_DP")
	)
	(segment
		(start 102.156006 -358.323134)
		(end 102.489 -358.656128)
		(width 0.1143)
		(layer "B.Cu")
		(net "CLK_100M_DB800ZL_PEX1_S3_R_DP")
	)
	(segment
		(start 102.489 -358.656128)
		(end 102.489 -359.731056)
		(width 0.1143)
		(layer "B.Cu")
		(net "CLK_100M_DB800ZL_PEX1_S3_R_DP")
	)
	(segment
		(start 202.829668 -301.02048)
		(end 202.829668 -301.83963)
		(width 0.13208)
		(layer "F.Cu")
		(net "RST_PEX1_S3_PERST_R_N")
	)
	(segment
		(start 188.099954 -306.349908)
		(end 187.624974 -306.824888)
		(width 0.13208)
		(layer "F.Cu")
		(net "RST_PEX1_S3_PERST_R_N")
	)
	(via
		(at 200.850246 -303.819052)
		(size 0.6604)
		(drill 0.3302)
		(layers "F.Cu" "B.Cu")
		(net "RST_PEX1_S3_PERST_R_N")
	)
	(via
		(at 187.624974 -306.824888)
		(size 0.4064)
		(drill 0.2032)
		(layers "F.Cu" "B.Cu")
		(net "RST_PEX1_S3_PERST_R_N")
	)
	(via
		(at 202.829668 -301.83963)
		(size 0.508)
		(drill 0.254)
		(layers "F.Cu" "B.Cu")
		(net "RST_PEX1_S3_PERST_R_N")
	)
	(segment
		(start 200.505822 -303.474628)
		(end 200.505822 -302.435768)
		(width 0.13208)
		(layer "B.Cu")
		(net "RST_PEX1_S3_PERST_R_N")
	)
	(segment
		(start 187.624974 -306.824888)
		(end 188.083698 -306.366164)
		(width 0.13208)
		(layer "B.Cu")
		(net "RST_PEX1_S3_PERST_R_N")
	)
	(segment
		(start 188.9252 -305.3588)
		(end 189.357 -304.927)
		(width 0.13208)
		(layer "B.Cu")
		(net "RST_PEX1_S3_PERST_R_N")
	)
	(segment
		(start 188.083698 -305.4858)
		(end 188.210698 -305.3588)
		(width 0.13208)
		(layer "B.Cu")
		(net "RST_PEX1_S3_PERST_R_N")
	)
	(segment
		(start 200.505822 -302.435768)
		(end 201.10196 -301.83963)
		(width 0.13208)
		(layer "B.Cu")
		(net "RST_PEX1_S3_PERST_R_N")
	)
	(segment
		(start 200.850246 -303.819052)
		(end 200.505822 -303.474628)
		(width 0.13208)
		(layer "B.Cu")
		(net "RST_PEX1_S3_PERST_R_N")
	)
	(segment
		(start 189.357 -304.927)
		(end 199.742298 -304.927)
		(width 0.13208)
		(layer "B.Cu")
		(net "RST_PEX1_S3_PERST_R_N")
	)
	(segment
		(start 201.10196 -301.83963)
		(end 202.829668 -301.83963)
		(width 0.13208)
		(layer "B.Cu")
		(net "RST_PEX1_S3_PERST_R_N")
	)
	(segment
		(start 188.083698 -306.366164)
		(end 188.083698 -305.4858)
		(width 0.13208)
		(layer "B.Cu")
		(net "RST_PEX1_S3_PERST_R_N")
	)
	(segment
		(start 188.210698 -305.3588)
		(end 188.9252 -305.3588)
		(width 0.13208)
		(layer "B.Cu")
		(net "RST_PEX1_S3_PERST_R_N")
	)
	(segment
		(start 199.742298 -304.927)
		(end 200.850246 -303.819052)
		(width 0.13208)
		(layer "B.Cu")
		(net "RST_PEX1_S3_PERST_R_N")
	)
	(segment
		(start 92.736924 -329.325478)
		(end 95.1611 -331.749654)
		(width 0.1143)
		(layer "F.Cu")
		(net "CLK_100M_DB800ZL_PEX0_S3_R_DP")
	)
	(segment
		(start 19.500596 -309.429658)
		(end 18.141188 -309.429658)
		(width 0.1143)
		(layer "F.Cu")
		(net "CLK_100M_DB800ZL_PEX0_S3_R_DP")
	)
	(segment
		(start 87.890604 -329.462638)
		(end 88.027764 -329.325478)
		(width 0.1143)
		(layer "F.Cu")
		(net "CLK_100M_DB800ZL_PEX0_S3_R_DP")
	)
	(segment
		(start 22.629368 -325.969376)
		(end 24.580342 -327.92035)
		(width 0.1143)
		(layer "F.Cu")
		(net "CLK_100M_DB800ZL_PEX0_S3_R_DP")
	)
	(segment
		(start 37.799772 -295.89984)
		(end 37.352732 -295.4528)
		(width 0.1143)
		(layer "F.Cu")
		(net "CLK_100M_DB800ZL_PEX0_S3_R_DP")
	)
	(segment
		(start 18.141188 -309.429658)
		(end 17.051274 -310.519572)
		(width 0.1143)
		(layer "F.Cu")
		(net "CLK_100M_DB800ZL_PEX0_S3_R_DP")
	)
	(segment
		(start 86.407244 -329.462638)
		(end 86.811104 -329.462638)
		(width 0.1143)
		(layer "F.Cu")
		(net "CLK_100M_DB800ZL_PEX0_S3_R_DP")
	)
	(segment
		(start 91.659964 -329.325478)
		(end 91.797124 -329.462638)
		(width 0.1143)
		(layer "F.Cu")
		(net "CLK_100M_DB800ZL_PEX0_S3_R_DP")
	)
	(segment
		(start 92.335604 -329.325478)
		(end 92.736924 -329.325478)
		(width 0.1143)
		(layer "F.Cu")
		(net "CLK_100M_DB800ZL_PEX0_S3_R_DP")
	)
	(segment
		(start 37.352732 -295.4528)
		(end 36.398454 -295.4528)
		(width 0.1143)
		(layer "F.Cu")
		(net "CLK_100M_DB800ZL_PEX0_S3_R_DP")
	)
	(segment
		(start 91.797124 -329.462638)
		(end 92.198444 -329.462638)
		(width 0.1143)
		(layer "F.Cu")
		(net "CLK_100M_DB800ZL_PEX0_S3_R_DP")
	)
	(segment
		(start 17.051274 -312.502296)
		(end 22.629368 -325.969376)
		(width 0.1143)
		(layer "F.Cu")
		(net "CLK_100M_DB800ZL_PEX0_S3_R_DP")
	)
	(segment
		(start 26.060654 -302.8696)
		(end 19.500596 -309.429658)
		(width 0.1143)
		(layer "F.Cu")
		(net "CLK_100M_DB800ZL_PEX0_S3_R_DP")
	)
	(segment
		(start 91.121484 -329.462638)
		(end 91.258644 -329.325478)
		(width 0.1143)
		(layer "F.Cu")
		(net "CLK_100M_DB800ZL_PEX0_S3_R_DP")
	)
	(segment
		(start 89.643204 -329.462638)
		(end 90.044524 -329.462638)
		(width 0.1143)
		(layer "F.Cu")
		(net "CLK_100M_DB800ZL_PEX0_S3_R_DP")
	)
	(segment
		(start 88.429084 -329.325478)
		(end 88.566244 -329.462638)
		(width 0.1143)
		(layer "F.Cu")
		(net "CLK_100M_DB800ZL_PEX0_S3_R_DP")
	)
	(segment
		(start 90.583004 -329.325478)
		(end 90.720164 -329.462638)
		(width 0.1143)
		(layer "F.Cu")
		(net "CLK_100M_DB800ZL_PEX0_S3_R_DP")
	)
	(segment
		(start 89.506044 -329.325478)
		(end 89.643204 -329.462638)
		(width 0.1143)
		(layer "F.Cu")
		(net "CLK_100M_DB800ZL_PEX0_S3_R_DP")
	)
	(segment
		(start 90.181684 -329.325478)
		(end 90.583004 -329.325478)
		(width 0.1143)
		(layer "F.Cu")
		(net "CLK_100M_DB800ZL_PEX0_S3_R_DP")
	)
	(segment
		(start 88.967564 -329.462638)
		(end 89.104724 -329.325478)
		(width 0.1143)
		(layer "F.Cu")
		(net "CLK_100M_DB800ZL_PEX0_S3_R_DP")
	)
	(segment
		(start 95.1611 -332.841346)
		(end 94.66834 -333.334106)
		(width 0.1143)
		(layer "F.Cu")
		(net "CLK_100M_DB800ZL_PEX0_S3_R_DP")
	)
	(segment
		(start 34.991802 -296.859452)
		(end 34.991802 -301.951644)
		(width 0.1143)
		(layer "F.Cu")
		(net "CLK_100M_DB800ZL_PEX0_S3_R_DP")
	)
	(segment
		(start 34.073846 -302.8696)
		(end 26.060654 -302.8696)
		(width 0.1143)
		(layer "F.Cu")
		(net "CLK_100M_DB800ZL_PEX0_S3_R_DP")
	)
	(segment
		(start 92.198444 -329.462638)
		(end 92.335604 -329.325478)
		(width 0.1143)
		(layer "F.Cu")
		(net "CLK_100M_DB800ZL_PEX0_S3_R_DP")
	)
	(segment
		(start 88.566244 -329.462638)
		(end 88.967564 -329.462638)
		(width 0.1143)
		(layer "F.Cu")
		(net "CLK_100M_DB800ZL_PEX0_S3_R_DP")
	)
	(segment
		(start 90.720164 -329.462638)
		(end 91.121484 -329.462638)
		(width 0.1143)
		(layer "F.Cu")
		(net "CLK_100M_DB800ZL_PEX0_S3_R_DP")
	)
	(segment
		(start 87.352124 -329.325478)
		(end 87.489284 -329.462638)
		(width 0.1143)
		(layer "F.Cu")
		(net "CLK_100M_DB800ZL_PEX0_S3_R_DP")
	)
	(segment
		(start 36.398454 -295.4528)
		(end 34.991802 -296.859452)
		(width 0.1143)
		(layer "F.Cu")
		(net "CLK_100M_DB800ZL_PEX0_S3_R_DP")
	)
	(segment
		(start 88.027764 -329.325478)
		(end 88.429084 -329.325478)
		(width 0.1143)
		(layer "F.Cu")
		(net "CLK_100M_DB800ZL_PEX0_S3_R_DP")
	)
	(segment
		(start 89.104724 -329.325478)
		(end 89.506044 -329.325478)
		(width 0.1143)
		(layer "F.Cu")
		(net "CLK_100M_DB800ZL_PEX0_S3_R_DP")
	)
	(segment
		(start 94.66834 -333.334106)
		(end 94.278958 -333.334106)
		(width 0.1143)
		(layer "F.Cu")
		(net "CLK_100M_DB800ZL_PEX0_S3_R_DP")
	)
	(segment
		(start 87.489284 -329.462638)
		(end 87.890604 -329.462638)
		(width 0.1143)
		(layer "F.Cu")
		(net "CLK_100M_DB800ZL_PEX0_S3_R_DP")
	)
	(segment
		(start 27.97302 -329.325478)
		(end 86.270084 -329.325478)
		(width 0.1143)
		(layer "F.Cu")
		(net "CLK_100M_DB800ZL_PEX0_S3_R_DP")
	)
	(segment
		(start 86.811104 -329.462638)
		(end 86.948264 -329.325478)
		(width 0.1143)
		(layer "F.Cu")
		(net "CLK_100M_DB800ZL_PEX0_S3_R_DP")
	)
	(segment
		(start 94.278958 -333.334106)
		(end 94.031308 -333.086456)
		(width 0.1143)
		(layer "F.Cu")
		(net "CLK_100M_DB800ZL_PEX0_S3_R_DP")
	)
	(segment
		(start 34.991802 -301.951644)
		(end 34.073846 -302.8696)
		(width 0.1143)
		(layer "F.Cu")
		(net "CLK_100M_DB800ZL_PEX0_S3_R_DP")
	)
	(segment
		(start 24.580342 -327.92035)
		(end 27.97302 -329.325478)
		(width 0.1143)
		(layer "F.Cu")
		(net "CLK_100M_DB800ZL_PEX0_S3_R_DP")
	)
	(segment
		(start 86.270084 -329.325478)
		(end 86.407244 -329.462638)
		(width 0.1143)
		(layer "F.Cu")
		(net "CLK_100M_DB800ZL_PEX0_S3_R_DP")
	)
	(segment
		(start 86.948264 -329.325478)
		(end 87.352124 -329.325478)
		(width 0.1143)
		(layer "F.Cu")
		(net "CLK_100M_DB800ZL_PEX0_S3_R_DP")
	)
	(segment
		(start 90.044524 -329.462638)
		(end 90.181684 -329.325478)
		(width 0.1143)
		(layer "F.Cu")
		(net "CLK_100M_DB800ZL_PEX0_S3_R_DP")
	)
	(segment
		(start 17.051274 -310.519572)
		(end 17.051274 -312.502296)
		(width 0.1143)
		(layer "F.Cu")
		(net "CLK_100M_DB800ZL_PEX0_S3_R_DP")
	)
	(segment
		(start 95.1611 -331.749654)
		(end 95.1611 -332.841346)
		(width 0.1143)
		(layer "F.Cu")
		(net "CLK_100M_DB800ZL_PEX0_S3_R_DP")
	)
	(segment
		(start 91.258644 -329.325478)
		(end 91.659964 -329.325478)
		(width 0.1143)
		(layer "F.Cu")
		(net "CLK_100M_DB800ZL_PEX0_S3_R_DP")
	)
	(via
		(at 94.031308 -333.086456)
		(size 0.508)
		(drill 0.254)
		(layers "F.Cu" "B.Cu")
		(net "CLK_100M_DB800ZL_PEX0_S3_R_DP")
	)
	(segment
		(start 97.138744 -352.0313)
		(end 96.785684 -351.67824)
		(width 0.1143)
		(layer "B.Cu")
		(net "CLK_100M_DB800ZL_PEX0_S3_R_DP")
	)
	(segment
		(start 97.892362 -351.719388)
		(end 97.58045 -352.0313)
		(width 0.1143)
		(layer "B.Cu")
		(net "CLK_100M_DB800ZL_PEX0_S3_R_DP")
	)
	(segment
		(start 94.285308 -333.340456)
		(end 94.031308 -333.086456)
		(width 0.1143)
		(layer "B.Cu")
		(net "CLK_100M_DB800ZL_PEX0_S3_R_DP")
	)
	(segment
		(start 95.9104 -336.92084)
		(end 95.9104 -333.893668)
		(width 0.1143)
		(layer "B.Cu")
		(net "CLK_100M_DB800ZL_PEX0_S3_R_DP")
	)
	(segment
		(start 96.785684 -337.796124)
		(end 95.9104 -336.92084)
		(width 0.1143)
		(layer "B.Cu")
		(net "CLK_100M_DB800ZL_PEX0_S3_R_DP")
	)
	(segment
		(start 95.357188 -333.340456)
		(end 94.285308 -333.340456)
		(width 0.1143)
		(layer "B.Cu")
		(net "CLK_100M_DB800ZL_PEX0_S3_R_DP")
	)
	(segment
		(start 95.9104 -333.893668)
		(end 95.357188 -333.340456)
		(width 0.1143)
		(layer "B.Cu")
		(net "CLK_100M_DB800ZL_PEX0_S3_R_DP")
	)
	(segment
		(start 96.785684 -351.67824)
		(end 96.785684 -337.796124)
		(width 0.1143)
		(layer "B.Cu")
		(net "CLK_100M_DB800ZL_PEX0_S3_R_DP")
	)
	(segment
		(start 97.58045 -352.0313)
		(end 97.138744 -352.0313)
		(width 0.1143)
		(layer "B.Cu")
		(net "CLK_100M_DB800ZL_PEX0_S3_R_DP")
	)
	(segment
		(start 29.81706 -303.37506)
		(end 30.21838 -303.37506)
		(width 0.1143)
		(layer "F.Cu")
		(net "CLK_100M_DB800ZL_PEX0_S3_R_DN")
	)
	(segment
		(start 17.983962 -313.433206)
		(end 17.830546 -313.062112)
		(width 0.1143)
		(layer "F.Cu")
		(net "CLK_100M_DB800ZL_PEX0_S3_R_DN")
	)
	(segment
		(start 36.472368 -295.89984)
		(end 36.849812 -295.89984)
		(width 0.1143)
		(layer "F.Cu")
		(net "CLK_100M_DB800ZL_PEX0_S3_R_DN")
	)
	(segment
		(start 20.303998 -319.03289)
		(end 20.12442 -318.958722)
		(width 0.1143)
		(layer "F.Cu")
		(net "CLK_100M_DB800ZL_PEX0_S3_R_DN")
	)
	(segment
		(start 31.29534 -303.37506)
		(end 31.4325 -303.2379)
		(width 0.1143)
		(layer "F.Cu")
		(net "CLK_100M_DB800ZL_PEX0_S3_R_DN")
	)
	(segment
		(start 33.44926 -303.37506)
		(end 33.58642 -303.2379)
		(width 0.1143)
		(layer "F.Cu")
		(net "CLK_100M_DB800ZL_PEX0_S3_R_DN")
	)
	(segment
		(start 20.418552 -309.226712)
		(end 20.418552 -309.032656)
		(width 0.1143)
		(layer "F.Cu")
		(net "CLK_100M_DB800ZL_PEX0_S3_R_DN")
	)
	(segment
		(start 30.89402 -303.37506)
		(end 31.29534 -303.37506)
		(width 0.1143)
		(layer "F.Cu")
		(net "CLK_100M_DB800ZL_PEX0_S3_R_DN")
	)
	(segment
		(start 20.71624 -320.028316)
		(end 20.536662 -319.953894)
		(width 0.1143)
		(layer "F.Cu")
		(net "CLK_100M_DB800ZL_PEX0_S3_R_DN")
	)
	(segment
		(start 24.78913 -327.60793)
		(end 22.941788 -325.760588)
		(width 0.1143)
		(layer "F.Cu")
		(net "CLK_100M_DB800ZL_PEX0_S3_R_DN")
	)
	(segment
		(start 29.6799 -303.2379)
		(end 29.81706 -303.37506)
		(width 0.1143)
		(layer "F.Cu")
		(net "CLK_100M_DB800ZL_PEX0_S3_R_DN")
	)
	(segment
		(start 31.4325 -303.2379)
		(end 31.83382 -303.2379)
		(width 0.1143)
		(layer "F.Cu")
		(net "CLK_100M_DB800ZL_PEX0_S3_R_DN")
	)
	(segment
		(start 20.132548 -309.512462)
		(end 20.418552 -309.226712)
		(width 0.1143)
		(layer "F.Cu")
		(net "CLK_100M_DB800ZL_PEX0_S3_R_DN")
	)
	(segment
		(start 18.65503 -315.052202)
		(end 18.475452 -314.978034)
		(width 0.1143)
		(layer "F.Cu")
		(net "CLK_100M_DB800ZL_PEX0_S3_R_DN")
	)
	(segment
		(start 19.558762 -317.592964)
		(end 19.63293 -317.41364)
		(width 0.1143)
		(layer "F.Cu")
		(net "CLK_100M_DB800ZL_PEX0_S3_R_DN")
	)
	(segment
		(start 18.734278 -315.60262)
		(end 18.808446 -315.423296)
		(width 0.1143)
		(layer "F.Cu")
		(net "CLK_100M_DB800ZL_PEX0_S3_R_DN")
	)
	(segment
		(start 18.06321 -313.982862)
		(end 17.909794 -313.612276)
		(width 0.1143)
		(layer "F.Cu")
		(net "CLK_100M_DB800ZL_PEX0_S3_R_DN")
	)
	(segment
		(start 17.650968 -312.987944)
		(end 17.419574 -312.42889)
		(width 0.1143)
		(layer "F.Cu")
		(net "CLK_100M_DB800ZL_PEX0_S3_R_DN")
	)
	(segment
		(start 28.7401 -303.37506)
		(end 29.14142 -303.37506)
		(width 0.1143)
		(layer "F.Cu")
		(net "CLK_100M_DB800ZL_PEX0_S3_R_DN")
	)
	(segment
		(start 21.69414 -322.3895)
		(end 21.540724 -322.01866)
		(width 0.1143)
		(layer "F.Cu")
		(net "CLK_100M_DB800ZL_PEX0_S3_R_DN")
	)
	(segment
		(start 20.045172 -318.408812)
		(end 19.891756 -318.037718)
		(width 0.1143)
		(layer "F.Cu")
		(net "CLK_100M_DB800ZL_PEX0_S3_R_DN")
	)
	(segment
		(start 95.5294 -331.597)
		(end 92.889578 -328.957178)
		(width 0.1143)
		(layer "F.Cu")
		(net "CLK_100M_DB800ZL_PEX0_S3_R_DN")
	)
	(segment
		(start 18.396204 -314.428124)
		(end 18.242788 -314.05703)
		(width 0.1143)
		(layer "F.Cu")
		(net "CLK_100M_DB800ZL_PEX0_S3_R_DN")
	)
	(segment
		(start 33.58642 -303.2379)
		(end 34.2265 -303.2379)
		(width 0.1143)
		(layer "F.Cu")
		(net "CLK_100M_DB800ZL_PEX0_S3_R_DN")
	)
	(segment
		(start 21.540724 -322.01866)
		(end 21.361146 -321.944238)
		(width 0.1143)
		(layer "F.Cu")
		(net "CLK_100M_DB800ZL_PEX0_S3_R_DN")
	)
	(segment
		(start 18.242788 -314.05703)
		(end 18.06321 -313.982862)
		(width 0.1143)
		(layer "F.Cu")
		(net "CLK_100M_DB800ZL_PEX0_S3_R_DN")
	)
	(segment
		(start 20.869656 -320.399156)
		(end 20.71624 -320.028316)
		(width 0.1143)
		(layer "F.Cu")
		(net "CLK_100M_DB800ZL_PEX0_S3_R_DN")
	)
	(segment
		(start 28.046426 -328.957178)
		(end 24.78913 -327.60793)
		(width 0.1143)
		(layer "F.Cu")
		(net "CLK_100M_DB800ZL_PEX0_S3_R_DN")
	)
	(segment
		(start 21.20773 -321.573652)
		(end 21.281898 -321.394328)
		(width 0.1143)
		(layer "F.Cu")
		(net "CLK_100M_DB800ZL_PEX0_S3_R_DN")
	)
	(segment
		(start 19.938746 -309.512462)
		(end 20.132548 -309.512462)
		(width 0.1143)
		(layer "F.Cu")
		(net "CLK_100M_DB800ZL_PEX0_S3_R_DN")
	)
	(segment
		(start 34.2265 -303.2379)
		(end 35.360102 -302.104298)
		(width 0.1143)
		(layer "F.Cu")
		(net "CLK_100M_DB800ZL_PEX0_S3_R_DN")
	)
	(segment
		(start 19.63293 -317.41364)
		(end 19.479514 -317.042546)
		(width 0.1143)
		(layer "F.Cu")
		(net "CLK_100M_DB800ZL_PEX0_S3_R_DN")
	)
	(segment
		(start 35.360102 -297.012106)
		(end 36.472368 -295.89984)
		(width 0.1143)
		(layer "F.Cu")
		(net "CLK_100M_DB800ZL_PEX0_S3_R_DN")
	)
	(segment
		(start 20.536662 -319.953894)
		(end 20.383246 -319.583308)
		(width 0.1143)
		(layer "F.Cu")
		(net "CLK_100M_DB800ZL_PEX0_S3_R_DN")
	)
	(segment
		(start 95.5294 -332.994)
		(end 95.5294 -331.597)
		(width 0.1143)
		(layer "F.Cu")
		(net "CLK_100M_DB800ZL_PEX0_S3_R_DN")
	)
	(segment
		(start 19.971004 -318.588136)
		(end 20.045172 -318.408812)
		(width 0.1143)
		(layer "F.Cu")
		(net "CLK_100M_DB800ZL_PEX0_S3_R_DN")
	)
	(segment
		(start 18.808446 -315.423296)
		(end 18.65503 -315.052202)
		(width 0.1143)
		(layer "F.Cu")
		(net "CLK_100M_DB800ZL_PEX0_S3_R_DN")
	)
	(segment
		(start 19.14652 -316.597792)
		(end 19.220688 -316.418468)
		(width 0.1143)
		(layer "F.Cu")
		(net "CLK_100M_DB800ZL_PEX0_S3_R_DN")
	)
	(segment
		(start 19.65325 -309.797958)
		(end 19.938746 -309.512462)
		(width 0.1143)
		(layer "F.Cu")
		(net "CLK_100M_DB800ZL_PEX0_S3_R_DN")
	)
	(segment
		(start 18.887694 -315.973206)
		(end 18.734278 -315.60262)
		(width 0.1143)
		(layer "F.Cu")
		(net "CLK_100M_DB800ZL_PEX0_S3_R_DN")
	)
	(segment
		(start 21.619972 -322.568824)
		(end 21.69414 -322.3895)
		(width 0.1143)
		(layer "F.Cu")
		(net "CLK_100M_DB800ZL_PEX0_S3_R_DN")
	)
	(segment
		(start 17.419574 -312.42889)
		(end 17.419574 -310.672226)
		(width 0.1143)
		(layer "F.Cu")
		(net "CLK_100M_DB800ZL_PEX0_S3_R_DN")
	)
	(segment
		(start 32.3723 -303.37506)
		(end 32.50946 -303.2379)
		(width 0.1143)
		(layer "F.Cu")
		(net "CLK_100M_DB800ZL_PEX0_S3_R_DN")
	)
	(segment
		(start 18.322036 -314.607448)
		(end 18.396204 -314.428124)
		(width 0.1143)
		(layer "F.Cu")
		(net "CLK_100M_DB800ZL_PEX0_S3_R_DN")
	)
	(segment
		(start 30.35554 -303.2379)
		(end 30.75686 -303.2379)
		(width 0.1143)
		(layer "F.Cu")
		(net "CLK_100M_DB800ZL_PEX0_S3_R_DN")
	)
	(segment
		(start 20.418552 -309.032656)
		(end 26.213308 -303.2379)
		(width 0.1143)
		(layer "F.Cu")
		(net "CLK_100M_DB800ZL_PEX0_S3_R_DN")
	)
	(segment
		(start 19.479514 -317.042546)
		(end 19.299936 -316.968378)
		(width 0.1143)
		(layer "F.Cu")
		(net "CLK_100M_DB800ZL_PEX0_S3_R_DN")
	)
	(segment
		(start 19.712178 -317.96355)
		(end 19.558762 -317.592964)
		(width 0.1143)
		(layer "F.Cu")
		(net "CLK_100M_DB800ZL_PEX0_S3_R_DN")
	)
	(segment
		(start 20.795488 -320.57848)
		(end 20.869656 -320.399156)
		(width 0.1143)
		(layer "F.Cu")
		(net "CLK_100M_DB800ZL_PEX0_S3_R_DN")
	)
	(segment
		(start 31.83382 -303.2379)
		(end 31.97098 -303.37506)
		(width 0.1143)
		(layer "F.Cu")
		(net "CLK_100M_DB800ZL_PEX0_S3_R_DN")
	)
	(segment
		(start 21.281898 -321.394328)
		(end 21.128482 -321.023488)
		(width 0.1143)
		(layer "F.Cu")
		(net "CLK_100M_DB800ZL_PEX0_S3_R_DN")
	)
	(segment
		(start 17.909794 -313.612276)
		(end 17.983962 -313.433206)
		(width 0.1143)
		(layer "F.Cu")
		(net "CLK_100M_DB800ZL_PEX0_S3_R_DN")
	)
	(segment
		(start 22.941788 -325.760588)
		(end 21.619972 -322.568824)
		(width 0.1143)
		(layer "F.Cu")
		(net "CLK_100M_DB800ZL_PEX0_S3_R_DN")
	)
	(segment
		(start 29.14142 -303.37506)
		(end 29.27858 -303.2379)
		(width 0.1143)
		(layer "F.Cu")
		(net "CLK_100M_DB800ZL_PEX0_S3_R_DN")
	)
	(segment
		(start 92.889578 -328.957178)
		(end 28.046426 -328.957178)
		(width 0.1143)
		(layer "F.Cu")
		(net "CLK_100M_DB800ZL_PEX0_S3_R_DN")
	)
	(segment
		(start 29.27858 -303.2379)
		(end 29.6799 -303.2379)
		(width 0.1143)
		(layer "F.Cu")
		(net "CLK_100M_DB800ZL_PEX0_S3_R_DN")
	)
	(segment
		(start 94.820994 -333.702406)
		(end 95.5294 -332.994)
		(width 0.1143)
		(layer "F.Cu")
		(net "CLK_100M_DB800ZL_PEX0_S3_R_DN")
	)
	(segment
		(start 32.91078 -303.2379)
		(end 33.04794 -303.37506)
		(width 0.1143)
		(layer "F.Cu")
		(net "CLK_100M_DB800ZL_PEX0_S3_R_DN")
	)
	(segment
		(start 19.299936 -316.968378)
		(end 19.14652 -316.597792)
		(width 0.1143)
		(layer "F.Cu")
		(net "CLK_100M_DB800ZL_PEX0_S3_R_DN")
	)
	(segment
		(start 20.457414 -319.403984)
		(end 20.303998 -319.03289)
		(width 0.1143)
		(layer "F.Cu")
		(net "CLK_100M_DB800ZL_PEX0_S3_R_DN")
	)
	(segment
		(start 28.60294 -303.2379)
		(end 28.7401 -303.37506)
		(width 0.1143)
		(layer "F.Cu")
		(net "CLK_100M_DB800ZL_PEX0_S3_R_DN")
	)
	(segment
		(start 20.383246 -319.583308)
		(end 20.457414 -319.403984)
		(width 0.1143)
		(layer "F.Cu")
		(net "CLK_100M_DB800ZL_PEX0_S3_R_DN")
	)
	(segment
		(start 18.475452 -314.978034)
		(end 18.322036 -314.607448)
		(width 0.1143)
		(layer "F.Cu")
		(net "CLK_100M_DB800ZL_PEX0_S3_R_DN")
	)
	(segment
		(start 19.891756 -318.037718)
		(end 19.712178 -317.96355)
		(width 0.1143)
		(layer "F.Cu")
		(net "CLK_100M_DB800ZL_PEX0_S3_R_DN")
	)
	(segment
		(start 20.12442 -318.958722)
		(end 19.971004 -318.588136)
		(width 0.1143)
		(layer "F.Cu")
		(net "CLK_100M_DB800ZL_PEX0_S3_R_DN")
	)
	(segment
		(start 35.360102 -302.104298)
		(end 35.360102 -297.012106)
		(width 0.1143)
		(layer "F.Cu")
		(net "CLK_100M_DB800ZL_PEX0_S3_R_DN")
	)
	(segment
		(start 20.948904 -320.949066)
		(end 20.795488 -320.57848)
		(width 0.1143)
		(layer "F.Cu")
		(net "CLK_100M_DB800ZL_PEX0_S3_R_DN")
	)
	(segment
		(start 26.213308 -303.2379)
		(end 28.60294 -303.2379)
		(width 0.1143)
		(layer "F.Cu")
		(net "CLK_100M_DB800ZL_PEX0_S3_R_DN")
	)
	(segment
		(start 30.75686 -303.2379)
		(end 30.89402 -303.37506)
		(width 0.1143)
		(layer "F.Cu")
		(net "CLK_100M_DB800ZL_PEX0_S3_R_DN")
	)
	(segment
		(start 19.067272 -316.047374)
		(end 18.887694 -315.973206)
		(width 0.1143)
		(layer "F.Cu")
		(net "CLK_100M_DB800ZL_PEX0_S3_R_DN")
	)
	(segment
		(start 18.293842 -309.797958)
		(end 19.65325 -309.797958)
		(width 0.1143)
		(layer "F.Cu")
		(net "CLK_100M_DB800ZL_PEX0_S3_R_DN")
	)
	(segment
		(start 21.128482 -321.023488)
		(end 20.948904 -320.949066)
		(width 0.1143)
		(layer "F.Cu")
		(net "CLK_100M_DB800ZL_PEX0_S3_R_DN")
	)
	(segment
		(start 33.04794 -303.37506)
		(end 33.44926 -303.37506)
		(width 0.1143)
		(layer "F.Cu")
		(net "CLK_100M_DB800ZL_PEX0_S3_R_DN")
	)
	(segment
		(start 30.21838 -303.37506)
		(end 30.35554 -303.2379)
		(width 0.1143)
		(layer "F.Cu")
		(net "CLK_100M_DB800ZL_PEX0_S3_R_DN")
	)
	(segment
		(start 94.278958 -333.702406)
		(end 94.820994 -333.702406)
		(width 0.1143)
		(layer "F.Cu")
		(net "CLK_100M_DB800ZL_PEX0_S3_R_DN")
	)
	(segment
		(start 31.97098 -303.37506)
		(end 32.3723 -303.37506)
		(width 0.1143)
		(layer "F.Cu")
		(net "CLK_100M_DB800ZL_PEX0_S3_R_DN")
	)
	(segment
		(start 17.830546 -313.062112)
		(end 17.650968 -312.987944)
		(width 0.1143)
		(layer "F.Cu")
		(net "CLK_100M_DB800ZL_PEX0_S3_R_DN")
	)
	(segment
		(start 94.031308 -333.950056)
		(end 94.278958 -333.702406)
		(width 0.1143)
		(layer "F.Cu")
		(net "CLK_100M_DB800ZL_PEX0_S3_R_DN")
	)
	(segment
		(start 32.50946 -303.2379)
		(end 32.91078 -303.2379)
		(width 0.1143)
		(layer "F.Cu")
		(net "CLK_100M_DB800ZL_PEX0_S3_R_DN")
	)
	(segment
		(start 17.419574 -310.672226)
		(end 18.293842 -309.797958)
		(width 0.1143)
		(layer "F.Cu")
		(net "CLK_100M_DB800ZL_PEX0_S3_R_DN")
	)
	(segment
		(start 21.361146 -321.944238)
		(end 21.20773 -321.573652)
		(width 0.1143)
		(layer "F.Cu")
		(net "CLK_100M_DB800ZL_PEX0_S3_R_DN")
	)
	(segment
		(start 19.220688 -316.418468)
		(end 19.067272 -316.047374)
		(width 0.1143)
		(layer "F.Cu")
		(net "CLK_100M_DB800ZL_PEX0_S3_R_DN")
	)
	(via
		(at 94.031308 -333.950056)
		(size 0.508)
		(drill 0.254)
		(layers "F.Cu" "B.Cu")
		(net "CLK_100M_DB800ZL_PEX0_S3_R_DN")
	)
	(segment
		(start 94.272608 -333.708756)
		(end 94.031308 -333.950056)
		(width 0.1143)
		(layer "B.Cu")
		(net "CLK_100M_DB800ZL_PEX0_S3_R_DN")
	)
	(segment
		(start 97.556574 -352.3996)
		(end 96.98609 -352.3996)
		(width 0.1143)
		(layer "B.Cu")
		(net "CLK_100M_DB800ZL_PEX0_S3_R_DN")
	)
	(segment
		(start 96.98609 -352.3996)
		(end 96.417384 -351.830894)
		(width 0.1143)
		(layer "B.Cu")
		(net "CLK_100M_DB800ZL_PEX0_S3_R_DN")
	)
	(segment
		(start 95.204534 -333.708756)
		(end 94.272608 -333.708756)
		(width 0.1143)
		(layer "B.Cu")
		(net "CLK_100M_DB800ZL_PEX0_S3_R_DN")
	)
	(segment
		(start 97.892362 -352.735388)
		(end 97.556574 -352.3996)
		(width 0.1143)
		(layer "B.Cu")
		(net "CLK_100M_DB800ZL_PEX0_S3_R_DN")
	)
	(segment
		(start 95.5421 -337.073494)
		(end 95.5421 -334.046322)
		(width 0.1143)
		(layer "B.Cu")
		(net "CLK_100M_DB800ZL_PEX0_S3_R_DN")
	)
	(segment
		(start 95.5421 -334.046322)
		(end 95.204534 -333.708756)
		(width 0.1143)
		(layer "B.Cu")
		(net "CLK_100M_DB800ZL_PEX0_S3_R_DN")
	)
	(segment
		(start 96.417384 -337.948778)
		(end 95.5421 -337.073494)
		(width 0.1143)
		(layer "B.Cu")
		(net "CLK_100M_DB800ZL_PEX0_S3_R_DN")
	)
	(segment
		(start 96.417384 -351.830894)
		(end 96.417384 -337.948778)
		(width 0.1143)
		(layer "B.Cu")
		(net "CLK_100M_DB800ZL_PEX0_S3_R_DN")
	)
	(segment
		(start 86.72957 -301.02048)
		(end 86.72957 -301.315882)
		(width 0.13208)
		(layer "F.Cu")
		(net "RST_PEX0_S3_PERST_R_N")
	)
	(segment
		(start 71.999856 -306.349908)
		(end 71.524876 -306.824888)
		(width 0.13208)
		(layer "F.Cu")
		(net "RST_PEX0_S3_PERST_R_N")
	)
	(segment
		(start 86.72957 -301.315882)
		(end 86.303104 -301.742348)
		(width 0.13208)
		(layer "F.Cu")
		(net "RST_PEX0_S3_PERST_R_N")
	)
	(via
		(at 71.524876 -306.824888)
		(size 0.4064)
		(drill 0.2032)
		(layers "F.Cu" "B.Cu")
		(net "RST_PEX0_S3_PERST_R_N")
	)
	(via
		(at 86.303104 -301.742348)
		(size 0.508)
		(drill 0.254)
		(layers "F.Cu" "B.Cu")
		(net "RST_PEX0_S3_PERST_R_N")
	)
	(segment
		(start 71.9836 -306.366164)
		(end 71.9836 -304.5714)
		(width 0.13208)
		(layer "B.Cu")
		(net "RST_PEX0_S3_PERST_R_N")
	)
	(segment
		(start 78.2066 -304.0126)
		(end 78.810612 -303.408588)
		(width 0.13208)
		(layer "B.Cu")
		(net "RST_PEX0_S3_PERST_R_N")
	)
	(segment
		(start 78.810612 -303.408588)
		(end 85.160612 -303.408588)
		(width 0.13208)
		(layer "B.Cu")
		(net "RST_PEX0_S3_PERST_R_N")
	)
	(segment
		(start 71.524876 -306.824888)
		(end 71.9836 -306.366164)
		(width 0.13208)
		(layer "B.Cu")
		(net "RST_PEX0_S3_PERST_R_N")
	)
	(segment
		(start 86.303104 -302.266096)
		(end 86.303104 -301.742348)
		(width 0.13208)
		(layer "B.Cu")
		(net "RST_PEX0_S3_PERST_R_N")
	)
	(segment
		(start 72.1614 -304.3936)
		(end 72.745854 -304.3936)
		(width 0.13208)
		(layer "B.Cu")
		(net "RST_PEX0_S3_PERST_R_N")
	)
	(segment
		(start 71.9836 -304.5714)
		(end 72.1614 -304.3936)
		(width 0.13208)
		(layer "B.Cu")
		(net "RST_PEX0_S3_PERST_R_N")
	)
	(segment
		(start 73.126854 -304.0126)
		(end 78.2066 -304.0126)
		(width 0.13208)
		(layer "B.Cu")
		(net "RST_PEX0_S3_PERST_R_N")
	)
	(segment
		(start 72.745854 -304.3936)
		(end 73.126854 -304.0126)
		(width 0.13208)
		(layer "B.Cu")
		(net "RST_PEX0_S3_PERST_R_N")
	)
	(segment
		(start 85.160612 -303.408588)
		(end 86.303104 -302.266096)
		(width 0.13208)
		(layer "B.Cu")
		(net "RST_PEX0_S3_PERST_R_N")
	)
	(segment
		(start 343.69375 -224.786952)
		(end 344.093546 -225.186748)
		(width 0.13208)
		(layer "F.Cu")
		(net "Net_404")
	)
	(via
		(at 344.093546 -225.186748)
		(size 0.4572)
		(drill 0.254)
		(layers "F.Cu" "B.Cu")
		(net "Net_404")
	)
	(segment
		(start 202.4126 -299.803312)
		(end 202.4126 -298.2722)
		(width 0.13208)
		(layer "F.Cu")
		(net "RST_PEX1_S3_PERST_N")
	)
	(segment
		(start 202.4126 -298.2722)
		(end 202.781662 -297.903138)
		(width 0.13208)
		(layer "F.Cu")
		(net "RST_PEX1_S3_PERST_N")
	)
	(segment
		(start 202.829668 -300.22038)
		(end 202.4126 -299.803312)
		(width 0.13208)
		(layer "F.Cu")
		(net "RST_PEX1_S3_PERST_N")
	)
	(segment
		(start 202.781662 -297.690794)
		(end 202.781662 -296.623232)
		(width 0.13208)
		(layer "F.Cu")
		(net "RST_PEX1_S3_PERST_N")
	)
	(segment
		(start 202.781662 -297.903138)
		(end 202.781662 -297.690794)
		(width 0.13208)
		(layer "F.Cu")
		(net "RST_PEX1_S3_PERST_N")
	)
	(via
		(at 202.781662 -297.690794)
		(size 0.508)
		(drill 0.254)
		(layers "F.Cu" "B.Cu")
		(net "RST_PEX1_S3_PERST_N")
	)
	(segment
		(start 204.081888 -298.23664)
		(end 204.081888 -296.623232)
		(width 0.13208)
		(layer "F.Cu")
		(net "RST_PEX1_S1_PERST_N")
	)
	(segment
		(start 203.849732 -300.2026)
		(end 203.849732 -298.468796)
		(width 0.13208)
		(layer "F.Cu")
		(net "RST_PEX1_S1_PERST_N")
	)
	(segment
		(start 203.861924 -298.456604)
		(end 204.081888 -298.23664)
		(width 0.13208)
		(layer "F.Cu")
		(net "RST_PEX1_S1_PERST_N")
	)
	(segment
		(start 203.849732 -298.468796)
		(end 203.861924 -298.456604)
		(width 0.13208)
		(layer "F.Cu")
		(net "RST_PEX1_S1_PERST_N")
	)
	(via
		(at 203.861924 -298.456604)
		(size 0.762)
		(drill 0.381)
		(layers "F.Cu" "B.Cu")
		(net "RST_PEX1_S1_PERST_N")
	)
	(segment
		(start 201.635868 -291.22497)
		(end 201.635868 -290.419536)
		(width 0.13208)
		(layer "F.Cu")
		(net "RST_PEX1_S0_PERST_N")
	)
	(segment
		(start 202.409298 -291.9984)
		(end 201.635868 -291.22497)
		(width 0.13208)
		(layer "F.Cu")
		(net "RST_PEX1_S0_PERST_N")
	)
	(segment
		(start 201.635868 -290.419536)
		(end 201.635868 -289.630866)
		(width 0.13208)
		(layer "F.Cu")
		(net "RST_PEX1_S0_PERST_N")
	)
	(segment
		(start 202.781662 -292.923468)
		(end 202.781662 -292.142164)
		(width 0.13208)
		(layer "F.Cu")
		(net "RST_PEX1_S0_PERST_N")
	)
	(segment
		(start 202.637898 -291.9984)
		(end 202.409298 -291.9984)
		(width 0.13208)
		(layer "F.Cu")
		(net "RST_PEX1_S0_PERST_N")
	)
	(segment
		(start 202.781662 -292.142164)
		(end 202.637898 -291.9984)
		(width 0.13208)
		(layer "F.Cu")
		(net "RST_PEX1_S0_PERST_N")
	)
	(via
		(at 201.635868 -290.419536)
		(size 0.508)
		(drill 0.254)
		(layers "F.Cu" "B.Cu")
		(net "RST_PEX1_S0_PERST_N")
	)
	(via
		(at 201.862182 -232.532682)
		(size 0.6604)
		(drill 0.3302)
		(layers "F.Cu" "B.Cu")
		(net "SMB_PEX0_MUX_SDA")
	)
	(segment
		(start 201.210926 -253.100586)
		(end 198.5772 -250.46686)
		(width 0.13208)
		(layer "B.Cu")
		(net "SMB_PEX0_MUX_SDA")
	)
	(segment
		(start 198.5772 -250.46686)
		(end 198.5772 -235.817664)
		(width 0.13208)
		(layer "B.Cu")
		(net "SMB_PEX0_MUX_SDA")
	)
	(segment
		(start 204.764894 -258.279646)
		(end 204.764894 -254.530606)
		(width 0.13208)
		(layer "B.Cu")
		(net "SMB_PEX0_MUX_SDA")
	)
	(segment
		(start 208.029302 -230.068882)
		(end 207.766412 -229.805992)
		(width 0.13208)
		(layer "B.Cu")
		(net "SMB_PEX0_MUX_SDA")
	)
	(segment
		(start 204.588872 -229.805992)
		(end 201.862182 -232.532682)
		(width 0.13208)
		(layer "B.Cu")
		(net "SMB_PEX0_MUX_SDA")
	)
	(segment
		(start 204.764894 -253.597918)
		(end 204.267562 -253.100586)
		(width 0.13208)
		(layer "B.Cu")
		(net "SMB_PEX0_MUX_SDA")
	)
	(segment
		(start 198.5772 -235.817664)
		(end 201.862182 -232.532682)
		(width 0.13208)
		(layer "B.Cu")
		(net "SMB_PEX0_MUX_SDA")
	)
	(segment
		(start 204.132942 -258.911598)
		(end 204.764894 -258.279646)
		(width 0.13208)
		(layer "B.Cu")
		(net "SMB_PEX0_MUX_SDA")
	)
	(segment
		(start 212.409532 -230.113078)
		(end 212.084412 -229.787958)
		(width 0.13208)
		(layer "B.Cu")
		(net "SMB_PEX0_MUX_SDA")
	)
	(segment
		(start 210.411314 -230.068882)
		(end 208.029302 -230.068882)
		(width 0.13208)
		(layer "B.Cu")
		(net "SMB_PEX0_MUX_SDA")
	)
	(segment
		(start 210.692238 -229.787958)
		(end 210.411314 -230.068882)
		(width 0.13208)
		(layer "B.Cu")
		(net "SMB_PEX0_MUX_SDA")
	)
	(segment
		(start 204.267562 -253.100586)
		(end 201.210926 -253.100586)
		(width 0.13208)
		(layer "B.Cu")
		(net "SMB_PEX0_MUX_SDA")
	)
	(segment
		(start 212.084412 -229.787958)
		(end 210.692238 -229.787958)
		(width 0.13208)
		(layer "B.Cu")
		(net "SMB_PEX0_MUX_SDA")
	)
	(segment
		(start 212.409532 -230.25354)
		(end 212.409532 -230.113078)
		(width 0.13208)
		(layer "B.Cu")
		(net "SMB_PEX0_MUX_SDA")
	)
	(segment
		(start 204.764894 -254.530606)
		(end 204.764894 -253.597918)
		(width 0.13208)
		(layer "B.Cu")
		(net "SMB_PEX0_MUX_SDA")
	)
	(segment
		(start 207.766412 -229.805992)
		(end 204.588872 -229.805992)
		(width 0.13208)
		(layer "B.Cu")
		(net "SMB_PEX0_MUX_SDA")
	)
	(via
		(at 209.181446 -256.434082)
		(size 0.6604)
		(drill 0.3302)
		(layers "F.Cu" "B.Cu")
		(net "SMB_PEX3_MUX_SDA")
	)
	(segment
		(start 201.747374 -249.871992)
		(end 202.354688 -250.479306)
		(width 0.13208)
		(layer "B.Cu")
		(net "SMB_PEX3_MUX_SDA")
	)
	(segment
		(start 206.593186 -235.00334)
		(end 201.747374 -239.849152)
		(width 0.13208)
		(layer "B.Cu")
		(net "SMB_PEX3_MUX_SDA")
	)
	(segment
		(start 205.819756 -250.479306)
		(end 208.665064 -253.324614)
		(width 0.13208)
		(layer "B.Cu")
		(net "SMB_PEX3_MUX_SDA")
	)
	(segment
		(start 208.665064 -255.9177)
		(end 209.181446 -256.434082)
		(width 0.13208)
		(layer "B.Cu")
		(net "SMB_PEX3_MUX_SDA")
	)
	(segment
		(start 210.228942 -258.911598)
		(end 210.228942 -257.481578)
		(width 0.13208)
		(layer "B.Cu")
		(net "SMB_PEX3_MUX_SDA")
	)
	(segment
		(start 208.665064 -254.530606)
		(end 208.665064 -255.9177)
		(width 0.13208)
		(layer "B.Cu")
		(net "SMB_PEX3_MUX_SDA")
	)
	(segment
		(start 201.747374 -239.849152)
		(end 201.747374 -249.871992)
		(width 0.13208)
		(layer "B.Cu")
		(net "SMB_PEX3_MUX_SDA")
	)
	(segment
		(start 210.228942 -257.481578)
		(end 209.181446 -256.434082)
		(width 0.13208)
		(layer "B.Cu")
		(net "SMB_PEX3_MUX_SDA")
	)
	(segment
		(start 213.05901 -235.00334)
		(end 206.593186 -235.00334)
		(width 0.13208)
		(layer "B.Cu")
		(net "SMB_PEX3_MUX_SDA")
	)
	(segment
		(start 208.665064 -253.324614)
		(end 208.665064 -254.530606)
		(width 0.13208)
		(layer "B.Cu")
		(net "SMB_PEX3_MUX_SDA")
	)
	(segment
		(start 202.354688 -250.479306)
		(end 205.819756 -250.479306)
		(width 0.13208)
		(layer "B.Cu")
		(net "SMB_PEX3_MUX_SDA")
	)
	(segment
		(start 213.456774 -234.605576)
		(end 213.05901 -235.00334)
		(width 0.13208)
		(layer "B.Cu")
		(net "SMB_PEX3_MUX_SDA")
	)
	(via
		(at 210.697318 -256.616962)
		(size 0.6604)
		(drill 0.3302)
		(layers "F.Cu" "B.Cu")
		(net "SMB_PEX3_MUX_SCL")
	)
	(segment
		(start 209.31505 -254.530606)
		(end 209.31505 -255.234694)
		(width 0.13208)
		(layer "B.Cu")
		(net "SMB_PEX3_MUX_SCL")
	)
	(segment
		(start 206.031338 -250.042426)
		(end 209.31505 -253.326138)
		(width 0.13208)
		(layer "B.Cu")
		(net "SMB_PEX3_MUX_SCL")
	)
	(segment
		(start 214.143844 -235.904024)
		(end 213.072218 -235.904024)
		(width 0.13208)
		(layer "B.Cu")
		(net "SMB_PEX3_MUX_SCL")
	)
	(segment
		(start 207.072992 -235.44022)
		(end 202.204066 -240.309146)
		(width 0.13208)
		(layer "B.Cu")
		(net "SMB_PEX3_MUX_SCL")
	)
	(segment
		(start 211.244942 -258.911598)
		(end 211.244942 -257.164586)
		(width 0.13208)
		(layer "B.Cu")
		(net "SMB_PEX3_MUX_SCL")
	)
	(segment
		(start 214.472774 -234.605576)
		(end 214.472774 -235.575094)
		(width 0.13208)
		(layer "B.Cu")
		(net "SMB_PEX3_MUX_SCL")
	)
	(segment
		(start 209.31505 -253.326138)
		(end 209.31505 -254.530606)
		(width 0.13208)
		(layer "B.Cu")
		(net "SMB_PEX3_MUX_SCL")
	)
	(segment
		(start 202.204066 -240.309146)
		(end 202.204066 -249.575574)
		(width 0.13208)
		(layer "B.Cu")
		(net "SMB_PEX3_MUX_SCL")
	)
	(segment
		(start 213.072218 -235.904024)
		(end 212.608414 -235.44022)
		(width 0.13208)
		(layer "B.Cu")
		(net "SMB_PEX3_MUX_SCL")
	)
	(segment
		(start 214.472774 -235.575094)
		(end 214.143844 -235.904024)
		(width 0.13208)
		(layer "B.Cu")
		(net "SMB_PEX3_MUX_SCL")
	)
	(segment
		(start 212.608414 -235.44022)
		(end 207.072992 -235.44022)
		(width 0.13208)
		(layer "B.Cu")
		(net "SMB_PEX3_MUX_SCL")
	)
	(segment
		(start 209.31505 -255.234694)
		(end 210.697318 -256.616962)
		(width 0.13208)
		(layer "B.Cu")
		(net "SMB_PEX3_MUX_SCL")
	)
	(segment
		(start 202.670918 -250.042426)
		(end 206.031338 -250.042426)
		(width 0.13208)
		(layer "B.Cu")
		(net "SMB_PEX3_MUX_SCL")
	)
	(segment
		(start 202.204066 -249.575574)
		(end 202.670918 -250.042426)
		(width 0.13208)
		(layer "B.Cu")
		(net "SMB_PEX3_MUX_SCL")
	)
	(segment
		(start 211.244942 -257.164586)
		(end 210.697318 -256.616962)
		(width 0.13208)
		(layer "B.Cu")
		(net "SMB_PEX3_MUX_SCL")
	)
	(via
		(at 202.483212 -234.377484)
		(size 0.6604)
		(drill 0.3302)
		(layers "F.Cu" "B.Cu")
		(net "SMB_PEX1_MUX_SDA")
	)
	(segment
		(start 206.064866 -254.530606)
		(end 206.064866 -253.482602)
		(width 0.13208)
		(layer "B.Cu")
		(net "SMB_PEX1_MUX_SDA")
	)
	(segment
		(start 199.5424 -237.318296)
		(end 202.483212 -234.377484)
		(width 0.13208)
		(layer "B.Cu")
		(net "SMB_PEX1_MUX_SDA")
	)
	(segment
		(start 199.5424 -250.195588)
		(end 199.5424 -237.318296)
		(width 0.13208)
		(layer "B.Cu")
		(net "SMB_PEX1_MUX_SDA")
	)
	(segment
		(start 204.80909 -252.226826)
		(end 201.573638 -252.226826)
		(width 0.13208)
		(layer "B.Cu")
		(net "SMB_PEX1_MUX_SDA")
	)
	(segment
		(start 206.164942 -258.911598)
		(end 206.064866 -258.811522)
		(width 0.13208)
		(layer "B.Cu")
		(net "SMB_PEX1_MUX_SDA")
	)
	(segment
		(start 206.064866 -258.811522)
		(end 206.064866 -254.530606)
		(width 0.13208)
		(layer "B.Cu")
		(net "SMB_PEX1_MUX_SDA")
	)
	(segment
		(start 206.064866 -253.482602)
		(end 204.80909 -252.226826)
		(width 0.13208)
		(layer "B.Cu")
		(net "SMB_PEX1_MUX_SDA")
	)
	(segment
		(start 201.573638 -252.226826)
		(end 199.5424 -250.195588)
		(width 0.13208)
		(layer "B.Cu")
		(net "SMB_PEX1_MUX_SDA")
	)
	(segment
		(start 205.712568 -232.58907)
		(end 204.271626 -232.58907)
		(width 0.13208)
		(layer "B.Cu")
		(net "SMB_PEX1_MUX_SDA")
	)
	(segment
		(start 204.271626 -232.58907)
		(end 202.483212 -234.377484)
		(width 0.13208)
		(layer "B.Cu")
		(net "SMB_PEX1_MUX_SDA")
	)
	(via
		(at 204.090778 -235.254038)
		(size 0.6604)
		(drill 0.3302)
		(layers "F.Cu" "B.Cu")
		(net "SMB_PEX2_MUX_SDA")
	)
	(segment
		(start 205.405736 -251.353066)
		(end 201.93635 -251.353066)
		(width 0.13208)
		(layer "B.Cu")
		(net "SMB_PEX2_MUX_SDA")
	)
	(segment
		(start 208.888584 -234.12958)
		(end 205.215236 -234.12958)
		(width 0.13208)
		(layer "B.Cu")
		(net "SMB_PEX2_MUX_SDA")
	)
	(segment
		(start 207.365092 -256.188972)
		(end 207.365092 -254.530606)
		(width 0.13208)
		(layer "B.Cu")
		(net "SMB_PEX2_MUX_SDA")
	)
	(segment
		(start 208.196942 -257.020822)
		(end 207.365092 -256.188972)
		(width 0.13208)
		(layer "B.Cu")
		(net "SMB_PEX2_MUX_SDA")
	)
	(segment
		(start 200.51268 -238.832136)
		(end 204.090778 -235.254038)
		(width 0.13208)
		(layer "B.Cu")
		(net "SMB_PEX2_MUX_SDA")
	)
	(segment
		(start 205.215236 -234.12958)
		(end 204.090778 -235.254038)
		(width 0.13208)
		(layer "B.Cu")
		(net "SMB_PEX2_MUX_SDA")
	)
	(segment
		(start 208.984342 -234.033822)
		(end 208.888584 -234.12958)
		(width 0.13208)
		(layer "B.Cu")
		(net "SMB_PEX2_MUX_SDA")
	)
	(segment
		(start 201.93635 -251.353066)
		(end 200.51268 -249.929396)
		(width 0.13208)
		(layer "B.Cu")
		(net "SMB_PEX2_MUX_SDA")
	)
	(segment
		(start 200.51268 -249.929396)
		(end 200.51268 -238.832136)
		(width 0.13208)
		(layer "B.Cu")
		(net "SMB_PEX2_MUX_SDA")
	)
	(segment
		(start 208.196942 -258.911598)
		(end 208.196942 -257.020822)
		(width 0.13208)
		(layer "B.Cu")
		(net "SMB_PEX2_MUX_SDA")
	)
	(segment
		(start 207.365092 -253.312422)
		(end 205.405736 -251.353066)
		(width 0.13208)
		(layer "B.Cu")
		(net "SMB_PEX2_MUX_SDA")
	)
	(segment
		(start 207.365092 -254.530606)
		(end 207.365092 -253.312422)
		(width 0.13208)
		(layer "B.Cu")
		(net "SMB_PEX2_MUX_SDA")
	)
	(via
		(at 201.31405 -236.93501)
		(size 0.6604)
		(drill 0.3302)
		(layers "F.Cu" "B.Cu")
		(net "SMB_PEX1_MUX_SCL")
	)
	(segment
		(start 206.715106 -253.374906)
		(end 205.130146 -251.789946)
		(width 0.13208)
		(layer "B.Cu")
		(net "SMB_PEX1_MUX_SCL")
	)
	(segment
		(start 207.180942 -256.744978)
		(end 206.715106 -256.279142)
		(width 0.13208)
		(layer "B.Cu")
		(net "SMB_PEX1_MUX_SCL")
	)
	(segment
		(start 207.180942 -258.911598)
		(end 207.180942 -256.744978)
		(width 0.13208)
		(layer "B.Cu")
		(net "SMB_PEX1_MUX_SCL")
	)
	(segment
		(start 204.562456 -233.686604)
		(end 201.31405 -236.93501)
		(width 0.13208)
		(layer "B.Cu")
		(net "SMB_PEX1_MUX_SCL")
	)
	(segment
		(start 206.715106 -256.279142)
		(end 206.715106 -254.530606)
		(width 0.13208)
		(layer "B.Cu")
		(net "SMB_PEX1_MUX_SCL")
	)
	(segment
		(start 200.0758 -238.17326)
		(end 201.31405 -236.93501)
		(width 0.13208)
		(layer "B.Cu")
		(net "SMB_PEX1_MUX_SCL")
	)
	(segment
		(start 206.715106 -254.530606)
		(end 206.715106 -253.374906)
		(width 0.13208)
		(layer "B.Cu")
		(net "SMB_PEX1_MUX_SCL")
	)
	(segment
		(start 205.130146 -251.789946)
		(end 201.754994 -251.789946)
		(width 0.13208)
		(layer "B.Cu")
		(net "SMB_PEX1_MUX_SCL")
	)
	(segment
		(start 200.0758 -250.110752)
		(end 200.0758 -238.17326)
		(width 0.13208)
		(layer "B.Cu")
		(net "SMB_PEX1_MUX_SCL")
	)
	(segment
		(start 207.100678 -233.686604)
		(end 204.562456 -233.686604)
		(width 0.13208)
		(layer "B.Cu")
		(net "SMB_PEX1_MUX_SCL")
	)
	(segment
		(start 201.754994 -251.789946)
		(end 200.0758 -250.110752)
		(width 0.13208)
		(layer "B.Cu")
		(net "SMB_PEX1_MUX_SCL")
	)
	(via
		(at 203.204572 -237.236)
		(size 0.6604)
		(drill 0.3302)
		(layers "F.Cu" "B.Cu")
		(net "SMB_PEX2_MUX_SCL")
	)
	(segment
		(start 210.732624 -234.56646)
		(end 205.874112 -234.56646)
		(width 0.13208)
		(layer "B.Cu")
		(net "SMB_PEX2_MUX_SCL")
	)
	(segment
		(start 202.173586 -250.916186)
		(end 200.9902 -249.7328)
		(width 0.13208)
		(layer "B.Cu")
		(net "SMB_PEX2_MUX_SCL")
	)
	(segment
		(start 210.81873 -234.480354)
		(end 210.732624 -234.56646)
		(width 0.13208)
		(layer "B.Cu")
		(net "SMB_PEX2_MUX_SCL")
	)
	(segment
		(start 205.627986 -250.916186)
		(end 202.173586 -250.916186)
		(width 0.13208)
		(layer "B.Cu")
		(net "SMB_PEX2_MUX_SCL")
	)
	(segment
		(start 208.015078 -254.530606)
		(end 208.015078 -253.303278)
		(width 0.13208)
		(layer "B.Cu")
		(net "SMB_PEX2_MUX_SCL")
	)
	(segment
		(start 200.9902 -249.7328)
		(end 200.9902 -239.450372)
		(width 0.13208)
		(layer "B.Cu")
		(net "SMB_PEX2_MUX_SCL")
	)
	(segment
		(start 209.212942 -257.388106)
		(end 208.015078 -256.190242)
		(width 0.13208)
		(layer "B.Cu")
		(net "SMB_PEX2_MUX_SCL")
	)
	(segment
		(start 208.015078 -253.303278)
		(end 205.627986 -250.916186)
		(width 0.13208)
		(layer "B.Cu")
		(net "SMB_PEX2_MUX_SCL")
	)
	(segment
		(start 209.212942 -258.911598)
		(end 209.212942 -257.388106)
		(width 0.13208)
		(layer "B.Cu")
		(net "SMB_PEX2_MUX_SCL")
	)
	(segment
		(start 205.874112 -234.56646)
		(end 203.204572 -237.236)
		(width 0.13208)
		(layer "B.Cu")
		(net "SMB_PEX2_MUX_SCL")
	)
	(segment
		(start 200.9902 -239.450372)
		(end 203.204572 -237.236)
		(width 0.13208)
		(layer "B.Cu")
		(net "SMB_PEX2_MUX_SCL")
	)
	(segment
		(start 208.015078 -256.190242)
		(end 208.015078 -254.530606)
		(width 0.13208)
		(layer "B.Cu")
		(net "SMB_PEX2_MUX_SCL")
	)
	(via
		(at 204.766672 -231.182164)
		(size 0.6604)
		(drill 0.3302)
		(layers "F.Cu" "B.Cu")
		(net "SMB_PEX0_MUX_SCL")
	)
	(segment
		(start 205.148942 -258.911598)
		(end 205.41488 -258.64566)
		(width 0.13208)
		(layer "B.Cu")
		(net "SMB_PEX0_MUX_SCL")
	)
	(segment
		(start 209.287364 -231.182164)
		(end 204.766672 -231.182164)
		(width 0.13208)
		(layer "B.Cu")
		(net "SMB_PEX0_MUX_SCL")
	)
	(segment
		(start 204.326744 -231.182164)
		(end 204.766672 -231.182164)
		(width 0.13208)
		(layer "B.Cu")
		(net "SMB_PEX0_MUX_SCL")
	)
	(segment
		(start 209.884772 -230.584756)
		(end 209.287364 -231.182164)
		(width 0.13208)
		(layer "B.Cu")
		(net "SMB_PEX0_MUX_SCL")
	)
	(segment
		(start 211.393532 -230.244396)
		(end 211.053172 -230.584756)
		(width 0.13208)
		(layer "B.Cu")
		(net "SMB_PEX0_MUX_SCL")
	)
	(segment
		(start 199.0598 -250.331224)
		(end 199.0598 -236.449108)
		(width 0.13208)
		(layer "B.Cu")
		(net "SMB_PEX0_MUX_SCL")
	)
	(segment
		(start 205.41488 -253.499366)
		(end 204.57922 -252.663706)
		(width 0.13208)
		(layer "B.Cu")
		(net "SMB_PEX0_MUX_SCL")
	)
	(segment
		(start 205.41488 -258.64566)
		(end 205.41488 -254.530606)
		(width 0.13208)
		(layer "B.Cu")
		(net "SMB_PEX0_MUX_SCL")
	)
	(segment
		(start 199.0598 -236.449108)
		(end 204.326744 -231.182164)
		(width 0.13208)
		(layer "B.Cu")
		(net "SMB_PEX0_MUX_SCL")
	)
	(segment
		(start 201.392282 -252.663706)
		(end 199.0598 -250.331224)
		(width 0.13208)
		(layer "B.Cu")
		(net "SMB_PEX0_MUX_SCL")
	)
	(segment
		(start 211.053172 -230.584756)
		(end 209.884772 -230.584756)
		(width 0.13208)
		(layer "B.Cu")
		(net "SMB_PEX0_MUX_SCL")
	)
	(segment
		(start 204.57922 -252.663706)
		(end 201.392282 -252.663706)
		(width 0.13208)
		(layer "B.Cu")
		(net "SMB_PEX0_MUX_SCL")
	)
	(segment
		(start 205.41488 -254.530606)
		(end 205.41488 -253.499366)
		(width 0.13208)
		(layer "B.Cu")
		(net "SMB_PEX0_MUX_SCL")
	)
	(via
		(at 207.78978 -247.071642)
		(size 0.6604)
		(drill 0.3302)
		(layers "F.Cu" "B.Cu")
		(net "PEX_MUX_A2")
	)
	(segment
		(start 207.78978 -247.071642)
		(end 205.50759 -247.071642)
		(width 0.13208)
		(layer "B.Cu")
		(net "PEX_MUX_A2")
	)
	(segment
		(start 209.60207 -247.086628)
		(end 209.587084 -247.071642)
		(width 0.13208)
		(layer "B.Cu")
		(net "PEX_MUX_A2")
	)
	(segment
		(start 210.691476 -247.086628)
		(end 209.60207 -247.086628)
		(width 0.13208)
		(layer "B.Cu")
		(net "PEX_MUX_A2")
	)
	(segment
		(start 209.587084 -247.071642)
		(end 207.78978 -247.071642)
		(width 0.13208)
		(layer "B.Cu")
		(net "PEX_MUX_A2")
	)
	(segment
		(start 205.50759 -247.071642)
		(end 204.764894 -247.814338)
		(width 0.13208)
		(layer "B.Cu")
		(net "PEX_MUX_A2")
	)
	(segment
		(start 204.764894 -247.814338)
		(end 204.764894 -248.930414)
		(width 0.13208)
		(layer "B.Cu")
		(net "PEX_MUX_A2")
	)
	(via
		(at 203.464922 -256.736342)
		(size 0.6604)
		(drill 0.3302)
		(layers "F.Cu" "B.Cu")
		(net "PEX_MUX_A1")
	)
	(segment
		(start 203.464922 -257.29819)
		(end 202.090274 -258.672838)
		(width 0.13208)
		(layer "B.Cu")
		(net "PEX_MUX_A1")
	)
	(segment
		(start 203.464922 -256.736342)
		(end 203.464922 -254.530606)
		(width 0.13208)
		(layer "B.Cu")
		(net "PEX_MUX_A1")
	)
	(segment
		(start 201.088244 -258.911598)
		(end 202.090274 -258.911598)
		(width 0.13208)
		(layer "B.Cu")
		(net "PEX_MUX_A1")
	)
	(segment
		(start 203.464922 -256.736342)
		(end 203.464922 -257.29819)
		(width 0.13208)
		(layer "B.Cu")
		(net "PEX_MUX_A1")
	)
	(segment
		(start 202.090274 -258.672838)
		(end 202.090274 -258.911598)
		(width 0.13208)
		(layer "B.Cu")
		(net "PEX_MUX_A1")
	)
	(via
		(at 201.62774 -257.332988)
		(size 0.6604)
		(drill 0.3302)
		(layers "F.Cu" "B.Cu")
		(net "PEX_MUX_A0")
	)
	(segment
		(start 200.058274 -258.902454)
		(end 201.62774 -257.332988)
		(width 0.13208)
		(layer "B.Cu")
		(net "PEX_MUX_A0")
	)
	(segment
		(start 202.814936 -256.145792)
		(end 202.814936 -254.530606)
		(width 0.13208)
		(layer "B.Cu")
		(net "PEX_MUX_A0")
	)
	(segment
		(start 199.049386 -258.911598)
		(end 200.058274 -258.911598)
		(width 0.13208)
		(layer "B.Cu")
		(net "PEX_MUX_A0")
	)
	(segment
		(start 201.62774 -257.332988)
		(end 202.814936 -256.145792)
		(width 0.13208)
		(layer "B.Cu")
		(net "PEX_MUX_A0")
	)
	(segment
		(start 200.058274 -258.911598)
		(end 200.058274 -258.902454)
		(width 0.13208)
		(layer "B.Cu")
		(net "PEX_MUX_A0")
	)
	(segment
		(start 208.96326 -235.36402)
		(end 207.815942 -236.511338)
		(width 0.13208)
		(layer "F.Cu")
		(net "SMB_PEX_MUX_SCL")
	)
	(segment
		(start 207.815942 -236.511338)
		(end 207.395826 -236.511338)
		(width 0.13208)
		(layer "F.Cu")
		(net "SMB_PEX_MUX_SCL")
	)
	(segment
		(start 210.054698 -235.36402)
		(end 208.96326 -235.36402)
		(width 0.13208)
		(layer "F.Cu")
		(net "SMB_PEX_MUX_SCL")
	)
	(via
		(at 207.395826 -236.511338)
		(size 0.508)
		(drill 0.254)
		(layers "F.Cu" "B.Cu")
		(net "SMB_PEX_MUX_SCL")
	)
	(via
		(at 208.998566 -243.995956)
		(size 0.6604)
		(drill 0.3302)
		(layers "F.Cu" "B.Cu")
		(net "SMB_PEX_MUX_SCL")
	)
	(segment
		(start 209.15376 -243.995956)
		(end 210.898232 -242.251484)
		(width 0.13208)
		(layer "B.Cu")
		(net "SMB_PEX_MUX_SCL")
	)
	(segment
		(start 210.085432 -238.48822)
		(end 208.10855 -236.511338)
		(width 0.13208)
		(layer "B.Cu")
		(net "SMB_PEX_MUX_SCL")
	)
	(segment
		(start 208.998566 -243.995956)
		(end 207.884522 -243.995956)
		(width 0.13208)
		(layer "B.Cu")
		(net "SMB_PEX_MUX_SCL")
	)
	(segment
		(start 208.10855 -236.511338)
		(end 207.395826 -236.511338)
		(width 0.13208)
		(layer "B.Cu")
		(net "SMB_PEX_MUX_SCL")
	)
	(segment
		(start 207.884522 -243.995956)
		(end 204.114908 -247.76557)
		(width 0.13208)
		(layer "B.Cu")
		(net "SMB_PEX_MUX_SCL")
	)
	(segment
		(start 204.114908 -247.76557)
		(end 204.114908 -248.930414)
		(width 0.13208)
		(layer "B.Cu")
		(net "SMB_PEX_MUX_SCL")
	)
	(segment
		(start 208.998566 -243.995956)
		(end 209.15376 -243.995956)
		(width 0.13208)
		(layer "B.Cu")
		(net "SMB_PEX_MUX_SCL")
	)
	(segment
		(start 210.898232 -242.251484)
		(end 210.898232 -240.579656)
		(width 0.13208)
		(layer "B.Cu")
		(net "SMB_PEX_MUX_SCL")
	)
	(segment
		(start 210.085432 -239.766856)
		(end 210.085432 -238.48822)
		(width 0.13208)
		(layer "B.Cu")
		(net "SMB_PEX_MUX_SCL")
	)
	(segment
		(start 210.898232 -240.579656)
		(end 210.085432 -239.766856)
		(width 0.13208)
		(layer "B.Cu")
		(net "SMB_PEX_MUX_SCL")
	)
	(segment
		(start 215.69807 -235.365036)
		(end 215.69807 -234.728766)
		(width 0.13208)
		(layer "F.Cu")
		(net "SMB_PEX_MUX_SDA")
	)
	(via
		(at 207.576166 -237.577376)
		(size 0.6604)
		(drill 0.3302)
		(layers "F.Cu" "B.Cu")
		(net "SMB_PEX_MUX_SDA")
	)
	(via
		(at 215.69807 -234.728766)
		(size 0.508)
		(drill 0.254)
		(layers "F.Cu" "B.Cu")
		(net "SMB_PEX_MUX_SDA")
	)
	(segment
		(start 203.464922 -247.49633)
		(end 207.615282 -243.34597)
		(width 0.13208)
		(layer "B.Cu")
		(net "SMB_PEX_MUX_SDA")
	)
	(segment
		(start 208.52384 -238.52505)
		(end 207.576166 -237.577376)
		(width 0.13208)
		(layer "B.Cu")
		(net "SMB_PEX_MUX_SDA")
	)
	(segment
		(start 207.220058 -235.92536)
		(end 206.907384 -236.238034)
		(width 0.13208)
		(layer "B.Cu")
		(net "SMB_PEX_MUX_SDA")
	)
	(segment
		(start 207.615282 -243.34597)
		(end 208.580228 -243.34597)
		(width 0.13208)
		(layer "B.Cu")
		(net "SMB_PEX_MUX_SDA")
	)
	(segment
		(start 215.69807 -235.067602)
		(end 214.423498 -236.342174)
		(width 0.13208)
		(layer "B.Cu")
		(net "SMB_PEX_MUX_SDA")
	)
	(segment
		(start 208.580228 -243.34597)
		(end 209.885026 -242.041172)
		(width 0.13208)
		(layer "B.Cu")
		(net "SMB_PEX_MUX_SDA")
	)
	(segment
		(start 210.243928 -235.92536)
		(end 207.220058 -235.92536)
		(width 0.13208)
		(layer "B.Cu")
		(net "SMB_PEX_MUX_SDA")
	)
	(segment
		(start 209.885026 -240.571274)
		(end 208.52384 -239.210088)
		(width 0.13208)
		(layer "B.Cu")
		(net "SMB_PEX_MUX_SDA")
	)
	(segment
		(start 208.52384 -239.210088)
		(end 208.52384 -238.52505)
		(width 0.13208)
		(layer "B.Cu")
		(net "SMB_PEX_MUX_SDA")
	)
	(segment
		(start 210.660742 -236.342174)
		(end 210.243928 -235.92536)
		(width 0.13208)
		(layer "B.Cu")
		(net "SMB_PEX_MUX_SDA")
	)
	(segment
		(start 206.907384 -236.908594)
		(end 207.576166 -237.577376)
		(width 0.13208)
		(layer "B.Cu")
		(net "SMB_PEX_MUX_SDA")
	)
	(segment
		(start 203.464922 -248.930414)
		(end 203.464922 -247.49633)
		(width 0.13208)
		(layer "B.Cu")
		(net "SMB_PEX_MUX_SDA")
	)
	(segment
		(start 209.885026 -242.041172)
		(end 209.885026 -240.571274)
		(width 0.13208)
		(layer "B.Cu")
		(net "SMB_PEX_MUX_SDA")
	)
	(segment
		(start 214.423498 -236.342174)
		(end 210.660742 -236.342174)
		(width 0.13208)
		(layer "B.Cu")
		(net "SMB_PEX_MUX_SDA")
	)
	(segment
		(start 215.69807 -234.728766)
		(end 215.69807 -235.067602)
		(width 0.13208)
		(layer "B.Cu")
		(net "SMB_PEX_MUX_SDA")
	)
	(segment
		(start 206.907384 -236.238034)
		(end 206.907384 -236.908594)
		(width 0.13208)
		(layer "B.Cu")
		(net "SMB_PEX_MUX_SDA")
	)
	(via
		(at 358.1146 -366.358424)
		(size 0.6604)
		(drill 0.3302)
		(layers "F.Cu" "B.Cu")
		(net "SWB_HSC_PWRGD")
	)
	(segment
		(start 358.38765 -363.09935)
		(end 358.1146 -363.3724)
		(width 0.13208)
		(layer "B.Cu")
		(net "SWB_HSC_PWRGD")
	)
	(segment
		(start 349.528892 -412.090108)
		(end 349.08998 -412.090108)
		(width 0.13208)
		(layer "B.Cu")
		(net "SWB_HSC_PWRGD")
	)
	(segment
		(start 358.1146 -382.0414)
		(end 350.1644 -389.9916)
		(width 0.13208)
		(layer "B.Cu")
		(net "SWB_HSC_PWRGD")
	)
	(segment
		(start 350.1644 -389.9916)
		(end 350.1644 -411.4546)
		(width 0.13208)
		(layer "B.Cu")
		(net "SWB_HSC_PWRGD")
	)
	(segment
		(start 358.1146 -366.358424)
		(end 358.1146 -382.0414)
		(width 0.13208)
		(layer "B.Cu")
		(net "SWB_HSC_PWRGD")
	)
	(segment
		(start 358.38765 -361.6198)
		(end 358.38765 -363.09935)
		(width 0.13208)
		(layer "B.Cu")
		(net "SWB_HSC_PWRGD")
	)
	(segment
		(start 358.1146 -363.3724)
		(end 358.1146 -366.358424)
		(width 0.13208)
		(layer "B.Cu")
		(net "SWB_HSC_PWRGD")
	)
	(segment
		(start 350.1644 -411.4546)
		(end 349.528892 -412.090108)
		(width 0.13208)
		(layer "B.Cu")
		(net "SWB_HSC_PWRGD")
	)
	(segment
		(start 86.36 -299.85081)
		(end 86.36 -298.2722)
		(width 0.13208)
		(layer "F.Cu")
		(net "RST_PEX0_S3_PERST_N")
	)
	(segment
		(start 86.681564 -297.950636)
		(end 86.681564 -297.676824)
		(width 0.13208)
		(layer "F.Cu")
		(net "RST_PEX0_S3_PERST_N")
	)
	(segment
		(start 86.681564 -297.676824)
		(end 86.681564 -296.623232)
		(width 0.13208)
		(layer "F.Cu")
		(net "RST_PEX0_S3_PERST_N")
	)
	(segment
		(start 86.36 -298.2722)
		(end 86.681564 -297.950636)
		(width 0.13208)
		(layer "F.Cu")
		(net "RST_PEX0_S3_PERST_N")
	)
	(segment
		(start 86.72957 -300.22038)
		(end 86.36 -299.85081)
		(width 0.13208)
		(layer "F.Cu")
		(net "RST_PEX0_S3_PERST_N")
	)
	(via
		(at 86.681564 -297.676824)
		(size 0.508)
		(drill 0.254)
		(layers "F.Cu" "B.Cu")
		(net "RST_PEX0_S3_PERST_N")
	)
	(segment
		(start 87.98179 -298.13631)
		(end 87.98179 -296.623232)
		(width 0.13208)
		(layer "F.Cu")
		(net "RST_PEX0_S1_PERST_N")
	)
	(segment
		(start 87.790274 -298.327826)
		(end 87.98179 -298.13631)
		(width 0.13208)
		(layer "F.Cu")
		(net "RST_PEX0_S1_PERST_N")
	)
	(segment
		(start 87.790274 -298.423838)
		(end 87.790274 -298.327826)
		(width 0.13208)
		(layer "F.Cu")
		(net "RST_PEX0_S1_PERST_N")
	)
	(segment
		(start 87.790274 -298.423838)
		(end 87.790274 -300.16196)
		(width 0.13208)
		(layer "F.Cu")
		(net "RST_PEX0_S1_PERST_N")
	)
	(segment
		(start 87.790274 -300.16196)
		(end 87.749634 -300.2026)
		(width 0.13208)
		(layer "F.Cu")
		(net "RST_PEX0_S1_PERST_N")
	)
	(via
		(at 87.790274 -298.423838)
		(size 0.762)
		(drill 0.381)
		(layers "F.Cu" "B.Cu")
		(net "RST_PEX0_S1_PERST_N")
	)
	(segment
		(start 85.53577 -290.446206)
		(end 85.53577 -289.630866)
		(width 0.13208)
		(layer "F.Cu")
		(net "RST_PEX0_S0_PERST_N")
	)
	(segment
		(start 86.681564 -292.142164)
		(end 86.5378 -291.9984)
		(width 0.13208)
		(layer "F.Cu")
		(net "RST_PEX0_S0_PERST_N")
	)
	(segment
		(start 86.3092 -291.9984)
		(end 85.53577 -291.22497)
		(width 0.13208)
		(layer "F.Cu")
		(net "RST_PEX0_S0_PERST_N")
	)
	(segment
		(start 86.681564 -292.923468)
		(end 86.681564 -292.142164)
		(width 0.13208)
		(layer "F.Cu")
		(net "RST_PEX0_S0_PERST_N")
	)
	(segment
		(start 85.53577 -291.22497)
		(end 85.53577 -290.446206)
		(width 0.13208)
		(layer "F.Cu")
		(net "RST_PEX0_S0_PERST_N")
	)
	(segment
		(start 86.5378 -291.9984)
		(end 86.3092 -291.9984)
		(width 0.13208)
		(layer "F.Cu")
		(net "RST_PEX0_S0_PERST_N")
	)
	(via
		(at 85.53577 -290.446206)
		(size 0.508)
		(drill 0.254)
		(layers "F.Cu" "B.Cu")
		(net "RST_PEX0_S0_PERST_N")
	)
	(segment
		(start 211.558886 -230.424736)
		(end 210.688936 -229.554786)
		(width 0.13208)
		(layer "F.Cu")
		(net "SMB_PEX_LS_R_SDA")
	)
	(segment
		(start 214.117936 -231.186736)
		(end 214.117936 -231.866948)
		(width 0.13208)
		(layer "F.Cu")
		(net "SMB_PEX_LS_R_SDA")
	)
	(segment
		(start 214.117936 -231.866948)
		(end 214.67445 -232.423462)
		(width 0.13208)
		(layer "F.Cu")
		(net "SMB_PEX_LS_R_SDA")
	)
	(segment
		(start 212.574886 -230.750872)
		(end 211.558886 -230.750872)
		(width 0.13208)
		(layer "F.Cu")
		(net "SMB_PEX_LS_R_SDA")
	)
	(segment
		(start 213.590886 -230.750872)
		(end 213.682072 -230.750872)
		(width 0.13208)
		(layer "F.Cu")
		(net "SMB_PEX_LS_R_SDA")
	)
	(segment
		(start 210.542886 -229.700836)
		(end 210.688936 -229.554786)
		(width 0.13208)
		(layer "F.Cu")
		(net "SMB_PEX_LS_R_SDA")
	)
	(segment
		(start 214.67445 -235.301028)
		(end 214.73033 -235.356908)
		(width 0.13208)
		(layer "F.Cu")
		(net "SMB_PEX_LS_R_SDA")
	)
	(segment
		(start 211.558886 -230.750872)
		(end 211.558886 -230.424736)
		(width 0.13208)
		(layer "F.Cu")
		(net "SMB_PEX_LS_R_SDA")
	)
	(segment
		(start 213.590886 -230.750872)
		(end 212.574886 -230.750872)
		(width 0.13208)
		(layer "F.Cu")
		(net "SMB_PEX_LS_R_SDA")
	)
	(segment
		(start 214.67445 -232.423462)
		(end 214.67445 -235.301028)
		(width 0.13208)
		(layer "F.Cu")
		(net "SMB_PEX_LS_R_SDA")
	)
	(segment
		(start 213.682072 -230.750872)
		(end 214.117936 -231.186736)
		(width 0.13208)
		(layer "F.Cu")
		(net "SMB_PEX_LS_R_SDA")
	)
	(segment
		(start 210.542886 -230.750872)
		(end 210.542886 -229.700836)
		(width 0.13208)
		(layer "F.Cu")
		(net "SMB_PEX_LS_R_SDA")
	)
	(via
		(at 210.688936 -229.554786)
		(size 0.762)
		(drill 0.381)
		(layers "F.Cu" "B.Cu")
		(net "SMB_PEX_LS_R_SDA")
	)
	(segment
		(start 212.65769 -234.230672)
		(end 212.60689 -234.281472)
		(width 0.13208)
		(layer "F.Cu")
		(net "SMB_PEX_LS_R_SCL")
	)
	(segment
		(start 210.161886 -234.738164)
		(end 210.78063 -235.356908)
		(width 0.13208)
		(layer "F.Cu")
		(net "SMB_PEX_LS_R_SCL")
	)
	(segment
		(start 210.78063 -235.356908)
		(end 211.051902 -235.356908)
		(width 0.13208)
		(layer "F.Cu")
		(net "SMB_PEX_LS_R_SCL")
	)
	(segment
		(start 211.177886 -234.281472)
		(end 212.026754 -234.281472)
		(width 0.13208)
		(layer "F.Cu")
		(net "SMB_PEX_LS_R_SCL")
	)
	(segment
		(start 210.161886 -234.281472)
		(end 211.177886 -234.281472)
		(width 0.13208)
		(layer "F.Cu")
		(net "SMB_PEX_LS_R_SCL")
	)
	(segment
		(start 210.161886 -234.281472)
		(end 210.161886 -234.738164)
		(width 0.13208)
		(layer "F.Cu")
		(net "SMB_PEX_LS_R_SCL")
	)
	(segment
		(start 213.630256 -234.230672)
		(end 212.65769 -234.230672)
		(width 0.13208)
		(layer "F.Cu")
		(net "SMB_PEX_LS_R_SCL")
	)
	(segment
		(start 212.60689 -234.281472)
		(end 212.026754 -234.281472)
		(width 0.13208)
		(layer "F.Cu")
		(net "SMB_PEX_LS_R_SCL")
	)
	(via
		(at 212.026754 -234.281472)
		(size 0.508)
		(drill 0.254)
		(layers "F.Cu" "B.Cu")
		(net "SMB_PEX_LS_R_SCL")
	)
	(segment
		(start 360.511598 -239.34039)
		(end 360.511598 -240.44529)
		(width 0.13208)
		(layer "F.Cu")
		(net "PWRGD_P3V3_AUX_BUF_R")
	)
	(segment
		(start 360.511598 -240.44529)
		(end 360.755438 -240.68913)
		(width 0.13208)
		(layer "F.Cu")
		(net "PWRGD_P3V3_AUX_BUF_R")
	)
	(segment
		(start 338.093812 -223.987106)
		(end 337.694016 -224.386902)
		(width 0.13208)
		(layer "F.Cu")
		(net "PWRGD_P3V3_AUX_BUF_R")
	)
	(segment
		(start 360.755438 -240.68913)
		(end 361.936284 -240.68913)
		(width 0.13208)
		(layer "F.Cu")
		(net "PWRGD_P3V3_AUX_BUF_R")
	)
	(via
		(at 337.694016 -224.386902)
		(size 0.4572)
		(drill 0.254)
		(layers "F.Cu" "B.Cu")
		(net "PWRGD_P3V3_AUX_BUF_R")
	)
	(via
		(at 360.511598 -239.34039)
		(size 0.508)
		(drill 0.254)
		(layers "F.Cu" "B.Cu")
		(net "PWRGD_P3V3_AUX_BUF_R")
	)
	(segment
		(start 343.867486 -225.586544)
		(end 345.116404 -225.586544)
		(width 0.0889)
		(layer "In15.Cu")
		(net "PWRGD_P3V3_AUX_BUF_R")
	)
	(segment
		(start 354.931218 -235.90377)
		(end 357.074978 -235.90377)
		(width 0.15494)
		(layer "In15.Cu")
		(net "PWRGD_P3V3_AUX_BUF_R")
	)
	(segment
		(start 342.8746 -223.186498)
		(end 343.511378 -223.186498)
		(width 0.0889)
		(layer "In15.Cu")
		(net "PWRGD_P3V3_AUX_BUF_R")
	)
	(segment
		(start 345.116404 -225.586544)
		(end 345.296236 -225.766376)
		(width 0.0889)
		(layer "In15.Cu")
		(net "PWRGD_P3V3_AUX_BUF_R")
	)
	(segment
		(start 354.538534 -235.511086)
		(end 354.931218 -235.90377)
		(width 0.15494)
		(layer "In15.Cu")
		(net "PWRGD_P3V3_AUX_BUF_R")
	)
	(segment
		(start 347.926406 -228.506274)
		(end 347.926406 -229.46487)
		(width 0.15494)
		(layer "In15.Cu")
		(net "PWRGD_P3V3_AUX_BUF_R")
	)
	(segment
		(start 343.69375 -223.36887)
		(end 343.69375 -225.412808)
		(width 0.0889)
		(layer "In15.Cu")
		(net "PWRGD_P3V3_AUX_BUF_R")
	)
	(segment
		(start 338.2264 -223.1898)
		(end 342.871298 -223.1898)
		(width 0.0889)
		(layer "In15.Cu")
		(net "PWRGD_P3V3_AUX_BUF_R")
	)
	(segment
		(start 347.50629 -228.086158)
		(end 347.926406 -228.506274)
		(width 0.15494)
		(layer "In15.Cu")
		(net "PWRGD_P3V3_AUX_BUF_R")
	)
	(segment
		(start 338.074 -224.006918)
		(end 338.074 -223.3422)
		(width 0.0889)
		(layer "In15.Cu")
		(net "PWRGD_P3V3_AUX_BUF_R")
	)
	(segment
		(start 357.074978 -235.90377)
		(end 360.511598 -239.34039)
		(width 0.15494)
		(layer "In15.Cu")
		(net "PWRGD_P3V3_AUX_BUF_R")
	)
	(segment
		(start 338.074 -223.3422)
		(end 338.2264 -223.1898)
		(width 0.0889)
		(layer "In15.Cu")
		(net "PWRGD_P3V3_AUX_BUF_R")
	)
	(segment
		(start 345.296236 -227.46589)
		(end 345.916504 -228.086158)
		(width 0.15494)
		(layer "In15.Cu")
		(net "PWRGD_P3V3_AUX_BUF_R")
	)
	(segment
		(start 351.817178 -233.355642)
		(end 353.19589 -233.355642)
		(width 0.15494)
		(layer "In15.Cu")
		(net "PWRGD_P3V3_AUX_BUF_R")
	)
	(segment
		(start 347.926406 -229.46487)
		(end 351.817178 -233.355642)
		(width 0.15494)
		(layer "In15.Cu")
		(net "PWRGD_P3V3_AUX_BUF_R")
	)
	(segment
		(start 345.296236 -227.1776)
		(end 345.296236 -227.46589)
		(width 0.15494)
		(layer "In15.Cu")
		(net "PWRGD_P3V3_AUX_BUF_R")
	)
	(segment
		(start 354.538534 -234.698286)
		(end 354.538534 -235.511086)
		(width 0.15494)
		(layer "In15.Cu")
		(net "PWRGD_P3V3_AUX_BUF_R")
	)
	(segment
		(start 342.871298 -223.1898)
		(end 342.8746 -223.186498)
		(width 0.0889)
		(layer "In15.Cu")
		(net "PWRGD_P3V3_AUX_BUF_R")
	)
	(segment
		(start 343.511378 -223.186498)
		(end 343.69375 -223.36887)
		(width 0.0889)
		(layer "In15.Cu")
		(net "PWRGD_P3V3_AUX_BUF_R")
	)
	(segment
		(start 345.296236 -225.766376)
		(end 345.296236 -227.1776)
		(width 0.0889)
		(layer "In15.Cu")
		(net "PWRGD_P3V3_AUX_BUF_R")
	)
	(segment
		(start 343.69375 -225.412808)
		(end 343.867486 -225.586544)
		(width 0.0889)
		(layer "In15.Cu")
		(net "PWRGD_P3V3_AUX_BUF_R")
	)
	(segment
		(start 345.916504 -228.086158)
		(end 347.50629 -228.086158)
		(width 0.15494)
		(layer "In15.Cu")
		(net "PWRGD_P3V3_AUX_BUF_R")
	)
	(segment
		(start 337.694016 -224.386902)
		(end 338.074 -224.006918)
		(width 0.0889)
		(layer "In15.Cu")
		(net "PWRGD_P3V3_AUX_BUF_R")
	)
	(segment
		(start 353.19589 -233.355642)
		(end 354.538534 -234.698286)
		(width 0.15494)
		(layer "In15.Cu")
		(net "PWRGD_P3V3_AUX_BUF_R")
	)
	(segment
		(start 371.319552 -237.75797)
		(end 371.319552 -237.75416)
		(width 0.13208)
		(layer "F.Cu")
		(net "PWRGD_P5V_AUX_BUF_R")
	)
	(segment
		(start 336.493866 -225.587052)
		(end 336.093816 -225.987102)
		(width 0.13208)
		(layer "F.Cu")
		(net "PWRGD_P5V_AUX_BUF_R")
	)
	(segment
		(start 371.319552 -237.75416)
		(end 372.090442 -236.98327)
		(width 0.13208)
		(layer "F.Cu")
		(net "PWRGD_P5V_AUX_BUF_R")
	)
	(segment
		(start 372.090442 -236.98327)
		(end 372.090442 -236.953298)
		(width 0.13208)
		(layer "F.Cu")
		(net "PWRGD_P5V_AUX_BUF_R")
	)
	(via
		(at 371.319552 -237.75797)
		(size 0.508)
		(drill 0.254)
		(layers "F.Cu" "B.Cu")
		(net "PWRGD_P5V_AUX_BUF_R")
	)
	(via
		(at 336.093816 -225.987102)
		(size 0.4572)
		(drill 0.254)
		(layers "F.Cu" "B.Cu")
		(net "PWRGD_P5V_AUX_BUF_R")
	)
	(via
		(at 336.181446 -227.84943)
		(size 0.6604)
		(drill 0.3302)
		(layers "F.Cu" "B.Cu")
		(net "PWRGD_P5V_AUX_BUF_R")
	)
	(segment
		(start 336.493612 -227.537264)
		(end 336.181446 -227.84943)
		(width 0.13208)
		(layer "B.Cu")
		(net "PWRGD_P5V_AUX_BUF_R")
	)
	(segment
		(start 363.09173 -239.068102)
		(end 363.21492 -238.944912)
		(width 0.13208)
		(layer "B.Cu")
		(net "PWRGD_P5V_AUX_BUF_R")
	)
	(segment
		(start 332.833472 -236.431074)
		(end 335.455514 -236.431074)
		(width 0.13208)
		(layer "B.Cu")
		(net "PWRGD_P5V_AUX_BUF_R")
	)
	(segment
		(start 335.980532 -235.906056)
		(end 336.61985 -235.906056)
		(width 0.13208)
		(layer "B.Cu")
		(net "PWRGD_P5V_AUX_BUF_R")
	)
	(segment
		(start 326.06615 -233.918252)
		(end 331.65415 -233.918252)
		(width 0.13208)
		(layer "B.Cu")
		(net "PWRGD_P5V_AUX_BUF_R")
	)
	(segment
		(start 371.014244 -238.944912)
		(end 371.319552 -238.639604)
		(width 0.13208)
		(layer "B.Cu")
		(net "PWRGD_P5V_AUX_BUF_R")
	)
	(segment
		(start 336.61985 -235.906056)
		(end 336.85734 -236.143546)
		(width 0.13208)
		(layer "B.Cu")
		(net "PWRGD_P5V_AUX_BUF_R")
	)
	(segment
		(start 352.478594 -236.296454)
		(end 360.531664 -236.296454)
		(width 0.13208)
		(layer "B.Cu")
		(net "PWRGD_P5V_AUX_BUF_R")
	)
	(segment
		(start 323.149976 -231.599994)
		(end 322.576698 -232.173272)
		(width 0.13208)
		(layer "B.Cu")
		(net "PWRGD_P5V_AUX_BUF_R")
	)
	(segment
		(start 324.229984 -231.599994)
		(end 323.149976 -231.599994)
		(width 0.13208)
		(layer "B.Cu")
		(net "PWRGD_P5V_AUX_BUF_R")
	)
	(segment
		(start 336.85734 -237.239556)
		(end 337.381342 -237.763558)
		(width 0.13208)
		(layer "B.Cu")
		(net "PWRGD_P5V_AUX_BUF_R")
	)
	(segment
		(start 337.381342 -237.763558)
		(end 341.439246 -237.763558)
		(width 0.13208)
		(layer "B.Cu")
		(net "PWRGD_P5V_AUX_BUF_R")
	)
	(segment
		(start 341.439246 -237.763558)
		(end 342.278716 -236.924088)
		(width 0.13208)
		(layer "B.Cu")
		(net "PWRGD_P5V_AUX_BUF_R")
	)
	(segment
		(start 331.65415 -233.918252)
		(end 332.431644 -234.695746)
		(width 0.13208)
		(layer "B.Cu")
		(net "PWRGD_P5V_AUX_BUF_R")
	)
	(segment
		(start 322.576698 -232.173272)
		(end 322.576698 -233.417872)
		(width 0.13208)
		(layer "B.Cu")
		(net "PWRGD_P5V_AUX_BUF_R")
	)
	(segment
		(start 336.093816 -226.034346)
		(end 336.493612 -226.434142)
		(width 0.0889)
		(layer "B.Cu")
		(net "PWRGD_P5V_AUX_BUF_R")
	)
	(segment
		(start 363.21492 -238.944912)
		(end 371.014244 -238.944912)
		(width 0.13208)
		(layer "B.Cu")
		(net "PWRGD_P5V_AUX_BUF_R")
	)
	(segment
		(start 335.455514 -236.431074)
		(end 335.980532 -235.906056)
		(width 0.13208)
		(layer "B.Cu")
		(net "PWRGD_P5V_AUX_BUF_R")
	)
	(segment
		(start 361.778804 -239.068102)
		(end 363.09173 -239.068102)
		(width 0.13208)
		(layer "B.Cu")
		(net "PWRGD_P5V_AUX_BUF_R")
	)
	(segment
		(start 360.950002 -238.2393)
		(end 361.778804 -239.068102)
		(width 0.13208)
		(layer "B.Cu")
		(net "PWRGD_P5V_AUX_BUF_R")
	)
	(segment
		(start 332.431644 -236.029246)
		(end 332.833472 -236.431074)
		(width 0.13208)
		(layer "B.Cu")
		(net "PWRGD_P5V_AUX_BUF_R")
	)
	(segment
		(start 324.942454 -232.312464)
		(end 324.229984 -231.599994)
		(width 0.13208)
		(layer "B.Cu")
		(net "PWRGD_P5V_AUX_BUF_R")
	)
	(segment
		(start 351.85096 -236.924088)
		(end 352.478594 -236.296454)
		(width 0.13208)
		(layer "B.Cu")
		(net "PWRGD_P5V_AUX_BUF_R")
	)
	(segment
		(start 331.743812 -230.759)
		(end 329.32116 -230.759)
		(width 0.13208)
		(layer "B.Cu")
		(net "PWRGD_P5V_AUX_BUF_R")
	)
	(segment
		(start 336.493612 -226.434142)
		(end 336.493612 -227.537264)
		(width 0.0889)
		(layer "B.Cu")
		(net "PWRGD_P5V_AUX_BUF_R")
	)
	(segment
		(start 323.433186 -234.27436)
		(end 325.710042 -234.27436)
		(width 0.13208)
		(layer "B.Cu")
		(net "PWRGD_P5V_AUX_BUF_R")
	)
	(segment
		(start 334.060038 -229.258876)
		(end 333.243936 -229.258876)
		(width 0.13208)
		(layer "B.Cu")
		(net "PWRGD_P5V_AUX_BUF_R")
	)
	(segment
		(start 360.531664 -236.296454)
		(end 360.950002 -236.714792)
		(width 0.13208)
		(layer "B.Cu")
		(net "PWRGD_P5V_AUX_BUF_R")
	)
	(segment
		(start 371.319552 -238.639604)
		(end 371.319552 -237.75797)
		(width 0.13208)
		(layer "B.Cu")
		(net "PWRGD_P5V_AUX_BUF_R")
	)
	(segment
		(start 333.243936 -229.258876)
		(end 331.743812 -230.759)
		(width 0.13208)
		(layer "B.Cu")
		(net "PWRGD_P5V_AUX_BUF_R")
	)
	(segment
		(start 336.093816 -225.987102)
		(end 336.093816 -226.034346)
		(width 0.0889)
		(layer "B.Cu")
		(net "PWRGD_P5V_AUX_BUF_R")
	)
	(segment
		(start 336.181446 -227.84943)
		(end 335.675224 -228.355652)
		(width 0.13208)
		(layer "B.Cu")
		(net "PWRGD_P5V_AUX_BUF_R")
	)
	(segment
		(start 334.963262 -228.355652)
		(end 334.060038 -229.258876)
		(width 0.13208)
		(layer "B.Cu")
		(net "PWRGD_P5V_AUX_BUF_R")
	)
	(segment
		(start 336.85734 -236.143546)
		(end 336.85734 -237.239556)
		(width 0.13208)
		(layer "B.Cu")
		(net "PWRGD_P5V_AUX_BUF_R")
	)
	(segment
		(start 322.576698 -233.417872)
		(end 323.433186 -234.27436)
		(width 0.13208)
		(layer "B.Cu")
		(net "PWRGD_P5V_AUX_BUF_R")
	)
	(segment
		(start 342.278716 -236.924088)
		(end 351.85096 -236.924088)
		(width 0.13208)
		(layer "B.Cu")
		(net "PWRGD_P5V_AUX_BUF_R")
	)
	(segment
		(start 332.431644 -234.695746)
		(end 332.431644 -236.029246)
		(width 0.13208)
		(layer "B.Cu")
		(net "PWRGD_P5V_AUX_BUF_R")
	)
	(segment
		(start 327.767696 -232.312464)
		(end 324.942454 -232.312464)
		(width 0.13208)
		(layer "B.Cu")
		(net "PWRGD_P5V_AUX_BUF_R")
	)
	(segment
		(start 329.32116 -230.759)
		(end 327.767696 -232.312464)
		(width 0.13208)
		(layer "B.Cu")
		(net "PWRGD_P5V_AUX_BUF_R")
	)
	(segment
		(start 325.710042 -234.27436)
		(end 326.06615 -233.918252)
		(width 0.13208)
		(layer "B.Cu")
		(net "PWRGD_P5V_AUX_BUF_R")
	)
	(segment
		(start 360.950002 -236.714792)
		(end 360.950002 -238.2393)
		(width 0.13208)
		(layer "B.Cu")
		(net "PWRGD_P5V_AUX_BUF_R")
	)
	(segment
		(start 335.675224 -228.355652)
		(end 334.963262 -228.355652)
		(width 0.13208)
		(layer "B.Cu")
		(net "PWRGD_P5V_AUX_BUF_R")
	)
	(segment
		(start 375.371106 -240.50752)
		(end 374.51157 -239.647984)
		(width 0.13208)
		(layer "F.Cu")
		(net "PWRGD_P12V_AUX_BUF_R")
	)
	(segment
		(start 375.956576 -240.50752)
		(end 375.371106 -240.50752)
		(width 0.13208)
		(layer "F.Cu")
		(net "PWRGD_P12V_AUX_BUF_R")
	)
	(segment
		(start 335.693766 -225.587052)
		(end 335.29397 -225.986848)
		(width 0.13208)
		(layer "F.Cu")
		(net "PWRGD_P12V_AUX_BUF_R")
	)
	(segment
		(start 374.51157 -239.647984)
		(end 373.313706 -239.647984)
		(width 0.13208)
		(layer "F.Cu")
		(net "PWRGD_P12V_AUX_BUF_R")
	)
	(via
		(at 375.956576 -240.50752)
		(size 0.508)
		(drill 0.254)
		(layers "F.Cu" "B.Cu")
		(net "PWRGD_P12V_AUX_BUF_R")
	)
	(via
		(at 335.29397 -225.986848)
		(size 0.4572)
		(drill 0.254)
		(layers "F.Cu" "B.Cu")
		(net "PWRGD_P12V_AUX_BUF_R")
	)
	(segment
		(start 327.604374 -231.918764)
		(end 329.157838 -230.3653)
		(width 0.13208)
		(layer "B.Cu")
		(net "PWRGD_P12V_AUX_BUF_R")
	)
	(segment
		(start 376.48007 -239.370108)
		(end 376.264932 -239.15497)
		(width 0.13208)
		(layer "B.Cu")
		(net "PWRGD_P12V_AUX_BUF_R")
	)
	(segment
		(start 335.35239 -225.986848)
		(end 335.29397 -225.986848)
		(width 0.0889)
		(layer "B.Cu")
		(net "PWRGD_P12V_AUX_BUF_R")
	)
	(segment
		(start 375.31548 -239.356138)
		(end 363.762798 -239.356138)
		(width 0.13208)
		(layer "B.Cu")
		(net "PWRGD_P12V_AUX_BUF_R")
	)
	(segment
		(start 323.269864 -234.66806)
		(end 322.182998 -233.581194)
		(width 0.13208)
		(layer "B.Cu")
		(net "PWRGD_P12V_AUX_BUF_R")
	)
	(segment
		(start 326.229472 -234.311952)
		(end 325.873364 -234.66806)
		(width 0.13208)
		(layer "B.Cu")
		(net "PWRGD_P12V_AUX_BUF_R")
	)
	(segment
		(start 332.037944 -234.859068)
		(end 331.490828 -234.311952)
		(width 0.13208)
		(layer "B.Cu")
		(net "PWRGD_P12V_AUX_BUF_R")
	)
	(segment
		(start 335.347818 -227.565712)
		(end 335.697576 -227.215954)
		(width 0.13208)
		(layer "B.Cu")
		(net "PWRGD_P12V_AUX_BUF_R")
	)
	(segment
		(start 376.48007 -239.984026)
		(end 376.48007 -239.370108)
		(width 0.13208)
		(layer "B.Cu")
		(net "PWRGD_P12V_AUX_BUF_R")
	)
	(segment
		(start 341.607902 -238.170212)
		(end 337.230212 -238.170212)
		(width 0.13208)
		(layer "B.Cu")
		(net "PWRGD_P12V_AUX_BUF_R")
	)
	(segment
		(start 332.037944 -236.192568)
		(end 332.037944 -234.859068)
		(width 0.13208)
		(layer "B.Cu")
		(net "PWRGD_P12V_AUX_BUF_R")
	)
	(segment
		(start 360.452162 -236.92104)
		(end 360.325416 -236.794294)
		(width 0.13208)
		(layer "B.Cu")
		(net "PWRGD_P12V_AUX_BUF_R")
	)
	(segment
		(start 360.452162 -238.385604)
		(end 360.452162 -236.92104)
		(width 0.13208)
		(layer "B.Cu")
		(net "PWRGD_P12V_AUX_BUF_R")
	)
	(segment
		(start 336.87385 -237.81385)
		(end 335.102454 -237.81385)
		(width 0.13208)
		(layer "B.Cu")
		(net "PWRGD_P12V_AUX_BUF_R")
	)
	(segment
		(start 322.182998 -233.581194)
		(end 322.182998 -232.00995)
		(width 0.13208)
		(layer "B.Cu")
		(net "PWRGD_P12V_AUX_BUF_R")
	)
	(segment
		(start 332.93812 -228.895656)
		(end 333.838804 -228.895656)
		(width 0.13208)
		(layer "B.Cu")
		(net "PWRGD_P12V_AUX_BUF_R")
	)
	(segment
		(start 331.490828 -234.311952)
		(end 326.229472 -234.311952)
		(width 0.13208)
		(layer "B.Cu")
		(net "PWRGD_P12V_AUX_BUF_R")
	)
	(segment
		(start 325.105776 -231.918764)
		(end 327.604374 -231.918764)
		(width 0.13208)
		(layer "B.Cu")
		(net "PWRGD_P12V_AUX_BUF_R")
	)
	(segment
		(start 329.157838 -230.3653)
		(end 331.468476 -230.3653)
		(width 0.13208)
		(layer "B.Cu")
		(net "PWRGD_P12V_AUX_BUF_R")
	)
	(segment
		(start 324.393306 -231.206294)
		(end 325.105776 -231.918764)
		(width 0.13208)
		(layer "B.Cu")
		(net "PWRGD_P12V_AUX_BUF_R")
	)
	(segment
		(start 342.447372 -237.330742)
		(end 341.607902 -238.170212)
		(width 0.13208)
		(layer "B.Cu")
		(net "PWRGD_P12V_AUX_BUF_R")
	)
	(segment
		(start 322.986654 -231.206294)
		(end 324.393306 -231.206294)
		(width 0.13208)
		(layer "B.Cu")
		(net "PWRGD_P12V_AUX_BUF_R")
	)
	(segment
		(start 335.697576 -227.215954)
		(end 335.697576 -226.332034)
		(width 0.0889)
		(layer "B.Cu")
		(net "PWRGD_P12V_AUX_BUF_R")
	)
	(segment
		(start 333.838804 -228.895656)
		(end 335.168748 -227.565712)
		(width 0.13208)
		(layer "B.Cu")
		(net "PWRGD_P12V_AUX_BUF_R")
	)
	(segment
		(start 331.468476 -230.3653)
		(end 332.93812 -228.895656)
		(width 0.13208)
		(layer "B.Cu")
		(net "PWRGD_P12V_AUX_BUF_R")
	)
	(segment
		(start 322.182998 -232.00995)
		(end 322.986654 -231.206294)
		(width 0.13208)
		(layer "B.Cu")
		(net "PWRGD_P12V_AUX_BUF_R")
	)
	(segment
		(start 337.230212 -238.170212)
		(end 336.87385 -237.81385)
		(width 0.13208)
		(layer "B.Cu")
		(net "PWRGD_P12V_AUX_BUF_R")
	)
	(segment
		(start 376.264932 -239.15497)
		(end 375.516648 -239.15497)
		(width 0.13208)
		(layer "B.Cu")
		(net "PWRGD_P12V_AUX_BUF_R")
	)
	(segment
		(start 375.956576 -240.50752)
		(end 376.48007 -239.984026)
		(width 0.13208)
		(layer "B.Cu")
		(net "PWRGD_P12V_AUX_BUF_R")
	)
	(segment
		(start 363.762798 -239.356138)
		(end 363.635036 -239.4839)
		(width 0.13208)
		(layer "B.Cu")
		(net "PWRGD_P12V_AUX_BUF_R")
	)
	(segment
		(start 335.697576 -226.332034)
		(end 335.35239 -225.986848)
		(width 0.0889)
		(layer "B.Cu")
		(net "PWRGD_P12V_AUX_BUF_R")
	)
	(segment
		(start 335.168748 -227.565712)
		(end 335.347818 -227.565712)
		(width 0.13208)
		(layer "B.Cu")
		(net "PWRGD_P12V_AUX_BUF_R")
	)
	(segment
		(start 334.113378 -236.824774)
		(end 332.67015 -236.824774)
		(width 0.13208)
		(layer "B.Cu")
		(net "PWRGD_P12V_AUX_BUF_R")
	)
	(segment
		(start 335.102454 -237.81385)
		(end 334.113378 -236.824774)
		(width 0.13208)
		(layer "B.Cu")
		(net "PWRGD_P12V_AUX_BUF_R")
	)
	(segment
		(start 325.873364 -234.66806)
		(end 323.269864 -234.66806)
		(width 0.13208)
		(layer "B.Cu")
		(net "PWRGD_P12V_AUX_BUF_R")
	)
	(segment
		(start 352.019616 -237.330742)
		(end 342.447372 -237.330742)
		(width 0.13208)
		(layer "B.Cu")
		(net "PWRGD_P12V_AUX_BUF_R")
	)
	(segment
		(start 352.556064 -236.794294)
		(end 352.019616 -237.330742)
		(width 0.13208)
		(layer "B.Cu")
		(net "PWRGD_P12V_AUX_BUF_R")
	)
	(segment
		(start 360.325416 -236.794294)
		(end 352.556064 -236.794294)
		(width 0.13208)
		(layer "B.Cu")
		(net "PWRGD_P12V_AUX_BUF_R")
	)
	(segment
		(start 363.635036 -239.4839)
		(end 361.550458 -239.4839)
		(width 0.13208)
		(layer "B.Cu")
		(net "PWRGD_P12V_AUX_BUF_R")
	)
	(segment
		(start 332.67015 -236.824774)
		(end 332.037944 -236.192568)
		(width 0.13208)
		(layer "B.Cu")
		(net "PWRGD_P12V_AUX_BUF_R")
	)
	(segment
		(start 361.550458 -239.4839)
		(end 360.452162 -238.385604)
		(width 0.13208)
		(layer "B.Cu")
		(net "PWRGD_P12V_AUX_BUF_R")
	)
	(segment
		(start 375.516648 -239.15497)
		(end 375.31548 -239.356138)
		(width 0.13208)
		(layer "B.Cu")
		(net "PWRGD_P12V_AUX_BUF_R")
	)
	(segment
		(start 363.234986 -239.125506)
		(end 363.935772 -239.125506)
		(width 0.13208)
		(layer "F.Cu")
		(net "PWRGD_P3V3_AUX_BUF")
	)
	(segment
		(start 363.935772 -239.125506)
		(end 364.307882 -239.125506)
		(width 0.13208)
		(layer "F.Cu")
		(net "PWRGD_P3V3_AUX_BUF")
	)
	(segment
		(start 362.739432 -239.62106)
		(end 363.234986 -239.125506)
		(width 0.13208)
		(layer "F.Cu")
		(net "PWRGD_P3V3_AUX_BUF")
	)
	(segment
		(start 364.307882 -239.125506)
		(end 364.808516 -239.62614)
		(width 0.13208)
		(layer "F.Cu")
		(net "PWRGD_P3V3_AUX_BUF")
	)
	(segment
		(start 364.808516 -239.62614)
		(end 365.565436 -239.62614)
		(width 0.13208)
		(layer "F.Cu")
		(net "PWRGD_P3V3_AUX_BUF")
	)
	(segment
		(start 362.736384 -239.624108)
		(end 362.739432 -239.62106)
		(width 0.13208)
		(layer "F.Cu")
		(net "PWRGD_P3V3_AUX_BUF")
	)
	(segment
		(start 362.736384 -240.68913)
		(end 362.736384 -239.624108)
		(width 0.13208)
		(layer "F.Cu")
		(net "PWRGD_P3V3_AUX_BUF")
	)
	(via
		(at 363.935772 -239.125506)
		(size 0.762)
		(drill 0.381)
		(layers "F.Cu" "B.Cu")
		(net "PWRGD_P3V3_AUX_BUF")
	)
	(segment
		(start 370.200682 -236.953298)
		(end 371.290342 -236.953298)
		(width 0.13208)
		(layer "F.Cu")
		(net "PWRGD_P5V_AUX_BUF")
	)
	(segment
		(start 369.2652 -238.325914)
		(end 369.2652 -237.88878)
		(width 0.13208)
		(layer "F.Cu")
		(net "PWRGD_P5V_AUX_BUF")
	)
	(segment
		(start 371.290342 -235.757466)
		(end 371.289834 -235.756958)
		(width 0.13208)
		(layer "F.Cu")
		(net "PWRGD_P5V_AUX_BUF")
	)
	(segment
		(start 369.993926 -237.160054)
		(end 370.200682 -236.953298)
		(width 0.13208)
		(layer "F.Cu")
		(net "PWRGD_P5V_AUX_BUF")
	)
	(segment
		(start 369.2652 -237.88878)
		(end 369.993926 -237.160054)
		(width 0.13208)
		(layer "F.Cu")
		(net "PWRGD_P5V_AUX_BUF")
	)
	(segment
		(start 371.290342 -236.953298)
		(end 371.290342 -235.757466)
		(width 0.13208)
		(layer "F.Cu")
		(net "PWRGD_P5V_AUX_BUF")
	)
	(via
		(at 369.993926 -237.160054)
		(size 0.762)
		(drill 0.381)
		(layers "F.Cu" "B.Cu")
		(net "PWRGD_P5V_AUX_BUF")
	)
	(segment
		(start 372.501668 -239.678464)
		(end 372.471188 -239.647984)
		(width 0.13208)
		(layer "F.Cu")
		(net "PWRGD_P12V_AUX_BUF")
	)
	(segment
		(start 370.713 -239.995456)
		(end 370.343684 -239.62614)
		(width 0.13208)
		(layer "F.Cu")
		(net "PWRGD_P12V_AUX_BUF")
	)
	(segment
		(start 371.671596 -239.995456)
		(end 371.206014 -239.995456)
		(width 0.13208)
		(layer "F.Cu")
		(net "PWRGD_P12V_AUX_BUF")
	)
	(segment
		(start 372.513606 -239.647984)
		(end 372.471188 -239.647984)
		(width 0.13208)
		(layer "F.Cu")
		(net "PWRGD_P12V_AUX_BUF")
	)
	(segment
		(start 371.206014 -239.995456)
		(end 370.713 -239.995456)
		(width 0.13208)
		(layer "F.Cu")
		(net "PWRGD_P12V_AUX_BUF")
	)
	(segment
		(start 372.019068 -239.647984)
		(end 371.671596 -239.995456)
		(width 0.13208)
		(layer "F.Cu")
		(net "PWRGD_P12V_AUX_BUF")
	)
	(segment
		(start 372.501668 -240.6904)
		(end 372.501668 -239.678464)
		(width 0.13208)
		(layer "F.Cu")
		(net "PWRGD_P12V_AUX_BUF")
	)
	(segment
		(start 370.343684 -239.62614)
		(end 369.2652 -239.62614)
		(width 0.13208)
		(layer "F.Cu")
		(net "PWRGD_P12V_AUX_BUF")
	)
	(segment
		(start 372.471188 -239.647984)
		(end 372.019068 -239.647984)
		(width 0.13208)
		(layer "F.Cu")
		(net "PWRGD_P12V_AUX_BUF")
	)
	(via
		(at 371.206014 -239.995456)
		(size 0.762)
		(drill 0.381)
		(layers "F.Cu" "B.Cu")
		(net "PWRGD_P12V_AUX_BUF")
	)
	(segment
		(start 369.2652 -238.9759)
		(end 370.289328 -238.9759)
		(width 0.13208)
		(layer "F.Cu")
		(net "PWRGD_P3V3_AUX_R2")
	)
	(segment
		(start 370.621306 -238.643922)
		(end 371.24259 -238.643922)
		(width 0.13208)
		(layer "F.Cu")
		(net "PWRGD_P3V3_AUX_R2")
	)
	(segment
		(start 370.289328 -238.9759)
		(end 370.621306 -238.643922)
		(width 0.13208)
		(layer "F.Cu")
		(net "PWRGD_P3V3_AUX_R2")
	)
	(segment
		(start 371.24259 -238.643922)
		(end 372.52275 -238.643922)
		(width 0.13208)
		(layer "F.Cu")
		(net "PWRGD_P3V3_AUX_R2")
	)
	(via
		(at 371.24259 -238.643922)
		(size 0.762)
		(drill 0.381)
		(layers "F.Cu" "B.Cu")
		(net "PWRGD_P3V3_AUX_R2")
	)
	(segment
		(start 363.64418 -236.986064)
		(end 362.765848 -236.986064)
		(width 0.13208)
		(layer "F.Cu")
		(net "PWRGD_P5V_AUX_R2")
	)
	(segment
		(start 365.565436 -238.9759)
		(end 364.825788 -238.9759)
		(width 0.13208)
		(layer "F.Cu")
		(net "PWRGD_P5V_AUX_R2")
	)
	(segment
		(start 361.306364 -236.986064)
		(end 361.007406 -237.285022)
		(width 0.13208)
		(layer "F.Cu")
		(net "PWRGD_P5V_AUX_R2")
	)
	(segment
		(start 364.068868 -237.410752)
		(end 363.64418 -236.986064)
		(width 0.13208)
		(layer "F.Cu")
		(net "PWRGD_P5V_AUX_R2")
	)
	(segment
		(start 364.068868 -238.21898)
		(end 364.068868 -237.410752)
		(width 0.13208)
		(layer "F.Cu")
		(net "PWRGD_P5V_AUX_R2")
	)
	(segment
		(start 364.825788 -238.9759)
		(end 364.068868 -238.21898)
		(width 0.13208)
		(layer "F.Cu")
		(net "PWRGD_P5V_AUX_R2")
	)
	(segment
		(start 361.007406 -237.285022)
		(end 361.007406 -238.580168)
		(width 0.13208)
		(layer "F.Cu")
		(net "PWRGD_P5V_AUX_R2")
	)
	(segment
		(start 362.765848 -236.986064)
		(end 361.306364 -236.986064)
		(width 0.13208)
		(layer "F.Cu")
		(net "PWRGD_P5V_AUX_R2")
	)
	(via
		(at 362.765848 -236.986064)
		(size 0.762)
		(drill 0.381)
		(layers "F.Cu" "B.Cu")
		(net "PWRGD_P5V_AUX_R2")
	)
	(segment
		(start 363.932724 -240.552986)
		(end 362.788708 -241.697002)
		(width 0.13208)
		(layer "F.Cu")
		(net "PWRGD_P12V_AUX_R1")
	)
	(segment
		(start 365.565436 -240.276126)
		(end 364.209584 -240.276126)
		(width 0.13208)
		(layer "F.Cu")
		(net "PWRGD_P12V_AUX_R1")
	)
	(segment
		(start 364.209584 -240.276126)
		(end 363.932724 -240.552986)
		(width 0.13208)
		(layer "F.Cu")
		(net "PWRGD_P12V_AUX_R1")
	)
	(segment
		(start 362.788708 -241.697002)
		(end 362.751624 -241.697002)
		(width 0.13208)
		(layer "F.Cu")
		(net "PWRGD_P12V_AUX_R1")
	)
	(via
		(at 363.932724 -240.552986)
		(size 0.762)
		(drill 0.381)
		(layers "F.Cu" "B.Cu")
		(net "PWRGD_P12V_AUX_R1")
	)
	(via
		(at 100.52558 -353.013518)
		(size 0.508)
		(drill 0.254)
		(layers "F.Cu" "B.Cu")
		(net "PEX_S3_REF_CLK_BUFFER_EN_N")
	)
	(via
		(at 106.91495 -353.14382)
		(size 0.508)
		(drill 0.254)
		(layers "F.Cu" "B.Cu")
		(net "PEX_S3_REF_CLK_BUFFER_EN_N")
	)
	(via
		(at 101.17836 -355.543866)
		(size 0.508)
		(drill 0.254)
		(layers "F.Cu" "B.Cu")
		(net "PEX_S3_REF_CLK_BUFFER_EN_N")
	)
	(via
		(at 106.43743 -355.313996)
		(size 0.508)
		(drill 0.254)
		(layers "F.Cu" "B.Cu")
		(net "PEX_S3_REF_CLK_BUFFER_EN_N")
	)
	(via
		(at 107.791504 -353.261676)
		(size 0.6604)
		(drill 0.3302)
		(layers "F.Cu" "B.Cu")
		(net "PEX_S3_REF_CLK_BUFFER_EN_N")
	)
	(segment
		(start 105.440734 -355.000052)
		(end 105.440734 -354.138484)
		(width 0.254)
		(layer "B.Cu")
		(net "PEX_S3_REF_CLK_BUFFER_EN_N")
	)
	(segment
		(start 107.242102 -353.14382)
		(end 106.91495 -353.14382)
		(width 0.13208)
		(layer "B.Cu")
		(net "PEX_S3_REF_CLK_BUFFER_EN_N")
	)
	(segment
		(start 107.791504 -353.261676)
		(end 107.359958 -353.261676)
		(width 0.13208)
		(layer "B.Cu")
		(net "PEX_S3_REF_CLK_BUFFER_EN_N")
	)
	(segment
		(start 106.62285 -353.088448)
		(end 106.590338 -353.055936)
		(width 0.254)
		(layer "B.Cu")
		(net "PEX_S3_REF_CLK_BUFFER_EN_N")
	)
	(segment
		(start 105.754678 -355.313996)
		(end 105.440734 -355.000052)
		(width 0.254)
		(layer "B.Cu")
		(net "PEX_S3_REF_CLK_BUFFER_EN_N")
	)
	(segment
		(start 101.829362 -355.177598)
		(end 102.44074 -354.56622)
		(width 0.254)
		(layer "B.Cu")
		(net "PEX_S3_REF_CLK_BUFFER_EN_N")
	)
	(segment
		(start 106.590338 -353.055936)
		(end 106.54411 -353.055936)
		(width 0.254)
		(layer "B.Cu")
		(net "PEX_S3_REF_CLK_BUFFER_EN_N")
	)
	(segment
		(start 101.315774 -353.013518)
		(end 100.52558 -353.013518)
		(width 0.254)
		(layer "B.Cu")
		(net "PEX_S3_REF_CLK_BUFFER_EN_N")
	)
	(segment
		(start 106.5276 -353.039426)
		(end 106.41838 -353.039426)
		(width 0.254)
		(layer "B.Cu")
		(net "PEX_S3_REF_CLK_BUFFER_EN_N")
	)
	(segment
		(start 106.646218 -353.088448)
		(end 106.62285 -353.088448)
		(width 0.254)
		(layer "B.Cu")
		(net "PEX_S3_REF_CLK_BUFFER_EN_N")
	)
	(segment
		(start 101.17836 -355.543866)
		(end 101.296216 -355.661722)
		(width 0.254)
		(layer "B.Cu")
		(net "PEX_S3_REF_CLK_BUFFER_EN_N")
	)
	(segment
		(start 101.296216 -355.661722)
		(end 101.823266 -355.661722)
		(width 0.254)
		(layer "B.Cu")
		(net "PEX_S3_REF_CLK_BUFFER_EN_N")
	)
	(segment
		(start 102.44074 -354.56622)
		(end 102.44074 -354.138484)
		(width 0.254)
		(layer "B.Cu")
		(net "PEX_S3_REF_CLK_BUFFER_EN_N")
	)
	(segment
		(start 106.91495 -353.14382)
		(end 106.70159 -353.14382)
		(width 0.254)
		(layer "B.Cu")
		(net "PEX_S3_REF_CLK_BUFFER_EN_N")
	)
	(segment
		(start 101.823266 -355.661722)
		(end 101.829362 -355.177598)
		(width 0.254)
		(layer "B.Cu")
		(net "PEX_S3_REF_CLK_BUFFER_EN_N")
	)
	(segment
		(start 106.54411 -353.055936)
		(end 106.5276 -353.039426)
		(width 0.254)
		(layer "B.Cu")
		(net "PEX_S3_REF_CLK_BUFFER_EN_N")
	)
	(segment
		(start 106.392472 -353.013518)
		(end 106.065574 -353.013518)
		(width 0.254)
		(layer "B.Cu")
		(net "PEX_S3_REF_CLK_BUFFER_EN_N")
	)
	(segment
		(start 107.359958 -353.261676)
		(end 107.242102 -353.14382)
		(width 0.13208)
		(layer "B.Cu")
		(net "PEX_S3_REF_CLK_BUFFER_EN_N")
	)
	(segment
		(start 106.43743 -355.313996)
		(end 105.754678 -355.313996)
		(width 0.254)
		(layer "B.Cu")
		(net "PEX_S3_REF_CLK_BUFFER_EN_N")
	)
	(segment
		(start 106.41838 -353.039426)
		(end 106.392472 -353.013518)
		(width 0.254)
		(layer "B.Cu")
		(net "PEX_S3_REF_CLK_BUFFER_EN_N")
	)
	(segment
		(start 106.70159 -353.14382)
		(end 106.646218 -353.088448)
		(width 0.254)
		(layer "B.Cu")
		(net "PEX_S3_REF_CLK_BUFFER_EN_N")
	)
	(segment
		(start 434.981604 -292.923468)
		(end 434.981604 -292.142164)
		(width 0.13208)
		(layer "F.Cu")
		(net "RST_PEX3_S0_PERST_N")
	)
	(segment
		(start 434.60924 -291.9984)
		(end 433.842668 -291.231828)
		(width 0.13208)
		(layer "F.Cu")
		(net "RST_PEX3_S0_PERST_N")
	)
	(segment
		(start 433.83581 -291.231828)
		(end 433.83581 -290.2458)
		(width 0.13208)
		(layer "F.Cu")
		(net "RST_PEX3_S0_PERST_N")
	)
	(segment
		(start 434.981604 -292.142164)
		(end 434.83784 -291.9984)
		(width 0.13208)
		(layer "F.Cu")
		(net "RST_PEX3_S0_PERST_N")
	)
	(segment
		(start 433.842668 -291.231828)
		(end 433.83581 -291.231828)
		(width 0.13208)
		(layer "F.Cu")
		(net "RST_PEX3_S0_PERST_N")
	)
	(segment
		(start 433.83581 -290.2458)
		(end 433.83581 -289.630866)
		(width 0.13208)
		(layer "F.Cu")
		(net "RST_PEX3_S0_PERST_N")
	)
	(segment
		(start 434.83784 -291.9984)
		(end 434.60924 -291.9984)
		(width 0.13208)
		(layer "F.Cu")
		(net "RST_PEX3_S0_PERST_N")
	)
	(via
		(at 433.83581 -290.2458)
		(size 0.508)
		(drill 0.254)
		(layers "F.Cu" "B.Cu")
		(net "RST_PEX3_S0_PERST_N")
	)
	(segment
		(start 436.0418 -298.329604)
		(end 436.28183 -298.089574)
		(width 0.13208)
		(layer "F.Cu")
		(net "RST_PEX3_S1_PERST_N")
	)
	(segment
		(start 436.0418 -300.194726)
		(end 436.0418 -298.329604)
		(width 0.13208)
		(layer "F.Cu")
		(net "RST_PEX3_S1_PERST_N")
	)
	(segment
		(start 436.049674 -300.2026)
		(end 436.0418 -300.194726)
		(width 0.13208)
		(layer "F.Cu")
		(net "RST_PEX3_S1_PERST_N")
	)
	(segment
		(start 436.28183 -298.089574)
		(end 436.28183 -296.623232)
		(width 0.13208)
		(layer "F.Cu")
		(net "RST_PEX3_S1_PERST_N")
	)
	(via
		(at 436.0418 -298.329604)
		(size 0.762)
		(drill 0.381)
		(layers "F.Cu" "B.Cu")
		(net "RST_PEX3_S1_PERST_N")
	)
	(segment
		(start 434.981604 -297.6753)
		(end 434.981604 -296.623232)
		(width 0.13208)
		(layer "F.Cu")
		(net "RST_PEX3_S3_PERST_N")
	)
	(segment
		(start 434.981604 -297.909996)
		(end 434.981604 -297.6753)
		(width 0.13208)
		(layer "F.Cu")
		(net "RST_PEX3_S3_PERST_N")
	)
	(segment
		(start 434.6194 -298.2722)
		(end 434.981604 -297.909996)
		(width 0.13208)
		(layer "F.Cu")
		(net "RST_PEX3_S3_PERST_N")
	)
	(segment
		(start 434.6194 -299.81017)
		(end 434.6194 -298.2722)
		(width 0.13208)
		(layer "F.Cu")
		(net "RST_PEX3_S3_PERST_N")
	)
	(segment
		(start 435.02961 -300.22038)
		(end 434.6194 -299.81017)
		(width 0.13208)
		(layer "F.Cu")
		(net "RST_PEX3_S3_PERST_N")
	)
	(via
		(at 434.981604 -297.6753)
		(size 0.508)
		(drill 0.254)
		(layers "F.Cu" "B.Cu")
		(net "RST_PEX3_S3_PERST_N")
	)
	(segment
		(start 103.006398 -354.892356)
		(end 103.006398 -354.398326)
		(width 0.1143)
		(layer "B.Cu")
		(net "CLK_100M_DB800ZL_PEX1_S3_DP")
	)
	(segment
		(start 102.940612 -354.33254)
		(end 102.940612 -354.138484)
		(width 0.1143)
		(layer "B.Cu")
		(net "CLK_100M_DB800ZL_PEX1_S3_DP")
	)
	(segment
		(start 102.479856 -357.199184)
		(end 102.479856 -355.418898)
		(width 0.1143)
		(layer "B.Cu")
		(net "CLK_100M_DB800ZL_PEX1_S3_DP")
	)
	(segment
		(start 103.006398 -354.398326)
		(end 102.940612 -354.33254)
		(width 0.1143)
		(layer "B.Cu")
		(net "CLK_100M_DB800ZL_PEX1_S3_DP")
	)
	(segment
		(start 102.479856 -355.418898)
		(end 103.006398 -354.892356)
		(width 0.1143)
		(layer "B.Cu")
		(net "CLK_100M_DB800ZL_PEX1_S3_DP")
	)
	(segment
		(start 102.156006 -357.523034)
		(end 102.479856 -357.199184)
		(width 0.1143)
		(layer "B.Cu")
		(net "CLK_100M_DB800ZL_PEX1_S3_DP")
	)
	(segment
		(start 99.04603 -352.072956)
		(end 101.05517 -352.072956)
		(width 0.1143)
		(layer "B.Cu")
		(net "CLK_100M_DB800ZL_PEX0_S3_DP")
	)
	(segment
		(start 101.114606 -352.01352)
		(end 101.315774 -352.01352)
		(width 0.1143)
		(layer "B.Cu")
		(net "CLK_100M_DB800ZL_PEX0_S3_DP")
	)
	(segment
		(start 98.692462 -351.719388)
		(end 99.04603 -352.072956)
		(width 0.1143)
		(layer "B.Cu")
		(net "CLK_100M_DB800ZL_PEX0_S3_DP")
	)
	(segment
		(start 101.05517 -352.072956)
		(end 101.114606 -352.01352)
		(width 0.1143)
		(layer "B.Cu")
		(net "CLK_100M_DB800ZL_PEX0_S3_DP")
	)
	(segment
		(start 106.236008 -352.513646)
		(end 106.065574 -352.513646)
		(width 0.1143)
		(layer "B.Cu")
		(net "CLK_100M_DB800ZL_PEX3_S3_DP")
	)
	(segment
		(start 106.302048 -352.447606)
		(end 106.236008 -352.513646)
		(width 0.1143)
		(layer "B.Cu")
		(net "CLK_100M_DB800ZL_PEX3_S3_DP")
	)
	(segment
		(start 108.77804 -352.447606)
		(end 106.302048 -352.447606)
		(width 0.1143)
		(layer "B.Cu")
		(net "CLK_100M_DB800ZL_PEX3_S3_DP")
	)
	(segment
		(start 109.143038 -352.812604)
		(end 108.77804 -352.447606)
		(width 0.1143)
		(layer "B.Cu")
		(net "CLK_100M_DB800ZL_PEX3_S3_DP")
	)
	(segment
		(start 102.848156 -355.572822)
		(end 103.374698 -355.04628)
		(width 0.1143)
		(layer "B.Cu")
		(net "CLK_100M_DB800ZL_PEX1_S3_DN")
	)
	(segment
		(start 103.374698 -355.04628)
		(end 103.374698 -354.40493)
		(width 0.1143)
		(layer "B.Cu")
		(net "CLK_100M_DB800ZL_PEX1_S3_DN")
	)
	(segment
		(start 103.172006 -357.523034)
		(end 102.848156 -357.199184)
		(width 0.1143)
		(layer "B.Cu")
		(net "CLK_100M_DB800ZL_PEX1_S3_DN")
	)
	(segment
		(start 103.374698 -354.40493)
		(end 103.440738 -354.33889)
		(width 0.1143)
		(layer "B.Cu")
		(net "CLK_100M_DB800ZL_PEX1_S3_DN")
	)
	(segment
		(start 103.440738 -354.33889)
		(end 103.440738 -354.138484)
		(width 0.1143)
		(layer "B.Cu")
		(net "CLK_100M_DB800ZL_PEX1_S3_DN")
	)
	(segment
		(start 102.848156 -357.199184)
		(end 102.848156 -355.572822)
		(width 0.1143)
		(layer "B.Cu")
		(net "CLK_100M_DB800ZL_PEX1_S3_DN")
	)
	(segment
		(start 296.6466 -140.5382)
		(end 296.6466 -140.2588)
		(width 0.13208)
		(layer "F.Cu")
		(net "SMB_BMC_9FGL0451E_S3_SDA")
	)
	(segment
		(start 99.627436 -346.583254)
		(end 100.122736 -346.087954)
		(width 0.13208)
		(layer "F.Cu")
		(net "SMB_BMC_9FGL0451E_S3_SDA")
	)
	(segment
		(start 243.823236 -218.65971)
		(end 243.823236 -227.677472)
		(width 0.13208)
		(layer "F.Cu")
		(net "SMB_BMC_9FGL0451E_S3_SDA")
	)
	(segment
		(start 251.522484 -257.249676)
		(end 251.65304 -257.56489)
		(width 0.13208)
		(layer "F.Cu")
		(net "SMB_BMC_9FGL0451E_S3_SDA")
	)
	(segment
		(start 100.122736 -346.087954)
		(end 102.526846 -346.087954)
		(width 0.13208)
		(layer "F.Cu")
		(net "SMB_BMC_9FGL0451E_S3_SDA")
	)
	(segment
		(start 245.165626 -327.57491)
		(end 236.48289 -327.57491)
		(width 0.13208)
		(layer "F.Cu")
		(net "SMB_BMC_9FGL0451E_S3_SDA")
	)
	(segment
		(start 248.412 -246.163084)
		(end 251.522484 -249.273568)
		(width 0.13208)
		(layer "F.Cu")
		(net "SMB_BMC_9FGL0451E_S3_SDA")
	)
	(segment
		(start 310.22544 -103.363014)
		(end 310.22544 -95.621094)
		(width 0.13208)
		(layer "F.Cu")
		(net "SMB_BMC_9FGL0451E_S3_SDA")
	)
	(segment
		(start 248.412 -235.709714)
		(end 248.412 -246.163084)
		(width 0.13208)
		(layer "F.Cu")
		(net "SMB_BMC_9FGL0451E_S3_SDA")
	)
	(segment
		(start 109.1184 -338.6582)
		(end 114.3 -338.6582)
		(width 0.13208)
		(layer "F.Cu")
		(net "SMB_BMC_9FGL0451E_S3_SDA")
	)
	(segment
		(start 244.6274 -203.289916)
		(end 243.5606 -204.356716)
		(width 0.13208)
		(layer "F.Cu")
		(net "SMB_BMC_9FGL0451E_S3_SDA")
	)
	(segment
		(start 251.65304 -257.56489)
		(end 252.052328 -257.964178)
		(width 0.13208)
		(layer "F.Cu")
		(net "SMB_BMC_9FGL0451E_S3_SDA")
	)
	(segment
		(start 297.078654 -105.8164)
		(end 307.772054 -105.8164)
		(width 0.13208)
		(layer "F.Cu")
		(net "SMB_BMC_9FGL0451E_S3_SDA")
	)
	(segment
		(start 256.790952 -301.880016)
		(end 251.269754 -307.401214)
		(width 0.13208)
		(layer "F.Cu")
		(net "SMB_BMC_9FGL0451E_S3_SDA")
	)
	(segment
		(start 118.7196 -334.2386)
		(end 121.440448 -334.2386)
		(width 0.13208)
		(layer "F.Cu")
		(net "SMB_BMC_9FGL0451E_S3_SDA")
	)
	(segment
		(start 252.052328 -257.964178)
		(end 252.052328 -259.07746)
		(width 0.13208)
		(layer "F.Cu")
		(net "SMB_BMC_9FGL0451E_S3_SDA")
	)
	(segment
		(start 243.560346 -227.940362)
		(end 243.560346 -230.85806)
		(width 0.13208)
		(layer "F.Cu")
		(net "SMB_BMC_9FGL0451E_S3_SDA")
	)
	(segment
		(start 104.7242 -343.8906)
		(end 104.7242 -341.0966)
		(width 0.13208)
		(layer "F.Cu")
		(net "SMB_BMC_9FGL0451E_S3_SDA")
	)
	(segment
		(start 251.522484 -249.273568)
		(end 251.522484 -257.249676)
		(width 0.13208)
		(layer "F.Cu")
		(net "SMB_BMC_9FGL0451E_S3_SDA")
	)
	(segment
		(start 252.910086 -261.399274)
		(end 252.910086 -275.812758)
		(width 0.13208)
		(layer "F.Cu")
		(net "SMB_BMC_9FGL0451E_S3_SDA")
	)
	(segment
		(start 243.560346 -230.85806)
		(end 248.412 -235.709714)
		(width 0.13208)
		(layer "F.Cu")
		(net "SMB_BMC_9FGL0451E_S3_SDA")
	)
	(segment
		(start 105.8926 -339.9282)
		(end 107.8484 -339.9282)
		(width 0.13208)
		(layer "F.Cu")
		(net "SMB_BMC_9FGL0451E_S3_SDA")
	)
	(segment
		(start 244.84584 -217.637106)
		(end 243.823236 -218.65971)
		(width 0.13208)
		(layer "F.Cu")
		(net "SMB_BMC_9FGL0451E_S3_SDA")
	)
	(segment
		(start 243.205 -198.3232)
		(end 244.6274 -199.7456)
		(width 0.13208)
		(layer "F.Cu")
		(net "SMB_BMC_9FGL0451E_S3_SDA")
	)
	(segment
		(start 295.656 -139.9286)
		(end 295.1226 -140.462)
		(width 0.13208)
		(layer "F.Cu")
		(net "SMB_BMC_9FGL0451E_S3_SDA")
	)
	(segment
		(start 222.9612 -329.3872)
		(end 222.029782 -329.3872)
		(width 0.13208)
		(layer "F.Cu")
		(net "SMB_BMC_9FGL0451E_S3_SDA")
	)
	(segment
		(start 236.48289 -327.57491)
		(end 233.1466 -330.9112)
		(width 0.13208)
		(layer "F.Cu")
		(net "SMB_BMC_9FGL0451E_S3_SDA")
	)
	(segment
		(start 244.6274 -199.7456)
		(end 244.6274 -203.289916)
		(width 0.13208)
		(layer "F.Cu")
		(net "SMB_BMC_9FGL0451E_S3_SDA")
	)
	(segment
		(start 252.35916 -259.818124)
		(end 252.35916 -260.848348)
		(width 0.13208)
		(layer "F.Cu")
		(net "SMB_BMC_9FGL0451E_S3_SDA")
	)
	(segment
		(start 121.440448 -334.2386)
		(end 123.8504 -331.828648)
		(width 0.13208)
		(layer "F.Cu")
		(net "SMB_BMC_9FGL0451E_S3_SDA")
	)
	(segment
		(start 296.6466 -140.2588)
		(end 296.3164 -139.9286)
		(width 0.13208)
		(layer "F.Cu")
		(net "SMB_BMC_9FGL0451E_S3_SDA")
	)
	(segment
		(start 222.029782 -329.3872)
		(end 221.6404 -329.776582)
		(width 0.13208)
		(layer "F.Cu")
		(net "SMB_BMC_9FGL0451E_S3_SDA")
	)
	(segment
		(start 251.269754 -318.677798)
		(end 249.295158 -323.445378)
		(width 0.13208)
		(layer "F.Cu")
		(net "SMB_BMC_9FGL0451E_S3_SDA")
	)
	(segment
		(start 102.526846 -346.087954)
		(end 104.7242 -343.8906)
		(width 0.13208)
		(layer "F.Cu")
		(net "SMB_BMC_9FGL0451E_S3_SDA")
	)
	(segment
		(start 114.3 -338.6582)
		(end 118.7196 -334.2386)
		(width 0.13208)
		(layer "F.Cu")
		(net "SMB_BMC_9FGL0451E_S3_SDA")
	)
	(segment
		(start 252.35916 -260.848348)
		(end 252.910086 -261.399274)
		(width 0.13208)
		(layer "F.Cu")
		(net "SMB_BMC_9FGL0451E_S3_SDA")
	)
	(segment
		(start 104.7242 -341.0966)
		(end 105.8926 -339.9282)
		(width 0.13208)
		(layer "F.Cu")
		(net "SMB_BMC_9FGL0451E_S3_SDA")
	)
	(segment
		(start 244.3226 -211.7852)
		(end 244.84584 -212.30844)
		(width 0.13208)
		(layer "F.Cu")
		(net "SMB_BMC_9FGL0451E_S3_SDA")
	)
	(segment
		(start 295.1226 -140.462)
		(end 293.9796 -140.462)
		(width 0.13208)
		(layer "F.Cu")
		(net "SMB_BMC_9FGL0451E_S3_SDA")
	)
	(segment
		(start 320.538094 -92.52204)
		(end 325.03237 -88.027764)
		(width 0.13208)
		(layer "F.Cu")
		(net "SMB_BMC_9FGL0451E_S3_SDA")
	)
	(segment
		(start 310.22544 -95.621094)
		(end 310.581294 -95.26524)
		(width 0.13208)
		(layer "F.Cu")
		(net "SMB_BMC_9FGL0451E_S3_SDA")
	)
	(segment
		(start 107.8484 -339.9282)
		(end 109.1184 -338.6582)
		(width 0.13208)
		(layer "F.Cu")
		(net "SMB_BMC_9FGL0451E_S3_SDA")
	)
	(segment
		(start 243.5606 -208.520284)
		(end 244.3226 -209.282284)
		(width 0.13208)
		(layer "F.Cu")
		(net "SMB_BMC_9FGL0451E_S3_SDA")
	)
	(segment
		(start 233.1466 -330.9112)
		(end 224.4852 -330.9112)
		(width 0.13208)
		(layer "F.Cu")
		(net "SMB_BMC_9FGL0451E_S3_SDA")
	)
	(segment
		(start 244.84584 -212.30844)
		(end 244.84584 -217.637106)
		(width 0.13208)
		(layer "F.Cu")
		(net "SMB_BMC_9FGL0451E_S3_SDA")
	)
	(segment
		(start 292.0238 -138.5062)
		(end 292.0238 -110.871254)
		(width 0.13208)
		(layer "F.Cu")
		(net "SMB_BMC_9FGL0451E_S3_SDA")
	)
	(segment
		(start 224.4852 -330.9112)
		(end 222.9612 -329.3872)
		(width 0.13208)
		(layer "F.Cu")
		(net "SMB_BMC_9FGL0451E_S3_SDA")
	)
	(segment
		(start 249.295158 -323.445378)
		(end 245.165626 -327.57491)
		(width 0.13208)
		(layer "F.Cu")
		(net "SMB_BMC_9FGL0451E_S3_SDA")
	)
	(segment
		(start 293.9796 -140.462)
		(end 292.0238 -138.5062)
		(width 0.13208)
		(layer "F.Cu")
		(net "SMB_BMC_9FGL0451E_S3_SDA")
	)
	(segment
		(start 252.052328 -259.07746)
		(end 252.35916 -259.818124)
		(width 0.13208)
		(layer "F.Cu")
		(net "SMB_BMC_9FGL0451E_S3_SDA")
	)
	(segment
		(start 252.910086 -275.812758)
		(end 256.790952 -279.693624)
		(width 0.13208)
		(layer "F.Cu")
		(net "SMB_BMC_9FGL0451E_S3_SDA")
	)
	(segment
		(start 123.8504 -331.828648)
		(end 123.8504 -330.7334)
		(width 0.13208)
		(layer "F.Cu")
		(net "SMB_BMC_9FGL0451E_S3_SDA")
	)
	(segment
		(start 292.0238 -110.871254)
		(end 297.078654 -105.8164)
		(width 0.13208)
		(layer "F.Cu")
		(net "SMB_BMC_9FGL0451E_S3_SDA")
	)
	(segment
		(start 244.3226 -209.282284)
		(end 244.3226 -211.7852)
		(width 0.13208)
		(layer "F.Cu")
		(net "SMB_BMC_9FGL0451E_S3_SDA")
	)
	(segment
		(start 307.772054 -105.8164)
		(end 310.22544 -103.363014)
		(width 0.13208)
		(layer "F.Cu")
		(net "SMB_BMC_9FGL0451E_S3_SDA")
	)
	(segment
		(start 315.788294 -92.52204)
		(end 320.538094 -92.52204)
		(width 0.13208)
		(layer "F.Cu")
		(net "SMB_BMC_9FGL0451E_S3_SDA")
	)
	(segment
		(start 310.581294 -95.26524)
		(end 313.045094 -95.26524)
		(width 0.13208)
		(layer "F.Cu")
		(net "SMB_BMC_9FGL0451E_S3_SDA")
	)
	(segment
		(start 313.045094 -95.26524)
		(end 315.788294 -92.52204)
		(width 0.13208)
		(layer "F.Cu")
		(net "SMB_BMC_9FGL0451E_S3_SDA")
	)
	(segment
		(start 296.3164 -139.9286)
		(end 295.656 -139.9286)
		(width 0.13208)
		(layer "F.Cu")
		(net "SMB_BMC_9FGL0451E_S3_SDA")
	)
	(segment
		(start 256.790952 -279.693624)
		(end 256.790952 -301.880016)
		(width 0.13208)
		(layer "F.Cu")
		(net "SMB_BMC_9FGL0451E_S3_SDA")
	)
	(segment
		(start 243.823236 -227.677472)
		(end 243.560346 -227.940362)
		(width 0.13208)
		(layer "F.Cu")
		(net "SMB_BMC_9FGL0451E_S3_SDA")
	)
	(segment
		(start 243.5606 -204.356716)
		(end 243.5606 -208.520284)
		(width 0.13208)
		(layer "F.Cu")
		(net "SMB_BMC_9FGL0451E_S3_SDA")
	)
	(segment
		(start 251.269754 -307.401214)
		(end 251.269754 -318.677798)
		(width 0.13208)
		(layer "F.Cu")
		(net "SMB_BMC_9FGL0451E_S3_SDA")
	)
	(segment
		(start 325.03237 -88.027764)
		(end 325.03237 -87.814404)
		(width 0.13208)
		(layer "F.Cu")
		(net "SMB_BMC_9FGL0451E_S3_SDA")
	)
	(via
		(at 296.6466 -140.5382)
		(size 0.508)
		(drill 0.254)
		(layers "F.Cu" "B.Cu")
		(net "SMB_BMC_9FGL0451E_S3_SDA")
	)
	(via
		(at 123.8504 -330.7334)
		(size 0.508)
		(drill 0.254)
		(layers "F.Cu" "B.Cu")
		(net "SMB_BMC_9FGL0451E_S3_SDA")
	)
	(via
		(at 99.627436 -346.583254)
		(size 0.508)
		(drill 0.254)
		(layers "F.Cu" "B.Cu")
		(net "SMB_BMC_9FGL0451E_S3_SDA")
	)
	(via
		(at 221.6404 -329.776582)
		(size 0.508)
		(drill 0.254)
		(layers "F.Cu" "B.Cu")
		(net "SMB_BMC_9FGL0451E_S3_SDA")
	)
	(via
		(at 243.205 -198.3232)
		(size 0.508)
		(drill 0.254)
		(layers "F.Cu" "B.Cu")
		(net "SMB_BMC_9FGL0451E_S3_SDA")
	)
	(via
		(at 233.2482 -159.9438)
		(size 0.508)
		(drill 0.254)
		(layers "F.Cu" "B.Cu")
		(net "SMB_BMC_9FGL0451E_S3_SDA")
	)
	(segment
		(start 102.940612 -348.474792)
		(end 101.905308 -347.439488)
		(width 0.13208)
		(layer "B.Cu")
		(net "SMB_BMC_9FGL0451E_S3_SDA")
	)
	(segment
		(start 101.905308 -347.285818)
		(end 101.535992 -346.916502)
		(width 0.13208)
		(layer "B.Cu")
		(net "SMB_BMC_9FGL0451E_S3_SDA")
	)
	(segment
		(start 123.8504 -330.61148)
		(end 123.8504 -330.7334)
		(width 0.13208)
		(layer "B.Cu")
		(net "SMB_BMC_9FGL0451E_S3_SDA")
	)
	(segment
		(start 249.682 -184.277)
		(end 248.7422 -183.3372)
		(width 0.13208)
		(layer "B.Cu")
		(net "SMB_BMC_9FGL0451E_S3_SDA")
	)
	(segment
		(start 243.205 -198.3232)
		(end 243.205 -196.85)
		(width 0.13208)
		(layer "B.Cu")
		(net "SMB_BMC_9FGL0451E_S3_SDA")
	)
	(segment
		(start 248.7422 -179.5526)
		(end 233.2482 -164.0586)
		(width 0.13208)
		(layer "B.Cu")
		(net "SMB_BMC_9FGL0451E_S3_SDA")
	)
	(segment
		(start 221.6404 -329.776582)
		(end 124.685298 -329.776582)
		(width 0.13208)
		(layer "B.Cu")
		(net "SMB_BMC_9FGL0451E_S3_SDA")
	)
	(segment
		(start 248.7422 -183.3372)
		(end 248.7422 -179.5526)
		(width 0.13208)
		(layer "B.Cu")
		(net "SMB_BMC_9FGL0451E_S3_SDA")
	)
	(segment
		(start 100.396548 -346.84843)
		(end 100.356924 -346.84843)
		(width 0.13208)
		(layer "B.Cu")
		(net "SMB_BMC_9FGL0451E_S3_SDA")
	)
	(segment
		(start 233.2482 -164.0586)
		(end 233.2482 -159.9438)
		(width 0.13208)
		(layer "B.Cu")
		(net "SMB_BMC_9FGL0451E_S3_SDA")
	)
	(segment
		(start 100.356924 -346.84843)
		(end 100.091748 -346.583254)
		(width 0.13208)
		(layer "B.Cu")
		(net "SMB_BMC_9FGL0451E_S3_SDA")
	)
	(segment
		(start 100.46462 -346.916502)
		(end 100.396548 -346.84843)
		(width 0.13208)
		(layer "B.Cu")
		(net "SMB_BMC_9FGL0451E_S3_SDA")
	)
	(segment
		(start 244.4242 -195.6308)
		(end 244.4242 -191.3382)
		(width 0.13208)
		(layer "B.Cu")
		(net "SMB_BMC_9FGL0451E_S3_SDA")
	)
	(segment
		(start 102.940612 -349.388684)
		(end 102.940612 -348.474792)
		(width 0.13208)
		(layer "B.Cu")
		(net "SMB_BMC_9FGL0451E_S3_SDA")
	)
	(segment
		(start 244.4242 -191.3382)
		(end 249.682 -186.0804)
		(width 0.13208)
		(layer "B.Cu")
		(net "SMB_BMC_9FGL0451E_S3_SDA")
	)
	(segment
		(start 249.682 -186.0804)
		(end 249.682 -184.277)
		(width 0.13208)
		(layer "B.Cu")
		(net "SMB_BMC_9FGL0451E_S3_SDA")
	)
	(segment
		(start 101.535992 -346.916502)
		(end 100.46462 -346.916502)
		(width 0.13208)
		(layer "B.Cu")
		(net "SMB_BMC_9FGL0451E_S3_SDA")
	)
	(segment
		(start 124.685298 -329.776582)
		(end 123.8504 -330.61148)
		(width 0.13208)
		(layer "B.Cu")
		(net "SMB_BMC_9FGL0451E_S3_SDA")
	)
	(segment
		(start 100.091748 -346.583254)
		(end 99.627436 -346.583254)
		(width 0.13208)
		(layer "B.Cu")
		(net "SMB_BMC_9FGL0451E_S3_SDA")
	)
	(segment
		(start 243.205 -196.85)
		(end 244.4242 -195.6308)
		(width 0.13208)
		(layer "B.Cu")
		(net "SMB_BMC_9FGL0451E_S3_SDA")
	)
	(segment
		(start 101.905308 -347.439488)
		(end 101.905308 -347.285818)
		(width 0.13208)
		(layer "B.Cu")
		(net "SMB_BMC_9FGL0451E_S3_SDA")
	)
	(segment
		(start 267.1064 -140.5636)
		(end 269.1892 -138.4808)
		(width 0.15494)
		(layer "In13.Cu")
		(net "SMB_BMC_9FGL0451E_S3_SDA")
	)
	(segment
		(start 283.3878 -137.9474)
		(end 286.6136 -137.9474)
		(width 0.15494)
		(layer "In13.Cu")
		(net "SMB_BMC_9FGL0451E_S3_SDA")
	)
	(segment
		(start 247.5992 -161.7726)
		(end 250.9012 -158.4706)
		(width 0.15494)
		(layer "In13.Cu")
		(net "SMB_BMC_9FGL0451E_S3_SDA")
	)
	(segment
		(start 273.7358 -138.4808)
		(end 276.1234 -136.0932)
		(width 0.15494)
		(layer "In13.Cu")
		(net "SMB_BMC_9FGL0451E_S3_SDA")
	)
	(segment
		(start 252.8316 -158.4706)
		(end 254.1524 -157.1498)
		(width 0.15494)
		(layer "In13.Cu")
		(net "SMB_BMC_9FGL0451E_S3_SDA")
	)
	(segment
		(start 287.782 -136.779)
		(end 287.782 -135.636)
		(width 0.15494)
		(layer "In13.Cu")
		(net "SMB_BMC_9FGL0451E_S3_SDA")
	)
	(segment
		(start 296.668952 -140.515848)
		(end 296.6466 -140.5382)
		(width 0.15494)
		(layer "In13.Cu")
		(net "SMB_BMC_9FGL0451E_S3_SDA")
	)
	(segment
		(start 259.0292 -157.1498)
		(end 267.1064 -149.0726)
		(width 0.15494)
		(layer "In13.Cu")
		(net "SMB_BMC_9FGL0451E_S3_SDA")
	)
	(segment
		(start 276.1234 -136.0932)
		(end 281.5336 -136.0932)
		(width 0.15494)
		(layer "In13.Cu")
		(net "SMB_BMC_9FGL0451E_S3_SDA")
	)
	(segment
		(start 254.1524 -157.1498)
		(end 259.0292 -157.1498)
		(width 0.15494)
		(layer "In13.Cu")
		(net "SMB_BMC_9FGL0451E_S3_SDA")
	)
	(segment
		(start 288.1884 -135.2296)
		(end 289.6362 -135.2296)
		(width 0.15494)
		(layer "In13.Cu")
		(net "SMB_BMC_9FGL0451E_S3_SDA")
	)
	(segment
		(start 233.2482 -159.9438)
		(end 233.2482 -161.3408)
		(width 0.15494)
		(layer "In13.Cu")
		(net "SMB_BMC_9FGL0451E_S3_SDA")
	)
	(segment
		(start 233.68 -161.7726)
		(end 247.5992 -161.7726)
		(width 0.15494)
		(layer "In13.Cu")
		(net "SMB_BMC_9FGL0451E_S3_SDA")
	)
	(segment
		(start 233.2482 -161.3408)
		(end 233.68 -161.7726)
		(width 0.15494)
		(layer "In13.Cu")
		(net "SMB_BMC_9FGL0451E_S3_SDA")
	)
	(segment
		(start 294.5638 -136.3726)
		(end 296.668952 -138.477752)
		(width 0.15494)
		(layer "In13.Cu")
		(net "SMB_BMC_9FGL0451E_S3_SDA")
	)
	(segment
		(start 250.9012 -158.4706)
		(end 252.8316 -158.4706)
		(width 0.15494)
		(layer "In13.Cu")
		(net "SMB_BMC_9FGL0451E_S3_SDA")
	)
	(segment
		(start 269.1892 -138.4808)
		(end 273.7358 -138.4808)
		(width 0.15494)
		(layer "In13.Cu")
		(net "SMB_BMC_9FGL0451E_S3_SDA")
	)
	(segment
		(start 281.5336 -136.0932)
		(end 283.3878 -137.9474)
		(width 0.15494)
		(layer "In13.Cu")
		(net "SMB_BMC_9FGL0451E_S3_SDA")
	)
	(segment
		(start 290.7792 -136.3726)
		(end 294.5638 -136.3726)
		(width 0.15494)
		(layer "In13.Cu")
		(net "SMB_BMC_9FGL0451E_S3_SDA")
	)
	(segment
		(start 289.6362 -135.2296)
		(end 290.7792 -136.3726)
		(width 0.15494)
		(layer "In13.Cu")
		(net "SMB_BMC_9FGL0451E_S3_SDA")
	)
	(segment
		(start 267.1064 -149.0726)
		(end 267.1064 -140.5636)
		(width 0.15494)
		(layer "In13.Cu")
		(net "SMB_BMC_9FGL0451E_S3_SDA")
	)
	(segment
		(start 287.782 -135.636)
		(end 288.1884 -135.2296)
		(width 0.15494)
		(layer "In13.Cu")
		(net "SMB_BMC_9FGL0451E_S3_SDA")
	)
	(segment
		(start 296.668952 -138.477752)
		(end 296.668952 -140.515848)
		(width 0.15494)
		(layer "In13.Cu")
		(net "SMB_BMC_9FGL0451E_S3_SDA")
	)
	(segment
		(start 286.6136 -137.9474)
		(end 287.782 -136.779)
		(width 0.15494)
		(layer "In13.Cu")
		(net "SMB_BMC_9FGL0451E_S3_SDA")
	)
	(segment
		(start 105.277412 -355.685852)
		(end 105.277412 -356.988872)
		(width 0.1143)
		(layer "B.Cu")
		(net "CLK_100M_DB800ZL_PEX2_S3_DN")
	)
	(segment
		(start 104.940608 -354.138484)
		(end 104.940608 -354.3427)
		(width 0.1143)
		(layer "B.Cu")
		(net "CLK_100M_DB800ZL_PEX2_S3_DN")
	)
	(segment
		(start 104.874822 -354.408486)
		(end 104.874822 -354.713794)
		(width 0.1143)
		(layer "B.Cu")
		(net "CLK_100M_DB800ZL_PEX2_S3_DN")
	)
	(segment
		(start 105.899712 -357.611172)
		(end 105.899712 -358.000808)
		(width 0.1143)
		(layer "B.Cu")
		(net "CLK_100M_DB800ZL_PEX2_S3_DN")
	)
	(segment
		(start 105.277412 -356.988872)
		(end 105.899712 -357.611172)
		(width 0.1143)
		(layer "B.Cu")
		(net "CLK_100M_DB800ZL_PEX2_S3_DN")
	)
	(segment
		(start 104.940608 -354.3427)
		(end 104.874822 -354.408486)
		(width 0.1143)
		(layer "B.Cu")
		(net "CLK_100M_DB800ZL_PEX2_S3_DN")
	)
	(segment
		(start 105.899712 -358.000808)
		(end 106.223562 -358.324658)
		(width 0.1143)
		(layer "B.Cu")
		(net "CLK_100M_DB800ZL_PEX2_S3_DN")
	)
	(segment
		(start 104.874822 -354.713794)
		(end 105.277412 -355.685852)
		(width 0.1143)
		(layer "B.Cu")
		(net "CLK_100M_DB800ZL_PEX2_S3_DN")
	)
	(segment
		(start 245.35511 -328.03211)
		(end 236.672374 -328.03211)
		(width 0.13208)
		(layer "F.Cu")
		(net "SMB_BMC_9FGL0451E_S3_SCL")
	)
	(segment
		(start 108.048552 -340.4108)
		(end 109.318552 -339.1408)
		(width 0.13208)
		(layer "F.Cu")
		(net "SMB_BMC_9FGL0451E_S3_SCL")
	)
	(segment
		(start 114.500152 -339.1408)
		(end 118.919752 -334.7212)
		(width 0.13208)
		(layer "F.Cu")
		(net "SMB_BMC_9FGL0451E_S3_SCL")
	)
	(segment
		(start 315.5188 -91.8718)
		(end 312.7756 -94.615)
		(width 0.13208)
		(layer "F.Cu")
		(net "SMB_BMC_9FGL0451E_S3_SCL")
	)
	(segment
		(start 242.828318 -195.6562)
		(end 245.0846 -197.912482)
		(width 0.13208)
		(layer "F.Cu")
		(net "SMB_BMC_9FGL0451E_S3_SCL")
	)
	(segment
		(start 244.0178 -204.5462)
		(end 244.0178 -208.3308)
		(width 0.13208)
		(layer "F.Cu")
		(net "SMB_BMC_9FGL0451E_S3_SCL")
	)
	(segment
		(start 101.656134 -347.873066)
		(end 105.5624 -343.9668)
		(width 0.13208)
		(layer "F.Cu")
		(net "SMB_BMC_9FGL0451E_S3_SCL")
	)
	(segment
		(start 245.0846 -203.4794)
		(end 244.0178 -204.5462)
		(width 0.13208)
		(layer "F.Cu")
		(net "SMB_BMC_9FGL0451E_S3_SCL")
	)
	(segment
		(start 252.08992 -257.383788)
		(end 252.489208 -257.783076)
		(width 0.13208)
		(layer "F.Cu")
		(net "SMB_BMC_9FGL0451E_S3_SCL")
	)
	(segment
		(start 257.248152 -302.0695)
		(end 251.726954 -307.590698)
		(width 0.13208)
		(layer "F.Cu")
		(net "SMB_BMC_9FGL0451E_S3_SCL")
	)
	(segment
		(start 252.489208 -257.783076)
		(end 252.489208 -258.990084)
		(width 0.13208)
		(layer "F.Cu")
		(net "SMB_BMC_9FGL0451E_S3_SCL")
	)
	(segment
		(start 253.346966 -261.217918)
		(end 253.346966 -275.631402)
		(width 0.13208)
		(layer "F.Cu")
		(net "SMB_BMC_9FGL0451E_S3_SCL")
	)
	(segment
		(start 244.8814 -211.5312)
		(end 245.28272 -211.93252)
		(width 0.13208)
		(layer "F.Cu")
		(net "SMB_BMC_9FGL0451E_S3_SCL")
	)
	(segment
		(start 324.01764 -88.12276)
		(end 320.2686 -91.8718)
		(width 0.13208)
		(layer "F.Cu")
		(net "SMB_BMC_9FGL0451E_S3_SCL")
	)
	(segment
		(start 245.28272 -217.962734)
		(end 244.260116 -218.985338)
		(width 0.13208)
		(layer "F.Cu")
		(net "SMB_BMC_9FGL0451E_S3_SCL")
	)
	(segment
		(start 105.5624 -343.9668)
		(end 105.5624 -341.0204)
		(width 0.13208)
		(layer "F.Cu")
		(net "SMB_BMC_9FGL0451E_S3_SCL")
	)
	(segment
		(start 252.79604 -260.666992)
		(end 253.346966 -261.217918)
		(width 0.13208)
		(layer "F.Cu")
		(net "SMB_BMC_9FGL0451E_S3_SCL")
	)
	(segment
		(start 251.959364 -249.063764)
		(end 251.959364 -257.06832)
		(width 0.13208)
		(layer "F.Cu")
		(net "SMB_BMC_9FGL0451E_S3_SCL")
	)
	(segment
		(start 310.3118 -94.615)
		(end 309.5752 -95.3516)
		(width 0.13208)
		(layer "F.Cu")
		(net "SMB_BMC_9FGL0451E_S3_SCL")
	)
	(segment
		(start 293.7764 -141.0716)
		(end 295.4782 -141.0716)
		(width 0.13208)
		(layer "F.Cu")
		(net "SMB_BMC_9FGL0451E_S3_SCL")
	)
	(segment
		(start 296.799 -105.3592)
		(end 291.5158 -110.6424)
		(width 0.13208)
		(layer "F.Cu")
		(net "SMB_BMC_9FGL0451E_S3_SCL")
	)
	(segment
		(start 222.1992 -331.3684)
		(end 221.6404 -330.8096)
		(width 0.13208)
		(layer "F.Cu")
		(net "SMB_BMC_9FGL0451E_S3_SCL")
	)
	(segment
		(start 248.8692 -245.9736)
		(end 251.959364 -249.063764)
		(width 0.13208)
		(layer "F.Cu")
		(net "SMB_BMC_9FGL0451E_S3_SCL")
	)
	(segment
		(start 244.260116 -218.985338)
		(end 244.260116 -228.882448)
		(width 0.13208)
		(layer "F.Cu")
		(net "SMB_BMC_9FGL0451E_S3_SCL")
	)
	(segment
		(start 251.726954 -307.590698)
		(end 251.726954 -318.827912)
		(width 0.13208)
		(layer "F.Cu")
		(net "SMB_BMC_9FGL0451E_S3_SCL")
	)
	(segment
		(start 236.672374 -328.03211)
		(end 233.336084 -331.3684)
		(width 0.13208)
		(layer "F.Cu")
		(net "SMB_BMC_9FGL0451E_S3_SCL")
	)
	(segment
		(start 99.627436 -347.873066)
		(end 101.656134 -347.873066)
		(width 0.13208)
		(layer "F.Cu")
		(net "SMB_BMC_9FGL0451E_S3_SCL")
	)
	(segment
		(start 309.5752 -95.3516)
		(end 309.5752 -103.3018)
		(width 0.13208)
		(layer "F.Cu")
		(net "SMB_BMC_9FGL0451E_S3_SCL")
	)
	(segment
		(start 320.2686 -91.8718)
		(end 315.5188 -91.8718)
		(width 0.13208)
		(layer "F.Cu")
		(net "SMB_BMC_9FGL0451E_S3_SCL")
	)
	(segment
		(start 295.4782 -141.0716)
		(end 296.0116 -140.5382)
		(width 0.13208)
		(layer "F.Cu")
		(net "SMB_BMC_9FGL0451E_S3_SCL")
	)
	(segment
		(start 233.336084 -331.3684)
		(end 222.1992 -331.3684)
		(width 0.13208)
		(layer "F.Cu")
		(net "SMB_BMC_9FGL0451E_S3_SCL")
	)
	(segment
		(start 309.5752 -103.3018)
		(end 307.5178 -105.3592)
		(width 0.13208)
		(layer "F.Cu")
		(net "SMB_BMC_9FGL0451E_S3_SCL")
	)
	(segment
		(start 251.959364 -257.06832)
		(end 252.08992 -257.383788)
		(width 0.13208)
		(layer "F.Cu")
		(net "SMB_BMC_9FGL0451E_S3_SCL")
	)
	(segment
		(start 118.919752 -334.7212)
		(end 121.6406 -334.7212)
		(width 0.13208)
		(layer "F.Cu")
		(net "SMB_BMC_9FGL0451E_S3_SCL")
	)
	(segment
		(start 324.01764 -87.82939)
		(end 324.01764 -88.12276)
		(width 0.13208)
		(layer "F.Cu")
		(net "SMB_BMC_9FGL0451E_S3_SCL")
	)
	(segment
		(start 291.5158 -110.6424)
		(end 291.5158 -138.811)
		(width 0.13208)
		(layer "F.Cu")
		(net "SMB_BMC_9FGL0451E_S3_SCL")
	)
	(segment
		(start 109.318552 -339.1408)
		(end 114.500152 -339.1408)
		(width 0.13208)
		(layer "F.Cu")
		(net "SMB_BMC_9FGL0451E_S3_SCL")
	)
	(segment
		(start 245.28272 -211.93252)
		(end 245.28272 -217.962734)
		(width 0.13208)
		(layer "F.Cu")
		(net "SMB_BMC_9FGL0451E_S3_SCL")
	)
	(segment
		(start 248.8692 -235.4326)
		(end 248.8692 -245.9736)
		(width 0.13208)
		(layer "F.Cu")
		(net "SMB_BMC_9FGL0451E_S3_SCL")
	)
	(segment
		(start 252.489208 -258.990084)
		(end 252.79604 -259.731002)
		(width 0.13208)
		(layer "F.Cu")
		(net "SMB_BMC_9FGL0451E_S3_SCL")
	)
	(segment
		(start 307.5178 -105.3592)
		(end 296.799 -105.3592)
		(width 0.13208)
		(layer "F.Cu")
		(net "SMB_BMC_9FGL0451E_S3_SCL")
	)
	(segment
		(start 221.6404 -330.8096)
		(end 221.6404 -330.411582)
		(width 0.13208)
		(layer "F.Cu")
		(net "SMB_BMC_9FGL0451E_S3_SCL")
	)
	(segment
		(start 243.997226 -229.145338)
		(end 243.997226 -230.560626)
		(width 0.13208)
		(layer "F.Cu")
		(net "SMB_BMC_9FGL0451E_S3_SCL")
	)
	(segment
		(start 257.248152 -279.532588)
		(end 257.248152 -302.0695)
		(width 0.13208)
		(layer "F.Cu")
		(net "SMB_BMC_9FGL0451E_S3_SCL")
	)
	(segment
		(start 291.5158 -138.811)
		(end 293.7764 -141.0716)
		(width 0.13208)
		(layer "F.Cu")
		(net "SMB_BMC_9FGL0451E_S3_SCL")
	)
	(segment
		(start 244.0178 -208.3308)
		(end 244.8814 -209.1944)
		(width 0.13208)
		(layer "F.Cu")
		(net "SMB_BMC_9FGL0451E_S3_SCL")
	)
	(segment
		(start 106.172 -340.4108)
		(end 108.048552 -340.4108)
		(width 0.13208)
		(layer "F.Cu")
		(net "SMB_BMC_9FGL0451E_S3_SCL")
	)
	(segment
		(start 245.0846 -197.912482)
		(end 245.0846 -203.4794)
		(width 0.13208)
		(layer "F.Cu")
		(net "SMB_BMC_9FGL0451E_S3_SCL")
	)
	(segment
		(start 249.724164 -323.663056)
		(end 245.35511 -328.03211)
		(width 0.13208)
		(layer "F.Cu")
		(net "SMB_BMC_9FGL0451E_S3_SCL")
	)
	(segment
		(start 312.7756 -94.615)
		(end 310.3118 -94.615)
		(width 0.13208)
		(layer "F.Cu")
		(net "SMB_BMC_9FGL0451E_S3_SCL")
	)
	(segment
		(start 243.997226 -230.560626)
		(end 248.8692 -235.4326)
		(width 0.13208)
		(layer "F.Cu")
		(net "SMB_BMC_9FGL0451E_S3_SCL")
	)
	(segment
		(start 244.8814 -209.1944)
		(end 244.8814 -211.5312)
		(width 0.13208)
		(layer "F.Cu")
		(net "SMB_BMC_9FGL0451E_S3_SCL")
	)
	(segment
		(start 252.79604 -259.731002)
		(end 252.79604 -260.666992)
		(width 0.13208)
		(layer "F.Cu")
		(net "SMB_BMC_9FGL0451E_S3_SCL")
	)
	(segment
		(start 105.5624 -341.0204)
		(end 106.172 -340.4108)
		(width 0.13208)
		(layer "F.Cu")
		(net "SMB_BMC_9FGL0451E_S3_SCL")
	)
	(segment
		(start 244.260116 -228.882448)
		(end 243.997226 -229.145338)
		(width 0.13208)
		(layer "F.Cu")
		(net "SMB_BMC_9FGL0451E_S3_SCL")
	)
	(segment
		(start 121.6406 -334.7212)
		(end 124.4854 -331.8764)
		(width 0.13208)
		(layer "F.Cu")
		(net "SMB_BMC_9FGL0451E_S3_SCL")
	)
	(segment
		(start 251.726954 -318.827912)
		(end 249.724164 -323.663056)
		(width 0.13208)
		(layer "F.Cu")
		(net "SMB_BMC_9FGL0451E_S3_SCL")
	)
	(segment
		(start 124.4854 -331.8764)
		(end 124.4854 -330.7334)
		(width 0.13208)
		(layer "F.Cu")
		(net "SMB_BMC_9FGL0451E_S3_SCL")
	)
	(segment
		(start 253.346966 -275.631402)
		(end 257.248152 -279.532588)
		(width 0.13208)
		(layer "F.Cu")
		(net "SMB_BMC_9FGL0451E_S3_SCL")
	)
	(via
		(at 242.828318 -195.6562)
		(size 0.508)
		(drill 0.254)
		(layers "F.Cu" "B.Cu")
		(net "SMB_BMC_9FGL0451E_S3_SCL")
	)
	(via
		(at 221.6404 -330.411582)
		(size 0.508)
		(drill 0.254)
		(layers "F.Cu" "B.Cu")
		(net "SMB_BMC_9FGL0451E_S3_SCL")
	)
	(via
		(at 232.6132 -159.9438)
		(size 0.508)
		(drill 0.254)
		(layers "F.Cu" "B.Cu")
		(net "SMB_BMC_9FGL0451E_S3_SCL")
	)
	(via
		(at 99.627436 -347.873066)
		(size 0.508)
		(drill 0.254)
		(layers "F.Cu" "B.Cu")
		(net "SMB_BMC_9FGL0451E_S3_SCL")
	)
	(via
		(at 296.0116 -140.5382)
		(size 0.508)
		(drill 0.254)
		(layers "F.Cu" "B.Cu")
		(net "SMB_BMC_9FGL0451E_S3_SCL")
	)
	(via
		(at 124.4854 -330.7334)
		(size 0.508)
		(drill 0.254)
		(layers "F.Cu" "B.Cu")
		(net "SMB_BMC_9FGL0451E_S3_SCL")
	)
	(segment
		(start 101.535992 -348.186502)
		(end 102.029768 -348.186502)
		(width 0.13208)
		(layer "B.Cu")
		(net "SMB_BMC_9FGL0451E_S3_SCL")
	)
	(segment
		(start 248.2342 -183.540654)
		(end 249.174 -184.480454)
		(width 0.13208)
		(layer "B.Cu")
		(net "SMB_BMC_9FGL0451E_S3_SCL")
	)
	(segment
		(start 243.031518 -195.8594)
		(end 242.828318 -195.6562)
		(width 0.13208)
		(layer "B.Cu")
		(net "SMB_BMC_9FGL0451E_S3_SCL")
	)
	(segment
		(start 249.174 -185.92673)
		(end 243.967 -191.13373)
		(width 0.13208)
		(layer "B.Cu")
		(net "SMB_BMC_9FGL0451E_S3_SCL")
	)
	(segment
		(start 243.967 -191.13373)
		(end 243.967 -195.2244)
		(width 0.13208)
		(layer "B.Cu")
		(net "SMB_BMC_9FGL0451E_S3_SCL")
	)
	(segment
		(start 248.2342 -179.83327)
		(end 248.2342 -183.540654)
		(width 0.13208)
		(layer "B.Cu")
		(net "SMB_BMC_9FGL0451E_S3_SCL")
	)
	(segment
		(start 249.174 -184.480454)
		(end 249.174 -185.92673)
		(width 0.13208)
		(layer "B.Cu")
		(net "SMB_BMC_9FGL0451E_S3_SCL")
	)
	(segment
		(start 102.029768 -348.186502)
		(end 102.44074 -348.597474)
		(width 0.13208)
		(layer "B.Cu")
		(net "SMB_BMC_9FGL0451E_S3_SCL")
	)
	(segment
		(start 221.623382 -330.4286)
		(end 124.7902 -330.4286)
		(width 0.13208)
		(layer "B.Cu")
		(net "SMB_BMC_9FGL0451E_S3_SCL")
	)
	(segment
		(start 243.967 -195.2244)
		(end 243.332 -195.8594)
		(width 0.13208)
		(layer "B.Cu")
		(net "SMB_BMC_9FGL0451E_S3_SCL")
	)
	(segment
		(start 243.332 -195.8594)
		(end 243.031518 -195.8594)
		(width 0.13208)
		(layer "B.Cu")
		(net "SMB_BMC_9FGL0451E_S3_SCL")
	)
	(segment
		(start 232.6132 -164.21227)
		(end 248.2342 -179.83327)
		(width 0.13208)
		(layer "B.Cu")
		(net "SMB_BMC_9FGL0451E_S3_SCL")
	)
	(segment
		(start 101.535992 -348.186502)
		(end 99.940872 -348.186502)
		(width 0.13208)
		(layer "B.Cu")
		(net "SMB_BMC_9FGL0451E_S3_SCL")
	)
	(segment
		(start 99.940872 -348.186502)
		(end 99.627436 -347.873066)
		(width 0.13208)
		(layer "B.Cu")
		(net "SMB_BMC_9FGL0451E_S3_SCL")
	)
	(segment
		(start 102.44074 -348.597474)
		(end 102.44074 -349.388684)
		(width 0.13208)
		(layer "B.Cu")
		(net "SMB_BMC_9FGL0451E_S3_SCL")
	)
	(segment
		(start 124.7902 -330.4286)
		(end 124.4854 -330.7334)
		(width 0.13208)
		(layer "B.Cu")
		(net "SMB_BMC_9FGL0451E_S3_SCL")
	)
	(segment
		(start 232.6132 -159.9438)
		(end 232.6132 -164.21227)
		(width 0.13208)
		(layer "B.Cu")
		(net "SMB_BMC_9FGL0451E_S3_SCL")
	)
	(segment
		(start 221.6404 -330.411582)
		(end 221.623382 -330.4286)
		(width 0.13208)
		(layer "B.Cu")
		(net "SMB_BMC_9FGL0451E_S3_SCL")
	)
	(segment
		(start 232.6132 -161.603944)
		(end 233.264456 -162.2552)
		(width 0.15494)
		(layer "In13.Cu")
		(net "SMB_BMC_9FGL0451E_S3_SCL")
	)
	(segment
		(start 254.352552 -157.6324)
		(end 259.229352 -157.6324)
		(width 0.15494)
		(layer "In13.Cu")
		(net "SMB_BMC_9FGL0451E_S3_SCL")
	)
	(segment
		(start 233.264456 -162.2552)
		(end 247.773952 -162.2552)
		(width 0.15494)
		(layer "In13.Cu")
		(net "SMB_BMC_9FGL0451E_S3_SCL")
	)
	(segment
		(start 253.031752 -158.9532)
		(end 254.352552 -157.6324)
		(width 0.15494)
		(layer "In13.Cu")
		(net "SMB_BMC_9FGL0451E_S3_SCL")
	)
	(segment
		(start 276.323552 -136.5758)
		(end 281.333448 -136.5758)
		(width 0.15494)
		(layer "In13.Cu")
		(net "SMB_BMC_9FGL0451E_S3_SCL")
	)
	(segment
		(start 259.229352 -157.6324)
		(end 267.589 -149.272752)
		(width 0.15494)
		(layer "In13.Cu")
		(net "SMB_BMC_9FGL0451E_S3_SCL")
	)
	(segment
		(start 232.6132 -159.9438)
		(end 232.6132 -161.603944)
		(width 0.15494)
		(layer "In13.Cu")
		(net "SMB_BMC_9FGL0451E_S3_SCL")
	)
	(segment
		(start 251.075952 -158.9532)
		(end 253.031752 -158.9532)
		(width 0.15494)
		(layer "In13.Cu")
		(net "SMB_BMC_9FGL0451E_S3_SCL")
	)
	(segment
		(start 281.333448 -136.5758)
		(end 283.187648 -138.43)
		(width 0.15494)
		(layer "In13.Cu")
		(net "SMB_BMC_9FGL0451E_S3_SCL")
	)
	(segment
		(start 269.389352 -138.9634)
		(end 273.935952 -138.9634)
		(width 0.15494)
		(layer "In13.Cu")
		(net "SMB_BMC_9FGL0451E_S3_SCL")
	)
	(segment
		(start 273.935952 -138.9634)
		(end 276.323552 -136.5758)
		(width 0.15494)
		(layer "In13.Cu")
		(net "SMB_BMC_9FGL0451E_S3_SCL")
	)
	(segment
		(start 283.187648 -138.43)
		(end 286.813752 -138.43)
		(width 0.15494)
		(layer "In13.Cu")
		(net "SMB_BMC_9FGL0451E_S3_SCL")
	)
	(segment
		(start 286.813752 -138.43)
		(end 288.693352 -136.5504)
		(width 0.15494)
		(layer "In13.Cu")
		(net "SMB_BMC_9FGL0451E_S3_SCL")
	)
	(segment
		(start 267.589 -140.763752)
		(end 269.389352 -138.9634)
		(width 0.15494)
		(layer "In13.Cu")
		(net "SMB_BMC_9FGL0451E_S3_SCL")
	)
	(segment
		(start 288.693352 -136.5504)
		(end 289.9664 -136.5504)
		(width 0.15494)
		(layer "In13.Cu")
		(net "SMB_BMC_9FGL0451E_S3_SCL")
	)
	(segment
		(start 267.589 -149.272752)
		(end 267.589 -140.763752)
		(width 0.15494)
		(layer "In13.Cu")
		(net "SMB_BMC_9FGL0451E_S3_SCL")
	)
	(segment
		(start 296.0116 -138.4808)
		(end 296.0116 -140.5382)
		(width 0.15494)
		(layer "In13.Cu")
		(net "SMB_BMC_9FGL0451E_S3_SCL")
	)
	(segment
		(start 290.2712 -136.8552)
		(end 294.386 -136.8552)
		(width 0.15494)
		(layer "In13.Cu")
		(net "SMB_BMC_9FGL0451E_S3_SCL")
	)
	(segment
		(start 247.773952 -162.2552)
		(end 251.075952 -158.9532)
		(width 0.15494)
		(layer "In13.Cu")
		(net "SMB_BMC_9FGL0451E_S3_SCL")
	)
	(segment
		(start 294.386 -136.8552)
		(end 296.0116 -138.4808)
		(width 0.15494)
		(layer "In13.Cu")
		(net "SMB_BMC_9FGL0451E_S3_SCL")
	)
	(segment
		(start 289.9664 -136.5504)
		(end 290.2712 -136.8552)
		(width 0.15494)
		(layer "In13.Cu")
		(net "SMB_BMC_9FGL0451E_S3_SCL")
	)
	(segment
		(start 98.986594 -352.441256)
		(end 101.049582 -352.441256)
		(width 0.1143)
		(layer "B.Cu")
		(net "CLK_100M_DB800ZL_PEX0_S3_DN")
	)
	(segment
		(start 98.692462 -352.735388)
		(end 98.986594 -352.441256)
		(width 0.1143)
		(layer "B.Cu")
		(net "CLK_100M_DB800ZL_PEX0_S3_DN")
	)
	(segment
		(start 101.121972 -352.513646)
		(end 101.315774 -352.513646)
		(width 0.1143)
		(layer "B.Cu")
		(net "CLK_100M_DB800ZL_PEX0_S3_DN")
	)
	(segment
		(start 101.049582 -352.441256)
		(end 101.121972 -352.513646)
		(width 0.1143)
		(layer "B.Cu")
		(net "CLK_100M_DB800ZL_PEX0_S3_DN")
	)
	(segment
		(start 104.909112 -355.759766)
		(end 104.909112 -357.14178)
		(width 0.1143)
		(layer "B.Cu")
		(net "CLK_100M_DB800ZL_PEX2_S3_DP")
	)
	(segment
		(start 105.531412 -358.000808)
		(end 105.207562 -358.324658)
		(width 0.1143)
		(layer "B.Cu")
		(net "CLK_100M_DB800ZL_PEX2_S3_DP")
	)
	(segment
		(start 105.531412 -357.76408)
		(end 105.531412 -358.000808)
		(width 0.1143)
		(layer "B.Cu")
		(net "CLK_100M_DB800ZL_PEX2_S3_DP")
	)
	(segment
		(start 104.909112 -357.14178)
		(end 105.531412 -357.76408)
		(width 0.1143)
		(layer "B.Cu")
		(net "CLK_100M_DB800ZL_PEX2_S3_DP")
	)
	(segment
		(start 104.506522 -354.399342)
		(end 104.506522 -354.787962)
		(width 0.1143)
		(layer "B.Cu")
		(net "CLK_100M_DB800ZL_PEX2_S3_DP")
	)
	(segment
		(start 104.506522 -354.787962)
		(end 104.909112 -355.759766)
		(width 0.1143)
		(layer "B.Cu")
		(net "CLK_100M_DB800ZL_PEX2_S3_DP")
	)
	(segment
		(start 104.440736 -354.333556)
		(end 104.506522 -354.399342)
		(width 0.1143)
		(layer "B.Cu")
		(net "CLK_100M_DB800ZL_PEX2_S3_DP")
	)
	(segment
		(start 104.440736 -354.138484)
		(end 104.440736 -354.333556)
		(width 0.1143)
		(layer "B.Cu")
		(net "CLK_100M_DB800ZL_PEX2_S3_DP")
	)
	(segment
		(start 106.243374 -352.01352)
		(end 106.30916 -352.079306)
		(width 0.1143)
		(layer "B.Cu")
		(net "CLK_100M_DB800ZL_PEX3_S3_DN")
	)
	(segment
		(start 106.30916 -352.079306)
		(end 108.860336 -352.079306)
		(width 0.1143)
		(layer "B.Cu")
		(net "CLK_100M_DB800ZL_PEX3_S3_DN")
	)
	(segment
		(start 106.065574 -352.01352)
		(end 106.243374 -352.01352)
		(width 0.1143)
		(layer "B.Cu")
		(net "CLK_100M_DB800ZL_PEX3_S3_DN")
	)
	(segment
		(start 108.860336 -352.079306)
		(end 109.143038 -351.796604)
		(width 0.1143)
		(layer "B.Cu")
		(net "CLK_100M_DB800ZL_PEX3_S3_DN")
	)
	(via
		(at 102.944676 -347.409008)
		(size 0.6604)
		(drill 0.3302)
		(layers "F.Cu" "B.Cu")
		(net "SMB_9ZXL0451E_S3_ADDR0")
	)
	(segment
		(start 102.987348 -347.45168)
		(end 103.440738 -348.546166)
		(width 0.13208)
		(layer "B.Cu")
		(net "SMB_9ZXL0451E_S3_ADDR0")
	)
	(segment
		(start 101.589586 -344.964004)
		(end 101.589586 -346.053918)
		(width 0.13208)
		(layer "B.Cu")
		(net "SMB_9ZXL0451E_S3_ADDR0")
	)
	(segment
		(start 101.589586 -346.053918)
		(end 102.944676 -347.409008)
		(width 0.13208)
		(layer "B.Cu")
		(net "SMB_9ZXL0451E_S3_ADDR0")
	)
	(segment
		(start 100.573586 -344.964004)
		(end 101.589586 -344.964004)
		(width 0.13208)
		(layer "B.Cu")
		(net "SMB_9ZXL0451E_S3_ADDR0")
	)
	(segment
		(start 102.944676 -347.409008)
		(end 102.987348 -347.45168)
		(width 0.13208)
		(layer "B.Cu")
		(net "SMB_9ZXL0451E_S3_ADDR0")
	)
	(segment
		(start 103.440738 -348.546166)
		(end 103.440738 -349.388684)
		(width 0.13208)
		(layer "B.Cu")
		(net "SMB_9ZXL0451E_S3_ADDR0")
	)
	(segment
		(start 104.440736 -349.245936)
		(end 104.327706 -349.132906)
		(width 0.13462)
		(layer "B.Cu")
		(net "CLK_100M_MB_1_R_DP")
	)
	(segment
		(start 104.327706 -348.2721)
		(end 103.377746 -345.97848)
		(width 0.13462)
		(layer "B.Cu")
		(net "CLK_100M_MB_1_R_DP")
	)
	(segment
		(start 104.440736 -349.388684)
		(end 104.440736 -349.245936)
		(width 0.13462)
		(layer "B.Cu")
		(net "CLK_100M_MB_1_R_DP")
	)
	(segment
		(start 103.377746 -345.97848)
		(end 103.377746 -345.334844)
		(width 0.13462)
		(layer "B.Cu")
		(net "CLK_100M_MB_1_R_DP")
	)
	(segment
		(start 104.327706 -349.132906)
		(end 104.327706 -348.2721)
		(width 0.13462)
		(layer "B.Cu")
		(net "CLK_100M_MB_1_R_DP")
	)
	(segment
		(start 103.377746 -345.334844)
		(end 103.748586 -344.964004)
		(width 0.13462)
		(layer "B.Cu")
		(net "CLK_100M_MB_1_R_DP")
	)
	(via
		(at 102.808786 -342.664288)
		(size 0.508)
		(drill 0.254)
		(layers "F.Cu" "B.Cu")
		(net "CLK_100M_MB_1_DN")
	)
	(segment
		(start 103.103426 -342.958928)
		(end 102.808786 -342.664288)
		(width 0.13462)
		(layer "B.Cu")
		(net "CLK_100M_MB_1_DN")
	)
	(segment
		(start 102.732586 -344.163904)
		(end 103.103426 -343.793064)
		(width 0.13462)
		(layer "B.Cu")
		(net "CLK_100M_MB_1_DN")
	)
	(segment
		(start 103.103426 -343.793064)
		(end 103.103426 -342.958928)
		(width 0.13462)
		(layer "B.Cu")
		(net "CLK_100M_MB_1_DN")
	)
	(segment
		(start 91.710002 -384.22453)
		(end 91.710002 -384.590036)
		(width 0.1651)
		(layer "In5.Cu")
		(net "CLK_100M_MB_1_DN")
	)
	(segment
		(start 104.922574 -342.254586)
		(end 104.922574 -343.678002)
		(width 0.1651)
		(layer "In5.Cu")
		(net "CLK_100M_MB_1_DN")
	)
	(segment
		(start 98.0694 -360.139996)
		(end 95.199454 -364.434628)
		(width 0.1651)
		(layer "In5.Cu")
		(net "CLK_100M_MB_1_DN")
	)
	(segment
		(start 99.5934 -344.932)
		(end 98.0694 -346.456)
		(width 0.1651)
		(layer "In5.Cu")
		(net "CLK_100M_MB_1_DN")
	)
	(segment
		(start 102.808786 -342.664288)
		(end 103.0986 -342.374474)
		(width 0.1651)
		(layer "In5.Cu")
		(net "CLK_100M_MB_1_DN")
	)
	(segment
		(start 95.199454 -364.434628)
		(end 93.1926 -369.279678)
		(width 0.1651)
		(layer "In5.Cu")
		(net "CLK_100M_MB_1_DN")
	)
	(segment
		(start 98.0694 -346.456)
		(end 98.0694 -360.139996)
		(width 0.1651)
		(layer "In5.Cu")
		(net "CLK_100M_MB_1_DN")
	)
	(segment
		(start 103.0986 -342.0364)
		(end 103.45674 -341.67826)
		(width 0.1651)
		(layer "In5.Cu")
		(net "CLK_100M_MB_1_DN")
	)
	(segment
		(start 103.45674 -341.67826)
		(end 104.346248 -341.67826)
		(width 0.1651)
		(layer "In5.Cu")
		(net "CLK_100M_MB_1_DN")
	)
	(segment
		(start 93.1926 -369.279678)
		(end 93.1926 -383.285746)
		(width 0.1651)
		(layer "In5.Cu")
		(net "CLK_100M_MB_1_DN")
	)
	(segment
		(start 91.849702 -384.08483)
		(end 91.710002 -384.22453)
		(width 0.1651)
		(layer "In5.Cu")
		(net "CLK_100M_MB_1_DN")
	)
	(segment
		(start 104.922574 -343.678002)
		(end 103.668576 -344.932)
		(width 0.1651)
		(layer "In5.Cu")
		(net "CLK_100M_MB_1_DN")
	)
	(segment
		(start 104.346248 -341.67826)
		(end 104.922574 -342.254586)
		(width 0.1651)
		(layer "In5.Cu")
		(net "CLK_100M_MB_1_DN")
	)
	(segment
		(start 93.1926 -383.285746)
		(end 92.393516 -384.08483)
		(width 0.1651)
		(layer "In5.Cu")
		(net "CLK_100M_MB_1_DN")
	)
	(segment
		(start 103.0986 -342.374474)
		(end 103.0986 -342.0364)
		(width 0.1651)
		(layer "In5.Cu")
		(net "CLK_100M_MB_1_DN")
	)
	(segment
		(start 103.668576 -344.932)
		(end 99.5934 -344.932)
		(width 0.1651)
		(layer "In5.Cu")
		(net "CLK_100M_MB_1_DN")
	)
	(segment
		(start 92.393516 -384.08483)
		(end 91.849702 -384.08483)
		(width 0.1651)
		(layer "In5.Cu")
		(net "CLK_100M_MB_1_DN")
	)
	(segment
		(start 103.103426 -345.334844)
		(end 103.103426 -346.03309)
		(width 0.13462)
		(layer "B.Cu")
		(net "CLK_100M_MB_1_R_DN")
	)
	(segment
		(start 103.94061 -349.245682)
		(end 103.94061 -349.388684)
		(width 0.13462)
		(layer "B.Cu")
		(net "CLK_100M_MB_1_R_DN")
	)
	(segment
		(start 104.053386 -348.32671)
		(end 104.053386 -349.132906)
		(width 0.13462)
		(layer "B.Cu")
		(net "CLK_100M_MB_1_R_DN")
	)
	(segment
		(start 104.053386 -349.132906)
		(end 103.94061 -349.245682)
		(width 0.13462)
		(layer "B.Cu")
		(net "CLK_100M_MB_1_R_DN")
	)
	(segment
		(start 102.732586 -344.964004)
		(end 103.103426 -345.334844)
		(width 0.13462)
		(layer "B.Cu")
		(net "CLK_100M_MB_1_R_DN")
	)
	(segment
		(start 103.103426 -346.03309)
		(end 104.053386 -348.32671)
		(width 0.13462)
		(layer "B.Cu")
		(net "CLK_100M_MB_1_R_DN")
	)
	(via
		(at 107.41025 -346.025216)
		(size 0.6604)
		(drill 0.3302)
		(layers "F.Cu" "B.Cu")
		(net "PU_9ZXL0451E_S3_HBW")
	)
	(segment
		(start 107.41025 -346.62999)
		(end 107.41025 -346.025216)
		(width 0.13208)
		(layer "B.Cu")
		(net "PU_9ZXL0451E_S3_HBW")
	)
	(segment
		(start 107.221782 -346.818458)
		(end 107.41025 -346.62999)
		(width 0.13208)
		(layer "B.Cu")
		(net "PU_9ZXL0451E_S3_HBW")
	)
	(segment
		(start 106.710988 -349.886524)
		(end 106.710988 -348.737682)
		(width 0.13208)
		(layer "B.Cu")
		(net "PU_9ZXL0451E_S3_HBW")
	)
	(segment
		(start 107.221782 -348.226888)
		(end 107.221782 -347.210888)
		(width 0.13208)
		(layer "B.Cu")
		(net "PU_9ZXL0451E_S3_HBW")
	)
	(segment
		(start 106.710988 -348.737682)
		(end 107.221782 -348.226888)
		(width 0.13208)
		(layer "B.Cu")
		(net "PU_9ZXL0451E_S3_HBW")
	)
	(segment
		(start 106.583988 -350.013524)
		(end 106.710988 -349.886524)
		(width 0.13208)
		(layer "B.Cu")
		(net "PU_9ZXL0451E_S3_HBW")
	)
	(segment
		(start 106.065574 -350.013524)
		(end 106.583988 -350.013524)
		(width 0.13208)
		(layer "B.Cu")
		(net "PU_9ZXL0451E_S3_HBW")
	)
	(segment
		(start 107.221782 -347.210888)
		(end 107.221782 -346.818458)
		(width 0.13208)
		(layer "B.Cu")
		(net "PU_9ZXL0451E_S3_HBW")
	)
	(via
		(at 103.672386 -342.664288)
		(size 0.508)
		(drill 0.254)
		(layers "F.Cu" "B.Cu")
		(net "CLK_100M_MB_1_DP")
	)
	(segment
		(start 103.672386 -342.664288)
		(end 103.377746 -342.958928)
		(width 0.13462)
		(layer "B.Cu")
		(net "CLK_100M_MB_1_DP")
	)
	(segment
		(start 103.377746 -342.958928)
		(end 103.377746 -343.793064)
		(width 0.13462)
		(layer "B.Cu")
		(net "CLK_100M_MB_1_DP")
	)
	(segment
		(start 103.377746 -343.793064)
		(end 103.748586 -344.163904)
		(width 0.13462)
		(layer "B.Cu")
		(net "CLK_100M_MB_1_DP")
	)
	(segment
		(start 97.78746 -360.054398)
		(end 94.949518 -364.301024)
		(width 0.1651)
		(layer "In5.Cu")
		(net "CLK_100M_MB_1_DP")
	)
	(segment
		(start 104.229408 -341.9602)
		(end 104.640634 -342.371426)
		(width 0.1651)
		(layer "In5.Cu")
		(net "CLK_100M_MB_1_DP")
	)
	(segment
		(start 103.38054 -342.15324)
		(end 103.57358 -341.9602)
		(width 0.1651)
		(layer "In5.Cu")
		(net "CLK_100M_MB_1_DP")
	)
	(segment
		(start 100.097336 -344.5383)
		(end 99.985576 -344.65006)
		(width 0.1651)
		(layer "In5.Cu")
		(net "CLK_100M_MB_1_DP")
	)
	(segment
		(start 94.46006 -365.482886)
		(end 94.275402 -365.928656)
		(width 0.1651)
		(layer "In5.Cu")
		(net "CLK_100M_MB_1_DP")
	)
	(segment
		(start 97.78746 -357.194358)
		(end 97.78746 -357.676958)
		(width 0.1651)
		(layer "In5.Cu")
		(net "CLK_100M_MB_1_DP")
	)
	(segment
		(start 97.78746 -352.922078)
		(end 97.6757 -353.033838)
		(width 0.1651)
		(layer "In5.Cu")
		(net "CLK_100M_MB_1_DP")
	)
	(segment
		(start 97.6757 -357.788718)
		(end 97.6757 -358.271318)
		(width 0.1651)
		(layer "In5.Cu")
		(net "CLK_100M_MB_1_DP")
	)
	(segment
		(start 91.710002 -383.65557)
		(end 91.710002 -383.290064)
		(width 0.1651)
		(layer "In5.Cu")
		(net "CLK_100M_MB_1_DP")
	)
	(segment
		(start 94.275402 -365.928656)
		(end 94.129352 -365.989108)
		(width 0.1651)
		(layer "In5.Cu")
		(net "CLK_100M_MB_1_DP")
	)
	(segment
		(start 97.78746 -346.33916)
		(end 97.78746 -352.922078)
		(width 0.1651)
		(layer "In5.Cu")
		(net "CLK_100M_MB_1_DP")
	)
	(segment
		(start 99.135438 -344.991182)
		(end 98.97745 -344.991182)
		(width 0.1651)
		(layer "In5.Cu")
		(net "CLK_100M_MB_1_DP")
	)
	(segment
		(start 93.219524 -368.1857)
		(end 93.034612 -368.631724)
		(width 0.1651)
		(layer "In5.Cu")
		(net "CLK_100M_MB_1_DP")
	)
	(segment
		(start 97.6757 -359.460038)
		(end 97.78746 -359.571798)
		(width 0.1651)
		(layer "In5.Cu")
		(net "CLK_100M_MB_1_DP")
	)
	(segment
		(start 98.63582 -345.332812)
		(end 98.63582 -345.4908)
		(width 0.1651)
		(layer "In5.Cu")
		(net "CLK_100M_MB_1_DP")
	)
	(segment
		(start 104.640634 -343.561162)
		(end 103.551736 -344.65006)
		(width 0.1651)
		(layer "In5.Cu")
		(net "CLK_100M_MB_1_DP")
	)
	(segment
		(start 97.6757 -355.411278)
		(end 97.6757 -355.893878)
		(width 0.1651)
		(layer "In5.Cu")
		(net "CLK_100M_MB_1_DP")
	)
	(segment
		(start 97.78746 -355.299518)
		(end 97.6757 -355.411278)
		(width 0.1651)
		(layer "In5.Cu")
		(net "CLK_100M_MB_1_DP")
	)
	(segment
		(start 97.78746 -359.571798)
		(end 97.78746 -360.054398)
		(width 0.1651)
		(layer "In5.Cu")
		(net "CLK_100M_MB_1_DP")
	)
	(segment
		(start 94.005146 -366.581182)
		(end 93.820488 -367.026952)
		(width 0.1651)
		(layer "In5.Cu")
		(net "CLK_100M_MB_1_DP")
	)
	(segment
		(start 93.820488 -367.026952)
		(end 93.674438 -367.087404)
		(width 0.1651)
		(layer "In5.Cu")
		(net "CLK_100M_MB_1_DP")
	)
	(segment
		(start 97.6757 -358.271318)
		(end 97.78746 -358.383078)
		(width 0.1651)
		(layer "In5.Cu")
		(net "CLK_100M_MB_1_DP")
	)
	(segment
		(start 91.857322 -383.80289)
		(end 91.710002 -383.65557)
		(width 0.1651)
		(layer "In5.Cu")
		(net "CLK_100M_MB_1_DP")
	)
	(segment
		(start 97.78746 -357.676958)
		(end 97.6757 -357.788718)
		(width 0.1651)
		(layer "In5.Cu")
		(net "CLK_100M_MB_1_DP")
	)
	(segment
		(start 97.6757 -355.893878)
		(end 97.78746 -356.005638)
		(width 0.1651)
		(layer "In5.Cu")
		(net "CLK_100M_MB_1_DP")
	)
	(segment
		(start 103.38054 -342.372442)
		(end 103.38054 -342.15324)
		(width 0.1651)
		(layer "In5.Cu")
		(net "CLK_100M_MB_1_DP")
	)
	(segment
		(start 99.47656 -344.65006)
		(end 99.135438 -344.991182)
		(width 0.1651)
		(layer "In5.Cu")
		(net "CLK_100M_MB_1_DP")
	)
	(segment
		(start 102.363016 -344.65006)
		(end 101.880416 -344.65006)
		(width 0.1651)
		(layer "In5.Cu")
		(net "CLK_100M_MB_1_DP")
	)
	(segment
		(start 93.095318 -368.777774)
		(end 92.91066 -369.223544)
		(width 0.1651)
		(layer "In5.Cu")
		(net "CLK_100M_MB_1_DP")
	)
	(segment
		(start 103.551736 -344.65006)
		(end 103.069136 -344.65006)
		(width 0.1651)
		(layer "In5.Cu")
		(net "CLK_100M_MB_1_DP")
	)
	(segment
		(start 94.129352 -365.989108)
		(end 93.94444 -366.435132)
		(width 0.1651)
		(layer "In5.Cu")
		(net "CLK_100M_MB_1_DP")
	)
	(segment
		(start 97.78746 -358.865678)
		(end 97.6757 -358.977438)
		(width 0.1651)
		(layer "In5.Cu")
		(net "CLK_100M_MB_1_DP")
	)
	(segment
		(start 98.63582 -345.4908)
		(end 97.78746 -346.33916)
		(width 0.1651)
		(layer "In5.Cu")
		(net "CLK_100M_MB_1_DP")
	)
	(segment
		(start 97.6757 -353.033838)
		(end 97.6757 -353.516438)
		(width 0.1651)
		(layer "In5.Cu")
		(net "CLK_100M_MB_1_DP")
	)
	(segment
		(start 94.949518 -364.301024)
		(end 94.730316 -364.83036)
		(width 0.1651)
		(layer "In5.Cu")
		(net "CLK_100M_MB_1_DP")
	)
	(segment
		(start 94.730316 -364.83036)
		(end 94.584012 -364.890812)
		(width 0.1651)
		(layer "In5.Cu")
		(net "CLK_100M_MB_1_DP")
	)
	(segment
		(start 97.6757 -357.082598)
		(end 97.78746 -357.194358)
		(width 0.1651)
		(layer "In5.Cu")
		(net "CLK_100M_MB_1_DP")
	)
	(segment
		(start 100.579936 -344.5383)
		(end 100.097336 -344.5383)
		(width 0.1651)
		(layer "In5.Cu")
		(net "CLK_100M_MB_1_DP")
	)
	(segment
		(start 92.91066 -383.168906)
		(end 92.276676 -383.80289)
		(width 0.1651)
		(layer "In5.Cu")
		(net "CLK_100M_MB_1_DP")
	)
	(segment
		(start 93.94444 -366.435132)
		(end 94.005146 -366.581182)
		(width 0.1651)
		(layer "In5.Cu")
		(net "CLK_100M_MB_1_DP")
	)
	(segment
		(start 97.6757 -354.705158)
		(end 97.78746 -354.816918)
		(width 0.1651)
		(layer "In5.Cu")
		(net "CLK_100M_MB_1_DP")
	)
	(segment
		(start 97.6757 -354.222558)
		(end 97.6757 -354.705158)
		(width 0.1651)
		(layer "In5.Cu")
		(net "CLK_100M_MB_1_DP")
	)
	(segment
		(start 97.78746 -353.628198)
		(end 97.78746 -354.110798)
		(width 0.1651)
		(layer "In5.Cu")
		(net "CLK_100M_MB_1_DP")
	)
	(segment
		(start 94.399354 -365.336836)
		(end 94.46006 -365.482886)
		(width 0.1651)
		(layer "In5.Cu")
		(net "CLK_100M_MB_1_DP")
	)
	(segment
		(start 97.78746 -356.005638)
		(end 97.78746 -356.488238)
		(width 0.1651)
		(layer "In5.Cu")
		(net "CLK_100M_MB_1_DP")
	)
	(segment
		(start 94.584012 -364.890812)
		(end 94.399354 -365.336836)
		(width 0.1651)
		(layer "In5.Cu")
		(net "CLK_100M_MB_1_DP")
	)
	(segment
		(start 103.57358 -341.9602)
		(end 104.229408 -341.9602)
		(width 0.1651)
		(layer "In5.Cu")
		(net "CLK_100M_MB_1_DP")
	)
	(segment
		(start 93.034612 -368.631724)
		(end 93.095318 -368.777774)
		(width 0.1651)
		(layer "In5.Cu")
		(net "CLK_100M_MB_1_DP")
	)
	(segment
		(start 93.365574 -368.125248)
		(end 93.219524 -368.1857)
		(width 0.1651)
		(layer "In5.Cu")
		(net "CLK_100M_MB_1_DP")
	)
	(segment
		(start 101.880416 -344.65006)
		(end 101.768656 -344.5383)
		(width 0.1651)
		(layer "In5.Cu")
		(net "CLK_100M_MB_1_DP")
	)
	(segment
		(start 103.069136 -344.65006)
		(end 102.957376 -344.5383)
		(width 0.1651)
		(layer "In5.Cu")
		(net "CLK_100M_MB_1_DP")
	)
	(segment
		(start 93.489526 -367.533428)
		(end 93.550232 -367.679478)
		(width 0.1651)
		(layer "In5.Cu")
		(net "CLK_100M_MB_1_DP")
	)
	(segment
		(start 92.276676 -383.80289)
		(end 91.857322 -383.80289)
		(width 0.1651)
		(layer "In5.Cu")
		(net "CLK_100M_MB_1_DP")
	)
	(segment
		(start 97.78746 -354.110798)
		(end 97.6757 -354.222558)
		(width 0.1651)
		(layer "In5.Cu")
		(net "CLK_100M_MB_1_DP")
	)
	(segment
		(start 97.78746 -356.488238)
		(end 97.6757 -356.599998)
		(width 0.1651)
		(layer "In5.Cu")
		(net "CLK_100M_MB_1_DP")
	)
	(segment
		(start 98.97745 -344.991182)
		(end 98.63582 -345.332812)
		(width 0.1651)
		(layer "In5.Cu")
		(net "CLK_100M_MB_1_DP")
	)
	(segment
		(start 104.640634 -342.371426)
		(end 104.640634 -343.561162)
		(width 0.1651)
		(layer "In5.Cu")
		(net "CLK_100M_MB_1_DP")
	)
	(segment
		(start 101.768656 -344.5383)
		(end 101.286056 -344.5383)
		(width 0.1651)
		(layer "In5.Cu")
		(net "CLK_100M_MB_1_DP")
	)
	(segment
		(start 97.6757 -358.977438)
		(end 97.6757 -359.460038)
		(width 0.1651)
		(layer "In5.Cu")
		(net "CLK_100M_MB_1_DP")
	)
	(segment
		(start 102.957376 -344.5383)
		(end 102.474776 -344.5383)
		(width 0.1651)
		(layer "In5.Cu")
		(net "CLK_100M_MB_1_DP")
	)
	(segment
		(start 99.985576 -344.65006)
		(end 99.47656 -344.65006)
		(width 0.1651)
		(layer "In5.Cu")
		(net "CLK_100M_MB_1_DP")
	)
	(segment
		(start 97.78746 -354.816918)
		(end 97.78746 -355.299518)
		(width 0.1651)
		(layer "In5.Cu")
		(net "CLK_100M_MB_1_DP")
	)
	(segment
		(start 93.674438 -367.087404)
		(end 93.489526 -367.533428)
		(width 0.1651)
		(layer "In5.Cu")
		(net "CLK_100M_MB_1_DP")
	)
	(segment
		(start 101.174296 -344.65006)
		(end 100.691696 -344.65006)
		(width 0.1651)
		(layer "In5.Cu")
		(net "CLK_100M_MB_1_DP")
	)
	(segment
		(start 93.550232 -367.679478)
		(end 93.365574 -368.125248)
		(width 0.1651)
		(layer "In5.Cu")
		(net "CLK_100M_MB_1_DP")
	)
	(segment
		(start 92.91066 -369.223544)
		(end 92.91066 -383.168906)
		(width 0.1651)
		(layer "In5.Cu")
		(net "CLK_100M_MB_1_DP")
	)
	(segment
		(start 103.672386 -342.664288)
		(end 103.38054 -342.372442)
		(width 0.1651)
		(layer "In5.Cu")
		(net "CLK_100M_MB_1_DP")
	)
	(segment
		(start 97.78746 -358.383078)
		(end 97.78746 -358.865678)
		(width 0.1651)
		(layer "In5.Cu")
		(net "CLK_100M_MB_1_DP")
	)
	(segment
		(start 100.691696 -344.65006)
		(end 100.579936 -344.5383)
		(width 0.1651)
		(layer "In5.Cu")
		(net "CLK_100M_MB_1_DP")
	)
	(segment
		(start 101.286056 -344.5383)
		(end 101.174296 -344.65006)
		(width 0.1651)
		(layer "In5.Cu")
		(net "CLK_100M_MB_1_DP")
	)
	(segment
		(start 102.474776 -344.5383)
		(end 102.363016 -344.65006)
		(width 0.1651)
		(layer "In5.Cu")
		(net "CLK_100M_MB_1_DP")
	)
	(segment
		(start 97.6757 -353.516438)
		(end 97.78746 -353.628198)
		(width 0.1651)
		(layer "In5.Cu")
		(net "CLK_100M_MB_1_DP")
	)
	(segment
		(start 97.6757 -356.599998)
		(end 97.6757 -357.082598)
		(width 0.1651)
		(layer "In5.Cu")
		(net "CLK_100M_MB_1_DP")
	)
	(segment
		(start 317.735712 -291.22497)
		(end 317.735712 -290.278312)
		(width 0.13208)
		(layer "F.Cu")
		(net "RST_PEX2_S0_PERST_N")
	)
	(segment
		(start 318.737742 -291.9984)
		(end 318.509142 -291.9984)
		(width 0.13208)
		(layer "F.Cu")
		(net "RST_PEX2_S0_PERST_N")
	)
	(segment
		(start 317.735712 -290.278312)
		(end 317.735712 -289.630866)
		(width 0.13208)
		(layer "F.Cu")
		(net "RST_PEX2_S0_PERST_N")
	)
	(segment
		(start 318.881506 -292.142164)
		(end 318.737742 -291.9984)
		(width 0.13208)
		(layer "F.Cu")
		(net "RST_PEX2_S0_PERST_N")
	)
	(segment
		(start 318.509142 -291.9984)
		(end 317.735712 -291.22497)
		(width 0.13208)
		(layer "F.Cu")
		(net "RST_PEX2_S0_PERST_N")
	)
	(segment
		(start 318.881506 -292.923468)
		(end 318.881506 -292.142164)
		(width 0.13208)
		(layer "F.Cu")
		(net "RST_PEX2_S0_PERST_N")
	)
	(via
		(at 317.735712 -290.278312)
		(size 0.508)
		(drill 0.254)
		(layers "F.Cu" "B.Cu")
		(net "RST_PEX2_S0_PERST_N")
	)
	(segment
		(start 319.9892 -300.162976)
		(end 319.949576 -300.2026)
		(width 0.13208)
		(layer "F.Cu")
		(net "RST_PEX2_S1_PERST_N")
	)
	(segment
		(start 320.181732 -296.623232)
		(end 320.181732 -298.11218)
		(width 0.13208)
		(layer "F.Cu")
		(net "RST_PEX2_S1_PERST_N")
	)
	(segment
		(start 319.989708 -298.304204)
		(end 319.9892 -298.304712)
		(width 0.13208)
		(layer "F.Cu")
		(net "RST_PEX2_S1_PERST_N")
	)
	(segment
		(start 319.9892 -298.304712)
		(end 319.9892 -300.162976)
		(width 0.13208)
		(layer "F.Cu")
		(net "RST_PEX2_S1_PERST_N")
	)
	(segment
		(start 320.181732 -298.11218)
		(end 319.989708 -298.304204)
		(width 0.13208)
		(layer "F.Cu")
		(net "RST_PEX2_S1_PERST_N")
	)
	(via
		(at 319.989708 -298.304204)
		(size 0.762)
		(drill 0.381)
		(layers "F.Cu" "B.Cu")
		(net "RST_PEX2_S1_PERST_N")
	)
	(via
		(at 110.062772 -344.848434)
		(size 0.6604)
		(drill 0.3302)
		(layers "F.Cu" "B.Cu")
		(net "P3V3_CLK_BUFFER_9ZXL0451E_S3_VZX3P3A")
	)
	(via
		(at 108.733336 -350.194372)
		(size 0.6604)
		(drill 0.3302)
		(layers "F.Cu" "B.Cu")
		(net "P3V3_CLK_BUFFER_9ZXL0451E_S3_VZX3P3A")
	)
	(via
		(at 109.506258 -346.761562)
		(size 0.6604)
		(drill 0.3302)
		(layers "F.Cu" "B.Cu")
		(net "P3V3_CLK_BUFFER_9ZXL0451E_S3_VZX3P3A")
	)
	(via
		(at 108.181648 -344.713814)
		(size 0.508)
		(drill 0.254)
		(layers "F.Cu" "B.Cu")
		(net "P3V3_CLK_BUFFER_9ZXL0451E_S3_VZX3P3A")
	)
	(via
		(at 106.32694 -348.38386)
		(size 0.508)
		(drill 0.254)
		(layers "F.Cu" "B.Cu")
		(net "P3V3_CLK_BUFFER_9ZXL0451E_S3_VZX3P3A")
	)
	(via
		(at 108.16717 -345.56573)
		(size 0.508)
		(drill 0.254)
		(layers "F.Cu" "B.Cu")
		(net "P3V3_CLK_BUFFER_9ZXL0451E_S3_VZX3P3A")
	)
	(segment
		(start 105.99547 -347.537786)
		(end 106.32694 -347.869256)
		(width 0.381)
		(layer "B.Cu")
		(net "P3V3_CLK_BUFFER_9ZXL0451E_S3_VZX3P3A")
	)
	(segment
		(start 104.940608 -347.619828)
		(end 104.940608 -349.388684)
		(width 0.254)
		(layer "B.Cu")
		(net "P3V3_CLK_BUFFER_9ZXL0451E_S3_VZX3P3A")
	)
	(segment
		(start 105.98277 -347.525086)
		(end 104.845866 -347.525086)
		(width 0.254)
		(layer "B.Cu")
		(net "P3V3_CLK_BUFFER_9ZXL0451E_S3_VZX3P3A")
	)
	(segment
		(start 106.065574 -350.51365)
		(end 107.364276 -350.51365)
		(width 0.254)
		(layer "B.Cu")
		(net "P3V3_CLK_BUFFER_9ZXL0451E_S3_VZX3P3A")
	)
	(segment
		(start 107.573318 -350.304608)
		(end 108.6231 -350.304608)
		(width 0.508)
		(layer "B.Cu")
		(net "P3V3_CLK_BUFFER_9ZXL0451E_S3_VZX3P3A")
	)
	(segment
		(start 105.99547 -347.537786)
		(end 105.98277 -347.525086)
		(width 0.254)
		(layer "B.Cu")
		(net "P3V3_CLK_BUFFER_9ZXL0451E_S3_VZX3P3A")
	)
	(segment
		(start 106.32694 -347.869256)
		(end 106.32694 -348.38386)
		(width 0.381)
		(layer "B.Cu")
		(net "P3V3_CLK_BUFFER_9ZXL0451E_S3_VZX3P3A")
	)
	(segment
		(start 107.364276 -350.51365)
		(end 107.573318 -350.304608)
		(width 0.254)
		(layer "B.Cu")
		(net "P3V3_CLK_BUFFER_9ZXL0451E_S3_VZX3P3A")
	)
	(segment
		(start 104.845866 -347.525086)
		(end 104.940608 -347.619828)
		(width 0.254)
		(layer "B.Cu")
		(net "P3V3_CLK_BUFFER_9ZXL0451E_S3_VZX3P3A")
	)
	(segment
		(start 108.6231 -350.304608)
		(end 108.733336 -350.194372)
		(width 0.508)
		(layer "B.Cu")
		(net "P3V3_CLK_BUFFER_9ZXL0451E_S3_VZX3P3A")
	)
	(segment
		(start 318.881506 -297.805094)
		(end 318.516 -298.1706)
		(width 0.13208)
		(layer "F.Cu")
		(net "RST_PEX2_S3_PERST_N")
	)
	(segment
		(start 318.516 -298.1706)
		(end 318.516 -299.806868)
		(width 0.13208)
		(layer "F.Cu")
		(net "RST_PEX2_S3_PERST_N")
	)
	(segment
		(start 318.881506 -296.623232)
		(end 318.881506 -297.690032)
		(width 0.13208)
		(layer "F.Cu")
		(net "RST_PEX2_S3_PERST_N")
	)
	(segment
		(start 318.516 -299.806868)
		(end 318.929512 -300.22038)
		(width 0.13208)
		(layer "F.Cu")
		(net "RST_PEX2_S3_PERST_N")
	)
	(segment
		(start 318.881506 -297.690032)
		(end 318.881506 -297.805094)
		(width 0.13208)
		(layer "F.Cu")
		(net "RST_PEX2_S3_PERST_N")
	)
	(via
		(at 318.881506 -297.690032)
		(size 0.508)
		(drill 0.254)
		(layers "F.Cu" "B.Cu")
		(net "RST_PEX2_S3_PERST_N")
	)
	(via
		(at 103.828342 -355.513386)
		(size 0.6604)
		(drill 0.3302)
		(layers "F.Cu" "B.Cu")
		(net "P3V3_CLK_BUFFER_9ZXL0451E_S3_VZX3P3")
	)
	(via
		(at 107.4928 -354.965)
		(size 0.508)
		(drill 0.254)
		(layers "F.Cu" "B.Cu")
		(net "P3V3_CLK_BUFFER_9ZXL0451E_S3_VZX3P3")
	)
	(via
		(at 100.358448 -354.50526)
		(size 0.508)
		(drill 0.254)
		(layers "F.Cu" "B.Cu")
		(net "P3V3_CLK_BUFFER_9ZXL0451E_S3_VZX3P3")
	)
	(via
		(at 106.28122 -354.136198)
		(size 0.508)
		(drill 0.254)
		(layers "F.Cu" "B.Cu")
		(net "P3V3_CLK_BUFFER_9ZXL0451E_S3_VZX3P3")
	)
	(via
		(at 106.841544 -351.513648)
		(size 0.508)
		(drill 0.254)
		(layers "F.Cu" "B.Cu")
		(net "P3V3_CLK_BUFFER_9ZXL0451E_S3_VZX3P3")
	)
	(via
		(at 107.373166 -355.72446)
		(size 0.508)
		(drill 0.254)
		(layers "F.Cu" "B.Cu")
		(net "P3V3_CLK_BUFFER_9ZXL0451E_S3_VZX3P3")
	)
	(via
		(at 105.99547 -344.197432)
		(size 0.6604)
		(drill 0.3302)
		(layers "F.Cu" "B.Cu")
		(net "P3V3_CLK_BUFFER_9ZXL0451E_S3_VZX3P3")
	)
	(via
		(at 104.183688 -356.221284)
		(size 0.508)
		(drill 0.254)
		(layers "F.Cu" "B.Cu")
		(net "P3V3_CLK_BUFFER_9ZXL0451E_S3_VZX3P3")
	)
	(via
		(at 99.506278 -351.40392)
		(size 0.508)
		(drill 0.254)
		(layers "F.Cu" "B.Cu")
		(net "P3V3_CLK_BUFFER_9ZXL0451E_S3_VZX3P3")
	)
	(via
		(at 99.530408 -353.042474)
		(size 0.508)
		(drill 0.254)
		(layers "F.Cu" "B.Cu")
		(net "P3V3_CLK_BUFFER_9ZXL0451E_S3_VZX3P3")
	)
	(via
		(at 105.99547 -345.228926)
		(size 0.508)
		(drill 0.254)
		(layers "F.Cu" "B.Cu")
		(net "P3V3_CLK_BUFFER_9ZXL0451E_S3_VZX3P3")
	)
	(via
		(at 107.5436 -354.203)
		(size 0.508)
		(drill 0.254)
		(layers "F.Cu" "B.Cu")
		(net "P3V3_CLK_BUFFER_9ZXL0451E_S3_VZX3P3")
	)
	(segment
		(start 99.665282 -354.50526)
		(end 99.530408 -354.370386)
		(width 0.508)
		(layer "B.Cu")
		(net "P3V3_CLK_BUFFER_9ZXL0451E_S3_VZX3P3")
	)
	(segment
		(start 103.94061 -354.138484)
		(end 103.94061 -355.401118)
		(width 0.254)
		(layer "B.Cu")
		(net "P3V3_CLK_BUFFER_9ZXL0451E_S3_VZX3P3")
	)
	(segment
		(start 100.358448 -354.50526)
		(end 99.665282 -354.50526)
		(width 0.508)
		(layer "B.Cu")
		(net "P3V3_CLK_BUFFER_9ZXL0451E_S3_VZX3P3")
	)
	(segment
		(start 105.99547 -346.064586)
		(end 105.99547 -345.228926)
		(width 0.381)
		(layer "B.Cu")
		(net "P3V3_CLK_BUFFER_9ZXL0451E_S3_VZX3P3")
	)
	(segment
		(start 101.315774 -353.513644)
		(end 101.111304 -353.718114)
		(width 0.254)
		(layer "B.Cu")
		(net "P3V3_CLK_BUFFER_9ZXL0451E_S3_VZX3P3")
	)
	(segment
		(start 99.506278 -351.40392)
		(end 99.506278 -350.78035)
		(width 0.3048)
		(layer "B.Cu")
		(net "P3V3_CLK_BUFFER_9ZXL0451E_S3_VZX3P3")
	)
	(segment
		(start 103.828342 -355.865938)
		(end 103.828342 -355.513386)
		(width 0.508)
		(layer "B.Cu")
		(net "P3V3_CLK_BUFFER_9ZXL0451E_S3_VZX3P3")
	)
	(segment
		(start 99.530408 -353.042474)
		(end 99.530408 -353.718114)
		(width 0.508)
		(layer "B.Cu")
		(net "P3V3_CLK_BUFFER_9ZXL0451E_S3_VZX3P3")
	)
	(segment
		(start 100.032058 -350.78035)
		(end 100.765356 -351.513648)
		(width 0.254)
		(layer "B.Cu")
		(net "P3V3_CLK_BUFFER_9ZXL0451E_S3_VZX3P3")
	)
	(segment
		(start 104.178608 -356.226364)
		(end 104.183688 -356.221284)
		(width 0.508)
		(layer "B.Cu")
		(net "P3V3_CLK_BUFFER_9ZXL0451E_S3_VZX3P3")
	)
	(segment
		(start 101.111304 -353.718114)
		(end 100.59289 -353.718114)
		(width 0.254)
		(layer "B.Cu")
		(net "P3V3_CLK_BUFFER_9ZXL0451E_S3_VZX3P3")
	)
	(segment
		(start 99.506278 -350.78035)
		(end 100.032058 -350.78035)
		(width 0.254)
		(layer "B.Cu")
		(net "P3V3_CLK_BUFFER_9ZXL0451E_S3_VZX3P3")
	)
	(segment
		(start 106.065574 -351.513648)
		(end 106.841544 -351.513648)
		(width 0.254)
		(layer "B.Cu")
		(net "P3V3_CLK_BUFFER_9ZXL0451E_S3_VZX3P3")
	)
	(segment
		(start 103.94061 -355.401118)
		(end 103.828342 -355.513386)
		(width 0.254)
		(layer "B.Cu")
		(net "P3V3_CLK_BUFFER_9ZXL0451E_S3_VZX3P3")
	)
	(segment
		(start 100.59289 -353.718114)
		(end 99.530408 -353.718114)
		(width 0.508)
		(layer "B.Cu")
		(net "P3V3_CLK_BUFFER_9ZXL0451E_S3_VZX3P3")
	)
	(segment
		(start 105.99547 -345.228926)
		(end 105.99547 -344.197432)
		(width 0.13208)
		(layer "B.Cu")
		(net "P3V3_CLK_BUFFER_9ZXL0451E_S3_VZX3P3")
	)
	(segment
		(start 104.178608 -356.966012)
		(end 104.178608 -356.226364)
		(width 0.508)
		(layer "B.Cu")
		(net "P3V3_CLK_BUFFER_9ZXL0451E_S3_VZX3P3")
	)
	(segment
		(start 100.765356 -351.513648)
		(end 101.315774 -351.513648)
		(width 0.254)
		(layer "B.Cu")
		(net "P3V3_CLK_BUFFER_9ZXL0451E_S3_VZX3P3")
	)
	(segment
		(start 104.183688 -356.221284)
		(end 103.828342 -355.865938)
		(width 0.508)
		(layer "B.Cu")
		(net "P3V3_CLK_BUFFER_9ZXL0451E_S3_VZX3P3")
	)
	(segment
		(start 99.530408 -354.370386)
		(end 99.530408 -353.718114)
		(width 0.508)
		(layer "B.Cu")
		(net "P3V3_CLK_BUFFER_9ZXL0451E_S3_VZX3P3")
	)
	(segment
		(start 225.067622 -223.104202)
		(end 224.667826 -223.503998)
		(width 0.13208)
		(layer "F.Cu")
		(net "RST_PEX_MUX_N")
	)
	(segment
		(start 218.250262 -229.154482)
		(end 216.212674 -229.154482)
		(width 0.13208)
		(layer "F.Cu")
		(net "RST_PEX_MUX_N")
	)
	(segment
		(start 221.382336 -228.2444)
		(end 219.160344 -228.2444)
		(width 0.13208)
		(layer "F.Cu")
		(net "RST_PEX_MUX_N")
	)
	(segment
		(start 216.212674 -229.154482)
		(end 214.616284 -230.750872)
		(width 0.13208)
		(layer "F.Cu")
		(net "RST_PEX_MUX_N")
	)
	(segment
		(start 221.3864 -228.240336)
		(end 221.382336 -228.2444)
		(width 0.13208)
		(layer "F.Cu")
		(net "RST_PEX_MUX_N")
	)
	(segment
		(start 219.160344 -228.2444)
		(end 218.250262 -229.154482)
		(width 0.13208)
		(layer "F.Cu")
		(net "RST_PEX_MUX_N")
	)
	(via
		(at 221.3864 -228.240336)
		(size 0.508)
		(drill 0.254)
		(layers "F.Cu" "B.Cu")
		(net "RST_PEX_MUX_N")
	)
	(via
		(at 224.667826 -223.503998)
		(size 0.4572)
		(drill 0.254)
		(layers "F.Cu" "B.Cu")
		(net "RST_PEX_MUX_N")
	)
	(segment
		(start 221.3864 -228.240336)
		(end 221.3356 -228.189536)
		(width 0.15494)
		(layer "In13.Cu")
		(net "RST_PEX_MUX_N")
	)
	(segment
		(start 222.062802 -223.503998)
		(end 224.667826 -223.503998)
		(width 0.15494)
		(layer "In13.Cu")
		(net "RST_PEX_MUX_N")
	)
	(segment
		(start 221.3356 -224.2312)
		(end 222.062802 -223.503998)
		(width 0.15494)
		(layer "In13.Cu")
		(net "RST_PEX_MUX_N")
	)
	(segment
		(start 221.3356 -228.189536)
		(end 221.3356 -224.2312)
		(width 0.15494)
		(layer "In13.Cu")
		(net "RST_PEX_MUX_N")
	)
	(segment
		(start 215.7984 -233.179112)
		(end 215.161876 -232.542588)
		(width 0.13208)
		(layer "F.Cu")
		(net "RST_PEX_MUX_R_N")
	)
	(segment
		(start 215.161876 -232.248964)
		(end 214.616284 -231.703372)
		(width 0.13208)
		(layer "F.Cu")
		(net "RST_PEX_MUX_R_N")
	)
	(segment
		(start 214.616284 -231.703372)
		(end 214.616284 -231.550972)
		(width 0.13208)
		(layer "F.Cu")
		(net "RST_PEX_MUX_R_N")
	)
	(segment
		(start 215.161876 -232.542588)
		(end 215.161876 -232.248964)
		(width 0.13208)
		(layer "F.Cu")
		(net "RST_PEX_MUX_R_N")
	)
	(via
		(at 215.7984 -233.179112)
		(size 0.508)
		(drill 0.254)
		(layers "F.Cu" "B.Cu")
		(net "RST_PEX_MUX_R_N")
	)
	(via
		(at 214.29091 -230.40594)
		(size 0.6604)
		(drill 0.3302)
		(layers "F.Cu" "B.Cu")
		(net "RST_PEX_MUX_R_N")
	)
	(segment
		(start 208.175606 -229.59695)
		(end 207.906874 -229.328218)
		(width 0.13208)
		(layer "B.Cu")
		(net "RST_PEX_MUX_R_N")
	)
	(segment
		(start 207.906874 -229.328218)
		(end 204.205586 -229.328218)
		(width 0.13208)
		(layer "B.Cu")
		(net "RST_PEX_MUX_R_N")
	)
	(segment
		(start 203.987908 -253.537466)
		(end 204.114908 -253.664466)
		(width 0.13208)
		(layer "B.Cu")
		(net "RST_PEX_MUX_R_N")
	)
	(segment
		(start 204.114908 -253.664466)
		(end 204.114908 -254.530606)
		(width 0.13208)
		(layer "B.Cu")
		(net "RST_PEX_MUX_R_N")
	)
	(segment
		(start 215.773 -233.179112)
		(end 215.7476 -233.153712)
		(width 0.13208)
		(layer "B.Cu")
		(net "RST_PEX_MUX_R_N")
	)
	(segment
		(start 214.29091 -230.40594)
		(end 213.218522 -229.333552)
		(width 0.13208)
		(layer "B.Cu")
		(net "RST_PEX_MUX_R_N")
	)
	(segment
		(start 215.7476 -233.153712)
		(end 215.449912 -233.153712)
		(width 0.13208)
		(layer "B.Cu")
		(net "RST_PEX_MUX_R_N")
	)
	(segment
		(start 204.205586 -229.328218)
		(end 198.12 -235.413804)
		(width 0.13208)
		(layer "B.Cu")
		(net "RST_PEX_MUX_R_N")
	)
	(segment
		(start 210.21802 -229.59695)
		(end 208.175606 -229.59695)
		(width 0.13208)
		(layer "B.Cu")
		(net "RST_PEX_MUX_R_N")
	)
	(segment
		(start 215.449912 -233.153712)
		(end 214.820754 -232.524554)
		(width 0.13208)
		(layer "B.Cu")
		(net "RST_PEX_MUX_R_N")
	)
	(segment
		(start 198.12 -250.627642)
		(end 201.029824 -253.537466)
		(width 0.13208)
		(layer "B.Cu")
		(net "RST_PEX_MUX_R_N")
	)
	(segment
		(start 215.7984 -233.179112)
		(end 215.773 -233.179112)
		(width 0.13208)
		(layer "B.Cu")
		(net "RST_PEX_MUX_R_N")
	)
	(segment
		(start 214.820754 -230.935784)
		(end 214.29091 -230.40594)
		(width 0.13208)
		(layer "B.Cu")
		(net "RST_PEX_MUX_R_N")
	)
	(segment
		(start 198.12 -235.413804)
		(end 198.12 -250.627642)
		(width 0.13208)
		(layer "B.Cu")
		(net "RST_PEX_MUX_R_N")
	)
	(segment
		(start 201.029824 -253.537466)
		(end 203.987908 -253.537466)
		(width 0.13208)
		(layer "B.Cu")
		(net "RST_PEX_MUX_R_N")
	)
	(segment
		(start 203.106274 -258.911598)
		(end 204.114908 -257.902964)
		(width 0.13208)
		(layer "B.Cu")
		(net "RST_PEX_MUX_R_N")
	)
	(segment
		(start 204.114908 -257.902964)
		(end 204.114908 -254.530606)
		(width 0.13208)
		(layer "B.Cu")
		(net "RST_PEX_MUX_R_N")
	)
	(segment
		(start 214.820754 -232.524554)
		(end 214.820754 -230.935784)
		(width 0.13208)
		(layer "B.Cu")
		(net "RST_PEX_MUX_R_N")
	)
	(segment
		(start 213.218522 -229.333552)
		(end 210.481418 -229.333552)
		(width 0.13208)
		(layer "B.Cu")
		(net "RST_PEX_MUX_R_N")
	)
	(segment
		(start 210.481418 -229.333552)
		(end 210.21802 -229.59695)
		(width 0.13208)
		(layer "B.Cu")
		(net "RST_PEX_MUX_R_N")
	)
	(segment
		(start 217.805 -193.04)
		(end 218.186 -193.04)
		(width 0.13208)
		(layer "F.Cu")
		(net "SMB_NIC7_LS_R_SCL")
	)
	(segment
		(start 218.186 -193.04)
		(end 218.80195 -193.04)
		(width 0.13208)
		(layer "F.Cu")
		(net "SMB_NIC7_LS_R_SCL")
	)
	(segment
		(start 216.991946 -193.22288)
		(end 217.62212 -193.22288)
		(width 0.13208)
		(layer "F.Cu")
		(net "SMB_NIC7_LS_R_SCL")
	)
	(segment
		(start 217.62212 -193.22288)
		(end 217.805 -193.04)
		(width 0.13208)
		(layer "F.Cu")
		(net "SMB_NIC7_LS_R_SCL")
	)
	(via
		(at 216.58834 -192.00495)
		(size 0.6604)
		(drill 0.3302)
		(layers "F.Cu" "B.Cu")
		(net "SMB_NIC7_LS_R_SCL")
	)
	(via
		(at 218.186 -193.04)
		(size 0.508)
		(drill 0.254)
		(layers "F.Cu" "B.Cu")
		(net "SMB_NIC7_LS_R_SCL")
	)
	(segment
		(start 213.106 -192.00495)
		(end 216.58834 -192.00495)
		(width 0.13208)
		(layer "B.Cu")
		(net "SMB_NIC7_LS_R_SCL")
	)
	(segment
		(start 212.09 -192.00495)
		(end 213.106 -192.00495)
		(width 0.13208)
		(layer "B.Cu")
		(net "SMB_NIC7_LS_R_SCL")
	)
	(segment
		(start 217.15095 -192.00495)
		(end 218.186 -193.04)
		(width 0.13208)
		(layer "B.Cu")
		(net "SMB_NIC7_LS_R_SCL")
	)
	(segment
		(start 216.58834 -192.00495)
		(end 217.15095 -192.00495)
		(width 0.13208)
		(layer "B.Cu")
		(net "SMB_NIC7_LS_R_SCL")
	)
	(segment
		(start 216.991946 -193.87312)
		(end 217.62212 -193.87312)
		(width 0.13208)
		(layer "F.Cu")
		(net "SMB_NIC7_LS_R_SDA")
	)
	(segment
		(start 217.805 -194.056)
		(end 218.186 -194.056)
		(width 0.13208)
		(layer "F.Cu")
		(net "SMB_NIC7_LS_R_SDA")
	)
	(segment
		(start 217.62212 -193.87312)
		(end 217.805 -194.056)
		(width 0.13208)
		(layer "F.Cu")
		(net "SMB_NIC7_LS_R_SDA")
	)
	(segment
		(start 218.186 -194.056)
		(end 218.80195 -194.056)
		(width 0.13208)
		(layer "F.Cu")
		(net "SMB_NIC7_LS_R_SDA")
	)
	(via
		(at 217.108532 -194.58305)
		(size 0.6604)
		(drill 0.3302)
		(layers "F.Cu" "B.Cu")
		(net "SMB_NIC7_LS_R_SDA")
	)
	(via
		(at 218.186 -194.056)
		(size 0.508)
		(drill 0.254)
		(layers "F.Cu" "B.Cu")
		(net "SMB_NIC7_LS_R_SDA")
	)
	(segment
		(start 213.106 -194.58305)
		(end 213.340696 -194.58305)
		(width 0.13208)
		(layer "B.Cu")
		(net "SMB_NIC7_LS_R_SDA")
	)
	(segment
		(start 217.108532 -194.58305)
		(end 217.65895 -194.58305)
		(width 0.13208)
		(layer "B.Cu")
		(net "SMB_NIC7_LS_R_SDA")
	)
	(segment
		(start 214.90305 -194.58305)
		(end 217.108532 -194.58305)
		(width 0.13208)
		(layer "B.Cu")
		(net "SMB_NIC7_LS_R_SDA")
	)
	(segment
		(start 217.65895 -194.58305)
		(end 218.186 -194.056)
		(width 0.13208)
		(layer "B.Cu")
		(net "SMB_NIC7_LS_R_SDA")
	)
	(segment
		(start 214.63 -194.31)
		(end 214.90305 -194.58305)
		(width 0.13208)
		(layer "B.Cu")
		(net "SMB_NIC7_LS_R_SDA")
	)
	(segment
		(start 213.340696 -194.58305)
		(end 213.613746 -194.31)
		(width 0.13208)
		(layer "B.Cu")
		(net "SMB_NIC7_LS_R_SDA")
	)
	(segment
		(start 212.09 -194.58305)
		(end 213.106 -194.58305)
		(width 0.13208)
		(layer "B.Cu")
		(net "SMB_NIC7_LS_R_SDA")
	)
	(segment
		(start 213.613746 -194.31)
		(end 214.63 -194.31)
		(width 0.13208)
		(layer "B.Cu")
		(net "SMB_NIC7_LS_R_SDA")
	)
	(segment
		(start 216.991946 -197.79488)
		(end 217.62212 -197.79488)
		(width 0.13208)
		(layer "F.Cu")
		(net "SMB_NIC6_LS_R_SCL")
	)
	(segment
		(start 217.805 -197.612)
		(end 218.186 -197.612)
		(width 0.13208)
		(layer "F.Cu")
		(net "SMB_NIC6_LS_R_SCL")
	)
	(segment
		(start 218.186 -197.612)
		(end 218.80195 -197.612)
		(width 0.13208)
		(layer "F.Cu")
		(net "SMB_NIC6_LS_R_SCL")
	)
	(segment
		(start 217.62212 -197.79488)
		(end 217.805 -197.612)
		(width 0.13208)
		(layer "F.Cu")
		(net "SMB_NIC6_LS_R_SCL")
	)
	(via
		(at 216.302336 -196.57695)
		(size 0.6604)
		(drill 0.3302)
		(layers "F.Cu" "B.Cu")
		(net "SMB_NIC6_LS_R_SCL")
	)
	(via
		(at 218.186 -197.612)
		(size 0.508)
		(drill 0.254)
		(layers "F.Cu" "B.Cu")
		(net "SMB_NIC6_LS_R_SCL")
	)
	(segment
		(start 214.042752 -196.57695)
		(end 214.071962 -196.60616)
		(width 0.13208)
		(layer "B.Cu")
		(net "SMB_NIC6_LS_R_SCL")
	)
	(segment
		(start 213.106 -196.57695)
		(end 214.042752 -196.57695)
		(width 0.13208)
		(layer "B.Cu")
		(net "SMB_NIC6_LS_R_SCL")
	)
	(segment
		(start 217.15095 -196.57695)
		(end 218.186 -197.612)
		(width 0.13208)
		(layer "B.Cu")
		(net "SMB_NIC6_LS_R_SCL")
	)
	(segment
		(start 216.273126 -196.60616)
		(end 216.302336 -196.57695)
		(width 0.13208)
		(layer "B.Cu")
		(net "SMB_NIC6_LS_R_SCL")
	)
	(segment
		(start 216.302336 -196.57695)
		(end 217.15095 -196.57695)
		(width 0.13208)
		(layer "B.Cu")
		(net "SMB_NIC6_LS_R_SCL")
	)
	(segment
		(start 214.071962 -196.60616)
		(end 216.273126 -196.60616)
		(width 0.13208)
		(layer "B.Cu")
		(net "SMB_NIC6_LS_R_SCL")
	)
	(segment
		(start 212.09 -196.57695)
		(end 213.106 -196.57695)
		(width 0.13208)
		(layer "B.Cu")
		(net "SMB_NIC6_LS_R_SCL")
	)
	(segment
		(start 217.805 -198.44512)
		(end 216.991946 -198.44512)
		(width 0.13208)
		(layer "F.Cu")
		(net "SMB_NIC6_LS_R_SDA")
	)
	(segment
		(start 218.186 -198.374)
		(end 217.87612 -198.374)
		(width 0.13208)
		(layer "F.Cu")
		(net "SMB_NIC6_LS_R_SDA")
	)
	(segment
		(start 217.87612 -198.374)
		(end 217.805 -198.44512)
		(width 0.13208)
		(layer "F.Cu")
		(net "SMB_NIC6_LS_R_SDA")
	)
	(segment
		(start 218.44 -198.628)
		(end 218.186 -198.374)
		(width 0.13208)
		(layer "F.Cu")
		(net "SMB_NIC6_LS_R_SDA")
	)
	(segment
		(start 218.80195 -198.628)
		(end 218.44 -198.628)
		(width 0.13208)
		(layer "F.Cu")
		(net "SMB_NIC6_LS_R_SDA")
	)
	(via
		(at 218.186 -198.374)
		(size 0.508)
		(drill 0.254)
		(layers "F.Cu" "B.Cu")
		(net "SMB_NIC6_LS_R_SDA")
	)
	(via
		(at 216.874598 -199.15505)
		(size 0.6604)
		(drill 0.3302)
		(layers "F.Cu" "B.Cu")
		(net "SMB_NIC6_LS_R_SDA")
	)
	(segment
		(start 216.874598 -199.15505)
		(end 213.106 -199.15505)
		(width 0.13208)
		(layer "B.Cu")
		(net "SMB_NIC6_LS_R_SDA")
	)
	(segment
		(start 218.186 -198.374)
		(end 217.40495 -199.15505)
		(width 0.13208)
		(layer "B.Cu")
		(net "SMB_NIC6_LS_R_SDA")
	)
	(segment
		(start 217.40495 -199.15505)
		(end 216.874598 -199.15505)
		(width 0.13208)
		(layer "B.Cu")
		(net "SMB_NIC6_LS_R_SDA")
	)
	(segment
		(start 212.09 -199.15505)
		(end 213.106 -199.15505)
		(width 0.13208)
		(layer "B.Cu")
		(net "SMB_NIC6_LS_R_SDA")
	)
	(segment
		(start 217.805 -202.184)
		(end 217.62212 -202.36688)
		(width 0.13208)
		(layer "F.Cu")
		(net "SMB_NIC5_LS_R_SCL")
	)
	(segment
		(start 217.62212 -202.36688)
		(end 216.991946 -202.36688)
		(width 0.13208)
		(layer "F.Cu")
		(net "SMB_NIC5_LS_R_SCL")
	)
	(segment
		(start 218.186 -202.184)
		(end 217.805 -202.184)
		(width 0.13208)
		(layer "F.Cu")
		(net "SMB_NIC5_LS_R_SCL")
	)
	(segment
		(start 218.80195 -202.184)
		(end 218.186 -202.184)
		(width 0.13208)
		(layer "F.Cu")
		(net "SMB_NIC5_LS_R_SCL")
	)
	(via
		(at 218.186 -202.184)
		(size 0.508)
		(drill 0.254)
		(layers "F.Cu" "B.Cu")
		(net "SMB_NIC5_LS_R_SCL")
	)
	(via
		(at 214.50808 -201.14895)
		(size 0.6604)
		(drill 0.3302)
		(layers "F.Cu" "B.Cu")
		(net "SMB_NIC5_LS_R_SCL")
	)
	(segment
		(start 212.09 -201.14895)
		(end 213.106 -201.14895)
		(width 0.13208)
		(layer "B.Cu")
		(net "SMB_NIC5_LS_R_SCL")
	)
	(segment
		(start 213.106 -201.14895)
		(end 214.50808 -201.14895)
		(width 0.13208)
		(layer "B.Cu")
		(net "SMB_NIC5_LS_R_SCL")
	)
	(segment
		(start 217.15095 -201.14895)
		(end 218.186 -202.184)
		(width 0.13208)
		(layer "B.Cu")
		(net "SMB_NIC5_LS_R_SCL")
	)
	(segment
		(start 214.50808 -201.14895)
		(end 217.15095 -201.14895)
		(width 0.13208)
		(layer "B.Cu")
		(net "SMB_NIC5_LS_R_SCL")
	)
	(segment
		(start 217.805 -203.2)
		(end 218.186 -203.2)
		(width 0.13208)
		(layer "F.Cu")
		(net "SMB_NIC5_LS_R_SDA")
	)
	(segment
		(start 217.62212 -203.01712)
		(end 217.805 -203.2)
		(width 0.13208)
		(layer "F.Cu")
		(net "SMB_NIC5_LS_R_SDA")
	)
	(segment
		(start 216.991946 -203.01712)
		(end 217.62212 -203.01712)
		(width 0.13208)
		(layer "F.Cu")
		(net "SMB_NIC5_LS_R_SDA")
	)
	(segment
		(start 218.186 -203.2)
		(end 218.80195 -203.2)
		(width 0.13208)
		(layer "F.Cu")
		(net "SMB_NIC5_LS_R_SDA")
	)
	(via
		(at 218.186 -203.2)
		(size 0.508)
		(drill 0.254)
		(layers "F.Cu" "B.Cu")
		(net "SMB_NIC5_LS_R_SDA")
	)
	(via
		(at 216.874598 -203.72705)
		(size 0.6604)
		(drill 0.3302)
		(layers "F.Cu" "B.Cu")
		(net "SMB_NIC5_LS_R_SDA")
	)
	(segment
		(start 217.65895 -203.72705)
		(end 218.186 -203.2)
		(width 0.13208)
		(layer "B.Cu")
		(net "SMB_NIC5_LS_R_SDA")
	)
	(segment
		(start 216.874598 -203.72705)
		(end 217.65895 -203.72705)
		(width 0.13208)
		(layer "B.Cu")
		(net "SMB_NIC5_LS_R_SDA")
	)
	(segment
		(start 212.09 -203.72705)
		(end 213.106 -203.72705)
		(width 0.13208)
		(layer "B.Cu")
		(net "SMB_NIC5_LS_R_SDA")
	)
	(segment
		(start 213.106 -203.72705)
		(end 216.874598 -203.72705)
		(width 0.13208)
		(layer "B.Cu")
		(net "SMB_NIC5_LS_R_SDA")
	)
	(segment
		(start 217.62212 -206.93888)
		(end 217.805 -206.756)
		(width 0.13208)
		(layer "F.Cu")
		(net "SMB_NIC4_LS_R_SCL")
	)
	(segment
		(start 218.186 -206.756)
		(end 218.80195 -206.756)
		(width 0.13208)
		(layer "F.Cu")
		(net "SMB_NIC4_LS_R_SCL")
	)
	(segment
		(start 217.805 -206.756)
		(end 218.186 -206.756)
		(width 0.13208)
		(layer "F.Cu")
		(net "SMB_NIC4_LS_R_SCL")
	)
	(segment
		(start 216.991946 -206.93888)
		(end 217.62212 -206.93888)
		(width 0.13208)
		(layer "F.Cu")
		(net "SMB_NIC4_LS_R_SCL")
	)
	(via
		(at 216.4715 -205.72095)
		(size 0.6604)
		(drill 0.3302)
		(layers "F.Cu" "B.Cu")
		(net "SMB_NIC4_LS_R_SCL")
	)
	(via
		(at 218.186 -206.756)
		(size 0.508)
		(drill 0.254)
		(layers "F.Cu" "B.Cu")
		(net "SMB_NIC4_LS_R_SCL")
	)
	(segment
		(start 217.15095 -205.72095)
		(end 218.186 -206.756)
		(width 0.13208)
		(layer "B.Cu")
		(net "SMB_NIC4_LS_R_SCL")
	)
	(segment
		(start 216.4715 -205.72095)
		(end 217.15095 -205.72095)
		(width 0.13208)
		(layer "B.Cu")
		(net "SMB_NIC4_LS_R_SCL")
	)
	(segment
		(start 212.09 -205.72095)
		(end 213.106 -205.72095)
		(width 0.13208)
		(layer "B.Cu")
		(net "SMB_NIC4_LS_R_SCL")
	)
	(segment
		(start 213.106 -205.72095)
		(end 216.4715 -205.72095)
		(width 0.13208)
		(layer "B.Cu")
		(net "SMB_NIC4_LS_R_SCL")
	)
	(segment
		(start 216.991946 -207.58912)
		(end 217.62212 -207.58912)
		(width 0.13208)
		(layer "F.Cu")
		(net "SMB_NIC4_LS_R_SDA")
	)
	(segment
		(start 217.805 -207.772)
		(end 218.186 -207.772)
		(width 0.13208)
		(layer "F.Cu")
		(net "SMB_NIC4_LS_R_SDA")
	)
	(segment
		(start 217.62212 -207.58912)
		(end 217.805 -207.772)
		(width 0.13208)
		(layer "F.Cu")
		(net "SMB_NIC4_LS_R_SDA")
	)
	(segment
		(start 218.186 -207.772)
		(end 218.80195 -207.772)
		(width 0.13208)
		(layer "F.Cu")
		(net "SMB_NIC4_LS_R_SDA")
	)
	(via
		(at 216.878154 -207.772)
		(size 0.6604)
		(drill 0.3302)
		(layers "F.Cu" "B.Cu")
		(net "SMB_NIC4_LS_R_SDA")
	)
	(via
		(at 218.186 -207.772)
		(size 0.508)
		(drill 0.254)
		(layers "F.Cu" "B.Cu")
		(net "SMB_NIC4_LS_R_SDA")
	)
	(segment
		(start 212.09 -208.29905)
		(end 213.106 -208.29905)
		(width 0.13208)
		(layer "B.Cu")
		(net "SMB_NIC4_LS_R_SDA")
	)
	(segment
		(start 216.500964 -208.14919)
		(end 216.878154 -207.772)
		(width 0.13208)
		(layer "B.Cu")
		(net "SMB_NIC4_LS_R_SDA")
	)
	(segment
		(start 213.106 -208.29905)
		(end 213.25586 -208.14919)
		(width 0.13208)
		(layer "B.Cu")
		(net "SMB_NIC4_LS_R_SDA")
	)
	(segment
		(start 216.878154 -207.772)
		(end 218.186 -207.772)
		(width 0.13208)
		(layer "B.Cu")
		(net "SMB_NIC4_LS_R_SDA")
	)
	(segment
		(start 213.25586 -208.14919)
		(end 216.500964 -208.14919)
		(width 0.13208)
		(layer "B.Cu")
		(net "SMB_NIC4_LS_R_SDA")
	)
	(segment
		(start 212.8901 -229.00005)
		(end 212.87105 -228.981)
		(width 0.13208)
		(layer "F.Cu")
		(net "PRSNT_DBV2_SLIMSAS_R")
	)
	(segment
		(start 213.868 -229.00005)
		(end 214.884 -229.00005)
		(width 0.13208)
		(layer "F.Cu")
		(net "PRSNT_DBV2_SLIMSAS_R")
	)
	(segment
		(start 217.601292 -228.751638)
		(end 215.749124 -228.751638)
		(width 0.13208)
		(layer "F.Cu")
		(net "PRSNT_DBV2_SLIMSAS_R")
	)
	(segment
		(start 226.667568 -222.304102)
		(end 226.267772 -222.703898)
		(width 0.13208)
		(layer "F.Cu")
		(net "PRSNT_DBV2_SLIMSAS_R")
	)
	(segment
		(start 213.868 -229.00005)
		(end 212.8901 -229.00005)
		(width 0.13208)
		(layer "F.Cu")
		(net "PRSNT_DBV2_SLIMSAS_R")
	)
	(segment
		(start 215.500712 -229.00005)
		(end 214.884 -229.00005)
		(width 0.13208)
		(layer "F.Cu")
		(net "PRSNT_DBV2_SLIMSAS_R")
	)
	(segment
		(start 215.749124 -228.751638)
		(end 215.500712 -229.00005)
		(width 0.13208)
		(layer "F.Cu")
		(net "PRSNT_DBV2_SLIMSAS_R")
	)
	(segment
		(start 218.182952 -228.169978)
		(end 217.601292 -228.751638)
		(width 0.13208)
		(layer "F.Cu")
		(net "PRSNT_DBV2_SLIMSAS_R")
	)
	(via
		(at 226.267772 -222.703898)
		(size 0.4572)
		(drill 0.254)
		(layers "F.Cu" "B.Cu")
		(net "PRSNT_DBV2_SLIMSAS_R")
	)
	(via
		(at 218.182952 -228.169978)
		(size 0.508)
		(drill 0.254)
		(layers "F.Cu" "B.Cu")
		(net "PRSNT_DBV2_SLIMSAS_R")
	)
	(segment
		(start 218.687142 -227.665788)
		(end 224.298764 -227.665788)
		(width 0.15494)
		(layer "In7.Cu")
		(net "PRSNT_DBV2_SLIMSAS_R")
	)
	(segment
		(start 225.870262 -223.101408)
		(end 226.267772 -222.703898)
		(width 0.0889)
		(layer "In7.Cu")
		(net "PRSNT_DBV2_SLIMSAS_R")
	)
	(segment
		(start 224.298764 -227.665788)
		(end 225.870262 -226.09429)
		(width 0.15494)
		(layer "In7.Cu")
		(net "PRSNT_DBV2_SLIMSAS_R")
	)
	(segment
		(start 218.182952 -228.169978)
		(end 218.687142 -227.665788)
		(width 0.15494)
		(layer "In7.Cu")
		(net "PRSNT_DBV2_SLIMSAS_R")
	)
	(segment
		(start 225.870262 -226.09429)
		(end 225.870262 -223.901)
		(width 0.15494)
		(layer "In7.Cu")
		(net "PRSNT_DBV2_SLIMSAS_R")
	)
	(segment
		(start 225.870262 -223.901)
		(end 225.870262 -223.101408)
		(width 0.0889)
		(layer "In7.Cu")
		(net "PRSNT_DBV2_SLIMSAS_R")
	)
	(segment
		(start 368.21999 -7.167372)
		(end 368.21999 -8.693912)
		(width 0.13208)
		(layer "F.Cu")
		(net "SMB_BIC_I2C6_MUX_THERMAL_R2_SCL")
	)
	(segment
		(start 368.611404 -9.085326)
		(end 368.21999 -8.693912)
		(width 0.13208)
		(layer "F.Cu")
		(net "SMB_BIC_I2C6_MUX_THERMAL_R2_SCL")
	)
	(segment
		(start 368.68354 -6.703822)
		(end 368.21999 -7.167372)
		(width 0.13208)
		(layer "F.Cu")
		(net "SMB_BIC_I2C6_MUX_THERMAL_R2_SCL")
	)
	(segment
		(start 368.611404 -9.955022)
		(end 368.611404 -9.085326)
		(width 0.13208)
		(layer "F.Cu")
		(net "SMB_BIC_I2C6_MUX_THERMAL_R2_SCL")
	)
	(via
		(at 368.21999 -8.693912)
		(size 0.508)
		(drill 0.254)
		(layers "F.Cu" "B.Cu")
		(net "SMB_BIC_I2C6_MUX_THERMAL_R2_SCL")
	)
	(via
		(at 381.254 -80.645)
		(size 0.508)
		(drill 0.254)
		(layers "F.Cu" "B.Cu")
		(net "SMB_BIC_I2C6_MUX_THERMAL_R2_SCL")
	)
	(via
		(at 454.828656 -18.264632)
		(size 0.508)
		(drill 0.254)
		(layers "F.Cu" "B.Cu")
		(net "SMB_BIC_I2C6_MUX_THERMAL_R2_SCL")
	)
	(segment
		(start 380.746 -80.645)
		(end 380.619 -80.772)
		(width 0.13208)
		(layer "B.Cu")
		(net "SMB_BIC_I2C6_MUX_THERMAL_R2_SCL")
	)
	(segment
		(start 380.619 -80.772)
		(end 379.74905 -80.772)
		(width 0.13208)
		(layer "B.Cu")
		(net "SMB_BIC_I2C6_MUX_THERMAL_R2_SCL")
	)
	(segment
		(start 381.254 -80.645)
		(end 380.746 -80.645)
		(width 0.13208)
		(layer "B.Cu")
		(net "SMB_BIC_I2C6_MUX_THERMAL_R2_SCL")
	)
	(segment
		(start 397.028416 -81.025492)
		(end 423.619676 -81.025492)
		(width 0.15494)
		(layer "In13.Cu")
		(net "SMB_BIC_I2C6_MUX_THERMAL_R2_SCL")
	)
	(segment
		(start 458.526642 -35.563556)
		(end 452.91248 -29.949394)
		(width 0.15494)
		(layer "In13.Cu")
		(net "SMB_BIC_I2C6_MUX_THERMAL_R2_SCL")
	)
	(segment
		(start 396.646654 -81.407254)
		(end 397.028416 -81.025492)
		(width 0.15494)
		(layer "In13.Cu")
		(net "SMB_BIC_I2C6_MUX_THERMAL_R2_SCL")
	)
	(segment
		(start 429.401224 -75.243944)
		(end 452.576692 -75.243944)
		(width 0.15494)
		(layer "In13.Cu")
		(net "SMB_BIC_I2C6_MUX_THERMAL_R2_SCL")
	)
	(segment
		(start 452.91248 -29.949394)
		(end 452.91248 -25.877266)
		(width 0.15494)
		(layer "In13.Cu")
		(net "SMB_BIC_I2C6_MUX_THERMAL_R2_SCL")
	)
	(segment
		(start 393.892786 -81.015332)
		(end 394.284708 -81.407254)
		(width 0.15494)
		(layer "In13.Cu")
		(net "SMB_BIC_I2C6_MUX_THERMAL_R2_SCL")
	)
	(segment
		(start 382.016 -80.645)
		(end 382.386332 -81.015332)
		(width 0.15494)
		(layer "In13.Cu")
		(net "SMB_BIC_I2C6_MUX_THERMAL_R2_SCL")
	)
	(segment
		(start 382.386332 -81.015332)
		(end 393.892786 -81.015332)
		(width 0.15494)
		(layer "In13.Cu")
		(net "SMB_BIC_I2C6_MUX_THERMAL_R2_SCL")
	)
	(segment
		(start 458.526642 -69.293994)
		(end 458.526642 -35.563556)
		(width 0.15494)
		(layer "In13.Cu")
		(net "SMB_BIC_I2C6_MUX_THERMAL_R2_SCL")
	)
	(segment
		(start 423.619676 -81.025492)
		(end 429.401224 -75.243944)
		(width 0.15494)
		(layer "In13.Cu")
		(net "SMB_BIC_I2C6_MUX_THERMAL_R2_SCL")
	)
	(segment
		(start 394.284708 -81.407254)
		(end 396.646654 -81.407254)
		(width 0.15494)
		(layer "In13.Cu")
		(net "SMB_BIC_I2C6_MUX_THERMAL_R2_SCL")
	)
	(segment
		(start 452.91248 -25.877266)
		(end 454.24725 -24.542496)
		(width 0.15494)
		(layer "In13.Cu")
		(net "SMB_BIC_I2C6_MUX_THERMAL_R2_SCL")
	)
	(segment
		(start 454.24725 -24.542496)
		(end 454.24725 -18.846038)
		(width 0.15494)
		(layer "In13.Cu")
		(net "SMB_BIC_I2C6_MUX_THERMAL_R2_SCL")
	)
	(segment
		(start 452.576692 -75.243944)
		(end 458.526642 -69.293994)
		(width 0.15494)
		(layer "In13.Cu")
		(net "SMB_BIC_I2C6_MUX_THERMAL_R2_SCL")
	)
	(segment
		(start 381.254 -80.645)
		(end 382.016 -80.645)
		(width 0.15494)
		(layer "In13.Cu")
		(net "SMB_BIC_I2C6_MUX_THERMAL_R2_SCL")
	)
	(segment
		(start 454.24725 -18.846038)
		(end 454.828656 -18.264632)
		(width 0.15494)
		(layer "In13.Cu")
		(net "SMB_BIC_I2C6_MUX_THERMAL_R2_SCL")
	)
	(segment
		(start 425.02328 -18.06448)
		(end 424.91914 -17.96034)
		(width 0.15494)
		(layer "In15.Cu")
		(net "SMB_BIC_I2C6_MUX_THERMAL_R2_SCL")
	)
	(segment
		(start 369.42268 -7.491222)
		(end 368.21999 -8.693912)
		(width 0.15494)
		(layer "In15.Cu")
		(net "SMB_BIC_I2C6_MUX_THERMAL_R2_SCL")
	)
	(segment
		(start 374.825514 -7.491222)
		(end 369.42268 -7.491222)
		(width 0.15494)
		(layer "In15.Cu")
		(net "SMB_BIC_I2C6_MUX_THERMAL_R2_SCL")
	)
	(segment
		(start 454.828656 -18.264632)
		(end 454.648824 -18.0848)
		(width 0.15494)
		(layer "In15.Cu")
		(net "SMB_BIC_I2C6_MUX_THERMAL_R2_SCL")
	)
	(segment
		(start 448.558666 -18.06448)
		(end 438.367678 -18.06448)
		(width 0.15494)
		(layer "In15.Cu")
		(net "SMB_BIC_I2C6_MUX_THERMAL_R2_SCL")
	)
	(segment
		(start 438.367678 -18.06448)
		(end 437.919876 -17.616678)
		(width 0.15494)
		(layer "In15.Cu")
		(net "SMB_BIC_I2C6_MUX_THERMAL_R2_SCL")
	)
	(segment
		(start 449.158868 -17.96034)
		(end 448.757548 -17.96034)
		(width 0.15494)
		(layer "In15.Cu")
		(net "SMB_BIC_I2C6_MUX_THERMAL_R2_SCL")
	)
	(segment
		(start 448.757548 -17.96034)
		(end 448.633088 -18.0848)
		(width 0.15494)
		(layer "In15.Cu")
		(net "SMB_BIC_I2C6_MUX_THERMAL_R2_SCL")
	)
	(segment
		(start 395.861032 -17.341088)
		(end 395.111478 -18.090642)
		(width 0.15494)
		(layer "In15.Cu")
		(net "SMB_BIC_I2C6_MUX_THERMAL_R2_SCL")
	)
	(segment
		(start 390.337548 -18.090642)
		(end 390.325102 -18.103088)
		(width 0.15494)
		(layer "In15.Cu")
		(net "SMB_BIC_I2C6_MUX_THERMAL_R2_SCL")
	)
	(segment
		(start 449.283328 -18.0848)
		(end 449.158868 -17.96034)
		(width 0.15494)
		(layer "In15.Cu")
		(net "SMB_BIC_I2C6_MUX_THERMAL_R2_SCL")
	)
	(segment
		(start 422.715182 -18.002758)
		(end 416.23234 -18.002758)
		(width 0.15494)
		(layer "In15.Cu")
		(net "SMB_BIC_I2C6_MUX_THERMAL_R2_SCL")
	)
	(segment
		(start 398.340072 -18.002758)
		(end 397.678402 -17.341088)
		(width 0.15494)
		(layer "In15.Cu")
		(net "SMB_BIC_I2C6_MUX_THERMAL_R2_SCL")
	)
	(segment
		(start 454.648824 -18.0848)
		(end 449.283328 -18.0848)
		(width 0.15494)
		(layer "In15.Cu")
		(net "SMB_BIC_I2C6_MUX_THERMAL_R2_SCL")
	)
	(segment
		(start 386.660644 -18.090388)
		(end 386.280152 -18.090388)
		(width 0.15494)
		(layer "In15.Cu")
		(net "SMB_BIC_I2C6_MUX_THERMAL_R2_SCL")
	)
	(segment
		(start 416.23234 -18.002758)
		(end 415.913316 -18.321782)
		(width 0.15494)
		(layer "In15.Cu")
		(net "SMB_BIC_I2C6_MUX_THERMAL_R2_SCL")
	)
	(segment
		(start 424.91914 -17.96034)
		(end 422.7576 -17.96034)
		(width 0.15494)
		(layer "In15.Cu")
		(net "SMB_BIC_I2C6_MUX_THERMAL_R2_SCL")
	)
	(segment
		(start 412.884112 -18.002758)
		(end 398.340072 -18.002758)
		(width 0.15494)
		(layer "In15.Cu")
		(net "SMB_BIC_I2C6_MUX_THERMAL_R2_SCL")
	)
	(segment
		(start 397.678402 -17.341088)
		(end 395.861032 -17.341088)
		(width 0.15494)
		(layer "In15.Cu")
		(net "SMB_BIC_I2C6_MUX_THERMAL_R2_SCL")
	)
	(segment
		(start 437.919876 -17.616678)
		(end 431.140108 -17.616678)
		(width 0.15494)
		(layer "In15.Cu")
		(net "SMB_BIC_I2C6_MUX_THERMAL_R2_SCL")
	)
	(segment
		(start 448.578986 -18.0848)
		(end 448.558666 -18.06448)
		(width 0.15494)
		(layer "In15.Cu")
		(net "SMB_BIC_I2C6_MUX_THERMAL_R2_SCL")
	)
	(segment
		(start 413.203136 -18.321782)
		(end 412.884112 -18.002758)
		(width 0.15494)
		(layer "In15.Cu")
		(net "SMB_BIC_I2C6_MUX_THERMAL_R2_SCL")
	)
	(segment
		(start 386.280152 -18.090388)
		(end 386.279898 -18.090642)
		(width 0.15494)
		(layer "In15.Cu")
		(net "SMB_BIC_I2C6_MUX_THERMAL_R2_SCL")
	)
	(segment
		(start 386.673344 -18.103088)
		(end 386.660644 -18.090388)
		(width 0.15494)
		(layer "In15.Cu")
		(net "SMB_BIC_I2C6_MUX_THERMAL_R2_SCL")
	)
	(segment
		(start 395.111478 -18.090642)
		(end 390.337548 -18.090642)
		(width 0.15494)
		(layer "In15.Cu")
		(net "SMB_BIC_I2C6_MUX_THERMAL_R2_SCL")
	)
	(segment
		(start 431.140108 -17.616678)
		(end 430.692306 -18.06448)
		(width 0.15494)
		(layer "In15.Cu")
		(net "SMB_BIC_I2C6_MUX_THERMAL_R2_SCL")
	)
	(segment
		(start 430.692306 -18.06448)
		(end 425.02328 -18.06448)
		(width 0.15494)
		(layer "In15.Cu")
		(net "SMB_BIC_I2C6_MUX_THERMAL_R2_SCL")
	)
	(segment
		(start 385.424934 -18.090642)
		(end 374.825514 -7.491222)
		(width 0.15494)
		(layer "In15.Cu")
		(net "SMB_BIC_I2C6_MUX_THERMAL_R2_SCL")
	)
	(segment
		(start 386.279898 -18.090642)
		(end 385.424934 -18.090642)
		(width 0.15494)
		(layer "In15.Cu")
		(net "SMB_BIC_I2C6_MUX_THERMAL_R2_SCL")
	)
	(segment
		(start 390.325102 -18.103088)
		(end 386.673344 -18.103088)
		(width 0.15494)
		(layer "In15.Cu")
		(net "SMB_BIC_I2C6_MUX_THERMAL_R2_SCL")
	)
	(segment
		(start 415.913316 -18.321782)
		(end 413.203136 -18.321782)
		(width 0.15494)
		(layer "In15.Cu")
		(net "SMB_BIC_I2C6_MUX_THERMAL_R2_SCL")
	)
	(segment
		(start 422.7576 -17.96034)
		(end 422.715182 -18.002758)
		(width 0.15494)
		(layer "In15.Cu")
		(net "SMB_BIC_I2C6_MUX_THERMAL_R2_SCL")
	)
	(segment
		(start 448.633088 -18.0848)
		(end 448.578986 -18.0848)
		(width 0.15494)
		(layer "In15.Cu")
		(net "SMB_BIC_I2C6_MUX_THERMAL_R2_SCL")
	)
	(segment
		(start 70.099936 -304.449734)
		(end 70.574916 -304.924714)
		(width 0.249936)
		(layer "F.Cu")
		(net "Net_479")
	)
	(via
		(at 70.574916 -304.924714)
		(size 0.4064)
		(drill 0.2032)
		(layers "F.Cu" "B.Cu")
		(net "Net_479")
	)
	(segment
		(start 69.149976 -298.74972)
		(end 69.624956 -299.224954)
		(width 0.249936)
		(layer "F.Cu")
		(net "Net_481")
	)
	(via
		(at 69.624956 -299.224954)
		(size 0.4064)
		(drill 0.2032)
		(layers "F.Cu" "B.Cu")
		(net "Net_481")
	)
	(segment
		(start 70.099936 -303.499774)
		(end 70.574916 -303.974754)
		(width 0.249936)
		(layer "F.Cu")
		(net "Net_482")
	)
	(via
		(at 70.574916 -303.974754)
		(size 0.4064)
		(drill 0.2032)
		(layers "F.Cu" "B.Cu")
		(net "Net_482")
	)
	(segment
		(start 70.574916 -306.824888)
		(end 70.099936 -306.349908)
		(width 0.13208)
		(layer "F.Cu")
		(net "Net_484")
	)
	(via
		(at 70.574916 -306.824888)
		(size 0.4064)
		(drill 0.2032)
		(layers "F.Cu" "B.Cu")
		(net "Net_484")
	)
	(segment
		(start 49.1998 -287.349946)
		(end 48.72482 -286.874966)
		(width 0.13208)
		(layer "F.Cu")
		(net "Net_486")
	)
	(via
		(at 48.72482 -286.874966)
		(size 0.4064)
		(drill 0.2032)
		(layers "F.Cu" "B.Cu")
		(net "Net_486")
	)
	(segment
		(start 70.099936 -305.399948)
		(end 70.574916 -305.874928)
		(width 0.249936)
		(layer "F.Cu")
		(net "Net_488")
	)
	(via
		(at 70.574916 -305.874928)
		(size 0.4064)
		(drill 0.2032)
		(layers "F.Cu" "B.Cu")
		(net "Net_488")
	)
	(segment
		(start 49.1998 -288.299906)
		(end 48.72482 -287.824926)
		(width 0.13208)
		(layer "F.Cu")
		(net "Net_491")
	)
	(via
		(at 48.72482 -287.824926)
		(size 0.4064)
		(drill 0.2032)
		(layers "F.Cu" "B.Cu")
		(net "Net_491")
	)
	(segment
		(start 186.675014 -306.824888)
		(end 186.200034 -306.349908)
		(width 0.13208)
		(layer "F.Cu")
		(net "Net_495")
	)
	(via
		(at 186.675014 -306.824888)
		(size 0.4064)
		(drill 0.2032)
		(layers "F.Cu" "B.Cu")
		(net "Net_495")
	)
	(segment
		(start 186.200034 -304.449734)
		(end 186.675014 -304.924714)
		(width 0.249936)
		(layer "F.Cu")
		(net "Net_496")
	)
	(via
		(at 186.675014 -304.924714)
		(size 0.4064)
		(drill 0.2032)
		(layers "F.Cu" "B.Cu")
		(net "Net_496")
	)
	(segment
		(start 186.200034 -305.399948)
		(end 186.675014 -305.874928)
		(width 0.249936)
		(layer "F.Cu")
		(net "Net_497")
	)
	(via
		(at 186.675014 -305.874928)
		(size 0.4064)
		(drill 0.2032)
		(layers "F.Cu" "B.Cu")
		(net "Net_497")
	)
	(segment
		(start 165.299898 -288.299906)
		(end 164.824918 -287.824926)
		(width 0.13208)
		(layer "F.Cu")
		(net "Net_505")
	)
	(via
		(at 164.824918 -287.824926)
		(size 0.4064)
		(drill 0.2032)
		(layers "F.Cu" "B.Cu")
		(net "Net_505")
	)
	(segment
		(start 186.200034 -303.499774)
		(end 186.675014 -303.974754)
		(width 0.249936)
		(layer "F.Cu")
		(net "Net_508")
	)
	(via
		(at 186.675014 -303.974754)
		(size 0.4064)
		(drill 0.2032)
		(layers "F.Cu" "B.Cu")
		(net "Net_508")
	)
	(segment
		(start 185.250074 -298.74972)
		(end 185.725054 -299.224954)
		(width 0.249936)
		(layer "F.Cu")
		(net "Net_509")
	)
	(via
		(at 185.725054 -299.224954)
		(size 0.4064)
		(drill 0.2032)
		(layers "F.Cu" "B.Cu")
		(net "Net_509")
	)
	(segment
		(start 165.299898 -287.349946)
		(end 164.824918 -286.874966)
		(width 0.13208)
		(layer "F.Cu")
		(net "Net_510")
	)
	(via
		(at 164.824918 -286.874966)
		(size 0.4064)
		(drill 0.2032)
		(layers "F.Cu" "B.Cu")
		(net "Net_510")
	)
	(segment
		(start 302.299878 -305.399948)
		(end 302.774858 -305.874928)
		(width 0.249936)
		(layer "F.Cu")
		(net "Net_513")
	)
	(via
		(at 302.774858 -305.874928)
		(size 0.4064)
		(drill 0.2032)
		(layers "F.Cu" "B.Cu")
		(net "Net_513")
	)
	(segment
		(start 302.774858 -306.824888)
		(end 302.299878 -306.349908)
		(width 0.13208)
		(layer "F.Cu")
		(net "Net_517")
	)
	(via
		(at 302.774858 -306.824888)
		(size 0.4064)
		(drill 0.2032)
		(layers "F.Cu" "B.Cu")
		(net "Net_517")
	)
	(segment
		(start 281.399742 -288.299906)
		(end 280.924762 -287.824926)
		(width 0.13208)
		(layer "F.Cu")
		(net "Net_519")
	)
	(via
		(at 280.924762 -287.824926)
		(size 0.4064)
		(drill 0.2032)
		(layers "F.Cu" "B.Cu")
		(net "Net_519")
	)
	(segment
		(start 281.399742 -287.349946)
		(end 280.924762 -286.874966)
		(width 0.13208)
		(layer "F.Cu")
		(net "Net_521")
	)
	(via
		(at 280.924762 -286.874966)
		(size 0.4064)
		(drill 0.2032)
		(layers "F.Cu" "B.Cu")
		(net "Net_521")
	)
	(segment
		(start 302.299878 -304.449734)
		(end 302.774858 -304.924714)
		(width 0.249936)
		(layer "F.Cu")
		(net "Net_522")
	)
	(via
		(at 302.774858 -304.924714)
		(size 0.4064)
		(drill 0.2032)
		(layers "F.Cu" "B.Cu")
		(net "Net_522")
	)
	(segment
		(start 302.299878 -303.499774)
		(end 302.774858 -303.974754)
		(width 0.249936)
		(layer "F.Cu")
		(net "Net_523")
	)
	(via
		(at 302.774858 -303.974754)
		(size 0.4064)
		(drill 0.2032)
		(layers "F.Cu" "B.Cu")
		(net "Net_523")
	)
	(segment
		(start 301.349918 -298.74972)
		(end 301.824898 -299.224954)
		(width 0.249936)
		(layer "F.Cu")
		(net "Net_524")
	)
	(via
		(at 301.824898 -299.224954)
		(size 0.4064)
		(drill 0.2032)
		(layers "F.Cu" "B.Cu")
		(net "Net_524")
	)
	(segment
		(start 397.49984 -288.299906)
		(end 397.02486 -287.824926)
		(width 0.13208)
		(layer "F.Cu")
		(net "Net_527")
	)
	(via
		(at 397.02486 -287.824926)
		(size 0.4064)
		(drill 0.2032)
		(layers "F.Cu" "B.Cu")
		(net "Net_527")
	)
	(segment
		(start 418.399976 -304.449734)
		(end 418.874956 -304.924714)
		(width 0.249936)
		(layer "F.Cu")
		(net "Net_529")
	)
	(via
		(at 418.874956 -304.924714)
		(size 0.4064)
		(drill 0.2032)
		(layers "F.Cu" "B.Cu")
		(net "Net_529")
	)
	(segment
		(start 397.49984 -287.349946)
		(end 397.02486 -286.874966)
		(width 0.13208)
		(layer "F.Cu")
		(net "Net_530")
	)
	(via
		(at 397.02486 -286.874966)
		(size 0.4064)
		(drill 0.2032)
		(layers "F.Cu" "B.Cu")
		(net "Net_530")
	)
	(segment
		(start 417.450016 -298.74972)
		(end 417.924996 -299.224954)
		(width 0.249936)
		(layer "F.Cu")
		(net "Net_532")
	)
	(via
		(at 417.924996 -299.224954)
		(size 0.4064)
		(drill 0.2032)
		(layers "F.Cu" "B.Cu")
		(net "Net_532")
	)
	(segment
		(start 418.399976 -303.499774)
		(end 418.874956 -303.974754)
		(width 0.249936)
		(layer "F.Cu")
		(net "Net_533")
	)
	(via
		(at 418.874956 -303.974754)
		(size 0.4064)
		(drill 0.2032)
		(layers "F.Cu" "B.Cu")
		(net "Net_533")
	)
	(segment
		(start 418.399976 -305.399948)
		(end 418.874956 -305.874928)
		(width 0.249936)
		(layer "F.Cu")
		(net "Net_534")
	)
	(via
		(at 418.874956 -305.874928)
		(size 0.4064)
		(drill 0.2032)
		(layers "F.Cu" "B.Cu")
		(net "Net_534")
	)
	(segment
		(start 418.874956 -306.824888)
		(end 418.399976 -306.349908)
		(width 0.13208)
		(layer "F.Cu")
		(net "Net_538")
	)
	(via
		(at 418.874956 -306.824888)
		(size 0.4064)
		(drill 0.2032)
		(layers "F.Cu" "B.Cu")
		(net "Net_538")
	)
	(segment
		(start 448.328288 -403.624542)
		(end 447.802 -403.098254)
		(width 0.13208)
		(layer "F.Cu")
		(net "SMB_BIC_I2C6_MUX_THERMAL_R1_SCL")
	)
	(segment
		(start 448.643502 -401.370292)
		(end 448.643502 -402.256498)
		(width 0.13208)
		(layer "F.Cu")
		(net "SMB_BIC_I2C6_MUX_THERMAL_R1_SCL")
	)
	(segment
		(start 448.328288 -404.670768)
		(end 448.328288 -403.624542)
		(width 0.13208)
		(layer "F.Cu")
		(net "SMB_BIC_I2C6_MUX_THERMAL_R1_SCL")
	)
	(segment
		(start 448.643502 -402.256498)
		(end 448.29095 -402.60905)
		(width 0.13208)
		(layer "F.Cu")
		(net "SMB_BIC_I2C6_MUX_THERMAL_R1_SCL")
	)
	(segment
		(start 448.29095 -402.60905)
		(end 447.802 -402.60905)
		(width 0.13208)
		(layer "F.Cu")
		(net "SMB_BIC_I2C6_MUX_THERMAL_R1_SCL")
	)
	(segment
		(start 447.802 -403.098254)
		(end 447.802 -402.60905)
		(width 0.13208)
		(layer "F.Cu")
		(net "SMB_BIC_I2C6_MUX_THERMAL_R1_SCL")
	)
	(via
		(at 436.05577 -82.849466)
		(size 0.508)
		(drill 0.254)
		(layers "F.Cu" "B.Cu")
		(net "SMB_BIC_I2C6_MUX_THERMAL_R1_SCL")
	)
	(via
		(at 448.643502 -401.370292)
		(size 0.508)
		(drill 0.254)
		(layers "F.Cu" "B.Cu")
		(net "SMB_BIC_I2C6_MUX_THERMAL_R1_SCL")
	)
	(via
		(at 381.381 -81.534)
		(size 0.508)
		(drill 0.254)
		(layers "F.Cu" "B.Cu")
		(net "SMB_BIC_I2C6_MUX_THERMAL_R1_SCL")
	)
	(segment
		(start 380.4412 -83.1088)
		(end 379.633734 -83.1088)
		(width 0.13208)
		(layer "B.Cu")
		(net "SMB_BIC_I2C6_MUX_THERMAL_R1_SCL")
	)
	(segment
		(start 381.381 -81.534)
		(end 380.873 -82.042)
		(width 0.13208)
		(layer "B.Cu")
		(net "SMB_BIC_I2C6_MUX_THERMAL_R1_SCL")
	)
	(segment
		(start 380.873 -82.677)
		(end 380.4412 -83.1088)
		(width 0.13208)
		(layer "B.Cu")
		(net "SMB_BIC_I2C6_MUX_THERMAL_R1_SCL")
	)
	(segment
		(start 380.873 -82.042)
		(end 380.873 -82.677)
		(width 0.13208)
		(layer "B.Cu")
		(net "SMB_BIC_I2C6_MUX_THERMAL_R1_SCL")
	)
	(segment
		(start 434.41366 -120.2309)
		(end 431.87366 -117.6909)
		(width 0.15494)
		(layer "In5.Cu")
		(net "SMB_BIC_I2C6_MUX_THERMAL_R1_SCL")
	)
	(segment
		(start 449.72986 -265.5951)
		(end 447.79946 -263.6647)
		(width 0.15494)
		(layer "In5.Cu")
		(net "SMB_BIC_I2C6_MUX_THERMAL_R1_SCL")
	)
	(segment
		(start 443.3824 -311.29224)
		(end 443.3824 -305.30546)
		(width 0.15494)
		(layer "In5.Cu")
		(net "SMB_BIC_I2C6_MUX_THERMAL_R1_SCL")
	)
	(segment
		(start 431.87366 -117.6909)
		(end 431.87366 -112.9157)
		(width 0.15494)
		(layer "In5.Cu")
		(net "SMB_BIC_I2C6_MUX_THERMAL_R1_SCL")
	)
	(segment
		(start 448.643502 -401.370292)
		(end 448.99326 -401.020534)
		(width 0.15494)
		(layer "In5.Cu")
		(net "SMB_BIC_I2C6_MUX_THERMAL_R1_SCL")
	)
	(segment
		(start 443.3824 -305.30546)
		(end 443.65926 -305.0286)
		(width 0.15494)
		(layer "In5.Cu")
		(net "SMB_BIC_I2C6_MUX_THERMAL_R1_SCL")
	)
	(segment
		(start 448.99326 -316.9031)
		(end 443.3824 -311.29224)
		(width 0.15494)
		(layer "In5.Cu")
		(net "SMB_BIC_I2C6_MUX_THERMAL_R1_SCL")
	)
	(segment
		(start 434.41366 -128.832864)
		(end 434.41366 -120.2309)
		(width 0.15494)
		(layer "In5.Cu")
		(net "SMB_BIC_I2C6_MUX_THERMAL_R1_SCL")
	)
	(segment
		(start 449.72986 -274.0279)
		(end 449.72986 -265.5951)
		(width 0.15494)
		(layer "In5.Cu")
		(net "SMB_BIC_I2C6_MUX_THERMAL_R1_SCL")
	)
	(segment
		(start 448.96786 -254.8763)
		(end 448.96786 -247.5865)
		(width 0.15494)
		(layer "In5.Cu")
		(net "SMB_BIC_I2C6_MUX_THERMAL_R1_SCL")
	)
	(segment
		(start 428.03826 -109.0803)
		(end 428.03826 -99.8347)
		(width 0.15494)
		(layer "In5.Cu")
		(net "SMB_BIC_I2C6_MUX_THERMAL_R1_SCL")
	)
	(segment
		(start 428.03826 -99.8347)
		(end 433.9082 -93.96476)
		(width 0.15494)
		(layer "In5.Cu")
		(net "SMB_BIC_I2C6_MUX_THERMAL_R1_SCL")
	)
	(segment
		(start 443.65926 -305.0286)
		(end 443.65926 -281.5209)
		(width 0.15494)
		(layer "In5.Cu")
		(net "SMB_BIC_I2C6_MUX_THERMAL_R1_SCL")
	)
	(segment
		(start 440.39282 -239.01146)
		(end 440.39282 -136.39546)
		(width 0.15494)
		(layer "In5.Cu")
		(net "SMB_BIC_I2C6_MUX_THERMAL_R1_SCL")
	)
	(segment
		(start 433.9082 -93.96476)
		(end 433.9082 -84.536788)
		(width 0.15494)
		(layer "In5.Cu")
		(net "SMB_BIC_I2C6_MUX_THERMAL_R1_SCL")
	)
	(segment
		(start 435.533292 -131.535932)
		(end 434.41366 -128.832864)
		(width 0.15494)
		(layer "In5.Cu")
		(net "SMB_BIC_I2C6_MUX_THERMAL_R1_SCL")
	)
	(segment
		(start 448.07886 -277.1013)
		(end 448.07886 -275.6789)
		(width 0.15494)
		(layer "In5.Cu")
		(net "SMB_BIC_I2C6_MUX_THERMAL_R1_SCL")
	)
	(segment
		(start 448.96786 -247.5865)
		(end 440.39282 -239.01146)
		(width 0.15494)
		(layer "In5.Cu")
		(net "SMB_BIC_I2C6_MUX_THERMAL_R1_SCL")
	)
	(segment
		(start 447.79946 -263.6647)
		(end 447.79946 -256.0447)
		(width 0.15494)
		(layer "In5.Cu")
		(net "SMB_BIC_I2C6_MUX_THERMAL_R1_SCL")
	)
	(segment
		(start 448.07886 -275.6789)
		(end 449.72986 -274.0279)
		(width 0.15494)
		(layer "In5.Cu")
		(net "SMB_BIC_I2C6_MUX_THERMAL_R1_SCL")
	)
	(segment
		(start 448.99326 -401.020534)
		(end 448.99326 -316.9031)
		(width 0.15494)
		(layer "In5.Cu")
		(net "SMB_BIC_I2C6_MUX_THERMAL_R1_SCL")
	)
	(segment
		(start 440.39282 -136.39546)
		(end 435.533292 -131.535932)
		(width 0.15494)
		(layer "In5.Cu")
		(net "SMB_BIC_I2C6_MUX_THERMAL_R1_SCL")
	)
	(segment
		(start 447.79946 -256.0447)
		(end 448.96786 -254.8763)
		(width 0.15494)
		(layer "In5.Cu")
		(net "SMB_BIC_I2C6_MUX_THERMAL_R1_SCL")
	)
	(segment
		(start 435.595522 -82.849466)
		(end 436.05577 -82.849466)
		(width 0.15494)
		(layer "In5.Cu")
		(net "SMB_BIC_I2C6_MUX_THERMAL_R1_SCL")
	)
	(segment
		(start 433.9082 -84.536788)
		(end 435.595522 -82.849466)
		(width 0.15494)
		(layer "In5.Cu")
		(net "SMB_BIC_I2C6_MUX_THERMAL_R1_SCL")
	)
	(segment
		(start 431.87366 -112.9157)
		(end 428.03826 -109.0803)
		(width 0.15494)
		(layer "In5.Cu")
		(net "SMB_BIC_I2C6_MUX_THERMAL_R1_SCL")
	)
	(segment
		(start 443.65926 -281.5209)
		(end 448.07886 -277.1013)
		(width 0.15494)
		(layer "In5.Cu")
		(net "SMB_BIC_I2C6_MUX_THERMAL_R1_SCL")
	)
	(segment
		(start 397.56842 -83.183984)
		(end 396.709392 -83.183984)
		(width 0.15494)
		(layer "In15.Cu")
		(net "SMB_BIC_I2C6_MUX_THERMAL_R1_SCL")
	)
	(segment
		(start 419.205918 -81.901538)
		(end 418.544756 -81.240376)
		(width 0.15494)
		(layer "In15.Cu")
		(net "SMB_BIC_I2C6_MUX_THERMAL_R1_SCL")
	)
	(segment
		(start 429.703992 -82.849466)
		(end 428.221394 -81.366868)
		(width 0.15494)
		(layer "In15.Cu")
		(net "SMB_BIC_I2C6_MUX_THERMAL_R1_SCL")
	)
	(segment
		(start 428.221394 -81.366868)
		(end 422.722802 -81.366868)
		(width 0.15494)
		(layer "In15.Cu")
		(net "SMB_BIC_I2C6_MUX_THERMAL_R1_SCL")
	)
	(segment
		(start 396.709392 -83.183984)
		(end 396.136368 -83.757008)
		(width 0.15494)
		(layer "In15.Cu")
		(net "SMB_BIC_I2C6_MUX_THERMAL_R1_SCL")
	)
	(segment
		(start 396.136368 -83.757008)
		(end 392.929872 -83.757008)
		(width 0.15494)
		(layer "In15.Cu")
		(net "SMB_BIC_I2C6_MUX_THERMAL_R1_SCL")
	)
	(segment
		(start 392.929872 -83.757008)
		(end 391.883392 -82.710528)
		(width 0.15494)
		(layer "In15.Cu")
		(net "SMB_BIC_I2C6_MUX_THERMAL_R1_SCL")
	)
	(segment
		(start 383.446528 -82.710528)
		(end 382.27 -81.534)
		(width 0.15494)
		(layer "In15.Cu")
		(net "SMB_BIC_I2C6_MUX_THERMAL_R1_SCL")
	)
	(segment
		(start 422.722802 -81.366868)
		(end 422.188132 -81.901538)
		(width 0.15494)
		(layer "In15.Cu")
		(net "SMB_BIC_I2C6_MUX_THERMAL_R1_SCL")
	)
	(segment
		(start 418.544756 -81.240376)
		(end 399.512028 -81.240376)
		(width 0.15494)
		(layer "In15.Cu")
		(net "SMB_BIC_I2C6_MUX_THERMAL_R1_SCL")
	)
	(segment
		(start 382.27 -81.534)
		(end 381.381 -81.534)
		(width 0.15494)
		(layer "In15.Cu")
		(net "SMB_BIC_I2C6_MUX_THERMAL_R1_SCL")
	)
	(segment
		(start 436.05577 -82.849466)
		(end 429.703992 -82.849466)
		(width 0.15494)
		(layer "In15.Cu")
		(net "SMB_BIC_I2C6_MUX_THERMAL_R1_SCL")
	)
	(segment
		(start 422.188132 -81.901538)
		(end 419.205918 -81.901538)
		(width 0.15494)
		(layer "In15.Cu")
		(net "SMB_BIC_I2C6_MUX_THERMAL_R1_SCL")
	)
	(segment
		(start 391.883392 -82.710528)
		(end 383.446528 -82.710528)
		(width 0.15494)
		(layer "In15.Cu")
		(net "SMB_BIC_I2C6_MUX_THERMAL_R1_SCL")
	)
	(segment
		(start 399.512028 -81.240376)
		(end 397.56842 -83.183984)
		(width 0.15494)
		(layer "In15.Cu")
		(net "SMB_BIC_I2C6_MUX_THERMAL_R1_SCL")
	)
	(segment
		(start 409.415488 -86.424008)
		(end 410.647388 -86.424008)
		(width 0.13208)
		(layer "F.Cu")
		(net "SMB_CLK_ISO_R_SCL_R1")
	)
	(segment
		(start 227.76053 -134.811262)
		(end 227.47605 -134.526782)
		(width 0.13208)
		(layer "F.Cu")
		(net "SMB_CLK_ISO_R_SCL_R1")
	)
	(segment
		(start 245.960392 -102.201726)
		(end 246.566944 -102.201726)
		(width 0.13208)
		(layer "F.Cu")
		(net "SMB_CLK_ISO_R_SCL_R1")
	)
	(segment
		(start 413.906462 -83.583018)
		(end 412.986982 -83.583018)
		(width 0.13208)
		(layer "F.Cu")
		(net "SMB_CLK_ISO_R_SCL_R1")
	)
	(segment
		(start 247.528588 -107.520232)
		(end 245.989348 -109.059472)
		(width 0.13208)
		(layer "F.Cu")
		(net "SMB_CLK_ISO_R_SCL_R1")
	)
	(segment
		(start 246.566944 -102.201726)
		(end 247.528588 -103.16337)
		(width 0.13208)
		(layer "F.Cu")
		(net "SMB_CLK_ISO_R_SCL_R1")
	)
	(segment
		(start 410.647388 -85.922612)
		(end 410.647388 -86.424008)
		(width 0.13208)
		(layer "F.Cu")
		(net "SMB_CLK_ISO_R_SCL_R1")
	)
	(segment
		(start 247.528588 -103.16337)
		(end 247.528588 -107.520232)
		(width 0.13208)
		(layer "F.Cu")
		(net "SMB_CLK_ISO_R_SCL_R1")
	)
	(segment
		(start 248.419874 -87.150448)
		(end 247.810274 -87.150448)
		(width 0.13208)
		(layer "F.Cu")
		(net "SMB_CLK_ISO_R_SCL_R1")
	)
	(segment
		(start 228.48062 -134.811262)
		(end 227.76053 -134.811262)
		(width 0.13208)
		(layer "F.Cu")
		(net "SMB_CLK_ISO_R_SCL_R1")
	)
	(segment
		(start 412.986982 -83.583018)
		(end 410.647388 -85.922612)
		(width 0.13208)
		(layer "F.Cu")
		(net "SMB_CLK_ISO_R_SCL_R1")
	)
	(via
		(at 228.48062 -134.811262)
		(size 0.508)
		(drill 0.254)
		(layers "F.Cu" "B.Cu")
		(net "SMB_CLK_ISO_R_SCL_R1")
	)
	(via
		(at 413.906462 -83.583018)
		(size 0.508)
		(drill 0.254)
		(layers "F.Cu" "B.Cu")
		(net "SMB_CLK_ISO_R_SCL_R1")
	)
	(via
		(at 279.10663 -89.764616)
		(size 0.508)
		(drill 0.254)
		(layers "F.Cu" "B.Cu")
		(net "SMB_CLK_ISO_R_SCL_R1")
	)
	(via
		(at 245.960392 -102.201726)
		(size 0.508)
		(drill 0.254)
		(layers "F.Cu" "B.Cu")
		(net "SMB_CLK_ISO_R_SCL_R1")
	)
	(via
		(at 247.810274 -87.150448)
		(size 0.508)
		(drill 0.254)
		(layers "F.Cu" "B.Cu")
		(net "SMB_CLK_ISO_R_SCL_R1")
	)
	(via
		(at 245.989348 -109.059472)
		(size 0.508)
		(drill 0.254)
		(layers "F.Cu" "B.Cu")
		(net "SMB_CLK_ISO_R_SCL_R1")
	)
	(segment
		(start 240.88852 -120.070626)
		(end 240.88852 -114.1603)
		(width 0.15494)
		(layer "In5.Cu")
		(net "SMB_CLK_ISO_R_SCL_R1")
	)
	(segment
		(start 246.725948 -86.866222)
		(end 245.960392 -87.631778)
		(width 0.15494)
		(layer "In5.Cu")
		(net "SMB_CLK_ISO_R_SCL_R1")
	)
	(segment
		(start 247.810274 -87.150448)
		(end 247.526048 -86.866222)
		(width 0.15494)
		(layer "In5.Cu")
		(net "SMB_CLK_ISO_R_SCL_R1")
	)
	(segment
		(start 228.48062 -134.811262)
		(end 228.14788 -134.478522)
		(width 0.15494)
		(layer "In5.Cu")
		(net "SMB_CLK_ISO_R_SCL_R1")
	)
	(segment
		(start 228.14788 -134.478522)
		(end 228.14788 -132.811266)
		(width 0.15494)
		(layer "In5.Cu")
		(net "SMB_CLK_ISO_R_SCL_R1")
	)
	(segment
		(start 240.88852 -114.1603)
		(end 245.989348 -109.059472)
		(width 0.15494)
		(layer "In5.Cu")
		(net "SMB_CLK_ISO_R_SCL_R1")
	)
	(segment
		(start 228.14788 -132.811266)
		(end 240.88852 -120.070626)
		(width 0.15494)
		(layer "In5.Cu")
		(net "SMB_CLK_ISO_R_SCL_R1")
	)
	(segment
		(start 247.526048 -86.866222)
		(end 246.725948 -86.866222)
		(width 0.15494)
		(layer "In5.Cu")
		(net "SMB_CLK_ISO_R_SCL_R1")
	)
	(segment
		(start 245.960392 -87.631778)
		(end 245.960392 -102.201726)
		(width 0.15494)
		(layer "In5.Cu")
		(net "SMB_CLK_ISO_R_SCL_R1")
	)
	(segment
		(start 264.693654 -90.4494)
		(end 266.60856 -88.534494)
		(width 0.15494)
		(layer "In9.Cu")
		(net "SMB_CLK_ISO_R_SCL_R1")
	)
	(segment
		(start 248.636536 -89.565734)
		(end 249.520202 -90.4494)
		(width 0.15494)
		(layer "In9.Cu")
		(net "SMB_CLK_ISO_R_SCL_R1")
	)
	(segment
		(start 248.636536 -87.97671)
		(end 248.636536 -89.565734)
		(width 0.15494)
		(layer "In9.Cu")
		(net "SMB_CLK_ISO_R_SCL_R1")
	)
	(segment
		(start 266.60856 -88.534494)
		(end 274.284694 -88.534494)
		(width 0.15494)
		(layer "In9.Cu")
		(net "SMB_CLK_ISO_R_SCL_R1")
	)
	(segment
		(start 249.520202 -90.4494)
		(end 264.693654 -90.4494)
		(width 0.15494)
		(layer "In9.Cu")
		(net "SMB_CLK_ISO_R_SCL_R1")
	)
	(segment
		(start 276.072092 -90.321892)
		(end 278.549354 -90.321892)
		(width 0.15494)
		(layer "In9.Cu")
		(net "SMB_CLK_ISO_R_SCL_R1")
	)
	(segment
		(start 278.549354 -90.321892)
		(end 279.10663 -89.764616)
		(width 0.15494)
		(layer "In9.Cu")
		(net "SMB_CLK_ISO_R_SCL_R1")
	)
	(segment
		(start 274.284694 -88.534494)
		(end 276.072092 -90.321892)
		(width 0.15494)
		(layer "In9.Cu")
		(net "SMB_CLK_ISO_R_SCL_R1")
	)
	(segment
		(start 247.810274 -87.150448)
		(end 248.636536 -87.97671)
		(width 0.15494)
		(layer "In9.Cu")
		(net "SMB_CLK_ISO_R_SCL_R1")
	)
	(segment
		(start 408.576526 -87.9856)
		(end 412.763208 -83.798918)
		(width 0.15494)
		(layer "In13.Cu")
		(net "SMB_CLK_ISO_R_SCL_R1")
	)
	(segment
		(start 396.315946 -87.9856)
		(end 408.576526 -87.9856)
		(width 0.15494)
		(layer "In13.Cu")
		(net "SMB_CLK_ISO_R_SCL_R1")
	)
	(segment
		(start 395.417548 -87.087202)
		(end 396.315946 -87.9856)
		(width 0.15494)
		(layer "In13.Cu")
		(net "SMB_CLK_ISO_R_SCL_R1")
	)
	(segment
		(start 326.03313 -89.25433)
		(end 327.9648 -91.186)
		(width 0.15494)
		(layer "In13.Cu")
		(net "SMB_CLK_ISO_R_SCL_R1")
	)
	(segment
		(start 279.10663 -89.764616)
		(end 279.616916 -89.25433)
		(width 0.15494)
		(layer "In13.Cu")
		(net "SMB_CLK_ISO_R_SCL_R1")
	)
	(segment
		(start 391.299954 -85.451442)
		(end 392.120882 -85.451442)
		(width 0.15494)
		(layer "In13.Cu")
		(net "SMB_CLK_ISO_R_SCL_R1")
	)
	(segment
		(start 279.616916 -89.25433)
		(end 326.03313 -89.25433)
		(width 0.15494)
		(layer "In13.Cu")
		(net "SMB_CLK_ISO_R_SCL_R1")
	)
	(segment
		(start 336.042 -94.90583)
		(end 338.82457 -97.6884)
		(width 0.15494)
		(layer "In13.Cu")
		(net "SMB_CLK_ISO_R_SCL_R1")
	)
	(segment
		(start 353.477068 -97.6884)
		(end 363.662468 -87.503)
		(width 0.15494)
		(layer "In13.Cu")
		(net "SMB_CLK_ISO_R_SCL_R1")
	)
	(segment
		(start 371.409976 -85.586824)
		(end 372.259352 -84.737448)
		(width 0.15494)
		(layer "In13.Cu")
		(net "SMB_CLK_ISO_R_SCL_R1")
	)
	(segment
		(start 375.095516 -84.7344)
		(end 375.096786 -84.73567)
		(width 0.15494)
		(layer "In13.Cu")
		(net "SMB_CLK_ISO_R_SCL_R1")
	)
	(segment
		(start 336.042 -93.015562)
		(end 336.042 -94.90583)
		(width 0.15494)
		(layer "In13.Cu")
		(net "SMB_CLK_ISO_R_SCL_R1")
	)
	(segment
		(start 393.756642 -87.087202)
		(end 395.417548 -87.087202)
		(width 0.15494)
		(layer "In13.Cu")
		(net "SMB_CLK_ISO_R_SCL_R1")
	)
	(segment
		(start 412.763208 -83.798918)
		(end 412.79191 -83.798918)
		(width 0.15494)
		(layer "In13.Cu")
		(net "SMB_CLK_ISO_R_SCL_R1")
	)
	(segment
		(start 338.82457 -97.6884)
		(end 353.477068 -97.6884)
		(width 0.15494)
		(layer "In13.Cu")
		(net "SMB_CLK_ISO_R_SCL_R1")
	)
	(segment
		(start 368.434366 -85.979)
		(end 368.440716 -85.98535)
		(width 0.15494)
		(layer "In13.Cu")
		(net "SMB_CLK_ISO_R_SCL_R1")
	)
	(segment
		(start 375.499376 -84.7344)
		(end 379.49124 -84.7344)
		(width 0.15494)
		(layer "In13.Cu")
		(net "SMB_CLK_ISO_R_SCL_R1")
	)
	(segment
		(start 379.704346 -84.947506)
		(end 390.796018 -84.947506)
		(width 0.15494)
		(layer "In13.Cu")
		(net "SMB_CLK_ISO_R_SCL_R1")
	)
	(segment
		(start 368.440716 -85.98535)
		(end 368.842036 -85.98535)
		(width 0.15494)
		(layer "In13.Cu")
		(net "SMB_CLK_ISO_R_SCL_R1")
	)
	(segment
		(start 363.662468 -87.503)
		(end 365.0488 -87.503)
		(width 0.15494)
		(layer "In13.Cu")
		(net "SMB_CLK_ISO_R_SCL_R1")
	)
	(segment
		(start 373.42953 -84.737448)
		(end 373.432578 -84.7344)
		(width 0.15494)
		(layer "In13.Cu")
		(net "SMB_CLK_ISO_R_SCL_R1")
	)
	(segment
		(start 412.79191 -83.798918)
		(end 413.00781 -83.583018)
		(width 0.15494)
		(layer "In13.Cu")
		(net "SMB_CLK_ISO_R_SCL_R1")
	)
	(segment
		(start 365.0488 -87.503)
		(end 366.5728 -85.979)
		(width 0.15494)
		(layer "In13.Cu")
		(net "SMB_CLK_ISO_R_SCL_R1")
	)
	(segment
		(start 379.49124 -84.7344)
		(end 379.704346 -84.947506)
		(width 0.15494)
		(layer "In13.Cu")
		(net "SMB_CLK_ISO_R_SCL_R1")
	)
	(segment
		(start 375.498106 -84.73567)
		(end 375.499376 -84.7344)
		(width 0.15494)
		(layer "In13.Cu")
		(net "SMB_CLK_ISO_R_SCL_R1")
	)
	(segment
		(start 366.5728 -85.979)
		(end 368.434366 -85.979)
		(width 0.15494)
		(layer "In13.Cu")
		(net "SMB_CLK_ISO_R_SCL_R1")
	)
	(segment
		(start 372.259352 -84.737448)
		(end 373.42953 -84.737448)
		(width 0.15494)
		(layer "In13.Cu")
		(net "SMB_CLK_ISO_R_SCL_R1")
	)
	(segment
		(start 375.096786 -84.73567)
		(end 375.498106 -84.73567)
		(width 0.15494)
		(layer "In13.Cu")
		(net "SMB_CLK_ISO_R_SCL_R1")
	)
	(segment
		(start 327.9648 -91.186)
		(end 334.212438 -91.186)
		(width 0.15494)
		(layer "In13.Cu")
		(net "SMB_CLK_ISO_R_SCL_R1")
	)
	(segment
		(start 390.796018 -84.947506)
		(end 391.299954 -85.451442)
		(width 0.15494)
		(layer "In13.Cu")
		(net "SMB_CLK_ISO_R_SCL_R1")
	)
	(segment
		(start 413.00781 -83.583018)
		(end 413.906462 -83.583018)
		(width 0.15494)
		(layer "In13.Cu")
		(net "SMB_CLK_ISO_R_SCL_R1")
	)
	(segment
		(start 368.842036 -85.98535)
		(end 369.240562 -85.586824)
		(width 0.15494)
		(layer "In13.Cu")
		(net "SMB_CLK_ISO_R_SCL_R1")
	)
	(segment
		(start 373.432578 -84.7344)
		(end 375.095516 -84.7344)
		(width 0.15494)
		(layer "In13.Cu")
		(net "SMB_CLK_ISO_R_SCL_R1")
	)
	(segment
		(start 392.120882 -85.451442)
		(end 393.756642 -87.087202)
		(width 0.15494)
		(layer "In13.Cu")
		(net "SMB_CLK_ISO_R_SCL_R1")
	)
	(segment
		(start 334.212438 -91.186)
		(end 336.042 -93.015562)
		(width 0.15494)
		(layer "In13.Cu")
		(net "SMB_CLK_ISO_R_SCL_R1")
	)
	(segment
		(start 369.240562 -85.586824)
		(end 371.409976 -85.586824)
		(width 0.15494)
		(layer "In13.Cu")
		(net "SMB_CLK_ISO_R_SCL_R1")
	)
	(segment
		(start 339.693758 -224.786952)
		(end 339.293962 -225.186748)
		(width 0.13208)
		(layer "F.Cu")
		(net "JTAG_FPGA_R_TDO")
	)
	(via
		(at 339.293962 -225.186748)
		(size 0.4572)
		(drill 0.254)
		(layers "F.Cu" "B.Cu")
		(net "JTAG_FPGA_R_TDO")
	)
	(via
		(at 323.696584 -220.191584)
		(size 0.508)
		(drill 0.254)
		(layers "F.Cu" "B.Cu")
		(net "JTAG_FPGA_R_TDO")
	)
	(segment
		(start 322.984622 -220.356938)
		(end 322.512182 -220.356938)
		(width 0.13208)
		(layer "B.Cu")
		(net "JTAG_FPGA_R_TDO")
	)
	(segment
		(start 323.696584 -220.191584)
		(end 323.149976 -220.191584)
		(width 0.13208)
		(layer "B.Cu")
		(net "JTAG_FPGA_R_TDO")
	)
	(segment
		(start 323.149976 -220.191584)
		(end 322.984622 -220.356938)
		(width 0.13208)
		(layer "B.Cu")
		(net "JTAG_FPGA_R_TDO")
	)
	(segment
		(start 339.293962 -225.186748)
		(end 338.896452 -225.584258)
		(width 0.0889)
		(layer "In13.Cu")
		(net "JTAG_FPGA_R_TDO")
	)
	(segment
		(start 328.34834 -221.92107)
		(end 328.34707 -221.9198)
		(width 0.15494)
		(layer "In13.Cu")
		(net "JTAG_FPGA_R_TDO")
	)
	(segment
		(start 327.445624 -221.079822)
		(end 325.930768 -221.079822)
		(width 0.15494)
		(layer "In13.Cu")
		(net "JTAG_FPGA_R_TDO")
	)
	(segment
		(start 338.896452 -225.584258)
		(end 333.755746 -225.584258)
		(width 0.0889)
		(layer "In13.Cu")
		(net "JTAG_FPGA_R_TDO")
	)
	(segment
		(start 325.930768 -221.079822)
		(end 325.04253 -220.191584)
		(width 0.15494)
		(layer "In13.Cu")
		(net "JTAG_FPGA_R_TDO")
	)
	(segment
		(start 331.550264 -224.682558)
		(end 328.787506 -221.9198)
		(width 0.15494)
		(layer "In13.Cu")
		(net "JTAG_FPGA_R_TDO")
	)
	(segment
		(start 325.04253 -220.191584)
		(end 323.696584 -220.191584)
		(width 0.15494)
		(layer "In13.Cu")
		(net "JTAG_FPGA_R_TDO")
	)
	(segment
		(start 332.854046 -224.682558)
		(end 331.550264 -224.682558)
		(width 0.15494)
		(layer "In13.Cu")
		(net "JTAG_FPGA_R_TDO")
	)
	(segment
		(start 333.755746 -225.584258)
		(end 332.854046 -224.682558)
		(width 0.15494)
		(layer "In13.Cu")
		(net "JTAG_FPGA_R_TDO")
	)
	(segment
		(start 328.75093 -221.9198)
		(end 328.74966 -221.92107)
		(width 0.15494)
		(layer "In13.Cu")
		(net "JTAG_FPGA_R_TDO")
	)
	(segment
		(start 328.787506 -221.9198)
		(end 328.75093 -221.9198)
		(width 0.15494)
		(layer "In13.Cu")
		(net "JTAG_FPGA_R_TDO")
	)
	(segment
		(start 328.34707 -221.9198)
		(end 328.285602 -221.9198)
		(width 0.15494)
		(layer "In13.Cu")
		(net "JTAG_FPGA_R_TDO")
	)
	(segment
		(start 328.74966 -221.92107)
		(end 328.34834 -221.92107)
		(width 0.15494)
		(layer "In13.Cu")
		(net "JTAG_FPGA_R_TDO")
	)
	(segment
		(start 328.285602 -221.9198)
		(end 327.445624 -221.079822)
		(width 0.15494)
		(layer "In13.Cu")
		(net "JTAG_FPGA_R_TDO")
	)
	(segment
		(start 408.615388 -87.440008)
		(end 408.615388 -87.305388)
		(width 0.13208)
		(layer "F.Cu")
		(net "SMB_CLK_ISO_SDA")
	)
	(segment
		(start 405.613362 -86.580726)
		(end 406.289002 -86.580726)
		(width 0.13208)
		(layer "F.Cu")
		(net "SMB_CLK_ISO_SDA")
	)
	(segment
		(start 406.382728 -86.487)
		(end 406.289002 -86.580726)
		(width 0.13208)
		(layer "F.Cu")
		(net "SMB_CLK_ISO_SDA")
	)
	(segment
		(start 405.157686 -87.036402)
		(end 405.613362 -86.580726)
		(width 0.13208)
		(layer "F.Cu")
		(net "SMB_CLK_ISO_SDA")
	)
	(segment
		(start 407.797 -86.487)
		(end 406.382728 -86.487)
		(width 0.13208)
		(layer "F.Cu")
		(net "SMB_CLK_ISO_SDA")
	)
	(segment
		(start 408.615388 -87.305388)
		(end 407.797 -86.487)
		(width 0.13208)
		(layer "F.Cu")
		(net "SMB_CLK_ISO_SDA")
	)
	(via
		(at 405.157686 -87.036402)
		(size 0.508)
		(drill 0.254)
		(layers "F.Cu" "B.Cu")
		(net "SMB_CLK_ISO_SDA")
	)
	(segment
		(start 403.723094 -87.036402)
		(end 403.50059 -86.813898)
		(width 0.13208)
		(layer "B.Cu")
		(net "SMB_CLK_ISO_SDA")
	)
	(segment
		(start 405.157686 -87.036402)
		(end 403.723094 -87.036402)
		(width 0.13208)
		(layer "B.Cu")
		(net "SMB_CLK_ISO_SDA")
	)
	(segment
		(start 405.147526 -85.689694)
		(end 405.388318 -85.930486)
		(width 0.13208)
		(layer "F.Cu")
		(net "SMB_CLK_ISO_SCL")
	)
	(segment
		(start 408.121866 -85.930486)
		(end 406.289002 -85.930486)
		(width 0.13208)
		(layer "F.Cu")
		(net "SMB_CLK_ISO_SCL")
	)
	(segment
		(start 408.615388 -86.424008)
		(end 408.121866 -85.930486)
		(width 0.13208)
		(layer "F.Cu")
		(net "SMB_CLK_ISO_SCL")
	)
	(segment
		(start 405.388318 -85.930486)
		(end 406.289002 -85.930486)
		(width 0.13208)
		(layer "F.Cu")
		(net "SMB_CLK_ISO_SCL")
	)
	(via
		(at 405.147526 -85.689694)
		(size 0.508)
		(drill 0.254)
		(layers "F.Cu" "B.Cu")
		(net "SMB_CLK_ISO_SCL")
	)
	(segment
		(start 403.608794 -85.689694)
		(end 403.50059 -85.797898)
		(width 0.13208)
		(layer "B.Cu")
		(net "SMB_CLK_ISO_SCL")
	)
	(segment
		(start 405.147526 -85.689694)
		(end 403.608794 -85.689694)
		(width 0.13208)
		(layer "B.Cu")
		(net "SMB_CLK_ISO_SCL")
	)
	(segment
		(start 401.188174 -87.305642)
		(end 401.085558 -87.408258)
		(width 0.13208)
		(layer "F.Cu")
		(net "CLK_ISO_EN")
	)
	(segment
		(start 399.99285 -87.408258)
		(end 399.99285 -86.7664)
		(width 0.13208)
		(layer "F.Cu")
		(net "CLK_ISO_EN")
	)
	(segment
		(start 401.085558 -87.408258)
		(end 399.99285 -87.408258)
		(width 0.13208)
		(layer "F.Cu")
		(net "CLK_ISO_EN")
	)
	(segment
		(start 401.938998 -87.305642)
		(end 401.188174 -87.305642)
		(width 0.13208)
		(layer "F.Cu")
		(net "CLK_ISO_EN")
	)
	(via
		(at 399.99285 -87.408258)
		(size 0.508)
		(drill 0.254)
		(layers "F.Cu" "B.Cu")
		(net "CLK_ISO_EN")
	)
	(segment
		(start 320.929 -85.344)
		(end 320.31305 -85.344)
		(width 0.13208)
		(layer "F.Cu")
		(net "CB_ISO_EN")
	)
	(segment
		(start 321.056 -85.344)
		(end 320.929 -85.344)
		(width 0.13208)
		(layer "F.Cu")
		(net "CB_ISO_EN")
	)
	(segment
		(start 321.073526 -85.361526)
		(end 321.056 -85.344)
		(width 0.13208)
		(layer "F.Cu")
		(net "CB_ISO_EN")
	)
	(segment
		(start 322.146676 -85.361526)
		(end 321.073526 -85.361526)
		(width 0.13208)
		(layer "F.Cu")
		(net "CB_ISO_EN")
	)
	(via
		(at 320.929 -85.344)
		(size 0.508)
		(drill 0.254)
		(layers "F.Cu" "B.Cu")
		(net "CB_ISO_EN")
	)
	(segment
		(start 326.49668 -84.63661)
		(end 327.46061 -84.63661)
		(width 0.13208)
		(layer "F.Cu")
		(net "SMB_ISO_CB_SDA")
	)
	(segment
		(start 325.03237 -87.014304)
		(end 325.03237 -84.903564)
		(width 0.13208)
		(layer "F.Cu")
		(net "SMB_ISO_CB_SDA")
	)
	(segment
		(start 325.299324 -84.63661)
		(end 326.49668 -84.63661)
		(width 0.13208)
		(layer "F.Cu")
		(net "SMB_ISO_CB_SDA")
	)
	(segment
		(start 329.03795 -84.709)
		(end 328.65695 -85.09)
		(width 0.13208)
		(layer "F.Cu")
		(net "SMB_ISO_CB_SDA")
	)
	(segment
		(start 329.211178 -85.167724)
		(end 329.651106 -85.167724)
		(width 0.13208)
		(layer "F.Cu")
		(net "SMB_ISO_CB_SDA")
	)
	(segment
		(start 329.651106 -85.167724)
		(end 329.83805 -85.354668)
		(width 0.13208)
		(layer "F.Cu")
		(net "SMB_ISO_CB_SDA")
	)
	(segment
		(start 329.03795 -84.709)
		(end 329.03795 -84.994496)
		(width 0.13208)
		(layer "F.Cu")
		(net "SMB_ISO_CB_SDA")
	)
	(segment
		(start 328.65695 -85.09)
		(end 328.295 -85.09)
		(width 0.13208)
		(layer "F.Cu")
		(net "SMB_ISO_CB_SDA")
	)
	(segment
		(start 329.03795 -84.994496)
		(end 329.211178 -85.167724)
		(width 0.13208)
		(layer "F.Cu")
		(net "SMB_ISO_CB_SDA")
	)
	(segment
		(start 329.83805 -85.354668)
		(end 329.83805 -85.598)
		(width 0.13208)
		(layer "F.Cu")
		(net "SMB_ISO_CB_SDA")
	)
	(segment
		(start 325.03237 -84.903564)
		(end 325.299324 -84.63661)
		(width 0.13208)
		(layer "F.Cu")
		(net "SMB_ISO_CB_SDA")
	)
	(segment
		(start 327.46061 -84.63661)
		(end 327.914 -85.09)
		(width 0.13208)
		(layer "F.Cu")
		(net "SMB_ISO_CB_SDA")
	)
	(segment
		(start 327.914 -85.09)
		(end 328.295 -85.09)
		(width 0.13208)
		(layer "F.Cu")
		(net "SMB_ISO_CB_SDA")
	)
	(via
		(at 328.295 -85.09)
		(size 0.508)
		(drill 0.254)
		(layers "F.Cu" "B.Cu")
		(net "SMB_ISO_CB_SDA")
	)
	(segment
		(start 325.13905 -85.09)
		(end 325.01205 -84.963)
		(width 0.13208)
		(layer "B.Cu")
		(net "SMB_ISO_CB_SDA")
	)
	(segment
		(start 328.295 -85.09)
		(end 325.13905 -85.09)
		(width 0.13208)
		(layer "B.Cu")
		(net "SMB_ISO_CB_SDA")
	)
	(segment
		(start 329.03795 -83.47964)
		(end 329.160124 -83.357466)
		(width 0.13208)
		(layer "F.Cu")
		(net "SMB_ISO_CB_SCL")
	)
	(segment
		(start 326.49668 -83.98637)
		(end 327.49363 -83.98637)
		(width 0.13208)
		(layer "F.Cu")
		(net "SMB_ISO_CB_SCL")
	)
	(segment
		(start 328.676254 -83.82)
		(end 328.422254 -83.566)
		(width 0.13208)
		(layer "F.Cu")
		(net "SMB_ISO_CB_SCL")
	)
	(segment
		(start 328.422254 -83.566)
		(end 327.914 -83.566)
		(width 0.13208)
		(layer "F.Cu")
		(net "SMB_ISO_CB_SCL")
	)
	(segment
		(start 327.914 -83.566)
		(end 327.49363 -83.98637)
		(width 0.13208)
		(layer "F.Cu")
		(net "SMB_ISO_CB_SCL")
	)
	(segment
		(start 329.658472 -83.357466)
		(end 329.83805 -83.177888)
		(width 0.13208)
		(layer "F.Cu")
		(net "SMB_ISO_CB_SCL")
	)
	(segment
		(start 325.02983 -83.98637)
		(end 326.49668 -83.98637)
		(width 0.13208)
		(layer "F.Cu")
		(net "SMB_ISO_CB_SCL")
	)
	(segment
		(start 329.03795 -83.82)
		(end 328.676254 -83.82)
		(width 0.13208)
		(layer "F.Cu")
		(net "SMB_ISO_CB_SCL")
	)
	(segment
		(start 329.160124 -83.357466)
		(end 329.658472 -83.357466)
		(width 0.13208)
		(layer "F.Cu")
		(net "SMB_ISO_CB_SCL")
	)
	(segment
		(start 329.83805 -83.177888)
		(end 329.83805 -82.931)
		(width 0.13208)
		(layer "F.Cu")
		(net "SMB_ISO_CB_SCL")
	)
	(segment
		(start 329.03795 -83.82)
		(end 329.03795 -83.47964)
		(width 0.13208)
		(layer "F.Cu")
		(net "SMB_ISO_CB_SCL")
	)
	(segment
		(start 324.01764 -87.02929)
		(end 324.01764 -84.99856)
		(width 0.13208)
		(layer "F.Cu")
		(net "SMB_ISO_CB_SCL")
	)
	(segment
		(start 324.01764 -84.99856)
		(end 325.02983 -83.98637)
		(width 0.13208)
		(layer "F.Cu")
		(net "SMB_ISO_CB_SCL")
	)
	(via
		(at 327.49363 -83.98637)
		(size 0.508)
		(drill 0.254)
		(layers "F.Cu" "B.Cu")
		(net "SMB_ISO_CB_SCL")
	)
	(segment
		(start 327.49363 -83.98637)
		(end 325.921116 -83.98637)
		(width 0.13208)
		(layer "B.Cu")
		(net "SMB_ISO_CB_SCL")
	)
	(segment
		(start 325.921116 -83.98637)
		(end 325.881746 -83.947)
		(width 0.13208)
		(layer "B.Cu")
		(net "SMB_ISO_CB_SCL")
	)
	(segment
		(start 325.881746 -83.947)
		(end 325.01205 -83.947)
		(width 0.13208)
		(layer "B.Cu")
		(net "SMB_ISO_CB_SCL")
	)
	(segment
		(start 207.454246 -228.833426)
		(end 207.22082 -228.6)
		(width 0.13208)
		(layer "F.Cu")
		(net "PD_BIC_UART_SEL")
	)
	(segment
		(start 204.163676 -226.896676)
		(end 201.107294 -226.896676)
		(width 0.13208)
		(layer "F.Cu")
		(net "PD_BIC_UART_SEL")
	)
	(segment
		(start 207.22082 -228.6)
		(end 205.867 -228.6)
		(width 0.13208)
		(layer "F.Cu")
		(net "PD_BIC_UART_SEL")
	)
	(segment
		(start 205.867 -228.6)
		(end 204.163676 -226.896676)
		(width 0.13208)
		(layer "F.Cu")
		(net "PD_BIC_UART_SEL")
	)
	(via
		(at 205.867 -228.6)
		(size 0.762)
		(drill 0.381)
		(layers "F.Cu" "B.Cu")
		(net "PD_BIC_UART_SEL")
	)
	(segment
		(start 205.613 -224.282254)
		(end 203.147422 -221.816676)
		(width 0.13208)
		(layer "F.Cu")
		(net "PU_BIC_UART_SEL")
	)
	(segment
		(start 205.613 -225.425)
		(end 205.613 -224.282254)
		(width 0.13208)
		(layer "F.Cu")
		(net "PU_BIC_UART_SEL")
	)
	(segment
		(start 205.613 -226.23018)
		(end 205.613 -225.425)
		(width 0.13208)
		(layer "F.Cu")
		(net "PU_BIC_UART_SEL")
	)
	(segment
		(start 203.147422 -221.816676)
		(end 201.107294 -221.816676)
		(width 0.13208)
		(layer "F.Cu")
		(net "PU_BIC_UART_SEL")
	)
	(segment
		(start 206.311246 -226.928426)
		(end 205.613 -226.23018)
		(width 0.13208)
		(layer "F.Cu")
		(net "PU_BIC_UART_SEL")
	)
	(via
		(at 205.613 -225.425)
		(size 0.762)
		(drill 0.381)
		(layers "F.Cu" "B.Cu")
		(net "PU_BIC_UART_SEL")
	)
	(segment
		(start 405.680164 -380.064264)
		(end 405.67991 -380.06401)
		(width 0.13208)
		(layer "F.Cu")
		(net "I3C_MB_BMC_R_SCL")
	)
	(segment
		(start 405.892 -382.397254)
		(end 405.892 -383.26695)
		(width 0.13208)
		(layer "F.Cu")
		(net "I3C_MB_BMC_R_SCL")
	)
	(segment
		(start 405.765 -382.270254)
		(end 405.892 -382.397254)
		(width 0.13208)
		(layer "F.Cu")
		(net "I3C_MB_BMC_R_SCL")
	)
	(segment
		(start 405.67991 -379.254258)
		(end 405.393652 -378.968)
		(width 0.13208)
		(layer "F.Cu")
		(net "I3C_MB_BMC_R_SCL")
	)
	(segment
		(start 405.765 -380.873)
		(end 405.765 -382.270254)
		(width 0.13208)
		(layer "F.Cu")
		(net "I3C_MB_BMC_R_SCL")
	)
	(segment
		(start 405.67991 -380.06401)
		(end 405.67991 -379.254258)
		(width 0.13208)
		(layer "F.Cu")
		(net "I3C_MB_BMC_R_SCL")
	)
	(segment
		(start 405.892 -383.26695)
		(end 405.003 -383.26695)
		(width 0.13208)
		(layer "F.Cu")
		(net "I3C_MB_BMC_R_SCL")
	)
	(segment
		(start 405.680164 -380.788164)
		(end 405.765 -380.873)
		(width 0.13208)
		(layer "F.Cu")
		(net "I3C_MB_BMC_R_SCL")
	)
	(segment
		(start 405.680164 -380.064264)
		(end 405.680164 -380.788164)
		(width 0.13208)
		(layer "F.Cu")
		(net "I3C_MB_BMC_R_SCL")
	)
	(via
		(at 405.393652 -378.968)
		(size 0.508)
		(drill 0.254)
		(layers "F.Cu" "B.Cu")
		(net "I3C_MB_BMC_R_SCL")
	)
	(segment
		(start 405.393652 -376.892312)
		(end 405.393652 -378.968)
		(width 0.13208)
		(layer "B.Cu")
		(net "I3C_MB_BMC_R_SCL")
	)
	(segment
		(start 406.781 -383.26695)
		(end 406.781 -381.75438)
		(width 0.13208)
		(layer "F.Cu")
		(net "I3C_MB_BMC_R_SDA")
	)
	(segment
		(start 406.330404 -380.666244)
		(end 406.330404 -380.064264)
		(width 0.13208)
		(layer "F.Cu")
		(net "I3C_MB_BMC_R_SDA")
	)
	(segment
		(start 406.402032 -378.076968)
		(end 406.402032 -378.838968)
		(width 0.13208)
		(layer "F.Cu")
		(net "I3C_MB_BMC_R_SDA")
	)
	(segment
		(start 406.402032 -378.838968)
		(end 406.330404 -378.910596)
		(width 0.13208)
		(layer "F.Cu")
		(net "I3C_MB_BMC_R_SDA")
	)
	(segment
		(start 406.330404 -378.910596)
		(end 406.330404 -380.064264)
		(width 0.13208)
		(layer "F.Cu")
		(net "I3C_MB_BMC_R_SDA")
	)
	(segment
		(start 406.781 -383.26695)
		(end 407.67 -383.26695)
		(width 0.13208)
		(layer "F.Cu")
		(net "I3C_MB_BMC_R_SDA")
	)
	(segment
		(start 406.781 -381.75438)
		(end 406.330404 -380.666244)
		(width 0.13208)
		(layer "F.Cu")
		(net "I3C_MB_BMC_R_SDA")
	)
	(via
		(at 406.402032 -378.076968)
		(size 0.508)
		(drill 0.254)
		(layers "F.Cu" "B.Cu")
		(net "I3C_MB_BMC_R_SDA")
	)
	(segment
		(start 406.402032 -376.892312)
		(end 406.402032 -378.076968)
		(width 0.13208)
		(layer "B.Cu")
		(net "I3C_MB_BMC_R_SDA")
	)
	(segment
		(start 209.633566 -214.83447)
		(end 208.942432 -215.525604)
		(width 0.13208)
		(layer "F.Cu")
		(net "BIC_UART_SEL1")
	)
	(segment
		(start 196.081904 -240.867946)
		(end 197.211442 -241.997484)
		(width 0.13208)
		(layer "F.Cu")
		(net "BIC_UART_SEL1")
	)
	(segment
		(start 196.081904 -237.535466)
		(end 196.081904 -240.867946)
		(width 0.13208)
		(layer "F.Cu")
		(net "BIC_UART_SEL1")
	)
	(segment
		(start 206.584042 -241.997484)
		(end 209.401156 -239.18037)
		(width 0.13208)
		(layer "F.Cu")
		(net "BIC_UART_SEL1")
	)
	(segment
		(start 196.430138 -237.187232)
		(end 196.081904 -237.535466)
		(width 0.13208)
		(layer "F.Cu")
		(net "BIC_UART_SEL1")
	)
	(segment
		(start 209.401156 -239.18037)
		(end 209.401156 -238.67237)
		(width 0.13208)
		(layer "F.Cu")
		(net "BIC_UART_SEL1")
	)
	(segment
		(start 207.400652 -216.14257)
		(end 208.43621 -216.14257)
		(width 0.13208)
		(layer "F.Cu")
		(net "BIC_UART_SEL1")
	)
	(segment
		(start 210.346036 -215.557354)
		(end 210.346036 -214.993728)
		(width 0.13208)
		(layer "F.Cu")
		(net "BIC_UART_SEL1")
	)
	(segment
		(start 208.942432 -215.636348)
		(end 208.942432 -215.525604)
		(width 0.13208)
		(layer "F.Cu")
		(net "BIC_UART_SEL1")
	)
	(segment
		(start 198.495666 -237.187232)
		(end 196.430138 -237.187232)
		(width 0.13208)
		(layer "F.Cu")
		(net "BIC_UART_SEL1")
	)
	(segment
		(start 210.186778 -214.83447)
		(end 209.633566 -214.83447)
		(width 0.13208)
		(layer "F.Cu")
		(net "BIC_UART_SEL1")
	)
	(segment
		(start 208.43621 -216.14257)
		(end 208.942432 -215.636348)
		(width 0.13208)
		(layer "F.Cu")
		(net "BIC_UART_SEL1")
	)
	(segment
		(start 197.211442 -241.997484)
		(end 206.584042 -241.997484)
		(width 0.13208)
		(layer "F.Cu")
		(net "BIC_UART_SEL1")
	)
	(segment
		(start 210.346036 -214.993728)
		(end 210.186778 -214.83447)
		(width 0.13208)
		(layer "F.Cu")
		(net "BIC_UART_SEL1")
	)
	(segment
		(start 207.273652 -215.536526)
		(end 207.273652 -216.01557)
		(width 0.13208)
		(layer "F.Cu")
		(net "BIC_UART_SEL1")
	)
	(segment
		(start 207.273652 -216.01557)
		(end 207.400652 -216.14257)
		(width 0.13208)
		(layer "F.Cu")
		(net "BIC_UART_SEL1")
	)
	(via
		(at 208.942432 -215.525604)
		(size 0.508)
		(drill 0.254)
		(layers "F.Cu" "B.Cu")
		(net "BIC_UART_SEL1")
	)
	(via
		(at 209.401156 -238.67237)
		(size 0.508)
		(drill 0.254)
		(layers "F.Cu" "B.Cu")
		(net "BIC_UART_SEL1")
	)
	(segment
		(start 208.7626 -222.498158)
		(end 210.384136 -220.876622)
		(width 0.15494)
		(layer "In5.Cu")
		(net "BIC_UART_SEL1")
	)
	(segment
		(start 209.504534 -216.087706)
		(end 208.942432 -215.525604)
		(width 0.15494)
		(layer "In5.Cu")
		(net "BIC_UART_SEL1")
	)
	(segment
		(start 210.384136 -220.876622)
		(end 210.384136 -218.004136)
		(width 0.15494)
		(layer "In5.Cu")
		(net "BIC_UART_SEL1")
	)
	(segment
		(start 209.401156 -238.67237)
		(end 209.401156 -237.493302)
		(width 0.15494)
		(layer "In5.Cu")
		(net "BIC_UART_SEL1")
	)
	(segment
		(start 208.407 -226.435666)
		(end 208.7626 -226.080066)
		(width 0.15494)
		(layer "In5.Cu")
		(net "BIC_UART_SEL1")
	)
	(segment
		(start 209.504534 -217.124534)
		(end 209.504534 -216.087706)
		(width 0.15494)
		(layer "In5.Cu")
		(net "BIC_UART_SEL1")
	)
	(segment
		(start 208.407 -236.499146)
		(end 208.407 -226.435666)
		(width 0.15494)
		(layer "In5.Cu")
		(net "BIC_UART_SEL1")
	)
	(segment
		(start 208.7626 -226.080066)
		(end 208.7626 -222.498158)
		(width 0.15494)
		(layer "In5.Cu")
		(net "BIC_UART_SEL1")
	)
	(segment
		(start 209.401156 -237.493302)
		(end 208.407 -236.499146)
		(width 0.15494)
		(layer "In5.Cu")
		(net "BIC_UART_SEL1")
	)
	(segment
		(start 210.384136 -218.004136)
		(end 209.504534 -217.124534)
		(width 0.15494)
		(layer "In5.Cu")
		(net "BIC_UART_SEL1")
	)
	(segment
		(start 198.18731 -224.356676)
		(end 197.051422 -224.356676)
		(width 0.13208)
		(layer "F.Cu")
		(net "BIC_UART_HW_SEL1")
	)
	(segment
		(start 197.051422 -224.356676)
		(end 195.71843 -225.689668)
		(width 0.13208)
		(layer "F.Cu")
		(net "BIC_UART_HW_SEL1")
	)
	(segment
		(start 198.096632 -234.647232)
		(end 195.71843 -232.26903)
		(width 0.13208)
		(layer "F.Cu")
		(net "BIC_UART_HW_SEL1")
	)
	(segment
		(start 195.71843 -232.26903)
		(end 195.71843 -228.72065)
		(width 0.13208)
		(layer "F.Cu")
		(net "BIC_UART_HW_SEL1")
	)
	(segment
		(start 195.71843 -225.689668)
		(end 195.71843 -228.72065)
		(width 0.13208)
		(layer "F.Cu")
		(net "BIC_UART_HW_SEL1")
	)
	(segment
		(start 201.41565 -234.647232)
		(end 198.096632 -234.647232)
		(width 0.13208)
		(layer "F.Cu")
		(net "BIC_UART_HW_SEL1")
	)
	(via
		(at 195.71843 -228.72065)
		(size 0.762)
		(drill 0.381)
		(layers "F.Cu" "B.Cu")
		(net "BIC_UART_HW_SEL1")
	)
	(segment
		(start 209.939636 -237.871)
		(end 210.722718 -238.654082)
		(width 0.13208)
		(layer "F.Cu")
		(net "BIC_UART_SW_SEL1_R")
	)
	(segment
		(start 226.407218 -239.046004)
		(end 226.407218 -238.768128)
		(width 0.13208)
		(layer "F.Cu")
		(net "BIC_UART_SW_SEL1_R")
	)
	(segment
		(start 208.061306 -239.727232)
		(end 208.866486 -238.922052)
		(width 0.13208)
		(layer "F.Cu")
		(net "BIC_UART_SW_SEL1_R")
	)
	(segment
		(start 226.407218 -238.768128)
		(end 227.040694 -238.134652)
		(width 0.13208)
		(layer "F.Cu")
		(net "BIC_UART_SW_SEL1_R")
	)
	(segment
		(start 209.365088 -237.871)
		(end 209.939636 -237.871)
		(width 0.13208)
		(layer "F.Cu")
		(net "BIC_UART_SW_SEL1_R")
	)
	(segment
		(start 208.866486 -238.922052)
		(end 208.866486 -238.369602)
		(width 0.13208)
		(layer "F.Cu")
		(net "BIC_UART_SW_SEL1_R")
	)
	(segment
		(start 208.866486 -238.369602)
		(end 209.365088 -237.871)
		(width 0.13208)
		(layer "F.Cu")
		(net "BIC_UART_SW_SEL1_R")
	)
	(segment
		(start 227.040694 -238.134652)
		(end 229.630478 -238.134652)
		(width 0.13208)
		(layer "F.Cu")
		(net "BIC_UART_SW_SEL1_R")
	)
	(segment
		(start 201.41565 -239.727232)
		(end 208.061306 -239.727232)
		(width 0.13208)
		(layer "F.Cu")
		(net "BIC_UART_SW_SEL1_R")
	)
	(via
		(at 226.407218 -239.046004)
		(size 0.508)
		(drill 0.254)
		(layers "F.Cu" "B.Cu")
		(net "BIC_UART_SW_SEL1_R")
	)
	(via
		(at 210.722718 -238.654082)
		(size 0.508)
		(drill 0.254)
		(layers "F.Cu" "B.Cu")
		(net "BIC_UART_SW_SEL1_R")
	)
	(segment
		(start 221.577916 -236.67212)
		(end 215.134444 -236.67212)
		(width 0.13208)
		(layer "B.Cu")
		(net "BIC_UART_SW_SEL1_R")
	)
	(segment
		(start 211.56549 -237.346744)
		(end 210.722718 -238.189516)
		(width 0.13208)
		(layer "B.Cu")
		(net "BIC_UART_SW_SEL1_R")
	)
	(segment
		(start 223.9518 -239.046004)
		(end 221.577916 -236.67212)
		(width 0.13208)
		(layer "B.Cu")
		(net "BIC_UART_SW_SEL1_R")
	)
	(segment
		(start 210.722718 -238.189516)
		(end 210.722718 -238.654082)
		(width 0.13208)
		(layer "B.Cu")
		(net "BIC_UART_SW_SEL1_R")
	)
	(segment
		(start 215.134444 -236.67212)
		(end 214.45982 -237.346744)
		(width 0.13208)
		(layer "B.Cu")
		(net "BIC_UART_SW_SEL1_R")
	)
	(segment
		(start 214.45982 -237.346744)
		(end 211.56549 -237.346744)
		(width 0.13208)
		(layer "B.Cu")
		(net "BIC_UART_SW_SEL1_R")
	)
	(segment
		(start 226.407218 -239.046004)
		(end 223.9518 -239.046004)
		(width 0.13208)
		(layer "B.Cu")
		(net "BIC_UART_SW_SEL1_R")
	)
	(segment
		(start 155.215082 -92.007944)
		(end 170.027346 -92.007944)
		(width 0.13208)
		(layer "F.Cu")
		(net "SMB_CLK_ISO_R_SDA")
	)
	(segment
		(start 411.04439 -88.12784)
		(end 412.11246 -88.12784)
		(width 0.13208)
		(layer "F.Cu")
		(net "SMB_CLK_ISO_R_SDA")
	)
	(segment
		(start 184.370218 -127.474218)
		(end 185.5724 -128.6764)
		(width 0.13208)
		(layer "F.Cu")
		(net "SMB_CLK_ISO_R_SDA")
	)
	(segment
		(start 190.106554 -127.98679)
		(end 218.625166 -127.98679)
		(width 0.13208)
		(layer "F.Cu")
		(net "SMB_CLK_ISO_R_SDA")
	)
	(segment
		(start 248.419874 -88.039448)
		(end 247.810274 -88.039448)
		(width 0.13208)
		(layer "F.Cu")
		(net "SMB_CLK_ISO_R_SDA")
	)
	(segment
		(start 218.625166 -127.98679)
		(end 225.026474 -134.388098)
		(width 0.13208)
		(layer "F.Cu")
		(net "SMB_CLK_ISO_R_SDA")
	)
	(segment
		(start 145.000472 -96.328738)
		(end 150.894288 -96.328738)
		(width 0.13208)
		(layer "F.Cu")
		(net "SMB_CLK_ISO_R_SDA")
	)
	(segment
		(start 245.540276 -108.610146)
		(end 246.817134 -107.333288)
		(width 0.13208)
		(layer "F.Cu")
		(net "SMB_CLK_ISO_R_SDA")
	)
	(segment
		(start 412.11246 -88.12784)
		(end 414.335722 -85.904578)
		(width 0.13208)
		(layer "F.Cu")
		(net "SMB_CLK_ISO_R_SDA")
	)
	(segment
		(start 185.5724 -128.6764)
		(end 189.416944 -128.6764)
		(width 0.13208)
		(layer "F.Cu")
		(net "SMB_CLK_ISO_R_SDA")
	)
	(segment
		(start 410.647388 -87.440008)
		(end 409.415488 -87.440008)
		(width 0.13208)
		(layer "F.Cu")
		(net "SMB_CLK_ISO_R_SDA")
	)
	(segment
		(start 410.647388 -87.730838)
		(end 411.04439 -88.12784)
		(width 0.13208)
		(layer "F.Cu")
		(net "SMB_CLK_ISO_R_SDA")
	)
	(segment
		(start 102.611174 -85.239606)
		(end 101.852222 -85.239606)
		(width 0.13208)
		(layer "F.Cu")
		(net "SMB_CLK_ISO_R_SDA")
	)
	(segment
		(start 174.57801 -124.651516)
		(end 177.400712 -127.474218)
		(width 0.13208)
		(layer "F.Cu")
		(net "SMB_CLK_ISO_R_SDA")
	)
	(segment
		(start 177.400712 -127.474218)
		(end 184.370218 -127.474218)
		(width 0.13208)
		(layer "F.Cu")
		(net "SMB_CLK_ISO_R_SDA")
	)
	(segment
		(start 170.027346 -92.007944)
		(end 172.252132 -94.23273)
		(width 0.13208)
		(layer "F.Cu")
		(net "SMB_CLK_ISO_R_SDA")
	)
	(segment
		(start 414.335722 -84.697824)
		(end 413.896556 -84.258658)
		(width 0.13208)
		(layer "F.Cu")
		(net "SMB_CLK_ISO_R_SDA")
	)
	(segment
		(start 246.817134 -107.333288)
		(end 246.817134 -103.571548)
		(width 0.13208)
		(layer "F.Cu")
		(net "SMB_CLK_ISO_R_SDA")
	)
	(segment
		(start 174.57801 -110.077758)
		(end 174.57801 -124.651516)
		(width 0.13208)
		(layer "F.Cu")
		(net "SMB_CLK_ISO_R_SDA")
	)
	(segment
		(start 172.252132 -94.23273)
		(end 172.252132 -107.75188)
		(width 0.13208)
		(layer "F.Cu")
		(net "SMB_CLK_ISO_R_SDA")
	)
	(segment
		(start 410.647388 -87.440008)
		(end 410.647388 -87.730838)
		(width 0.13208)
		(layer "F.Cu")
		(net "SMB_CLK_ISO_R_SDA")
	)
	(segment
		(start 189.416944 -128.6764)
		(end 190.106554 -127.98679)
		(width 0.13208)
		(layer "F.Cu")
		(net "SMB_CLK_ISO_R_SDA")
	)
	(segment
		(start 144.764252 -96.092518)
		(end 145.000472 -96.328738)
		(width 0.13208)
		(layer "F.Cu")
		(net "SMB_CLK_ISO_R_SDA")
	)
	(segment
		(start 172.252132 -107.75188)
		(end 174.57801 -110.077758)
		(width 0.13208)
		(layer "F.Cu")
		(net "SMB_CLK_ISO_R_SDA")
	)
	(segment
		(start 225.026474 -134.388098)
		(end 225.026474 -135.659622)
		(width 0.13208)
		(layer "F.Cu")
		(net "SMB_CLK_ISO_R_SDA")
	)
	(segment
		(start 414.335722 -85.904578)
		(end 414.335722 -84.697824)
		(width 0.13208)
		(layer "F.Cu")
		(net "SMB_CLK_ISO_R_SDA")
	)
	(segment
		(start 150.894288 -96.328738)
		(end 155.215082 -92.007944)
		(width 0.13208)
		(layer "F.Cu")
		(net "SMB_CLK_ISO_R_SDA")
	)
	(segment
		(start 225.026474 -135.659622)
		(end 225.026474 -136.269222)
		(width 0.13208)
		(layer "F.Cu")
		(net "SMB_CLK_ISO_R_SDA")
	)
	(via
		(at 131.778248 -168.369996)
		(size 0.508)
		(drill 0.254)
		(layers "F.Cu" "B.Cu")
		(net "SMB_CLK_ISO_R_SDA")
	)
	(via
		(at 245.540276 -108.610146)
		(size 0.508)
		(drill 0.254)
		(layers "F.Cu" "B.Cu")
		(net "SMB_CLK_ISO_R_SDA")
	)
	(via
		(at 247.810274 -88.039448)
		(size 0.508)
		(drill 0.254)
		(layers "F.Cu" "B.Cu")
		(net "SMB_CLK_ISO_R_SDA")
	)
	(via
		(at 144.764252 -96.092518)
		(size 0.508)
		(drill 0.254)
		(layers "F.Cu" "B.Cu")
		(net "SMB_CLK_ISO_R_SDA")
	)
	(via
		(at 246.817134 -103.571548)
		(size 0.508)
		(drill 0.254)
		(layers "F.Cu" "B.Cu")
		(net "SMB_CLK_ISO_R_SDA")
	)
	(via
		(at 280.673048 -89.790016)
		(size 0.508)
		(drill 0.254)
		(layers "F.Cu" "B.Cu")
		(net "SMB_CLK_ISO_R_SDA")
	)
	(via
		(at 413.896556 -84.258658)
		(size 0.508)
		(drill 0.254)
		(layers "F.Cu" "B.Cu")
		(net "SMB_CLK_ISO_R_SDA")
	)
	(via
		(at 225.026474 -135.659622)
		(size 0.508)
		(drill 0.254)
		(layers "F.Cu" "B.Cu")
		(net "SMB_CLK_ISO_R_SDA")
	)
	(via
		(at 111.990124 -327.456292)
		(size 0.508)
		(drill 0.254)
		(layers "F.Cu" "B.Cu")
		(net "SMB_CLK_ISO_R_SDA")
	)
	(via
		(at 101.852222 -85.239606)
		(size 0.508)
		(drill 0.254)
		(layers "F.Cu" "B.Cu")
		(net "SMB_CLK_ISO_R_SDA")
	)
	(segment
		(start 111.229648 -327.456292)
		(end 111.990124 -327.456292)
		(width 0.13208)
		(layer "B.Cu")
		(net "SMB_CLK_ISO_R_SDA")
	)
	(segment
		(start 131.778248 -168.369996)
		(end 130.49885 -169.649394)
		(width 0.13208)
		(layer "B.Cu")
		(net "SMB_CLK_ISO_R_SDA")
	)
	(segment
		(start 130.49885 -169.649394)
		(end 130.49885 -171.03852)
		(width 0.13208)
		(layer "B.Cu")
		(net "SMB_CLK_ISO_R_SDA")
	)
	(segment
		(start 246.503698 -89.346024)
		(end 247.810274 -88.039448)
		(width 0.15494)
		(layer "In5.Cu")
		(net "SMB_CLK_ISO_R_SDA")
	)
	(segment
		(start 225.026474 -135.659622)
		(end 225.026474 -135.18007)
		(width 0.15494)
		(layer "In5.Cu")
		(net "SMB_CLK_ISO_R_SDA")
	)
	(segment
		(start 240.3856 -119.820944)
		(end 240.3856 -113.764822)
		(width 0.15494)
		(layer "In5.Cu")
		(net "SMB_CLK_ISO_R_SDA")
	)
	(segment
		(start 246.817134 -103.571548)
		(end 246.817134 -102.86492)
		(width 0.15494)
		(layer "In5.Cu")
		(net "SMB_CLK_ISO_R_SDA")
	)
	(segment
		(start 246.817134 -102.86492)
		(end 246.503698 -102.551484)
		(width 0.15494)
		(layer "In5.Cu")
		(net "SMB_CLK_ISO_R_SDA")
	)
	(segment
		(start 246.503698 -102.551484)
		(end 246.503698 -89.346024)
		(width 0.15494)
		(layer "In5.Cu")
		(net "SMB_CLK_ISO_R_SDA")
	)
	(segment
		(start 225.026474 -135.18007)
		(end 240.3856 -119.820944)
		(width 0.15494)
		(layer "In5.Cu")
		(net "SMB_CLK_ISO_R_SDA")
	)
	(segment
		(start 240.3856 -113.764822)
		(end 245.540276 -108.610146)
		(width 0.15494)
		(layer "In5.Cu")
		(net "SMB_CLK_ISO_R_SDA")
	)
	(segment
		(start 102.9716 -89.268046)
		(end 102.9716 -93.025214)
		(width 0.15494)
		(layer "In7.Cu")
		(net "SMB_CLK_ISO_R_SDA")
	)
	(segment
		(start 120.73382 -145.761202)
		(end 120.73382 -160.545018)
		(width 0.15494)
		(layer "In7.Cu")
		(net "SMB_CLK_ISO_R_SDA")
	)
	(segment
		(start 116.305838 -101.573838)
		(end 116.305838 -112.652048)
		(width 0.15494)
		(layer "In7.Cu")
		(net "SMB_CLK_ISO_R_SDA")
	)
	(segment
		(start 101.852222 -85.239606)
		(end 102.254304 -85.641688)
		(width 0.15494)
		(layer "In7.Cu")
		(net "SMB_CLK_ISO_R_SDA")
	)
	(segment
		(start 109.886496 -95.154496)
		(end 116.305838 -101.573838)
		(width 0.15494)
		(layer "In7.Cu")
		(net "SMB_CLK_ISO_R_SDA")
	)
	(segment
		(start 102.254304 -85.641688)
		(end 102.254304 -88.55075)
		(width 0.15494)
		(layer "In7.Cu")
		(net "SMB_CLK_ISO_R_SDA")
	)
	(segment
		(start 102.254304 -88.55075)
		(end 102.9716 -89.268046)
		(width 0.15494)
		(layer "In7.Cu")
		(net "SMB_CLK_ISO_R_SDA")
	)
	(segment
		(start 105.100882 -95.154496)
		(end 109.886496 -95.154496)
		(width 0.15494)
		(layer "In7.Cu")
		(net "SMB_CLK_ISO_R_SDA")
	)
	(segment
		(start 121.51106 -117.85727)
		(end 121.51106 -121.27738)
		(width 0.15494)
		(layer "In7.Cu")
		(net "SMB_CLK_ISO_R_SDA")
	)
	(segment
		(start 128.042924 -164.634672)
		(end 131.778248 -168.369996)
		(width 0.15494)
		(layer "In7.Cu")
		(net "SMB_CLK_ISO_R_SDA")
	)
	(segment
		(start 102.9716 -93.025214)
		(end 105.100882 -95.154496)
		(width 0.15494)
		(layer "In7.Cu")
		(net "SMB_CLK_ISO_R_SDA")
	)
	(segment
		(start 121.121678 -145.373344)
		(end 120.73382 -145.761202)
		(width 0.15494)
		(layer "In7.Cu")
		(net "SMB_CLK_ISO_R_SDA")
	)
	(segment
		(start 121.121678 -121.666762)
		(end 121.121678 -145.373344)
		(width 0.15494)
		(layer "In7.Cu")
		(net "SMB_CLK_ISO_R_SDA")
	)
	(segment
		(start 116.305838 -112.652048)
		(end 121.51106 -117.85727)
		(width 0.15494)
		(layer "In7.Cu")
		(net "SMB_CLK_ISO_R_SDA")
	)
	(segment
		(start 124.823474 -164.634672)
		(end 128.042924 -164.634672)
		(width 0.15494)
		(layer "In7.Cu")
		(net "SMB_CLK_ISO_R_SDA")
	)
	(segment
		(start 120.73382 -160.545018)
		(end 124.823474 -164.634672)
		(width 0.15494)
		(layer "In7.Cu")
		(net "SMB_CLK_ISO_R_SDA")
	)
	(segment
		(start 121.51106 -121.27738)
		(end 121.121678 -121.666762)
		(width 0.15494)
		(layer "In7.Cu")
		(net "SMB_CLK_ISO_R_SDA")
	)
	(segment
		(start 279.658064 -90.805)
		(end 280.673048 -89.790016)
		(width 0.15494)
		(layer "In9.Cu")
		(net "SMB_CLK_ISO_R_SDA")
	)
	(segment
		(start 249.310652 -90.92565)
		(end 264.894822 -90.92565)
		(width 0.15494)
		(layer "In9.Cu")
		(net "SMB_CLK_ISO_R_SDA")
	)
	(segment
		(start 275.895054 -90.805)
		(end 279.658064 -90.805)
		(width 0.15494)
		(layer "In9.Cu")
		(net "SMB_CLK_ISO_R_SDA")
	)
	(segment
		(start 266.82446 -88.996012)
		(end 274.086066 -88.996012)
		(width 0.15494)
		(layer "In9.Cu")
		(net "SMB_CLK_ISO_R_SDA")
	)
	(segment
		(start 247.810274 -89.425272)
		(end 249.310652 -90.92565)
		(width 0.15494)
		(layer "In9.Cu")
		(net "SMB_CLK_ISO_R_SDA")
	)
	(segment
		(start 247.810274 -88.039448)
		(end 247.810274 -89.425272)
		(width 0.15494)
		(layer "In9.Cu")
		(net "SMB_CLK_ISO_R_SDA")
	)
	(segment
		(start 274.086066 -88.996012)
		(end 275.895054 -90.805)
		(width 0.15494)
		(layer "In9.Cu")
		(net "SMB_CLK_ISO_R_SDA")
	)
	(segment
		(start 264.894822 -90.92565)
		(end 266.82446 -88.996012)
		(width 0.15494)
		(layer "In9.Cu")
		(net "SMB_CLK_ISO_R_SDA")
	)
	(segment
		(start 96.148144 -294.649144)
		(end 96.148144 -310.939942)
		(width 0.15494)
		(layer "In11.Cu")
		(net "SMB_CLK_ISO_R_SDA")
	)
	(segment
		(start 107.746546 -327.5076)
		(end 108.432854 -327.5076)
		(width 0.15494)
		(layer "In11.Cu")
		(net "SMB_CLK_ISO_R_SDA")
	)
	(segment
		(start 100.92055 -317.479172)
		(end 100.92055 -324.772782)
		(width 0.15494)
		(layer "In11.Cu")
		(net "SMB_CLK_ISO_R_SDA")
	)
	(segment
		(start 99.671124 -314.462922)
		(end 100.92055 -317.479172)
		(width 0.15494)
		(layer "In11.Cu")
		(net "SMB_CLK_ISO_R_SDA")
	)
	(segment
		(start 96.148144 -310.939942)
		(end 99.671124 -314.462922)
		(width 0.15494)
		(layer "In11.Cu")
		(net "SMB_CLK_ISO_R_SDA")
	)
	(segment
		(start 94.4626 -288.7726)
		(end 94.4626 -292.9636)
		(width 0.15494)
		(layer "In11.Cu")
		(net "SMB_CLK_ISO_R_SDA")
	)
	(segment
		(start 101.731572 -181.939184)
		(end 98.610674 -178.818286)
		(width 0.15494)
		(layer "In11.Cu")
		(net "SMB_CLK_ISO_R_SDA")
	)
	(segment
		(start 131.360164 -168.78808)
		(end 127.630936 -168.78808)
		(width 0.15494)
		(layer "In11.Cu")
		(net "SMB_CLK_ISO_R_SDA")
	)
	(segment
		(start 108.966254 -328.041)
		(end 111.405416 -328.041)
		(width 0.15494)
		(layer "In11.Cu")
		(net "SMB_CLK_ISO_R_SDA")
	)
	(segment
		(start 111.405416 -328.041)
		(end 111.990124 -327.456292)
		(width 0.15494)
		(layer "In11.Cu")
		(net "SMB_CLK_ISO_R_SDA")
	)
	(segment
		(start 131.778248 -168.369996)
		(end 131.360164 -168.78808)
		(width 0.15494)
		(layer "In11.Cu")
		(net "SMB_CLK_ISO_R_SDA")
	)
	(segment
		(start 87.927434 -282.237434)
		(end 94.4626 -288.7726)
		(width 0.15494)
		(layer "In11.Cu")
		(net "SMB_CLK_ISO_R_SDA")
	)
	(segment
		(start 104.036368 -327.8886)
		(end 107.365546 -327.8886)
		(width 0.15494)
		(layer "In11.Cu")
		(net "SMB_CLK_ISO_R_SDA")
	)
	(segment
		(start 94.4626 -292.9636)
		(end 96.148144 -294.649144)
		(width 0.15494)
		(layer "In11.Cu")
		(net "SMB_CLK_ISO_R_SDA")
	)
	(segment
		(start 107.365546 -327.8886)
		(end 107.746546 -327.5076)
		(width 0.15494)
		(layer "In11.Cu")
		(net "SMB_CLK_ISO_R_SDA")
	)
	(segment
		(start 127.630936 -168.78808)
		(end 124.4854 -171.933616)
		(width 0.15494)
		(layer "In11.Cu")
		(net "SMB_CLK_ISO_R_SDA")
	)
	(segment
		(start 122.048016 -181.939184)
		(end 101.731572 -181.939184)
		(width 0.15494)
		(layer "In11.Cu")
		(net "SMB_CLK_ISO_R_SDA")
	)
	(segment
		(start 98.610674 -178.818286)
		(end 89.31529 -178.818286)
		(width 0.15494)
		(layer "In11.Cu")
		(net "SMB_CLK_ISO_R_SDA")
	)
	(segment
		(start 83.4644 -271.46631)
		(end 87.927434 -282.237434)
		(width 0.15494)
		(layer "In11.Cu")
		(net "SMB_CLK_ISO_R_SDA")
	)
	(segment
		(start 108.432854 -327.5076)
		(end 108.966254 -328.041)
		(width 0.15494)
		(layer "In11.Cu")
		(net "SMB_CLK_ISO_R_SDA")
	)
	(segment
		(start 77.5716 -190.561976)
		(end 77.5716 -253.6698)
		(width 0.15494)
		(layer "In11.Cu")
		(net "SMB_CLK_ISO_R_SDA")
	)
	(segment
		(start 124.4854 -179.5018)
		(end 122.048016 -181.939184)
		(width 0.15494)
		(layer "In11.Cu")
		(net "SMB_CLK_ISO_R_SDA")
	)
	(segment
		(start 100.92055 -324.772782)
		(end 104.036368 -327.8886)
		(width 0.15494)
		(layer "In11.Cu")
		(net "SMB_CLK_ISO_R_SDA")
	)
	(segment
		(start 124.4854 -171.933616)
		(end 124.4854 -179.5018)
		(width 0.15494)
		(layer "In11.Cu")
		(net "SMB_CLK_ISO_R_SDA")
	)
	(segment
		(start 77.5716 -253.6698)
		(end 83.4644 -259.5626)
		(width 0.15494)
		(layer "In11.Cu")
		(net "SMB_CLK_ISO_R_SDA")
	)
	(segment
		(start 89.31529 -178.818286)
		(end 77.5716 -190.561976)
		(width 0.15494)
		(layer "In11.Cu")
		(net "SMB_CLK_ISO_R_SDA")
	)
	(segment
		(start 83.4644 -259.5626)
		(end 83.4644 -271.46631)
		(width 0.15494)
		(layer "In11.Cu")
		(net "SMB_CLK_ISO_R_SDA")
	)
	(segment
		(start 376.202194 -85.397086)
		(end 377.94819 -85.397086)
		(width 0.15494)
		(layer "In13.Cu")
		(net "SMB_CLK_ISO_R_SDA")
	)
	(segment
		(start 315.826902 -89.756234)
		(end 325.545704 -89.756234)
		(width 0.15494)
		(layer "In13.Cu")
		(net "SMB_CLK_ISO_R_SDA")
	)
	(segment
		(start 408.767026 -88.44534)
		(end 412.953708 -84.258658)
		(width 0.15494)
		(layer "In13.Cu")
		(net "SMB_CLK_ISO_R_SDA")
	)
	(segment
		(start 375.62155 -85.97773)
		(end 376.202194 -85.397086)
		(width 0.15494)
		(layer "In13.Cu")
		(net "SMB_CLK_ISO_R_SDA")
	)
	(segment
		(start 371.023642 -86.6394)
		(end 371.685312 -85.97773)
		(width 0.15494)
		(layer "In13.Cu")
		(net "SMB_CLK_ISO_R_SDA")
	)
	(segment
		(start 334.973422 -92.835222)
		(end 334.973422 -94.537022)
		(width 0.15494)
		(layer "In13.Cu")
		(net "SMB_CLK_ISO_R_SDA")
	)
	(segment
		(start 327.48347 -91.694)
		(end 333.8322 -91.694)
		(width 0.15494)
		(layer "In13.Cu")
		(net "SMB_CLK_ISO_R_SDA")
	)
	(segment
		(start 353.240848 -98.671888)
		(end 362.741972 -89.170764)
		(width 0.15494)
		(layer "In13.Cu")
		(net "SMB_CLK_ISO_R_SDA")
	)
	(segment
		(start 366.187228 -87.090504)
		(end 368.823748 -87.090504)
		(width 0.15494)
		(layer "In13.Cu")
		(net "SMB_CLK_ISO_R_SDA")
	)
	(segment
		(start 369.106958 -86.807294)
		(end 369.106958 -86.792816)
		(width 0.15494)
		(layer "In13.Cu")
		(net "SMB_CLK_ISO_R_SDA")
	)
	(segment
		(start 280.673048 -89.790016)
		(end 281.471116 -90.588084)
		(width 0.15494)
		(layer "In13.Cu")
		(net "SMB_CLK_ISO_R_SDA")
	)
	(segment
		(start 337.264502 -98.671888)
		(end 353.240848 -98.671888)
		(width 0.15494)
		(layer "In13.Cu")
		(net "SMB_CLK_ISO_R_SDA")
	)
	(segment
		(start 395.754606 -88.44534)
		(end 408.767026 -88.44534)
		(width 0.15494)
		(layer "In13.Cu")
		(net "SMB_CLK_ISO_R_SDA")
	)
	(segment
		(start 281.471116 -90.588084)
		(end 314.995052 -90.588084)
		(width 0.15494)
		(layer "In13.Cu")
		(net "SMB_CLK_ISO_R_SDA")
	)
	(segment
		(start 378.528834 -85.97773)
		(end 389.604758 -85.97773)
		(width 0.15494)
		(layer "In13.Cu")
		(net "SMB_CLK_ISO_R_SDA")
	)
	(segment
		(start 369.260374 -86.6394)
		(end 371.023642 -86.6394)
		(width 0.15494)
		(layer "In13.Cu")
		(net "SMB_CLK_ISO_R_SDA")
	)
	(segment
		(start 392.52525 -88.898222)
		(end 395.301724 -88.898222)
		(width 0.15494)
		(layer "In13.Cu")
		(net "SMB_CLK_ISO_R_SDA")
	)
	(segment
		(start 377.94819 -85.397086)
		(end 378.528834 -85.97773)
		(width 0.15494)
		(layer "In13.Cu")
		(net "SMB_CLK_ISO_R_SDA")
	)
	(segment
		(start 314.995052 -90.588084)
		(end 315.826902 -89.756234)
		(width 0.15494)
		(layer "In13.Cu")
		(net "SMB_CLK_ISO_R_SDA")
	)
	(segment
		(start 389.604758 -85.97773)
		(end 392.52525 -88.898222)
		(width 0.15494)
		(layer "In13.Cu")
		(net "SMB_CLK_ISO_R_SDA")
	)
	(segment
		(start 395.301724 -88.898222)
		(end 395.754606 -88.44534)
		(width 0.15494)
		(layer "In13.Cu")
		(net "SMB_CLK_ISO_R_SDA")
	)
	(segment
		(start 337.0072 -96.5708)
		(end 337.0072 -98.414586)
		(width 0.15494)
		(layer "In13.Cu")
		(net "SMB_CLK_ISO_R_SDA")
	)
	(segment
		(start 369.106958 -86.792816)
		(end 369.260374 -86.6394)
		(width 0.15494)
		(layer "In13.Cu")
		(net "SMB_CLK_ISO_R_SDA")
	)
	(segment
		(start 362.741972 -89.170764)
		(end 364.106968 -89.170764)
		(width 0.15494)
		(layer "In13.Cu")
		(net "SMB_CLK_ISO_R_SDA")
	)
	(segment
		(start 412.953708 -84.258658)
		(end 413.896556 -84.258658)
		(width 0.15494)
		(layer "In13.Cu")
		(net "SMB_CLK_ISO_R_SDA")
	)
	(segment
		(start 371.685312 -85.97773)
		(end 375.62155 -85.97773)
		(width 0.15494)
		(layer "In13.Cu")
		(net "SMB_CLK_ISO_R_SDA")
	)
	(segment
		(start 368.823748 -87.090504)
		(end 369.106958 -86.807294)
		(width 0.15494)
		(layer "In13.Cu")
		(net "SMB_CLK_ISO_R_SDA")
	)
	(segment
		(start 325.545704 -89.756234)
		(end 327.48347 -91.694)
		(width 0.15494)
		(layer "In13.Cu")
		(net "SMB_CLK_ISO_R_SDA")
	)
	(segment
		(start 334.973422 -94.537022)
		(end 337.0072 -96.5708)
		(width 0.15494)
		(layer "In13.Cu")
		(net "SMB_CLK_ISO_R_SDA")
	)
	(segment
		(start 364.106968 -89.170764)
		(end 366.187228 -87.090504)
		(width 0.15494)
		(layer "In13.Cu")
		(net "SMB_CLK_ISO_R_SDA")
	)
	(segment
		(start 333.8322 -91.694)
		(end 334.973422 -92.835222)
		(width 0.15494)
		(layer "In13.Cu")
		(net "SMB_CLK_ISO_R_SDA")
	)
	(segment
		(start 337.0072 -98.414586)
		(end 337.264502 -98.671888)
		(width 0.15494)
		(layer "In13.Cu")
		(net "SMB_CLK_ISO_R_SDA")
	)
	(segment
		(start 125.130306 -88.4428)
		(end 133.952488 -88.4428)
		(width 0.15494)
		(layer "In15.Cu")
		(net "SMB_CLK_ISO_R_SDA")
	)
	(segment
		(start 114.136678 -83.409282)
		(end 115.790218 -81.755742)
		(width 0.15494)
		(layer "In15.Cu")
		(net "SMB_CLK_ISO_R_SDA")
	)
	(segment
		(start 135.46074 -86.934548)
		(end 140.857224 -86.934548)
		(width 0.15494)
		(layer "In15.Cu")
		(net "SMB_CLK_ISO_R_SDA")
	)
	(segment
		(start 105.74147 -86.106)
		(end 106.55427 -85.2932)
		(width 0.15494)
		(layer "In15.Cu")
		(net "SMB_CLK_ISO_R_SDA")
	)
	(segment
		(start 106.55427 -85.2932)
		(end 112.964976 -85.2932)
		(width 0.15494)
		(layer "In15.Cu")
		(net "SMB_CLK_ISO_R_SDA")
	)
	(segment
		(start 114.136678 -84.121498)
		(end 114.136678 -83.409282)
		(width 0.15494)
		(layer "In15.Cu")
		(net "SMB_CLK_ISO_R_SDA")
	)
	(segment
		(start 118.443248 -81.755742)
		(end 125.130306 -88.4428)
		(width 0.15494)
		(layer "In15.Cu")
		(net "SMB_CLK_ISO_R_SDA")
	)
	(segment
		(start 133.952488 -88.4428)
		(end 135.46074 -86.934548)
		(width 0.15494)
		(layer "In15.Cu")
		(net "SMB_CLK_ISO_R_SDA")
	)
	(segment
		(start 115.790218 -81.755742)
		(end 118.443248 -81.755742)
		(width 0.15494)
		(layer "In15.Cu")
		(net "SMB_CLK_ISO_R_SDA")
	)
	(segment
		(start 142.738094 -88.815418)
		(end 142.738094 -94.06636)
		(width 0.15494)
		(layer "In15.Cu")
		(net "SMB_CLK_ISO_R_SDA")
	)
	(segment
		(start 101.852222 -85.239606)
		(end 102.718616 -86.106)
		(width 0.15494)
		(layer "In15.Cu")
		(net "SMB_CLK_ISO_R_SDA")
	)
	(segment
		(start 102.718616 -86.106)
		(end 105.74147 -86.106)
		(width 0.15494)
		(layer "In15.Cu")
		(net "SMB_CLK_ISO_R_SDA")
	)
	(segment
		(start 142.738094 -94.06636)
		(end 144.764252 -96.092518)
		(width 0.15494)
		(layer "In15.Cu")
		(net "SMB_CLK_ISO_R_SDA")
	)
	(segment
		(start 140.857224 -86.934548)
		(end 142.738094 -88.815418)
		(width 0.15494)
		(layer "In15.Cu")
		(net "SMB_CLK_ISO_R_SDA")
	)
	(segment
		(start 112.964976 -85.2932)
		(end 114.136678 -84.121498)
		(width 0.15494)
		(layer "In15.Cu")
		(net "SMB_CLK_ISO_R_SDA")
	)
	(segment
		(start 172.797216 -107.526074)
		(end 172.797216 -94.006924)
		(width 0.13208)
		(layer "F.Cu")
		(net "SMB_CLK_ISO_R_SCL")
	)
	(segment
		(start 102.611174 -84.223606)
		(end 101.852222 -84.223606)
		(width 0.13208)
		(layer "F.Cu")
		(net "SMB_CLK_ISO_R_SCL")
	)
	(segment
		(start 150.668482 -95.783654)
		(end 146.27225 -95.783654)
		(width 0.13208)
		(layer "F.Cu")
		(net "SMB_CLK_ISO_R_SCL")
	)
	(segment
		(start 184.295796 -126.929134)
		(end 177.626518 -126.929134)
		(width 0.13208)
		(layer "F.Cu")
		(net "SMB_CLK_ISO_R_SCL")
	)
	(segment
		(start 219.26169 -127.441706)
		(end 190.33236 -127.441706)
		(width 0.13208)
		(layer "F.Cu")
		(net "SMB_CLK_ISO_R_SCL")
	)
	(segment
		(start 170.253152 -91.46286)
		(end 154.989276 -91.46286)
		(width 0.13208)
		(layer "F.Cu")
		(net "SMB_CLK_ISO_R_SCL")
	)
	(segment
		(start 226.346766 -134.526782)
		(end 219.26169 -127.441706)
		(width 0.13208)
		(layer "F.Cu")
		(net "SMB_CLK_ISO_R_SCL")
	)
	(segment
		(start 175.123094 -109.851952)
		(end 172.797216 -107.526074)
		(width 0.13208)
		(layer "F.Cu")
		(net "SMB_CLK_ISO_R_SCL")
	)
	(segment
		(start 154.989276 -91.46286)
		(end 150.668482 -95.783654)
		(width 0.13208)
		(layer "F.Cu")
		(net "SMB_CLK_ISO_R_SCL")
	)
	(segment
		(start 175.123094 -124.42571)
		(end 175.123094 -109.851952)
		(width 0.13208)
		(layer "F.Cu")
		(net "SMB_CLK_ISO_R_SCL")
	)
	(segment
		(start 177.626518 -126.929134)
		(end 175.123094 -124.42571)
		(width 0.13208)
		(layer "F.Cu")
		(net "SMB_CLK_ISO_R_SCL")
	)
	(segment
		(start 225.915474 -135.708898)
		(end 225.915474 -136.269222)
		(width 0.13208)
		(layer "F.Cu")
		(net "SMB_CLK_ISO_R_SCL")
	)
	(segment
		(start 190.33236 -127.441706)
		(end 189.127892 -126.237238)
		(width 0.13208)
		(layer "F.Cu")
		(net "SMB_CLK_ISO_R_SCL")
	)
	(segment
		(start 172.797216 -94.006924)
		(end 170.253152 -91.46286)
		(width 0.13208)
		(layer "F.Cu")
		(net "SMB_CLK_ISO_R_SCL")
	)
	(segment
		(start 226.67595 -134.948422)
		(end 225.915474 -135.708898)
		(width 0.13208)
		(layer "F.Cu")
		(net "SMB_CLK_ISO_R_SCL")
	)
	(segment
		(start 146.27225 -95.783654)
		(end 145.663666 -95.17507)
		(width 0.13208)
		(layer "F.Cu")
		(net "SMB_CLK_ISO_R_SCL")
	)
	(segment
		(start 189.127892 -126.237238)
		(end 184.987692 -126.237238)
		(width 0.13208)
		(layer "F.Cu")
		(net "SMB_CLK_ISO_R_SCL")
	)
	(segment
		(start 226.67595 -134.526782)
		(end 226.346766 -134.526782)
		(width 0.13208)
		(layer "F.Cu")
		(net "SMB_CLK_ISO_R_SCL")
	)
	(segment
		(start 184.987692 -126.237238)
		(end 184.295796 -126.929134)
		(width 0.13208)
		(layer "F.Cu")
		(net "SMB_CLK_ISO_R_SCL")
	)
	(segment
		(start 226.67595 -134.526782)
		(end 226.67595 -134.948422)
		(width 0.13208)
		(layer "F.Cu")
		(net "SMB_CLK_ISO_R_SCL")
	)
	(via
		(at 145.663666 -95.17507)
		(size 0.508)
		(drill 0.254)
		(layers "F.Cu" "B.Cu")
		(net "SMB_CLK_ISO_R_SCL")
	)
	(via
		(at 101.852222 -84.223606)
		(size 0.508)
		(drill 0.254)
		(layers "F.Cu" "B.Cu")
		(net "SMB_CLK_ISO_R_SCL")
	)
	(via
		(at 132.554472 -169.310558)
		(size 0.508)
		(drill 0.254)
		(layers "F.Cu" "B.Cu")
		(net "SMB_CLK_ISO_R_SCL")
	)
	(segment
		(start 132.625846 -169.75963)
		(end 132.554472 -169.688256)
		(width 0.13208)
		(layer "B.Cu")
		(net "SMB_CLK_ISO_R_SCL")
	)
	(segment
		(start 132.089144 -170.464226)
		(end 132.625846 -170.464226)
		(width 0.13208)
		(layer "B.Cu")
		(net "SMB_CLK_ISO_R_SCL")
	)
	(segment
		(start 131.51485 -171.03852)
		(end 132.089144 -170.464226)
		(width 0.13208)
		(layer "B.Cu")
		(net "SMB_CLK_ISO_R_SCL")
	)
	(segment
		(start 132.554472 -169.688256)
		(end 132.554472 -169.310558)
		(width 0.13208)
		(layer "B.Cu")
		(net "SMB_CLK_ISO_R_SCL")
	)
	(segment
		(start 132.625846 -170.464226)
		(end 132.625846 -169.75963)
		(width 0.13208)
		(layer "B.Cu")
		(net "SMB_CLK_ISO_R_SCL")
	)
	(segment
		(start 130.933698 -168.423844)
		(end 130.933698 -169.344594)
		(width 0.15494)
		(layer "In7.Cu")
		(net "SMB_CLK_ISO_R_SCL")
	)
	(segment
		(start 100.827332 -85.141308)
		(end 101.7016 -86.015576)
		(width 0.15494)
		(layer "In7.Cu")
		(net "SMB_CLK_ISO_R_SCL")
	)
	(segment
		(start 121.05132 -121.08688)
		(end 120.661938 -121.476262)
		(width 0.15494)
		(layer "In7.Cu")
		(net "SMB_CLK_ISO_R_SCL")
	)
	(segment
		(start 115.820952 -112.852962)
		(end 121.05132 -118.08333)
		(width 0.15494)
		(layer "In7.Cu")
		(net "SMB_CLK_ISO_R_SCL")
	)
	(segment
		(start 124.62129 -165.094412)
		(end 127.604266 -165.094412)
		(width 0.15494)
		(layer "In7.Cu")
		(net "SMB_CLK_ISO_R_SCL")
	)
	(segment
		(start 101.188012 -84.223606)
		(end 100.827332 -84.584286)
		(width 0.15494)
		(layer "In7.Cu")
		(net "SMB_CLK_ISO_R_SCL")
	)
	(segment
		(start 132.029962 -169.835068)
		(end 132.554472 -169.310558)
		(width 0.15494)
		(layer "In7.Cu")
		(net "SMB_CLK_ISO_R_SCL")
	)
	(segment
		(start 101.7016 -86.015576)
		(end 101.7016 -88.69426)
		(width 0.15494)
		(layer "In7.Cu")
		(net "SMB_CLK_ISO_R_SCL")
	)
	(segment
		(start 115.820952 -101.774752)
		(end 115.820952 -112.852962)
		(width 0.15494)
		(layer "In7.Cu")
		(net "SMB_CLK_ISO_R_SCL")
	)
	(segment
		(start 121.05132 -118.08333)
		(end 121.05132 -121.08688)
		(width 0.15494)
		(layer "In7.Cu")
		(net "SMB_CLK_ISO_R_SCL")
	)
	(segment
		(start 102.4636 -89.45626)
		(end 102.4636 -93.167708)
		(width 0.15494)
		(layer "In7.Cu")
		(net "SMB_CLK_ISO_R_SCL")
	)
	(segment
		(start 127.604266 -165.094412)
		(end 130.933698 -168.423844)
		(width 0.15494)
		(layer "In7.Cu")
		(net "SMB_CLK_ISO_R_SCL")
	)
	(segment
		(start 104.910128 -95.614236)
		(end 109.660436 -95.614236)
		(width 0.15494)
		(layer "In7.Cu")
		(net "SMB_CLK_ISO_R_SCL")
	)
	(segment
		(start 120.661938 -121.476262)
		(end 120.661938 -145.182844)
		(width 0.15494)
		(layer "In7.Cu")
		(net "SMB_CLK_ISO_R_SCL")
	)
	(segment
		(start 120.661938 -145.182844)
		(end 120.27408 -145.570702)
		(width 0.15494)
		(layer "In7.Cu")
		(net "SMB_CLK_ISO_R_SCL")
	)
	(segment
		(start 120.27408 -145.570702)
		(end 120.27408 -160.747202)
		(width 0.15494)
		(layer "In7.Cu")
		(net "SMB_CLK_ISO_R_SCL")
	)
	(segment
		(start 101.7016 -88.69426)
		(end 102.4636 -89.45626)
		(width 0.15494)
		(layer "In7.Cu")
		(net "SMB_CLK_ISO_R_SCL")
	)
	(segment
		(start 101.852222 -84.223606)
		(end 101.188012 -84.223606)
		(width 0.15494)
		(layer "In7.Cu")
		(net "SMB_CLK_ISO_R_SCL")
	)
	(segment
		(start 130.933698 -169.344594)
		(end 131.424172 -169.835068)
		(width 0.15494)
		(layer "In7.Cu")
		(net "SMB_CLK_ISO_R_SCL")
	)
	(segment
		(start 120.27408 -160.747202)
		(end 124.62129 -165.094412)
		(width 0.15494)
		(layer "In7.Cu")
		(net "SMB_CLK_ISO_R_SCL")
	)
	(segment
		(start 109.660436 -95.614236)
		(end 115.820952 -101.774752)
		(width 0.15494)
		(layer "In7.Cu")
		(net "SMB_CLK_ISO_R_SCL")
	)
	(segment
		(start 131.424172 -169.835068)
		(end 132.029962 -169.835068)
		(width 0.15494)
		(layer "In7.Cu")
		(net "SMB_CLK_ISO_R_SCL")
	)
	(segment
		(start 100.827332 -84.584286)
		(end 100.827332 -85.141308)
		(width 0.15494)
		(layer "In7.Cu")
		(net "SMB_CLK_ISO_R_SCL")
	)
	(segment
		(start 102.4636 -93.167708)
		(end 104.910128 -95.614236)
		(width 0.15494)
		(layer "In7.Cu")
		(net "SMB_CLK_ISO_R_SCL")
	)
	(segment
		(start 141.120876 -86.298532)
		(end 135.197088 -86.298532)
		(width 0.15494)
		(layer "In15.Cu")
		(net "SMB_CLK_ISO_R_SCL")
	)
	(segment
		(start 125.67539 -87.806784)
		(end 119.151908 -81.283302)
		(width 0.15494)
		(layer "In15.Cu")
		(net "SMB_CLK_ISO_R_SCL")
	)
	(segment
		(start 135.197088 -86.298532)
		(end 133.688836 -87.806784)
		(width 0.15494)
		(layer "In15.Cu")
		(net "SMB_CLK_ISO_R_SCL")
	)
	(segment
		(start 102.598474 -84.969858)
		(end 101.852222 -84.223606)
		(width 0.15494)
		(layer "In15.Cu")
		(net "SMB_CLK_ISO_R_SCL")
	)
	(segment
		(start 105.603548 -85.172042)
		(end 104.615996 -85.172042)
		(width 0.15494)
		(layer "In15.Cu")
		(net "SMB_CLK_ISO_R_SCL")
	)
	(segment
		(start 104.413812 -84.969858)
		(end 102.598474 -84.969858)
		(width 0.15494)
		(layer "In15.Cu")
		(net "SMB_CLK_ISO_R_SCL")
	)
	(segment
		(start 111.65078 -84.775802)
		(end 105.999788 -84.775802)
		(width 0.15494)
		(layer "In15.Cu")
		(net "SMB_CLK_ISO_R_SCL")
	)
	(segment
		(start 145.663666 -90.841322)
		(end 141.120876 -86.298532)
		(width 0.15494)
		(layer "In15.Cu")
		(net "SMB_CLK_ISO_R_SCL")
	)
	(segment
		(start 104.615996 -85.172042)
		(end 104.413812 -84.969858)
		(width 0.15494)
		(layer "In15.Cu")
		(net "SMB_CLK_ISO_R_SCL")
	)
	(segment
		(start 112.359694 -84.066888)
		(end 111.65078 -84.775802)
		(width 0.15494)
		(layer "In15.Cu")
		(net "SMB_CLK_ISO_R_SCL")
	)
	(segment
		(start 114.481864 -81.283302)
		(end 112.359694 -83.405472)
		(width 0.15494)
		(layer "In15.Cu")
		(net "SMB_CLK_ISO_R_SCL")
	)
	(segment
		(start 105.999788 -84.775802)
		(end 105.603548 -85.172042)
		(width 0.15494)
		(layer "In15.Cu")
		(net "SMB_CLK_ISO_R_SCL")
	)
	(segment
		(start 133.688836 -87.806784)
		(end 125.67539 -87.806784)
		(width 0.15494)
		(layer "In15.Cu")
		(net "SMB_CLK_ISO_R_SCL")
	)
	(segment
		(start 145.663666 -95.17507)
		(end 145.663666 -90.841322)
		(width 0.15494)
		(layer "In15.Cu")
		(net "SMB_CLK_ISO_R_SCL")
	)
	(segment
		(start 119.151908 -81.283302)
		(end 114.481864 -81.283302)
		(width 0.15494)
		(layer "In15.Cu")
		(net "SMB_CLK_ISO_R_SCL")
	)
	(segment
		(start 112.359694 -83.405472)
		(end 112.359694 -84.066888)
		(width 0.15494)
		(layer "In15.Cu")
		(net "SMB_CLK_ISO_R_SCL")
	)
	(segment
		(start 406.330404 -375.71426)
		(end 406.330404 -374.64746)
		(width 0.13208)
		(layer "F.Cu")
		(net "SMB_MB_I3C_ISO_SDA")
	)
	(segment
		(start 215.728296 -222.910146)
		(end 214.602822 -222.910146)
		(width 0.13208)
		(layer "F.Cu")
		(net "SMB_MB_I3C_ISO_SDA")
	)
	(segment
		(start 216.200736 -223.382586)
		(end 215.728296 -222.910146)
		(width 0.13208)
		(layer "F.Cu")
		(net "SMB_MB_I3C_ISO_SDA")
	)
	(segment
		(start 216.200736 -223.382586)
		(end 216.835736 -223.382586)
		(width 0.13208)
		(layer "F.Cu")
		(net "SMB_MB_I3C_ISO_SDA")
	)
	(segment
		(start 214.602822 -222.910146)
		(end 214.130382 -223.382586)
		(width 0.13208)
		(layer "F.Cu")
		(net "SMB_MB_I3C_ISO_SDA")
	)
	(via
		(at 406.330404 -374.64746)
		(size 0.508)
		(drill 0.254)
		(layers "F.Cu" "B.Cu")
		(net "SMB_MB_I3C_ISO_SDA")
	)
	(via
		(at 215.40978 -259.63626)
		(size 0.508)
		(drill 0.254)
		(layers "F.Cu" "B.Cu")
		(net "SMB_MB_I3C_ISO_SDA")
	)
	(via
		(at 239.828578 -335.467706)
		(size 0.508)
		(drill 0.254)
		(layers "F.Cu" "B.Cu")
		(net "SMB_MB_I3C_ISO_SDA")
	)
	(via
		(at 361.881928 -330.607162)
		(size 0.508)
		(drill 0.254)
		(layers "F.Cu" "B.Cu")
		(net "SMB_MB_I3C_ISO_SDA")
	)
	(via
		(at 216.200736 -223.382586)
		(size 0.508)
		(drill 0.254)
		(layers "F.Cu" "B.Cu")
		(net "SMB_MB_I3C_ISO_SDA")
	)
	(segment
		(start 361.881928 -330.72197)
		(end 358.854502 -333.749396)
		(width 0.13208)
		(layer "B.Cu")
		(net "SMB_MB_I3C_ISO_SDA")
	)
	(segment
		(start 406.402032 -375.397268)
		(end 406.330404 -375.32564)
		(width 0.13208)
		(layer "B.Cu")
		(net "SMB_MB_I3C_ISO_SDA")
	)
	(segment
		(start 406.330404 -375.32564)
		(end 406.330404 -374.64746)
		(width 0.13208)
		(layer "B.Cu")
		(net "SMB_MB_I3C_ISO_SDA")
	)
	(segment
		(start 406.402032 -376.092212)
		(end 406.402032 -375.397268)
		(width 0.13208)
		(layer "B.Cu")
		(net "SMB_MB_I3C_ISO_SDA")
	)
	(segment
		(start 240.94948 -333.749396)
		(end 239.828578 -334.870298)
		(width 0.13208)
		(layer "B.Cu")
		(net "SMB_MB_I3C_ISO_SDA")
	)
	(segment
		(start 358.854502 -333.749396)
		(end 240.94948 -333.749396)
		(width 0.13208)
		(layer "B.Cu")
		(net "SMB_MB_I3C_ISO_SDA")
	)
	(segment
		(start 239.828578 -334.870298)
		(end 239.828578 -335.467706)
		(width 0.13208)
		(layer "B.Cu")
		(net "SMB_MB_I3C_ISO_SDA")
	)
	(segment
		(start 361.881928 -330.607162)
		(end 361.881928 -330.72197)
		(width 0.13208)
		(layer "B.Cu")
		(net "SMB_MB_I3C_ISO_SDA")
	)
	(segment
		(start 216.28227 -229.413816)
		(end 216.0778 -229.209346)
		(width 0.15494)
		(layer "In5.Cu")
		(net "SMB_MB_I3C_ISO_SDA")
	)
	(segment
		(start 216.228676 -259.63626)
		(end 217.0176 -258.847336)
		(width 0.15494)
		(layer "In5.Cu")
		(net "SMB_MB_I3C_ISO_SDA")
	)
	(segment
		(start 217.0176 -258.306316)
		(end 218.203526 -257.12039)
		(width 0.15494)
		(layer "In5.Cu")
		(net "SMB_MB_I3C_ISO_SDA")
	)
	(segment
		(start 216.027 -236.080046)
		(end 216.28227 -235.824776)
		(width 0.15494)
		(layer "In5.Cu")
		(net "SMB_MB_I3C_ISO_SDA")
	)
	(segment
		(start 216.0778 -227.485448)
		(end 216.684606 -226.021138)
		(width 0.15494)
		(layer "In5.Cu")
		(net "SMB_MB_I3C_ISO_SDA")
	)
	(segment
		(start 216.28227 -235.824776)
		(end 216.28227 -229.413816)
		(width 0.15494)
		(layer "In5.Cu")
		(net "SMB_MB_I3C_ISO_SDA")
	)
	(segment
		(start 216.027 -237.975394)
		(end 216.027 -236.080046)
		(width 0.15494)
		(layer "In5.Cu")
		(net "SMB_MB_I3C_ISO_SDA")
	)
	(segment
		(start 218.203526 -240.797588)
		(end 216.483946 -239.078008)
		(width 0.15494)
		(layer "In5.Cu")
		(net "SMB_MB_I3C_ISO_SDA")
	)
	(segment
		(start 218.203526 -257.12039)
		(end 218.203526 -240.797588)
		(width 0.15494)
		(layer "In5.Cu")
		(net "SMB_MB_I3C_ISO_SDA")
	)
	(segment
		(start 217.0176 -258.847336)
		(end 217.0176 -258.306316)
		(width 0.15494)
		(layer "In5.Cu")
		(net "SMB_MB_I3C_ISO_SDA")
	)
	(segment
		(start 216.483946 -239.078008)
		(end 216.027 -237.975394)
		(width 0.15494)
		(layer "In5.Cu")
		(net "SMB_MB_I3C_ISO_SDA")
	)
	(segment
		(start 215.40978 -259.63626)
		(end 216.228676 -259.63626)
		(width 0.15494)
		(layer "In5.Cu")
		(net "SMB_MB_I3C_ISO_SDA")
	)
	(segment
		(start 216.684606 -224.397316)
		(end 216.453466 -223.635316)
		(width 0.15494)
		(layer "In5.Cu")
		(net "SMB_MB_I3C_ISO_SDA")
	)
	(segment
		(start 216.0778 -229.209346)
		(end 216.0778 -227.485448)
		(width 0.15494)
		(layer "In5.Cu")
		(net "SMB_MB_I3C_ISO_SDA")
	)
	(segment
		(start 216.453466 -223.635316)
		(end 216.200736 -223.382586)
		(width 0.15494)
		(layer "In5.Cu")
		(net "SMB_MB_I3C_ISO_SDA")
	)
	(segment
		(start 216.684606 -226.021138)
		(end 216.684606 -224.397316)
		(width 0.15494)
		(layer "In5.Cu")
		(net "SMB_MB_I3C_ISO_SDA")
	)
	(segment
		(start 237.254034 -339.01634)
		(end 234.21594 -339.01634)
		(width 0.15494)
		(layer "In9.Cu")
		(net "SMB_MB_I3C_ISO_SDA")
	)
	(segment
		(start 211.7598 -313.65317)
		(end 211.7598 -284.8356)
		(width 0.15494)
		(layer "In9.Cu")
		(net "SMB_MB_I3C_ISO_SDA")
	)
	(segment
		(start 234.21594 -339.01634)
		(end 228.8286 -333.629)
		(width 0.15494)
		(layer "In9.Cu")
		(net "SMB_MB_I3C_ISO_SDA")
	)
	(segment
		(start 378.492004 -353.092004)
		(end 379.383036 -353.983036)
		(width 0.15494)
		(layer "In9.Cu")
		(net "SMB_MB_I3C_ISO_SDA")
	)
	(segment
		(start 369.9891 -339.318346)
		(end 375.795286 -339.318346)
		(width 0.15494)
		(layer "In9.Cu")
		(net "SMB_MB_I3C_ISO_SDA")
	)
	(segment
		(start 383.177796 -362.987336)
		(end 391.926572 -362.987336)
		(width 0.15494)
		(layer "In9.Cu")
		(net "SMB_MB_I3C_ISO_SDA")
	)
	(segment
		(start 218.948 -277.6474)
		(end 218.948 -266.32027)
		(width 0.15494)
		(layer "In9.Cu")
		(net "SMB_MB_I3C_ISO_SDA")
	)
	(segment
		(start 376.282966 -352.261678)
		(end 377.113292 -353.092004)
		(width 0.15494)
		(layer "In9.Cu")
		(net "SMB_MB_I3C_ISO_SDA")
	)
	(segment
		(start 215.6206 -321.8942)
		(end 215.6206 -317.51397)
		(width 0.15494)
		(layer "In9.Cu")
		(net "SMB_MB_I3C_ISO_SDA")
	)
	(segment
		(start 376.282966 -339.806026)
		(end 376.282966 -352.261678)
		(width 0.15494)
		(layer "In9.Cu")
		(net "SMB_MB_I3C_ISO_SDA")
	)
	(segment
		(start 239.828578 -336.441796)
		(end 237.254034 -339.01634)
		(width 0.15494)
		(layer "In9.Cu")
		(net "SMB_MB_I3C_ISO_SDA")
	)
	(segment
		(start 361.881928 -330.607162)
		(end 361.881928 -331.211174)
		(width 0.15494)
		(layer "In9.Cu")
		(net "SMB_MB_I3C_ISO_SDA")
	)
	(segment
		(start 377.113292 -353.092004)
		(end 378.492004 -353.092004)
		(width 0.15494)
		(layer "In9.Cu")
		(net "SMB_MB_I3C_ISO_SDA")
	)
	(segment
		(start 211.7598 -284.8356)
		(end 218.948 -277.6474)
		(width 0.15494)
		(layer "In9.Cu")
		(net "SMB_MB_I3C_ISO_SDA")
	)
	(segment
		(start 379.383036 -353.983036)
		(end 379.383036 -359.192576)
		(width 0.15494)
		(layer "In9.Cu")
		(net "SMB_MB_I3C_ISO_SDA")
	)
	(segment
		(start 217.297 -323.5706)
		(end 215.6206 -321.8942)
		(width 0.15494)
		(layer "In9.Cu")
		(net "SMB_MB_I3C_ISO_SDA")
	)
	(segment
		(start 228.8286 -328.3458)
		(end 224.0534 -323.5706)
		(width 0.15494)
		(layer "In9.Cu")
		(net "SMB_MB_I3C_ISO_SDA")
	)
	(segment
		(start 375.795286 -339.318346)
		(end 376.282966 -339.806026)
		(width 0.15494)
		(layer "In9.Cu")
		(net "SMB_MB_I3C_ISO_SDA")
	)
	(segment
		(start 218.948 -266.32027)
		(end 216.723468 -260.949948)
		(width 0.15494)
		(layer "In9.Cu")
		(net "SMB_MB_I3C_ISO_SDA")
	)
	(segment
		(start 216.723468 -260.949948)
		(end 215.40978 -259.63626)
		(width 0.15494)
		(layer "In9.Cu")
		(net "SMB_MB_I3C_ISO_SDA")
	)
	(segment
		(start 228.8286 -333.629)
		(end 228.8286 -328.3458)
		(width 0.15494)
		(layer "In9.Cu")
		(net "SMB_MB_I3C_ISO_SDA")
	)
	(segment
		(start 379.383036 -359.192576)
		(end 383.177796 -362.987336)
		(width 0.15494)
		(layer "In9.Cu")
		(net "SMB_MB_I3C_ISO_SDA")
	)
	(segment
		(start 405.985726 -375.40057)
		(end 406.330404 -375.055892)
		(width 0.15494)
		(layer "In9.Cu")
		(net "SMB_MB_I3C_ISO_SDA")
	)
	(segment
		(start 239.828578 -335.467706)
		(end 239.828578 -336.441796)
		(width 0.15494)
		(layer "In9.Cu")
		(net "SMB_MB_I3C_ISO_SDA")
	)
	(segment
		(start 215.6206 -317.51397)
		(end 211.7598 -313.65317)
		(width 0.15494)
		(layer "In9.Cu")
		(net "SMB_MB_I3C_ISO_SDA")
	)
	(segment
		(start 361.881928 -331.211174)
		(end 369.9891 -339.318346)
		(width 0.15494)
		(layer "In9.Cu")
		(net "SMB_MB_I3C_ISO_SDA")
	)
	(segment
		(start 404.339806 -375.40057)
		(end 405.985726 -375.40057)
		(width 0.15494)
		(layer "In9.Cu")
		(net "SMB_MB_I3C_ISO_SDA")
	)
	(segment
		(start 391.926572 -362.987336)
		(end 404.339806 -375.40057)
		(width 0.15494)
		(layer "In9.Cu")
		(net "SMB_MB_I3C_ISO_SDA")
	)
	(segment
		(start 406.330404 -375.055892)
		(end 406.330404 -374.64746)
		(width 0.15494)
		(layer "In9.Cu")
		(net "SMB_MB_I3C_ISO_SDA")
	)
	(segment
		(start 224.0534 -323.5706)
		(end 217.297 -323.5706)
		(width 0.15494)
		(layer "In9.Cu")
		(net "SMB_MB_I3C_ISO_SDA")
	)
	(segment
		(start 405.680164 -375.71426)
		(end 405.680164 -374.707658)
		(width 0.13208)
		(layer "F.Cu")
		(net "SMB_MB_I3C_ISO_SCL")
	)
	(segment
		(start 405.680164 -374.707658)
		(end 405.647906 -374.6754)
		(width 0.13208)
		(layer "F.Cu")
		(net "SMB_MB_I3C_ISO_SCL")
	)
	(segment
		(start 216.154 -224.3582)
		(end 216.1032 -224.409)
		(width 0.13208)
		(layer "F.Cu")
		(net "SMB_MB_I3C_ISO_SCL")
	)
	(segment
		(start 215.7984 -223.8756)
		(end 214.653368 -223.8756)
		(width 0.13208)
		(layer "F.Cu")
		(net "SMB_MB_I3C_ISO_SCL")
	)
	(segment
		(start 216.79535 -224.3582)
		(end 216.154 -224.3582)
		(width 0.13208)
		(layer "F.Cu")
		(net "SMB_MB_I3C_ISO_SCL")
	)
	(segment
		(start 216.835736 -224.398586)
		(end 216.79535 -224.3582)
		(width 0.13208)
		(layer "F.Cu")
		(net "SMB_MB_I3C_ISO_SCL")
	)
	(segment
		(start 216.1032 -224.409)
		(end 216.1032 -224.1804)
		(width 0.13208)
		(layer "F.Cu")
		(net "SMB_MB_I3C_ISO_SCL")
	)
	(segment
		(start 216.1032 -224.1804)
		(end 215.7984 -223.8756)
		(width 0.13208)
		(layer "F.Cu")
		(net "SMB_MB_I3C_ISO_SCL")
	)
	(segment
		(start 214.653368 -223.8756)
		(end 214.130382 -224.398586)
		(width 0.13208)
		(layer "F.Cu")
		(net "SMB_MB_I3C_ISO_SCL")
	)
	(via
		(at 240.616232 -336.55889)
		(size 0.508)
		(drill 0.254)
		(layers "F.Cu" "B.Cu")
		(net "SMB_MB_I3C_ISO_SCL")
	)
	(via
		(at 405.647906 -374.6754)
		(size 0.508)
		(drill 0.254)
		(layers "F.Cu" "B.Cu")
		(net "SMB_MB_I3C_ISO_SCL")
	)
	(via
		(at 216.1032 -224.409)
		(size 0.508)
		(drill 0.254)
		(layers "F.Cu" "B.Cu")
		(net "SMB_MB_I3C_ISO_SCL")
	)
	(via
		(at 362.714286 -330.64704)
		(size 0.508)
		(drill 0.254)
		(layers "F.Cu" "B.Cu")
		(net "SMB_MB_I3C_ISO_SCL")
	)
	(via
		(at 215.40343 -258.90474)
		(size 0.508)
		(drill 0.254)
		(layers "F.Cu" "B.Cu")
		(net "SMB_MB_I3C_ISO_SCL")
	)
	(segment
		(start 240.616232 -335.499456)
		(end 240.616232 -336.55889)
		(width 0.13208)
		(layer "B.Cu")
		(net "SMB_MB_I3C_ISO_SCL")
	)
	(segment
		(start 241.672364 -334.443324)
		(end 240.616232 -335.499456)
		(width 0.13208)
		(layer "B.Cu")
		(net "SMB_MB_I3C_ISO_SCL")
	)
	(segment
		(start 405.393652 -376.092212)
		(end 405.393652 -375.579386)
		(width 0.13208)
		(layer "B.Cu")
		(net "SMB_MB_I3C_ISO_SCL")
	)
	(segment
		(start 362.714286 -330.791312)
		(end 359.062274 -334.443324)
		(width 0.13208)
		(layer "B.Cu")
		(net "SMB_MB_I3C_ISO_SCL")
	)
	(segment
		(start 405.647906 -375.325132)
		(end 405.647906 -374.6754)
		(width 0.13208)
		(layer "B.Cu")
		(net "SMB_MB_I3C_ISO_SCL")
	)
	(segment
		(start 359.062274 -334.443324)
		(end 241.672364 -334.443324)
		(width 0.13208)
		(layer "B.Cu")
		(net "SMB_MB_I3C_ISO_SCL")
	)
	(segment
		(start 405.393652 -375.579386)
		(end 405.647906 -375.325132)
		(width 0.13208)
		(layer "B.Cu")
		(net "SMB_MB_I3C_ISO_SCL")
	)
	(segment
		(start 362.714286 -330.64704)
		(end 362.714286 -330.791312)
		(width 0.13208)
		(layer "B.Cu")
		(net "SMB_MB_I3C_ISO_SCL")
	)
	(segment
		(start 217.489786 -241.093244)
		(end 217.489786 -256.251964)
		(width 0.15494)
		(layer "In5.Cu")
		(net "SMB_MB_I3C_ISO_SCL")
	)
	(segment
		(start 215.59647 -224.91573)
		(end 214.697056 -224.91573)
		(width 0.15494)
		(layer "In5.Cu")
		(net "SMB_MB_I3C_ISO_SCL")
	)
	(segment
		(start 214.68588 -230.31831)
		(end 214.68588 -236.604048)
		(width 0.15494)
		(layer "In5.Cu")
		(net "SMB_MB_I3C_ISO_SCL")
	)
	(segment
		(start 216.1032 -224.409)
		(end 215.59647 -224.91573)
		(width 0.15494)
		(layer "In5.Cu")
		(net "SMB_MB_I3C_ISO_SCL")
	)
	(segment
		(start 214.68588 -236.604048)
		(end 215.87841 -239.481868)
		(width 0.15494)
		(layer "In5.Cu")
		(net "SMB_MB_I3C_ISO_SCL")
	)
	(segment
		(start 214.697056 -224.91573)
		(end 213.312502 -226.300284)
		(width 0.15494)
		(layer "In5.Cu")
		(net "SMB_MB_I3C_ISO_SCL")
	)
	(segment
		(start 217.489786 -256.251964)
		(end 216.295732 -257.446018)
		(width 0.15494)
		(layer "In5.Cu")
		(net "SMB_MB_I3C_ISO_SCL")
	)
	(segment
		(start 215.87841 -239.481868)
		(end 217.489786 -241.093244)
		(width 0.15494)
		(layer "In5.Cu")
		(net "SMB_MB_I3C_ISO_SCL")
	)
	(segment
		(start 213.312502 -226.300284)
		(end 213.312502 -228.944932)
		(width 0.15494)
		(layer "In5.Cu")
		(net "SMB_MB_I3C_ISO_SCL")
	)
	(segment
		(start 215.658446 -258.90474)
		(end 215.40343 -258.90474)
		(width 0.15494)
		(layer "In5.Cu")
		(net "SMB_MB_I3C_ISO_SCL")
	)
	(segment
		(start 213.312502 -228.944932)
		(end 214.68588 -230.31831)
		(width 0.15494)
		(layer "In5.Cu")
		(net "SMB_MB_I3C_ISO_SCL")
	)
	(segment
		(start 216.295732 -258.267454)
		(end 215.658446 -258.90474)
		(width 0.15494)
		(layer "In5.Cu")
		(net "SMB_MB_I3C_ISO_SCL")
	)
	(segment
		(start 216.295732 -257.446018)
		(end 216.295732 -258.267454)
		(width 0.15494)
		(layer "In5.Cu")
		(net "SMB_MB_I3C_ISO_SCL")
	)
	(segment
		(start 362.714286 -330.64704)
		(end 362.988352 -331.308202)
		(width 0.15494)
		(layer "In9.Cu")
		(net "SMB_MB_I3C_ISO_SCL")
	)
	(segment
		(start 228.092 -333.9338)
		(end 233.9594 -339.8012)
		(width 0.15494)
		(layer "In9.Cu")
		(net "SMB_MB_I3C_ISO_SCL")
	)
	(segment
		(start 218.189048 -277.328122)
		(end 210.9978 -284.51937)
		(width 0.15494)
		(layer "In9.Cu")
		(net "SMB_MB_I3C_ISO_SCL")
	)
	(segment
		(start 237.706154 -339.8012)
		(end 240.616232 -336.891122)
		(width 0.15494)
		(layer "In9.Cu")
		(net "SMB_MB_I3C_ISO_SCL")
	)
	(segment
		(start 214.807038 -259.156962)
		(end 214.807038 -261.457186)
		(width 0.15494)
		(layer "In9.Cu")
		(net "SMB_MB_I3C_ISO_SCL")
	)
	(segment
		(start 233.9594 -339.8012)
		(end 237.706154 -339.8012)
		(width 0.15494)
		(layer "In9.Cu")
		(net "SMB_MB_I3C_ISO_SCL")
	)
	(segment
		(start 240.616232 -336.891122)
		(end 240.616232 -336.55889)
		(width 0.15494)
		(layer "In9.Cu")
		(net "SMB_MB_I3C_ISO_SCL")
	)
	(segment
		(start 215.40343 -258.90474)
		(end 215.05926 -258.90474)
		(width 0.15494)
		(layer "In9.Cu")
		(net "SMB_MB_I3C_ISO_SCL")
	)
	(segment
		(start 214.8586 -317.7794)
		(end 214.8586 -322.199)
		(width 0.15494)
		(layer "In9.Cu")
		(net "SMB_MB_I3C_ISO_SCL")
	)
	(segment
		(start 215.05926 -258.90474)
		(end 214.807038 -259.156962)
		(width 0.15494)
		(layer "In9.Cu")
		(net "SMB_MB_I3C_ISO_SCL")
	)
	(segment
		(start 379.383036 -352.131884)
		(end 380.75362 -353.502468)
		(width 0.15494)
		(layer "In9.Cu")
		(net "SMB_MB_I3C_ISO_SCL")
	)
	(segment
		(start 370.24437 -338.56422)
		(end 376.501914 -338.56422)
		(width 0.15494)
		(layer "In9.Cu")
		(net "SMB_MB_I3C_ISO_SCL")
	)
	(segment
		(start 210.9978 -284.51937)
		(end 210.9978 -313.9186)
		(width 0.15494)
		(layer "In9.Cu")
		(net "SMB_MB_I3C_ISO_SCL")
	)
	(segment
		(start 218.189048 -266.598146)
		(end 218.189048 -277.328122)
		(width 0.15494)
		(layer "In9.Cu")
		(net "SMB_MB_I3C_ISO_SCL")
	)
	(segment
		(start 385.676648 -362.084874)
		(end 392.033506 -362.084874)
		(width 0.15494)
		(layer "In9.Cu")
		(net "SMB_MB_I3C_ISO_SCL")
	)
	(segment
		(start 404.490682 -372.464076)
		(end 405.13 -373.103394)
		(width 0.15494)
		(layer "In9.Cu")
		(net "SMB_MB_I3C_ISO_SCL")
	)
	(segment
		(start 362.988352 -331.308202)
		(end 370.24437 -338.56422)
		(width 0.15494)
		(layer "In9.Cu")
		(net "SMB_MB_I3C_ISO_SCL")
	)
	(segment
		(start 382.515364 -353.84359)
		(end 382.515364 -358.92359)
		(width 0.15494)
		(layer "In9.Cu")
		(net "SMB_MB_I3C_ISO_SCL")
	)
	(segment
		(start 217.0176 -324.358)
		(end 223.7994 -324.358)
		(width 0.15494)
		(layer "In9.Cu")
		(net "SMB_MB_I3C_ISO_SCL")
	)
	(segment
		(start 392.033506 -362.084874)
		(end 402.412708 -372.464076)
		(width 0.15494)
		(layer "In9.Cu")
		(net "SMB_MB_I3C_ISO_SCL")
	)
	(segment
		(start 405.13 -373.103394)
		(end 405.13 -374.157494)
		(width 0.15494)
		(layer "In9.Cu")
		(net "SMB_MB_I3C_ISO_SCL")
	)
	(segment
		(start 382.174242 -353.502468)
		(end 382.515364 -353.84359)
		(width 0.15494)
		(layer "In9.Cu")
		(net "SMB_MB_I3C_ISO_SCL")
	)
	(segment
		(start 216.945464 -263.595612)
		(end 218.189048 -266.598146)
		(width 0.15494)
		(layer "In9.Cu")
		(net "SMB_MB_I3C_ISO_SCL")
	)
	(segment
		(start 376.501914 -338.56422)
		(end 379.383036 -341.445342)
		(width 0.15494)
		(layer "In9.Cu")
		(net "SMB_MB_I3C_ISO_SCL")
	)
	(segment
		(start 379.383036 -341.445342)
		(end 379.383036 -352.131884)
		(width 0.15494)
		(layer "In9.Cu")
		(net "SMB_MB_I3C_ISO_SCL")
	)
	(segment
		(start 405.13 -374.157494)
		(end 405.647906 -374.6754)
		(width 0.15494)
		(layer "In9.Cu")
		(net "SMB_MB_I3C_ISO_SCL")
	)
	(segment
		(start 382.515364 -358.92359)
		(end 385.676648 -362.084874)
		(width 0.15494)
		(layer "In9.Cu")
		(net "SMB_MB_I3C_ISO_SCL")
	)
	(segment
		(start 228.092 -328.6506)
		(end 228.092 -333.9338)
		(width 0.15494)
		(layer "In9.Cu")
		(net "SMB_MB_I3C_ISO_SCL")
	)
	(segment
		(start 214.8586 -322.199)
		(end 217.0176 -324.358)
		(width 0.15494)
		(layer "In9.Cu")
		(net "SMB_MB_I3C_ISO_SCL")
	)
	(segment
		(start 210.9978 -313.9186)
		(end 214.8586 -317.7794)
		(width 0.15494)
		(layer "In9.Cu")
		(net "SMB_MB_I3C_ISO_SCL")
	)
	(segment
		(start 402.412708 -372.464076)
		(end 404.490682 -372.464076)
		(width 0.15494)
		(layer "In9.Cu")
		(net "SMB_MB_I3C_ISO_SCL")
	)
	(segment
		(start 223.7994 -324.358)
		(end 228.092 -328.6506)
		(width 0.15494)
		(layer "In9.Cu")
		(net "SMB_MB_I3C_ISO_SCL")
	)
	(segment
		(start 214.807038 -261.457186)
		(end 216.945464 -263.595612)
		(width 0.15494)
		(layer "In9.Cu")
		(net "SMB_MB_I3C_ISO_SCL")
	)
	(segment
		(start 380.75362 -353.502468)
		(end 382.174242 -353.502468)
		(width 0.15494)
		(layer "In9.Cu")
		(net "SMB_MB_I3C_ISO_SCL")
	)
	(segment
		(start 408.559 -383.26695)
		(end 408.559 -382.524)
		(width 0.13208)
		(layer "F.Cu")
		(net "MB_I3C_ISO_EN")
	)
	(segment
		(start 407.05532 -380.417832)
		(end 407.05532 -380.064264)
		(width 0.13208)
		(layer "F.Cu")
		(net "MB_I3C_ISO_EN")
	)
	(segment
		(start 408.559 -381.921512)
		(end 407.05532 -380.417832)
		(width 0.13208)
		(layer "F.Cu")
		(net "MB_I3C_ISO_EN")
	)
	(segment
		(start 408.559 -382.524)
		(end 408.559 -381.921512)
		(width 0.13208)
		(layer "F.Cu")
		(net "MB_I3C_ISO_EN")
	)
	(via
		(at 408.559 -382.524)
		(size 0.508)
		(drill 0.254)
		(layers "F.Cu" "B.Cu")
		(net "MB_I3C_ISO_EN")
	)
	(segment
		(start 228.267768 -212.704172)
		(end 228.667564 -212.304376)
		(width 0.13208)
		(layer "F.Cu")
		(net "Net_587")
	)
	(via
		(at 228.667564 -212.304376)
		(size 0.4572)
		(drill 0.254)
		(layers "F.Cu" "B.Cu")
		(net "Net_587")
	)
	(segment
		(start 61.632592 -390.23671)
		(end 64.40551 -390.23671)
		(width 0.13208)
		(layer "F.Cu")
		(net "GPU_HGX_DETECT_R_N")
	)
	(segment
		(start 64.36741 -386.37591)
		(end 62.26175 -386.37591)
		(width 0.13208)
		(layer "F.Cu")
		(net "GPU_HGX_DETECT_R_N")
	)
	(segment
		(start 64.86906 -386.87756)
		(end 64.36741 -386.37591)
		(width 0.13208)
		(layer "F.Cu")
		(net "GPU_HGX_DETECT_R_N")
	)
	(segment
		(start 60.358782 -384.472942)
		(end 60.358782 -384.024886)
		(width 0.13208)
		(layer "F.Cu")
		(net "GPU_HGX_DETECT_R_N")
	)
	(segment
		(start 62.26175 -386.37591)
		(end 60.358782 -384.472942)
		(width 0.13208)
		(layer "F.Cu")
		(net "GPU_HGX_DETECT_R_N")
	)
	(segment
		(start 64.40551 -390.23671)
		(end 64.86906 -389.77316)
		(width 0.13208)
		(layer "F.Cu")
		(net "GPU_HGX_DETECT_R_N")
	)
	(segment
		(start 60.389262 -389.67156)
		(end 61.067442 -389.67156)
		(width 0.13208)
		(layer "F.Cu")
		(net "GPU_HGX_DETECT_R_N")
	)
	(segment
		(start 61.067442 -389.67156)
		(end 61.632592 -390.23671)
		(width 0.13208)
		(layer "F.Cu")
		(net "GPU_HGX_DETECT_R_N")
	)
	(segment
		(start 64.86906 -389.77316)
		(end 64.86906 -386.87756)
		(width 0.13208)
		(layer "F.Cu")
		(net "GPU_HGX_DETECT_R_N")
	)
	(via
		(at 60.358782 -384.024886)
		(size 0.508)
		(drill 0.254)
		(layers "F.Cu" "B.Cu")
		(net "GPU_HGX_DETECT_R_N")
	)
	(segment
		(start 71.503286 -412.693358)
		(end 75.706732 -412.693358)
		(width 0.15494)
		(layer "In9.Cu")
		(net "GPU_HGX_DETECT_R_N")
	)
	(segment
		(start 75.706732 -412.693358)
		(end 76.309982 -412.090108)
		(width 0.15494)
		(layer "In9.Cu")
		(net "GPU_HGX_DETECT_R_N")
	)
	(segment
		(start 70.149974 -390.368028)
		(end 70.149974 -411.340046)
		(width 0.15494)
		(layer "In9.Cu")
		(net "GPU_HGX_DETECT_R_N")
	)
	(segment
		(start 64.380364 -384.598418)
		(end 70.149974 -390.368028)
		(width 0.15494)
		(layer "In9.Cu")
		(net "GPU_HGX_DETECT_R_N")
	)
	(segment
		(start 70.149974 -411.340046)
		(end 71.503286 -412.693358)
		(width 0.15494)
		(layer "In9.Cu")
		(net "GPU_HGX_DETECT_R_N")
	)
	(segment
		(start 60.932314 -384.598418)
		(end 64.380364 -384.598418)
		(width 0.15494)
		(layer "In9.Cu")
		(net "GPU_HGX_DETECT_R_N")
	)
	(segment
		(start 60.358782 -384.024886)
		(end 60.932314 -384.598418)
		(width 0.15494)
		(layer "In9.Cu")
		(net "GPU_HGX_DETECT_R_N")
	)
	(segment
		(start 226.667568 -215.904064)
		(end 226.267772 -215.504268)
		(width 0.13208)
		(layer "F.Cu")
		(net "Net_589")
	)
	(via
		(at 226.267772 -215.504268)
		(size 0.4572)
		(drill 0.254)
		(layers "F.Cu" "B.Cu")
		(net "Net_589")
	)
	(segment
		(start 199.147684 -406.511252)
		(end 197.889622 -406.511252)
		(width 0.13208)
		(layer "F.Cu")
		(net "MB_HSC_EN")
	)
	(segment
		(start 201.06894 -406.295352)
		(end 200.01738 -406.295352)
		(width 0.13208)
		(layer "F.Cu")
		(net "MB_HSC_EN")
	)
	(segment
		(start 199.357742 -406.301194)
		(end 199.147684 -406.511252)
		(width 0.13208)
		(layer "F.Cu")
		(net "MB_HSC_EN")
	)
	(segment
		(start 200.01738 -406.295352)
		(end 200.011538 -406.301194)
		(width 0.13208)
		(layer "F.Cu")
		(net "MB_HSC_EN")
	)
	(segment
		(start 197.739 -406.36063)
		(end 197.739 -405.95804)
		(width 0.13208)
		(layer "F.Cu")
		(net "MB_HSC_EN")
	)
	(segment
		(start 197.889622 -406.511252)
		(end 197.739 -406.36063)
		(width 0.13208)
		(layer "F.Cu")
		(net "MB_HSC_EN")
	)
	(segment
		(start 200.011538 -406.301194)
		(end 199.357742 -406.301194)
		(width 0.13208)
		(layer "F.Cu")
		(net "MB_HSC_EN")
	)
	(via
		(at 199.147684 -406.511252)
		(size 0.508)
		(drill 0.254)
		(layers "F.Cu" "B.Cu")
		(net "MB_HSC_EN")
	)
	(via
		(at 190.357506 -370.529358)
		(size 0.508)
		(drill 0.254)
		(layers "F.Cu" "B.Cu")
		(net "MB_HSC_EN")
	)
	(segment
		(start 202.481942 -362.740194)
		(end 202.481942 -361.25404)
		(width 0.13208)
		(layer "B.Cu")
		(net "MB_HSC_EN")
	)
	(segment
		(start 200.906888 -359.678986)
		(end 200.906888 -358.351074)
		(width 0.13208)
		(layer "B.Cu")
		(net "MB_HSC_EN")
	)
	(segment
		(start 270.037814 -360.402886)
		(end 344.807286 -360.402886)
		(width 0.13208)
		(layer "B.Cu")
		(net "MB_HSC_EN")
	)
	(segment
		(start 190.828422 -370.529358)
		(end 197.271132 -364.086648)
		(width 0.13208)
		(layer "B.Cu")
		(net "MB_HSC_EN")
	)
	(segment
		(start 200.023476 -364.707932)
		(end 201.05116 -363.680248)
		(width 0.13208)
		(layer "B.Cu")
		(net "MB_HSC_EN")
	)
	(segment
		(start 346.890086 -361.437936)
		(end 346.890086 -368.990118)
		(width 0.13208)
		(layer "B.Cu")
		(net "MB_HSC_EN")
	)
	(segment
		(start 197.271132 -364.086648)
		(end 197.897242 -364.086648)
		(width 0.13208)
		(layer "B.Cu")
		(net "MB_HSC_EN")
	)
	(segment
		(start 190.357506 -370.529358)
		(end 190.828422 -370.529358)
		(width 0.13208)
		(layer "B.Cu")
		(net "MB_HSC_EN")
	)
	(segment
		(start 346.86875 -361.4166)
		(end 346.890086 -361.437936)
		(width 0.13208)
		(layer "B.Cu")
		(net "MB_HSC_EN")
	)
	(segment
		(start 201.541888 -363.680248)
		(end 202.481942 -362.740194)
		(width 0.13208)
		(layer "B.Cu")
		(net "MB_HSC_EN")
	)
	(segment
		(start 265.04265 -349.605092)
		(end 265.04265 -355.407722)
		(width 0.13208)
		(layer "B.Cu")
		(net "MB_HSC_EN")
	)
	(segment
		(start 201.05116 -363.680248)
		(end 201.541888 -363.680248)
		(width 0.13208)
		(layer "B.Cu")
		(net "MB_HSC_EN")
	)
	(segment
		(start 200.906888 -358.351074)
		(end 202.481942 -356.77602)
		(width 0.13208)
		(layer "B.Cu")
		(net "MB_HSC_EN")
	)
	(segment
		(start 251.54636 -343.581482)
		(end 252.664722 -344.699844)
		(width 0.13208)
		(layer "B.Cu")
		(net "MB_HSC_EN")
	)
	(segment
		(start 222.010478 -341.994998)
		(end 223.596962 -343.581482)
		(width 0.13208)
		(layer "B.Cu")
		(net "MB_HSC_EN")
	)
	(segment
		(start 260.137402 -344.699844)
		(end 265.04265 -349.605092)
		(width 0.13208)
		(layer "B.Cu")
		(net "MB_HSC_EN")
	)
	(segment
		(start 344.807286 -360.402886)
		(end 345.821 -361.4166)
		(width 0.13208)
		(layer "B.Cu")
		(net "MB_HSC_EN")
	)
	(segment
		(start 197.897242 -364.086648)
		(end 198.518526 -364.707932)
		(width 0.13208)
		(layer "B.Cu")
		(net "MB_HSC_EN")
	)
	(segment
		(start 252.664722 -344.699844)
		(end 260.137402 -344.699844)
		(width 0.13208)
		(layer "B.Cu")
		(net "MB_HSC_EN")
	)
	(segment
		(start 202.481942 -348.822518)
		(end 209.309462 -341.994998)
		(width 0.13208)
		(layer "B.Cu")
		(net "MB_HSC_EN")
	)
	(segment
		(start 265.04265 -355.407722)
		(end 270.037814 -360.402886)
		(width 0.13208)
		(layer "B.Cu")
		(net "MB_HSC_EN")
	)
	(segment
		(start 198.518526 -364.707932)
		(end 200.023476 -364.707932)
		(width 0.13208)
		(layer "B.Cu")
		(net "MB_HSC_EN")
	)
	(segment
		(start 202.481942 -361.25404)
		(end 200.906888 -359.678986)
		(width 0.13208)
		(layer "B.Cu")
		(net "MB_HSC_EN")
	)
	(segment
		(start 209.309462 -341.994998)
		(end 222.010478 -341.994998)
		(width 0.13208)
		(layer "B.Cu")
		(net "MB_HSC_EN")
	)
	(segment
		(start 202.481942 -356.77602)
		(end 202.481942 -348.822518)
		(width 0.13208)
		(layer "B.Cu")
		(net "MB_HSC_EN")
	)
	(segment
		(start 345.821 -361.4166)
		(end 346.86875 -361.4166)
		(width 0.13208)
		(layer "B.Cu")
		(net "MB_HSC_EN")
	)
	(segment
		(start 223.596962 -343.581482)
		(end 251.54636 -343.581482)
		(width 0.13208)
		(layer "B.Cu")
		(net "MB_HSC_EN")
	)
	(segment
		(start 197.622668 -406.511252)
		(end 199.147684 -406.511252)
		(width 0.15494)
		(layer "In5.Cu")
		(net "MB_HSC_EN")
	)
	(segment
		(start 186.813952 -375.904506)
		(end 186.813952 -402.510752)
		(width 0.15494)
		(layer "In5.Cu")
		(net "MB_HSC_EN")
	)
	(segment
		(start 189.935358 -405.632158)
		(end 196.743574 -405.632158)
		(width 0.15494)
		(layer "In5.Cu")
		(net "MB_HSC_EN")
	)
	(segment
		(start 190.357506 -370.529358)
		(end 190.357506 -372.360952)
		(width 0.15494)
		(layer "In5.Cu")
		(net "MB_HSC_EN")
	)
	(segment
		(start 196.743574 -405.632158)
		(end 197.622668 -406.511252)
		(width 0.15494)
		(layer "In5.Cu")
		(net "MB_HSC_EN")
	)
	(segment
		(start 186.813952 -402.510752)
		(end 189.935358 -405.632158)
		(width 0.15494)
		(layer "In5.Cu")
		(net "MB_HSC_EN")
	)
	(segment
		(start 190.357506 -372.360952)
		(end 186.813952 -375.904506)
		(width 0.15494)
		(layer "In5.Cu")
		(net "MB_HSC_EN")
	)
	(segment
		(start 353.099878 -254.588518)
		(end 353.099878 -255.291082)
		(width 0.13208)
		(layer "F.Cu")
		(net "NC_P0V8_PEX2_PWM6")
	)
	(segment
		(start 353.175824 -255.370584)
		(end 353.175824 -255.994916)
		(width 0.13208)
		(layer "F.Cu")
		(net "NC_P0V8_PEX2_PWM6")
	)
	(segment
		(start 353.099878 -255.291082)
		(end 353.109784 -255.300988)
		(width 0.13208)
		(layer "F.Cu")
		(net "NC_P0V8_PEX2_PWM6")
	)
	(segment
		(start 353.109784 -255.300988)
		(end 353.109784 -255.304544)
		(width 0.13208)
		(layer "F.Cu")
		(net "NC_P0V8_PEX2_PWM6")
	)
	(segment
		(start 353.421188 -254.267208)
		(end 353.099878 -254.588518)
		(width 0.13208)
		(layer "F.Cu")
		(net "NC_P0V8_PEX2_PWM6")
	)
	(segment
		(start 353.109784 -255.304544)
		(end 353.175824 -255.370584)
		(width 0.13208)
		(layer "F.Cu")
		(net "NC_P0V8_PEX2_PWM6")
	)
	(via
		(at 353.421188 -254.267208)
		(size 0.762)
		(drill 0.381)
		(layers "F.Cu" "B.Cu")
		(net "NC_P0V8_PEX2_PWM6")
	)
	(segment
		(start 352.776028 -254.684784)
		(end 352.776028 -255.994916)
		(width 0.13208)
		(layer "F.Cu")
		(net "NC_P0V8_PEX2_PWM5")
	)
	(segment
		(start 352.828098 -254.632714)
		(end 352.776028 -254.684784)
		(width 0.13208)
		(layer "F.Cu")
		(net "NC_P0V8_PEX2_PWM5")
	)
	(segment
		(start 352.828098 -253.590298)
		(end 352.828098 -254.632714)
		(width 0.13208)
		(layer "F.Cu")
		(net "NC_P0V8_PEX2_PWM5")
	)
	(segment
		(start 353.421188 -252.997208)
		(end 352.828098 -253.590298)
		(width 0.13208)
		(layer "F.Cu")
		(net "NC_P0V8_PEX2_PWM5")
	)
	(via
		(at 353.421188 -252.997208)
		(size 0.762)
		(drill 0.381)
		(layers "F.Cu" "B.Cu")
		(net "NC_P0V8_PEX2_PWM5")
	)
	(segment
		(start 353.175824 -260.967982)
		(end 353.175824 -260.795008)
		(width 0.13208)
		(layer "F.Cu")
		(net "NC_P0V8_PEX2_ISEN6")
	)
	(segment
		(start 351.041208 -264.758678)
		(end 351.426272 -265.143742)
		(width 0.13208)
		(layer "F.Cu")
		(net "NC_P0V8_PEX2_ISEN6")
	)
	(segment
		(start 351.426272 -265.143742)
		(end 351.949512 -265.143742)
		(width 0.13208)
		(layer "F.Cu")
		(net "NC_P0V8_PEX2_ISEN6")
	)
	(segment
		(start 349.849948 -265.949938)
		(end 351.041208 -264.758678)
		(width 0.13208)
		(layer "F.Cu")
		(net "NC_P0V8_PEX2_ISEN6")
	)
	(segment
		(start 351.949512 -265.143742)
		(end 353.271328 -263.821926)
		(width 0.13208)
		(layer "F.Cu")
		(net "NC_P0V8_PEX2_ISEN6")
	)
	(segment
		(start 353.271328 -263.821926)
		(end 353.271328 -261.199122)
		(width 0.13208)
		(layer "F.Cu")
		(net "NC_P0V8_PEX2_ISEN6")
	)
	(segment
		(start 347.939614 -265.949938)
		(end 349.849948 -265.949938)
		(width 0.13208)
		(layer "F.Cu")
		(net "NC_P0V8_PEX2_ISEN6")
	)
	(segment
		(start 353.271328 -261.199122)
		(end 353.175824 -260.967982)
		(width 0.13208)
		(layer "F.Cu")
		(net "NC_P0V8_PEX2_ISEN6")
	)
	(via
		(at 351.041208 -264.758678)
		(size 0.762)
		(drill 0.381)
		(layers "F.Cu" "B.Cu")
		(net "NC_P0V8_PEX2_ISEN6")
	)
	(segment
		(start 351.792032 -264.537444)
		(end 351.366836 -264.112248)
		(width 0.13208)
		(layer "F.Cu")
		(net "NC_P0V8_PEX2_ISEN5")
	)
	(segment
		(start 349.18015 -264.95756)
		(end 349.522034 -264.615676)
		(width 0.13208)
		(layer "F.Cu")
		(net "NC_P0V8_PEX2_ISEN5")
	)
	(segment
		(start 352.9838 -261.289292)
		(end 352.9838 -263.654286)
		(width 0.13208)
		(layer "F.Cu")
		(net "NC_P0V8_PEX2_ISEN5")
	)
	(segment
		(start 352.9838 -263.654286)
		(end 352.100642 -264.537444)
		(width 0.13208)
		(layer "F.Cu")
		(net "NC_P0V8_PEX2_ISEN5")
	)
	(segment
		(start 350.242124 -264.615676)
		(end 349.522034 -264.615676)
		(width 0.13208)
		(layer "F.Cu")
		(net "NC_P0V8_PEX2_ISEN5")
	)
	(segment
		(start 351.366836 -264.112248)
		(end 350.745552 -264.112248)
		(width 0.13208)
		(layer "F.Cu")
		(net "NC_P0V8_PEX2_ISEN5")
	)
	(segment
		(start 350.745552 -264.112248)
		(end 350.242124 -264.615676)
		(width 0.13208)
		(layer "F.Cu")
		(net "NC_P0V8_PEX2_ISEN5")
	)
	(segment
		(start 347.959172 -264.95756)
		(end 349.18015 -264.95756)
		(width 0.13208)
		(layer "F.Cu")
		(net "NC_P0V8_PEX2_ISEN5")
	)
	(segment
		(start 352.100642 -264.537444)
		(end 351.792032 -264.537444)
		(width 0.13208)
		(layer "F.Cu")
		(net "NC_P0V8_PEX2_ISEN5")
	)
	(segment
		(start 352.776028 -260.795008)
		(end 352.776028 -261.08152)
		(width 0.13208)
		(layer "F.Cu")
		(net "NC_P0V8_PEX2_ISEN5")
	)
	(segment
		(start 352.776028 -261.08152)
		(end 352.9838 -261.289292)
		(width 0.13208)
		(layer "F.Cu")
		(net "NC_P0V8_PEX2_ISEN5")
	)
	(via
		(at 349.522034 -264.615676)
		(size 0.762)
		(drill 0.381)
		(layers "F.Cu" "B.Cu")
		(net "NC_P0V8_PEX2_ISEN5")
	)
	(segment
		(start 214.921592 -222.295466)
		(end 215.418416 -222.295466)
		(width 0.13208)
		(layer "F.Cu")
		(net "SMB_BIC_FPGA_R_SDA")
	)
	(segment
		(start 342.011 -233.97464)
		(end 342.519 -231.420416)
		(width 0.13208)
		(layer "F.Cu")
		(net "SMB_BIC_FPGA_R_SDA")
	)
	(segment
		(start 342.011 -235.077)
		(end 342.011 -233.97464)
		(width 0.13208)
		(layer "F.Cu")
		(net "SMB_BIC_FPGA_R_SDA")
	)
	(segment
		(start 342.773 -231.166416)
		(end 342.773 -228.345746)
		(width 0.13208)
		(layer "F.Cu")
		(net "SMB_BIC_FPGA_R_SDA")
	)
	(segment
		(start 214.83828 -222.378778)
		(end 214.921592 -222.295466)
		(width 0.13208)
		(layer "F.Cu")
		(net "SMB_BIC_FPGA_R_SDA")
	)
	(segment
		(start 342.519 -231.420416)
		(end 342.773 -231.166416)
		(width 0.13208)
		(layer "F.Cu")
		(net "SMB_BIC_FPGA_R_SDA")
	)
	(segment
		(start 342.893904 -228.224842)
		(end 342.893904 -227.987098)
		(width 0.13208)
		(layer "F.Cu")
		(net "SMB_BIC_FPGA_R_SDA")
	)
	(segment
		(start 215.418416 -222.295466)
		(end 215.489536 -222.366586)
		(width 0.13208)
		(layer "F.Cu")
		(net "SMB_BIC_FPGA_R_SDA")
	)
	(segment
		(start 342.773 -228.345746)
		(end 342.893904 -228.224842)
		(width 0.13208)
		(layer "F.Cu")
		(net "SMB_BIC_FPGA_R_SDA")
	)
	(via
		(at 342.011 -235.077)
		(size 0.508)
		(drill 0.254)
		(layers "F.Cu" "B.Cu")
		(net "SMB_BIC_FPGA_R_SDA")
	)
	(via
		(at 216.66962 -237.41126)
		(size 0.508)
		(drill 0.254)
		(layers "F.Cu" "B.Cu")
		(net "SMB_BIC_FPGA_R_SDA")
	)
	(via
		(at 215.489536 -222.366586)
		(size 0.508)
		(drill 0.254)
		(layers "F.Cu" "B.Cu")
		(net "SMB_BIC_FPGA_R_SDA")
	)
	(segment
		(start 215.489536 -222.366586)
		(end 215.485218 -222.370904)
		(width 0.13208)
		(layer "B.Cu")
		(net "SMB_BIC_FPGA_R_SDA")
	)
	(segment
		(start 215.485218 -222.370904)
		(end 214.832692 -222.370904)
		(width 0.13208)
		(layer "B.Cu")
		(net "SMB_BIC_FPGA_R_SDA")
	)
	(segment
		(start 216.8144 -228.7778)
		(end 216.8144 -227.573078)
		(width 0.15494)
		(layer "In5.Cu")
		(net "SMB_BIC_FPGA_R_SDA")
	)
	(segment
		(start 217.398346 -224.226628)
		(end 217.21318 -223.30918)
		(width 0.15494)
		(layer "In5.Cu")
		(net "SMB_BIC_FPGA_R_SDA")
	)
	(segment
		(start 215.999822 -222.850456)
		(end 215.874854 -222.725488)
		(width 0.15494)
		(layer "In5.Cu")
		(net "SMB_BIC_FPGA_R_SDA")
	)
	(segment
		(start 217.0684 -237.01248)
		(end 217.0684 -232.3084)
		(width 0.15494)
		(layer "In5.Cu")
		(net "SMB_BIC_FPGA_R_SDA")
	)
	(segment
		(start 216.66962 -237.41126)
		(end 217.0684 -237.01248)
		(width 0.15494)
		(layer "In5.Cu")
		(net "SMB_BIC_FPGA_R_SDA")
	)
	(segment
		(start 215.874854 -222.725488)
		(end 215.848438 -222.725488)
		(width 0.15494)
		(layer "In5.Cu")
		(net "SMB_BIC_FPGA_R_SDA")
	)
	(segment
		(start 215.848438 -222.725488)
		(end 215.489536 -222.366586)
		(width 0.15494)
		(layer "In5.Cu")
		(net "SMB_BIC_FPGA_R_SDA")
	)
	(segment
		(start 217.0176 -232.2576)
		(end 217.0176 -228.981)
		(width 0.15494)
		(layer "In5.Cu")
		(net "SMB_BIC_FPGA_R_SDA")
	)
	(segment
		(start 217.21318 -223.30918)
		(end 216.754456 -222.850456)
		(width 0.15494)
		(layer "In5.Cu")
		(net "SMB_BIC_FPGA_R_SDA")
	)
	(segment
		(start 217.0684 -232.3084)
		(end 217.0176 -232.2576)
		(width 0.15494)
		(layer "In5.Cu")
		(net "SMB_BIC_FPGA_R_SDA")
	)
	(segment
		(start 217.398346 -226.163378)
		(end 217.398346 -224.226628)
		(width 0.15494)
		(layer "In5.Cu")
		(net "SMB_BIC_FPGA_R_SDA")
	)
	(segment
		(start 216.754456 -222.850456)
		(end 215.999822 -222.850456)
		(width 0.15494)
		(layer "In5.Cu")
		(net "SMB_BIC_FPGA_R_SDA")
	)
	(segment
		(start 217.0176 -228.981)
		(end 216.8144 -228.7778)
		(width 0.15494)
		(layer "In5.Cu")
		(net "SMB_BIC_FPGA_R_SDA")
	)
	(segment
		(start 216.8144 -227.573078)
		(end 217.398346 -226.163378)
		(width 0.15494)
		(layer "In5.Cu")
		(net "SMB_BIC_FPGA_R_SDA")
	)
	(segment
		(start 269.713456 -235.687616)
		(end 269.808452 -235.687616)
		(width 0.15494)
		(layer "In15.Cu")
		(net "SMB_BIC_FPGA_R_SDA")
	)
	(segment
		(start 272.27022 -237.565184)
		(end 272.50009 -237.335314)
		(width 0.15494)
		(layer "In15.Cu")
		(net "SMB_BIC_FPGA_R_SDA")
	)
	(segment
		(start 270.38046 -236.35462)
		(end 270.38046 -236.49686)
		(width 0.15494)
		(layer "In15.Cu")
		(net "SMB_BIC_FPGA_R_SDA")
	)
	(segment
		(start 325.073518 -237.881414)
		(end 325.64451 -237.881414)
		(width 0.15494)
		(layer "In15.Cu")
		(net "SMB_BIC_FPGA_R_SDA")
	)
	(segment
		(start 342.011 -234.61853)
		(end 342.011 -235.077)
		(width 0.15494)
		(layer "In15.Cu")
		(net "SMB_BIC_FPGA_R_SDA")
	)
	(segment
		(start 270.360902 -236.240066)
		(end 270.360902 -236.335062)
		(width 0.15494)
		(layer "In15.Cu")
		(net "SMB_BIC_FPGA_R_SDA")
	)
	(segment
		(start 216.66962 -237.41126)
		(end 216.66962 -236.827568)
		(width 0.15494)
		(layer "In15.Cu")
		(net "SMB_BIC_FPGA_R_SDA")
	)
	(segment
		(start 231.094534 -235.70946)
		(end 231.67721 -236.292136)
		(width 0.15494)
		(layer "In15.Cu")
		(net "SMB_BIC_FPGA_R_SDA")
	)
	(segment
		(start 334.151732 -234.052364)
		(end 336.755486 -234.052364)
		(width 0.15494)
		(layer "In15.Cu")
		(net "SMB_BIC_FPGA_R_SDA")
	)
	(segment
		(start 247.066308 -234.66806)
		(end 250.701556 -231.032812)
		(width 0.15494)
		(layer "In15.Cu")
		(net "SMB_BIC_FPGA_R_SDA")
	)
	(segment
		(start 257.672078 -229.23246)
		(end 258.309618 -229.87)
		(width 0.15494)
		(layer "In15.Cu")
		(net "SMB_BIC_FPGA_R_SDA")
	)
	(segment
		(start 328.68489 -236.76864)
		(end 330.2508 -235.20273)
		(width 0.15494)
		(layer "In15.Cu")
		(net "SMB_BIC_FPGA_R_SDA")
	)
	(segment
		(start 319.251838 -237.335314)
		(end 320.423286 -238.506762)
		(width 0.15494)
		(layer "In15.Cu")
		(net "SMB_BIC_FPGA_R_SDA")
	)
	(segment
		(start 216.66962 -236.827568)
		(end 217.787728 -235.70946)
		(width 0.15494)
		(layer "In15.Cu")
		(net "SMB_BIC_FPGA_R_SDA")
	)
	(segment
		(start 241.689636 -234.66806)
		(end 247.066308 -234.66806)
		(width 0.15494)
		(layer "In15.Cu")
		(net "SMB_BIC_FPGA_R_SDA")
	)
	(segment
		(start 325.64451 -237.881414)
		(end 326.757284 -236.76864)
		(width 0.15494)
		(layer "In15.Cu")
		(net "SMB_BIC_FPGA_R_SDA")
	)
	(segment
		(start 326.757284 -236.76864)
		(end 328.68489 -236.76864)
		(width 0.15494)
		(layer "In15.Cu")
		(net "SMB_BIC_FPGA_R_SDA")
	)
	(segment
		(start 252.252988 -231.032812)
		(end 254.05334 -229.23246)
		(width 0.15494)
		(layer "In15.Cu")
		(net "SMB_BIC_FPGA_R_SDA")
	)
	(segment
		(start 337.0326 -233.77525)
		(end 341.16772 -233.77525)
		(width 0.15494)
		(layer "In15.Cu")
		(net "SMB_BIC_FPGA_R_SDA")
	)
	(segment
		(start 231.67721 -236.292136)
		(end 240.06556 -236.292136)
		(width 0.15494)
		(layer "In15.Cu")
		(net "SMB_BIC_FPGA_R_SDA")
	)
	(segment
		(start 265.0109 -230.98506)
		(end 269.713456 -235.687616)
		(width 0.15494)
		(layer "In15.Cu")
		(net "SMB_BIC_FPGA_R_SDA")
	)
	(segment
		(start 269.808452 -235.687616)
		(end 270.360902 -236.240066)
		(width 0.15494)
		(layer "In15.Cu")
		(net "SMB_BIC_FPGA_R_SDA")
	)
	(segment
		(start 333.862172 -234.341924)
		(end 334.151732 -234.052364)
		(width 0.15494)
		(layer "In15.Cu")
		(net "SMB_BIC_FPGA_R_SDA")
	)
	(segment
		(start 324.44817 -238.506762)
		(end 325.073518 -237.881414)
		(width 0.15494)
		(layer "In15.Cu")
		(net "SMB_BIC_FPGA_R_SDA")
	)
	(segment
		(start 330.2508 -235.20273)
		(end 332.328774 -234.341924)
		(width 0.15494)
		(layer "In15.Cu")
		(net "SMB_BIC_FPGA_R_SDA")
	)
	(segment
		(start 250.701556 -231.032812)
		(end 252.252988 -231.032812)
		(width 0.15494)
		(layer "In15.Cu")
		(net "SMB_BIC_FPGA_R_SDA")
	)
	(segment
		(start 341.16772 -233.77525)
		(end 342.011 -234.61853)
		(width 0.15494)
		(layer "In15.Cu")
		(net "SMB_BIC_FPGA_R_SDA")
	)
	(segment
		(start 270.389096 -236.7915)
		(end 271.16278 -237.565184)
		(width 0.15494)
		(layer "In15.Cu")
		(net "SMB_BIC_FPGA_R_SDA")
	)
	(segment
		(start 258.309618 -229.87)
		(end 262.86968 -229.87)
		(width 0.15494)
		(layer "In15.Cu")
		(net "SMB_BIC_FPGA_R_SDA")
	)
	(segment
		(start 332.328774 -234.341924)
		(end 333.862172 -234.341924)
		(width 0.15494)
		(layer "In15.Cu")
		(net "SMB_BIC_FPGA_R_SDA")
	)
	(segment
		(start 270.389096 -236.505496)
		(end 270.389096 -236.7915)
		(width 0.15494)
		(layer "In15.Cu")
		(net "SMB_BIC_FPGA_R_SDA")
	)
	(segment
		(start 240.06556 -236.292136)
		(end 241.689636 -234.66806)
		(width 0.15494)
		(layer "In15.Cu")
		(net "SMB_BIC_FPGA_R_SDA")
	)
	(segment
		(start 262.86968 -229.87)
		(end 263.98474 -230.98506)
		(width 0.15494)
		(layer "In15.Cu")
		(net "SMB_BIC_FPGA_R_SDA")
	)
	(segment
		(start 320.423286 -238.506762)
		(end 324.44817 -238.506762)
		(width 0.15494)
		(layer "In15.Cu")
		(net "SMB_BIC_FPGA_R_SDA")
	)
	(segment
		(start 270.38046 -236.49686)
		(end 270.389096 -236.505496)
		(width 0.15494)
		(layer "In15.Cu")
		(net "SMB_BIC_FPGA_R_SDA")
	)
	(segment
		(start 270.360902 -236.335062)
		(end 270.38046 -236.35462)
		(width 0.15494)
		(layer "In15.Cu")
		(net "SMB_BIC_FPGA_R_SDA")
	)
	(segment
		(start 254.05334 -229.23246)
		(end 257.672078 -229.23246)
		(width 0.15494)
		(layer "In15.Cu")
		(net "SMB_BIC_FPGA_R_SDA")
	)
	(segment
		(start 336.755486 -234.052364)
		(end 337.0326 -233.77525)
		(width 0.15494)
		(layer "In15.Cu")
		(net "SMB_BIC_FPGA_R_SDA")
	)
	(segment
		(start 271.16278 -237.565184)
		(end 272.27022 -237.565184)
		(width 0.15494)
		(layer "In15.Cu")
		(net "SMB_BIC_FPGA_R_SDA")
	)
	(segment
		(start 263.98474 -230.98506)
		(end 265.0109 -230.98506)
		(width 0.15494)
		(layer "In15.Cu")
		(net "SMB_BIC_FPGA_R_SDA")
	)
	(segment
		(start 217.787728 -235.70946)
		(end 231.094534 -235.70946)
		(width 0.15494)
		(layer "In15.Cu")
		(net "SMB_BIC_FPGA_R_SDA")
	)
	(segment
		(start 272.50009 -237.335314)
		(end 319.251838 -237.335314)
		(width 0.15494)
		(layer "In15.Cu")
		(net "SMB_BIC_FPGA_R_SDA")
	)
	(segment
		(start 343.290144 -227.583238)
		(end 342.893904 -227.186998)
		(width 0.13208)
		(layer "F.Cu")
		(net "SMB_BIC_FPGA_R_SCL")
	)
	(segment
		(start 343.283794 -228.6)
		(end 343.290144 -228.59365)
		(width 0.13208)
		(layer "F.Cu")
		(net "SMB_BIC_FPGA_R_SCL")
	)
	(segment
		(start 343.290144 -228.59365)
		(end 343.290144 -227.583238)
		(width 0.13208)
		(layer "F.Cu")
		(net "SMB_BIC_FPGA_R_SCL")
	)
	(via
		(at 218.084654 -237.36427)
		(size 0.508)
		(drill 0.254)
		(layers "F.Cu" "B.Cu")
		(net "SMB_BIC_FPGA_R_SCL")
	)
	(via
		(at 215.489536 -221.350586)
		(size 0.508)
		(drill 0.254)
		(layers "F.Cu" "B.Cu")
		(net "SMB_BIC_FPGA_R_SCL")
	)
	(via
		(at 343.283794 -228.6)
		(size 0.508)
		(drill 0.254)
		(layers "F.Cu" "B.Cu")
		(net "SMB_BIC_FPGA_R_SCL")
	)
	(via
		(at 335.166716 -235.09859)
		(size 0.508)
		(drill 0.254)
		(layers "F.Cu" "B.Cu")
		(net "SMB_BIC_FPGA_R_SCL")
	)
	(segment
		(start 216.52992 -220.83903)
		(end 216.001092 -220.83903)
		(width 0.13208)
		(layer "B.Cu")
		(net "SMB_BIC_FPGA_R_SCL")
	)
	(segment
		(start 214.213186 -221.350586)
		(end 215.489536 -221.350586)
		(width 0.13208)
		(layer "B.Cu")
		(net "SMB_BIC_FPGA_R_SCL")
	)
	(segment
		(start 216.001092 -220.83903)
		(end 215.489536 -221.350586)
		(width 0.13208)
		(layer "B.Cu")
		(net "SMB_BIC_FPGA_R_SCL")
	)
	(segment
		(start 216.835736 -221.144846)
		(end 216.52992 -220.83903)
		(width 0.13208)
		(layer "B.Cu")
		(net "SMB_BIC_FPGA_R_SCL")
	)
	(segment
		(start 216.835736 -221.350586)
		(end 216.835736 -221.144846)
		(width 0.13208)
		(layer "B.Cu")
		(net "SMB_BIC_FPGA_R_SCL")
	)
	(segment
		(start 217.858086 -224.175574)
		(end 217.858086 -226.353878)
		(width 0.15494)
		(layer "In5.Cu")
		(net "SMB_BIC_FPGA_R_SCL")
	)
	(segment
		(start 217.8558 -226.379278)
		(end 218.666822 -227.1903)
		(width 0.15494)
		(layer "In5.Cu")
		(net "SMB_BIC_FPGA_R_SCL")
	)
	(segment
		(start 216.021666 -221.882716)
		(end 216.650316 -221.882716)
		(width 0.15494)
		(layer "In5.Cu")
		(net "SMB_BIC_FPGA_R_SCL")
	)
	(segment
		(start 217.8558 -226.356164)
		(end 217.8558 -226.379278)
		(width 0.15494)
		(layer "In5.Cu")
		(net "SMB_BIC_FPGA_R_SCL")
	)
	(segment
		(start 217.858086 -226.353878)
		(end 217.8558 -226.356164)
		(width 0.15494)
		(layer "In5.Cu")
		(net "SMB_BIC_FPGA_R_SCL")
	)
	(segment
		(start 216.650316 -221.882716)
		(end 217.591132 -222.823532)
		(width 0.15494)
		(layer "In5.Cu")
		(net "SMB_BIC_FPGA_R_SCL")
	)
	(segment
		(start 218.666822 -227.1903)
		(end 218.666822 -230.871522)
		(width 0.15494)
		(layer "In5.Cu")
		(net "SMB_BIC_FPGA_R_SCL")
	)
	(segment
		(start 218.084654 -231.45369)
		(end 218.084654 -237.36427)
		(width 0.15494)
		(layer "In5.Cu")
		(net "SMB_BIC_FPGA_R_SCL")
	)
	(segment
		(start 215.489536 -221.350586)
		(end 216.021666 -221.882716)
		(width 0.15494)
		(layer "In5.Cu")
		(net "SMB_BIC_FPGA_R_SCL")
	)
	(segment
		(start 217.591132 -222.823532)
		(end 217.858086 -224.175574)
		(width 0.15494)
		(layer "In5.Cu")
		(net "SMB_BIC_FPGA_R_SCL")
	)
	(segment
		(start 218.666822 -230.871522)
		(end 218.084654 -231.45369)
		(width 0.15494)
		(layer "In5.Cu")
		(net "SMB_BIC_FPGA_R_SCL")
	)
	(segment
		(start 335.166716 -235.09859)
		(end 335.188306 -235.09859)
		(width 0.15494)
		(layer "In9.Cu")
		(net "SMB_BIC_FPGA_R_SCL")
	)
	(segment
		(start 335.188306 -235.09859)
		(end 339.451696 -230.8352)
		(width 0.15494)
		(layer "In9.Cu")
		(net "SMB_BIC_FPGA_R_SCL")
	)
	(segment
		(start 341.048594 -230.8352)
		(end 343.283794 -228.6)
		(width 0.15494)
		(layer "In9.Cu")
		(net "SMB_BIC_FPGA_R_SCL")
	)
	(segment
		(start 339.451696 -230.8352)
		(end 341.048594 -230.8352)
		(width 0.15494)
		(layer "In9.Cu")
		(net "SMB_BIC_FPGA_R_SCL")
	)
	(segment
		(start 252.148594 -231.883966)
		(end 253.2253 -230.80726)
		(width 0.15494)
		(layer "In15.Cu")
		(net "SMB_BIC_FPGA_R_SCL")
	)
	(segment
		(start 269.617952 -236.147356)
		(end 269.901162 -236.430566)
		(width 0.15494)
		(layer "In15.Cu")
		(net "SMB_BIC_FPGA_R_SCL")
	)
	(segment
		(start 333.17688 -235.2802)
		(end 333.48422 -235.58754)
		(width 0.15494)
		(layer "In15.Cu")
		(net "SMB_BIC_FPGA_R_SCL")
	)
	(segment
		(start 264.8204 -231.4448)
		(end 269.522956 -236.147356)
		(width 0.15494)
		(layer "In15.Cu")
		(net "SMB_BIC_FPGA_R_SCL")
	)
	(segment
		(start 231.517444 -236.78261)
		(end 240.524792 -236.78261)
		(width 0.15494)
		(layer "In15.Cu")
		(net "SMB_BIC_FPGA_R_SCL")
	)
	(segment
		(start 247.236996 -235.147612)
		(end 250.500642 -231.883966)
		(width 0.15494)
		(layer "In15.Cu")
		(net "SMB_BIC_FPGA_R_SCL")
	)
	(segment
		(start 276.426676 -238.040418)
		(end 276.861778 -238.47552)
		(width 0.15494)
		(layer "In15.Cu")
		(net "SMB_BIC_FPGA_R_SCL")
	)
	(segment
		(start 256.376932 -230.01224)
		(end 257.801618 -230.01224)
		(width 0.15494)
		(layer "In15.Cu")
		(net "SMB_BIC_FPGA_R_SCL")
	)
	(segment
		(start 328.87539 -237.22838)
		(end 330.431902 -235.671868)
		(width 0.15494)
		(layer "In15.Cu")
		(net "SMB_BIC_FPGA_R_SCL")
	)
	(segment
		(start 250.500642 -231.883966)
		(end 252.148594 -231.883966)
		(width 0.15494)
		(layer "In15.Cu")
		(net "SMB_BIC_FPGA_R_SCL")
	)
	(segment
		(start 219.279724 -236.1692)
		(end 230.904034 -236.1692)
		(width 0.15494)
		(layer "In15.Cu")
		(net "SMB_BIC_FPGA_R_SCL")
	)
	(segment
		(start 269.901162 -236.525562)
		(end 269.92072 -236.54512)
		(width 0.15494)
		(layer "In15.Cu")
		(net "SMB_BIC_FPGA_R_SCL")
	)
	(segment
		(start 333.48422 -235.58754)
		(end 334.690974 -235.58754)
		(width 0.15494)
		(layer "In15.Cu")
		(net "SMB_BIC_FPGA_R_SCL")
	)
	(segment
		(start 325.83501 -238.341154)
		(end 326.947784 -237.22838)
		(width 0.15494)
		(layer "In15.Cu")
		(net "SMB_BIC_FPGA_R_SCL")
	)
	(segment
		(start 326.947784 -237.22838)
		(end 328.87539 -237.22838)
		(width 0.15494)
		(layer "In15.Cu")
		(net "SMB_BIC_FPGA_R_SCL")
	)
	(segment
		(start 270.987774 -238.040418)
		(end 276.426676 -238.040418)
		(width 0.15494)
		(layer "In15.Cu")
		(net "SMB_BIC_FPGA_R_SCL")
	)
	(segment
		(start 246.497348 -235.147612)
		(end 247.236996 -235.147612)
		(width 0.15494)
		(layer "In15.Cu")
		(net "SMB_BIC_FPGA_R_SCL")
	)
	(segment
		(start 330.431902 -235.671868)
		(end 331.377544 -235.2802)
		(width 0.15494)
		(layer "In15.Cu")
		(net "SMB_BIC_FPGA_R_SCL")
	)
	(segment
		(start 218.084654 -237.36427)
		(end 219.279724 -236.1692)
		(width 0.15494)
		(layer "In15.Cu")
		(net "SMB_BIC_FPGA_R_SCL")
	)
	(segment
		(start 276.861778 -238.47552)
		(end 301.840138 -238.47552)
		(width 0.15494)
		(layer "In15.Cu")
		(net "SMB_BIC_FPGA_R_SCL")
	)
	(segment
		(start 241.168428 -236.139228)
		(end 245.505732 -236.139228)
		(width 0.15494)
		(layer "In15.Cu")
		(net "SMB_BIC_FPGA_R_SCL")
	)
	(segment
		(start 319.362328 -238.43996)
		(end 319.88887 -238.966502)
		(width 0.15494)
		(layer "In15.Cu")
		(net "SMB_BIC_FPGA_R_SCL")
	)
	(segment
		(start 255.581912 -230.80726)
		(end 256.376932 -230.01224)
		(width 0.15494)
		(layer "In15.Cu")
		(net "SMB_BIC_FPGA_R_SCL")
	)
	(segment
		(start 253.2253 -230.80726)
		(end 255.581912 -230.80726)
		(width 0.15494)
		(layer "In15.Cu")
		(net "SMB_BIC_FPGA_R_SCL")
	)
	(segment
		(start 269.92072 -236.54512)
		(end 269.92072 -236.973364)
		(width 0.15494)
		(layer "In15.Cu")
		(net "SMB_BIC_FPGA_R_SCL")
	)
	(segment
		(start 240.5761 -236.731556)
		(end 241.168428 -236.139228)
		(width 0.15494)
		(layer "In15.Cu")
		(net "SMB_BIC_FPGA_R_SCL")
	)
	(segment
		(start 240.575846 -236.731556)
		(end 240.5761 -236.731556)
		(width 0.15494)
		(layer "In15.Cu")
		(net "SMB_BIC_FPGA_R_SCL")
	)
	(segment
		(start 324.63867 -238.966502)
		(end 325.264018 -238.341154)
		(width 0.15494)
		(layer "In15.Cu")
		(net "SMB_BIC_FPGA_R_SCL")
	)
	(segment
		(start 331.377544 -235.2802)
		(end 333.17688 -235.2802)
		(width 0.15494)
		(layer "In15.Cu")
		(net "SMB_BIC_FPGA_R_SCL")
	)
	(segment
		(start 262.609076 -230.32974)
		(end 263.724136 -231.4448)
		(width 0.15494)
		(layer "In15.Cu")
		(net "SMB_BIC_FPGA_R_SCL")
	)
	(segment
		(start 301.840138 -238.47552)
		(end 301.875698 -238.43996)
		(width 0.15494)
		(layer "In15.Cu")
		(net "SMB_BIC_FPGA_R_SCL")
	)
	(segment
		(start 301.875698 -238.43996)
		(end 319.362328 -238.43996)
		(width 0.15494)
		(layer "In15.Cu")
		(net "SMB_BIC_FPGA_R_SCL")
	)
	(segment
		(start 240.524792 -236.78261)
		(end 240.575846 -236.731556)
		(width 0.15494)
		(layer "In15.Cu")
		(net "SMB_BIC_FPGA_R_SCL")
	)
	(segment
		(start 335.166716 -235.111798)
		(end 335.166716 -235.09859)
		(width 0.15494)
		(layer "In15.Cu")
		(net "SMB_BIC_FPGA_R_SCL")
	)
	(segment
		(start 325.264018 -238.341154)
		(end 325.83501 -238.341154)
		(width 0.15494)
		(layer "In15.Cu")
		(net "SMB_BIC_FPGA_R_SCL")
	)
	(segment
		(start 319.88887 -238.966502)
		(end 324.63867 -238.966502)
		(width 0.15494)
		(layer "In15.Cu")
		(net "SMB_BIC_FPGA_R_SCL")
	)
	(segment
		(start 269.92072 -236.973364)
		(end 270.987774 -238.040418)
		(width 0.15494)
		(layer "In15.Cu")
		(net "SMB_BIC_FPGA_R_SCL")
	)
	(segment
		(start 230.904034 -236.1692)
		(end 231.517444 -236.78261)
		(width 0.15494)
		(layer "In15.Cu")
		(net "SMB_BIC_FPGA_R_SCL")
	)
	(segment
		(start 245.505732 -236.139228)
		(end 246.497348 -235.147612)
		(width 0.15494)
		(layer "In15.Cu")
		(net "SMB_BIC_FPGA_R_SCL")
	)
	(segment
		(start 269.901162 -236.430566)
		(end 269.901162 -236.525562)
		(width 0.15494)
		(layer "In15.Cu")
		(net "SMB_BIC_FPGA_R_SCL")
	)
	(segment
		(start 334.690974 -235.58754)
		(end 335.166716 -235.111798)
		(width 0.15494)
		(layer "In15.Cu")
		(net "SMB_BIC_FPGA_R_SCL")
	)
	(segment
		(start 258.119118 -230.32974)
		(end 262.609076 -230.32974)
		(width 0.15494)
		(layer "In15.Cu")
		(net "SMB_BIC_FPGA_R_SCL")
	)
	(segment
		(start 257.801618 -230.01224)
		(end 258.119118 -230.32974)
		(width 0.15494)
		(layer "In15.Cu")
		(net "SMB_BIC_FPGA_R_SCL")
	)
	(segment
		(start 263.724136 -231.4448)
		(end 264.8204 -231.4448)
		(width 0.15494)
		(layer "In15.Cu")
		(net "SMB_BIC_FPGA_R_SCL")
	)
	(segment
		(start 269.522956 -236.147356)
		(end 269.617952 -236.147356)
		(width 0.15494)
		(layer "In15.Cu")
		(net "SMB_BIC_FPGA_R_SCL")
	)
	(segment
		(start 244.431566 -238.388144)
		(end 243.787676 -239.032034)
		(width 0.13208)
		(layer "F.Cu")
		(net "SMB_BIC_RECOVER_IOEXP_SDA")
	)
	(segment
		(start 244.431566 -237.802166)
		(end 244.431566 -237.142528)
		(width 0.13208)
		(layer "F.Cu")
		(net "SMB_BIC_RECOVER_IOEXP_SDA")
	)
	(segment
		(start 244.431566 -237.802166)
		(end 244.431566 -238.388144)
		(width 0.13208)
		(layer "F.Cu")
		(net "SMB_BIC_RECOVER_IOEXP_SDA")
	)
	(segment
		(start 244.431566 -237.142528)
		(end 244.492018 -237.082076)
		(width 0.13208)
		(layer "F.Cu")
		(net "SMB_BIC_RECOVER_IOEXP_SDA")
	)
	(segment
		(start 243.787676 -239.032034)
		(end 243.787676 -239.883442)
		(width 0.13208)
		(layer "F.Cu")
		(net "SMB_BIC_RECOVER_IOEXP_SDA")
	)
	(via
		(at 244.431566 -237.802166)
		(size 0.508)
		(drill 0.254)
		(layers "F.Cu" "B.Cu")
		(net "SMB_BIC_RECOVER_IOEXP_SDA")
	)
	(segment
		(start 243.13769 -237.420404)
		(end 243.13769 -237.845092)
		(width 0.13208)
		(layer "F.Cu")
		(net "SMB_BIC_RECOVER_IOEXP_SCL")
	)
	(segment
		(start 243.476018 -237.082076)
		(end 243.13769 -237.420404)
		(width 0.13208)
		(layer "F.Cu")
		(net "SMB_BIC_RECOVER_IOEXP_SCL")
	)
	(segment
		(start 243.13769 -237.845092)
		(end 243.13769 -239.883442)
		(width 0.13208)
		(layer "F.Cu")
		(net "SMB_BIC_RECOVER_IOEXP_SCL")
	)
	(via
		(at 243.13769 -237.845092)
		(size 0.508)
		(drill 0.254)
		(layers "F.Cu" "B.Cu")
		(net "SMB_BIC_RECOVER_IOEXP_SCL")
	)
	(segment
		(start 236.154214 -245.619524)
		(end 236.154214 -249.170952)
		(width 0.13208)
		(layer "F.Cu")
		(net "BIC_UART_BMC_SEL_R")
	)
	(segment
		(start 228.899466 -243.62791)
		(end 226.158806 -240.88725)
		(width 0.13208)
		(layer "F.Cu")
		(net "BIC_UART_BMC_SEL_R")
	)
	(segment
		(start 234.60329 -243.62791)
		(end 236.154214 -245.178834)
		(width 0.13208)
		(layer "F.Cu")
		(net "BIC_UART_BMC_SEL_R")
	)
	(segment
		(start 236.154214 -245.178834)
		(end 236.154214 -245.619524)
		(width 0.13208)
		(layer "F.Cu")
		(net "BIC_UART_BMC_SEL_R")
	)
	(segment
		(start 230.156512 -243.62791)
		(end 228.899466 -243.62791)
		(width 0.13208)
		(layer "F.Cu")
		(net "BIC_UART_BMC_SEL_R")
	)
	(segment
		(start 236.154214 -249.170952)
		(end 238.143034 -251.159772)
		(width 0.13208)
		(layer "F.Cu")
		(net "BIC_UART_BMC_SEL_R")
	)
	(segment
		(start 226.158806 -240.88725)
		(end 225.152712 -240.88725)
		(width 0.13208)
		(layer "F.Cu")
		(net "BIC_UART_BMC_SEL_R")
	)
	(segment
		(start 230.156512 -243.62791)
		(end 234.60329 -243.62791)
		(width 0.13208)
		(layer "F.Cu")
		(net "BIC_UART_BMC_SEL_R")
	)
	(segment
		(start 238.143034 -251.159772)
		(end 240.200434 -251.159772)
		(width 0.13208)
		(layer "F.Cu")
		(net "BIC_UART_BMC_SEL_R")
	)
	(via
		(at 236.154214 -245.619524)
		(size 0.508)
		(drill 0.254)
		(layers "F.Cu" "B.Cu")
		(net "BIC_UART_BMC_SEL_R")
	)
	(segment
		(start 240.200434 -248.34469)
		(end 241.837718 -246.707406)
		(width 0.13208)
		(layer "F.Cu")
		(net "BIC_UART_BMC_SEL")
	)
	(segment
		(start 241.837718 -246.707406)
		(end 241.837718 -245.73357)
		(width 0.13208)
		(layer "F.Cu")
		(net "BIC_UART_BMC_SEL")
	)
	(segment
		(start 240.200434 -249.476514)
		(end 240.200434 -248.34469)
		(width 0.13208)
		(layer "F.Cu")
		(net "BIC_UART_BMC_SEL")
	)
	(segment
		(start 240.200434 -250.359672)
		(end 240.200434 -249.476514)
		(width 0.13208)
		(layer "F.Cu")
		(net "BIC_UART_BMC_SEL")
	)
	(via
		(at 240.200434 -249.476514)
		(size 0.508)
		(drill 0.254)
		(layers "F.Cu" "B.Cu")
		(net "BIC_UART_BMC_SEL")
	)
	(segment
		(start 225.152712 -239.93729)
		(end 225.061526 -239.846104)
		(width 0.13208)
		(layer "F.Cu")
		(net "BIC_UART_BIC_SEL_R")
	)
	(segment
		(start 225.061526 -239.846104)
		(end 223.45396 -239.846104)
		(width 0.13208)
		(layer "F.Cu")
		(net "BIC_UART_BIC_SEL_R")
	)
	(segment
		(start 221.033086 -241.143536)
		(end 222.330518 -239.846104)
		(width 0.13208)
		(layer "F.Cu")
		(net "BIC_UART_BIC_SEL_R")
	)
	(segment
		(start 222.330518 -239.846104)
		(end 223.45396 -239.846104)
		(width 0.13208)
		(layer "F.Cu")
		(net "BIC_UART_BIC_SEL_R")
	)
	(via
		(at 215.579706 -215.254586)
		(size 0.508)
		(drill 0.254)
		(layers "F.Cu" "B.Cu")
		(net "BIC_UART_BIC_SEL_R")
	)
	(via
		(at 221.033086 -241.143536)
		(size 0.508)
		(drill 0.254)
		(layers "F.Cu" "B.Cu")
		(net "BIC_UART_BIC_SEL_R")
	)
	(segment
		(start 215.579706 -215.254586)
		(end 215.579706 -215.164416)
		(width 0.13208)
		(layer "B.Cu")
		(net "BIC_UART_BIC_SEL_R")
	)
	(segment
		(start 215.579706 -215.164416)
		(end 215.96477 -214.779352)
		(width 0.13208)
		(layer "B.Cu")
		(net "BIC_UART_BIC_SEL_R")
	)
	(segment
		(start 215.96477 -214.779352)
		(end 216.421208 -214.779352)
		(width 0.13208)
		(layer "B.Cu")
		(net "BIC_UART_BIC_SEL_R")
	)
	(segment
		(start 216.421208 -214.779352)
		(end 216.835736 -215.19388)
		(width 0.13208)
		(layer "B.Cu")
		(net "BIC_UART_BIC_SEL_R")
	)
	(segment
		(start 216.835736 -215.19388)
		(end 216.835736 -215.254586)
		(width 0.13208)
		(layer "B.Cu")
		(net "BIC_UART_BIC_SEL_R")
	)
	(segment
		(start 219.460826 -218.107006)
		(end 219.460826 -218.909646)
		(width 0.15494)
		(layer "In5.Cu")
		(net "BIC_UART_BIC_SEL_R")
	)
	(segment
		(start 215.579706 -215.344756)
		(end 215.974422 -215.739472)
		(width 0.15494)
		(layer "In5.Cu")
		(net "BIC_UART_BIC_SEL_R")
	)
	(segment
		(start 219.460826 -218.909646)
		(end 218.825826 -219.544646)
		(width 0.15494)
		(layer "In5.Cu")
		(net "BIC_UART_BIC_SEL_R")
	)
	(segment
		(start 215.579706 -215.254586)
		(end 215.579706 -215.344756)
		(width 0.15494)
		(layer "In5.Cu")
		(net "BIC_UART_BIC_SEL_R")
	)
	(segment
		(start 218.7702 -231.418384)
		(end 218.7702 -231.418638)
		(width 0.15494)
		(layer "In5.Cu")
		(net "BIC_UART_BIC_SEL_R")
	)
	(segment
		(start 219.126562 -231.062022)
		(end 218.7702 -231.418384)
		(width 0.15494)
		(layer "In5.Cu")
		(net "BIC_UART_BIC_SEL_R")
	)
	(segment
		(start 219.126562 -226.9998)
		(end 219.126562 -231.062022)
		(width 0.15494)
		(layer "In5.Cu")
		(net "BIC_UART_BIC_SEL_R")
	)
	(segment
		(start 218.82608 -224.363534)
		(end 218.82608 -226.699318)
		(width 0.15494)
		(layer "In5.Cu")
		(net "BIC_UART_BIC_SEL_R")
	)
	(segment
		(start 218.544394 -231.644444)
		(end 218.544394 -234.368848)
		(width 0.15494)
		(layer "In5.Cu")
		(net "BIC_UART_BIC_SEL_R")
	)
	(segment
		(start 218.825826 -219.544646)
		(end 218.825826 -224.36328)
		(width 0.15494)
		(layer "In5.Cu")
		(net "BIC_UART_BIC_SEL_R")
	)
	(segment
		(start 218.839034 -234.663488)
		(end 218.839034 -238.949484)
		(width 0.15494)
		(layer "In5.Cu")
		(net "BIC_UART_BIC_SEL_R")
	)
	(segment
		(start 218.825826 -224.36328)
		(end 218.82608 -224.363534)
		(width 0.15494)
		(layer "In5.Cu")
		(net "BIC_UART_BIC_SEL_R")
	)
	(segment
		(start 218.82608 -226.699318)
		(end 219.126562 -226.9998)
		(width 0.15494)
		(layer "In5.Cu")
		(net "BIC_UART_BIC_SEL_R")
	)
	(segment
		(start 215.974422 -215.739472)
		(end 217.093292 -215.739472)
		(width 0.15494)
		(layer "In5.Cu")
		(net "BIC_UART_BIC_SEL_R")
	)
	(segment
		(start 218.7702 -231.418638)
		(end 218.544394 -231.644444)
		(width 0.15494)
		(layer "In5.Cu")
		(net "BIC_UART_BIC_SEL_R")
	)
	(segment
		(start 218.839034 -238.949484)
		(end 221.033086 -241.143536)
		(width 0.15494)
		(layer "In5.Cu")
		(net "BIC_UART_BIC_SEL_R")
	)
	(segment
		(start 218.544394 -234.368848)
		(end 218.839034 -234.663488)
		(width 0.15494)
		(layer "In5.Cu")
		(net "BIC_UART_BIC_SEL_R")
	)
	(segment
		(start 217.093292 -215.739472)
		(end 219.460826 -218.107006)
		(width 0.15494)
		(layer "In5.Cu")
		(net "BIC_UART_BIC_SEL_R")
	)
	(segment
		(start 228.849682 -238.98733)
		(end 228.90226 -238.934752)
		(width 0.13208)
		(layer "F.Cu")
		(net "BIC_UART_SW_SEL1")
	)
	(segment
		(start 228.90226 -238.934752)
		(end 229.630478 -238.934752)
		(width 0.13208)
		(layer "F.Cu")
		(net "BIC_UART_SW_SEL1")
	)
	(segment
		(start 227.602796 -238.98733)
		(end 228.849682 -238.98733)
		(width 0.13208)
		(layer "F.Cu")
		(net "BIC_UART_SW_SEL1")
	)
	(via
		(at 228.849682 -238.98733)
		(size 0.508)
		(drill 0.254)
		(layers "F.Cu" "B.Cu")
		(net "BIC_UART_SW_SEL1")
	)
	(segment
		(start 241.216434 -248.391934)
		(end 242.487704 -247.120664)
		(width 0.13208)
		(layer "F.Cu")
		(net "BIC_FWSPICK_IOEXP")
	)
	(segment
		(start 242.487704 -247.120664)
		(end 242.487704 -245.73357)
		(width 0.13208)
		(layer "F.Cu")
		(net "BIC_FWSPICK_IOEXP")
	)
	(segment
		(start 241.216434 -250.359672)
		(end 241.216434 -248.391934)
		(width 0.13208)
		(layer "F.Cu")
		(net "BIC_FWSPICK_IOEXP")
	)
	(via
		(at 241.216434 -248.391934)
		(size 0.508)
		(drill 0.254)
		(layers "F.Cu" "B.Cu")
		(net "BIC_FWSPICK_IOEXP")
	)
	(segment
		(start 244.537484 -245.73357)
		(end 244.537484 -248.733564)
		(width 0.13208)
		(layer "F.Cu")
		(net "IRQ_BIC_RECOVER_IOEXP_N")
	)
	(segment
		(start 244.537484 -248.733564)
		(end 245.280434 -249.476514)
		(width 0.13208)
		(layer "F.Cu")
		(net "IRQ_BIC_RECOVER_IOEXP_N")
	)
	(segment
		(start 245.280434 -249.476514)
		(end 245.280434 -250.359672)
		(width 0.13208)
		(layer "F.Cu")
		(net "IRQ_BIC_RECOVER_IOEXP_N")
	)
	(via
		(at 245.280434 -249.476514)
		(size 0.508)
		(drill 0.254)
		(layers "F.Cu" "B.Cu")
		(net "IRQ_BIC_RECOVER_IOEXP_N")
	)
	(segment
		(start 243.13769 -247.149366)
		(end 243.13769 -245.73357)
		(width 0.13208)
		(layer "F.Cu")
		(net "RST_BIC_RECOVER_N")
	)
	(segment
		(start 242.232434 -248.054622)
		(end 243.13769 -247.149366)
		(width 0.13208)
		(layer "F.Cu")
		(net "RST_BIC_RECOVER_N")
	)
	(segment
		(start 242.232434 -249.476514)
		(end 242.232434 -248.054622)
		(width 0.13208)
		(layer "F.Cu")
		(net "RST_BIC_RECOVER_N")
	)
	(segment
		(start 242.232434 -250.359672)
		(end 242.232434 -249.476514)
		(width 0.13208)
		(layer "F.Cu")
		(net "RST_BIC_RECOVER_N")
	)
	(via
		(at 242.232434 -249.476514)
		(size 0.508)
		(drill 0.254)
		(layers "F.Cu" "B.Cu")
		(net "RST_BIC_RECOVER_N")
	)
	(segment
		(start 243.248434 -250.359672)
		(end 244.264434 -250.359672)
		(width 0.13208)
		(layer "F.Cu")
		(net "BIC_RECOVER_IOEXP_A1")
	)
	(segment
		(start 243.787676 -247.852692)
		(end 243.787676 -245.73357)
		(width 0.13208)
		(layer "F.Cu")
		(net "BIC_RECOVER_IOEXP_A1")
	)
	(segment
		(start 243.248434 -249.343672)
		(end 243.248434 -248.391934)
		(width 0.13208)
		(layer "F.Cu")
		(net "BIC_RECOVER_IOEXP_A1")
	)
	(segment
		(start 244.264434 -250.359672)
		(end 243.248434 -249.343672)
		(width 0.13208)
		(layer "F.Cu")
		(net "BIC_RECOVER_IOEXP_A1")
	)
	(segment
		(start 243.248434 -248.391934)
		(end 243.787676 -247.852692)
		(width 0.13208)
		(layer "F.Cu")
		(net "BIC_RECOVER_IOEXP_A1")
	)
	(via
		(at 243.248434 -248.391934)
		(size 0.508)
		(drill 0.254)
		(layers "F.Cu" "B.Cu")
		(net "BIC_RECOVER_IOEXP_A1")
	)
	(segment
		(start 194.5259 -357.534718)
		(end 199.039734 -357.534718)
		(width 0.13208)
		(layer "F.Cu")
		(net "PD_MB_HSC_ISO_D1_EN")
	)
	(segment
		(start 202.430888 -355.029262)
		(end 202.414886 -355.01326)
		(width 0.13208)
		(layer "F.Cu")
		(net "PD_MB_HSC_ISO_D1_EN")
	)
	(segment
		(start 202.414886 -355.01326)
		(end 201.561192 -355.01326)
		(width 0.13208)
		(layer "F.Cu")
		(net "PD_MB_HSC_ISO_D1_EN")
	)
	(segment
		(start 199.039734 -357.534718)
		(end 201.561192 -355.01326)
		(width 0.13208)
		(layer "F.Cu")
		(net "PD_MB_HSC_ISO_D1_EN")
	)
	(via
		(at 201.561192 -355.01326)
		(size 0.508)
		(drill 0.254)
		(layers "F.Cu" "B.Cu")
		(net "PD_MB_HSC_ISO_D1_EN")
	)
	(segment
		(start 261.78129 -209.434684)
		(end 262.886698 -210.540092)
		(width 0.508)
		(layer "F.Cu")
		(net "P3V3_AUX_JTAG")
	)
	(segment
		(start 261.78129 -209.434684)
		(end 262.886698 -208.329276)
		(width 0.508)
		(layer "F.Cu")
		(net "P3V3_AUX_JTAG")
	)
	(segment
		(start 260.675882 -210.540092)
		(end 261.78129 -209.434684)
		(width 0.508)
		(layer "F.Cu")
		(net "P3V3_AUX_JTAG")
	)
	(segment
		(start 260.675882 -208.329276)
		(end 261.78129 -209.434684)
		(width 0.508)
		(layer "F.Cu")
		(net "P3V3_AUX_JTAG")
	)
	(via
		(at 267.552932 -209.930746)
		(size 0.762)
		(drill 0.381)
		(layers "F.Cu" "B.Cu")
		(net "P3V3_AUX_JTAG")
	)
	(segment
		(start 242.487704 -238.501174)
		(end 241.773202 -237.786672)
		(width 0.13208)
		(layer "F.Cu")
		(net "BIC_RECOVER_IOEXP_A0")
	)
	(segment
		(start 242.066064 -237.786672)
		(end 242.487704 -237.365032)
		(width 0.13208)
		(layer "F.Cu")
		(net "BIC_RECOVER_IOEXP_A0")
	)
	(segment
		(start 242.487704 -237.365032)
		(end 242.487704 -237.109762)
		(width 0.13208)
		(layer "F.Cu")
		(net "BIC_RECOVER_IOEXP_A0")
	)
	(segment
		(start 241.773202 -237.786672)
		(end 242.066064 -237.786672)
		(width 0.13208)
		(layer "F.Cu")
		(net "BIC_RECOVER_IOEXP_A0")
	)
	(segment
		(start 242.487704 -239.883442)
		(end 242.487704 -238.501174)
		(width 0.13208)
		(layer "F.Cu")
		(net "BIC_RECOVER_IOEXP_A0")
	)
	(segment
		(start 242.487704 -237.109762)
		(end 242.460018 -237.082076)
		(width 0.13208)
		(layer "F.Cu")
		(net "BIC_RECOVER_IOEXP_A0")
	)
	(segment
		(start 241.444018 -237.082076)
		(end 242.460018 -237.082076)
		(width 0.13208)
		(layer "F.Cu")
		(net "BIC_RECOVER_IOEXP_A0")
	)
	(via
		(at 241.773202 -237.786672)
		(size 0.508)
		(drill 0.254)
		(layers "F.Cu" "B.Cu")
		(net "BIC_RECOVER_IOEXP_A0")
	)
	(segment
		(start 120.575832 -254.937768)
		(end 120.627902 -254.885698)
		(width 0.13208)
		(layer "F.Cu")
		(net "NC_P0V8_PEX0_PWM4")
	)
	(segment
		(start 120.627902 -253.590298)
		(end 121.220992 -252.997208)
		(width 0.13208)
		(layer "F.Cu")
		(net "NC_P0V8_PEX0_PWM4")
	)
	(segment
		(start 120.575832 -255.994916)
		(end 120.575832 -254.937768)
		(width 0.13208)
		(layer "F.Cu")
		(net "NC_P0V8_PEX0_PWM4")
	)
	(segment
		(start 120.627902 -254.885698)
		(end 120.627902 -253.590298)
		(width 0.13208)
		(layer "F.Cu")
		(net "NC_P0V8_PEX0_PWM4")
	)
	(via
		(at 121.220992 -252.997208)
		(size 0.762)
		(drill 0.381)
		(layers "F.Cu" "B.Cu")
		(net "NC_P0V8_PEX0_PWM4")
	)
	(segment
		(start 225.977196 -64.057784)
		(end 225.335592 -63.41618)
		(width 0.13208)
		(layer "F.Cu")
		(net "PRSNT_DBV2_SLIMSAS")
	)
	(segment
		(start 227.578666 -64.057784)
		(end 225.977196 -64.057784)
		(width 0.13208)
		(layer "F.Cu")
		(net "PRSNT_DBV2_SLIMSAS")
	)
	(segment
		(start 228.036374 -63.600076)
		(end 227.578666 -64.057784)
		(width 0.13208)
		(layer "F.Cu")
		(net "PRSNT_DBV2_SLIMSAS")
	)
	(segment
		(start 209.500216 -228.217476)
		(end 209.500216 -228.19233)
		(width 0.13208)
		(layer "F.Cu")
		(net "PRSNT_DBV2_SLIMSAS")
	)
	(segment
		(start 210.21421 -228.93147)
		(end 209.500216 -228.217476)
		(width 0.13208)
		(layer "F.Cu")
		(net "PRSNT_DBV2_SLIMSAS")
	)
	(segment
		(start 212.07095 -228.981)
		(end 212.02142 -228.93147)
		(width 0.13208)
		(layer "F.Cu")
		(net "PRSNT_DBV2_SLIMSAS")
	)
	(segment
		(start 229.437438 -63.600076)
		(end 228.036374 -63.600076)
		(width 0.13208)
		(layer "F.Cu")
		(net "PRSNT_DBV2_SLIMSAS")
	)
	(segment
		(start 212.02142 -228.93147)
		(end 210.21421 -228.93147)
		(width 0.13208)
		(layer "F.Cu")
		(net "PRSNT_DBV2_SLIMSAS")
	)
	(via
		(at 225.335592 -63.41618)
		(size 0.508)
		(drill 0.254)
		(layers "F.Cu" "B.Cu")
		(net "PRSNT_DBV2_SLIMSAS")
	)
	(via
		(at 209.500216 -228.19233)
		(size 0.508)
		(drill 0.254)
		(layers "F.Cu" "B.Cu")
		(net "PRSNT_DBV2_SLIMSAS")
	)
	(via
		(at 213.92896 -82.512916)
		(size 0.508)
		(drill 0.254)
		(layers "F.Cu" "B.Cu")
		(net "PRSNT_DBV2_SLIMSAS")
	)
	(segment
		(start 210.058 -216.789254)
		(end 210.058 -215.851486)
		(width 0.15494)
		(layer "In5.Cu")
		(net "PRSNT_DBV2_SLIMSAS")
	)
	(segment
		(start 207.663796 -186.82335)
		(end 207.976978 -186.510168)
		(width 0.15494)
		(layer "In5.Cu")
		(net "PRSNT_DBV2_SLIMSAS")
	)
	(segment
		(start 211.294218 -176.580038)
		(end 211.8614 -176.012094)
		(width 0.15494)
		(layer "In5.Cu")
		(net "PRSNT_DBV2_SLIMSAS")
	)
	(segment
		(start 210.834224 -222.725234)
		(end 210.834224 -221.310962)
		(width 0.15494)
		(layer "In5.Cu")
		(net "PRSNT_DBV2_SLIMSAS")
	)
	(segment
		(start 210.2358 -182.1688)
		(end 210.2358 -180.848254)
		(width 0.15494)
		(layer "In5.Cu")
		(net "PRSNT_DBV2_SLIMSAS")
	)
	(segment
		(start 210.163156 -203.651612)
		(end 210.163156 -200.91146)
		(width 0.15494)
		(layer "In5.Cu")
		(net "PRSNT_DBV2_SLIMSAS")
	)
	(segment
		(start 210.2358 -180.848254)
		(end 211.294218 -179.789836)
		(width 0.15494)
		(layer "In5.Cu")
		(net "PRSNT_DBV2_SLIMSAS")
	)
	(segment
		(start 210.450176 -184.095136)
		(end 210.450176 -182.383176)
		(width 0.15494)
		(layer "In5.Cu")
		(net "PRSNT_DBV2_SLIMSAS")
	)
	(segment
		(start 210.7184 -169.6466)
		(end 210.7184 -138.546332)
		(width 0.15494)
		(layer "In5.Cu")
		(net "PRSNT_DBV2_SLIMSAS")
	)
	(segment
		(start 217.623898 -113.866676)
		(end 212.281262 -108.52404)
		(width 0.15494)
		(layer "In5.Cu")
		(net "PRSNT_DBV2_SLIMSAS")
	)
	(segment
		(start 208.910936 -199.65924)
		(end 208.910936 -191.67983)
		(width 0.15494)
		(layer "In5.Cu")
		(net "PRSNT_DBV2_SLIMSAS")
	)
	(segment
		(start 211.8614 -170.7896)
		(end 210.7184 -169.6466)
		(width 0.15494)
		(layer "In5.Cu")
		(net "PRSNT_DBV2_SLIMSAS")
	)
	(segment
		(start 209.500216 -228.19233)
		(end 209.948526 -228.19233)
		(width 0.15494)
		(layer "In5.Cu")
		(net "PRSNT_DBV2_SLIMSAS")
	)
	(segment
		(start 209.948526 -228.19233)
		(end 210.490308 -227.650548)
		(width 0.15494)
		(layer "In5.Cu")
		(net "PRSNT_DBV2_SLIMSAS")
	)
	(segment
		(start 211.8614 -176.012094)
		(end 211.8614 -170.7896)
		(width 0.15494)
		(layer "In5.Cu")
		(net "PRSNT_DBV2_SLIMSAS")
	)
	(segment
		(start 211.723986 -220.4212)
		(end 211.723986 -218.45524)
		(width 0.15494)
		(layer "In5.Cu")
		(net "PRSNT_DBV2_SLIMSAS")
	)
	(segment
		(start 207.976978 -186.079892)
		(end 208.91627 -185.1406)
		(width 0.15494)
		(layer "In5.Cu")
		(net "PRSNT_DBV2_SLIMSAS")
	)
	(segment
		(start 212.281262 -104.881426)
		(end 213.92896 -100.90277)
		(width 0.15494)
		(layer "In5.Cu")
		(net "PRSNT_DBV2_SLIMSAS")
	)
	(segment
		(start 210.834224 -221.310962)
		(end 211.723986 -220.4212)
		(width 0.15494)
		(layer "In5.Cu")
		(net "PRSNT_DBV2_SLIMSAS")
	)
	(segment
		(start 217.004392 -132.259832)
		(end 217.004392 -119.989346)
		(width 0.15494)
		(layer "In5.Cu")
		(net "PRSNT_DBV2_SLIMSAS")
	)
	(segment
		(start 207.663796 -189.232794)
		(end 207.663796 -186.82335)
		(width 0.15494)
		(layer "In5.Cu")
		(net "PRSNT_DBV2_SLIMSAS")
	)
	(segment
		(start 210.450176 -182.383176)
		(end 210.2358 -182.1688)
		(width 0.15494)
		(layer "In5.Cu")
		(net "PRSNT_DBV2_SLIMSAS")
	)
	(segment
		(start 211.723986 -218.45524)
		(end 210.058 -216.789254)
		(width 0.15494)
		(layer "In5.Cu")
		(net "PRSNT_DBV2_SLIMSAS")
	)
	(segment
		(start 217.004392 -119.989346)
		(end 217.623898 -119.36984)
		(width 0.15494)
		(layer "In5.Cu")
		(net "PRSNT_DBV2_SLIMSAS")
	)
	(segment
		(start 208.910936 -191.67983)
		(end 209.310224 -191.280542)
		(width 0.15494)
		(layer "In5.Cu")
		(net "PRSNT_DBV2_SLIMSAS")
	)
	(segment
		(start 208.91119 -204.903578)
		(end 210.163156 -203.651612)
		(width 0.15494)
		(layer "In5.Cu")
		(net "PRSNT_DBV2_SLIMSAS")
	)
	(segment
		(start 210.058 -215.851486)
		(end 208.91119 -214.704676)
		(width 0.15494)
		(layer "In5.Cu")
		(net "PRSNT_DBV2_SLIMSAS")
	)
	(segment
		(start 211.294218 -179.789836)
		(end 211.294218 -176.580038)
		(width 0.15494)
		(layer "In5.Cu")
		(net "PRSNT_DBV2_SLIMSAS")
	)
	(segment
		(start 217.623898 -119.36984)
		(end 217.623898 -113.866676)
		(width 0.15494)
		(layer "In5.Cu")
		(net "PRSNT_DBV2_SLIMSAS")
	)
	(segment
		(start 210.7184 -138.546332)
		(end 217.004392 -132.259832)
		(width 0.15494)
		(layer "In5.Cu")
		(net "PRSNT_DBV2_SLIMSAS")
	)
	(segment
		(start 210.163156 -200.91146)
		(end 208.910936 -199.65924)
		(width 0.15494)
		(layer "In5.Cu")
		(net "PRSNT_DBV2_SLIMSAS")
	)
	(segment
		(start 209.310224 -190.879222)
		(end 207.663796 -189.232794)
		(width 0.15494)
		(layer "In5.Cu")
		(net "PRSNT_DBV2_SLIMSAS")
	)
	(segment
		(start 208.91627 -185.1406)
		(end 209.404712 -185.1406)
		(width 0.15494)
		(layer "In5.Cu")
		(net "PRSNT_DBV2_SLIMSAS")
	)
	(segment
		(start 209.404712 -185.1406)
		(end 210.450176 -184.095136)
		(width 0.15494)
		(layer "In5.Cu")
		(net "PRSNT_DBV2_SLIMSAS")
	)
	(segment
		(start 210.490308 -223.06915)
		(end 210.834224 -222.725234)
		(width 0.15494)
		(layer "In5.Cu")
		(net "PRSNT_DBV2_SLIMSAS")
	)
	(segment
		(start 210.490308 -227.650548)
		(end 210.490308 -223.06915)
		(width 0.15494)
		(layer "In5.Cu")
		(net "PRSNT_DBV2_SLIMSAS")
	)
	(segment
		(start 208.91119 -214.704676)
		(end 208.91119 -204.903578)
		(width 0.15494)
		(layer "In5.Cu")
		(net "PRSNT_DBV2_SLIMSAS")
	)
	(segment
		(start 212.281262 -108.52404)
		(end 212.281262 -104.881426)
		(width 0.15494)
		(layer "In5.Cu")
		(net "PRSNT_DBV2_SLIMSAS")
	)
	(segment
		(start 209.310224 -191.280542)
		(end 209.310224 -190.879222)
		(width 0.15494)
		(layer "In5.Cu")
		(net "PRSNT_DBV2_SLIMSAS")
	)
	(segment
		(start 213.92896 -100.90277)
		(end 213.92896 -82.512916)
		(width 0.15494)
		(layer "In5.Cu")
		(net "PRSNT_DBV2_SLIMSAS")
	)
	(segment
		(start 207.976978 -186.510168)
		(end 207.976978 -186.079892)
		(width 0.15494)
		(layer "In5.Cu")
		(net "PRSNT_DBV2_SLIMSAS")
	)
	(segment
		(start 213.92896 -80.02905)
		(end 213.92896 -82.512916)
		(width 0.15494)
		(layer "In7.Cu")
		(net "PRSNT_DBV2_SLIMSAS")
	)
	(segment
		(start 224.244662 -64.058546)
		(end 224.244662 -65.45453)
		(width 0.15494)
		(layer "In7.Cu")
		(net "PRSNT_DBV2_SLIMSAS")
	)
	(segment
		(start 224.244662 -65.45453)
		(end 223.368362 -66.33083)
		(width 0.15494)
		(layer "In7.Cu")
		(net "PRSNT_DBV2_SLIMSAS")
	)
	(segment
		(start 223.368362 -67.114166)
		(end 223.74606 -67.491864)
		(width 0.15494)
		(layer "In7.Cu")
		(net "PRSNT_DBV2_SLIMSAS")
	)
	(segment
		(start 224.887028 -63.41618)
		(end 224.244662 -64.058546)
		(width 0.15494)
		(layer "In7.Cu")
		(net "PRSNT_DBV2_SLIMSAS")
	)
	(segment
		(start 223.74606 -67.491864)
		(end 223.74606 -70.83298)
		(width 0.15494)
		(layer "In7.Cu")
		(net "PRSNT_DBV2_SLIMSAS")
	)
	(segment
		(start 222.365824 -72.213216)
		(end 221.744794 -72.213216)
		(width 0.15494)
		(layer "In7.Cu")
		(net "PRSNT_DBV2_SLIMSAS")
	)
	(segment
		(start 221.744794 -72.213216)
		(end 213.92896 -80.02905)
		(width 0.15494)
		(layer "In7.Cu")
		(net "PRSNT_DBV2_SLIMSAS")
	)
	(segment
		(start 223.74606 -70.83298)
		(end 222.365824 -72.213216)
		(width 0.15494)
		(layer "In7.Cu")
		(net "PRSNT_DBV2_SLIMSAS")
	)
	(segment
		(start 223.368362 -66.33083)
		(end 223.368362 -67.114166)
		(width 0.15494)
		(layer "In7.Cu")
		(net "PRSNT_DBV2_SLIMSAS")
	)
	(segment
		(start 225.335592 -63.41618)
		(end 224.887028 -63.41618)
		(width 0.15494)
		(layer "In7.Cu")
		(net "PRSNT_DBV2_SLIMSAS")
	)
	(segment
		(start 119.591836 -264.537444)
		(end 119.16664 -264.112248)
		(width 0.13208)
		(layer "F.Cu")
		(net "NC_P0V8_PEX0_ISEN4")
	)
	(segment
		(start 120.575832 -261.08152)
		(end 120.777 -261.282688)
		(width 0.13208)
		(layer "F.Cu")
		(net "NC_P0V8_PEX0_ISEN4")
	)
	(segment
		(start 118.538752 -264.112248)
		(end 118.035324 -264.615676)
		(width 0.13208)
		(layer "F.Cu")
		(net "NC_P0V8_PEX0_ISEN4")
	)
	(segment
		(start 119.900446 -264.537444)
		(end 119.591836 -264.537444)
		(width 0.13208)
		(layer "F.Cu")
		(net "NC_P0V8_PEX0_ISEN4")
	)
	(segment
		(start 120.575832 -260.795008)
		(end 120.575832 -261.08152)
		(width 0.13208)
		(layer "F.Cu")
		(net "NC_P0V8_PEX0_ISEN4")
	)
	(segment
		(start 120.777 -261.282688)
		(end 120.777 -263.66089)
		(width 0.13208)
		(layer "F.Cu")
		(net "NC_P0V8_PEX0_ISEN4")
	)
	(segment
		(start 119.16664 -264.112248)
		(end 118.538752 -264.112248)
		(width 0.13208)
		(layer "F.Cu")
		(net "NC_P0V8_PEX0_ISEN4")
	)
	(segment
		(start 116.979954 -264.95756)
		(end 117.321838 -264.615676)
		(width 0.13208)
		(layer "F.Cu")
		(net "NC_P0V8_PEX0_ISEN4")
	)
	(segment
		(start 115.758976 -264.95756)
		(end 116.979954 -264.95756)
		(width 0.13208)
		(layer "F.Cu")
		(net "NC_P0V8_PEX0_ISEN4")
	)
	(segment
		(start 118.035324 -264.615676)
		(end 117.321838 -264.615676)
		(width 0.13208)
		(layer "F.Cu")
		(net "NC_P0V8_PEX0_ISEN4")
	)
	(segment
		(start 120.777 -263.66089)
		(end 119.900446 -264.537444)
		(width 0.13208)
		(layer "F.Cu")
		(net "NC_P0V8_PEX0_ISEN4")
	)
	(via
		(at 117.321838 -264.615676)
		(size 0.762)
		(drill 0.381)
		(layers "F.Cu" "B.Cu")
		(net "NC_P0V8_PEX0_ISEN4")
	)
	(segment
		(start 197.739 -407.85796)
		(end 197.739 -408.315414)
		(width 0.13208)
		(layer "F.Cu")
		(net "MB_HSC_ISO_D1_EN")
	)
	(segment
		(start 197.739 -408.315414)
		(end 197.372986 -408.681428)
		(width 0.13208)
		(layer "F.Cu")
		(net "MB_HSC_ISO_D1_EN")
	)
	(segment
		(start 197.425564 -360.074718)
		(end 197.78599 -359.714292)
		(width 0.13208)
		(layer "F.Cu")
		(net "MB_HSC_ISO_D1_EN")
	)
	(segment
		(start 197.372986 -408.681428)
		(end 197.089014 -408.397456)
		(width 0.13208)
		(layer "F.Cu")
		(net "MB_HSC_ISO_D1_EN")
	)
	(segment
		(start 204.449426 -378.268738)
		(end 204.449426 -377.025916)
		(width 0.13208)
		(layer "F.Cu")
		(net "MB_HSC_ISO_D1_EN")
	)
	(segment
		(start 191.605916 -360.074718)
		(end 197.425564 -360.074718)
		(width 0.13208)
		(layer "F.Cu")
		(net "MB_HSC_ISO_D1_EN")
	)
	(segment
		(start 197.089014 -408.397456)
		(end 197.089014 -407.85796)
		(width 0.13208)
		(layer "F.Cu")
		(net "MB_HSC_ISO_D1_EN")
	)
	(via
		(at 197.78599 -359.714292)
		(size 0.508)
		(drill 0.254)
		(layers "F.Cu" "B.Cu")
		(net "MB_HSC_ISO_D1_EN")
	)
	(via
		(at 204.449426 -378.268738)
		(size 0.508)
		(drill 0.254)
		(layers "F.Cu" "B.Cu")
		(net "MB_HSC_ISO_D1_EN")
	)
	(via
		(at 197.372986 -408.681428)
		(size 0.508)
		(drill 0.254)
		(layers "F.Cu" "B.Cu")
		(net "MB_HSC_ISO_D1_EN")
	)
	(segment
		(start 199.535542 -408.681428)
		(end 197.372986 -408.681428)
		(width 0.15494)
		(layer "In5.Cu")
		(net "MB_HSC_ISO_D1_EN")
	)
	(segment
		(start 188.57849 -386.64769)
		(end 188.57849 -393.753848)
		(width 0.15494)
		(layer "In5.Cu")
		(net "MB_HSC_ISO_D1_EN")
	)
	(segment
		(start 200.58507 -403.412706)
		(end 200.58507 -407.6319)
		(width 0.15494)
		(layer "In5.Cu")
		(net "MB_HSC_ISO_D1_EN")
	)
	(segment
		(start 188.57849 -393.753848)
		(end 196.49821 -401.673568)
		(width 0.15494)
		(layer "In5.Cu")
		(net "MB_HSC_ISO_D1_EN")
	)
	(segment
		(start 192.080642 -372.15826)
		(end 188.001148 -376.237754)
		(width 0.15494)
		(layer "In5.Cu")
		(net "MB_HSC_ISO_D1_EN")
	)
	(segment
		(start 198.845932 -401.673568)
		(end 200.58507 -403.412706)
		(width 0.15494)
		(layer "In5.Cu")
		(net "MB_HSC_ISO_D1_EN")
	)
	(segment
		(start 198.3359 -372.15826)
		(end 192.080642 -372.15826)
		(width 0.15494)
		(layer "In5.Cu")
		(net "MB_HSC_ISO_D1_EN")
	)
	(segment
		(start 200.58507 -407.6319)
		(end 199.535542 -408.681428)
		(width 0.15494)
		(layer "In5.Cu")
		(net "MB_HSC_ISO_D1_EN")
	)
	(segment
		(start 188.001148 -376.237754)
		(end 188.001148 -386.070348)
		(width 0.15494)
		(layer "In5.Cu")
		(net "MB_HSC_ISO_D1_EN")
	)
	(segment
		(start 188.001148 -386.070348)
		(end 188.57849 -386.64769)
		(width 0.15494)
		(layer "In5.Cu")
		(net "MB_HSC_ISO_D1_EN")
	)
	(segment
		(start 196.49821 -401.673568)
		(end 198.845932 -401.673568)
		(width 0.15494)
		(layer "In5.Cu")
		(net "MB_HSC_ISO_D1_EN")
	)
	(segment
		(start 204.446378 -378.268738)
		(end 198.3359 -372.15826)
		(width 0.15494)
		(layer "In5.Cu")
		(net "MB_HSC_ISO_D1_EN")
	)
	(segment
		(start 204.449426 -378.268738)
		(end 204.446378 -378.268738)
		(width 0.15494)
		(layer "In5.Cu")
		(net "MB_HSC_ISO_D1_EN")
	)
	(segment
		(start 204.449426 -377.980956)
		(end 195.828158 -369.359688)
		(width 0.15494)
		(layer "In7.Cu")
		(net "MB_HSC_ISO_D1_EN")
	)
	(segment
		(start 193.4972 -365.362998)
		(end 193.4972 -363.160818)
		(width 0.15494)
		(layer "In7.Cu")
		(net "MB_HSC_ISO_D1_EN")
	)
	(segment
		(start 193.640202 -365.506)
		(end 193.4972 -365.362998)
		(width 0.15494)
		(layer "In7.Cu")
		(net "MB_HSC_ISO_D1_EN")
	)
	(segment
		(start 193.640202 -366.729772)
		(end 193.640202 -365.506)
		(width 0.15494)
		(layer "In7.Cu")
		(net "MB_HSC_ISO_D1_EN")
	)
	(segment
		(start 195.828158 -369.359688)
		(end 195.828158 -368.917728)
		(width 0.15494)
		(layer "In7.Cu")
		(net "MB_HSC_ISO_D1_EN")
	)
	(segment
		(start 195.828158 -368.917728)
		(end 193.640202 -366.729772)
		(width 0.15494)
		(layer "In7.Cu")
		(net "MB_HSC_ISO_D1_EN")
	)
	(segment
		(start 204.449426 -378.268738)
		(end 204.449426 -377.980956)
		(width 0.15494)
		(layer "In7.Cu")
		(net "MB_HSC_ISO_D1_EN")
	)
	(segment
		(start 193.4972 -363.160818)
		(end 196.943726 -359.714292)
		(width 0.15494)
		(layer "In7.Cu")
		(net "MB_HSC_ISO_D1_EN")
	)
	(segment
		(start 196.943726 -359.714292)
		(end 197.78599 -359.714292)
		(width 0.15494)
		(layer "In7.Cu")
		(net "MB_HSC_ISO_D1_EN")
	)
	(segment
		(start 119.749316 -265.143742)
		(end 121.071132 -263.821926)
		(width 0.13208)
		(layer "F.Cu")
		(net "NC_P0V8_PEX0_ISEN5")
	)
	(segment
		(start 119.226076 -265.143742)
		(end 119.749316 -265.143742)
		(width 0.13208)
		(layer "F.Cu")
		(net "NC_P0V8_PEX0_ISEN5")
	)
	(segment
		(start 115.739418 -265.949938)
		(end 117.649752 -265.949938)
		(width 0.13208)
		(layer "F.Cu")
		(net "NC_P0V8_PEX0_ISEN5")
	)
	(segment
		(start 121.071132 -261.199122)
		(end 120.975628 -260.967982)
		(width 0.13208)
		(layer "F.Cu")
		(net "NC_P0V8_PEX0_ISEN5")
	)
	(segment
		(start 117.649752 -265.949938)
		(end 118.841012 -264.758678)
		(width 0.13208)
		(layer "F.Cu")
		(net "NC_P0V8_PEX0_ISEN5")
	)
	(segment
		(start 120.975628 -260.967982)
		(end 120.975628 -260.795008)
		(width 0.13208)
		(layer "F.Cu")
		(net "NC_P0V8_PEX0_ISEN5")
	)
	(segment
		(start 118.841012 -264.758678)
		(end 119.226076 -265.143742)
		(width 0.13208)
		(layer "F.Cu")
		(net "NC_P0V8_PEX0_ISEN5")
	)
	(segment
		(start 121.071132 -263.821926)
		(end 121.071132 -261.199122)
		(width 0.13208)
		(layer "F.Cu")
		(net "NC_P0V8_PEX0_ISEN5")
	)
	(via
		(at 118.841012 -264.758678)
		(size 0.762)
		(drill 0.381)
		(layers "F.Cu" "B.Cu")
		(net "NC_P0V8_PEX0_ISEN5")
	)
	(segment
		(start 120.899682 -254.588518)
		(end 120.899682 -255.291082)
		(width 0.13208)
		(layer "F.Cu")
		(net "NC_P0V8_PEX0_PWM5")
	)
	(segment
		(start 121.220992 -254.267208)
		(end 120.899682 -254.588518)
		(width 0.13208)
		(layer "F.Cu")
		(net "NC_P0V8_PEX0_PWM5")
	)
	(segment
		(start 120.899682 -255.291082)
		(end 120.909588 -255.300988)
		(width 0.13208)
		(layer "F.Cu")
		(net "NC_P0V8_PEX0_PWM5")
	)
	(segment
		(start 120.909588 -255.304544)
		(end 120.975628 -255.370584)
		(width 0.13208)
		(layer "F.Cu")
		(net "NC_P0V8_PEX0_PWM5")
	)
	(segment
		(start 120.975628 -255.370584)
		(end 120.975628 -255.994916)
		(width 0.13208)
		(layer "F.Cu")
		(net "NC_P0V8_PEX0_PWM5")
	)
	(segment
		(start 120.909588 -255.300988)
		(end 120.909588 -255.304544)
		(width 0.13208)
		(layer "F.Cu")
		(net "NC_P0V8_PEX0_PWM5")
	)
	(via
		(at 121.220992 -254.267208)
		(size 0.762)
		(drill 0.381)
		(layers "F.Cu" "B.Cu")
		(net "NC_P0V8_PEX0_PWM5")
	)
	(segment
		(start 55.449724 -368.2238)
		(end 54.640988 -368.2238)
		(width 0.13462)
		(layer "F.Cu")
		(net "P4E_PEX0_STN3_TX_C_DN<49>")
	)
	(segment
		(start 55.767986 -368.542062)
		(end 55.449724 -368.2238)
		(width 0.13462)
		(layer "F.Cu")
		(net "P4E_PEX0_STN3_TX_C_DN<49>")
	)
	(segment
		(start 54.640988 -368.2238)
		(end 54.348126 -368.516662)
		(width 0.13462)
		(layer "F.Cu")
		(net "P4E_PEX0_STN3_TX_C_DN<49>")
	)
	(segment
		(start 46.67504 -369.042696)
		(end 47.491904 -368.225832)
		(width 0.1651)
		(layer "In15.Cu")
		(net "P4E_PEX0_STN3_TX_C_DN<49>")
	)
	(segment
		(start 45.509942 -371.357144)
		(end 45.586142 -371.280944)
		(width 0.1651)
		(layer "In15.Cu")
		(net "P4E_PEX0_STN3_TX_C_DN<49>")
	)
	(segment
		(start 45.586142 -371.280944)
		(end 45.96384 -371.280944)
		(width 0.1651)
		(layer "In15.Cu")
		(net "P4E_PEX0_STN3_TX_C_DN<49>")
	)
	(segment
		(start 45.509942 -371.790214)
		(end 45.509942 -371.357144)
		(width 0.1651)
		(layer "In15.Cu")
		(net "P4E_PEX0_STN3_TX_C_DN<49>")
	)
	(segment
		(start 46.67504 -370.569744)
		(end 46.67504 -369.042696)
		(width 0.1651)
		(layer "In15.Cu")
		(net "P4E_PEX0_STN3_TX_C_DN<49>")
	)
	(segment
		(start 45.96384 -371.280944)
		(end 46.67504 -370.569744)
		(width 0.1651)
		(layer "In15.Cu")
		(net "P4E_PEX0_STN3_TX_C_DN<49>")
	)
	(segment
		(start 47.491904 -368.225832)
		(end 54.057296 -368.225832)
		(width 0.1651)
		(layer "In15.Cu")
		(net "P4E_PEX0_STN3_TX_C_DN<49>")
	)
	(segment
		(start 54.057296 -368.225832)
		(end 54.348126 -368.516662)
		(width 0.1651)
		(layer "In15.Cu")
		(net "P4E_PEX0_STN3_TX_C_DN<49>")
	)
	(segment
		(start 39.699946 -288.299906)
		(end 39.224966 -287.824926)
		(width 0.13462)
		(layer "F.Cu")
		(net "P4E_PEX0_STN3_RX_DP<49>")
	)
	(segment
		(start 54.32298 -348.198186)
		(end 54.42458 -348.299786)
		(width 0.1651)
		(layer "In13.Cu")
		(net "P4E_PEX0_STN3_RX_DP<49>")
	)
	(segment
		(start 35.575748 -287.212786)
		(end 34.58337 -287.212786)
		(width 0.1651)
		(layer "In13.Cu")
		(net "P4E_PEX0_STN3_RX_DP<49>")
	)
	(segment
		(start 53.912516 -346.135706)
		(end 54.102508 -346.593414)
		(width 0.1651)
		(layer "In13.Cu")
		(net "P4E_PEX0_STN3_RX_DP<49>")
	)
	(segment
		(start 53.053742 -343.79662)
		(end 52.998878 -343.929462)
		(width 0.1651)
		(layer "In13.Cu")
		(net "P4E_PEX0_STN3_RX_DP<49>")
	)
	(segment
		(start 39.224966 -287.824926)
		(end 38.934136 -287.824926)
		(width 0.1143)
		(layer "In13.Cu")
		(net "P4E_PEX0_STN3_RX_DP<49>")
	)
	(segment
		(start 45.636942 -374.899174)
		(end 45.509942 -374.772174)
		(width 0.1651)
		(layer "In13.Cu")
		(net "P4E_PEX0_STN3_RX_DP<49>")
	)
	(segment
		(start 46.648624 -368.073686)
		(end 46.327822 -369.165378)
		(width 0.1651)
		(layer "In13.Cu")
		(net "P4E_PEX0_STN3_RX_DP<49>")
	)
	(segment
		(start 51.727608 -341.358728)
		(end 52.44338 -342.322658)
		(width 0.1651)
		(layer "In13.Cu")
		(net "P4E_PEX0_STN3_RX_DP<49>")
	)
	(segment
		(start 54.32298 -347.702886)
		(end 54.32298 -348.198186)
		(width 0.1651)
		(layer "In13.Cu")
		(net "P4E_PEX0_STN3_RX_DP<49>")
	)
	(segment
		(start 23.223982 -322.494148)
		(end 23.821136 -323.935852)
		(width 0.1651)
		(layer "In13.Cu")
		(net "P4E_PEX0_STN3_RX_DP<49>")
	)
	(segment
		(start 31.102046 -288.556954)
		(end 30.74797 -288.91103)
		(width 0.1651)
		(layer "In13.Cu")
		(net "P4E_PEX0_STN3_RX_DP<49>")
	)
	(segment
		(start 45.509942 -374.772174)
		(end 45.509942 -374.390158)
		(width 0.1651)
		(layer "In13.Cu")
		(net "P4E_PEX0_STN3_RX_DP<49>")
	)
	(segment
		(start 29.13126 -300.631352)
		(end 27.885136 -303.639982)
		(width 0.1651)
		(layer "In13.Cu")
		(net "P4E_PEX0_STN3_RX_DP<49>")
	)
	(segment
		(start 32.60471 -287.9344)
		(end 31.102046 -288.556954)
		(width 0.1651)
		(layer "In13.Cu")
		(net "P4E_PEX0_STN3_RX_DP<49>")
	)
	(segment
		(start 50.140616 -362.647484)
		(end 46.648624 -368.073686)
		(width 0.1651)
		(layer "In13.Cu")
		(net "P4E_PEX0_STN3_RX_DP<49>")
	)
	(segment
		(start 46.327822 -369.165378)
		(end 46.327822 -374.772174)
		(width 0.1651)
		(layer "In13.Cu")
		(net "P4E_PEX0_STN3_RX_DP<49>")
	)
	(segment
		(start 50.812446 -361.394502)
		(end 50.138584 -362.638848)
		(width 0.1651)
		(layer "In13.Cu")
		(net "P4E_PEX0_STN3_RX_DP<49>")
	)
	(segment
		(start 54.42458 -348.299786)
		(end 54.42458 -353.32797)
		(width 0.1651)
		(layer "In13.Cu")
		(net "P4E_PEX0_STN3_RX_DP<49>")
	)
	(segment
		(start 46.200822 -374.899174)
		(end 45.636942 -374.899174)
		(width 0.1651)
		(layer "In13.Cu")
		(net "P4E_PEX0_STN3_RX_DP<49>")
	)
	(segment
		(start 23.223982 -318.470788)
		(end 23.223982 -322.494148)
		(width 0.1651)
		(layer "In13.Cu")
		(net "P4E_PEX0_STN3_RX_DP<49>")
	)
	(segment
		(start 54.235096 -346.648532)
		(end 54.42458 -347.105986)
		(width 0.1651)
		(layer "In13.Cu")
		(net "P4E_PEX0_STN3_RX_DP<49>")
	)
	(segment
		(start 53.188616 -344.38717)
		(end 53.321204 -344.442288)
		(width 0.1651)
		(layer "In13.Cu")
		(net "P4E_PEX0_STN3_RX_DP<49>")
	)
	(segment
		(start 53.321204 -344.442288)
		(end 53.510688 -344.899742)
		(width 0.1651)
		(layer "In13.Cu")
		(net "P4E_PEX0_STN3_RX_DP<49>")
	)
	(segment
		(start 25.760426 -325.875142)
		(end 31.611316 -329.784456)
		(width 0.1651)
		(layer "In13.Cu")
		(net "P4E_PEX0_STN3_RX_DP<49>")
	)
	(segment
		(start 38.845236 -287.736026)
		(end 38.845236 -287.531302)
		(width 0.1143)
		(layer "In13.Cu")
		(net "P4E_PEX0_STN3_RX_DP<49>")
	)
	(segment
		(start 50.138584 -362.638848)
		(end 50.140616 -362.647484)
		(width 0.1651)
		(layer "In13.Cu")
		(net "P4E_PEX0_STN3_RX_DP<49>")
	)
	(segment
		(start 35.639756 -287.254696)
		(end 35.597846 -287.212786)
		(width 0.1143)
		(layer "In13.Cu")
		(net "P4E_PEX0_STN3_RX_DP<49>")
	)
	(segment
		(start 46.327822 -374.772174)
		(end 46.200822 -374.899174)
		(width 0.1651)
		(layer "In13.Cu")
		(net "P4E_PEX0_STN3_RX_DP<49>")
	)
	(segment
		(start 53.77815 -345.54541)
		(end 53.967634 -346.002864)
		(width 0.1651)
		(layer "In13.Cu")
		(net "P4E_PEX0_STN3_RX_DP<49>")
	)
	(segment
		(start 33.861756 -287.9344)
		(end 32.60471 -287.9344)
		(width 0.1651)
		(layer "In13.Cu")
		(net "P4E_PEX0_STN3_RX_DP<49>")
	)
	(segment
		(start 35.597846 -287.212786)
		(end 35.575748 -287.212786)
		(width 0.1143)
		(layer "In13.Cu")
		(net "P4E_PEX0_STN3_RX_DP<49>")
	)
	(segment
		(start 25.184862 -308.611778)
		(end 23.223982 -318.470788)
		(width 0.1651)
		(layer "In13.Cu")
		(net "P4E_PEX0_STN3_RX_DP<49>")
	)
	(segment
		(start 38.845236 -287.531302)
		(end 38.56863 -287.254696)
		(width 0.1143)
		(layer "In13.Cu")
		(net "P4E_PEX0_STN3_RX_DP<49>")
	)
	(segment
		(start 54.42458 -347.105986)
		(end 54.42458 -347.601286)
		(width 0.1651)
		(layer "In13.Cu")
		(net "P4E_PEX0_STN3_RX_DP<49>")
	)
	(segment
		(start 27.885136 -303.639982)
		(end 26.791158 -304.73396)
		(width 0.1651)
		(layer "In13.Cu")
		(net "P4E_PEX0_STN3_RX_DP<49>")
	)
	(segment
		(start 23.821136 -323.935852)
		(end 25.760426 -325.875142)
		(width 0.1651)
		(layer "In13.Cu")
		(net "P4E_PEX0_STN3_RX_DP<49>")
	)
	(segment
		(start 29.13126 -292.81247)
		(end 29.13126 -300.631352)
		(width 0.1651)
		(layer "In13.Cu")
		(net "P4E_PEX0_STN3_RX_DP<49>")
	)
	(segment
		(start 52.44338 -342.322658)
		(end 53.053742 -343.79662)
		(width 0.1651)
		(layer "In13.Cu")
		(net "P4E_PEX0_STN3_RX_DP<49>")
	)
	(segment
		(start 54.42458 -347.601286)
		(end 54.32298 -347.702886)
		(width 0.1651)
		(layer "In13.Cu")
		(net "P4E_PEX0_STN3_RX_DP<49>")
	)
	(segment
		(start 53.967634 -346.002864)
		(end 53.912516 -346.135706)
		(width 0.1651)
		(layer "In13.Cu")
		(net "P4E_PEX0_STN3_RX_DP<49>")
	)
	(segment
		(start 26.791158 -304.73396)
		(end 25.184862 -308.611778)
		(width 0.1651)
		(layer "In13.Cu")
		(net "P4E_PEX0_STN3_RX_DP<49>")
	)
	(segment
		(start 53.645562 -345.490292)
		(end 53.77815 -345.54541)
		(width 0.1651)
		(layer "In13.Cu")
		(net "P4E_PEX0_STN3_RX_DP<49>")
	)
	(segment
		(start 31.611316 -329.784456)
		(end 51.727608 -341.358728)
		(width 0.1651)
		(layer "In13.Cu")
		(net "P4E_PEX0_STN3_RX_DP<49>")
	)
	(segment
		(start 53.455824 -345.032584)
		(end 53.645562 -345.490292)
		(width 0.1651)
		(layer "In13.Cu")
		(net "P4E_PEX0_STN3_RX_DP<49>")
	)
	(segment
		(start 52.998878 -343.929462)
		(end 53.188616 -344.38717)
		(width 0.1651)
		(layer "In13.Cu")
		(net "P4E_PEX0_STN3_RX_DP<49>")
	)
	(segment
		(start 53.510688 -344.899742)
		(end 53.455824 -345.032584)
		(width 0.1651)
		(layer "In13.Cu")
		(net "P4E_PEX0_STN3_RX_DP<49>")
	)
	(segment
		(start 38.934136 -287.824926)
		(end 38.845236 -287.736026)
		(width 0.1143)
		(layer "In13.Cu")
		(net "P4E_PEX0_STN3_RX_DP<49>")
	)
	(segment
		(start 34.58337 -287.212786)
		(end 33.861756 -287.9344)
		(width 0.1651)
		(layer "In13.Cu")
		(net "P4E_PEX0_STN3_RX_DP<49>")
	)
	(segment
		(start 38.56863 -287.254696)
		(end 35.639756 -287.254696)
		(width 0.1143)
		(layer "In13.Cu")
		(net "P4E_PEX0_STN3_RX_DP<49>")
	)
	(segment
		(start 30.74797 -288.91103)
		(end 29.13126 -292.81247)
		(width 0.1651)
		(layer "In13.Cu")
		(net "P4E_PEX0_STN3_RX_DP<49>")
	)
	(segment
		(start 54.42458 -353.32797)
		(end 50.812446 -361.394502)
		(width 0.1651)
		(layer "In13.Cu")
		(net "P4E_PEX0_STN3_RX_DP<49>")
	)
	(segment
		(start 54.102508 -346.593414)
		(end 54.235096 -346.648532)
		(width 0.1651)
		(layer "In13.Cu")
		(net "P4E_PEX0_STN3_RX_DP<49>")
	)
	(segment
		(start 55.767986 -367.627662)
		(end 55.446168 -367.94948)
		(width 0.13462)
		(layer "F.Cu")
		(net "P4E_PEX0_STN3_TX_C_DP<49>")
	)
	(segment
		(start 54.644544 -367.94948)
		(end 54.348126 -367.653062)
		(width 0.13462)
		(layer "F.Cu")
		(net "P4E_PEX0_STN3_TX_C_DP<49>")
	)
	(segment
		(start 55.446168 -367.94948)
		(end 54.644544 -367.94948)
		(width 0.13462)
		(layer "F.Cu")
		(net "P4E_PEX0_STN3_TX_C_DP<49>")
	)
	(segment
		(start 54.057296 -367.943892)
		(end 54.348126 -367.653062)
		(width 0.1651)
		(layer "In15.Cu")
		(net "P4E_PEX0_STN3_TX_C_DP<49>")
	)
	(segment
		(start 45.509942 -370.489988)
		(end 45.509942 -370.922804)
		(width 0.1651)
		(layer "In15.Cu")
		(net "P4E_PEX0_STN3_TX_C_DP<49>")
	)
	(segment
		(start 45.586142 -370.999004)
		(end 45.847 -370.999004)
		(width 0.1651)
		(layer "In15.Cu")
		(net "P4E_PEX0_STN3_TX_C_DP<49>")
	)
	(segment
		(start 46.3931 -370.452904)
		(end 46.3931 -368.925856)
		(width 0.1651)
		(layer "In15.Cu")
		(net "P4E_PEX0_STN3_TX_C_DP<49>")
	)
	(segment
		(start 45.847 -370.999004)
		(end 46.3931 -370.452904)
		(width 0.1651)
		(layer "In15.Cu")
		(net "P4E_PEX0_STN3_TX_C_DP<49>")
	)
	(segment
		(start 47.375064 -367.943892)
		(end 54.057296 -367.943892)
		(width 0.1651)
		(layer "In15.Cu")
		(net "P4E_PEX0_STN3_TX_C_DP<49>")
	)
	(segment
		(start 46.3931 -368.925856)
		(end 47.375064 -367.943892)
		(width 0.1651)
		(layer "In15.Cu")
		(net "P4E_PEX0_STN3_TX_C_DP<49>")
	)
	(segment
		(start 45.509942 -370.922804)
		(end 45.586142 -370.999004)
		(width 0.1651)
		(layer "In15.Cu")
		(net "P4E_PEX0_STN3_TX_C_DP<49>")
	)
	(segment
		(start 57.721246 -371.310662)
		(end 57.428384 -371.0178)
		(width 0.13462)
		(layer "F.Cu")
		(net "P4E_PEX0_STN3_TX_DN<48>")
	)
	(segment
		(start 56.619648 -371.0178)
		(end 56.301386 -371.336062)
		(width 0.13462)
		(layer "F.Cu")
		(net "P4E_PEX0_STN3_TX_DN<48>")
	)
	(segment
		(start 43.499786 -289.249866)
		(end 43.024806 -288.774886)
		(width 0.13462)
		(layer "F.Cu")
		(net "P4E_PEX0_STN3_TX_DN<48>")
	)
	(segment
		(start 57.428384 -371.0178)
		(end 56.619648 -371.0178)
		(width 0.13462)
		(layer "F.Cu")
		(net "P4E_PEX0_STN3_TX_DN<48>")
	)
	(segment
		(start 42.840656 -288.395156)
		(end 42.645076 -288.590736)
		(width 0.1143)
		(layer "In13.Cu")
		(net "P4E_PEX0_STN3_TX_DN<48>")
	)
	(segment
		(start 41.13022 -326.47763)
		(end 41.115742 -326.620632)
		(width 0.1651)
		(layer "In13.Cu")
		(net "P4E_PEX0_STN3_TX_DN<48>")
	)
	(segment
		(start 43.404536 -288.685986)
		(end 43.404536 -288.560256)
		(width 0.1143)
		(layer "In13.Cu")
		(net "P4E_PEX0_STN3_TX_DN<48>")
	)
	(segment
		(start 35.348164 -312.470292)
		(end 35.325812 -317.71336)
		(width 0.1651)
		(layer "In13.Cu")
		(net "P4E_PEX0_STN3_TX_DN<48>")
	)
	(segment
		(start 60.265056 -369.57127)
		(end 58.816494 -371.019832)
		(width 0.1651)
		(layer "In13.Cu")
		(net "P4E_PEX0_STN3_TX_DN<48>")
	)
	(segment
		(start 35.918394 -295.009062)
		(end 35.897058 -295.030398)
		(width 0.1651)
		(layer "In13.Cu")
		(net "P4E_PEX0_STN3_TX_DN<48>")
	)
	(segment
		(start 58.012076 -371.019832)
		(end 57.721246 -371.310662)
		(width 0.1651)
		(layer "In13.Cu")
		(net "P4E_PEX0_STN3_TX_DN<48>")
	)
	(segment
		(start 35.26282 -309.2704)
		(end 35.442906 -310.01843)
		(width 0.1651)
		(layer "In13.Cu")
		(net "P4E_PEX0_STN3_TX_DN<48>")
	)
	(segment
		(start 35.372802 -317.893446)
		(end 36.91001 -320.607182)
		(width 0.1651)
		(layer "In13.Cu")
		(net "P4E_PEX0_STN3_TX_DN<48>")
	)
	(segment
		(start 36.91001 -320.607182)
		(end 37.048694 -320.645536)
		(width 0.1651)
		(layer "In13.Cu")
		(net "P4E_PEX0_STN3_TX_DN<48>")
	)
	(segment
		(start 35.918394 -291.103304)
		(end 35.918394 -295.009062)
		(width 0.1651)
		(layer "In13.Cu")
		(net "P4E_PEX0_STN3_TX_DN<48>")
	)
	(segment
		(start 60.265056 -367.171478)
		(end 60.265056 -369.57127)
		(width 0.1651)
		(layer "In13.Cu")
		(net "P4E_PEX0_STN3_TX_DN<48>")
	)
	(segment
		(start 59.636406 -361.445048)
		(end 59.95035 -364.30458)
		(width 0.1651)
		(layer "In13.Cu")
		(net "P4E_PEX0_STN3_TX_DN<48>")
	)
	(segment
		(start 35.897058 -295.030398)
		(end 35.301936 -296.467784)
		(width 0.1651)
		(layer "In13.Cu")
		(net "P4E_PEX0_STN3_TX_DN<48>")
	)
	(segment
		(start 42.645076 -288.590736)
		(end 42.645076 -290.09467)
		(width 0.1143)
		(layer "In13.Cu")
		(net "P4E_PEX0_STN3_TX_DN<48>")
	)
	(segment
		(start 54.707536 -338.678012)
		(end 57.636918 -342.591898)
		(width 0.1651)
		(layer "In13.Cu")
		(net "P4E_PEX0_STN3_TX_DN<48>")
	)
	(segment
		(start 59.95035 -364.304834)
		(end 60.265056 -367.171478)
		(width 0.1651)
		(layer "In13.Cu")
		(net "P4E_PEX0_STN3_TX_DN<48>")
	)
	(segment
		(start 57.636918 -342.591898)
		(end 58.208164 -345.555824)
		(width 0.1651)
		(layer "In13.Cu")
		(net "P4E_PEX0_STN3_TX_DN<48>")
	)
	(segment
		(start 37.637212 -321.684396)
		(end 37.88156 -322.115688)
		(width 0.1651)
		(layer "In13.Cu")
		(net "P4E_PEX0_STN3_TX_DN<48>")
	)
	(segment
		(start 35.910774 -291.081206)
		(end 35.910774 -291.095684)
		(width 0.1143)
		(layer "In13.Cu")
		(net "P4E_PEX0_STN3_TX_DN<48>")
	)
	(segment
		(start 37.498782 -321.646042)
		(end 37.637212 -321.684396)
		(width 0.1651)
		(layer "In13.Cu")
		(net "P4E_PEX0_STN3_TX_DN<48>")
	)
	(segment
		(start 59.95035 -364.30458)
		(end 59.95035 -364.304834)
		(width 0.1651)
		(layer "In13.Cu")
		(net "P4E_PEX0_STN3_TX_DN<48>")
	)
	(segment
		(start 37.048694 -320.645536)
		(end 37.293042 -321.076828)
		(width 0.1651)
		(layer "In13.Cu")
		(net "P4E_PEX0_STN3_TX_DN<48>")
	)
	(segment
		(start 58.208164 -353.173284)
		(end 59.636406 -361.445048)
		(width 0.1651)
		(layer "In13.Cu")
		(net "P4E_PEX0_STN3_TX_DN<48>")
	)
	(segment
		(start 35.075114 -303.761902)
		(end 35.26282 -309.2704)
		(width 0.1651)
		(layer "In13.Cu")
		(net "P4E_PEX0_STN3_TX_DN<48>")
	)
	(segment
		(start 37.293042 -321.076828)
		(end 37.254688 -321.215258)
		(width 0.1651)
		(layer "In13.Cu")
		(net "P4E_PEX0_STN3_TX_DN<48>")
	)
	(segment
		(start 37.88156 -322.115688)
		(end 37.843206 -322.254118)
		(width 0.1651)
		(layer "In13.Cu")
		(net "P4E_PEX0_STN3_TX_DN<48>")
	)
	(segment
		(start 35.301936 -296.467784)
		(end 35.301936 -302.620934)
		(width 0.1651)
		(layer "In13.Cu")
		(net "P4E_PEX0_STN3_TX_DN<48>")
	)
	(segment
		(start 48.992282 -335.020412)
		(end 54.707536 -338.678012)
		(width 0.1651)
		(layer "In13.Cu")
		(net "P4E_PEX0_STN3_TX_DN<48>")
	)
	(segment
		(start 35.910774 -291.095684)
		(end 35.918394 -291.103304)
		(width 0.1143)
		(layer "In13.Cu")
		(net "P4E_PEX0_STN3_TX_DN<48>")
	)
	(segment
		(start 36.068 -290.297616)
		(end 35.868864 -290.496752)
		(width 0.1143)
		(layer "In13.Cu")
		(net "P4E_PEX0_STN3_TX_DN<48>")
	)
	(segment
		(start 43.024806 -288.774886)
		(end 43.315636 -288.774886)
		(width 0.1143)
		(layer "In13.Cu")
		(net "P4E_PEX0_STN3_TX_DN<48>")
	)
	(segment
		(start 42.44213 -290.297616)
		(end 36.068 -290.297616)
		(width 0.1143)
		(layer "In13.Cu")
		(net "P4E_PEX0_STN3_TX_DN<48>")
	)
	(segment
		(start 35.868864 -291.039296)
		(end 35.910774 -291.081206)
		(width 0.1143)
		(layer "In13.Cu")
		(net "P4E_PEX0_STN3_TX_DN<48>")
	)
	(segment
		(start 38.506908 -323.42582)
		(end 40.673782 -326.079358)
		(width 0.1651)
		(layer "In13.Cu")
		(net "P4E_PEX0_STN3_TX_DN<48>")
	)
	(segment
		(start 35.442906 -310.01843)
		(end 35.495738 -311.607454)
		(width 0.1651)
		(layer "In13.Cu")
		(net "P4E_PEX0_STN3_TX_DN<48>")
	)
	(segment
		(start 35.495738 -311.607454)
		(end 35.348164 -312.470292)
		(width 0.1651)
		(layer "In13.Cu")
		(net "P4E_PEX0_STN3_TX_DN<48>")
	)
	(segment
		(start 43.404536 -288.560256)
		(end 43.239436 -288.395156)
		(width 0.1143)
		(layer "In13.Cu")
		(net "P4E_PEX0_STN3_TX_DN<48>")
	)
	(segment
		(start 40.816784 -326.093836)
		(end 41.13022 -326.47763)
		(width 0.1651)
		(layer "In13.Cu")
		(net "P4E_PEX0_STN3_TX_DN<48>")
	)
	(segment
		(start 58.816494 -371.019832)
		(end 58.012076 -371.019832)
		(width 0.1651)
		(layer "In13.Cu")
		(net "P4E_PEX0_STN3_TX_DN<48>")
	)
	(segment
		(start 58.208164 -345.555824)
		(end 58.208164 -353.173284)
		(width 0.1651)
		(layer "In13.Cu")
		(net "P4E_PEX0_STN3_TX_DN<48>")
	)
	(segment
		(start 35.301936 -302.620934)
		(end 35.075114 -303.761902)
		(width 0.1651)
		(layer "In13.Cu")
		(net "P4E_PEX0_STN3_TX_DN<48>")
	)
	(segment
		(start 37.254688 -321.215258)
		(end 37.498782 -321.646042)
		(width 0.1651)
		(layer "In13.Cu")
		(net "P4E_PEX0_STN3_TX_DN<48>")
	)
	(segment
		(start 46.014132 -332.619096)
		(end 48.992282 -335.020412)
		(width 0.1651)
		(layer "In13.Cu")
		(net "P4E_PEX0_STN3_TX_DN<48>")
	)
	(segment
		(start 43.315636 -288.774886)
		(end 43.404536 -288.685986)
		(width 0.1143)
		(layer "In13.Cu")
		(net "P4E_PEX0_STN3_TX_DN<48>")
	)
	(segment
		(start 35.325812 -317.71336)
		(end 35.372802 -317.893446)
		(width 0.1651)
		(layer "In13.Cu")
		(net "P4E_PEX0_STN3_TX_DN<48>")
	)
	(segment
		(start 42.645076 -290.09467)
		(end 42.44213 -290.297616)
		(width 0.1143)
		(layer "In13.Cu")
		(net "P4E_PEX0_STN3_TX_DN<48>")
	)
	(segment
		(start 37.843206 -322.254118)
		(end 38.506908 -323.42582)
		(width 0.1651)
		(layer "In13.Cu")
		(net "P4E_PEX0_STN3_TX_DN<48>")
	)
	(segment
		(start 43.239436 -288.395156)
		(end 42.840656 -288.395156)
		(width 0.1143)
		(layer "In13.Cu")
		(net "P4E_PEX0_STN3_TX_DN<48>")
	)
	(segment
		(start 41.115742 -326.620632)
		(end 46.014132 -332.619096)
		(width 0.1651)
		(layer "In13.Cu")
		(net "P4E_PEX0_STN3_TX_DN<48>")
	)
	(segment
		(start 35.868864 -290.496752)
		(end 35.868864 -291.039296)
		(width 0.1143)
		(layer "In13.Cu")
		(net "P4E_PEX0_STN3_TX_DN<48>")
	)
	(segment
		(start 40.673782 -326.079358)
		(end 40.816784 -326.093836)
		(width 0.1651)
		(layer "In13.Cu")
		(net "P4E_PEX0_STN3_TX_DN<48>")
	)
	(segment
		(start 56.623204 -370.74348)
		(end 56.301386 -370.421662)
		(width 0.13462)
		(layer "F.Cu")
		(net "P4E_PEX0_STN3_TX_DP<48>")
	)
	(segment
		(start 57.424828 -370.74348)
		(end 56.623204 -370.74348)
		(width 0.13462)
		(layer "F.Cu")
		(net "P4E_PEX0_STN3_TX_DP<48>")
	)
	(segment
		(start 57.721246 -370.447062)
		(end 57.424828 -370.74348)
		(width 0.13462)
		(layer "F.Cu")
		(net "P4E_PEX0_STN3_TX_DP<48>")
	)
	(segment
		(start 44.449746 -289.249866)
		(end 43.974766 -288.774886)
		(width 0.13462)
		(layer "F.Cu")
		(net "P4E_PEX0_STN3_TX_DP<48>")
	)
	(segment
		(start 42.761662 -288.204656)
		(end 43.31843 -288.204656)
		(width 0.1143)
		(layer "In13.Cu")
		(net "P4E_PEX0_STN3_TX_DP<48>")
	)
	(segment
		(start 43.31843 -288.204656)
		(end 43.595036 -288.481262)
		(width 0.1143)
		(layer "In13.Cu")
		(net "P4E_PEX0_STN3_TX_DP<48>")
	)
	(segment
		(start 35.019996 -296.41165)
		(end 35.636454 -294.922702)
		(width 0.1651)
		(layer "In13.Cu")
		(net "P4E_PEX0_STN3_TX_DP<48>")
	)
	(segment
		(start 34.981896 -309.3085)
		(end 34.792158 -303.738788)
		(width 0.1651)
		(layer "In13.Cu")
		(net "P4E_PEX0_STN3_TX_DP<48>")
	)
	(segment
		(start 58.699654 -370.737892)
		(end 59.983116 -369.45443)
		(width 0.1651)
		(layer "In13.Cu")
		(net "P4E_PEX0_STN3_TX_DP<48>")
	)
	(segment
		(start 35.161982 -310.05653)
		(end 34.981896 -309.3085)
		(width 0.1651)
		(layer "In13.Cu")
		(net "P4E_PEX0_STN3_TX_DP<48>")
	)
	(segment
		(start 43.595036 -288.685986)
		(end 43.683936 -288.774886)
		(width 0.1143)
		(layer "In13.Cu")
		(net "P4E_PEX0_STN3_TX_DP<48>")
	)
	(segment
		(start 45.814234 -332.820264)
		(end 38.273228 -323.58584)
		(width 0.1651)
		(layer "In13.Cu")
		(net "P4E_PEX0_STN3_TX_DP<48>")
	)
	(segment
		(start 59.166252 -360.379518)
		(end 59.04865 -360.296714)
		(width 0.1651)
		(layer "In13.Cu")
		(net "P4E_PEX0_STN3_TX_DP<48>")
	)
	(segment
		(start 58.963052 -359.20299)
		(end 58.84545 -359.120186)
		(width 0.1651)
		(layer "In13.Cu")
		(net "P4E_PEX0_STN3_TX_DP<48>")
	)
	(segment
		(start 59.04865 -360.296714)
		(end 58.964322 -359.808272)
		(width 0.1651)
		(layer "In13.Cu")
		(net "P4E_PEX0_STN3_TX_DP<48>")
	)
	(segment
		(start 59.669934 -364.335568)
		(end 59.669934 -364.335314)
		(width 0.1651)
		(layer "In13.Cu")
		(net "P4E_PEX0_STN3_TX_DP<48>")
	)
	(segment
		(start 35.636454 -294.922702)
		(end 35.636454 -291.103304)
		(width 0.1651)
		(layer "In13.Cu")
		(net "P4E_PEX0_STN3_TX_DP<48>")
	)
	(segment
		(start 35.019996 -302.592994)
		(end 35.019996 -296.41165)
		(width 0.1651)
		(layer "In13.Cu")
		(net "P4E_PEX0_STN3_TX_DP<48>")
	)
	(segment
		(start 35.212782 -311.58815)
		(end 35.161982 -310.05653)
		(width 0.1651)
		(layer "In13.Cu")
		(net "P4E_PEX0_STN3_TX_DP<48>")
	)
	(segment
		(start 35.678364 -290.417758)
		(end 35.989006 -290.107116)
		(width 0.1143)
		(layer "In13.Cu")
		(net "P4E_PEX0_STN3_TX_DP<48>")
	)
	(segment
		(start 57.926224 -345.583002)
		(end 57.37225 -342.708992)
		(width 0.1651)
		(layer "In13.Cu")
		(net "P4E_PEX0_STN3_TX_DP<48>")
	)
	(segment
		(start 54.51221 -338.88807)
		(end 48.827182 -335.249774)
		(width 0.1651)
		(layer "In13.Cu")
		(net "P4E_PEX0_STN3_TX_DP<48>")
	)
	(segment
		(start 59.983116 -367.187226)
		(end 59.982862 -367.186972)
		(width 0.1651)
		(layer "In13.Cu")
		(net "P4E_PEX0_STN3_TX_DP<48>")
	)
	(segment
		(start 35.10915 -318.00038)
		(end 35.043618 -317.74892)
		(width 0.1651)
		(layer "In13.Cu")
		(net "P4E_PEX0_STN3_TX_DP<48>")
	)
	(segment
		(start 58.964322 -359.808272)
		(end 59.047126 -359.690924)
		(width 0.1651)
		(layer "In13.Cu")
		(net "P4E_PEX0_STN3_TX_DP<48>")
	)
	(segment
		(start 48.827182 -335.249774)
		(end 45.814234 -332.820264)
		(width 0.1651)
		(layer "In13.Cu")
		(net "P4E_PEX0_STN3_TX_DP<48>")
	)
	(segment
		(start 35.989006 -290.107116)
		(end 42.363136 -290.107116)
		(width 0.1143)
		(layer "In13.Cu")
		(net "P4E_PEX0_STN3_TX_DP<48>")
	)
	(segment
		(start 59.983116 -369.45443)
		(end 59.983116 -367.187226)
		(width 0.1651)
		(layer "In13.Cu")
		(net "P4E_PEX0_STN3_TX_DP<48>")
	)
	(segment
		(start 58.84545 -359.120186)
		(end 58.761122 -358.631744)
		(width 0.1651)
		(layer "In13.Cu")
		(net "P4E_PEX0_STN3_TX_DP<48>")
	)
	(segment
		(start 35.043618 -317.74892)
		(end 35.066224 -312.445654)
		(width 0.1651)
		(layer "In13.Cu")
		(net "P4E_PEX0_STN3_TX_DP<48>")
	)
	(segment
		(start 43.683936 -288.774886)
		(end 43.974766 -288.774886)
		(width 0.1143)
		(layer "In13.Cu")
		(net "P4E_PEX0_STN3_TX_DP<48>")
	)
	(segment
		(start 42.363136 -290.107116)
		(end 42.454576 -290.015676)
		(width 0.1143)
		(layer "In13.Cu")
		(net "P4E_PEX0_STN3_TX_DP<48>")
	)
	(segment
		(start 35.636454 -291.081206)
		(end 35.678364 -291.039296)
		(width 0.1143)
		(layer "In13.Cu")
		(net "P4E_PEX0_STN3_TX_DP<48>")
	)
	(segment
		(start 58.012076 -370.737892)
		(end 58.699654 -370.737892)
		(width 0.1651)
		(layer "In13.Cu")
		(net "P4E_PEX0_STN3_TX_DP<48>")
	)
	(segment
		(start 59.357006 -361.484418)
		(end 59.166252 -360.379518)
		(width 0.1651)
		(layer "In13.Cu")
		(net "P4E_PEX0_STN3_TX_DP<48>")
	)
	(segment
		(start 35.678364 -291.039296)
		(end 35.678364 -290.417758)
		(width 0.1143)
		(layer "In13.Cu")
		(net "P4E_PEX0_STN3_TX_DP<48>")
	)
	(segment
		(start 58.761122 -358.631744)
		(end 58.843926 -358.514396)
		(width 0.1651)
		(layer "In13.Cu")
		(net "P4E_PEX0_STN3_TX_DP<48>")
	)
	(segment
		(start 35.636454 -291.103304)
		(end 35.636454 -291.081206)
		(width 0.1143)
		(layer "In13.Cu")
		(net "P4E_PEX0_STN3_TX_DP<48>")
	)
	(segment
		(start 43.595036 -288.481262)
		(end 43.595036 -288.685986)
		(width 0.1143)
		(layer "In13.Cu")
		(net "P4E_PEX0_STN3_TX_DP<48>")
	)
	(segment
		(start 57.37225 -342.708992)
		(end 54.51221 -338.88807)
		(width 0.1651)
		(layer "In13.Cu")
		(net "P4E_PEX0_STN3_TX_DP<48>")
	)
	(segment
		(start 38.273228 -323.58584)
		(end 35.10915 -318.00038)
		(width 0.1651)
		(layer "In13.Cu")
		(net "P4E_PEX0_STN3_TX_DP<48>")
	)
	(segment
		(start 57.721246 -370.447062)
		(end 58.012076 -370.737892)
		(width 0.1651)
		(layer "In13.Cu")
		(net "P4E_PEX0_STN3_TX_DP<48>")
	)
	(segment
		(start 34.792158 -303.738788)
		(end 35.019996 -302.592994)
		(width 0.1651)
		(layer "In13.Cu")
		(net "P4E_PEX0_STN3_TX_DP<48>")
	)
	(segment
		(start 58.843926 -358.514396)
		(end 57.926224 -353.197668)
		(width 0.1651)
		(layer "In13.Cu")
		(net "P4E_PEX0_STN3_TX_DP<48>")
	)
	(segment
		(start 35.066224 -312.445654)
		(end 35.212782 -311.58815)
		(width 0.1651)
		(layer "In13.Cu")
		(net "P4E_PEX0_STN3_TX_DP<48>")
	)
	(segment
		(start 42.454576 -290.015676)
		(end 42.454576 -288.511742)
		(width 0.1143)
		(layer "In13.Cu")
		(net "P4E_PEX0_STN3_TX_DP<48>")
	)
	(segment
		(start 59.982862 -367.186972)
		(end 59.669934 -364.335568)
		(width 0.1651)
		(layer "In13.Cu")
		(net "P4E_PEX0_STN3_TX_DP<48>")
	)
	(segment
		(start 57.926224 -353.197668)
		(end 57.926224 -345.583002)
		(width 0.1651)
		(layer "In13.Cu")
		(net "P4E_PEX0_STN3_TX_DP<48>")
	)
	(segment
		(start 59.047126 -359.690924)
		(end 58.963052 -359.20299)
		(width 0.1651)
		(layer "In13.Cu")
		(net "P4E_PEX0_STN3_TX_DP<48>")
	)
	(segment
		(start 59.669934 -364.335314)
		(end 59.357006 -361.484418)
		(width 0.1651)
		(layer "In13.Cu")
		(net "P4E_PEX0_STN3_TX_DP<48>")
	)
	(segment
		(start 42.454576 -288.511742)
		(end 42.761662 -288.204656)
		(width 0.1143)
		(layer "In13.Cu")
		(net "P4E_PEX0_STN3_TX_DP<48>")
	)
	(segment
		(start 41.599866 -288.299906)
		(end 41.124886 -287.824926)
		(width 0.13462)
		(layer "F.Cu")
		(net "P4E_PEX0_STN3_TX_DN<49>")
	)
	(segment
		(start 57.721246 -368.516662)
		(end 57.428384 -368.2238)
		(width 0.13462)
		(layer "F.Cu")
		(net "P4E_PEX0_STN3_TX_DN<49>")
	)
	(segment
		(start 57.428384 -368.2238)
		(end 56.619648 -368.2238)
		(width 0.13462)
		(layer "F.Cu")
		(net "P4E_PEX0_STN3_TX_DN<49>")
	)
	(segment
		(start 56.619648 -368.2238)
		(end 56.301386 -368.542062)
		(width 0.13462)
		(layer "F.Cu")
		(net "P4E_PEX0_STN3_TX_DN<49>")
	)
	(segment
		(start 41.504616 -287.610296)
		(end 41.339516 -287.445196)
		(width 0.1143)
		(layer "In13.Cu")
		(net "P4E_PEX0_STN3_TX_DN<49>")
	)
	(segment
		(start 34.920174 -290.355782)
		(end 34.920174 -293.962074)
		(width 0.1651)
		(layer "In13.Cu")
		(net "P4E_PEX0_STN3_TX_DN<49>")
	)
	(segment
		(start 35.354006 -289.92195)
		(end 35.338512 -289.937444)
		(width 0.1143)
		(layer "In13.Cu")
		(net "P4E_PEX0_STN3_TX_DN<49>")
	)
	(segment
		(start 35.866578 -289.345116)
		(end 35.353752 -289.857942)
		(width 0.1143)
		(layer "In13.Cu")
		(net "P4E_PEX0_STN3_TX_DN<49>")
	)
	(segment
		(start 33.271714 -305.61788)
		(end 33.323022 -308.048914)
		(width 0.1651)
		(layer "In13.Cu")
		(net "P4E_PEX0_STN3_TX_DN<49>")
	)
	(segment
		(start 35.353752 -289.857942)
		(end 35.354006 -289.92195)
		(width 0.1143)
		(layer "In13.Cu")
		(net "P4E_PEX0_STN3_TX_DN<49>")
	)
	(segment
		(start 32.6136 -299.58538)
		(end 32.6136 -302.581056)
		(width 0.1651)
		(layer "In13.Cu")
		(net "P4E_PEX0_STN3_TX_DN<49>")
	)
	(segment
		(start 59.261248 -367.834418)
		(end 58.869834 -368.225832)
		(width 0.1651)
		(layer "In13.Cu")
		(net "P4E_PEX0_STN3_TX_DN<49>")
	)
	(segment
		(start 57.132728 -345.81592)
		(end 57.132728 -353.836224)
		(width 0.1651)
		(layer "In13.Cu")
		(net "P4E_PEX0_STN3_TX_DN<49>")
	)
	(segment
		(start 42.629582 -330.487528)
		(end 42.77233 -330.502006)
		(width 0.1651)
		(layer "In13.Cu")
		(net "P4E_PEX0_STN3_TX_DN<49>")
	)
	(segment
		(start 40.745156 -287.571942)
		(end 40.745156 -289.099244)
		(width 0.1143)
		(layer "In13.Cu")
		(net "P4E_PEX0_STN3_TX_DN<49>")
	)
	(segment
		(start 43.08602 -330.8858)
		(end 43.071542 -331.028802)
		(width 0.1651)
		(layer "In13.Cu")
		(net "P4E_PEX0_STN3_TX_DN<49>")
	)
	(segment
		(start 56.302402 -343.125298)
		(end 57.132728 -345.81592)
		(width 0.1651)
		(layer "In13.Cu")
		(net "P4E_PEX0_STN3_TX_DN<49>")
	)
	(segment
		(start 41.504616 -287.736026)
		(end 41.504616 -287.610296)
		(width 0.1143)
		(layer "In13.Cu")
		(net "P4E_PEX0_STN3_TX_DN<49>")
	)
	(segment
		(start 41.415716 -287.824926)
		(end 41.504616 -287.736026)
		(width 0.1143)
		(layer "In13.Cu")
		(net "P4E_PEX0_STN3_TX_DN<49>")
	)
	(segment
		(start 33.76676 -310.852058)
		(end 33.745424 -314.51423)
		(width 0.1651)
		(layer "In13.Cu")
		(net "P4E_PEX0_STN3_TX_DN<49>")
	)
	(segment
		(start 34.026602 -316.156594)
		(end 34.144204 -316.239398)
		(width 0.1651)
		(layer "In13.Cu")
		(net "P4E_PEX0_STN3_TX_DN<49>")
	)
	(segment
		(start 33.005522 -303.909476)
		(end 32.927798 -304.03038)
		(width 0.1651)
		(layer "In13.Cu")
		(net "P4E_PEX0_STN3_TX_DN<49>")
	)
	(segment
		(start 54.105302 -339.586824)
		(end 56.302402 -343.125298)
		(width 0.1651)
		(layer "In13.Cu")
		(net "P4E_PEX0_STN3_TX_DN<49>")
	)
	(segment
		(start 34.144966 -316.845188)
		(end 34.467292 -318.728598)
		(width 0.1651)
		(layer "In13.Cu")
		(net "P4E_PEX0_STN3_TX_DN<49>")
	)
	(segment
		(start 43.071542 -331.028802)
		(end 44.230544 -332.448408)
		(width 0.1651)
		(layer "In13.Cu")
		(net "P4E_PEX0_STN3_TX_DN<49>")
	)
	(segment
		(start 32.961834 -295.920414)
		(end 32.388302 -297.305476)
		(width 0.1651)
		(layer "In13.Cu")
		(net "P4E_PEX0_STN3_TX_DN<49>")
	)
	(segment
		(start 42.77233 -330.502006)
		(end 43.08602 -330.8858)
		(width 0.1651)
		(layer "In13.Cu")
		(net "P4E_PEX0_STN3_TX_DN<49>")
	)
	(segment
		(start 32.388302 -297.305476)
		(end 32.388302 -298.273724)
		(width 0.1651)
		(layer "In13.Cu")
		(net "P4E_PEX0_STN3_TX_DN<49>")
	)
	(segment
		(start 58.869834 -368.225832)
		(end 58.012076 -368.225832)
		(width 0.1651)
		(layer "In13.Cu")
		(net "P4E_PEX0_STN3_TX_DN<49>")
	)
	(segment
		(start 41.339516 -287.445196)
		(end 40.871902 -287.445196)
		(width 0.1143)
		(layer "In13.Cu")
		(net "P4E_PEX0_STN3_TX_DN<49>")
	)
	(segment
		(start 58.552842 -362.017564)
		(end 59.261248 -367.007902)
		(width 0.1651)
		(layer "In13.Cu")
		(net "P4E_PEX0_STN3_TX_DN<49>")
	)
	(segment
		(start 40.871902 -287.445196)
		(end 40.745156 -287.571942)
		(width 0.1143)
		(layer "In13.Cu")
		(net "P4E_PEX0_STN3_TX_DN<49>")
	)
	(segment
		(start 59.261248 -367.007902)
		(end 59.261248 -367.834418)
		(width 0.1651)
		(layer "In13.Cu")
		(net "P4E_PEX0_STN3_TX_DN<49>")
	)
	(segment
		(start 41.124886 -287.824926)
		(end 41.415716 -287.824926)
		(width 0.1143)
		(layer "In13.Cu")
		(net "P4E_PEX0_STN3_TX_DN<49>")
	)
	(segment
		(start 35.338512 -289.937444)
		(end 34.920174 -290.355782)
		(width 0.1651)
		(layer "In13.Cu")
		(net "P4E_PEX0_STN3_TX_DN<49>")
	)
	(segment
		(start 32.779462 -303.347374)
		(end 32.90062 -303.425098)
		(width 0.1651)
		(layer "In13.Cu")
		(net "P4E_PEX0_STN3_TX_DN<49>")
	)
	(segment
		(start 32.6644 -299.53458)
		(end 32.6136 -299.58538)
		(width 0.1651)
		(layer "In13.Cu")
		(net "P4E_PEX0_STN3_TX_DN<49>")
	)
	(segment
		(start 32.388302 -298.273724)
		(end 32.6644 -298.940474)
		(width 0.1651)
		(layer "In13.Cu")
		(net "P4E_PEX0_STN3_TX_DN<49>")
	)
	(segment
		(start 33.323022 -308.048914)
		(end 33.76676 -310.852058)
		(width 0.1651)
		(layer "In13.Cu")
		(net "P4E_PEX0_STN3_TX_DN<49>")
	)
	(segment
		(start 32.6644 -298.940474)
		(end 32.6644 -299.53458)
		(width 0.1651)
		(layer "In13.Cu")
		(net "P4E_PEX0_STN3_TX_DN<49>")
	)
	(segment
		(start 34.144204 -316.239398)
		(end 34.22777 -316.72784)
		(width 0.1651)
		(layer "In13.Cu")
		(net "P4E_PEX0_STN3_TX_DN<49>")
	)
	(segment
		(start 34.467292 -318.728598)
		(end 35.72129 -320.942208)
		(width 0.1651)
		(layer "In13.Cu")
		(net "P4E_PEX0_STN3_TX_DN<49>")
	)
	(segment
		(start 57.137808 -353.841304)
		(end 57.140348 -353.841304)
		(width 0.1651)
		(layer "In13.Cu")
		(net "P4E_PEX0_STN3_TX_DN<49>")
	)
	(segment
		(start 57.140348 -353.841304)
		(end 58.552334 -362.013246)
		(width 0.1651)
		(layer "In13.Cu")
		(net "P4E_PEX0_STN3_TX_DN<49>")
	)
	(segment
		(start 40.499284 -289.345116)
		(end 35.866578 -289.345116)
		(width 0.1143)
		(layer "In13.Cu")
		(net "P4E_PEX0_STN3_TX_DN<49>")
	)
	(segment
		(start 58.012076 -368.225832)
		(end 57.721246 -368.516662)
		(width 0.1651)
		(layer "In13.Cu")
		(net "P4E_PEX0_STN3_TX_DN<49>")
	)
	(segment
		(start 32.927798 -304.03038)
		(end 33.271714 -305.61788)
		(width 0.1651)
		(layer "In13.Cu")
		(net "P4E_PEX0_STN3_TX_DN<49>")
	)
	(segment
		(start 40.745156 -289.099244)
		(end 40.499284 -289.345116)
		(width 0.1143)
		(layer "In13.Cu")
		(net "P4E_PEX0_STN3_TX_DN<49>")
	)
	(segment
		(start 36.104068 -321.411854)
		(end 36.065714 -321.550284)
		(width 0.1651)
		(layer "In13.Cu")
		(net "P4E_PEX0_STN3_TX_DN<49>")
	)
	(segment
		(start 32.90062 -303.425098)
		(end 33.005522 -303.909476)
		(width 0.1651)
		(layer "In13.Cu")
		(net "P4E_PEX0_STN3_TX_DN<49>")
	)
	(segment
		(start 34.22777 -316.72784)
		(end 34.144966 -316.845188)
		(width 0.1651)
		(layer "In13.Cu")
		(net "P4E_PEX0_STN3_TX_DN<49>")
	)
	(segment
		(start 49.013364 -336.333338)
		(end 54.105302 -339.586824)
		(width 0.1651)
		(layer "In13.Cu")
		(net "P4E_PEX0_STN3_TX_DN<49>")
	)
	(segment
		(start 58.552334 -362.013246)
		(end 58.552842 -362.017564)
		(width 0.1651)
		(layer "In13.Cu")
		(net "P4E_PEX0_STN3_TX_DN<49>")
	)
	(segment
		(start 35.72129 -320.942208)
		(end 35.85972 -320.980562)
		(width 0.1651)
		(layer "In13.Cu")
		(net "P4E_PEX0_STN3_TX_DN<49>")
	)
	(segment
		(start 37.727128 -324.483476)
		(end 42.629582 -330.487528)
		(width 0.1651)
		(layer "In13.Cu")
		(net "P4E_PEX0_STN3_TX_DN<49>")
	)
	(segment
		(start 35.85972 -320.980562)
		(end 36.104068 -321.411854)
		(width 0.1651)
		(layer "In13.Cu")
		(net "P4E_PEX0_STN3_TX_DN<49>")
	)
	(segment
		(start 34.920174 -293.962074)
		(end 32.961834 -295.920414)
		(width 0.1651)
		(layer "In13.Cu")
		(net "P4E_PEX0_STN3_TX_DN<49>")
	)
	(segment
		(start 33.745424 -314.51423)
		(end 34.026602 -316.156594)
		(width 0.1651)
		(layer "In13.Cu")
		(net "P4E_PEX0_STN3_TX_DN<49>")
	)
	(segment
		(start 36.065714 -321.550284)
		(end 37.727128 -324.483476)
		(width 0.1651)
		(layer "In13.Cu")
		(net "P4E_PEX0_STN3_TX_DN<49>")
	)
	(segment
		(start 32.6136 -302.581056)
		(end 32.779462 -303.347374)
		(width 0.1651)
		(layer "In13.Cu")
		(net "P4E_PEX0_STN3_TX_DN<49>")
	)
	(segment
		(start 44.230544 -332.448408)
		(end 49.013364 -336.333338)
		(width 0.1651)
		(layer "In13.Cu")
		(net "P4E_PEX0_STN3_TX_DN<49>")
	)
	(segment
		(start 57.132728 -353.836224)
		(end 57.137808 -353.841304)
		(width 0.1651)
		(layer "In13.Cu")
		(net "P4E_PEX0_STN3_TX_DN<49>")
	)
	(segment
		(start 56.623204 -367.94948)
		(end 56.301386 -367.627662)
		(width 0.13462)
		(layer "F.Cu")
		(net "P4E_PEX0_STN3_TX_DP<49>")
	)
	(segment
		(start 57.721246 -367.653062)
		(end 57.424828 -367.94948)
		(width 0.13462)
		(layer "F.Cu")
		(net "P4E_PEX0_STN3_TX_DP<49>")
	)
	(segment
		(start 42.549826 -288.299906)
		(end 42.074846 -287.824926)
		(width 0.13462)
		(layer "F.Cu")
		(net "P4E_PEX0_STN3_TX_DP<49>")
	)
	(segment
		(start 57.424828 -367.94948)
		(end 56.623204 -367.94948)
		(width 0.13462)
		(layer "F.Cu")
		(net "P4E_PEX0_STN3_TX_DP<49>")
	)
	(segment
		(start 56.858408 -353.850194)
		(end 56.858408 -353.866196)
		(width 0.1651)
		(layer "In13.Cu")
		(net "P4E_PEX0_STN3_TX_DP<49>")
	)
	(segment
		(start 32.38246 -298.996608)
		(end 32.38246 -299.41774)
		(width 0.1651)
		(layer "In13.Cu")
		(net "P4E_PEX0_STN3_TX_DP<49>")
	)
	(segment
		(start 35.154616 -289.72256)
		(end 35.139122 -289.738054)
		(width 0.1143)
		(layer "In13.Cu")
		(net "P4E_PEX0_STN3_TX_DP<49>")
	)
	(segment
		(start 35.82035 -321.689222)
		(end 37.493448 -324.643496)
		(width 0.1651)
		(layer "In13.Cu")
		(net "P4E_PEX0_STN3_TX_DP<49>")
	)
	(segment
		(start 32.33166 -302.611282)
		(end 32.52851 -303.521618)
		(width 0.1651)
		(layer "In13.Cu")
		(net "P4E_PEX0_STN3_TX_DP<49>")
	)
	(segment
		(start 57.402222 -357.013002)
		(end 57.486296 -357.500936)
		(width 0.1651)
		(layer "In13.Cu")
		(net "P4E_PEX0_STN3_TX_DP<49>")
	)
	(segment
		(start 56.850788 -345.858592)
		(end 56.850788 -353.842574)
		(width 0.1651)
		(layer "In13.Cu")
		(net "P4E_PEX0_STN3_TX_DP<49>")
	)
	(segment
		(start 56.850788 -353.842574)
		(end 56.858408 -353.850194)
		(width 0.1651)
		(layer "In13.Cu")
		(net "P4E_PEX0_STN3_TX_DP<49>")
	)
	(segment
		(start 32.38246 -299.41774)
		(end 32.33166 -299.46854)
		(width 0.1651)
		(layer "In13.Cu")
		(net "P4E_PEX0_STN3_TX_DP<49>")
	)
	(segment
		(start 41.41851 -287.254696)
		(end 40.792908 -287.254696)
		(width 0.1143)
		(layer "In13.Cu")
		(net "P4E_PEX0_STN3_TX_DP<49>")
	)
	(segment
		(start 57.200292 -356.441756)
		(end 57.28462 -356.930198)
		(width 0.1651)
		(layer "In13.Cu")
		(net "P4E_PEX0_STN3_TX_DP<49>")
	)
	(segment
		(start 32.106362 -297.249342)
		(end 32.106362 -298.329858)
		(width 0.1651)
		(layer "In13.Cu")
		(net "P4E_PEX0_STN3_TX_DP<49>")
	)
	(segment
		(start 34.638234 -293.845234)
		(end 32.72282 -295.760648)
		(width 0.1651)
		(layer "In13.Cu")
		(net "P4E_PEX0_STN3_TX_DP<49>")
	)
	(segment
		(start 33.46323 -314.537344)
		(end 34.197544 -318.824864)
		(width 0.1651)
		(layer "In13.Cu")
		(net "P4E_PEX0_STN3_TX_DP<49>")
	)
	(segment
		(start 35.787584 -289.154616)
		(end 35.21964 -289.72256)
		(width 0.1143)
		(layer "In13.Cu")
		(net "P4E_PEX0_STN3_TX_DP<49>")
	)
	(segment
		(start 32.72282 -295.760648)
		(end 32.106362 -297.249342)
		(width 0.1651)
		(layer "In13.Cu")
		(net "P4E_PEX0_STN3_TX_DP<49>")
	)
	(segment
		(start 42.074846 -287.824926)
		(end 41.784016 -287.824926)
		(width 0.1143)
		(layer "In13.Cu")
		(net "P4E_PEX0_STN3_TX_DP<49>")
	)
	(segment
		(start 58.012076 -367.943892)
		(end 57.721246 -367.653062)
		(width 0.1651)
		(layer "In13.Cu")
		(net "P4E_PEX0_STN3_TX_DP<49>")
	)
	(segment
		(start 32.990282 -305.651154)
		(end 33.041336 -308.07406)
		(width 0.1651)
		(layer "In13.Cu")
		(net "P4E_PEX0_STN3_TX_DP<49>")
	)
	(segment
		(start 40.554656 -289.02025)
		(end 40.42029 -289.154616)
		(width 0.1143)
		(layer "In13.Cu")
		(net "P4E_PEX0_STN3_TX_DP<49>")
	)
	(segment
		(start 32.52851 -303.521618)
		(end 32.528764 -303.521872)
		(width 0.1651)
		(layer "In13.Cu")
		(net "P4E_PEX0_STN3_TX_DP<49>")
	)
	(segment
		(start 35.139122 -289.738054)
		(end 34.638234 -290.238942)
		(width 0.1651)
		(layer "In13.Cu")
		(net "P4E_PEX0_STN3_TX_DP<49>")
	)
	(segment
		(start 33.484566 -310.873394)
		(end 33.46323 -314.537344)
		(width 0.1651)
		(layer "In13.Cu")
		(net "P4E_PEX0_STN3_TX_DP<49>")
	)
	(segment
		(start 40.792908 -287.254696)
		(end 40.554656 -287.492948)
		(width 0.1143)
		(layer "In13.Cu")
		(net "P4E_PEX0_STN3_TX_DP<49>")
	)
	(segment
		(start 32.528764 -303.521872)
		(end 32.990282 -305.651154)
		(width 0.1651)
		(layer "In13.Cu")
		(net "P4E_PEX0_STN3_TX_DP<49>")
	)
	(segment
		(start 41.695116 -287.736026)
		(end 41.695116 -287.531302)
		(width 0.1143)
		(layer "In13.Cu")
		(net "P4E_PEX0_STN3_TX_DP<49>")
	)
	(segment
		(start 35.21964 -289.72256)
		(end 35.154616 -289.72256)
		(width 0.1143)
		(layer "In13.Cu")
		(net "P4E_PEX0_STN3_TX_DP<49>")
	)
	(segment
		(start 58.979308 -367.027968)
		(end 58.979308 -367.717578)
		(width 0.1651)
		(layer "In13.Cu")
		(net "P4E_PEX0_STN3_TX_DP<49>")
	)
	(segment
		(start 41.695116 -287.531302)
		(end 41.41851 -287.254696)
		(width 0.1143)
		(layer "In13.Cu")
		(net "P4E_PEX0_STN3_TX_DP<49>")
	)
	(segment
		(start 37.493448 -324.643496)
		(end 44.030392 -332.649068)
		(width 0.1651)
		(layer "In13.Cu")
		(net "P4E_PEX0_STN3_TX_DP<49>")
	)
	(segment
		(start 57.28462 -356.930198)
		(end 57.402222 -357.013002)
		(width 0.1651)
		(layer "In13.Cu")
		(net "P4E_PEX0_STN3_TX_DP<49>")
	)
	(segment
		(start 34.197544 -318.824864)
		(end 35.820096 -321.689222)
		(width 0.1651)
		(layer "In13.Cu")
		(net "P4E_PEX0_STN3_TX_DP<49>")
	)
	(segment
		(start 41.784016 -287.824926)
		(end 41.695116 -287.736026)
		(width 0.1143)
		(layer "In13.Cu")
		(net "P4E_PEX0_STN3_TX_DP<49>")
	)
	(segment
		(start 57.48782 -358.106726)
		(end 57.605676 -358.18953)
		(width 0.1651)
		(layer "In13.Cu")
		(net "P4E_PEX0_STN3_TX_DP<49>")
	)
	(segment
		(start 57.486296 -357.500936)
		(end 57.403492 -357.618284)
		(width 0.1651)
		(layer "In13.Cu")
		(net "P4E_PEX0_STN3_TX_DP<49>")
	)
	(segment
		(start 58.752994 -367.943892)
		(end 58.012076 -367.943892)
		(width 0.1651)
		(layer "In13.Cu")
		(net "P4E_PEX0_STN3_TX_DP<49>")
	)
	(segment
		(start 53.899562 -339.790024)
		(end 56.043576 -343.243154)
		(width 0.1651)
		(layer "In13.Cu")
		(net "P4E_PEX0_STN3_TX_DP<49>")
	)
	(segment
		(start 34.638234 -290.238942)
		(end 34.638234 -293.845234)
		(width 0.1651)
		(layer "In13.Cu")
		(net "P4E_PEX0_STN3_TX_DP<49>")
	)
	(segment
		(start 35.820096 -321.689222)
		(end 35.82035 -321.689222)
		(width 0.1651)
		(layer "In13.Cu")
		(net "P4E_PEX0_STN3_TX_DP<49>")
	)
	(segment
		(start 57.403492 -357.618284)
		(end 57.48782 -358.106726)
		(width 0.1651)
		(layer "In13.Cu")
		(net "P4E_PEX0_STN3_TX_DP<49>")
	)
	(segment
		(start 33.041336 -308.07406)
		(end 33.484566 -310.873394)
		(width 0.1651)
		(layer "In13.Cu")
		(net "P4E_PEX0_STN3_TX_DP<49>")
	)
	(segment
		(start 57.605676 -358.18953)
		(end 57.605422 -358.18953)
		(width 0.1651)
		(layer "In13.Cu")
		(net "P4E_PEX0_STN3_TX_DP<49>")
	)
	(segment
		(start 57.283096 -356.324408)
		(end 57.200292 -356.441756)
		(width 0.1651)
		(layer "In13.Cu")
		(net "P4E_PEX0_STN3_TX_DP<49>")
	)
	(segment
		(start 32.106362 -298.329858)
		(end 32.38246 -298.996608)
		(width 0.1651)
		(layer "In13.Cu")
		(net "P4E_PEX0_STN3_TX_DP<49>")
	)
	(segment
		(start 57.605422 -358.18953)
		(end 58.273696 -362.057188)
		(width 0.1651)
		(layer "In13.Cu")
		(net "P4E_PEX0_STN3_TX_DP<49>")
	)
	(segment
		(start 58.979308 -367.717578)
		(end 58.752994 -367.943892)
		(width 0.1651)
		(layer "In13.Cu")
		(net "P4E_PEX0_STN3_TX_DP<49>")
	)
	(segment
		(start 56.858408 -353.866196)
		(end 57.283096 -356.324408)
		(width 0.1651)
		(layer "In13.Cu")
		(net "P4E_PEX0_STN3_TX_DP<49>")
	)
	(segment
		(start 40.42029 -289.154616)
		(end 35.787584 -289.154616)
		(width 0.1143)
		(layer "In13.Cu")
		(net "P4E_PEX0_STN3_TX_DP<49>")
	)
	(segment
		(start 58.273696 -362.057188)
		(end 58.979308 -367.027968)
		(width 0.1651)
		(layer "In13.Cu")
		(net "P4E_PEX0_STN3_TX_DP<49>")
	)
	(segment
		(start 40.554656 -287.492948)
		(end 40.554656 -289.02025)
		(width 0.1143)
		(layer "In13.Cu")
		(net "P4E_PEX0_STN3_TX_DP<49>")
	)
	(segment
		(start 48.84801 -336.562446)
		(end 53.899562 -339.790024)
		(width 0.1651)
		(layer "In13.Cu")
		(net "P4E_PEX0_STN3_TX_DP<49>")
	)
	(segment
		(start 56.043576 -343.243154)
		(end 56.850788 -345.858592)
		(width 0.1651)
		(layer "In13.Cu")
		(net "P4E_PEX0_STN3_TX_DP<49>")
	)
	(segment
		(start 32.33166 -299.46854)
		(end 32.33166 -302.611282)
		(width 0.1651)
		(layer "In13.Cu")
		(net "P4E_PEX0_STN3_TX_DP<49>")
	)
	(segment
		(start 44.030392 -332.649068)
		(end 48.84801 -336.562446)
		(width 0.1651)
		(layer "In13.Cu")
		(net "P4E_PEX0_STN3_TX_DP<49>")
	)
	(segment
		(start 36.849812 -289.249866)
		(end 36.374832 -288.774886)
		(width 0.13462)
		(layer "F.Cu")
		(net "P4E_PEX0_STN3_RX_DN<48>")
	)
	(segment
		(start 26.47442 -309.877206)
		(end 27.356054 -307.748686)
		(width 0.1651)
		(layer "In13.Cu")
		(net "P4E_PEX0_STN3_RX_DN<48>")
	)
	(segment
		(start 30.439868 -297.47845)
		(end 30.541468 -297.37685)
		(width 0.1651)
		(layer "In13.Cu")
		(net "P4E_PEX0_STN3_RX_DN<48>")
	)
	(segment
		(start 50.273966 -339.069426)
		(end 31.762954 -328.238104)
		(width 0.1651)
		(layer "In13.Cu")
		(net "P4E_PEX0_STN3_RX_DN<48>")
	)
	(segment
		(start 55.73014 -346.67571)
		(end 54.270656 -342.70188)
		(width 0.1651)
		(layer "In13.Cu")
		(net "P4E_PEX0_STN3_RX_DN<48>")
	)
	(segment
		(start 47.83709 -376.281188)
		(end 48.569626 -376.281188)
		(width 0.1651)
		(layer "In13.Cu")
		(net "P4E_PEX0_STN3_RX_DN<48>")
	)
	(segment
		(start 30.541468 -294.49395)
		(end 30.439868 -294.39235)
		(width 0.1651)
		(layer "In13.Cu")
		(net "P4E_PEX0_STN3_RX_DN<48>")
	)
	(segment
		(start 26.509218 -324.729602)
		(end 24.900128 -323.120004)
		(width 0.1651)
		(layer "In13.Cu")
		(net "P4E_PEX0_STN3_RX_DN<48>")
	)
	(segment
		(start 48.96866 -372.356126)
		(end 55.73014 -353.459542)
		(width 0.1651)
		(layer "In13.Cu")
		(net "P4E_PEX0_STN3_RX_DN<48>")
	)
	(segment
		(start 33.01873 -289.410394)
		(end 33.214564 -289.21456)
		(width 0.1651)
		(layer "In13.Cu")
		(net "P4E_PEX0_STN3_RX_DN<48>")
	)
	(segment
		(start 31.569914 -292.060884)
		(end 31.920434 -291.710364)
		(width 0.1651)
		(layer "In13.Cu")
		(net "P4E_PEX0_STN3_RX_DN<48>")
	)
	(segment
		(start 34.46907 -289.21456)
		(end 34.874962 -288.808668)
		(width 0.1651)
		(layer "In13.Cu")
		(net "P4E_PEX0_STN3_RX_DN<48>")
	)
	(segment
		(start 47.71009 -376.790204)
		(end 47.71009 -376.408188)
		(width 0.1651)
		(layer "In13.Cu")
		(net "P4E_PEX0_STN3_RX_DN<48>")
	)
	(segment
		(start 30.541468 -297.37685)
		(end 30.541468 -296.88155)
		(width 0.1651)
		(layer "In13.Cu")
		(net "P4E_PEX0_STN3_RX_DN<48>")
	)
	(segment
		(start 31.762954 -328.238104)
		(end 26.509218 -324.729602)
		(width 0.1651)
		(layer "In13.Cu")
		(net "P4E_PEX0_STN3_RX_DN<48>")
	)
	(segment
		(start 36.754562 -288.560256)
		(end 36.754562 -288.685986)
		(width 0.1143)
		(layer "In13.Cu")
		(net "P4E_PEX0_STN3_RX_DN<48>")
	)
	(segment
		(start 30.439868 -294.39235)
		(end 30.439868 -293.047166)
		(width 0.1651)
		(layer "In13.Cu")
		(net "P4E_PEX0_STN3_RX_DN<48>")
	)
	(segment
		(start 30.439868 -296.28465)
		(end 30.541468 -296.18305)
		(width 0.1651)
		(layer "In13.Cu")
		(net "P4E_PEX0_STN3_RX_DN<48>")
	)
	(segment
		(start 24.900128 -323.120004)
		(end 24.46528 -322.070222)
		(width 0.1651)
		(layer "In13.Cu")
		(net "P4E_PEX0_STN3_RX_DN<48>")
	)
	(segment
		(start 30.439868 -295.09085)
		(end 30.541468 -294.98925)
		(width 0.1651)
		(layer "In13.Cu")
		(net "P4E_PEX0_STN3_RX_DN<48>")
	)
	(segment
		(start 32.270446 -291.216588)
		(end 33.01873 -289.410394)
		(width 0.1651)
		(layer "In13.Cu")
		(net "P4E_PEX0_STN3_RX_DN<48>")
	)
	(segment
		(start 31.920434 -291.5666)
		(end 32.270446 -291.216588)
		(width 0.1651)
		(layer "In13.Cu")
		(net "P4E_PEX0_STN3_RX_DN<48>")
	)
	(segment
		(start 30.439868 -295.58615)
		(end 30.439868 -295.09085)
		(width 0.1651)
		(layer "In13.Cu")
		(net "P4E_PEX0_STN3_RX_DN<48>")
	)
	(segment
		(start 35.245294 -288.3789)
		(end 36.573206 -288.3789)
		(width 0.1143)
		(layer "In13.Cu")
		(net "P4E_PEX0_STN3_RX_DN<48>")
	)
	(segment
		(start 52.792376 -340.404958)
		(end 50.273966 -339.069426)
		(width 0.1651)
		(layer "In13.Cu")
		(net "P4E_PEX0_STN3_RX_DN<48>")
	)
	(segment
		(start 30.541468 -294.98925)
		(end 30.541468 -294.49395)
		(width 0.1651)
		(layer "In13.Cu")
		(net "P4E_PEX0_STN3_RX_DN<48>")
	)
	(segment
		(start 34.890456 -288.793174)
		(end 34.890456 -288.733738)
		(width 0.1143)
		(layer "In13.Cu")
		(net "P4E_PEX0_STN3_RX_DN<48>")
	)
	(segment
		(start 55.73014 -353.459542)
		(end 55.73014 -346.67571)
		(width 0.1651)
		(layer "In13.Cu")
		(net "P4E_PEX0_STN3_RX_DN<48>")
	)
	(segment
		(start 30.439868 -296.77995)
		(end 30.439868 -296.28465)
		(width 0.1651)
		(layer "In13.Cu")
		(net "P4E_PEX0_STN3_RX_DN<48>")
	)
	(segment
		(start 24.46528 -319.97777)
		(end 26.47442 -309.877206)
		(width 0.1651)
		(layer "In13.Cu")
		(net "P4E_PEX0_STN3_RX_DN<48>")
	)
	(segment
		(start 34.890456 -288.733738)
		(end 35.245294 -288.3789)
		(width 0.1143)
		(layer "In13.Cu")
		(net "P4E_PEX0_STN3_RX_DN<48>")
	)
	(segment
		(start 31.42615 -292.060884)
		(end 31.569914 -292.060884)
		(width 0.1651)
		(layer "In13.Cu")
		(net "P4E_PEX0_STN3_RX_DN<48>")
	)
	(segment
		(start 47.71009 -376.408188)
		(end 47.83709 -376.281188)
		(width 0.1651)
		(layer "In13.Cu")
		(net "P4E_PEX0_STN3_RX_DN<48>")
	)
	(segment
		(start 36.754562 -288.685986)
		(end 36.665662 -288.774886)
		(width 0.1143)
		(layer "In13.Cu")
		(net "P4E_PEX0_STN3_RX_DN<48>")
	)
	(segment
		(start 24.46528 -322.070222)
		(end 24.46528 -319.97777)
		(width 0.1651)
		(layer "In13.Cu")
		(net "P4E_PEX0_STN3_RX_DN<48>")
	)
	(segment
		(start 48.96866 -375.882154)
		(end 48.96866 -372.356126)
		(width 0.1651)
		(layer "In13.Cu")
		(net "P4E_PEX0_STN3_RX_DN<48>")
	)
	(segment
		(start 31.920434 -291.710364)
		(end 31.920434 -291.5666)
		(width 0.1651)
		(layer "In13.Cu")
		(net "P4E_PEX0_STN3_RX_DN<48>")
	)
	(segment
		(start 54.270656 -342.70188)
		(end 52.792376 -340.404958)
		(width 0.1651)
		(layer "In13.Cu")
		(net "P4E_PEX0_STN3_RX_DN<48>")
	)
	(segment
		(start 30.541468 -296.88155)
		(end 30.439868 -296.77995)
		(width 0.1651)
		(layer "In13.Cu")
		(net "P4E_PEX0_STN3_RX_DN<48>")
	)
	(segment
		(start 34.874962 -288.808668)
		(end 34.890456 -288.793174)
		(width 0.1143)
		(layer "In13.Cu")
		(net "P4E_PEX0_STN3_RX_DN<48>")
	)
	(segment
		(start 36.573206 -288.3789)
		(end 36.754562 -288.560256)
		(width 0.1143)
		(layer "In13.Cu")
		(net "P4E_PEX0_STN3_RX_DN<48>")
	)
	(segment
		(start 30.541468 -295.68775)
		(end 30.439868 -295.58615)
		(width 0.1651)
		(layer "In13.Cu")
		(net "P4E_PEX0_STN3_RX_DN<48>")
	)
	(segment
		(start 30.439868 -293.047166)
		(end 31.42615 -292.060884)
		(width 0.1651)
		(layer "In13.Cu")
		(net "P4E_PEX0_STN3_RX_DN<48>")
	)
	(segment
		(start 36.665662 -288.774886)
		(end 36.374832 -288.774886)
		(width 0.1143)
		(layer "In13.Cu")
		(net "P4E_PEX0_STN3_RX_DN<48>")
	)
	(segment
		(start 33.214564 -289.21456)
		(end 34.46907 -289.21456)
		(width 0.1651)
		(layer "In13.Cu")
		(net "P4E_PEX0_STN3_RX_DN<48>")
	)
	(segment
		(start 30.541468 -296.18305)
		(end 30.541468 -295.68775)
		(width 0.1651)
		(layer "In13.Cu")
		(net "P4E_PEX0_STN3_RX_DN<48>")
	)
	(segment
		(start 27.356054 -307.748686)
		(end 28.148788 -306.955952)
		(width 0.1651)
		(layer "In13.Cu")
		(net "P4E_PEX0_STN3_RX_DN<48>")
	)
	(segment
		(start 28.148788 -306.955952)
		(end 30.439868 -301.425102)
		(width 0.1651)
		(layer "In13.Cu")
		(net "P4E_PEX0_STN3_RX_DN<48>")
	)
	(segment
		(start 30.439868 -301.425102)
		(end 30.439868 -297.47845)
		(width 0.1651)
		(layer "In13.Cu")
		(net "P4E_PEX0_STN3_RX_DN<48>")
	)
	(segment
		(start 48.569626 -376.281188)
		(end 48.96866 -375.882154)
		(width 0.1651)
		(layer "In13.Cu")
		(net "P4E_PEX0_STN3_RX_DN<48>")
	)
	(segment
		(start 55.767986 -370.421662)
		(end 55.446168 -370.74348)
		(width 0.13462)
		(layer "F.Cu")
		(net "P4E_PEX0_STN3_TX_C_DP<48>")
	)
	(segment
		(start 55.446168 -370.74348)
		(end 54.644544 -370.74348)
		(width 0.13462)
		(layer "F.Cu")
		(net "P4E_PEX0_STN3_TX_C_DP<48>")
	)
	(segment
		(start 54.644544 -370.74348)
		(end 54.348126 -370.447062)
		(width 0.13462)
		(layer "F.Cu")
		(net "P4E_PEX0_STN3_TX_C_DP<48>")
	)
	(segment
		(start 47.78629 -372.099078)
		(end 48.626014 -372.099078)
		(width 0.1651)
		(layer "In15.Cu")
		(net "P4E_PEX0_STN3_TX_C_DP<48>")
	)
	(segment
		(start 48.626014 -372.099078)
		(end 51.912266 -370.737892)
		(width 0.1651)
		(layer "In15.Cu")
		(net "P4E_PEX0_STN3_TX_C_DP<48>")
	)
	(segment
		(start 51.912266 -370.737892)
		(end 54.057296 -370.737892)
		(width 0.1651)
		(layer "In15.Cu")
		(net "P4E_PEX0_STN3_TX_C_DP<48>")
	)
	(segment
		(start 54.057296 -370.737892)
		(end 54.348126 -370.447062)
		(width 0.1651)
		(layer "In15.Cu")
		(net "P4E_PEX0_STN3_TX_C_DP<48>")
	)
	(segment
		(start 47.71009 -372.022878)
		(end 47.78629 -372.099078)
		(width 0.1651)
		(layer "In15.Cu")
		(net "P4E_PEX0_STN3_TX_C_DP<48>")
	)
	(segment
		(start 47.71009 -371.590062)
		(end 47.71009 -372.022878)
		(width 0.1651)
		(layer "In15.Cu")
		(net "P4E_PEX0_STN3_TX_C_DP<48>")
	)
	(segment
		(start 54.640988 -371.0178)
		(end 54.348126 -371.310662)
		(width 0.13462)
		(layer "F.Cu")
		(net "P4E_PEX0_STN3_TX_C_DN<48>")
	)
	(segment
		(start 55.449724 -371.0178)
		(end 54.640988 -371.0178)
		(width 0.13462)
		(layer "F.Cu")
		(net "P4E_PEX0_STN3_TX_C_DN<48>")
	)
	(segment
		(start 55.767986 -371.336062)
		(end 55.449724 -371.0178)
		(width 0.13462)
		(layer "F.Cu")
		(net "P4E_PEX0_STN3_TX_C_DN<48>")
	)
	(segment
		(start 54.057296 -371.019832)
		(end 54.348126 -371.310662)
		(width 0.1651)
		(layer "In15.Cu")
		(net "P4E_PEX0_STN3_TX_C_DN<48>")
	)
	(segment
		(start 48.682148 -372.381018)
		(end 51.9684 -371.019832)
		(width 0.1651)
		(layer "In15.Cu")
		(net "P4E_PEX0_STN3_TX_C_DN<48>")
	)
	(segment
		(start 51.9684 -371.019832)
		(end 54.057296 -371.019832)
		(width 0.1651)
		(layer "In15.Cu")
		(net "P4E_PEX0_STN3_TX_C_DN<48>")
	)
	(segment
		(start 47.71009 -372.457218)
		(end 47.78629 -372.381018)
		(width 0.1651)
		(layer "In15.Cu")
		(net "P4E_PEX0_STN3_TX_C_DN<48>")
	)
	(segment
		(start 47.71009 -372.890034)
		(end 47.71009 -372.457218)
		(width 0.1651)
		(layer "In15.Cu")
		(net "P4E_PEX0_STN3_TX_C_DN<48>")
	)
	(segment
		(start 47.78629 -372.381018)
		(end 48.682148 -372.381018)
		(width 0.1651)
		(layer "In15.Cu")
		(net "P4E_PEX0_STN3_TX_C_DN<48>")
	)
	(segment
		(start 37.799772 -289.249866)
		(end 37.324792 -288.774886)
		(width 0.13462)
		(layer "F.Cu")
		(net "P4E_PEX0_STN3_RX_DP<48>")
	)
	(segment
		(start 36.6522 -288.1884)
		(end 36.945062 -288.481262)
		(width 0.1143)
		(layer "In13.Cu")
		(net "P4E_PEX0_STN3_RX_DP<48>")
	)
	(segment
		(start 34.755328 -288.599372)
		(end 35.1663 -288.1884)
		(width 0.1143)
		(layer "In13.Cu")
		(net "P4E_PEX0_STN3_RX_DP<48>")
	)
	(segment
		(start 55.039006 -345.611704)
		(end 54.90845 -345.551252)
		(width 0.1651)
		(layer "In13.Cu")
		(net "P4E_PEX0_STN3_RX_DP<48>")
	)
	(segment
		(start 52.595018 -340.619588)
		(end 50.136552 -339.315806)
		(width 0.1651)
		(layer "In13.Cu")
		(net "P4E_PEX0_STN3_RX_DP<48>")
	)
	(segment
		(start 34.675572 -288.609278)
		(end 34.68624 -288.609278)
		(width 0.1143)
		(layer "In13.Cu")
		(net "P4E_PEX0_STN3_RX_DP<48>")
	)
	(segment
		(start 24.661114 -323.27977)
		(end 24.18334 -322.12661)
		(width 0.1651)
		(layer "In13.Cu")
		(net "P4E_PEX0_STN3_RX_DP<48>")
	)
	(segment
		(start 54.016656 -342.828372)
		(end 52.595018 -340.619588)
		(width 0.1651)
		(layer "In13.Cu")
		(net "P4E_PEX0_STN3_RX_DP<48>")
	)
	(segment
		(start 54.90845 -345.551252)
		(end 54.737508 -345.086178)
		(width 0.1651)
		(layer "In13.Cu")
		(net "P4E_PEX0_STN3_RX_DP<48>")
	)
	(segment
		(start 47.71009 -375.490232)
		(end 47.71009 -375.872248)
		(width 0.1651)
		(layer "In13.Cu")
		(net "P4E_PEX0_STN3_RX_DP<48>")
	)
	(segment
		(start 32.779716 -289.250628)
		(end 33.097724 -288.93262)
		(width 0.1651)
		(layer "In13.Cu")
		(net "P4E_PEX0_STN3_RX_DP<48>")
	)
	(segment
		(start 48.68672 -375.765314)
		(end 48.68672 -372.307104)
		(width 0.1651)
		(layer "In13.Cu")
		(net "P4E_PEX0_STN3_RX_DP<48>")
	)
	(segment
		(start 30.157928 -301.368968)
		(end 30.157928 -292.930326)
		(width 0.1651)
		(layer "In13.Cu")
		(net "P4E_PEX0_STN3_RX_DP<48>")
	)
	(segment
		(start 55.4482 -353.41052)
		(end 55.4482 -346.726002)
		(width 0.1651)
		(layer "In13.Cu")
		(net "P4E_PEX0_STN3_RX_DP<48>")
	)
	(segment
		(start 48.68672 -372.307104)
		(end 55.4482 -353.41052)
		(width 0.1651)
		(layer "In13.Cu")
		(net "P4E_PEX0_STN3_RX_DP<48>")
	)
	(segment
		(start 34.35223 -288.93262)
		(end 34.675572 -288.609278)
		(width 0.1651)
		(layer "In13.Cu")
		(net "P4E_PEX0_STN3_RX_DP<48>")
	)
	(segment
		(start 27.909774 -306.796186)
		(end 30.157928 -301.368968)
		(width 0.1651)
		(layer "In13.Cu")
		(net "P4E_PEX0_STN3_RX_DP<48>")
	)
	(segment
		(start 34.6964 -288.599118)
		(end 34.755328 -288.599372)
		(width 0.1143)
		(layer "In13.Cu")
		(net "P4E_PEX0_STN3_RX_DP<48>")
	)
	(segment
		(start 48.452786 -375.999248)
		(end 48.68672 -375.765314)
		(width 0.1651)
		(layer "In13.Cu")
		(net "P4E_PEX0_STN3_RX_DP<48>")
	)
	(segment
		(start 54.737508 -345.086178)
		(end 54.79796 -344.955622)
		(width 0.1651)
		(layer "In13.Cu")
		(net "P4E_PEX0_STN3_RX_DP<48>")
	)
	(segment
		(start 54.79796 -344.955622)
		(end 54.016656 -342.828372)
		(width 0.1651)
		(layer "In13.Cu")
		(net "P4E_PEX0_STN3_RX_DP<48>")
	)
	(segment
		(start 55.4482 -346.726002)
		(end 55.039006 -345.611704)
		(width 0.1651)
		(layer "In13.Cu")
		(net "P4E_PEX0_STN3_RX_DP<48>")
	)
	(segment
		(start 30.157928 -292.930326)
		(end 32.031432 -291.056822)
		(width 0.1651)
		(layer "In13.Cu")
		(net "P4E_PEX0_STN3_RX_DP<48>")
	)
	(segment
		(start 26.203148 -309.79491)
		(end 27.11704 -307.58892)
		(width 0.1651)
		(layer "In13.Cu")
		(net "P4E_PEX0_STN3_RX_DP<48>")
	)
	(segment
		(start 24.18334 -319.94983)
		(end 26.203148 -309.79491)
		(width 0.1651)
		(layer "In13.Cu")
		(net "P4E_PEX0_STN3_RX_DP<48>")
	)
	(segment
		(start 47.83709 -375.999248)
		(end 48.452786 -375.999248)
		(width 0.1651)
		(layer "In13.Cu")
		(net "P4E_PEX0_STN3_RX_DP<48>")
	)
	(segment
		(start 47.71009 -375.872248)
		(end 47.83709 -375.999248)
		(width 0.1651)
		(layer "In13.Cu")
		(net "P4E_PEX0_STN3_RX_DP<48>")
	)
	(segment
		(start 37.033962 -288.774886)
		(end 37.324792 -288.774886)
		(width 0.1143)
		(layer "In13.Cu")
		(net "P4E_PEX0_STN3_RX_DP<48>")
	)
	(segment
		(start 50.136552 -339.315806)
		(end 31.613094 -328.477372)
		(width 0.1651)
		(layer "In13.Cu")
		(net "P4E_PEX0_STN3_RX_DP<48>")
	)
	(segment
		(start 32.031432 -291.056822)
		(end 32.779716 -289.250628)
		(width 0.1651)
		(layer "In13.Cu")
		(net "P4E_PEX0_STN3_RX_DP<48>")
	)
	(segment
		(start 34.68624 -288.609278)
		(end 34.6964 -288.599118)
		(width 0.1143)
		(layer "In13.Cu")
		(net "P4E_PEX0_STN3_RX_DP<48>")
	)
	(segment
		(start 36.945062 -288.685986)
		(end 37.033962 -288.774886)
		(width 0.1143)
		(layer "In13.Cu")
		(net "P4E_PEX0_STN3_RX_DP<48>")
	)
	(segment
		(start 31.613094 -328.477372)
		(end 26.329386 -324.94855)
		(width 0.1651)
		(layer "In13.Cu")
		(net "P4E_PEX0_STN3_RX_DP<48>")
	)
	(segment
		(start 26.329386 -324.94855)
		(end 24.661114 -323.27977)
		(width 0.1651)
		(layer "In13.Cu")
		(net "P4E_PEX0_STN3_RX_DP<48>")
	)
	(segment
		(start 33.097724 -288.93262)
		(end 34.35223 -288.93262)
		(width 0.1651)
		(layer "In13.Cu")
		(net "P4E_PEX0_STN3_RX_DP<48>")
	)
	(segment
		(start 27.11704 -307.58892)
		(end 27.909774 -306.796186)
		(width 0.1651)
		(layer "In13.Cu")
		(net "P4E_PEX0_STN3_RX_DP<48>")
	)
	(segment
		(start 36.945062 -288.481262)
		(end 36.945062 -288.685986)
		(width 0.1143)
		(layer "In13.Cu")
		(net "P4E_PEX0_STN3_RX_DP<48>")
	)
	(segment
		(start 24.18334 -322.12661)
		(end 24.18334 -319.94983)
		(width 0.1651)
		(layer "In13.Cu")
		(net "P4E_PEX0_STN3_RX_DP<48>")
	)
	(segment
		(start 35.1663 -288.1884)
		(end 36.6522 -288.1884)
		(width 0.1143)
		(layer "In13.Cu")
		(net "P4E_PEX0_STN3_RX_DP<48>")
	)
	(segment
		(start 38.749986 -288.299906)
		(end 38.275006 -287.824926)
		(width 0.13462)
		(layer "F.Cu")
		(net "P4E_PEX0_STN3_RX_DN<49>")
	)
	(segment
		(start 25.940258 -325.656194)
		(end 24.06015 -323.776086)
		(width 0.1651)
		(layer "In13.Cu")
		(net "P4E_PEX0_STN3_RX_DN<49>")
	)
	(segment
		(start 24.66594 -313.188096)
		(end 24.76246 -312.70194)
		(width 0.1651)
		(layer "In13.Cu")
		(net "P4E_PEX0_STN3_RX_DN<49>")
	)
	(segment
		(start 25.14854 -310.240426)
		(end 25.456134 -308.694074)
		(width 0.1651)
		(layer "In13.Cu")
		(net "P4E_PEX0_STN3_RX_DN<49>")
	)
	(segment
		(start 30.470856 -290.316666)
		(end 30.986984 -289.070796)
		(width 0.1651)
		(layer "In13.Cu")
		(net "P4E_PEX0_STN3_RX_DN<49>")
	)
	(segment
		(start 25.456134 -308.694074)
		(end 27.030172 -304.893726)
		(width 0.1651)
		(layer "In13.Cu")
		(net "P4E_PEX0_STN3_RX_DN<49>")
	)
	(segment
		(start 31.76016 -329.54468)
		(end 25.940258 -325.656194)
		(width 0.1651)
		(layer "In13.Cu")
		(net "P4E_PEX0_STN3_RX_DN<49>")
	)
	(segment
		(start 35.597846 -287.487106)
		(end 35.639756 -287.445196)
		(width 0.1143)
		(layer "In13.Cu")
		(net "P4E_PEX0_STN3_RX_DN<49>")
	)
	(segment
		(start 34.70021 -287.494726)
		(end 35.575748 -287.494726)
		(width 0.1651)
		(layer "In13.Cu")
		(net "P4E_PEX0_STN3_RX_DN<49>")
	)
	(segment
		(start 29.878782 -292.010084)
		(end 30.068774 -291.552376)
		(width 0.1651)
		(layer "In13.Cu")
		(net "P4E_PEX0_STN3_RX_DN<49>")
	)
	(segment
		(start 38.565836 -287.824926)
		(end 38.275006 -287.824926)
		(width 0.1143)
		(layer "In13.Cu")
		(net "P4E_PEX0_STN3_RX_DN<49>")
	)
	(segment
		(start 30.013656 -291.419534)
		(end 30.20314 -290.96208)
		(width 0.1651)
		(layer "In13.Cu")
		(net "P4E_PEX0_STN3_RX_DN<49>")
	)
	(segment
		(start 35.639756 -287.445196)
		(end 38.489636 -287.445196)
		(width 0.1143)
		(layer "In13.Cu")
		(net "P4E_PEX0_STN3_RX_DN<49>")
	)
	(segment
		(start 51.06543 -361.51947)
		(end 54.70652 -353.388422)
		(width 0.1651)
		(layer "In13.Cu")
		(net "P4E_PEX0_STN3_RX_DN<49>")
	)
	(segment
		(start 29.4132 -292.868604)
		(end 29.74594 -292.065202)
		(width 0.1651)
		(layer "In13.Cu")
		(net "P4E_PEX0_STN3_RX_DN<49>")
	)
	(segment
		(start 46.609762 -369.206018)
		(end 46.907958 -368.192304)
		(width 0.1651)
		(layer "In13.Cu")
		(net "P4E_PEX0_STN3_RX_DN<49>")
	)
	(segment
		(start 25.012142 -310.925972)
		(end 25.131776 -310.845962)
		(width 0.1651)
		(layer "In13.Cu")
		(net "P4E_PEX0_STN3_RX_DN<49>")
	)
	(segment
		(start 25.131776 -310.845962)
		(end 25.22855 -310.36006)
		(width 0.1651)
		(layer "In13.Cu")
		(net "P4E_PEX0_STN3_RX_DN<49>")
	)
	(segment
		(start 23.505922 -322.438014)
		(end 23.505922 -318.498728)
		(width 0.1651)
		(layer "In13.Cu")
		(net "P4E_PEX0_STN3_RX_DN<49>")
	)
	(segment
		(start 52.690522 -342.18245)
		(end 51.919124 -341.14359)
		(width 0.1651)
		(layer "In13.Cu")
		(net "P4E_PEX0_STN3_RX_DN<49>")
	)
	(segment
		(start 25.22855 -310.36006)
		(end 25.14854 -310.240426)
		(width 0.1651)
		(layer "In13.Cu")
		(net "P4E_PEX0_STN3_RX_DN<49>")
	)
	(segment
		(start 38.489636 -287.445196)
		(end 38.654736 -287.610296)
		(width 0.1143)
		(layer "In13.Cu")
		(net "P4E_PEX0_STN3_RX_DN<49>")
	)
	(segment
		(start 46.317662 -375.181114)
		(end 46.609762 -374.889014)
		(width 0.1651)
		(layer "In13.Cu")
		(net "P4E_PEX0_STN3_RX_DN<49>")
	)
	(segment
		(start 30.52572 -290.449254)
		(end 30.470856 -290.316666)
		(width 0.1651)
		(layer "In13.Cu")
		(net "P4E_PEX0_STN3_RX_DN<49>")
	)
	(segment
		(start 28.12415 -303.799748)
		(end 29.4132 -300.687486)
		(width 0.1651)
		(layer "In13.Cu")
		(net "P4E_PEX0_STN3_RX_DN<49>")
	)
	(segment
		(start 24.06015 -323.776086)
		(end 23.505922 -322.438014)
		(width 0.1651)
		(layer "In13.Cu")
		(net "P4E_PEX0_STN3_RX_DN<49>")
	)
	(segment
		(start 24.682704 -312.58256)
		(end 24.779224 -312.096912)
		(width 0.1651)
		(layer "In13.Cu")
		(net "P4E_PEX0_STN3_RX_DN<49>")
	)
	(segment
		(start 24.915622 -311.41162)
		(end 25.012142 -310.925972)
		(width 0.1651)
		(layer "In13.Cu")
		(net "P4E_PEX0_STN3_RX_DN<49>")
	)
	(segment
		(start 38.654736 -287.610296)
		(end 38.654736 -287.736026)
		(width 0.1143)
		(layer "In13.Cu")
		(net "P4E_PEX0_STN3_RX_DN<49>")
	)
	(segment
		(start 23.505922 -318.498728)
		(end 24.546306 -313.267852)
		(width 0.1651)
		(layer "In13.Cu")
		(net "P4E_PEX0_STN3_RX_DN<49>")
	)
	(segment
		(start 45.509942 -375.308114)
		(end 45.636942 -375.181114)
		(width 0.1651)
		(layer "In13.Cu")
		(net "P4E_PEX0_STN3_RX_DN<49>")
	)
	(segment
		(start 45.509942 -375.69013)
		(end 45.509942 -375.308114)
		(width 0.1651)
		(layer "In13.Cu")
		(net "P4E_PEX0_STN3_RX_DN<49>")
	)
	(segment
		(start 30.20314 -290.96208)
		(end 30.335982 -290.907216)
		(width 0.1651)
		(layer "In13.Cu")
		(net "P4E_PEX0_STN3_RX_DN<49>")
	)
	(segment
		(start 24.76246 -312.70194)
		(end 24.682704 -312.58256)
		(width 0.1651)
		(layer "In13.Cu")
		(net "P4E_PEX0_STN3_RX_DN<49>")
	)
	(segment
		(start 29.4132 -300.687486)
		(end 29.4132 -292.868604)
		(width 0.1651)
		(layer "In13.Cu")
		(net "P4E_PEX0_STN3_RX_DN<49>")
	)
	(segment
		(start 30.068774 -291.552376)
		(end 30.013656 -291.419534)
		(width 0.1651)
		(layer "In13.Cu")
		(net "P4E_PEX0_STN3_RX_DN<49>")
	)
	(segment
		(start 46.907958 -368.192304)
		(end 50.38725 -362.78566)
		(width 0.1651)
		(layer "In13.Cu")
		(net "P4E_PEX0_STN3_RX_DN<49>")
	)
	(segment
		(start 30.986984 -289.070796)
		(end 31.261812 -288.795968)
		(width 0.1651)
		(layer "In13.Cu")
		(net "P4E_PEX0_STN3_RX_DN<49>")
	)
	(segment
		(start 50.38725 -362.78566)
		(end 50.386488 -362.773214)
		(width 0.1651)
		(layer "In13.Cu")
		(net "P4E_PEX0_STN3_RX_DN<49>")
	)
	(segment
		(start 27.030172 -304.893726)
		(end 28.12415 -303.799748)
		(width 0.1651)
		(layer "In13.Cu")
		(net "P4E_PEX0_STN3_RX_DN<49>")
	)
	(segment
		(start 35.575748 -287.494726)
		(end 35.583368 -287.487106)
		(width 0.1143)
		(layer "In13.Cu")
		(net "P4E_PEX0_STN3_RX_DN<49>")
	)
	(segment
		(start 30.335982 -290.907216)
		(end 30.52572 -290.449254)
		(width 0.1651)
		(layer "In13.Cu")
		(net "P4E_PEX0_STN3_RX_DN<49>")
	)
	(segment
		(start 50.386488 -362.773214)
		(end 51.06543 -361.51947)
		(width 0.1651)
		(layer "In13.Cu")
		(net "P4E_PEX0_STN3_RX_DN<49>")
	)
	(segment
		(start 46.609762 -374.889014)
		(end 46.609762 -369.206018)
		(width 0.1651)
		(layer "In13.Cu")
		(net "P4E_PEX0_STN3_RX_DN<49>")
	)
	(segment
		(start 51.919124 -341.14359)
		(end 31.76016 -329.54468)
		(width 0.1651)
		(layer "In13.Cu")
		(net "P4E_PEX0_STN3_RX_DN<49>")
	)
	(segment
		(start 24.779224 -312.096912)
		(end 24.898858 -312.017156)
		(width 0.1651)
		(layer "In13.Cu")
		(net "P4E_PEX0_STN3_RX_DN<49>")
	)
	(segment
		(start 29.74594 -292.065202)
		(end 29.878782 -292.010084)
		(width 0.1651)
		(layer "In13.Cu")
		(net "P4E_PEX0_STN3_RX_DN<49>")
	)
	(segment
		(start 54.70652 -353.388422)
		(end 54.70652 -347.049852)
		(width 0.1651)
		(layer "In13.Cu")
		(net "P4E_PEX0_STN3_RX_DN<49>")
	)
	(segment
		(start 38.654736 -287.736026)
		(end 38.565836 -287.824926)
		(width 0.1143)
		(layer "In13.Cu")
		(net "P4E_PEX0_STN3_RX_DN<49>")
	)
	(segment
		(start 24.546306 -313.267852)
		(end 24.66594 -313.188096)
		(width 0.1651)
		(layer "In13.Cu")
		(net "P4E_PEX0_STN3_RX_DN<49>")
	)
	(segment
		(start 45.636942 -375.181114)
		(end 46.317662 -375.181114)
		(width 0.1651)
		(layer "In13.Cu")
		(net "P4E_PEX0_STN3_RX_DN<49>")
	)
	(segment
		(start 32.660844 -288.21634)
		(end 33.978596 -288.21634)
		(width 0.1651)
		(layer "In13.Cu")
		(net "P4E_PEX0_STN3_RX_DN<49>")
	)
	(segment
		(start 24.898858 -312.017156)
		(end 24.995378 -311.531)
		(width 0.1651)
		(layer "In13.Cu")
		(net "P4E_PEX0_STN3_RX_DN<49>")
	)
	(segment
		(start 31.261812 -288.795968)
		(end 32.660844 -288.21634)
		(width 0.1651)
		(layer "In13.Cu")
		(net "P4E_PEX0_STN3_RX_DN<49>")
	)
	(segment
		(start 24.995378 -311.531)
		(end 24.915622 -311.41162)
		(width 0.1651)
		(layer "In13.Cu")
		(net "P4E_PEX0_STN3_RX_DN<49>")
	)
	(segment
		(start 35.583368 -287.487106)
		(end 35.597846 -287.487106)
		(width 0.1143)
		(layer "In13.Cu")
		(net "P4E_PEX0_STN3_RX_DN<49>")
	)
	(segment
		(start 54.70652 -347.049852)
		(end 52.690522 -342.18245)
		(width 0.1651)
		(layer "In13.Cu")
		(net "P4E_PEX0_STN3_RX_DN<49>")
	)
	(segment
		(start 33.978596 -288.21634)
		(end 34.70021 -287.494726)
		(width 0.1651)
		(layer "In13.Cu")
		(net "P4E_PEX0_STN3_RX_DN<49>")
	)
	(segment
		(start 346.893896 -224.786952)
		(end 347.293692 -225.186748)
		(width 0.13208)
		(layer "F.Cu")
		(net "TP_DONE")
	)
	(via
		(at 347.293692 -225.186748)
		(size 0.4572)
		(drill 0.254)
		(layers "F.Cu" "B.Cu")
		(net "TP_DONE")
	)
	(via
		(at 356.155498 -230.70058)
		(size 0.508)
		(drill 0.254)
		(layers "F.Cu" "B.Cu")
		(net "TP_DONE")
	)
	(segment
		(start 347.293692 -225.186748)
		(end 347.691202 -225.584258)
		(width 0.0889)
		(layer "In5.Cu")
		(net "TP_DONE")
	)
	(segment
		(start 351.934526 -230.70058)
		(end 356.155498 -230.70058)
		(width 0.15494)
		(layer "In5.Cu")
		(net "TP_DONE")
	)
	(segment
		(start 350.418654 -228.950774)
		(end 350.418654 -229.794562)
		(width 0.15494)
		(layer "In5.Cu")
		(net "TP_DONE")
	)
	(segment
		(start 351.343722 -230.109776)
		(end 351.934526 -230.70058)
		(width 0.15494)
		(layer "In5.Cu")
		(net "TP_DONE")
	)
	(segment
		(start 347.691202 -227.27158)
		(end 348.558104 -228.138482)
		(width 0.15494)
		(layer "In5.Cu")
		(net "TP_DONE")
	)
	(segment
		(start 350.418654 -229.794562)
		(end 350.733868 -230.109776)
		(width 0.15494)
		(layer "In5.Cu")
		(net "TP_DONE")
	)
	(segment
		(start 350.733868 -230.109776)
		(end 351.343722 -230.109776)
		(width 0.15494)
		(layer "In5.Cu")
		(net "TP_DONE")
	)
	(segment
		(start 348.558104 -228.138482)
		(end 349.606362 -228.138482)
		(width 0.15494)
		(layer "In5.Cu")
		(net "TP_DONE")
	)
	(segment
		(start 347.691202 -225.584258)
		(end 347.691202 -227.27158)
		(width 0.0889)
		(layer "In5.Cu")
		(net "TP_DONE")
	)
	(segment
		(start 349.606362 -228.138482)
		(end 350.418654 -228.950774)
		(width 0.15494)
		(layer "In5.Cu")
		(net "TP_DONE")
	)
	(segment
		(start 346.093796 -223.987106)
		(end 346.493592 -224.386902)
		(width 0.13208)
		(layer "F.Cu")
		(net "TP_INITN")
	)
	(via
		(at 346.493592 -224.386902)
		(size 0.4572)
		(drill 0.254)
		(layers "F.Cu" "B.Cu")
		(net "TP_INITN")
	)
	(via
		(at 354.302314 -232.354882)
		(size 0.508)
		(drill 0.254)
		(layers "F.Cu" "B.Cu")
		(net "TP_INITN")
	)
	(segment
		(start 347.642434 -227.698046)
		(end 347.431106 -227.698046)
		(width 0.15494)
		(layer "In5.Cu")
		(net "TP_INITN")
	)
	(segment
		(start 347.431106 -227.698046)
		(end 346.891102 -227.158042)
		(width 0.15494)
		(layer "In5.Cu")
		(net "TP_INITN")
	)
	(segment
		(start 346.891102 -227.158042)
		(end 346.891102 -226.946714)
		(width 0.15494)
		(layer "In5.Cu")
		(net "TP_INITN")
	)
	(segment
		(start 351.113598 -231.16921)
		(end 347.642434 -227.698046)
		(width 0.15494)
		(layer "In5.Cu")
		(net "TP_INITN")
	)
	(segment
		(start 353.116642 -231.16921)
		(end 351.113598 -231.16921)
		(width 0.15494)
		(layer "In5.Cu")
		(net "TP_INITN")
	)
	(segment
		(start 354.302314 -232.354882)
		(end 353.116642 -231.16921)
		(width 0.15494)
		(layer "In5.Cu")
		(net "TP_INITN")
	)
	(segment
		(start 346.891102 -226.946714)
		(end 346.891102 -224.784412)
		(width 0.0889)
		(layer "In5.Cu")
		(net "TP_INITN")
	)
	(segment
		(start 346.891102 -224.784412)
		(end 346.493592 -224.386902)
		(width 0.0889)
		(layer "In5.Cu")
		(net "TP_INITN")
	)
	(segment
		(start 224.267776 -215.904064)
		(end 223.86798 -215.504268)
		(width 0.13208)
		(layer "F.Cu")
		(net "Net_640")
	)
	(via
		(at 223.86798 -215.504268)
		(size 0.4572)
		(drill 0.254)
		(layers "F.Cu" "B.Cu")
		(net "Net_640")
	)
	(segment
		(start 233.067606 -214.304118)
		(end 233.467402 -213.904322)
		(width 0.13208)
		(layer "F.Cu")
		(net "Net_641")
	)
	(via
		(at 233.467402 -213.904322)
		(size 0.4572)
		(drill 0.254)
		(layers "F.Cu" "B.Cu")
		(net "Net_641")
	)
	(segment
		(start 233.067606 -213.504272)
		(end 233.467402 -213.104476)
		(width 0.13208)
		(layer "F.Cu")
		(net "BIC_SPI1DQ3")
	)
	(via
		(at 233.467402 -213.104476)
		(size 0.4572)
		(drill 0.254)
		(layers "F.Cu" "B.Cu")
		(net "BIC_SPI1DQ3")
	)
	(via
		(at 233.604308 -210.015582)
		(size 0.6604)
		(drill 0.3302)
		(layers "F.Cu" "B.Cu")
		(net "BIC_SPI1DQ3")
	)
	(segment
		(start 232.980738 -212.411564)
		(end 232.980738 -210.639152)
		(width 0.13208)
		(layer "B.Cu")
		(net "BIC_SPI1DQ3")
	)
	(segment
		(start 233.020362 -208.809082)
		(end 233.604308 -209.393028)
		(width 0.13208)
		(layer "B.Cu")
		(net "BIC_SPI1DQ3")
	)
	(segment
		(start 233.604308 -209.393028)
		(end 233.604308 -210.015582)
		(width 0.13208)
		(layer "B.Cu")
		(net "BIC_SPI1DQ3")
	)
	(segment
		(start 233.467402 -212.898228)
		(end 232.980738 -212.411564)
		(width 0.13208)
		(layer "B.Cu")
		(net "BIC_SPI1DQ3")
	)
	(segment
		(start 232.980738 -210.639152)
		(end 233.604308 -210.015582)
		(width 0.13208)
		(layer "B.Cu")
		(net "BIC_SPI1DQ3")
	)
	(segment
		(start 233.467402 -213.104476)
		(end 233.467402 -212.898228)
		(width 0.13208)
		(layer "B.Cu")
		(net "BIC_SPI1DQ3")
	)
	(segment
		(start 233.067606 -212.704172)
		(end 233.467402 -212.304376)
		(width 0.13208)
		(layer "F.Cu")
		(net "BIC_SPI1DQ2")
	)
	(via
		(at 233.467402 -212.304376)
		(size 0.4572)
		(drill 0.254)
		(layers "F.Cu" "B.Cu")
		(net "BIC_SPI1DQ2")
	)
	(via
		(at 234.166664 -208.81213)
		(size 0.6604)
		(drill 0.3302)
		(layers "F.Cu" "B.Cu")
		(net "BIC_SPI1DQ2")
	)
	(segment
		(start 233.467402 -212.304376)
		(end 233.265218 -212.102192)
		(width 0.13208)
		(layer "B.Cu")
		(net "BIC_SPI1DQ2")
	)
	(segment
		(start 233.642662 -208.288128)
		(end 234.166664 -208.81213)
		(width 0.13208)
		(layer "B.Cu")
		(net "BIC_SPI1DQ2")
	)
	(segment
		(start 233.265218 -212.102192)
		(end 233.265218 -211.130896)
		(width 0.13208)
		(layer "B.Cu")
		(net "BIC_SPI1DQ2")
	)
	(segment
		(start 233.265218 -211.130896)
		(end 234.166664 -210.22945)
		(width 0.13208)
		(layer "B.Cu")
		(net "BIC_SPI1DQ2")
	)
	(segment
		(start 234.166664 -210.22945)
		(end 234.166664 -208.81213)
		(width 0.13208)
		(layer "B.Cu")
		(net "BIC_SPI1DQ2")
	)
	(segment
		(start 233.045762 -207.767428)
		(end 233.566462 -208.288128)
		(width 0.13208)
		(layer "B.Cu")
		(net "BIC_SPI1DQ2")
	)
	(segment
		(start 233.566462 -208.288128)
		(end 233.642662 -208.288128)
		(width 0.13208)
		(layer "B.Cu")
		(net "BIC_SPI1DQ2")
	)
	(via
		(at 255.374902 -226.767898)
		(size 0.6604)
		(drill 0.3302)
		(layers "F.Cu" "B.Cu")
		(net "SPI_PEX2_SDIO1_MUX")
	)
	(segment
		(start 255.374902 -226.767898)
		(end 255.374902 -227.94595)
		(width 0.13208)
		(layer "B.Cu")
		(net "SPI_PEX2_SDIO1_MUX")
	)
	(segment
		(start 252.235716 -226.083876)
		(end 252.919738 -226.767898)
		(width 0.13208)
		(layer "B.Cu")
		(net "SPI_PEX2_SDIO1_MUX")
	)
	(segment
		(start 252.235716 -224.341182)
		(end 252.235716 -226.083876)
		(width 0.13208)
		(layer "B.Cu")
		(net "SPI_PEX2_SDIO1_MUX")
	)
	(segment
		(start 252.919738 -226.767898)
		(end 255.374902 -226.767898)
		(width 0.13208)
		(layer "B.Cu")
		(net "SPI_PEX2_SDIO1_MUX")
	)
	(segment
		(start 241.200686 -203.687426)
		(end 241.200686 -203.005182)
		(width 0.13208)
		(layer "F.Cu")
		(net "BIC_FWSPIDQ3")
	)
	(segment
		(start 232.26776 -215.104218)
		(end 232.667556 -214.704422)
		(width 0.13208)
		(layer "F.Cu")
		(net "BIC_FWSPIDQ3")
	)
	(segment
		(start 242.219734 -203.814426)
		(end 241.327686 -203.814426)
		(width 0.13208)
		(layer "F.Cu")
		(net "BIC_FWSPIDQ3")
	)
	(segment
		(start 243.201698 -202.832462)
		(end 242.219734 -203.814426)
		(width 0.13208)
		(layer "F.Cu")
		(net "BIC_FWSPIDQ3")
	)
	(segment
		(start 241.327686 -203.814426)
		(end 241.200686 -203.687426)
		(width 0.13208)
		(layer "F.Cu")
		(net "BIC_FWSPIDQ3")
	)
	(via
		(at 243.201698 -202.832462)
		(size 0.508)
		(drill 0.254)
		(layers "F.Cu" "B.Cu")
		(net "BIC_FWSPIDQ3")
	)
	(via
		(at 232.667556 -214.704422)
		(size 0.4572)
		(drill 0.254)
		(layers "F.Cu" "B.Cu")
		(net "BIC_FWSPIDQ3")
	)
	(segment
		(start 233.059732 -212.135466)
		(end 233.059732 -213.453472)
		(width 0.15494)
		(layer "In7.Cu")
		(net "BIC_FWSPIDQ3")
	)
	(segment
		(start 240.9698 -206.8068)
		(end 240.7158 -207.0608)
		(width 0.15494)
		(layer "In7.Cu")
		(net "BIC_FWSPIDQ3")
	)
	(segment
		(start 243.201698 -202.832462)
		(end 242.2906 -203.74356)
		(width 0.15494)
		(layer "In7.Cu")
		(net "BIC_FWSPIDQ3")
	)
	(segment
		(start 241.859054 -206.8068)
		(end 240.9698 -206.8068)
		(width 0.15494)
		(layer "In7.Cu")
		(net "BIC_FWSPIDQ3")
	)
	(segment
		(start 233.298492 -211.896706)
		(end 233.059732 -212.135466)
		(width 0.15494)
		(layer "In7.Cu")
		(net "BIC_FWSPIDQ3")
	)
	(segment
		(start 233.059732 -213.453472)
		(end 233.059732 -214.312246)
		(width 0.0889)
		(layer "In7.Cu")
		(net "BIC_FWSPIDQ3")
	)
	(segment
		(start 242.2906 -206.375254)
		(end 241.859054 -206.8068)
		(width 0.15494)
		(layer "In7.Cu")
		(net "BIC_FWSPIDQ3")
	)
	(segment
		(start 240.7158 -207.0608)
		(end 238.148622 -207.0608)
		(width 0.15494)
		(layer "In7.Cu")
		(net "BIC_FWSPIDQ3")
	)
	(segment
		(start 233.059732 -214.312246)
		(end 232.667556 -214.704422)
		(width 0.0889)
		(layer "In7.Cu")
		(net "BIC_FWSPIDQ3")
	)
	(segment
		(start 233.312716 -211.896706)
		(end 233.298492 -211.896706)
		(width 0.15494)
		(layer "In7.Cu")
		(net "BIC_FWSPIDQ3")
	)
	(segment
		(start 238.148622 -207.0608)
		(end 233.312716 -211.896706)
		(width 0.15494)
		(layer "In7.Cu")
		(net "BIC_FWSPIDQ3")
	)
	(segment
		(start 242.2906 -203.74356)
		(end 242.2906 -206.375254)
		(width 0.15494)
		(layer "In7.Cu")
		(net "BIC_FWSPIDQ3")
	)
	(segment
		(start 241.161062 -198.363078)
		(end 241.477546 -198.046594)
		(width 0.13208)
		(layer "F.Cu")
		(net "BIC_FWSPIDQ2")
	)
	(segment
		(start 241.161062 -198.746618)
		(end 241.161062 -198.363078)
		(width 0.13208)
		(layer "F.Cu")
		(net "BIC_FWSPIDQ2")
	)
	(segment
		(start 229.867714 -215.104218)
		(end 230.26751 -214.704422)
		(width 0.13208)
		(layer "F.Cu")
		(net "BIC_FWSPIDQ2")
	)
	(via
		(at 230.26751 -214.704422)
		(size 0.4572)
		(drill 0.254)
		(layers "F.Cu" "B.Cu")
		(net "BIC_FWSPIDQ2")
	)
	(via
		(at 241.477546 -198.046594)
		(size 0.508)
		(drill 0.254)
		(layers "F.Cu" "B.Cu")
		(net "BIC_FWSPIDQ2")
	)
	(segment
		(start 236.190282 -205.120748)
		(end 233.478832 -207.832198)
		(width 0.15494)
		(layer "In7.Cu")
		(net "BIC_FWSPIDQ2")
	)
	(segment
		(start 233.478832 -207.832198)
		(end 231.807004 -207.832198)
		(width 0.15494)
		(layer "In7.Cu")
		(net "BIC_FWSPIDQ2")
	)
	(segment
		(start 229.616 -210.023202)
		(end 229.616 -214.052912)
		(width 0.15494)
		(layer "In7.Cu")
		(net "BIC_FWSPIDQ2")
	)
	(segment
		(start 231.807004 -207.832198)
		(end 229.616 -210.023202)
		(width 0.15494)
		(layer "In7.Cu")
		(net "BIC_FWSPIDQ2")
	)
	(segment
		(start 236.190282 -202.280266)
		(end 236.190282 -205.120748)
		(width 0.15494)
		(layer "In7.Cu")
		(net "BIC_FWSPIDQ2")
	)
	(segment
		(start 229.616 -214.052912)
		(end 230.26751 -214.704422)
		(width 0.15494)
		(layer "In7.Cu")
		(net "BIC_FWSPIDQ2")
	)
	(segment
		(start 240.423954 -198.046594)
		(end 236.190282 -202.280266)
		(width 0.15494)
		(layer "In7.Cu")
		(net "BIC_FWSPIDQ2")
	)
	(segment
		(start 241.477546 -198.046594)
		(end 240.423954 -198.046594)
		(width 0.15494)
		(layer "In7.Cu")
		(net "BIC_FWSPIDQ2")
	)
	(segment
		(start 230.66756 -216.704164)
		(end 231.067356 -216.304368)
		(width 0.13208)
		(layer "F.Cu")
		(net "BIC_FWSPICS1_N")
	)
	(segment
		(start 241.142012 -199.736964)
		(end 240.53038 -199.736964)
		(width 0.13208)
		(layer "F.Cu")
		(net "BIC_FWSPICS1_N")
	)
	(via
		(at 240.53038 -199.736964)
		(size 0.508)
		(drill 0.254)
		(layers "F.Cu" "B.Cu")
		(net "BIC_FWSPICS1_N")
	)
	(via
		(at 231.067356 -216.304368)
		(size 0.4572)
		(drill 0.254)
		(layers "F.Cu" "B.Cu")
		(net "BIC_FWSPICS1_N")
	)
	(segment
		(start 231.692958 -210.13166)
		(end 231.692958 -210.980782)
		(width 0.15494)
		(layer "In7.Cu")
		(net "BIC_FWSPICS1_N")
	)
	(segment
		(start 230.6574 -212.01634)
		(end 230.6574 -212.8774)
		(width 0.15494)
		(layer "In7.Cu")
		(net "BIC_FWSPICS1_N")
	)
	(segment
		(start 236.548422 -205.276196)
		(end 231.692958 -210.13166)
		(width 0.15494)
		(layer "In7.Cu")
		(net "BIC_FWSPICS1_N")
	)
	(segment
		(start 239.105186 -199.875902)
		(end 239.101884 -199.875394)
		(width 0.15494)
		(layer "In7.Cu")
		(net "BIC_FWSPICS1_N")
	)
	(segment
		(start 239.244124 -199.736964)
		(end 239.105186 -199.875902)
		(width 0.15494)
		(layer "In7.Cu")
		(net "BIC_FWSPICS1_N")
	)
	(segment
		(start 230.6574 -215.894412)
		(end 231.067356 -216.304368)
		(width 0.0889)
		(layer "In7.Cu")
		(net "BIC_FWSPICS1_N")
	)
	(segment
		(start 230.6574 -212.8774)
		(end 230.6574 -215.894412)
		(width 0.0889)
		(layer "In7.Cu")
		(net "BIC_FWSPICS1_N")
	)
	(segment
		(start 239.101884 -199.875394)
		(end 236.548422 -202.428856)
		(width 0.15494)
		(layer "In7.Cu")
		(net "BIC_FWSPICS1_N")
	)
	(segment
		(start 231.692958 -210.980782)
		(end 230.6574 -212.01634)
		(width 0.15494)
		(layer "In7.Cu")
		(net "BIC_FWSPICS1_N")
	)
	(segment
		(start 240.53038 -199.736964)
		(end 239.244124 -199.736964)
		(width 0.15494)
		(layer "In7.Cu")
		(net "BIC_FWSPICS1_N")
	)
	(segment
		(start 236.548422 -202.428856)
		(end 236.548422 -205.276196)
		(width 0.15494)
		(layer "In7.Cu")
		(net "BIC_FWSPICS1_N")
	)
	(segment
		(start 115.847114 -263.071864)
		(end 116.7638 -263.071864)
		(width 0.254)
		(layer "F.Cu")
		(net "SH_P0V8_PEX1_VSEN1_L")
	)
	(via
		(at 117.67566 -329.44689)
		(size 0.508)
		(drill 0.254)
		(layers "F.Cu" "B.Cu")
		(net "SH_P0V8_PEX1_VSEN1_L")
	)
	(via
		(at 118.30939 -303.141634)
		(size 0.508)
		(drill 0.254)
		(layers "F.Cu" "B.Cu")
		(net "SH_P0V8_PEX1_VSEN1_L")
	)
	(via
		(at 116.7638 -263.071864)
		(size 0.508)
		(drill 0.254)
		(layers "F.Cu" "B.Cu")
		(net "SH_P0V8_PEX1_VSEN1_L")
	)
	(segment
		(start 117.569234 -328.396092)
		(end 117.318028 -328.647298)
		(width 0.254)
		(layer "B.Cu")
		(net "SH_P0V8_PEX1_VSEN1_L")
	)
	(segment
		(start 133.562598 -328.066654)
		(end 132.992876 -328.066654)
		(width 0.254)
		(layer "B.Cu")
		(net "SH_P0V8_PEX1_VSEN1_L")
	)
	(segment
		(start 117.318028 -329.089258)
		(end 117.67566 -329.44689)
		(width 0.254)
		(layer "B.Cu")
		(net "SH_P0V8_PEX1_VSEN1_L")
	)
	(segment
		(start 117.318028 -328.647298)
		(end 117.318028 -329.089258)
		(width 0.254)
		(layer "B.Cu")
		(net "SH_P0V8_PEX1_VSEN1_L")
	)
	(segment
		(start 132.010912 -329.048618)
		(end 118.976648 -329.048618)
		(width 0.254)
		(layer "B.Cu")
		(net "SH_P0V8_PEX1_VSEN1_L")
	)
	(segment
		(start 132.992876 -328.066654)
		(end 132.010912 -329.048618)
		(width 0.254)
		(layer "B.Cu")
		(net "SH_P0V8_PEX1_VSEN1_L")
	)
	(segment
		(start 118.976648 -329.048618)
		(end 118.324122 -328.396092)
		(width 0.254)
		(layer "B.Cu")
		(net "SH_P0V8_PEX1_VSEN1_L")
	)
	(segment
		(start 133.892544 -328.422)
		(end 133.562598 -328.066654)
		(width 0.254)
		(layer "B.Cu")
		(net "SH_P0V8_PEX1_VSEN1_L")
	)
	(segment
		(start 118.947438 -303.141634)
		(end 118.30939 -303.141634)
		(width 0.254)
		(layer "B.Cu")
		(net "SH_P0V8_PEX1_VSEN1_L")
	)
	(segment
		(start 118.324122 -328.396092)
		(end 117.569234 -328.396092)
		(width 0.254)
		(layer "B.Cu")
		(net "SH_P0V8_PEX1_VSEN1_L")
	)
	(segment
		(start 119.144288 -303.459134)
		(end 119.5451 -303.859946)
		(width 0.254)
		(layer "In5.Cu")
		(net "SH_P0V8_PEX1_VSEN1_L")
	)
	(segment
		(start 119.5451 -303.859946)
		(end 119.5451 -306.04079)
		(width 0.254)
		(layer "In5.Cu")
		(net "SH_P0V8_PEX1_VSEN1_L")
	)
	(segment
		(start 118.578884 -307.007006)
		(end 118.578884 -327.24217)
		(width 0.254)
		(layer "In5.Cu")
		(net "SH_P0V8_PEX1_VSEN1_L")
	)
	(segment
		(start 118.578884 -327.24217)
		(end 117.341904 -328.47915)
		(width 0.254)
		(layer "In5.Cu")
		(net "SH_P0V8_PEX1_VSEN1_L")
	)
	(segment
		(start 119.5451 -306.04079)
		(end 118.578884 -307.007006)
		(width 0.254)
		(layer "In5.Cu")
		(net "SH_P0V8_PEX1_VSEN1_L")
	)
	(segment
		(start 117.341904 -328.47915)
		(end 117.341904 -329.113134)
		(width 0.254)
		(layer "In5.Cu")
		(net "SH_P0V8_PEX1_VSEN1_L")
	)
	(segment
		(start 117.341904 -329.113134)
		(end 117.67566 -329.44689)
		(width 0.254)
		(layer "In5.Cu")
		(net "SH_P0V8_PEX1_VSEN1_L")
	)
	(segment
		(start 118.62689 -303.459134)
		(end 119.144288 -303.459134)
		(width 0.254)
		(layer "In5.Cu")
		(net "SH_P0V8_PEX1_VSEN1_L")
	)
	(segment
		(start 118.30939 -303.141634)
		(end 118.62689 -303.459134)
		(width 0.254)
		(layer "In5.Cu")
		(net "SH_P0V8_PEX1_VSEN1_L")
	)
	(segment
		(start 135.066786 -303.459134)
		(end 118.62689 -303.459134)
		(width 0.254)
		(layer "In9.Cu")
		(net "SH_P0V8_PEX1_VSEN1_L")
	)
	(segment
		(start 131.086606 -264.44702)
		(end 140.542772 -273.903186)
		(width 0.254)
		(layer "In9.Cu")
		(net "SH_P0V8_PEX1_VSEN1_L")
	)
	(segment
		(start 118.152672 -262.824214)
		(end 118.792498 -262.184388)
		(width 0.254)
		(layer "In9.Cu")
		(net "SH_P0V8_PEX1_VSEN1_L")
	)
	(segment
		(start 136.261856 -302.264064)
		(end 135.066786 -303.459134)
		(width 0.254)
		(layer "In9.Cu")
		(net "SH_P0V8_PEX1_VSEN1_L")
	)
	(segment
		(start 118.62689 -303.459134)
		(end 118.30939 -303.141634)
		(width 0.254)
		(layer "In9.Cu")
		(net "SH_P0V8_PEX1_VSEN1_L")
	)
	(segment
		(start 116.7638 -263.071864)
		(end 117.01145 -262.824214)
		(width 0.254)
		(layer "In9.Cu")
		(net "SH_P0V8_PEX1_VSEN1_L")
	)
	(segment
		(start 136.261856 -282.125928)
		(end 136.261856 -302.264064)
		(width 0.254)
		(layer "In9.Cu")
		(net "SH_P0V8_PEX1_VSEN1_L")
	)
	(segment
		(start 123.096274 -260.895084)
		(end 126.64821 -264.44702)
		(width 0.254)
		(layer "In9.Cu")
		(net "SH_P0V8_PEX1_VSEN1_L")
	)
	(segment
		(start 140.542772 -273.903186)
		(end 140.542772 -277.845012)
		(width 0.254)
		(layer "In9.Cu")
		(net "SH_P0V8_PEX1_VSEN1_L")
	)
	(segment
		(start 119.191532 -260.895084)
		(end 123.096274 -260.895084)
		(width 0.254)
		(layer "In9.Cu")
		(net "SH_P0V8_PEX1_VSEN1_L")
	)
	(segment
		(start 126.64821 -264.44702)
		(end 131.086606 -264.44702)
		(width 0.254)
		(layer "In9.Cu")
		(net "SH_P0V8_PEX1_VSEN1_L")
	)
	(segment
		(start 118.792498 -261.294118)
		(end 119.191532 -260.895084)
		(width 0.254)
		(layer "In9.Cu")
		(net "SH_P0V8_PEX1_VSEN1_L")
	)
	(segment
		(start 117.01145 -262.824214)
		(end 118.152672 -262.824214)
		(width 0.254)
		(layer "In9.Cu")
		(net "SH_P0V8_PEX1_VSEN1_L")
	)
	(segment
		(start 118.792498 -262.184388)
		(end 118.792498 -261.294118)
		(width 0.254)
		(layer "In9.Cu")
		(net "SH_P0V8_PEX1_VSEN1_L")
	)
	(segment
		(start 140.542772 -277.845012)
		(end 136.261856 -282.125928)
		(width 0.254)
		(layer "In9.Cu")
		(net "SH_P0V8_PEX1_VSEN1_L")
	)
	(segment
		(start 335.788 -229.235)
		(end 335.153 -229.87)
		(width 0.13208)
		(layer "F.Cu")
		(net "PRSNT_GPU_ISO_R1_N")
	)
	(segment
		(start 335.788 -228.727)
		(end 335.788 -229.235)
		(width 0.13208)
		(layer "F.Cu")
		(net "PRSNT_GPU_ISO_R1_N")
	)
	(segment
		(start 335.693766 -227.186998)
		(end 336.090006 -227.583238)
		(width 0.13208)
		(layer "F.Cu")
		(net "PRSNT_GPU_ISO_R1_N")
	)
	(segment
		(start 336.090006 -227.583238)
		(end 336.090006 -228.424994)
		(width 0.13208)
		(layer "F.Cu")
		(net "PRSNT_GPU_ISO_R1_N")
	)
	(segment
		(start 330.708 -233.66095)
		(end 330.708 -232.918)
		(width 0.13208)
		(layer "F.Cu")
		(net "PRSNT_GPU_ISO_R1_N")
	)
	(segment
		(start 336.090006 -228.424994)
		(end 335.788 -228.727)
		(width 0.13208)
		(layer "F.Cu")
		(net "PRSNT_GPU_ISO_R1_N")
	)
	(via
		(at 330.708 -232.918)
		(size 0.508)
		(drill 0.254)
		(layers "F.Cu" "B.Cu")
		(net "PRSNT_GPU_ISO_R1_N")
	)
	(via
		(at 335.153 -229.87)
		(size 0.508)
		(drill 0.254)
		(layers "F.Cu" "B.Cu")
		(net "PRSNT_GPU_ISO_R1_N")
	)
	(segment
		(start 332.624684 -231.001316)
		(end 330.708 -232.918)
		(width 0.15494)
		(layer "In9.Cu")
		(net "PRSNT_GPU_ISO_R1_N")
	)
	(segment
		(start 335.153 -229.87)
		(end 334.021684 -231.001316)
		(width 0.15494)
		(layer "In9.Cu")
		(net "PRSNT_GPU_ISO_R1_N")
	)
	(segment
		(start 334.021684 -231.001316)
		(end 332.624684 -231.001316)
		(width 0.15494)
		(layer "In9.Cu")
		(net "PRSNT_GPU_ISO_R1_N")
	)
	(segment
		(start 123.01855 -263.18337)
		(end 122.48134 -262.64616)
		(width 0.254)
		(layer "F.Cu")
		(net "SH_P0V8_PEX0_RGND0")
	)
	(segment
		(start 122.48134 -262.04672)
		(end 122.48134 -261.64667)
		(width 0.2032)
		(layer "F.Cu")
		(net "SH_P0V8_PEX0_RGND0")
	)
	(segment
		(start 122.48134 -262.64616)
		(end 122.48134 -262.04672)
		(width 0.254)
		(layer "F.Cu")
		(net "SH_P0V8_PEX0_RGND0")
	)
	(segment
		(start 123.350782 -263.18337)
		(end 123.01855 -263.18337)
		(width 0.254)
		(layer "F.Cu")
		(net "SH_P0V8_PEX0_RGND0")
	)
	(segment
		(start 122.48134 -261.64667)
		(end 122.175778 -261.341108)
		(width 0.2032)
		(layer "F.Cu")
		(net "SH_P0V8_PEX0_RGND0")
	)
	(segment
		(start 122.175778 -261.341108)
		(end 122.175778 -260.795008)
		(width 0.2032)
		(layer "F.Cu")
		(net "SH_P0V8_PEX0_RGND0")
	)
	(via
		(at 102.698296 -324.075806)
		(size 0.508)
		(drill 0.254)
		(layers "F.Cu" "B.Cu")
		(net "SH_P0V8_PEX0_RGND0")
	)
	(via
		(at 123.350782 -263.18337)
		(size 0.508)
		(drill 0.254)
		(layers "F.Cu" "B.Cu")
		(net "SH_P0V8_PEX0_RGND0")
	)
	(via
		(at 117.16639 -304.157634)
		(size 0.508)
		(drill 0.254)
		(layers "F.Cu" "B.Cu")
		(net "SH_P0V8_PEX0_RGND0")
	)
	(segment
		(start 102.698296 -324.075806)
		(end 102.42169 -323.7992)
		(width 0.254)
		(layer "B.Cu")
		(net "SH_P0V8_PEX0_RGND0")
	)
	(segment
		(start 116.528342 -304.157634)
		(end 117.16639 -304.157634)
		(width 0.254)
		(layer "B.Cu")
		(net "SH_P0V8_PEX0_RGND0")
	)
	(segment
		(start 102.42169 -323.7992)
		(end 101.654102 -323.7992)
		(width 0.254)
		(layer "B.Cu")
		(net "SH_P0V8_PEX0_RGND0")
	)
	(segment
		(start 101.654102 -323.7992)
		(end 101.30028 -324.178422)
		(width 0.254)
		(layer "B.Cu")
		(net "SH_P0V8_PEX0_RGND0")
	)
	(segment
		(start 116.48948 -303.840134)
		(end 116.84889 -303.840134)
		(width 0.254)
		(layer "In5.Cu")
		(net "SH_P0V8_PEX0_RGND0")
	)
	(segment
		(start 115.639088 -323.751194)
		(end 117.083586 -322.306696)
		(width 0.254)
		(layer "In5.Cu")
		(net "SH_P0V8_PEX0_RGND0")
	)
	(segment
		(start 117.083586 -322.306696)
		(end 117.083586 -306.906676)
		(width 0.254)
		(layer "In5.Cu")
		(net "SH_P0V8_PEX0_RGND0")
	)
	(segment
		(start 102.698296 -324.075806)
		(end 103.022908 -323.751194)
		(width 0.254)
		(layer "In5.Cu")
		(net "SH_P0V8_PEX0_RGND0")
	)
	(segment
		(start 116.23548 -306.05857)
		(end 116.23548 -304.094134)
		(width 0.254)
		(layer "In5.Cu")
		(net "SH_P0V8_PEX0_RGND0")
	)
	(segment
		(start 116.84889 -303.840134)
		(end 117.16639 -304.157634)
		(width 0.254)
		(layer "In5.Cu")
		(net "SH_P0V8_PEX0_RGND0")
	)
	(segment
		(start 103.022908 -323.751194)
		(end 115.639088 -323.751194)
		(width 0.254)
		(layer "In5.Cu")
		(net "SH_P0V8_PEX0_RGND0")
	)
	(segment
		(start 117.083586 -306.906676)
		(end 116.23548 -306.05857)
		(width 0.254)
		(layer "In5.Cu")
		(net "SH_P0V8_PEX0_RGND0")
	)
	(segment
		(start 116.23548 -304.094134)
		(end 116.48948 -303.840134)
		(width 0.254)
		(layer "In5.Cu")
		(net "SH_P0V8_PEX0_RGND0")
	)
	(segment
		(start 107.089448 -268.269974)
		(end 108.66882 -266.690602)
		(width 0.254)
		(layer "In9.Cu")
		(net "SH_P0V8_PEX0_RGND0")
	)
	(segment
		(start 121.173494 -266.690602)
		(end 122.01779 -265.846306)
		(width 0.254)
		(layer "In9.Cu")
		(net "SH_P0V8_PEX0_RGND0")
	)
	(segment
		(start 100.65639 -279.698704)
		(end 103.829612 -279.698704)
		(width 0.254)
		(layer "In9.Cu")
		(net "SH_P0V8_PEX0_RGND0")
	)
	(segment
		(start 122.714766 -263.48182)
		(end 123.063508 -263.477502)
		(width 0.254)
		(layer "In9.Cu")
		(net "SH_P0V8_PEX0_RGND0")
	)
	(segment
		(start 117.16639 -304.157634)
		(end 116.84889 -303.840134)
		(width 0.254)
		(layer "In9.Cu")
		(net "SH_P0V8_PEX0_RGND0")
	)
	(segment
		(start 116.84889 -303.840134)
		(end 100.981256 -303.840134)
		(width 0.254)
		(layer "In9.Cu")
		(net "SH_P0V8_PEX0_RGND0")
	)
	(segment
		(start 100.293424 -303.152302)
		(end 100.293424 -297.055032)
		(width 0.254)
		(layer "In9.Cu")
		(net "SH_P0V8_PEX0_RGND0")
	)
	(segment
		(start 95.526098 -284.828996)
		(end 100.65639 -279.698704)
		(width 0.254)
		(layer "In9.Cu")
		(net "SH_P0V8_PEX0_RGND0")
	)
	(segment
		(start 107.089448 -276.438868)
		(end 107.089448 -268.269974)
		(width 0.254)
		(layer "In9.Cu")
		(net "SH_P0V8_PEX0_RGND0")
	)
	(segment
		(start 103.829612 -279.698704)
		(end 107.089448 -276.438868)
		(width 0.254)
		(layer "In9.Cu")
		(net "SH_P0V8_PEX0_RGND0")
	)
	(segment
		(start 122.01779 -263.925304)
		(end 122.461274 -263.48182)
		(width 0.254)
		(layer "In9.Cu")
		(net "SH_P0V8_PEX0_RGND0")
	)
	(segment
		(start 94.655132 -286.931608)
		(end 95.526098 -284.828996)
		(width 0.254)
		(layer "In9.Cu")
		(net "SH_P0V8_PEX0_RGND0")
	)
	(segment
		(start 94.655132 -291.41674)
		(end 94.655132 -286.931608)
		(width 0.254)
		(layer "In9.Cu")
		(net "SH_P0V8_PEX0_RGND0")
	)
	(segment
		(start 123.063508 -263.477502)
		(end 123.350782 -263.18337)
		(width 0.254)
		(layer "In9.Cu")
		(net "SH_P0V8_PEX0_RGND0")
	)
	(segment
		(start 108.66882 -266.690602)
		(end 121.173494 -266.690602)
		(width 0.254)
		(layer "In9.Cu")
		(net "SH_P0V8_PEX0_RGND0")
	)
	(segment
		(start 100.293424 -297.055032)
		(end 94.655132 -291.41674)
		(width 0.254)
		(layer "In9.Cu")
		(net "SH_P0V8_PEX0_RGND0")
	)
	(segment
		(start 100.981256 -303.840134)
		(end 100.293424 -303.152302)
		(width 0.254)
		(layer "In9.Cu")
		(net "SH_P0V8_PEX0_RGND0")
	)
	(segment
		(start 122.461274 -263.48182)
		(end 122.714766 -263.48182)
		(width 0.254)
		(layer "In9.Cu")
		(net "SH_P0V8_PEX0_RGND0")
	)
	(segment
		(start 122.01779 -265.846306)
		(end 122.01779 -263.925304)
		(width 0.254)
		(layer "In9.Cu")
		(net "SH_P0V8_PEX0_RGND0")
	)
	(segment
		(start 395.59992 -289.249866)
		(end 395.12494 -288.774886)
		(width 0.254)
		(layer "F.Cu")
		(net "TP_PEX3_VDDQ_EFUSE")
	)
	(via
		(at 395.12494 -288.774886)
		(size 0.4064)
		(drill 0.2032)
		(layers "F.Cu" "B.Cu")
		(net "TP_PEX3_VDDQ_EFUSE")
	)
	(via
		(at 395.590776 -288.30016)
		(size 0.6604)
		(drill 0.3302)
		(layers "F.Cu" "B.Cu")
		(net "TP_PEX3_VDDQ_EFUSE")
	)
	(segment
		(start 395.590776 -288.30905)
		(end 395.12494 -288.774886)
		(width 0.13208)
		(layer "B.Cu")
		(net "TP_PEX3_VDDQ_EFUSE")
	)
	(segment
		(start 395.590776 -288.30016)
		(end 395.590776 -288.30905)
		(width 0.13208)
		(layer "B.Cu")
		(net "TP_PEX3_VDDQ_EFUSE")
	)
	(segment
		(start 279.499822 -289.249866)
		(end 279.024842 -288.774886)
		(width 0.254)
		(layer "F.Cu")
		(net "TP_PEX2_VDDQ_EFUSE")
	)
	(via
		(at 279.024842 -288.774886)
		(size 0.4064)
		(drill 0.2032)
		(layers "F.Cu" "B.Cu")
		(net "TP_PEX2_VDDQ_EFUSE")
	)
	(via
		(at 279.490678 -288.30016)
		(size 0.6604)
		(drill 0.3302)
		(layers "F.Cu" "B.Cu")
		(net "TP_PEX2_VDDQ_EFUSE")
	)
	(segment
		(start 279.490678 -288.30905)
		(end 279.024842 -288.774886)
		(width 0.13208)
		(layer "B.Cu")
		(net "TP_PEX2_VDDQ_EFUSE")
	)
	(segment
		(start 279.490678 -288.30016)
		(end 279.490678 -288.30905)
		(width 0.13208)
		(layer "B.Cu")
		(net "TP_PEX2_VDDQ_EFUSE")
	)
	(segment
		(start 163.399978 -289.249866)
		(end 162.924998 -288.774886)
		(width 0.254)
		(layer "F.Cu")
		(net "TP_PEX1_VDDQ_EFUSE")
	)
	(via
		(at 162.924998 -288.774886)
		(size 0.4064)
		(drill 0.2032)
		(layers "F.Cu" "B.Cu")
		(net "TP_PEX1_VDDQ_EFUSE")
	)
	(via
		(at 163.390834 -288.30016)
		(size 0.6604)
		(drill 0.3302)
		(layers "F.Cu" "B.Cu")
		(net "TP_PEX1_VDDQ_EFUSE")
	)
	(segment
		(start 163.390834 -288.30016)
		(end 163.390834 -288.30905)
		(width 0.13208)
		(layer "B.Cu")
		(net "TP_PEX1_VDDQ_EFUSE")
	)
	(segment
		(start 163.390834 -288.30905)
		(end 162.924998 -288.774886)
		(width 0.13208)
		(layer "B.Cu")
		(net "TP_PEX1_VDDQ_EFUSE")
	)
	(segment
		(start 47.29988 -289.249866)
		(end 46.8249 -288.774886)
		(width 0.254)
		(layer "F.Cu")
		(net "TP_PEX0_VDDQ_EFUSE")
	)
	(via
		(at 46.8249 -288.774886)
		(size 0.4064)
		(drill 0.2032)
		(layers "F.Cu" "B.Cu")
		(net "TP_PEX0_VDDQ_EFUSE")
	)
	(via
		(at 47.290736 -288.30016)
		(size 0.6604)
		(drill 0.3302)
		(layers "F.Cu" "B.Cu")
		(net "TP_PEX0_VDDQ_EFUSE")
	)
	(segment
		(start 47.290736 -288.30905)
		(end 46.8249 -288.774886)
		(width 0.13208)
		(layer "B.Cu")
		(net "TP_PEX0_VDDQ_EFUSE")
	)
	(segment
		(start 47.290736 -288.30016)
		(end 47.290736 -288.30905)
		(width 0.13208)
		(layer "B.Cu")
		(net "TP_PEX0_VDDQ_EFUSE")
	)
	(segment
		(start 123.362212 -264.12952)
		(end 123.921012 -263.57072)
		(width 0.254)
		(layer "F.Cu")
		(net "SH_P0V8_PEX0_VSEN0_L")
	)
	(segment
		(start 123.921012 -263.57072)
		(end 124.41809 -263.57072)
		(width 0.254)
		(layer "F.Cu")
		(net "SH_P0V8_PEX0_VSEN0_L")
	)
	(via
		(at 123.362212 -264.12952)
		(size 0.508)
		(drill 0.254)
		(layers "F.Cu" "B.Cu")
		(net "SH_P0V8_PEX0_VSEN0_L")
	)
	(via
		(at 117.16639 -303.141634)
		(size 0.508)
		(drill 0.254)
		(layers "F.Cu" "B.Cu")
		(net "SH_P0V8_PEX0_VSEN0_L")
	)
	(via
		(at 102.698296 -323.059806)
		(size 0.508)
		(drill 0.254)
		(layers "F.Cu" "B.Cu")
		(net "SH_P0V8_PEX0_VSEN0_L")
	)
	(segment
		(start 101.581458 -323.4182)
		(end 101.30028 -323.111622)
		(width 0.254)
		(layer "B.Cu")
		(net "SH_P0V8_PEX0_VSEN0_L")
	)
	(segment
		(start 102.698296 -323.059806)
		(end 102.339902 -323.4182)
		(width 0.254)
		(layer "B.Cu")
		(net "SH_P0V8_PEX0_VSEN0_L")
	)
	(segment
		(start 116.528342 -303.141634)
		(end 117.16639 -303.141634)
		(width 0.254)
		(layer "B.Cu")
		(net "SH_P0V8_PEX0_VSEN0_L")
	)
	(segment
		(start 102.339902 -323.4182)
		(end 101.581458 -323.4182)
		(width 0.254)
		(layer "B.Cu")
		(net "SH_P0V8_PEX0_VSEN0_L")
	)
	(segment
		(start 116.702586 -307.064664)
		(end 115.85448 -306.216558)
		(width 0.254)
		(layer "In5.Cu")
		(net "SH_P0V8_PEX0_VSEN0_L")
	)
	(segment
		(start 116.331492 -303.459134)
		(end 116.84889 -303.459134)
		(width 0.254)
		(layer "In5.Cu")
		(net "SH_P0V8_PEX0_VSEN0_L")
	)
	(segment
		(start 116.702586 -322.148708)
		(end 116.702586 -307.064664)
		(width 0.254)
		(layer "In5.Cu")
		(net "SH_P0V8_PEX0_VSEN0_L")
	)
	(segment
		(start 115.4811 -323.370194)
		(end 116.702586 -322.148708)
		(width 0.254)
		(layer "In5.Cu")
		(net "SH_P0V8_PEX0_VSEN0_L")
	)
	(segment
		(start 115.85448 -303.936146)
		(end 116.331492 -303.459134)
		(width 0.254)
		(layer "In5.Cu")
		(net "SH_P0V8_PEX0_VSEN0_L")
	)
	(segment
		(start 102.698296 -323.059806)
		(end 103.008684 -323.370194)
		(width 0.254)
		(layer "In5.Cu")
		(net "SH_P0V8_PEX0_VSEN0_L")
	)
	(segment
		(start 116.84889 -303.459134)
		(end 117.16639 -303.141634)
		(width 0.254)
		(layer "In5.Cu")
		(net "SH_P0V8_PEX0_VSEN0_L")
	)
	(segment
		(start 115.85448 -306.216558)
		(end 115.85448 -303.936146)
		(width 0.254)
		(layer "In5.Cu")
		(net "SH_P0V8_PEX0_VSEN0_L")
	)
	(segment
		(start 103.008684 -323.370194)
		(end 115.4811 -323.370194)
		(width 0.254)
		(layer "In5.Cu")
		(net "SH_P0V8_PEX0_VSEN0_L")
	)
	(segment
		(start 122.619262 -263.86282)
		(end 122.717306 -263.86282)
		(width 0.254)
		(layer "In9.Cu")
		(net "SH_P0V8_PEX0_VSEN0_L")
	)
	(segment
		(start 100.674424 -302.994314)
		(end 100.674424 -296.897044)
		(width 0.254)
		(layer "In9.Cu")
		(net "SH_P0V8_PEX0_VSEN0_L")
	)
	(segment
		(start 116.84889 -303.459134)
		(end 101.139244 -303.459134)
		(width 0.254)
		(layer "In9.Cu")
		(net "SH_P0V8_PEX0_VSEN0_L")
	)
	(segment
		(start 123.084082 -263.858502)
		(end 123.362212 -264.12952)
		(width 0.254)
		(layer "In9.Cu")
		(net "SH_P0V8_PEX0_VSEN0_L")
	)
	(segment
		(start 122.717306 -263.86282)
		(end 123.084082 -263.858502)
		(width 0.254)
		(layer "In9.Cu")
		(net "SH_P0V8_PEX0_VSEN0_L")
	)
	(segment
		(start 100.814378 -280.079704)
		(end 103.9876 -280.079704)
		(width 0.254)
		(layer "In9.Cu")
		(net "SH_P0V8_PEX0_VSEN0_L")
	)
	(segment
		(start 108.826808 -267.071602)
		(end 121.331482 -267.071602)
		(width 0.254)
		(layer "In9.Cu")
		(net "SH_P0V8_PEX0_VSEN0_L")
	)
	(segment
		(start 107.470448 -276.596856)
		(end 107.470448 -268.427962)
		(width 0.254)
		(layer "In9.Cu")
		(net "SH_P0V8_PEX0_VSEN0_L")
	)
	(segment
		(start 95.036132 -287.007554)
		(end 95.849186 -285.044896)
		(width 0.254)
		(layer "In9.Cu")
		(net "SH_P0V8_PEX0_VSEN0_L")
	)
	(segment
		(start 101.139244 -303.459134)
		(end 100.674424 -302.994314)
		(width 0.254)
		(layer "In9.Cu")
		(net "SH_P0V8_PEX0_VSEN0_L")
	)
	(segment
		(start 107.470448 -268.427962)
		(end 108.826808 -267.071602)
		(width 0.254)
		(layer "In9.Cu")
		(net "SH_P0V8_PEX0_VSEN0_L")
	)
	(segment
		(start 122.39879 -264.083292)
		(end 122.619262 -263.86282)
		(width 0.254)
		(layer "In9.Cu")
		(net "SH_P0V8_PEX0_VSEN0_L")
	)
	(segment
		(start 103.9876 -280.079704)
		(end 107.470448 -276.596856)
		(width 0.254)
		(layer "In9.Cu")
		(net "SH_P0V8_PEX0_VSEN0_L")
	)
	(segment
		(start 100.674424 -296.897044)
		(end 95.036132 -291.258752)
		(width 0.254)
		(layer "In9.Cu")
		(net "SH_P0V8_PEX0_VSEN0_L")
	)
	(segment
		(start 121.331482 -267.071602)
		(end 122.39879 -266.004294)
		(width 0.254)
		(layer "In9.Cu")
		(net "SH_P0V8_PEX0_VSEN0_L")
	)
	(segment
		(start 122.39879 -266.004294)
		(end 122.39879 -264.083292)
		(width 0.254)
		(layer "In9.Cu")
		(net "SH_P0V8_PEX0_VSEN0_L")
	)
	(segment
		(start 117.16639 -303.141634)
		(end 116.84889 -303.459134)
		(width 0.254)
		(layer "In9.Cu")
		(net "SH_P0V8_PEX0_VSEN0_L")
	)
	(segment
		(start 95.036132 -291.258752)
		(end 95.036132 -287.007554)
		(width 0.254)
		(layer "In9.Cu")
		(net "SH_P0V8_PEX0_VSEN0_L")
	)
	(segment
		(start 95.849186 -285.044896)
		(end 100.814378 -280.079704)
		(width 0.254)
		(layer "In9.Cu")
		(net "SH_P0V8_PEX0_VSEN0_L")
	)
	(segment
		(start 372.882922 -223.59493)
		(end 375.077482 -223.59493)
		(width 0.13208)
		(layer "F.Cu")
		(net "SPI_PEX3_RST_R_N")
	)
	(segment
		(start 375.077482 -223.59493)
		(end 376.47753 -224.994978)
		(width 0.13208)
		(layer "F.Cu")
		(net "SPI_PEX3_RST_R_N")
	)
	(via
		(at 376.47753 -224.994978)
		(size 0.508)
		(drill 0.254)
		(layers "F.Cu" "B.Cu")
		(net "SPI_PEX3_RST_R_N")
	)
	(segment
		(start 376.97537 -225.492818)
		(end 376.47753 -224.994978)
		(width 0.13208)
		(layer "B.Cu")
		(net "SPI_PEX3_RST_R_N")
	)
	(segment
		(start 377.725178 -225.492818)
		(end 377.725178 -226.431094)
		(width 0.13208)
		(layer "B.Cu")
		(net "SPI_PEX3_RST_R_N")
	)
	(segment
		(start 377.725178 -226.431094)
		(end 377.764294 -226.47021)
		(width 0.13208)
		(layer "B.Cu")
		(net "SPI_PEX3_RST_R_N")
	)
	(segment
		(start 377.725178 -225.492818)
		(end 376.97537 -225.492818)
		(width 0.13208)
		(layer "B.Cu")
		(net "SPI_PEX3_RST_R_N")
	)
	(segment
		(start 377.725178 -225.492818)
		(end 378.741178 -225.492818)
		(width 0.13208)
		(layer "B.Cu")
		(net "SPI_PEX3_RST_R_N")
	)
	(segment
		(start 256.859786 -223.59493)
		(end 257.989832 -223.59493)
		(width 0.13208)
		(layer "F.Cu")
		(net "SPI_PEX2_RST_R_N")
	)
	(segment
		(start 257.989832 -223.59493)
		(end 258.930902 -224.536)
		(width 0.13208)
		(layer "F.Cu")
		(net "SPI_PEX2_RST_R_N")
	)
	(segment
		(start 256.859786 -223.59493)
		(end 256.699766 -223.59493)
		(width 0.13208)
		(layer "F.Cu")
		(net "SPI_PEX2_RST_R_N")
	)
	(segment
		(start 258.930902 -224.536)
		(end 260.327902 -224.536)
		(width 0.13208)
		(layer "F.Cu")
		(net "SPI_PEX2_RST_R_N")
	)
	(via
		(at 260.327902 -224.536)
		(size 0.508)
		(drill 0.254)
		(layers "F.Cu" "B.Cu")
		(net "SPI_PEX2_RST_R_N")
	)
	(segment
		(start 261.504176 -226.78263)
		(end 261.504176 -225.76663)
		(width 0.13208)
		(layer "B.Cu")
		(net "SPI_PEX2_RST_R_N")
	)
	(segment
		(start 261.504176 -224.75063)
		(end 261.289546 -224.536)
		(width 0.13208)
		(layer "B.Cu")
		(net "SPI_PEX2_RST_R_N")
	)
	(segment
		(start 261.289546 -224.536)
		(end 260.327902 -224.536)
		(width 0.13208)
		(layer "B.Cu")
		(net "SPI_PEX2_RST_R_N")
	)
	(segment
		(start 261.504176 -225.76663)
		(end 261.504176 -224.75063)
		(width 0.13208)
		(layer "B.Cu")
		(net "SPI_PEX2_RST_R_N")
	)
	(segment
		(start 140.68298 -223.59493)
		(end 141.889988 -223.59493)
		(width 0.13208)
		(layer "F.Cu")
		(net "SPI_PEX1_RST_R_N")
	)
	(segment
		(start 142.831058 -224.536)
		(end 144.228058 -224.536)
		(width 0.13208)
		(layer "F.Cu")
		(net "SPI_PEX1_RST_R_N")
	)
	(segment
		(start 141.889988 -223.59493)
		(end 142.831058 -224.536)
		(width 0.13208)
		(layer "F.Cu")
		(net "SPI_PEX1_RST_R_N")
	)
	(via
		(at 144.228058 -224.536)
		(size 0.508)
		(drill 0.254)
		(layers "F.Cu" "B.Cu")
		(net "SPI_PEX1_RST_R_N")
	)
	(segment
		(start 145.404332 -225.76663)
		(end 145.404332 -226.78263)
		(width 0.13208)
		(layer "B.Cu")
		(net "SPI_PEX1_RST_R_N")
	)
	(segment
		(start 145.189702 -224.536)
		(end 145.404332 -224.75063)
		(width 0.13208)
		(layer "B.Cu")
		(net "SPI_PEX1_RST_R_N")
	)
	(segment
		(start 145.404332 -224.75063)
		(end 145.404332 -225.76663)
		(width 0.13208)
		(layer "B.Cu")
		(net "SPI_PEX1_RST_R_N")
	)
	(segment
		(start 144.228058 -224.536)
		(end 145.189702 -224.536)
		(width 0.13208)
		(layer "B.Cu")
		(net "SPI_PEX1_RST_R_N")
	)
	(segment
		(start 104.003094 -396.788386)
		(end 104.003094 -397.112236)
		(width 0.13208)
		(layer "F.Cu")
		(net "RST_BIC_USB_HUB_R1_N")
	)
	(segment
		(start 106.035094 -397.112236)
		(end 107.051094 -397.112236)
		(width 0.13208)
		(layer "F.Cu")
		(net "RST_BIC_USB_HUB_R1_N")
	)
	(segment
		(start 103.876856 -396.085568)
		(end 104.291384 -396.500096)
		(width 0.13208)
		(layer "F.Cu")
		(net "RST_BIC_USB_HUB_R1_N")
	)
	(segment
		(start 103.876856 -394.566902)
		(end 103.876856 -396.085568)
		(width 0.13208)
		(layer "F.Cu")
		(net "RST_BIC_USB_HUB_R1_N")
	)
	(segment
		(start 104.291384 -396.500096)
		(end 104.003094 -396.788386)
		(width 0.13208)
		(layer "F.Cu")
		(net "RST_BIC_USB_HUB_R1_N")
	)
	(segment
		(start 105.019094 -397.112236)
		(end 106.035094 -397.112236)
		(width 0.13208)
		(layer "F.Cu")
		(net "RST_BIC_USB_HUB_R1_N")
	)
	(segment
		(start 104.003094 -397.112236)
		(end 105.019094 -397.112236)
		(width 0.13208)
		(layer "F.Cu")
		(net "RST_BIC_USB_HUB_R1_N")
	)
	(via
		(at 104.291384 -396.500096)
		(size 0.508)
		(drill 0.254)
		(layers "F.Cu" "B.Cu")
		(net "RST_BIC_USB_HUB_R1_N")
	)
	(segment
		(start 116.7638 -261.424928)
		(end 117.117114 -261.071614)
		(width 0.254)
		(layer "F.Cu")
		(net "SH_P0V8_PEX1_RGND1")
	)
	(segment
		(start 117.640354 -261.071614)
		(end 117.818662 -260.893306)
		(width 0.1778)
		(layer "F.Cu")
		(net "SH_P0V8_PEX1_RGND1")
	)
	(segment
		(start 117.818662 -260.893306)
		(end 117.818662 -260.478016)
		(width 0.1778)
		(layer "F.Cu")
		(net "SH_P0V8_PEX1_RGND1")
	)
	(segment
		(start 116.7638 -262.195564)
		(end 116.7638 -261.424928)
		(width 0.254)
		(layer "F.Cu")
		(net "SH_P0V8_PEX1_RGND1")
	)
	(segment
		(start 117.117114 -261.071614)
		(end 117.640354 -261.071614)
		(width 0.1778)
		(layer "F.Cu")
		(net "SH_P0V8_PEX1_RGND1")
	)
	(segment
		(start 117.818662 -260.478016)
		(end 118.101618 -260.19506)
		(width 0.1778)
		(layer "F.Cu")
		(net "SH_P0V8_PEX1_RGND1")
	)
	(segment
		(start 118.101618 -260.19506)
		(end 118.375684 -260.19506)
		(width 0.1778)
		(layer "F.Cu")
		(net "SH_P0V8_PEX1_RGND1")
	)
	(via
		(at 118.30939 -304.157634)
		(size 0.508)
		(drill 0.254)
		(layers "F.Cu" "B.Cu")
		(net "SH_P0V8_PEX1_RGND1")
	)
	(via
		(at 116.7638 -262.195564)
		(size 0.508)
		(drill 0.254)
		(layers "F.Cu" "B.Cu")
		(net "SH_P0V8_PEX1_RGND1")
	)
	(via
		(at 116.65966 -329.44689)
		(size 0.508)
		(drill 0.254)
		(layers "F.Cu" "B.Cu")
		(net "SH_P0V8_PEX1_RGND1")
	)
	(segment
		(start 118.48211 -328.015092)
		(end 117.411246 -328.015092)
		(width 0.254)
		(layer "B.Cu")
		(net "SH_P0V8_PEX1_RGND1")
	)
	(segment
		(start 132.834888 -327.685654)
		(end 131.852924 -328.667618)
		(width 0.254)
		(layer "B.Cu")
		(net "SH_P0V8_PEX1_RGND1")
	)
	(segment
		(start 133.58749 -327.685654)
		(end 132.834888 -327.685654)
		(width 0.254)
		(layer "B.Cu")
		(net "SH_P0V8_PEX1_RGND1")
	)
	(segment
		(start 118.947438 -304.157634)
		(end 118.30939 -304.157634)
		(width 0.254)
		(layer "B.Cu")
		(net "SH_P0V8_PEX1_RGND1")
	)
	(segment
		(start 133.892544 -327.3552)
		(end 133.58749 -327.685654)
		(width 0.254)
		(layer "B.Cu")
		(net "SH_P0V8_PEX1_RGND1")
	)
	(segment
		(start 116.937028 -329.169522)
		(end 116.65966 -329.44689)
		(width 0.254)
		(layer "B.Cu")
		(net "SH_P0V8_PEX1_RGND1")
	)
	(segment
		(start 131.852924 -328.667618)
		(end 119.134636 -328.667618)
		(width 0.254)
		(layer "B.Cu")
		(net "SH_P0V8_PEX1_RGND1")
	)
	(segment
		(start 119.134636 -328.667618)
		(end 118.48211 -328.015092)
		(width 0.254)
		(layer "B.Cu")
		(net "SH_P0V8_PEX1_RGND1")
	)
	(segment
		(start 116.937028 -328.48931)
		(end 116.937028 -329.169522)
		(width 0.254)
		(layer "B.Cu")
		(net "SH_P0V8_PEX1_RGND1")
	)
	(segment
		(start 117.411246 -328.015092)
		(end 116.937028 -328.48931)
		(width 0.254)
		(layer "B.Cu")
		(net "SH_P0V8_PEX1_RGND1")
	)
	(segment
		(start 119.1641 -304.12563)
		(end 119.1641 -305.882802)
		(width 0.254)
		(layer "In5.Cu")
		(net "SH_P0V8_PEX1_RGND1")
	)
	(segment
		(start 118.197884 -306.849018)
		(end 118.197884 -327.084182)
		(width 0.254)
		(layer "In5.Cu")
		(net "SH_P0V8_PEX1_RGND1")
	)
	(segment
		(start 116.960904 -328.321162)
		(end 116.960904 -329.145646)
		(width 0.254)
		(layer "In5.Cu")
		(net "SH_P0V8_PEX1_RGND1")
	)
	(segment
		(start 118.30939 -304.157634)
		(end 118.55069 -303.916334)
		(width 0.254)
		(layer "In5.Cu")
		(net "SH_P0V8_PEX1_RGND1")
	)
	(segment
		(start 118.954804 -303.916334)
		(end 119.1641 -304.12563)
		(width 0.254)
		(layer "In5.Cu")
		(net "SH_P0V8_PEX1_RGND1")
	)
	(segment
		(start 116.960904 -329.145646)
		(end 116.65966 -329.44689)
		(width 0.254)
		(layer "In5.Cu")
		(net "SH_P0V8_PEX1_RGND1")
	)
	(segment
		(start 118.55069 -303.916334)
		(end 118.954804 -303.916334)
		(width 0.254)
		(layer "In5.Cu")
		(net "SH_P0V8_PEX1_RGND1")
	)
	(segment
		(start 118.197884 -327.084182)
		(end 116.960904 -328.321162)
		(width 0.254)
		(layer "In5.Cu")
		(net "SH_P0V8_PEX1_RGND1")
	)
	(segment
		(start 119.1641 -305.882802)
		(end 118.197884 -306.849018)
		(width 0.254)
		(layer "In5.Cu")
		(net "SH_P0V8_PEX1_RGND1")
	)
	(segment
		(start 140.923772 -278.003)
		(end 136.642856 -282.283916)
		(width 0.254)
		(layer "In9.Cu")
		(net "SH_P0V8_PEX1_RGND1")
	)
	(segment
		(start 136.642856 -282.283916)
		(end 136.642856 -302.422052)
		(width 0.254)
		(layer "In9.Cu")
		(net "SH_P0V8_PEX1_RGND1")
	)
	(segment
		(start 126.806198 -264.06602)
		(end 131.244594 -264.06602)
		(width 0.254)
		(layer "In9.Cu")
		(net "SH_P0V8_PEX1_RGND1")
	)
	(segment
		(start 117.01145 -262.443214)
		(end 117.994684 -262.443214)
		(width 0.254)
		(layer "In9.Cu")
		(net "SH_P0V8_PEX1_RGND1")
	)
	(segment
		(start 136.642856 -302.422052)
		(end 135.224774 -303.840134)
		(width 0.254)
		(layer "In9.Cu")
		(net "SH_P0V8_PEX1_RGND1")
	)
	(segment
		(start 140.923772 -273.745198)
		(end 140.923772 -278.003)
		(width 0.254)
		(layer "In9.Cu")
		(net "SH_P0V8_PEX1_RGND1")
	)
	(segment
		(start 117.994684 -262.443214)
		(end 118.411498 -262.0264)
		(width 0.254)
		(layer "In9.Cu")
		(net "SH_P0V8_PEX1_RGND1")
	)
	(segment
		(start 118.411498 -262.0264)
		(end 118.411498 -261.13613)
		(width 0.254)
		(layer "In9.Cu")
		(net "SH_P0V8_PEX1_RGND1")
	)
	(segment
		(start 123.254262 -260.514084)
		(end 126.806198 -264.06602)
		(width 0.254)
		(layer "In9.Cu")
		(net "SH_P0V8_PEX1_RGND1")
	)
	(segment
		(start 131.244594 -264.06602)
		(end 140.923772 -273.745198)
		(width 0.254)
		(layer "In9.Cu")
		(net "SH_P0V8_PEX1_RGND1")
	)
	(segment
		(start 119.033544 -260.514084)
		(end 123.254262 -260.514084)
		(width 0.254)
		(layer "In9.Cu")
		(net "SH_P0V8_PEX1_RGND1")
	)
	(segment
		(start 118.62689 -303.840134)
		(end 118.30939 -304.157634)
		(width 0.254)
		(layer "In9.Cu")
		(net "SH_P0V8_PEX1_RGND1")
	)
	(segment
		(start 116.7638 -262.195564)
		(end 117.01145 -262.443214)
		(width 0.254)
		(layer "In9.Cu")
		(net "SH_P0V8_PEX1_RGND1")
	)
	(segment
		(start 118.411498 -261.13613)
		(end 119.033544 -260.514084)
		(width 0.254)
		(layer "In9.Cu")
		(net "SH_P0V8_PEX1_RGND1")
	)
	(segment
		(start 135.224774 -303.840134)
		(end 118.62689 -303.840134)
		(width 0.254)
		(layer "In9.Cu")
		(net "SH_P0V8_PEX1_RGND1")
	)
	(segment
		(start 348.04731 -263.071864)
		(end 348.963996 -263.071864)
		(width 0.254)
		(layer "F.Cu")
		(net "SH_P0V8_PEX3_VSEN3_L")
	)
	(via
		(at 352.819208 -330.997306)
		(size 0.508)
		(drill 0.254)
		(layers "F.Cu" "B.Cu")
		(net "SH_P0V8_PEX3_VSEN3_L")
	)
	(via
		(at 348.963996 -263.071864)
		(size 0.508)
		(drill 0.254)
		(layers "F.Cu" "B.Cu")
		(net "SH_P0V8_PEX3_VSEN3_L")
	)
	(via
		(at 350.509586 -303.141634)
		(size 0.508)
		(drill 0.254)
		(layers "F.Cu" "B.Cu")
		(net "SH_P0V8_PEX3_VSEN3_L")
	)
	(segment
		(start 352.819208 -330.997306)
		(end 352.501708 -330.679806)
		(width 0.254)
		(layer "B.Cu")
		(net "SH_P0V8_PEX3_VSEN3_L")
	)
	(segment
		(start 352.655886 -330.062332)
		(end 357.142288 -330.062332)
		(width 0.254)
		(layer "B.Cu")
		(net "SH_P0V8_PEX3_VSEN3_L")
	)
	(segment
		(start 352.501708 -330.679806)
		(end 352.501708 -330.21651)
		(width 0.254)
		(layer "B.Cu")
		(net "SH_P0V8_PEX3_VSEN3_L")
	)
	(segment
		(start 351.147634 -303.141634)
		(end 350.509586 -303.141634)
		(width 0.254)
		(layer "B.Cu")
		(net "SH_P0V8_PEX3_VSEN3_L")
	)
	(segment
		(start 357.142288 -330.062332)
		(end 358.040432 -329.164188)
		(width 0.254)
		(layer "B.Cu")
		(net "SH_P0V8_PEX3_VSEN3_L")
	)
	(segment
		(start 365.774986 -328.0791)
		(end 366.092486 -328.422)
		(width 0.254)
		(layer "B.Cu")
		(net "SH_P0V8_PEX3_VSEN3_L")
	)
	(segment
		(start 360.409998 -329.164188)
		(end 361.495086 -328.0791)
		(width 0.254)
		(layer "B.Cu")
		(net "SH_P0V8_PEX3_VSEN3_L")
	)
	(segment
		(start 358.040432 -329.164188)
		(end 360.409998 -329.164188)
		(width 0.254)
		(layer "B.Cu")
		(net "SH_P0V8_PEX3_VSEN3_L")
	)
	(segment
		(start 352.501708 -330.21651)
		(end 352.655886 -330.062332)
		(width 0.254)
		(layer "B.Cu")
		(net "SH_P0V8_PEX3_VSEN3_L")
	)
	(segment
		(start 361.495086 -328.0791)
		(end 365.774986 -328.0791)
		(width 0.254)
		(layer "B.Cu")
		(net "SH_P0V8_PEX3_VSEN3_L")
	)
	(segment
		(start 351.745296 -306.04079)
		(end 351.745296 -303.859946)
		(width 0.254)
		(layer "In5.Cu")
		(net "SH_P0V8_PEX3_VSEN3_L")
	)
	(segment
		(start 352.485452 -330.66355)
		(end 352.485452 -329.668886)
		(width 0.254)
		(layer "In5.Cu")
		(net "SH_P0V8_PEX3_VSEN3_L")
	)
	(segment
		(start 351.344484 -303.459134)
		(end 350.827086 -303.459134)
		(width 0.254)
		(layer "In5.Cu")
		(net "SH_P0V8_PEX3_VSEN3_L")
	)
	(segment
		(start 350.77908 -307.007006)
		(end 351.745296 -306.04079)
		(width 0.254)
		(layer "In5.Cu")
		(net "SH_P0V8_PEX3_VSEN3_L")
	)
	(segment
		(start 350.77908 -327.962514)
		(end 350.77908 -307.007006)
		(width 0.254)
		(layer "In5.Cu")
		(net "SH_P0V8_PEX3_VSEN3_L")
	)
	(segment
		(start 351.745296 -303.859946)
		(end 351.344484 -303.459134)
		(width 0.254)
		(layer "In5.Cu")
		(net "SH_P0V8_PEX3_VSEN3_L")
	)
	(segment
		(start 352.819208 -330.997306)
		(end 352.485452 -330.66355)
		(width 0.254)
		(layer "In5.Cu")
		(net "SH_P0V8_PEX3_VSEN3_L")
	)
	(segment
		(start 350.827086 -303.459134)
		(end 350.509586 -303.141634)
		(width 0.254)
		(layer "In5.Cu")
		(net "SH_P0V8_PEX3_VSEN3_L")
	)
	(segment
		(start 352.485452 -329.668886)
		(end 350.77908 -327.962514)
		(width 0.254)
		(layer "In5.Cu")
		(net "SH_P0V8_PEX3_VSEN3_L")
	)
	(segment
		(start 349.211646 -262.824214)
		(end 348.963996 -263.071864)
		(width 0.254)
		(layer "In9.Cu")
		(net "SH_P0V8_PEX3_VSEN3_L")
	)
	(segment
		(start 350.509586 -303.141634)
		(end 350.827086 -303.459134)
		(width 0.254)
		(layer "In9.Cu")
		(net "SH_P0V8_PEX3_VSEN3_L")
	)
	(segment
		(start 350.827086 -303.459134)
		(end 367.266982 -303.459134)
		(width 0.254)
		(layer "In9.Cu")
		(net "SH_P0V8_PEX3_VSEN3_L")
	)
	(segment
		(start 368.462052 -302.264064)
		(end 368.462052 -282.125928)
		(width 0.254)
		(layer "In9.Cu")
		(net "SH_P0V8_PEX3_VSEN3_L")
	)
	(segment
		(start 358.848406 -264.44702)
		(end 355.29647 -260.895084)
		(width 0.254)
		(layer "In9.Cu")
		(net "SH_P0V8_PEX3_VSEN3_L")
	)
	(segment
		(start 350.992694 -262.184388)
		(end 350.352868 -262.824214)
		(width 0.254)
		(layer "In9.Cu")
		(net "SH_P0V8_PEX3_VSEN3_L")
	)
	(segment
		(start 350.992694 -261.294118)
		(end 350.992694 -262.184388)
		(width 0.254)
		(layer "In9.Cu")
		(net "SH_P0V8_PEX3_VSEN3_L")
	)
	(segment
		(start 351.391728 -260.895084)
		(end 350.992694 -261.294118)
		(width 0.254)
		(layer "In9.Cu")
		(net "SH_P0V8_PEX3_VSEN3_L")
	)
	(segment
		(start 367.266982 -303.459134)
		(end 368.462052 -302.264064)
		(width 0.254)
		(layer "In9.Cu")
		(net "SH_P0V8_PEX3_VSEN3_L")
	)
	(segment
		(start 372.742968 -277.845012)
		(end 372.742968 -273.903186)
		(width 0.254)
		(layer "In9.Cu")
		(net "SH_P0V8_PEX3_VSEN3_L")
	)
	(segment
		(start 363.286802 -264.44702)
		(end 358.848406 -264.44702)
		(width 0.254)
		(layer "In9.Cu")
		(net "SH_P0V8_PEX3_VSEN3_L")
	)
	(segment
		(start 372.742968 -273.903186)
		(end 363.286802 -264.44702)
		(width 0.254)
		(layer "In9.Cu")
		(net "SH_P0V8_PEX3_VSEN3_L")
	)
	(segment
		(start 350.352868 -262.824214)
		(end 349.211646 -262.824214)
		(width 0.254)
		(layer "In9.Cu")
		(net "SH_P0V8_PEX3_VSEN3_L")
	)
	(segment
		(start 355.29647 -260.895084)
		(end 351.391728 -260.895084)
		(width 0.254)
		(layer "In9.Cu")
		(net "SH_P0V8_PEX3_VSEN3_L")
	)
	(segment
		(start 368.462052 -282.125928)
		(end 372.742968 -277.845012)
		(width 0.254)
		(layer "In9.Cu")
		(net "SH_P0V8_PEX3_VSEN3_L")
	)
	(segment
		(start 349.865188 -260.909562)
		(end 349.865188 -260.554978)
		(width 0.1778)
		(layer "F.Cu")
		(net "SH_P0V8_PEX3_RGND3")
	)
	(segment
		(start 348.963996 -261.424928)
		(end 349.31731 -261.071614)
		(width 0.254)
		(layer "F.Cu")
		(net "SH_P0V8_PEX3_RGND3")
	)
	(segment
		(start 349.703136 -261.071614)
		(end 349.865188 -260.909562)
		(width 0.1778)
		(layer "F.Cu")
		(net "SH_P0V8_PEX3_RGND3")
	)
	(segment
		(start 350.225106 -260.19506)
		(end 350.57588 -260.19506)
		(width 0.1778)
		(layer "F.Cu")
		(net "SH_P0V8_PEX3_RGND3")
	)
	(segment
		(start 349.865188 -260.554978)
		(end 350.225106 -260.19506)
		(width 0.1778)
		(layer "F.Cu")
		(net "SH_P0V8_PEX3_RGND3")
	)
	(segment
		(start 349.31731 -261.071614)
		(end 349.703136 -261.071614)
		(width 0.1778)
		(layer "F.Cu")
		(net "SH_P0V8_PEX3_RGND3")
	)
	(segment
		(start 348.963996 -262.195564)
		(end 348.963996 -261.424928)
		(width 0.254)
		(layer "F.Cu")
		(net "SH_P0V8_PEX3_RGND3")
	)
	(via
		(at 348.963996 -262.195564)
		(size 0.508)
		(drill 0.254)
		(layers "F.Cu" "B.Cu")
		(net "SH_P0V8_PEX3_RGND3")
	)
	(via
		(at 350.509586 -304.157634)
		(size 0.508)
		(drill 0.254)
		(layers "F.Cu" "B.Cu")
		(net "SH_P0V8_PEX3_RGND3")
	)
	(via
		(at 351.803208 -330.997306)
		(size 0.508)
		(drill 0.254)
		(layers "F.Cu" "B.Cu")
		(net "SH_P0V8_PEX3_RGND3")
	)
	(segment
		(start 352.497898 -329.681332)
		(end 356.9843 -329.681332)
		(width 0.254)
		(layer "B.Cu")
		(net "SH_P0V8_PEX3_RGND3")
	)
	(segment
		(start 351.147634 -304.157634)
		(end 350.509586 -304.157634)
		(width 0.254)
		(layer "B.Cu")
		(net "SH_P0V8_PEX3_RGND3")
	)
	(segment
		(start 361.337098 -327.6981)
		(end 365.774986 -327.6981)
		(width 0.254)
		(layer "B.Cu")
		(net "SH_P0V8_PEX3_RGND3")
	)
	(segment
		(start 360.25201 -328.783188)
		(end 361.337098 -327.6981)
		(width 0.254)
		(layer "B.Cu")
		(net "SH_P0V8_PEX3_RGND3")
	)
	(segment
		(start 356.9843 -329.681332)
		(end 357.882444 -328.783188)
		(width 0.254)
		(layer "B.Cu")
		(net "SH_P0V8_PEX3_RGND3")
	)
	(segment
		(start 365.774986 -327.6981)
		(end 366.092486 -327.3552)
		(width 0.254)
		(layer "B.Cu")
		(net "SH_P0V8_PEX3_RGND3")
	)
	(segment
		(start 351.803208 -330.997306)
		(end 352.120708 -330.679806)
		(width 0.254)
		(layer "B.Cu")
		(net "SH_P0V8_PEX3_RGND3")
	)
	(segment
		(start 357.882444 -328.783188)
		(end 360.25201 -328.783188)
		(width 0.254)
		(layer "B.Cu")
		(net "SH_P0V8_PEX3_RGND3")
	)
	(segment
		(start 352.120708 -330.058522)
		(end 352.497898 -329.681332)
		(width 0.254)
		(layer "B.Cu")
		(net "SH_P0V8_PEX3_RGND3")
	)
	(segment
		(start 352.120708 -330.679806)
		(end 352.120708 -330.058522)
		(width 0.254)
		(layer "B.Cu")
		(net "SH_P0V8_PEX3_RGND3")
	)
	(segment
		(start 350.39808 -328.120502)
		(end 350.39808 -306.849018)
		(width 0.254)
		(layer "In5.Cu")
		(net "SH_P0V8_PEX3_RGND3")
	)
	(segment
		(start 351.364296 -304.12563)
		(end 351.155 -303.916334)
		(width 0.254)
		(layer "In5.Cu")
		(net "SH_P0V8_PEX3_RGND3")
	)
	(segment
		(start 350.750886 -303.916334)
		(end 350.509586 -304.157634)
		(width 0.254)
		(layer "In5.Cu")
		(net "SH_P0V8_PEX3_RGND3")
	)
	(segment
		(start 351.155 -303.916334)
		(end 350.750886 -303.916334)
		(width 0.254)
		(layer "In5.Cu")
		(net "SH_P0V8_PEX3_RGND3")
	)
	(segment
		(start 352.104452 -329.826874)
		(end 350.39808 -328.120502)
		(width 0.254)
		(layer "In5.Cu")
		(net "SH_P0V8_PEX3_RGND3")
	)
	(segment
		(start 350.39808 -306.849018)
		(end 351.364296 -305.882802)
		(width 0.254)
		(layer "In5.Cu")
		(net "SH_P0V8_PEX3_RGND3")
	)
	(segment
		(start 352.104452 -330.696062)
		(end 352.104452 -329.826874)
		(width 0.254)
		(layer "In5.Cu")
		(net "SH_P0V8_PEX3_RGND3")
	)
	(segment
		(start 351.803208 -330.997306)
		(end 352.104452 -330.696062)
		(width 0.254)
		(layer "In5.Cu")
		(net "SH_P0V8_PEX3_RGND3")
	)
	(segment
		(start 351.364296 -305.882802)
		(end 351.364296 -304.12563)
		(width 0.254)
		(layer "In5.Cu")
		(net "SH_P0V8_PEX3_RGND3")
	)
	(segment
		(start 359.006394 -264.06602)
		(end 363.44479 -264.06602)
		(width 0.254)
		(layer "In9.Cu")
		(net "SH_P0V8_PEX3_RGND3")
	)
	(segment
		(start 373.123968 -278.003)
		(end 368.843052 -282.283916)
		(width 0.254)
		(layer "In9.Cu")
		(net "SH_P0V8_PEX3_RGND3")
	)
	(segment
		(start 368.843052 -282.283916)
		(end 368.843052 -302.422052)
		(width 0.254)
		(layer "In9.Cu")
		(net "SH_P0V8_PEX3_RGND3")
	)
	(segment
		(start 349.211646 -262.443214)
		(end 350.19488 -262.443214)
		(width 0.254)
		(layer "In9.Cu")
		(net "SH_P0V8_PEX3_RGND3")
	)
	(segment
		(start 373.123968 -273.745198)
		(end 373.123968 -278.003)
		(width 0.254)
		(layer "In9.Cu")
		(net "SH_P0V8_PEX3_RGND3")
	)
	(segment
		(start 351.23374 -260.514084)
		(end 355.454458 -260.514084)
		(width 0.254)
		(layer "In9.Cu")
		(net "SH_P0V8_PEX3_RGND3")
	)
	(segment
		(start 348.963996 -262.195564)
		(end 349.211646 -262.443214)
		(width 0.254)
		(layer "In9.Cu")
		(net "SH_P0V8_PEX3_RGND3")
	)
	(segment
		(start 350.827086 -303.840134)
		(end 350.509586 -304.157634)
		(width 0.254)
		(layer "In9.Cu")
		(net "SH_P0V8_PEX3_RGND3")
	)
	(segment
		(start 355.454458 -260.514084)
		(end 359.006394 -264.06602)
		(width 0.254)
		(layer "In9.Cu")
		(net "SH_P0V8_PEX3_RGND3")
	)
	(segment
		(start 350.611694 -261.13613)
		(end 351.23374 -260.514084)
		(width 0.254)
		(layer "In9.Cu")
		(net "SH_P0V8_PEX3_RGND3")
	)
	(segment
		(start 363.44479 -264.06602)
		(end 373.123968 -273.745198)
		(width 0.254)
		(layer "In9.Cu")
		(net "SH_P0V8_PEX3_RGND3")
	)
	(segment
		(start 350.611694 -262.0264)
		(end 350.611694 -261.13613)
		(width 0.254)
		(layer "In9.Cu")
		(net "SH_P0V8_PEX3_RGND3")
	)
	(segment
		(start 350.19488 -262.443214)
		(end 350.611694 -262.0264)
		(width 0.254)
		(layer "In9.Cu")
		(net "SH_P0V8_PEX3_RGND3")
	)
	(segment
		(start 367.42497 -303.840134)
		(end 350.827086 -303.840134)
		(width 0.254)
		(layer "In9.Cu")
		(net "SH_P0V8_PEX3_RGND3")
	)
	(segment
		(start 368.843052 -302.422052)
		(end 367.42497 -303.840134)
		(width 0.254)
		(layer "In9.Cu")
		(net "SH_P0V8_PEX3_RGND3")
	)
	(segment
		(start 355.562408 -264.103866)
		(end 355.588062 -264.103866)
		(width 0.254)
		(layer "F.Cu")
		(net "SH_P0V8_PEX2_VSEN2_L")
	)
	(segment
		(start 355.588062 -264.103866)
		(end 356.121208 -263.57072)
		(width 0.254)
		(layer "F.Cu")
		(net "SH_P0V8_PEX2_VSEN2_L")
	)
	(segment
		(start 356.121208 -263.57072)
		(end 356.618286 -263.57072)
		(width 0.254)
		(layer "F.Cu")
		(net "SH_P0V8_PEX2_VSEN2_L")
	)
	(via
		(at 355.562408 -264.103866)
		(size 0.508)
		(drill 0.254)
		(layers "F.Cu" "B.Cu")
		(net "SH_P0V8_PEX2_VSEN2_L")
	)
	(via
		(at 334.844898 -328.010774)
		(size 0.508)
		(drill 0.254)
		(layers "F.Cu" "B.Cu")
		(net "SH_P0V8_PEX2_VSEN2_L")
	)
	(via
		(at 349.366586 -303.141634)
		(size 0.508)
		(drill 0.254)
		(layers "F.Cu" "B.Cu")
		(net "SH_P0V8_PEX2_VSEN2_L")
	)
	(segment
		(start 334.560926 -328.294746)
		(end 334.844898 -328.010774)
		(width 0.254)
		(layer "B.Cu")
		(net "SH_P0V8_PEX2_VSEN2_L")
	)
	(segment
		(start 348.728538 -303.141634)
		(end 349.366586 -303.141634)
		(width 0.254)
		(layer "B.Cu")
		(net "SH_P0V8_PEX2_VSEN2_L")
	)
	(segment
		(start 333.800958 -328.294746)
		(end 334.560926 -328.294746)
		(width 0.254)
		(layer "B.Cu")
		(net "SH_P0V8_PEX2_VSEN2_L")
	)
	(segment
		(start 333.473806 -327.942194)
		(end 333.800958 -328.294746)
		(width 0.254)
		(layer "B.Cu")
		(net "SH_P0V8_PEX2_VSEN2_L")
	)
	(segment
		(start 348.054676 -303.936146)
		(end 348.531688 -303.459134)
		(width 0.254)
		(layer "In5.Cu")
		(net "SH_P0V8_PEX2_VSEN2_L")
	)
	(segment
		(start 348.054676 -306.216558)
		(end 348.054676 -303.936146)
		(width 0.254)
		(layer "In5.Cu")
		(net "SH_P0V8_PEX2_VSEN2_L")
	)
	(segment
		(start 334.844898 -328.010774)
		(end 335.148428 -328.314304)
		(width 0.254)
		(layer "In5.Cu")
		(net "SH_P0V8_PEX2_VSEN2_L")
	)
	(segment
		(start 348.902782 -307.064664)
		(end 348.054676 -306.216558)
		(width 0.254)
		(layer "In5.Cu")
		(net "SH_P0V8_PEX2_VSEN2_L")
	)
	(segment
		(start 346.364306 -328.314304)
		(end 348.902782 -325.775828)
		(width 0.254)
		(layer "In5.Cu")
		(net "SH_P0V8_PEX2_VSEN2_L")
	)
	(segment
		(start 335.148428 -328.314304)
		(end 346.364306 -328.314304)
		(width 0.254)
		(layer "In5.Cu")
		(net "SH_P0V8_PEX2_VSEN2_L")
	)
	(segment
		(start 348.531688 -303.459134)
		(end 349.049086 -303.459134)
		(width 0.254)
		(layer "In5.Cu")
		(net "SH_P0V8_PEX2_VSEN2_L")
	)
	(segment
		(start 348.902782 -325.775828)
		(end 348.902782 -307.064664)
		(width 0.254)
		(layer "In5.Cu")
		(net "SH_P0V8_PEX2_VSEN2_L")
	)
	(segment
		(start 349.049086 -303.459134)
		(end 349.366586 -303.141634)
		(width 0.254)
		(layer "In5.Cu")
		(net "SH_P0V8_PEX2_VSEN2_L")
	)
	(segment
		(start 333.33944 -303.459134)
		(end 332.87462 -302.994314)
		(width 0.254)
		(layer "In9.Cu")
		(net "SH_P0V8_PEX2_VSEN2_L")
	)
	(segment
		(start 332.87462 -296.897044)
		(end 327.236328 -291.258752)
		(width 0.254)
		(layer "In9.Cu")
		(net "SH_P0V8_PEX2_VSEN2_L")
	)
	(segment
		(start 332.841346 -280.252932)
		(end 336.014568 -280.252932)
		(width 0.254)
		(layer "In9.Cu")
		(net "SH_P0V8_PEX2_VSEN2_L")
	)
	(segment
		(start 341.027004 -267.071602)
		(end 353.531678 -267.071602)
		(width 0.254)
		(layer "In9.Cu")
		(net "SH_P0V8_PEX2_VSEN2_L")
	)
	(segment
		(start 339.670644 -276.596856)
		(end 339.670644 -268.427962)
		(width 0.254)
		(layer "In9.Cu")
		(net "SH_P0V8_PEX2_VSEN2_L")
	)
	(segment
		(start 355.284278 -263.858502)
		(end 355.535992 -264.103866)
		(width 0.254)
		(layer "In9.Cu")
		(net "SH_P0V8_PEX2_VSEN2_L")
	)
	(segment
		(start 354.598986 -266.004294)
		(end 354.598986 -264.083292)
		(width 0.254)
		(layer "In9.Cu")
		(net "SH_P0V8_PEX2_VSEN2_L")
	)
	(segment
		(start 339.670644 -268.427962)
		(end 341.027004 -267.071602)
		(width 0.254)
		(layer "In9.Cu")
		(net "SH_P0V8_PEX2_VSEN2_L")
	)
	(segment
		(start 355.535992 -264.103866)
		(end 355.562408 -264.103866)
		(width 0.254)
		(layer "In9.Cu")
		(net "SH_P0V8_PEX2_VSEN2_L")
	)
	(segment
		(start 353.531678 -267.071602)
		(end 354.598986 -266.004294)
		(width 0.254)
		(layer "In9.Cu")
		(net "SH_P0V8_PEX2_VSEN2_L")
	)
	(segment
		(start 354.819458 -263.86282)
		(end 354.917502 -263.86282)
		(width 0.254)
		(layer "In9.Cu")
		(net "SH_P0V8_PEX2_VSEN2_L")
	)
	(segment
		(start 327.236328 -285.85795)
		(end 332.841346 -280.252932)
		(width 0.254)
		(layer "In9.Cu")
		(net "SH_P0V8_PEX2_VSEN2_L")
	)
	(segment
		(start 332.87462 -302.994314)
		(end 332.87462 -296.897044)
		(width 0.254)
		(layer "In9.Cu")
		(net "SH_P0V8_PEX2_VSEN2_L")
	)
	(segment
		(start 354.598986 -264.083292)
		(end 354.819458 -263.86282)
		(width 0.254)
		(layer "In9.Cu")
		(net "SH_P0V8_PEX2_VSEN2_L")
	)
	(segment
		(start 336.014568 -280.252932)
		(end 339.670644 -276.596856)
		(width 0.254)
		(layer "In9.Cu")
		(net "SH_P0V8_PEX2_VSEN2_L")
	)
	(segment
		(start 349.049086 -303.459134)
		(end 333.33944 -303.459134)
		(width 0.254)
		(layer "In9.Cu")
		(net "SH_P0V8_PEX2_VSEN2_L")
	)
	(segment
		(start 354.917502 -263.86282)
		(end 355.284278 -263.858502)
		(width 0.254)
		(layer "In9.Cu")
		(net "SH_P0V8_PEX2_VSEN2_L")
	)
	(segment
		(start 349.366586 -303.141634)
		(end 349.049086 -303.459134)
		(width 0.254)
		(layer "In9.Cu")
		(net "SH_P0V8_PEX2_VSEN2_L")
	)
	(segment
		(start 327.236328 -291.258752)
		(end 327.236328 -285.85795)
		(width 0.254)
		(layer "In9.Cu")
		(net "SH_P0V8_PEX2_VSEN2_L")
	)
	(segment
		(start 354.681536 -262.04672)
		(end 354.681536 -262.707628)
		(width 0.254)
		(layer "F.Cu")
		(net "SH_P0V8_PEX2_RGND2")
	)
	(segment
		(start 354.375974 -260.795008)
		(end 354.375974 -261.341108)
		(width 0.2032)
		(layer "F.Cu")
		(net "SH_P0V8_PEX2_RGND2")
	)
	(segment
		(start 355.157278 -263.18337)
		(end 355.550978 -263.18337)
		(width 0.254)
		(layer "F.Cu")
		(net "SH_P0V8_PEX2_RGND2")
	)
	(segment
		(start 354.681536 -261.64667)
		(end 354.681536 -262.04672)
		(width 0.2032)
		(layer "F.Cu")
		(net "SH_P0V8_PEX2_RGND2")
	)
	(segment
		(start 354.375974 -261.341108)
		(end 354.681536 -261.64667)
		(width 0.2032)
		(layer "F.Cu")
		(net "SH_P0V8_PEX2_RGND2")
	)
	(segment
		(start 354.681536 -262.707628)
		(end 355.157278 -263.18337)
		(width 0.254)
		(layer "F.Cu")
		(net "SH_P0V8_PEX2_RGND2")
	)
	(via
		(at 334.844898 -329.026774)
		(size 0.508)
		(drill 0.254)
		(layers "F.Cu" "B.Cu")
		(net "SH_P0V8_PEX2_RGND2")
	)
	(via
		(at 355.550978 -263.18337)
		(size 0.508)
		(drill 0.254)
		(layers "F.Cu" "B.Cu")
		(net "SH_P0V8_PEX2_RGND2")
	)
	(via
		(at 349.366586 -304.157634)
		(size 0.508)
		(drill 0.254)
		(layers "F.Cu" "B.Cu")
		(net "SH_P0V8_PEX2_RGND2")
	)
	(segment
		(start 348.728538 -304.157634)
		(end 349.366586 -304.157634)
		(width 0.254)
		(layer "B.Cu")
		(net "SH_P0V8_PEX2_RGND2")
	)
	(segment
		(start 334.49387 -328.675746)
		(end 333.781654 -328.675746)
		(width 0.254)
		(layer "B.Cu")
		(net "SH_P0V8_PEX2_RGND2")
	)
	(segment
		(start 334.844898 -329.026774)
		(end 334.49387 -328.675746)
		(width 0.254)
		(layer "B.Cu")
		(net "SH_P0V8_PEX2_RGND2")
	)
	(segment
		(start 333.781654 -328.675746)
		(end 333.473806 -329.008994)
		(width 0.254)
		(layer "B.Cu")
		(net "SH_P0V8_PEX2_RGND2")
	)
	(segment
		(start 346.522294 -328.695304)
		(end 349.283782 -325.933816)
		(width 0.254)
		(layer "In5.Cu")
		(net "SH_P0V8_PEX2_RGND2")
	)
	(segment
		(start 348.435676 -306.05857)
		(end 348.435676 -304.094134)
		(width 0.254)
		(layer "In5.Cu")
		(net "SH_P0V8_PEX2_RGND2")
	)
	(segment
		(start 349.283782 -306.906676)
		(end 348.435676 -306.05857)
		(width 0.254)
		(layer "In5.Cu")
		(net "SH_P0V8_PEX2_RGND2")
	)
	(segment
		(start 348.435676 -304.094134)
		(end 348.689676 -303.840134)
		(width 0.254)
		(layer "In5.Cu")
		(net "SH_P0V8_PEX2_RGND2")
	)
	(segment
		(start 349.049086 -303.840134)
		(end 349.366586 -304.157634)
		(width 0.254)
		(layer "In5.Cu")
		(net "SH_P0V8_PEX2_RGND2")
	)
	(segment
		(start 335.176368 -328.695304)
		(end 346.522294 -328.695304)
		(width 0.254)
		(layer "In5.Cu")
		(net "SH_P0V8_PEX2_RGND2")
	)
	(segment
		(start 349.283782 -325.933816)
		(end 349.283782 -306.906676)
		(width 0.254)
		(layer "In5.Cu")
		(net "SH_P0V8_PEX2_RGND2")
	)
	(segment
		(start 334.844898 -329.026774)
		(end 335.176368 -328.695304)
		(width 0.254)
		(layer "In5.Cu")
		(net "SH_P0V8_PEX2_RGND2")
	)
	(segment
		(start 348.689676 -303.840134)
		(end 349.049086 -303.840134)
		(width 0.254)
		(layer "In5.Cu")
		(net "SH_P0V8_PEX2_RGND2")
	)
	(segment
		(start 354.217986 -265.846306)
		(end 354.217986 -263.925304)
		(width 0.254)
		(layer "In9.Cu")
		(net "SH_P0V8_PEX2_RGND2")
	)
	(segment
		(start 326.855328 -291.41674)
		(end 326.855328 -285.699962)
		(width 0.254)
		(layer "In9.Cu")
		(net "SH_P0V8_PEX2_RGND2")
	)
	(segment
		(start 332.683358 -279.871932)
		(end 335.85658 -279.871932)
		(width 0.254)
		(layer "In9.Cu")
		(net "SH_P0V8_PEX2_RGND2")
	)
	(segment
		(start 332.49362 -297.055032)
		(end 326.855328 -291.41674)
		(width 0.254)
		(layer "In9.Cu")
		(net "SH_P0V8_PEX2_RGND2")
	)
	(segment
		(start 335.85658 -279.871932)
		(end 339.289644 -276.438868)
		(width 0.254)
		(layer "In9.Cu")
		(net "SH_P0V8_PEX2_RGND2")
	)
	(segment
		(start 339.289644 -268.269974)
		(end 340.869016 -266.690602)
		(width 0.254)
		(layer "In9.Cu")
		(net "SH_P0V8_PEX2_RGND2")
	)
	(segment
		(start 340.869016 -266.690602)
		(end 353.37369 -266.690602)
		(width 0.254)
		(layer "In9.Cu")
		(net "SH_P0V8_PEX2_RGND2")
	)
	(segment
		(start 332.49362 -303.152302)
		(end 332.49362 -297.055032)
		(width 0.254)
		(layer "In9.Cu")
		(net "SH_P0V8_PEX2_RGND2")
	)
	(segment
		(start 349.366586 -304.157634)
		(end 349.049086 -303.840134)
		(width 0.254)
		(layer "In9.Cu")
		(net "SH_P0V8_PEX2_RGND2")
	)
	(segment
		(start 354.217986 -263.925304)
		(end 354.66147 -263.48182)
		(width 0.254)
		(layer "In9.Cu")
		(net "SH_P0V8_PEX2_RGND2")
	)
	(segment
		(start 349.049086 -303.840134)
		(end 333.181452 -303.840134)
		(width 0.254)
		(layer "In9.Cu")
		(net "SH_P0V8_PEX2_RGND2")
	)
	(segment
		(start 354.914962 -263.48182)
		(end 355.263704 -263.477502)
		(width 0.254)
		(layer "In9.Cu")
		(net "SH_P0V8_PEX2_RGND2")
	)
	(segment
		(start 354.66147 -263.48182)
		(end 354.914962 -263.48182)
		(width 0.254)
		(layer "In9.Cu")
		(net "SH_P0V8_PEX2_RGND2")
	)
	(segment
		(start 326.855328 -285.699962)
		(end 332.683358 -279.871932)
		(width 0.254)
		(layer "In9.Cu")
		(net "SH_P0V8_PEX2_RGND2")
	)
	(segment
		(start 353.37369 -266.690602)
		(end 354.217986 -265.846306)
		(width 0.254)
		(layer "In9.Cu")
		(net "SH_P0V8_PEX2_RGND2")
	)
	(segment
		(start 339.289644 -276.438868)
		(end 339.289644 -268.269974)
		(width 0.254)
		(layer "In9.Cu")
		(net "SH_P0V8_PEX2_RGND2")
	)
	(segment
		(start 355.263704 -263.477502)
		(end 355.550978 -263.18337)
		(width 0.254)
		(layer "In9.Cu")
		(net "SH_P0V8_PEX2_RGND2")
	)
	(segment
		(start 333.181452 -303.840134)
		(end 332.49362 -303.152302)
		(width 0.254)
		(layer "In9.Cu")
		(net "SH_P0V8_PEX2_RGND2")
	)
	(segment
		(start 390.849866 -293.99992)
		(end 390.374886 -293.52494)
		(width 0.13208)
		(layer "F.Cu")
		(net "SPI_PEX3_RST_N")
	)
	(via
		(at 390.374886 -293.52494)
		(size 0.4064)
		(drill 0.2032)
		(layers "F.Cu" "B.Cu")
		(net "SPI_PEX3_RST_N")
	)
	(via
		(at 389.145018 -264.625328)
		(size 0.508)
		(drill 0.254)
		(layers "F.Cu" "B.Cu")
		(net "SPI_PEX3_RST_N")
	)
	(via
		(at 379.718316 -227.397056)
		(size 0.508)
		(drill 0.254)
		(layers "F.Cu" "B.Cu")
		(net "SPI_PEX3_RST_N")
	)
	(segment
		(start 389.941308 -293.033704)
		(end 388.294372 -293.033704)
		(width 0.13208)
		(layer "B.Cu")
		(net "SPI_PEX3_RST_N")
	)
	(segment
		(start 388.069582 -265.700764)
		(end 389.145018 -264.625328)
		(width 0.13208)
		(layer "B.Cu")
		(net "SPI_PEX3_RST_N")
	)
	(segment
		(start 386.104638 -268.163802)
		(end 386.369814 -267.898626)
		(width 0.13208)
		(layer "B.Cu")
		(net "SPI_PEX3_RST_N")
	)
	(segment
		(start 388.008876 -292.748208)
		(end 388.008876 -292.499288)
		(width 0.13208)
		(layer "B.Cu")
		(net "SPI_PEX3_RST_N")
	)
	(segment
		(start 379.718316 -227.039932)
		(end 379.718316 -227.397056)
		(width 0.13208)
		(layer "B.Cu")
		(net "SPI_PEX3_RST_N")
	)
	(segment
		(start 390.374886 -293.467282)
		(end 389.941308 -293.033704)
		(width 0.13208)
		(layer "B.Cu")
		(net "SPI_PEX3_RST_N")
	)
	(segment
		(start 386.753608 -291.090096)
		(end 385.45262 -291.090096)
		(width 0.13208)
		(layer "B.Cu")
		(net "SPI_PEX3_RST_N")
	)
	(segment
		(start 387.047232 -291.537644)
		(end 387.047232 -291.38372)
		(width 0.13208)
		(layer "B.Cu")
		(net "SPI_PEX3_RST_N")
	)
	(segment
		(start 385.179316 -279.148286)
		(end 385.4831 -278.844502)
		(width 0.13208)
		(layer "B.Cu")
		(net "SPI_PEX3_RST_N")
	)
	(segment
		(start 387.047232 -291.38372)
		(end 386.753608 -291.090096)
		(width 0.13208)
		(layer "B.Cu")
		(net "SPI_PEX3_RST_N")
	)
	(segment
		(start 388.294372 -293.033704)
		(end 388.008876 -292.748208)
		(width 0.13208)
		(layer "B.Cu")
		(net "SPI_PEX3_RST_N")
	)
	(segment
		(start 378.564394 -226.47021)
		(end 379.148594 -226.47021)
		(width 0.13208)
		(layer "B.Cu")
		(net "SPI_PEX3_RST_N")
	)
	(segment
		(start 385.45262 -291.090096)
		(end 385.179316 -290.816792)
		(width 0.13208)
		(layer "B.Cu")
		(net "SPI_PEX3_RST_N")
	)
	(segment
		(start 390.374886 -293.52494)
		(end 390.374886 -293.467282)
		(width 0.13208)
		(layer "B.Cu")
		(net "SPI_PEX3_RST_N")
	)
	(segment
		(start 386.369814 -266.650978)
		(end 387.320028 -265.700764)
		(width 0.13208)
		(layer "B.Cu")
		(net "SPI_PEX3_RST_N")
	)
	(segment
		(start 387.320028 -265.700764)
		(end 388.069582 -265.700764)
		(width 0.13208)
		(layer "B.Cu")
		(net "SPI_PEX3_RST_N")
	)
	(segment
		(start 386.104638 -278.583898)
		(end 386.104638 -268.163802)
		(width 0.13208)
		(layer "B.Cu")
		(net "SPI_PEX3_RST_N")
	)
	(segment
		(start 385.179316 -290.816792)
		(end 385.179316 -279.148286)
		(width 0.13208)
		(layer "B.Cu")
		(net "SPI_PEX3_RST_N")
	)
	(segment
		(start 385.844034 -278.844502)
		(end 386.104638 -278.583898)
		(width 0.13208)
		(layer "B.Cu")
		(net "SPI_PEX3_RST_N")
	)
	(segment
		(start 388.008876 -292.499288)
		(end 387.047232 -291.537644)
		(width 0.13208)
		(layer "B.Cu")
		(net "SPI_PEX3_RST_N")
	)
	(segment
		(start 385.4831 -278.844502)
		(end 385.844034 -278.844502)
		(width 0.13208)
		(layer "B.Cu")
		(net "SPI_PEX3_RST_N")
	)
	(segment
		(start 379.148594 -226.47021)
		(end 379.718316 -227.039932)
		(width 0.13208)
		(layer "B.Cu")
		(net "SPI_PEX3_RST_N")
	)
	(segment
		(start 386.369814 -267.898626)
		(end 386.369814 -266.650978)
		(width 0.13208)
		(layer "B.Cu")
		(net "SPI_PEX3_RST_N")
	)
	(segment
		(start 377.998482 -255.763522)
		(end 377.998482 -256.779522)
		(width 0.15494)
		(layer "In5.Cu")
		(net "SPI_PEX3_RST_N")
	)
	(segment
		(start 382.56972 -258.988814)
		(end 385.414266 -258.988814)
		(width 0.15494)
		(layer "In5.Cu")
		(net "SPI_PEX3_RST_N")
	)
	(segment
		(start 375.103136 -234.603036)
		(end 375.103136 -244.867684)
		(width 0.15494)
		(layer "In5.Cu")
		(net "SPI_PEX3_RST_N")
	)
	(segment
		(start 375.103136 -244.867684)
		(end 376.630692 -246.39524)
		(width 0.15494)
		(layer "In5.Cu")
		(net "SPI_PEX3_RST_N")
	)
	(segment
		(start 377.998482 -256.779522)
		(end 378.633228 -257.414268)
		(width 0.15494)
		(layer "In5.Cu")
		(net "SPI_PEX3_RST_N")
	)
	(segment
		(start 376.630692 -247.605804)
		(end 377.236482 -248.211594)
		(width 0.15494)
		(layer "In5.Cu")
		(net "SPI_PEX3_RST_N")
	)
	(segment
		(start 380.995174 -257.414268)
		(end 382.56972 -258.988814)
		(width 0.15494)
		(layer "In5.Cu")
		(net "SPI_PEX3_RST_N")
	)
	(segment
		(start 379.333506 -227.781866)
		(end 379.333506 -230.372666)
		(width 0.15494)
		(layer "In5.Cu")
		(net "SPI_PEX3_RST_N")
	)
	(segment
		(start 386.607812 -260.927342)
		(end 389.145018 -263.464548)
		(width 0.15494)
		(layer "In5.Cu")
		(net "SPI_PEX3_RST_N")
	)
	(segment
		(start 386.607812 -260.18236)
		(end 386.607812 -260.927342)
		(width 0.15494)
		(layer "In5.Cu")
		(net "SPI_PEX3_RST_N")
	)
	(segment
		(start 377.236482 -255.001522)
		(end 377.998482 -255.763522)
		(width 0.15494)
		(layer "In5.Cu")
		(net "SPI_PEX3_RST_N")
	)
	(segment
		(start 376.630692 -246.39524)
		(end 376.630692 -247.605804)
		(width 0.15494)
		(layer "In5.Cu")
		(net "SPI_PEX3_RST_N")
	)
	(segment
		(start 377.236482 -248.211594)
		(end 377.236482 -255.001522)
		(width 0.15494)
		(layer "In5.Cu")
		(net "SPI_PEX3_RST_N")
	)
	(segment
		(start 379.333506 -230.372666)
		(end 375.103136 -234.603036)
		(width 0.15494)
		(layer "In5.Cu")
		(net "SPI_PEX3_RST_N")
	)
	(segment
		(start 378.633228 -257.414268)
		(end 380.995174 -257.414268)
		(width 0.15494)
		(layer "In5.Cu")
		(net "SPI_PEX3_RST_N")
	)
	(segment
		(start 385.414266 -258.988814)
		(end 386.607812 -260.18236)
		(width 0.15494)
		(layer "In5.Cu")
		(net "SPI_PEX3_RST_N")
	)
	(segment
		(start 389.145018 -263.464548)
		(end 389.145018 -264.625328)
		(width 0.15494)
		(layer "In5.Cu")
		(net "SPI_PEX3_RST_N")
	)
	(segment
		(start 379.718316 -227.397056)
		(end 379.333506 -227.781866)
		(width 0.15494)
		(layer "In5.Cu")
		(net "SPI_PEX3_RST_N")
	)
	(segment
		(start 274.749768 -293.99992)
		(end 274.274788 -293.52494)
		(width 0.13208)
		(layer "F.Cu")
		(net "SPI_PEX2_RST_N")
	)
	(via
		(at 263.65454 -229.25151)
		(size 0.508)
		(drill 0.254)
		(layers "F.Cu" "B.Cu")
		(net "SPI_PEX2_RST_N")
	)
	(via
		(at 274.274788 -293.52494)
		(size 0.4064)
		(drill 0.2032)
		(layers "F.Cu" "B.Cu")
		(net "SPI_PEX2_RST_N")
	)
	(via
		(at 274.111212 -263.622536)
		(size 0.508)
		(drill 0.254)
		(layers "F.Cu" "B.Cu")
		(net "SPI_PEX2_RST_N")
	)
	(segment
		(start 273.789648 -293.0398)
		(end 272.20418 -293.0398)
		(width 0.13208)
		(layer "B.Cu")
		(net "SPI_PEX2_RST_N")
	)
	(segment
		(start 262.304276 -227.901246)
		(end 263.65454 -229.25151)
		(width 0.13208)
		(layer "B.Cu")
		(net "SPI_PEX2_RST_N")
	)
	(segment
		(start 271.3482 -291.8206)
		(end 270.6624 -291.1348)
		(width 0.13208)
		(layer "B.Cu")
		(net "SPI_PEX2_RST_N")
	)
	(segment
		(start 270.6624 -291.1348)
		(end 269.265146 -291.1348)
		(width 0.13208)
		(layer "B.Cu")
		(net "SPI_PEX2_RST_N")
	)
	(segment
		(start 270.183356 -267.88237)
		(end 270.183356 -266.666218)
		(width 0.13208)
		(layer "B.Cu")
		(net "SPI_PEX2_RST_N")
	)
	(segment
		(start 274.274788 -293.52494)
		(end 273.789648 -293.0398)
		(width 0.13208)
		(layer "B.Cu")
		(net "SPI_PEX2_RST_N")
	)
	(segment
		(start 269.0622 -269.003526)
		(end 270.183356 -267.88237)
		(width 0.13208)
		(layer "B.Cu")
		(net "SPI_PEX2_RST_N")
	)
	(segment
		(start 272.20418 -293.0398)
		(end 271.9832 -292.81882)
		(width 0.13208)
		(layer "B.Cu")
		(net "SPI_PEX2_RST_N")
	)
	(segment
		(start 273.227038 -263.622536)
		(end 274.111212 -263.622536)
		(width 0.13208)
		(layer "B.Cu")
		(net "SPI_PEX2_RST_N")
	)
	(segment
		(start 270.183356 -266.666218)
		(end 273.227038 -263.622536)
		(width 0.13208)
		(layer "B.Cu")
		(net "SPI_PEX2_RST_N")
	)
	(segment
		(start 269.265146 -291.1348)
		(end 269.0622 -290.931854)
		(width 0.13208)
		(layer "B.Cu")
		(net "SPI_PEX2_RST_N")
	)
	(segment
		(start 271.9832 -292.81882)
		(end 271.9832 -292.5826)
		(width 0.13208)
		(layer "B.Cu")
		(net "SPI_PEX2_RST_N")
	)
	(segment
		(start 271.3482 -291.9476)
		(end 271.3482 -291.8206)
		(width 0.13208)
		(layer "B.Cu")
		(net "SPI_PEX2_RST_N")
	)
	(segment
		(start 262.304276 -226.78263)
		(end 262.304276 -227.901246)
		(width 0.13208)
		(layer "B.Cu")
		(net "SPI_PEX2_RST_N")
	)
	(segment
		(start 269.0622 -290.931854)
		(end 269.0622 -269.003526)
		(width 0.13208)
		(layer "B.Cu")
		(net "SPI_PEX2_RST_N")
	)
	(segment
		(start 271.9832 -292.5826)
		(end 271.3482 -291.9476)
		(width 0.13208)
		(layer "B.Cu")
		(net "SPI_PEX2_RST_N")
	)
	(segment
		(start 274.755356 -262.978392)
		(end 274.111212 -263.622536)
		(width 0.15494)
		(layer "In5.Cu")
		(net "SPI_PEX2_RST_N")
	)
	(segment
		(start 266.722606 -232.319576)
		(end 266.722606 -245.838472)
		(width 0.15494)
		(layer "In5.Cu")
		(net "SPI_PEX2_RST_N")
	)
	(segment
		(start 266.722606 -245.838472)
		(end 270.235172 -249.351038)
		(width 0.15494)
		(layer "In5.Cu")
		(net "SPI_PEX2_RST_N")
	)
	(segment
		(start 270.235172 -255.810004)
		(end 270.793464 -256.368296)
		(width 0.15494)
		(layer "In5.Cu")
		(net "SPI_PEX2_RST_N")
	)
	(segment
		(start 270.793464 -256.368296)
		(end 270.793464 -257.407664)
		(width 0.15494)
		(layer "In5.Cu")
		(net "SPI_PEX2_RST_N")
	)
	(segment
		(start 274.755356 -261.369556)
		(end 274.755356 -262.978392)
		(width 0.15494)
		(layer "In5.Cu")
		(net "SPI_PEX2_RST_N")
	)
	(segment
		(start 270.235172 -249.351038)
		(end 270.235172 -255.810004)
		(width 0.15494)
		(layer "In5.Cu")
		(net "SPI_PEX2_RST_N")
	)
	(segment
		(start 270.793464 -257.407664)
		(end 274.755356 -261.369556)
		(width 0.15494)
		(layer "In5.Cu")
		(net "SPI_PEX2_RST_N")
	)
	(segment
		(start 263.65454 -229.25151)
		(end 266.722606 -232.319576)
		(width 0.15494)
		(layer "In5.Cu")
		(net "SPI_PEX2_RST_N")
	)
	(segment
		(start 158.649924 -293.99992)
		(end 158.174944 -293.52494)
		(width 0.13208)
		(layer "F.Cu")
		(net "SPI_PEX1_RST_N")
	)
	(via
		(at 158.174944 -293.52494)
		(size 0.4064)
		(drill 0.2032)
		(layers "F.Cu" "B.Cu")
		(net "SPI_PEX1_RST_N")
	)
	(via
		(at 147.403058 -226.568)
		(size 0.508)
		(drill 0.254)
		(layers "F.Cu" "B.Cu")
		(net "SPI_PEX1_RST_N")
	)
	(via
		(at 156.945076 -265.16457)
		(size 0.508)
		(drill 0.254)
		(layers "F.Cu" "B.Cu")
		(net "SPI_PEX1_RST_N")
	)
	(segment
		(start 155.8036 -292.480746)
		(end 154.84729 -291.524436)
		(width 0.13208)
		(layer "B.Cu")
		(net "SPI_PEX1_RST_N")
	)
	(segment
		(start 153.252678 -291.090096)
		(end 152.979374 -290.816792)
		(width 0.13208)
		(layer "B.Cu")
		(net "SPI_PEX1_RST_N")
	)
	(segment
		(start 152.979374 -290.816792)
		(end 152.979374 -269.089124)
		(width 0.13208)
		(layer "B.Cu")
		(net "SPI_PEX1_RST_N")
	)
	(segment
		(start 154.84729 -291.524436)
		(end 154.84729 -291.38372)
		(width 0.13208)
		(layer "B.Cu")
		(net "SPI_PEX1_RST_N")
	)
	(segment
		(start 155.8036 -292.810946)
		(end 155.8036 -292.480746)
		(width 0.13208)
		(layer "B.Cu")
		(net "SPI_PEX1_RST_N")
	)
	(segment
		(start 152.979374 -269.089124)
		(end 154.143456 -267.925042)
		(width 0.13208)
		(layer "B.Cu")
		(net "SPI_PEX1_RST_N")
	)
	(segment
		(start 157.747462 -293.0398)
		(end 156.032454 -293.0398)
		(width 0.13208)
		(layer "B.Cu")
		(net "SPI_PEX1_RST_N")
	)
	(segment
		(start 146.419062 -226.568)
		(end 147.403058 -226.568)
		(width 0.13208)
		(layer "B.Cu")
		(net "SPI_PEX1_RST_N")
	)
	(segment
		(start 158.174944 -293.467282)
		(end 157.747462 -293.0398)
		(width 0.13208)
		(layer "B.Cu")
		(net "SPI_PEX1_RST_N")
	)
	(segment
		(start 154.143456 -266.624562)
		(end 155.067254 -265.700764)
		(width 0.13208)
		(layer "B.Cu")
		(net "SPI_PEX1_RST_N")
	)
	(segment
		(start 155.067254 -265.700764)
		(end 156.408882 -265.700764)
		(width 0.13208)
		(layer "B.Cu")
		(net "SPI_PEX1_RST_N")
	)
	(segment
		(start 154.84729 -291.38372)
		(end 154.553666 -291.090096)
		(width 0.13208)
		(layer "B.Cu")
		(net "SPI_PEX1_RST_N")
	)
	(segment
		(start 156.032454 -293.0398)
		(end 155.8036 -292.810946)
		(width 0.13208)
		(layer "B.Cu")
		(net "SPI_PEX1_RST_N")
	)
	(segment
		(start 154.143456 -267.925042)
		(end 154.143456 -266.624562)
		(width 0.13208)
		(layer "B.Cu")
		(net "SPI_PEX1_RST_N")
	)
	(segment
		(start 146.204432 -226.78263)
		(end 146.419062 -226.568)
		(width 0.13208)
		(layer "B.Cu")
		(net "SPI_PEX1_RST_N")
	)
	(segment
		(start 154.553666 -291.090096)
		(end 153.252678 -291.090096)
		(width 0.13208)
		(layer "B.Cu")
		(net "SPI_PEX1_RST_N")
	)
	(segment
		(start 156.408882 -265.700764)
		(end 156.945076 -265.16457)
		(width 0.13208)
		(layer "B.Cu")
		(net "SPI_PEX1_RST_N")
	)
	(segment
		(start 158.174944 -293.52494)
		(end 158.174944 -293.467282)
		(width 0.13208)
		(layer "B.Cu")
		(net "SPI_PEX1_RST_N")
	)
	(segment
		(start 151.515064 -237.16869)
		(end 146.426174 -232.0798)
		(width 0.15494)
		(layer "In5.Cu")
		(net "SPI_PEX1_RST_N")
	)
	(segment
		(start 143.098012 -258.268216)
		(end 143.098012 -256.394204)
		(width 0.15494)
		(layer "In5.Cu")
		(net "SPI_PEX1_RST_N")
	)
	(segment
		(start 156.716476 -264.93597)
		(end 156.716476 -263.898126)
		(width 0.15494)
		(layer "In5.Cu")
		(net "SPI_PEX1_RST_N")
	)
	(segment
		(start 142.008606 -255.8542)
		(end 140.594588 -254.440182)
		(width 0.15494)
		(layer "In5.Cu")
		(net "SPI_PEX1_RST_N")
	)
	(segment
		(start 146.426174 -229.033324)
		(end 147.403058 -228.05644)
		(width 0.15494)
		(layer "In5.Cu")
		(net "SPI_PEX1_RST_N")
	)
	(segment
		(start 154.15895 -261.3406)
		(end 150.132034 -261.3406)
		(width 0.15494)
		(layer "In5.Cu")
		(net "SPI_PEX1_RST_N")
	)
	(segment
		(start 151.515064 -240.512092)
		(end 151.515064 -237.16869)
		(width 0.15494)
		(layer "In5.Cu")
		(net "SPI_PEX1_RST_N")
	)
	(segment
		(start 144.658334 -258.848352)
		(end 143.678148 -258.848352)
		(width 0.15494)
		(layer "In5.Cu")
		(net "SPI_PEX1_RST_N")
	)
	(segment
		(start 144.902428 -259.092446)
		(end 144.658334 -258.848352)
		(width 0.15494)
		(layer "In5.Cu")
		(net "SPI_PEX1_RST_N")
	)
	(segment
		(start 147.88388 -259.092446)
		(end 144.902428 -259.092446)
		(width 0.15494)
		(layer "In5.Cu")
		(net "SPI_PEX1_RST_N")
	)
	(segment
		(start 139.425172 -247.899428)
		(end 140.41374 -246.91086)
		(width 0.15494)
		(layer "In5.Cu")
		(net "SPI_PEX1_RST_N")
	)
	(segment
		(start 151.423878 -246.91086)
		(end 152.355296 -245.979442)
		(width 0.15494)
		(layer "In5.Cu")
		(net "SPI_PEX1_RST_N")
	)
	(segment
		(start 156.716476 -263.898126)
		(end 154.15895 -261.3406)
		(width 0.15494)
		(layer "In5.Cu")
		(net "SPI_PEX1_RST_N")
	)
	(segment
		(start 140.41374 -246.91086)
		(end 151.423878 -246.91086)
		(width 0.15494)
		(layer "In5.Cu")
		(net "SPI_PEX1_RST_N")
	)
	(segment
		(start 150.132034 -261.3406)
		(end 147.88388 -259.092446)
		(width 0.15494)
		(layer "In5.Cu")
		(net "SPI_PEX1_RST_N")
	)
	(segment
		(start 152.355296 -245.979442)
		(end 152.355296 -245.287546)
		(width 0.15494)
		(layer "In5.Cu")
		(net "SPI_PEX1_RST_N")
	)
	(segment
		(start 152.355296 -245.287546)
		(end 152.56891 -245.073932)
		(width 0.15494)
		(layer "In5.Cu")
		(net "SPI_PEX1_RST_N")
	)
	(segment
		(start 143.678148 -258.848352)
		(end 143.098012 -258.268216)
		(width 0.15494)
		(layer "In5.Cu")
		(net "SPI_PEX1_RST_N")
	)
	(segment
		(start 147.403058 -228.05644)
		(end 147.403058 -226.568)
		(width 0.15494)
		(layer "In5.Cu")
		(net "SPI_PEX1_RST_N")
	)
	(segment
		(start 140.594588 -254.440182)
		(end 139.784582 -254.440182)
		(width 0.15494)
		(layer "In5.Cu")
		(net "SPI_PEX1_RST_N")
	)
	(segment
		(start 156.945076 -265.16457)
		(end 156.716476 -264.93597)
		(width 0.15494)
		(layer "In5.Cu")
		(net "SPI_PEX1_RST_N")
	)
	(segment
		(start 143.098012 -256.394204)
		(end 142.558008 -255.8542)
		(width 0.15494)
		(layer "In5.Cu")
		(net "SPI_PEX1_RST_N")
	)
	(segment
		(start 152.56891 -241.565938)
		(end 151.515064 -240.512092)
		(width 0.15494)
		(layer "In5.Cu")
		(net "SPI_PEX1_RST_N")
	)
	(segment
		(start 146.426174 -232.0798)
		(end 146.426174 -229.033324)
		(width 0.15494)
		(layer "In5.Cu")
		(net "SPI_PEX1_RST_N")
	)
	(segment
		(start 139.425172 -254.080772)
		(end 139.425172 -247.899428)
		(width 0.15494)
		(layer "In5.Cu")
		(net "SPI_PEX1_RST_N")
	)
	(segment
		(start 139.784582 -254.440182)
		(end 139.425172 -254.080772)
		(width 0.15494)
		(layer "In5.Cu")
		(net "SPI_PEX1_RST_N")
	)
	(segment
		(start 142.558008 -255.8542)
		(end 142.008606 -255.8542)
		(width 0.15494)
		(layer "In5.Cu")
		(net "SPI_PEX1_RST_N")
	)
	(segment
		(start 152.56891 -245.073932)
		(end 152.56891 -241.565938)
		(width 0.15494)
		(layer "In5.Cu")
		(net "SPI_PEX1_RST_N")
	)
	(segment
		(start 26.768298 -224.536)
		(end 28.165298 -224.536)
		(width 0.13208)
		(layer "F.Cu")
		(net "SPI_PEX0_RST_R_N")
	)
	(segment
		(start 25.827228 -223.59493)
		(end 26.768298 -224.536)
		(width 0.13208)
		(layer "F.Cu")
		(net "SPI_PEX0_RST_R_N")
	)
	(segment
		(start 24.62022 -223.59493)
		(end 25.827228 -223.59493)
		(width 0.13208)
		(layer "F.Cu")
		(net "SPI_PEX0_RST_R_N")
	)
	(via
		(at 28.165298 -224.536)
		(size 0.508)
		(drill 0.254)
		(layers "F.Cu" "B.Cu")
		(net "SPI_PEX0_RST_R_N")
	)
	(segment
		(start 29.341572 -224.75063)
		(end 29.341572 -225.76663)
		(width 0.13208)
		(layer "B.Cu")
		(net "SPI_PEX0_RST_R_N")
	)
	(segment
		(start 29.126942 -224.536)
		(end 28.165298 -224.536)
		(width 0.13208)
		(layer "B.Cu")
		(net "SPI_PEX0_RST_R_N")
	)
	(segment
		(start 29.341572 -225.76663)
		(end 29.341572 -226.78263)
		(width 0.13208)
		(layer "B.Cu")
		(net "SPI_PEX0_RST_R_N")
	)
	(segment
		(start 29.341572 -224.75063)
		(end 29.126942 -224.536)
		(width 0.13208)
		(layer "B.Cu")
		(net "SPI_PEX0_RST_R_N")
	)
	(segment
		(start 42.549826 -293.99992)
		(end 42.074846 -293.52494)
		(width 0.13208)
		(layer "F.Cu")
		(net "SPI_PEX0_RST_N")
	)
	(via
		(at 31.340298 -226.568)
		(size 0.508)
		(drill 0.254)
		(layers "F.Cu" "B.Cu")
		(net "SPI_PEX0_RST_N")
	)
	(via
		(at 40.844978 -265.16457)
		(size 0.508)
		(drill 0.254)
		(layers "F.Cu" "B.Cu")
		(net "SPI_PEX0_RST_N")
	)
	(via
		(at 42.074846 -293.52494)
		(size 0.4064)
		(drill 0.2032)
		(layers "F.Cu" "B.Cu")
		(net "SPI_PEX0_RST_N")
	)
	(segment
		(start 38.453568 -291.090096)
		(end 38.072822 -291.090096)
		(width 0.13208)
		(layer "B.Cu")
		(net "SPI_PEX0_RST_N")
	)
	(segment
		(start 42.074846 -293.52494)
		(end 42.074846 -293.467282)
		(width 0.13208)
		(layer "B.Cu")
		(net "SPI_PEX0_RST_N")
	)
	(segment
		(start 38.747192 -291.38372)
		(end 38.453568 -291.090096)
		(width 0.13208)
		(layer "B.Cu")
		(net "SPI_PEX0_RST_N")
	)
	(segment
		(start 37.822378 -288.640266)
		(end 37.548058 -288.365946)
		(width 0.13208)
		(layer "B.Cu")
		(net "SPI_PEX0_RST_N")
	)
	(segment
		(start 37.126672 -288.365946)
		(end 36.879276 -288.11855)
		(width 0.13208)
		(layer "B.Cu")
		(net "SPI_PEX0_RST_N")
	)
	(segment
		(start 41.621964 -293.0144)
		(end 39.9288 -293.0144)
		(width 0.13208)
		(layer "B.Cu")
		(net "SPI_PEX0_RST_N")
	)
	(segment
		(start 38.747192 -291.553392)
		(end 38.747192 -291.38372)
		(width 0.13208)
		(layer "B.Cu")
		(net "SPI_PEX0_RST_N")
	)
	(segment
		(start 39.9288 -293.0144)
		(end 39.6748 -292.7604)
		(width 0.13208)
		(layer "B.Cu")
		(net "SPI_PEX0_RST_N")
	)
	(segment
		(start 36.879276 -268.971268)
		(end 38.048438 -267.802106)
		(width 0.13208)
		(layer "B.Cu")
		(net "SPI_PEX0_RST_N")
	)
	(segment
		(start 38.048438 -267.802106)
		(end 38.048438 -266.62253)
		(width 0.13208)
		(layer "B.Cu")
		(net "SPI_PEX0_RST_N")
	)
	(segment
		(start 42.074846 -293.467282)
		(end 41.621964 -293.0144)
		(width 0.13208)
		(layer "B.Cu")
		(net "SPI_PEX0_RST_N")
	)
	(segment
		(start 38.048438 -266.62253)
		(end 38.970204 -265.700764)
		(width 0.13208)
		(layer "B.Cu")
		(net "SPI_PEX0_RST_N")
	)
	(segment
		(start 30.356302 -226.568)
		(end 31.340298 -226.568)
		(width 0.13208)
		(layer "B.Cu")
		(net "SPI_PEX0_RST_N")
	)
	(segment
		(start 38.072822 -291.090096)
		(end 37.822378 -290.839652)
		(width 0.13208)
		(layer "B.Cu")
		(net "SPI_PEX0_RST_N")
	)
	(segment
		(start 37.822378 -290.839652)
		(end 37.822378 -288.640266)
		(width 0.13208)
		(layer "B.Cu")
		(net "SPI_PEX0_RST_N")
	)
	(segment
		(start 40.308784 -265.700764)
		(end 40.844978 -265.16457)
		(width 0.13208)
		(layer "B.Cu")
		(net "SPI_PEX0_RST_N")
	)
	(segment
		(start 39.6748 -292.481)
		(end 38.747192 -291.553392)
		(width 0.13208)
		(layer "B.Cu")
		(net "SPI_PEX0_RST_N")
	)
	(segment
		(start 30.141672 -226.78263)
		(end 30.356302 -226.568)
		(width 0.13208)
		(layer "B.Cu")
		(net "SPI_PEX0_RST_N")
	)
	(segment
		(start 37.548058 -288.365946)
		(end 37.126672 -288.365946)
		(width 0.13208)
		(layer "B.Cu")
		(net "SPI_PEX0_RST_N")
	)
	(segment
		(start 39.6748 -292.7604)
		(end 39.6748 -292.481)
		(width 0.13208)
		(layer "B.Cu")
		(net "SPI_PEX0_RST_N")
	)
	(segment
		(start 36.879276 -288.11855)
		(end 36.879276 -268.971268)
		(width 0.13208)
		(layer "B.Cu")
		(net "SPI_PEX0_RST_N")
	)
	(segment
		(start 38.970204 -265.700764)
		(end 40.308784 -265.700764)
		(width 0.13208)
		(layer "B.Cu")
		(net "SPI_PEX0_RST_N")
	)
	(segment
		(start 24.479504 -233.428794)
		(end 31.340298 -226.568)
		(width 0.15494)
		(layer "In5.Cu")
		(net "SPI_PEX0_RST_N")
	)
	(segment
		(start 39.25697 -261.98703)
		(end 32.965136 -261.98703)
		(width 0.15494)
		(layer "In5.Cu")
		(net "SPI_PEX0_RST_N")
	)
	(segment
		(start 20.666456 -259.930138)
		(end 20.666456 -246.21109)
		(width 0.15494)
		(layer "In5.Cu")
		(net "SPI_PEX0_RST_N")
	)
	(segment
		(start 23.388574 -261.903972)
		(end 22.64029 -261.903972)
		(width 0.15494)
		(layer "In5.Cu")
		(net "SPI_PEX0_RST_N")
	)
	(segment
		(start 20.666456 -246.21109)
		(end 24.479504 -242.398042)
		(width 0.15494)
		(layer "In5.Cu")
		(net "SPI_PEX0_RST_N")
	)
	(segment
		(start 40.844978 -263.575038)
		(end 39.25697 -261.98703)
		(width 0.15494)
		(layer "In5.Cu")
		(net "SPI_PEX0_RST_N")
	)
	(segment
		(start 40.844978 -265.16457)
		(end 40.844978 -263.575038)
		(width 0.15494)
		(layer "In5.Cu")
		(net "SPI_PEX0_RST_N")
	)
	(segment
		(start 22.64029 -261.903972)
		(end 20.666456 -259.930138)
		(width 0.15494)
		(layer "In5.Cu")
		(net "SPI_PEX0_RST_N")
	)
	(segment
		(start 32.526986 -262.42518)
		(end 23.909782 -262.42518)
		(width 0.15494)
		(layer "In5.Cu")
		(net "SPI_PEX0_RST_N")
	)
	(segment
		(start 24.479504 -242.398042)
		(end 24.479504 -233.428794)
		(width 0.15494)
		(layer "In5.Cu")
		(net "SPI_PEX0_RST_N")
	)
	(segment
		(start 32.965136 -261.98703)
		(end 32.526986 -262.42518)
		(width 0.15494)
		(layer "In5.Cu")
		(net "SPI_PEX0_RST_N")
	)
	(segment
		(start 23.909782 -262.42518)
		(end 23.388574 -261.903972)
		(width 0.15494)
		(layer "In5.Cu")
		(net "SPI_PEX0_RST_N")
	)
	(segment
		(start 213.257892 -241.083084)
		(end 213.130638 -241.210338)
		(width 0.13208)
		(layer "F.Cu")
		(net "PWRGD_P1V8_PEX_R1")
	)
	(segment
		(start 213.467442 -243.616226)
		(end 213.467442 -243.089938)
		(width 0.13208)
		(layer "F.Cu")
		(net "PWRGD_P1V8_PEX_R1")
	)
	(segment
		(start 214.085424 -242.471956)
		(end 214.085424 -241.083084)
		(width 0.13208)
		(layer "F.Cu")
		(net "PWRGD_P1V8_PEX_R1")
	)
	(segment
		(start 213.467442 -243.089938)
		(end 214.085424 -242.471956)
		(width 0.13208)
		(layer "F.Cu")
		(net "PWRGD_P1V8_PEX_R1")
	)
	(segment
		(start 214.085424 -241.083084)
		(end 213.257892 -241.083084)
		(width 0.13208)
		(layer "F.Cu")
		(net "PWRGD_P1V8_PEX_R1")
	)
	(segment
		(start 213.130638 -241.210338)
		(end 213.130638 -242.03787)
		(width 0.13208)
		(layer "F.Cu")
		(net "PWRGD_P1V8_PEX_R1")
	)
	(via
		(at 214.085424 -241.083084)
		(size 0.508)
		(drill 0.254)
		(layers "F.Cu" "B.Cu")
		(net "PWRGD_P1V8_PEX_R1")
	)
	(segment
		(start 459.82763 -112.547654)
		(end 460.211932 -112.547654)
		(width 0.254)
		(layer "F.Cu")
		(net "P12V_NIC7_CO_ISET_R")
	)
	(segment
		(start 459.576932 -112.296956)
		(end 459.82763 -112.547654)
		(width 0.254)
		(layer "F.Cu")
		(net "P12V_NIC7_CO_ISET_R")
	)
	(segment
		(start 458.935836 -112.296956)
		(end 459.576932 -112.296956)
		(width 0.254)
		(layer "F.Cu")
		(net "P12V_NIC7_CO_ISET_R")
	)
	(via
		(at 459.576932 -112.296956)
		(size 0.508)
		(drill 0.254)
		(layers "F.Cu" "B.Cu")
		(net "P12V_NIC7_CO_ISET_R")
	)
	(via
		(at 241.469418 -156.69387)
		(size 0.508)
		(drill 0.254)
		(layers "F.Cu" "B.Cu")
		(net "P12V_NIC4_CO_OV_FB")
	)
	(segment
		(start 459.571852 -113.568734)
		(end 459.576932 -113.563654)
		(width 0.254)
		(layer "F.Cu")
		(net "P12V_NIC7_CO_SS")
	)
	(segment
		(start 457.31303 -112.285526)
		(end 457.874624 -112.285526)
		(width 0.254)
		(layer "F.Cu")
		(net "P12V_NIC7_CO_SS")
	)
	(segment
		(start 459.293468 -113.563654)
		(end 459.566772 -113.563654)
		(width 0.254)
		(layer "F.Cu")
		(net "P12V_NIC7_CO_SS")
	)
	(segment
		(start 457.874624 -112.285526)
		(end 458.114908 -112.385094)
		(width 0.254)
		(layer "F.Cu")
		(net "P12V_NIC7_CO_SS")
	)
	(segment
		(start 458.114908 -112.385094)
		(end 459.293468 -113.563654)
		(width 0.254)
		(layer "F.Cu")
		(net "P12V_NIC7_CO_SS")
	)
	(segment
		(start 459.576932 -113.563654)
		(end 460.211932 -113.563654)
		(width 0.254)
		(layer "F.Cu")
		(net "P12V_NIC7_CO_SS")
	)
	(segment
		(start 459.566772 -113.563654)
		(end 459.571852 -113.568734)
		(width 0.254)
		(layer "F.Cu")
		(net "P12V_NIC7_CO_SS")
	)
	(via
		(at 459.571852 -113.568734)
		(size 0.508)
		(drill 0.254)
		(layers "F.Cu" "B.Cu")
		(net "P12V_NIC7_CO_SS")
	)
	(via
		(at 242.45189 -155.079192)
		(size 0.508)
		(drill 0.254)
		(layers "F.Cu" "B.Cu")
		(net "P12V_NIC4_CO_AVIN_PD")
	)
	(segment
		(start 361.29468 -159.679894)
		(end 362.064808 -160.450022)
		(width 0.13208)
		(layer "F.Cu")
		(net "P12V_NIC6_CO_TIMER")
	)
	(segment
		(start 362.064808 -160.450022)
		(end 362.064808 -160.902142)
		(width 0.13208)
		(layer "F.Cu")
		(net "P12V_NIC6_CO_TIMER")
	)
	(segment
		(start 362.064808 -160.902142)
		(end 362.064808 -161.603944)
		(width 0.13208)
		(layer "F.Cu")
		(net "P12V_NIC6_CO_TIMER")
	)
	(segment
		(start 361.29468 -158.705042)
		(end 361.29468 -159.679894)
		(width 0.13208)
		(layer "F.Cu")
		(net "P12V_NIC6_CO_TIMER")
	)
	(via
		(at 362.064808 -160.902142)
		(size 0.508)
		(drill 0.254)
		(layers "F.Cu" "B.Cu")
		(net "P12V_NIC6_CO_TIMER")
	)
	(segment
		(start 343.354914 -114.960654)
		(end 343.473786 -114.960654)
		(width 0.254)
		(layer "F.Cu")
		(net "P12V_NIC5_CO_IMON_VR")
	)
	(segment
		(start 341.680038 -113.285778)
		(end 343.354914 -114.960654)
		(width 0.254)
		(layer "F.Cu")
		(net "P12V_NIC5_CO_IMON_VR")
	)
	(segment
		(start 341.212932 -113.285778)
		(end 341.680038 -113.285778)
		(width 0.254)
		(layer "F.Cu")
		(net "P12V_NIC5_CO_IMON_VR")
	)
	(segment
		(start 343.473786 -114.960654)
		(end 344.111834 -114.960654)
		(width 0.254)
		(layer "F.Cu")
		(net "P12V_NIC5_CO_IMON_VR")
	)
	(via
		(at 343.473786 -114.960654)
		(size 0.508)
		(drill 0.254)
		(layers "F.Cu" "B.Cu")
		(net "P12V_NIC5_CO_IMON_VR")
	)
	(segment
		(start 358.319324 -159.439102)
		(end 357.59009 -159.439102)
		(width 0.254)
		(layer "F.Cu")
		(net "P12V_NIC6_CO_FLTB")
	)
	(segment
		(start 358.794812 -158.963614)
		(end 358.319324 -159.439102)
		(width 0.254)
		(layer "F.Cu")
		(net "P12V_NIC6_CO_FLTB")
	)
	(segment
		(start 358.794812 -158.705042)
		(end 358.794812 -158.963614)
		(width 0.254)
		(layer "F.Cu")
		(net "P12V_NIC6_CO_FLTB")
	)
	(segment
		(start 357.59009 -159.439102)
		(end 357.184198 -159.844994)
		(width 0.254)
		(layer "F.Cu")
		(net "P12V_NIC6_CO_FLTB")
	)
	(segment
		(start 357.184198 -159.844994)
		(end 356.749858 -159.844994)
		(width 0.254)
		(layer "F.Cu")
		(net "P12V_NIC6_CO_FLTB")
	)
	(via
		(at 357.59009 -159.439102)
		(size 0.508)
		(drill 0.254)
		(layers "F.Cu" "B.Cu")
		(net "P12V_NIC6_CO_FLTB")
	)
	(segment
		(start 342.039702 -111.785654)
		(end 342.20404 -111.785654)
		(width 0.254)
		(layer "F.Cu")
		(net "P12V_NIC5_CO_ISET")
	)
	(segment
		(start 341.212932 -111.785654)
		(end 342.039702 -111.785654)
		(width 0.254)
		(layer "F.Cu")
		(net "P12V_NIC5_CO_ISET")
	)
	(segment
		(start 344.111834 -111.531654)
		(end 344.077036 -111.496856)
		(width 0.254)
		(layer "F.Cu")
		(net "P12V_NIC5_CO_ISET")
	)
	(segment
		(start 342.492838 -111.496856)
		(end 342.835738 -111.496856)
		(width 0.254)
		(layer "F.Cu")
		(net "P12V_NIC5_CO_ISET")
	)
	(segment
		(start 344.077036 -111.496856)
		(end 342.835738 -111.496856)
		(width 0.254)
		(layer "F.Cu")
		(net "P12V_NIC5_CO_ISET")
	)
	(segment
		(start 342.20404 -111.785654)
		(end 342.492838 -111.496856)
		(width 0.254)
		(layer "F.Cu")
		(net "P12V_NIC5_CO_ISET")
	)
	(via
		(at 342.039702 -111.785654)
		(size 0.508)
		(drill 0.254)
		(layers "F.Cu" "B.Cu")
		(net "P12V_NIC5_CO_ISET")
	)
	(via
		(at 455.301858 -115.010946)
		(size 0.508)
		(drill 0.254)
		(layers "F.Cu" "B.Cu")
		(net "P12V_NIC7_CO_OV_FB")
	)
	(via
		(at 453.68718 -114.028474)
		(size 0.508)
		(drill 0.254)
		(layers "F.Cu" "B.Cu")
		(net "P12V_NIC7_CO_AVIN_PD")
	)
	(segment
		(start 340.320884 -115.306094)
		(end 340.320884 -115.830604)
		(width 0.13208)
		(layer "F.Cu")
		(net "PWRGD_P12V_NIC5_CO")
	)
	(segment
		(start 340.312756 -114.803174)
		(end 340.56828 -115.058698)
		(width 0.13208)
		(layer "F.Cu")
		(net "PWRGD_P12V_NIC5_CO")
	)
	(segment
		(start 340.56828 -115.058698)
		(end 340.320884 -115.306094)
		(width 0.13208)
		(layer "F.Cu")
		(net "PWRGD_P12V_NIC5_CO")
	)
	(segment
		(start 341.336884 -115.830604)
		(end 340.320884 -115.830604)
		(width 0.13208)
		(layer "F.Cu")
		(net "PWRGD_P12V_NIC5_CO")
	)
	(segment
		(start 340.312756 -114.1857)
		(end 340.312756 -114.803174)
		(width 0.13208)
		(layer "F.Cu")
		(net "PWRGD_P12V_NIC5_CO")
	)
	(via
		(at 340.56828 -115.058698)
		(size 0.508)
		(drill 0.254)
		(layers "F.Cu" "B.Cu")
		(net "PWRGD_P12V_NIC5_CO")
	)
	(via
		(at 357.569516 -156.69387)
		(size 0.508)
		(drill 0.254)
		(layers "F.Cu" "B.Cu")
		(net "P12V_NIC6_CO_OV_FB")
	)
	(segment
		(start 342.835738 -112.296956)
		(end 343.476834 -112.296956)
		(width 0.254)
		(layer "F.Cu")
		(net "P12V_NIC5_CO_ISET_R")
	)
	(segment
		(start 343.727532 -112.547654)
		(end 344.111834 -112.547654)
		(width 0.254)
		(layer "F.Cu")
		(net "P12V_NIC5_CO_ISET_R")
	)
	(segment
		(start 343.476834 -112.296956)
		(end 343.727532 -112.547654)
		(width 0.254)
		(layer "F.Cu")
		(net "P12V_NIC5_CO_ISET_R")
	)
	(via
		(at 343.476834 -112.296956)
		(size 0.508)
		(drill 0.254)
		(layers "F.Cu" "B.Cu")
		(net "P12V_NIC5_CO_ISET_R")
	)
	(segment
		(start 459.14564 -109.626654)
		(end 459.021434 -109.502448)
		(width 0.13208)
		(layer "F.Cu")
		(net "P12V_NIC7_CO_EN")
	)
	(segment
		(start 460.211932 -108.737654)
		(end 460.211932 -109.626654)
		(width 0.13208)
		(layer "F.Cu")
		(net "P12V_NIC7_CO_EN")
	)
	(segment
		(start 459.021434 -109.502448)
		(end 458.09662 -109.502448)
		(width 0.13208)
		(layer "F.Cu")
		(net "P12V_NIC7_CO_EN")
	)
	(segment
		(start 460.211932 -109.626654)
		(end 459.14564 -109.626654)
		(width 0.13208)
		(layer "F.Cu")
		(net "P12V_NIC7_CO_EN")
	)
	(segment
		(start 457.81341 -109.785658)
		(end 458.09662 -109.502448)
		(width 0.13208)
		(layer "F.Cu")
		(net "P12V_NIC7_CO_EN")
	)
	(segment
		(start 457.287884 -109.785658)
		(end 457.81341 -109.785658)
		(width 0.13208)
		(layer "F.Cu")
		(net "P12V_NIC7_CO_EN")
	)
	(segment
		(start 460.211932 -107.848654)
		(end 460.211932 -108.737654)
		(width 0.13208)
		(layer "F.Cu")
		(net "P12V_NIC7_CO_EN")
	)
	(via
		(at 458.09662 -109.502448)
		(size 0.508)
		(drill 0.254)
		(layers "F.Cu" "B.Cu")
		(net "P12V_NIC7_CO_EN")
	)
	(segment
		(start 359.016808 -160.958784)
		(end 359.011728 -160.963864)
		(width 0.254)
		(layer "F.Cu")
		(net "P12V_NIC6_CO_SS")
	)
	(segment
		(start 360.294936 -158.705042)
		(end 360.294936 -159.266636)
		(width 0.254)
		(layer "F.Cu")
		(net "P12V_NIC6_CO_SS")
	)
	(segment
		(start 359.016808 -160.968944)
		(end 359.016808 -161.603944)
		(width 0.254)
		(layer "F.Cu")
		(net "P12V_NIC6_CO_SS")
	)
	(segment
		(start 360.195368 -159.50692)
		(end 359.016808 -160.68548)
		(width 0.254)
		(layer "F.Cu")
		(net "P12V_NIC6_CO_SS")
	)
	(segment
		(start 360.294936 -159.266636)
		(end 360.195368 -159.50692)
		(width 0.254)
		(layer "F.Cu")
		(net "P12V_NIC6_CO_SS")
	)
	(segment
		(start 359.016808 -160.68548)
		(end 359.016808 -160.958784)
		(width 0.254)
		(layer "F.Cu")
		(net "P12V_NIC6_CO_SS")
	)
	(segment
		(start 359.011728 -160.963864)
		(end 359.016808 -160.968944)
		(width 0.254)
		(layer "F.Cu")
		(net "P12V_NIC6_CO_SS")
	)
	(via
		(at 359.011728 -160.963864)
		(size 0.508)
		(drill 0.254)
		(layers "F.Cu" "B.Cu")
		(net "P12V_NIC6_CO_SS")
	)
	(segment
		(start 458.304138 -111.785654)
		(end 458.592936 -111.496856)
		(width 0.254)
		(layer "F.Cu")
		(net "P12V_NIC7_CO_ISET")
	)
	(segment
		(start 458.592936 -111.496856)
		(end 458.935836 -111.496856)
		(width 0.254)
		(layer "F.Cu")
		(net "P12V_NIC7_CO_ISET")
	)
	(segment
		(start 460.177134 -111.496856)
		(end 460.211932 -111.531654)
		(width 0.254)
		(layer "F.Cu")
		(net "P12V_NIC7_CO_ISET")
	)
	(segment
		(start 457.31303 -111.785654)
		(end 458.1398 -111.785654)
		(width 0.254)
		(layer "F.Cu")
		(net "P12V_NIC7_CO_ISET")
	)
	(segment
		(start 458.935836 -111.496856)
		(end 460.177134 -111.496856)
		(width 0.254)
		(layer "F.Cu")
		(net "P12V_NIC7_CO_ISET")
	)
	(segment
		(start 458.1398 -111.785654)
		(end 458.304138 -111.785654)
		(width 0.254)
		(layer "F.Cu")
		(net "P12V_NIC7_CO_ISET")
	)
	(via
		(at 458.1398 -111.785654)
		(size 0.508)
		(drill 0.254)
		(layers "F.Cu" "B.Cu")
		(net "P12V_NIC7_CO_ISET")
	)
	(segment
		(start 359.294684 -159.172148)
		(end 359.294684 -158.705042)
		(width 0.254)
		(layer "F.Cu")
		(net "P12V_NIC6_CO_IMON_VR")
	)
	(segment
		(start 357.619808 -160.965896)
		(end 357.619808 -160.847024)
		(width 0.254)
		(layer "F.Cu")
		(net "P12V_NIC6_CO_IMON_VR")
	)
	(segment
		(start 357.619808 -160.847024)
		(end 359.294684 -159.172148)
		(width 0.254)
		(layer "F.Cu")
		(net "P12V_NIC6_CO_IMON_VR")
	)
	(segment
		(start 357.619808 -161.603944)
		(end 357.619808 -160.965896)
		(width 0.254)
		(layer "F.Cu")
		(net "P12V_NIC6_CO_IMON_VR")
	)
	(via
		(at 357.619808 -160.965896)
		(size 0.508)
		(drill 0.254)
		(layers "F.Cu" "B.Cu")
		(net "P12V_NIC6_CO_IMON_VR")
	)
	(via
		(at 337.587082 -114.028474)
		(size 0.508)
		(drill 0.254)
		(layers "F.Cu" "B.Cu")
		(net "P12V_NIC5_CO_AVIN_PD")
	)
	(segment
		(start 245.96471 -160.450022)
		(end 245.96471 -160.902142)
		(width 0.13208)
		(layer "F.Cu")
		(net "P12V_NIC4_CO_TIMER")
	)
	(segment
		(start 245.194582 -159.679894)
		(end 245.96471 -160.450022)
		(width 0.13208)
		(layer "F.Cu")
		(net "P12V_NIC4_CO_TIMER")
	)
	(segment
		(start 245.96471 -160.902142)
		(end 245.96471 -161.603944)
		(width 0.13208)
		(layer "F.Cu")
		(net "P12V_NIC4_CO_TIMER")
	)
	(segment
		(start 245.194582 -158.705042)
		(end 245.194582 -159.679894)
		(width 0.13208)
		(layer "F.Cu")
		(net "P12V_NIC4_CO_TIMER")
	)
	(via
		(at 245.96471 -160.902142)
		(size 0.508)
		(drill 0.254)
		(layers "F.Cu" "B.Cu")
		(net "P12V_NIC4_CO_TIMER")
	)
	(segment
		(start 456.412854 -114.1857)
		(end 456.412854 -114.803174)
		(width 0.13208)
		(layer "F.Cu")
		(net "PWRGD_P12V_NIC7_CO")
	)
	(segment
		(start 457.436982 -115.830604)
		(end 456.420982 -115.830604)
		(width 0.13208)
		(layer "F.Cu")
		(net "PWRGD_P12V_NIC7_CO")
	)
	(segment
		(start 456.668378 -115.058698)
		(end 456.420982 -115.306094)
		(width 0.13208)
		(layer "F.Cu")
		(net "PWRGD_P12V_NIC7_CO")
	)
	(segment
		(start 456.420982 -115.306094)
		(end 456.420982 -115.830604)
		(width 0.13208)
		(layer "F.Cu")
		(net "PWRGD_P12V_NIC7_CO")
	)
	(segment
		(start 456.412854 -114.803174)
		(end 456.668378 -115.058698)
		(width 0.13208)
		(layer "F.Cu")
		(net "PWRGD_P12V_NIC7_CO")
	)
	(via
		(at 456.668378 -115.058698)
		(size 0.508)
		(drill 0.254)
		(layers "F.Cu" "B.Cu")
		(net "PWRGD_P12V_NIC7_CO")
	)
	(segment
		(start 242.91163 -160.963864)
		(end 242.91671 -160.968944)
		(width 0.254)
		(layer "F.Cu")
		(net "P12V_NIC4_CO_SS")
	)
	(segment
		(start 242.91671 -160.958784)
		(end 242.91163 -160.963864)
		(width 0.254)
		(layer "F.Cu")
		(net "P12V_NIC4_CO_SS")
	)
	(segment
		(start 242.91671 -160.968944)
		(end 242.91671 -161.603944)
		(width 0.254)
		(layer "F.Cu")
		(net "P12V_NIC4_CO_SS")
	)
	(segment
		(start 244.194838 -158.705042)
		(end 244.194838 -159.266636)
		(width 0.254)
		(layer "F.Cu")
		(net "P12V_NIC4_CO_SS")
	)
	(segment
		(start 244.09527 -159.50692)
		(end 242.91671 -160.68548)
		(width 0.254)
		(layer "F.Cu")
		(net "P12V_NIC4_CO_SS")
	)
	(segment
		(start 244.194838 -159.266636)
		(end 244.09527 -159.50692)
		(width 0.254)
		(layer "F.Cu")
		(net "P12V_NIC4_CO_SS")
	)
	(segment
		(start 242.91671 -160.68548)
		(end 242.91671 -160.958784)
		(width 0.254)
		(layer "F.Cu")
		(net "P12V_NIC4_CO_SS")
	)
	(via
		(at 242.91163 -160.963864)
		(size 0.508)
		(drill 0.254)
		(layers "F.Cu" "B.Cu")
		(net "P12V_NIC4_CO_SS")
	)
	(segment
		(start 357.274368 -157.812994)
		(end 357.521764 -158.06039)
		(width 0.13208)
		(layer "F.Cu")
		(net "PWRGD_P12V_NIC6_CO")
	)
	(segment
		(start 356.749858 -158.828994)
		(end 356.749858 -157.812994)
		(width 0.13208)
		(layer "F.Cu")
		(net "PWRGD_P12V_NIC6_CO")
	)
	(segment
		(start 357.777288 -157.804866)
		(end 358.394762 -157.804866)
		(width 0.13208)
		(layer "F.Cu")
		(net "PWRGD_P12V_NIC6_CO")
	)
	(segment
		(start 357.521764 -158.06039)
		(end 357.777288 -157.804866)
		(width 0.13208)
		(layer "F.Cu")
		(net "PWRGD_P12V_NIC6_CO")
	)
	(segment
		(start 356.749858 -157.812994)
		(end 357.274368 -157.812994)
		(width 0.13208)
		(layer "F.Cu")
		(net "PWRGD_P12V_NIC6_CO")
	)
	(via
		(at 357.521764 -158.06039)
		(size 0.508)
		(drill 0.254)
		(layers "F.Cu" "B.Cu")
		(net "PWRGD_P12V_NIC6_CO")
	)
	(segment
		(start 459.455012 -114.960654)
		(end 459.573884 -114.960654)
		(width 0.254)
		(layer "F.Cu")
		(net "P12V_NIC7_CO_IMON_VR")
	)
	(segment
		(start 457.31303 -113.285778)
		(end 457.780136 -113.285778)
		(width 0.254)
		(layer "F.Cu")
		(net "P12V_NIC7_CO_IMON_VR")
	)
	(segment
		(start 457.780136 -113.285778)
		(end 459.455012 -114.960654)
		(width 0.254)
		(layer "F.Cu")
		(net "P12V_NIC7_CO_IMON_VR")
	)
	(segment
		(start 459.573884 -114.960654)
		(end 460.211932 -114.960654)
		(width 0.254)
		(layer "F.Cu")
		(net "P12V_NIC7_CO_IMON_VR")
	)
	(via
		(at 459.573884 -114.960654)
		(size 0.508)
		(drill 0.254)
		(layers "F.Cu" "B.Cu")
		(net "P12V_NIC7_CO_IMON_VR")
	)
	(segment
		(start 341.946992 -114.261138)
		(end 341.946992 -114.990372)
		(width 0.254)
		(layer "F.Cu")
		(net "P12V_NIC5_CO_FLTB")
	)
	(segment
		(start 341.471504 -113.78565)
		(end 341.946992 -114.261138)
		(width 0.254)
		(layer "F.Cu")
		(net "P12V_NIC5_CO_FLTB")
	)
	(segment
		(start 341.212932 -113.78565)
		(end 341.471504 -113.78565)
		(width 0.254)
		(layer "F.Cu")
		(net "P12V_NIC5_CO_FLTB")
	)
	(segment
		(start 342.352884 -115.396264)
		(end 342.352884 -115.830604)
		(width 0.254)
		(layer "F.Cu")
		(net "P12V_NIC5_CO_FLTB")
	)
	(segment
		(start 341.946992 -114.990372)
		(end 342.352884 -115.396264)
		(width 0.254)
		(layer "F.Cu")
		(net "P12V_NIC5_CO_FLTB")
	)
	(via
		(at 341.946992 -114.990372)
		(size 0.508)
		(drill 0.254)
		(layers "F.Cu" "B.Cu")
		(net "P12V_NIC5_CO_FLTB")
	)
	(segment
		(start 360.283506 -160.968944)
		(end 360.283506 -160.327848)
		(width 0.254)
		(layer "F.Cu")
		(net "P12V_NIC6_CO_ISET_R")
	)
	(segment
		(start 360.032808 -161.219642)
		(end 360.283506 -160.968944)
		(width 0.254)
		(layer "F.Cu")
		(net "P12V_NIC6_CO_ISET_R")
	)
	(segment
		(start 360.032808 -161.603944)
		(end 360.032808 -161.219642)
		(width 0.254)
		(layer "F.Cu")
		(net "P12V_NIC6_CO_ISET_R")
	)
	(via
		(at 360.283506 -160.968944)
		(size 0.508)
		(drill 0.254)
		(layers "F.Cu" "B.Cu")
		(net "P12V_NIC6_CO_ISET_R")
	)
	(segment
		(start 242.219226 -159.439102)
		(end 241.489992 -159.439102)
		(width 0.254)
		(layer "F.Cu")
		(net "P12V_NIC4_CO_FLTB")
	)
	(segment
		(start 242.694714 -158.705042)
		(end 242.694714 -158.963614)
		(width 0.254)
		(layer "F.Cu")
		(net "P12V_NIC4_CO_FLTB")
	)
	(segment
		(start 241.489992 -159.439102)
		(end 241.0841 -159.844994)
		(width 0.254)
		(layer "F.Cu")
		(net "P12V_NIC4_CO_FLTB")
	)
	(segment
		(start 241.0841 -159.844994)
		(end 240.64976 -159.844994)
		(width 0.254)
		(layer "F.Cu")
		(net "P12V_NIC4_CO_FLTB")
	)
	(segment
		(start 242.694714 -158.963614)
		(end 242.219226 -159.439102)
		(width 0.254)
		(layer "F.Cu")
		(net "P12V_NIC4_CO_FLTB")
	)
	(via
		(at 241.489992 -159.439102)
		(size 0.508)
		(drill 0.254)
		(layers "F.Cu" "B.Cu")
		(net "P12V_NIC4_CO_FLTB")
	)
	(via
		(at 339.20176 -115.010946)
		(size 0.508)
		(drill 0.254)
		(layers "F.Cu" "B.Cu")
		(net "P12V_NIC5_CO_OV_FB")
	)
	(segment
		(start 341.212932 -112.285526)
		(end 341.774526 -112.285526)
		(width 0.254)
		(layer "F.Cu")
		(net "P12V_NIC5_CO_SS")
	)
	(segment
		(start 342.01481 -112.385094)
		(end 343.19337 -113.563654)
		(width 0.254)
		(layer "F.Cu")
		(net "P12V_NIC5_CO_SS")
	)
	(segment
		(start 343.471754 -113.568734)
		(end 343.476834 -113.563654)
		(width 0.254)
		(layer "F.Cu")
		(net "P12V_NIC5_CO_SS")
	)
	(segment
		(start 343.466674 -113.563654)
		(end 343.471754 -113.568734)
		(width 0.254)
		(layer "F.Cu")
		(net "P12V_NIC5_CO_SS")
	)
	(segment
		(start 341.774526 -112.285526)
		(end 342.01481 -112.385094)
		(width 0.254)
		(layer "F.Cu")
		(net "P12V_NIC5_CO_SS")
	)
	(segment
		(start 343.476834 -113.563654)
		(end 344.111834 -113.563654)
		(width 0.254)
		(layer "F.Cu")
		(net "P12V_NIC5_CO_SS")
	)
	(segment
		(start 343.19337 -113.563654)
		(end 343.466674 -113.563654)
		(width 0.254)
		(layer "F.Cu")
		(net "P12V_NIC5_CO_SS")
	)
	(via
		(at 343.471754 -113.568734)
		(size 0.508)
		(drill 0.254)
		(layers "F.Cu" "B.Cu")
		(net "P12V_NIC5_CO_SS")
	)
	(segment
		(start 240.64976 -158.828994)
		(end 240.64976 -157.812994)
		(width 0.13208)
		(layer "F.Cu")
		(net "PWRGD_P12V_NIC4_CO")
	)
	(segment
		(start 241.421666 -158.06039)
		(end 241.67719 -157.804866)
		(width 0.13208)
		(layer "F.Cu")
		(net "PWRGD_P12V_NIC4_CO")
	)
	(segment
		(start 240.64976 -157.812994)
		(end 241.17427 -157.812994)
		(width 0.13208)
		(layer "F.Cu")
		(net "PWRGD_P12V_NIC4_CO")
	)
	(segment
		(start 241.17427 -157.812994)
		(end 241.421666 -158.06039)
		(width 0.13208)
		(layer "F.Cu")
		(net "PWRGD_P12V_NIC4_CO")
	)
	(segment
		(start 241.67719 -157.804866)
		(end 242.294664 -157.804866)
		(width 0.13208)
		(layer "F.Cu")
		(net "PWRGD_P12V_NIC4_CO")
	)
	(via
		(at 241.421666 -158.06039)
		(size 0.508)
		(drill 0.254)
		(layers "F.Cu" "B.Cu")
		(net "PWRGD_P12V_NIC4_CO")
	)
	(segment
		(start 362.953808 -160.537652)
		(end 363.26445 -160.22701)
		(width 0.13208)
		(layer "F.Cu")
		(net "P12V_NIC6_CO_EN")
	)
	(segment
		(start 363.842808 -161.603944)
		(end 362.953808 -161.603944)
		(width 0.13208)
		(layer "F.Cu")
		(net "P12V_NIC6_CO_EN")
	)
	(segment
		(start 363.26445 -159.474408)
		(end 362.794804 -159.004762)
		(width 0.13208)
		(layer "F.Cu")
		(net "P12V_NIC6_CO_EN")
	)
	(segment
		(start 362.794804 -159.004762)
		(end 362.794804 -158.679896)
		(width 0.13208)
		(layer "F.Cu")
		(net "P12V_NIC6_CO_EN")
	)
	(segment
		(start 363.26445 -160.22701)
		(end 363.26445 -159.474408)
		(width 0.13208)
		(layer "F.Cu")
		(net "P12V_NIC6_CO_EN")
	)
	(segment
		(start 362.953808 -161.603944)
		(end 362.953808 -160.537652)
		(width 0.13208)
		(layer "F.Cu")
		(net "P12V_NIC6_CO_EN")
	)
	(segment
		(start 364.731808 -161.603944)
		(end 363.842808 -161.603944)
		(width 0.13208)
		(layer "F.Cu")
		(net "P12V_NIC6_CO_EN")
	)
	(via
		(at 363.26445 -159.474408)
		(size 0.508)
		(drill 0.254)
		(layers "F.Cu" "B.Cu")
		(net "P12V_NIC6_CO_EN")
	)
	(segment
		(start 243.194586 -159.172148)
		(end 241.51971 -160.847024)
		(width 0.254)
		(layer "F.Cu")
		(net "P12V_NIC4_CO_IMON_VR")
	)
	(segment
		(start 243.194586 -158.705042)
		(end 243.194586 -159.172148)
		(width 0.254)
		(layer "F.Cu")
		(net "P12V_NIC4_CO_IMON_VR")
	)
	(segment
		(start 241.51971 -160.847024)
		(end 241.51971 -160.965896)
		(width 0.254)
		(layer "F.Cu")
		(net "P12V_NIC4_CO_IMON_VR")
	)
	(segment
		(start 241.51971 -160.965896)
		(end 241.51971 -161.603944)
		(width 0.254)
		(layer "F.Cu")
		(net "P12V_NIC4_CO_IMON_VR")
	)
	(via
		(at 241.51971 -160.965896)
		(size 0.508)
		(drill 0.254)
		(layers "F.Cu" "B.Cu")
		(net "P12V_NIC4_CO_IMON_VR")
	)
	(segment
		(start 342.187784 -111.285782)
		(end 342.957912 -110.515654)
		(width 0.13208)
		(layer "F.Cu")
		(net "P12V_NIC5_CO_TIMER")
	)
	(segment
		(start 341.212932 -111.285782)
		(end 342.187784 -111.285782)
		(width 0.13208)
		(layer "F.Cu")
		(net "P12V_NIC5_CO_TIMER")
	)
	(segment
		(start 342.957912 -110.515654)
		(end 343.410032 -110.515654)
		(width 0.13208)
		(layer "F.Cu")
		(net "P12V_NIC5_CO_TIMER")
	)
	(segment
		(start 343.410032 -110.515654)
		(end 344.111834 -110.515654)
		(width 0.13208)
		(layer "F.Cu")
		(net "P12V_NIC5_CO_TIMER")
	)
	(via
		(at 343.410032 -110.515654)
		(size 0.508)
		(drill 0.254)
		(layers "F.Cu" "B.Cu")
		(net "P12V_NIC5_CO_TIMER")
	)
	(segment
		(start 246.977916 -159.488632)
		(end 246.694706 -159.205422)
		(width 0.13208)
		(layer "F.Cu")
		(net "P12V_NIC4_CO_EN")
	)
	(segment
		(start 247.74271 -161.603944)
		(end 246.85371 -161.603944)
		(width 0.13208)
		(layer "F.Cu")
		(net "P12V_NIC4_CO_EN")
	)
	(segment
		(start 246.694706 -159.205422)
		(end 246.694706 -158.679896)
		(width 0.13208)
		(layer "F.Cu")
		(net "P12V_NIC4_CO_EN")
	)
	(segment
		(start 246.977916 -160.413446)
		(end 246.977916 -159.488632)
		(width 0.13208)
		(layer "F.Cu")
		(net "P12V_NIC4_CO_EN")
	)
	(segment
		(start 246.85371 -161.603944)
		(end 246.85371 -160.537652)
		(width 0.13208)
		(layer "F.Cu")
		(net "P12V_NIC4_CO_EN")
	)
	(segment
		(start 248.63171 -161.603944)
		(end 247.74271 -161.603944)
		(width 0.13208)
		(layer "F.Cu")
		(net "P12V_NIC4_CO_EN")
	)
	(segment
		(start 246.85371 -160.537652)
		(end 246.977916 -160.413446)
		(width 0.13208)
		(layer "F.Cu")
		(net "P12V_NIC4_CO_EN")
	)
	(via
		(at 246.977916 -159.488632)
		(size 0.508)
		(drill 0.254)
		(layers "F.Cu" "B.Cu")
		(net "P12V_NIC4_CO_EN")
	)
	(segment
		(start 457.31303 -113.78565)
		(end 457.571602 -113.78565)
		(width 0.254)
		(layer "F.Cu")
		(net "P12V_NIC7_CO_FLTB")
	)
	(segment
		(start 458.04709 -114.261138)
		(end 458.04709 -114.990372)
		(width 0.254)
		(layer "F.Cu")
		(net "P12V_NIC7_CO_FLTB")
	)
	(segment
		(start 458.04709 -114.990372)
		(end 458.452982 -115.396264)
		(width 0.254)
		(layer "F.Cu")
		(net "P12V_NIC7_CO_FLTB")
	)
	(segment
		(start 457.571602 -113.78565)
		(end 458.04709 -114.261138)
		(width 0.254)
		(layer "F.Cu")
		(net "P12V_NIC7_CO_FLTB")
	)
	(segment
		(start 458.452982 -115.396264)
		(end 458.452982 -115.830604)
		(width 0.254)
		(layer "F.Cu")
		(net "P12V_NIC7_CO_FLTB")
	)
	(via
		(at 458.04709 -114.990372)
		(size 0.508)
		(drill 0.254)
		(layers "F.Cu" "B.Cu")
		(net "P12V_NIC7_CO_FLTB")
	)
	(segment
		(start 243.93271 -161.603944)
		(end 243.93271 -161.219642)
		(width 0.254)
		(layer "F.Cu")
		(net "P12V_NIC4_CO_ISET_R")
	)
	(segment
		(start 243.93271 -161.219642)
		(end 244.183408 -160.968944)
		(width 0.254)
		(layer "F.Cu")
		(net "P12V_NIC4_CO_ISET_R")
	)
	(segment
		(start 244.183408 -160.968944)
		(end 244.183408 -160.327848)
		(width 0.254)
		(layer "F.Cu")
		(net "P12V_NIC4_CO_ISET_R")
	)
	(via
		(at 244.183408 -160.968944)
		(size 0.508)
		(drill 0.254)
		(layers "F.Cu" "B.Cu")
		(net "P12V_NIC4_CO_ISET_R")
	)
	(segment
		(start 360.794808 -160.03905)
		(end 361.083606 -160.327848)
		(width 0.254)
		(layer "F.Cu")
		(net "P12V_NIC6_CO_ISET")
	)
	(segment
		(start 360.794808 -159.531812)
		(end 360.794808 -160.03905)
		(width 0.254)
		(layer "F.Cu")
		(net "P12V_NIC6_CO_ISET")
	)
	(segment
		(start 361.083606 -160.327848)
		(end 361.083606 -161.569146)
		(width 0.254)
		(layer "F.Cu")
		(net "P12V_NIC6_CO_ISET")
	)
	(segment
		(start 360.794808 -158.705042)
		(end 360.794808 -159.531812)
		(width 0.254)
		(layer "F.Cu")
		(net "P12V_NIC6_CO_ISET")
	)
	(segment
		(start 361.083606 -161.569146)
		(end 361.048808 -161.603944)
		(width 0.254)
		(layer "F.Cu")
		(net "P12V_NIC6_CO_ISET")
	)
	(via
		(at 360.794808 -159.531812)
		(size 0.508)
		(drill 0.254)
		(layers "F.Cu" "B.Cu")
		(net "P12V_NIC6_CO_ISET")
	)
	(segment
		(start 224.822004 -225.994468)
		(end 225.1456 -225.670872)
		(width 0.13208)
		(layer "F.Cu")
		(net "HSC_TIMER_N")
	)
	(segment
		(start 225.1456 -224.782126)
		(end 225.067622 -224.704148)
		(width 0.13208)
		(layer "F.Cu")
		(net "HSC_TIMER_N")
	)
	(segment
		(start 225.1456 -225.670872)
		(end 225.1456 -224.782126)
		(width 0.13208)
		(layer "F.Cu")
		(net "HSC_TIMER_N")
	)
	(segment
		(start 327.13295 -209.169)
		(end 325.571358 -209.169)
		(width 0.13208)
		(layer "F.Cu")
		(net "HSC_TIMER_N")
	)
	(via
		(at 325.571358 -209.169)
		(size 0.508)
		(drill 0.254)
		(layers "F.Cu" "B.Cu")
		(net "HSC_TIMER_N")
	)
	(via
		(at 224.822004 -225.994468)
		(size 0.4572)
		(drill 0.254)
		(layers "F.Cu" "B.Cu")
		(net "HSC_TIMER_N")
	)
	(via
		(at 225.93935 -183.40324)
		(size 0.508)
		(drill 0.254)
		(layers "F.Cu" "B.Cu")
		(net "HSC_TIMER_N")
	)
	(segment
		(start 227.25888 -192.5066)
		(end 227.70338 -192.0621)
		(width 0.15494)
		(layer "In7.Cu")
		(net "HSC_TIMER_N")
	)
	(segment
		(start 226.06 -205.9178)
		(end 226.06 -204.600302)
		(width 0.15494)
		(layer "In7.Cu")
		(net "HSC_TIMER_N")
	)
	(segment
		(start 223.784668 -207.893158)
		(end 225.531426 -206.1464)
		(width 0.15494)
		(layer "In7.Cu")
		(net "HSC_TIMER_N")
	)
	(segment
		(start 227.3046 -200.6346)
		(end 227.99929 -199.93991)
		(width 0.15494)
		(layer "In7.Cu")
		(net "HSC_TIMER_N")
	)
	(segment
		(start 225.8314 -206.1464)
		(end 226.06 -205.9178)
		(width 0.15494)
		(layer "In7.Cu")
		(net "HSC_TIMER_N")
	)
	(segment
		(start 221.3102 -224.028)
		(end 221.3102 -209.524854)
		(width 0.15494)
		(layer "In7.Cu")
		(net "HSC_TIMER_N")
	)
	(segment
		(start 227.99929 -199.93991)
		(end 227.99929 -198.535544)
		(width 0.15494)
		(layer "In7.Cu")
		(net "HSC_TIMER_N")
	)
	(segment
		(start 222.941896 -207.893158)
		(end 223.784668 -207.893158)
		(width 0.15494)
		(layer "In7.Cu")
		(net "HSC_TIMER_N")
	)
	(segment
		(start 227.99929 -198.535544)
		(end 227.25888 -197.795134)
		(width 0.15494)
		(layer "In7.Cu")
		(net "HSC_TIMER_N")
	)
	(segment
		(start 223.276668 -225.994468)
		(end 221.3102 -224.028)
		(width 0.15494)
		(layer "In7.Cu")
		(net "HSC_TIMER_N")
	)
	(segment
		(start 227.70338 -192.0621)
		(end 227.70338 -185.16727)
		(width 0.15494)
		(layer "In7.Cu")
		(net "HSC_TIMER_N")
	)
	(segment
		(start 221.3102 -209.524854)
		(end 222.941896 -207.893158)
		(width 0.15494)
		(layer "In7.Cu")
		(net "HSC_TIMER_N")
	)
	(segment
		(start 225.531426 -206.1464)
		(end 225.8314 -206.1464)
		(width 0.15494)
		(layer "In7.Cu")
		(net "HSC_TIMER_N")
	)
	(segment
		(start 226.06 -204.600302)
		(end 227.0506 -203.609702)
		(width 0.15494)
		(layer "In7.Cu")
		(net "HSC_TIMER_N")
	)
	(segment
		(start 227.0506 -202.061064)
		(end 227.3046 -201.807064)
		(width 0.15494)
		(layer "In7.Cu")
		(net "HSC_TIMER_N")
	)
	(segment
		(start 227.3046 -201.807064)
		(end 227.3046 -200.6346)
		(width 0.15494)
		(layer "In7.Cu")
		(net "HSC_TIMER_N")
	)
	(segment
		(start 227.25888 -197.795134)
		(end 227.25888 -192.5066)
		(width 0.15494)
		(layer "In7.Cu")
		(net "HSC_TIMER_N")
	)
	(segment
		(start 227.0506 -203.609702)
		(end 227.0506 -202.061064)
		(width 0.15494)
		(layer "In7.Cu")
		(net "HSC_TIMER_N")
	)
	(segment
		(start 224.822004 -225.994468)
		(end 223.276668 -225.994468)
		(width 0.15494)
		(layer "In7.Cu")
		(net "HSC_TIMER_N")
	)
	(segment
		(start 227.70338 -185.16727)
		(end 225.93935 -183.40324)
		(width 0.15494)
		(layer "In7.Cu")
		(net "HSC_TIMER_N")
	)
	(segment
		(start 244.021356 -184.413906)
		(end 244.31625 -184.7088)
		(width 0.15494)
		(layer "In13.Cu")
		(net "HSC_TIMER_N")
	)
	(segment
		(start 262.864346 -190.5508)
		(end 281.366976 -209.05343)
		(width 0.15494)
		(layer "In13.Cu")
		(net "HSC_TIMER_N")
	)
	(segment
		(start 258.8768 -191.4906)
		(end 259.8166 -190.5508)
		(width 0.15494)
		(layer "In13.Cu")
		(net "HSC_TIMER_N")
	)
	(segment
		(start 225.93935 -183.40324)
		(end 226.35591 -183.8198)
		(width 0.15494)
		(layer "In13.Cu")
		(net "HSC_TIMER_N")
	)
	(segment
		(start 233.84256 -183.8198)
		(end 235.72216 -181.9402)
		(width 0.15494)
		(layer "In13.Cu")
		(net "HSC_TIMER_N")
	)
	(segment
		(start 244.31625 -184.7088)
		(end 252.146308 -184.7088)
		(width 0.15494)
		(layer "In13.Cu")
		(net "HSC_TIMER_N")
	)
	(segment
		(start 258.4196 -191.4906)
		(end 258.8768 -191.4906)
		(width 0.15494)
		(layer "In13.Cu")
		(net "HSC_TIMER_N")
	)
	(segment
		(start 244.021356 -183.72201)
		(end 244.021356 -184.413906)
		(width 0.15494)
		(layer "In13.Cu")
		(net "HSC_TIMER_N")
	)
	(segment
		(start 257.9624 -190.524892)
		(end 257.9624 -191.0334)
		(width 0.15494)
		(layer "In13.Cu")
		(net "HSC_TIMER_N")
	)
	(segment
		(start 242.239546 -181.9402)
		(end 244.021356 -183.72201)
		(width 0.15494)
		(layer "In13.Cu")
		(net "HSC_TIMER_N")
	)
	(segment
		(start 281.366976 -209.05343)
		(end 325.455788 -209.05343)
		(width 0.15494)
		(layer "In13.Cu")
		(net "HSC_TIMER_N")
	)
	(segment
		(start 226.35591 -183.8198)
		(end 233.84256 -183.8198)
		(width 0.15494)
		(layer "In13.Cu")
		(net "HSC_TIMER_N")
	)
	(segment
		(start 235.72216 -181.9402)
		(end 242.239546 -181.9402)
		(width 0.15494)
		(layer "In13.Cu")
		(net "HSC_TIMER_N")
	)
	(segment
		(start 325.455788 -209.05343)
		(end 325.571358 -209.169)
		(width 0.15494)
		(layer "In13.Cu")
		(net "HSC_TIMER_N")
	)
	(segment
		(start 257.9624 -191.0334)
		(end 258.4196 -191.4906)
		(width 0.15494)
		(layer "In13.Cu")
		(net "HSC_TIMER_N")
	)
	(segment
		(start 259.8166 -190.5508)
		(end 262.864346 -190.5508)
		(width 0.15494)
		(layer "In13.Cu")
		(net "HSC_TIMER_N")
	)
	(segment
		(start 252.146308 -184.7088)
		(end 257.9624 -190.524892)
		(width 0.15494)
		(layer "In13.Cu")
		(net "HSC_TIMER_N")
	)
	(segment
		(start 244.69471 -158.705042)
		(end 244.69471 -159.531812)
		(width 0.254)
		(layer "F.Cu")
		(net "P12V_NIC4_CO_ISET")
	)
	(segment
		(start 244.983508 -160.327848)
		(end 244.983508 -161.569146)
		(width 0.254)
		(layer "F.Cu")
		(net "P12V_NIC4_CO_ISET")
	)
	(segment
		(start 244.69471 -159.674306)
		(end 244.983508 -159.963104)
		(width 0.254)
		(layer "F.Cu")
		(net "P12V_NIC4_CO_ISET")
	)
	(segment
		(start 244.983508 -159.963104)
		(end 244.983508 -160.327848)
		(width 0.254)
		(layer "F.Cu")
		(net "P12V_NIC4_CO_ISET")
	)
	(segment
		(start 244.69471 -159.531812)
		(end 244.69471 -159.674306)
		(width 0.254)
		(layer "F.Cu")
		(net "P12V_NIC4_CO_ISET")
	)
	(segment
		(start 244.983508 -161.569146)
		(end 244.94871 -161.603944)
		(width 0.254)
		(layer "F.Cu")
		(net "P12V_NIC4_CO_ISET")
	)
	(via
		(at 244.69471 -159.531812)
		(size 0.508)
		(drill 0.254)
		(layers "F.Cu" "B.Cu")
		(net "P12V_NIC4_CO_ISET")
	)
	(segment
		(start 341.996522 -109.502448)
		(end 342.921336 -109.502448)
		(width 0.13208)
		(layer "F.Cu")
		(net "P12V_NIC5_CO_EN")
	)
	(segment
		(start 341.713312 -109.785658)
		(end 341.996522 -109.502448)
		(width 0.13208)
		(layer "F.Cu")
		(net "P12V_NIC5_CO_EN")
	)
	(segment
		(start 343.045542 -109.626654)
		(end 344.111834 -109.626654)
		(width 0.13208)
		(layer "F.Cu")
		(net "P12V_NIC5_CO_EN")
	)
	(segment
		(start 342.921336 -109.502448)
		(end 343.045542 -109.626654)
		(width 0.13208)
		(layer "F.Cu")
		(net "P12V_NIC5_CO_EN")
	)
	(segment
		(start 344.111834 -108.737654)
		(end 344.111834 -109.626654)
		(width 0.13208)
		(layer "F.Cu")
		(net "P12V_NIC5_CO_EN")
	)
	(segment
		(start 344.111834 -107.848654)
		(end 344.111834 -108.737654)
		(width 0.13208)
		(layer "F.Cu")
		(net "P12V_NIC5_CO_EN")
	)
	(segment
		(start 341.187786 -109.785658)
		(end 341.713312 -109.785658)
		(width 0.13208)
		(layer "F.Cu")
		(net "P12V_NIC5_CO_EN")
	)
	(via
		(at 341.996522 -109.502448)
		(size 0.508)
		(drill 0.254)
		(layers "F.Cu" "B.Cu")
		(net "P12V_NIC5_CO_EN")
	)
	(segment
		(start 458.287882 -111.285782)
		(end 457.31303 -111.285782)
		(width 0.13208)
		(layer "F.Cu")
		(net "P12V_NIC7_CO_TIMER")
	)
	(segment
		(start 459.05801 -110.515654)
		(end 458.287882 -111.285782)
		(width 0.13208)
		(layer "F.Cu")
		(net "P12V_NIC7_CO_TIMER")
	)
	(segment
		(start 459.51013 -110.515654)
		(end 460.211932 -110.515654)
		(width 0.13208)
		(layer "F.Cu")
		(net "P12V_NIC7_CO_TIMER")
	)
	(segment
		(start 459.51013 -110.515654)
		(end 459.05801 -110.515654)
		(width 0.13208)
		(layer "F.Cu")
		(net "P12V_NIC7_CO_TIMER")
	)
	(via
		(at 459.51013 -110.515654)
		(size 0.508)
		(drill 0.254)
		(layers "F.Cu" "B.Cu")
		(net "P12V_NIC7_CO_TIMER")
	)
	(via
		(at 358.551988 -155.079192)
		(size 0.508)
		(drill 0.254)
		(layers "F.Cu" "B.Cu")
		(net "P12V_NIC6_CO_AVIN_PD")
	)
	(segment
		(start 377.080018 -28.139136)
		(end 376.641868 -27.700986)
		(width 0.13208)
		(layer "F.Cu")
		(net "P3V3_SSD13_CO_ILIMIT")
	)
	(segment
		(start 377.082558 -28.141676)
		(end 377.080018 -28.139136)
		(width 0.13208)
		(layer "F.Cu")
		(net "P3V3_SSD13_CO_ILIMIT")
	)
	(segment
		(start 376.641868 -27.700986)
		(end 376.641868 -27.406346)
		(width 0.13208)
		(layer "F.Cu")
		(net "P3V3_SSD13_CO_ILIMIT")
	)
	(segment
		(start 377.082558 -28.875736)
		(end 377.082558 -28.141676)
		(width 0.13208)
		(layer "F.Cu")
		(net "P3V3_SSD13_CO_ILIMIT")
	)
	(via
		(at 377.080018 -28.139136)
		(size 0.508)
		(drill 0.254)
		(layers "F.Cu" "B.Cu")
		(net "P3V3_SSD13_CO_ILIMIT")
	)
	(segment
		(start 376.967496 -32.25927)
		(end 377.156218 -32.447992)
		(width 0.13208)
		(layer "F.Cu")
		(net "P3V3_SSD13_CO_EN")
	)
	(segment
		(start 377.082558 -31.44139)
		(end 376.967496 -31.719266)
		(width 0.13208)
		(layer "F.Cu")
		(net "P3V3_SSD13_CO_EN")
	)
	(segment
		(start 376.967496 -31.719266)
		(end 376.967496 -32.25927)
		(width 0.13208)
		(layer "F.Cu")
		(net "P3V3_SSD13_CO_EN")
	)
	(segment
		(start 377.082558 -30.875732)
		(end 377.082558 -31.44139)
		(width 0.13208)
		(layer "F.Cu")
		(net "P3V3_SSD13_CO_EN")
	)
	(via
		(at 376.967496 -31.719266)
		(size 0.508)
		(drill 0.254)
		(layers "F.Cu" "B.Cu")
		(net "P3V3_SSD13_CO_EN")
	)
	(segment
		(start 404.673816 -27.815286)
		(end 404.673816 -27.406346)
		(width 0.13208)
		(layer "F.Cu")
		(net "P3V3_SSD14_CO_MODE")
	)
	(segment
		(start 403.582378 -28.875736)
		(end 403.582378 -28.329636)
		(width 0.13208)
		(layer "F.Cu")
		(net "P3V3_SSD14_CO_MODE")
	)
	(segment
		(start 404.349966 -28.139136)
		(end 404.673816 -27.815286)
		(width 0.13208)
		(layer "F.Cu")
		(net "P3V3_SSD14_CO_MODE")
	)
	(segment
		(start 403.582378 -28.329636)
		(end 403.772878 -28.139136)
		(width 0.13208)
		(layer "F.Cu")
		(net "P3V3_SSD14_CO_MODE")
	)
	(segment
		(start 403.657816 -27.406346)
		(end 404.673816 -27.406346)
		(width 0.13208)
		(layer "F.Cu")
		(net "P3V3_SSD14_CO_MODE")
	)
	(segment
		(start 403.772878 -28.139136)
		(end 404.349966 -28.139136)
		(width 0.13208)
		(layer "F.Cu")
		(net "P3V3_SSD14_CO_MODE")
	)
	(via
		(at 404.349966 -28.139136)
		(size 0.508)
		(drill 0.254)
		(layers "F.Cu" "B.Cu")
		(net "P3V3_SSD14_CO_MODE")
	)
	(segment
		(start 429.082454 -28.141676)
		(end 429.079914 -28.139136)
		(width 0.13208)
		(layer "F.Cu")
		(net "P3V3_SSD15_CO_ILIMIT")
	)
	(segment
		(start 429.082454 -28.875736)
		(end 429.082454 -28.141676)
		(width 0.13208)
		(layer "F.Cu")
		(net "P3V3_SSD15_CO_ILIMIT")
	)
	(segment
		(start 428.641764 -27.700986)
		(end 428.641764 -27.406346)
		(width 0.13208)
		(layer "F.Cu")
		(net "P3V3_SSD15_CO_ILIMIT")
	)
	(segment
		(start 429.079914 -28.139136)
		(end 428.641764 -27.700986)
		(width 0.13208)
		(layer "F.Cu")
		(net "P3V3_SSD15_CO_ILIMIT")
	)
	(via
		(at 429.079914 -28.139136)
		(size 0.508)
		(drill 0.254)
		(layers "F.Cu" "B.Cu")
		(net "P3V3_SSD15_CO_ILIMIT")
	)
	(segment
		(start 429.657764 -27.406346)
		(end 430.673764 -27.406346)
		(width 0.13208)
		(layer "F.Cu")
		(net "P3V3_SSD15_CO_MODE")
	)
	(segment
		(start 430.349914 -28.139136)
		(end 430.673764 -27.815286)
		(width 0.13208)
		(layer "F.Cu")
		(net "P3V3_SSD15_CO_MODE")
	)
	(segment
		(start 429.582326 -28.329636)
		(end 429.772826 -28.139136)
		(width 0.13208)
		(layer "F.Cu")
		(net "P3V3_SSD15_CO_MODE")
	)
	(segment
		(start 429.772826 -28.139136)
		(end 430.349914 -28.139136)
		(width 0.13208)
		(layer "F.Cu")
		(net "P3V3_SSD15_CO_MODE")
	)
	(segment
		(start 430.673764 -27.815286)
		(end 430.673764 -27.406346)
		(width 0.13208)
		(layer "F.Cu")
		(net "P3V3_SSD15_CO_MODE")
	)
	(segment
		(start 429.582326 -28.875736)
		(end 429.582326 -28.329636)
		(width 0.13208)
		(layer "F.Cu")
		(net "P3V3_SSD15_CO_MODE")
	)
	(via
		(at 430.349914 -28.139136)
		(size 0.508)
		(drill 0.254)
		(layers "F.Cu" "B.Cu")
		(net "P3V3_SSD15_CO_MODE")
	)
	(segment
		(start 314.249816 -28.139136)
		(end 313.672728 -28.139136)
		(width 0.13208)
		(layer "F.Cu")
		(net "P3V3_SSD11_CO_MODE")
	)
	(segment
		(start 313.557666 -27.406346)
		(end 314.573666 -27.406346)
		(width 0.13208)
		(layer "F.Cu")
		(net "P3V3_SSD11_CO_MODE")
	)
	(segment
		(start 314.573666 -27.406346)
		(end 314.573666 -27.815286)
		(width 0.13208)
		(layer "F.Cu")
		(net "P3V3_SSD11_CO_MODE")
	)
	(segment
		(start 314.573666 -27.815286)
		(end 314.249816 -28.139136)
		(width 0.13208)
		(layer "F.Cu")
		(net "P3V3_SSD11_CO_MODE")
	)
	(segment
		(start 313.672728 -28.139136)
		(end 313.482228 -28.329636)
		(width 0.13208)
		(layer "F.Cu")
		(net "P3V3_SSD11_CO_MODE")
	)
	(segment
		(start 313.482228 -28.329636)
		(end 313.482228 -28.875736)
		(width 0.13208)
		(layer "F.Cu")
		(net "P3V3_SSD11_CO_MODE")
	)
	(via
		(at 314.249816 -28.139136)
		(size 0.508)
		(drill 0.254)
		(layers "F.Cu" "B.Cu")
		(net "P3V3_SSD11_CO_MODE")
	)
	(segment
		(start 251.846842 -38.49116)
		(end 251.846842 -37.47516)
		(width 0.13208)
		(layer "F.Cu")
		(net "P3V3_SSD9_PG_G1")
	)
	(segment
		(start 252.27407 -37.47516)
		(end 251.846842 -37.47516)
		(width 0.13208)
		(layer "F.Cu")
		(net "P3V3_SSD9_PG_G1")
	)
	(segment
		(start 252.461268 -37.662358)
		(end 252.27407 -37.47516)
		(width 0.13208)
		(layer "F.Cu")
		(net "P3V3_SSD9_PG_G1")
	)
	(segment
		(start 252.530356 -37.662358)
		(end 252.461268 -37.662358)
		(width 0.13208)
		(layer "F.Cu")
		(net "P3V3_SSD9_PG_G1")
	)
	(segment
		(start 252.819154 -37.951156)
		(end 252.530356 -37.662358)
		(width 0.13208)
		(layer "F.Cu")
		(net "P3V3_SSD9_PG_G1")
	)
	(segment
		(start 253.261114 -37.951156)
		(end 252.819154 -37.951156)
		(width 0.13208)
		(layer "F.Cu")
		(net "P3V3_SSD9_PG_G1")
	)
	(via
		(at 252.530356 -37.662358)
		(size 0.508)
		(drill 0.254)
		(layers "F.Cu" "B.Cu")
		(net "P3V3_SSD9_PG_G1")
	)
	(segment
		(start 403.082506 -28.875736)
		(end 403.082506 -28.141676)
		(width 0.13208)
		(layer "F.Cu")
		(net "P3V3_SSD14_CO_ILIMIT")
	)
	(segment
		(start 403.079966 -28.139136)
		(end 402.641816 -27.700986)
		(width 0.13208)
		(layer "F.Cu")
		(net "P3V3_SSD14_CO_ILIMIT")
	)
	(segment
		(start 403.082506 -28.141676)
		(end 403.079966 -28.139136)
		(width 0.13208)
		(layer "F.Cu")
		(net "P3V3_SSD14_CO_ILIMIT")
	)
	(segment
		(start 402.641816 -27.700986)
		(end 402.641816 -27.406346)
		(width 0.13208)
		(layer "F.Cu")
		(net "P3V3_SSD14_CO_ILIMIT")
	)
	(via
		(at 403.079966 -28.139136)
		(size 0.508)
		(drill 0.254)
		(layers "F.Cu" "B.Cu")
		(net "P3V3_SSD14_CO_ILIMIT")
	)
	(segment
		(start 226.530408 -37.662358)
		(end 226.46132 -37.662358)
		(width 0.13208)
		(layer "F.Cu")
		(net "P3V3_SSD8_PG_G1")
	)
	(segment
		(start 225.846894 -38.49116)
		(end 225.846894 -37.47516)
		(width 0.13208)
		(layer "F.Cu")
		(net "P3V3_SSD8_PG_G1")
	)
	(segment
		(start 226.46132 -37.662358)
		(end 226.274122 -37.47516)
		(width 0.13208)
		(layer "F.Cu")
		(net "P3V3_SSD8_PG_G1")
	)
	(segment
		(start 226.274122 -37.47516)
		(end 225.846894 -37.47516)
		(width 0.13208)
		(layer "F.Cu")
		(net "P3V3_SSD8_PG_G1")
	)
	(segment
		(start 227.261166 -37.951156)
		(end 226.819206 -37.951156)
		(width 0.13208)
		(layer "F.Cu")
		(net "P3V3_SSD8_PG_G1")
	)
	(segment
		(start 226.819206 -37.951156)
		(end 226.530408 -37.662358)
		(width 0.13208)
		(layer "F.Cu")
		(net "P3V3_SSD8_PG_G1")
	)
	(via
		(at 226.530408 -37.662358)
		(size 0.508)
		(drill 0.254)
		(layers "F.Cu" "B.Cu")
		(net "P3V3_SSD8_PG_G1")
	)
	(segment
		(start 350.967548 -32.25927)
		(end 351.15627 -32.447992)
		(width 0.13208)
		(layer "F.Cu")
		(net "P3V3_SSD12_CO_EN")
	)
	(segment
		(start 350.967548 -31.719266)
		(end 350.967548 -32.25927)
		(width 0.13208)
		(layer "F.Cu")
		(net "P3V3_SSD12_CO_EN")
	)
	(segment
		(start 351.08261 -31.44139)
		(end 350.967548 -31.719266)
		(width 0.13208)
		(layer "F.Cu")
		(net "P3V3_SSD12_CO_EN")
	)
	(segment
		(start 351.08261 -30.875732)
		(end 351.08261 -31.44139)
		(width 0.13208)
		(layer "F.Cu")
		(net "P3V3_SSD12_CO_EN")
	)
	(via
		(at 350.967548 -31.719266)
		(size 0.508)
		(drill 0.254)
		(layers "F.Cu" "B.Cu")
		(net "P3V3_SSD12_CO_EN")
	)
	(segment
		(start 233.588814 -31.996634)
		(end 234.040172 -32.447992)
		(width 0.13208)
		(layer "F.Cu")
		(net "P3V3_SSD8_CO_DV_DT")
	)
	(segment
		(start 234.48264 -30.875732)
		(end 234.48264 -31.274004)
		(width 0.13208)
		(layer "F.Cu")
		(net "P3V3_SSD8_CO_DV_DT")
	)
	(segment
		(start 233.580686 -31.567882)
		(end 233.588814 -31.57601)
		(width 0.13208)
		(layer "F.Cu")
		(net "P3V3_SSD8_CO_DV_DT")
	)
	(segment
		(start 234.48264 -31.274004)
		(end 234.188762 -31.567882)
		(width 0.13208)
		(layer "F.Cu")
		(net "P3V3_SSD8_CO_DV_DT")
	)
	(segment
		(start 234.188762 -31.567882)
		(end 233.580686 -31.567882)
		(width 0.13208)
		(layer "F.Cu")
		(net "P3V3_SSD8_CO_DV_DT")
	)
	(segment
		(start 233.588814 -31.57601)
		(end 233.588814 -31.996634)
		(width 0.13208)
		(layer "F.Cu")
		(net "P3V3_SSD8_CO_DV_DT")
	)
	(via
		(at 233.580686 -31.567882)
		(size 0.508)
		(drill 0.254)
		(layers "F.Cu" "B.Cu")
		(net "P3V3_SSD8_CO_DV_DT")
	)
	(segment
		(start 367.94694 -38.49116)
		(end 367.94694 -37.47516)
		(width 0.13208)
		(layer "F.Cu")
		(net "P3V3_SSD13_PG_G1")
	)
	(segment
		(start 368.561366 -37.662358)
		(end 368.374168 -37.47516)
		(width 0.13208)
		(layer "F.Cu")
		(net "P3V3_SSD13_PG_G1")
	)
	(segment
		(start 368.630454 -37.662358)
		(end 368.561366 -37.662358)
		(width 0.13208)
		(layer "F.Cu")
		(net "P3V3_SSD13_PG_G1")
	)
	(segment
		(start 369.361212 -37.951156)
		(end 368.919252 -37.951156)
		(width 0.13208)
		(layer "F.Cu")
		(net "P3V3_SSD13_PG_G1")
	)
	(segment
		(start 368.919252 -37.951156)
		(end 368.630454 -37.662358)
		(width 0.13208)
		(layer "F.Cu")
		(net "P3V3_SSD13_PG_G1")
	)
	(segment
		(start 368.374168 -37.47516)
		(end 367.94694 -37.47516)
		(width 0.13208)
		(layer "F.Cu")
		(net "P3V3_SSD13_PG_G1")
	)
	(via
		(at 368.630454 -37.662358)
		(size 0.508)
		(drill 0.254)
		(layers "F.Cu" "B.Cu")
		(net "P3V3_SSD13_PG_G1")
	)
	(segment
		(start 261.05612 -32.447992)
		(end 260.867398 -32.25927)
		(width 0.13208)
		(layer "F.Cu")
		(net "P3V3_SSD9_CO_EN")
	)
	(segment
		(start 260.867398 -32.25927)
		(end 260.867398 -31.719266)
		(width 0.13208)
		(layer "F.Cu")
		(net "P3V3_SSD9_CO_EN")
	)
	(segment
		(start 260.867398 -31.719266)
		(end 260.98246 -31.44139)
		(width 0.13208)
		(layer "F.Cu")
		(net "P3V3_SSD9_CO_EN")
	)
	(segment
		(start 260.98246 -31.44139)
		(end 260.98246 -30.875732)
		(width 0.13208)
		(layer "F.Cu")
		(net "P3V3_SSD9_CO_EN")
	)
	(via
		(at 260.867398 -31.719266)
		(size 0.508)
		(drill 0.254)
		(layers "F.Cu" "B.Cu")
		(net "P3V3_SSD9_CO_EN")
	)
	(segment
		(start 394.561314 -37.662358)
		(end 394.374116 -37.47516)
		(width 0.13208)
		(layer "F.Cu")
		(net "P3V3_SSD14_PG_G1")
	)
	(segment
		(start 394.9192 -37.951156)
		(end 394.630402 -37.662358)
		(width 0.13208)
		(layer "F.Cu")
		(net "P3V3_SSD14_PG_G1")
	)
	(segment
		(start 394.630402 -37.662358)
		(end 394.561314 -37.662358)
		(width 0.13208)
		(layer "F.Cu")
		(net "P3V3_SSD14_PG_G1")
	)
	(segment
		(start 395.36116 -37.951156)
		(end 394.9192 -37.951156)
		(width 0.13208)
		(layer "F.Cu")
		(net "P3V3_SSD14_PG_G1")
	)
	(segment
		(start 393.946888 -38.49116)
		(end 393.946888 -37.47516)
		(width 0.13208)
		(layer "F.Cu")
		(net "P3V3_SSD14_PG_G1")
	)
	(segment
		(start 394.374116 -37.47516)
		(end 393.946888 -37.47516)
		(width 0.13208)
		(layer "F.Cu")
		(net "P3V3_SSD14_PG_G1")
	)
	(via
		(at 394.630402 -37.662358)
		(size 0.508)
		(drill 0.254)
		(layers "F.Cu" "B.Cu")
		(net "P3V3_SSD14_PG_G1")
	)
	(segment
		(start 342.561418 -37.662358)
		(end 342.37422 -37.47516)
		(width 0.13208)
		(layer "F.Cu")
		(net "P3V3_SSD12_PG_G1")
	)
	(segment
		(start 342.919304 -37.951156)
		(end 342.630506 -37.662358)
		(width 0.13208)
		(layer "F.Cu")
		(net "P3V3_SSD12_PG_G1")
	)
	(segment
		(start 342.37422 -37.47516)
		(end 341.946992 -37.47516)
		(width 0.13208)
		(layer "F.Cu")
		(net "P3V3_SSD12_PG_G1")
	)
	(segment
		(start 342.630506 -37.662358)
		(end 342.561418 -37.662358)
		(width 0.13208)
		(layer "F.Cu")
		(net "P3V3_SSD12_PG_G1")
	)
	(segment
		(start 343.361264 -37.951156)
		(end 342.919304 -37.951156)
		(width 0.13208)
		(layer "F.Cu")
		(net "P3V3_SSD12_PG_G1")
	)
	(segment
		(start 341.946992 -38.49116)
		(end 341.946992 -37.47516)
		(width 0.13208)
		(layer "F.Cu")
		(net "P3V3_SSD12_PG_G1")
	)
	(via
		(at 342.630506 -37.662358)
		(size 0.508)
		(drill 0.254)
		(layers "F.Cu" "B.Cu")
		(net "P3V3_SSD12_PG_G1")
	)
	(segment
		(start 136.71931 -37.951156)
		(end 136.430512 -37.662358)
		(width 0.13208)
		(layer "F.Cu")
		(net "P3V3_SSD5_PG_G1")
	)
	(segment
		(start 136.430512 -37.662358)
		(end 136.361424 -37.662358)
		(width 0.13208)
		(layer "F.Cu")
		(net "P3V3_SSD5_PG_G1")
	)
	(segment
		(start 136.174226 -37.47516)
		(end 135.746998 -37.47516)
		(width 0.13208)
		(layer "F.Cu")
		(net "P3V3_SSD5_PG_G1")
	)
	(segment
		(start 135.746998 -38.49116)
		(end 135.746998 -37.47516)
		(width 0.13208)
		(layer "F.Cu")
		(net "P3V3_SSD5_PG_G1")
	)
	(segment
		(start 136.361424 -37.662358)
		(end 136.174226 -37.47516)
		(width 0.13208)
		(layer "F.Cu")
		(net "P3V3_SSD5_PG_G1")
	)
	(segment
		(start 137.16127 -37.951156)
		(end 136.71931 -37.951156)
		(width 0.13208)
		(layer "F.Cu")
		(net "P3V3_SSD5_PG_G1")
	)
	(via
		(at 136.430512 -37.662358)
		(size 0.508)
		(drill 0.254)
		(layers "F.Cu" "B.Cu")
		(net "P3V3_SSD5_PG_G1")
	)
	(segment
		(start 286.188658 -31.567882)
		(end 285.580582 -31.567882)
		(width 0.13208)
		(layer "F.Cu")
		(net "P3V3_SSD10_CO_DV_DT")
	)
	(segment
		(start 285.58871 -31.57601)
		(end 285.58871 -31.996634)
		(width 0.13208)
		(layer "F.Cu")
		(net "P3V3_SSD10_CO_DV_DT")
	)
	(segment
		(start 286.482536 -30.875732)
		(end 286.482536 -31.274004)
		(width 0.13208)
		(layer "F.Cu")
		(net "P3V3_SSD10_CO_DV_DT")
	)
	(segment
		(start 286.482536 -31.274004)
		(end 286.188658 -31.567882)
		(width 0.13208)
		(layer "F.Cu")
		(net "P3V3_SSD10_CO_DV_DT")
	)
	(segment
		(start 285.580582 -31.567882)
		(end 285.58871 -31.57601)
		(width 0.13208)
		(layer "F.Cu")
		(net "P3V3_SSD10_CO_DV_DT")
	)
	(segment
		(start 285.58871 -31.996634)
		(end 286.040068 -32.447992)
		(width 0.13208)
		(layer "F.Cu")
		(net "P3V3_SSD10_CO_DV_DT")
	)
	(via
		(at 285.580582 -31.567882)
		(size 0.508)
		(drill 0.254)
		(layers "F.Cu" "B.Cu")
		(net "P3V3_SSD10_CO_DV_DT")
	)
	(segment
		(start 428.967392 -32.25927)
		(end 429.156114 -32.447992)
		(width 0.13208)
		(layer "F.Cu")
		(net "P3V3_SSD15_CO_EN")
	)
	(segment
		(start 429.082454 -30.875732)
		(end 429.082454 -31.44139)
		(width 0.13208)
		(layer "F.Cu")
		(net "P3V3_SSD15_CO_EN")
	)
	(segment
		(start 429.082454 -31.44139)
		(end 428.967392 -31.719266)
		(width 0.13208)
		(layer "F.Cu")
		(net "P3V3_SSD15_CO_EN")
	)
	(segment
		(start 428.967392 -31.719266)
		(end 428.967392 -32.25927)
		(width 0.13208)
		(layer "F.Cu")
		(net "P3V3_SSD15_CO_EN")
	)
	(via
		(at 428.967392 -31.719266)
		(size 0.508)
		(drill 0.254)
		(layers "F.Cu" "B.Cu")
		(net "P3V3_SSD15_CO_EN")
	)
	(segment
		(start 118.882668 -28.141676)
		(end 118.880128 -28.139136)
		(width 0.13208)
		(layer "F.Cu")
		(net "P3V3_SSD4_CO_ILIMIT")
	)
	(segment
		(start 118.880128 -28.139136)
		(end 118.441978 -27.700986)
		(width 0.13208)
		(layer "F.Cu")
		(net "P3V3_SSD4_CO_ILIMIT")
	)
	(segment
		(start 118.441978 -27.700986)
		(end 118.441978 -27.406346)
		(width 0.13208)
		(layer "F.Cu")
		(net "P3V3_SSD4_CO_ILIMIT")
	)
	(segment
		(start 118.882668 -28.875736)
		(end 118.882668 -28.141676)
		(width 0.13208)
		(layer "F.Cu")
		(net "P3V3_SSD4_CO_ILIMIT")
	)
	(via
		(at 118.880128 -28.139136)
		(size 0.508)
		(drill 0.254)
		(layers "F.Cu" "B.Cu")
		(net "P3V3_SSD4_CO_ILIMIT")
	)
	(segment
		(start 236.072172 -32.076898)
		(end 236.072172 -32.447992)
		(width 0.13208)
		(layer "F.Cu")
		(net "P3V3_SSD8_CO_GATE")
	)
	(segment
		(start 236.143038 -32.006032)
		(end 236.072172 -32.076898)
		(width 0.13208)
		(layer "F.Cu")
		(net "P3V3_SSD8_CO_GATE")
	)
	(segment
		(start 236.143038 -31.664402)
		(end 236.143038 -32.006032)
		(width 0.13208)
		(layer "F.Cu")
		(net "P3V3_SSD8_CO_GATE")
	)
	(segment
		(start 235.482384 -30.875732)
		(end 235.482384 -31.537402)
		(width 0.13208)
		(layer "F.Cu")
		(net "P3V3_SSD8_CO_GATE")
	)
	(segment
		(start 235.482384 -31.537402)
		(end 235.609384 -31.664402)
		(width 0.13208)
		(layer "F.Cu")
		(net "P3V3_SSD8_CO_GATE")
	)
	(segment
		(start 235.609384 -31.664402)
		(end 236.143038 -31.664402)
		(width 0.13208)
		(layer "F.Cu")
		(net "P3V3_SSD8_CO_GATE")
	)
	(via
		(at 236.143038 -31.664402)
		(size 0.508)
		(drill 0.254)
		(layers "F.Cu" "B.Cu")
		(net "P3V3_SSD8_CO_GATE")
	)
	(segment
		(start 350.28886 -31.567882)
		(end 349.680784 -31.567882)
		(width 0.13208)
		(layer "F.Cu")
		(net "P3V3_SSD12_CO_DV_DT")
	)
	(segment
		(start 350.582738 -30.875732)
		(end 350.582738 -31.274004)
		(width 0.13208)
		(layer "F.Cu")
		(net "P3V3_SSD12_CO_DV_DT")
	)
	(segment
		(start 349.688912 -31.57601)
		(end 349.688912 -31.996634)
		(width 0.13208)
		(layer "F.Cu")
		(net "P3V3_SSD12_CO_DV_DT")
	)
	(segment
		(start 350.582738 -31.274004)
		(end 350.28886 -31.567882)
		(width 0.13208)
		(layer "F.Cu")
		(net "P3V3_SSD12_CO_DV_DT")
	)
	(segment
		(start 349.688912 -31.996634)
		(end 350.14027 -32.447992)
		(width 0.13208)
		(layer "F.Cu")
		(net "P3V3_SSD12_CO_DV_DT")
	)
	(segment
		(start 349.680784 -31.567882)
		(end 349.688912 -31.57601)
		(width 0.13208)
		(layer "F.Cu")
		(net "P3V3_SSD12_CO_DV_DT")
	)
	(via
		(at 349.680784 -31.567882)
		(size 0.508)
		(drill 0.254)
		(layers "F.Cu" "B.Cu")
		(net "P3V3_SSD12_CO_DV_DT")
	)
	(segment
		(start 170.767502 -31.719266)
		(end 170.767502 -32.25927)
		(width 0.13208)
		(layer "F.Cu")
		(net "P3V3_SSD6_CO_EN")
	)
	(segment
		(start 170.767502 -32.25927)
		(end 170.956224 -32.447992)
		(width 0.13208)
		(layer "F.Cu")
		(net "P3V3_SSD6_CO_EN")
	)
	(segment
		(start 170.882564 -31.44139)
		(end 170.767502 -31.719266)
		(width 0.13208)
		(layer "F.Cu")
		(net "P3V3_SSD6_CO_EN")
	)
	(segment
		(start 170.882564 -30.875732)
		(end 170.882564 -31.44139)
		(width 0.13208)
		(layer "F.Cu")
		(net "P3V3_SSD6_CO_EN")
	)
	(via
		(at 170.767502 -31.719266)
		(size 0.508)
		(drill 0.254)
		(layers "F.Cu" "B.Cu")
		(net "P3V3_SSD6_CO_EN")
	)
	(segment
		(start 278.274018 -37.47516)
		(end 277.84679 -37.47516)
		(width 0.13208)
		(layer "F.Cu")
		(net "P3V3_SSD10_PG_G1")
	)
	(segment
		(start 278.819102 -37.951156)
		(end 278.530304 -37.662358)
		(width 0.13208)
		(layer "F.Cu")
		(net "P3V3_SSD10_PG_G1")
	)
	(segment
		(start 279.261062 -37.951156)
		(end 278.819102 -37.951156)
		(width 0.13208)
		(layer "F.Cu")
		(net "P3V3_SSD10_PG_G1")
	)
	(segment
		(start 277.84679 -38.49116)
		(end 277.84679 -37.47516)
		(width 0.13208)
		(layer "F.Cu")
		(net "P3V3_SSD10_PG_G1")
	)
	(segment
		(start 278.461216 -37.662358)
		(end 278.274018 -37.47516)
		(width 0.13208)
		(layer "F.Cu")
		(net "P3V3_SSD10_PG_G1")
	)
	(segment
		(start 278.530304 -37.662358)
		(end 278.461216 -37.662358)
		(width 0.13208)
		(layer "F.Cu")
		(net "P3V3_SSD10_PG_G1")
	)
	(via
		(at 278.530304 -37.662358)
		(size 0.508)
		(drill 0.254)
		(layers "F.Cu" "B.Cu")
		(net "P3V3_SSD10_PG_G1")
	)
	(segment
		(start 375.68886 -32.39135)
		(end 375.632218 -32.447992)
		(width 0.13208)
		(layer "F.Cu")
		(net "P3V3_SSD13_CO_DV_DT")
	)
	(segment
		(start 376.582686 -31.274004)
		(end 376.288808 -31.567882)
		(width 0.13208)
		(layer "F.Cu")
		(net "P3V3_SSD13_CO_DV_DT")
	)
	(segment
		(start 376.288808 -31.567882)
		(end 375.680732 -31.567882)
		(width 0.13208)
		(layer "F.Cu")
		(net "P3V3_SSD13_CO_DV_DT")
	)
	(segment
		(start 375.68886 -31.57601)
		(end 375.68886 -32.39135)
		(width 0.13208)
		(layer "F.Cu")
		(net "P3V3_SSD13_CO_DV_DT")
	)
	(segment
		(start 375.680732 -31.567882)
		(end 375.68886 -31.57601)
		(width 0.13208)
		(layer "F.Cu")
		(net "P3V3_SSD13_CO_DV_DT")
	)
	(segment
		(start 376.582686 -30.875732)
		(end 376.582686 -31.274004)
		(width 0.13208)
		(layer "F.Cu")
		(net "P3V3_SSD13_CO_DV_DT")
	)
	(via
		(at 375.680732 -31.567882)
		(size 0.508)
		(drill 0.254)
		(layers "F.Cu" "B.Cu")
		(net "P3V3_SSD13_CO_DV_DT")
	)
	(segment
		(start 138.961114 -37.951156)
		(end 140.092176 -37.951156)
		(width 0.13208)
		(layer "F.Cu")
		(net "P3V3_SSD5_PG_G2")
	)
	(segment
		(start 140.092176 -37.951156)
		(end 140.182092 -38.041072)
		(width 0.13208)
		(layer "F.Cu")
		(net "P3V3_SSD5_PG_G2")
	)
	(segment
		(start 138.961114 -38.701218)
		(end 140.180568 -38.701218)
		(width 0.13208)
		(layer "F.Cu")
		(net "P3V3_SSD5_PG_G2")
	)
	(segment
		(start 140.182092 -38.702742)
		(end 140.182092 -38.041072)
		(width 0.13208)
		(layer "F.Cu")
		(net "P3V3_SSD5_PG_G2")
	)
	(segment
		(start 140.180568 -38.701218)
		(end 140.182092 -38.702742)
		(width 0.13208)
		(layer "F.Cu")
		(net "P3V3_SSD5_PG_G2")
	)
	(via
		(at 140.182092 -38.702742)
		(size 0.508)
		(drill 0.254)
		(layers "F.Cu" "B.Cu")
		(net "P3V3_SSD5_PG_G2")
	)
	(segment
		(start 351.582482 -28.329636)
		(end 351.772982 -28.139136)
		(width 0.13208)
		(layer "F.Cu")
		(net "P3V3_SSD12_CO_MODE")
	)
	(segment
		(start 351.65792 -27.406346)
		(end 352.67392 -27.406346)
		(width 0.13208)
		(layer "F.Cu")
		(net "P3V3_SSD12_CO_MODE")
	)
	(segment
		(start 352.67392 -27.815286)
		(end 352.67392 -27.406346)
		(width 0.13208)
		(layer "F.Cu")
		(net "P3V3_SSD12_CO_MODE")
	)
	(segment
		(start 352.35007 -28.139136)
		(end 352.67392 -27.815286)
		(width 0.13208)
		(layer "F.Cu")
		(net "P3V3_SSD12_CO_MODE")
	)
	(segment
		(start 351.582482 -28.875736)
		(end 351.582482 -28.329636)
		(width 0.13208)
		(layer "F.Cu")
		(net "P3V3_SSD12_CO_MODE")
	)
	(segment
		(start 351.772982 -28.139136)
		(end 352.35007 -28.139136)
		(width 0.13208)
		(layer "F.Cu")
		(net "P3V3_SSD12_CO_MODE")
	)
	(via
		(at 352.35007 -28.139136)
		(size 0.508)
		(drill 0.254)
		(layers "F.Cu" "B.Cu")
		(net "P3V3_SSD12_CO_MODE")
	)
	(segment
		(start 145.382488 -28.329636)
		(end 145.572988 -28.139136)
		(width 0.13208)
		(layer "F.Cu")
		(net "P3V3_SSD5_CO_MODE")
	)
	(segment
		(start 145.382488 -28.875736)
		(end 145.382488 -28.329636)
		(width 0.13208)
		(layer "F.Cu")
		(net "P3V3_SSD5_CO_MODE")
	)
	(segment
		(start 145.572988 -28.139136)
		(end 146.150076 -28.139136)
		(width 0.13208)
		(layer "F.Cu")
		(net "P3V3_SSD5_CO_MODE")
	)
	(segment
		(start 146.473926 -27.815286)
		(end 146.473926 -27.406346)
		(width 0.13208)
		(layer "F.Cu")
		(net "P3V3_SSD5_CO_MODE")
	)
	(segment
		(start 145.457926 -27.406346)
		(end 146.473926 -27.406346)
		(width 0.13208)
		(layer "F.Cu")
		(net "P3V3_SSD5_CO_MODE")
	)
	(segment
		(start 146.150076 -28.139136)
		(end 146.473926 -27.815286)
		(width 0.13208)
		(layer "F.Cu")
		(net "P3V3_SSD5_CO_MODE")
	)
	(via
		(at 146.150076 -28.139136)
		(size 0.508)
		(drill 0.254)
		(layers "F.Cu" "B.Cu")
		(net "P3V3_SSD5_CO_MODE")
	)
	(segment
		(start 312.867294 -31.719266)
		(end 312.867294 -32.25927)
		(width 0.13208)
		(layer "F.Cu")
		(net "P3V3_SSD11_CO_EN")
	)
	(segment
		(start 312.867294 -32.25927)
		(end 313.056016 -32.447992)
		(width 0.13208)
		(layer "F.Cu")
		(net "P3V3_SSD11_CO_EN")
	)
	(segment
		(start 312.982356 -31.44139)
		(end 312.867294 -31.719266)
		(width 0.13208)
		(layer "F.Cu")
		(net "P3V3_SSD11_CO_EN")
	)
	(segment
		(start 312.982356 -30.875732)
		(end 312.982356 -31.44139)
		(width 0.13208)
		(layer "F.Cu")
		(net "P3V3_SSD11_CO_EN")
	)
	(via
		(at 312.867294 -31.719266)
		(size 0.508)
		(drill 0.254)
		(layers "F.Cu" "B.Cu")
		(net "P3V3_SSD11_CO_EN")
	)
	(segment
		(start 345.161108 -38.701218)
		(end 346.380562 -38.701218)
		(width 0.13208)
		(layer "F.Cu")
		(net "P3V3_SSD12_PG_G2")
	)
	(segment
		(start 346.380562 -38.701218)
		(end 346.382086 -38.702742)
		(width 0.13208)
		(layer "F.Cu")
		(net "P3V3_SSD12_PG_G2")
	)
	(segment
		(start 346.29217 -37.951156)
		(end 346.382086 -38.041072)
		(width 0.13208)
		(layer "F.Cu")
		(net "P3V3_SSD12_PG_G2")
	)
	(segment
		(start 345.161108 -37.951156)
		(end 346.29217 -37.951156)
		(width 0.13208)
		(layer "F.Cu")
		(net "P3V3_SSD12_PG_G2")
	)
	(segment
		(start 346.382086 -38.702742)
		(end 346.382086 -38.041072)
		(width 0.13208)
		(layer "F.Cu")
		(net "P3V3_SSD12_PG_G2")
	)
	(via
		(at 346.382086 -38.702742)
		(size 0.508)
		(drill 0.254)
		(layers "F.Cu" "B.Cu")
		(net "P3V3_SSD12_PG_G2")
	)
	(segment
		(start 197.457822 -27.406346)
		(end 198.473822 -27.406346)
		(width 0.13208)
		(layer "F.Cu")
		(net "P3V3_SSD7_CO_MODE")
	)
	(segment
		(start 198.473822 -27.815286)
		(end 198.149972 -28.139136)
		(width 0.13208)
		(layer "F.Cu")
		(net "P3V3_SSD7_CO_MODE")
	)
	(segment
		(start 197.382384 -28.875736)
		(end 197.382384 -28.329636)
		(width 0.13208)
		(layer "F.Cu")
		(net "P3V3_SSD7_CO_MODE")
	)
	(segment
		(start 198.473822 -27.406346)
		(end 198.473822 -27.815286)
		(width 0.13208)
		(layer "F.Cu")
		(net "P3V3_SSD7_CO_MODE")
	)
	(segment
		(start 197.572884 -28.139136)
		(end 198.149972 -28.139136)
		(width 0.13208)
		(layer "F.Cu")
		(net "P3V3_SSD7_CO_MODE")
	)
	(segment
		(start 197.382384 -28.329636)
		(end 197.572884 -28.139136)
		(width 0.13208)
		(layer "F.Cu")
		(net "P3V3_SSD7_CO_MODE")
	)
	(via
		(at 198.149972 -28.139136)
		(size 0.508)
		(drill 0.254)
		(layers "F.Cu" "B.Cu")
		(net "P3V3_SSD7_CO_MODE")
	)
	(segment
		(start 234.982512 -31.44139)
		(end 234.86745 -31.719266)
		(width 0.13208)
		(layer "F.Cu")
		(net "P3V3_SSD8_CO_EN")
	)
	(segment
		(start 234.982512 -30.875732)
		(end 234.982512 -31.44139)
		(width 0.13208)
		(layer "F.Cu")
		(net "P3V3_SSD8_CO_EN")
	)
	(segment
		(start 234.86745 -31.719266)
		(end 234.86745 -32.25927)
		(width 0.13208)
		(layer "F.Cu")
		(net "P3V3_SSD8_CO_EN")
	)
	(segment
		(start 234.86745 -32.25927)
		(end 235.056172 -32.447992)
		(width 0.13208)
		(layer "F.Cu")
		(net "P3V3_SSD8_CO_EN")
	)
	(via
		(at 234.86745 -31.719266)
		(size 0.508)
		(drill 0.254)
		(layers "F.Cu" "B.Cu")
		(net "P3V3_SSD8_CO_EN")
	)
	(segment
		(start 372.382034 -38.702742)
		(end 372.382034 -38.041072)
		(width 0.13208)
		(layer "F.Cu")
		(net "P3V3_SSD13_PG_G2")
	)
	(segment
		(start 372.382034 -38.041072)
		(end 372.292118 -37.951156)
		(width 0.13208)
		(layer "F.Cu")
		(net "P3V3_SSD13_PG_G2")
	)
	(segment
		(start 372.292118 -37.951156)
		(end 371.161056 -37.951156)
		(width 0.13208)
		(layer "F.Cu")
		(net "P3V3_SSD13_PG_G2")
	)
	(segment
		(start 372.38051 -38.701218)
		(end 371.161056 -38.701218)
		(width 0.13208)
		(layer "F.Cu")
		(net "P3V3_SSD13_PG_G2")
	)
	(segment
		(start 372.382034 -38.702742)
		(end 372.38051 -38.701218)
		(width 0.13208)
		(layer "F.Cu")
		(net "P3V3_SSD13_PG_G2")
	)
	(via
		(at 372.382034 -38.702742)
		(size 0.508)
		(drill 0.254)
		(layers "F.Cu" "B.Cu")
		(net "P3V3_SSD13_PG_G2")
	)
	(segment
		(start 170.882564 -28.875736)
		(end 170.882564 -28.141676)
		(width 0.13208)
		(layer "F.Cu")
		(net "P3V3_SSD6_CO_ILIMIT")
	)
	(segment
		(start 170.882564 -28.141676)
		(end 170.880024 -28.139136)
		(width 0.13208)
		(layer "F.Cu")
		(net "P3V3_SSD6_CO_ILIMIT")
	)
	(segment
		(start 170.880024 -28.139136)
		(end 170.441874 -27.700986)
		(width 0.13208)
		(layer "F.Cu")
		(net "P3V3_SSD6_CO_ILIMIT")
	)
	(segment
		(start 170.441874 -27.700986)
		(end 170.441874 -27.406346)
		(width 0.13208)
		(layer "F.Cu")
		(net "P3V3_SSD6_CO_ILIMIT")
	)
	(via
		(at 170.880024 -28.139136)
		(size 0.508)
		(drill 0.254)
		(layers "F.Cu" "B.Cu")
		(net "P3V3_SSD6_CO_ILIMIT")
	)
	(segment
		(start 304.461164 -37.662358)
		(end 304.530252 -37.662358)
		(width 0.13208)
		(layer "F.Cu")
		(net "P3V3_SSD11_PG_G1")
	)
	(segment
		(start 303.846738 -38.49116)
		(end 303.846738 -37.47516)
		(width 0.13208)
		(layer "F.Cu")
		(net "P3V3_SSD11_PG_G1")
	)
	(segment
		(start 305.26101 -37.951156)
		(end 304.81905 -37.951156)
		(width 0.13208)
		(layer "F.Cu")
		(net "P3V3_SSD11_PG_G1")
	)
	(segment
		(start 303.846738 -37.47516)
		(end 304.273966 -37.47516)
		(width 0.13208)
		(layer "F.Cu")
		(net "P3V3_SSD11_PG_G1")
	)
	(segment
		(start 304.81905 -37.951156)
		(end 304.530252 -37.662358)
		(width 0.13208)
		(layer "F.Cu")
		(net "P3V3_SSD11_PG_G1")
	)
	(segment
		(start 304.273966 -37.47516)
		(end 304.461164 -37.662358)
		(width 0.13208)
		(layer "F.Cu")
		(net "P3V3_SSD11_PG_G1")
	)
	(via
		(at 304.530252 -37.662358)
		(size 0.508)
		(drill 0.254)
		(layers "F.Cu" "B.Cu")
		(net "P3V3_SSD11_PG_G1")
	)
	(segment
		(start 420.63035 -37.662358)
		(end 420.561262 -37.662358)
		(width 0.13208)
		(layer "F.Cu")
		(net "P3V3_SSD15_PG_G1")
	)
	(segment
		(start 420.561262 -37.662358)
		(end 420.374064 -37.47516)
		(width 0.13208)
		(layer "F.Cu")
		(net "P3V3_SSD15_PG_G1")
	)
	(segment
		(start 420.374064 -37.47516)
		(end 419.946836 -37.47516)
		(width 0.13208)
		(layer "F.Cu")
		(net "P3V3_SSD15_PG_G1")
	)
	(segment
		(start 421.361108 -37.951156)
		(end 420.919148 -37.951156)
		(width 0.13208)
		(layer "F.Cu")
		(net "P3V3_SSD15_PG_G1")
	)
	(segment
		(start 419.946836 -38.49116)
		(end 419.946836 -37.47516)
		(width 0.13208)
		(layer "F.Cu")
		(net "P3V3_SSD15_PG_G1")
	)
	(segment
		(start 420.919148 -37.951156)
		(end 420.63035 -37.662358)
		(width 0.13208)
		(layer "F.Cu")
		(net "P3V3_SSD15_PG_G1")
	)
	(via
		(at 420.63035 -37.662358)
		(size 0.508)
		(drill 0.254)
		(layers "F.Cu" "B.Cu")
		(net "P3V3_SSD15_PG_G1")
	)
	(segment
		(start 110.174278 -37.47516)
		(end 109.74705 -37.47516)
		(width 0.13208)
		(layer "F.Cu")
		(net "P3V3_SSD4_PG_G1")
	)
	(segment
		(start 111.161322 -37.951156)
		(end 110.719362 -37.951156)
		(width 0.13208)
		(layer "F.Cu")
		(net "P3V3_SSD4_PG_G1")
	)
	(segment
		(start 110.361476 -37.662358)
		(end 110.174278 -37.47516)
		(width 0.13208)
		(layer "F.Cu")
		(net "P3V3_SSD4_PG_G1")
	)
	(segment
		(start 110.430564 -37.662358)
		(end 110.361476 -37.662358)
		(width 0.13208)
		(layer "F.Cu")
		(net "P3V3_SSD4_PG_G1")
	)
	(segment
		(start 109.74705 -38.49116)
		(end 109.74705 -37.47516)
		(width 0.13208)
		(layer "F.Cu")
		(net "P3V3_SSD4_PG_G1")
	)
	(segment
		(start 110.719362 -37.951156)
		(end 110.430564 -37.662358)
		(width 0.13208)
		(layer "F.Cu")
		(net "P3V3_SSD4_PG_G1")
	)
	(via
		(at 110.430564 -37.662358)
		(size 0.508)
		(drill 0.254)
		(layers "F.Cu" "B.Cu")
		(net "P3V3_SSD4_PG_G1")
	)
	(segment
		(start 312.188606 -31.567882)
		(end 311.58053 -31.567882)
		(width 0.13208)
		(layer "F.Cu")
		(net "P3V3_SSD11_CO_DV_DT")
	)
	(segment
		(start 312.482484 -30.875732)
		(end 312.482484 -31.274004)
		(width 0.13208)
		(layer "F.Cu")
		(net "P3V3_SSD11_CO_DV_DT")
	)
	(segment
		(start 311.588658 -31.57601)
		(end 311.588658 -32.39135)
		(width 0.13208)
		(layer "F.Cu")
		(net "P3V3_SSD11_CO_DV_DT")
	)
	(segment
		(start 311.588658 -32.39135)
		(end 311.532016 -32.447992)
		(width 0.13208)
		(layer "F.Cu")
		(net "P3V3_SSD11_CO_DV_DT")
	)
	(segment
		(start 311.58053 -31.567882)
		(end 311.588658 -31.57601)
		(width 0.13208)
		(layer "F.Cu")
		(net "P3V3_SSD11_CO_DV_DT")
	)
	(segment
		(start 312.482484 -31.274004)
		(end 312.188606 -31.567882)
		(width 0.13208)
		(layer "F.Cu")
		(net "P3V3_SSD11_CO_DV_DT")
	)
	(via
		(at 311.58053 -31.567882)
		(size 0.508)
		(drill 0.254)
		(layers "F.Cu" "B.Cu")
		(net "P3V3_SSD11_CO_DV_DT")
	)
	(segment
		(start 162.43046 -37.662358)
		(end 162.361372 -37.662358)
		(width 0.13208)
		(layer "F.Cu")
		(net "P3V3_SSD6_PG_G1")
	)
	(segment
		(start 163.161218 -37.951156)
		(end 162.719258 -37.951156)
		(width 0.13208)
		(layer "F.Cu")
		(net "P3V3_SSD6_PG_G1")
	)
	(segment
		(start 162.719258 -37.951156)
		(end 162.43046 -37.662358)
		(width 0.13208)
		(layer "F.Cu")
		(net "P3V3_SSD6_PG_G1")
	)
	(segment
		(start 162.174174 -37.47516)
		(end 161.746946 -37.47516)
		(width 0.13208)
		(layer "F.Cu")
		(net "P3V3_SSD6_PG_G1")
	)
	(segment
		(start 162.361372 -37.662358)
		(end 162.174174 -37.47516)
		(width 0.13208)
		(layer "F.Cu")
		(net "P3V3_SSD6_PG_G1")
	)
	(segment
		(start 161.746946 -38.49116)
		(end 161.746946 -37.47516)
		(width 0.13208)
		(layer "F.Cu")
		(net "P3V3_SSD6_PG_G1")
	)
	(via
		(at 162.43046 -37.662358)
		(size 0.508)
		(drill 0.254)
		(layers "F.Cu" "B.Cu")
		(net "P3V3_SSD6_PG_G1")
	)
	(segment
		(start 262.142986 -32.006032)
		(end 262.07212 -32.076898)
		(width 0.13208)
		(layer "F.Cu")
		(net "P3V3_SSD9_CO_GATE")
	)
	(segment
		(start 261.609332 -31.664402)
		(end 262.142986 -31.664402)
		(width 0.13208)
		(layer "F.Cu")
		(net "P3V3_SSD9_CO_GATE")
	)
	(segment
		(start 262.142986 -31.664402)
		(end 262.142986 -32.006032)
		(width 0.13208)
		(layer "F.Cu")
		(net "P3V3_SSD9_CO_GATE")
	)
	(segment
		(start 261.482332 -31.537402)
		(end 261.609332 -31.664402)
		(width 0.13208)
		(layer "F.Cu")
		(net "P3V3_SSD9_CO_GATE")
	)
	(segment
		(start 262.07212 -32.076898)
		(end 262.07212 -32.447992)
		(width 0.13208)
		(layer "F.Cu")
		(net "P3V3_SSD9_CO_GATE")
	)
	(segment
		(start 261.482332 -30.875732)
		(end 261.482332 -31.537402)
		(width 0.13208)
		(layer "F.Cu")
		(net "P3V3_SSD9_CO_GATE")
	)
	(via
		(at 262.142986 -31.664402)
		(size 0.508)
		(drill 0.254)
		(layers "F.Cu" "B.Cu")
		(net "P3V3_SSD9_CO_GATE")
	)
	(segment
		(start 429.709326 -31.664402)
		(end 430.24298 -31.664402)
		(width 0.13208)
		(layer "F.Cu")
		(net "P3V3_SSD15_CO_GATE")
	)
	(segment
		(start 429.582326 -31.537402)
		(end 429.709326 -31.664402)
		(width 0.13208)
		(layer "F.Cu")
		(net "P3V3_SSD15_CO_GATE")
	)
	(segment
		(start 430.172114 -32.076898)
		(end 430.172114 -32.447992)
		(width 0.13208)
		(layer "F.Cu")
		(net "P3V3_SSD15_CO_GATE")
	)
	(segment
		(start 430.24298 -32.006032)
		(end 430.172114 -32.076898)
		(width 0.13208)
		(layer "F.Cu")
		(net "P3V3_SSD15_CO_GATE")
	)
	(segment
		(start 429.582326 -30.875732)
		(end 429.582326 -31.537402)
		(width 0.13208)
		(layer "F.Cu")
		(net "P3V3_SSD15_CO_GATE")
	)
	(segment
		(start 430.24298 -31.664402)
		(end 430.24298 -32.006032)
		(width 0.13208)
		(layer "F.Cu")
		(net "P3V3_SSD15_CO_GATE")
	)
	(via
		(at 430.24298 -31.664402)
		(size 0.508)
		(drill 0.254)
		(layers "F.Cu" "B.Cu")
		(net "P3V3_SSD15_CO_GATE")
	)
	(segment
		(start 196.76745 -32.25927)
		(end 196.76745 -31.719266)
		(width 0.13208)
		(layer "F.Cu")
		(net "P3V3_SSD7_CO_EN")
	)
	(segment
		(start 196.882512 -30.875732)
		(end 196.882512 -31.44139)
		(width 0.13208)
		(layer "F.Cu")
		(net "P3V3_SSD7_CO_EN")
	)
	(segment
		(start 196.956172 -32.447992)
		(end 196.76745 -32.25927)
		(width 0.13208)
		(layer "F.Cu")
		(net "P3V3_SSD7_CO_EN")
	)
	(segment
		(start 196.882512 -31.44139)
		(end 196.76745 -31.719266)
		(width 0.13208)
		(layer "F.Cu")
		(net "P3V3_SSD7_CO_EN")
	)
	(via
		(at 196.76745 -31.719266)
		(size 0.508)
		(drill 0.254)
		(layers "F.Cu" "B.Cu")
		(net "P3V3_SSD7_CO_EN")
	)
	(segment
		(start 287.557718 -27.406346)
		(end 288.573718 -27.406346)
		(width 0.13208)
		(layer "F.Cu")
		(net "P3V3_SSD10_CO_MODE")
	)
	(segment
		(start 288.573718 -27.815286)
		(end 288.573718 -27.406346)
		(width 0.13208)
		(layer "F.Cu")
		(net "P3V3_SSD10_CO_MODE")
	)
	(segment
		(start 288.249868 -28.139136)
		(end 288.573718 -27.815286)
		(width 0.13208)
		(layer "F.Cu")
		(net "P3V3_SSD10_CO_MODE")
	)
	(segment
		(start 287.48228 -28.875736)
		(end 287.48228 -28.329636)
		(width 0.13208)
		(layer "F.Cu")
		(net "P3V3_SSD10_CO_MODE")
	)
	(segment
		(start 287.67278 -28.139136)
		(end 288.249868 -28.139136)
		(width 0.13208)
		(layer "F.Cu")
		(net "P3V3_SSD10_CO_MODE")
	)
	(segment
		(start 287.48228 -28.329636)
		(end 287.67278 -28.139136)
		(width 0.13208)
		(layer "F.Cu")
		(net "P3V3_SSD10_CO_MODE")
	)
	(via
		(at 288.249868 -28.139136)
		(size 0.508)
		(drill 0.254)
		(layers "F.Cu" "B.Cu")
		(net "P3V3_SSD10_CO_MODE")
	)
	(segment
		(start 404.243032 -31.664402)
		(end 404.243032 -32.006032)
		(width 0.13208)
		(layer "F.Cu")
		(net "P3V3_SSD14_CO_GATE")
	)
	(segment
		(start 403.582378 -31.537402)
		(end 403.709378 -31.664402)
		(width 0.13208)
		(layer "F.Cu")
		(net "P3V3_SSD14_CO_GATE")
	)
	(segment
		(start 404.172166 -32.076898)
		(end 404.172166 -32.447992)
		(width 0.13208)
		(layer "F.Cu")
		(net "P3V3_SSD14_CO_GATE")
	)
	(segment
		(start 403.582378 -30.875732)
		(end 403.582378 -31.537402)
		(width 0.13208)
		(layer "F.Cu")
		(net "P3V3_SSD14_CO_GATE")
	)
	(segment
		(start 403.709378 -31.664402)
		(end 404.243032 -31.664402)
		(width 0.13208)
		(layer "F.Cu")
		(net "P3V3_SSD14_CO_GATE")
	)
	(segment
		(start 404.243032 -32.006032)
		(end 404.172166 -32.076898)
		(width 0.13208)
		(layer "F.Cu")
		(net "P3V3_SSD14_CO_GATE")
	)
	(via
		(at 404.243032 -31.664402)
		(size 0.508)
		(drill 0.254)
		(layers "F.Cu" "B.Cu")
		(net "P3V3_SSD14_CO_GATE")
	)
	(segment
		(start 351.582482 -31.537402)
		(end 351.709482 -31.664402)
		(width 0.13208)
		(layer "F.Cu")
		(net "P3V3_SSD12_CO_GATE")
	)
	(segment
		(start 351.582482 -30.875732)
		(end 351.582482 -31.537402)
		(width 0.13208)
		(layer "F.Cu")
		(net "P3V3_SSD12_CO_GATE")
	)
	(segment
		(start 352.243136 -32.006032)
		(end 352.17227 -32.076898)
		(width 0.13208)
		(layer "F.Cu")
		(net "P3V3_SSD12_CO_GATE")
	)
	(segment
		(start 352.17227 -32.076898)
		(end 352.17227 -32.447992)
		(width 0.13208)
		(layer "F.Cu")
		(net "P3V3_SSD12_CO_GATE")
	)
	(segment
		(start 351.709482 -31.664402)
		(end 352.243136 -31.664402)
		(width 0.13208)
		(layer "F.Cu")
		(net "P3V3_SSD12_CO_GATE")
	)
	(segment
		(start 352.243136 -31.664402)
		(end 352.243136 -32.006032)
		(width 0.13208)
		(layer "F.Cu")
		(net "P3V3_SSD12_CO_GATE")
	)
	(via
		(at 352.243136 -31.664402)
		(size 0.508)
		(drill 0.254)
		(layers "F.Cu" "B.Cu")
		(net "P3V3_SSD12_CO_GATE")
	)
	(segment
		(start 229.06101 -38.701218)
		(end 230.280464 -38.701218)
		(width 0.13208)
		(layer "F.Cu")
		(net "P3V3_SSD8_PG_G2")
	)
	(segment
		(start 230.281988 -38.702742)
		(end 230.281988 -38.041072)
		(width 0.13208)
		(layer "F.Cu")
		(net "P3V3_SSD8_PG_G2")
	)
	(segment
		(start 230.192072 -37.951156)
		(end 230.281988 -38.041072)
		(width 0.13208)
		(layer "F.Cu")
		(net "P3V3_SSD8_PG_G2")
	)
	(segment
		(start 229.06101 -37.951156)
		(end 230.192072 -37.951156)
		(width 0.13208)
		(layer "F.Cu")
		(net "P3V3_SSD8_PG_G2")
	)
	(segment
		(start 230.280464 -38.701218)
		(end 230.281988 -38.702742)
		(width 0.13208)
		(layer "F.Cu")
		(net "P3V3_SSD8_PG_G2")
	)
	(via
		(at 230.281988 -38.702742)
		(size 0.508)
		(drill 0.254)
		(layers "F.Cu" "B.Cu")
		(net "P3V3_SSD8_PG_G2")
	)
	(segment
		(start 424.380406 -38.701218)
		(end 424.38193 -38.702742)
		(width 0.13208)
		(layer "F.Cu")
		(net "P3V3_SSD15_PG_G2")
	)
	(segment
		(start 424.292014 -37.951156)
		(end 424.38193 -38.041072)
		(width 0.13208)
		(layer "F.Cu")
		(net "P3V3_SSD15_PG_G2")
	)
	(segment
		(start 423.160952 -38.701218)
		(end 424.380406 -38.701218)
		(width 0.13208)
		(layer "F.Cu")
		(net "P3V3_SSD15_PG_G2")
	)
	(segment
		(start 424.38193 -38.702742)
		(end 424.38193 -38.041072)
		(width 0.13208)
		(layer "F.Cu")
		(net "P3V3_SSD15_PG_G2")
	)
	(segment
		(start 423.160952 -37.951156)
		(end 424.292014 -37.951156)
		(width 0.13208)
		(layer "F.Cu")
		(net "P3V3_SSD15_PG_G2")
	)
	(via
		(at 424.38193 -38.702742)
		(size 0.508)
		(drill 0.254)
		(layers "F.Cu" "B.Cu")
		(net "P3V3_SSD15_PG_G2")
	)
	(segment
		(start 119.50954 -31.664402)
		(end 120.043194 -31.664402)
		(width 0.13208)
		(layer "F.Cu")
		(net "P3V3_SSD4_CO_GATE")
	)
	(segment
		(start 119.38254 -30.875732)
		(end 119.38254 -31.537402)
		(width 0.13208)
		(layer "F.Cu")
		(net "P3V3_SSD4_CO_GATE")
	)
	(segment
		(start 120.043194 -31.664402)
		(end 120.043194 -32.006032)
		(width 0.13208)
		(layer "F.Cu")
		(net "P3V3_SSD4_CO_GATE")
	)
	(segment
		(start 119.38254 -31.537402)
		(end 119.50954 -31.664402)
		(width 0.13208)
		(layer "F.Cu")
		(net "P3V3_SSD4_CO_GATE")
	)
	(segment
		(start 120.043194 -32.006032)
		(end 119.972328 -32.076898)
		(width 0.13208)
		(layer "F.Cu")
		(net "P3V3_SSD4_CO_GATE")
	)
	(segment
		(start 119.972328 -32.076898)
		(end 119.972328 -32.447992)
		(width 0.13208)
		(layer "F.Cu")
		(net "P3V3_SSD4_CO_GATE")
	)
	(via
		(at 120.043194 -31.664402)
		(size 0.508)
		(drill 0.254)
		(layers "F.Cu" "B.Cu")
		(net "P3V3_SSD4_CO_GATE")
	)
	(segment
		(start 314.142882 -32.006032)
		(end 314.072016 -32.076898)
		(width 0.13208)
		(layer "F.Cu")
		(net "P3V3_SSD11_CO_GATE")
	)
	(segment
		(start 313.609228 -31.664402)
		(end 314.142882 -31.664402)
		(width 0.13208)
		(layer "F.Cu")
		(net "P3V3_SSD11_CO_GATE")
	)
	(segment
		(start 314.142882 -31.664402)
		(end 314.142882 -32.006032)
		(width 0.13208)
		(layer "F.Cu")
		(net "P3V3_SSD11_CO_GATE")
	)
	(segment
		(start 313.482228 -30.875732)
		(end 313.482228 -31.537402)
		(width 0.13208)
		(layer "F.Cu")
		(net "P3V3_SSD11_CO_GATE")
	)
	(segment
		(start 313.482228 -31.537402)
		(end 313.609228 -31.664402)
		(width 0.13208)
		(layer "F.Cu")
		(net "P3V3_SSD11_CO_GATE")
	)
	(segment
		(start 314.072016 -32.076898)
		(end 314.072016 -32.447992)
		(width 0.13208)
		(layer "F.Cu")
		(net "P3V3_SSD11_CO_GATE")
	)
	(via
		(at 314.142882 -31.664402)
		(size 0.508)
		(drill 0.254)
		(layers "F.Cu" "B.Cu")
		(net "P3V3_SSD11_CO_GATE")
	)
	(segment
		(start 403.082506 -30.875732)
		(end 403.082506 -31.44139)
		(width 0.13208)
		(layer "F.Cu")
		(net "P3V3_SSD14_CO_EN")
	)
	(segment
		(start 402.967444 -32.25927)
		(end 403.156166 -32.447992)
		(width 0.13208)
		(layer "F.Cu")
		(net "P3V3_SSD14_CO_EN")
	)
	(segment
		(start 403.082506 -31.44139)
		(end 402.967444 -31.719266)
		(width 0.13208)
		(layer "F.Cu")
		(net "P3V3_SSD14_CO_EN")
	)
	(segment
		(start 402.967444 -31.719266)
		(end 402.967444 -32.25927)
		(width 0.13208)
		(layer "F.Cu")
		(net "P3V3_SSD14_CO_EN")
	)
	(via
		(at 402.967444 -31.719266)
		(size 0.508)
		(drill 0.254)
		(layers "F.Cu" "B.Cu")
		(net "P3V3_SSD14_CO_EN")
	)
	(segment
		(start 337.824318 -120.526302)
		(end 338.575396 -120.526302)
		(width 0.13208)
		(layer "F.Cu")
		(net "P3V3_NIC5_PG_G2")
	)
	(segment
		(start 338.587334 -120.53824)
		(end 339.318346 -120.53824)
		(width 0.13208)
		(layer "F.Cu")
		(net "P3V3_NIC5_PG_G2")
	)
	(segment
		(start 339.318346 -120.53824)
		(end 339.318346 -119.90324)
		(width 0.13208)
		(layer "F.Cu")
		(net "P3V3_NIC5_PG_G2")
	)
	(segment
		(start 339.318346 -119.90324)
		(end 339.191346 -119.77624)
		(width 0.13208)
		(layer "F.Cu")
		(net "P3V3_NIC5_PG_G2")
	)
	(segment
		(start 338.575396 -120.526302)
		(end 338.587334 -120.53824)
		(width 0.13208)
		(layer "F.Cu")
		(net "P3V3_NIC5_PG_G2")
	)
	(segment
		(start 339.191346 -119.77624)
		(end 337.824318 -119.77624)
		(width 0.13208)
		(layer "F.Cu")
		(net "P3V3_NIC5_PG_G2")
	)
	(via
		(at 338.575396 -120.526302)
		(size 0.508)
		(drill 0.254)
		(layers "F.Cu" "B.Cu")
		(net "P3V3_NIC5_PG_G2")
	)
	(segment
		(start 144.441926 -27.700986)
		(end 144.441926 -27.406346)
		(width 0.13208)
		(layer "F.Cu")
		(net "P3V3_SSD5_CO_ILIMIT")
	)
	(segment
		(start 144.882616 -28.875736)
		(end 144.882616 -28.141676)
		(width 0.13208)
		(layer "F.Cu")
		(net "P3V3_SSD5_CO_ILIMIT")
	)
	(segment
		(start 144.880076 -28.139136)
		(end 144.441926 -27.700986)
		(width 0.13208)
		(layer "F.Cu")
		(net "P3V3_SSD5_CO_ILIMIT")
	)
	(segment
		(start 144.882616 -28.141676)
		(end 144.880076 -28.139136)
		(width 0.13208)
		(layer "F.Cu")
		(net "P3V3_SSD5_CO_ILIMIT")
	)
	(via
		(at 144.880076 -28.139136)
		(size 0.508)
		(drill 0.254)
		(layers "F.Cu" "B.Cu")
		(net "P3V3_SSD5_CO_ILIMIT")
	)
	(segment
		(start 287.60928 -31.664402)
		(end 288.142934 -31.664402)
		(width 0.13208)
		(layer "F.Cu")
		(net "P3V3_SSD10_CO_GATE")
	)
	(segment
		(start 288.072068 -32.076898)
		(end 288.072068 -32.447992)
		(width 0.13208)
		(layer "F.Cu")
		(net "P3V3_SSD10_CO_GATE")
	)
	(segment
		(start 287.48228 -31.537402)
		(end 287.60928 -31.664402)
		(width 0.13208)
		(layer "F.Cu")
		(net "P3V3_SSD10_CO_GATE")
	)
	(segment
		(start 287.48228 -30.875732)
		(end 287.48228 -31.537402)
		(width 0.13208)
		(layer "F.Cu")
		(net "P3V3_SSD10_CO_GATE")
	)
	(segment
		(start 288.142934 -32.006032)
		(end 288.072068 -32.076898)
		(width 0.13208)
		(layer "F.Cu")
		(net "P3V3_SSD10_CO_GATE")
	)
	(segment
		(start 288.142934 -31.664402)
		(end 288.142934 -32.006032)
		(width 0.13208)
		(layer "F.Cu")
		(net "P3V3_SSD10_CO_GATE")
	)
	(via
		(at 288.142934 -31.664402)
		(size 0.508)
		(drill 0.254)
		(layers "F.Cu" "B.Cu")
		(net "P3V3_SSD10_CO_GATE")
	)
	(segment
		(start 364.98022 -117.611652)
		(end 364.98022 -117.301772)
		(width 0.13208)
		(layer "F.Cu")
		(net "P3V3_NIC6_CO_GATE")
	)
	(segment
		(start 364.98022 -117.301772)
		(end 364.98022 -117.016276)
		(width 0.13208)
		(layer "F.Cu")
		(net "P3V3_NIC6_CO_GATE")
	)
	(segment
		(start 364.333028 -116.369084)
		(end 364.333028 -115.933474)
		(width 0.13208)
		(layer "F.Cu")
		(net "P3V3_NIC6_CO_GATE")
	)
	(segment
		(start 364.612936 -117.978936)
		(end 364.98022 -117.611652)
		(width 0.13208)
		(layer "F.Cu")
		(net "P3V3_NIC6_CO_GATE")
	)
	(segment
		(start 364.98022 -117.016276)
		(end 364.333028 -116.369084)
		(width 0.13208)
		(layer "F.Cu")
		(net "P3V3_NIC6_CO_GATE")
	)
	(via
		(at 364.98022 -117.301772)
		(size 0.508)
		(drill 0.254)
		(layers "F.Cu" "B.Cu")
		(net "P3V3_NIC6_CO_GATE")
	)
	(segment
		(start 144.767554 -31.719266)
		(end 144.767554 -32.25927)
		(width 0.13208)
		(layer "F.Cu")
		(net "P3V3_SSD5_CO_EN")
	)
	(segment
		(start 144.882616 -30.875732)
		(end 144.882616 -31.44139)
		(width 0.13208)
		(layer "F.Cu")
		(net "P3V3_SSD5_CO_EN")
	)
	(segment
		(start 144.882616 -31.44139)
		(end 144.767554 -31.719266)
		(width 0.13208)
		(layer "F.Cu")
		(net "P3V3_SSD5_CO_EN")
	)
	(segment
		(start 144.767554 -32.25927)
		(end 144.956276 -32.447992)
		(width 0.13208)
		(layer "F.Cu")
		(net "P3V3_SSD5_CO_EN")
	)
	(via
		(at 144.767554 -31.719266)
		(size 0.508)
		(drill 0.254)
		(layers "F.Cu" "B.Cu")
		(net "P3V3_SSD5_CO_EN")
	)
	(segment
		(start 234.982512 -28.875736)
		(end 234.982512 -28.141676)
		(width 0.13208)
		(layer "F.Cu")
		(net "P3V3_SSD8_CO_ILIMIT")
	)
	(segment
		(start 234.979972 -28.139136)
		(end 234.541822 -27.700986)
		(width 0.13208)
		(layer "F.Cu")
		(net "P3V3_SSD8_CO_ILIMIT")
	)
	(segment
		(start 234.541822 -27.700986)
		(end 234.541822 -27.406346)
		(width 0.13208)
		(layer "F.Cu")
		(net "P3V3_SSD8_CO_ILIMIT")
	)
	(segment
		(start 234.982512 -28.141676)
		(end 234.979972 -28.139136)
		(width 0.13208)
		(layer "F.Cu")
		(net "P3V3_SSD8_CO_ILIMIT")
	)
	(via
		(at 234.979972 -28.139136)
		(size 0.508)
		(drill 0.254)
		(layers "F.Cu" "B.Cu")
		(net "P3V3_SSD8_CO_ILIMIT")
	)
	(segment
		(start 378.243084 -32.006032)
		(end 378.172218 -32.076898)
		(width 0.13208)
		(layer "F.Cu")
		(net "P3V3_SSD13_CO_GATE")
	)
	(segment
		(start 378.172218 -32.076898)
		(end 378.172218 -32.447992)
		(width 0.13208)
		(layer "F.Cu")
		(net "P3V3_SSD13_CO_GATE")
	)
	(segment
		(start 377.58243 -30.875732)
		(end 377.58243 -31.537402)
		(width 0.13208)
		(layer "F.Cu")
		(net "P3V3_SSD13_CO_GATE")
	)
	(segment
		(start 377.58243 -31.537402)
		(end 377.70943 -31.664402)
		(width 0.13208)
		(layer "F.Cu")
		(net "P3V3_SSD13_CO_GATE")
	)
	(segment
		(start 378.243084 -31.664402)
		(end 378.243084 -32.006032)
		(width 0.13208)
		(layer "F.Cu")
		(net "P3V3_SSD13_CO_GATE")
	)
	(segment
		(start 377.70943 -31.664402)
		(end 378.243084 -31.664402)
		(width 0.13208)
		(layer "F.Cu")
		(net "P3V3_SSD13_CO_GATE")
	)
	(via
		(at 378.243084 -31.664402)
		(size 0.508)
		(drill 0.254)
		(layers "F.Cu" "B.Cu")
		(net "P3V3_SSD13_CO_GATE")
	)
	(segment
		(start 363.333284 -116.596668)
		(end 363.333284 -115.933474)
		(width 0.13208)
		(layer "F.Cu")
		(net "P3V3_NIC6_CO_DV_DT")
	)
	(segment
		(start 362.580936 -117.349016)
		(end 363.333284 -116.596668)
		(width 0.13208)
		(layer "F.Cu")
		(net "P3V3_NIC6_CO_DV_DT")
	)
	(segment
		(start 362.580936 -117.978936)
		(end 362.580936 -117.349016)
		(width 0.13208)
		(layer "F.Cu")
		(net "P3V3_NIC6_CO_DV_DT")
	)
	(via
		(at 362.580936 -117.349016)
		(size 0.508)
		(drill 0.254)
		(layers "F.Cu" "B.Cu")
		(net "P3V3_NIC6_CO_DV_DT")
	)
	(segment
		(start 118.882668 -30.875732)
		(end 118.882668 -31.44139)
		(width 0.13208)
		(layer "F.Cu")
		(net "P3V3_SSD4_CO_EN")
	)
	(segment
		(start 118.767606 -32.25927)
		(end 118.956328 -32.447992)
		(width 0.13208)
		(layer "F.Cu")
		(net "P3V3_SSD4_CO_EN")
	)
	(segment
		(start 118.767606 -31.719266)
		(end 118.767606 -32.25927)
		(width 0.13208)
		(layer "F.Cu")
		(net "P3V3_SSD4_CO_EN")
	)
	(segment
		(start 118.882668 -31.44139)
		(end 118.767606 -31.719266)
		(width 0.13208)
		(layer "F.Cu")
		(net "P3V3_SSD4_CO_EN")
	)
	(via
		(at 118.767606 -31.719266)
		(size 0.508)
		(drill 0.254)
		(layers "F.Cu" "B.Cu")
		(net "P3V3_SSD4_CO_EN")
	)
	(segment
		(start 397.161004 -37.951156)
		(end 398.292066 -37.951156)
		(width 0.13208)
		(layer "F.Cu")
		(net "P3V3_SSD14_PG_G2")
	)
	(segment
		(start 398.381982 -38.702742)
		(end 398.381982 -38.041072)
		(width 0.13208)
		(layer "F.Cu")
		(net "P3V3_SSD14_PG_G2")
	)
	(segment
		(start 398.380458 -38.701218)
		(end 398.381982 -38.702742)
		(width 0.13208)
		(layer "F.Cu")
		(net "P3V3_SSD14_PG_G2")
	)
	(segment
		(start 397.161004 -38.701218)
		(end 398.380458 -38.701218)
		(width 0.13208)
		(layer "F.Cu")
		(net "P3V3_SSD14_PG_G2")
	)
	(segment
		(start 398.292066 -37.951156)
		(end 398.381982 -38.041072)
		(width 0.13208)
		(layer "F.Cu")
		(net "P3V3_SSD14_PG_G2")
	)
	(via
		(at 398.381982 -38.702742)
		(size 0.508)
		(drill 0.254)
		(layers "F.Cu" "B.Cu")
		(net "P3V3_SSD14_PG_G2")
	)
	(segment
		(start 196.441822 -27.406346)
		(end 196.441822 -27.700986)
		(width 0.13208)
		(layer "F.Cu")
		(net "P3V3_SSD7_CO_ILIMIT")
	)
	(segment
		(start 196.882512 -28.141676)
		(end 196.882512 -28.875736)
		(width 0.13208)
		(layer "F.Cu")
		(net "P3V3_SSD7_CO_ILIMIT")
	)
	(segment
		(start 196.879972 -28.139136)
		(end 196.882512 -28.141676)
		(width 0.13208)
		(layer "F.Cu")
		(net "P3V3_SSD7_CO_ILIMIT")
	)
	(segment
		(start 196.441822 -27.700986)
		(end 196.879972 -28.139136)
		(width 0.13208)
		(layer "F.Cu")
		(net "P3V3_SSD7_CO_ILIMIT")
	)
	(via
		(at 196.879972 -28.139136)
		(size 0.508)
		(drill 0.254)
		(layers "F.Cu" "B.Cu")
		(net "P3V3_SSD7_CO_ILIMIT")
	)
	(segment
		(start 282.191968 -37.951156)
		(end 282.281884 -38.041072)
		(width 0.13208)
		(layer "F.Cu")
		(net "P3V3_SSD10_PG_G2")
	)
	(segment
		(start 282.281884 -38.702742)
		(end 282.281884 -38.041072)
		(width 0.13208)
		(layer "F.Cu")
		(net "P3V3_SSD10_PG_G2")
	)
	(segment
		(start 282.28036 -38.701218)
		(end 282.281884 -38.702742)
		(width 0.13208)
		(layer "F.Cu")
		(net "P3V3_SSD10_PG_G2")
	)
	(segment
		(start 281.060906 -38.701218)
		(end 282.28036 -38.701218)
		(width 0.13208)
		(layer "F.Cu")
		(net "P3V3_SSD10_PG_G2")
	)
	(segment
		(start 281.060906 -37.951156)
		(end 282.191968 -37.951156)
		(width 0.13208)
		(layer "F.Cu")
		(net "P3V3_SSD10_PG_G2")
	)
	(via
		(at 282.281884 -38.702742)
		(size 0.508)
		(drill 0.254)
		(layers "F.Cu" "B.Cu")
		(net "P3V3_SSD10_PG_G2")
	)
	(segment
		(start 427.688756 -32.39135)
		(end 427.688756 -31.57601)
		(width 0.13208)
		(layer "F.Cu")
		(net "P3V3_SSD15_CO_DV_DT")
	)
	(segment
		(start 427.632114 -32.447992)
		(end 427.688756 -32.39135)
		(width 0.13208)
		(layer "F.Cu")
		(net "P3V3_SSD15_CO_DV_DT")
	)
	(segment
		(start 427.688756 -31.57601)
		(end 427.680628 -31.567882)
		(width 0.13208)
		(layer "F.Cu")
		(net "P3V3_SSD15_CO_DV_DT")
	)
	(segment
		(start 428.288704 -31.567882)
		(end 428.582582 -31.274004)
		(width 0.13208)
		(layer "F.Cu")
		(net "P3V3_SSD15_CO_DV_DT")
	)
	(segment
		(start 428.582582 -31.274004)
		(end 428.582582 -30.875732)
		(width 0.13208)
		(layer "F.Cu")
		(net "P3V3_SSD15_CO_DV_DT")
	)
	(segment
		(start 427.680628 -31.567882)
		(end 428.288704 -31.567882)
		(width 0.13208)
		(layer "F.Cu")
		(net "P3V3_SSD15_CO_DV_DT")
	)
	(via
		(at 427.680628 -31.567882)
		(size 0.508)
		(drill 0.254)
		(layers "F.Cu" "B.Cu")
		(net "P3V3_SSD15_CO_DV_DT")
	)
	(segment
		(start 452.124572 -119.77624)
		(end 451.627494 -119.77624)
		(width 0.13208)
		(layer "F.Cu")
		(net "P3V3_NIC7_PG_G1")
	)
	(segment
		(start 450.630544 -121.80824)
		(end 450.630544 -120.79224)
		(width 0.13208)
		(layer "F.Cu")
		(net "P3V3_NIC7_PG_G1")
	)
	(segment
		(start 451.373494 -120.79224)
		(end 450.630544 -120.79224)
		(width 0.13208)
		(layer "F.Cu")
		(net "P3V3_NIC7_PG_G1")
	)
	(segment
		(start 451.627494 -119.77624)
		(end 451.373494 -120.03024)
		(width 0.13208)
		(layer "F.Cu")
		(net "P3V3_NIC7_PG_G1")
	)
	(segment
		(start 451.373494 -120.03024)
		(end 451.373494 -120.79224)
		(width 0.13208)
		(layer "F.Cu")
		(net "P3V3_NIC7_PG_G1")
	)
	(via
		(at 451.373494 -120.79224)
		(size 0.508)
		(drill 0.254)
		(layers "F.Cu" "B.Cu")
		(net "P3V3_NIC7_PG_G1")
	)
	(segment
		(start 172.04309 -31.664402)
		(end 172.04309 -32.006032)
		(width 0.13208)
		(layer "F.Cu")
		(net "P3V3_SSD6_CO_GATE")
	)
	(segment
		(start 172.04309 -32.006032)
		(end 171.972224 -32.076898)
		(width 0.13208)
		(layer "F.Cu")
		(net "P3V3_SSD6_CO_GATE")
	)
	(segment
		(start 171.382436 -31.537402)
		(end 171.509436 -31.664402)
		(width 0.13208)
		(layer "F.Cu")
		(net "P3V3_SSD6_CO_GATE")
	)
	(segment
		(start 171.509436 -31.664402)
		(end 172.04309 -31.664402)
		(width 0.13208)
		(layer "F.Cu")
		(net "P3V3_SSD6_CO_GATE")
	)
	(segment
		(start 171.382436 -30.875732)
		(end 171.382436 -31.537402)
		(width 0.13208)
		(layer "F.Cu")
		(net "P3V3_SSD6_CO_GATE")
	)
	(segment
		(start 171.972224 -32.076898)
		(end 171.972224 -32.447992)
		(width 0.13208)
		(layer "F.Cu")
		(net "P3V3_SSD6_CO_GATE")
	)
	(via
		(at 172.04309 -31.664402)
		(size 0.508)
		(drill 0.254)
		(layers "F.Cu" "B.Cu")
		(net "P3V3_SSD6_CO_GATE")
	)
	(segment
		(start 312.541666 -27.700986)
		(end 312.541666 -27.406346)
		(width 0.13208)
		(layer "F.Cu")
		(net "P3V3_SSD11_CO_ILIMIT")
	)
	(segment
		(start 312.982356 -28.141676)
		(end 312.979816 -28.139136)
		(width 0.13208)
		(layer "F.Cu")
		(net "P3V3_SSD11_CO_ILIMIT")
	)
	(segment
		(start 312.982356 -28.875736)
		(end 312.982356 -28.141676)
		(width 0.13208)
		(layer "F.Cu")
		(net "P3V3_SSD11_CO_ILIMIT")
	)
	(segment
		(start 312.979816 -28.139136)
		(end 312.541666 -27.700986)
		(width 0.13208)
		(layer "F.Cu")
		(net "P3V3_SSD11_CO_ILIMIT")
	)
	(via
		(at 312.979816 -28.139136)
		(size 0.508)
		(drill 0.254)
		(layers "F.Cu" "B.Cu")
		(net "P3V3_SSD11_CO_ILIMIT")
	)
	(segment
		(start 350.64192 -27.700986)
		(end 350.64192 -27.406346)
		(width 0.13208)
		(layer "F.Cu")
		(net "P3V3_SSD12_CO_ILIMIT")
	)
	(segment
		(start 351.08261 -28.141676)
		(end 351.08007 -28.139136)
		(width 0.13208)
		(layer "F.Cu")
		(net "P3V3_SSD12_CO_ILIMIT")
	)
	(segment
		(start 351.08007 -28.139136)
		(end 350.64192 -27.700986)
		(width 0.13208)
		(layer "F.Cu")
		(net "P3V3_SSD12_CO_ILIMIT")
	)
	(segment
		(start 351.08261 -28.875736)
		(end 351.08261 -28.141676)
		(width 0.13208)
		(layer "F.Cu")
		(net "P3V3_SSD12_CO_ILIMIT")
	)
	(via
		(at 351.08007 -28.139136)
		(size 0.508)
		(drill 0.254)
		(layers "F.Cu" "B.Cu")
		(net "P3V3_SSD12_CO_ILIMIT")
	)
	(segment
		(start 131.63296 -116.680234)
		(end 131.63296 -115.933474)
		(width 0.13208)
		(layer "F.Cu")
		(net "P3V3_NIC2_CO_EN")
	)
	(segment
		(start 131.39674 -117.978936)
		(end 131.39674 -116.916454)
		(width 0.13208)
		(layer "F.Cu")
		(net "P3V3_NIC2_CO_EN")
	)
	(segment
		(start 131.39674 -116.916454)
		(end 131.63296 -116.680234)
		(width 0.13208)
		(layer "F.Cu")
		(net "P3V3_NIC2_CO_EN")
	)
	(via
		(at 131.63296 -116.680234)
		(size 0.508)
		(drill 0.254)
		(layers "F.Cu" "B.Cu")
		(net "P3V3_NIC2_CO_EN")
	)
	(segment
		(start 248.004838 -117.678454)
		(end 248.004838 -118.740936)
		(width 0.13208)
		(layer "F.Cu")
		(net "P3V3_NIC4_CO_EN")
	)
	(segment
		(start 248.241058 -116.695474)
		(end 248.241058 -117.442234)
		(width 0.13208)
		(layer "F.Cu")
		(net "P3V3_NIC4_CO_EN")
	)
	(segment
		(start 248.241058 -117.442234)
		(end 248.004838 -117.678454)
		(width 0.13208)
		(layer "F.Cu")
		(net "P3V3_NIC4_CO_EN")
	)
	(via
		(at 248.241058 -117.442234)
		(size 0.508)
		(drill 0.254)
		(layers "F.Cu" "B.Cu")
		(net "P3V3_NIC4_CO_EN")
	)
	(segment
		(start 286.982408 -28.875736)
		(end 286.982408 -28.141676)
		(width 0.13208)
		(layer "F.Cu")
		(net "P3V3_SSD10_CO_ILIMIT")
	)
	(segment
		(start 286.982408 -28.141676)
		(end 286.979868 -28.139136)
		(width 0.13208)
		(layer "F.Cu")
		(net "P3V3_SSD10_CO_ILIMIT")
	)
	(segment
		(start 286.541718 -27.700986)
		(end 286.541718 -27.406346)
		(width 0.13208)
		(layer "F.Cu")
		(net "P3V3_SSD10_CO_ILIMIT")
	)
	(segment
		(start 286.979868 -28.139136)
		(end 286.541718 -27.700986)
		(width 0.13208)
		(layer "F.Cu")
		(net "P3V3_SSD10_CO_ILIMIT")
	)
	(via
		(at 286.979868 -28.139136)
		(size 0.508)
		(drill 0.254)
		(layers "F.Cu" "B.Cu")
		(net "P3V3_SSD10_CO_ILIMIT")
	)
	(segment
		(start 402.288756 -31.567882)
		(end 401.68068 -31.567882)
		(width 0.13208)
		(layer "F.Cu")
		(net "P3V3_SSD14_CO_DV_DT")
	)
	(segment
		(start 402.582634 -31.274004)
		(end 402.288756 -31.567882)
		(width 0.13208)
		(layer "F.Cu")
		(net "P3V3_SSD14_CO_DV_DT")
	)
	(segment
		(start 401.688808 -31.996634)
		(end 402.140166 -32.447992)
		(width 0.13208)
		(layer "F.Cu")
		(net "P3V3_SSD14_CO_DV_DT")
	)
	(segment
		(start 401.688808 -31.57601)
		(end 401.688808 -31.996634)
		(width 0.13208)
		(layer "F.Cu")
		(net "P3V3_SSD14_CO_DV_DT")
	)
	(segment
		(start 402.582634 -30.875732)
		(end 402.582634 -31.274004)
		(width 0.13208)
		(layer "F.Cu")
		(net "P3V3_SSD14_CO_DV_DT")
	)
	(segment
		(start 401.68068 -31.567882)
		(end 401.688808 -31.57601)
		(width 0.13208)
		(layer "F.Cu")
		(net "P3V3_SSD14_CO_DV_DT")
	)
	(via
		(at 401.68068 -31.567882)
		(size 0.508)
		(drill 0.254)
		(layers "F.Cu" "B.Cu")
		(net "P3V3_SSD14_CO_DV_DT")
	)
	(segment
		(start 228.935534 4.454652)
		(end 228.438202 4.10591)
		(width 0.13462)
		(layer "B.Cu")
		(net "85_10INCH_BOTTOM_DN")
	)
	(segment
		(start 206.39532 11.74877)
		(end 206.177134 12.060682)
		(width 0.13462)
		(layer "B.Cu")
		(net "85_10INCH_BOTTOM_DN")
	)
	(segment
		(start 224.817686 4.117086)
		(end 223.636586 4.32562)
		(width 0.13462)
		(layer "B.Cu")
		(net "85_10INCH_BOTTOM_DN")
	)
	(segment
		(start 184.45607 7.946644)
		(end 184.343294 7.833868)
		(width 0.13462)
		(layer "B.Cu")
		(net "85_10INCH_BOTTOM_DN")
	)
	(segment
		(start 205.191868 4.922266)
		(end 206.39532 11.74877)
		(width 0.13462)
		(layer "B.Cu")
		(net "85_10INCH_BOTTOM_DN")
	)
	(segment
		(start 234.504738 4.332224)
		(end 234.15625 4.829556)
		(width 0.13462)
		(layer "B.Cu")
		(net "85_10INCH_BOTTOM_DN")
	)
	(segment
		(start 233.91495 12.144248)
		(end 232.560622 4.469384)
		(width 0.13462)
		(layer "B.Cu")
		(net "85_10INCH_BOTTOM_DN")
	)
	(segment
		(start 216.414096 4.458462)
		(end 216.065862 4.956302)
		(width 0.13462)
		(layer "B.Cu")
		(net "85_10INCH_BOTTOM_DN")
	)
	(segment
		(start 219.71127 12.227052)
		(end 219.400374 12.009374)
		(width 0.13462)
		(layer "B.Cu")
		(net "85_10INCH_BOTTOM_DN")
	)
	(segment
		(start 231.557068 12.181586)
		(end 230.601012 12.350242)
		(width 0.13462)
		(layer "B.Cu")
		(net "85_10INCH_BOTTOM_DN")
	)
	(segment
		(start 199.972676 4.557268)
		(end 199.47509 4.208526)
		(width 0.13462)
		(layer "B.Cu")
		(net "85_10INCH_BOTTOM_DN")
	)
	(segment
		(start 241.285268 7.826756)
		(end 241.093498 7.826756)
		(width 0.13462)
		(layer "B.Cu")
		(net "85_10INCH_BOTTOM_DN")
	)
	(segment
		(start 217.483436 4.26974)
		(end 217.483436 4.269994)
		(width 0.13462)
		(layer "B.Cu")
		(net "85_10INCH_BOTTOM_DN")
	)
	(segment
		(start 191.68872 12.07135)
		(end 190.732664 12.240006)
		(width 0.13462)
		(layer "B.Cu")
		(net "85_10INCH_BOTTOM_DN")
	)
	(segment
		(start 230.288592 12.132056)
		(end 228.935534 4.454652)
		(width 0.13462)
		(layer "B.Cu")
		(net "85_10INCH_BOTTOM_DN")
	)
	(segment
		(start 217.264742 11.756644)
		(end 217.046556 12.068302)
		(width 0.13462)
		(layer "B.Cu")
		(net "85_10INCH_BOTTOM_DN")
	)
	(segment
		(start 235.39958 11.881612)
		(end 235.181394 12.19327)
		(width 0.13462)
		(layer "B.Cu")
		(net "85_10INCH_BOTTOM_DN")
	)
	(segment
		(start 191.906906 11.759692)
		(end 191.68872 12.07135)
		(width 0.13462)
		(layer "B.Cu")
		(net "85_10INCH_BOTTOM_DN")
	)
	(segment
		(start 210.843622 4.575302)
		(end 210.345782 4.22656)
		(width 0.13462)
		(layer "B.Cu")
		(net "85_10INCH_BOTTOM_DN")
	)
	(segment
		(start 212.465666 12.225274)
		(end 212.15477 12.007596)
		(width 0.13462)
		(layer "B.Cu")
		(net "85_10INCH_BOTTOM_DN")
	)
	(segment
		(start 197.669404 12.03833)
		(end 196.351906 4.568444)
		(width 0.13462)
		(layer "B.Cu")
		(net "85_10INCH_BOTTOM_DN")
	)
	(segment
		(start 205.221078 12.229338)
		(end 204.910182 12.01166)
		(width 0.13462)
		(layer "B.Cu")
		(net "85_10INCH_BOTTOM_DN")
	)
	(segment
		(start 235.181394 12.19327)
		(end 234.225592 12.361926)
		(width 0.13462)
		(layer "B.Cu")
		(net "85_10INCH_BOTTOM_DN")
	)
	(segment
		(start 217.595196 4.250182)
		(end 217.483436 4.26974)
		(width 0.13462)
		(layer "B.Cu")
		(net "85_10INCH_BOTTOM_DN")
	)
	(segment
		(start 228.438202 4.10591)
		(end 227.257356 4.314698)
		(width 0.13462)
		(layer "B.Cu")
		(net "85_10INCH_BOTTOM_DN")
	)
	(segment
		(start 220.885512 11.746738)
		(end 220.667326 12.058396)
		(width 0.13462)
		(layer "B.Cu")
		(net "85_10INCH_BOTTOM_DN")
	)
	(segment
		(start 221.10446 4.261612)
		(end 220.03512 4.45008)
		(width 0.13462)
		(layer "B.Cu")
		(net "85_10INCH_BOTTOM_DN")
	)
	(segment
		(start 194.046602 12.038076)
		(end 192.73139 4.580128)
		(width 0.13462)
		(layer "B.Cu")
		(net "85_10INCH_BOTTOM_DN")
	)
	(segment
		(start 230.533194 4.826)
		(end 231.775254 11.870182)
		(width 0.13462)
		(layer "B.Cu")
		(net "85_10INCH_BOTTOM_DN")
	)
	(segment
		(start 209.164682 4.43484)
		(end 208.816448 4.93268)
		(width 0.13462)
		(layer "B.Cu")
		(net "85_10INCH_BOTTOM_DN")
	)
	(segment
		(start 208.816448 4.93268)
		(end 210.02371 11.780774)
		(width 0.13462)
		(layer "B.Cu")
		(net "85_10INCH_BOTTOM_DN")
	)
	(segment
		(start 190.704216 4.937506)
		(end 191.906906 11.759692)
		(width 0.13462)
		(layer "B.Cu")
		(net "85_10INCH_BOTTOM_DN")
	)
	(segment
		(start 216.065862 4.956302)
		(end 217.264742 11.756644)
		(width 0.13462)
		(layer "B.Cu")
		(net "85_10INCH_BOTTOM_DN")
	)
	(segment
		(start 224.52838 11.862562)
		(end 224.310194 12.174982)
		(width 0.13462)
		(layer "B.Cu")
		(net "85_10INCH_BOTTOM_DN")
	)
	(segment
		(start 223.636586 4.32562)
		(end 223.28759 4.823714)
		(width 0.13462)
		(layer "B.Cu")
		(net "85_10INCH_BOTTOM_DN")
	)
	(segment
		(start 236.771688 7.806182)
		(end 236.183678 4.472432)
		(width 0.13462)
		(layer "B.Cu")
		(net "85_10INCH_BOTTOM_DN")
	)
	(segment
		(start 226.978972 12.352782)
		(end 226.66706 12.134342)
		(width 0.13462)
		(layer "B.Cu")
		(net "85_10INCH_BOTTOM_DN")
	)
	(segment
		(start 204.910182 12.01166)
		(end 203.598526 4.576318)
		(width 0.13462)
		(layer "B.Cu")
		(net "85_10INCH_BOTTOM_DN")
	)
	(segment
		(start 208.538318 12.043156)
		(end 207.219042 4.564888)
		(width 0.13462)
		(layer "B.Cu")
		(net "85_10INCH_BOTTOM_DN")
	)
	(segment
		(start 202.55738 12.076176)
		(end 201.601324 12.244832)
		(width 0.13462)
		(layer "B.Cu")
		(net "85_10INCH_BOTTOM_DN")
	)
	(segment
		(start 189.429898 7.946644)
		(end 184.45607 7.946644)
		(width 0.13462)
		(layer "B.Cu")
		(net "85_10INCH_BOTTOM_DN")
	)
	(segment
		(start 208.849468 12.261088)
		(end 208.538318 12.043156)
		(width 0.13462)
		(layer "B.Cu")
		(net "85_10INCH_BOTTOM_DN")
	)
	(segment
		(start 203.598526 4.576318)
		(end 203.100686 4.227576)
		(width 0.13462)
		(layer "B.Cu")
		(net "85_10INCH_BOTTOM_DN")
	)
	(segment
		(start 226.66706 12.134342)
		(end 225.314764 4.465828)
		(width 0.13462)
		(layer "B.Cu")
		(net "85_10INCH_BOTTOM_DN")
	)
	(segment
		(start 223.354392 12.343384)
		(end 223.043496 12.125706)
		(width 0.13462)
		(layer "B.Cu")
		(net "85_10INCH_BOTTOM_DN")
	)
	(segment
		(start 210.345782 4.22656)
		(end 210.234022 4.246118)
		(width 0.13462)
		(layer "B.Cu")
		(net "85_10INCH_BOTTOM_DN")
	)
	(segment
		(start 195.532756 11.776202)
		(end 195.314824 12.087606)
		(width 0.13462)
		(layer "B.Cu")
		(net "85_10INCH_BOTTOM_DN")
	)
	(segment
		(start 226.90836 4.812792)
		(end 228.15296 11.872214)
		(width 0.13462)
		(layer "B.Cu")
		(net "85_10INCH_BOTTOM_DN")
	)
	(segment
		(start 214.470742 4.601464)
		(end 213.972902 4.252722)
		(width 0.13462)
		(layer "B.Cu")
		(net "85_10INCH_BOTTOM_DN")
	)
	(segment
		(start 235.685838 4.12369)
		(end 234.504738 4.332224)
		(width 0.13462)
		(layer "B.Cu")
		(net "85_10INCH_BOTTOM_DN")
	)
	(segment
		(start 219.400374 12.009374)
		(end 218.093036 4.598924)
		(width 0.13462)
		(layer "B.Cu")
		(net "85_10INCH_BOTTOM_DN")
	)
	(segment
		(start 184.343294 7.833868)
		(end 184.151524 7.833868)
		(width 0.13462)
		(layer "B.Cu")
		(net "85_10INCH_BOTTOM_DN")
	)
	(segment
		(start 209.805524 12.092432)
		(end 208.849468 12.261088)
		(width 0.13462)
		(layer "B.Cu")
		(net "85_10INCH_BOTTOM_DN")
	)
	(segment
		(start 213.972902 4.252722)
		(end 213.861142 4.27228)
		(width 0.13462)
		(layer "B.Cu")
		(net "85_10INCH_BOTTOM_DN")
	)
	(segment
		(start 213.639908 11.74496)
		(end 213.421722 12.056618)
		(width 0.13462)
		(layer "B.Cu")
		(net "85_10INCH_BOTTOM_DN")
	)
	(segment
		(start 206.721202 4.216146)
		(end 206.609442 4.235704)
		(width 0.13462)
		(layer "B.Cu")
		(net "85_10INCH_BOTTOM_DN")
	)
	(segment
		(start 230.881682 4.32943)
		(end 230.533194 4.826)
		(width 0.13462)
		(layer "B.Cu")
		(net "85_10INCH_BOTTOM_DN")
	)
	(segment
		(start 202.775566 11.764518)
		(end 202.55738 12.076176)
		(width 0.13462)
		(layer "B.Cu")
		(net "85_10INCH_BOTTOM_DN")
	)
	(segment
		(start 219.686886 4.94792)
		(end 220.885512 11.746738)
		(width 0.13462)
		(layer "B.Cu")
		(net "85_10INCH_BOTTOM_DN")
	)
	(segment
		(start 212.443568 4.958842)
		(end 213.639908 11.74496)
		(width 0.13462)
		(layer "B.Cu")
		(net "85_10INCH_BOTTOM_DN")
	)
	(segment
		(start 201.601324 12.244832)
		(end 201.290428 12.027154)
		(width 0.13462)
		(layer "B.Cu")
		(net "85_10INCH_BOTTOM_DN")
	)
	(segment
		(start 216.0905 12.236958)
		(end 215.77935 12.019026)
		(width 0.13462)
		(layer "B.Cu")
		(net "85_10INCH_BOTTOM_DN")
	)
	(segment
		(start 199.15505 11.775948)
		(end 198.936864 12.087606)
		(width 0.13462)
		(layer "B.Cu")
		(net "85_10INCH_BOTTOM_DN")
	)
	(segment
		(start 234.15625 4.829556)
		(end 235.39958 11.881612)
		(width 0.13462)
		(layer "B.Cu")
		(net "85_10INCH_BOTTOM_DN")
	)
	(segment
		(start 201.290428 12.027154)
		(end 199.972676 4.557268)
		(width 0.13462)
		(layer "B.Cu")
		(net "85_10INCH_BOTTOM_DN")
	)
	(segment
		(start 192.73139 4.580128)
		(end 192.233804 4.231386)
		(width 0.13462)
		(layer "B.Cu")
		(net "85_10INCH_BOTTOM_DN")
	)
	(segment
		(start 194.358514 12.256008)
		(end 194.046602 12.038076)
		(width 0.13462)
		(layer "B.Cu")
		(net "85_10INCH_BOTTOM_DN")
	)
	(segment
		(start 236.930438 7.939532)
		(end 236.771688 7.806182)
		(width 0.13462)
		(layer "B.Cu")
		(net "85_10INCH_BOTTOM_DN")
	)
	(segment
		(start 206.177134 12.060682)
		(end 205.221078 12.229338)
		(width 0.13462)
		(layer "B.Cu")
		(net "85_10INCH_BOTTOM_DN")
	)
	(segment
		(start 213.421722 12.056618)
		(end 212.465666 12.225274)
		(width 0.13462)
		(layer "B.Cu")
		(net "85_10INCH_BOTTOM_DN")
	)
	(segment
		(start 191.05245 4.439666)
		(end 190.704216 4.937506)
		(width 0.13462)
		(layer "B.Cu")
		(net "85_10INCH_BOTTOM_DN")
	)
	(segment
		(start 202.988926 4.247388)
		(end 201.919586 4.435856)
		(width 0.13462)
		(layer "B.Cu")
		(net "85_10INCH_BOTTOM_DN")
	)
	(segment
		(start 190.732664 12.240006)
		(end 190.422276 12.022582)
		(width 0.13462)
		(layer "B.Cu")
		(net "85_10INCH_BOTTOM_DN")
	)
	(segment
		(start 206.609442 4.235704)
		(end 206.609442 4.235958)
		(width 0.13462)
		(layer "B.Cu")
		(net "85_10INCH_BOTTOM_DN")
	)
	(segment
		(start 195.314824 12.087606)
		(end 194.358514 12.256008)
		(width 0.13462)
		(layer "B.Cu")
		(net "85_10INCH_BOTTOM_DN")
	)
	(segment
		(start 220.667326 12.058396)
		(end 219.71127 12.227052)
		(width 0.13462)
		(layer "B.Cu")
		(net "85_10INCH_BOTTOM_DN")
	)
	(segment
		(start 195.854066 4.219702)
		(end 194.67322 4.428236)
		(width 0.13462)
		(layer "B.Cu")
		(net "85_10INCH_BOTTOM_DN")
	)
	(segment
		(start 198.936864 12.087606)
		(end 197.980808 12.256262)
		(width 0.13462)
		(layer "B.Cu")
		(net "85_10INCH_BOTTOM_DN")
	)
	(segment
		(start 241.093498 7.826756)
		(end 240.980722 7.939532)
		(width 0.13462)
		(layer "B.Cu")
		(net "85_10INCH_BOTTOM_DN")
	)
	(segment
		(start 190.422276 12.022582)
		(end 189.761368 8.278114)
		(width 0.13462)
		(layer "B.Cu")
		(net "85_10INCH_BOTTOM_DN")
	)
	(segment
		(start 223.043496 12.125706)
		(end 221.71406 4.590542)
		(width 0.13462)
		(layer "B.Cu")
		(net "85_10INCH_BOTTOM_DN")
	)
	(segment
		(start 221.10446 4.261358)
		(end 221.10446 4.261612)
		(width 0.13462)
		(layer "B.Cu")
		(net "85_10INCH_BOTTOM_DN")
	)
	(segment
		(start 201.571352 4.933696)
		(end 202.775566 11.764518)
		(width 0.13462)
		(layer "B.Cu")
		(net "85_10INCH_BOTTOM_DN")
	)
	(segment
		(start 197.980808 12.256262)
		(end 197.669404 12.03833)
		(width 0.13462)
		(layer "B.Cu")
		(net "85_10INCH_BOTTOM_DN")
	)
	(segment
		(start 240.980722 7.939532)
		(end 236.930438 7.939532)
		(width 0.13462)
		(layer "B.Cu")
		(net "85_10INCH_BOTTOM_DN")
	)
	(segment
		(start 227.257356 4.314698)
		(end 226.90836 4.812792)
		(width 0.13462)
		(layer "B.Cu")
		(net "85_10INCH_BOTTOM_DN")
	)
	(segment
		(start 196.351906 4.568444)
		(end 195.854066 4.219702)
		(width 0.13462)
		(layer "B.Cu")
		(net "85_10INCH_BOTTOM_DN")
	)
	(segment
		(start 210.234022 4.246372)
		(end 209.164682 4.43484)
		(width 0.13462)
		(layer "B.Cu")
		(net "85_10INCH_BOTTOM_DN")
	)
	(segment
		(start 227.934774 12.184126)
		(end 226.978972 12.352782)
		(width 0.13462)
		(layer "B.Cu")
		(net "85_10INCH_BOTTOM_DN")
	)
	(segment
		(start 220.03512 4.45008)
		(end 219.686886 4.94792)
		(width 0.13462)
		(layer "B.Cu")
		(net "85_10INCH_BOTTOM_DN")
	)
	(segment
		(start 218.093036 4.598924)
		(end 217.595196 4.250182)
		(width 0.13462)
		(layer "B.Cu")
		(net "85_10INCH_BOTTOM_DN")
	)
	(segment
		(start 203.100686 4.227576)
		(end 202.988926 4.247134)
		(width 0.13462)
		(layer "B.Cu")
		(net "85_10INCH_BOTTOM_DN")
	)
	(segment
		(start 228.15296 11.872214)
		(end 227.934774 12.184126)
		(width 0.13462)
		(layer "B.Cu")
		(net "85_10INCH_BOTTOM_DN")
	)
	(segment
		(start 197.945502 4.914392)
		(end 199.15505 11.775948)
		(width 0.13462)
		(layer "B.Cu")
		(net "85_10INCH_BOTTOM_DN")
	)
	(segment
		(start 194.67322 4.428236)
		(end 194.324478 4.925822)
		(width 0.13462)
		(layer "B.Cu")
		(net "85_10INCH_BOTTOM_DN")
	)
	(segment
		(start 212.791802 4.461002)
		(end 212.443568 4.958842)
		(width 0.13462)
		(layer "B.Cu")
		(net "85_10INCH_BOTTOM_DN")
	)
	(segment
		(start 217.483436 4.269994)
		(end 216.414096 4.458462)
		(width 0.13462)
		(layer "B.Cu")
		(net "85_10INCH_BOTTOM_DN")
	)
	(segment
		(start 215.77935 12.019026)
		(end 214.470742 4.601464)
		(width 0.13462)
		(layer "B.Cu")
		(net "85_10INCH_BOTTOM_DN")
	)
	(segment
		(start 223.28759 4.823714)
		(end 224.52838 11.862562)
		(width 0.13462)
		(layer "B.Cu")
		(net "85_10INCH_BOTTOM_DN")
	)
	(segment
		(start 232.062528 4.120642)
		(end 230.881682 4.32943)
		(width 0.13462)
		(layer "B.Cu")
		(net "85_10INCH_BOTTOM_DN")
	)
	(segment
		(start 207.219042 4.564888)
		(end 206.721202 4.216146)
		(width 0.13462)
		(layer "B.Cu")
		(net "85_10INCH_BOTTOM_DN")
	)
	(segment
		(start 213.861142 4.272534)
		(end 212.791802 4.461002)
		(width 0.13462)
		(layer "B.Cu")
		(net "85_10INCH_BOTTOM_DN")
	)
	(segment
		(start 230.601012 12.350242)
		(end 230.288592 12.132056)
		(width 0.13462)
		(layer "B.Cu")
		(net "85_10INCH_BOTTOM_DN")
	)
	(segment
		(start 221.21622 4.2418)
		(end 221.10446 4.261358)
		(width 0.13462)
		(layer "B.Cu")
		(net "85_10INCH_BOTTOM_DN")
	)
	(segment
		(start 217.046556 12.068302)
		(end 216.0905 12.236958)
		(width 0.13462)
		(layer "B.Cu")
		(net "85_10INCH_BOTTOM_DN")
	)
	(segment
		(start 213.861142 4.27228)
		(end 213.861142 4.272534)
		(width 0.13462)
		(layer "B.Cu")
		(net "85_10INCH_BOTTOM_DN")
	)
	(segment
		(start 202.988926 4.247134)
		(end 202.988926 4.247388)
		(width 0.13462)
		(layer "B.Cu")
		(net "85_10INCH_BOTTOM_DN")
	)
	(segment
		(start 232.560622 4.469384)
		(end 232.062528 4.120642)
		(width 0.13462)
		(layer "B.Cu")
		(net "85_10INCH_BOTTOM_DN")
	)
	(segment
		(start 206.609442 4.235958)
		(end 205.540102 4.424426)
		(width 0.13462)
		(layer "B.Cu")
		(net "85_10INCH_BOTTOM_DN")
	)
	(segment
		(start 225.314764 4.465828)
		(end 224.817686 4.117086)
		(width 0.13462)
		(layer "B.Cu")
		(net "85_10INCH_BOTTOM_DN")
	)
	(segment
		(start 236.183678 4.472432)
		(end 235.685838 4.12369)
		(width 0.13462)
		(layer "B.Cu")
		(net "85_10INCH_BOTTOM_DN")
	)
	(segment
		(start 189.761368 8.278114)
		(end 189.429898 7.946644)
		(width 0.13462)
		(layer "B.Cu")
		(net "85_10INCH_BOTTOM_DN")
	)
	(segment
		(start 224.310194 12.174982)
		(end 223.354392 12.343384)
		(width 0.13462)
		(layer "B.Cu")
		(net "85_10INCH_BOTTOM_DN")
	)
	(segment
		(start 210.234022 4.246118)
		(end 210.234022 4.246372)
		(width 0.13462)
		(layer "B.Cu")
		(net "85_10INCH_BOTTOM_DN")
	)
	(segment
		(start 231.775254 11.870182)
		(end 231.557068 12.181586)
		(width 0.13462)
		(layer "B.Cu")
		(net "85_10INCH_BOTTOM_DN")
	)
	(segment
		(start 198.29399 4.41706)
		(end 197.945502 4.914392)
		(width 0.13462)
		(layer "B.Cu")
		(net "85_10INCH_BOTTOM_DN")
	)
	(segment
		(start 201.919586 4.435856)
		(end 201.571352 4.933696)
		(width 0.13462)
		(layer "B.Cu")
		(net "85_10INCH_BOTTOM_DN")
	)
	(segment
		(start 212.15477 12.007596)
		(end 210.843622 4.575302)
		(width 0.13462)
		(layer "B.Cu")
		(net "85_10INCH_BOTTOM_DN")
	)
	(segment
		(start 205.540102 4.424426)
		(end 205.191868 4.922266)
		(width 0.13462)
		(layer "B.Cu")
		(net "85_10INCH_BOTTOM_DN")
	)
	(segment
		(start 234.225592 12.361926)
		(end 233.91495 12.144248)
		(width 0.13462)
		(layer "B.Cu")
		(net "85_10INCH_BOTTOM_DN")
	)
	(segment
		(start 199.47509 4.208526)
		(end 198.29399 4.41706)
		(width 0.13462)
		(layer "B.Cu")
		(net "85_10INCH_BOTTOM_DN")
	)
	(segment
		(start 221.71406 4.590542)
		(end 221.21622 4.2418)
		(width 0.13462)
		(layer "B.Cu")
		(net "85_10INCH_BOTTOM_DN")
	)
	(segment
		(start 194.324478 4.925822)
		(end 195.532756 11.776202)
		(width 0.13462)
		(layer "B.Cu")
		(net "85_10INCH_BOTTOM_DN")
	)
	(segment
		(start 192.233804 4.231386)
		(end 191.05245 4.439666)
		(width 0.13462)
		(layer "B.Cu")
		(net "85_10INCH_BOTTOM_DN")
	)
	(segment
		(start 210.02371 11.780774)
		(end 209.805524 12.092432)
		(width 0.13462)
		(layer "B.Cu")
		(net "85_10INCH_BOTTOM_DN")
	)
	(segment
		(start 441.470796 -116.335048)
		(end 441.661296 -116.525548)
		(width 0.13208)
		(layer "F.Cu")
		(net "P3V3_NIC7_CO_MODE")
	)
	(segment
		(start 441.661296 -116.525548)
		(end 441.661296 -117.102636)
		(width 0.13208)
		(layer "F.Cu")
		(net "P3V3_NIC7_CO_MODE")
	)
	(segment
		(start 442.394086 -116.410486)
		(end 442.394086 -117.426486)
		(width 0.13208)
		(layer "F.Cu")
		(net "P3V3_NIC7_CO_MODE")
	)
	(segment
		(start 441.661296 -117.102636)
		(end 441.985146 -117.426486)
		(width 0.13208)
		(layer "F.Cu")
		(net "P3V3_NIC7_CO_MODE")
	)
	(segment
		(start 441.985146 -117.426486)
		(end 442.394086 -117.426486)
		(width 0.13208)
		(layer "F.Cu")
		(net "P3V3_NIC7_CO_MODE")
	)
	(segment
		(start 440.924696 -116.335048)
		(end 441.470796 -116.335048)
		(width 0.13208)
		(layer "F.Cu")
		(net "P3V3_NIC7_CO_MODE")
	)
	(via
		(at 441.661296 -117.102636)
		(size 0.508)
		(drill 0.254)
		(layers "F.Cu" "B.Cu")
		(net "P3V3_NIC7_CO_MODE")
	)
	(segment
		(start 170.382692 -30.875732)
		(end 170.382692 -31.274004)
		(width 0.13208)
		(layer "F.Cu")
		(net "P3V3_SSD6_CO_DV_DT")
	)
	(segment
		(start 169.480738 -31.567882)
		(end 169.488866 -31.57601)
		(width 0.13208)
		(layer "F.Cu")
		(net "P3V3_SSD6_CO_DV_DT")
	)
	(segment
		(start 170.088814 -31.567882)
		(end 169.480738 -31.567882)
		(width 0.13208)
		(layer "F.Cu")
		(net "P3V3_SSD6_CO_DV_DT")
	)
	(segment
		(start 169.488866 -31.57601)
		(end 169.488866 -31.996634)
		(width 0.13208)
		(layer "F.Cu")
		(net "P3V3_SSD6_CO_DV_DT")
	)
	(segment
		(start 169.488866 -31.996634)
		(end 169.940224 -32.447992)
		(width 0.13208)
		(layer "F.Cu")
		(net "P3V3_SSD6_CO_DV_DT")
	)
	(segment
		(start 170.382692 -31.274004)
		(end 170.088814 -31.567882)
		(width 0.13208)
		(layer "F.Cu")
		(net "P3V3_SSD6_CO_DV_DT")
	)
	(via
		(at 169.480738 -31.567882)
		(size 0.508)
		(drill 0.254)
		(layers "F.Cu" "B.Cu")
		(net "P3V3_SSD6_CO_DV_DT")
	)
	(segment
		(start 235.482384 -28.329636)
		(end 235.672884 -28.139136)
		(width 0.13208)
		(layer "F.Cu")
		(net "P3V3_SSD8_CO_MODE")
	)
	(segment
		(start 235.557822 -27.406346)
		(end 236.573822 -27.406346)
		(width 0.13208)
		(layer "F.Cu")
		(net "P3V3_SSD8_CO_MODE")
	)
	(segment
		(start 236.573822 -27.815286)
		(end 236.573822 -27.406346)
		(width 0.13208)
		(layer "F.Cu")
		(net "P3V3_SSD8_CO_MODE")
	)
	(segment
		(start 235.482384 -28.875736)
		(end 235.482384 -28.329636)
		(width 0.13208)
		(layer "F.Cu")
		(net "P3V3_SSD8_CO_MODE")
	)
	(segment
		(start 235.672884 -28.139136)
		(end 236.249972 -28.139136)
		(width 0.13208)
		(layer "F.Cu")
		(net "P3V3_SSD8_CO_MODE")
	)
	(segment
		(start 236.249972 -28.139136)
		(end 236.573822 -27.815286)
		(width 0.13208)
		(layer "F.Cu")
		(net "P3V3_SSD8_CO_MODE")
	)
	(via
		(at 236.249972 -28.139136)
		(size 0.508)
		(drill 0.254)
		(layers "F.Cu" "B.Cu")
		(net "P3V3_SSD8_CO_MODE")
	)
	(segment
		(start 377.58243 -28.875736)
		(end 377.58243 -28.329636)
		(width 0.13208)
		(layer "F.Cu")
		(net "P3V3_SSD13_CO_MODE")
	)
	(segment
		(start 378.350018 -28.139136)
		(end 378.673868 -27.815286)
		(width 0.13208)
		(layer "F.Cu")
		(net "P3V3_SSD13_CO_MODE")
	)
	(segment
		(start 377.657868 -27.406346)
		(end 378.673868 -27.406346)
		(width 0.13208)
		(layer "F.Cu")
		(net "P3V3_SSD13_CO_MODE")
	)
	(segment
		(start 377.58243 -28.329636)
		(end 377.77293 -28.139136)
		(width 0.13208)
		(layer "F.Cu")
		(net "P3V3_SSD13_CO_MODE")
	)
	(segment
		(start 377.77293 -28.139136)
		(end 378.350018 -28.139136)
		(width 0.13208)
		(layer "F.Cu")
		(net "P3V3_SSD13_CO_MODE")
	)
	(segment
		(start 378.673868 -27.815286)
		(end 378.673868 -27.406346)
		(width 0.13208)
		(layer "F.Cu")
		(net "P3V3_SSD13_CO_MODE")
	)
	(via
		(at 378.350018 -28.139136)
		(size 0.508)
		(drill 0.254)
		(layers "F.Cu" "B.Cu")
		(net "P3V3_SSD13_CO_MODE")
	)
	(segment
		(start 328.931524 10.90676)
		(end 329.612498 11.088624)
		(width 0.13462)
		(layer "B.Cu")
		(net "85_10INCH_IN4_DP")
	)
	(segment
		(start 386.065268 10.932668)
		(end 385.384294 11.114532)
		(width 0.13462)
		(layer "B.Cu")
		(net "85_10INCH_IN4_DP")
	)
	(segment
		(start 336.032094 14.75359)
		(end 336.434176 14.179804)
		(width 0.1651)
		(layer "In11.Cu")
		(net "85_10INCH_IN4_DP")
	)
	(segment
		(start 340.446868 14.19987)
		(end 339.147658 6.83133)
		(width 0.1651)
		(layer "In11.Cu")
		(net "85_10INCH_IN4_DP")
	)
	(segment
		(start 356.090474 14.82471)
		(end 356.492556 14.251178)
		(width 0.1651)
		(layer "In11.Cu")
		(net "85_10INCH_IN4_DP")
	)
	(segment
		(start 340.432136 6.269736)
		(end 340.814152 6.537452)
		(width 0.1651)
		(layer "In11.Cu")
		(net "85_10INCH_IN4_DP")
	)
	(segment
		(start 376.514614 6.271768)
		(end 376.897138 6.539738)
		(width 0.1651)
		(layer "In11.Cu")
		(net "85_10INCH_IN4_DP")
	)
	(segment
		(start 372.53164 14.264132)
		(end 371.220238 6.826504)
		(width 0.1651)
		(layer "In11.Cu")
		(net "85_10INCH_IN4_DP")
	)
	(segment
		(start 368.876834 6.5278)
		(end 370.309902 14.6558)
		(width 0.1651)
		(layer "In11.Cu")
		(net "85_10INCH_IN4_DP")
	)
	(segment
		(start 366.879378 15.085822)
		(end 368.125248 14.865604)
		(width 0.1651)
		(layer "In11.Cu")
		(net "85_10INCH_IN4_DP")
	)
	(segment
		(start 336.434176 14.179804)
		(end 335.138014 6.827774)
		(width 0.1651)
		(layer "In11.Cu")
		(net "85_10INCH_IN4_DP")
	)
	(segment
		(start 329.612498 11.088624)
		(end 329.903328 10.797794)
		(width 0.1651)
		(layer "In11.Cu")
		(net "85_10INCH_IN4_DP")
	)
	(segment
		(start 352.48723 14.27226)
		(end 351.174304 6.82625)
		(width 0.1651)
		(layer "In11.Cu")
		(net "85_10INCH_IN4_DP")
	)
	(segment
		(start 354.844604 15.044928)
		(end 356.090474 14.82471)
		(width 0.1651)
		(layer "In11.Cu")
		(net "85_10INCH_IN4_DP")
	)
	(segment
		(start 363.20349 6.835394)
		(end 363.471206 6.453378)
		(width 0.1651)
		(layer "In11.Cu")
		(net "85_10INCH_IN4_DP")
	)
	(segment
		(start 358.284018 14.665198)
		(end 358.857804 15.06728)
		(width 0.1651)
		(layer "In11.Cu")
		(net "85_10INCH_IN4_DP")
	)
	(segment
		(start 374.31599 14.63929)
		(end 374.889776 15.041372)
		(width 0.1651)
		(layer "In11.Cu")
		(net "85_10INCH_IN4_DP")
	)
	(segment
		(start 338.225638 14.592554)
		(end 338.798916 14.994382)
		(width 0.1651)
		(layer "In11.Cu")
		(net "85_10INCH_IN4_DP")
	)
	(segment
		(start 372.129558 14.837664)
		(end 372.53164 14.264132)
		(width 0.1651)
		(layer "In11.Cu")
		(net "85_10INCH_IN4_DP")
	)
	(segment
		(start 381.605028 10.501884)
		(end 382.06426 10.823702)
		(width 0.1651)
		(layer "In11.Cu")
		(net "85_10INCH_IN4_DP")
	)
	(segment
		(start 343.42578 6.455664)
		(end 344.442542 6.276086)
		(width 0.1651)
		(layer "In11.Cu")
		(net "85_10INCH_IN4_DP")
	)
	(segment
		(start 352.085148 14.845792)
		(end 352.48723 14.27226)
		(width 0.1651)
		(layer "In11.Cu")
		(net "85_10INCH_IN4_DP")
	)
	(segment
		(start 363.471206 6.453378)
		(end 364.487968 6.2738)
		(width 0.1651)
		(layer "In11.Cu")
		(net "85_10INCH_IN4_DP")
	)
	(segment
		(start 348.832678 6.537198)
		(end 350.265492 14.663928)
		(width 0.1651)
		(layer "In11.Cu")
		(net "85_10INCH_IN4_DP")
	)
	(segment
		(start 352.458782 6.264656)
		(end 352.840798 6.532372)
		(width 0.1651)
		(layer "In11.Cu")
		(net "85_10INCH_IN4_DP")
	)
	(segment
		(start 360.103674 14.847062)
		(end 360.505756 14.27353)
		(width 0.1651)
		(layer "In11.Cu")
		(net "85_10INCH_IN4_DP")
	)
	(segment
		(start 364.869984 6.541516)
		(end 366.305592 14.68374)
		(width 0.1651)
		(layer "In11.Cu")
		(net "85_10INCH_IN4_DP")
	)
	(segment
		(start 378.901706 15.056612)
		(end 380.147576 14.836394)
		(width 0.1651)
		(layer "In11.Cu")
		(net "85_10INCH_IN4_DP")
	)
	(segment
		(start 334.786224 14.973808)
		(end 336.032094 14.75359)
		(width 0.1651)
		(layer "In11.Cu")
		(net "85_10INCH_IN4_DP")
	)
	(segment
		(start 348.450662 6.269482)
		(end 348.832678 6.537198)
		(width 0.1651)
		(layer "In11.Cu")
		(net "85_10INCH_IN4_DP")
	)
	(segment
		(start 378.32792 14.65453)
		(end 378.901706 15.056612)
		(width 0.1651)
		(layer "In11.Cu")
		(net "85_10INCH_IN4_DP")
	)
	(segment
		(start 352.840798 6.532372)
		(end 354.270818 14.642846)
		(width 0.1651)
		(layer "In11.Cu")
		(net "85_10INCH_IN4_DP")
	)
	(segment
		(start 360.479594 6.279134)
		(end 360.861864 6.54685)
		(width 0.1651)
		(layer "In11.Cu")
		(net "85_10INCH_IN4_DP")
	)
	(segment
		(start 346.264484 14.711426)
		(end 346.838778 15.113508)
		(width 0.1651)
		(layer "In11.Cu")
		(net "85_10INCH_IN4_DP")
	)
	(segment
		(start 360.861864 6.54685)
		(end 362.301028 14.709648)
		(width 0.1651)
		(layer "In11.Cu")
		(net "85_10INCH_IN4_DP")
	)
	(segment
		(start 336.804508 6.533896)
		(end 338.225638 14.592554)
		(width 0.1651)
		(layer "In11.Cu")
		(net "85_10INCH_IN4_DP")
	)
	(segment
		(start 339.415374 6.449314)
		(end 340.432136 6.269736)
		(width 0.1651)
		(layer "In11.Cu")
		(net "85_10INCH_IN4_DP")
	)
	(segment
		(start 364.522766 14.31798)
		(end 363.20349 6.835394)
		(width 0.1651)
		(layer "In11.Cu")
		(net "85_10INCH_IN4_DP")
	)
	(segment
		(start 372.504716 6.26491)
		(end 372.886732 6.532626)
		(width 0.1651)
		(layer "In11.Cu")
		(net "85_10INCH_IN4_DP")
	)
	(segment
		(start 380.549658 14.262862)
		(end 379.243336 6.85419)
		(width 0.1651)
		(layer "In11.Cu")
		(net "85_10INCH_IN4_DP")
	)
	(segment
		(start 375.230136 6.833362)
		(end 375.497852 6.451346)
		(width 0.1651)
		(layer "In11.Cu")
		(net "85_10INCH_IN4_DP")
	)
	(segment
		(start 380.910084 6.56082)
		(end 381.605028 10.501884)
		(width 0.1651)
		(layer "In11.Cu")
		(net "85_10INCH_IN4_DP")
	)
	(segment
		(start 346.838778 15.113508)
		(end 348.084648 14.89329)
		(width 0.1651)
		(layer "In11.Cu")
		(net "85_10INCH_IN4_DP")
	)
	(segment
		(start 385.093464 10.823702)
		(end 385.384294 11.114532)
		(width 0.1651)
		(layer "In11.Cu")
		(net "85_10INCH_IN4_DP")
	)
	(segment
		(start 355.18471 6.834124)
		(end 355.452426 6.452108)
		(width 0.1651)
		(layer "In11.Cu")
		(net "85_10INCH_IN4_DP")
	)
	(segment
		(start 356.851458 6.5405)
		(end 358.284018 14.665198)
		(width 0.1651)
		(layer "In11.Cu")
		(net "85_10INCH_IN4_DP")
	)
	(segment
		(start 355.452426 6.452108)
		(end 356.469188 6.27253)
		(width 0.1651)
		(layer "In11.Cu")
		(net "85_10INCH_IN4_DP")
	)
	(segment
		(start 359.195116 6.840728)
		(end 359.462832 6.458712)
		(width 0.1651)
		(layer "In11.Cu")
		(net "85_10INCH_IN4_DP")
	)
	(segment
		(start 333.141828 10.797794)
		(end 333.633572 11.289538)
		(width 0.1651)
		(layer "In11.Cu")
		(net "85_10INCH_IN4_DP")
	)
	(segment
		(start 329.903328 10.797794)
		(end 333.141828 10.797794)
		(width 0.1651)
		(layer "In11.Cu")
		(net "85_10INCH_IN4_DP")
	)
	(segment
		(start 347.4339 6.44906)
		(end 348.450662 6.269482)
		(width 0.1651)
		(layer "In11.Cu")
		(net "85_10INCH_IN4_DP")
	)
	(segment
		(start 362.301028 14.709648)
		(end 362.874814 15.11173)
		(width 0.1651)
		(layer "In11.Cu")
		(net "85_10INCH_IN4_DP")
	)
	(segment
		(start 338.798916 14.994382)
		(end 340.044532 14.77391)
		(width 0.1651)
		(layer "In11.Cu")
		(net "85_10INCH_IN4_DP")
	)
	(segment
		(start 350.265492 14.663928)
		(end 350.839278 15.06601)
		(width 0.1651)
		(layer "In11.Cu")
		(net "85_10INCH_IN4_DP")
	)
	(segment
		(start 371.487954 6.444488)
		(end 372.504716 6.26491)
		(width 0.1651)
		(layer "In11.Cu")
		(net "85_10INCH_IN4_DP")
	)
	(segment
		(start 372.886732 6.532626)
		(end 374.31599 14.63929)
		(width 0.1651)
		(layer "In11.Cu")
		(net "85_10INCH_IN4_DP")
	)
	(segment
		(start 375.497852 6.451346)
		(end 376.514614 6.271768)
		(width 0.1651)
		(layer "In11.Cu")
		(net "85_10INCH_IN4_DP")
	)
	(segment
		(start 333.633572 11.289538)
		(end 334.212692 14.571726)
		(width 0.1651)
		(layer "In11.Cu")
		(net "85_10INCH_IN4_DP")
	)
	(segment
		(start 342.826594 15.098268)
		(end 344.072464 14.87805)
		(width 0.1651)
		(layer "In11.Cu")
		(net "85_10INCH_IN4_DP")
	)
	(segment
		(start 344.072464 14.87805)
		(end 344.474546 14.304518)
		(width 0.1651)
		(layer "In11.Cu")
		(net "85_10INCH_IN4_DP")
	)
	(segment
		(start 340.814152 6.537452)
		(end 342.253062 14.696186)
		(width 0.1651)
		(layer "In11.Cu")
		(net "85_10INCH_IN4_DP")
	)
	(segment
		(start 367.478056 6.439662)
		(end 368.494818 6.260084)
		(width 0.1651)
		(layer "In11.Cu")
		(net "85_10INCH_IN4_DP")
	)
	(segment
		(start 356.469188 6.27253)
		(end 356.851458 6.5405)
		(width 0.1651)
		(layer "In11.Cu")
		(net "85_10INCH_IN4_DP")
	)
	(segment
		(start 340.044532 14.77391)
		(end 340.446868 14.19987)
		(width 0.1651)
		(layer "In11.Cu")
		(net "85_10INCH_IN4_DP")
	)
	(segment
		(start 351.174304 6.82625)
		(end 351.44202 6.444234)
		(width 0.1651)
		(layer "In11.Cu")
		(net "85_10INCH_IN4_DP")
	)
	(segment
		(start 364.120684 14.891512)
		(end 364.522766 14.31798)
		(width 0.1651)
		(layer "In11.Cu")
		(net "85_10INCH_IN4_DP")
	)
	(segment
		(start 348.084648 14.89329)
		(end 348.48673 14.320266)
		(width 0.1651)
		(layer "In11.Cu")
		(net "85_10INCH_IN4_DP")
	)
	(segment
		(start 344.824558 6.543802)
		(end 346.264484 14.711426)
		(width 0.1651)
		(layer "In11.Cu")
		(net "85_10INCH_IN4_DP")
	)
	(segment
		(start 364.487968 6.2738)
		(end 364.869984 6.541516)
		(width 0.1651)
		(layer "In11.Cu")
		(net "85_10INCH_IN4_DP")
	)
	(segment
		(start 379.511052 6.472174)
		(end 380.52756 6.292596)
		(width 0.1651)
		(layer "In11.Cu")
		(net "85_10INCH_IN4_DP")
	)
	(segment
		(start 368.52733 14.292072)
		(end 367.21034 6.821678)
		(width 0.1651)
		(layer "In11.Cu")
		(net "85_10INCH_IN4_DP")
	)
	(segment
		(start 360.505756 14.27353)
		(end 359.195116 6.840728)
		(width 0.1651)
		(layer "In11.Cu")
		(net "85_10INCH_IN4_DP")
	)
	(segment
		(start 339.147658 6.83133)
		(end 339.415374 6.449314)
		(width 0.1651)
		(layer "In11.Cu")
		(net "85_10INCH_IN4_DP")
	)
	(segment
		(start 371.220238 6.826504)
		(end 371.487954 6.444488)
		(width 0.1651)
		(layer "In11.Cu")
		(net "85_10INCH_IN4_DP")
	)
	(segment
		(start 368.125248 14.865604)
		(end 368.52733 14.292072)
		(width 0.1651)
		(layer "In11.Cu")
		(net "85_10INCH_IN4_DP")
	)
	(segment
		(start 354.270818 14.642846)
		(end 354.844604 15.044928)
		(width 0.1651)
		(layer "In11.Cu")
		(net "85_10INCH_IN4_DP")
	)
	(segment
		(start 362.874814 15.11173)
		(end 364.120684 14.891512)
		(width 0.1651)
		(layer "In11.Cu")
		(net "85_10INCH_IN4_DP")
	)
	(segment
		(start 335.138014 6.827774)
		(end 335.40573 6.445758)
		(width 0.1651)
		(layer "In11.Cu")
		(net "85_10INCH_IN4_DP")
	)
	(segment
		(start 368.494818 6.260084)
		(end 368.876834 6.5278)
		(width 0.1651)
		(layer "In11.Cu")
		(net "85_10INCH_IN4_DP")
	)
	(segment
		(start 334.212692 14.571726)
		(end 334.786224 14.973808)
		(width 0.1651)
		(layer "In11.Cu")
		(net "85_10INCH_IN4_DP")
	)
	(segment
		(start 366.305592 14.68374)
		(end 366.879378 15.085822)
		(width 0.1651)
		(layer "In11.Cu")
		(net "85_10INCH_IN4_DP")
	)
	(segment
		(start 359.462832 6.458712)
		(end 360.479594 6.279134)
		(width 0.1651)
		(layer "In11.Cu")
		(net "85_10INCH_IN4_DP")
	)
	(segment
		(start 344.474546 14.304518)
		(end 343.158064 6.83768)
		(width 0.1651)
		(layer "In11.Cu")
		(net "85_10INCH_IN4_DP")
	)
	(segment
		(start 342.253062 14.696186)
		(end 342.826594 15.098268)
		(width 0.1651)
		(layer "In11.Cu")
		(net "85_10INCH_IN4_DP")
	)
	(segment
		(start 380.147576 14.836394)
		(end 380.549658 14.262862)
		(width 0.1651)
		(layer "In11.Cu")
		(net "85_10INCH_IN4_DP")
	)
	(segment
		(start 376.897138 6.539738)
		(end 378.32792 14.65453)
		(width 0.1651)
		(layer "In11.Cu")
		(net "85_10INCH_IN4_DP")
	)
	(segment
		(start 358.857804 15.06728)
		(end 360.103674 14.847062)
		(width 0.1651)
		(layer "In11.Cu")
		(net "85_10INCH_IN4_DP")
	)
	(segment
		(start 376.135646 14.821154)
		(end 376.537982 14.247368)
		(width 0.1651)
		(layer "In11.Cu")
		(net "85_10INCH_IN4_DP")
	)
	(segment
		(start 370.883688 15.057882)
		(end 372.129558 14.837664)
		(width 0.1651)
		(layer "In11.Cu")
		(net "85_10INCH_IN4_DP")
	)
	(segment
		(start 367.21034 6.821678)
		(end 367.478056 6.439662)
		(width 0.1651)
		(layer "In11.Cu")
		(net "85_10INCH_IN4_DP")
	)
	(segment
		(start 335.40573 6.445758)
		(end 336.422492 6.26618)
		(width 0.1651)
		(layer "In11.Cu")
		(net "85_10INCH_IN4_DP")
	)
	(segment
		(start 370.309902 14.6558)
		(end 370.883688 15.057882)
		(width 0.1651)
		(layer "In11.Cu")
		(net "85_10INCH_IN4_DP")
	)
	(segment
		(start 348.48673 14.320266)
		(end 347.166184 6.831076)
		(width 0.1651)
		(layer "In11.Cu")
		(net "85_10INCH_IN4_DP")
	)
	(segment
		(start 376.537982 14.247368)
		(end 375.230136 6.833362)
		(width 0.1651)
		(layer "In11.Cu")
		(net "85_10INCH_IN4_DP")
	)
	(segment
		(start 347.166184 6.831076)
		(end 347.4339 6.44906)
		(width 0.1651)
		(layer "In11.Cu")
		(net "85_10INCH_IN4_DP")
	)
	(segment
		(start 350.839278 15.06601)
		(end 352.085148 14.845792)
		(width 0.1651)
		(layer "In11.Cu")
		(net "85_10INCH_IN4_DP")
	)
	(segment
		(start 344.442542 6.276086)
		(end 344.824558 6.543802)
		(width 0.1651)
		(layer "In11.Cu")
		(net "85_10INCH_IN4_DP")
	)
	(segment
		(start 351.44202 6.444234)
		(end 352.458782 6.264656)
		(width 0.1651)
		(layer "In11.Cu")
		(net "85_10INCH_IN4_DP")
	)
	(segment
		(start 374.889776 15.041372)
		(end 376.135646 14.821154)
		(width 0.1651)
		(layer "In11.Cu")
		(net "85_10INCH_IN4_DP")
	)
	(segment
		(start 336.422492 6.26618)
		(end 336.804508 6.533896)
		(width 0.1651)
		(layer "In11.Cu")
		(net "85_10INCH_IN4_DP")
	)
	(segment
		(start 382.06426 10.823702)
		(end 385.093464 10.823702)
		(width 0.1651)
		(layer "In11.Cu")
		(net "85_10INCH_IN4_DP")
	)
	(segment
		(start 356.492556 14.251178)
		(end 355.18471 6.834124)
		(width 0.1651)
		(layer "In11.Cu")
		(net "85_10INCH_IN4_DP")
	)
	(segment
		(start 379.243336 6.85419)
		(end 379.511052 6.472174)
		(width 0.1651)
		(layer "In11.Cu")
		(net "85_10INCH_IN4_DP")
	)
	(segment
		(start 380.52756 6.292596)
		(end 380.910084 6.56082)
		(width 0.1651)
		(layer "In11.Cu")
		(net "85_10INCH_IN4_DP")
	)
	(segment
		(start 343.158064 6.83768)
		(end 343.42578 6.455664)
		(width 0.1651)
		(layer "In11.Cu")
		(net "85_10INCH_IN4_DP")
	)
	(segment
		(start 118.088918 -31.567882)
		(end 117.480842 -31.567882)
		(width 0.13208)
		(layer "F.Cu")
		(net "P3V3_SSD4_CO_DV_DT")
	)
	(segment
		(start 118.382796 -30.875732)
		(end 118.382796 -31.274004)
		(width 0.13208)
		(layer "F.Cu")
		(net "P3V3_SSD4_CO_DV_DT")
	)
	(segment
		(start 117.48897 -31.996634)
		(end 117.940328 -32.447992)
		(width 0.13208)
		(layer "F.Cu")
		(net "P3V3_SSD4_CO_DV_DT")
	)
	(segment
		(start 118.382796 -31.274004)
		(end 118.088918 -31.567882)
		(width 0.13208)
		(layer "F.Cu")
		(net "P3V3_SSD4_CO_DV_DT")
	)
	(segment
		(start 117.48897 -31.57601)
		(end 117.48897 -31.996634)
		(width 0.13208)
		(layer "F.Cu")
		(net "P3V3_SSD4_CO_DV_DT")
	)
	(segment
		(start 117.480842 -31.567882)
		(end 117.48897 -31.57601)
		(width 0.13208)
		(layer "F.Cu")
		(net "P3V3_SSD4_CO_DV_DT")
	)
	(via
		(at 117.480842 -31.567882)
		(size 0.508)
		(drill 0.254)
		(layers "F.Cu" "B.Cu")
		(net "P3V3_SSD4_CO_DV_DT")
	)
	(segment
		(start 261.482332 -28.329636)
		(end 261.672832 -28.139136)
		(width 0.13208)
		(layer "F.Cu")
		(net "P3V3_SSD9_CO_MODE")
	)
	(segment
		(start 261.482332 -28.875736)
		(end 261.482332 -28.329636)
		(width 0.13208)
		(layer "F.Cu")
		(net "P3V3_SSD9_CO_MODE")
	)
	(segment
		(start 262.57377 -27.815286)
		(end 262.57377 -27.406346)
		(width 0.13208)
		(layer "F.Cu")
		(net "P3V3_SSD9_CO_MODE")
	)
	(segment
		(start 261.55777 -27.406346)
		(end 262.57377 -27.406346)
		(width 0.13208)
		(layer "F.Cu")
		(net "P3V3_SSD9_CO_MODE")
	)
	(segment
		(start 261.672832 -28.139136)
		(end 262.24992 -28.139136)
		(width 0.13208)
		(layer "F.Cu")
		(net "P3V3_SSD9_CO_MODE")
	)
	(segment
		(start 262.24992 -28.139136)
		(end 262.57377 -27.815286)
		(width 0.13208)
		(layer "F.Cu")
		(net "P3V3_SSD9_CO_MODE")
	)
	(via
		(at 262.24992 -28.139136)
		(size 0.508)
		(drill 0.254)
		(layers "F.Cu" "B.Cu")
		(net "P3V3_SSD9_CO_MODE")
	)
	(segment
		(start 458.328268 10.465816)
		(end 457.647294 10.283952)
		(width 0.13462)
		(layer "B.Cu")
		(net "85_10INCH_IN5_DN")
	)
	(segment
		(start 401.194524 10.439908)
		(end 401.875498 10.258044)
		(width 0.13462)
		(layer "B.Cu")
		(net "85_10INCH_IN5_DN")
	)
	(segment
		(start 415.155634 14.833092)
		(end 416.17138 14.653514)
		(width 0.1651)
		(layer "In13.Cu")
		(net "85_10INCH_IN5_DN")
	)
	(segment
		(start 434.821584 14.578584)
		(end 435.203854 14.846554)
		(width 0.1651)
		(layer "In13.Cu")
		(net "85_10INCH_IN5_DN")
	)
	(segment
		(start 419.130988 6.797802)
		(end 419.532816 6.224524)
		(width 0.1651)
		(layer "In13.Cu")
		(net "85_10INCH_IN5_DN")
	)
	(segment
		(start 442.830458 14.524736)
		(end 443.212728 14.792706)
		(width 0.1651)
		(layer "In13.Cu")
		(net "85_10INCH_IN5_DN")
	)
	(segment
		(start 409.325064 6.402832)
		(end 410.746194 14.461236)
		(width 0.1651)
		(layer "In13.Cu")
		(net "85_10INCH_IN5_DN")
	)
	(segment
		(start 412.143448 14.549374)
		(end 412.411672 14.166596)
		(width 0.1651)
		(layer "In13.Cu")
		(net "85_10INCH_IN5_DN")
	)
	(segment
		(start 415.524696 6.231128)
		(end 416.771582 6.01091)
		(width 0.1651)
		(layer "In13.Cu")
		(net "85_10INCH_IN5_DN")
	)
	(segment
		(start 448.234562 14.596618)
		(end 448.502786 14.214094)
		(width 0.1651)
		(layer "In13.Cu")
		(net "85_10INCH_IN5_DN")
	)
	(segment
		(start 439.208418 14.820646)
		(end 440.224164 14.641068)
		(width 0.1651)
		(layer "In13.Cu")
		(net "85_10INCH_IN5_DN")
	)
	(segment
		(start 402.166328 10.548874)
		(end 405.521668 10.548874)
		(width 0.1651)
		(layer "In13.Cu")
		(net "85_10INCH_IN5_DN")
	)
	(segment
		(start 429.372014 6.409436)
		(end 430.804574 14.534134)
		(width 0.1651)
		(layer "In13.Cu")
		(net "85_10INCH_IN5_DN")
	)
	(segment
		(start 424.452034 14.238986)
		(end 423.139108 6.792976)
		(width 0.1651)
		(layer "In13.Cu")
		(net "85_10INCH_IN5_DN")
	)
	(segment
		(start 412.761176 6.00456)
		(end 413.334708 6.406388)
		(width 0.1651)
		(layer "In13.Cu")
		(net "85_10INCH_IN5_DN")
	)
	(segment
		(start 447.218816 14.776196)
		(end 448.234562 14.596618)
		(width 0.1651)
		(layer "In13.Cu")
		(net "85_10INCH_IN5_DN")
	)
	(segment
		(start 445.407288 6.401562)
		(end 446.836546 14.508226)
		(width 0.1651)
		(layer "In13.Cu")
		(net "85_10INCH_IN5_DN")
	)
	(segment
		(start 439.175144 6.788404)
		(end 439.576972 6.215126)
		(width 0.1651)
		(layer "In13.Cu")
		(net "85_10INCH_IN5_DN")
	)
	(segment
		(start 453.43064 6.429756)
		(end 454.125584 10.37082)
		(width 0.1651)
		(layer "In13.Cu")
		(net "85_10INCH_IN5_DN")
	)
	(segment
		(start 426.791374 14.511782)
		(end 427.173644 14.779752)
		(width 0.1651)
		(layer "In13.Cu")
		(net "85_10INCH_IN5_DN")
	)
	(segment
		(start 411.51429 6.224778)
		(end 412.761176 6.00456)
		(width 0.1651)
		(layer "In13.Cu")
		(net "85_10INCH_IN5_DN")
	)
	(segment
		(start 454.125584 10.37082)
		(end 454.416414 10.574782)
		(width 0.1651)
		(layer "In13.Cu")
		(net "85_10INCH_IN5_DN")
	)
	(segment
		(start 435.203854 14.846554)
		(end 436.2196 14.666976)
		(width 0.1651)
		(layer "In13.Cu")
		(net "85_10INCH_IN5_DN")
	)
	(segment
		(start 452.246492 14.611858)
		(end 452.514462 14.229588)
		(width 0.1651)
		(layer "In13.Cu")
		(net "85_10INCH_IN5_DN")
	)
	(segment
		(start 406.733248 14.440662)
		(end 407.115264 14.708632)
		(width 0.1651)
		(layer "In13.Cu")
		(net "85_10INCH_IN5_DN")
	)
	(segment
		(start 430.804574 14.534134)
		(end 431.186844 14.802104)
		(width 0.1651)
		(layer "In13.Cu")
		(net "85_10INCH_IN5_DN")
	)
	(segment
		(start 417.345114 6.412738)
		(end 418.78504 14.580362)
		(width 0.1651)
		(layer "In13.Cu")
		(net "85_10INCH_IN5_DN")
	)
	(segment
		(start 431.186844 14.802104)
		(end 432.20259 14.622526)
		(width 0.1651)
		(layer "In13.Cu")
		(net "85_10INCH_IN5_DN")
	)
	(segment
		(start 457.356464 10.574782)
		(end 457.647294 10.283952)
		(width 0.1651)
		(layer "In13.Cu")
		(net "85_10INCH_IN5_DN")
	)
	(segment
		(start 440.823858 5.994908)
		(end 441.39739 6.396736)
		(width 0.1651)
		(layer "In13.Cu")
		(net "85_10INCH_IN5_DN")
	)
	(segment
		(start 408.13101 14.529054)
		(end 408.39898 14.14653)
		(width 0.1651)
		(layer "In13.Cu")
		(net "85_10INCH_IN5_DN")
	)
	(segment
		(start 436.817008 6.008624)
		(end 437.39054 6.410452)
		(width 0.1651)
		(layer "In13.Cu")
		(net "85_10INCH_IN5_DN")
	)
	(segment
		(start 451.609968 6.247638)
		(end 452.856854 6.02742)
		(width 0.1651)
		(layer "In13.Cu")
		(net "85_10INCH_IN5_DN")
	)
	(segment
		(start 448.502786 14.214094)
		(end 447.19494 6.800342)
		(width 0.1651)
		(layer "In13.Cu")
		(net "85_10INCH_IN5_DN")
	)
	(segment
		(start 438.826148 14.552676)
		(end 439.208418 14.820646)
		(width 0.1651)
		(layer "In13.Cu")
		(net "85_10INCH_IN5_DN")
	)
	(segment
		(start 408.39898 14.14653)
		(end 407.102818 6.7945)
		(width 0.1651)
		(layer "In13.Cu")
		(net "85_10INCH_IN5_DN")
	)
	(segment
		(start 439.576972 6.215126)
		(end 440.823858 5.994908)
		(width 0.1651)
		(layer "In13.Cu")
		(net "85_10INCH_IN5_DN")
	)
	(segment
		(start 416.17138 14.653514)
		(end 416.43935 14.271244)
		(width 0.1651)
		(layer "In13.Cu")
		(net "85_10INCH_IN5_DN")
	)
	(segment
		(start 432.808634 6.013958)
		(end 433.38242 6.415786)
		(width 0.1651)
		(layer "In13.Cu")
		(net "85_10INCH_IN5_DN")
	)
	(segment
		(start 424.787822 5.99948)
		(end 425.361354 6.401308)
		(width 0.1651)
		(layer "In13.Cu")
		(net "85_10INCH_IN5_DN")
	)
	(segment
		(start 443.185042 6.79323)
		(end 443.58687 6.219952)
		(width 0.1651)
		(layer "In13.Cu")
		(net "85_10INCH_IN5_DN")
	)
	(segment
		(start 435.168294 6.80212)
		(end 435.570122 6.228842)
		(width 0.1651)
		(layer "In13.Cu")
		(net "85_10INCH_IN5_DN")
	)
	(segment
		(start 447.19494 6.800342)
		(end 447.596768 6.22681)
		(width 0.1651)
		(layer "In13.Cu")
		(net "85_10INCH_IN5_DN")
	)
	(segment
		(start 420.183564 14.668754)
		(end 420.451534 14.286992)
		(width 0.1651)
		(layer "In13.Cu")
		(net "85_10INCH_IN5_DN")
	)
	(segment
		(start 423.168318 14.800834)
		(end 424.184064 14.621256)
		(width 0.1651)
		(layer "In13.Cu")
		(net "85_10INCH_IN5_DN")
	)
	(segment
		(start 431.561748 6.234176)
		(end 432.808634 6.013958)
		(width 0.1651)
		(layer "In13.Cu")
		(net "85_10INCH_IN5_DN")
	)
	(segment
		(start 452.514462 14.229588)
		(end 451.20814 6.820916)
		(width 0.1651)
		(layer "In13.Cu")
		(net "85_10INCH_IN5_DN")
	)
	(segment
		(start 423.139108 6.792976)
		(end 423.540936 6.219698)
		(width 0.1651)
		(layer "In13.Cu")
		(net "85_10INCH_IN5_DN")
	)
	(segment
		(start 452.856854 6.02742)
		(end 453.43064 6.429756)
		(width 0.1651)
		(layer "In13.Cu")
		(net "85_10INCH_IN5_DN")
	)
	(segment
		(start 405.521668 10.548874)
		(end 406.158954 11.185906)
		(width 0.1651)
		(layer "In13.Cu")
		(net "85_10INCH_IN5_DN")
	)
	(segment
		(start 443.58687 6.219952)
		(end 444.833756 5.999734)
		(width 0.1651)
		(layer "In13.Cu")
		(net "85_10INCH_IN5_DN")
	)
	(segment
		(start 406.158954 11.185906)
		(end 406.733248 14.440662)
		(width 0.1651)
		(layer "In13.Cu")
		(net "85_10INCH_IN5_DN")
	)
	(segment
		(start 420.451534 14.286992)
		(end 419.130988 6.797802)
		(width 0.1651)
		(layer "In13.Cu")
		(net "85_10INCH_IN5_DN")
	)
	(segment
		(start 427.149514 6.80085)
		(end 427.551342 6.227572)
		(width 0.1651)
		(layer "In13.Cu")
		(net "85_10INCH_IN5_DN")
	)
	(segment
		(start 451.230746 14.791436)
		(end 452.246492 14.611858)
		(width 0.1651)
		(layer "In13.Cu")
		(net "85_10INCH_IN5_DN")
	)
	(segment
		(start 440.492134 14.258798)
		(end 439.175144 6.788404)
		(width 0.1651)
		(layer "In13.Cu")
		(net "85_10INCH_IN5_DN")
	)
	(segment
		(start 421.353234 6.406134)
		(end 422.786048 14.532864)
		(width 0.1651)
		(layer "In13.Cu")
		(net "85_10INCH_IN5_DN")
	)
	(segment
		(start 414.773618 14.565122)
		(end 415.155634 14.833092)
		(width 0.1651)
		(layer "In13.Cu")
		(net "85_10INCH_IN5_DN")
	)
	(segment
		(start 441.39739 6.396736)
		(end 442.830458 14.524736)
		(width 0.1651)
		(layer "In13.Cu")
		(net "85_10INCH_IN5_DN")
	)
	(segment
		(start 423.540936 6.219698)
		(end 424.787822 5.99948)
		(width 0.1651)
		(layer "In13.Cu")
		(net "85_10INCH_IN5_DN")
	)
	(segment
		(start 413.334708 6.406388)
		(end 414.773618 14.565122)
		(width 0.1651)
		(layer "In13.Cu")
		(net "85_10INCH_IN5_DN")
	)
	(segment
		(start 427.173644 14.779752)
		(end 428.18939 14.600174)
		(width 0.1651)
		(layer "In13.Cu")
		(net "85_10INCH_IN5_DN")
	)
	(segment
		(start 432.47056 14.240256)
		(end 431.15992 6.807454)
		(width 0.1651)
		(layer "In13.Cu")
		(net "85_10INCH_IN5_DN")
	)
	(segment
		(start 411.112462 6.798056)
		(end 411.51429 6.224778)
		(width 0.1651)
		(layer "In13.Cu")
		(net "85_10INCH_IN5_DN")
	)
	(segment
		(start 427.551342 6.227572)
		(end 428.798228 6.007354)
		(width 0.1651)
		(layer "In13.Cu")
		(net "85_10INCH_IN5_DN")
	)
	(segment
		(start 444.228474 14.613128)
		(end 444.496444 14.230858)
		(width 0.1651)
		(layer "In13.Cu")
		(net "85_10INCH_IN5_DN")
	)
	(segment
		(start 420.779702 6.004306)
		(end 421.353234 6.406134)
		(width 0.1651)
		(layer "In13.Cu")
		(net "85_10INCH_IN5_DN")
	)
	(segment
		(start 419.532816 6.224524)
		(end 420.779702 6.004306)
		(width 0.1651)
		(layer "In13.Cu")
		(net "85_10INCH_IN5_DN")
	)
	(segment
		(start 432.20259 14.622526)
		(end 432.47056 14.240256)
		(width 0.1651)
		(layer "In13.Cu")
		(net "85_10INCH_IN5_DN")
	)
	(segment
		(start 433.38242 6.415786)
		(end 434.821584 14.578584)
		(width 0.1651)
		(layer "In13.Cu")
		(net "85_10INCH_IN5_DN")
	)
	(segment
		(start 415.122868 6.804406)
		(end 415.524696 6.231128)
		(width 0.1651)
		(layer "In13.Cu")
		(net "85_10INCH_IN5_DN")
	)
	(segment
		(start 425.361354 6.401308)
		(end 426.791374 14.511782)
		(width 0.1651)
		(layer "In13.Cu")
		(net "85_10INCH_IN5_DN")
	)
	(segment
		(start 447.596768 6.22681)
		(end 448.843654 6.006592)
		(width 0.1651)
		(layer "In13.Cu")
		(net "85_10INCH_IN5_DN")
	)
	(segment
		(start 448.843654 6.006592)
		(end 449.417694 6.408674)
		(width 0.1651)
		(layer "In13.Cu")
		(net "85_10INCH_IN5_DN")
	)
	(segment
		(start 407.115264 14.708632)
		(end 408.13101 14.529054)
		(width 0.1651)
		(layer "In13.Cu")
		(net "85_10INCH_IN5_DN")
	)
	(segment
		(start 437.39054 6.410452)
		(end 438.826148 14.552676)
		(width 0.1651)
		(layer "In13.Cu")
		(net "85_10INCH_IN5_DN")
	)
	(segment
		(start 449.417694 6.408674)
		(end 450.848476 14.523466)
		(width 0.1651)
		(layer "In13.Cu")
		(net "85_10INCH_IN5_DN")
	)
	(segment
		(start 440.224164 14.641068)
		(end 440.492134 14.258798)
		(width 0.1651)
		(layer "In13.Cu")
		(net "85_10INCH_IN5_DN")
	)
	(segment
		(start 410.746194 14.461236)
		(end 411.127956 14.729206)
		(width 0.1651)
		(layer "In13.Cu")
		(net "85_10INCH_IN5_DN")
	)
	(segment
		(start 424.184064 14.621256)
		(end 424.452034 14.238986)
		(width 0.1651)
		(layer "In13.Cu")
		(net "85_10INCH_IN5_DN")
	)
	(segment
		(start 446.836546 14.508226)
		(end 447.218816 14.776196)
		(width 0.1651)
		(layer "In13.Cu")
		(net "85_10INCH_IN5_DN")
	)
	(segment
		(start 431.15992 6.807454)
		(end 431.561748 6.234176)
		(width 0.1651)
		(layer "In13.Cu")
		(net "85_10INCH_IN5_DN")
	)
	(segment
		(start 450.848476 14.523466)
		(end 451.230746 14.791436)
		(width 0.1651)
		(layer "In13.Cu")
		(net "85_10INCH_IN5_DN")
	)
	(segment
		(start 428.18939 14.600174)
		(end 428.45736 14.217904)
		(width 0.1651)
		(layer "In13.Cu")
		(net "85_10INCH_IN5_DN")
	)
	(segment
		(start 412.411672 14.166596)
		(end 411.112462 6.798056)
		(width 0.1651)
		(layer "In13.Cu")
		(net "85_10INCH_IN5_DN")
	)
	(segment
		(start 418.78504 14.580362)
		(end 419.167818 14.848332)
		(width 0.1651)
		(layer "In13.Cu")
		(net "85_10INCH_IN5_DN")
	)
	(segment
		(start 416.43935 14.271244)
		(end 415.122868 6.804406)
		(width 0.1651)
		(layer "In13.Cu")
		(net "85_10INCH_IN5_DN")
	)
	(segment
		(start 444.833756 5.999734)
		(end 445.407288 6.401562)
		(width 0.1651)
		(layer "In13.Cu")
		(net "85_10INCH_IN5_DN")
	)
	(segment
		(start 428.45736 14.217904)
		(end 427.149514 6.80085)
		(width 0.1651)
		(layer "In13.Cu")
		(net "85_10INCH_IN5_DN")
	)
	(segment
		(start 428.798228 6.007354)
		(end 429.372014 6.409436)
		(width 0.1651)
		(layer "In13.Cu")
		(net "85_10INCH_IN5_DN")
	)
	(segment
		(start 454.416414 10.574782)
		(end 457.356464 10.574782)
		(width 0.1651)
		(layer "In13.Cu")
		(net "85_10INCH_IN5_DN")
	)
	(segment
		(start 444.496444 14.230858)
		(end 443.185042 6.79323)
		(width 0.1651)
		(layer "In13.Cu")
		(net "85_10INCH_IN5_DN")
	)
	(segment
		(start 401.875498 10.258044)
		(end 402.166328 10.548874)
		(width 0.1651)
		(layer "In13.Cu")
		(net "85_10INCH_IN5_DN")
	)
	(segment
		(start 443.212728 14.792706)
		(end 444.228474 14.613128)
		(width 0.1651)
		(layer "In13.Cu")
		(net "85_10INCH_IN5_DN")
	)
	(segment
		(start 451.20814 6.820916)
		(end 451.609968 6.247638)
		(width 0.1651)
		(layer "In13.Cu")
		(net "85_10INCH_IN5_DN")
	)
	(segment
		(start 419.167818 14.848332)
		(end 420.183564 14.668754)
		(width 0.1651)
		(layer "In13.Cu")
		(net "85_10INCH_IN5_DN")
	)
	(segment
		(start 407.504646 6.221222)
		(end 408.751532 6.001004)
		(width 0.1651)
		(layer "In13.Cu")
		(net "85_10INCH_IN5_DN")
	)
	(segment
		(start 436.2196 14.666976)
		(end 436.48757 14.284706)
		(width 0.1651)
		(layer "In13.Cu")
		(net "85_10INCH_IN5_DN")
	)
	(segment
		(start 422.786048 14.532864)
		(end 423.168318 14.800834)
		(width 0.1651)
		(layer "In13.Cu")
		(net "85_10INCH_IN5_DN")
	)
	(segment
		(start 411.127956 14.729206)
		(end 412.143448 14.549374)
		(width 0.1651)
		(layer "In13.Cu")
		(net "85_10INCH_IN5_DN")
	)
	(segment
		(start 435.570122 6.228842)
		(end 436.817008 6.008624)
		(width 0.1651)
		(layer "In13.Cu")
		(net "85_10INCH_IN5_DN")
	)
	(segment
		(start 436.48757 14.284706)
		(end 435.168294 6.80212)
		(width 0.1651)
		(layer "In13.Cu")
		(net "85_10INCH_IN5_DN")
	)
	(segment
		(start 416.771582 6.01091)
		(end 417.345114 6.412738)
		(width 0.1651)
		(layer "In13.Cu")
		(net "85_10INCH_IN5_DN")
	)
	(segment
		(start 408.751532 6.001004)
		(end 409.325064 6.402832)
		(width 0.1651)
		(layer "In13.Cu")
		(net "85_10INCH_IN5_DN")
	)
	(segment
		(start 407.102818 6.7945)
		(end 407.504646 6.221222)
		(width 0.1651)
		(layer "In13.Cu")
		(net "85_10INCH_IN5_DN")
	)
	(segment
		(start 249.388122 -118.063772)
		(end 249.388122 -118.373652)
		(width 0.13208)
		(layer "F.Cu")
		(net "P3V3_NIC4_CO_GATE")
	)
	(segment
		(start 248.74093 -116.695474)
		(end 248.74093 -117.131084)
		(width 0.13208)
		(layer "F.Cu")
		(net "P3V3_NIC4_CO_GATE")
	)
	(segment
		(start 248.74093 -117.131084)
		(end 249.388122 -117.778276)
		(width 0.13208)
		(layer "F.Cu")
		(net "P3V3_NIC4_CO_GATE")
	)
	(segment
		(start 249.388122 -118.373652)
		(end 249.020838 -118.740936)
		(width 0.13208)
		(layer "F.Cu")
		(net "P3V3_NIC4_CO_GATE")
	)
	(segment
		(start 249.388122 -117.778276)
		(end 249.388122 -118.063772)
		(width 0.13208)
		(layer "F.Cu")
		(net "P3V3_NIC4_CO_GATE")
	)
	(via
		(at 249.388122 -118.063772)
		(size 0.508)
		(drill 0.254)
		(layers "F.Cu" "B.Cu")
		(net "P3V3_NIC4_CO_GATE")
	)
	(segment
		(start 144.382744 -30.875732)
		(end 144.382744 -31.274004)
		(width 0.13208)
		(layer "F.Cu")
		(net "P3V3_SSD5_CO_DV_DT")
	)
	(segment
		(start 143.488918 -32.39135)
		(end 143.432276 -32.447992)
		(width 0.13208)
		(layer "F.Cu")
		(net "P3V3_SSD5_CO_DV_DT")
	)
	(segment
		(start 144.088866 -31.567882)
		(end 143.48079 -31.567882)
		(width 0.13208)
		(layer "F.Cu")
		(net "P3V3_SSD5_CO_DV_DT")
	)
	(segment
		(start 143.48079 -31.567882)
		(end 143.488918 -31.57601)
		(width 0.13208)
		(layer "F.Cu")
		(net "P3V3_SSD5_CO_DV_DT")
	)
	(segment
		(start 143.488918 -31.57601)
		(end 143.488918 -32.39135)
		(width 0.13208)
		(layer "F.Cu")
		(net "P3V3_SSD5_CO_DV_DT")
	)
	(segment
		(start 144.382744 -31.274004)
		(end 144.088866 -31.567882)
		(width 0.13208)
		(layer "F.Cu")
		(net "P3V3_SSD5_CO_DV_DT")
	)
	(via
		(at 143.48079 -31.567882)
		(size 0.508)
		(drill 0.254)
		(layers "F.Cu" "B.Cu")
		(net "P3V3_SSD5_CO_DV_DT")
	)
	(segment
		(start 260.98246 -28.141676)
		(end 260.98246 -28.875736)
		(width 0.13208)
		(layer "F.Cu")
		(net "P3V3_SSD9_CO_ILIMIT")
	)
	(segment
		(start 260.97992 -28.139136)
		(end 260.98246 -28.141676)
		(width 0.13208)
		(layer "F.Cu")
		(net "P3V3_SSD9_CO_ILIMIT")
	)
	(segment
		(start 260.54177 -27.700986)
		(end 260.97992 -28.139136)
		(width 0.13208)
		(layer "F.Cu")
		(net "P3V3_SSD9_CO_ILIMIT")
	)
	(segment
		(start 260.54177 -27.406346)
		(end 260.54177 -27.700986)
		(width 0.13208)
		(layer "F.Cu")
		(net "P3V3_SSD9_CO_ILIMIT")
	)
	(via
		(at 260.97992 -28.139136)
		(size 0.508)
		(drill 0.254)
		(layers "F.Cu" "B.Cu")
		(net "P3V3_SSD9_CO_ILIMIT")
	)
	(segment
		(start 242.16487 14.311122)
		(end 242.662964 14.65961)
		(width 0.13462)
		(layer "B.Cu")
		(net "85_5INCH_BOTTOM_DP")
	)
	(segment
		(start 227.673662 14.306042)
		(end 228.171248 14.654784)
		(width 0.13462)
		(layer "B.Cu")
		(net "85_5INCH_BOTTOM_DP")
	)
	(segment
		(start 240.98377 14.519656)
		(end 242.16487 14.311122)
		(width 0.13462)
		(layer "B.Cu")
		(net "85_5INCH_BOTTOM_DP")
	)
	(segment
		(start 220.928184 14.665452)
		(end 222.19666 21.858224)
		(width 0.13462)
		(layer "B.Cu")
		(net "85_5INCH_BOTTOM_DP")
	)
	(segment
		(start 234.60075 21.883878)
		(end 233.387392 15.000224)
		(width 0.13462)
		(layer "B.Cu")
		(net "85_5INCH_BOTTOM_DP")
	)
	(segment
		(start 237.360714 14.516862)
		(end 238.54156 14.308074)
		(width 0.13462)
		(layer "B.Cu")
		(net "85_5INCH_BOTTOM_DP")
	)
	(segment
		(start 226.144328 15.012416)
		(end 226.492562 14.514322)
		(width 0.13462)
		(layer "B.Cu")
		(net "85_5INCH_BOTTOM_DP")
	)
	(segment
		(start 233.736388 14.50213)
		(end 234.917234 14.293342)
		(width 0.13462)
		(layer "B.Cu")
		(net "85_5INCH_BOTTOM_DP")
	)
	(segment
		(start 243.367814 17.891252)
		(end 247.291098 17.891252)
		(width 0.13462)
		(layer "B.Cu")
		(net "85_5INCH_BOTTOM_DP")
	)
	(segment
		(start 238.54156 14.308074)
		(end 239.039654 14.656562)
		(width 0.13462)
		(layer "B.Cu")
		(net "85_5INCH_BOTTOM_DP")
	)
	(segment
		(start 218.23426 17.898364)
		(end 219.247212 17.719802)
		(width 0.13462)
		(layer "B.Cu")
		(net "85_5INCH_BOTTOM_DP")
	)
	(segment
		(start 237.012226 15.013432)
		(end 237.360714 14.516862)
		(width 0.13462)
		(layer "B.Cu")
		(net "85_5INCH_BOTTOM_DP")
	)
	(segment
		(start 247.403874 17.778476)
		(end 247.595644 17.778476)
		(width 0.13462)
		(layer "B.Cu")
		(net "85_5INCH_BOTTOM_DP")
	)
	(segment
		(start 214.631524 17.785588)
		(end 214.823294 17.785588)
		(width 0.13462)
		(layer "B.Cu")
		(net "85_5INCH_BOTTOM_DP")
	)
	(segment
		(start 243.209064 17.757902)
		(end 243.367814 17.891252)
		(width 0.13462)
		(layer "B.Cu")
		(net "85_5INCH_BOTTOM_DP")
	)
	(segment
		(start 231.296718 14.304518)
		(end 231.793796 14.65326)
		(width 0.13462)
		(layer "B.Cu")
		(net "85_5INCH_BOTTOM_DP")
	)
	(segment
		(start 214.823294 17.785588)
		(end 214.93607 17.898364)
		(width 0.13462)
		(layer "B.Cu")
		(net "85_5INCH_BOTTOM_DP")
	)
	(segment
		(start 236.992414 22.041612)
		(end 237.94847 21.872956)
		(width 0.13462)
		(layer "B.Cu")
		(net "85_5INCH_BOTTOM_DP")
	)
	(segment
		(start 247.291098 17.891252)
		(end 247.403874 17.778476)
		(width 0.13462)
		(layer "B.Cu")
		(net "85_5INCH_BOTTOM_DP")
	)
	(segment
		(start 222.983806 14.502892)
		(end 224.052638 14.314424)
		(width 0.13462)
		(layer "B.Cu")
		(net "85_5INCH_BOTTOM_DP")
	)
	(segment
		(start 229.766622 15.011146)
		(end 230.115618 14.513052)
		(width 0.13462)
		(layer "B.Cu")
		(net "85_5INCH_BOTTOM_DP")
	)
	(segment
		(start 241.790982 21.572982)
		(end 240.635282 15.016988)
		(width 0.13462)
		(layer "B.Cu")
		(net "85_5INCH_BOTTOM_DP")
	)
	(segment
		(start 242.662964 14.65961)
		(end 243.209064 17.757902)
		(width 0.13462)
		(layer "B.Cu")
		(net "85_5INCH_BOTTOM_DP")
	)
	(segment
		(start 229.46106 21.964904)
		(end 229.771956 22.182582)
		(width 0.13462)
		(layer "B.Cu")
		(net "85_5INCH_BOTTOM_DP")
	)
	(segment
		(start 241.572796 21.88464)
		(end 241.790982 21.572982)
		(width 0.13462)
		(layer "B.Cu")
		(net "85_5INCH_BOTTOM_DP")
	)
	(segment
		(start 219.247212 17.719802)
		(end 219.350082 17.57299)
		(width 0.13462)
		(layer "B.Cu")
		(net "85_5INCH_BOTTOM_DP")
	)
	(segment
		(start 227.303076 21.585682)
		(end 226.144328 15.012416)
		(width 0.13462)
		(layer "B.Cu")
		(net "85_5INCH_BOTTOM_DP")
	)
	(segment
		(start 224.052638 14.314424)
		(end 224.550224 14.663166)
		(width 0.13462)
		(layer "B.Cu")
		(net "85_5INCH_BOTTOM_DP")
	)
	(segment
		(start 223.46412 21.907246)
		(end 223.682306 21.595588)
		(width 0.13462)
		(layer "B.Cu")
		(net "85_5INCH_BOTTOM_DP")
	)
	(segment
		(start 226.60483 14.49451)
		(end 227.673662 14.306042)
		(width 0.13462)
		(layer "B.Cu")
		(net "85_5INCH_BOTTOM_DP")
	)
	(segment
		(start 235.414566 14.642084)
		(end 236.680502 21.823426)
		(width 0.13462)
		(layer "B.Cu")
		(net "85_5INCH_BOTTOM_DP")
	)
	(segment
		(start 234.382564 22.19579)
		(end 234.60075 21.883878)
		(width 0.13462)
		(layer "B.Cu")
		(net "85_5INCH_BOTTOM_DP")
	)
	(segment
		(start 229.771956 22.182582)
		(end 230.727758 22.013926)
		(width 0.13462)
		(layer "B.Cu")
		(net "85_5INCH_BOTTOM_DP")
	)
	(segment
		(start 228.171248 14.654784)
		(end 229.46106 21.964904)
		(width 0.13462)
		(layer "B.Cu")
		(net "85_5INCH_BOTTOM_DP")
	)
	(segment
		(start 224.550224 14.663166)
		(end 225.817938 21.848572)
		(width 0.13462)
		(layer "B.Cu")
		(net "85_5INCH_BOTTOM_DP")
	)
	(segment
		(start 240.617248 22.053296)
		(end 241.572796 21.88464)
		(width 0.13462)
		(layer "B.Cu")
		(net "85_5INCH_BOTTOM_DP")
	)
	(segment
		(start 222.871538 14.522704)
		(end 222.983552 14.502892)
		(width 0.13462)
		(layer "B.Cu")
		(net "85_5INCH_BOTTOM_DP")
	)
	(segment
		(start 223.682306 21.595588)
		(end 222.523304 15.020798)
		(width 0.13462)
		(layer "B.Cu")
		(net "85_5INCH_BOTTOM_DP")
	)
	(segment
		(start 240.635282 15.016988)
		(end 240.98377 14.519656)
		(width 0.13462)
		(layer "B.Cu")
		(net "85_5INCH_BOTTOM_DP")
	)
	(segment
		(start 222.983552 14.502892)
		(end 222.983806 14.502892)
		(width 0.13462)
		(layer "B.Cu")
		(net "85_5INCH_BOTTOM_DP")
	)
	(segment
		(start 218.90101 15.0241)
		(end 219.24899 14.52499)
		(width 0.13462)
		(layer "B.Cu")
		(net "85_5INCH_BOTTOM_DP")
	)
	(segment
		(start 230.945944 21.702014)
		(end 229.766622 15.011146)
		(width 0.13462)
		(layer "B.Cu")
		(net "85_5INCH_BOTTOM_DP")
	)
	(segment
		(start 239.039654 14.656562)
		(end 240.306606 21.835618)
		(width 0.13462)
		(layer "B.Cu")
		(net "85_5INCH_BOTTOM_DP")
	)
	(segment
		(start 219.24899 14.52499)
		(end 220.43009 14.316964)
		(width 0.13462)
		(layer "B.Cu")
		(net "85_5INCH_BOTTOM_DP")
	)
	(segment
		(start 238.166656 21.561298)
		(end 237.012226 15.013432)
		(width 0.13462)
		(layer "B.Cu")
		(net "85_5INCH_BOTTOM_DP")
	)
	(segment
		(start 226.492562 14.514322)
		(end 226.604576 14.49451)
		(width 0.13462)
		(layer "B.Cu")
		(net "85_5INCH_BOTTOM_DP")
	)
	(segment
		(start 226.128834 22.06625)
		(end 227.08489 21.89734)
		(width 0.13462)
		(layer "B.Cu")
		(net "85_5INCH_BOTTOM_DP")
	)
	(segment
		(start 237.94847 21.872956)
		(end 238.166656 21.561298)
		(width 0.13462)
		(layer "B.Cu")
		(net "85_5INCH_BOTTOM_DP")
	)
	(segment
		(start 222.523304 15.020798)
		(end 222.871538 14.522704)
		(width 0.13462)
		(layer "B.Cu")
		(net "85_5INCH_BOTTOM_DP")
	)
	(segment
		(start 240.306606 21.835618)
		(end 240.617248 22.053296)
		(width 0.13462)
		(layer "B.Cu")
		(net "85_5INCH_BOTTOM_DP")
	)
	(segment
		(start 214.93607 17.898364)
		(end 218.23426 17.898364)
		(width 0.13462)
		(layer "B.Cu")
		(net "85_5INCH_BOTTOM_DP")
	)
	(segment
		(start 230.115618 14.513052)
		(end 231.296718 14.304518)
		(width 0.13462)
		(layer "B.Cu")
		(net "85_5INCH_BOTTOM_DP")
	)
	(segment
		(start 233.11485 22.146006)
		(end 233.426762 22.364446)
		(width 0.13462)
		(layer "B.Cu")
		(net "85_5INCH_BOTTOM_DP")
	)
	(segment
		(start 233.387392 15.000224)
		(end 233.736388 14.50213)
		(width 0.13462)
		(layer "B.Cu")
		(net "85_5INCH_BOTTOM_DP")
	)
	(segment
		(start 220.43009 14.316964)
		(end 220.928184 14.665452)
		(width 0.13462)
		(layer "B.Cu")
		(net "85_5INCH_BOTTOM_DP")
	)
	(segment
		(start 222.19666 21.858224)
		(end 222.508064 22.076156)
		(width 0.13462)
		(layer "B.Cu")
		(net "85_5INCH_BOTTOM_DP")
	)
	(segment
		(start 231.793796 14.65326)
		(end 233.11485 22.146006)
		(width 0.13462)
		(layer "B.Cu")
		(net "85_5INCH_BOTTOM_DP")
	)
	(segment
		(start 227.08489 21.89734)
		(end 227.303076 21.585682)
		(width 0.13462)
		(layer "B.Cu")
		(net "85_5INCH_BOTTOM_DP")
	)
	(segment
		(start 233.426762 22.364446)
		(end 234.382564 22.19579)
		(width 0.13462)
		(layer "B.Cu")
		(net "85_5INCH_BOTTOM_DP")
	)
	(segment
		(start 230.727758 22.013926)
		(end 230.945944 21.702014)
		(width 0.13462)
		(layer "B.Cu")
		(net "85_5INCH_BOTTOM_DP")
	)
	(segment
		(start 222.508064 22.076156)
		(end 223.46412 21.907246)
		(width 0.13462)
		(layer "B.Cu")
		(net "85_5INCH_BOTTOM_DP")
	)
	(segment
		(start 236.680502 21.823426)
		(end 236.992414 22.041612)
		(width 0.13462)
		(layer "B.Cu")
		(net "85_5INCH_BOTTOM_DP")
	)
	(segment
		(start 234.917234 14.293342)
		(end 235.414566 14.642084)
		(width 0.13462)
		(layer "B.Cu")
		(net "85_5INCH_BOTTOM_DP")
	)
	(segment
		(start 225.817938 21.848572)
		(end 226.128834 22.06625)
		(width 0.13462)
		(layer "B.Cu")
		(net "85_5INCH_BOTTOM_DP")
	)
	(segment
		(start 226.604576 14.49451)
		(end 226.60483 14.49451)
		(width 0.13462)
		(layer "B.Cu")
		(net "85_5INCH_BOTTOM_DP")
	)
	(segment
		(start 219.350082 17.57299)
		(end 218.90101 15.0241)
		(width 0.13462)
		(layer "B.Cu")
		(net "85_5INCH_BOTTOM_DP")
	)
	(segment
		(start 243.793264 -117.708426)
		(end 244.047264 -117.962426)
		(width 0.13208)
		(layer "F.Cu")
		(net "P3V3_NIC4_PG_G1")
	)
	(segment
		(start 244.809264 -117.962426)
		(end 244.809264 -118.705376)
		(width 0.13208)
		(layer "F.Cu")
		(net "P3V3_NIC4_PG_G1")
	)
	(segment
		(start 243.793264 -117.211348)
		(end 243.793264 -117.708426)
		(width 0.13208)
		(layer "F.Cu")
		(net "P3V3_NIC4_PG_G1")
	)
	(segment
		(start 245.825264 -118.705376)
		(end 244.809264 -118.705376)
		(width 0.13208)
		(layer "F.Cu")
		(net "P3V3_NIC4_PG_G1")
	)
	(segment
		(start 244.047264 -117.962426)
		(end 244.809264 -117.962426)
		(width 0.13208)
		(layer "F.Cu")
		(net "P3V3_NIC4_PG_G1")
	)
	(via
		(at 244.809264 -117.962426)
		(size 0.508)
		(drill 0.254)
		(layers "F.Cu" "B.Cu")
		(net "P3V3_NIC4_PG_G1")
	)
	(segment
		(start 197.509384 -31.664402)
		(end 198.043038 -31.664402)
		(width 0.13208)
		(layer "F.Cu")
		(net "P3V3_SSD7_CO_GATE")
	)
	(segment
		(start 197.382384 -31.537402)
		(end 197.509384 -31.664402)
		(width 0.13208)
		(layer "F.Cu")
		(net "P3V3_SSD7_CO_GATE")
	)
	(segment
		(start 197.382384 -30.875732)
		(end 197.382384 -31.537402)
		(width 0.13208)
		(layer "F.Cu")
		(net "P3V3_SSD7_CO_GATE")
	)
	(segment
		(start 198.043038 -32.006032)
		(end 198.043038 -31.664402)
		(width 0.13208)
		(layer "F.Cu")
		(net "P3V3_SSD7_CO_GATE")
	)
	(segment
		(start 197.972172 -32.076898)
		(end 198.043038 -32.006032)
		(width 0.13208)
		(layer "F.Cu")
		(net "P3V3_SSD7_CO_GATE")
	)
	(segment
		(start 197.972172 -32.447992)
		(end 197.972172 -32.076898)
		(width 0.13208)
		(layer "F.Cu")
		(net "P3V3_SSD7_CO_GATE")
	)
	(via
		(at 198.043038 -31.664402)
		(size 0.508)
		(drill 0.254)
		(layers "F.Cu" "B.Cu")
		(net "P3V3_SSD7_CO_GATE")
	)
	(segment
		(start 308.191916 -37.951156)
		(end 308.281832 -38.041072)
		(width 0.13208)
		(layer "F.Cu")
		(net "P3V3_SSD11_PG_G2")
	)
	(segment
		(start 308.281832 -38.702742)
		(end 308.281832 -38.041072)
		(width 0.13208)
		(layer "F.Cu")
		(net "P3V3_SSD11_PG_G2")
	)
	(segment
		(start 308.280308 -38.701218)
		(end 308.281832 -38.702742)
		(width 0.13208)
		(layer "F.Cu")
		(net "P3V3_SSD11_PG_G2")
	)
	(segment
		(start 307.060854 -38.701218)
		(end 308.280308 -38.701218)
		(width 0.13208)
		(layer "F.Cu")
		(net "P3V3_SSD11_PG_G2")
	)
	(segment
		(start 307.060854 -37.951156)
		(end 308.191916 -37.951156)
		(width 0.13208)
		(layer "F.Cu")
		(net "P3V3_SSD11_PG_G2")
	)
	(via
		(at 308.281832 -38.702742)
		(size 0.508)
		(drill 0.254)
		(layers "F.Cu" "B.Cu")
		(net "P3V3_SSD11_PG_G2")
	)
	(segment
		(start 313.294268 10.399776)
		(end 312.613294 10.217912)
		(width 0.13462)
		(layer "B.Cu")
		(net "85_10INCH_IN6_DN")
	)
	(segment
		(start 256.160524 10.373868)
		(end 256.841498 10.192004)
		(width 0.13462)
		(layer "B.Cu")
		(net "85_10INCH_IN6_DN")
	)
	(segment
		(start 280.327354 6.335268)
		(end 281.757374 14.445742)
		(width 0.1651)
		(layer "In15.Cu")
		(net "85_10INCH_IN6_DN")
	)
	(segment
		(start 284.338014 6.343396)
		(end 285.770574 14.468094)
		(width 0.1651)
		(layer "In15.Cu")
		(net "85_10INCH_IN6_DN")
	)
	(segment
		(start 292.35654 6.344412)
		(end 293.792148 14.486636)
		(width 0.1651)
		(layer "In15.Cu")
		(net "85_10INCH_IN6_DN")
	)
	(segment
		(start 261.699248 14.374622)
		(end 262.081264 14.642592)
		(width 0.1651)
		(layer "In15.Cu")
		(net "85_10INCH_IN6_DN")
	)
	(segment
		(start 272.311114 6.346698)
		(end 273.75104 14.514322)
		(width 0.1651)
		(layer "In15.Cu")
		(net "85_10INCH_IN6_DN")
	)
	(segment
		(start 298.55287 6.153912)
		(end 299.799756 5.933694)
		(width 0.1651)
		(layer "In15.Cu")
		(net "85_10INCH_IN6_DN")
	)
	(segment
		(start 290.134294 6.73608)
		(end 290.536122 6.162802)
		(width 0.1651)
		(layer "In15.Cu")
		(net "85_10INCH_IN6_DN")
	)
	(segment
		(start 276.319234 6.340094)
		(end 277.752048 14.466824)
		(width 0.1651)
		(layer "In15.Cu")
		(net "85_10INCH_IN6_DN")
	)
	(segment
		(start 275.149564 14.602714)
		(end 275.417534 14.220952)
		(width 0.1651)
		(layer "In15.Cu")
		(net "85_10INCH_IN6_DN")
	)
	(segment
		(start 262.470646 6.155182)
		(end 263.717532 5.934964)
		(width 0.1651)
		(layer "In15.Cu")
		(net "85_10INCH_IN6_DN")
	)
	(segment
		(start 266.078462 6.732016)
		(end 266.48029 6.158738)
		(width 0.1651)
		(layer "In15.Cu")
		(net "85_10INCH_IN6_DN")
	)
	(segment
		(start 291.45357 14.218666)
		(end 290.134294 6.73608)
		(width 0.1651)
		(layer "In15.Cu")
		(net "85_10INCH_IN6_DN")
	)
	(segment
		(start 281.757374 14.445742)
		(end 282.139644 14.713712)
		(width 0.1651)
		(layer "In15.Cu")
		(net "85_10INCH_IN6_DN")
	)
	(segment
		(start 290.536122 6.162802)
		(end 291.783008 5.942584)
		(width 0.1651)
		(layer "In15.Cu")
		(net "85_10INCH_IN6_DN")
	)
	(segment
		(start 274.133818 14.782292)
		(end 275.149564 14.602714)
		(width 0.1651)
		(layer "In15.Cu")
		(net "85_10INCH_IN6_DN")
	)
	(segment
		(start 298.151042 6.72719)
		(end 298.55287 6.153912)
		(width 0.1651)
		(layer "In15.Cu")
		(net "85_10INCH_IN6_DN")
	)
	(segment
		(start 268.300708 6.340348)
		(end 269.739618 14.499082)
		(width 0.1651)
		(layer "In15.Cu")
		(net "85_10INCH_IN6_DN")
	)
	(segment
		(start 282.517342 6.161532)
		(end 283.764228 5.941314)
		(width 0.1651)
		(layer "In15.Cu")
		(net "85_10INCH_IN6_DN")
	)
	(segment
		(start 286.527748 6.168136)
		(end 287.774634 5.947918)
		(width 0.1651)
		(layer "In15.Cu")
		(net "85_10INCH_IN6_DN")
	)
	(segment
		(start 290.169854 14.780514)
		(end 291.1856 14.600936)
		(width 0.1651)
		(layer "In15.Cu")
		(net "85_10INCH_IN6_DN")
	)
	(segment
		(start 279.150064 14.555216)
		(end 279.418034 14.172946)
		(width 0.1651)
		(layer "In15.Cu")
		(net "85_10INCH_IN6_DN")
	)
	(segment
		(start 267.109448 14.483334)
		(end 267.377672 14.100556)
		(width 0.1651)
		(layer "In15.Cu")
		(net "85_10INCH_IN6_DN")
	)
	(segment
		(start 275.417534 14.220952)
		(end 274.096988 6.731762)
		(width 0.1651)
		(layer "In15.Cu")
		(net "85_10INCH_IN6_DN")
	)
	(segment
		(start 279.418034 14.172946)
		(end 278.105108 6.726936)
		(width 0.1651)
		(layer "In15.Cu")
		(net "85_10INCH_IN6_DN")
	)
	(segment
		(start 286.152844 14.736064)
		(end 287.16859 14.556486)
		(width 0.1651)
		(layer "In15.Cu")
		(net "85_10INCH_IN6_DN")
	)
	(segment
		(start 261.124954 11.119866)
		(end 261.699248 14.374622)
		(width 0.1651)
		(layer "In15.Cu")
		(net "85_10INCH_IN6_DN")
	)
	(segment
		(start 304.383694 6.342634)
		(end 305.814476 14.457426)
		(width 0.1651)
		(layer "In15.Cu")
		(net "85_10INCH_IN6_DN")
	)
	(segment
		(start 262.081264 14.642592)
		(end 263.09701 14.463014)
		(width 0.1651)
		(layer "In15.Cu")
		(net "85_10INCH_IN6_DN")
	)
	(segment
		(start 306.575968 6.181598)
		(end 307.822854 5.96138)
		(width 0.1651)
		(layer "In15.Cu")
		(net "85_10INCH_IN6_DN")
	)
	(segment
		(start 283.42336 14.151864)
		(end 282.115514 6.73481)
		(width 0.1651)
		(layer "In15.Cu")
		(net "85_10INCH_IN6_DN")
	)
	(segment
		(start 271.40535 14.205204)
		(end 270.088868 6.738366)
		(width 0.1651)
		(layer "In15.Cu")
		(net "85_10INCH_IN6_DN")
	)
	(segment
		(start 283.764228 5.941314)
		(end 284.338014 6.343396)
		(width 0.1651)
		(layer "In15.Cu")
		(net "85_10INCH_IN6_DN")
	)
	(segment
		(start 307.822854 5.96138)
		(end 308.39664 6.363716)
		(width 0.1651)
		(layer "In15.Cu")
		(net "85_10INCH_IN6_DN")
	)
	(segment
		(start 267.727176 5.93852)
		(end 268.300708 6.340348)
		(width 0.1651)
		(layer "In15.Cu")
		(net "85_10INCH_IN6_DN")
	)
	(segment
		(start 294.542972 6.149086)
		(end 295.789858 5.928868)
		(width 0.1651)
		(layer "In15.Cu")
		(net "85_10INCH_IN6_DN")
	)
	(segment
		(start 263.717532 5.934964)
		(end 264.291064 6.336792)
		(width 0.1651)
		(layer "In15.Cu")
		(net "85_10INCH_IN6_DN")
	)
	(segment
		(start 270.121634 14.767052)
		(end 271.13738 14.587474)
		(width 0.1651)
		(layer "In15.Cu")
		(net "85_10INCH_IN6_DN")
	)
	(segment
		(start 282.139644 14.713712)
		(end 283.15539 14.534134)
		(width 0.1651)
		(layer "In15.Cu")
		(net "85_10INCH_IN6_DN")
	)
	(segment
		(start 275.745702 5.938266)
		(end 276.319234 6.340094)
		(width 0.1651)
		(layer "In15.Cu")
		(net "85_10INCH_IN6_DN")
	)
	(segment
		(start 309.382414 10.508742)
		(end 312.322464 10.508742)
		(width 0.1651)
		(layer "In15.Cu")
		(net "85_10INCH_IN6_DN")
	)
	(segment
		(start 279.753822 5.93344)
		(end 280.327354 6.335268)
		(width 0.1651)
		(layer "In15.Cu")
		(net "85_10INCH_IN6_DN")
	)
	(segment
		(start 306.17414 6.754876)
		(end 306.575968 6.181598)
		(width 0.1651)
		(layer "In15.Cu")
		(net "85_10INCH_IN6_DN")
	)
	(segment
		(start 302.16094 6.734302)
		(end 302.562768 6.16077)
		(width 0.1651)
		(layer "In15.Cu")
		(net "85_10INCH_IN6_DN")
	)
	(segment
		(start 293.792148 14.486636)
		(end 294.174418 14.754606)
		(width 0.1651)
		(layer "In15.Cu")
		(net "85_10INCH_IN6_DN")
	)
	(segment
		(start 307.480462 14.163548)
		(end 306.17414 6.754876)
		(width 0.1651)
		(layer "In15.Cu")
		(net "85_10INCH_IN6_DN")
	)
	(segment
		(start 271.13738 14.587474)
		(end 271.40535 14.205204)
		(width 0.1651)
		(layer "In15.Cu")
		(net "85_10INCH_IN6_DN")
	)
	(segment
		(start 303.809654 5.940552)
		(end 304.383694 6.342634)
		(width 0.1651)
		(layer "In15.Cu")
		(net "85_10INCH_IN6_DN")
	)
	(segment
		(start 282.115514 6.73481)
		(end 282.517342 6.161532)
		(width 0.1651)
		(layer "In15.Cu")
		(net "85_10INCH_IN6_DN")
	)
	(segment
		(start 291.783008 5.942584)
		(end 292.35654 6.344412)
		(width 0.1651)
		(layer "In15.Cu")
		(net "85_10INCH_IN6_DN")
	)
	(segment
		(start 312.322464 10.508742)
		(end 312.613294 10.217912)
		(width 0.1651)
		(layer "In15.Cu")
		(net "85_10INCH_IN6_DN")
	)
	(segment
		(start 308.39664 6.363716)
		(end 309.091584 10.30478)
		(width 0.1651)
		(layer "In15.Cu")
		(net "85_10INCH_IN6_DN")
	)
	(segment
		(start 269.739618 14.499082)
		(end 270.121634 14.767052)
		(width 0.1651)
		(layer "In15.Cu")
		(net "85_10INCH_IN6_DN")
	)
	(segment
		(start 299.194474 14.547088)
		(end 299.462444 14.164818)
		(width 0.1651)
		(layer "In15.Cu")
		(net "85_10INCH_IN6_DN")
	)
	(segment
		(start 305.814476 14.457426)
		(end 306.196746 14.725396)
		(width 0.1651)
		(layer "In15.Cu")
		(net "85_10INCH_IN6_DN")
	)
	(segment
		(start 267.377672 14.100556)
		(end 266.078462 6.732016)
		(width 0.1651)
		(layer "In15.Cu")
		(net "85_10INCH_IN6_DN")
	)
	(segment
		(start 274.498816 6.158484)
		(end 275.745702 5.938266)
		(width 0.1651)
		(layer "In15.Cu")
		(net "85_10INCH_IN6_DN")
	)
	(segment
		(start 266.48029 6.158738)
		(end 267.727176 5.93852)
		(width 0.1651)
		(layer "In15.Cu")
		(net "85_10INCH_IN6_DN")
	)
	(segment
		(start 296.36339 6.330696)
		(end 297.796458 14.458696)
		(width 0.1651)
		(layer "In15.Cu")
		(net "85_10INCH_IN6_DN")
	)
	(segment
		(start 265.712194 14.395196)
		(end 266.093956 14.663166)
		(width 0.1651)
		(layer "In15.Cu")
		(net "85_10INCH_IN6_DN")
	)
	(segment
		(start 263.09701 14.463014)
		(end 263.36498 14.08049)
		(width 0.1651)
		(layer "In15.Cu")
		(net "85_10INCH_IN6_DN")
	)
	(segment
		(start 278.105108 6.726936)
		(end 278.506936 6.153658)
		(width 0.1651)
		(layer "In15.Cu")
		(net "85_10INCH_IN6_DN")
	)
	(segment
		(start 260.487668 10.482834)
		(end 261.124954 11.119866)
		(width 0.1651)
		(layer "In15.Cu")
		(net "85_10INCH_IN6_DN")
	)
	(segment
		(start 257.132328 10.482834)
		(end 260.487668 10.482834)
		(width 0.1651)
		(layer "In15.Cu")
		(net "85_10INCH_IN6_DN")
	)
	(segment
		(start 301.802546 14.442186)
		(end 302.184816 14.710156)
		(width 0.1651)
		(layer "In15.Cu")
		(net "85_10INCH_IN6_DN")
	)
	(segment
		(start 283.15539 14.534134)
		(end 283.42336 14.151864)
		(width 0.1651)
		(layer "In15.Cu")
		(net "85_10INCH_IN6_DN")
	)
	(segment
		(start 264.291064 6.336792)
		(end 265.712194 14.395196)
		(width 0.1651)
		(layer "In15.Cu")
		(net "85_10INCH_IN6_DN")
	)
	(segment
		(start 266.093956 14.663166)
		(end 267.109448 14.483334)
		(width 0.1651)
		(layer "In15.Cu")
		(net "85_10INCH_IN6_DN")
	)
	(segment
		(start 295.458134 14.192758)
		(end 294.141144 6.722364)
		(width 0.1651)
		(layer "In15.Cu")
		(net "85_10INCH_IN6_DN")
	)
	(segment
		(start 298.178728 14.726666)
		(end 299.194474 14.547088)
		(width 0.1651)
		(layer "In15.Cu")
		(net "85_10INCH_IN6_DN")
	)
	(segment
		(start 287.774634 5.947918)
		(end 288.34842 6.349746)
		(width 0.1651)
		(layer "In15.Cu")
		(net "85_10INCH_IN6_DN")
	)
	(segment
		(start 277.752048 14.466824)
		(end 278.134318 14.734794)
		(width 0.1651)
		(layer "In15.Cu")
		(net "85_10INCH_IN6_DN")
	)
	(segment
		(start 256.841498 10.192004)
		(end 257.132328 10.482834)
		(width 0.1651)
		(layer "In15.Cu")
		(net "85_10INCH_IN6_DN")
	)
	(segment
		(start 294.174418 14.754606)
		(end 295.190164 14.575028)
		(width 0.1651)
		(layer "In15.Cu")
		(net "85_10INCH_IN6_DN")
	)
	(segment
		(start 271.737582 5.94487)
		(end 272.311114 6.346698)
		(width 0.1651)
		(layer "In15.Cu")
		(net "85_10INCH_IN6_DN")
	)
	(segment
		(start 270.088868 6.738366)
		(end 270.490696 6.165088)
		(width 0.1651)
		(layer "In15.Cu")
		(net "85_10INCH_IN6_DN")
	)
	(segment
		(start 287.43656 14.174216)
		(end 286.12592 6.741414)
		(width 0.1651)
		(layer "In15.Cu")
		(net "85_10INCH_IN6_DN")
	)
	(segment
		(start 297.796458 14.458696)
		(end 298.178728 14.726666)
		(width 0.1651)
		(layer "In15.Cu")
		(net "85_10INCH_IN6_DN")
	)
	(segment
		(start 300.373288 6.335522)
		(end 301.802546 14.442186)
		(width 0.1651)
		(layer "In15.Cu")
		(net "85_10INCH_IN6_DN")
	)
	(segment
		(start 302.184816 14.710156)
		(end 303.200562 14.530578)
		(width 0.1651)
		(layer "In15.Cu")
		(net "85_10INCH_IN6_DN")
	)
	(segment
		(start 302.562768 6.16077)
		(end 303.809654 5.940552)
		(width 0.1651)
		(layer "In15.Cu")
		(net "85_10INCH_IN6_DN")
	)
	(segment
		(start 306.196746 14.725396)
		(end 307.212492 14.545818)
		(width 0.1651)
		(layer "In15.Cu")
		(net "85_10INCH_IN6_DN")
	)
	(segment
		(start 303.468786 14.148054)
		(end 302.16094 6.734302)
		(width 0.1651)
		(layer "In15.Cu")
		(net "85_10INCH_IN6_DN")
	)
	(segment
		(start 294.141144 6.722364)
		(end 294.542972 6.149086)
		(width 0.1651)
		(layer "In15.Cu")
		(net "85_10INCH_IN6_DN")
	)
	(segment
		(start 299.799756 5.933694)
		(end 300.373288 6.335522)
		(width 0.1651)
		(layer "In15.Cu")
		(net "85_10INCH_IN6_DN")
	)
	(segment
		(start 285.770574 14.468094)
		(end 286.152844 14.736064)
		(width 0.1651)
		(layer "In15.Cu")
		(net "85_10INCH_IN6_DN")
	)
	(segment
		(start 288.34842 6.349746)
		(end 289.787584 14.512544)
		(width 0.1651)
		(layer "In15.Cu")
		(net "85_10INCH_IN6_DN")
	)
	(segment
		(start 270.490696 6.165088)
		(end 271.737582 5.94487)
		(width 0.1651)
		(layer "In15.Cu")
		(net "85_10INCH_IN6_DN")
	)
	(segment
		(start 262.068818 6.72846)
		(end 262.470646 6.155182)
		(width 0.1651)
		(layer "In15.Cu")
		(net "85_10INCH_IN6_DN")
	)
	(segment
		(start 299.462444 14.164818)
		(end 298.151042 6.72719)
		(width 0.1651)
		(layer "In15.Cu")
		(net "85_10INCH_IN6_DN")
	)
	(segment
		(start 287.16859 14.556486)
		(end 287.43656 14.174216)
		(width 0.1651)
		(layer "In15.Cu")
		(net "85_10INCH_IN6_DN")
	)
	(segment
		(start 303.200562 14.530578)
		(end 303.468786 14.148054)
		(width 0.1651)
		(layer "In15.Cu")
		(net "85_10INCH_IN6_DN")
	)
	(segment
		(start 295.789858 5.928868)
		(end 296.36339 6.330696)
		(width 0.1651)
		(layer "In15.Cu")
		(net "85_10INCH_IN6_DN")
	)
	(segment
		(start 274.096988 6.731762)
		(end 274.498816 6.158484)
		(width 0.1651)
		(layer "In15.Cu")
		(net "85_10INCH_IN6_DN")
	)
	(segment
		(start 307.212492 14.545818)
		(end 307.480462 14.163548)
		(width 0.1651)
		(layer "In15.Cu")
		(net "85_10INCH_IN6_DN")
	)
	(segment
		(start 295.190164 14.575028)
		(end 295.458134 14.192758)
		(width 0.1651)
		(layer "In15.Cu")
		(net "85_10INCH_IN6_DN")
	)
	(segment
		(start 309.091584 10.30478)
		(end 309.382414 10.508742)
		(width 0.1651)
		(layer "In15.Cu")
		(net "85_10INCH_IN6_DN")
	)
	(segment
		(start 263.36498 14.08049)
		(end 262.068818 6.72846)
		(width 0.1651)
		(layer "In15.Cu")
		(net "85_10INCH_IN6_DN")
	)
	(segment
		(start 273.75104 14.514322)
		(end 274.133818 14.782292)
		(width 0.1651)
		(layer "In15.Cu")
		(net "85_10INCH_IN6_DN")
	)
	(segment
		(start 289.787584 14.512544)
		(end 290.169854 14.780514)
		(width 0.1651)
		(layer "In15.Cu")
		(net "85_10INCH_IN6_DN")
	)
	(segment
		(start 278.134318 14.734794)
		(end 279.150064 14.555216)
		(width 0.1651)
		(layer "In15.Cu")
		(net "85_10INCH_IN6_DN")
	)
	(segment
		(start 278.506936 6.153658)
		(end 279.753822 5.93344)
		(width 0.1651)
		(layer "In15.Cu")
		(net "85_10INCH_IN6_DN")
	)
	(segment
		(start 291.1856 14.600936)
		(end 291.45357 14.218666)
		(width 0.1651)
		(layer "In15.Cu")
		(net "85_10INCH_IN6_DN")
	)
	(segment
		(start 286.12592 6.741414)
		(end 286.527748 6.168136)
		(width 0.1651)
		(layer "In15.Cu")
		(net "85_10INCH_IN6_DN")
	)
	(segment
		(start 206.307944 -114.311176)
		(end 205.843124 -113.846356)
		(width 0.13208)
		(layer "F.Cu")
		(net "P3V3_NIC3_CO_EN")
	)
	(segment
		(start 206.724504 -114.311176)
		(end 206.307944 -114.311176)
		(width 0.13208)
		(layer "F.Cu")
		(net "P3V3_NIC3_CO_EN")
	)
	(segment
		(start 205.152244 -113.876836)
		(end 205.515972 -113.876836)
		(width 0.13208)
		(layer "F.Cu")
		(net "P3V3_NIC3_CO_EN")
	)
	(segment
		(start 205.546452 -113.846356)
		(end 205.843124 -113.846356)
		(width 0.13208)
		(layer "F.Cu")
		(net "P3V3_NIC3_CO_EN")
	)
	(segment
		(start 205.515972 -113.876836)
		(end 205.546452 -113.846356)
		(width 0.13208)
		(layer "F.Cu")
		(net "P3V3_NIC3_CO_EN")
	)
	(via
		(at 205.843124 -113.846356)
		(size 0.508)
		(drill 0.254)
		(layers "F.Cu" "B.Cu")
		(net "P3V3_NIC3_CO_EN")
	)
	(segment
		(start 325.561198 -115.832636)
		(end 325.999348 -115.394486)
		(width 0.13208)
		(layer "F.Cu")
		(net "P3V3_NIC5_CO_ILIMIT")
	)
	(segment
		(start 325.558658 -115.835176)
		(end 325.561198 -115.832636)
		(width 0.13208)
		(layer "F.Cu")
		(net "P3V3_NIC5_CO_ILIMIT")
	)
	(segment
		(start 325.999348 -115.394486)
		(end 326.293988 -115.394486)
		(width 0.13208)
		(layer "F.Cu")
		(net "P3V3_NIC5_CO_ILIMIT")
	)
	(segment
		(start 324.824598 -115.835176)
		(end 325.558658 -115.835176)
		(width 0.13208)
		(layer "F.Cu")
		(net "P3V3_NIC5_CO_ILIMIT")
	)
	(via
		(at 325.561198 -115.832636)
		(size 0.508)
		(drill 0.254)
		(layers "F.Cu" "B.Cu")
		(net "P3V3_NIC5_CO_ILIMIT")
	)
	(segment
		(start 166.18204 -38.702742)
		(end 166.18204 -38.041072)
		(width 0.13208)
		(layer "F.Cu")
		(net "P3V3_SSD6_PG_G2")
	)
	(segment
		(start 166.18204 -38.041072)
		(end 166.092124 -37.951156)
		(width 0.13208)
		(layer "F.Cu")
		(net "P3V3_SSD6_PG_G2")
	)
	(segment
		(start 166.092124 -37.951156)
		(end 164.961062 -37.951156)
		(width 0.13208)
		(layer "F.Cu")
		(net "P3V3_SSD6_PG_G2")
	)
	(segment
		(start 166.180516 -38.701218)
		(end 164.961062 -38.701218)
		(width 0.13208)
		(layer "F.Cu")
		(net "P3V3_SSD6_PG_G2")
	)
	(segment
		(start 166.18204 -38.702742)
		(end 166.180516 -38.701218)
		(width 0.13208)
		(layer "F.Cu")
		(net "P3V3_SSD6_PG_G2")
	)
	(via
		(at 166.18204 -38.702742)
		(size 0.508)
		(drill 0.254)
		(layers "F.Cu" "B.Cu")
		(net "P3V3_SSD6_PG_G2")
	)
	(segment
		(start 286.867346 -32.25927)
		(end 287.056068 -32.447992)
		(width 0.13208)
		(layer "F.Cu")
		(net "P3V3_SSD10_CO_EN")
	)
	(segment
		(start 286.982408 -30.875732)
		(end 286.982408 -31.44139)
		(width 0.13208)
		(layer "F.Cu")
		(net "P3V3_SSD10_CO_EN")
	)
	(segment
		(start 286.982408 -31.44139)
		(end 286.867346 -31.719266)
		(width 0.13208)
		(layer "F.Cu")
		(net "P3V3_SSD10_CO_EN")
	)
	(segment
		(start 286.867346 -31.719266)
		(end 286.867346 -32.25927)
		(width 0.13208)
		(layer "F.Cu")
		(net "P3V3_SSD10_CO_EN")
	)
	(via
		(at 286.867346 -31.719266)
		(size 0.508)
		(drill 0.254)
		(layers "F.Cu" "B.Cu")
		(net "P3V3_SSD10_CO_EN")
	)
	(segment
		(start 401.194524 7.899908)
		(end 401.875498 7.718044)
		(width 0.13462)
		(layer "F.Cu")
		(net "85_10INCH_IN3_DN")
	)
	(segment
		(start 458.328268 7.925816)
		(end 457.647294 7.743952)
		(width 0.13462)
		(layer "F.Cu")
		(net "85_10INCH_IN3_DN")
	)
	(segment
		(start 415.25317 5.003546)
		(end 415.654998 4.430268)
		(width 0.1651)
		(layer "In9.Cu")
		(net "85_10INCH_IN3_DN")
	)
	(segment
		(start 441.527692 4.595876)
		(end 442.96076 12.723876)
		(width 0.1651)
		(layer "In9.Cu")
		(net "85_10INCH_IN3_DN")
	)
	(segment
		(start 448.633088 12.413234)
		(end 447.325242 4.999228)
		(width 0.1651)
		(layer "In9.Cu")
		(net "85_10INCH_IN3_DN")
	)
	(segment
		(start 439.305446 4.987544)
		(end 439.707274 4.414266)
		(width 0.1651)
		(layer "In9.Cu")
		(net "85_10INCH_IN3_DN")
	)
	(segment
		(start 439.707274 4.414266)
		(end 440.95416 4.194048)
		(width 0.1651)
		(layer "In9.Cu")
		(net "85_10INCH_IN3_DN")
	)
	(segment
		(start 452.987156 4.22656)
		(end 453.560942 4.628896)
		(width 0.1651)
		(layer "In9.Cu")
		(net "85_10INCH_IN3_DN")
	)
	(segment
		(start 410.876496 12.66063)
		(end 411.258258 12.928346)
		(width 0.1651)
		(layer "In9.Cu")
		(net "85_10INCH_IN3_DN")
	)
	(segment
		(start 429.502316 4.608576)
		(end 430.934876 12.733274)
		(width 0.1651)
		(layer "In9.Cu")
		(net "85_10INCH_IN3_DN")
	)
	(segment
		(start 431.290222 5.006594)
		(end 431.69205 4.433316)
		(width 0.1651)
		(layer "In9.Cu")
		(net "85_10INCH_IN3_DN")
	)
	(segment
		(start 435.700424 4.427982)
		(end 436.94731 4.207764)
		(width 0.1651)
		(layer "In9.Cu")
		(net "85_10INCH_IN3_DN")
	)
	(segment
		(start 435.334156 13.045694)
		(end 436.349902 12.866116)
		(width 0.1651)
		(layer "In9.Cu")
		(net "85_10INCH_IN3_DN")
	)
	(segment
		(start 437.520842 4.609592)
		(end 438.95645 12.751816)
		(width 0.1651)
		(layer "In9.Cu")
		(net "85_10INCH_IN3_DN")
	)
	(segment
		(start 413.46501 4.605528)
		(end 414.90392 12.764008)
		(width 0.1651)
		(layer "In9.Cu")
		(net "85_10INCH_IN3_DN")
	)
	(segment
		(start 408.881834 4.200144)
		(end 409.455366 4.601972)
		(width 0.1651)
		(layer "In9.Cu")
		(net "85_10INCH_IN3_DN")
	)
	(segment
		(start 418.915342 12.779502)
		(end 419.29812 13.047472)
		(width 0.1651)
		(layer "In9.Cu")
		(net "85_10INCH_IN3_DN")
	)
	(segment
		(start 409.455366 4.601972)
		(end 410.876496 12.66063)
		(width 0.1651)
		(layer "In9.Cu")
		(net "85_10INCH_IN3_DN")
	)
	(segment
		(start 416.301682 12.8524)
		(end 416.569652 12.47013)
		(width 0.1651)
		(layer "In9.Cu")
		(net "85_10INCH_IN3_DN")
	)
	(segment
		(start 443.717172 4.419092)
		(end 444.964058 4.198874)
		(width 0.1651)
		(layer "In9.Cu")
		(net "85_10INCH_IN3_DN")
	)
	(segment
		(start 427.279816 4.99999)
		(end 427.681644 4.426712)
		(width 0.1651)
		(layer "In9.Cu")
		(net "85_10INCH_IN3_DN")
	)
	(segment
		(start 447.349118 12.975336)
		(end 448.364864 12.795758)
		(width 0.1651)
		(layer "In9.Cu")
		(net "85_10INCH_IN3_DN")
	)
	(segment
		(start 440.95416 4.194048)
		(end 441.527692 4.595876)
		(width 0.1651)
		(layer "In9.Cu")
		(net "85_10INCH_IN3_DN")
	)
	(segment
		(start 423.29862 12.999974)
		(end 424.314366 12.820396)
		(width 0.1651)
		(layer "In9.Cu")
		(net "85_10INCH_IN3_DN")
	)
	(segment
		(start 428.319692 12.799314)
		(end 428.587662 12.417044)
		(width 0.1651)
		(layer "In9.Cu")
		(net "85_10INCH_IN3_DN")
	)
	(segment
		(start 442.96076 12.723876)
		(end 443.34303 12.991846)
		(width 0.1651)
		(layer "In9.Cu")
		(net "85_10INCH_IN3_DN")
	)
	(segment
		(start 431.317146 13.001244)
		(end 432.332892 12.821666)
		(width 0.1651)
		(layer "In9.Cu")
		(net "85_10INCH_IN3_DN")
	)
	(segment
		(start 436.349902 12.866116)
		(end 436.617872 12.483846)
		(width 0.1651)
		(layer "In9.Cu")
		(net "85_10INCH_IN3_DN")
	)
	(segment
		(start 427.303946 12.978892)
		(end 428.319692 12.799314)
		(width 0.1651)
		(layer "In9.Cu")
		(net "85_10INCH_IN3_DN")
	)
	(segment
		(start 436.617872 12.483846)
		(end 435.298596 5.00126)
		(width 0.1651)
		(layer "In9.Cu")
		(net "85_10INCH_IN3_DN")
	)
	(segment
		(start 412.27375 12.748768)
		(end 412.541974 12.36599)
		(width 0.1651)
		(layer "In9.Cu")
		(net "85_10INCH_IN3_DN")
	)
	(segment
		(start 451.74027 4.446778)
		(end 452.987156 4.22656)
		(width 0.1651)
		(layer "In9.Cu")
		(net "85_10INCH_IN3_DN")
	)
	(segment
		(start 457.356464 8.034782)
		(end 457.647294 7.743952)
		(width 0.1651)
		(layer "In9.Cu")
		(net "85_10INCH_IN3_DN")
	)
	(segment
		(start 450.978778 12.722606)
		(end 451.361048 12.990576)
		(width 0.1651)
		(layer "In9.Cu")
		(net "85_10INCH_IN3_DN")
	)
	(segment
		(start 408.529282 12.345416)
		(end 407.23312 4.99364)
		(width 0.1651)
		(layer "In9.Cu")
		(net "85_10INCH_IN3_DN")
	)
	(segment
		(start 432.938936 4.213098)
		(end 433.512722 4.614926)
		(width 0.1651)
		(layer "In9.Cu")
		(net "85_10INCH_IN3_DN")
	)
	(segment
		(start 412.541974 12.36599)
		(end 411.242764 4.997196)
		(width 0.1651)
		(layer "In9.Cu")
		(net "85_10INCH_IN3_DN")
	)
	(segment
		(start 444.626746 12.429998)
		(end 443.315344 4.99237)
		(width 0.1651)
		(layer "In9.Cu")
		(net "85_10INCH_IN3_DN")
	)
	(segment
		(start 428.928784 4.206494)
		(end 429.502316 4.608576)
		(width 0.1651)
		(layer "In9.Cu")
		(net "85_10INCH_IN3_DN")
	)
	(segment
		(start 434.951886 12.777724)
		(end 435.334156 13.045694)
		(width 0.1651)
		(layer "In9.Cu")
		(net "85_10INCH_IN3_DN")
	)
	(segment
		(start 425.491656 4.600448)
		(end 426.921676 12.710922)
		(width 0.1651)
		(layer "In9.Cu")
		(net "85_10INCH_IN3_DN")
	)
	(segment
		(start 432.600862 12.439396)
		(end 431.290222 5.006594)
		(width 0.1651)
		(layer "In9.Cu")
		(net "85_10INCH_IN3_DN")
	)
	(segment
		(start 407.23312 4.99364)
		(end 407.634948 4.420362)
		(width 0.1651)
		(layer "In9.Cu")
		(net "85_10INCH_IN3_DN")
	)
	(segment
		(start 419.663118 4.423664)
		(end 420.910004 4.203446)
		(width 0.1651)
		(layer "In9.Cu")
		(net "85_10INCH_IN3_DN")
	)
	(segment
		(start 431.69205 4.433316)
		(end 432.938936 4.213098)
		(width 0.1651)
		(layer "In9.Cu")
		(net "85_10INCH_IN3_DN")
	)
	(segment
		(start 436.94731 4.207764)
		(end 437.520842 4.609592)
		(width 0.1651)
		(layer "In9.Cu")
		(net "85_10INCH_IN3_DN")
	)
	(segment
		(start 432.332892 12.821666)
		(end 432.600862 12.439396)
		(width 0.1651)
		(layer "In9.Cu")
		(net "85_10INCH_IN3_DN")
	)
	(segment
		(start 406.86355 12.639548)
		(end 407.245566 12.907518)
		(width 0.1651)
		(layer "In9.Cu")
		(net "85_10INCH_IN3_DN")
	)
	(segment
		(start 402.166328 8.008874)
		(end 405.521668 8.008874)
		(width 0.1651)
		(layer "In9.Cu")
		(net "85_10INCH_IN3_DN")
	)
	(segment
		(start 405.521668 8.008874)
		(end 406.158954 8.645906)
		(width 0.1651)
		(layer "In9.Cu")
		(net "85_10INCH_IN3_DN")
	)
	(segment
		(start 415.654998 4.430268)
		(end 416.901884 4.21005)
		(width 0.1651)
		(layer "In9.Cu")
		(net "85_10INCH_IN3_DN")
	)
	(segment
		(start 444.964058 4.198874)
		(end 445.53759 4.600702)
		(width 0.1651)
		(layer "In9.Cu")
		(net "85_10INCH_IN3_DN")
	)
	(segment
		(start 408.261312 12.72794)
		(end 408.529282 12.345416)
		(width 0.1651)
		(layer "In9.Cu")
		(net "85_10INCH_IN3_DN")
	)
	(segment
		(start 445.53759 4.600702)
		(end 446.966848 12.707366)
		(width 0.1651)
		(layer "In9.Cu")
		(net "85_10INCH_IN3_DN")
	)
	(segment
		(start 449.547996 4.60756)
		(end 450.978778 12.722606)
		(width 0.1651)
		(layer "In9.Cu")
		(net "85_10INCH_IN3_DN")
	)
	(segment
		(start 424.314366 12.820396)
		(end 424.582336 12.438126)
		(width 0.1651)
		(layer "In9.Cu")
		(net "85_10INCH_IN3_DN")
	)
	(segment
		(start 453.560942 4.628896)
		(end 454.125584 7.83082)
		(width 0.1651)
		(layer "In9.Cu")
		(net "85_10INCH_IN3_DN")
	)
	(segment
		(start 435.298596 5.00126)
		(end 435.700424 4.427982)
		(width 0.1651)
		(layer "In9.Cu")
		(net "85_10INCH_IN3_DN")
	)
	(segment
		(start 412.891478 4.2037)
		(end 413.46501 4.605528)
		(width 0.1651)
		(layer "In9.Cu")
		(net "85_10INCH_IN3_DN")
	)
	(segment
		(start 421.483536 4.605274)
		(end 422.91635 12.732004)
		(width 0.1651)
		(layer "In9.Cu")
		(net "85_10INCH_IN3_DN")
	)
	(segment
		(start 447.72707 4.425696)
		(end 448.973956 4.205478)
		(width 0.1651)
		(layer "In9.Cu")
		(net "85_10INCH_IN3_DN")
	)
	(segment
		(start 419.26129 4.996942)
		(end 419.663118 4.423664)
		(width 0.1651)
		(layer "In9.Cu")
		(net "85_10INCH_IN3_DN")
	)
	(segment
		(start 452.376794 12.810998)
		(end 452.644764 12.428728)
		(width 0.1651)
		(layer "In9.Cu")
		(net "85_10INCH_IN3_DN")
	)
	(segment
		(start 448.364864 12.795758)
		(end 448.633088 12.413234)
		(width 0.1651)
		(layer "In9.Cu")
		(net "85_10INCH_IN3_DN")
	)
	(segment
		(start 411.258258 12.928346)
		(end 412.27375 12.748768)
		(width 0.1651)
		(layer "In9.Cu")
		(net "85_10INCH_IN3_DN")
	)
	(segment
		(start 414.90392 12.764008)
		(end 415.285936 13.031978)
		(width 0.1651)
		(layer "In9.Cu")
		(net "85_10INCH_IN3_DN")
	)
	(segment
		(start 420.581836 12.486132)
		(end 419.26129 4.996942)
		(width 0.1651)
		(layer "In9.Cu")
		(net "85_10INCH_IN3_DN")
	)
	(segment
		(start 426.921676 12.710922)
		(end 427.303946 12.978892)
		(width 0.1651)
		(layer "In9.Cu")
		(net "85_10INCH_IN3_DN")
	)
	(segment
		(start 422.91635 12.732004)
		(end 423.29862 12.999974)
		(width 0.1651)
		(layer "In9.Cu")
		(net "85_10INCH_IN3_DN")
	)
	(segment
		(start 423.26941 4.992116)
		(end 423.671238 4.418838)
		(width 0.1651)
		(layer "In9.Cu")
		(net "85_10INCH_IN3_DN")
	)
	(segment
		(start 406.158954 8.645906)
		(end 406.86355 12.639548)
		(width 0.1651)
		(layer "In9.Cu")
		(net "85_10INCH_IN3_DN")
	)
	(segment
		(start 454.125584 7.83082)
		(end 454.416414 8.034782)
		(width 0.1651)
		(layer "In9.Cu")
		(net "85_10INCH_IN3_DN")
	)
	(segment
		(start 451.361048 12.990576)
		(end 452.376794 12.810998)
		(width 0.1651)
		(layer "In9.Cu")
		(net "85_10INCH_IN3_DN")
	)
	(segment
		(start 420.910004 4.203446)
		(end 421.483536 4.605274)
		(width 0.1651)
		(layer "In9.Cu")
		(net "85_10INCH_IN3_DN")
	)
	(segment
		(start 428.587662 12.417044)
		(end 427.279816 4.99999)
		(width 0.1651)
		(layer "In9.Cu")
		(net "85_10INCH_IN3_DN")
	)
	(segment
		(start 452.644764 12.428728)
		(end 451.338442 5.020056)
		(width 0.1651)
		(layer "In9.Cu")
		(net "85_10INCH_IN3_DN")
	)
	(segment
		(start 448.973956 4.205478)
		(end 449.547996 4.60756)
		(width 0.1651)
		(layer "In9.Cu")
		(net "85_10INCH_IN3_DN")
	)
	(segment
		(start 451.338442 5.020056)
		(end 451.74027 4.446778)
		(width 0.1651)
		(layer "In9.Cu")
		(net "85_10INCH_IN3_DN")
	)
	(segment
		(start 443.34303 12.991846)
		(end 444.358776 12.812268)
		(width 0.1651)
		(layer "In9.Cu")
		(net "85_10INCH_IN3_DN")
	)
	(segment
		(start 443.315344 4.99237)
		(end 443.717172 4.419092)
		(width 0.1651)
		(layer "In9.Cu")
		(net "85_10INCH_IN3_DN")
	)
	(segment
		(start 411.644592 4.423918)
		(end 412.891478 4.2037)
		(width 0.1651)
		(layer "In9.Cu")
		(net "85_10INCH_IN3_DN")
	)
	(segment
		(start 420.313866 12.867894)
		(end 420.581836 12.486132)
		(width 0.1651)
		(layer "In9.Cu")
		(net "85_10INCH_IN3_DN")
	)
	(segment
		(start 416.569652 12.47013)
		(end 415.25317 5.003546)
		(width 0.1651)
		(layer "In9.Cu")
		(net "85_10INCH_IN3_DN")
	)
	(segment
		(start 416.901884 4.21005)
		(end 417.475416 4.611878)
		(width 0.1651)
		(layer "In9.Cu")
		(net "85_10INCH_IN3_DN")
	)
	(segment
		(start 419.29812 13.047472)
		(end 420.313866 12.867894)
		(width 0.1651)
		(layer "In9.Cu")
		(net "85_10INCH_IN3_DN")
	)
	(segment
		(start 433.512722 4.614926)
		(end 434.951886 12.777724)
		(width 0.1651)
		(layer "In9.Cu")
		(net "85_10INCH_IN3_DN")
	)
	(segment
		(start 417.475416 4.611878)
		(end 418.915342 12.779502)
		(width 0.1651)
		(layer "In9.Cu")
		(net "85_10INCH_IN3_DN")
	)
	(segment
		(start 427.681644 4.426712)
		(end 428.928784 4.206494)
		(width 0.1651)
		(layer "In9.Cu")
		(net "85_10INCH_IN3_DN")
	)
	(segment
		(start 438.95645 12.751816)
		(end 439.33872 13.019786)
		(width 0.1651)
		(layer "In9.Cu")
		(net "85_10INCH_IN3_DN")
	)
	(segment
		(start 446.966848 12.707366)
		(end 447.349118 12.975336)
		(width 0.1651)
		(layer "In9.Cu")
		(net "85_10INCH_IN3_DN")
	)
	(segment
		(start 440.622436 12.457938)
		(end 439.305446 4.987544)
		(width 0.1651)
		(layer "In9.Cu")
		(net "85_10INCH_IN3_DN")
	)
	(segment
		(start 440.354466 12.840208)
		(end 440.622436 12.457938)
		(width 0.1651)
		(layer "In9.Cu")
		(net "85_10INCH_IN3_DN")
	)
	(segment
		(start 454.416414 8.034782)
		(end 457.356464 8.034782)
		(width 0.1651)
		(layer "In9.Cu")
		(net "85_10INCH_IN3_DN")
	)
	(segment
		(start 401.875498 7.718044)
		(end 402.166328 8.008874)
		(width 0.1651)
		(layer "In9.Cu")
		(net "85_10INCH_IN3_DN")
	)
	(segment
		(start 407.245566 12.907518)
		(end 408.261312 12.72794)
		(width 0.1651)
		(layer "In9.Cu")
		(net "85_10INCH_IN3_DN")
	)
	(segment
		(start 424.582336 12.438126)
		(end 423.26941 4.992116)
		(width 0.1651)
		(layer "In9.Cu")
		(net "85_10INCH_IN3_DN")
	)
	(segment
		(start 407.634948 4.420362)
		(end 408.881834 4.200144)
		(width 0.1651)
		(layer "In9.Cu")
		(net "85_10INCH_IN3_DN")
	)
	(segment
		(start 411.242764 4.997196)
		(end 411.644592 4.423918)
		(width 0.1651)
		(layer "In9.Cu")
		(net "85_10INCH_IN3_DN")
	)
	(segment
		(start 430.934876 12.733274)
		(end 431.317146 13.001244)
		(width 0.1651)
		(layer "In9.Cu")
		(net "85_10INCH_IN3_DN")
	)
	(segment
		(start 424.918124 4.19862)
		(end 425.491656 4.600448)
		(width 0.1651)
		(layer "In9.Cu")
		(net "85_10INCH_IN3_DN")
	)
	(segment
		(start 439.33872 13.019786)
		(end 440.354466 12.840208)
		(width 0.1651)
		(layer "In9.Cu")
		(net "85_10INCH_IN3_DN")
	)
	(segment
		(start 415.285936 13.031978)
		(end 416.301682 12.8524)
		(width 0.1651)
		(layer "In9.Cu")
		(net "85_10INCH_IN3_DN")
	)
	(segment
		(start 447.325242 4.999228)
		(end 447.72707 4.425696)
		(width 0.1651)
		(layer "In9.Cu")
		(net "85_10INCH_IN3_DN")
	)
	(segment
		(start 423.671238 4.418838)
		(end 424.918124 4.19862)
		(width 0.1651)
		(layer "In9.Cu")
		(net "85_10INCH_IN3_DN")
	)
	(segment
		(start 444.358776 12.812268)
		(end 444.626746 12.429998)
		(width 0.1651)
		(layer "In9.Cu")
		(net "85_10INCH_IN3_DN")
	)
	(segment
		(start 381.920496 -63.56223)
		(end 382.010412 -63.652146)
		(width 0.13208)
		(layer "F.Cu")
		(net "P12V_SSD13_PG_G2")
	)
	(segment
		(start 382.060196 -64.496442)
		(end 382.060196 -63.70193)
		(width 0.13208)
		(layer "F.Cu")
		(net "P12V_SSD13_PG_G2")
	)
	(segment
		(start 380.789434 -65.124076)
		(end 381.432562 -65.124076)
		(width 0.13208)
		(layer "F.Cu")
		(net "P12V_SSD13_PG_G2")
	)
	(segment
		(start 381.432562 -65.124076)
		(end 382.060196 -64.496442)
		(width 0.13208)
		(layer "F.Cu")
		(net "P12V_SSD13_PG_G2")
	)
	(segment
		(start 382.060196 -63.70193)
		(end 382.010412 -63.652146)
		(width 0.13208)
		(layer "F.Cu")
		(net "P12V_SSD13_PG_G2")
	)
	(segment
		(start 380.789434 -64.312292)
		(end 380.789434 -65.124076)
		(width 0.13208)
		(layer "F.Cu")
		(net "P12V_SSD13_PG_G2")
	)
	(segment
		(start 380.789434 -63.56223)
		(end 381.920496 -63.56223)
		(width 0.13208)
		(layer "F.Cu")
		(net "P12V_SSD13_PG_G2")
	)
	(via
		(at 380.789434 -65.124076)
		(size 0.508)
		(drill 0.254)
		(layers "F.Cu" "B.Cu")
		(net "P12V_SSD13_PG_G2")
	)
	(segment
		(start 363.833156 -113.933478)
		(end 363.833156 -113.15827)
		(width 0.13208)
		(layer "F.Cu")
		(net "P3V3_NIC6_CO_ILIMIT")
	)
	(segment
		(start 363.833156 -113.15827)
		(end 363.21492 -112.540034)
		(width 0.13208)
		(layer "F.Cu")
		(net "P3V3_NIC6_CO_ILIMIT")
	)
	(segment
		(start 362.462826 -112.515142)
		(end 362.462826 -111.777526)
		(width 0.13208)
		(layer "F.Cu")
		(net "P3V3_NIC6_CO_ILIMIT")
	)
	(segment
		(start 363.21492 -112.540034)
		(end 362.487718 -112.540034)
		(width 0.13208)
		(layer "F.Cu")
		(net "P3V3_NIC6_CO_ILIMIT")
	)
	(segment
		(start 362.487718 -112.540034)
		(end 362.462826 -112.515142)
		(width 0.13208)
		(layer "F.Cu")
		(net "P3V3_NIC6_CO_ILIMIT")
	)
	(via
		(at 362.487718 -112.540034)
		(size 0.508)
		(drill 0.254)
		(layers "F.Cu" "B.Cu")
		(net "P3V3_NIC6_CO_ILIMIT")
	)
	(segment
		(start 114.182144 -38.702742)
		(end 114.182144 -38.041072)
		(width 0.13208)
		(layer "F.Cu")
		(net "P3V3_SSD4_PG_G2")
	)
	(segment
		(start 114.18062 -38.701218)
		(end 114.182144 -38.702742)
		(width 0.13208)
		(layer "F.Cu")
		(net "P3V3_SSD4_PG_G2")
	)
	(segment
		(start 114.092228 -37.951156)
		(end 114.182144 -38.041072)
		(width 0.13208)
		(layer "F.Cu")
		(net "P3V3_SSD4_PG_G2")
	)
	(segment
		(start 112.961166 -37.951156)
		(end 114.092228 -37.951156)
		(width 0.13208)
		(layer "F.Cu")
		(net "P3V3_SSD4_PG_G2")
	)
	(segment
		(start 112.961166 -38.701218)
		(end 114.18062 -38.701218)
		(width 0.13208)
		(layer "F.Cu")
		(net "P3V3_SSD4_PG_G2")
	)
	(via
		(at 114.182144 -38.702742)
		(size 0.508)
		(drill 0.254)
		(layers "F.Cu" "B.Cu")
		(net "P3V3_SSD4_PG_G2")
	)
	(segment
		(start 256.281936 -38.702742)
		(end 256.281936 -38.041072)
		(width 0.13208)
		(layer "F.Cu")
		(net "P3V3_SSD9_PG_G2")
	)
	(segment
		(start 256.280412 -38.701218)
		(end 256.281936 -38.702742)
		(width 0.13208)
		(layer "F.Cu")
		(net "P3V3_SSD9_PG_G2")
	)
	(segment
		(start 255.060958 -38.701218)
		(end 256.280412 -38.701218)
		(width 0.13208)
		(layer "F.Cu")
		(net "P3V3_SSD9_PG_G2")
	)
	(segment
		(start 255.060958 -37.951156)
		(end 256.19202 -37.951156)
		(width 0.13208)
		(layer "F.Cu")
		(net "P3V3_SSD9_PG_G2")
	)
	(segment
		(start 256.19202 -37.951156)
		(end 256.281936 -38.041072)
		(width 0.13208)
		(layer "F.Cu")
		(net "P3V3_SSD9_PG_G2")
	)
	(via
		(at 256.281936 -38.702742)
		(size 0.508)
		(drill 0.254)
		(layers "F.Cu" "B.Cu")
		(net "P3V3_SSD9_PG_G2")
	)
	(segment
		(start 213.861142 4.27228)
		(end 213.861142 4.272534)
		(width 0.13462)
		(layer "F.Cu")
		(net "85_10INCH_TOP_DP")
	)
	(segment
		(start 230.533194 4.826)
		(end 231.775254 11.870182)
		(width 0.13462)
		(layer "F.Cu")
		(net "85_10INCH_TOP_DP")
	)
	(segment
		(start 228.15296 11.872214)
		(end 227.934774 12.184126)
		(width 0.13462)
		(layer "F.Cu")
		(net "85_10INCH_TOP_DP")
	)
	(segment
		(start 210.02371 11.780774)
		(end 209.805524 12.092432)
		(width 0.13462)
		(layer "F.Cu")
		(net "85_10INCH_TOP_DP")
	)
	(segment
		(start 209.805524 12.092432)
		(end 208.849468 12.261088)
		(width 0.13462)
		(layer "F.Cu")
		(net "85_10INCH_TOP_DP")
	)
	(segment
		(start 219.400374 12.009374)
		(end 218.093036 4.598924)
		(width 0.13462)
		(layer "F.Cu")
		(net "85_10INCH_TOP_DP")
	)
	(segment
		(start 227.934774 12.184126)
		(end 226.978972 12.352782)
		(width 0.13462)
		(layer "F.Cu")
		(net "85_10INCH_TOP_DP")
	)
	(segment
		(start 224.52838 11.862562)
		(end 224.310194 12.174982)
		(width 0.13462)
		(layer "F.Cu")
		(net "85_10INCH_TOP_DP")
	)
	(segment
		(start 194.324478 4.925822)
		(end 195.532756 11.776202)
		(width 0.13462)
		(layer "F.Cu")
		(net "85_10INCH_TOP_DP")
	)
	(segment
		(start 231.557068 12.181586)
		(end 230.601012 12.350242)
		(width 0.13462)
		(layer "F.Cu")
		(net "85_10INCH_TOP_DP")
	)
	(segment
		(start 227.257356 4.314698)
		(end 226.90836 4.812792)
		(width 0.13462)
		(layer "F.Cu")
		(net "85_10INCH_TOP_DP")
	)
	(segment
		(start 232.560622 4.469384)
		(end 232.062528 4.120642)
		(width 0.13462)
		(layer "F.Cu")
		(net "85_10INCH_TOP_DP")
	)
	(segment
		(start 212.15477 12.007596)
		(end 210.843622 4.575302)
		(width 0.13462)
		(layer "F.Cu")
		(net "85_10INCH_TOP_DP")
	)
	(segment
		(start 198.29399 4.41706)
		(end 197.945502 4.914392)
		(width 0.13462)
		(layer "F.Cu")
		(net "85_10INCH_TOP_DP")
	)
	(segment
		(start 192.233804 4.231386)
		(end 191.05245 4.439666)
		(width 0.13462)
		(layer "F.Cu")
		(net "85_10INCH_TOP_DP")
	)
	(segment
		(start 199.15505 11.775948)
		(end 198.936864 12.087606)
		(width 0.13462)
		(layer "F.Cu")
		(net "85_10INCH_TOP_DP")
	)
	(segment
		(start 210.843622 4.575302)
		(end 210.345782 4.22656)
		(width 0.13462)
		(layer "F.Cu")
		(net "85_10INCH_TOP_DP")
	)
	(segment
		(start 191.68872 12.07135)
		(end 190.732664 12.240006)
		(width 0.13462)
		(layer "F.Cu")
		(net "85_10INCH_TOP_DP")
	)
	(segment
		(start 212.465666 12.225274)
		(end 212.15477 12.007596)
		(width 0.13462)
		(layer "F.Cu")
		(net "85_10INCH_TOP_DP")
	)
	(segment
		(start 234.504738 4.332224)
		(end 234.15625 4.829556)
		(width 0.13462)
		(layer "F.Cu")
		(net "85_10INCH_TOP_DP")
	)
	(segment
		(start 228.935534 4.454652)
		(end 228.438202 4.10591)
		(width 0.13462)
		(layer "F.Cu")
		(net "85_10INCH_TOP_DP")
	)
	(segment
		(start 223.28759 4.823714)
		(end 224.52838 11.862562)
		(width 0.13462)
		(layer "F.Cu")
		(net "85_10INCH_TOP_DP")
	)
	(segment
		(start 203.598526 4.576318)
		(end 203.100686 4.227576)
		(width 0.13462)
		(layer "F.Cu")
		(net "85_10INCH_TOP_DP")
	)
	(segment
		(start 225.314764 4.465828)
		(end 224.817686 4.117086)
		(width 0.13462)
		(layer "F.Cu")
		(net "85_10INCH_TOP_DP")
	)
	(segment
		(start 220.885512 11.746738)
		(end 220.667326 12.058396)
		(width 0.13462)
		(layer "F.Cu")
		(net "85_10INCH_TOP_DP")
	)
	(segment
		(start 198.936864 12.087606)
		(end 197.980808 12.256262)
		(width 0.13462)
		(layer "F.Cu")
		(net "85_10INCH_TOP_DP")
	)
	(segment
		(start 194.358514 12.256008)
		(end 194.046602 12.038076)
		(width 0.13462)
		(layer "F.Cu")
		(net "85_10INCH_TOP_DP")
	)
	(segment
		(start 236.930438 7.939532)
		(end 236.771688 7.806182)
		(width 0.13462)
		(layer "F.Cu")
		(net "85_10INCH_TOP_DP")
	)
	(segment
		(start 213.861142 4.272534)
		(end 212.791802 4.461002)
		(width 0.13462)
		(layer "F.Cu")
		(net "85_10INCH_TOP_DP")
	)
	(segment
		(start 205.191868 4.922266)
		(end 206.39532 11.74877)
		(width 0.13462)
		(layer "F.Cu")
		(net "85_10INCH_TOP_DP")
	)
	(segment
		(start 197.945502 4.914392)
		(end 199.15505 11.775948)
		(width 0.13462)
		(layer "F.Cu")
		(net "85_10INCH_TOP_DP")
	)
	(segment
		(start 241.285268 7.826756)
		(end 241.093498 7.826756)
		(width 0.13462)
		(layer "F.Cu")
		(net "85_10INCH_TOP_DP")
	)
	(segment
		(start 217.483436 4.269994)
		(end 216.414096 4.458462)
		(width 0.13462)
		(layer "F.Cu")
		(net "85_10INCH_TOP_DP")
	)
	(segment
		(start 206.609442 4.235704)
		(end 206.609442 4.235958)
		(width 0.13462)
		(layer "F.Cu")
		(net "85_10INCH_TOP_DP")
	)
	(segment
		(start 217.046556 12.068302)
		(end 216.0905 12.236958)
		(width 0.13462)
		(layer "F.Cu")
		(net "85_10INCH_TOP_DP")
	)
	(segment
		(start 241.093498 7.826756)
		(end 240.980722 7.939532)
		(width 0.13462)
		(layer "F.Cu")
		(net "85_10INCH_TOP_DP")
	)
	(segment
		(start 208.538318 12.043156)
		(end 207.219042 4.564888)
		(width 0.13462)
		(layer "F.Cu")
		(net "85_10INCH_TOP_DP")
	)
	(segment
		(start 199.47509 4.208526)
		(end 198.29399 4.41706)
		(width 0.13462)
		(layer "F.Cu")
		(net "85_10INCH_TOP_DP")
	)
	(segment
		(start 220.667326 12.058396)
		(end 219.71127 12.227052)
		(width 0.13462)
		(layer "F.Cu")
		(net "85_10INCH_TOP_DP")
	)
	(segment
		(start 223.636586 4.32562)
		(end 223.28759 4.823714)
		(width 0.13462)
		(layer "F.Cu")
		(net "85_10INCH_TOP_DP")
	)
	(segment
		(start 190.422276 12.022582)
		(end 189.761368 8.278114)
		(width 0.13462)
		(layer "F.Cu")
		(net "85_10INCH_TOP_DP")
	)
	(segment
		(start 202.988926 4.247388)
		(end 201.919586 4.435856)
		(width 0.13462)
		(layer "F.Cu")
		(net "85_10INCH_TOP_DP")
	)
	(segment
		(start 199.972676 4.557268)
		(end 199.47509 4.208526)
		(width 0.13462)
		(layer "F.Cu")
		(net "85_10INCH_TOP_DP")
	)
	(segment
		(start 217.264742 11.756644)
		(end 217.046556 12.068302)
		(width 0.13462)
		(layer "F.Cu")
		(net "85_10INCH_TOP_DP")
	)
	(segment
		(start 235.39958 11.881612)
		(end 235.181394 12.19327)
		(width 0.13462)
		(layer "F.Cu")
		(net "85_10INCH_TOP_DP")
	)
	(segment
		(start 212.443568 4.958842)
		(end 213.639908 11.74496)
		(width 0.13462)
		(layer "F.Cu")
		(net "85_10INCH_TOP_DP")
	)
	(segment
		(start 217.595196 4.250182)
		(end 217.483436 4.26974)
		(width 0.13462)
		(layer "F.Cu")
		(net "85_10INCH_TOP_DP")
	)
	(segment
		(start 196.351906 4.568444)
		(end 195.854066 4.219702)
		(width 0.13462)
		(layer "F.Cu")
		(net "85_10INCH_TOP_DP")
	)
	(segment
		(start 201.919586 4.435856)
		(end 201.571352 4.933696)
		(width 0.13462)
		(layer "F.Cu")
		(net "85_10INCH_TOP_DP")
	)
	(segment
		(start 206.39532 11.74877)
		(end 206.177134 12.060682)
		(width 0.13462)
		(layer "F.Cu")
		(net "85_10INCH_TOP_DP")
	)
	(segment
		(start 201.290428 12.027154)
		(end 199.972676 4.557268)
		(width 0.13462)
		(layer "F.Cu")
		(net "85_10INCH_TOP_DP")
	)
	(segment
		(start 202.55738 12.076176)
		(end 201.601324 12.244832)
		(width 0.13462)
		(layer "F.Cu")
		(net "85_10INCH_TOP_DP")
	)
	(segment
		(start 210.234022 4.246372)
		(end 209.164682 4.43484)
		(width 0.13462)
		(layer "F.Cu")
		(net "85_10INCH_TOP_DP")
	)
	(segment
		(start 230.881682 4.32943)
		(end 230.533194 4.826)
		(width 0.13462)
		(layer "F.Cu")
		(net "85_10INCH_TOP_DP")
	)
	(segment
		(start 219.71127 12.227052)
		(end 219.400374 12.009374)
		(width 0.13462)
		(layer "F.Cu")
		(net "85_10INCH_TOP_DP")
	)
	(segment
		(start 230.601012 12.350242)
		(end 230.288592 12.132056)
		(width 0.13462)
		(layer "F.Cu")
		(net "85_10INCH_TOP_DP")
	)
	(segment
		(start 235.685838 4.12369)
		(end 234.504738 4.332224)
		(width 0.13462)
		(layer "F.Cu")
		(net "85_10INCH_TOP_DP")
	)
	(segment
		(start 226.90836 4.812792)
		(end 228.15296 11.872214)
		(width 0.13462)
		(layer "F.Cu")
		(net "85_10INCH_TOP_DP")
	)
	(segment
		(start 215.77935 12.019026)
		(end 214.470742 4.601464)
		(width 0.13462)
		(layer "F.Cu")
		(net "85_10INCH_TOP_DP")
	)
	(segment
		(start 226.66706 12.134342)
		(end 225.314764 4.465828)
		(width 0.13462)
		(layer "F.Cu")
		(net "85_10INCH_TOP_DP")
	)
	(segment
		(start 216.414096 4.458462)
		(end 216.065862 4.956302)
		(width 0.13462)
		(layer "F.Cu")
		(net "85_10INCH_TOP_DP")
	)
	(segment
		(start 210.234022 4.246118)
		(end 210.234022 4.246372)
		(width 0.13462)
		(layer "F.Cu")
		(net "85_10INCH_TOP_DP")
	)
	(segment
		(start 206.609442 4.235958)
		(end 205.540102 4.424426)
		(width 0.13462)
		(layer "F.Cu")
		(net "85_10INCH_TOP_DP")
	)
	(segment
		(start 221.21622 4.2418)
		(end 221.10446 4.261358)
		(width 0.13462)
		(layer "F.Cu")
		(net "85_10INCH_TOP_DP")
	)
	(segment
		(start 190.704216 4.937506)
		(end 191.906906 11.759692)
		(width 0.13462)
		(layer "F.Cu")
		(net "85_10INCH_TOP_DP")
	)
	(segment
		(start 221.10446 4.261612)
		(end 220.03512 4.45008)
		(width 0.13462)
		(layer "F.Cu")
		(net "85_10INCH_TOP_DP")
	)
	(segment
		(start 189.761368 8.278114)
		(end 189.429898 7.946644)
		(width 0.13462)
		(layer "F.Cu")
		(net "85_10INCH_TOP_DP")
	)
	(segment
		(start 195.314824 12.087606)
		(end 194.358514 12.256008)
		(width 0.13462)
		(layer "F.Cu")
		(net "85_10INCH_TOP_DP")
	)
	(segment
		(start 197.980808 12.256262)
		(end 197.669404 12.03833)
		(width 0.13462)
		(layer "F.Cu")
		(net "85_10INCH_TOP_DP")
	)
	(segment
		(start 213.639908 11.74496)
		(end 213.421722 12.056618)
		(width 0.13462)
		(layer "F.Cu")
		(net "85_10INCH_TOP_DP")
	)
	(segment
		(start 234.15625 4.829556)
		(end 235.39958 11.881612)
		(width 0.13462)
		(layer "F.Cu")
		(net "85_10INCH_TOP_DP")
	)
	(segment
		(start 228.438202 4.10591)
		(end 227.257356 4.314698)
		(width 0.13462)
		(layer "F.Cu")
		(net "85_10INCH_TOP_DP")
	)
	(segment
		(start 184.343294 7.833868)
		(end 184.151524 7.833868)
		(width 0.13462)
		(layer "F.Cu")
		(net "85_10INCH_TOP_DP")
	)
	(segment
		(start 201.571352 4.933696)
		(end 202.775566 11.764518)
		(width 0.13462)
		(layer "F.Cu")
		(net "85_10INCH_TOP_DP")
	)
	(segment
		(start 210.345782 4.22656)
		(end 210.234022 4.246118)
		(width 0.13462)
		(layer "F.Cu")
		(net "85_10INCH_TOP_DP")
	)
	(segment
		(start 214.470742 4.601464)
		(end 213.972902 4.252722)
		(width 0.13462)
		(layer "F.Cu")
		(net "85_10INCH_TOP_DP")
	)
	(segment
		(start 202.775566 11.764518)
		(end 202.55738 12.076176)
		(width 0.13462)
		(layer "F.Cu")
		(net "85_10INCH_TOP_DP")
	)
	(segment
		(start 208.816448 4.93268)
		(end 210.02371 11.780774)
		(width 0.13462)
		(layer "F.Cu")
		(net "85_10INCH_TOP_DP")
	)
	(segment
		(start 221.71406 4.590542)
		(end 221.21622 4.2418)
		(width 0.13462)
		(layer "F.Cu")
		(net "85_10INCH_TOP_DP")
	)
	(segment
		(start 234.225592 12.361926)
		(end 233.91495 12.144248)
		(width 0.13462)
		(layer "F.Cu")
		(net "85_10INCH_TOP_DP")
	)
	(segment
		(start 224.310194 12.174982)
		(end 223.354392 12.343384)
		(width 0.13462)
		(layer "F.Cu")
		(net "85_10INCH_TOP_DP")
	)
	(segment
		(start 216.065862 4.956302)
		(end 217.264742 11.756644)
		(width 0.13462)
		(layer "F.Cu")
		(net "85_10INCH_TOP_DP")
	)
	(segment
		(start 224.817686 4.117086)
		(end 223.636586 4.32562)
		(width 0.13462)
		(layer "F.Cu")
		(net "85_10INCH_TOP_DP")
	)
	(segment
		(start 223.043496 12.125706)
		(end 221.71406 4.590542)
		(width 0.13462)
		(layer "F.Cu")
		(net "85_10INCH_TOP_DP")
	)
	(segment
		(start 191.906906 11.759692)
		(end 191.68872 12.07135)
		(width 0.13462)
		(layer "F.Cu")
		(net "85_10INCH_TOP_DP")
	)
	(segment
		(start 206.721202 4.216146)
		(end 206.609442 4.235704)
		(width 0.13462)
		(layer "F.Cu")
		(net "85_10INCH_TOP_DP")
	)
	(segment
		(start 194.046602 12.038076)
		(end 192.73139 4.580128)
		(width 0.13462)
		(layer "F.Cu")
		(net "85_10INCH_TOP_DP")
	)
	(segment
		(start 190.732664 12.240006)
		(end 190.422276 12.022582)
		(width 0.13462)
		(layer "F.Cu")
		(net "85_10INCH_TOP_DP")
	)
	(segment
		(start 233.91495 12.144248)
		(end 232.560622 4.469384)
		(width 0.13462)
		(layer "F.Cu")
		(net "85_10INCH_TOP_DP")
	)
	(segment
		(start 203.100686 4.227576)
		(end 202.988926 4.247134)
		(width 0.13462)
		(layer "F.Cu")
		(net "85_10INCH_TOP_DP")
	)
	(segment
		(start 212.791802 4.461002)
		(end 212.443568 4.958842)
		(width 0.13462)
		(layer "F.Cu")
		(net "85_10INCH_TOP_DP")
	)
	(segment
		(start 223.354392 12.343384)
		(end 223.043496 12.125706)
		(width 0.13462)
		(layer "F.Cu")
		(net "85_10INCH_TOP_DP")
	)
	(segment
		(start 195.854066 4.219702)
		(end 194.67322 4.428236)
		(width 0.13462)
		(layer "F.Cu")
		(net "85_10INCH_TOP_DP")
	)
	(segment
		(start 192.73139 4.580128)
		(end 192.233804 4.231386)
		(width 0.13462)
		(layer "F.Cu")
		(net "85_10INCH_TOP_DP")
	)
	(segment
		(start 219.686886 4.94792)
		(end 220.885512 11.746738)
		(width 0.13462)
		(layer "F.Cu")
		(net "85_10INCH_TOP_DP")
	)
	(segment
		(start 231.775254 11.870182)
		(end 231.557068 12.181586)
		(width 0.13462)
		(layer "F.Cu")
		(net "85_10INCH_TOP_DP")
	)
	(segment
		(start 202.988926 4.247134)
		(end 202.988926 4.247388)
		(width 0.13462)
		(layer "F.Cu")
		(net "85_10INCH_TOP_DP")
	)
	(segment
		(start 230.288592 12.132056)
		(end 228.935534 4.454652)
		(width 0.13462)
		(layer "F.Cu")
		(net "85_10INCH_TOP_DP")
	)
	(segment
		(start 184.45607 7.946644)
		(end 184.343294 7.833868)
		(width 0.13462)
		(layer "F.Cu")
		(net "85_10INCH_TOP_DP")
	)
	(segment
		(start 213.421722 12.056618)
		(end 212.465666 12.225274)
		(width 0.13462)
		(layer "F.Cu")
		(net "85_10INCH_TOP_DP")
	)
	(segment
		(start 197.669404 12.03833)
		(end 196.351906 4.568444)
		(width 0.13462)
		(layer "F.Cu")
		(net "85_10INCH_TOP_DP")
	)
	(segment
		(start 232.062528 4.120642)
		(end 230.881682 4.32943)
		(width 0.13462)
		(layer "F.Cu")
		(net "85_10INCH_TOP_DP")
	)
	(segment
		(start 221.10446 4.261358)
		(end 221.10446 4.261612)
		(width 0.13462)
		(layer "F.Cu")
		(net "85_10INCH_TOP_DP")
	)
	(segment
		(start 213.972902 4.252722)
		(end 213.861142 4.27228)
		(width 0.13462)
		(layer "F.Cu")
		(net "85_10INCH_TOP_DP")
	)
	(segment
		(start 206.177134 12.060682)
		(end 205.221078 12.229338)
		(width 0.13462)
		(layer "F.Cu")
		(net "85_10INCH_TOP_DP")
	)
	(segment
		(start 220.03512 4.45008)
		(end 219.686886 4.94792)
		(width 0.13462)
		(layer "F.Cu")
		(net "85_10INCH_TOP_DP")
	)
	(segment
		(start 218.093036 4.598924)
		(end 217.595196 4.250182)
		(width 0.13462)
		(layer "F.Cu")
		(net "85_10INCH_TOP_DP")
	)
	(segment
		(start 216.0905 12.236958)
		(end 215.77935 12.019026)
		(width 0.13462)
		(layer "F.Cu")
		(net "85_10INCH_TOP_DP")
	)
	(segment
		(start 191.05245 4.439666)
		(end 190.704216 4.937506)
		(width 0.13462)
		(layer "F.Cu")
		(net "85_10INCH_TOP_DP")
	)
	(segment
		(start 226.978972 12.352782)
		(end 226.66706 12.134342)
		(width 0.13462)
		(layer "F.Cu")
		(net "85_10INCH_TOP_DP")
	)
	(segment
		(start 195.532756 11.776202)
		(end 195.314824 12.087606)
		(width 0.13462)
		(layer "F.Cu")
		(net "85_10INCH_TOP_DP")
	)
	(segment
		(start 204.910182 12.01166)
		(end 203.598526 4.576318)
		(width 0.13462)
		(layer "F.Cu")
		(net "85_10INCH_TOP_DP")
	)
	(segment
		(start 207.219042 4.564888)
		(end 206.721202 4.216146)
		(width 0.13462)
		(layer "F.Cu")
		(net "85_10INCH_TOP_DP")
	)
	(segment
		(start 236.771688 7.806182)
		(end 236.183678 4.472432)
		(width 0.13462)
		(layer "F.Cu")
		(net "85_10INCH_TOP_DP")
	)
	(segment
		(start 205.221078 12.229338)
		(end 204.910182 12.01166)
		(width 0.13462)
		(layer "F.Cu")
		(net "85_10INCH_TOP_DP")
	)
	(segment
		(start 235.181394 12.19327)
		(end 234.225592 12.361926)
		(width 0.13462)
		(layer "F.Cu")
		(net "85_10INCH_TOP_DP")
	)
	(segment
		(start 189.429898 7.946644)
		(end 184.45607 7.946644)
		(width 0.13462)
		(layer "F.Cu")
		(net "85_10INCH_TOP_DP")
	)
	(segment
		(start 205.540102 4.424426)
		(end 205.191868 4.922266)
		(width 0.13462)
		(layer "F.Cu")
		(net "85_10INCH_TOP_DP")
	)
	(segment
		(start 208.849468 12.261088)
		(end 208.538318 12.043156)
		(width 0.13462)
		(layer "F.Cu")
		(net "85_10INCH_TOP_DP")
	)
	(segment
		(start 194.67322 4.428236)
		(end 194.324478 4.925822)
		(width 0.13462)
		(layer "F.Cu")
		(net "85_10INCH_TOP_DP")
	)
	(segment
		(start 217.483436 4.26974)
		(end 217.483436 4.269994)
		(width 0.13462)
		(layer "F.Cu")
		(net "85_10INCH_TOP_DP")
	)
	(segment
		(start 240.980722 7.939532)
		(end 236.930438 7.939532)
		(width 0.13462)
		(layer "F.Cu")
		(net "85_10INCH_TOP_DP")
	)
	(segment
		(start 209.164682 4.43484)
		(end 208.816448 4.93268)
		(width 0.13462)
		(layer "F.Cu")
		(net "85_10INCH_TOP_DP")
	)
	(segment
		(start 236.183678 4.472432)
		(end 235.685838 4.12369)
		(width 0.13462)
		(layer "F.Cu")
		(net "85_10INCH_TOP_DP")
	)
	(segment
		(start 201.601324 12.244832)
		(end 201.290428 12.027154)
		(width 0.13462)
		(layer "F.Cu")
		(net "85_10INCH_TOP_DP")
	)
	(segment
		(start 406.789382 -64.312292)
		(end 407.587958 -64.312292)
		(width 0.13208)
		(layer "F.Cu")
		(net "P12V_SSD14_PG_G2")
	)
	(segment
		(start 407.920444 -63.56223)
		(end 408.01036 -63.652146)
		(width 0.13208)
		(layer "F.Cu")
		(net "P12V_SSD14_PG_G2")
	)
	(segment
		(start 408.060144 -64.222122)
		(end 408.060144 -63.70193)
		(width 0.13208)
		(layer "F.Cu")
		(net "P12V_SSD14_PG_G2")
	)
	(segment
		(start 407.969974 -64.312292)
		(end 408.060144 -64.222122)
		(width 0.13208)
		(layer "F.Cu")
		(net "P12V_SSD14_PG_G2")
	)
	(segment
		(start 408.060144 -63.70193)
		(end 408.01036 -63.652146)
		(width 0.13208)
		(layer "F.Cu")
		(net "P12V_SSD14_PG_G2")
	)
	(segment
		(start 407.587958 -64.312292)
		(end 407.969974 -64.312292)
		(width 0.13208)
		(layer "F.Cu")
		(net "P12V_SSD14_PG_G2")
	)
	(segment
		(start 406.789382 -63.56223)
		(end 407.920444 -63.56223)
		(width 0.13208)
		(layer "F.Cu")
		(net "P12V_SSD14_PG_G2")
	)
	(via
		(at 407.587958 -64.312292)
		(size 0.508)
		(drill 0.254)
		(layers "F.Cu" "B.Cu")
		(net "P12V_SSD14_PG_G2")
	)
	(segment
		(start 363.596936 -117.978936)
		(end 363.596936 -116.916454)
		(width 0.13208)
		(layer "F.Cu")
		(net "P3V3_NIC6_CO_EN")
	)
	(segment
		(start 363.596936 -116.916454)
		(end 363.833156 -116.680234)
		(width 0.13208)
		(layer "F.Cu")
		(net "P3V3_NIC6_CO_EN")
	)
	(segment
		(start 363.833156 -116.680234)
		(end 363.833156 -115.933474)
		(width 0.13208)
		(layer "F.Cu")
		(net "P3V3_NIC6_CO_EN")
	)
	(via
		(at 363.833156 -116.680234)
		(size 0.508)
		(drill 0.254)
		(layers "F.Cu" "B.Cu")
		(net "P3V3_NIC6_CO_EN")
	)
	(segment
		(start 190.96101 -38.701218)
		(end 192.180464 -38.701218)
		(width 0.13208)
		(layer "F.Cu")
		(net "P3V3_SSD7_PG_G2")
	)
	(segment
		(start 192.092072 -37.951156)
		(end 192.181988 -38.041072)
		(width 0.13208)
		(layer "F.Cu")
		(net "P3V3_SSD7_PG_G2")
	)
	(segment
		(start 192.180464 -38.701218)
		(end 192.181988 -38.702742)
		(width 0.13208)
		(layer "F.Cu")
		(net "P3V3_SSD7_PG_G2")
	)
	(segment
		(start 192.181988 -38.702742)
		(end 192.181988 -38.041072)
		(width 0.13208)
		(layer "F.Cu")
		(net "P3V3_SSD7_PG_G2")
	)
	(segment
		(start 190.96101 -37.951156)
		(end 192.092072 -37.951156)
		(width 0.13208)
		(layer "F.Cu")
		(net "P3V3_SSD7_PG_G2")
	)
	(via
		(at 192.181988 -38.702742)
		(size 0.508)
		(drill 0.254)
		(layers "F.Cu" "B.Cu")
		(net "P3V3_SSD7_PG_G2")
	)
	(segment
		(start 259.588762 -32.39135)
		(end 259.53212 -32.447992)
		(width 0.13208)
		(layer "F.Cu")
		(net "P3V3_SSD9_CO_DV_DT")
	)
	(segment
		(start 259.580634 -31.567882)
		(end 259.588762 -31.57601)
		(width 0.13208)
		(layer "F.Cu")
		(net "P3V3_SSD9_CO_DV_DT")
	)
	(segment
		(start 260.482588 -30.875732)
		(end 260.482588 -31.274004)
		(width 0.13208)
		(layer "F.Cu")
		(net "P3V3_SSD9_CO_DV_DT")
	)
	(segment
		(start 260.18871 -31.567882)
		(end 259.580634 -31.567882)
		(width 0.13208)
		(layer "F.Cu")
		(net "P3V3_SSD9_CO_DV_DT")
	)
	(segment
		(start 259.588762 -31.57601)
		(end 259.588762 -32.39135)
		(width 0.13208)
		(layer "F.Cu")
		(net "P3V3_SSD9_CO_DV_DT")
	)
	(segment
		(start 260.482588 -31.274004)
		(end 260.18871 -31.567882)
		(width 0.13208)
		(layer "F.Cu")
		(net "P3V3_SSD9_CO_DV_DT")
	)
	(via
		(at 259.580634 -31.567882)
		(size 0.508)
		(drill 0.254)
		(layers "F.Cu" "B.Cu")
		(net "P3V3_SSD9_CO_DV_DT")
	)
	(segment
		(start 386.065268 7.892796)
		(end 385.384294 7.710932)
		(width 0.13462)
		(layer "F.Cu")
		(net "85_10INCH_IN2_DN")
	)
	(segment
		(start 328.931524 7.866888)
		(end 329.612498 7.685024)
		(width 0.13462)
		(layer "F.Cu")
		(net "85_10INCH_IN2_DN")
	)
	(segment
		(start 344.638884 4.17703)
		(end 345.212416 4.578858)
		(width 0.1651)
		(layer "In7.Cu")
		(net "85_10INCH_IN2_DN")
	)
	(segment
		(start 338.979764 4.964176)
		(end 339.381592 4.390898)
		(width 0.1651)
		(layer "In7.Cu")
		(net "85_10INCH_IN2_DN")
	)
	(segment
		(start 364.086902 12.833096)
		(end 364.354872 12.450826)
		(width 0.1651)
		(layer "In7.Cu")
		(net "85_10INCH_IN2_DN")
	)
	(segment
		(start 372.701058 4.165854)
		(end 373.27459 4.567682)
		(width 0.1651)
		(layer "In7.Cu")
		(net "85_10INCH_IN2_DN")
	)
	(segment
		(start 348.050866 12.834874)
		(end 348.318836 12.453112)
		(width 0.1651)
		(layer "In7.Cu")
		(net "85_10INCH_IN2_DN")
	)
	(segment
		(start 346.652342 12.746482)
		(end 347.03512 13.014452)
		(width 0.1651)
		(layer "In7.Cu")
		(net "85_10INCH_IN2_DN")
	)
	(segment
		(start 367.444274 4.381246)
		(end 368.69116 4.161028)
		(width 0.1651)
		(layer "In7.Cu")
		(net "85_10INCH_IN2_DN")
	)
	(segment
		(start 345.212416 4.578858)
		(end 346.652342 12.746482)
		(width 0.1651)
		(layer "In7.Cu")
		(net "85_10INCH_IN2_DN")
	)
	(segment
		(start 372.363746 12.396978)
		(end 371.052344 4.95935)
		(width 0.1651)
		(layer "In7.Cu")
		(net "85_10INCH_IN2_DN")
	)
	(segment
		(start 366.69345 12.718796)
		(end 367.07572 12.986766)
		(width 0.1651)
		(layer "In7.Cu")
		(net "85_10INCH_IN2_DN")
	)
	(segment
		(start 367.07572 12.986766)
		(end 368.091466 12.807188)
		(width 0.1651)
		(layer "In7.Cu")
		(net "85_10INCH_IN2_DN")
	)
	(segment
		(start 380.113794 12.777978)
		(end 380.381764 12.395708)
		(width 0.1651)
		(layer "In7.Cu")
		(net "85_10INCH_IN2_DN")
	)
	(segment
		(start 340.628478 4.17068)
		(end 341.20201 4.572508)
		(width 0.1651)
		(layer "In7.Cu")
		(net "85_10INCH_IN2_DN")
	)
	(segment
		(start 334.97012 4.96062)
		(end 335.371948 4.387342)
		(width 0.1651)
		(layer "In7.Cu")
		(net "85_10INCH_IN2_DN")
	)
	(segment
		(start 363.035596 4.96824)
		(end 363.437424 4.394962)
		(width 0.1651)
		(layer "In7.Cu")
		(net "85_10INCH_IN2_DN")
	)
	(segment
		(start 351.03562 12.966954)
		(end 352.051366 12.787376)
		(width 0.1651)
		(layer "In7.Cu")
		(net "85_10INCH_IN2_DN")
	)
	(segment
		(start 351.408238 4.385818)
		(end 352.655124 4.1656)
		(width 0.1651)
		(layer "In7.Cu")
		(net "85_10INCH_IN2_DN")
	)
	(segment
		(start 342.64092 12.730988)
		(end 343.022936 12.998958)
		(width 0.1651)
		(layer "In7.Cu")
		(net "85_10INCH_IN2_DN")
	)
	(segment
		(start 381.862584 7.7978)
		(end 382.153414 8.001762)
		(width 0.1651)
		(layer "In7.Cu")
		(net "85_10INCH_IN2_DN")
	)
	(segment
		(start 352.655124 4.1656)
		(end 353.228656 4.567428)
		(width 0.1651)
		(layer "In7.Cu")
		(net "85_10INCH_IN2_DN")
	)
	(segment
		(start 348.318836 12.453112)
		(end 346.99829 4.963922)
		(width 0.1651)
		(layer "In7.Cu")
		(net "85_10INCH_IN2_DN")
	)
	(segment
		(start 348.647004 4.170426)
		(end 349.220536 4.572254)
		(width 0.1651)
		(layer "In7.Cu")
		(net "85_10INCH_IN2_DN")
	)
	(segment
		(start 379.075442 4.987036)
		(end 379.47727 4.413758)
		(width 0.1651)
		(layer "In7.Cu")
		(net "85_10INCH_IN2_DN")
	)
	(segment
		(start 354.658676 12.677902)
		(end 355.040946 12.945872)
		(width 0.1651)
		(layer "In7.Cu")
		(net "85_10INCH_IN2_DN")
	)
	(segment
		(start 369.264692 4.562856)
		(end 370.69776 12.690856)
		(width 0.1651)
		(layer "In7.Cu")
		(net "85_10INCH_IN2_DN")
	)
	(segment
		(start 338.995258 12.895326)
		(end 340.01075 12.715748)
		(width 0.1651)
		(layer "In7.Cu")
		(net "85_10INCH_IN2_DN")
	)
	(segment
		(start 359.027222 4.973574)
		(end 359.42905 4.400296)
		(width 0.1651)
		(layer "In7.Cu")
		(net "85_10INCH_IN2_DN")
	)
	(segment
		(start 368.091466 12.807188)
		(end 368.359436 12.424918)
		(width 0.1651)
		(layer "In7.Cu")
		(net "85_10INCH_IN2_DN")
	)
	(segment
		(start 335.998312 12.69492)
		(end 336.266282 12.312396)
		(width 0.1651)
		(layer "In7.Cu")
		(net "85_10INCH_IN2_DN")
	)
	(segment
		(start 356.665784 4.173474)
		(end 357.239316 4.575556)
		(width 0.1651)
		(layer "In7.Cu")
		(net "85_10INCH_IN2_DN")
	)
	(segment
		(start 381.297942 4.595876)
		(end 381.862584 7.7978)
		(width 0.1651)
		(layer "In7.Cu")
		(net "85_10INCH_IN2_DN")
	)
	(segment
		(start 363.437424 4.394962)
		(end 364.68431 4.174744)
		(width 0.1651)
		(layer "In7.Cu")
		(net "85_10INCH_IN2_DN")
	)
	(segment
		(start 362.688886 12.744704)
		(end 363.071156 13.012674)
		(width 0.1651)
		(layer "In7.Cu")
		(net "85_10INCH_IN2_DN")
	)
	(segment
		(start 333.895954 8.612886)
		(end 334.60055 12.606528)
		(width 0.1651)
		(layer "In7.Cu")
		(net "85_10INCH_IN2_DN")
	)
	(segment
		(start 365.257842 4.576572)
		(end 366.69345 12.718796)
		(width 0.1651)
		(layer "In7.Cu")
		(net "85_10INCH_IN2_DN")
	)
	(segment
		(start 334.60055 12.606528)
		(end 334.982566 12.874498)
		(width 0.1651)
		(layer "In7.Cu")
		(net "85_10INCH_IN2_DN")
	)
	(segment
		(start 335.371948 4.387342)
		(end 336.618834 4.167124)
		(width 0.1651)
		(layer "In7.Cu")
		(net "85_10INCH_IN2_DN")
	)
	(segment
		(start 344.038682 12.81938)
		(end 344.306652 12.43711)
		(width 0.1651)
		(layer "In7.Cu")
		(net "85_10INCH_IN2_DN")
	)
	(segment
		(start 338.613496 12.62761)
		(end 338.995258 12.895326)
		(width 0.1651)
		(layer "In7.Cu")
		(net "85_10INCH_IN2_DN")
	)
	(segment
		(start 342.99017 4.970526)
		(end 343.391998 4.397248)
		(width 0.1651)
		(layer "In7.Cu")
		(net "85_10INCH_IN2_DN")
	)
	(segment
		(start 352.051366 12.787376)
		(end 352.319336 12.405106)
		(width 0.1651)
		(layer "In7.Cu")
		(net "85_10INCH_IN2_DN")
	)
	(segment
		(start 333.258668 7.975854)
		(end 333.895954 8.612886)
		(width 0.1651)
		(layer "In7.Cu")
		(net "85_10INCH_IN2_DN")
	)
	(segment
		(start 376.101864 12.762738)
		(end 376.370088 12.380214)
		(width 0.1651)
		(layer "In7.Cu")
		(net "85_10INCH_IN2_DN")
	)
	(segment
		(start 372.095776 12.779248)
		(end 372.363746 12.396978)
		(width 0.1651)
		(layer "In7.Cu")
		(net "85_10INCH_IN2_DN")
	)
	(segment
		(start 359.054146 12.968224)
		(end 360.069892 12.788646)
		(width 0.1651)
		(layer "In7.Cu")
		(net "85_10INCH_IN2_DN")
	)
	(segment
		(start 361.249722 4.581906)
		(end 362.688886 12.744704)
		(width 0.1651)
		(layer "In7.Cu")
		(net "85_10INCH_IN2_DN")
	)
	(segment
		(start 385.093464 8.001762)
		(end 385.384294 7.710932)
		(width 0.1651)
		(layer "In7.Cu")
		(net "85_10INCH_IN2_DN")
	)
	(segment
		(start 380.381764 12.395708)
		(end 379.075442 4.987036)
		(width 0.1651)
		(layer "In7.Cu")
		(net "85_10INCH_IN2_DN")
	)
	(segment
		(start 343.391998 4.397248)
		(end 344.638884 4.17703)
		(width 0.1651)
		(layer "In7.Cu")
		(net "85_10INCH_IN2_DN")
	)
	(segment
		(start 359.42905 4.400296)
		(end 360.675936 4.180078)
		(width 0.1651)
		(layer "In7.Cu")
		(net "85_10INCH_IN2_DN")
	)
	(segment
		(start 370.69776 12.690856)
		(end 371.08003 12.958826)
		(width 0.1651)
		(layer "In7.Cu")
		(net "85_10INCH_IN2_DN")
	)
	(segment
		(start 364.68431 4.174744)
		(end 365.257842 4.576572)
		(width 0.1651)
		(layer "In7.Cu")
		(net "85_10INCH_IN2_DN")
	)
	(segment
		(start 356.324662 12.384024)
		(end 355.016816 4.96697)
		(width 0.1651)
		(layer "In7.Cu")
		(net "85_10INCH_IN2_DN")
	)
	(segment
		(start 376.710956 4.172458)
		(end 377.284996 4.57454)
		(width 0.1651)
		(layer "In7.Cu")
		(net "85_10INCH_IN2_DN")
	)
	(segment
		(start 377.284996 4.57454)
		(end 378.715778 12.689586)
		(width 0.1651)
		(layer "In7.Cu")
		(net "85_10INCH_IN2_DN")
	)
	(segment
		(start 375.46407 4.392676)
		(end 376.710956 4.172458)
		(width 0.1651)
		(layer "In7.Cu")
		(net "85_10INCH_IN2_DN")
	)
	(segment
		(start 343.022936 12.998958)
		(end 344.038682 12.81938)
		(width 0.1651)
		(layer "In7.Cu")
		(net "85_10INCH_IN2_DN")
	)
	(segment
		(start 351.00641 4.959096)
		(end 351.408238 4.385818)
		(width 0.1651)
		(layer "In7.Cu")
		(net "85_10INCH_IN2_DN")
	)
	(segment
		(start 375.086118 12.942316)
		(end 376.101864 12.762738)
		(width 0.1651)
		(layer "In7.Cu")
		(net "85_10INCH_IN2_DN")
	)
	(segment
		(start 371.052344 4.95935)
		(end 371.454172 4.386072)
		(width 0.1651)
		(layer "In7.Cu")
		(net "85_10INCH_IN2_DN")
	)
	(segment
		(start 337.192366 4.568952)
		(end 338.613496 12.62761)
		(width 0.1651)
		(layer "In7.Cu")
		(net "85_10INCH_IN2_DN")
	)
	(segment
		(start 344.306652 12.43711)
		(end 342.99017 4.970526)
		(width 0.1651)
		(layer "In7.Cu")
		(net "85_10INCH_IN2_DN")
	)
	(segment
		(start 334.982566 12.874498)
		(end 335.998312 12.69492)
		(width 0.1651)
		(layer "In7.Cu")
		(net "85_10INCH_IN2_DN")
	)
	(segment
		(start 346.99829 4.963922)
		(end 347.400118 4.390644)
		(width 0.1651)
		(layer "In7.Cu")
		(net "85_10INCH_IN2_DN")
	)
	(segment
		(start 329.612498 7.685024)
		(end 329.903328 7.975854)
		(width 0.1651)
		(layer "In7.Cu")
		(net "85_10INCH_IN2_DN")
	)
	(segment
		(start 382.153414 8.001762)
		(end 385.093464 8.001762)
		(width 0.1651)
		(layer "In7.Cu")
		(net "85_10INCH_IN2_DN")
	)
	(segment
		(start 368.359436 12.424918)
		(end 367.042446 4.954524)
		(width 0.1651)
		(layer "In7.Cu")
		(net "85_10INCH_IN2_DN")
	)
	(segment
		(start 360.337862 12.406376)
		(end 359.027222 4.973574)
		(width 0.1651)
		(layer "In7.Cu")
		(net "85_10INCH_IN2_DN")
	)
	(segment
		(start 356.056692 12.766294)
		(end 356.324662 12.384024)
		(width 0.1651)
		(layer "In7.Cu")
		(net "85_10INCH_IN2_DN")
	)
	(segment
		(start 341.20201 4.572508)
		(end 342.64092 12.730988)
		(width 0.1651)
		(layer "In7.Cu")
		(net "85_10INCH_IN2_DN")
	)
	(segment
		(start 353.228656 4.567428)
		(end 354.658676 12.677902)
		(width 0.1651)
		(layer "In7.Cu")
		(net "85_10INCH_IN2_DN")
	)
	(segment
		(start 374.703848 12.674346)
		(end 375.086118 12.942316)
		(width 0.1651)
		(layer "In7.Cu")
		(net "85_10INCH_IN2_DN")
	)
	(segment
		(start 378.715778 12.689586)
		(end 379.098048 12.957556)
		(width 0.1651)
		(layer "In7.Cu")
		(net "85_10INCH_IN2_DN")
	)
	(segment
		(start 355.040946 12.945872)
		(end 356.056692 12.766294)
		(width 0.1651)
		(layer "In7.Cu")
		(net "85_10INCH_IN2_DN")
	)
	(segment
		(start 350.65335 12.698984)
		(end 351.03562 12.966954)
		(width 0.1651)
		(layer "In7.Cu")
		(net "85_10INCH_IN2_DN")
	)
	(segment
		(start 347.03512 13.014452)
		(end 348.050866 12.834874)
		(width 0.1651)
		(layer "In7.Cu")
		(net "85_10INCH_IN2_DN")
	)
	(segment
		(start 363.071156 13.012674)
		(end 364.086902 12.833096)
		(width 0.1651)
		(layer "In7.Cu")
		(net "85_10INCH_IN2_DN")
	)
	(segment
		(start 340.01075 12.715748)
		(end 340.278974 12.33297)
		(width 0.1651)
		(layer "In7.Cu")
		(net "85_10INCH_IN2_DN")
	)
	(segment
		(start 339.381592 4.390898)
		(end 340.628478 4.17068)
		(width 0.1651)
		(layer "In7.Cu")
		(net "85_10INCH_IN2_DN")
	)
	(segment
		(start 340.278974 12.33297)
		(end 338.979764 4.964176)
		(width 0.1651)
		(layer "In7.Cu")
		(net "85_10INCH_IN2_DN")
	)
	(segment
		(start 379.098048 12.957556)
		(end 380.113794 12.777978)
		(width 0.1651)
		(layer "In7.Cu")
		(net "85_10INCH_IN2_DN")
	)
	(segment
		(start 355.418644 4.393692)
		(end 356.665784 4.173474)
		(width 0.1651)
		(layer "In7.Cu")
		(net "85_10INCH_IN2_DN")
	)
	(segment
		(start 371.08003 12.958826)
		(end 372.095776 12.779248)
		(width 0.1651)
		(layer "In7.Cu")
		(net "85_10INCH_IN2_DN")
	)
	(segment
		(start 357.239316 4.575556)
		(end 358.671876 12.700254)
		(width 0.1651)
		(layer "In7.Cu")
		(net "85_10INCH_IN2_DN")
	)
	(segment
		(start 376.370088 12.380214)
		(end 375.062242 4.966208)
		(width 0.1651)
		(layer "In7.Cu")
		(net "85_10INCH_IN2_DN")
	)
	(segment
		(start 368.69116 4.161028)
		(end 369.264692 4.562856)
		(width 0.1651)
		(layer "In7.Cu")
		(net "85_10INCH_IN2_DN")
	)
	(segment
		(start 329.903328 7.975854)
		(end 333.258668 7.975854)
		(width 0.1651)
		(layer "In7.Cu")
		(net "85_10INCH_IN2_DN")
	)
	(segment
		(start 367.042446 4.954524)
		(end 367.444274 4.381246)
		(width 0.1651)
		(layer "In7.Cu")
		(net "85_10INCH_IN2_DN")
	)
	(segment
		(start 336.618834 4.167124)
		(end 337.192366 4.568952)
		(width 0.1651)
		(layer "In7.Cu")
		(net "85_10INCH_IN2_DN")
	)
	(segment
		(start 364.354872 12.450826)
		(end 363.035596 4.96824)
		(width 0.1651)
		(layer "In7.Cu")
		(net "85_10INCH_IN2_DN")
	)
	(segment
		(start 373.27459 4.567682)
		(end 374.703848 12.674346)
		(width 0.1651)
		(layer "In7.Cu")
		(net "85_10INCH_IN2_DN")
	)
	(segment
		(start 360.069892 12.788646)
		(end 360.337862 12.406376)
		(width 0.1651)
		(layer "In7.Cu")
		(net "85_10INCH_IN2_DN")
	)
	(segment
		(start 352.319336 12.405106)
		(end 351.00641 4.959096)
		(width 0.1651)
		(layer "In7.Cu")
		(net "85_10INCH_IN2_DN")
	)
	(segment
		(start 355.016816 4.96697)
		(end 355.418644 4.393692)
		(width 0.1651)
		(layer "In7.Cu")
		(net "85_10INCH_IN2_DN")
	)
	(segment
		(start 336.266282 12.312396)
		(end 334.97012 4.96062)
		(width 0.1651)
		(layer "In7.Cu")
		(net "85_10INCH_IN2_DN")
	)
	(segment
		(start 380.724156 4.19354)
		(end 381.297942 4.595876)
		(width 0.1651)
		(layer "In7.Cu")
		(net "85_10INCH_IN2_DN")
	)
	(segment
		(start 379.47727 4.413758)
		(end 380.724156 4.19354)
		(width 0.1651)
		(layer "In7.Cu")
		(net "85_10INCH_IN2_DN")
	)
	(segment
		(start 360.675936 4.180078)
		(end 361.249722 4.581906)
		(width 0.1651)
		(layer "In7.Cu")
		(net "85_10INCH_IN2_DN")
	)
	(segment
		(start 371.454172 4.386072)
		(end 372.701058 4.165854)
		(width 0.1651)
		(layer "In7.Cu")
		(net "85_10INCH_IN2_DN")
	)
	(segment
		(start 347.400118 4.390644)
		(end 348.647004 4.170426)
		(width 0.1651)
		(layer "In7.Cu")
		(net "85_10INCH_IN2_DN")
	)
	(segment
		(start 349.220536 4.572254)
		(end 350.65335 12.698984)
		(width 0.1651)
		(layer "In7.Cu")
		(net "85_10INCH_IN2_DN")
	)
	(segment
		(start 375.062242 4.966208)
		(end 375.46407 4.392676)
		(width 0.1651)
		(layer "In7.Cu")
		(net "85_10INCH_IN2_DN")
	)
	(segment
		(start 358.671876 12.700254)
		(end 359.054146 12.968224)
		(width 0.1651)
		(layer "In7.Cu")
		(net "85_10INCH_IN2_DN")
	)
	(segment
		(start 368.221514 -71.555864)
		(end 367.876582 -71.555864)
		(width 0.13208)
		(layer "F.Cu")
		(net "P12V_SSD12_CO_MODE")
	)
	(segment
		(start 367.558066 -72.366632)
		(end 368.574066 -72.366632)
		(width 0.13208)
		(layer "F.Cu")
		(net "P12V_SSD12_CO_MODE")
	)
	(segment
		(start 368.574066 -72.366632)
		(end 368.574066 -71.908416)
		(width 0.13208)
		(layer "F.Cu")
		(net "P12V_SSD12_CO_MODE")
	)
	(segment
		(start 368.574066 -71.908416)
		(end 368.221514 -71.555864)
		(width 0.13208)
		(layer "F.Cu")
		(net "P12V_SSD12_CO_MODE")
	)
	(segment
		(start 368.375692 -70.479158)
		(end 368.375692 -71.056754)
		(width 0.13208)
		(layer "F.Cu")
		(net "P12V_SSD12_CO_MODE")
	)
	(segment
		(start 368.375692 -71.056754)
		(end 367.876582 -71.555864)
		(width 0.13208)
		(layer "F.Cu")
		(net "P12V_SSD12_CO_MODE")
	)
	(via
		(at 367.876582 -71.555864)
		(size 0.508)
		(drill 0.254)
		(layers "F.Cu" "B.Cu")
		(net "P12V_SSD12_CO_MODE")
	)
	(segment
		(start 132.780024 -117.301772)
		(end 132.780024 -117.016276)
		(width 0.13208)
		(layer "F.Cu")
		(net "P3V3_NIC2_CO_GATE")
	)
	(segment
		(start 132.132832 -116.369084)
		(end 132.132832 -115.933474)
		(width 0.13208)
		(layer "F.Cu")
		(net "P3V3_NIC2_CO_GATE")
	)
	(segment
		(start 132.780024 -117.611652)
		(end 132.780024 -117.301772)
		(width 0.13208)
		(layer "F.Cu")
		(net "P3V3_NIC2_CO_GATE")
	)
	(segment
		(start 132.780024 -117.016276)
		(end 132.132832 -116.369084)
		(width 0.13208)
		(layer "F.Cu")
		(net "P3V3_NIC2_CO_GATE")
	)
	(segment
		(start 132.41274 -117.978936)
		(end 132.780024 -117.611652)
		(width 0.13208)
		(layer "F.Cu")
		(net "P3V3_NIC2_CO_GATE")
	)
	(via
		(at 132.780024 -117.301772)
		(size 0.508)
		(drill 0.254)
		(layers "F.Cu" "B.Cu")
		(net "P3V3_NIC2_CO_GATE")
	)
	(segment
		(start 248.74093 -113.93424)
		(end 248.89714 -113.77803)
		(width 0.13208)
		(layer "F.Cu")
		(net "P3V3_NIC4_CO_MODE")
	)
	(segment
		(start 248.902728 -113.177574)
		(end 248.902728 -112.539526)
		(width 0.13208)
		(layer "F.Cu")
		(net "P3V3_NIC4_CO_MODE")
	)
	(segment
		(start 248.74093 -114.695478)
		(end 248.74093 -113.93424)
		(width 0.13208)
		(layer "F.Cu")
		(net "P3V3_NIC4_CO_MODE")
	)
	(segment
		(start 247.886728 -112.539526)
		(end 248.902728 -112.539526)
		(width 0.13208)
		(layer "F.Cu")
		(net "P3V3_NIC4_CO_MODE")
	)
	(segment
		(start 248.89714 -113.183162)
		(end 248.902728 -113.177574)
		(width 0.13208)
		(layer "F.Cu")
		(net "P3V3_NIC4_CO_MODE")
	)
	(segment
		(start 248.89714 -113.77803)
		(end 248.89714 -113.183162)
		(width 0.13208)
		(layer "F.Cu")
		(net "P3V3_NIC4_CO_MODE")
	)
	(via
		(at 248.89714 -113.183162)
		(size 0.508)
		(drill 0.254)
		(layers "F.Cu" "B.Cu")
		(net "P3V3_NIC4_CO_MODE")
	)
	(segment
		(start 172.473874 -27.815286)
		(end 172.473874 -27.406346)
		(width 0.13208)
		(layer "F.Cu")
		(net "P3V3_SSD6_CO_MODE")
	)
	(segment
		(start 171.457874 -27.406346)
		(end 172.473874 -27.406346)
		(width 0.13208)
		(layer "F.Cu")
		(net "P3V3_SSD6_CO_MODE")
	)
	(segment
		(start 171.382436 -28.875736)
		(end 171.382436 -28.329636)
		(width 0.13208)
		(layer "F.Cu")
		(net "P3V3_SSD6_CO_MODE")
	)
	(segment
		(start 171.382436 -28.329636)
		(end 171.572936 -28.139136)
		(width 0.13208)
		(layer "F.Cu")
		(net "P3V3_SSD6_CO_MODE")
	)
	(segment
		(start 172.150024 -28.139136)
		(end 172.473874 -27.815286)
		(width 0.13208)
		(layer "F.Cu")
		(net "P3V3_SSD6_CO_MODE")
	)
	(segment
		(start 171.572936 -28.139136)
		(end 172.150024 -28.139136)
		(width 0.13208)
		(layer "F.Cu")
		(net "P3V3_SSD6_CO_MODE")
	)
	(via
		(at 172.150024 -28.139136)
		(size 0.508)
		(drill 0.254)
		(layers "F.Cu" "B.Cu")
		(net "P3V3_SSD6_CO_MODE")
	)
	(segment
		(start 311.933844 20.818348)
		(end 311.25287 21.000212)
		(width 0.13462)
		(layer "B.Cu")
		(net "85_5INCH_IN6_DN")
	)
	(segment
		(start 273.940524 20.82546)
		(end 274.621498 21.007324)
		(width 0.13462)
		(layer "B.Cu")
		(net "85_5INCH_IN6_DN")
	)
	(segment
		(start 295.925748 24.002746)
		(end 297.171618 23.782528)
		(width 0.1651)
		(layer "In15.Cu")
		(net "85_5INCH_IN6_DN")
	)
	(segment
		(start 306.813204 20.387564)
		(end 307.272436 20.709382)
		(width 0.1651)
		(layer "In15.Cu")
		(net "85_5INCH_IN6_DN")
	)
	(segment
		(start 296.853102 17.220184)
		(end 297.869864 17.040606)
		(width 0.1651)
		(layer "In15.Cu")
		(net "85_5INCH_IN6_DN")
	)
	(segment
		(start 274.621498 21.007324)
		(end 274.912328 20.716494)
		(width 0.1651)
		(layer "In15.Cu")
		(net "85_5INCH_IN6_DN")
	)
	(segment
		(start 287.914842 24.044148)
		(end 289.160712 23.82393)
		(width 0.1651)
		(layer "In15.Cu")
		(net "85_5INCH_IN6_DN")
	)
	(segment
		(start 289.160712 23.82393)
		(end 289.562794 23.250398)
		(width 0.1651)
		(layer "In15.Cu")
		(net "85_5INCH_IN6_DN")
	)
	(segment
		(start 279.310846 23.575264)
		(end 279.884632 23.977346)
		(width 0.1651)
		(layer "In15.Cu")
		(net "85_5INCH_IN6_DN")
	)
	(segment
		(start 297.869864 17.040606)
		(end 298.25188 17.308322)
		(width 0.1651)
		(layer "In15.Cu")
		(net "85_5INCH_IN6_DN")
	)
	(segment
		(start 307.272436 20.709382)
		(end 310.96204 20.709382)
		(width 0.1651)
		(layer "In15.Cu")
		(net "85_5INCH_IN6_DN")
	)
	(segment
		(start 284.558486 17.60601)
		(end 284.826202 17.223994)
		(width 0.1651)
		(layer "In15.Cu")
		(net "85_5INCH_IN6_DN")
	)
	(segment
		(start 301.879254 17.04467)
		(end 302.261778 17.31264)
		(width 0.1651)
		(layer "In15.Cu")
		(net "85_5INCH_IN6_DN")
	)
	(segment
		(start 302.261778 17.31264)
		(end 303.371758 23.611586)
		(width 0.1651)
		(layer "In15.Cu")
		(net "85_5INCH_IN6_DN")
	)
	(segment
		(start 283.897832 23.999698)
		(end 285.143702 23.77948)
		(width 0.1651)
		(layer "In15.Cu")
		(net "85_5INCH_IN6_DN")
	)
	(segment
		(start 305.19243 23.79345)
		(end 305.594512 23.220934)
		(width 0.1651)
		(layer "In15.Cu")
		(net "85_5INCH_IN6_DN")
	)
	(segment
		(start 297.5737 23.208488)
		(end 296.585386 17.6022)
		(width 0.1651)
		(layer "In15.Cu")
		(net "85_5INCH_IN6_DN")
	)
	(segment
		(start 296.585386 17.6022)
		(end 296.853102 17.220184)
		(width 0.1651)
		(layer "In15.Cu")
		(net "85_5INCH_IN6_DN")
	)
	(segment
		(start 281.834844 17.049496)
		(end 282.21686 17.317466)
		(width 0.1651)
		(layer "In15.Cu")
		(net "85_5INCH_IN6_DN")
	)
	(segment
		(start 310.96204 20.709382)
		(end 311.25287 21.000212)
		(width 0.1651)
		(layer "In15.Cu")
		(net "85_5INCH_IN6_DN")
	)
	(segment
		(start 290.234116 17.31137)
		(end 291.34562 23.616158)
		(width 0.1651)
		(layer "In15.Cu")
		(net "85_5INCH_IN6_DN")
	)
	(segment
		(start 286.22498 17.312132)
		(end 287.341056 23.642066)
		(width 0.1651)
		(layer "In15.Cu")
		(net "85_5INCH_IN6_DN")
	)
	(segment
		(start 292.844474 17.22247)
		(end 293.861236 17.042892)
		(width 0.1651)
		(layer "In15.Cu")
		(net "85_5INCH_IN6_DN")
	)
	(segment
		(start 305.594512 23.220934)
		(end 304.603404 17.602454)
		(width 0.1651)
		(layer "In15.Cu")
		(net "85_5INCH_IN6_DN")
	)
	(segment
		(start 298.25188 17.308322)
		(end 299.36059 23.596092)
		(width 0.1651)
		(layer "In15.Cu")
		(net "85_5INCH_IN6_DN")
	)
	(segment
		(start 293.861236 17.042892)
		(end 294.243252 17.310608)
		(width 0.1651)
		(layer "In15.Cu")
		(net "85_5INCH_IN6_DN")
	)
	(segment
		(start 283.324046 23.597616)
		(end 283.897832 23.999698)
		(width 0.1651)
		(layer "In15.Cu")
		(net "85_5INCH_IN6_DN")
	)
	(segment
		(start 282.21686 17.317466)
		(end 283.324046 23.597616)
		(width 0.1651)
		(layer "In15.Cu")
		(net "85_5INCH_IN6_DN")
	)
	(segment
		(start 289.562794 23.250398)
		(end 288.567622 17.605248)
		(width 0.1651)
		(layer "In15.Cu")
		(net "85_5INCH_IN6_DN")
	)
	(segment
		(start 291.919406 24.01824)
		(end 293.165276 23.798022)
		(width 0.1651)
		(layer "In15.Cu")
		(net "85_5INCH_IN6_DN")
	)
	(segment
		(start 289.8521 17.043654)
		(end 290.234116 17.31137)
		(width 0.1651)
		(layer "In15.Cu")
		(net "85_5INCH_IN6_DN")
	)
	(segment
		(start 300.594776 17.606264)
		(end 300.862492 17.224248)
		(width 0.1651)
		(layer "In15.Cu")
		(net "85_5INCH_IN6_DN")
	)
	(segment
		(start 288.567622 17.605248)
		(end 288.835338 17.223232)
		(width 0.1651)
		(layer "In15.Cu")
		(net "85_5INCH_IN6_DN")
	)
	(segment
		(start 280.817828 17.229074)
		(end 281.834844 17.049496)
		(width 0.1651)
		(layer "In15.Cu")
		(net "85_5INCH_IN6_DN")
	)
	(segment
		(start 292.576758 17.604486)
		(end 292.844474 17.22247)
		(width 0.1651)
		(layer "In15.Cu")
		(net "85_5INCH_IN6_DN")
	)
	(segment
		(start 293.165276 23.798022)
		(end 293.567358 23.223982)
		(width 0.1651)
		(layer "In15.Cu")
		(net "85_5INCH_IN6_DN")
	)
	(segment
		(start 305.887628 17.04086)
		(end 306.270152 17.309084)
		(width 0.1651)
		(layer "In15.Cu")
		(net "85_5INCH_IN6_DN")
	)
	(segment
		(start 278.689308 20.716494)
		(end 278.82723 20.832064)
		(width 0.1651)
		(layer "In15.Cu")
		(net "85_5INCH_IN6_DN")
	)
	(segment
		(start 280.550112 17.61109)
		(end 280.817828 17.229074)
		(width 0.1651)
		(layer "In15.Cu")
		(net "85_5INCH_IN6_DN")
	)
	(segment
		(start 304.87112 17.220438)
		(end 305.887628 17.04086)
		(width 0.1651)
		(layer "In15.Cu")
		(net "85_5INCH_IN6_DN")
	)
	(segment
		(start 281.532584 23.183596)
		(end 280.550112 17.61109)
		(width 0.1651)
		(layer "In15.Cu")
		(net "85_5INCH_IN6_DN")
	)
	(segment
		(start 278.82723 20.832064)
		(end 279.310846 23.575264)
		(width 0.1651)
		(layer "In15.Cu")
		(net "85_5INCH_IN6_DN")
	)
	(segment
		(start 295.352216 23.60041)
		(end 295.925748 24.002746)
		(width 0.1651)
		(layer "In15.Cu")
		(net "85_5INCH_IN6_DN")
	)
	(segment
		(start 281.130502 23.757128)
		(end 281.532584 23.183596)
		(width 0.1651)
		(layer "In15.Cu")
		(net "85_5INCH_IN6_DN")
	)
	(segment
		(start 299.36059 23.596092)
		(end 299.934122 23.998428)
		(width 0.1651)
		(layer "In15.Cu")
		(net "85_5INCH_IN6_DN")
	)
	(segment
		(start 299.934122 23.998428)
		(end 301.179992 23.77821)
		(width 0.1651)
		(layer "In15.Cu")
		(net "85_5INCH_IN6_DN")
	)
	(segment
		(start 300.862492 17.224248)
		(end 301.879254 17.04467)
		(width 0.1651)
		(layer "In15.Cu")
		(net "85_5INCH_IN6_DN")
	)
	(segment
		(start 294.243252 17.310608)
		(end 295.352216 23.60041)
		(width 0.1651)
		(layer "In15.Cu")
		(net "85_5INCH_IN6_DN")
	)
	(segment
		(start 301.582328 23.204424)
		(end 300.594776 17.606264)
		(width 0.1651)
		(layer "In15.Cu")
		(net "85_5INCH_IN6_DN")
	)
	(segment
		(start 284.826202 17.223994)
		(end 285.842964 17.044416)
		(width 0.1651)
		(layer "In15.Cu")
		(net "85_5INCH_IN6_DN")
	)
	(segment
		(start 291.34562 23.616158)
		(end 291.919406 24.01824)
		(width 0.1651)
		(layer "In15.Cu")
		(net "85_5INCH_IN6_DN")
	)
	(segment
		(start 285.842964 17.044416)
		(end 286.22498 17.312132)
		(width 0.1651)
		(layer "In15.Cu")
		(net "85_5INCH_IN6_DN")
	)
	(segment
		(start 304.603404 17.602454)
		(end 304.87112 17.220438)
		(width 0.1651)
		(layer "In15.Cu")
		(net "85_5INCH_IN6_DN")
	)
	(segment
		(start 297.171618 23.782528)
		(end 297.5737 23.208488)
		(width 0.1651)
		(layer "In15.Cu")
		(net "85_5INCH_IN6_DN")
	)
	(segment
		(start 279.884632 23.977346)
		(end 281.130502 23.757128)
		(width 0.1651)
		(layer "In15.Cu")
		(net "85_5INCH_IN6_DN")
	)
	(segment
		(start 285.545784 23.205948)
		(end 284.558486 17.60601)
		(width 0.1651)
		(layer "In15.Cu")
		(net "85_5INCH_IN6_DN")
	)
	(segment
		(start 303.94656 24.013668)
		(end 305.19243 23.79345)
		(width 0.1651)
		(layer "In15.Cu")
		(net "85_5INCH_IN6_DN")
	)
	(segment
		(start 306.270152 17.309084)
		(end 306.813204 20.387564)
		(width 0.1651)
		(layer "In15.Cu")
		(net "85_5INCH_IN6_DN")
	)
	(segment
		(start 285.143702 23.77948)
		(end 285.545784 23.205948)
		(width 0.1651)
		(layer "In15.Cu")
		(net "85_5INCH_IN6_DN")
	)
	(segment
		(start 293.567358 23.223982)
		(end 292.576758 17.604486)
		(width 0.1651)
		(layer "In15.Cu")
		(net "85_5INCH_IN6_DN")
	)
	(segment
		(start 288.835338 17.223232)
		(end 289.8521 17.043654)
		(width 0.1651)
		(layer "In15.Cu")
		(net "85_5INCH_IN6_DN")
	)
	(segment
		(start 301.179992 23.77821)
		(end 301.582328 23.204424)
		(width 0.1651)
		(layer "In15.Cu")
		(net "85_5INCH_IN6_DN")
	)
	(segment
		(start 303.371758 23.611586)
		(end 303.94656 24.013668)
		(width 0.1651)
		(layer "In15.Cu")
		(net "85_5INCH_IN6_DN")
	)
	(segment
		(start 274.912328 20.716494)
		(end 278.689308 20.716494)
		(width 0.1651)
		(layer "In15.Cu")
		(net "85_5INCH_IN6_DN")
	)
	(segment
		(start 287.341056 23.642066)
		(end 287.914842 24.044148)
		(width 0.1651)
		(layer "In15.Cu")
		(net "85_5INCH_IN6_DN")
	)
	(segment
		(start 393.87653 -71.555864)
		(end 394.37564 -71.056754)
		(width 0.13208)
		(layer "F.Cu")
		(net "P12V_SSD13_CO_MODE")
	)
	(segment
		(start 394.221462 -71.555864)
		(end 393.87653 -71.555864)
		(width 0.13208)
		(layer "F.Cu")
		(net "P12V_SSD13_CO_MODE")
	)
	(segment
		(start 394.574014 -72.366632)
		(end 394.574014 -71.908416)
		(width 0.13208)
		(layer "F.Cu")
		(net "P12V_SSD13_CO_MODE")
	)
	(segment
		(start 394.37564 -71.056754)
		(end 394.37564 -70.479158)
		(width 0.13208)
		(layer "F.Cu")
		(net "P12V_SSD13_CO_MODE")
	)
	(segment
		(start 394.574014 -71.908416)
		(end 394.221462 -71.555864)
		(width 0.13208)
		(layer "F.Cu")
		(net "P12V_SSD13_CO_MODE")
	)
	(segment
		(start 393.558014 -72.366632)
		(end 394.574014 -72.366632)
		(width 0.13208)
		(layer "F.Cu")
		(net "P12V_SSD13_CO_MODE")
	)
	(via
		(at 393.87653 -71.555864)
		(size 0.508)
		(drill 0.254)
		(layers "F.Cu" "B.Cu")
		(net "P12V_SSD13_CO_MODE")
	)
	(segment
		(start 209.4611 -114.308636)
		(end 209.45856 -114.311176)
		(width 0.13208)
		(layer "F.Cu")
		(net "P3V3_NIC3_CO_ILIMIT")
	)
	(segment
		(start 209.45856 -114.311176)
		(end 208.7245 -114.311176)
		(width 0.13208)
		(layer "F.Cu")
		(net "P3V3_NIC3_CO_ILIMIT")
	)
	(segment
		(start 209.89925 -113.870486)
		(end 209.4611 -114.308636)
		(width 0.13208)
		(layer "F.Cu")
		(net "P3V3_NIC3_CO_ILIMIT")
	)
	(segment
		(start 210.19389 -113.870486)
		(end 209.89925 -113.870486)
		(width 0.13208)
		(layer "F.Cu")
		(net "P3V3_NIC3_CO_ILIMIT")
	)
	(via
		(at 209.4611 -114.308636)
		(size 0.508)
		(drill 0.254)
		(layers "F.Cu" "B.Cu")
		(net "P3V3_NIC3_CO_ILIMIT")
	)
	(segment
		(start 322.529454 -115.335304)
		(end 322.824602 -115.335304)
		(width 0.13208)
		(layer "F.Cu")
		(net "P3V3_NIC5_CO_DV_DT")
	)
	(segment
		(start 322.380102 -114.407188)
		(end 322.380102 -115.185952)
		(width 0.13208)
		(layer "F.Cu")
		(net "P3V3_NIC5_CO_DV_DT")
	)
	(segment
		(start 321.702938 -114.384836)
		(end 322.030344 -114.05743)
		(width 0.13208)
		(layer "F.Cu")
		(net "P3V3_NIC5_CO_DV_DT")
	)
	(segment
		(start 321.252342 -114.384836)
		(end 321.702938 -114.384836)
		(width 0.13208)
		(layer "F.Cu")
		(net "P3V3_NIC5_CO_DV_DT")
	)
	(segment
		(start 322.380102 -115.185952)
		(end 322.529454 -115.335304)
		(width 0.13208)
		(layer "F.Cu")
		(net "P3V3_NIC5_CO_DV_DT")
	)
	(segment
		(start 322.030344 -114.05743)
		(end 322.380102 -114.407188)
		(width 0.13208)
		(layer "F.Cu")
		(net "P3V3_NIC5_CO_DV_DT")
	)
	(via
		(at 322.030344 -114.05743)
		(size 0.508)
		(drill 0.254)
		(layers "F.Cu" "B.Cu")
		(net "P3V3_NIC5_CO_DV_DT")
	)
	(segment
		(start 188.174122 -37.47516)
		(end 187.746894 -37.47516)
		(width 0.13208)
		(layer "F.Cu")
		(net "P3V3_SSD7_PG_G1")
	)
	(segment
		(start 188.36132 -37.662358)
		(end 188.174122 -37.47516)
		(width 0.13208)
		(layer "F.Cu")
		(net "P3V3_SSD7_PG_G1")
	)
	(segment
		(start 189.161166 -37.951156)
		(end 188.719206 -37.951156)
		(width 0.13208)
		(layer "F.Cu")
		(net "P3V3_SSD7_PG_G1")
	)
	(segment
		(start 188.430408 -37.662358)
		(end 188.36132 -37.662358)
		(width 0.13208)
		(layer "F.Cu")
		(net "P3V3_SSD7_PG_G1")
	)
	(segment
		(start 187.746894 -38.49116)
		(end 187.746894 -37.47516)
		(width 0.13208)
		(layer "F.Cu")
		(net "P3V3_SSD7_PG_G1")
	)
	(segment
		(start 188.719206 -37.951156)
		(end 188.430408 -37.662358)
		(width 0.13208)
		(layer "F.Cu")
		(net "P3V3_SSD7_PG_G1")
	)
	(via
		(at 188.430408 -37.662358)
		(size 0.508)
		(drill 0.254)
		(layers "F.Cu" "B.Cu")
		(net "P3V3_SSD7_PG_G1")
	)
	(segment
		(start 328.931524 10.406888)
		(end 329.612498 10.225024)
		(width 0.13462)
		(layer "B.Cu")
		(net "85_10INCH_IN4_DN")
	)
	(segment
		(start 386.065268 10.432796)
		(end 385.384294 10.250932)
		(width 0.13462)
		(layer "B.Cu")
		(net "85_10INCH_IN4_DN")
	)
	(segment
		(start 374.93194 6.767322)
		(end 375.333768 6.19379)
		(width 0.1651)
		(layer "In11.Cu")
		(net "85_10INCH_IN4_DN")
	)
	(segment
		(start 351.277936 6.186678)
		(end 352.524822 5.96646)
		(width 0.1651)
		(layer "In11.Cu")
		(net "85_10INCH_IN4_DN")
	)
	(segment
		(start 336.13598 14.11351)
		(end 334.839818 6.76148)
		(width 0.1651)
		(layer "In11.Cu")
		(net "85_10INCH_IN4_DN")
	)
	(segment
		(start 373.144288 6.368542)
		(end 374.573546 14.475206)
		(width 0.1651)
		(layer "In11.Cu")
		(net "85_10INCH_IN4_DN")
	)
	(segment
		(start 370.949728 14.759686)
		(end 371.965474 14.580108)
		(width 0.1651)
		(layer "In11.Cu")
		(net "85_10INCH_IN4_DN")
	)
	(segment
		(start 354.528374 14.478762)
		(end 354.910644 14.746732)
		(width 0.1651)
		(layer "In11.Cu")
		(net "85_10INCH_IN4_DN")
	)
	(segment
		(start 350.905318 14.767814)
		(end 351.921064 14.588236)
		(width 0.1651)
		(layer "In11.Cu")
		(net "85_10INCH_IN4_DN")
	)
	(segment
		(start 385.093464 10.541762)
		(end 385.384294 10.250932)
		(width 0.1651)
		(layer "In11.Cu")
		(net "85_10INCH_IN4_DN")
	)
	(segment
		(start 348.516702 5.971286)
		(end 349.090234 6.373114)
		(width 0.1651)
		(layer "In11.Cu")
		(net "85_10INCH_IN4_DN")
	)
	(segment
		(start 361.11942 6.382766)
		(end 362.558584 14.545564)
		(width 0.1651)
		(layer "In11.Cu")
		(net "85_10INCH_IN4_DN")
	)
	(segment
		(start 352.524822 5.96646)
		(end 353.098354 6.368288)
		(width 0.1651)
		(layer "In11.Cu")
		(net "85_10INCH_IN4_DN")
	)
	(segment
		(start 362.905294 6.7691)
		(end 363.307122 6.195822)
		(width 0.1651)
		(layer "In11.Cu")
		(net "85_10INCH_IN4_DN")
	)
	(segment
		(start 355.92639 14.567154)
		(end 356.19436 14.184884)
		(width 0.1651)
		(layer "In11.Cu")
		(net "85_10INCH_IN4_DN")
	)
	(segment
		(start 357.109014 6.376416)
		(end 358.541574 14.501114)
		(width 0.1651)
		(layer "In11.Cu")
		(net "85_10INCH_IN4_DN")
	)
	(segment
		(start 340.148672 14.133576)
		(end 338.849462 6.765036)
		(width 0.1651)
		(layer "In11.Cu")
		(net "85_10INCH_IN4_DN")
	)
	(segment
		(start 349.090234 6.373114)
		(end 350.523048 14.499844)
		(width 0.1651)
		(layer "In11.Cu")
		(net "85_10INCH_IN4_DN")
	)
	(segment
		(start 362.558584 14.545564)
		(end 362.940854 14.813534)
		(width 0.1651)
		(layer "In11.Cu")
		(net "85_10INCH_IN4_DN")
	)
	(segment
		(start 329.903328 10.515854)
		(end 333.258668 10.515854)
		(width 0.1651)
		(layer "In11.Cu")
		(net "85_10INCH_IN4_DN")
	)
	(segment
		(start 335.241646 6.188202)
		(end 336.488532 5.967984)
		(width 0.1651)
		(layer "In11.Cu")
		(net "85_10INCH_IN4_DN")
	)
	(segment
		(start 346.904818 14.815312)
		(end 347.920564 14.635734)
		(width 0.1651)
		(layer "In11.Cu")
		(net "85_10INCH_IN4_DN")
	)
	(segment
		(start 375.333768 6.19379)
		(end 376.580654 5.973572)
		(width 0.1651)
		(layer "In11.Cu")
		(net "85_10INCH_IN4_DN")
	)
	(segment
		(start 360.20756 14.207236)
		(end 358.89692 6.774434)
		(width 0.1651)
		(layer "In11.Cu")
		(net "85_10INCH_IN4_DN")
	)
	(segment
		(start 358.89692 6.774434)
		(end 359.298748 6.201156)
		(width 0.1651)
		(layer "In11.Cu")
		(net "85_10INCH_IN4_DN")
	)
	(segment
		(start 358.541574 14.501114)
		(end 358.923844 14.769084)
		(width 0.1651)
		(layer "In11.Cu")
		(net "85_10INCH_IN4_DN")
	)
	(segment
		(start 350.523048 14.499844)
		(end 350.905318 14.767814)
		(width 0.1651)
		(layer "In11.Cu")
		(net "85_10INCH_IN4_DN")
	)
	(segment
		(start 358.923844 14.769084)
		(end 359.93959 14.589506)
		(width 0.1651)
		(layer "In11.Cu")
		(net "85_10INCH_IN4_DN")
	)
	(segment
		(start 379.346968 6.214618)
		(end 380.593854 5.9944)
		(width 0.1651)
		(layer "In11.Cu")
		(net "85_10INCH_IN4_DN")
	)
	(segment
		(start 344.17635 14.238224)
		(end 342.859868 6.771386)
		(width 0.1651)
		(layer "In11.Cu")
		(net "85_10INCH_IN4_DN")
	)
	(segment
		(start 380.251462 14.196568)
		(end 378.94514 6.787896)
		(width 0.1651)
		(layer "In11.Cu")
		(net "85_10INCH_IN4_DN")
	)
	(segment
		(start 366.563148 14.519656)
		(end 366.945418 14.787626)
		(width 0.1651)
		(layer "In11.Cu")
		(net "85_10INCH_IN4_DN")
	)
	(segment
		(start 364.22457 14.251686)
		(end 362.905294 6.7691)
		(width 0.1651)
		(layer "In11.Cu")
		(net "85_10INCH_IN4_DN")
	)
	(segment
		(start 378.967746 14.758416)
		(end 379.983492 14.578838)
		(width 0.1651)
		(layer "In11.Cu")
		(net "85_10INCH_IN4_DN")
	)
	(segment
		(start 366.945418 14.787626)
		(end 367.961164 14.608048)
		(width 0.1651)
		(layer "In11.Cu")
		(net "85_10INCH_IN4_DN")
	)
	(segment
		(start 381.16764 6.396736)
		(end 381.862584 10.3378)
		(width 0.1651)
		(layer "In11.Cu")
		(net "85_10INCH_IN4_DN")
	)
	(segment
		(start 359.93959 14.589506)
		(end 360.20756 14.207236)
		(width 0.1651)
		(layer "In11.Cu")
		(net "85_10INCH_IN4_DN")
	)
	(segment
		(start 338.483194 14.428216)
		(end 338.864956 14.696186)
		(width 0.1651)
		(layer "In11.Cu")
		(net "85_10INCH_IN4_DN")
	)
	(segment
		(start 348.188534 14.253972)
		(end 346.867988 6.764782)
		(width 0.1651)
		(layer "In11.Cu")
		(net "85_10INCH_IN4_DN")
	)
	(segment
		(start 364.554008 5.975604)
		(end 365.12754 6.377432)
		(width 0.1651)
		(layer "In11.Cu")
		(net "85_10INCH_IN4_DN")
	)
	(segment
		(start 368.229134 14.225778)
		(end 366.912144 6.755384)
		(width 0.1651)
		(layer "In11.Cu")
		(net "85_10INCH_IN4_DN")
	)
	(segment
		(start 367.961164 14.608048)
		(end 368.229134 14.225778)
		(width 0.1651)
		(layer "In11.Cu")
		(net "85_10INCH_IN4_DN")
	)
	(segment
		(start 342.510618 14.532102)
		(end 342.892634 14.800072)
		(width 0.1651)
		(layer "In11.Cu")
		(net "85_10INCH_IN4_DN")
	)
	(segment
		(start 344.508582 5.97789)
		(end 345.082114 6.379718)
		(width 0.1651)
		(layer "In11.Cu")
		(net "85_10INCH_IN4_DN")
	)
	(segment
		(start 353.098354 6.368288)
		(end 354.528374 14.478762)
		(width 0.1651)
		(layer "In11.Cu")
		(net "85_10INCH_IN4_DN")
	)
	(segment
		(start 365.12754 6.377432)
		(end 366.563148 14.519656)
		(width 0.1651)
		(layer "In11.Cu")
		(net "85_10INCH_IN4_DN")
	)
	(segment
		(start 342.859868 6.771386)
		(end 343.261696 6.198108)
		(width 0.1651)
		(layer "In11.Cu")
		(net "85_10INCH_IN4_DN")
	)
	(segment
		(start 372.233444 14.197838)
		(end 370.922042 6.76021)
		(width 0.1651)
		(layer "In11.Cu")
		(net "85_10INCH_IN4_DN")
	)
	(segment
		(start 341.071708 6.373368)
		(end 342.510618 14.532102)
		(width 0.1651)
		(layer "In11.Cu")
		(net "85_10INCH_IN4_DN")
	)
	(segment
		(start 338.849462 6.765036)
		(end 339.25129 6.191758)
		(width 0.1651)
		(layer "In11.Cu")
		(net "85_10INCH_IN4_DN")
	)
	(segment
		(start 377.154694 6.375654)
		(end 378.585476 14.490446)
		(width 0.1651)
		(layer "In11.Cu")
		(net "85_10INCH_IN4_DN")
	)
	(segment
		(start 334.839818 6.76148)
		(end 335.241646 6.188202)
		(width 0.1651)
		(layer "In11.Cu")
		(net "85_10INCH_IN4_DN")
	)
	(segment
		(start 333.258668 10.515854)
		(end 333.895954 11.152886)
		(width 0.1651)
		(layer "In11.Cu")
		(net "85_10INCH_IN4_DN")
	)
	(segment
		(start 339.880448 14.516354)
		(end 340.148672 14.133576)
		(width 0.1651)
		(layer "In11.Cu")
		(net "85_10INCH_IN4_DN")
	)
	(segment
		(start 369.13439 6.363716)
		(end 370.567458 14.491716)
		(width 0.1651)
		(layer "In11.Cu")
		(net "85_10INCH_IN4_DN")
	)
	(segment
		(start 378.94514 6.787896)
		(end 379.346968 6.214618)
		(width 0.1651)
		(layer "In11.Cu")
		(net "85_10INCH_IN4_DN")
	)
	(segment
		(start 335.86801 14.496034)
		(end 336.13598 14.11351)
		(width 0.1651)
		(layer "In11.Cu")
		(net "85_10INCH_IN4_DN")
	)
	(segment
		(start 370.567458 14.491716)
		(end 370.949728 14.759686)
		(width 0.1651)
		(layer "In11.Cu")
		(net "85_10INCH_IN4_DN")
	)
	(segment
		(start 375.971562 14.563598)
		(end 376.239786 14.181074)
		(width 0.1651)
		(layer "In11.Cu")
		(net "85_10INCH_IN4_DN")
	)
	(segment
		(start 350.876108 6.759956)
		(end 351.277936 6.186678)
		(width 0.1651)
		(layer "In11.Cu")
		(net "85_10INCH_IN4_DN")
	)
	(segment
		(start 346.52204 14.547342)
		(end 346.904818 14.815312)
		(width 0.1651)
		(layer "In11.Cu")
		(net "85_10INCH_IN4_DN")
	)
	(segment
		(start 340.498176 5.97154)
		(end 341.071708 6.373368)
		(width 0.1651)
		(layer "In11.Cu")
		(net "85_10INCH_IN4_DN")
	)
	(segment
		(start 360.545634 5.980938)
		(end 361.11942 6.382766)
		(width 0.1651)
		(layer "In11.Cu")
		(net "85_10INCH_IN4_DN")
	)
	(segment
		(start 368.560858 5.961888)
		(end 369.13439 6.363716)
		(width 0.1651)
		(layer "In11.Cu")
		(net "85_10INCH_IN4_DN")
	)
	(segment
		(start 374.955816 14.743176)
		(end 375.971562 14.563598)
		(width 0.1651)
		(layer "In11.Cu")
		(net "85_10INCH_IN4_DN")
	)
	(segment
		(start 343.90838 14.620494)
		(end 344.17635 14.238224)
		(width 0.1651)
		(layer "In11.Cu")
		(net "85_10INCH_IN4_DN")
	)
	(segment
		(start 371.965474 14.580108)
		(end 372.233444 14.197838)
		(width 0.1651)
		(layer "In11.Cu")
		(net "85_10INCH_IN4_DN")
	)
	(segment
		(start 381.862584 10.3378)
		(end 382.153414 10.541762)
		(width 0.1651)
		(layer "In11.Cu")
		(net "85_10INCH_IN4_DN")
	)
	(segment
		(start 382.153414 10.541762)
		(end 385.093464 10.541762)
		(width 0.1651)
		(layer "In11.Cu")
		(net "85_10INCH_IN4_DN")
	)
	(segment
		(start 363.9566 14.633956)
		(end 364.22457 14.251686)
		(width 0.1651)
		(layer "In11.Cu")
		(net "85_10INCH_IN4_DN")
	)
	(segment
		(start 347.269816 6.191504)
		(end 348.516702 5.971286)
		(width 0.1651)
		(layer "In11.Cu")
		(net "85_10INCH_IN4_DN")
	)
	(segment
		(start 356.535228 5.974334)
		(end 357.109014 6.376416)
		(width 0.1651)
		(layer "In11.Cu")
		(net "85_10INCH_IN4_DN")
	)
	(segment
		(start 359.298748 6.201156)
		(end 360.545634 5.980938)
		(width 0.1651)
		(layer "In11.Cu")
		(net "85_10INCH_IN4_DN")
	)
	(segment
		(start 334.470248 14.407642)
		(end 334.852264 14.675612)
		(width 0.1651)
		(layer "In11.Cu")
		(net "85_10INCH_IN4_DN")
	)
	(segment
		(start 329.612498 10.225024)
		(end 329.903328 10.515854)
		(width 0.1651)
		(layer "In11.Cu")
		(net "85_10INCH_IN4_DN")
	)
	(segment
		(start 351.921064 14.588236)
		(end 352.189034 14.205966)
		(width 0.1651)
		(layer "In11.Cu")
		(net "85_10INCH_IN4_DN")
	)
	(segment
		(start 343.261696 6.198108)
		(end 344.508582 5.97789)
		(width 0.1651)
		(layer "In11.Cu")
		(net "85_10INCH_IN4_DN")
	)
	(segment
		(start 366.912144 6.755384)
		(end 367.313972 6.182106)
		(width 0.1651)
		(layer "In11.Cu")
		(net "85_10INCH_IN4_DN")
	)
	(segment
		(start 378.585476 14.490446)
		(end 378.967746 14.758416)
		(width 0.1651)
		(layer "In11.Cu")
		(net "85_10INCH_IN4_DN")
	)
	(segment
		(start 370.922042 6.76021)
		(end 371.32387 6.186932)
		(width 0.1651)
		(layer "In11.Cu")
		(net "85_10INCH_IN4_DN")
	)
	(segment
		(start 337.062064 6.369812)
		(end 338.483194 14.428216)
		(width 0.1651)
		(layer "In11.Cu")
		(net "85_10INCH_IN4_DN")
	)
	(segment
		(start 376.239786 14.181074)
		(end 374.93194 6.767322)
		(width 0.1651)
		(layer "In11.Cu")
		(net "85_10INCH_IN4_DN")
	)
	(segment
		(start 352.189034 14.205966)
		(end 350.876108 6.759956)
		(width 0.1651)
		(layer "In11.Cu")
		(net "85_10INCH_IN4_DN")
	)
	(segment
		(start 333.895954 11.152886)
		(end 334.470248 14.407642)
		(width 0.1651)
		(layer "In11.Cu")
		(net "85_10INCH_IN4_DN")
	)
	(segment
		(start 371.32387 6.186932)
		(end 372.570756 5.966714)
		(width 0.1651)
		(layer "In11.Cu")
		(net "85_10INCH_IN4_DN")
	)
	(segment
		(start 346.867988 6.764782)
		(end 347.269816 6.191504)
		(width 0.1651)
		(layer "In11.Cu")
		(net "85_10INCH_IN4_DN")
	)
	(segment
		(start 372.570756 5.966714)
		(end 373.144288 6.368542)
		(width 0.1651)
		(layer "In11.Cu")
		(net "85_10INCH_IN4_DN")
	)
	(segment
		(start 345.082114 6.379718)
		(end 346.52204 14.547342)
		(width 0.1651)
		(layer "In11.Cu")
		(net "85_10INCH_IN4_DN")
	)
	(segment
		(start 334.852264 14.675612)
		(end 335.86801 14.496034)
		(width 0.1651)
		(layer "In11.Cu")
		(net "85_10INCH_IN4_DN")
	)
	(segment
		(start 347.920564 14.635734)
		(end 348.188534 14.253972)
		(width 0.1651)
		(layer "In11.Cu")
		(net "85_10INCH_IN4_DN")
	)
	(segment
		(start 338.864956 14.696186)
		(end 339.880448 14.516354)
		(width 0.1651)
		(layer "In11.Cu")
		(net "85_10INCH_IN4_DN")
	)
	(segment
		(start 336.488532 5.967984)
		(end 337.062064 6.369812)
		(width 0.1651)
		(layer "In11.Cu")
		(net "85_10INCH_IN4_DN")
	)
	(segment
		(start 374.573546 14.475206)
		(end 374.955816 14.743176)
		(width 0.1651)
		(layer "In11.Cu")
		(net "85_10INCH_IN4_DN")
	)
	(segment
		(start 354.886514 6.76783)
		(end 355.288342 6.194552)
		(width 0.1651)
		(layer "In11.Cu")
		(net "85_10INCH_IN4_DN")
	)
	(segment
		(start 355.288342 6.194552)
		(end 356.535228 5.974334)
		(width 0.1651)
		(layer "In11.Cu")
		(net "85_10INCH_IN4_DN")
	)
	(segment
		(start 356.19436 14.184884)
		(end 354.886514 6.76783)
		(width 0.1651)
		(layer "In11.Cu")
		(net "85_10INCH_IN4_DN")
	)
	(segment
		(start 376.580654 5.973572)
		(end 377.154694 6.375654)
		(width 0.1651)
		(layer "In11.Cu")
		(net "85_10INCH_IN4_DN")
	)
	(segment
		(start 362.940854 14.813534)
		(end 363.9566 14.633956)
		(width 0.1651)
		(layer "In11.Cu")
		(net "85_10INCH_IN4_DN")
	)
	(segment
		(start 354.910644 14.746732)
		(end 355.92639 14.567154)
		(width 0.1651)
		(layer "In11.Cu")
		(net "85_10INCH_IN4_DN")
	)
	(segment
		(start 380.593854 5.9944)
		(end 381.16764 6.396736)
		(width 0.1651)
		(layer "In11.Cu")
		(net "85_10INCH_IN4_DN")
	)
	(segment
		(start 367.313972 6.182106)
		(end 368.560858 5.961888)
		(width 0.1651)
		(layer "In11.Cu")
		(net "85_10INCH_IN4_DN")
	)
	(segment
		(start 339.25129 6.191758)
		(end 340.498176 5.97154)
		(width 0.1651)
		(layer "In11.Cu")
		(net "85_10INCH_IN4_DN")
	)
	(segment
		(start 342.892634 14.800072)
		(end 343.90838 14.620494)
		(width 0.1651)
		(layer "In11.Cu")
		(net "85_10INCH_IN4_DN")
	)
	(segment
		(start 379.983492 14.578838)
		(end 380.251462 14.196568)
		(width 0.1651)
		(layer "In11.Cu")
		(net "85_10INCH_IN4_DN")
	)
	(segment
		(start 363.307122 6.195822)
		(end 364.554008 5.975604)
		(width 0.1651)
		(layer "In11.Cu")
		(net "85_10INCH_IN4_DN")
	)
	(segment
		(start 434.060092 -63.70193)
		(end 434.010308 -63.652146)
		(width 0.13208)
		(layer "F.Cu")
		(net "P12V_SSD15_PG_G2")
	)
	(segment
		(start 433.920392 -63.56223)
		(end 432.78933 -63.56223)
		(width 0.13208)
		(layer "F.Cu")
		(net "P12V_SSD15_PG_G2")
	)
	(segment
		(start 434.060092 -64.496442)
		(end 434.060092 -63.70193)
		(width 0.13208)
		(layer "F.Cu")
		(net "P12V_SSD15_PG_G2")
	)
	(segment
		(start 433.432458 -65.124076)
		(end 434.060092 -64.496442)
		(width 0.13208)
		(layer "F.Cu")
		(net "P12V_SSD15_PG_G2")
	)
	(segment
		(start 432.78933 -64.312292)
		(end 432.78933 -65.124076)
		(width 0.13208)
		(layer "F.Cu")
		(net "P12V_SSD15_PG_G2")
	)
	(segment
		(start 432.78933 -65.124076)
		(end 433.432458 -65.124076)
		(width 0.13208)
		(layer "F.Cu")
		(net "P12V_SSD15_PG_G2")
	)
	(segment
		(start 434.010308 -63.652146)
		(end 433.920392 -63.56223)
		(width 0.13208)
		(layer "F.Cu")
		(net "P12V_SSD15_PG_G2")
	)
	(via
		(at 432.78933 -65.124076)
		(size 0.508)
		(drill 0.254)
		(layers "F.Cu" "B.Cu")
		(net "P12V_SSD15_PG_G2")
	)
	(segment
		(start 359.385362 -116.946426)
		(end 359.639362 -117.200426)
		(width 0.13208)
		(layer "F.Cu")
		(net "P3V3_NIC6_PG_G1")
	)
	(segment
		(start 361.417362 -117.943376)
		(end 360.401362 -117.943376)
		(width 0.13208)
		(layer "F.Cu")
		(net "P3V3_NIC6_PG_G1")
	)
	(segment
		(start 359.385362 -116.449348)
		(end 359.385362 -116.946426)
		(width 0.13208)
		(layer "F.Cu")
		(net "P3V3_NIC6_PG_G1")
	)
	(segment
		(start 360.401362 -117.200426)
		(end 360.401362 -117.943376)
		(width 0.13208)
		(layer "F.Cu")
		(net "P3V3_NIC6_PG_G1")
	)
	(segment
		(start 359.639362 -117.200426)
		(end 360.401362 -117.200426)
		(width 0.13208)
		(layer "F.Cu")
		(net "P3V3_NIC6_PG_G1")
	)
	(via
		(at 360.401362 -117.200426)
		(size 0.508)
		(drill 0.254)
		(layers "F.Cu" "B.Cu")
		(net "P3V3_NIC6_PG_G1")
	)
	(segment
		(start 120.473978 -27.815286)
		(end 120.150128 -28.139136)
		(width 0.13208)
		(layer "F.Cu")
		(net "P3V3_SSD4_CO_MODE")
	)
	(segment
		(start 119.57304 -28.139136)
		(end 119.38254 -28.329636)
		(width 0.13208)
		(layer "F.Cu")
		(net "P3V3_SSD4_CO_MODE")
	)
	(segment
		(start 120.150128 -28.139136)
		(end 119.57304 -28.139136)
		(width 0.13208)
		(layer "F.Cu")
		(net "P3V3_SSD4_CO_MODE")
	)
	(segment
		(start 119.457978 -27.406346)
		(end 120.473978 -27.406346)
		(width 0.13208)
		(layer "F.Cu")
		(net "P3V3_SSD4_CO_MODE")
	)
	(segment
		(start 119.38254 -28.329636)
		(end 119.38254 -28.875736)
		(width 0.13208)
		(layer "F.Cu")
		(net "P3V3_SSD4_CO_MODE")
	)
	(segment
		(start 120.473978 -27.406346)
		(end 120.473978 -27.815286)
		(width 0.13208)
		(layer "F.Cu")
		(net "P3V3_SSD4_CO_MODE")
	)
	(via
		(at 120.150128 -28.139136)
		(size 0.508)
		(drill 0.254)
		(layers "F.Cu" "B.Cu")
		(net "P3V3_SSD4_CO_MODE")
	)
	(segment
		(start 273.940524 20.325588)
		(end 274.621498 20.143724)
		(width 0.13462)
		(layer "B.Cu")
		(net "85_5INCH_IN6_DP")
	)
	(segment
		(start 311.933844 20.318476)
		(end 311.25287 20.136612)
		(width 0.13462)
		(layer "B.Cu")
		(net "85_5INCH_IN6_DP")
	)
	(segment
		(start 285.909004 16.74622)
		(end 286.482536 17.148048)
		(width 0.1651)
		(layer "In15.Cu")
		(net "85_5INCH_IN6_DP")
	)
	(segment
		(start 304.707036 16.962882)
		(end 305.953922 16.742664)
		(width 0.1651)
		(layer "In15.Cu")
		(net "85_5INCH_IN6_DP")
	)
	(segment
		(start 279.568402 23.41118)
		(end 279.950672 23.67915)
		(width 0.1651)
		(layer "In15.Cu")
		(net "85_5INCH_IN6_DP")
	)
	(segment
		(start 301.284132 23.13813)
		(end 300.29658 17.540224)
		(width 0.1651)
		(layer "In15.Cu")
		(net "85_5INCH_IN6_DP")
	)
	(segment
		(start 301.015908 23.520654)
		(end 301.284132 23.13813)
		(width 0.1651)
		(layer "In15.Cu")
		(net "85_5INCH_IN6_DP")
	)
	(segment
		(start 293.927276 16.744696)
		(end 294.500808 17.146524)
		(width 0.1651)
		(layer "In15.Cu")
		(net "85_5INCH_IN6_DP")
	)
	(segment
		(start 291.985446 23.720044)
		(end 293.001192 23.540466)
		(width 0.1651)
		(layer "In15.Cu")
		(net "85_5INCH_IN6_DP")
	)
	(segment
		(start 286.482536 17.148048)
		(end 287.598612 23.477982)
		(width 0.1651)
		(layer "In15.Cu")
		(net "85_5INCH_IN6_DP")
	)
	(segment
		(start 287.598612 23.477982)
		(end 287.980882 23.745952)
		(width 0.1651)
		(layer "In15.Cu")
		(net "85_5INCH_IN6_DP")
	)
	(segment
		(start 274.912328 20.434554)
		(end 278.791924 20.434554)
		(width 0.1651)
		(layer "In15.Cu")
		(net "85_5INCH_IN6_DP")
	)
	(segment
		(start 292.68039 16.964914)
		(end 293.927276 16.744696)
		(width 0.1651)
		(layer "In15.Cu")
		(net "85_5INCH_IN6_DP")
	)
	(segment
		(start 280.251916 17.544796)
		(end 280.653744 16.971518)
		(width 0.1651)
		(layer "In15.Cu")
		(net "85_5INCH_IN6_DP")
	)
	(segment
		(start 310.96204 20.427442)
		(end 311.25287 20.136612)
		(width 0.1651)
		(layer "In15.Cu")
		(net "85_5INCH_IN6_DP")
	)
	(segment
		(start 281.901138 16.7513)
		(end 282.474416 17.153382)
		(width 0.1651)
		(layer "In15.Cu")
		(net "85_5INCH_IN6_DP")
	)
	(segment
		(start 297.007534 23.524972)
		(end 297.275504 23.142448)
		(width 0.1651)
		(layer "In15.Cu")
		(net "85_5INCH_IN6_DP")
	)
	(segment
		(start 288.996628 23.566374)
		(end 289.264598 23.184104)
		(width 0.1651)
		(layer "In15.Cu")
		(net "85_5INCH_IN6_DP")
	)
	(segment
		(start 300.29658 17.540224)
		(end 300.698408 16.966692)
		(width 0.1651)
		(layer "In15.Cu")
		(net "85_5INCH_IN6_DP")
	)
	(segment
		(start 284.979618 23.521924)
		(end 285.247588 23.139654)
		(width 0.1651)
		(layer "In15.Cu")
		(net "85_5INCH_IN6_DP")
	)
	(segment
		(start 290.491672 17.147286)
		(end 291.603176 23.452074)
		(width 0.1651)
		(layer "In15.Cu")
		(net "85_5INCH_IN6_DP")
	)
	(segment
		(start 287.980882 23.745952)
		(end 288.996628 23.566374)
		(width 0.1651)
		(layer "In15.Cu")
		(net "85_5INCH_IN6_DP")
	)
	(segment
		(start 288.269426 17.538954)
		(end 288.671254 16.965676)
		(width 0.1651)
		(layer "In15.Cu")
		(net "85_5INCH_IN6_DP")
	)
	(segment
		(start 294.500808 17.146524)
		(end 295.609772 23.43658)
		(width 0.1651)
		(layer "In15.Cu")
		(net "85_5INCH_IN6_DP")
	)
	(segment
		(start 305.0286 23.535894)
		(end 305.296316 23.15464)
		(width 0.1651)
		(layer "In15.Cu")
		(net "85_5INCH_IN6_DP")
	)
	(segment
		(start 300.000162 23.700232)
		(end 301.015908 23.520654)
		(width 0.1651)
		(layer "In15.Cu")
		(net "85_5INCH_IN6_DP")
	)
	(segment
		(start 300.698408 16.966692)
		(end 301.945294 16.746474)
		(width 0.1651)
		(layer "In15.Cu")
		(net "85_5INCH_IN6_DP")
	)
	(segment
		(start 306.527708 17.145)
		(end 307.07076 20.22348)
		(width 0.1651)
		(layer "In15.Cu")
		(net "85_5INCH_IN6_DP")
	)
	(segment
		(start 304.305208 17.536414)
		(end 304.707036 16.962882)
		(width 0.1651)
		(layer "In15.Cu")
		(net "85_5INCH_IN6_DP")
	)
	(segment
		(start 282.474416 17.153382)
		(end 283.581602 23.433532)
		(width 0.1651)
		(layer "In15.Cu")
		(net "85_5INCH_IN6_DP")
	)
	(segment
		(start 307.36159 20.427442)
		(end 310.96204 20.427442)
		(width 0.1651)
		(layer "In15.Cu")
		(net "85_5INCH_IN6_DP")
	)
	(segment
		(start 274.621498 20.143724)
		(end 274.912328 20.434554)
		(width 0.1651)
		(layer "In15.Cu")
		(net "85_5INCH_IN6_DP")
	)
	(segment
		(start 285.247588 23.139654)
		(end 284.26029 17.539716)
		(width 0.1651)
		(layer "In15.Cu")
		(net "85_5INCH_IN6_DP")
	)
	(segment
		(start 283.581602 23.433532)
		(end 283.963872 23.701502)
		(width 0.1651)
		(layer "In15.Cu")
		(net "85_5INCH_IN6_DP")
	)
	(segment
		(start 301.945294 16.746474)
		(end 302.519334 17.148556)
		(width 0.1651)
		(layer "In15.Cu")
		(net "85_5INCH_IN6_DP")
	)
	(segment
		(start 307.07076 20.22348)
		(end 307.36159 20.427442)
		(width 0.1651)
		(layer "In15.Cu")
		(net "85_5INCH_IN6_DP")
	)
	(segment
		(start 289.264598 23.184104)
		(end 288.269426 17.538954)
		(width 0.1651)
		(layer "In15.Cu")
		(net "85_5INCH_IN6_DP")
	)
	(segment
		(start 302.519334 17.148556)
		(end 303.629314 23.447502)
		(width 0.1651)
		(layer "In15.Cu")
		(net "85_5INCH_IN6_DP")
	)
	(segment
		(start 298.509436 17.144238)
		(end 299.618146 23.432262)
		(width 0.1651)
		(layer "In15.Cu")
		(net "85_5INCH_IN6_DP")
	)
	(segment
		(start 279.950672 23.67915)
		(end 280.966418 23.499572)
		(width 0.1651)
		(layer "In15.Cu")
		(net "85_5INCH_IN6_DP")
	)
	(segment
		(start 297.935904 16.74241)
		(end 298.509436 17.144238)
		(width 0.1651)
		(layer "In15.Cu")
		(net "85_5INCH_IN6_DP")
	)
	(segment
		(start 295.609772 23.43658)
		(end 295.991788 23.70455)
		(width 0.1651)
		(layer "In15.Cu")
		(net "85_5INCH_IN6_DP")
	)
	(segment
		(start 295.991788 23.70455)
		(end 297.007534 23.524972)
		(width 0.1651)
		(layer "In15.Cu")
		(net "85_5INCH_IN6_DP")
	)
	(segment
		(start 280.653744 16.971518)
		(end 281.901138 16.7513)
		(width 0.1651)
		(layer "In15.Cu")
		(net "85_5INCH_IN6_DP")
	)
	(segment
		(start 279.087072 20.68195)
		(end 279.568402 23.41118)
		(width 0.1651)
		(layer "In15.Cu")
		(net "85_5INCH_IN6_DP")
	)
	(segment
		(start 289.91814 16.745458)
		(end 290.491672 17.147286)
		(width 0.1651)
		(layer "In15.Cu")
		(net "85_5INCH_IN6_DP")
	)
	(segment
		(start 303.629314 23.447502)
		(end 304.0126 23.715472)
		(width 0.1651)
		(layer "In15.Cu")
		(net "85_5INCH_IN6_DP")
	)
	(segment
		(start 280.966418 23.499572)
		(end 281.234388 23.117302)
		(width 0.1651)
		(layer "In15.Cu")
		(net "85_5INCH_IN6_DP")
	)
	(segment
		(start 305.296316 23.15464)
		(end 304.305208 17.536414)
		(width 0.1651)
		(layer "In15.Cu")
		(net "85_5INCH_IN6_DP")
	)
	(segment
		(start 299.618146 23.432262)
		(end 300.000162 23.700232)
		(width 0.1651)
		(layer "In15.Cu")
		(net "85_5INCH_IN6_DP")
	)
	(segment
		(start 296.28719 17.535906)
		(end 296.689018 16.962628)
		(width 0.1651)
		(layer "In15.Cu")
		(net "85_5INCH_IN6_DP")
	)
	(segment
		(start 284.662118 16.966438)
		(end 285.909004 16.74622)
		(width 0.1651)
		(layer "In15.Cu")
		(net "85_5INCH_IN6_DP")
	)
	(segment
		(start 291.603176 23.452074)
		(end 291.985446 23.720044)
		(width 0.1651)
		(layer "In15.Cu")
		(net "85_5INCH_IN6_DP")
	)
	(segment
		(start 292.278562 17.538192)
		(end 292.68039 16.964914)
		(width 0.1651)
		(layer "In15.Cu")
		(net "85_5INCH_IN6_DP")
	)
	(segment
		(start 305.953922 16.742664)
		(end 306.527708 17.145)
		(width 0.1651)
		(layer "In15.Cu")
		(net "85_5INCH_IN6_DP")
	)
	(segment
		(start 281.234388 23.117302)
		(end 280.251916 17.544796)
		(width 0.1651)
		(layer "In15.Cu")
		(net "85_5INCH_IN6_DP")
	)
	(segment
		(start 278.791924 20.434554)
		(end 279.087072 20.68195)
		(width 0.1651)
		(layer "In15.Cu")
		(net "85_5INCH_IN6_DP")
	)
	(segment
		(start 293.001192 23.540466)
		(end 293.269162 23.157942)
		(width 0.1651)
		(layer "In15.Cu")
		(net "85_5INCH_IN6_DP")
	)
	(segment
		(start 296.689018 16.962628)
		(end 297.935904 16.74241)
		(width 0.1651)
		(layer "In15.Cu")
		(net "85_5INCH_IN6_DP")
	)
	(segment
		(start 297.275504 23.142448)
		(end 296.28719 17.535906)
		(width 0.1651)
		(layer "In15.Cu")
		(net "85_5INCH_IN6_DP")
	)
	(segment
		(start 293.269162 23.157942)
		(end 292.278562 17.538192)
		(width 0.1651)
		(layer "In15.Cu")
		(net "85_5INCH_IN6_DP")
	)
	(segment
		(start 283.963872 23.701502)
		(end 284.979618 23.521924)
		(width 0.1651)
		(layer "In15.Cu")
		(net "85_5INCH_IN6_DP")
	)
	(segment
		(start 284.26029 17.539716)
		(end 284.662118 16.966438)
		(width 0.1651)
		(layer "In15.Cu")
		(net "85_5INCH_IN6_DP")
	)
	(segment
		(start 288.671254 16.965676)
		(end 289.91814 16.745458)
		(width 0.1651)
		(layer "In15.Cu")
		(net "85_5INCH_IN6_DP")
	)
	(segment
		(start 304.0126 23.715472)
		(end 305.0286 23.535894)
		(width 0.1651)
		(layer "In15.Cu")
		(net "85_5INCH_IN6_DP")
	)
	(segment
		(start 370.027454 -67.592956)
		(end 370.027454 -67.228212)
		(width 0.13208)
		(layer "F.Cu")
		(net "P12V_SSD12_CO_DV_DT")
	)
	(segment
		(start 370.027454 -67.228212)
		(end 369.830604 -67.031362)
		(width 0.13208)
		(layer "F.Cu")
		(net "P12V_SSD12_CO_DV_DT")
	)
	(segment
		(start 369.830604 -67.031362)
		(end 369.830604 -66.72199)
		(width 0.13208)
		(layer "F.Cu")
		(net "P12V_SSD12_CO_DV_DT")
	)
	(segment
		(start 369.375436 -68.479162)
		(end 369.375436 -68.244974)
		(width 0.13208)
		(layer "F.Cu")
		(net "P12V_SSD12_CO_DV_DT")
	)
	(segment
		(start 369.375436 -68.244974)
		(end 370.027454 -67.592956)
		(width 0.13208)
		(layer "F.Cu")
		(net "P12V_SSD12_CO_DV_DT")
	)
	(via
		(at 370.027454 -67.592956)
		(size 0.508)
		(drill 0.254)
		(layers "F.Cu" "B.Cu")
		(net "P12V_SSD12_CO_DV_DT")
	)
	(segment
		(start 437.803036 -114.384836)
		(end 437.35244 -114.384836)
		(width 0.13208)
		(layer "F.Cu")
		(net "P3V3_NIC7_CO_DV_DT")
	)
	(segment
		(start 438.4802 -114.407188)
		(end 438.130442 -114.05743)
		(width 0.13208)
		(layer "F.Cu")
		(net "P3V3_NIC7_CO_DV_DT")
	)
	(segment
		(start 438.629552 -115.335304)
		(end 438.4802 -115.185952)
		(width 0.13208)
		(layer "F.Cu")
		(net "P3V3_NIC7_CO_DV_DT")
	)
	(segment
		(start 438.130442 -114.05743)
		(end 437.803036 -114.384836)
		(width 0.13208)
		(layer "F.Cu")
		(net "P3V3_NIC7_CO_DV_DT")
	)
	(segment
		(start 438.9247 -115.335304)
		(end 438.629552 -115.335304)
		(width 0.13208)
		(layer "F.Cu")
		(net "P3V3_NIC7_CO_DV_DT")
	)
	(segment
		(start 438.4802 -115.185952)
		(end 438.4802 -114.407188)
		(width 0.13208)
		(layer "F.Cu")
		(net "P3V3_NIC7_CO_DV_DT")
	)
	(via
		(at 438.130442 -114.05743)
		(size 0.508)
		(drill 0.254)
		(layers "F.Cu" "B.Cu")
		(net "P3V3_NIC7_CO_DV_DT")
	)
	(segment
		(start 403.734524 18.28546)
		(end 404.415498 18.467324)
		(width 0.13462)
		(layer "F.Cu")
		(net "85_5INCH_IN3_DP")
	)
	(segment
		(start 441.727844 18.278348)
		(end 441.04687 18.460212)
		(width 0.13462)
		(layer "F.Cu")
		(net "85_5INCH_IN3_DP")
	)
	(segment
		(start 425.276518 21.799804)
		(end 425.85005 22.201886)
		(width 0.1651)
		(layer "In9.Cu")
		(net "85_5INCH_IN3_DP")
	)
	(segment
		(start 426.509688 15.80134)
		(end 426.777404 15.419324)
		(width 0.1651)
		(layer "In9.Cu")
		(net "85_5INCH_IN3_DP")
	)
	(segment
		(start 413.822134 22.198838)
		(end 415.068004 21.97862)
		(width 0.1651)
		(layer "In9.Cu")
		(net "85_5INCH_IN3_DP")
	)
	(segment
		(start 408.483308 18.176494)
		(end 408.62123 18.292064)
		(width 0.1651)
		(layer "In9.Cu")
		(net "85_5INCH_IN3_DP")
	)
	(segment
		(start 415.068004 21.97862)
		(end 415.470086 21.405088)
		(width 0.1651)
		(layer "In9.Cu")
		(net "85_5INCH_IN3_DP")
	)
	(segment
		(start 437.066436 18.169382)
		(end 440.75604 18.169382)
		(width 0.1651)
		(layer "In9.Cu")
		(net "85_5INCH_IN3_DP")
	)
	(segment
		(start 431.50663 21.403564)
		(end 430.519078 15.80515)
		(width 0.1651)
		(layer "In9.Cu")
		(net "85_5INCH_IN3_DP")
	)
	(segment
		(start 409.808934 22.176486)
		(end 411.054804 21.956268)
		(width 0.1651)
		(layer "In9.Cu")
		(net "85_5INCH_IN3_DP")
	)
	(segment
		(start 434.795422 15.419324)
		(end 435.81193 15.239746)
		(width 0.1651)
		(layer "In9.Cu")
		(net "85_5INCH_IN3_DP")
	)
	(segment
		(start 429.858424 22.197568)
		(end 431.104294 21.97735)
		(width 0.1651)
		(layer "In9.Cu")
		(net "85_5INCH_IN3_DP")
	)
	(segment
		(start 412.141162 15.516606)
		(end 413.248348 21.796756)
		(width 0.1651)
		(layer "In9.Cu")
		(net "85_5INCH_IN3_DP")
	)
	(segment
		(start 419.776402 15.242794)
		(end 420.158418 15.51051)
		(width 0.1651)
		(layer "In9.Cu")
		(net "85_5INCH_IN3_DP")
	)
	(segment
		(start 423.089578 21.997162)
		(end 423.49166 21.423376)
		(width 0.1651)
		(layer "In9.Cu")
		(net "85_5INCH_IN3_DP")
	)
	(segment
		(start 435.81193 15.239746)
		(end 436.194454 15.50797)
		(width 0.1651)
		(layer "In9.Cu")
		(net "85_5INCH_IN3_DP")
	)
	(segment
		(start 433.296568 21.810726)
		(end 433.870354 22.212808)
		(width 0.1651)
		(layer "In9.Cu")
		(net "85_5INCH_IN3_DP")
	)
	(segment
		(start 436.194454 15.50797)
		(end 436.607204 17.847564)
		(width 0.1651)
		(layer "In9.Cu")
		(net "85_5INCH_IN3_DP")
	)
	(segment
		(start 410.74213 15.428214)
		(end 411.759146 15.248636)
		(width 0.1651)
		(layer "In9.Cu")
		(net "85_5INCH_IN3_DP")
	)
	(segment
		(start 421.269922 21.815298)
		(end 421.843708 22.21738)
		(width 0.1651)
		(layer "In9.Cu")
		(net "85_5INCH_IN3_DP")
	)
	(segment
		(start 431.803556 15.243556)
		(end 432.18608 15.511526)
		(width 0.1651)
		(layer "In9.Cu")
		(net "85_5INCH_IN3_DP")
	)
	(segment
		(start 419.487096 21.449538)
		(end 418.491924 15.804388)
		(width 0.1651)
		(layer "In9.Cu")
		(net "85_5INCH_IN3_DP")
	)
	(segment
		(start 427.498002 21.407882)
		(end 426.509688 15.80134)
		(width 0.1651)
		(layer "In9.Cu")
		(net "85_5INCH_IN3_DP")
	)
	(segment
		(start 433.870354 22.212808)
		(end 435.116224 21.99259)
		(width 0.1651)
		(layer "In9.Cu")
		(net "85_5INCH_IN3_DP")
	)
	(segment
		(start 427.09592 21.981668)
		(end 427.498002 21.407882)
		(width 0.1651)
		(layer "In9.Cu")
		(net "85_5INCH_IN3_DP")
	)
	(segment
		(start 432.18608 15.511526)
		(end 433.296568 21.810726)
		(width 0.1651)
		(layer "In9.Cu")
		(net "85_5INCH_IN3_DP")
	)
	(segment
		(start 404.706328 18.176494)
		(end 408.483308 18.176494)
		(width 0.1651)
		(layer "In9.Cu")
		(net "85_5INCH_IN3_DP")
	)
	(segment
		(start 430.786794 15.423134)
		(end 431.803556 15.243556)
		(width 0.1651)
		(layer "In9.Cu")
		(net "85_5INCH_IN3_DP")
	)
	(segment
		(start 435.116224 21.99259)
		(end 435.518306 21.419058)
		(width 0.1651)
		(layer "In9.Cu")
		(net "85_5INCH_IN3_DP")
	)
	(segment
		(start 417.265358 21.841206)
		(end 417.839144 22.243288)
		(width 0.1651)
		(layer "In9.Cu")
		(net "85_5INCH_IN3_DP")
	)
	(segment
		(start 420.158418 15.51051)
		(end 421.269922 21.815298)
		(width 0.1651)
		(layer "In9.Cu")
		(net "85_5INCH_IN3_DP")
	)
	(segment
		(start 425.85005 22.201886)
		(end 427.09592 21.981668)
		(width 0.1651)
		(layer "In9.Cu")
		(net "85_5INCH_IN3_DP")
	)
	(segment
		(start 410.474414 15.81023)
		(end 410.74213 15.428214)
		(width 0.1651)
		(layer "In9.Cu")
		(net "85_5INCH_IN3_DP")
	)
	(segment
		(start 417.839144 22.243288)
		(end 419.085014 22.02307)
		(width 0.1651)
		(layer "In9.Cu")
		(net "85_5INCH_IN3_DP")
	)
	(segment
		(start 404.415498 18.467324)
		(end 404.706328 18.176494)
		(width 0.1651)
		(layer "In9.Cu")
		(net "85_5INCH_IN3_DP")
	)
	(segment
		(start 419.085014 22.02307)
		(end 419.487096 21.449538)
		(width 0.1651)
		(layer "In9.Cu")
		(net "85_5INCH_IN3_DP")
	)
	(segment
		(start 435.518306 21.419058)
		(end 434.527706 15.80134)
		(width 0.1651)
		(layer "In9.Cu")
		(net "85_5INCH_IN3_DP")
	)
	(segment
		(start 415.470086 21.405088)
		(end 414.482788 15.80515)
		(width 0.1651)
		(layer "In9.Cu")
		(net "85_5INCH_IN3_DP")
	)
	(segment
		(start 418.75964 15.422372)
		(end 419.776402 15.242794)
		(width 0.1651)
		(layer "In9.Cu")
		(net "85_5INCH_IN3_DP")
	)
	(segment
		(start 440.75604 18.169382)
		(end 441.04687 18.460212)
		(width 0.1651)
		(layer "In9.Cu")
		(net "85_5INCH_IN3_DP")
	)
	(segment
		(start 418.491924 15.804388)
		(end 418.75964 15.422372)
		(width 0.1651)
		(layer "In9.Cu")
		(net "85_5INCH_IN3_DP")
	)
	(segment
		(start 416.149282 15.511272)
		(end 417.265358 21.841206)
		(width 0.1651)
		(layer "In9.Cu")
		(net "85_5INCH_IN3_DP")
	)
	(segment
		(start 429.284892 21.795486)
		(end 429.858424 22.197568)
		(width 0.1651)
		(layer "In9.Cu")
		(net "85_5INCH_IN3_DP")
	)
	(segment
		(start 434.527706 15.80134)
		(end 434.795422 15.419324)
		(width 0.1651)
		(layer "In9.Cu")
		(net "85_5INCH_IN3_DP")
	)
	(segment
		(start 413.248348 21.796756)
		(end 413.822134 22.198838)
		(width 0.1651)
		(layer "In9.Cu")
		(net "85_5INCH_IN3_DP")
	)
	(segment
		(start 423.49166 21.423376)
		(end 422.50106 15.803626)
		(width 0.1651)
		(layer "In9.Cu")
		(net "85_5INCH_IN3_DP")
	)
	(segment
		(start 409.235148 21.774404)
		(end 409.808934 22.176486)
		(width 0.1651)
		(layer "In9.Cu")
		(net "85_5INCH_IN3_DP")
	)
	(segment
		(start 422.50106 15.803626)
		(end 422.768776 15.42161)
		(width 0.1651)
		(layer "In9.Cu")
		(net "85_5INCH_IN3_DP")
	)
	(segment
		(start 415.767266 15.243556)
		(end 416.149282 15.511272)
		(width 0.1651)
		(layer "In9.Cu")
		(net "85_5INCH_IN3_DP")
	)
	(segment
		(start 427.794166 15.239746)
		(end 428.176182 15.507462)
		(width 0.1651)
		(layer "In9.Cu")
		(net "85_5INCH_IN3_DP")
	)
	(segment
		(start 431.104294 21.97735)
		(end 431.50663 21.403564)
		(width 0.1651)
		(layer "In9.Cu")
		(net "85_5INCH_IN3_DP")
	)
	(segment
		(start 423.785538 15.242032)
		(end 424.167554 15.509748)
		(width 0.1651)
		(layer "In9.Cu")
		(net "85_5INCH_IN3_DP")
	)
	(segment
		(start 426.777404 15.419324)
		(end 427.794166 15.239746)
		(width 0.1651)
		(layer "In9.Cu")
		(net "85_5INCH_IN3_DP")
	)
	(segment
		(start 411.054804 21.956268)
		(end 411.456886 21.382736)
		(width 0.1651)
		(layer "In9.Cu")
		(net "85_5INCH_IN3_DP")
	)
	(segment
		(start 424.167554 15.509748)
		(end 425.276518 21.799804)
		(width 0.1651)
		(layer "In9.Cu")
		(net "85_5INCH_IN3_DP")
	)
	(segment
		(start 436.607204 17.847564)
		(end 437.066436 18.169382)
		(width 0.1651)
		(layer "In9.Cu")
		(net "85_5INCH_IN3_DP")
	)
	(segment
		(start 422.768776 15.42161)
		(end 423.785538 15.242032)
		(width 0.1651)
		(layer "In9.Cu")
		(net "85_5INCH_IN3_DP")
	)
	(segment
		(start 414.482788 15.80515)
		(end 414.750504 15.423134)
		(width 0.1651)
		(layer "In9.Cu")
		(net "85_5INCH_IN3_DP")
	)
	(segment
		(start 408.62123 18.292064)
		(end 409.235148 21.774404)
		(width 0.1651)
		(layer "In9.Cu")
		(net "85_5INCH_IN3_DP")
	)
	(segment
		(start 411.456886 21.382736)
		(end 410.474414 15.81023)
		(width 0.1651)
		(layer "In9.Cu")
		(net "85_5INCH_IN3_DP")
	)
	(segment
		(start 428.176182 15.507462)
		(end 429.284892 21.795486)
		(width 0.1651)
		(layer "In9.Cu")
		(net "85_5INCH_IN3_DP")
	)
	(segment
		(start 414.750504 15.423134)
		(end 415.767266 15.243556)
		(width 0.1651)
		(layer "In9.Cu")
		(net "85_5INCH_IN3_DP")
	)
	(segment
		(start 411.759146 15.248636)
		(end 412.141162 15.516606)
		(width 0.1651)
		(layer "In9.Cu")
		(net "85_5INCH_IN3_DP")
	)
	(segment
		(start 421.843708 22.21738)
		(end 423.089578 21.997162)
		(width 0.1651)
		(layer "In9.Cu")
		(net "85_5INCH_IN3_DP")
	)
	(segment
		(start 430.519078 15.80515)
		(end 430.786794 15.423134)
		(width 0.1651)
		(layer "In9.Cu")
		(net "85_5INCH_IN3_DP")
	)
	(segment
		(start 447.830448 -66.72199)
		(end 447.830448 -67.031362)
		(width 0.13208)
		(layer "F.Cu")
		(net "P12V_SSD15_CO_DV_DT")
	)
	(segment
		(start 448.027298 -67.228212)
		(end 448.027298 -67.592956)
		(width 0.13208)
		(layer "F.Cu")
		(net "P12V_SSD15_CO_DV_DT")
	)
	(segment
		(start 448.027298 -67.592956)
		(end 447.37528 -68.244974)
		(width 0.13208)
		(layer "F.Cu")
		(net "P12V_SSD15_CO_DV_DT")
	)
	(segment
		(start 447.37528 -68.244974)
		(end 447.37528 -68.479162)
		(width 0.13208)
		(layer "F.Cu")
		(net "P12V_SSD15_CO_DV_DT")
	)
	(segment
		(start 447.830448 -67.031362)
		(end 448.027298 -67.228212)
		(width 0.13208)
		(layer "F.Cu")
		(net "P12V_SSD15_CO_DV_DT")
	)
	(via
		(at 448.027298 -67.592956)
		(size 0.508)
		(drill 0.254)
		(layers "F.Cu" "B.Cu")
		(net "P12V_SSD15_CO_DV_DT")
	)
	(segment
		(start 132.289042 -113.01603)
		(end 132.289042 -112.421162)
		(width 0.13208)
		(layer "F.Cu")
		(net "P3V3_NIC2_CO_MODE")
	)
	(segment
		(start 131.27863 -111.777526)
		(end 132.29463 -111.777526)
		(width 0.13208)
		(layer "F.Cu")
		(net "P3V3_NIC2_CO_MODE")
	)
	(segment
		(start 132.132832 -113.17224)
		(end 132.289042 -113.01603)
		(width 0.13208)
		(layer "F.Cu")
		(net "P3V3_NIC2_CO_MODE")
	)
	(segment
		(start 132.132832 -113.933478)
		(end 132.132832 -113.17224)
		(width 0.13208)
		(layer "F.Cu")
		(net "P3V3_NIC2_CO_MODE")
	)
	(segment
		(start 132.29463 -112.415574)
		(end 132.29463 -111.777526)
		(width 0.13208)
		(layer "F.Cu")
		(net "P3V3_NIC2_CO_MODE")
	)
	(segment
		(start 132.289042 -112.421162)
		(end 132.29463 -112.415574)
		(width 0.13208)
		(layer "F.Cu")
		(net "P3V3_NIC2_CO_MODE")
	)
	(via
		(at 132.289042 -112.421162)
		(size 0.508)
		(drill 0.254)
		(layers "F.Cu" "B.Cu")
		(net "P3V3_NIC2_CO_MODE")
	)
	(segment
		(start 325.561198 -116.525548)
		(end 325.370698 -116.335048)
		(width 0.13208)
		(layer "F.Cu")
		(net "P3V3_NIC5_CO_MODE")
	)
	(segment
		(start 325.370698 -116.335048)
		(end 324.824598 -116.335048)
		(width 0.13208)
		(layer "F.Cu")
		(net "P3V3_NIC5_CO_MODE")
	)
	(segment
		(start 325.885048 -117.426486)
		(end 325.561198 -117.102636)
		(width 0.13208)
		(layer "F.Cu")
		(net "P3V3_NIC5_CO_MODE")
	)
	(segment
		(start 326.293988 -117.426486)
		(end 325.885048 -117.426486)
		(width 0.13208)
		(layer "F.Cu")
		(net "P3V3_NIC5_CO_MODE")
	)
	(segment
		(start 326.293988 -116.410486)
		(end 326.293988 -117.426486)
		(width 0.13208)
		(layer "F.Cu")
		(net "P3V3_NIC5_CO_MODE")
	)
	(segment
		(start 325.561198 -117.102636)
		(end 325.561198 -116.525548)
		(width 0.13208)
		(layer "F.Cu")
		(net "P3V3_NIC5_CO_MODE")
	)
	(via
		(at 325.561198 -117.102636)
		(size 0.508)
		(drill 0.254)
		(layers "F.Cu" "B.Cu")
		(net "P3V3_NIC5_CO_MODE")
	)
	(segment
		(start 196.38264 -31.274004)
		(end 196.088762 -31.567882)
		(width 0.13208)
		(layer "F.Cu")
		(net "P3V3_SSD7_CO_DV_DT")
	)
	(segment
		(start 196.088762 -31.567882)
		(end 195.480686 -31.567882)
		(width 0.13208)
		(layer "F.Cu")
		(net "P3V3_SSD7_CO_DV_DT")
	)
	(segment
		(start 195.432172 -32.447992)
		(end 195.488814 -32.39135)
		(width 0.13208)
		(layer "F.Cu")
		(net "P3V3_SSD7_CO_DV_DT")
	)
	(segment
		(start 195.488814 -32.39135)
		(end 195.488814 -31.57601)
		(width 0.13208)
		(layer "F.Cu")
		(net "P3V3_SSD7_CO_DV_DT")
	)
	(segment
		(start 196.38264 -30.875732)
		(end 196.38264 -31.274004)
		(width 0.13208)
		(layer "F.Cu")
		(net "P3V3_SSD7_CO_DV_DT")
	)
	(segment
		(start 195.488814 -31.57601)
		(end 195.480686 -31.567882)
		(width 0.13208)
		(layer "F.Cu")
		(net "P3V3_SSD7_CO_DV_DT")
	)
	(via
		(at 195.480686 -31.567882)
		(size 0.508)
		(drill 0.254)
		(layers "F.Cu" "B.Cu")
		(net "P3V3_SSD7_CO_DV_DT")
	)
	(segment
		(start 446.753234 -67.847972)
		(end 446.753234 -67.537584)
		(width 0.13208)
		(layer "F.Cu")
		(net "P12V_SSD15_CO_EN")
	)
	(segment
		(start 446.753234 -67.537584)
		(end 446.753234 -67.077844)
		(width 0.13208)
		(layer "F.Cu")
		(net "P12V_SSD15_CO_EN")
	)
	(segment
		(start 446.875408 -67.970146)
		(end 446.753234 -67.847972)
		(width 0.13208)
		(layer "F.Cu")
		(net "P12V_SSD15_CO_EN")
	)
	(segment
		(start 446.875408 -68.479162)
		(end 446.875408 -67.970146)
		(width 0.13208)
		(layer "F.Cu")
		(net "P12V_SSD15_CO_EN")
	)
	(segment
		(start 446.753234 -67.077844)
		(end 446.814448 -67.01663)
		(width 0.13208)
		(layer "F.Cu")
		(net "P12V_SSD15_CO_EN")
	)
	(segment
		(start 446.814448 -67.01663)
		(end 446.814448 -66.72199)
		(width 0.13208)
		(layer "F.Cu")
		(net "P12V_SSD15_CO_EN")
	)
	(via
		(at 446.753234 -67.537584)
		(size 0.508)
		(drill 0.254)
		(layers "F.Cu" "B.Cu")
		(net "P12V_SSD15_CO_EN")
	)
	(segment
		(start 243.974112 -113.917476)
		(end 243.793264 -114.098324)
		(width 0.13208)
		(layer "F.Cu")
		(net "P3V3_NIC4_PG_G2")
	)
	(segment
		(start 244.543326 -115.411504)
		(end 244.543326 -114.660426)
		(width 0.13208)
		(layer "F.Cu")
		(net "P3V3_NIC4_PG_G2")
	)
	(segment
		(start 244.555264 -114.648488)
		(end 244.555264 -113.917476)
		(width 0.13208)
		(layer "F.Cu")
		(net "P3V3_NIC4_PG_G2")
	)
	(segment
		(start 243.793264 -114.098324)
		(end 243.793264 -115.411504)
		(width 0.13208)
		(layer "F.Cu")
		(net "P3V3_NIC4_PG_G2")
	)
	(segment
		(start 244.555264 -113.917476)
		(end 243.974112 -113.917476)
		(width 0.13208)
		(layer "F.Cu")
		(net "P3V3_NIC4_PG_G2")
	)
	(segment
		(start 244.543326 -114.660426)
		(end 244.555264 -114.648488)
		(width 0.13208)
		(layer "F.Cu")
		(net "P3V3_NIC4_PG_G2")
	)
	(via
		(at 244.543326 -114.660426)
		(size 0.508)
		(drill 0.254)
		(layers "F.Cu" "B.Cu")
		(net "P3V3_NIC4_PG_G2")
	)
	(segment
		(start 145.382488 -30.875732)
		(end 145.382488 -31.537402)
		(width 0.13208)
		(layer "F.Cu")
		(net "P3V3_SSD5_CO_GATE")
	)
	(segment
		(start 146.043142 -32.006032)
		(end 145.972276 -32.076898)
		(width 0.13208)
		(layer "F.Cu")
		(net "P3V3_SSD5_CO_GATE")
	)
	(segment
		(start 145.382488 -31.537402)
		(end 145.509488 -31.664402)
		(width 0.13208)
		(layer "F.Cu")
		(net "P3V3_SSD5_CO_GATE")
	)
	(segment
		(start 145.509488 -31.664402)
		(end 146.043142 -31.664402)
		(width 0.13208)
		(layer "F.Cu")
		(net "P3V3_SSD5_CO_GATE")
	)
	(segment
		(start 146.043142 -31.664402)
		(end 146.043142 -32.006032)
		(width 0.13208)
		(layer "F.Cu")
		(net "P3V3_SSD5_CO_GATE")
	)
	(segment
		(start 145.972276 -32.076898)
		(end 145.972276 -32.447992)
		(width 0.13208)
		(layer "F.Cu")
		(net "P3V3_SSD5_CO_GATE")
	)
	(via
		(at 146.043142 -31.664402)
		(size 0.508)
		(drill 0.254)
		(layers "F.Cu" "B.Cu")
		(net "P3V3_SSD5_CO_GATE")
	)
	(segment
		(start 237.302294 15.077948)
		(end 237.520226 14.767306)
		(width 0.13462)
		(layer "F.Cu")
		(net "85_5INCH_TOP_DP")
	)
	(segment
		(start 241.143282 14.7701)
		(end 242.100608 14.60119)
		(width 0.13462)
		(layer "F.Cu")
		(net "85_5INCH_TOP_DP")
	)
	(segment
		(start 223.623632 22.15769)
		(end 223.972374 21.660104)
		(width 0.13462)
		(layer "F.Cu")
		(net "85_5INCH_TOP_DP")
	)
	(segment
		(start 234.852972 14.58341)
		(end 235.164122 14.801596)
		(width 0.13462)
		(layer "F.Cu")
		(net "85_5INCH_TOP_DP")
	)
	(segment
		(start 241.732562 22.135338)
		(end 242.08105 21.637244)
		(width 0.13462)
		(layer "F.Cu")
		(net "85_5INCH_TOP_DP")
	)
	(segment
		(start 238.788956 14.816328)
		(end 240.056162 21.99513)
		(width 0.13462)
		(layer "F.Cu")
		(net "85_5INCH_TOP_DP")
	)
	(segment
		(start 234.54233 22.446488)
		(end 234.890818 21.94814)
		(width 0.13462)
		(layer "F.Cu")
		(net "85_5INCH_TOP_DP")
	)
	(segment
		(start 238.477298 14.598142)
		(end 238.788956 14.816328)
		(width 0.13462)
		(layer "F.Cu")
		(net "85_5INCH_TOP_DP")
	)
	(segment
		(start 222.443802 22.366224)
		(end 223.623632 22.15769)
		(width 0.13462)
		(layer "F.Cu")
		(net "85_5INCH_TOP_DP")
	)
	(segment
		(start 236.429804 21.983192)
		(end 236.928152 22.33168)
		(width 0.13462)
		(layer "F.Cu")
		(net "85_5INCH_TOP_DP")
	)
	(segment
		(start 234.890818 21.94814)
		(end 233.67746 15.064486)
		(width 0.13462)
		(layer "F.Cu")
		(net "85_5INCH_TOP_DP")
	)
	(segment
		(start 242.95608 17.903952)
		(end 243.267738 18.165572)
		(width 0.13462)
		(layer "F.Cu")
		(net "85_5INCH_TOP_DP")
	)
	(segment
		(start 230.27513 14.763496)
		(end 231.232202 14.594586)
		(width 0.13462)
		(layer "F.Cu")
		(net "85_5INCH_TOP_DP")
	)
	(segment
		(start 223.972374 21.660104)
		(end 222.813372 15.08506)
		(width 0.13462)
		(layer "F.Cu")
		(net "85_5INCH_TOP_DP")
	)
	(segment
		(start 218.25839 18.172684)
		(end 219.406724 17.9705)
		(width 0.13462)
		(layer "F.Cu")
		(net "85_5INCH_TOP_DP")
	)
	(segment
		(start 219.40901 14.775688)
		(end 220.365828 14.607032)
		(width 0.13462)
		(layer "F.Cu")
		(net "85_5INCH_TOP_DP")
	)
	(segment
		(start 243.267738 18.165572)
		(end 247.291098 18.165572)
		(width 0.13462)
		(layer "F.Cu")
		(net "85_5INCH_TOP_DP")
	)
	(segment
		(start 247.403874 18.278348)
		(end 247.595644 18.278348)
		(width 0.13462)
		(layer "F.Cu")
		(net "85_5INCH_TOP_DP")
	)
	(segment
		(start 227.6094 14.59611)
		(end 227.920804 14.814296)
		(width 0.13462)
		(layer "F.Cu")
		(net "85_5INCH_TOP_DP")
	)
	(segment
		(start 229.210616 22.124416)
		(end 229.70744 22.47265)
		(width 0.13462)
		(layer "F.Cu")
		(net "85_5INCH_TOP_DP")
	)
	(segment
		(start 225.56724 22.008338)
		(end 226.064572 22.356318)
		(width 0.13462)
		(layer "F.Cu")
		(net "85_5INCH_TOP_DP")
	)
	(segment
		(start 223.988376 14.604492)
		(end 224.29978 14.822678)
		(width 0.13462)
		(layer "F.Cu")
		(net "85_5INCH_TOP_DP")
	)
	(segment
		(start 240.056162 21.99513)
		(end 240.552732 22.343364)
		(width 0.13462)
		(layer "F.Cu")
		(net "85_5INCH_TOP_DP")
	)
	(segment
		(start 231.543352 14.812772)
		(end 232.864406 22.305518)
		(width 0.13462)
		(layer "F.Cu")
		(net "85_5INCH_TOP_DP")
	)
	(segment
		(start 247.291098 18.165572)
		(end 247.403874 18.278348)
		(width 0.13462)
		(layer "F.Cu")
		(net "85_5INCH_TOP_DP")
	)
	(segment
		(start 237.520226 14.767306)
		(end 238.477298 14.598142)
		(width 0.13462)
		(layer "F.Cu")
		(net "85_5INCH_TOP_DP")
	)
	(segment
		(start 214.631524 18.28546)
		(end 214.823294 18.28546)
		(width 0.13462)
		(layer "F.Cu")
		(net "85_5INCH_TOP_DP")
	)
	(segment
		(start 222.813372 15.08506)
		(end 223.031304 14.773148)
		(width 0.13462)
		(layer "F.Cu")
		(net "85_5INCH_TOP_DP")
	)
	(segment
		(start 229.70744 22.47265)
		(end 230.887524 22.264624)
		(width 0.13462)
		(layer "F.Cu")
		(net "85_5INCH_TOP_DP")
	)
	(segment
		(start 240.552732 22.343364)
		(end 241.732562 22.135338)
		(width 0.13462)
		(layer "F.Cu")
		(net "85_5INCH_TOP_DP")
	)
	(segment
		(start 219.191078 15.088108)
		(end 219.40901 14.775688)
		(width 0.13462)
		(layer "F.Cu")
		(net "85_5INCH_TOP_DP")
	)
	(segment
		(start 214.823294 18.28546)
		(end 214.93607 18.172684)
		(width 0.13462)
		(layer "F.Cu")
		(net "85_5INCH_TOP_DP")
	)
	(segment
		(start 223.031304 14.773148)
		(end 223.988376 14.604492)
		(width 0.13462)
		(layer "F.Cu")
		(net "85_5INCH_TOP_DP")
	)
	(segment
		(start 227.593144 21.650198)
		(end 226.434396 15.076678)
		(width 0.13462)
		(layer "F.Cu")
		(net "85_5INCH_TOP_DP")
	)
	(segment
		(start 219.64015 17.637506)
		(end 219.191078 15.088108)
		(width 0.13462)
		(layer "F.Cu")
		(net "85_5INCH_TOP_DP")
	)
	(segment
		(start 233.67746 15.064486)
		(end 233.8959 14.752574)
		(width 0.13462)
		(layer "F.Cu")
		(net "85_5INCH_TOP_DP")
	)
	(segment
		(start 220.677486 14.825218)
		(end 221.945962 22.01799)
		(width 0.13462)
		(layer "F.Cu")
		(net "85_5INCH_TOP_DP")
	)
	(segment
		(start 233.3625 22.654514)
		(end 234.54233 22.446488)
		(width 0.13462)
		(layer "F.Cu")
		(net "85_5INCH_TOP_DP")
	)
	(segment
		(start 220.365828 14.607032)
		(end 220.677486 14.825218)
		(width 0.13462)
		(layer "F.Cu")
		(net "85_5INCH_TOP_DP")
	)
	(segment
		(start 242.08105 21.637244)
		(end 240.92535 15.08125)
		(width 0.13462)
		(layer "F.Cu")
		(net "85_5INCH_TOP_DP")
	)
	(segment
		(start 219.406724 17.9705)
		(end 219.64015 17.637506)
		(width 0.13462)
		(layer "F.Cu")
		(net "85_5INCH_TOP_DP")
	)
	(segment
		(start 242.412266 14.819376)
		(end 242.95608 17.903952)
		(width 0.13462)
		(layer "F.Cu")
		(net "85_5INCH_TOP_DP")
	)
	(segment
		(start 240.92535 15.08125)
		(end 241.143282 14.7701)
		(width 0.13462)
		(layer "F.Cu")
		(net "85_5INCH_TOP_DP")
	)
	(segment
		(start 224.29978 14.822678)
		(end 225.56724 22.008338)
		(width 0.13462)
		(layer "F.Cu")
		(net "85_5INCH_TOP_DP")
	)
	(segment
		(start 227.920804 14.814296)
		(end 229.210616 22.124416)
		(width 0.13462)
		(layer "F.Cu")
		(net "85_5INCH_TOP_DP")
	)
	(segment
		(start 231.236012 21.766276)
		(end 230.05669 15.075408)
		(width 0.13462)
		(layer "F.Cu")
		(net "85_5INCH_TOP_DP")
	)
	(segment
		(start 230.05669 15.075408)
		(end 230.27513 14.763496)
		(width 0.13462)
		(layer "F.Cu")
		(net "85_5INCH_TOP_DP")
	)
	(segment
		(start 226.064572 22.356318)
		(end 227.244402 22.147784)
		(width 0.13462)
		(layer "F.Cu")
		(net "85_5INCH_TOP_DP")
	)
	(segment
		(start 236.928152 22.33168)
		(end 238.107982 22.1234)
		(width 0.13462)
		(layer "F.Cu")
		(net "85_5INCH_TOP_DP")
	)
	(segment
		(start 232.864406 22.305518)
		(end 233.3625 22.654514)
		(width 0.13462)
		(layer "F.Cu")
		(net "85_5INCH_TOP_DP")
	)
	(segment
		(start 226.652328 14.764766)
		(end 227.6094 14.59611)
		(width 0.13462)
		(layer "F.Cu")
		(net "85_5INCH_TOP_DP")
	)
	(segment
		(start 221.945962 22.01799)
		(end 222.443802 22.366224)
		(width 0.13462)
		(layer "F.Cu")
		(net "85_5INCH_TOP_DP")
	)
	(segment
		(start 230.887524 22.264624)
		(end 231.236012 21.766276)
		(width 0.13462)
		(layer "F.Cu")
		(net "85_5INCH_TOP_DP")
	)
	(segment
		(start 238.107982 22.1234)
		(end 238.456724 21.625814)
		(width 0.13462)
		(layer "F.Cu")
		(net "85_5INCH_TOP_DP")
	)
	(segment
		(start 235.164122 14.801596)
		(end 236.429804 21.983192)
		(width 0.13462)
		(layer "F.Cu")
		(net "85_5INCH_TOP_DP")
	)
	(segment
		(start 242.100608 14.60119)
		(end 242.412266 14.819376)
		(width 0.13462)
		(layer "F.Cu")
		(net "85_5INCH_TOP_DP")
	)
	(segment
		(start 233.8959 14.752574)
		(end 234.852972 14.58341)
		(width 0.13462)
		(layer "F.Cu")
		(net "85_5INCH_TOP_DP")
	)
	(segment
		(start 226.434396 15.076678)
		(end 226.652328 14.764766)
		(width 0.13462)
		(layer "F.Cu")
		(net "85_5INCH_TOP_DP")
	)
	(segment
		(start 238.456724 21.625814)
		(end 237.302294 15.077948)
		(width 0.13462)
		(layer "F.Cu")
		(net "85_5INCH_TOP_DP")
	)
	(segment
		(start 231.232202 14.594586)
		(end 231.543352 14.812772)
		(width 0.13462)
		(layer "F.Cu")
		(net "85_5INCH_TOP_DP")
	)
	(segment
		(start 214.93607 18.172684)
		(end 218.25839 18.172684)
		(width 0.13462)
		(layer "F.Cu")
		(net "85_5INCH_TOP_DP")
	)
	(segment
		(start 227.244402 22.147784)
		(end 227.593144 21.650198)
		(width 0.13462)
		(layer "F.Cu")
		(net "85_5INCH_TOP_DP")
	)
	(segment
		(start 360.135424 -113.898426)
		(end 360.147362 -113.886488)
		(width 0.13208)
		(layer "F.Cu")
		(net "P3V3_NIC6_PG_G2")
	)
	(segment
		(start 359.385362 -113.336324)
		(end 359.385362 -114.649504)
		(width 0.13208)
		(layer "F.Cu")
		(net "P3V3_NIC6_PG_G2")
	)
	(segment
		(start 360.147362 -113.886488)
		(end 360.147362 -113.155476)
		(width 0.13208)
		(layer "F.Cu")
		(net "P3V3_NIC6_PG_G2")
	)
	(segment
		(start 359.56621 -113.155476)
		(end 359.385362 -113.336324)
		(width 0.13208)
		(layer "F.Cu")
		(net "P3V3_NIC6_PG_G2")
	)
	(segment
		(start 360.147362 -113.155476)
		(end 359.56621 -113.155476)
		(width 0.13208)
		(layer "F.Cu")
		(net "P3V3_NIC6_PG_G2")
	)
	(segment
		(start 360.135424 -114.649504)
		(end 360.135424 -113.898426)
		(width 0.13208)
		(layer "F.Cu")
		(net "P3V3_NIC6_PG_G2")
	)
	(via
		(at 360.135424 -113.898426)
		(size 0.508)
		(drill 0.254)
		(layers "F.Cu" "B.Cu")
		(net "P3V3_NIC6_PG_G2")
	)
	(segment
		(start 441.727844 20.818348)
		(end 441.04687 21.000212)
		(width 0.13462)
		(layer "B.Cu")
		(net "85_5INCH_IN5_DN")
	)
	(segment
		(start 403.734524 20.82546)
		(end 404.415498 21.007324)
		(width 0.13462)
		(layer "B.Cu")
		(net "85_5INCH_IN5_DN")
	)
	(segment
		(start 404.706328 20.716494)
		(end 408.483308 20.716494)
		(width 0.1651)
		(layer "In13.Cu")
		(net "85_5INCH_IN5_DN")
	)
	(segment
		(start 435.388512 23.220934)
		(end 434.397404 17.602454)
		(width 0.1651)
		(layer "In13.Cu")
		(net "85_5INCH_IN5_DN")
	)
	(segment
		(start 435.681628 17.04086)
		(end 436.064152 17.309084)
		(width 0.1651)
		(layer "In13.Cu")
		(net "85_5INCH_IN5_DN")
	)
	(segment
		(start 415.339784 23.205948)
		(end 414.352486 17.60601)
		(width 0.1651)
		(layer "In13.Cu")
		(net "85_5INCH_IN5_DN")
	)
	(segment
		(start 427.663864 17.040606)
		(end 428.04588 17.308322)
		(width 0.1651)
		(layer "In13.Cu")
		(net "85_5INCH_IN5_DN")
	)
	(segment
		(start 422.959276 23.798022)
		(end 423.361358 23.223982)
		(width 0.1651)
		(layer "In13.Cu")
		(net "85_5INCH_IN5_DN")
	)
	(segment
		(start 418.629338 17.223232)
		(end 419.6461 17.043654)
		(width 0.1651)
		(layer "In13.Cu")
		(net "85_5INCH_IN5_DN")
	)
	(segment
		(start 433.165758 23.611586)
		(end 433.74056 24.013668)
		(width 0.1651)
		(layer "In13.Cu")
		(net "85_5INCH_IN5_DN")
	)
	(segment
		(start 422.638474 17.22247)
		(end 423.655236 17.042892)
		(width 0.1651)
		(layer "In13.Cu")
		(net "85_5INCH_IN5_DN")
	)
	(segment
		(start 408.483308 20.716494)
		(end 408.62123 20.832064)
		(width 0.1651)
		(layer "In13.Cu")
		(net "85_5INCH_IN5_DN")
	)
	(segment
		(start 432.055778 17.31264)
		(end 433.165758 23.611586)
		(width 0.1651)
		(layer "In13.Cu")
		(net "85_5INCH_IN5_DN")
	)
	(segment
		(start 423.655236 17.042892)
		(end 424.037252 17.310608)
		(width 0.1651)
		(layer "In13.Cu")
		(net "85_5INCH_IN5_DN")
	)
	(segment
		(start 434.98643 23.79345)
		(end 435.388512 23.220934)
		(width 0.1651)
		(layer "In13.Cu")
		(net "85_5INCH_IN5_DN")
	)
	(segment
		(start 431.673254 17.04467)
		(end 432.055778 17.31264)
		(width 0.1651)
		(layer "In13.Cu")
		(net "85_5INCH_IN5_DN")
	)
	(segment
		(start 434.66512 17.220438)
		(end 435.681628 17.04086)
		(width 0.1651)
		(layer "In13.Cu")
		(net "85_5INCH_IN5_DN")
	)
	(segment
		(start 427.3677 23.208488)
		(end 426.379386 17.6022)
		(width 0.1651)
		(layer "In13.Cu")
		(net "85_5INCH_IN5_DN")
	)
	(segment
		(start 410.924502 23.757128)
		(end 411.326584 23.183596)
		(width 0.1651)
		(layer "In13.Cu")
		(net "85_5INCH_IN5_DN")
	)
	(segment
		(start 417.135056 23.642066)
		(end 417.708842 24.044148)
		(width 0.1651)
		(layer "In13.Cu")
		(net "85_5INCH_IN5_DN")
	)
	(segment
		(start 412.01086 17.317466)
		(end 413.118046 23.597616)
		(width 0.1651)
		(layer "In13.Cu")
		(net "85_5INCH_IN5_DN")
	)
	(segment
		(start 409.678632 23.977346)
		(end 410.924502 23.757128)
		(width 0.1651)
		(layer "In13.Cu")
		(net "85_5INCH_IN5_DN")
	)
	(segment
		(start 420.028116 17.31137)
		(end 421.13962 23.616158)
		(width 0.1651)
		(layer "In13.Cu")
		(net "85_5INCH_IN5_DN")
	)
	(segment
		(start 411.326584 23.183596)
		(end 410.344112 17.61109)
		(width 0.1651)
		(layer "In13.Cu")
		(net "85_5INCH_IN5_DN")
	)
	(segment
		(start 414.352486 17.60601)
		(end 414.620202 17.223994)
		(width 0.1651)
		(layer "In13.Cu")
		(net "85_5INCH_IN5_DN")
	)
	(segment
		(start 437.066436 20.709382)
		(end 440.75604 20.709382)
		(width 0.1651)
		(layer "In13.Cu")
		(net "85_5INCH_IN5_DN")
	)
	(segment
		(start 430.973992 23.77821)
		(end 431.376328 23.204424)
		(width 0.1651)
		(layer "In13.Cu")
		(net "85_5INCH_IN5_DN")
	)
	(segment
		(start 414.620202 17.223994)
		(end 415.636964 17.044416)
		(width 0.1651)
		(layer "In13.Cu")
		(net "85_5INCH_IN5_DN")
	)
	(segment
		(start 425.719748 24.002746)
		(end 426.965618 23.782528)
		(width 0.1651)
		(layer "In13.Cu")
		(net "85_5INCH_IN5_DN")
	)
	(segment
		(start 426.379386 17.6022)
		(end 426.647102 17.220184)
		(width 0.1651)
		(layer "In13.Cu")
		(net "85_5INCH_IN5_DN")
	)
	(segment
		(start 419.6461 17.043654)
		(end 420.028116 17.31137)
		(width 0.1651)
		(layer "In13.Cu")
		(net "85_5INCH_IN5_DN")
	)
	(segment
		(start 419.356794 23.250398)
		(end 418.361622 17.605248)
		(width 0.1651)
		(layer "In13.Cu")
		(net "85_5INCH_IN5_DN")
	)
	(segment
		(start 436.607204 20.387564)
		(end 437.066436 20.709382)
		(width 0.1651)
		(layer "In13.Cu")
		(net "85_5INCH_IN5_DN")
	)
	(segment
		(start 408.62123 20.832064)
		(end 409.104846 23.575264)
		(width 0.1651)
		(layer "In13.Cu")
		(net "85_5INCH_IN5_DN")
	)
	(segment
		(start 415.636964 17.044416)
		(end 416.01898 17.312132)
		(width 0.1651)
		(layer "In13.Cu")
		(net "85_5INCH_IN5_DN")
	)
	(segment
		(start 413.691832 23.999698)
		(end 414.937702 23.77948)
		(width 0.1651)
		(layer "In13.Cu")
		(net "85_5INCH_IN5_DN")
	)
	(segment
		(start 418.361622 17.605248)
		(end 418.629338 17.223232)
		(width 0.1651)
		(layer "In13.Cu")
		(net "85_5INCH_IN5_DN")
	)
	(segment
		(start 431.376328 23.204424)
		(end 430.388776 17.606264)
		(width 0.1651)
		(layer "In13.Cu")
		(net "85_5INCH_IN5_DN")
	)
	(segment
		(start 424.037252 17.310608)
		(end 425.146216 23.60041)
		(width 0.1651)
		(layer "In13.Cu")
		(net "85_5INCH_IN5_DN")
	)
	(segment
		(start 421.13962 23.616158)
		(end 421.713406 24.01824)
		(width 0.1651)
		(layer "In13.Cu")
		(net "85_5INCH_IN5_DN")
	)
	(segment
		(start 413.118046 23.597616)
		(end 413.691832 23.999698)
		(width 0.1651)
		(layer "In13.Cu")
		(net "85_5INCH_IN5_DN")
	)
	(segment
		(start 422.370758 17.604486)
		(end 422.638474 17.22247)
		(width 0.1651)
		(layer "In13.Cu")
		(net "85_5INCH_IN5_DN")
	)
	(segment
		(start 434.397404 17.602454)
		(end 434.66512 17.220438)
		(width 0.1651)
		(layer "In13.Cu")
		(net "85_5INCH_IN5_DN")
	)
	(segment
		(start 433.74056 24.013668)
		(end 434.98643 23.79345)
		(width 0.1651)
		(layer "In13.Cu")
		(net "85_5INCH_IN5_DN")
	)
	(segment
		(start 429.728122 23.998428)
		(end 430.973992 23.77821)
		(width 0.1651)
		(layer "In13.Cu")
		(net "85_5INCH_IN5_DN")
	)
	(segment
		(start 421.713406 24.01824)
		(end 422.959276 23.798022)
		(width 0.1651)
		(layer "In13.Cu")
		(net "85_5INCH_IN5_DN")
	)
	(segment
		(start 410.344112 17.61109)
		(end 410.611828 17.229074)
		(width 0.1651)
		(layer "In13.Cu")
		(net "85_5INCH_IN5_DN")
	)
	(segment
		(start 414.937702 23.77948)
		(end 415.339784 23.205948)
		(width 0.1651)
		(layer "In13.Cu")
		(net "85_5INCH_IN5_DN")
	)
	(segment
		(start 416.01898 17.312132)
		(end 417.135056 23.642066)
		(width 0.1651)
		(layer "In13.Cu")
		(net "85_5INCH_IN5_DN")
	)
	(segment
		(start 409.104846 23.575264)
		(end 409.678632 23.977346)
		(width 0.1651)
		(layer "In13.Cu")
		(net "85_5INCH_IN5_DN")
	)
	(segment
		(start 436.064152 17.309084)
		(end 436.607204 20.387564)
		(width 0.1651)
		(layer "In13.Cu")
		(net "85_5INCH_IN5_DN")
	)
	(segment
		(start 429.15459 23.596092)
		(end 429.728122 23.998428)
		(width 0.1651)
		(layer "In13.Cu")
		(net "85_5INCH_IN5_DN")
	)
	(segment
		(start 426.647102 17.220184)
		(end 427.663864 17.040606)
		(width 0.1651)
		(layer "In13.Cu")
		(net "85_5INCH_IN5_DN")
	)
	(segment
		(start 417.708842 24.044148)
		(end 418.954712 23.82393)
		(width 0.1651)
		(layer "In13.Cu")
		(net "85_5INCH_IN5_DN")
	)
	(segment
		(start 423.361358 23.223982)
		(end 422.370758 17.604486)
		(width 0.1651)
		(layer "In13.Cu")
		(net "85_5INCH_IN5_DN")
	)
	(segment
		(start 430.656492 17.224248)
		(end 431.673254 17.04467)
		(width 0.1651)
		(layer "In13.Cu")
		(net "85_5INCH_IN5_DN")
	)
	(segment
		(start 426.965618 23.782528)
		(end 427.3677 23.208488)
		(width 0.1651)
		(layer "In13.Cu")
		(net "85_5INCH_IN5_DN")
	)
	(segment
		(start 430.388776 17.606264)
		(end 430.656492 17.224248)
		(width 0.1651)
		(layer "In13.Cu")
		(net "85_5INCH_IN5_DN")
	)
	(segment
		(start 411.628844 17.049496)
		(end 412.01086 17.317466)
		(width 0.1651)
		(layer "In13.Cu")
		(net "85_5INCH_IN5_DN")
	)
	(segment
		(start 428.04588 17.308322)
		(end 429.15459 23.596092)
		(width 0.1651)
		(layer "In13.Cu")
		(net "85_5INCH_IN5_DN")
	)
	(segment
		(start 404.415498 21.007324)
		(end 404.706328 20.716494)
		(width 0.1651)
		(layer "In13.Cu")
		(net "85_5INCH_IN5_DN")
	)
	(segment
		(start 410.611828 17.229074)
		(end 411.628844 17.049496)
		(width 0.1651)
		(layer "In13.Cu")
		(net "85_5INCH_IN5_DN")
	)
	(segment
		(start 440.75604 20.709382)
		(end 441.04687 21.000212)
		(width 0.1651)
		(layer "In13.Cu")
		(net "85_5INCH_IN5_DN")
	)
	(segment
		(start 425.146216 23.60041)
		(end 425.719748 24.002746)
		(width 0.1651)
		(layer "In13.Cu")
		(net "85_5INCH_IN5_DN")
	)
	(segment
		(start 418.954712 23.82393)
		(end 419.356794 23.250398)
		(width 0.1651)
		(layer "In13.Cu")
		(net "85_5INCH_IN5_DN")
	)
	(segment
		(start 369.590066 -72.366632)
		(end 369.590066 -71.827898)
		(width 0.13208)
		(layer "F.Cu")
		(net "P12V_SSD12_CO_ILIMIT")
	)
	(segment
		(start 369.590066 -71.827898)
		(end 369.385596 -71.623428)
		(width 0.13208)
		(layer "F.Cu")
		(net "P12V_SSD12_CO_ILIMIT")
	)
	(segment
		(start 368.875564 -71.113396)
		(end 368.875564 -70.479158)
		(width 0.13208)
		(layer "F.Cu")
		(net "P12V_SSD12_CO_ILIMIT")
	)
	(segment
		(start 369.385596 -71.623428)
		(end 368.875564 -71.113396)
		(width 0.13208)
		(layer "F.Cu")
		(net "P12V_SSD12_CO_ILIMIT")
	)
	(via
		(at 369.385596 -71.623428)
		(size 0.508)
		(drill 0.254)
		(layers "F.Cu" "B.Cu")
		(net "P12V_SSD12_CO_ILIMIT")
	)
	(segment
		(start 225.013266 -123.520962)
		(end 224.282254 -123.520962)
		(width 0.13208)
		(layer "F.Cu")
		(net "P3V3_NIC3_PG_G2")
	)
	(segment
		(start 224.270316 -123.509024)
		(end 223.519238 -123.509024)
		(width 0.13208)
		(layer "F.Cu")
		(net "P3V3_NIC3_PG_G2")
	)
	(segment
		(start 225.013266 -122.885962)
		(end 225.013266 -123.520962)
		(width 0.13208)
		(layer "F.Cu")
		(net "P3V3_NIC3_PG_G2")
	)
	(segment
		(start 224.886266 -122.758962)
		(end 225.013266 -122.885962)
		(width 0.13208)
		(layer "F.Cu")
		(net "P3V3_NIC3_PG_G2")
	)
	(segment
		(start 224.282254 -123.520962)
		(end 224.270316 -123.509024)
		(width 0.13208)
		(layer "F.Cu")
		(net "P3V3_NIC3_PG_G2")
	)
	(segment
		(start 223.519238 -122.758962)
		(end 224.886266 -122.758962)
		(width 0.13208)
		(layer "F.Cu")
		(net "P3V3_NIC3_PG_G2")
	)
	(via
		(at 224.270316 -123.509024)
		(size 0.508)
		(drill 0.254)
		(layers "F.Cu" "B.Cu")
		(net "P3V3_NIC3_PG_G2")
	)
	(segment
		(start 246.870728 -113.277142)
		(end 246.870728 -112.539526)
		(width 0.13208)
		(layer "F.Cu")
		(net "P3V3_NIC4_CO_ILIMIT")
	)
	(segment
		(start 248.241058 -114.695478)
		(end 248.241058 -113.92027)
		(width 0.13208)
		(layer "F.Cu")
		(net "P3V3_NIC4_CO_ILIMIT")
	)
	(segment
		(start 247.622822 -113.302034)
		(end 246.89562 -113.302034)
		(width 0.13208)
		(layer "F.Cu")
		(net "P3V3_NIC4_CO_ILIMIT")
	)
	(segment
		(start 246.89562 -113.302034)
		(end 246.870728 -113.277142)
		(width 0.13208)
		(layer "F.Cu")
		(net "P3V3_NIC4_CO_ILIMIT")
	)
	(segment
		(start 248.241058 -113.92027)
		(end 247.622822 -113.302034)
		(width 0.13208)
		(layer "F.Cu")
		(net "P3V3_NIC4_CO_ILIMIT")
	)
	(via
		(at 246.89562 -113.302034)
		(size 0.508)
		(drill 0.254)
		(layers "F.Cu" "B.Cu")
		(net "P3V3_NIC4_CO_ILIMIT")
	)
	(segment
		(start 403.734524 20.325588)
		(end 404.415498 20.143724)
		(width 0.13462)
		(layer "B.Cu")
		(net "85_5INCH_IN5_DP")
	)
	(segment
		(start 441.727844 20.318476)
		(end 441.04687 20.136612)
		(width 0.13462)
		(layer "B.Cu")
		(net "85_5INCH_IN5_DP")
	)
	(segment
		(start 428.303436 17.144238)
		(end 429.412146 23.432262)
		(width 0.1651)
		(layer "In13.Cu")
		(net "85_5INCH_IN5_DP")
	)
	(segment
		(start 404.706328 20.434554)
		(end 408.585924 20.434554)
		(width 0.1651)
		(layer "In13.Cu")
		(net "85_5INCH_IN5_DP")
	)
	(segment
		(start 434.501036 16.962882)
		(end 435.747922 16.742664)
		(width 0.1651)
		(layer "In13.Cu")
		(net "85_5INCH_IN5_DP")
	)
	(segment
		(start 408.881072 20.68195)
		(end 409.362402 23.41118)
		(width 0.1651)
		(layer "In13.Cu")
		(net "85_5INCH_IN5_DP")
	)
	(segment
		(start 422.795192 23.540466)
		(end 423.063162 23.157942)
		(width 0.1651)
		(layer "In13.Cu")
		(net "85_5INCH_IN5_DP")
	)
	(segment
		(start 417.774882 23.745952)
		(end 418.790628 23.566374)
		(width 0.1651)
		(layer "In13.Cu")
		(net "85_5INCH_IN5_DP")
	)
	(segment
		(start 409.362402 23.41118)
		(end 409.744672 23.67915)
		(width 0.1651)
		(layer "In13.Cu")
		(net "85_5INCH_IN5_DP")
	)
	(segment
		(start 411.695138 16.7513)
		(end 412.268416 17.153382)
		(width 0.1651)
		(layer "In13.Cu")
		(net "85_5INCH_IN5_DP")
	)
	(segment
		(start 426.801534 23.524972)
		(end 427.069504 23.142448)
		(width 0.1651)
		(layer "In13.Cu")
		(net "85_5INCH_IN5_DP")
	)
	(segment
		(start 435.090316 23.15464)
		(end 434.099208 17.536414)
		(width 0.1651)
		(layer "In13.Cu")
		(net "85_5INCH_IN5_DP")
	)
	(segment
		(start 418.063426 17.538954)
		(end 418.465254 16.965676)
		(width 0.1651)
		(layer "In13.Cu")
		(net "85_5INCH_IN5_DP")
	)
	(segment
		(start 422.072562 17.538192)
		(end 422.47439 16.964914)
		(width 0.1651)
		(layer "In13.Cu")
		(net "85_5INCH_IN5_DP")
	)
	(segment
		(start 412.268416 17.153382)
		(end 413.375602 23.433532)
		(width 0.1651)
		(layer "In13.Cu")
		(net "85_5INCH_IN5_DP")
	)
	(segment
		(start 410.045916 17.544796)
		(end 410.447744 16.971518)
		(width 0.1651)
		(layer "In13.Cu")
		(net "85_5INCH_IN5_DP")
	)
	(segment
		(start 418.790628 23.566374)
		(end 419.058598 23.184104)
		(width 0.1651)
		(layer "In13.Cu")
		(net "85_5INCH_IN5_DP")
	)
	(segment
		(start 430.809908 23.520654)
		(end 431.078132 23.13813)
		(width 0.1651)
		(layer "In13.Cu")
		(net "85_5INCH_IN5_DP")
	)
	(segment
		(start 414.773618 23.521924)
		(end 415.041588 23.139654)
		(width 0.1651)
		(layer "In13.Cu")
		(net "85_5INCH_IN5_DP")
	)
	(segment
		(start 421.397176 23.452074)
		(end 421.779446 23.720044)
		(width 0.1651)
		(layer "In13.Cu")
		(net "85_5INCH_IN5_DP")
	)
	(segment
		(start 413.757872 23.701502)
		(end 414.773618 23.521924)
		(width 0.1651)
		(layer "In13.Cu")
		(net "85_5INCH_IN5_DP")
	)
	(segment
		(start 415.703004 16.74622)
		(end 416.276536 17.148048)
		(width 0.1651)
		(layer "In13.Cu")
		(net "85_5INCH_IN5_DP")
	)
	(segment
		(start 429.412146 23.432262)
		(end 429.794162 23.700232)
		(width 0.1651)
		(layer "In13.Cu")
		(net "85_5INCH_IN5_DP")
	)
	(segment
		(start 408.585924 20.434554)
		(end 408.881072 20.68195)
		(width 0.1651)
		(layer "In13.Cu")
		(net "85_5INCH_IN5_DP")
	)
	(segment
		(start 417.392612 23.477982)
		(end 417.774882 23.745952)
		(width 0.1651)
		(layer "In13.Cu")
		(net "85_5INCH_IN5_DP")
	)
	(segment
		(start 404.415498 20.143724)
		(end 404.706328 20.434554)
		(width 0.1651)
		(layer "In13.Cu")
		(net "85_5INCH_IN5_DP")
	)
	(segment
		(start 419.71214 16.745458)
		(end 420.285672 17.147286)
		(width 0.1651)
		(layer "In13.Cu")
		(net "85_5INCH_IN5_DP")
	)
	(segment
		(start 434.099208 17.536414)
		(end 434.501036 16.962882)
		(width 0.1651)
		(layer "In13.Cu")
		(net "85_5INCH_IN5_DP")
	)
	(segment
		(start 427.729904 16.74241)
		(end 428.303436 17.144238)
		(width 0.1651)
		(layer "In13.Cu")
		(net "85_5INCH_IN5_DP")
	)
	(segment
		(start 409.744672 23.67915)
		(end 410.760418 23.499572)
		(width 0.1651)
		(layer "In13.Cu")
		(net "85_5INCH_IN5_DP")
	)
	(segment
		(start 418.465254 16.965676)
		(end 419.71214 16.745458)
		(width 0.1651)
		(layer "In13.Cu")
		(net "85_5INCH_IN5_DP")
	)
	(segment
		(start 426.08119 17.535906)
		(end 426.483018 16.962628)
		(width 0.1651)
		(layer "In13.Cu")
		(net "85_5INCH_IN5_DP")
	)
	(segment
		(start 425.785788 23.70455)
		(end 426.801534 23.524972)
		(width 0.1651)
		(layer "In13.Cu")
		(net "85_5INCH_IN5_DP")
	)
	(segment
		(start 435.747922 16.742664)
		(end 436.321708 17.145)
		(width 0.1651)
		(layer "In13.Cu")
		(net "85_5INCH_IN5_DP")
	)
	(segment
		(start 429.794162 23.700232)
		(end 430.809908 23.520654)
		(width 0.1651)
		(layer "In13.Cu")
		(net "85_5INCH_IN5_DP")
	)
	(segment
		(start 411.028388 23.117302)
		(end 410.045916 17.544796)
		(width 0.1651)
		(layer "In13.Cu")
		(net "85_5INCH_IN5_DP")
	)
	(segment
		(start 421.779446 23.720044)
		(end 422.795192 23.540466)
		(width 0.1651)
		(layer "In13.Cu")
		(net "85_5INCH_IN5_DP")
	)
	(segment
		(start 436.321708 17.145)
		(end 436.86476 20.22348)
		(width 0.1651)
		(layer "In13.Cu")
		(net "85_5INCH_IN5_DP")
	)
	(segment
		(start 440.75604 20.427442)
		(end 441.04687 20.136612)
		(width 0.1651)
		(layer "In13.Cu")
		(net "85_5INCH_IN5_DP")
	)
	(segment
		(start 416.276536 17.148048)
		(end 417.392612 23.477982)
		(width 0.1651)
		(layer "In13.Cu")
		(net "85_5INCH_IN5_DP")
	)
	(segment
		(start 414.05429 17.539716)
		(end 414.456118 16.966438)
		(width 0.1651)
		(layer "In13.Cu")
		(net "85_5INCH_IN5_DP")
	)
	(segment
		(start 410.760418 23.499572)
		(end 411.028388 23.117302)
		(width 0.1651)
		(layer "In13.Cu")
		(net "85_5INCH_IN5_DP")
	)
	(segment
		(start 436.86476 20.22348)
		(end 437.15559 20.427442)
		(width 0.1651)
		(layer "In13.Cu")
		(net "85_5INCH_IN5_DP")
	)
	(segment
		(start 424.294808 17.146524)
		(end 425.403772 23.43658)
		(width 0.1651)
		(layer "In13.Cu")
		(net "85_5INCH_IN5_DP")
	)
	(segment
		(start 423.063162 23.157942)
		(end 422.072562 17.538192)
		(width 0.1651)
		(layer "In13.Cu")
		(net "85_5INCH_IN5_DP")
	)
	(segment
		(start 432.313334 17.148556)
		(end 433.423314 23.447502)
		(width 0.1651)
		(layer "In13.Cu")
		(net "85_5INCH_IN5_DP")
	)
	(segment
		(start 430.09058 17.540224)
		(end 430.492408 16.966692)
		(width 0.1651)
		(layer "In13.Cu")
		(net "85_5INCH_IN5_DP")
	)
	(segment
		(start 415.041588 23.139654)
		(end 414.05429 17.539716)
		(width 0.1651)
		(layer "In13.Cu")
		(net "85_5INCH_IN5_DP")
	)
	(segment
		(start 430.492408 16.966692)
		(end 431.739294 16.746474)
		(width 0.1651)
		(layer "In13.Cu")
		(net "85_5INCH_IN5_DP")
	)
	(segment
		(start 425.403772 23.43658)
		(end 425.785788 23.70455)
		(width 0.1651)
		(layer "In13.Cu")
		(net "85_5INCH_IN5_DP")
	)
	(segment
		(start 427.069504 23.142448)
		(end 426.08119 17.535906)
		(width 0.1651)
		(layer "In13.Cu")
		(net "85_5INCH_IN5_DP")
	)
	(segment
		(start 410.447744 16.971518)
		(end 411.695138 16.7513)
		(width 0.1651)
		(layer "In13.Cu")
		(net "85_5INCH_IN5_DP")
	)
	(segment
		(start 413.375602 23.433532)
		(end 413.757872 23.701502)
		(width 0.1651)
		(layer "In13.Cu")
		(net "85_5INCH_IN5_DP")
	)
	(segment
		(start 434.8226 23.535894)
		(end 435.090316 23.15464)
		(width 0.1651)
		(layer "In13.Cu")
		(net "85_5INCH_IN5_DP")
	)
	(segment
		(start 433.423314 23.447502)
		(end 433.8066 23.715472)
		(width 0.1651)
		(layer "In13.Cu")
		(net "85_5INCH_IN5_DP")
	)
	(segment
		(start 414.456118 16.966438)
		(end 415.703004 16.74622)
		(width 0.1651)
		(layer "In13.Cu")
		(net "85_5INCH_IN5_DP")
	)
	(segment
		(start 431.739294 16.746474)
		(end 432.313334 17.148556)
		(width 0.1651)
		(layer "In13.Cu")
		(net "85_5INCH_IN5_DP")
	)
	(segment
		(start 437.15559 20.427442)
		(end 440.75604 20.427442)
		(width 0.1651)
		(layer "In13.Cu")
		(net "85_5INCH_IN5_DP")
	)
	(segment
		(start 431.078132 23.13813)
		(end 430.09058 17.540224)
		(width 0.1651)
		(layer "In13.Cu")
		(net "85_5INCH_IN5_DP")
	)
	(segment
		(start 426.483018 16.962628)
		(end 427.729904 16.74241)
		(width 0.1651)
		(layer "In13.Cu")
		(net "85_5INCH_IN5_DP")
	)
	(segment
		(start 420.285672 17.147286)
		(end 421.397176 23.452074)
		(width 0.1651)
		(layer "In13.Cu")
		(net "85_5INCH_IN5_DP")
	)
	(segment
		(start 433.8066 23.715472)
		(end 434.8226 23.535894)
		(width 0.1651)
		(layer "In13.Cu")
		(net "85_5INCH_IN5_DP")
	)
	(segment
		(start 419.058598 23.184104)
		(end 418.063426 17.538954)
		(width 0.1651)
		(layer "In13.Cu")
		(net "85_5INCH_IN5_DP")
	)
	(segment
		(start 423.721276 16.744696)
		(end 424.294808 17.146524)
		(width 0.1651)
		(layer "In13.Cu")
		(net "85_5INCH_IN5_DP")
	)
	(segment
		(start 422.47439 16.964914)
		(end 423.721276 16.744696)
		(width 0.1651)
		(layer "In13.Cu")
		(net "85_5INCH_IN5_DP")
	)
	(segment
		(start 421.589962 -72.366632)
		(end 421.589962 -71.827898)
		(width 0.13208)
		(layer "F.Cu")
		(net "P12V_SSD14_CO_ILIMIT")
	)
	(segment
		(start 421.385492 -71.623428)
		(end 420.87546 -71.113396)
		(width 0.13208)
		(layer "F.Cu")
		(net "P12V_SSD14_CO_ILIMIT")
	)
	(segment
		(start 421.589962 -71.827898)
		(end 421.385492 -71.623428)
		(width 0.13208)
		(layer "F.Cu")
		(net "P12V_SSD14_CO_ILIMIT")
	)
	(segment
		(start 420.87546 -71.113396)
		(end 420.87546 -70.479158)
		(width 0.13208)
		(layer "F.Cu")
		(net "P12V_SSD14_CO_ILIMIT")
	)
	(via
		(at 421.385492 -71.623428)
		(size 0.508)
		(drill 0.254)
		(layers "F.Cu" "B.Cu")
		(net "P12V_SSD14_CO_ILIMIT")
	)
	(segment
		(start 206.189834 -114.811048)
		(end 205.855062 -115.14582)
		(width 0.13208)
		(layer "F.Cu")
		(net "P3V3_NIC3_CO_GATE")
	)
	(segment
		(start 205.152244 -114.892836)
		(end 205.602078 -114.892836)
		(width 0.13208)
		(layer "F.Cu")
		(net "P3V3_NIC3_CO_GATE")
	)
	(segment
		(start 205.602078 -114.892836)
		(end 205.855062 -115.14582)
		(width 0.13208)
		(layer "F.Cu")
		(net "P3V3_NIC3_CO_GATE")
	)
	(segment
		(start 206.724504 -114.811048)
		(end 206.189834 -114.811048)
		(width 0.13208)
		(layer "F.Cu")
		(net "P3V3_NIC3_CO_GATE")
	)
	(via
		(at 205.855062 -115.14582)
		(size 0.508)
		(drill 0.254)
		(layers "F.Cu" "B.Cu")
		(net "P3V3_NIC3_CO_GATE")
	)
	(segment
		(start 438.9247 -115.835176)
		(end 438.50814 -115.835176)
		(width 0.13208)
		(layer "F.Cu")
		(net "P3V3_NIC7_CO_EN")
	)
	(segment
		(start 437.716168 -115.400836)
		(end 437.35244 -115.400836)
		(width 0.13208)
		(layer "F.Cu")
		(net "P3V3_NIC7_CO_EN")
	)
	(segment
		(start 438.50814 -115.835176)
		(end 438.04332 -115.370356)
		(width 0.13208)
		(layer "F.Cu")
		(net "P3V3_NIC7_CO_EN")
	)
	(segment
		(start 437.746648 -115.370356)
		(end 437.716168 -115.400836)
		(width 0.13208)
		(layer "F.Cu")
		(net "P3V3_NIC7_CO_EN")
	)
	(segment
		(start 438.04332 -115.370356)
		(end 437.746648 -115.370356)
		(width 0.13208)
		(layer "F.Cu")
		(net "P3V3_NIC7_CO_EN")
	)
	(via
		(at 438.04332 -115.370356)
		(size 0.508)
		(drill 0.254)
		(layers "F.Cu" "B.Cu")
		(net "P3V3_NIC7_CO_EN")
	)
	(segment
		(start 256.160524 10.87374)
		(end 256.841498 11.055604)
		(width 0.13462)
		(layer "B.Cu")
		(net "85_10INCH_IN6_DP")
	)
	(segment
		(start 313.294268 10.899648)
		(end 312.613294 11.081512)
		(width 0.13462)
		(layer "B.Cu")
		(net "85_10INCH_IN6_DP")
	)
	(segment
		(start 284.080458 6.50748)
		(end 285.513018 14.632178)
		(width 0.1651)
		(layer "In15.Cu")
		(net "85_10INCH_IN6_DP")
	)
	(segment
		(start 273.493484 14.678406)
		(end 274.067778 15.080488)
		(width 0.1651)
		(layer "In15.Cu")
		(net "85_10INCH_IN6_DP")
	)
	(segment
		(start 264.033508 6.500876)
		(end 265.454638 14.559534)
		(width 0.1651)
		(layer "In15.Cu")
		(net "85_10INCH_IN6_DP")
	)
	(segment
		(start 271.671542 6.243066)
		(end 272.053558 6.510782)
		(width 0.1651)
		(layer "In15.Cu")
		(net "85_10INCH_IN6_DP")
	)
	(segment
		(start 307.376576 14.803374)
		(end 307.778658 14.229842)
		(width 0.1651)
		(layer "In15.Cu")
		(net "85_10INCH_IN6_DP")
	)
	(segment
		(start 290.43249 6.802374)
		(end 290.700206 6.420358)
		(width 0.1651)
		(layer "In15.Cu")
		(net "85_10INCH_IN6_DP")
	)
	(segment
		(start 292.098984 6.508496)
		(end 293.534592 14.65072)
		(width 0.1651)
		(layer "In15.Cu")
		(net "85_10INCH_IN6_DP")
	)
	(segment
		(start 279.314148 14.812772)
		(end 279.71623 14.23924)
		(width 0.1651)
		(layer "In15.Cu")
		(net "85_10INCH_IN6_DP")
	)
	(segment
		(start 266.376658 6.79831)
		(end 266.644374 6.416294)
		(width 0.1651)
		(layer "In15.Cu")
		(net "85_10INCH_IN6_DP")
	)
	(segment
		(start 281.499818 14.609826)
		(end 282.073604 15.011908)
		(width 0.1651)
		(layer "In15.Cu")
		(net "85_10INCH_IN6_DP")
	)
	(segment
		(start 308.834028 10.468864)
		(end 309.29326 10.790682)
		(width 0.1651)
		(layer "In15.Cu")
		(net "85_10INCH_IN6_DP")
	)
	(segment
		(start 306.740052 6.439154)
		(end 307.75656 6.259576)
		(width 0.1651)
		(layer "In15.Cu")
		(net "85_10INCH_IN6_DP")
	)
	(segment
		(start 272.053558 6.510782)
		(end 273.493484 14.678406)
		(width 0.1651)
		(layer "In15.Cu")
		(net "85_10INCH_IN6_DP")
	)
	(segment
		(start 279.71623 14.23924)
		(end 278.403304 6.79323)
		(width 0.1651)
		(layer "In15.Cu")
		(net "85_10INCH_IN6_DP")
	)
	(segment
		(start 262.015224 14.940788)
		(end 263.261094 14.72057)
		(width 0.1651)
		(layer "In15.Cu")
		(net "85_10INCH_IN6_DP")
	)
	(segment
		(start 283.319474 14.79169)
		(end 283.721556 14.218158)
		(width 0.1651)
		(layer "In15.Cu")
		(net "85_10INCH_IN6_DP")
	)
	(segment
		(start 299.733716 6.23189)
		(end 300.115732 6.499606)
		(width 0.1651)
		(layer "In15.Cu")
		(net "85_10INCH_IN6_DP")
	)
	(segment
		(start 262.367014 6.794754)
		(end 262.63473 6.412738)
		(width 0.1651)
		(layer "In15.Cu")
		(net "85_10INCH_IN6_DP")
	)
	(segment
		(start 286.086804 15.03426)
		(end 287.332674 14.814042)
		(width 0.1651)
		(layer "In15.Cu")
		(net "85_10INCH_IN6_DP")
	)
	(segment
		(start 283.698188 6.23951)
		(end 284.080458 6.50748)
		(width 0.1651)
		(layer "In15.Cu")
		(net "85_10INCH_IN6_DP")
	)
	(segment
		(start 266.027916 14.961362)
		(end 267.273532 14.74089)
		(width 0.1651)
		(layer "In15.Cu")
		(net "85_10INCH_IN6_DP")
	)
	(segment
		(start 294.707056 6.406642)
		(end 295.723818 6.227064)
		(width 0.1651)
		(layer "In15.Cu")
		(net "85_10INCH_IN6_DP")
	)
	(segment
		(start 278.403304 6.79323)
		(end 278.67102 6.411214)
		(width 0.1651)
		(layer "In15.Cu")
		(net "85_10INCH_IN6_DP")
	)
	(segment
		(start 291.349684 14.858492)
		(end 291.751766 14.28496)
		(width 0.1651)
		(layer "In15.Cu")
		(net "85_10INCH_IN6_DP")
	)
	(segment
		(start 280.069798 6.499352)
		(end 281.499818 14.609826)
		(width 0.1651)
		(layer "In15.Cu")
		(net "85_10INCH_IN6_DP")
	)
	(segment
		(start 275.679662 6.236462)
		(end 276.061678 6.504178)
		(width 0.1651)
		(layer "In15.Cu")
		(net "85_10INCH_IN6_DP")
	)
	(segment
		(start 295.723818 6.227064)
		(end 296.105834 6.49478)
		(width 0.1651)
		(layer "In15.Cu")
		(net "85_10INCH_IN6_DP")
	)
	(segment
		(start 303.364646 14.788134)
		(end 303.766982 14.214348)
		(width 0.1651)
		(layer "In15.Cu")
		(net "85_10INCH_IN6_DP")
	)
	(segment
		(start 290.700206 6.420358)
		(end 291.716968 6.24078)
		(width 0.1651)
		(layer "In15.Cu")
		(net "85_10INCH_IN6_DP")
	)
	(segment
		(start 291.751766 14.28496)
		(end 290.43249 6.802374)
		(width 0.1651)
		(layer "In15.Cu")
		(net "85_10INCH_IN6_DP")
	)
	(segment
		(start 303.743614 6.238748)
		(end 304.126138 6.506718)
		(width 0.1651)
		(layer "In15.Cu")
		(net "85_10INCH_IN6_DP")
	)
	(segment
		(start 274.6629 6.41604)
		(end 275.679662 6.236462)
		(width 0.1651)
		(layer "In15.Cu")
		(net "85_10INCH_IN6_DP")
	)
	(segment
		(start 286.691832 6.425692)
		(end 287.708594 6.246114)
		(width 0.1651)
		(layer "In15.Cu")
		(net "85_10INCH_IN6_DP")
	)
	(segment
		(start 279.687782 6.231636)
		(end 280.069798 6.499352)
		(width 0.1651)
		(layer "In15.Cu")
		(net "85_10INCH_IN6_DP")
	)
	(segment
		(start 274.067778 15.080488)
		(end 275.313648 14.86027)
		(width 0.1651)
		(layer "In15.Cu")
		(net "85_10INCH_IN6_DP")
	)
	(segment
		(start 302.459136 6.800342)
		(end 302.726852 6.418326)
		(width 0.1651)
		(layer "In15.Cu")
		(net "85_10INCH_IN6_DP")
	)
	(segment
		(start 299.358558 14.804644)
		(end 299.76064 14.231112)
		(width 0.1651)
		(layer "In15.Cu")
		(net "85_10INCH_IN6_DP")
	)
	(segment
		(start 282.41371 6.801104)
		(end 282.681426 6.419088)
		(width 0.1651)
		(layer "In15.Cu")
		(net "85_10INCH_IN6_DP")
	)
	(segment
		(start 293.534592 14.65072)
		(end 294.108378 15.052802)
		(width 0.1651)
		(layer "In15.Cu")
		(net "85_10INCH_IN6_DP")
	)
	(segment
		(start 307.75656 6.259576)
		(end 308.139084 6.5278)
		(width 0.1651)
		(layer "In15.Cu")
		(net "85_10INCH_IN6_DP")
	)
	(segment
		(start 291.716968 6.24078)
		(end 292.098984 6.508496)
		(width 0.1651)
		(layer "In15.Cu")
		(net "85_10INCH_IN6_DP")
	)
	(segment
		(start 270.055594 15.065248)
		(end 271.301464 14.84503)
		(width 0.1651)
		(layer "In15.Cu")
		(net "85_10INCH_IN6_DP")
	)
	(segment
		(start 288.090864 6.51383)
		(end 289.530028 14.676628)
		(width 0.1651)
		(layer "In15.Cu")
		(net "85_10INCH_IN6_DP")
	)
	(segment
		(start 295.75633 14.259052)
		(end 294.43934 6.788658)
		(width 0.1651)
		(layer "In15.Cu")
		(net "85_10INCH_IN6_DP")
	)
	(segment
		(start 297.538902 14.62278)
		(end 298.112688 15.024862)
		(width 0.1651)
		(layer "In15.Cu")
		(net "85_10INCH_IN6_DP")
	)
	(segment
		(start 303.766982 14.214348)
		(end 302.459136 6.800342)
		(width 0.1651)
		(layer "In15.Cu")
		(net "85_10INCH_IN6_DP")
	)
	(segment
		(start 267.661136 6.236716)
		(end 268.043152 6.504432)
		(width 0.1651)
		(layer "In15.Cu")
		(net "85_10INCH_IN6_DP")
	)
	(segment
		(start 298.449238 6.793484)
		(end 298.716954 6.411468)
		(width 0.1651)
		(layer "In15.Cu")
		(net "85_10INCH_IN6_DP")
	)
	(segment
		(start 270.387064 6.80466)
		(end 270.65478 6.422644)
		(width 0.1651)
		(layer "In15.Cu")
		(net "85_10INCH_IN6_DP")
	)
	(segment
		(start 269.482062 14.663166)
		(end 270.055594 15.065248)
		(width 0.1651)
		(layer "In15.Cu")
		(net "85_10INCH_IN6_DP")
	)
	(segment
		(start 306.130706 15.023592)
		(end 307.376576 14.803374)
		(width 0.1651)
		(layer "In15.Cu")
		(net "85_10INCH_IN6_DP")
	)
	(segment
		(start 290.103814 15.07871)
		(end 291.349684 14.858492)
		(width 0.1651)
		(layer "In15.Cu")
		(net "85_10INCH_IN6_DP")
	)
	(segment
		(start 263.651492 6.23316)
		(end 264.033508 6.500876)
		(width 0.1651)
		(layer "In15.Cu")
		(net "85_10INCH_IN6_DP")
	)
	(segment
		(start 286.424116 6.807708)
		(end 286.691832 6.425692)
		(width 0.1651)
		(layer "In15.Cu")
		(net "85_10INCH_IN6_DP")
	)
	(segment
		(start 278.068278 15.03299)
		(end 279.314148 14.812772)
		(width 0.1651)
		(layer "In15.Cu")
		(net "85_10INCH_IN6_DP")
	)
	(segment
		(start 298.112688 15.024862)
		(end 299.358558 14.804644)
		(width 0.1651)
		(layer "In15.Cu")
		(net "85_10INCH_IN6_DP")
	)
	(segment
		(start 256.841498 11.055604)
		(end 257.132328 10.764774)
		(width 0.1651)
		(layer "In15.Cu")
		(net "85_10INCH_IN6_DP")
	)
	(segment
		(start 267.675868 14.16685)
		(end 266.376658 6.79831)
		(width 0.1651)
		(layer "In15.Cu")
		(net "85_10INCH_IN6_DP")
	)
	(segment
		(start 265.454638 14.559534)
		(end 266.027916 14.961362)
		(width 0.1651)
		(layer "In15.Cu")
		(net "85_10INCH_IN6_DP")
	)
	(segment
		(start 275.71573 14.287246)
		(end 274.395184 6.798056)
		(width 0.1651)
		(layer "In15.Cu")
		(net "85_10INCH_IN6_DP")
	)
	(segment
		(start 261.441692 14.538706)
		(end 262.015224 14.940788)
		(width 0.1651)
		(layer "In15.Cu")
		(net "85_10INCH_IN6_DP")
	)
	(segment
		(start 307.778658 14.229842)
		(end 306.472336 6.82117)
		(width 0.1651)
		(layer "In15.Cu")
		(net "85_10INCH_IN6_DP")
	)
	(segment
		(start 296.105834 6.49478)
		(end 297.538902 14.62278)
		(width 0.1651)
		(layer "In15.Cu")
		(net "85_10INCH_IN6_DP")
	)
	(segment
		(start 282.681426 6.419088)
		(end 283.698188 6.23951)
		(width 0.1651)
		(layer "In15.Cu")
		(net "85_10INCH_IN6_DP")
	)
	(segment
		(start 268.043152 6.504432)
		(end 269.482062 14.663166)
		(width 0.1651)
		(layer "In15.Cu")
		(net "85_10INCH_IN6_DP")
	)
	(segment
		(start 275.313648 14.86027)
		(end 275.71573 14.287246)
		(width 0.1651)
		(layer "In15.Cu")
		(net "85_10INCH_IN6_DP")
	)
	(segment
		(start 294.43934 6.788658)
		(end 294.707056 6.406642)
		(width 0.1651)
		(layer "In15.Cu")
		(net "85_10INCH_IN6_DP")
	)
	(segment
		(start 294.108378 15.052802)
		(end 295.354248 14.832584)
		(width 0.1651)
		(layer "In15.Cu")
		(net "85_10INCH_IN6_DP")
	)
	(segment
		(start 283.721556 14.218158)
		(end 282.41371 6.801104)
		(width 0.1651)
		(layer "In15.Cu")
		(net "85_10INCH_IN6_DP")
	)
	(segment
		(start 263.261094 14.72057)
		(end 263.663176 14.146784)
		(width 0.1651)
		(layer "In15.Cu")
		(net "85_10INCH_IN6_DP")
	)
	(segment
		(start 260.370828 10.764774)
		(end 260.862572 11.256518)
		(width 0.1651)
		(layer "In15.Cu")
		(net "85_10INCH_IN6_DP")
	)
	(segment
		(start 302.118776 15.008352)
		(end 303.364646 14.788134)
		(width 0.1651)
		(layer "In15.Cu")
		(net "85_10INCH_IN6_DP")
	)
	(segment
		(start 274.395184 6.798056)
		(end 274.6629 6.41604)
		(width 0.1651)
		(layer "In15.Cu")
		(net "85_10INCH_IN6_DP")
	)
	(segment
		(start 278.67102 6.411214)
		(end 279.687782 6.231636)
		(width 0.1651)
		(layer "In15.Cu")
		(net "85_10INCH_IN6_DP")
	)
	(segment
		(start 304.126138 6.506718)
		(end 305.55692 14.62151)
		(width 0.1651)
		(layer "In15.Cu")
		(net "85_10INCH_IN6_DP")
	)
	(segment
		(start 295.354248 14.832584)
		(end 295.75633 14.259052)
		(width 0.1651)
		(layer "In15.Cu")
		(net "85_10INCH_IN6_DP")
	)
	(segment
		(start 285.513018 14.632178)
		(end 286.086804 15.03426)
		(width 0.1651)
		(layer "In15.Cu")
		(net "85_10INCH_IN6_DP")
	)
	(segment
		(start 277.494492 14.630908)
		(end 278.068278 15.03299)
		(width 0.1651)
		(layer "In15.Cu")
		(net "85_10INCH_IN6_DP")
	)
	(segment
		(start 312.322464 10.790682)
		(end 312.613294 11.081512)
		(width 0.1651)
		(layer "In15.Cu")
		(net "85_10INCH_IN6_DP")
	)
	(segment
		(start 300.115732 6.499606)
		(end 301.54499 14.60627)
		(width 0.1651)
		(layer "In15.Cu")
		(net "85_10INCH_IN6_DP")
	)
	(segment
		(start 271.301464 14.84503)
		(end 271.703546 14.271498)
		(width 0.1651)
		(layer "In15.Cu")
		(net "85_10INCH_IN6_DP")
	)
	(segment
		(start 302.726852 6.418326)
		(end 303.743614 6.238748)
		(width 0.1651)
		(layer "In15.Cu")
		(net "85_10INCH_IN6_DP")
	)
	(segment
		(start 257.132328 10.764774)
		(end 260.370828 10.764774)
		(width 0.1651)
		(layer "In15.Cu")
		(net "85_10INCH_IN6_DP")
	)
	(segment
		(start 306.472336 6.82117)
		(end 306.740052 6.439154)
		(width 0.1651)
		(layer "In15.Cu")
		(net "85_10INCH_IN6_DP")
	)
	(segment
		(start 270.65478 6.422644)
		(end 271.671542 6.243066)
		(width 0.1651)
		(layer "In15.Cu")
		(net "85_10INCH_IN6_DP")
	)
	(segment
		(start 263.663176 14.146784)
		(end 262.367014 6.794754)
		(width 0.1651)
		(layer "In15.Cu")
		(net "85_10INCH_IN6_DP")
	)
	(segment
		(start 262.63473 6.412738)
		(end 263.651492 6.23316)
		(width 0.1651)
		(layer "In15.Cu")
		(net "85_10INCH_IN6_DP")
	)
	(segment
		(start 301.54499 14.60627)
		(end 302.118776 15.008352)
		(width 0.1651)
		(layer "In15.Cu")
		(net "85_10INCH_IN6_DP")
	)
	(segment
		(start 271.703546 14.271498)
		(end 270.387064 6.80466)
		(width 0.1651)
		(layer "In15.Cu")
		(net "85_10INCH_IN6_DP")
	)
	(segment
		(start 287.708594 6.246114)
		(end 288.090864 6.51383)
		(width 0.1651)
		(layer "In15.Cu")
		(net "85_10INCH_IN6_DP")
	)
	(segment
		(start 267.273532 14.74089)
		(end 267.675868 14.16685)
		(width 0.1651)
		(layer "In15.Cu")
		(net "85_10INCH_IN6_DP")
	)
	(segment
		(start 309.29326 10.790682)
		(end 312.322464 10.790682)
		(width 0.1651)
		(layer "In15.Cu")
		(net "85_10INCH_IN6_DP")
	)
	(segment
		(start 287.332674 14.814042)
		(end 287.734756 14.24051)
		(width 0.1651)
		(layer "In15.Cu")
		(net "85_10INCH_IN6_DP")
	)
	(segment
		(start 260.862572 11.256518)
		(end 261.441692 14.538706)
		(width 0.1651)
		(layer "In15.Cu")
		(net "85_10INCH_IN6_DP")
	)
	(segment
		(start 276.061678 6.504178)
		(end 277.494492 14.630908)
		(width 0.1651)
		(layer "In15.Cu")
		(net "85_10INCH_IN6_DP")
	)
	(segment
		(start 266.644374 6.416294)
		(end 267.661136 6.236716)
		(width 0.1651)
		(layer "In15.Cu")
		(net "85_10INCH_IN6_DP")
	)
	(segment
		(start 299.76064 14.231112)
		(end 298.449238 6.793484)
		(width 0.1651)
		(layer "In15.Cu")
		(net "85_10INCH_IN6_DP")
	)
	(segment
		(start 282.073604 15.011908)
		(end 283.319474 14.79169)
		(width 0.1651)
		(layer "In15.Cu")
		(net "85_10INCH_IN6_DP")
	)
	(segment
		(start 305.55692 14.62151)
		(end 306.130706 15.023592)
		(width 0.1651)
		(layer "In15.Cu")
		(net "85_10INCH_IN6_DP")
	)
	(segment
		(start 308.139084 6.5278)
		(end 308.834028 10.468864)
		(width 0.1651)
		(layer "In15.Cu")
		(net "85_10INCH_IN6_DP")
	)
	(segment
		(start 289.530028 14.676628)
		(end 290.103814 15.07871)
		(width 0.1651)
		(layer "In15.Cu")
		(net "85_10INCH_IN6_DP")
	)
	(segment
		(start 298.716954 6.411468)
		(end 299.733716 6.23189)
		(width 0.1651)
		(layer "In15.Cu")
		(net "85_10INCH_IN6_DP")
	)
	(segment
		(start 287.734756 14.24051)
		(end 286.424116 6.807708)
		(width 0.1651)
		(layer "In15.Cu")
		(net "85_10INCH_IN6_DP")
	)
	(segment
		(start 205.152244 -112.860836)
		(end 205.60284 -112.860836)
		(width 0.13208)
		(layer "F.Cu")
		(net "P3V3_NIC3_CO_DV_DT")
	)
	(segment
		(start 205.930246 -112.53343)
		(end 206.280004 -112.883188)
		(width 0.13208)
		(layer "F.Cu")
		(net "P3V3_NIC3_CO_DV_DT")
	)
	(segment
		(start 206.280004 -112.883188)
		(end 206.280004 -113.661952)
		(width 0.13208)
		(layer "F.Cu")
		(net "P3V3_NIC3_CO_DV_DT")
	)
	(segment
		(start 206.429356 -113.811304)
		(end 206.724504 -113.811304)
		(width 0.13208)
		(layer "F.Cu")
		(net "P3V3_NIC3_CO_DV_DT")
	)
	(segment
		(start 206.280004 -113.661952)
		(end 206.429356 -113.811304)
		(width 0.13208)
		(layer "F.Cu")
		(net "P3V3_NIC3_CO_DV_DT")
	)
	(segment
		(start 205.60284 -112.860836)
		(end 205.930246 -112.53343)
		(width 0.13208)
		(layer "F.Cu")
		(net "P3V3_NIC3_CO_DV_DT")
	)
	(via
		(at 205.930246 -112.53343)
		(size 0.508)
		(drill 0.254)
		(layers "F.Cu" "B.Cu")
		(net "P3V3_NIC3_CO_DV_DT")
	)
	(segment
		(start 441.658756 -115.835176)
		(end 441.661296 -115.832636)
		(width 0.13208)
		(layer "F.Cu")
		(net "P3V3_NIC7_CO_ILIMIT")
	)
	(segment
		(start 442.099446 -115.394486)
		(end 442.394086 -115.394486)
		(width 0.13208)
		(layer "F.Cu")
		(net "P3V3_NIC7_CO_ILIMIT")
	)
	(segment
		(start 441.661296 -115.832636)
		(end 442.099446 -115.394486)
		(width 0.13208)
		(layer "F.Cu")
		(net "P3V3_NIC7_CO_ILIMIT")
	)
	(segment
		(start 440.924696 -115.835176)
		(end 441.658756 -115.835176)
		(width 0.13208)
		(layer "F.Cu")
		(net "P3V3_NIC7_CO_ILIMIT")
	)
	(via
		(at 441.661296 -115.832636)
		(size 0.508)
		(drill 0.254)
		(layers "F.Cu" "B.Cu")
		(net "P3V3_NIC7_CO_ILIMIT")
	)
	(segment
		(start 339.091524 20.82546)
		(end 339.772498 21.007324)
		(width 0.13462)
		(layer "B.Cu")
		(net "85_5INCH_IN4_DP")
	)
	(segment
		(start 377.084844 20.818348)
		(end 376.40387 21.000212)
		(width 0.13462)
		(layer "B.Cu")
		(net "85_5INCH_IN4_DP")
	)
	(segment
		(start 345.701112 17.61109)
		(end 345.968828 17.229074)
		(width 0.1651)
		(layer "In11.Cu")
		(net "85_5INCH_IN4_DP")
	)
	(segment
		(start 357.727758 17.604486)
		(end 357.995474 17.22247)
		(width 0.1651)
		(layer "In11.Cu")
		(net "85_5INCH_IN4_DP")
	)
	(segment
		(start 346.683584 23.183596)
		(end 345.701112 17.61109)
		(width 0.1651)
		(layer "In11.Cu")
		(net "85_5INCH_IN4_DP")
	)
	(segment
		(start 360.503216 23.60041)
		(end 361.076748 24.002746)
		(width 0.1651)
		(layer "In11.Cu")
		(net "85_5INCH_IN4_DP")
	)
	(segment
		(start 340.063328 20.716494)
		(end 343.840308 20.716494)
		(width 0.1651)
		(layer "In11.Cu")
		(net "85_5INCH_IN4_DP")
	)
	(segment
		(start 346.985844 17.049496)
		(end 347.36786 17.317466)
		(width 0.1651)
		(layer "In11.Cu")
		(net "85_5INCH_IN4_DP")
	)
	(segment
		(start 359.394252 17.310608)
		(end 360.503216 23.60041)
		(width 0.1651)
		(layer "In11.Cu")
		(net "85_5INCH_IN4_DP")
	)
	(segment
		(start 359.012236 17.042892)
		(end 359.394252 17.310608)
		(width 0.1651)
		(layer "In11.Cu")
		(net "85_5INCH_IN4_DP")
	)
	(segment
		(start 372.423436 20.709382)
		(end 376.11304 20.709382)
		(width 0.1651)
		(layer "In11.Cu")
		(net "85_5INCH_IN4_DP")
	)
	(segment
		(start 357.995474 17.22247)
		(end 359.012236 17.042892)
		(width 0.1651)
		(layer "In11.Cu")
		(net "85_5INCH_IN4_DP")
	)
	(segment
		(start 364.51159 23.596092)
		(end 365.085122 23.998428)
		(width 0.1651)
		(layer "In11.Cu")
		(net "85_5INCH_IN4_DP")
	)
	(segment
		(start 370.02212 17.220438)
		(end 371.038628 17.04086)
		(width 0.1651)
		(layer "In11.Cu")
		(net "85_5INCH_IN4_DP")
	)
	(segment
		(start 352.492056 23.642066)
		(end 353.065842 24.044148)
		(width 0.1651)
		(layer "In11.Cu")
		(net "85_5INCH_IN4_DP")
	)
	(segment
		(start 362.004102 17.220184)
		(end 363.020864 17.040606)
		(width 0.1651)
		(layer "In11.Cu")
		(net "85_5INCH_IN4_DP")
	)
	(segment
		(start 357.070406 24.01824)
		(end 358.316276 23.798022)
		(width 0.1651)
		(layer "In11.Cu")
		(net "85_5INCH_IN4_DP")
	)
	(segment
		(start 343.840308 20.716494)
		(end 343.97823 20.832064)
		(width 0.1651)
		(layer "In11.Cu")
		(net "85_5INCH_IN4_DP")
	)
	(segment
		(start 339.772498 21.007324)
		(end 340.063328 20.716494)
		(width 0.1651)
		(layer "In11.Cu")
		(net "85_5INCH_IN4_DP")
	)
	(segment
		(start 369.754404 17.602454)
		(end 370.02212 17.220438)
		(width 0.1651)
		(layer "In11.Cu")
		(net "85_5INCH_IN4_DP")
	)
	(segment
		(start 350.294702 23.77948)
		(end 350.696784 23.205948)
		(width 0.1651)
		(layer "In11.Cu")
		(net "85_5INCH_IN4_DP")
	)
	(segment
		(start 355.0031 17.043654)
		(end 355.385116 17.31137)
		(width 0.1651)
		(layer "In11.Cu")
		(net "85_5INCH_IN4_DP")
	)
	(segment
		(start 348.475046 23.597616)
		(end 349.048832 23.999698)
		(width 0.1651)
		(layer "In11.Cu")
		(net "85_5INCH_IN4_DP")
	)
	(segment
		(start 354.713794 23.250398)
		(end 353.718622 17.605248)
		(width 0.1651)
		(layer "In11.Cu")
		(net "85_5INCH_IN4_DP")
	)
	(segment
		(start 358.718358 23.223982)
		(end 357.727758 17.604486)
		(width 0.1651)
		(layer "In11.Cu")
		(net "85_5INCH_IN4_DP")
	)
	(segment
		(start 363.40288 17.308322)
		(end 364.51159 23.596092)
		(width 0.1651)
		(layer "In11.Cu")
		(net "85_5INCH_IN4_DP")
	)
	(segment
		(start 347.36786 17.317466)
		(end 348.475046 23.597616)
		(width 0.1651)
		(layer "In11.Cu")
		(net "85_5INCH_IN4_DP")
	)
	(segment
		(start 349.977202 17.223994)
		(end 350.993964 17.044416)
		(width 0.1651)
		(layer "In11.Cu")
		(net "85_5INCH_IN4_DP")
	)
	(segment
		(start 361.736386 17.6022)
		(end 362.004102 17.220184)
		(width 0.1651)
		(layer "In11.Cu")
		(net "85_5INCH_IN4_DP")
	)
	(segment
		(start 370.745512 23.220934)
		(end 369.754404 17.602454)
		(width 0.1651)
		(layer "In11.Cu")
		(net "85_5INCH_IN4_DP")
	)
	(segment
		(start 349.709486 17.60601)
		(end 349.977202 17.223994)
		(width 0.1651)
		(layer "In11.Cu")
		(net "85_5INCH_IN4_DP")
	)
	(segment
		(start 370.34343 23.79345)
		(end 370.745512 23.220934)
		(width 0.1651)
		(layer "In11.Cu")
		(net "85_5INCH_IN4_DP")
	)
	(segment
		(start 343.97823 20.832064)
		(end 344.461846 23.575264)
		(width 0.1651)
		(layer "In11.Cu")
		(net "85_5INCH_IN4_DP")
	)
	(segment
		(start 355.385116 17.31137)
		(end 356.49662 23.616158)
		(width 0.1651)
		(layer "In11.Cu")
		(net "85_5INCH_IN4_DP")
	)
	(segment
		(start 350.993964 17.044416)
		(end 351.37598 17.312132)
		(width 0.1651)
		(layer "In11.Cu")
		(net "85_5INCH_IN4_DP")
	)
	(segment
		(start 351.37598 17.312132)
		(end 352.492056 23.642066)
		(width 0.1651)
		(layer "In11.Cu")
		(net "85_5INCH_IN4_DP")
	)
	(segment
		(start 349.048832 23.999698)
		(end 350.294702 23.77948)
		(width 0.1651)
		(layer "In11.Cu")
		(net "85_5INCH_IN4_DP")
	)
	(segment
		(start 353.986338 17.223232)
		(end 355.0031 17.043654)
		(width 0.1651)
		(layer "In11.Cu")
		(net "85_5INCH_IN4_DP")
	)
	(segment
		(start 353.718622 17.605248)
		(end 353.986338 17.223232)
		(width 0.1651)
		(layer "In11.Cu")
		(net "85_5INCH_IN4_DP")
	)
	(segment
		(start 376.11304 20.709382)
		(end 376.40387 21.000212)
		(width 0.1651)
		(layer "In11.Cu")
		(net "85_5INCH_IN4_DP")
	)
	(segment
		(start 371.038628 17.04086)
		(end 371.421152 17.309084)
		(width 0.1651)
		(layer "In11.Cu")
		(net "85_5INCH_IN4_DP")
	)
	(segment
		(start 353.065842 24.044148)
		(end 354.311712 23.82393)
		(width 0.1651)
		(layer "In11.Cu")
		(net "85_5INCH_IN4_DP")
	)
	(segment
		(start 345.968828 17.229074)
		(end 346.985844 17.049496)
		(width 0.1651)
		(layer "In11.Cu")
		(net "85_5INCH_IN4_DP")
	)
	(segment
		(start 371.964204 20.387564)
		(end 372.423436 20.709382)
		(width 0.1651)
		(layer "In11.Cu")
		(net "85_5INCH_IN4_DP")
	)
	(segment
		(start 365.085122 23.998428)
		(end 366.330992 23.77821)
		(width 0.1651)
		(layer "In11.Cu")
		(net "85_5INCH_IN4_DP")
	)
	(segment
		(start 371.421152 17.309084)
		(end 371.964204 20.387564)
		(width 0.1651)
		(layer "In11.Cu")
		(net "85_5INCH_IN4_DP")
	)
	(segment
		(start 368.522758 23.611586)
		(end 369.09756 24.013668)
		(width 0.1651)
		(layer "In11.Cu")
		(net "85_5INCH_IN4_DP")
	)
	(segment
		(start 367.412778 17.31264)
		(end 368.522758 23.611586)
		(width 0.1651)
		(layer "In11.Cu")
		(net "85_5INCH_IN4_DP")
	)
	(segment
		(start 346.281502 23.757128)
		(end 346.683584 23.183596)
		(width 0.1651)
		(layer "In11.Cu")
		(net "85_5INCH_IN4_DP")
	)
	(segment
		(start 358.316276 23.798022)
		(end 358.718358 23.223982)
		(width 0.1651)
		(layer "In11.Cu")
		(net "85_5INCH_IN4_DP")
	)
	(segment
		(start 365.745776 17.606264)
		(end 366.013492 17.224248)
		(width 0.1651)
		(layer "In11.Cu")
		(net "85_5INCH_IN4_DP")
	)
	(segment
		(start 362.7247 23.208488)
		(end 361.736386 17.6022)
		(width 0.1651)
		(layer "In11.Cu")
		(net "85_5INCH_IN4_DP")
	)
	(segment
		(start 369.09756 24.013668)
		(end 370.34343 23.79345)
		(width 0.1651)
		(layer "In11.Cu")
		(net "85_5INCH_IN4_DP")
	)
	(segment
		(start 344.461846 23.575264)
		(end 345.035632 23.977346)
		(width 0.1651)
		(layer "In11.Cu")
		(net "85_5INCH_IN4_DP")
	)
	(segment
		(start 366.013492 17.224248)
		(end 367.030254 17.04467)
		(width 0.1651)
		(layer "In11.Cu")
		(net "85_5INCH_IN4_DP")
	)
	(segment
		(start 345.035632 23.977346)
		(end 346.281502 23.757128)
		(width 0.1651)
		(layer "In11.Cu")
		(net "85_5INCH_IN4_DP")
	)
	(segment
		(start 366.733328 23.204424)
		(end 365.745776 17.606264)
		(width 0.1651)
		(layer "In11.Cu")
		(net "85_5INCH_IN4_DP")
	)
	(segment
		(start 356.49662 23.616158)
		(end 357.070406 24.01824)
		(width 0.1651)
		(layer "In11.Cu")
		(net "85_5INCH_IN4_DP")
	)
	(segment
		(start 363.020864 17.040606)
		(end 363.40288 17.308322)
		(width 0.1651)
		(layer "In11.Cu")
		(net "85_5INCH_IN4_DP")
	)
	(segment
		(start 367.030254 17.04467)
		(end 367.412778 17.31264)
		(width 0.1651)
		(layer "In11.Cu")
		(net "85_5INCH_IN4_DP")
	)
	(segment
		(start 362.322618 23.782528)
		(end 362.7247 23.208488)
		(width 0.1651)
		(layer "In11.Cu")
		(net "85_5INCH_IN4_DP")
	)
	(segment
		(start 350.696784 23.205948)
		(end 349.709486 17.60601)
		(width 0.1651)
		(layer "In11.Cu")
		(net "85_5INCH_IN4_DP")
	)
	(segment
		(start 354.311712 23.82393)
		(end 354.713794 23.250398)
		(width 0.1651)
		(layer "In11.Cu")
		(net "85_5INCH_IN4_DP")
	)
	(segment
		(start 361.076748 24.002746)
		(end 362.322618 23.782528)
		(width 0.1651)
		(layer "In11.Cu")
		(net "85_5INCH_IN4_DP")
	)
	(segment
		(start 366.330992 23.77821)
		(end 366.733328 23.204424)
		(width 0.1651)
		(layer "In11.Cu")
		(net "85_5INCH_IN4_DP")
	)
	(segment
		(start 367.461292 -67.488054)
		(end 367.798604 -67.150742)
		(width 0.13208)
		(layer "F.Cu")
		(net "P12V_SSD12_CO_GATE")
	)
	(segment
		(start 367.798604 -67.150742)
		(end 367.798604 -66.72199)
		(width 0.13208)
		(layer "F.Cu")
		(net "P12V_SSD12_CO_GATE")
	)
	(segment
		(start 367.760504 -67.787266)
		(end 367.461292 -67.488054)
		(width 0.13208)
		(layer "F.Cu")
		(net "P12V_SSD12_CO_GATE")
	)
	(segment
		(start 368.375692 -68.479162)
		(end 368.375692 -67.96405)
		(width 0.13208)
		(layer "F.Cu")
		(net "P12V_SSD12_CO_GATE")
	)
	(segment
		(start 368.375692 -67.96405)
		(end 368.198908 -67.787266)
		(width 0.13208)
		(layer "F.Cu")
		(net "P12V_SSD12_CO_GATE")
	)
	(segment
		(start 368.198908 -67.787266)
		(end 367.760504 -67.787266)
		(width 0.13208)
		(layer "F.Cu")
		(net "P12V_SSD12_CO_GATE")
	)
	(via
		(at 367.461292 -67.488054)
		(size 0.508)
		(drill 0.254)
		(layers "F.Cu" "B.Cu")
		(net "P12V_SSD12_CO_GATE")
	)
	(segment
		(start 454.687432 -120.53824)
		(end 454.675494 -120.526302)
		(width 0.13208)
		(layer "F.Cu")
		(net "P3V3_NIC7_PG_G2")
	)
	(segment
		(start 454.675494 -120.526302)
		(end 453.924416 -120.526302)
		(width 0.13208)
		(layer "F.Cu")
		(net "P3V3_NIC7_PG_G2")
	)
	(segment
		(start 455.418444 -119.90324)
		(end 455.291444 -119.77624)
		(width 0.13208)
		(layer "F.Cu")
		(net "P3V3_NIC7_PG_G2")
	)
	(segment
		(start 455.418444 -120.53824)
		(end 455.418444 -119.90324)
		(width 0.13208)
		(layer "F.Cu")
		(net "P3V3_NIC7_PG_G2")
	)
	(segment
		(start 455.291444 -119.77624)
		(end 453.924416 -119.77624)
		(width 0.13208)
		(layer "F.Cu")
		(net "P3V3_NIC7_PG_G2")
	)
	(segment
		(start 455.418444 -120.53824)
		(end 454.687432 -120.53824)
		(width 0.13208)
		(layer "F.Cu")
		(net "P3V3_NIC7_PG_G2")
	)
	(via
		(at 454.675494 -120.526302)
		(size 0.508)
		(drill 0.254)
		(layers "F.Cu" "B.Cu")
		(net "P3V3_NIC7_PG_G2")
	)
	(segment
		(start 339.091524 20.325588)
		(end 339.772498 20.143724)
		(width 0.13462)
		(layer "B.Cu")
		(net "85_5INCH_IN4_DN")
	)
	(segment
		(start 377.084844 20.318476)
		(end 376.40387 20.136612)
		(width 0.13462)
		(layer "B.Cu")
		(net "85_5INCH_IN4_DN")
	)
	(segment
		(start 345.804744 16.971518)
		(end 347.052138 16.7513)
		(width 0.1651)
		(layer "In11.Cu")
		(net "85_5INCH_IN4_DN")
	)
	(segment
		(start 355.06914 16.745458)
		(end 355.642672 17.147286)
		(width 0.1651)
		(layer "In11.Cu")
		(net "85_5INCH_IN4_DN")
	)
	(segment
		(start 355.642672 17.147286)
		(end 356.754176 23.452074)
		(width 0.1651)
		(layer "In11.Cu")
		(net "85_5INCH_IN4_DN")
	)
	(segment
		(start 368.780314 23.447502)
		(end 369.1636 23.715472)
		(width 0.1651)
		(layer "In11.Cu")
		(net "85_5INCH_IN4_DN")
	)
	(segment
		(start 347.625416 17.153382)
		(end 348.732602 23.433532)
		(width 0.1651)
		(layer "In11.Cu")
		(net "85_5INCH_IN4_DN")
	)
	(segment
		(start 346.385388 23.117302)
		(end 345.402916 17.544796)
		(width 0.1651)
		(layer "In11.Cu")
		(net "85_5INCH_IN4_DN")
	)
	(segment
		(start 345.402916 17.544796)
		(end 345.804744 16.971518)
		(width 0.1651)
		(layer "In11.Cu")
		(net "85_5INCH_IN4_DN")
	)
	(segment
		(start 366.166908 23.520654)
		(end 366.435132 23.13813)
		(width 0.1651)
		(layer "In11.Cu")
		(net "85_5INCH_IN4_DN")
	)
	(segment
		(start 369.858036 16.962882)
		(end 371.104922 16.742664)
		(width 0.1651)
		(layer "In11.Cu")
		(net "85_5INCH_IN4_DN")
	)
	(segment
		(start 365.849408 16.966692)
		(end 367.096294 16.746474)
		(width 0.1651)
		(layer "In11.Cu")
		(net "85_5INCH_IN4_DN")
	)
	(segment
		(start 359.078276 16.744696)
		(end 359.651808 17.146524)
		(width 0.1651)
		(layer "In11.Cu")
		(net "85_5INCH_IN4_DN")
	)
	(segment
		(start 344.719402 23.41118)
		(end 345.101672 23.67915)
		(width 0.1651)
		(layer "In11.Cu")
		(net "85_5INCH_IN4_DN")
	)
	(segment
		(start 354.415598 23.184104)
		(end 353.420426 17.538954)
		(width 0.1651)
		(layer "In11.Cu")
		(net "85_5INCH_IN4_DN")
	)
	(segment
		(start 372.22176 20.22348)
		(end 372.51259 20.427442)
		(width 0.1651)
		(layer "In11.Cu")
		(net "85_5INCH_IN4_DN")
	)
	(segment
		(start 352.749612 23.477982)
		(end 353.131882 23.745952)
		(width 0.1651)
		(layer "In11.Cu")
		(net "85_5INCH_IN4_DN")
	)
	(segment
		(start 346.117418 23.499572)
		(end 346.385388 23.117302)
		(width 0.1651)
		(layer "In11.Cu")
		(net "85_5INCH_IN4_DN")
	)
	(segment
		(start 340.063328 20.434554)
		(end 343.942924 20.434554)
		(width 0.1651)
		(layer "In11.Cu")
		(net "85_5INCH_IN4_DN")
	)
	(segment
		(start 367.096294 16.746474)
		(end 367.670334 17.148556)
		(width 0.1651)
		(layer "In11.Cu")
		(net "85_5INCH_IN4_DN")
	)
	(segment
		(start 353.131882 23.745952)
		(end 354.147628 23.566374)
		(width 0.1651)
		(layer "In11.Cu")
		(net "85_5INCH_IN4_DN")
	)
	(segment
		(start 365.44758 17.540224)
		(end 365.849408 16.966692)
		(width 0.1651)
		(layer "In11.Cu")
		(net "85_5INCH_IN4_DN")
	)
	(segment
		(start 369.1636 23.715472)
		(end 370.1796 23.535894)
		(width 0.1651)
		(layer "In11.Cu")
		(net "85_5INCH_IN4_DN")
	)
	(segment
		(start 354.147628 23.566374)
		(end 354.415598 23.184104)
		(width 0.1651)
		(layer "In11.Cu")
		(net "85_5INCH_IN4_DN")
	)
	(segment
		(start 361.142788 23.70455)
		(end 362.158534 23.524972)
		(width 0.1651)
		(layer "In11.Cu")
		(net "85_5INCH_IN4_DN")
	)
	(segment
		(start 371.678708 17.145)
		(end 372.22176 20.22348)
		(width 0.1651)
		(layer "In11.Cu")
		(net "85_5INCH_IN4_DN")
	)
	(segment
		(start 366.435132 23.13813)
		(end 365.44758 17.540224)
		(width 0.1651)
		(layer "In11.Cu")
		(net "85_5INCH_IN4_DN")
	)
	(segment
		(start 357.83139 16.964914)
		(end 359.078276 16.744696)
		(width 0.1651)
		(layer "In11.Cu")
		(net "85_5INCH_IN4_DN")
	)
	(segment
		(start 350.398588 23.139654)
		(end 349.41129 17.539716)
		(width 0.1651)
		(layer "In11.Cu")
		(net "85_5INCH_IN4_DN")
	)
	(segment
		(start 362.426504 23.142448)
		(end 361.43819 17.535906)
		(width 0.1651)
		(layer "In11.Cu")
		(net "85_5INCH_IN4_DN")
	)
	(segment
		(start 376.11304 20.427442)
		(end 376.40387 20.136612)
		(width 0.1651)
		(layer "In11.Cu")
		(net "85_5INCH_IN4_DN")
	)
	(segment
		(start 370.1796 23.535894)
		(end 370.447316 23.15464)
		(width 0.1651)
		(layer "In11.Cu")
		(net "85_5INCH_IN4_DN")
	)
	(segment
		(start 351.060004 16.74622)
		(end 351.633536 17.148048)
		(width 0.1651)
		(layer "In11.Cu")
		(net "85_5INCH_IN4_DN")
	)
	(segment
		(start 350.130618 23.521924)
		(end 350.398588 23.139654)
		(width 0.1651)
		(layer "In11.Cu")
		(net "85_5INCH_IN4_DN")
	)
	(segment
		(start 361.43819 17.535906)
		(end 361.840018 16.962628)
		(width 0.1651)
		(layer "In11.Cu")
		(net "85_5INCH_IN4_DN")
	)
	(segment
		(start 371.104922 16.742664)
		(end 371.678708 17.145)
		(width 0.1651)
		(layer "In11.Cu")
		(net "85_5INCH_IN4_DN")
	)
	(segment
		(start 359.651808 17.146524)
		(end 360.760772 23.43658)
		(width 0.1651)
		(layer "In11.Cu")
		(net "85_5INCH_IN4_DN")
	)
	(segment
		(start 358.152192 23.540466)
		(end 358.420162 23.157942)
		(width 0.1651)
		(layer "In11.Cu")
		(net "85_5INCH_IN4_DN")
	)
	(segment
		(start 357.136446 23.720044)
		(end 358.152192 23.540466)
		(width 0.1651)
		(layer "In11.Cu")
		(net "85_5INCH_IN4_DN")
	)
	(segment
		(start 345.101672 23.67915)
		(end 346.117418 23.499572)
		(width 0.1651)
		(layer "In11.Cu")
		(net "85_5INCH_IN4_DN")
	)
	(segment
		(start 356.754176 23.452074)
		(end 357.136446 23.720044)
		(width 0.1651)
		(layer "In11.Cu")
		(net "85_5INCH_IN4_DN")
	)
	(segment
		(start 361.840018 16.962628)
		(end 363.086904 16.74241)
		(width 0.1651)
		(layer "In11.Cu")
		(net "85_5INCH_IN4_DN")
	)
	(segment
		(start 365.151162 23.700232)
		(end 366.166908 23.520654)
		(width 0.1651)
		(layer "In11.Cu")
		(net "85_5INCH_IN4_DN")
	)
	(segment
		(start 353.420426 17.538954)
		(end 353.822254 16.965676)
		(width 0.1651)
		(layer "In11.Cu")
		(net "85_5INCH_IN4_DN")
	)
	(segment
		(start 353.822254 16.965676)
		(end 355.06914 16.745458)
		(width 0.1651)
		(layer "In11.Cu")
		(net "85_5INCH_IN4_DN")
	)
	(segment
		(start 339.772498 20.143724)
		(end 340.063328 20.434554)
		(width 0.1651)
		(layer "In11.Cu")
		(net "85_5INCH_IN4_DN")
	)
	(segment
		(start 351.633536 17.148048)
		(end 352.749612 23.477982)
		(width 0.1651)
		(layer "In11.Cu")
		(net "85_5INCH_IN4_DN")
	)
	(segment
		(start 367.670334 17.148556)
		(end 368.780314 23.447502)
		(width 0.1651)
		(layer "In11.Cu")
		(net "85_5INCH_IN4_DN")
	)
	(segment
		(start 349.41129 17.539716)
		(end 349.813118 16.966438)
		(width 0.1651)
		(layer "In11.Cu")
		(net "85_5INCH_IN4_DN")
	)
	(segment
		(start 362.158534 23.524972)
		(end 362.426504 23.142448)
		(width 0.1651)
		(layer "In11.Cu")
		(net "85_5INCH_IN4_DN")
	)
	(segment
		(start 343.942924 20.434554)
		(end 344.238072 20.68195)
		(width 0.1651)
		(layer "In11.Cu")
		(net "85_5INCH_IN4_DN")
	)
	(segment
		(start 363.086904 16.74241)
		(end 363.660436 17.144238)
		(width 0.1651)
		(layer "In11.Cu")
		(net "85_5INCH_IN4_DN")
	)
	(segment
		(start 372.51259 20.427442)
		(end 376.11304 20.427442)
		(width 0.1651)
		(layer "In11.Cu")
		(net "85_5INCH_IN4_DN")
	)
	(segment
		(start 348.732602 23.433532)
		(end 349.114872 23.701502)
		(width 0.1651)
		(layer "In11.Cu")
		(net "85_5INCH_IN4_DN")
	)
	(segment
		(start 347.052138 16.7513)
		(end 347.625416 17.153382)
		(width 0.1651)
		(layer "In11.Cu")
		(net "85_5INCH_IN4_DN")
	)
	(segment
		(start 358.420162 23.157942)
		(end 357.429562 17.538192)
		(width 0.1651)
		(layer "In11.Cu")
		(net "85_5INCH_IN4_DN")
	)
	(segment
		(start 349.813118 16.966438)
		(end 351.060004 16.74622)
		(width 0.1651)
		(layer "In11.Cu")
		(net "85_5INCH_IN4_DN")
	)
	(segment
		(start 363.660436 17.144238)
		(end 364.769146 23.432262)
		(width 0.1651)
		(layer "In11.Cu")
		(net "85_5INCH_IN4_DN")
	)
	(segment
		(start 364.769146 23.432262)
		(end 365.151162 23.700232)
		(width 0.1651)
		(layer "In11.Cu")
		(net "85_5INCH_IN4_DN")
	)
	(segment
		(start 349.114872 23.701502)
		(end 350.130618 23.521924)
		(width 0.1651)
		(layer "In11.Cu")
		(net "85_5INCH_IN4_DN")
	)
	(segment
		(start 344.238072 20.68195)
		(end 344.719402 23.41118)
		(width 0.1651)
		(layer "In11.Cu")
		(net "85_5INCH_IN4_DN")
	)
	(segment
		(start 357.429562 17.538192)
		(end 357.83139 16.964914)
		(width 0.1651)
		(layer "In11.Cu")
		(net "85_5INCH_IN4_DN")
	)
	(segment
		(start 360.760772 23.43658)
		(end 361.142788 23.70455)
		(width 0.1651)
		(layer "In11.Cu")
		(net "85_5INCH_IN4_DN")
	)
	(segment
		(start 370.447316 23.15464)
		(end 369.456208 17.536414)
		(width 0.1651)
		(layer "In11.Cu")
		(net "85_5INCH_IN4_DN")
	)
	(segment
		(start 369.456208 17.536414)
		(end 369.858036 16.962882)
		(width 0.1651)
		(layer "In11.Cu")
		(net "85_5INCH_IN4_DN")
	)
	(segment
		(start 356.010464 -63.652146)
		(end 355.920548 -63.56223)
		(width 0.13208)
		(layer "F.Cu")
		(net "P12V_SSD12_PG_G2")
	)
	(segment
		(start 356.060248 -63.70193)
		(end 356.060248 -64.496442)
		(width 0.13208)
		(layer "F.Cu")
		(net "P12V_SSD12_PG_G2")
	)
	(segment
		(start 356.010464 -63.652146)
		(end 356.060248 -63.70193)
		(width 0.13208)
		(layer "F.Cu")
		(net "P12V_SSD12_PG_G2")
	)
	(segment
		(start 356.060248 -64.496442)
		(end 355.432614 -65.124076)
		(width 0.13208)
		(layer "F.Cu")
		(net "P12V_SSD12_PG_G2")
	)
	(segment
		(start 354.789486 -65.124076)
		(end 354.789486 -64.312292)
		(width 0.13208)
		(layer "F.Cu")
		(net "P12V_SSD12_PG_G2")
	)
	(segment
		(start 355.432614 -65.124076)
		(end 354.789486 -65.124076)
		(width 0.13208)
		(layer "F.Cu")
		(net "P12V_SSD12_PG_G2")
	)
	(segment
		(start 355.920548 -63.56223)
		(end 354.789486 -63.56223)
		(width 0.13208)
		(layer "F.Cu")
		(net "P12V_SSD12_PG_G2")
	)
	(via
		(at 354.789486 -65.124076)
		(size 0.508)
		(drill 0.254)
		(layers "F.Cu" "B.Cu")
		(net "P12V_SSD12_PG_G2")
	)
	(segment
		(start 131.133088 -116.596668)
		(end 131.133088 -115.933474)
		(width 0.13208)
		(layer "F.Cu")
		(net "P3V3_NIC2_CO_DV_DT")
	)
	(segment
		(start 130.38074 -117.349016)
		(end 131.133088 -116.596668)
		(width 0.13208)
		(layer "F.Cu")
		(net "P3V3_NIC2_CO_DV_DT")
	)
	(segment
		(start 130.38074 -117.978936)
		(end 130.38074 -117.349016)
		(width 0.13208)
		(layer "F.Cu")
		(net "P3V3_NIC2_CO_DV_DT")
	)
	(via
		(at 130.38074 -117.349016)
		(size 0.508)
		(drill 0.254)
		(layers "F.Cu" "B.Cu")
		(net "P3V3_NIC2_CO_DV_DT")
	)
	(segment
		(start 219.350082 17.57299)
		(end 218.90101 15.0241)
		(width 0.13462)
		(layer "F.Cu")
		(net "85_5INCH_TOP_DN")
	)
	(segment
		(start 243.209064 17.757902)
		(end 243.367814 17.891252)
		(width 0.13462)
		(layer "F.Cu")
		(net "85_5INCH_TOP_DN")
	)
	(segment
		(start 240.617248 22.053296)
		(end 241.572796 21.88464)
		(width 0.13462)
		(layer "F.Cu")
		(net "85_5INCH_TOP_DN")
	)
	(segment
		(start 225.817938 21.848572)
		(end 226.128834 22.06625)
		(width 0.13462)
		(layer "F.Cu")
		(net "85_5INCH_TOP_DN")
	)
	(segment
		(start 224.052638 14.314424)
		(end 224.550224 14.663166)
		(width 0.13462)
		(layer "F.Cu")
		(net "85_5INCH_TOP_DN")
	)
	(segment
		(start 239.039654 14.656562)
		(end 240.306606 21.835618)
		(width 0.13462)
		(layer "F.Cu")
		(net "85_5INCH_TOP_DN")
	)
	(segment
		(start 236.680502 21.823426)
		(end 236.992414 22.041612)
		(width 0.13462)
		(layer "F.Cu")
		(net "85_5INCH_TOP_DN")
	)
	(segment
		(start 224.550224 14.663166)
		(end 225.817938 21.848572)
		(width 0.13462)
		(layer "F.Cu")
		(net "85_5INCH_TOP_DN")
	)
	(segment
		(start 229.771956 22.182582)
		(end 230.727758 22.013926)
		(width 0.13462)
		(layer "F.Cu")
		(net "85_5INCH_TOP_DN")
	)
	(segment
		(start 230.115618 14.513052)
		(end 231.296718 14.304518)
		(width 0.13462)
		(layer "F.Cu")
		(net "85_5INCH_TOP_DN")
	)
	(segment
		(start 222.508064 22.076156)
		(end 223.46412 21.907246)
		(width 0.13462)
		(layer "F.Cu")
		(net "85_5INCH_TOP_DN")
	)
	(segment
		(start 234.60075 21.883878)
		(end 233.387392 15.000224)
		(width 0.13462)
		(layer "F.Cu")
		(net "85_5INCH_TOP_DN")
	)
	(segment
		(start 230.945944 21.702014)
		(end 229.766622 15.011146)
		(width 0.13462)
		(layer "F.Cu")
		(net "85_5INCH_TOP_DN")
	)
	(segment
		(start 226.60483 14.49451)
		(end 227.673662 14.306042)
		(width 0.13462)
		(layer "F.Cu")
		(net "85_5INCH_TOP_DN")
	)
	(segment
		(start 220.43009 14.316964)
		(end 220.928184 14.665452)
		(width 0.13462)
		(layer "F.Cu")
		(net "85_5INCH_TOP_DN")
	)
	(segment
		(start 227.303076 21.585682)
		(end 226.144328 15.012416)
		(width 0.13462)
		(layer "F.Cu")
		(net "85_5INCH_TOP_DN")
	)
	(segment
		(start 229.766622 15.011146)
		(end 230.115618 14.513052)
		(width 0.13462)
		(layer "F.Cu")
		(net "85_5INCH_TOP_DN")
	)
	(segment
		(start 247.403874 17.778476)
		(end 247.595644 17.778476)
		(width 0.13462)
		(layer "F.Cu")
		(net "85_5INCH_TOP_DN")
	)
	(segment
		(start 223.682306 21.595588)
		(end 222.523304 15.020798)
		(width 0.13462)
		(layer "F.Cu")
		(net "85_5INCH_TOP_DN")
	)
	(segment
		(start 237.360714 14.516862)
		(end 238.54156 14.308074)
		(width 0.13462)
		(layer "F.Cu")
		(net "85_5INCH_TOP_DN")
	)
	(segment
		(start 218.23426 17.898364)
		(end 219.247212 17.719802)
		(width 0.13462)
		(layer "F.Cu")
		(net "85_5INCH_TOP_DN")
	)
	(segment
		(start 219.24899 14.52499)
		(end 220.43009 14.316964)
		(width 0.13462)
		(layer "F.Cu")
		(net "85_5INCH_TOP_DN")
	)
	(segment
		(start 222.983552 14.502892)
		(end 222.983806 14.502892)
		(width 0.13462)
		(layer "F.Cu")
		(net "85_5INCH_TOP_DN")
	)
	(segment
		(start 234.382564 22.19579)
		(end 234.60075 21.883878)
		(width 0.13462)
		(layer "F.Cu")
		(net "85_5INCH_TOP_DN")
	)
	(segment
		(start 228.171248 14.654784)
		(end 229.46106 21.964904)
		(width 0.13462)
		(layer "F.Cu")
		(net "85_5INCH_TOP_DN")
	)
	(segment
		(start 243.367814 17.891252)
		(end 247.291098 17.891252)
		(width 0.13462)
		(layer "F.Cu")
		(net "85_5INCH_TOP_DN")
	)
	(segment
		(start 231.296718 14.304518)
		(end 231.793796 14.65326)
		(width 0.13462)
		(layer "F.Cu")
		(net "85_5INCH_TOP_DN")
	)
	(segment
		(start 226.144328 15.012416)
		(end 226.492562 14.514322)
		(width 0.13462)
		(layer "F.Cu")
		(net "85_5INCH_TOP_DN")
	)
	(segment
		(start 240.98377 14.519656)
		(end 242.16487 14.311122)
		(width 0.13462)
		(layer "F.Cu")
		(net "85_5INCH_TOP_DN")
	)
	(segment
		(start 233.387392 15.000224)
		(end 233.736388 14.50213)
		(width 0.13462)
		(layer "F.Cu")
		(net "85_5INCH_TOP_DN")
	)
	(segment
		(start 227.08489 21.89734)
		(end 227.303076 21.585682)
		(width 0.13462)
		(layer "F.Cu")
		(net "85_5INCH_TOP_DN")
	)
	(segment
		(start 226.492562 14.514322)
		(end 226.604576 14.49451)
		(width 0.13462)
		(layer "F.Cu")
		(net "85_5INCH_TOP_DN")
	)
	(segment
		(start 220.928184 14.665452)
		(end 222.19666 21.858224)
		(width 0.13462)
		(layer "F.Cu")
		(net "85_5INCH_TOP_DN")
	)
	(segment
		(start 233.11485 22.146006)
		(end 233.426762 22.364446)
		(width 0.13462)
		(layer "F.Cu")
		(net "85_5INCH_TOP_DN")
	)
	(segment
		(start 226.128834 22.06625)
		(end 227.08489 21.89734)
		(width 0.13462)
		(layer "F.Cu")
		(net "85_5INCH_TOP_DN")
	)
	(segment
		(start 223.46412 21.907246)
		(end 223.682306 21.595588)
		(width 0.13462)
		(layer "F.Cu")
		(net "85_5INCH_TOP_DN")
	)
	(segment
		(start 240.306606 21.835618)
		(end 240.617248 22.053296)
		(width 0.13462)
		(layer "F.Cu")
		(net "85_5INCH_TOP_DN")
	)
	(segment
		(start 237.012226 15.013432)
		(end 237.360714 14.516862)
		(width 0.13462)
		(layer "F.Cu")
		(net "85_5INCH_TOP_DN")
	)
	(segment
		(start 218.90101 15.0241)
		(end 219.24899 14.52499)
		(width 0.13462)
		(layer "F.Cu")
		(net "85_5INCH_TOP_DN")
	)
	(segment
		(start 241.572796 21.88464)
		(end 241.790982 21.572982)
		(width 0.13462)
		(layer "F.Cu")
		(net "85_5INCH_TOP_DN")
	)
	(segment
		(start 222.523304 15.020798)
		(end 222.871538 14.522704)
		(width 0.13462)
		(layer "F.Cu")
		(net "85_5INCH_TOP_DN")
	)
	(segment
		(start 230.727758 22.013926)
		(end 230.945944 21.702014)
		(width 0.13462)
		(layer "F.Cu")
		(net "85_5INCH_TOP_DN")
	)
	(segment
		(start 231.793796 14.65326)
		(end 233.11485 22.146006)
		(width 0.13462)
		(layer "F.Cu")
		(net "85_5INCH_TOP_DN")
	)
	(segment
		(start 219.247212 17.719802)
		(end 219.350082 17.57299)
		(width 0.13462)
		(layer "F.Cu")
		(net "85_5INCH_TOP_DN")
	)
	(segment
		(start 233.426762 22.364446)
		(end 234.382564 22.19579)
		(width 0.13462)
		(layer "F.Cu")
		(net "85_5INCH_TOP_DN")
	)
	(segment
		(start 238.54156 14.308074)
		(end 239.039654 14.656562)
		(width 0.13462)
		(layer "F.Cu")
		(net "85_5INCH_TOP_DN")
	)
	(segment
		(start 238.166656 21.561298)
		(end 237.012226 15.013432)
		(width 0.13462)
		(layer "F.Cu")
		(net "85_5INCH_TOP_DN")
	)
	(segment
		(start 236.992414 22.041612)
		(end 237.94847 21.872956)
		(width 0.13462)
		(layer "F.Cu")
		(net "85_5INCH_TOP_DN")
	)
	(segment
		(start 229.46106 21.964904)
		(end 229.771956 22.182582)
		(width 0.13462)
		(layer "F.Cu")
		(net "85_5INCH_TOP_DN")
	)
	(segment
		(start 241.790982 21.572982)
		(end 240.635282 15.016988)
		(width 0.13462)
		(layer "F.Cu")
		(net "85_5INCH_TOP_DN")
	)
	(segment
		(start 214.93607 17.898364)
		(end 218.23426 17.898364)
		(width 0.13462)
		(layer "F.Cu")
		(net "85_5INCH_TOP_DN")
	)
	(segment
		(start 214.823294 17.785588)
		(end 214.93607 17.898364)
		(width 0.13462)
		(layer "F.Cu")
		(net "85_5INCH_TOP_DN")
	)
	(segment
		(start 227.673662 14.306042)
		(end 228.171248 14.654784)
		(width 0.13462)
		(layer "F.Cu")
		(net "85_5INCH_TOP_DN")
	)
	(segment
		(start 235.414566 14.642084)
		(end 236.680502 21.823426)
		(width 0.13462)
		(layer "F.Cu")
		(net "85_5INCH_TOP_DN")
	)
	(segment
		(start 240.635282 15.016988)
		(end 240.98377 14.519656)
		(width 0.13462)
		(layer "F.Cu")
		(net "85_5INCH_TOP_DN")
	)
	(segment
		(start 233.736388 14.50213)
		(end 234.917234 14.293342)
		(width 0.13462)
		(layer "F.Cu")
		(net "85_5INCH_TOP_DN")
	)
	(segment
		(start 242.662964 14.65961)
		(end 243.209064 17.757902)
		(width 0.13462)
		(layer "F.Cu")
		(net "85_5INCH_TOP_DN")
	)
	(segment
		(start 222.871538 14.522704)
		(end 222.983552 14.502892)
		(width 0.13462)
		(layer "F.Cu")
		(net "85_5INCH_TOP_DN")
	)
	(segment
		(start 247.291098 17.891252)
		(end 247.403874 17.778476)
		(width 0.13462)
		(layer "F.Cu")
		(net "85_5INCH_TOP_DN")
	)
	(segment
		(start 242.16487 14.311122)
		(end 242.662964 14.65961)
		(width 0.13462)
		(layer "F.Cu")
		(net "85_5INCH_TOP_DN")
	)
	(segment
		(start 234.917234 14.293342)
		(end 235.414566 14.642084)
		(width 0.13462)
		(layer "F.Cu")
		(net "85_5INCH_TOP_DN")
	)
	(segment
		(start 222.983806 14.502892)
		(end 224.052638 14.314424)
		(width 0.13462)
		(layer "F.Cu")
		(net "85_5INCH_TOP_DN")
	)
	(segment
		(start 226.604576 14.49451)
		(end 226.60483 14.49451)
		(width 0.13462)
		(layer "F.Cu")
		(net "85_5INCH_TOP_DN")
	)
	(segment
		(start 222.19666 21.858224)
		(end 222.508064 22.076156)
		(width 0.13462)
		(layer "F.Cu")
		(net "85_5INCH_TOP_DN")
	)
	(segment
		(start 237.94847 21.872956)
		(end 238.166656 21.561298)
		(width 0.13462)
		(layer "F.Cu")
		(net "85_5INCH_TOP_DN")
	)
	(segment
		(start 214.631524 17.785588)
		(end 214.823294 17.785588)
		(width 0.13462)
		(layer "F.Cu")
		(net "85_5INCH_TOP_DN")
	)
	(segment
		(start 352.989642 -63.56223)
		(end 352.547682 -63.56223)
		(width 0.13208)
		(layer "F.Cu")
		(net "P12V_SSD12_PG_G1")
	)
	(segment
		(start 352.258884 -63.273432)
		(end 352.189796 -63.273432)
		(width 0.13208)
		(layer "F.Cu")
		(net "P12V_SSD12_PG_G1")
	)
	(segment
		(start 352.547682 -63.56223)
		(end 352.258884 -63.273432)
		(width 0.13208)
		(layer "F.Cu")
		(net "P12V_SSD12_PG_G1")
	)
	(segment
		(start 352.189796 -63.273432)
		(end 352.002598 -63.086234)
		(width 0.13208)
		(layer "F.Cu")
		(net "P12V_SSD12_PG_G1")
	)
	(segment
		(start 352.002598 -63.086234)
		(end 351.57537 -63.086234)
		(width 0.13208)
		(layer "F.Cu")
		(net "P12V_SSD12_PG_G1")
	)
	(segment
		(start 351.57537 -64.102234)
		(end 351.57537 -63.086234)
		(width 0.13208)
		(layer "F.Cu")
		(net "P12V_SSD12_PG_G1")
	)
	(via
		(at 352.258884 -63.273432)
		(size 0.508)
		(drill 0.254)
		(layers "F.Cu" "B.Cu")
		(net "P12V_SSD12_PG_G1")
	)
	(segment
		(start 220.225366 -124.790962)
		(end 220.225366 -123.774962)
		(width 0.13208)
		(layer "F.Cu")
		(net "P3V3_NIC3_PG_G1")
	)
	(segment
		(start 220.968316 -123.774962)
		(end 220.225366 -123.774962)
		(width 0.13208)
		(layer "F.Cu")
		(net "P3V3_NIC3_PG_G1")
	)
	(segment
		(start 221.719394 -122.758962)
		(end 221.222316 -122.758962)
		(width 0.13208)
		(layer "F.Cu")
		(net "P3V3_NIC3_PG_G1")
	)
	(segment
		(start 221.222316 -122.758962)
		(end 220.968316 -123.012962)
		(width 0.13208)
		(layer "F.Cu")
		(net "P3V3_NIC3_PG_G1")
	)
	(segment
		(start 220.968316 -123.012962)
		(end 220.968316 -123.774962)
		(width 0.13208)
		(layer "F.Cu")
		(net "P3V3_NIC3_PG_G1")
	)
	(via
		(at 220.968316 -123.774962)
		(size 0.508)
		(drill 0.254)
		(layers "F.Cu" "B.Cu")
		(net "P3V3_NIC3_PG_G1")
	)
	(segment
		(start 321.943222 -115.370356)
		(end 321.64655 -115.370356)
		(width 0.13208)
		(layer "F.Cu")
		(net "P3V3_NIC5_CO_EN")
	)
	(segment
		(start 322.408042 -115.835176)
		(end 321.943222 -115.370356)
		(width 0.13208)
		(layer "F.Cu")
		(net "P3V3_NIC5_CO_EN")
	)
	(segment
		(start 321.64655 -115.370356)
		(end 321.61607 -115.400836)
		(width 0.13208)
		(layer "F.Cu")
		(net "P3V3_NIC5_CO_EN")
	)
	(segment
		(start 321.61607 -115.400836)
		(end 321.252342 -115.400836)
		(width 0.13208)
		(layer "F.Cu")
		(net "P3V3_NIC5_CO_EN")
	)
	(segment
		(start 322.824602 -115.835176)
		(end 322.408042 -115.835176)
		(width 0.13208)
		(layer "F.Cu")
		(net "P3V3_NIC5_CO_EN")
	)
	(via
		(at 321.943222 -115.370356)
		(size 0.508)
		(drill 0.254)
		(layers "F.Cu" "B.Cu")
		(net "P3V3_NIC5_CO_EN")
	)
	(segment
		(start 328.931524 8.36676)
		(end 329.612498 8.548624)
		(width 0.13462)
		(layer "F.Cu")
		(net "85_10INCH_IN2_DP")
	)
	(segment
		(start 386.065268 8.392668)
		(end 385.384294 8.574532)
		(width 0.13462)
		(layer "F.Cu")
		(net "85_10INCH_IN2_DP")
	)
	(segment
		(start 336.162396 12.952476)
		(end 336.564478 12.37869)
		(width 0.1651)
		(layer "In7.Cu")
		(net "85_10INCH_IN2_DP")
	)
	(segment
		(start 336.93481 4.733036)
		(end 338.35594 12.791694)
		(width 0.1651)
		(layer "In7.Cu")
		(net "85_10INCH_IN2_DP")
	)
	(segment
		(start 344.202766 13.076936)
		(end 344.604848 12.503404)
		(width 0.1651)
		(layer "In7.Cu")
		(net "85_10INCH_IN2_DP")
	)
	(segment
		(start 343.288366 5.03682)
		(end 343.556082 4.654804)
		(width 0.1651)
		(layer "In7.Cu")
		(net "85_10INCH_IN2_DP")
	)
	(segment
		(start 342.383364 12.895072)
		(end 342.956896 13.297154)
		(width 0.1651)
		(layer "In7.Cu")
		(net "85_10INCH_IN2_DP")
	)
	(segment
		(start 362.43133 12.908788)
		(end 363.005116 13.31087)
		(width 0.1651)
		(layer "In7.Cu")
		(net "85_10INCH_IN2_DP")
	)
	(segment
		(start 360.992166 4.74599)
		(end 362.43133 12.908788)
		(width 0.1651)
		(layer "In7.Cu")
		(net "85_10INCH_IN2_DP")
	)
	(segment
		(start 354.40112 12.841986)
		(end 354.974906 13.244068)
		(width 0.1651)
		(layer "In7.Cu")
		(net "85_10INCH_IN2_DP")
	)
	(segment
		(start 367.340642 5.020818)
		(end 367.608358 4.638802)
		(width 0.1651)
		(layer "In7.Cu")
		(net "85_10INCH_IN2_DP")
	)
	(segment
		(start 379.641354 4.671314)
		(end 380.657862 4.491736)
		(width 0.1651)
		(layer "In7.Cu")
		(net "85_10INCH_IN2_DP")
	)
	(segment
		(start 347.564202 4.6482)
		(end 348.580964 4.468622)
		(width 0.1651)
		(layer "In7.Cu")
		(net "85_10INCH_IN2_DP")
	)
	(segment
		(start 333.633572 8.749538)
		(end 334.342994 12.770612)
		(width 0.1651)
		(layer "In7.Cu")
		(net "85_10INCH_IN2_DP")
	)
	(segment
		(start 376.644916 4.470654)
		(end 377.02744 4.738624)
		(width 0.1651)
		(layer "In7.Cu")
		(net "85_10INCH_IN2_DP")
	)
	(segment
		(start 363.333792 5.034534)
		(end 363.601508 4.652518)
		(width 0.1651)
		(layer "In7.Cu")
		(net "85_10INCH_IN2_DP")
	)
	(segment
		(start 346.96908 13.312648)
		(end 348.21495 13.09243)
		(width 0.1651)
		(layer "In7.Cu")
		(net "85_10INCH_IN2_DP")
	)
	(segment
		(start 376.265948 13.020294)
		(end 376.668284 12.446508)
		(width 0.1651)
		(layer "In7.Cu")
		(net "85_10INCH_IN2_DP")
	)
	(segment
		(start 352.9711 4.731512)
		(end 354.40112 12.841986)
		(width 0.1651)
		(layer "In7.Cu")
		(net "85_10INCH_IN2_DP")
	)
	(segment
		(start 344.604848 12.503404)
		(end 343.288366 5.03682)
		(width 0.1651)
		(layer "In7.Cu")
		(net "85_10INCH_IN2_DP")
	)
	(segment
		(start 381.040386 4.75996)
		(end 381.605028 7.961884)
		(width 0.1651)
		(layer "In7.Cu")
		(net "85_10INCH_IN2_DP")
	)
	(segment
		(start 370.440204 12.85494)
		(end 371.01399 13.257022)
		(width 0.1651)
		(layer "In7.Cu")
		(net "85_10INCH_IN2_DP")
	)
	(segment
		(start 348.580964 4.468622)
		(end 348.96298 4.736338)
		(width 0.1651)
		(layer "In7.Cu")
		(net "85_10INCH_IN2_DP")
	)
	(segment
		(start 351.572322 4.643374)
		(end 352.589084 4.463796)
		(width 0.1651)
		(layer "In7.Cu")
		(net "85_10INCH_IN2_DP")
	)
	(segment
		(start 351.304606 5.02539)
		(end 351.572322 4.643374)
		(width 0.1651)
		(layer "In7.Cu")
		(net "85_10INCH_IN2_DP")
	)
	(segment
		(start 379.373638 5.05333)
		(end 379.641354 4.671314)
		(width 0.1651)
		(layer "In7.Cu")
		(net "85_10INCH_IN2_DP")
	)
	(segment
		(start 344.95486 4.742942)
		(end 346.394786 12.910566)
		(width 0.1651)
		(layer "In7.Cu")
		(net "85_10INCH_IN2_DP")
	)
	(segment
		(start 363.601508 4.652518)
		(end 364.61827 4.47294)
		(width 0.1651)
		(layer "In7.Cu")
		(net "85_10INCH_IN2_DP")
	)
	(segment
		(start 360.609896 4.478274)
		(end 360.992166 4.74599)
		(width 0.1651)
		(layer "In7.Cu")
		(net "85_10INCH_IN2_DP")
	)
	(segment
		(start 375.020078 13.240512)
		(end 376.265948 13.020294)
		(width 0.1651)
		(layer "In7.Cu")
		(net "85_10INCH_IN2_DP")
	)
	(segment
		(start 342.956896 13.297154)
		(end 344.202766 13.076936)
		(width 0.1651)
		(layer "In7.Cu")
		(net "85_10INCH_IN2_DP")
	)
	(segment
		(start 373.017034 4.731766)
		(end 374.446292 12.83843)
		(width 0.1651)
		(layer "In7.Cu")
		(net "85_10INCH_IN2_DP")
	)
	(segment
		(start 372.25986 13.036804)
		(end 372.661942 12.463272)
		(width 0.1651)
		(layer "In7.Cu")
		(net "85_10INCH_IN2_DP")
	)
	(segment
		(start 371.01399 13.257022)
		(end 372.25986 13.036804)
		(width 0.1651)
		(layer "In7.Cu")
		(net "85_10INCH_IN2_DP")
	)
	(segment
		(start 339.27796 5.03047)
		(end 339.545676 4.648454)
		(width 0.1651)
		(layer "In7.Cu")
		(net "85_10INCH_IN2_DP")
	)
	(segment
		(start 356.622858 12.450318)
		(end 355.315012 5.033264)
		(width 0.1651)
		(layer "In7.Cu")
		(net "85_10INCH_IN2_DP")
	)
	(segment
		(start 359.593134 4.657852)
		(end 360.609896 4.478274)
		(width 0.1651)
		(layer "In7.Cu")
		(net "85_10INCH_IN2_DP")
	)
	(segment
		(start 343.556082 4.654804)
		(end 344.572844 4.475226)
		(width 0.1651)
		(layer "In7.Cu")
		(net "85_10INCH_IN2_DP")
	)
	(segment
		(start 356.98176 4.73964)
		(end 358.41432 12.864338)
		(width 0.1651)
		(layer "In7.Cu")
		(net "85_10INCH_IN2_DP")
	)
	(segment
		(start 348.21495 13.09243)
		(end 348.617032 12.519406)
		(width 0.1651)
		(layer "In7.Cu")
		(net "85_10INCH_IN2_DP")
	)
	(segment
		(start 356.220776 13.02385)
		(end 356.622858 12.450318)
		(width 0.1651)
		(layer "In7.Cu")
		(net "85_10INCH_IN2_DP")
	)
	(segment
		(start 338.929218 13.193522)
		(end 340.174834 12.97305)
		(width 0.1651)
		(layer "In7.Cu")
		(net "85_10INCH_IN2_DP")
	)
	(segment
		(start 375.628154 4.650232)
		(end 376.644916 4.470654)
		(width 0.1651)
		(layer "In7.Cu")
		(net "85_10INCH_IN2_DP")
	)
	(segment
		(start 334.916526 13.172694)
		(end 336.162396 12.952476)
		(width 0.1651)
		(layer "In7.Cu")
		(net "85_10INCH_IN2_DP")
	)
	(segment
		(start 374.446292 12.83843)
		(end 375.020078 13.240512)
		(width 0.1651)
		(layer "In7.Cu")
		(net "85_10INCH_IN2_DP")
	)
	(segment
		(start 364.250986 13.090652)
		(end 364.653068 12.51712)
		(width 0.1651)
		(layer "In7.Cu")
		(net "85_10INCH_IN2_DP")
	)
	(segment
		(start 336.552794 4.46532)
		(end 336.93481 4.733036)
		(width 0.1651)
		(layer "In7.Cu")
		(net "85_10INCH_IN2_DP")
	)
	(segment
		(start 360.636058 12.47267)
		(end 359.325418 5.039868)
		(width 0.1651)
		(layer "In7.Cu")
		(net "85_10INCH_IN2_DP")
	)
	(segment
		(start 378.458222 12.85367)
		(end 379.032008 13.255752)
		(width 0.1651)
		(layer "In7.Cu")
		(net "85_10INCH_IN2_DP")
	)
	(segment
		(start 358.41432 12.864338)
		(end 358.988106 13.26642)
		(width 0.1651)
		(layer "In7.Cu")
		(net "85_10INCH_IN2_DP")
	)
	(segment
		(start 350.96958 13.26515)
		(end 352.21545 13.044932)
		(width 0.1651)
		(layer "In7.Cu")
		(net "85_10INCH_IN2_DP")
	)
	(segment
		(start 348.96298 4.736338)
		(end 350.395794 12.863068)
		(width 0.1651)
		(layer "In7.Cu")
		(net "85_10INCH_IN2_DP")
	)
	(segment
		(start 338.35594 12.791694)
		(end 338.929218 13.193522)
		(width 0.1651)
		(layer "In7.Cu")
		(net "85_10INCH_IN2_DP")
	)
	(segment
		(start 356.59949 4.47167)
		(end 356.98176 4.73964)
		(width 0.1651)
		(layer "In7.Cu")
		(net "85_10INCH_IN2_DP")
	)
	(segment
		(start 340.57717 12.39901)
		(end 339.27796 5.03047)
		(width 0.1651)
		(layer "In7.Cu")
		(net "85_10INCH_IN2_DP")
	)
	(segment
		(start 380.657862 4.491736)
		(end 381.040386 4.75996)
		(width 0.1651)
		(layer "In7.Cu")
		(net "85_10INCH_IN2_DP")
	)
	(segment
		(start 380.277878 13.035534)
		(end 380.67996 12.462002)
		(width 0.1651)
		(layer "In7.Cu")
		(net "85_10INCH_IN2_DP")
	)
	(segment
		(start 352.21545 13.044932)
		(end 352.617532 12.4714)
		(width 0.1651)
		(layer "In7.Cu")
		(net "85_10INCH_IN2_DP")
	)
	(segment
		(start 344.572844 4.475226)
		(end 344.95486 4.742942)
		(width 0.1651)
		(layer "In7.Cu")
		(net "85_10INCH_IN2_DP")
	)
	(segment
		(start 366.435894 12.88288)
		(end 367.00968 13.284962)
		(width 0.1651)
		(layer "In7.Cu")
		(net "85_10INCH_IN2_DP")
	)
	(segment
		(start 350.395794 12.863068)
		(end 350.96958 13.26515)
		(width 0.1651)
		(layer "In7.Cu")
		(net "85_10INCH_IN2_DP")
	)
	(segment
		(start 385.093464 8.283702)
		(end 385.384294 8.574532)
		(width 0.1651)
		(layer "In7.Cu")
		(net "85_10INCH_IN2_DP")
	)
	(segment
		(start 336.564478 12.37869)
		(end 335.268316 5.026914)
		(width 0.1651)
		(layer "In7.Cu")
		(net "85_10INCH_IN2_DP")
	)
	(segment
		(start 379.032008 13.255752)
		(end 380.277878 13.035534)
		(width 0.1651)
		(layer "In7.Cu")
		(net "85_10INCH_IN2_DP")
	)
	(segment
		(start 348.617032 12.519406)
		(end 347.296486 5.030216)
		(width 0.1651)
		(layer "In7.Cu")
		(net "85_10INCH_IN2_DP")
	)
	(segment
		(start 369.007136 4.72694)
		(end 370.440204 12.85494)
		(width 0.1651)
		(layer "In7.Cu")
		(net "85_10INCH_IN2_DP")
	)
	(segment
		(start 372.661942 12.463272)
		(end 371.35054 5.025644)
		(width 0.1651)
		(layer "In7.Cu")
		(net "85_10INCH_IN2_DP")
	)
	(segment
		(start 364.61827 4.47294)
		(end 365.000286 4.740656)
		(width 0.1651)
		(layer "In7.Cu")
		(net "85_10INCH_IN2_DP")
	)
	(segment
		(start 346.394786 12.910566)
		(end 346.96908 13.312648)
		(width 0.1651)
		(layer "In7.Cu")
		(net "85_10INCH_IN2_DP")
	)
	(segment
		(start 363.005116 13.31087)
		(end 364.250986 13.090652)
		(width 0.1651)
		(layer "In7.Cu")
		(net "85_10INCH_IN2_DP")
	)
	(segment
		(start 335.536032 4.644898)
		(end 336.552794 4.46532)
		(width 0.1651)
		(layer "In7.Cu")
		(net "85_10INCH_IN2_DP")
	)
	(segment
		(start 367.00968 13.284962)
		(end 368.25555 13.064744)
		(width 0.1651)
		(layer "In7.Cu")
		(net "85_10INCH_IN2_DP")
	)
	(segment
		(start 335.268316 5.026914)
		(end 335.536032 4.644898)
		(width 0.1651)
		(layer "In7.Cu")
		(net "85_10INCH_IN2_DP")
	)
	(segment
		(start 376.668284 12.446508)
		(end 375.360438 5.032248)
		(width 0.1651)
		(layer "In7.Cu")
		(net "85_10INCH_IN2_DP")
	)
	(segment
		(start 371.618256 4.643628)
		(end 372.635018 4.46405)
		(width 0.1651)
		(layer "In7.Cu")
		(net "85_10INCH_IN2_DP")
	)
	(segment
		(start 365.000286 4.740656)
		(end 366.435894 12.88288)
		(width 0.1651)
		(layer "In7.Cu")
		(net "85_10INCH_IN2_DP")
	)
	(segment
		(start 334.342994 12.770612)
		(end 334.916526 13.172694)
		(width 0.1651)
		(layer "In7.Cu")
		(net "85_10INCH_IN2_DP")
	)
	(segment
		(start 368.62512 4.459224)
		(end 369.007136 4.72694)
		(width 0.1651)
		(layer "In7.Cu")
		(net "85_10INCH_IN2_DP")
	)
	(segment
		(start 352.617532 12.4714)
		(end 351.304606 5.02539)
		(width 0.1651)
		(layer "In7.Cu")
		(net "85_10INCH_IN2_DP")
	)
	(segment
		(start 360.233976 13.046202)
		(end 360.636058 12.47267)
		(width 0.1651)
		(layer "In7.Cu")
		(net "85_10INCH_IN2_DP")
	)
	(segment
		(start 339.545676 4.648454)
		(end 340.562438 4.468876)
		(width 0.1651)
		(layer "In7.Cu")
		(net "85_10INCH_IN2_DP")
	)
	(segment
		(start 377.02744 4.738624)
		(end 378.458222 12.85367)
		(width 0.1651)
		(layer "In7.Cu")
		(net "85_10INCH_IN2_DP")
	)
	(segment
		(start 354.974906 13.244068)
		(end 356.220776 13.02385)
		(width 0.1651)
		(layer "In7.Cu")
		(net "85_10INCH_IN2_DP")
	)
	(segment
		(start 340.174834 12.97305)
		(end 340.57717 12.39901)
		(width 0.1651)
		(layer "In7.Cu")
		(net "85_10INCH_IN2_DP")
	)
	(segment
		(start 329.903328 8.257794)
		(end 333.141828 8.257794)
		(width 0.1651)
		(layer "In7.Cu")
		(net "85_10INCH_IN2_DP")
	)
	(segment
		(start 347.296486 5.030216)
		(end 347.564202 4.6482)
		(width 0.1651)
		(layer "In7.Cu")
		(net "85_10INCH_IN2_DP")
	)
	(segment
		(start 371.35054 5.025644)
		(end 371.618256 4.643628)
		(width 0.1651)
		(layer "In7.Cu")
		(net "85_10INCH_IN2_DP")
	)
	(segment
		(start 372.635018 4.46405)
		(end 373.017034 4.731766)
		(width 0.1651)
		(layer "In7.Cu")
		(net "85_10INCH_IN2_DP")
	)
	(segment
		(start 368.657632 12.491212)
		(end 367.340642 5.020818)
		(width 0.1651)
		(layer "In7.Cu")
		(net "85_10INCH_IN2_DP")
	)
	(segment
		(start 329.612498 8.548624)
		(end 329.903328 8.257794)
		(width 0.1651)
		(layer "In7.Cu")
		(net "85_10INCH_IN2_DP")
	)
	(segment
		(start 375.360438 5.032248)
		(end 375.628154 4.650232)
		(width 0.1651)
		(layer "In7.Cu")
		(net "85_10INCH_IN2_DP")
	)
	(segment
		(start 340.944454 4.736592)
		(end 342.383364 12.895072)
		(width 0.1651)
		(layer "In7.Cu")
		(net "85_10INCH_IN2_DP")
	)
	(segment
		(start 355.315012 5.033264)
		(end 355.582728 4.651248)
		(width 0.1651)
		(layer "In7.Cu")
		(net "85_10INCH_IN2_DP")
	)
	(segment
		(start 333.141828 8.257794)
		(end 333.633572 8.749538)
		(width 0.1651)
		(layer "In7.Cu")
		(net "85_10INCH_IN2_DP")
	)
	(segment
		(start 352.589084 4.463796)
		(end 352.9711 4.731512)
		(width 0.1651)
		(layer "In7.Cu")
		(net "85_10INCH_IN2_DP")
	)
	(segment
		(start 382.06426 8.283702)
		(end 385.093464 8.283702)
		(width 0.1651)
		(layer "In7.Cu")
		(net "85_10INCH_IN2_DP")
	)
	(segment
		(start 381.605028 7.961884)
		(end 382.06426 8.283702)
		(width 0.1651)
		(layer "In7.Cu")
		(net "85_10INCH_IN2_DP")
	)
	(segment
		(start 340.562438 4.468876)
		(end 340.944454 4.736592)
		(width 0.1651)
		(layer "In7.Cu")
		(net "85_10INCH_IN2_DP")
	)
	(segment
		(start 380.67996 12.462002)
		(end 379.373638 5.05333)
		(width 0.1651)
		(layer "In7.Cu")
		(net "85_10INCH_IN2_DP")
	)
	(segment
		(start 367.608358 4.638802)
		(end 368.62512 4.459224)
		(width 0.1651)
		(layer "In7.Cu")
		(net "85_10INCH_IN2_DP")
	)
	(segment
		(start 358.988106 13.26642)
		(end 360.233976 13.046202)
		(width 0.1651)
		(layer "In7.Cu")
		(net "85_10INCH_IN2_DP")
	)
	(segment
		(start 359.325418 5.039868)
		(end 359.593134 4.657852)
		(width 0.1651)
		(layer "In7.Cu")
		(net "85_10INCH_IN2_DP")
	)
	(segment
		(start 368.25555 13.064744)
		(end 368.657632 12.491212)
		(width 0.1651)
		(layer "In7.Cu")
		(net "85_10INCH_IN2_DP")
	)
	(segment
		(start 364.653068 12.51712)
		(end 363.333792 5.034534)
		(width 0.1651)
		(layer "In7.Cu")
		(net "85_10INCH_IN2_DP")
	)
	(segment
		(start 355.582728 4.651248)
		(end 356.59949 4.47167)
		(width 0.1651)
		(layer "In7.Cu")
		(net "85_10INCH_IN2_DP")
	)
	(segment
		(start 446.875408 -71.113396)
		(end 446.875408 -70.479158)
		(width 0.13208)
		(layer "F.Cu")
		(net "P12V_SSD15_CO_ILIMIT")
	)
	(segment
		(start 447.58991 -71.827898)
		(end 447.38544 -71.623428)
		(width 0.13208)
		(layer "F.Cu")
		(net "P12V_SSD15_CO_ILIMIT")
	)
	(segment
		(start 447.38544 -71.623428)
		(end 446.875408 -71.113396)
		(width 0.13208)
		(layer "F.Cu")
		(net "P12V_SSD15_CO_ILIMIT")
	)
	(segment
		(start 447.58991 -72.366632)
		(end 447.58991 -71.827898)
		(width 0.13208)
		(layer "F.Cu")
		(net "P12V_SSD15_CO_ILIMIT")
	)
	(via
		(at 447.38544 -71.623428)
		(size 0.508)
		(drill 0.254)
		(layers "F.Cu" "B.Cu")
		(net "P12V_SSD15_CO_ILIMIT")
	)
	(segment
		(start 127.439166 -117.200426)
		(end 128.201166 -117.200426)
		(width 0.13208)
		(layer "F.Cu")
		(net "P3V3_NIC2_PG_G1")
	)
	(segment
		(start 127.185166 -116.449348)
		(end 127.185166 -116.946426)
		(width 0.13208)
		(layer "F.Cu")
		(net "P3V3_NIC2_PG_G1")
	)
	(segment
		(start 128.201166 -117.200426)
		(end 128.201166 -117.943376)
		(width 0.13208)
		(layer "F.Cu")
		(net "P3V3_NIC2_PG_G1")
	)
	(segment
		(start 127.185166 -116.946426)
		(end 127.439166 -117.200426)
		(width 0.13208)
		(layer "F.Cu")
		(net "P3V3_NIC2_PG_G1")
	)
	(segment
		(start 129.217166 -117.943376)
		(end 128.201166 -117.943376)
		(width 0.13208)
		(layer "F.Cu")
		(net "P3V3_NIC2_PG_G1")
	)
	(via
		(at 128.201166 -117.200426)
		(size 0.508)
		(drill 0.254)
		(layers "F.Cu" "B.Cu")
		(net "P3V3_NIC2_PG_G1")
	)
	(segment
		(start 321.95516 -116.66982)
		(end 321.702176 -116.416836)
		(width 0.13208)
		(layer "F.Cu")
		(net "P3V3_NIC5_CO_GATE")
	)
	(segment
		(start 322.824602 -116.335048)
		(end 322.289932 -116.335048)
		(width 0.13208)
		(layer "F.Cu")
		(net "P3V3_NIC5_CO_GATE")
	)
	(segment
		(start 321.702176 -116.416836)
		(end 321.252342 -116.416836)
		(width 0.13208)
		(layer "F.Cu")
		(net "P3V3_NIC5_CO_GATE")
	)
	(segment
		(start 322.289932 -116.335048)
		(end 321.95516 -116.66982)
		(width 0.13208)
		(layer "F.Cu")
		(net "P3V3_NIC5_CO_GATE")
	)
	(via
		(at 321.95516 -116.66982)
		(size 0.508)
		(drill 0.254)
		(layers "F.Cu" "B.Cu")
		(net "P3V3_NIC5_CO_GATE")
	)
	(segment
		(start 339.091524 18.28546)
		(end 339.772498 18.467324)
		(width 0.13462)
		(layer "F.Cu")
		(net "85_5INCH_IN2_DN")
	)
	(segment
		(start 377.084844 18.278348)
		(end 376.40387 18.460212)
		(width 0.13462)
		(layer "F.Cu")
		(net "85_5INCH_IN2_DN")
	)
	(segment
		(start 364.641892 21.795486)
		(end 365.215424 22.197568)
		(width 0.1651)
		(layer "In7.Cu")
		(net "85_5INCH_IN2_DN")
	)
	(segment
		(start 371.551454 15.50797)
		(end 371.964204 17.847564)
		(width 0.1651)
		(layer "In7.Cu")
		(net "85_5INCH_IN2_DN")
	)
	(segment
		(start 343.97823 18.292064)
		(end 344.592148 21.774404)
		(width 0.1651)
		(layer "In7.Cu")
		(net "85_5INCH_IN2_DN")
	)
	(segment
		(start 355.133402 15.242794)
		(end 355.515418 15.51051)
		(width 0.1651)
		(layer "In7.Cu")
		(net "85_5INCH_IN2_DN")
	)
	(segment
		(start 347.498162 15.516606)
		(end 348.605348 21.796756)
		(width 0.1651)
		(layer "In7.Cu")
		(net "85_5INCH_IN2_DN")
	)
	(segment
		(start 370.152422 15.419324)
		(end 371.16893 15.239746)
		(width 0.1651)
		(layer "In7.Cu")
		(net "85_5INCH_IN2_DN")
	)
	(segment
		(start 361.20705 22.201886)
		(end 362.45292 21.981668)
		(width 0.1651)
		(layer "In7.Cu")
		(net "85_5INCH_IN2_DN")
	)
	(segment
		(start 352.622358 21.841206)
		(end 353.196144 22.243288)
		(width 0.1651)
		(layer "In7.Cu")
		(net "85_5INCH_IN2_DN")
	)
	(segment
		(start 350.827086 21.405088)
		(end 349.839788 15.80515)
		(width 0.1651)
		(layer "In7.Cu")
		(net "85_5INCH_IN2_DN")
	)
	(segment
		(start 358.446578 21.997162)
		(end 358.84866 21.423376)
		(width 0.1651)
		(layer "In7.Cu")
		(net "85_5INCH_IN2_DN")
	)
	(segment
		(start 348.605348 21.796756)
		(end 349.179134 22.198838)
		(width 0.1651)
		(layer "In7.Cu")
		(net "85_5INCH_IN2_DN")
	)
	(segment
		(start 354.844096 21.449538)
		(end 353.848924 15.804388)
		(width 0.1651)
		(layer "In7.Cu")
		(net "85_5INCH_IN2_DN")
	)
	(segment
		(start 366.461294 21.97735)
		(end 366.86363 21.403564)
		(width 0.1651)
		(layer "In7.Cu")
		(net "85_5INCH_IN2_DN")
	)
	(segment
		(start 376.11304 18.169382)
		(end 376.40387 18.460212)
		(width 0.1651)
		(layer "In7.Cu")
		(net "85_5INCH_IN2_DN")
	)
	(segment
		(start 349.179134 22.198838)
		(end 350.425004 21.97862)
		(width 0.1651)
		(layer "In7.Cu")
		(net "85_5INCH_IN2_DN")
	)
	(segment
		(start 357.85806 15.803626)
		(end 358.125776 15.42161)
		(width 0.1651)
		(layer "In7.Cu")
		(net "85_5INCH_IN2_DN")
	)
	(segment
		(start 353.196144 22.243288)
		(end 354.442014 22.02307)
		(width 0.1651)
		(layer "In7.Cu")
		(net "85_5INCH_IN2_DN")
	)
	(segment
		(start 350.425004 21.97862)
		(end 350.827086 21.405088)
		(width 0.1651)
		(layer "In7.Cu")
		(net "85_5INCH_IN2_DN")
	)
	(segment
		(start 353.848924 15.804388)
		(end 354.11664 15.422372)
		(width 0.1651)
		(layer "In7.Cu")
		(net "85_5INCH_IN2_DN")
	)
	(segment
		(start 351.124266 15.243556)
		(end 351.506282 15.511272)
		(width 0.1651)
		(layer "In7.Cu")
		(net "85_5INCH_IN2_DN")
	)
	(segment
		(start 367.160556 15.243556)
		(end 367.54308 15.511526)
		(width 0.1651)
		(layer "In7.Cu")
		(net "85_5INCH_IN2_DN")
	)
	(segment
		(start 354.11664 15.422372)
		(end 355.133402 15.242794)
		(width 0.1651)
		(layer "In7.Cu")
		(net "85_5INCH_IN2_DN")
	)
	(segment
		(start 369.884706 15.80134)
		(end 370.152422 15.419324)
		(width 0.1651)
		(layer "In7.Cu")
		(net "85_5INCH_IN2_DN")
	)
	(segment
		(start 363.533182 15.507462)
		(end 364.641892 21.795486)
		(width 0.1651)
		(layer "In7.Cu")
		(net "85_5INCH_IN2_DN")
	)
	(segment
		(start 362.855002 21.407882)
		(end 361.866688 15.80134)
		(width 0.1651)
		(layer "In7.Cu")
		(net "85_5INCH_IN2_DN")
	)
	(segment
		(start 372.423436 18.169382)
		(end 376.11304 18.169382)
		(width 0.1651)
		(layer "In7.Cu")
		(net "85_5INCH_IN2_DN")
	)
	(segment
		(start 346.09913 15.428214)
		(end 347.116146 15.248636)
		(width 0.1651)
		(layer "In7.Cu")
		(net "85_5INCH_IN2_DN")
	)
	(segment
		(start 367.54308 15.511526)
		(end 368.653568 21.810726)
		(width 0.1651)
		(layer "In7.Cu")
		(net "85_5INCH_IN2_DN")
	)
	(segment
		(start 365.215424 22.197568)
		(end 366.461294 21.97735)
		(width 0.1651)
		(layer "In7.Cu")
		(net "85_5INCH_IN2_DN")
	)
	(segment
		(start 370.473224 21.99259)
		(end 370.875306 21.419058)
		(width 0.1651)
		(layer "In7.Cu")
		(net "85_5INCH_IN2_DN")
	)
	(segment
		(start 359.142538 15.242032)
		(end 359.524554 15.509748)
		(width 0.1651)
		(layer "In7.Cu")
		(net "85_5INCH_IN2_DN")
	)
	(segment
		(start 363.151166 15.239746)
		(end 363.533182 15.507462)
		(width 0.1651)
		(layer "In7.Cu")
		(net "85_5INCH_IN2_DN")
	)
	(segment
		(start 371.964204 17.847564)
		(end 372.423436 18.169382)
		(width 0.1651)
		(layer "In7.Cu")
		(net "85_5INCH_IN2_DN")
	)
	(segment
		(start 355.515418 15.51051)
		(end 356.626922 21.815298)
		(width 0.1651)
		(layer "In7.Cu")
		(net "85_5INCH_IN2_DN")
	)
	(segment
		(start 360.633518 21.799804)
		(end 361.20705 22.201886)
		(width 0.1651)
		(layer "In7.Cu")
		(net "85_5INCH_IN2_DN")
	)
	(segment
		(start 349.839788 15.80515)
		(end 350.107504 15.423134)
		(width 0.1651)
		(layer "In7.Cu")
		(net "85_5INCH_IN2_DN")
	)
	(segment
		(start 362.45292 21.981668)
		(end 362.855002 21.407882)
		(width 0.1651)
		(layer "In7.Cu")
		(net "85_5INCH_IN2_DN")
	)
	(segment
		(start 346.411804 21.956268)
		(end 346.813886 21.382736)
		(width 0.1651)
		(layer "In7.Cu")
		(net "85_5INCH_IN2_DN")
	)
	(segment
		(start 366.143794 15.423134)
		(end 367.160556 15.243556)
		(width 0.1651)
		(layer "In7.Cu")
		(net "85_5INCH_IN2_DN")
	)
	(segment
		(start 350.107504 15.423134)
		(end 351.124266 15.243556)
		(width 0.1651)
		(layer "In7.Cu")
		(net "85_5INCH_IN2_DN")
	)
	(segment
		(start 345.831414 15.81023)
		(end 346.09913 15.428214)
		(width 0.1651)
		(layer "In7.Cu")
		(net "85_5INCH_IN2_DN")
	)
	(segment
		(start 359.524554 15.509748)
		(end 360.633518 21.799804)
		(width 0.1651)
		(layer "In7.Cu")
		(net "85_5INCH_IN2_DN")
	)
	(segment
		(start 371.16893 15.239746)
		(end 371.551454 15.50797)
		(width 0.1651)
		(layer "In7.Cu")
		(net "85_5INCH_IN2_DN")
	)
	(segment
		(start 354.442014 22.02307)
		(end 354.844096 21.449538)
		(width 0.1651)
		(layer "In7.Cu")
		(net "85_5INCH_IN2_DN")
	)
	(segment
		(start 356.626922 21.815298)
		(end 357.200708 22.21738)
		(width 0.1651)
		(layer "In7.Cu")
		(net "85_5INCH_IN2_DN")
	)
	(segment
		(start 339.772498 18.467324)
		(end 340.063328 18.176494)
		(width 0.1651)
		(layer "In7.Cu")
		(net "85_5INCH_IN2_DN")
	)
	(segment
		(start 343.840308 18.176494)
		(end 343.97823 18.292064)
		(width 0.1651)
		(layer "In7.Cu")
		(net "85_5INCH_IN2_DN")
	)
	(segment
		(start 368.653568 21.810726)
		(end 369.227354 22.212808)
		(width 0.1651)
		(layer "In7.Cu")
		(net "85_5INCH_IN2_DN")
	)
	(segment
		(start 340.063328 18.176494)
		(end 343.840308 18.176494)
		(width 0.1651)
		(layer "In7.Cu")
		(net "85_5INCH_IN2_DN")
	)
	(segment
		(start 351.506282 15.511272)
		(end 352.622358 21.841206)
		(width 0.1651)
		(layer "In7.Cu")
		(net "85_5INCH_IN2_DN")
	)
	(segment
		(start 362.134404 15.419324)
		(end 363.151166 15.239746)
		(width 0.1651)
		(layer "In7.Cu")
		(net "85_5INCH_IN2_DN")
	)
	(segment
		(start 344.592148 21.774404)
		(end 345.165934 22.176486)
		(width 0.1651)
		(layer "In7.Cu")
		(net "85_5INCH_IN2_DN")
	)
	(segment
		(start 357.200708 22.21738)
		(end 358.446578 21.997162)
		(width 0.1651)
		(layer "In7.Cu")
		(net "85_5INCH_IN2_DN")
	)
	(segment
		(start 365.876078 15.80515)
		(end 366.143794 15.423134)
		(width 0.1651)
		(layer "In7.Cu")
		(net "85_5INCH_IN2_DN")
	)
	(segment
		(start 361.866688 15.80134)
		(end 362.134404 15.419324)
		(width 0.1651)
		(layer "In7.Cu")
		(net "85_5INCH_IN2_DN")
	)
	(segment
		(start 370.875306 21.419058)
		(end 369.884706 15.80134)
		(width 0.1651)
		(layer "In7.Cu")
		(net "85_5INCH_IN2_DN")
	)
	(segment
		(start 358.84866 21.423376)
		(end 357.85806 15.803626)
		(width 0.1651)
		(layer "In7.Cu")
		(net "85_5INCH_IN2_DN")
	)
	(segment
		(start 347.116146 15.248636)
		(end 347.498162 15.516606)
		(width 0.1651)
		(layer "In7.Cu")
		(net "85_5INCH_IN2_DN")
	)
	(segment
		(start 358.125776 15.42161)
		(end 359.142538 15.242032)
		(width 0.1651)
		(layer "In7.Cu")
		(net "85_5INCH_IN2_DN")
	)
	(segment
		(start 346.813886 21.382736)
		(end 345.831414 15.81023)
		(width 0.1651)
		(layer "In7.Cu")
		(net "85_5INCH_IN2_DN")
	)
	(segment
		(start 345.165934 22.176486)
		(end 346.411804 21.956268)
		(width 0.1651)
		(layer "In7.Cu")
		(net "85_5INCH_IN2_DN")
	)
	(segment
		(start 369.227354 22.212808)
		(end 370.473224 21.99259)
		(width 0.1651)
		(layer "In7.Cu")
		(net "85_5INCH_IN2_DN")
	)
	(segment
		(start 366.86363 21.403564)
		(end 365.876078 15.80515)
		(width 0.1651)
		(layer "In7.Cu")
		(net "85_5INCH_IN2_DN")
	)
	(segment
		(start 430.547526 -63.56223)
		(end 430.989486 -63.56223)
		(width 0.13208)
		(layer "F.Cu")
		(net "P12V_SSD15_PG_G1")
	)
	(segment
		(start 430.258728 -63.273432)
		(end 430.547526 -63.56223)
		(width 0.13208)
		(layer "F.Cu")
		(net "P12V_SSD15_PG_G1")
	)
	(segment
		(start 429.575214 -63.086234)
		(end 430.002442 -63.086234)
		(width 0.13208)
		(layer "F.Cu")
		(net "P12V_SSD15_PG_G1")
	)
	(segment
		(start 430.18964 -63.273432)
		(end 430.258728 -63.273432)
		(width 0.13208)
		(layer "F.Cu")
		(net "P12V_SSD15_PG_G1")
	)
	(segment
		(start 430.002442 -63.086234)
		(end 430.18964 -63.273432)
		(width 0.13208)
		(layer "F.Cu")
		(net "P12V_SSD15_PG_G1")
	)
	(segment
		(start 429.575214 -64.102234)
		(end 429.575214 -63.086234)
		(width 0.13208)
		(layer "F.Cu")
		(net "P12V_SSD15_PG_G1")
	)
	(via
		(at 430.258728 -63.273432)
		(size 0.508)
		(drill 0.254)
		(layers "F.Cu" "B.Cu")
		(net "P12V_SSD15_PG_G1")
	)
	(segment
		(start 364.494826 -112.415574)
		(end 364.494826 -111.777526)
		(width 0.13208)
		(layer "F.Cu")
		(net "P3V3_NIC6_CO_MODE")
	)
	(segment
		(start 364.489238 -113.01603)
		(end 364.489238 -112.421162)
		(width 0.13208)
		(layer "F.Cu")
		(net "P3V3_NIC6_CO_MODE")
	)
	(segment
		(start 364.333028 -113.17224)
		(end 364.489238 -113.01603)
		(width 0.13208)
		(layer "F.Cu")
		(net "P3V3_NIC6_CO_MODE")
	)
	(segment
		(start 364.489238 -112.421162)
		(end 364.494826 -112.415574)
		(width 0.13208)
		(layer "F.Cu")
		(net "P3V3_NIC6_CO_MODE")
	)
	(segment
		(start 363.478826 -111.777526)
		(end 364.494826 -111.777526)
		(width 0.13208)
		(layer "F.Cu")
		(net "P3V3_NIC6_CO_MODE")
	)
	(segment
		(start 364.333028 -113.933478)
		(end 364.333028 -113.17224)
		(width 0.13208)
		(layer "F.Cu")
		(net "P3V3_NIC6_CO_MODE")
	)
	(via
		(at 364.489238 -112.421162)
		(size 0.508)
		(drill 0.254)
		(layers "F.Cu" "B.Cu")
		(net "P3V3_NIC6_CO_MODE")
	)
	(segment
		(start 273.940524 17.785588)
		(end 274.621498 17.603724)
		(width 0.13462)
		(layer "F.Cu")
		(net "85_5INCH_IN1_DP")
	)
	(segment
		(start 311.933844 17.778476)
		(end 311.25287 17.596612)
		(width 0.13462)
		(layer "F.Cu")
		(net "85_5INCH_IN1_DP")
	)
	(segment
		(start 293.399464 21.357082)
		(end 292.408864 15.737332)
		(width 0.1651)
		(layer "In5.Cu")
		(net "85_5INCH_IN1_DP")
	)
	(segment
		(start 280.080974 21.87829)
		(end 281.09672 21.698712)
		(width 0.1651)
		(layer "In5.Cu")
		(net "85_5INCH_IN1_DP")
	)
	(segment
		(start 296.81932 15.161768)
		(end 298.066206 14.94155)
		(width 0.1651)
		(layer "In5.Cu")
		(net "85_5INCH_IN1_DP")
	)
	(segment
		(start 303.760124 21.646642)
		(end 304.142394 21.914612)
		(width 0.1651)
		(layer "In5.Cu")
		(net "85_5INCH_IN1_DP")
	)
	(segment
		(start 283.711904 21.632672)
		(end 284.094174 21.900642)
		(width 0.1651)
		(layer "In5.Cu")
		(net "85_5INCH_IN1_DP")
	)
	(segment
		(start 278.791924 17.894554)
		(end 279.087072 18.14195)
		(width 0.1651)
		(layer "In5.Cu")
		(net "85_5INCH_IN1_DP")
	)
	(segment
		(start 302.075596 14.94536)
		(end 302.649636 15.347442)
		(width 0.1651)
		(layer "In5.Cu")
		(net "85_5INCH_IN1_DP")
	)
	(segment
		(start 289.12693 21.765514)
		(end 289.3949 21.383244)
		(width 0.1651)
		(layer "In5.Cu")
		(net "85_5INCH_IN1_DP")
	)
	(segment
		(start 310.96204 17.887442)
		(end 311.25287 17.596612)
		(width 0.1651)
		(layer "In5.Cu")
		(net "85_5INCH_IN1_DP")
	)
	(segment
		(start 284.390592 15.738856)
		(end 284.79242 15.165578)
		(width 0.1651)
		(layer "In5.Cu")
		(net "85_5INCH_IN1_DP")
	)
	(segment
		(start 279.087072 18.14195)
		(end 279.698704 21.61032)
		(width 0.1651)
		(layer "In5.Cu")
		(net "85_5INCH_IN1_DP")
	)
	(segment
		(start 302.649636 15.347442)
		(end 303.760124 21.646642)
		(width 0.1651)
		(layer "In5.Cu")
		(net "85_5INCH_IN1_DP")
	)
	(segment
		(start 301.14621 21.719794)
		(end 301.414434 21.33727)
		(width 0.1651)
		(layer "In5.Cu")
		(net "85_5INCH_IN1_DP")
	)
	(segment
		(start 293.131494 21.739606)
		(end 293.399464 21.357082)
		(width 0.1651)
		(layer "In5.Cu")
		(net "85_5INCH_IN1_DP")
	)
	(segment
		(start 306.084224 14.94155)
		(end 306.65801 15.343886)
		(width 0.1651)
		(layer "In5.Cu")
		(net "85_5INCH_IN1_DP")
	)
	(segment
		(start 281.36469 21.316442)
		(end 280.382218 15.743936)
		(width 0.1651)
		(layer "In5.Cu")
		(net "85_5INCH_IN1_DP")
	)
	(segment
		(start 287.728914 21.677122)
		(end 288.111184 21.945092)
		(width 0.1651)
		(layer "In5.Cu")
		(net "85_5INCH_IN1_DP")
	)
	(segment
		(start 290.621974 15.346426)
		(end 291.733478 21.651214)
		(width 0.1651)
		(layer "In5.Cu")
		(net "85_5INCH_IN1_DP")
	)
	(segment
		(start 279.698704 21.61032)
		(end 280.080974 21.87829)
		(width 0.1651)
		(layer "In5.Cu")
		(net "85_5INCH_IN1_DP")
	)
	(segment
		(start 282.03144 14.95044)
		(end 282.604718 15.352522)
		(width 0.1651)
		(layer "In5.Cu")
		(net "85_5INCH_IN1_DP")
	)
	(segment
		(start 291.733478 21.651214)
		(end 292.115748 21.919184)
		(width 0.1651)
		(layer "In5.Cu")
		(net "85_5INCH_IN1_DP")
	)
	(segment
		(start 285.37789 21.338794)
		(end 284.390592 15.738856)
		(width 0.1651)
		(layer "In5.Cu")
		(net "85_5INCH_IN1_DP")
	)
	(segment
		(start 284.79242 15.165578)
		(end 286.039306 14.94536)
		(width 0.1651)
		(layer "In5.Cu")
		(net "85_5INCH_IN1_DP")
	)
	(segment
		(start 305.42611 21.352764)
		(end 304.43551 15.735046)
		(width 0.1651)
		(layer "In5.Cu")
		(net "85_5INCH_IN1_DP")
	)
	(segment
		(start 298.066206 14.94155)
		(end 298.639738 15.343378)
		(width 0.1651)
		(layer "In5.Cu")
		(net "85_5INCH_IN1_DP")
	)
	(segment
		(start 286.039306 14.94536)
		(end 286.612838 15.347188)
		(width 0.1651)
		(layer "In5.Cu")
		(net "85_5INCH_IN1_DP")
	)
	(segment
		(start 296.12209 21.90369)
		(end 297.137836 21.724112)
		(width 0.1651)
		(layer "In5.Cu")
		(net "85_5INCH_IN1_DP")
	)
	(segment
		(start 294.057578 14.943836)
		(end 294.63111 15.345664)
		(width 0.1651)
		(layer "In5.Cu")
		(net "85_5INCH_IN1_DP")
	)
	(segment
		(start 307.36159 17.887442)
		(end 310.96204 17.887442)
		(width 0.1651)
		(layer "In5.Cu")
		(net "85_5INCH_IN1_DP")
	)
	(segment
		(start 307.07076 17.68348)
		(end 307.36159 17.887442)
		(width 0.1651)
		(layer "In5.Cu")
		(net "85_5INCH_IN1_DP")
	)
	(segment
		(start 300.82871 15.165578)
		(end 302.075596 14.94536)
		(width 0.1651)
		(layer "In5.Cu")
		(net "85_5INCH_IN1_DP")
	)
	(segment
		(start 306.65801 15.343886)
		(end 307.07076 17.68348)
		(width 0.1651)
		(layer "In5.Cu")
		(net "85_5INCH_IN1_DP")
	)
	(segment
		(start 300.426882 15.73911)
		(end 300.82871 15.165578)
		(width 0.1651)
		(layer "In5.Cu")
		(net "85_5INCH_IN1_DP")
	)
	(segment
		(start 289.3949 21.383244)
		(end 288.399728 15.738094)
		(width 0.1651)
		(layer "In5.Cu")
		(net "85_5INCH_IN1_DP")
	)
	(segment
		(start 282.604718 15.352522)
		(end 283.711904 21.632672)
		(width 0.1651)
		(layer "In5.Cu")
		(net "85_5INCH_IN1_DP")
	)
	(segment
		(start 301.414434 21.33727)
		(end 300.426882 15.73911)
		(width 0.1651)
		(layer "In5.Cu")
		(net "85_5INCH_IN1_DP")
	)
	(segment
		(start 274.621498 17.603724)
		(end 274.912328 17.894554)
		(width 0.1651)
		(layer "In5.Cu")
		(net "85_5INCH_IN1_DP")
	)
	(segment
		(start 298.639738 15.343378)
		(end 299.748448 21.631402)
		(width 0.1651)
		(layer "In5.Cu")
		(net "85_5INCH_IN1_DP")
	)
	(segment
		(start 294.63111 15.345664)
		(end 295.740074 21.63572)
		(width 0.1651)
		(layer "In5.Cu")
		(net "85_5INCH_IN1_DP")
	)
	(segment
		(start 304.837338 15.161768)
		(end 306.084224 14.94155)
		(width 0.1651)
		(layer "In5.Cu")
		(net "85_5INCH_IN1_DP")
	)
	(segment
		(start 305.15814 21.735034)
		(end 305.42611 21.352764)
		(width 0.1651)
		(layer "In5.Cu")
		(net "85_5INCH_IN1_DP")
	)
	(segment
		(start 300.130464 21.899372)
		(end 301.14621 21.719794)
		(width 0.1651)
		(layer "In5.Cu")
		(net "85_5INCH_IN1_DP")
	)
	(segment
		(start 295.740074 21.63572)
		(end 296.12209 21.90369)
		(width 0.1651)
		(layer "In5.Cu")
		(net "85_5INCH_IN1_DP")
	)
	(segment
		(start 297.405806 21.341588)
		(end 296.417492 15.735046)
		(width 0.1651)
		(layer "In5.Cu")
		(net "85_5INCH_IN1_DP")
	)
	(segment
		(start 285.10992 21.721064)
		(end 285.37789 21.338794)
		(width 0.1651)
		(layer "In5.Cu")
		(net "85_5INCH_IN1_DP")
	)
	(segment
		(start 288.399728 15.738094)
		(end 288.801556 15.164816)
		(width 0.1651)
		(layer "In5.Cu")
		(net "85_5INCH_IN1_DP")
	)
	(segment
		(start 292.115748 21.919184)
		(end 293.131494 21.739606)
		(width 0.1651)
		(layer "In5.Cu")
		(net "85_5INCH_IN1_DP")
	)
	(segment
		(start 286.612838 15.347188)
		(end 287.728914 21.677122)
		(width 0.1651)
		(layer "In5.Cu")
		(net "85_5INCH_IN1_DP")
	)
	(segment
		(start 280.382218 15.743936)
		(end 280.784046 15.170658)
		(width 0.1651)
		(layer "In5.Cu")
		(net "85_5INCH_IN1_DP")
	)
	(segment
		(start 290.048442 14.944598)
		(end 290.621974 15.346426)
		(width 0.1651)
		(layer "In5.Cu")
		(net "85_5INCH_IN1_DP")
	)
	(segment
		(start 296.417492 15.735046)
		(end 296.81932 15.161768)
		(width 0.1651)
		(layer "In5.Cu")
		(net "85_5INCH_IN1_DP")
	)
	(segment
		(start 304.142394 21.914612)
		(end 305.15814 21.735034)
		(width 0.1651)
		(layer "In5.Cu")
		(net "85_5INCH_IN1_DP")
	)
	(segment
		(start 292.810692 15.164054)
		(end 294.057578 14.943836)
		(width 0.1651)
		(layer "In5.Cu")
		(net "85_5INCH_IN1_DP")
	)
	(segment
		(start 284.094174 21.900642)
		(end 285.10992 21.721064)
		(width 0.1651)
		(layer "In5.Cu")
		(net "85_5INCH_IN1_DP")
	)
	(segment
		(start 281.09672 21.698712)
		(end 281.36469 21.316442)
		(width 0.1651)
		(layer "In5.Cu")
		(net "85_5INCH_IN1_DP")
	)
	(segment
		(start 288.801556 15.164816)
		(end 290.048442 14.944598)
		(width 0.1651)
		(layer "In5.Cu")
		(net "85_5INCH_IN1_DP")
	)
	(segment
		(start 288.111184 21.945092)
		(end 289.12693 21.765514)
		(width 0.1651)
		(layer "In5.Cu")
		(net "85_5INCH_IN1_DP")
	)
	(segment
		(start 299.748448 21.631402)
		(end 300.130464 21.899372)
		(width 0.1651)
		(layer "In5.Cu")
		(net "85_5INCH_IN1_DP")
	)
	(segment
		(start 297.137836 21.724112)
		(end 297.405806 21.341588)
		(width 0.1651)
		(layer "In5.Cu")
		(net "85_5INCH_IN1_DP")
	)
	(segment
		(start 292.408864 15.737332)
		(end 292.810692 15.164054)
		(width 0.1651)
		(layer "In5.Cu")
		(net "85_5INCH_IN1_DP")
	)
	(segment
		(start 280.784046 15.170658)
		(end 282.03144 14.95044)
		(width 0.1651)
		(layer "In5.Cu")
		(net "85_5INCH_IN1_DP")
	)
	(segment
		(start 274.912328 17.894554)
		(end 278.791924 17.894554)
		(width 0.1651)
		(layer "In5.Cu")
		(net "85_5INCH_IN1_DP")
	)
	(segment
		(start 304.43551 15.735046)
		(end 304.837338 15.161768)
		(width 0.1651)
		(layer "In5.Cu")
		(net "85_5INCH_IN1_DP")
	)
	(segment
		(start 394.753338 -67.537584)
		(end 394.753338 -67.077844)
		(width 0.13208)
		(layer "F.Cu")
		(net "P12V_SSD13_CO_EN")
	)
	(segment
		(start 394.753338 -67.847972)
		(end 394.753338 -67.537584)
		(width 0.13208)
		(layer "F.Cu")
		(net "P12V_SSD13_CO_EN")
	)
	(segment
		(start 394.875512 -67.970146)
		(end 394.753338 -67.847972)
		(width 0.13208)
		(layer "F.Cu")
		(net "P12V_SSD13_CO_EN")
	)
	(segment
		(start 394.814552 -67.01663)
		(end 394.814552 -66.72199)
		(width 0.13208)
		(layer "F.Cu")
		(net "P12V_SSD13_CO_EN")
	)
	(segment
		(start 394.875512 -68.479162)
		(end 394.875512 -67.970146)
		(width 0.13208)
		(layer "F.Cu")
		(net "P12V_SSD13_CO_EN")
	)
	(segment
		(start 394.753338 -67.077844)
		(end 394.814552 -67.01663)
		(width 0.13208)
		(layer "F.Cu")
		(net "P12V_SSD13_CO_EN")
	)
	(via
		(at 394.753338 -67.537584)
		(size 0.508)
		(drill 0.254)
		(layers "F.Cu" "B.Cu")
		(net "P12V_SSD13_CO_EN")
	)
	(segment
		(start 438.055258 -116.66982)
		(end 437.802274 -116.416836)
		(width 0.13208)
		(layer "F.Cu")
		(net "P3V3_NIC7_CO_GATE")
	)
	(segment
		(start 438.9247 -116.335048)
		(end 438.39003 -116.335048)
		(width 0.13208)
		(layer "F.Cu")
		(net "P3V3_NIC7_CO_GATE")
	)
	(segment
		(start 437.802274 -116.416836)
		(end 437.35244 -116.416836)
		(width 0.13208)
		(layer "F.Cu")
		(net "P3V3_NIC7_CO_GATE")
	)
	(segment
		(start 438.39003 -116.335048)
		(end 438.055258 -116.66982)
		(width 0.13208)
		(layer "F.Cu")
		(net "P3V3_NIC7_CO_GATE")
	)
	(via
		(at 438.055258 -116.66982)
		(size 0.508)
		(drill 0.254)
		(layers "F.Cu" "B.Cu")
		(net "P3V3_NIC7_CO_GATE")
	)
	(segment
		(start 256.160524 7.833868)
		(end 256.841498 7.652004)
		(width 0.13462)
		(layer "F.Cu")
		(net "85_10INCH_IN1_DN")
	)
	(segment
		(start 313.294268 7.859776)
		(end 312.613294 7.677912)
		(width 0.13462)
		(layer "F.Cu")
		(net "85_10INCH_IN1_DN")
	)
	(segment
		(start 307.953156 4.16052)
		(end 308.526942 4.562856)
		(width 0.1651)
		(layer "In5.Cu")
		(net "85_10INCH_IN1_DN")
	)
	(segment
		(start 293.92245 12.685776)
		(end 294.30472 12.953746)
		(width 0.1651)
		(layer "In5.Cu")
		(net "85_10INCH_IN1_DN")
	)
	(segment
		(start 270.620998 4.364228)
		(end 271.867884 4.14401)
		(width 0.1651)
		(layer "In5.Cu")
		(net "85_10INCH_IN1_DN")
	)
	(segment
		(start 288.478722 4.548886)
		(end 289.917886 12.711684)
		(width 0.1651)
		(layer "In5.Cu")
		(net "85_10INCH_IN1_DN")
	)
	(segment
		(start 299.930058 4.132834)
		(end 300.50359 4.534662)
		(width 0.1651)
		(layer "In5.Cu")
		(net "85_10INCH_IN1_DN")
	)
	(segment
		(start 295.92016 4.128008)
		(end 296.493692 4.529836)
		(width 0.1651)
		(layer "In5.Cu")
		(net "85_10INCH_IN1_DN")
	)
	(segment
		(start 296.493692 4.529836)
		(end 297.92676 12.657836)
		(width 0.1651)
		(layer "In5.Cu")
		(net "85_10INCH_IN1_DN")
	)
	(segment
		(start 306.327048 12.924536)
		(end 307.342794 12.744958)
		(width 0.1651)
		(layer "In5.Cu")
		(net "85_10INCH_IN1_DN")
	)
	(segment
		(start 270.251936 12.965938)
		(end 271.267682 12.78636)
		(width 0.1651)
		(layer "In5.Cu")
		(net "85_10INCH_IN1_DN")
	)
	(segment
		(start 286.65805 4.367276)
		(end 287.904936 4.147058)
		(width 0.1651)
		(layer "In5.Cu")
		(net "85_10INCH_IN1_DN")
	)
	(segment
		(start 305.944778 12.656566)
		(end 306.327048 12.924536)
		(width 0.1651)
		(layer "In5.Cu")
		(net "85_10INCH_IN1_DN")
	)
	(segment
		(start 260.487668 7.942834)
		(end 261.124954 8.579866)
		(width 0.1651)
		(layer "In5.Cu")
		(net "85_10INCH_IN1_DN")
	)
	(segment
		(start 264.421366 4.535932)
		(end 265.842496 12.59459)
		(width 0.1651)
		(layer "In5.Cu")
		(net "85_10INCH_IN1_DN")
	)
	(segment
		(start 275.279866 12.801854)
		(end 275.547836 12.420092)
		(width 0.1651)
		(layer "In5.Cu")
		(net "85_10INCH_IN1_DN")
	)
	(segment
		(start 298.30903 12.925806)
		(end 299.324776 12.746228)
		(width 0.1651)
		(layer "In5.Cu")
		(net "85_10INCH_IN1_DN")
	)
	(segment
		(start 300.50359 4.534662)
		(end 301.932848 12.641326)
		(width 0.1651)
		(layer "In5.Cu")
		(net "85_10INCH_IN1_DN")
	)
	(segment
		(start 282.269946 12.912852)
		(end 283.285692 12.733274)
		(width 0.1651)
		(layer "In5.Cu")
		(net "85_10INCH_IN1_DN")
	)
	(segment
		(start 270.21917 4.937506)
		(end 270.620998 4.364228)
		(width 0.1651)
		(layer "In5.Cu")
		(net "85_10INCH_IN1_DN")
	)
	(segment
		(start 294.271446 4.921504)
		(end 294.673274 4.348226)
		(width 0.1651)
		(layer "In5.Cu")
		(net "85_10INCH_IN1_DN")
	)
	(segment
		(start 257.132328 7.942834)
		(end 260.487668 7.942834)
		(width 0.1651)
		(layer "In5.Cu")
		(net "85_10INCH_IN1_DN")
	)
	(segment
		(start 291.91331 4.141724)
		(end 292.486842 4.543552)
		(width 0.1651)
		(layer "In5.Cu")
		(net "85_10INCH_IN1_DN")
	)
	(segment
		(start 286.256222 4.940554)
		(end 286.65805 4.367276)
		(width 0.1651)
		(layer "In5.Cu")
		(net "85_10INCH_IN1_DN")
	)
	(segment
		(start 295.320466 12.774168)
		(end 295.588436 12.391898)
		(width 0.1651)
		(layer "In5.Cu")
		(net "85_10INCH_IN1_DN")
	)
	(segment
		(start 281.887676 12.644882)
		(end 282.269946 12.912852)
		(width 0.1651)
		(layer "In5.Cu")
		(net "85_10INCH_IN1_DN")
	)
	(segment
		(start 299.592746 12.363958)
		(end 298.281344 4.92633)
		(width 0.1651)
		(layer "In5.Cu")
		(net "85_10INCH_IN1_DN")
	)
	(segment
		(start 290.264596 4.93522)
		(end 290.666424 4.361942)
		(width 0.1651)
		(layer "In5.Cu")
		(net "85_10INCH_IN1_DN")
	)
	(segment
		(start 268.43101 4.539488)
		(end 269.86992 12.697968)
		(width 0.1651)
		(layer "In5.Cu")
		(net "85_10INCH_IN1_DN")
	)
	(segment
		(start 290.300156 12.979654)
		(end 291.315902 12.800076)
		(width 0.1651)
		(layer "In5.Cu")
		(net "85_10INCH_IN1_DN")
	)
	(segment
		(start 267.507974 12.29995)
		(end 266.208764 4.931156)
		(width 0.1651)
		(layer "In5.Cu")
		(net "85_10INCH_IN1_DN")
	)
	(segment
		(start 303.330864 12.729718)
		(end 303.599088 12.347194)
		(width 0.1651)
		(layer "In5.Cu")
		(net "85_10INCH_IN1_DN")
	)
	(segment
		(start 256.841498 7.652004)
		(end 257.132328 7.942834)
		(width 0.1651)
		(layer "In5.Cu")
		(net "85_10INCH_IN1_DN")
	)
	(segment
		(start 307.610764 12.362688)
		(end 306.304442 4.954016)
		(width 0.1651)
		(layer "In5.Cu")
		(net "85_10INCH_IN1_DN")
	)
	(segment
		(start 266.208764 4.931156)
		(end 266.610592 4.357878)
		(width 0.1651)
		(layer "In5.Cu")
		(net "85_10INCH_IN1_DN")
	)
	(segment
		(start 298.683172 4.353052)
		(end 299.930058 4.132834)
		(width 0.1651)
		(layer "In5.Cu")
		(net "85_10INCH_IN1_DN")
	)
	(segment
		(start 265.842496 12.59459)
		(end 266.224258 12.862306)
		(width 0.1651)
		(layer "In5.Cu")
		(net "85_10INCH_IN1_DN")
	)
	(segment
		(start 277.88235 12.665964)
		(end 278.26462 12.933934)
		(width 0.1651)
		(layer "In5.Cu")
		(net "85_10INCH_IN1_DN")
	)
	(segment
		(start 297.92676 12.657836)
		(end 298.30903 12.925806)
		(width 0.1651)
		(layer "In5.Cu")
		(net "85_10INCH_IN1_DN")
	)
	(segment
		(start 276.449536 4.539234)
		(end 277.88235 12.665964)
		(width 0.1651)
		(layer "In5.Cu")
		(net "85_10INCH_IN1_DN")
	)
	(segment
		(start 303.939956 4.139438)
		(end 304.513996 4.54152)
		(width 0.1651)
		(layer "In5.Cu")
		(net "85_10INCH_IN1_DN")
	)
	(segment
		(start 261.124954 8.579866)
		(end 261.82955 12.573508)
		(width 0.1651)
		(layer "In5.Cu")
		(net "85_10INCH_IN1_DN")
	)
	(segment
		(start 266.224258 12.862306)
		(end 267.23975 12.682728)
		(width 0.1651)
		(layer "In5.Cu")
		(net "85_10INCH_IN1_DN")
	)
	(segment
		(start 302.315118 12.909296)
		(end 303.330864 12.729718)
		(width 0.1651)
		(layer "In5.Cu")
		(net "85_10INCH_IN1_DN")
	)
	(segment
		(start 271.867884 4.14401)
		(end 272.441416 4.545838)
		(width 0.1651)
		(layer "In5.Cu")
		(net "85_10INCH_IN1_DN")
	)
	(segment
		(start 278.23541 4.926076)
		(end 278.637238 4.352798)
		(width 0.1651)
		(layer "In5.Cu")
		(net "85_10INCH_IN1_DN")
	)
	(segment
		(start 286.283146 12.935204)
		(end 287.298892 12.755626)
		(width 0.1651)
		(layer "In5.Cu")
		(net "85_10INCH_IN1_DN")
	)
	(segment
		(start 263.495282 12.279376)
		(end 262.19912 4.9276)
		(width 0.1651)
		(layer "In5.Cu")
		(net "85_10INCH_IN1_DN")
	)
	(segment
		(start 291.315902 12.800076)
		(end 291.583872 12.417806)
		(width 0.1651)
		(layer "In5.Cu")
		(net "85_10INCH_IN1_DN")
	)
	(segment
		(start 285.900876 12.667234)
		(end 286.283146 12.935204)
		(width 0.1651)
		(layer "In5.Cu")
		(net "85_10INCH_IN1_DN")
	)
	(segment
		(start 283.285692 12.733274)
		(end 283.553662 12.351004)
		(width 0.1651)
		(layer "In5.Cu")
		(net "85_10INCH_IN1_DN")
	)
	(segment
		(start 262.600948 4.354322)
		(end 263.847834 4.134104)
		(width 0.1651)
		(layer "In5.Cu")
		(net "85_10INCH_IN1_DN")
	)
	(segment
		(start 279.280366 12.754356)
		(end 279.548336 12.372086)
		(width 0.1651)
		(layer "In5.Cu")
		(net "85_10INCH_IN1_DN")
	)
	(segment
		(start 294.673274 4.348226)
		(end 295.92016 4.128008)
		(width 0.1651)
		(layer "In5.Cu")
		(net "85_10INCH_IN1_DN")
	)
	(segment
		(start 309.091584 7.76478)
		(end 309.382414 7.968742)
		(width 0.1651)
		(layer "In5.Cu")
		(net "85_10INCH_IN1_DN")
	)
	(segment
		(start 287.904936 4.147058)
		(end 288.478722 4.548886)
		(width 0.1651)
		(layer "In5.Cu")
		(net "85_10INCH_IN1_DN")
	)
	(segment
		(start 262.19912 4.9276)
		(end 262.600948 4.354322)
		(width 0.1651)
		(layer "In5.Cu")
		(net "85_10INCH_IN1_DN")
	)
	(segment
		(start 290.666424 4.361942)
		(end 291.91331 4.141724)
		(width 0.1651)
		(layer "In5.Cu")
		(net "85_10INCH_IN1_DN")
	)
	(segment
		(start 274.629118 4.357624)
		(end 275.876004 4.137406)
		(width 0.1651)
		(layer "In5.Cu")
		(net "85_10INCH_IN1_DN")
	)
	(segment
		(start 289.917886 12.711684)
		(end 290.300156 12.979654)
		(width 0.1651)
		(layer "In5.Cu")
		(net "85_10INCH_IN1_DN")
	)
	(segment
		(start 294.30472 12.953746)
		(end 295.320466 12.774168)
		(width 0.1651)
		(layer "In5.Cu")
		(net "85_10INCH_IN1_DN")
	)
	(segment
		(start 266.610592 4.357878)
		(end 267.857478 4.13766)
		(width 0.1651)
		(layer "In5.Cu")
		(net "85_10INCH_IN1_DN")
	)
	(segment
		(start 306.304442 4.954016)
		(end 306.70627 4.380738)
		(width 0.1651)
		(layer "In5.Cu")
		(net "85_10INCH_IN1_DN")
	)
	(segment
		(start 269.86992 12.697968)
		(end 270.251936 12.965938)
		(width 0.1651)
		(layer "In5.Cu")
		(net "85_10INCH_IN1_DN")
	)
	(segment
		(start 267.23975 12.682728)
		(end 267.507974 12.29995)
		(width 0.1651)
		(layer "In5.Cu")
		(net "85_10INCH_IN1_DN")
	)
	(segment
		(start 284.468316 4.542536)
		(end 285.900876 12.667234)
		(width 0.1651)
		(layer "In5.Cu")
		(net "85_10INCH_IN1_DN")
	)
	(segment
		(start 262.211566 12.841478)
		(end 263.227312 12.6619)
		(width 0.1651)
		(layer "In5.Cu")
		(net "85_10INCH_IN1_DN")
	)
	(segment
		(start 298.281344 4.92633)
		(end 298.683172 4.353052)
		(width 0.1651)
		(layer "In5.Cu")
		(net "85_10INCH_IN1_DN")
	)
	(segment
		(start 309.382414 7.968742)
		(end 312.322464 7.968742)
		(width 0.1651)
		(layer "In5.Cu")
		(net "85_10INCH_IN1_DN")
	)
	(segment
		(start 283.553662 12.351004)
		(end 282.245816 4.93395)
		(width 0.1651)
		(layer "In5.Cu")
		(net "85_10INCH_IN1_DN")
	)
	(segment
		(start 271.267682 12.78636)
		(end 271.535652 12.40409)
		(width 0.1651)
		(layer "In5.Cu")
		(net "85_10INCH_IN1_DN")
	)
	(segment
		(start 275.876004 4.137406)
		(end 276.449536 4.539234)
		(width 0.1651)
		(layer "In5.Cu")
		(net "85_10INCH_IN1_DN")
	)
	(segment
		(start 312.322464 7.968742)
		(end 312.613294 7.677912)
		(width 0.1651)
		(layer "In5.Cu")
		(net "85_10INCH_IN1_DN")
	)
	(segment
		(start 275.547836 12.420092)
		(end 274.22729 4.930902)
		(width 0.1651)
		(layer "In5.Cu")
		(net "85_10INCH_IN1_DN")
	)
	(segment
		(start 306.70627 4.380738)
		(end 307.953156 4.16052)
		(width 0.1651)
		(layer "In5.Cu")
		(net "85_10INCH_IN1_DN")
	)
	(segment
		(start 292.486842 4.543552)
		(end 293.92245 12.685776)
		(width 0.1651)
		(layer "In5.Cu")
		(net "85_10INCH_IN1_DN")
	)
	(segment
		(start 303.599088 12.347194)
		(end 302.291242 4.933188)
		(width 0.1651)
		(layer "In5.Cu")
		(net "85_10INCH_IN1_DN")
	)
	(segment
		(start 282.647644 4.360672)
		(end 283.894784 4.140454)
		(width 0.1651)
		(layer "In5.Cu")
		(net "85_10INCH_IN1_DN")
	)
	(segment
		(start 279.884124 4.13258)
		(end 280.457656 4.534408)
		(width 0.1651)
		(layer "In5.Cu")
		(net "85_10INCH_IN1_DN")
	)
	(segment
		(start 279.548336 12.372086)
		(end 278.23541 4.926076)
		(width 0.1651)
		(layer "In5.Cu")
		(net "85_10INCH_IN1_DN")
	)
	(segment
		(start 278.26462 12.933934)
		(end 279.280366 12.754356)
		(width 0.1651)
		(layer "In5.Cu")
		(net "85_10INCH_IN1_DN")
	)
	(segment
		(start 307.342794 12.744958)
		(end 307.610764 12.362688)
		(width 0.1651)
		(layer "In5.Cu")
		(net "85_10INCH_IN1_DN")
	)
	(segment
		(start 274.26412 12.981432)
		(end 275.279866 12.801854)
		(width 0.1651)
		(layer "In5.Cu")
		(net "85_10INCH_IN1_DN")
	)
	(segment
		(start 263.227312 12.6619)
		(end 263.495282 12.279376)
		(width 0.1651)
		(layer "In5.Cu")
		(net "85_10INCH_IN1_DN")
	)
	(segment
		(start 291.583872 12.417806)
		(end 290.264596 4.93522)
		(width 0.1651)
		(layer "In5.Cu")
		(net "85_10INCH_IN1_DN")
	)
	(segment
		(start 295.588436 12.391898)
		(end 294.271446 4.921504)
		(width 0.1651)
		(layer "In5.Cu")
		(net "85_10INCH_IN1_DN")
	)
	(segment
		(start 287.298892 12.755626)
		(end 287.566862 12.373356)
		(width 0.1651)
		(layer "In5.Cu")
		(net "85_10INCH_IN1_DN")
	)
	(segment
		(start 304.513996 4.54152)
		(end 305.944778 12.656566)
		(width 0.1651)
		(layer "In5.Cu")
		(net "85_10INCH_IN1_DN")
	)
	(segment
		(start 272.441416 4.545838)
		(end 273.881342 12.713462)
		(width 0.1651)
		(layer "In5.Cu")
		(net "85_10INCH_IN1_DN")
	)
	(segment
		(start 261.82955 12.573508)
		(end 262.211566 12.841478)
		(width 0.1651)
		(layer "In5.Cu")
		(net "85_10INCH_IN1_DN")
	)
	(segment
		(start 301.932848 12.641326)
		(end 302.315118 12.909296)
		(width 0.1651)
		(layer "In5.Cu")
		(net "85_10INCH_IN1_DN")
	)
	(segment
		(start 299.324776 12.746228)
		(end 299.592746 12.363958)
		(width 0.1651)
		(layer "In5.Cu")
		(net "85_10INCH_IN1_DN")
	)
	(segment
		(start 280.457656 4.534408)
		(end 281.887676 12.644882)
		(width 0.1651)
		(layer "In5.Cu")
		(net "85_10INCH_IN1_DN")
	)
	(segment
		(start 287.566862 12.373356)
		(end 286.256222 4.940554)
		(width 0.1651)
		(layer "In5.Cu")
		(net "85_10INCH_IN1_DN")
	)
	(segment
		(start 302.291242 4.933188)
		(end 302.69307 4.359656)
		(width 0.1651)
		(layer "In5.Cu")
		(net "85_10INCH_IN1_DN")
	)
	(segment
		(start 274.22729 4.930902)
		(end 274.629118 4.357624)
		(width 0.1651)
		(layer "In5.Cu")
		(net "85_10INCH_IN1_DN")
	)
	(segment
		(start 283.894784 4.140454)
		(end 284.468316 4.542536)
		(width 0.1651)
		(layer "In5.Cu")
		(net "85_10INCH_IN1_DN")
	)
	(segment
		(start 267.857478 4.13766)
		(end 268.43101 4.539488)
		(width 0.1651)
		(layer "In5.Cu")
		(net "85_10INCH_IN1_DN")
	)
	(segment
		(start 263.847834 4.134104)
		(end 264.421366 4.535932)
		(width 0.1651)
		(layer "In5.Cu")
		(net "85_10INCH_IN1_DN")
	)
	(segment
		(start 278.637238 4.352798)
		(end 279.884124 4.13258)
		(width 0.1651)
		(layer "In5.Cu")
		(net "85_10INCH_IN1_DN")
	)
	(segment
		(start 308.526942 4.562856)
		(end 309.091584 7.76478)
		(width 0.1651)
		(layer "In5.Cu")
		(net "85_10INCH_IN1_DN")
	)
	(segment
		(start 282.245816 4.93395)
		(end 282.647644 4.360672)
		(width 0.1651)
		(layer "In5.Cu")
		(net "85_10INCH_IN1_DN")
	)
	(segment
		(start 273.881342 12.713462)
		(end 274.26412 12.981432)
		(width 0.1651)
		(layer "In5.Cu")
		(net "85_10INCH_IN1_DN")
	)
	(segment
		(start 302.69307 4.359656)
		(end 303.939956 4.139438)
		(width 0.1651)
		(layer "In5.Cu")
		(net "85_10INCH_IN1_DN")
	)
	(segment
		(start 271.535652 12.40409)
		(end 270.21917 4.937506)
		(width 0.1651)
		(layer "In5.Cu")
		(net "85_10INCH_IN1_DN")
	)
	(segment
		(start 420.375588 -68.479162)
		(end 420.375588 -67.96405)
		(width 0.13208)
		(layer "F.Cu")
		(net "P12V_SSD14_CO_GATE")
	)
	(segment
		(start 420.375588 -67.96405)
		(end 420.198804 -67.787266)
		(width 0.13208)
		(layer "F.Cu")
		(net "P12V_SSD14_CO_GATE")
	)
	(segment
		(start 419.461188 -67.488054)
		(end 419.7985 -67.150742)
		(width 0.13208)
		(layer "F.Cu")
		(net "P12V_SSD14_CO_GATE")
	)
	(segment
		(start 419.7604 -67.787266)
		(end 419.461188 -67.488054)
		(width 0.13208)
		(layer "F.Cu")
		(net "P12V_SSD14_CO_GATE")
	)
	(segment
		(start 420.198804 -67.787266)
		(end 419.7604 -67.787266)
		(width 0.13208)
		(layer "F.Cu")
		(net "P12V_SSD14_CO_GATE")
	)
	(segment
		(start 419.7985 -67.150742)
		(end 419.7985 -66.72199)
		(width 0.13208)
		(layer "F.Cu")
		(net "P12V_SSD14_CO_GATE")
	)
	(via
		(at 419.461188 -67.488054)
		(size 0.508)
		(drill 0.254)
		(layers "F.Cu" "B.Cu")
		(net "P12V_SSD14_CO_GATE")
	)
	(segment
		(start 131.63296 -113.15827)
		(end 131.014724 -112.540034)
		(width 0.13208)
		(layer "F.Cu")
		(net "P3V3_NIC2_CO_ILIMIT")
	)
	(segment
		(start 131.014724 -112.540034)
		(end 130.287522 -112.540034)
		(width 0.13208)
		(layer "F.Cu")
		(net "P3V3_NIC2_CO_ILIMIT")
	)
	(segment
		(start 131.63296 -113.933478)
		(end 131.63296 -113.15827)
		(width 0.13208)
		(layer "F.Cu")
		(net "P3V3_NIC2_CO_ILIMIT")
	)
	(segment
		(start 130.26263 -112.515142)
		(end 130.26263 -111.777526)
		(width 0.13208)
		(layer "F.Cu")
		(net "P3V3_NIC2_CO_ILIMIT")
	)
	(segment
		(start 130.287522 -112.540034)
		(end 130.26263 -112.515142)
		(width 0.13208)
		(layer "F.Cu")
		(net "P3V3_NIC2_CO_ILIMIT")
	)
	(via
		(at 130.287522 -112.540034)
		(size 0.508)
		(drill 0.254)
		(layers "F.Cu" "B.Cu")
		(net "P3V3_NIC2_CO_ILIMIT")
	)
	(segment
		(start 335.273396 -120.79224)
		(end 334.530446 -120.79224)
		(width 0.13208)
		(layer "F.Cu")
		(net "P3V3_NIC5_PG_G1")
	)
	(segment
		(start 336.024474 -119.77624)
		(end 335.527396 -119.77624)
		(width 0.13208)
		(layer "F.Cu")
		(net "P3V3_NIC5_PG_G1")
	)
	(segment
		(start 335.527396 -119.77624)
		(end 335.273396 -120.03024)
		(width 0.13208)
		(layer "F.Cu")
		(net "P3V3_NIC5_PG_G1")
	)
	(segment
		(start 334.530446 -121.80824)
		(end 334.530446 -120.79224)
		(width 0.13208)
		(layer "F.Cu")
		(net "P3V3_NIC5_PG_G1")
	)
	(segment
		(start 335.273396 -120.03024)
		(end 335.273396 -120.79224)
		(width 0.13208)
		(layer "F.Cu")
		(net "P3V3_NIC5_PG_G1")
	)
	(via
		(at 335.273396 -120.79224)
		(size 0.508)
		(drill 0.254)
		(layers "F.Cu" "B.Cu")
		(net "P3V3_NIC5_PG_G1")
	)
	(segment
		(start 235.34116 12.443968)
		(end 234.161076 12.651994)
		(width 0.13462)
		(layer "F.Cu")
		(net "85_10INCH_TOP_DN")
	)
	(segment
		(start 205.156816 12.519406)
		(end 204.659738 12.171172)
		(width 0.13462)
		(layer "F.Cu")
		(net "85_10INCH_TOP_DN")
	)
	(segment
		(start 240.980722 8.213852)
		(end 236.830362 8.213852)
		(width 0.13462)
		(layer "F.Cu")
		(net "85_10INCH_TOP_DN")
	)
	(segment
		(start 228.37394 4.395978)
		(end 227.416868 4.565142)
		(width 0.13462)
		(layer "F.Cu")
		(net "85_10INCH_TOP_DN")
	)
	(segment
		(start 230.53675 12.64031)
		(end 230.038148 12.291822)
		(width 0.13462)
		(layer "F.Cu")
		(net "85_10INCH_TOP_DN")
	)
	(segment
		(start 195.789804 4.50977)
		(end 194.832732 4.67868)
		(width 0.13462)
		(layer "F.Cu")
		(net "85_10INCH_TOP_DN")
	)
	(segment
		(start 210.28152 4.516628)
		(end 209.324448 4.685538)
		(width 0.13462)
		(layer "F.Cu")
		(net "85_10INCH_TOP_DN")
	)
	(segment
		(start 217.206322 12.319)
		(end 216.026238 12.527026)
		(width 0.13462)
		(layer "F.Cu")
		(net "85_10INCH_TOP_DN")
	)
	(segment
		(start 213.90864 4.54279)
		(end 212.951568 4.7117)
		(width 0.13462)
		(layer "F.Cu")
		(net "85_10INCH_TOP_DN")
	)
	(segment
		(start 231.041194 4.579874)
		(end 230.823262 4.890516)
		(width 0.13462)
		(layer "F.Cu")
		(net "85_10INCH_TOP_DN")
	)
	(segment
		(start 206.968598 4.7244)
		(end 206.65694 4.506214)
		(width 0.13462)
		(layer "F.Cu")
		(net "85_10INCH_TOP_DN")
	)
	(segment
		(start 223.577658 4.887976)
		(end 224.818448 11.926824)
		(width 0.13462)
		(layer "F.Cu")
		(net "85_10INCH_TOP_DN")
	)
	(segment
		(start 212.733636 5.023104)
		(end 213.929976 11.809222)
		(width 0.13462)
		(layer "F.Cu")
		(net "85_10INCH_TOP_DN")
	)
	(segment
		(start 236.830362 8.213852)
		(end 236.518704 7.952232)
		(width 0.13462)
		(layer "F.Cu")
		(net "85_10INCH_TOP_DN")
	)
	(segment
		(start 198.23557 4.978654)
		(end 199.445118 11.84021)
		(width 0.13462)
		(layer "F.Cu")
		(net "85_10INCH_TOP_DN")
	)
	(segment
		(start 194.832732 4.67868)
		(end 194.614546 4.990084)
		(width 0.13462)
		(layer "F.Cu")
		(net "85_10INCH_TOP_DN")
	)
	(segment
		(start 189.316106 8.220964)
		(end 184.45607 8.220964)
		(width 0.13462)
		(layer "F.Cu")
		(net "85_10INCH_TOP_DN")
	)
	(segment
		(start 216.35593 5.020564)
		(end 217.55481 11.820906)
		(width 0.13462)
		(layer "F.Cu")
		(net "85_10INCH_TOP_DN")
	)
	(segment
		(start 214.220298 4.760976)
		(end 213.90864 4.54279)
		(width 0.13462)
		(layer "F.Cu")
		(net "85_10INCH_TOP_DN")
	)
	(segment
		(start 194.294252 12.546076)
		(end 193.796158 12.197842)
		(width 0.13462)
		(layer "F.Cu")
		(net "85_10INCH_TOP_DN")
	)
	(segment
		(start 213.929976 11.809222)
		(end 213.581488 12.307316)
		(width 0.13462)
		(layer "F.Cu")
		(net "85_10INCH_TOP_DN")
	)
	(segment
		(start 203.036424 4.517644)
		(end 202.079352 4.686554)
		(width 0.13462)
		(layer "F.Cu")
		(net "85_10INCH_TOP_DN")
	)
	(segment
		(start 190.994284 5.001768)
		(end 192.196974 11.823954)
		(width 0.13462)
		(layer "F.Cu")
		(net "85_10INCH_TOP_DN")
	)
	(segment
		(start 236.518704 7.952232)
		(end 235.933234 4.631944)
		(width 0.13462)
		(layer "F.Cu")
		(net "85_10INCH_TOP_DN")
	)
	(segment
		(start 234.446318 4.893818)
		(end 235.689648 11.945874)
		(width 0.13462)
		(layer "F.Cu")
		(net "85_10INCH_TOP_DN")
	)
	(segment
		(start 212.951568 4.7117)
		(end 212.733636 5.023104)
		(width 0.13462)
		(layer "F.Cu")
		(net "85_10INCH_TOP_DN")
	)
	(segment
		(start 206.3369 12.31138)
		(end 205.156816 12.519406)
		(width 0.13462)
		(layer "F.Cu")
		(net "85_10INCH_TOP_DN")
	)
	(segment
		(start 202.079352 4.686554)
		(end 201.86142 4.997958)
		(width 0.13462)
		(layer "F.Cu")
		(net "85_10INCH_TOP_DN")
	)
	(segment
		(start 199.722232 4.71678)
		(end 199.410828 4.498594)
		(width 0.13462)
		(layer "F.Cu")
		(net "85_10INCH_TOP_DN")
	)
	(segment
		(start 228.09454 12.434824)
		(end 226.914456 12.64285)
		(width 0.13462)
		(layer "F.Cu")
		(net "85_10INCH_TOP_DN")
	)
	(segment
		(start 212.401404 12.515342)
		(end 211.904326 12.167108)
		(width 0.13462)
		(layer "F.Cu")
		(net "85_10INCH_TOP_DN")
	)
	(segment
		(start 226.914456 12.64285)
		(end 226.416616 12.293854)
		(width 0.13462)
		(layer "F.Cu")
		(net "85_10INCH_TOP_DN")
	)
	(segment
		(start 220.194886 4.700778)
		(end 219.976954 5.012182)
		(width 0.13462)
		(layer "F.Cu")
		(net "85_10INCH_TOP_DN")
	)
	(segment
		(start 205.481936 4.986528)
		(end 206.685388 11.813032)
		(width 0.13462)
		(layer "F.Cu")
		(net "85_10INCH_TOP_DN")
	)
	(segment
		(start 195.822824 11.840464)
		(end 195.474336 12.33805)
		(width 0.13462)
		(layer "F.Cu")
		(net "85_10INCH_TOP_DN")
	)
	(segment
		(start 219.14993 12.168886)
		(end 217.842592 4.758436)
		(width 0.13462)
		(layer "F.Cu")
		(net "85_10INCH_TOP_DN")
	)
	(segment
		(start 209.96529 12.34313)
		(end 208.785206 12.551156)
		(width 0.13462)
		(layer "F.Cu")
		(net "85_10INCH_TOP_DN")
	)
	(segment
		(start 222.793052 12.285218)
		(end 221.463616 4.750054)
		(width 0.13462)
		(layer "F.Cu")
		(net "85_10INCH_TOP_DN")
	)
	(segment
		(start 199.445118 11.84021)
		(end 199.09663 12.338304)
		(width 0.13462)
		(layer "F.Cu")
		(net "85_10INCH_TOP_DN")
	)
	(segment
		(start 233.664506 12.30376)
		(end 232.310178 4.628896)
		(width 0.13462)
		(layer "F.Cu")
		(net "85_10INCH_TOP_DN")
	)
	(segment
		(start 228.68509 4.614164)
		(end 228.37394 4.395978)
		(width 0.13462)
		(layer "F.Cu")
		(net "85_10INCH_TOP_DN")
	)
	(segment
		(start 208.28762 12.202922)
		(end 206.968598 4.7244)
		(width 0.13462)
		(layer "F.Cu")
		(net "85_10INCH_TOP_DN")
	)
	(segment
		(start 221.17558 11.811)
		(end 220.827092 12.309094)
		(width 0.13462)
		(layer "F.Cu")
		(net "85_10INCH_TOP_DN")
	)
	(segment
		(start 217.842592 4.758436)
		(end 217.530934 4.54025)
		(width 0.13462)
		(layer "F.Cu")
		(net "85_10INCH_TOP_DN")
	)
	(segment
		(start 192.196974 11.823954)
		(end 191.848486 12.322048)
		(width 0.13462)
		(layer "F.Cu")
		(net "85_10INCH_TOP_DN")
	)
	(segment
		(start 191.848486 12.322048)
		(end 190.668402 12.530074)
		(width 0.13462)
		(layer "F.Cu")
		(net "85_10INCH_TOP_DN")
	)
	(segment
		(start 230.823262 4.890516)
		(end 232.065322 11.934444)
		(width 0.13462)
		(layer "F.Cu")
		(net "85_10INCH_TOP_DN")
	)
	(segment
		(start 226.416616 12.293854)
		(end 225.06432 4.62534)
		(width 0.13462)
		(layer "F.Cu")
		(net "85_10INCH_TOP_DN")
	)
	(segment
		(start 198.453502 4.667504)
		(end 198.23557 4.978654)
		(width 0.13462)
		(layer "F.Cu")
		(net "85_10INCH_TOP_DN")
	)
	(segment
		(start 208.785206 12.551156)
		(end 208.28762 12.202922)
		(width 0.13462)
		(layer "F.Cu")
		(net "85_10INCH_TOP_DN")
	)
	(segment
		(start 221.463616 4.750054)
		(end 221.151958 4.531868)
		(width 0.13462)
		(layer "F.Cu")
		(net "85_10INCH_TOP_DN")
	)
	(segment
		(start 184.45607 8.220964)
		(end 184.343294 8.33374)
		(width 0.13462)
		(layer "F.Cu")
		(net "85_10INCH_TOP_DN")
	)
	(segment
		(start 232.065322 11.934444)
		(end 231.716834 12.432284)
		(width 0.13462)
		(layer "F.Cu")
		(net "85_10INCH_TOP_DN")
	)
	(segment
		(start 227.416868 4.565142)
		(end 227.198428 4.877054)
		(width 0.13462)
		(layer "F.Cu")
		(net "85_10INCH_TOP_DN")
	)
	(segment
		(start 219.976954 5.012182)
		(end 221.17558 11.811)
		(width 0.13462)
		(layer "F.Cu")
		(net "85_10INCH_TOP_DN")
	)
	(segment
		(start 224.46996 12.425426)
		(end 223.289876 12.633452)
		(width 0.13462)
		(layer "F.Cu")
		(net "85_10INCH_TOP_DN")
	)
	(segment
		(start 220.827092 12.309094)
		(end 219.647008 12.51712)
		(width 0.13462)
		(layer "F.Cu")
		(net "85_10INCH_TOP_DN")
	)
	(segment
		(start 201.03973 12.18692)
		(end 199.722232 4.71678)
		(width 0.13462)
		(layer "F.Cu")
		(net "85_10INCH_TOP_DN")
	)
	(segment
		(start 210.313778 11.845036)
		(end 209.96529 12.34313)
		(width 0.13462)
		(layer "F.Cu")
		(net "85_10INCH_TOP_DN")
	)
	(segment
		(start 189.506098 8.410956)
		(end 189.316106 8.220964)
		(width 0.13462)
		(layer "F.Cu")
		(net "85_10INCH_TOP_DN")
	)
	(segment
		(start 206.65694 4.506214)
		(end 205.699868 4.675124)
		(width 0.13462)
		(layer "F.Cu")
		(net "85_10INCH_TOP_DN")
	)
	(segment
		(start 192.169288 4.521454)
		(end 191.212216 4.690364)
		(width 0.13462)
		(layer "F.Cu")
		(net "85_10INCH_TOP_DN")
	)
	(segment
		(start 210.593178 4.734814)
		(end 210.28152 4.516628)
		(width 0.13462)
		(layer "F.Cu")
		(net "85_10INCH_TOP_DN")
	)
	(segment
		(start 209.324448 4.685538)
		(end 209.106516 4.996942)
		(width 0.13462)
		(layer "F.Cu")
		(net "85_10INCH_TOP_DN")
	)
	(segment
		(start 235.689648 11.945874)
		(end 235.34116 12.443968)
		(width 0.13462)
		(layer "F.Cu")
		(net "85_10INCH_TOP_DN")
	)
	(segment
		(start 184.343294 8.33374)
		(end 184.151524 8.33374)
		(width 0.13462)
		(layer "F.Cu")
		(net "85_10INCH_TOP_DN")
	)
	(segment
		(start 234.66425 4.582668)
		(end 234.446318 4.893818)
		(width 0.13462)
		(layer "F.Cu")
		(net "85_10INCH_TOP_DN")
	)
	(segment
		(start 241.093498 8.326628)
		(end 240.980722 8.213852)
		(width 0.13462)
		(layer "F.Cu")
		(net "85_10INCH_TOP_DN")
	)
	(segment
		(start 216.573862 4.70916)
		(end 216.35593 5.020564)
		(width 0.13462)
		(layer "F.Cu")
		(net "85_10INCH_TOP_DN")
	)
	(segment
		(start 195.474336 12.33805)
		(end 194.294252 12.546076)
		(width 0.13462)
		(layer "F.Cu")
		(net "85_10INCH_TOP_DN")
	)
	(segment
		(start 206.685388 11.813032)
		(end 206.3369 12.31138)
		(width 0.13462)
		(layer "F.Cu")
		(net "85_10INCH_TOP_DN")
	)
	(segment
		(start 224.75317 4.407154)
		(end 223.796098 4.576064)
		(width 0.13462)
		(layer "F.Cu")
		(net "85_10INCH_TOP_DN")
	)
	(segment
		(start 219.647008 12.51712)
		(end 219.14993 12.168886)
		(width 0.13462)
		(layer "F.Cu")
		(net "85_10INCH_TOP_DN")
	)
	(segment
		(start 204.659738 12.171172)
		(end 203.348082 4.73583)
		(width 0.13462)
		(layer "F.Cu")
		(net "85_10INCH_TOP_DN")
	)
	(segment
		(start 199.09663 12.338304)
		(end 197.916546 12.54633)
		(width 0.13462)
		(layer "F.Cu")
		(net "85_10INCH_TOP_DN")
	)
	(segment
		(start 217.530934 4.54025)
		(end 216.573862 4.70916)
		(width 0.13462)
		(layer "F.Cu")
		(net "85_10INCH_TOP_DN")
	)
	(segment
		(start 230.038148 12.291822)
		(end 228.68509 4.614164)
		(width 0.13462)
		(layer "F.Cu")
		(net "85_10INCH_TOP_DN")
	)
	(segment
		(start 225.06432 4.62534)
		(end 224.75317 4.407154)
		(width 0.13462)
		(layer "F.Cu")
		(net "85_10INCH_TOP_DN")
	)
	(segment
		(start 223.289876 12.633452)
		(end 222.793052 12.285218)
		(width 0.13462)
		(layer "F.Cu")
		(net "85_10INCH_TOP_DN")
	)
	(segment
		(start 201.86142 4.997958)
		(end 203.065634 11.82878)
		(width 0.13462)
		(layer "F.Cu")
		(net "85_10INCH_TOP_DN")
	)
	(segment
		(start 216.026238 12.527026)
		(end 215.528652 12.178792)
		(width 0.13462)
		(layer "F.Cu")
		(net "85_10INCH_TOP_DN")
	)
	(segment
		(start 234.161076 12.651994)
		(end 233.664506 12.30376)
		(width 0.13462)
		(layer "F.Cu")
		(net "85_10INCH_TOP_DN")
	)
	(segment
		(start 231.998266 4.41071)
		(end 231.041194 4.579874)
		(width 0.13462)
		(layer "F.Cu")
		(net "85_10INCH_TOP_DN")
	)
	(segment
		(start 211.904326 12.167108)
		(end 210.593178 4.734814)
		(width 0.13462)
		(layer "F.Cu")
		(net "85_10INCH_TOP_DN")
	)
	(segment
		(start 193.796158 12.197842)
		(end 192.480946 4.73964)
		(width 0.13462)
		(layer "F.Cu")
		(net "85_10INCH_TOP_DN")
	)
	(segment
		(start 209.106516 4.996942)
		(end 210.313778 11.845036)
		(width 0.13462)
		(layer "F.Cu")
		(net "85_10INCH_TOP_DN")
	)
	(segment
		(start 203.348082 4.73583)
		(end 203.036424 4.517644)
		(width 0.13462)
		(layer "F.Cu")
		(net "85_10INCH_TOP_DN")
	)
	(segment
		(start 231.716834 12.432284)
		(end 230.53675 12.64031)
		(width 0.13462)
		(layer "F.Cu")
		(net "85_10INCH_TOP_DN")
	)
	(segment
		(start 227.198428 4.877054)
		(end 228.443028 11.936476)
		(width 0.13462)
		(layer "F.Cu")
		(net "85_10INCH_TOP_DN")
	)
	(segment
		(start 197.916546 12.54633)
		(end 197.418706 12.198096)
		(width 0.13462)
		(layer "F.Cu")
		(net "85_10INCH_TOP_DN")
	)
	(segment
		(start 190.668402 12.530074)
		(end 190.171578 12.182348)
		(width 0.13462)
		(layer "F.Cu")
		(net "85_10INCH_TOP_DN")
	)
	(segment
		(start 197.418706 12.198096)
		(end 196.101462 4.727956)
		(width 0.13462)
		(layer "F.Cu")
		(net "85_10INCH_TOP_DN")
	)
	(segment
		(start 232.310178 4.628896)
		(end 231.998266 4.41071)
		(width 0.13462)
		(layer "F.Cu")
		(net "85_10INCH_TOP_DN")
	)
	(segment
		(start 201.537062 12.5349)
		(end 201.03973 12.18692)
		(width 0.13462)
		(layer "F.Cu")
		(net "85_10INCH_TOP_DN")
	)
	(segment
		(start 241.285268 8.326628)
		(end 241.093498 8.326628)
		(width 0.13462)
		(layer "F.Cu")
		(net "85_10INCH_TOP_DN")
	)
	(segment
		(start 194.614546 4.990084)
		(end 195.822824 11.840464)
		(width 0.13462)
		(layer "F.Cu")
		(net "85_10INCH_TOP_DN")
	)
	(segment
		(start 223.796098 4.576064)
		(end 223.577658 4.887976)
		(width 0.13462)
		(layer "F.Cu")
		(net "85_10INCH_TOP_DN")
	)
	(segment
		(start 235.933234 4.631944)
		(end 235.621576 4.413758)
		(width 0.13462)
		(layer "F.Cu")
		(net "85_10INCH_TOP_DN")
	)
	(segment
		(start 213.581488 12.307316)
		(end 212.401404 12.515342)
		(width 0.13462)
		(layer "F.Cu")
		(net "85_10INCH_TOP_DN")
	)
	(segment
		(start 221.151958 4.531868)
		(end 220.194886 4.700778)
		(width 0.13462)
		(layer "F.Cu")
		(net "85_10INCH_TOP_DN")
	)
	(segment
		(start 191.212216 4.690364)
		(end 190.994284 5.001768)
		(width 0.13462)
		(layer "F.Cu")
		(net "85_10INCH_TOP_DN")
	)
	(segment
		(start 224.818448 11.926824)
		(end 224.46996 12.425426)
		(width 0.13462)
		(layer "F.Cu")
		(net "85_10INCH_TOP_DN")
	)
	(segment
		(start 192.480946 4.73964)
		(end 192.169288 4.521454)
		(width 0.13462)
		(layer "F.Cu")
		(net "85_10INCH_TOP_DN")
	)
	(segment
		(start 190.171578 12.182348)
		(end 189.506098 8.410956)
		(width 0.13462)
		(layer "F.Cu")
		(net "85_10INCH_TOP_DN")
	)
	(segment
		(start 202.717146 12.326874)
		(end 201.537062 12.5349)
		(width 0.13462)
		(layer "F.Cu")
		(net "85_10INCH_TOP_DN")
	)
	(segment
		(start 196.101462 4.727956)
		(end 195.789804 4.50977)
		(width 0.13462)
		(layer "F.Cu")
		(net "85_10INCH_TOP_DN")
	)
	(segment
		(start 199.410828 4.498594)
		(end 198.453502 4.667504)
		(width 0.13462)
		(layer "F.Cu")
		(net "85_10INCH_TOP_DN")
	)
	(segment
		(start 235.621576 4.413758)
		(end 234.66425 4.582668)
		(width 0.13462)
		(layer "F.Cu")
		(net "85_10INCH_TOP_DN")
	)
	(segment
		(start 205.699868 4.675124)
		(end 205.481936 4.986528)
		(width 0.13462)
		(layer "F.Cu")
		(net "85_10INCH_TOP_DN")
	)
	(segment
		(start 215.528652 12.178792)
		(end 214.220298 4.760976)
		(width 0.13462)
		(layer "F.Cu")
		(net "85_10INCH_TOP_DN")
	)
	(segment
		(start 217.55481 11.820906)
		(end 217.206322 12.319)
		(width 0.13462)
		(layer "F.Cu")
		(net "85_10INCH_TOP_DN")
	)
	(segment
		(start 203.065634 11.82878)
		(end 202.717146 12.326874)
		(width 0.13462)
		(layer "F.Cu")
		(net "85_10INCH_TOP_DN")
	)
	(segment
		(start 228.443028 11.936476)
		(end 228.09454 12.434824)
		(width 0.13462)
		(layer "F.Cu")
		(net "85_10INCH_TOP_DN")
	)
	(segment
		(start 445.760348 -67.787266)
		(end 446.198752 -67.787266)
		(width 0.13208)
		(layer "F.Cu")
		(net "P12V_SSD15_CO_GATE")
	)
	(segment
		(start 446.198752 -67.787266)
		(end 446.375536 -67.96405)
		(width 0.13208)
		(layer "F.Cu")
		(net "P12V_SSD15_CO_GATE")
	)
	(segment
		(start 445.798448 -67.150742)
		(end 445.461136 -67.488054)
		(width 0.13208)
		(layer "F.Cu")
		(net "P12V_SSD15_CO_GATE")
	)
	(segment
		(start 445.461136 -67.488054)
		(end 445.760348 -67.787266)
		(width 0.13208)
		(layer "F.Cu")
		(net "P12V_SSD15_CO_GATE")
	)
	(segment
		(start 446.375536 -67.96405)
		(end 446.375536 -68.479162)
		(width 0.13208)
		(layer "F.Cu")
		(net "P12V_SSD15_CO_GATE")
	)
	(segment
		(start 445.798448 -66.72199)
		(end 445.798448 -67.150742)
		(width 0.13208)
		(layer "F.Cu")
		(net "P12V_SSD15_CO_GATE")
	)
	(via
		(at 445.461136 -67.488054)
		(size 0.508)
		(drill 0.254)
		(layers "F.Cu" "B.Cu")
		(net "P12V_SSD15_CO_GATE")
	)
	(segment
		(start 210.19389 -115.902486)
		(end 209.78495 -115.902486)
		(width 0.13208)
		(layer "F.Cu")
		(net "P3V3_NIC3_CO_MODE")
	)
	(segment
		(start 209.4611 -115.001548)
		(end 209.4611 -115.578636)
		(width 0.13208)
		(layer "F.Cu")
		(net "P3V3_NIC3_CO_MODE")
	)
	(segment
		(start 210.19389 -114.886486)
		(end 210.19389 -115.902486)
		(width 0.13208)
		(layer "F.Cu")
		(net "P3V3_NIC3_CO_MODE")
	)
	(segment
		(start 209.78495 -115.902486)
		(end 209.4611 -115.578636)
		(width 0.13208)
		(layer "F.Cu")
		(net "P3V3_NIC3_CO_MODE")
	)
	(segment
		(start 208.7245 -114.811048)
		(end 209.2706 -114.811048)
		(width 0.13208)
		(layer "F.Cu")
		(net "P3V3_NIC3_CO_MODE")
	)
	(segment
		(start 209.2706 -114.811048)
		(end 209.4611 -115.001548)
		(width 0.13208)
		(layer "F.Cu")
		(net "P3V3_NIC3_CO_MODE")
	)
	(via
		(at 209.4611 -115.578636)
		(size 0.508)
		(drill 0.254)
		(layers "F.Cu" "B.Cu")
		(net "P3V3_NIC3_CO_MODE")
	)
	(segment
		(start 246.988838 -118.720616)
		(end 246.988838 -118.111016)
		(width 0.13208)
		(layer "F.Cu")
		(net "P3V3_NIC4_CO_DV_DT")
	)
	(segment
		(start 247.741186 -117.358668)
		(end 247.741186 -116.695474)
		(width 0.13208)
		(layer "F.Cu")
		(net "P3V3_NIC4_CO_DV_DT")
	)
	(segment
		(start 246.988838 -118.111016)
		(end 247.741186 -117.358668)
		(width 0.13208)
		(layer "F.Cu")
		(net "P3V3_NIC4_CO_DV_DT")
	)
	(via
		(at 246.988838 -118.111016)
		(size 0.508)
		(drill 0.254)
		(layers "F.Cu" "B.Cu")
		(net "P3V3_NIC4_CO_DV_DT")
	)
	(segment
		(start 256.160524 8.33374)
		(end 256.841498 8.515604)
		(width 0.13462)
		(layer "F.Cu")
		(net "85_10INCH_IN1_DP")
	)
	(segment
		(start 313.294268 8.359648)
		(end 312.613294 8.541512)
		(width 0.13462)
		(layer "F.Cu")
		(net "85_10INCH_IN1_DP")
	)
	(segment
		(start 267.403834 12.94003)
		(end 267.80617 12.36599)
		(width 0.1651)
		(layer "In5.Cu")
		(net "85_10INCH_IN1_DP")
	)
	(segment
		(start 274.525486 4.997196)
		(end 274.793202 4.61518)
		(width 0.1651)
		(layer "In5.Cu")
		(net "85_10INCH_IN1_DP")
	)
	(segment
		(start 282.203906 13.211048)
		(end 283.449776 12.99083)
		(width 0.1651)
		(layer "In5.Cu")
		(net "85_10INCH_IN1_DP")
	)
	(segment
		(start 271.801844 4.442206)
		(end 272.18386 4.709922)
		(width 0.1651)
		(layer "In5.Cu")
		(net "85_10INCH_IN1_DP")
	)
	(segment
		(start 266.50696 4.99745)
		(end 266.774676 4.615434)
		(width 0.1651)
		(layer "In5.Cu")
		(net "85_10INCH_IN1_DP")
	)
	(segment
		(start 308.834028 7.928864)
		(end 309.29326 8.250682)
		(width 0.1651)
		(layer "In5.Cu")
		(net "85_10INCH_IN1_DP")
	)
	(segment
		(start 295.886632 12.458192)
		(end 294.569642 4.987798)
		(width 0.1651)
		(layer "In5.Cu")
		(net "85_10INCH_IN1_DP")
	)
	(segment
		(start 267.80617 12.36599)
		(end 266.50696 4.99745)
		(width 0.1651)
		(layer "In5.Cu")
		(net "85_10INCH_IN1_DP")
	)
	(segment
		(start 261.571994 12.737592)
		(end 262.145526 13.139674)
		(width 0.1651)
		(layer "In5.Cu")
		(net "85_10INCH_IN1_DP")
	)
	(segment
		(start 299.890942 12.430252)
		(end 298.57954 4.992624)
		(width 0.1651)
		(layer "In5.Cu")
		(net "85_10INCH_IN1_DP")
	)
	(segment
		(start 306.261008 13.222732)
		(end 307.506878 13.002514)
		(width 0.1651)
		(layer "In5.Cu")
		(net "85_10INCH_IN1_DP")
	)
	(segment
		(start 296.236136 4.69392)
		(end 297.669204 12.82192)
		(width 0.1651)
		(layer "In5.Cu")
		(net "85_10INCH_IN1_DP")
	)
	(segment
		(start 290.234116 13.27785)
		(end 291.479986 13.057632)
		(width 0.1651)
		(layer "In5.Cu")
		(net "85_10INCH_IN1_DP")
	)
	(segment
		(start 284.21076 4.70662)
		(end 285.64332 12.831318)
		(width 0.1651)
		(layer "In5.Cu")
		(net "85_10INCH_IN1_DP")
	)
	(segment
		(start 303.494948 12.987274)
		(end 303.897284 12.413488)
		(width 0.1651)
		(layer "In5.Cu")
		(net "85_10INCH_IN1_DP")
	)
	(segment
		(start 299.864018 4.43103)
		(end 300.246034 4.698746)
		(width 0.1651)
		(layer "In5.Cu")
		(net "85_10INCH_IN1_DP")
	)
	(segment
		(start 269.612364 12.862052)
		(end 270.185896 13.264134)
		(width 0.1651)
		(layer "In5.Cu")
		(net "85_10INCH_IN1_DP")
	)
	(segment
		(start 279.818084 4.430776)
		(end 280.2001 4.698492)
		(width 0.1651)
		(layer "In5.Cu")
		(net "85_10INCH_IN1_DP")
	)
	(segment
		(start 275.846032 12.486386)
		(end 274.525486 4.997196)
		(width 0.1651)
		(layer "In5.Cu")
		(net "85_10INCH_IN1_DP")
	)
	(segment
		(start 299.48886 13.003784)
		(end 299.890942 12.430252)
		(width 0.1651)
		(layer "In5.Cu")
		(net "85_10INCH_IN1_DP")
	)
	(segment
		(start 263.781794 4.4323)
		(end 264.16381 4.700016)
		(width 0.1651)
		(layer "In5.Cu")
		(net "85_10INCH_IN1_DP")
	)
	(segment
		(start 298.847256 4.610608)
		(end 299.864018 4.43103)
		(width 0.1651)
		(layer "In5.Cu")
		(net "85_10INCH_IN1_DP")
	)
	(segment
		(start 260.370828 8.224774)
		(end 260.862572 8.716518)
		(width 0.1651)
		(layer "In5.Cu")
		(net "85_10INCH_IN1_DP")
	)
	(segment
		(start 306.870354 4.638294)
		(end 307.886862 4.458716)
		(width 0.1651)
		(layer "In5.Cu")
		(net "85_10INCH_IN1_DP")
	)
	(segment
		(start 273.623786 12.877546)
		(end 274.19808 13.279628)
		(width 0.1651)
		(layer "In5.Cu")
		(net "85_10INCH_IN1_DP")
	)
	(segment
		(start 262.497316 4.993894)
		(end 262.765032 4.611878)
		(width 0.1651)
		(layer "In5.Cu")
		(net "85_10INCH_IN1_DP")
	)
	(segment
		(start 294.569642 4.987798)
		(end 294.837358 4.605782)
		(width 0.1651)
		(layer "In5.Cu")
		(net "85_10INCH_IN1_DP")
	)
	(segment
		(start 288.221166 4.71297)
		(end 289.66033 12.875768)
		(width 0.1651)
		(layer "In5.Cu")
		(net "85_10INCH_IN1_DP")
	)
	(segment
		(start 287.838896 4.445254)
		(end 288.221166 4.71297)
		(width 0.1651)
		(layer "In5.Cu")
		(net "85_10INCH_IN1_DP")
	)
	(segment
		(start 265.58494 12.758674)
		(end 266.158218 13.160502)
		(width 0.1651)
		(layer "In5.Cu")
		(net "85_10INCH_IN1_DP")
	)
	(segment
		(start 312.322464 8.250682)
		(end 312.613294 8.541512)
		(width 0.1651)
		(layer "In5.Cu")
		(net "85_10INCH_IN1_DP")
	)
	(segment
		(start 294.837358 4.605782)
		(end 295.85412 4.426204)
		(width 0.1651)
		(layer "In5.Cu")
		(net "85_10INCH_IN1_DP")
	)
	(segment
		(start 267.791438 4.435856)
		(end 268.173454 4.703572)
		(width 0.1651)
		(layer "In5.Cu")
		(net "85_10INCH_IN1_DP")
	)
	(segment
		(start 268.173454 4.703572)
		(end 269.612364 12.862052)
		(width 0.1651)
		(layer "In5.Cu")
		(net "85_10INCH_IN1_DP")
	)
	(segment
		(start 280.2001 4.698492)
		(end 281.63012 12.808966)
		(width 0.1651)
		(layer "In5.Cu")
		(net "85_10INCH_IN1_DP")
	)
	(segment
		(start 285.64332 12.831318)
		(end 286.217106 13.2334)
		(width 0.1651)
		(layer "In5.Cu")
		(net "85_10INCH_IN1_DP")
	)
	(segment
		(start 281.63012 12.808966)
		(end 282.203906 13.211048)
		(width 0.1651)
		(layer "In5.Cu")
		(net "85_10INCH_IN1_DP")
	)
	(segment
		(start 283.82849 4.43865)
		(end 284.21076 4.70662)
		(width 0.1651)
		(layer "In5.Cu")
		(net "85_10INCH_IN1_DP")
	)
	(segment
		(start 279.846532 12.43838)
		(end 278.533606 4.99237)
		(width 0.1651)
		(layer "In5.Cu")
		(net "85_10INCH_IN1_DP")
	)
	(segment
		(start 291.84727 4.43992)
		(end 292.229286 4.707636)
		(width 0.1651)
		(layer "In5.Cu")
		(net "85_10INCH_IN1_DP")
	)
	(segment
		(start 263.793478 12.34567)
		(end 262.497316 4.993894)
		(width 0.1651)
		(layer "In5.Cu")
		(net "85_10INCH_IN1_DP")
	)
	(segment
		(start 278.801322 4.610354)
		(end 279.818084 4.430776)
		(width 0.1651)
		(layer "In5.Cu")
		(net "85_10INCH_IN1_DP")
	)
	(segment
		(start 286.217106 13.2334)
		(end 287.462976 13.013182)
		(width 0.1651)
		(layer "In5.Cu")
		(net "85_10INCH_IN1_DP")
	)
	(segment
		(start 302.589438 4.999228)
		(end 302.857154 4.617212)
		(width 0.1651)
		(layer "In5.Cu")
		(net "85_10INCH_IN1_DP")
	)
	(segment
		(start 286.822134 4.624832)
		(end 287.838896 4.445254)
		(width 0.1651)
		(layer "In5.Cu")
		(net "85_10INCH_IN1_DP")
	)
	(segment
		(start 304.25644 4.705604)
		(end 305.687222 12.82065)
		(width 0.1651)
		(layer "In5.Cu")
		(net "85_10INCH_IN1_DP")
	)
	(segment
		(start 287.462976 13.013182)
		(end 287.865058 12.43965)
		(width 0.1651)
		(layer "In5.Cu")
		(net "85_10INCH_IN1_DP")
	)
	(segment
		(start 286.554418 5.006848)
		(end 286.822134 4.624832)
		(width 0.1651)
		(layer "In5.Cu")
		(net "85_10INCH_IN1_DP")
	)
	(segment
		(start 302.857154 4.617212)
		(end 303.873916 4.437634)
		(width 0.1651)
		(layer "In5.Cu")
		(net "85_10INCH_IN1_DP")
	)
	(segment
		(start 283.851858 12.417298)
		(end 282.544012 5.000244)
		(width 0.1651)
		(layer "In5.Cu")
		(net "85_10INCH_IN1_DP")
	)
	(segment
		(start 297.669204 12.82192)
		(end 298.24299 13.224002)
		(width 0.1651)
		(layer "In5.Cu")
		(net "85_10INCH_IN1_DP")
	)
	(segment
		(start 260.862572 8.716518)
		(end 261.571994 12.737592)
		(width 0.1651)
		(layer "In5.Cu")
		(net "85_10INCH_IN1_DP")
	)
	(segment
		(start 291.479986 13.057632)
		(end 291.882068 12.4841)
		(width 0.1651)
		(layer "In5.Cu")
		(net "85_10INCH_IN1_DP")
	)
	(segment
		(start 306.602638 5.02031)
		(end 306.870354 4.638294)
		(width 0.1651)
		(layer "In5.Cu")
		(net "85_10INCH_IN1_DP")
	)
	(segment
		(start 275.809964 4.435602)
		(end 276.19198 4.703318)
		(width 0.1651)
		(layer "In5.Cu")
		(net "85_10INCH_IN1_DP")
	)
	(segment
		(start 307.506878 13.002514)
		(end 307.90896 12.428982)
		(width 0.1651)
		(layer "In5.Cu")
		(net "85_10INCH_IN1_DP")
	)
	(segment
		(start 307.886862 4.458716)
		(end 308.269386 4.72694)
		(width 0.1651)
		(layer "In5.Cu")
		(net "85_10INCH_IN1_DP")
	)
	(segment
		(start 287.865058 12.43965)
		(end 286.554418 5.006848)
		(width 0.1651)
		(layer "In5.Cu")
		(net "85_10INCH_IN1_DP")
	)
	(segment
		(start 282.544012 5.000244)
		(end 282.811728 4.618228)
		(width 0.1651)
		(layer "In5.Cu")
		(net "85_10INCH_IN1_DP")
	)
	(segment
		(start 301.675292 12.80541)
		(end 302.249078 13.207492)
		(width 0.1651)
		(layer "In5.Cu")
		(net "85_10INCH_IN1_DP")
	)
	(segment
		(start 278.19858 13.23213)
		(end 279.44445 13.011912)
		(width 0.1651)
		(layer "In5.Cu")
		(net "85_10INCH_IN1_DP")
	)
	(segment
		(start 270.185896 13.264134)
		(end 271.431766 13.043916)
		(width 0.1651)
		(layer "In5.Cu")
		(net "85_10INCH_IN1_DP")
	)
	(segment
		(start 298.24299 13.224002)
		(end 299.48886 13.003784)
		(width 0.1651)
		(layer "In5.Cu")
		(net "85_10INCH_IN1_DP")
	)
	(segment
		(start 270.785082 4.621784)
		(end 271.801844 4.442206)
		(width 0.1651)
		(layer "In5.Cu")
		(net "85_10INCH_IN1_DP")
	)
	(segment
		(start 293.664894 12.84986)
		(end 294.23868 13.251942)
		(width 0.1651)
		(layer "In5.Cu")
		(net "85_10INCH_IN1_DP")
	)
	(segment
		(start 302.249078 13.207492)
		(end 303.494948 12.987274)
		(width 0.1651)
		(layer "In5.Cu")
		(net "85_10INCH_IN1_DP")
	)
	(segment
		(start 290.562792 5.001514)
		(end 290.830508 4.619498)
		(width 0.1651)
		(layer "In5.Cu")
		(net "85_10INCH_IN1_DP")
	)
	(segment
		(start 266.774676 4.615434)
		(end 267.791438 4.435856)
		(width 0.1651)
		(layer "In5.Cu")
		(net "85_10INCH_IN1_DP")
	)
	(segment
		(start 266.158218 13.160502)
		(end 267.403834 12.94003)
		(width 0.1651)
		(layer "In5.Cu")
		(net "85_10INCH_IN1_DP")
	)
	(segment
		(start 298.57954 4.992624)
		(end 298.847256 4.610608)
		(width 0.1651)
		(layer "In5.Cu")
		(net "85_10INCH_IN1_DP")
	)
	(segment
		(start 272.18386 4.709922)
		(end 273.623786 12.877546)
		(width 0.1651)
		(layer "In5.Cu")
		(net "85_10INCH_IN1_DP")
	)
	(segment
		(start 283.449776 12.99083)
		(end 283.851858 12.417298)
		(width 0.1651)
		(layer "In5.Cu")
		(net "85_10INCH_IN1_DP")
	)
	(segment
		(start 276.19198 4.703318)
		(end 277.624794 12.830048)
		(width 0.1651)
		(layer "In5.Cu")
		(net "85_10INCH_IN1_DP")
	)
	(segment
		(start 300.246034 4.698746)
		(end 301.675292 12.80541)
		(width 0.1651)
		(layer "In5.Cu")
		(net "85_10INCH_IN1_DP")
	)
	(segment
		(start 291.882068 12.4841)
		(end 290.562792 5.001514)
		(width 0.1651)
		(layer "In5.Cu")
		(net "85_10INCH_IN1_DP")
	)
	(segment
		(start 271.431766 13.043916)
		(end 271.833848 12.470384)
		(width 0.1651)
		(layer "In5.Cu")
		(net "85_10INCH_IN1_DP")
	)
	(segment
		(start 290.830508 4.619498)
		(end 291.84727 4.43992)
		(width 0.1651)
		(layer "In5.Cu")
		(net "85_10INCH_IN1_DP")
	)
	(segment
		(start 308.269386 4.72694)
		(end 308.834028 7.928864)
		(width 0.1651)
		(layer "In5.Cu")
		(net "85_10INCH_IN1_DP")
	)
	(segment
		(start 275.44395 13.05941)
		(end 275.846032 12.486386)
		(width 0.1651)
		(layer "In5.Cu")
		(net "85_10INCH_IN1_DP")
	)
	(segment
		(start 289.66033 12.875768)
		(end 290.234116 13.27785)
		(width 0.1651)
		(layer "In5.Cu")
		(net "85_10INCH_IN1_DP")
	)
	(segment
		(start 277.624794 12.830048)
		(end 278.19858 13.23213)
		(width 0.1651)
		(layer "In5.Cu")
		(net "85_10INCH_IN1_DP")
	)
	(segment
		(start 264.16381 4.700016)
		(end 265.58494 12.758674)
		(width 0.1651)
		(layer "In5.Cu")
		(net "85_10INCH_IN1_DP")
	)
	(segment
		(start 270.517366 5.0038)
		(end 270.785082 4.621784)
		(width 0.1651)
		(layer "In5.Cu")
		(net "85_10INCH_IN1_DP")
	)
	(segment
		(start 257.132328 8.224774)
		(end 260.370828 8.224774)
		(width 0.1651)
		(layer "In5.Cu")
		(net "85_10INCH_IN1_DP")
	)
	(segment
		(start 295.85412 4.426204)
		(end 296.236136 4.69392)
		(width 0.1651)
		(layer "In5.Cu")
		(net "85_10INCH_IN1_DP")
	)
	(segment
		(start 282.811728 4.618228)
		(end 283.82849 4.43865)
		(width 0.1651)
		(layer "In5.Cu")
		(net "85_10INCH_IN1_DP")
	)
	(segment
		(start 262.765032 4.611878)
		(end 263.781794 4.4323)
		(width 0.1651)
		(layer "In5.Cu")
		(net "85_10INCH_IN1_DP")
	)
	(segment
		(start 309.29326 8.250682)
		(end 312.322464 8.250682)
		(width 0.1651)
		(layer "In5.Cu")
		(net "85_10INCH_IN1_DP")
	)
	(segment
		(start 262.145526 13.139674)
		(end 263.391396 12.919456)
		(width 0.1651)
		(layer "In5.Cu")
		(net "85_10INCH_IN1_DP")
	)
	(segment
		(start 278.533606 4.99237)
		(end 278.801322 4.610354)
		(width 0.1651)
		(layer "In5.Cu")
		(net "85_10INCH_IN1_DP")
	)
	(segment
		(start 263.391396 12.919456)
		(end 263.793478 12.34567)
		(width 0.1651)
		(layer "In5.Cu")
		(net "85_10INCH_IN1_DP")
	)
	(segment
		(start 292.229286 4.707636)
		(end 293.664894 12.84986)
		(width 0.1651)
		(layer "In5.Cu")
		(net "85_10INCH_IN1_DP")
	)
	(segment
		(start 274.19808 13.279628)
		(end 275.44395 13.05941)
		(width 0.1651)
		(layer "In5.Cu")
		(net "85_10INCH_IN1_DP")
	)
	(segment
		(start 294.23868 13.251942)
		(end 295.48455 13.031724)
		(width 0.1651)
		(layer "In5.Cu")
		(net "85_10INCH_IN1_DP")
	)
	(segment
		(start 295.48455 13.031724)
		(end 295.886632 12.458192)
		(width 0.1651)
		(layer "In5.Cu")
		(net "85_10INCH_IN1_DP")
	)
	(segment
		(start 271.833848 12.470384)
		(end 270.517366 5.0038)
		(width 0.1651)
		(layer "In5.Cu")
		(net "85_10INCH_IN1_DP")
	)
	(segment
		(start 256.841498 8.515604)
		(end 257.132328 8.224774)
		(width 0.1651)
		(layer "In5.Cu")
		(net "85_10INCH_IN1_DP")
	)
	(segment
		(start 303.873916 4.437634)
		(end 304.25644 4.705604)
		(width 0.1651)
		(layer "In5.Cu")
		(net "85_10INCH_IN1_DP")
	)
	(segment
		(start 307.90896 12.428982)
		(end 306.602638 5.02031)
		(width 0.1651)
		(layer "In5.Cu")
		(net "85_10INCH_IN1_DP")
	)
	(segment
		(start 279.44445 13.011912)
		(end 279.846532 12.43838)
		(width 0.1651)
		(layer "In5.Cu")
		(net "85_10INCH_IN1_DP")
	)
	(segment
		(start 274.793202 4.61518)
		(end 275.809964 4.435602)
		(width 0.1651)
		(layer "In5.Cu")
		(net "85_10INCH_IN1_DP")
	)
	(segment
		(start 305.687222 12.82065)
		(end 306.261008 13.222732)
		(width 0.1651)
		(layer "In5.Cu")
		(net "85_10INCH_IN1_DP")
	)
	(segment
		(start 303.897284 12.413488)
		(end 302.589438 4.999228)
		(width 0.1651)
		(layer "In5.Cu")
		(net "85_10INCH_IN1_DP")
	)
	(segment
		(start 395.590014 -72.366632)
		(end 395.590014 -71.827898)
		(width 0.13208)
		(layer "F.Cu")
		(net "P12V_SSD13_CO_ILIMIT")
	)
	(segment
		(start 394.875512 -71.113396)
		(end 394.875512 -70.479158)
		(width 0.13208)
		(layer "F.Cu")
		(net "P12V_SSD13_CO_ILIMIT")
	)
	(segment
		(start 395.385544 -71.623428)
		(end 394.875512 -71.113396)
		(width 0.13208)
		(layer "F.Cu")
		(net "P12V_SSD13_CO_ILIMIT")
	)
	(segment
		(start 395.590014 -71.827898)
		(end 395.385544 -71.623428)
		(width 0.13208)
		(layer "F.Cu")
		(net "P12V_SSD13_CO_ILIMIT")
	)
	(via
		(at 395.385544 -71.623428)
		(size 0.508)
		(drill 0.254)
		(layers "F.Cu" "B.Cu")
		(net "P12V_SSD13_CO_ILIMIT")
	)
	(segment
		(start 234.66425 4.582668)
		(end 234.446318 4.893818)
		(width 0.13462)
		(layer "B.Cu")
		(net "85_10INCH_BOTTOM_DP")
	)
	(segment
		(start 235.34116 12.443968)
		(end 234.161076 12.651994)
		(width 0.13462)
		(layer "B.Cu")
		(net "85_10INCH_BOTTOM_DP")
	)
	(segment
		(start 197.916546 12.54633)
		(end 197.418706 12.198096)
		(width 0.13462)
		(layer "B.Cu")
		(net "85_10INCH_BOTTOM_DP")
	)
	(segment
		(start 220.194886 4.700778)
		(end 219.976954 5.012182)
		(width 0.13462)
		(layer "B.Cu")
		(net "85_10INCH_BOTTOM_DP")
	)
	(segment
		(start 219.647008 12.51712)
		(end 219.14993 12.168886)
		(width 0.13462)
		(layer "B.Cu")
		(net "85_10INCH_BOTTOM_DP")
	)
	(segment
		(start 235.621576 4.413758)
		(end 234.66425 4.582668)
		(width 0.13462)
		(layer "B.Cu")
		(net "85_10INCH_BOTTOM_DP")
	)
	(segment
		(start 195.789804 4.50977)
		(end 194.832732 4.67868)
		(width 0.13462)
		(layer "B.Cu")
		(net "85_10INCH_BOTTOM_DP")
	)
	(segment
		(start 216.35593 5.020564)
		(end 217.55481 11.820906)
		(width 0.13462)
		(layer "B.Cu")
		(net "85_10INCH_BOTTOM_DP")
	)
	(segment
		(start 199.09663 12.338304)
		(end 197.916546 12.54633)
		(width 0.13462)
		(layer "B.Cu")
		(net "85_10INCH_BOTTOM_DP")
	)
	(segment
		(start 206.65694 4.506214)
		(end 205.699868 4.675124)
		(width 0.13462)
		(layer "B.Cu")
		(net "85_10INCH_BOTTOM_DP")
	)
	(segment
		(start 220.827092 12.309094)
		(end 219.647008 12.51712)
		(width 0.13462)
		(layer "B.Cu")
		(net "85_10INCH_BOTTOM_DP")
	)
	(segment
		(start 206.968598 4.7244)
		(end 206.65694 4.506214)
		(width 0.13462)
		(layer "B.Cu")
		(net "85_10INCH_BOTTOM_DP")
	)
	(segment
		(start 217.55481 11.820906)
		(end 217.206322 12.319)
		(width 0.13462)
		(layer "B.Cu")
		(net "85_10INCH_BOTTOM_DP")
	)
	(segment
		(start 217.530934 4.54025)
		(end 216.573862 4.70916)
		(width 0.13462)
		(layer "B.Cu")
		(net "85_10INCH_BOTTOM_DP")
	)
	(segment
		(start 217.206322 12.319)
		(end 216.026238 12.527026)
		(width 0.13462)
		(layer "B.Cu")
		(net "85_10INCH_BOTTOM_DP")
	)
	(segment
		(start 226.416616 12.293854)
		(end 225.06432 4.62534)
		(width 0.13462)
		(layer "B.Cu")
		(net "85_10INCH_BOTTOM_DP")
	)
	(segment
		(start 212.733636 5.023104)
		(end 213.929976 11.809222)
		(width 0.13462)
		(layer "B.Cu")
		(net "85_10INCH_BOTTOM_DP")
	)
	(segment
		(start 191.848486 12.322048)
		(end 190.668402 12.530074)
		(width 0.13462)
		(layer "B.Cu")
		(net "85_10INCH_BOTTOM_DP")
	)
	(segment
		(start 225.06432 4.62534)
		(end 224.75317 4.407154)
		(width 0.13462)
		(layer "B.Cu")
		(net "85_10INCH_BOTTOM_DP")
	)
	(segment
		(start 219.14993 12.168886)
		(end 217.842592 4.758436)
		(width 0.13462)
		(layer "B.Cu")
		(net "85_10INCH_BOTTOM_DP")
	)
	(segment
		(start 203.348082 4.73583)
		(end 203.036424 4.517644)
		(width 0.13462)
		(layer "B.Cu")
		(net "85_10INCH_BOTTOM_DP")
	)
	(segment
		(start 210.313778 11.845036)
		(end 209.96529 12.34313)
		(width 0.13462)
		(layer "B.Cu")
		(net "85_10INCH_BOTTOM_DP")
	)
	(segment
		(start 228.443028 11.936476)
		(end 228.09454 12.434824)
		(width 0.13462)
		(layer "B.Cu")
		(net "85_10INCH_BOTTOM_DP")
	)
	(segment
		(start 221.17558 11.811)
		(end 220.827092 12.309094)
		(width 0.13462)
		(layer "B.Cu")
		(net "85_10INCH_BOTTOM_DP")
	)
	(segment
		(start 199.410828 4.498594)
		(end 198.453502 4.667504)
		(width 0.13462)
		(layer "B.Cu")
		(net "85_10INCH_BOTTOM_DP")
	)
	(segment
		(start 209.96529 12.34313)
		(end 208.785206 12.551156)
		(width 0.13462)
		(layer "B.Cu")
		(net "85_10INCH_BOTTOM_DP")
	)
	(segment
		(start 215.528652 12.178792)
		(end 214.220298 4.760976)
		(width 0.13462)
		(layer "B.Cu")
		(net "85_10INCH_BOTTOM_DP")
	)
	(segment
		(start 227.198428 4.877054)
		(end 228.443028 11.936476)
		(width 0.13462)
		(layer "B.Cu")
		(net "85_10INCH_BOTTOM_DP")
	)
	(segment
		(start 208.785206 12.551156)
		(end 208.28762 12.202922)
		(width 0.13462)
		(layer "B.Cu")
		(net "85_10INCH_BOTTOM_DP")
	)
	(segment
		(start 205.699868 4.675124)
		(end 205.481936 4.986528)
		(width 0.13462)
		(layer "B.Cu")
		(net "85_10INCH_BOTTOM_DP")
	)
	(segment
		(start 228.09454 12.434824)
		(end 226.914456 12.64285)
		(width 0.13462)
		(layer "B.Cu")
		(net "85_10INCH_BOTTOM_DP")
	)
	(segment
		(start 203.036424 4.517644)
		(end 202.079352 4.686554)
		(width 0.13462)
		(layer "B.Cu")
		(net "85_10INCH_BOTTOM_DP")
	)
	(segment
		(start 192.196974 11.823954)
		(end 191.848486 12.322048)
		(width 0.13462)
		(layer "B.Cu")
		(net "85_10INCH_BOTTOM_DP")
	)
	(segment
		(start 231.041194 4.579874)
		(end 230.823262 4.890516)
		(width 0.13462)
		(layer "B.Cu")
		(net "85_10INCH_BOTTOM_DP")
	)
	(segment
		(start 216.026238 12.527026)
		(end 215.528652 12.178792)
		(width 0.13462)
		(layer "B.Cu")
		(net "85_10INCH_BOTTOM_DP")
	)
	(segment
		(start 192.480946 4.73964)
		(end 192.169288 4.521454)
		(width 0.13462)
		(layer "B.Cu")
		(net "85_10INCH_BOTTOM_DP")
	)
	(segment
		(start 201.03973 12.18692)
		(end 199.722232 4.71678)
		(width 0.13462)
		(layer "B.Cu")
		(net "85_10INCH_BOTTOM_DP")
	)
	(segment
		(start 226.914456 12.64285)
		(end 226.416616 12.293854)
		(width 0.13462)
		(layer "B.Cu")
		(net "85_10INCH_BOTTOM_DP")
	)
	(segment
		(start 194.832732 4.67868)
		(end 194.614546 4.990084)
		(width 0.13462)
		(layer "B.Cu")
		(net "85_10INCH_BOTTOM_DP")
	)
	(segment
		(start 232.310178 4.628896)
		(end 231.998266 4.41071)
		(width 0.13462)
		(layer "B.Cu")
		(net "85_10INCH_BOTTOM_DP")
	)
	(segment
		(start 205.156816 12.519406)
		(end 204.659738 12.171172)
		(width 0.13462)
		(layer "B.Cu")
		(net "85_10INCH_BOTTOM_DP")
	)
	(segment
		(start 213.929976 11.809222)
		(end 213.581488 12.307316)
		(width 0.13462)
		(layer "B.Cu")
		(net "85_10INCH_BOTTOM_DP")
	)
	(segment
		(start 223.289876 12.633452)
		(end 222.793052 12.285218)
		(width 0.13462)
		(layer "B.Cu")
		(net "85_10INCH_BOTTOM_DP")
	)
	(segment
		(start 230.53675 12.64031)
		(end 230.038148 12.291822)
		(width 0.13462)
		(layer "B.Cu")
		(net "85_10INCH_BOTTOM_DP")
	)
	(segment
		(start 231.716834 12.432284)
		(end 230.53675 12.64031)
		(width 0.13462)
		(layer "B.Cu")
		(net "85_10INCH_BOTTOM_DP")
	)
	(segment
		(start 214.220298 4.760976)
		(end 213.90864 4.54279)
		(width 0.13462)
		(layer "B.Cu")
		(net "85_10INCH_BOTTOM_DP")
	)
	(segment
		(start 184.343294 8.33374)
		(end 184.151524 8.33374)
		(width 0.13462)
		(layer "B.Cu")
		(net "85_10INCH_BOTTOM_DP")
	)
	(segment
		(start 209.324448 4.685538)
		(end 209.106516 4.996942)
		(width 0.13462)
		(layer "B.Cu")
		(net "85_10INCH_BOTTOM_DP")
	)
	(segment
		(start 228.68509 4.614164)
		(end 228.37394 4.395978)
		(width 0.13462)
		(layer "B.Cu")
		(net "85_10INCH_BOTTOM_DP")
	)
	(segment
		(start 199.445118 11.84021)
		(end 199.09663 12.338304)
		(width 0.13462)
		(layer "B.Cu")
		(net "85_10INCH_BOTTOM_DP")
	)
	(segment
		(start 228.37394 4.395978)
		(end 227.416868 4.565142)
		(width 0.13462)
		(layer "B.Cu")
		(net "85_10INCH_BOTTOM_DP")
	)
	(segment
		(start 224.75317 4.407154)
		(end 223.796098 4.576064)
		(width 0.13462)
		(layer "B.Cu")
		(net "85_10INCH_BOTTOM_DP")
	)
	(segment
		(start 212.401404 12.515342)
		(end 211.904326 12.167108)
		(width 0.13462)
		(layer "B.Cu")
		(net "85_10INCH_BOTTOM_DP")
	)
	(segment
		(start 241.093498 8.326628)
		(end 240.980722 8.213852)
		(width 0.13462)
		(layer "B.Cu")
		(net "85_10INCH_BOTTOM_DP")
	)
	(segment
		(start 195.822824 11.840464)
		(end 195.474336 12.33805)
		(width 0.13462)
		(layer "B.Cu")
		(net "85_10INCH_BOTTOM_DP")
	)
	(segment
		(start 210.593178 4.734814)
		(end 210.28152 4.516628)
		(width 0.13462)
		(layer "B.Cu")
		(net "85_10INCH_BOTTOM_DP")
	)
	(segment
		(start 204.659738 12.171172)
		(end 203.348082 4.73583)
		(width 0.13462)
		(layer "B.Cu")
		(net "85_10INCH_BOTTOM_DP")
	)
	(segment
		(start 194.614546 4.990084)
		(end 195.822824 11.840464)
		(width 0.13462)
		(layer "B.Cu")
		(net "85_10INCH_BOTTOM_DP")
	)
	(segment
		(start 222.793052 12.285218)
		(end 221.463616 4.750054)
		(width 0.13462)
		(layer "B.Cu")
		(net "85_10INCH_BOTTOM_DP")
	)
	(segment
		(start 219.976954 5.012182)
		(end 221.17558 11.811)
		(width 0.13462)
		(layer "B.Cu")
		(net "85_10INCH_BOTTOM_DP")
	)
	(segment
		(start 227.416868 4.565142)
		(end 227.198428 4.877054)
		(width 0.13462)
		(layer "B.Cu")
		(net "85_10INCH_BOTTOM_DP")
	)
	(segment
		(start 190.994284 5.001768)
		(end 192.196974 11.823954)
		(width 0.13462)
		(layer "B.Cu")
		(net "85_10INCH_BOTTOM_DP")
	)
	(segment
		(start 201.537062 12.5349)
		(end 201.03973 12.18692)
		(width 0.13462)
		(layer "B.Cu")
		(net "85_10INCH_BOTTOM_DP")
	)
	(segment
		(start 213.90864 4.54279)
		(end 212.951568 4.7117)
		(width 0.13462)
		(layer "B.Cu")
		(net "85_10INCH_BOTTOM_DP")
	)
	(segment
		(start 213.581488 12.307316)
		(end 212.401404 12.515342)
		(width 0.13462)
		(layer "B.Cu")
		(net "85_10INCH_BOTTOM_DP")
	)
	(segment
		(start 223.796098 4.576064)
		(end 223.577658 4.887976)
		(width 0.13462)
		(layer "B.Cu")
		(net "85_10INCH_BOTTOM_DP")
	)
	(segment
		(start 211.904326 12.167108)
		(end 210.593178 4.734814)
		(width 0.13462)
		(layer "B.Cu")
		(net "85_10INCH_BOTTOM_DP")
	)
	(segment
		(start 203.065634 11.82878)
		(end 202.717146 12.326874)
		(width 0.13462)
		(layer "B.Cu")
		(net "85_10INCH_BOTTOM_DP")
	)
	(segment
		(start 231.998266 4.41071)
		(end 231.041194 4.579874)
		(width 0.13462)
		(layer "B.Cu")
		(net "85_10INCH_BOTTOM_DP")
	)
	(segment
		(start 209.106516 4.996942)
		(end 210.313778 11.845036)
		(width 0.13462)
		(layer "B.Cu")
		(net "85_10INCH_BOTTOM_DP")
	)
	(segment
		(start 196.101462 4.727956)
		(end 195.789804 4.50977)
		(width 0.13462)
		(layer "B.Cu")
		(net "85_10INCH_BOTTOM_DP")
	)
	(segment
		(start 197.418706 12.198096)
		(end 196.101462 4.727956)
		(width 0.13462)
		(layer "B.Cu")
		(net "85_10INCH_BOTTOM_DP")
	)
	(segment
		(start 202.717146 12.326874)
		(end 201.537062 12.5349)
		(width 0.13462)
		(layer "B.Cu")
		(net "85_10INCH_BOTTOM_DP")
	)
	(segment
		(start 208.28762 12.202922)
		(end 206.968598 4.7244)
		(width 0.13462)
		(layer "B.Cu")
		(net "85_10INCH_BOTTOM_DP")
	)
	(segment
		(start 224.818448 11.926824)
		(end 224.46996 12.425426)
		(width 0.13462)
		(layer "B.Cu")
		(net "85_10INCH_BOTTOM_DP")
	)
	(segment
		(start 224.46996 12.425426)
		(end 223.289876 12.633452)
		(width 0.13462)
		(layer "B.Cu")
		(net "85_10INCH_BOTTOM_DP")
	)
	(segment
		(start 193.796158 12.197842)
		(end 192.480946 4.73964)
		(width 0.13462)
		(layer "B.Cu")
		(net "85_10INCH_BOTTOM_DP")
	)
	(segment
		(start 205.481936 4.986528)
		(end 206.685388 11.813032)
		(width 0.13462)
		(layer "B.Cu")
		(net "85_10INCH_BOTTOM_DP")
	)
	(segment
		(start 230.038148 12.291822)
		(end 228.68509 4.614164)
		(width 0.13462)
		(layer "B.Cu")
		(net "85_10INCH_BOTTOM_DP")
	)
	(segment
		(start 201.86142 4.997958)
		(end 203.065634 11.82878)
		(width 0.13462)
		(layer "B.Cu")
		(net "85_10INCH_BOTTOM_DP")
	)
	(segment
		(start 221.463616 4.750054)
		(end 221.151958 4.531868)
		(width 0.13462)
		(layer "B.Cu")
		(net "85_10INCH_BOTTOM_DP")
	)
	(segment
		(start 217.842592 4.758436)
		(end 217.530934 4.54025)
		(width 0.13462)
		(layer "B.Cu")
		(net "85_10INCH_BOTTOM_DP")
	)
	(segment
		(start 232.065322 11.934444)
		(end 231.716834 12.432284)
		(width 0.13462)
		(layer "B.Cu")
		(net "85_10INCH_BOTTOM_DP")
	)
	(segment
		(start 206.685388 11.813032)
		(end 206.3369 12.31138)
		(width 0.13462)
		(layer "B.Cu")
		(net "85_10INCH_BOTTOM_DP")
	)
	(segment
		(start 241.285268 8.326628)
		(end 241.093498 8.326628)
		(width 0.13462)
		(layer "B.Cu")
		(net "85_10INCH_BOTTOM_DP")
	)
	(segment
		(start 195.474336 12.33805)
		(end 194.294252 12.546076)
		(width 0.13462)
		(layer "B.Cu")
		(net "85_10INCH_BOTTOM_DP")
	)
	(segment
		(start 191.212216 4.690364)
		(end 190.994284 5.001768)
		(width 0.13462)
		(layer "B.Cu")
		(net "85_10INCH_BOTTOM_DP")
	)
	(segment
		(start 190.668402 12.530074)
		(end 190.171578 12.182348)
		(width 0.13462)
		(layer "B.Cu")
		(net "85_10INCH_BOTTOM_DP")
	)
	(segment
		(start 230.823262 4.890516)
		(end 232.065322 11.934444)
		(width 0.13462)
		(layer "B.Cu")
		(net "85_10INCH_BOTTOM_DP")
	)
	(segment
		(start 234.161076 12.651994)
		(end 233.664506 12.30376)
		(width 0.13462)
		(layer "B.Cu")
		(net "85_10INCH_BOTTOM_DP")
	)
	(segment
		(start 199.722232 4.71678)
		(end 199.410828 4.498594)
		(width 0.13462)
		(layer "B.Cu")
		(net "85_10INCH_BOTTOM_DP")
	)
	(segment
		(start 223.577658 4.887976)
		(end 224.818448 11.926824)
		(width 0.13462)
		(layer "B.Cu")
		(net "85_10INCH_BOTTOM_DP")
	)
	(segment
		(start 189.506098 8.410956)
		(end 189.316106 8.220964)
		(width 0.13462)
		(layer "B.Cu")
		(net "85_10INCH_BOTTOM_DP")
	)
	(segment
		(start 212.951568 4.7117)
		(end 212.733636 5.023104)
		(width 0.13462)
		(layer "B.Cu")
		(net "85_10INCH_BOTTOM_DP")
	)
	(segment
		(start 236.518704 7.952232)
		(end 235.933234 4.631944)
		(width 0.13462)
		(layer "B.Cu")
		(net "85_10INCH_BOTTOM_DP")
	)
	(segment
		(start 190.171578 12.182348)
		(end 189.506098 8.410956)
		(width 0.13462)
		(layer "B.Cu")
		(net "85_10INCH_BOTTOM_DP")
	)
	(segment
		(start 202.079352 4.686554)
		(end 201.86142 4.997958)
		(width 0.13462)
		(layer "B.Cu")
		(net "85_10INCH_BOTTOM_DP")
	)
	(segment
		(start 198.23557 4.978654)
		(end 199.445118 11.84021)
		(width 0.13462)
		(layer "B.Cu")
		(net "85_10INCH_BOTTOM_DP")
	)
	(segment
		(start 194.294252 12.546076)
		(end 193.796158 12.197842)
		(width 0.13462)
		(layer "B.Cu")
		(net "85_10INCH_BOTTOM_DP")
	)
	(segment
		(start 198.453502 4.667504)
		(end 198.23557 4.978654)
		(width 0.13462)
		(layer "B.Cu")
		(net "85_10INCH_BOTTOM_DP")
	)
	(segment
		(start 235.689648 11.945874)
		(end 235.34116 12.443968)
		(width 0.13462)
		(layer "B.Cu")
		(net "85_10INCH_BOTTOM_DP")
	)
	(segment
		(start 184.45607 8.220964)
		(end 184.343294 8.33374)
		(width 0.13462)
		(layer "B.Cu")
		(net "85_10INCH_BOTTOM_DP")
	)
	(segment
		(start 221.151958 4.531868)
		(end 220.194886 4.700778)
		(width 0.13462)
		(layer "B.Cu")
		(net "85_10INCH_BOTTOM_DP")
	)
	(segment
		(start 235.933234 4.631944)
		(end 235.621576 4.413758)
		(width 0.13462)
		(layer "B.Cu")
		(net "85_10INCH_BOTTOM_DP")
	)
	(segment
		(start 233.664506 12.30376)
		(end 232.310178 4.628896)
		(width 0.13462)
		(layer "B.Cu")
		(net "85_10INCH_BOTTOM_DP")
	)
	(segment
		(start 192.169288 4.521454)
		(end 191.212216 4.690364)
		(width 0.13462)
		(layer "B.Cu")
		(net "85_10INCH_BOTTOM_DP")
	)
	(segment
		(start 206.3369 12.31138)
		(end 205.156816 12.519406)
		(width 0.13462)
		(layer "B.Cu")
		(net "85_10INCH_BOTTOM_DP")
	)
	(segment
		(start 234.446318 4.893818)
		(end 235.689648 11.945874)
		(width 0.13462)
		(layer "B.Cu")
		(net "85_10INCH_BOTTOM_DP")
	)
	(segment
		(start 216.573862 4.70916)
		(end 216.35593 5.020564)
		(width 0.13462)
		(layer "B.Cu")
		(net "85_10INCH_BOTTOM_DP")
	)
	(segment
		(start 189.316106 8.220964)
		(end 184.45607 8.220964)
		(width 0.13462)
		(layer "B.Cu")
		(net "85_10INCH_BOTTOM_DP")
	)
	(segment
		(start 210.28152 4.516628)
		(end 209.324448 4.685538)
		(width 0.13462)
		(layer "B.Cu")
		(net "85_10INCH_BOTTOM_DP")
	)
	(segment
		(start 236.830362 8.213852)
		(end 236.518704 7.952232)
		(width 0.13462)
		(layer "B.Cu")
		(net "85_10INCH_BOTTOM_DP")
	)
	(segment
		(start 240.980722 8.213852)
		(end 236.830362 8.213852)
		(width 0.13462)
		(layer "B.Cu")
		(net "85_10INCH_BOTTOM_DP")
	)
	(segment
		(start 377.575318 -64.102234)
		(end 377.575318 -63.086234)
		(width 0.13208)
		(layer "F.Cu")
		(net "P12V_SSD13_PG_G1")
	)
	(segment
		(start 377.575318 -63.086234)
		(end 378.002546 -63.086234)
		(width 0.13208)
		(layer "F.Cu")
		(net "P12V_SSD13_PG_G1")
	)
	(segment
		(start 378.54763 -63.56223)
		(end 378.98959 -63.56223)
		(width 0.13208)
		(layer "F.Cu")
		(net "P12V_SSD13_PG_G1")
	)
	(segment
		(start 378.002546 -63.086234)
		(end 378.189744 -63.273432)
		(width 0.13208)
		(layer "F.Cu")
		(net "P12V_SSD13_PG_G1")
	)
	(segment
		(start 378.258832 -63.273432)
		(end 378.54763 -63.56223)
		(width 0.13208)
		(layer "F.Cu")
		(net "P12V_SSD13_PG_G1")
	)
	(segment
		(start 378.189744 -63.273432)
		(end 378.258832 -63.273432)
		(width 0.13208)
		(layer "F.Cu")
		(net "P12V_SSD13_PG_G1")
	)
	(via
		(at 378.258832 -63.273432)
		(size 0.508)
		(drill 0.254)
		(layers "F.Cu" "B.Cu")
		(net "P12V_SSD13_PG_G1")
	)
	(segment
		(start 233.67746 15.064486)
		(end 233.8959 14.752574)
		(width 0.13462)
		(layer "B.Cu")
		(net "85_5INCH_BOTTOM_DN")
	)
	(segment
		(start 241.143282 14.7701)
		(end 242.100608 14.60119)
		(width 0.13462)
		(layer "B.Cu")
		(net "85_5INCH_BOTTOM_DN")
	)
	(segment
		(start 230.887524 22.264624)
		(end 231.236012 21.766276)
		(width 0.13462)
		(layer "B.Cu")
		(net "85_5INCH_BOTTOM_DN")
	)
	(segment
		(start 221.945962 22.01799)
		(end 222.443802 22.366224)
		(width 0.13462)
		(layer "B.Cu")
		(net "85_5INCH_BOTTOM_DN")
	)
	(segment
		(start 232.864406 22.305518)
		(end 233.3625 22.654514)
		(width 0.13462)
		(layer "B.Cu")
		(net "85_5INCH_BOTTOM_DN")
	)
	(segment
		(start 238.456724 21.625814)
		(end 237.302294 15.077948)
		(width 0.13462)
		(layer "B.Cu")
		(net "85_5INCH_BOTTOM_DN")
	)
	(segment
		(start 219.191078 15.088108)
		(end 219.40901 14.775688)
		(width 0.13462)
		(layer "B.Cu")
		(net "85_5INCH_BOTTOM_DN")
	)
	(segment
		(start 226.434396 15.076678)
		(end 226.652328 14.764766)
		(width 0.13462)
		(layer "B.Cu")
		(net "85_5INCH_BOTTOM_DN")
	)
	(segment
		(start 231.236012 21.766276)
		(end 230.05669 15.075408)
		(width 0.13462)
		(layer "B.Cu")
		(net "85_5INCH_BOTTOM_DN")
	)
	(segment
		(start 219.40901 14.775688)
		(end 220.365828 14.607032)
		(width 0.13462)
		(layer "B.Cu")
		(net "85_5INCH_BOTTOM_DN")
	)
	(segment
		(start 238.788956 14.816328)
		(end 240.056162 21.99513)
		(width 0.13462)
		(layer "B.Cu")
		(net "85_5INCH_BOTTOM_DN")
	)
	(segment
		(start 247.403874 18.278348)
		(end 247.595644 18.278348)
		(width 0.13462)
		(layer "B.Cu")
		(net "85_5INCH_BOTTOM_DN")
	)
	(segment
		(start 234.54233 22.446488)
		(end 234.890818 21.94814)
		(width 0.13462)
		(layer "B.Cu")
		(net "85_5INCH_BOTTOM_DN")
	)
	(segment
		(start 219.64015 17.637506)
		(end 219.191078 15.088108)
		(width 0.13462)
		(layer "B.Cu")
		(net "85_5INCH_BOTTOM_DN")
	)
	(segment
		(start 214.93607 18.172684)
		(end 218.25839 18.172684)
		(width 0.13462)
		(layer "B.Cu")
		(net "85_5INCH_BOTTOM_DN")
	)
	(segment
		(start 242.95608 17.903952)
		(end 243.267738 18.165572)
		(width 0.13462)
		(layer "B.Cu")
		(net "85_5INCH_BOTTOM_DN")
	)
	(segment
		(start 223.972374 21.660104)
		(end 222.813372 15.08506)
		(width 0.13462)
		(layer "B.Cu")
		(net "85_5INCH_BOTTOM_DN")
	)
	(segment
		(start 227.244402 22.147784)
		(end 227.593144 21.650198)
		(width 0.13462)
		(layer "B.Cu")
		(net "85_5INCH_BOTTOM_DN")
	)
	(segment
		(start 214.823294 18.28546)
		(end 214.93607 18.172684)
		(width 0.13462)
		(layer "B.Cu")
		(net "85_5INCH_BOTTOM_DN")
	)
	(segment
		(start 241.732562 22.135338)
		(end 242.08105 21.637244)
		(width 0.13462)
		(layer "B.Cu")
		(net "85_5INCH_BOTTOM_DN")
	)
	(segment
		(start 242.412266 14.819376)
		(end 242.95608 17.903952)
		(width 0.13462)
		(layer "B.Cu")
		(net "85_5INCH_BOTTOM_DN")
	)
	(segment
		(start 223.988376 14.604492)
		(end 224.29978 14.822678)
		(width 0.13462)
		(layer "B.Cu")
		(net "85_5INCH_BOTTOM_DN")
	)
	(segment
		(start 227.6094 14.59611)
		(end 227.920804 14.814296)
		(width 0.13462)
		(layer "B.Cu")
		(net "85_5INCH_BOTTOM_DN")
	)
	(segment
		(start 240.056162 21.99513)
		(end 240.552732 22.343364)
		(width 0.13462)
		(layer "B.Cu")
		(net "85_5INCH_BOTTOM_DN")
	)
	(segment
		(start 220.365828 14.607032)
		(end 220.677486 14.825218)
		(width 0.13462)
		(layer "B.Cu")
		(net "85_5INCH_BOTTOM_DN")
	)
	(segment
		(start 237.302294 15.077948)
		(end 237.520226 14.767306)
		(width 0.13462)
		(layer "B.Cu")
		(net "85_5INCH_BOTTOM_DN")
	)
	(segment
		(start 234.852972 14.58341)
		(end 235.164122 14.801596)
		(width 0.13462)
		(layer "B.Cu")
		(net "85_5INCH_BOTTOM_DN")
	)
	(segment
		(start 243.267738 18.165572)
		(end 247.291098 18.165572)
		(width 0.13462)
		(layer "B.Cu")
		(net "85_5INCH_BOTTOM_DN")
	)
	(segment
		(start 214.631524 18.28546)
		(end 214.823294 18.28546)
		(width 0.13462)
		(layer "B.Cu")
		(net "85_5INCH_BOTTOM_DN")
	)
	(segment
		(start 240.92535 15.08125)
		(end 241.143282 14.7701)
		(width 0.13462)
		(layer "B.Cu")
		(net "85_5INCH_BOTTOM_DN")
	)
	(segment
		(start 229.70744 22.47265)
		(end 230.887524 22.264624)
		(width 0.13462)
		(layer "B.Cu")
		(net "85_5INCH_BOTTOM_DN")
	)
	(segment
		(start 226.064572 22.356318)
		(end 227.244402 22.147784)
		(width 0.13462)
		(layer "B.Cu")
		(net "85_5INCH_BOTTOM_DN")
	)
	(segment
		(start 219.406724 17.9705)
		(end 219.64015 17.637506)
		(width 0.13462)
		(layer "B.Cu")
		(net "85_5INCH_BOTTOM_DN")
	)
	(segment
		(start 237.520226 14.767306)
		(end 238.477298 14.598142)
		(width 0.13462)
		(layer "B.Cu")
		(net "85_5INCH_BOTTOM_DN")
	)
	(segment
		(start 238.107982 22.1234)
		(end 238.456724 21.625814)
		(width 0.13462)
		(layer "B.Cu")
		(net "85_5INCH_BOTTOM_DN")
	)
	(segment
		(start 231.543352 14.812772)
		(end 232.864406 22.305518)
		(width 0.13462)
		(layer "B.Cu")
		(net "85_5INCH_BOTTOM_DN")
	)
	(segment
		(start 229.210616 22.124416)
		(end 229.70744 22.47265)
		(width 0.13462)
		(layer "B.Cu")
		(net "85_5INCH_BOTTOM_DN")
	)
	(segment
		(start 218.25839 18.172684)
		(end 219.406724 17.9705)
		(width 0.13462)
		(layer "B.Cu")
		(net "85_5INCH_BOTTOM_DN")
	)
	(segment
		(start 227.920804 14.814296)
		(end 229.210616 22.124416)
		(width 0.13462)
		(layer "B.Cu")
		(net "85_5INCH_BOTTOM_DN")
	)
	(segment
		(start 220.677486 14.825218)
		(end 221.945962 22.01799)
		(width 0.13462)
		(layer "B.Cu")
		(net "85_5INCH_BOTTOM_DN")
	)
	(segment
		(start 238.477298 14.598142)
		(end 238.788956 14.816328)
		(width 0.13462)
		(layer "B.Cu")
		(net "85_5INCH_BOTTOM_DN")
	)
	(segment
		(start 230.05669 15.075408)
		(end 230.27513 14.763496)
		(width 0.13462)
		(layer "B.Cu")
		(net "85_5INCH_BOTTOM_DN")
	)
	(segment
		(start 226.652328 14.764766)
		(end 227.6094 14.59611)
		(width 0.13462)
		(layer "B.Cu")
		(net "85_5INCH_BOTTOM_DN")
	)
	(segment
		(start 240.552732 22.343364)
		(end 241.732562 22.135338)
		(width 0.13462)
		(layer "B.Cu")
		(net "85_5INCH_BOTTOM_DN")
	)
	(segment
		(start 242.100608 14.60119)
		(end 242.412266 14.819376)
		(width 0.13462)
		(layer "B.Cu")
		(net "85_5INCH_BOTTOM_DN")
	)
	(segment
		(start 224.29978 14.822678)
		(end 225.56724 22.008338)
		(width 0.13462)
		(layer "B.Cu")
		(net "85_5INCH_BOTTOM_DN")
	)
	(segment
		(start 230.27513 14.763496)
		(end 231.232202 14.594586)
		(width 0.13462)
		(layer "B.Cu")
		(net "85_5INCH_BOTTOM_DN")
	)
	(segment
		(start 231.232202 14.594586)
		(end 231.543352 14.812772)
		(width 0.13462)
		(layer "B.Cu")
		(net "85_5INCH_BOTTOM_DN")
	)
	(segment
		(start 227.593144 21.650198)
		(end 226.434396 15.076678)
		(width 0.13462)
		(layer "B.Cu")
		(net "85_5INCH_BOTTOM_DN")
	)
	(segment
		(start 236.928152 22.33168)
		(end 238.107982 22.1234)
		(width 0.13462)
		(layer "B.Cu")
		(net "85_5INCH_BOTTOM_DN")
	)
	(segment
		(start 223.031304 14.773148)
		(end 223.988376 14.604492)
		(width 0.13462)
		(layer "B.Cu")
		(net "85_5INCH_BOTTOM_DN")
	)
	(segment
		(start 235.164122 14.801596)
		(end 236.429804 21.983192)
		(width 0.13462)
		(layer "B.Cu")
		(net "85_5INCH_BOTTOM_DN")
	)
	(segment
		(start 247.291098 18.165572)
		(end 247.403874 18.278348)
		(width 0.13462)
		(layer "B.Cu")
		(net "85_5INCH_BOTTOM_DN")
	)
	(segment
		(start 233.8959 14.752574)
		(end 234.852972 14.58341)
		(width 0.13462)
		(layer "B.Cu")
		(net "85_5INCH_BOTTOM_DN")
	)
	(segment
		(start 236.429804 21.983192)
		(end 236.928152 22.33168)
		(width 0.13462)
		(layer "B.Cu")
		(net "85_5INCH_BOTTOM_DN")
	)
	(segment
		(start 223.623632 22.15769)
		(end 223.972374 21.660104)
		(width 0.13462)
		(layer "B.Cu")
		(net "85_5INCH_BOTTOM_DN")
	)
	(segment
		(start 233.3625 22.654514)
		(end 234.54233 22.446488)
		(width 0.13462)
		(layer "B.Cu")
		(net "85_5INCH_BOTTOM_DN")
	)
	(segment
		(start 222.443802 22.366224)
		(end 223.623632 22.15769)
		(width 0.13462)
		(layer "B.Cu")
		(net "85_5INCH_BOTTOM_DN")
	)
	(segment
		(start 225.56724 22.008338)
		(end 226.064572 22.356318)
		(width 0.13462)
		(layer "B.Cu")
		(net "85_5INCH_BOTTOM_DN")
	)
	(segment
		(start 222.813372 15.08506)
		(end 223.031304 14.773148)
		(width 0.13462)
		(layer "B.Cu")
		(net "85_5INCH_BOTTOM_DN")
	)
	(segment
		(start 234.890818 21.94814)
		(end 233.67746 15.064486)
		(width 0.13462)
		(layer "B.Cu")
		(net "85_5INCH_BOTTOM_DN")
	)
	(segment
		(start 242.08105 21.637244)
		(end 240.92535 15.08125)
		(width 0.13462)
		(layer "B.Cu")
		(net "85_5INCH_BOTTOM_DN")
	)
	(segment
		(start 368.75339 -67.077844)
		(end 368.814604 -67.01663)
		(width 0.13208)
		(layer "F.Cu")
		(net "P12V_SSD12_CO_EN")
	)
	(segment
		(start 368.875564 -67.970146)
		(end 368.75339 -67.847972)
		(width 0.13208)
		(layer "F.Cu")
		(net "P12V_SSD12_CO_EN")
	)
	(segment
		(start 368.75339 -67.537584)
		(end 368.75339 -67.077844)
		(width 0.13208)
		(layer "F.Cu")
		(net "P12V_SSD12_CO_EN")
	)
	(segment
		(start 368.875564 -68.479162)
		(end 368.875564 -67.970146)
		(width 0.13208)
		(layer "F.Cu")
		(net "P12V_SSD12_CO_EN")
	)
	(segment
		(start 368.75339 -67.847972)
		(end 368.75339 -67.537584)
		(width 0.13208)
		(layer "F.Cu")
		(net "P12V_SSD12_CO_EN")
	)
	(segment
		(start 368.814604 -67.01663)
		(end 368.814604 -66.72199)
		(width 0.13208)
		(layer "F.Cu")
		(net "P12V_SSD12_CO_EN")
	)
	(via
		(at 368.75339 -67.537584)
		(size 0.508)
		(drill 0.254)
		(layers "F.Cu" "B.Cu")
		(net "P12V_SSD12_CO_EN")
	)
	(segment
		(start 127.947166 -113.155476)
		(end 127.366014 -113.155476)
		(width 0.13208)
		(layer "F.Cu")
		(net "P3V3_NIC2_PG_G2")
	)
	(segment
		(start 127.935228 -113.898426)
		(end 127.947166 -113.886488)
		(width 0.13208)
		(layer "F.Cu")
		(net "P3V3_NIC2_PG_G2")
	)
	(segment
		(start 127.366014 -113.155476)
		(end 127.185166 -113.336324)
		(width 0.13208)
		(layer "F.Cu")
		(net "P3V3_NIC2_PG_G2")
	)
	(segment
		(start 127.935228 -114.649504)
		(end 127.935228 -113.898426)
		(width 0.13208)
		(layer "F.Cu")
		(net "P3V3_NIC2_PG_G2")
	)
	(segment
		(start 127.947166 -113.886488)
		(end 127.947166 -113.155476)
		(width 0.13208)
		(layer "F.Cu")
		(net "P3V3_NIC2_PG_G2")
	)
	(segment
		(start 127.185166 -113.336324)
		(end 127.185166 -114.649504)
		(width 0.13208)
		(layer "F.Cu")
		(net "P3V3_NIC2_PG_G2")
	)
	(via
		(at 127.935228 -113.898426)
		(size 0.508)
		(drill 0.254)
		(layers "F.Cu" "B.Cu")
		(net "P3V3_NIC2_PG_G2")
	)
	(segment
		(start 273.940524 18.28546)
		(end 274.621498 18.467324)
		(width 0.13462)
		(layer "F.Cu")
		(net "85_5INCH_IN1_DN")
	)
	(segment
		(start 311.933844 18.278348)
		(end 311.25287 18.460212)
		(width 0.13462)
		(layer "F.Cu")
		(net "85_5INCH_IN1_DN")
	)
	(segment
		(start 284.688788 15.80515)
		(end 284.956504 15.423134)
		(width 0.1651)
		(layer "In5.Cu")
		(net "85_5INCH_IN1_DN")
	)
	(segment
		(start 292.974776 15.42161)
		(end 293.991538 15.242032)
		(width 0.1651)
		(layer "In5.Cu")
		(net "85_5INCH_IN1_DN")
	)
	(segment
		(start 297.704002 21.407882)
		(end 296.715688 15.80134)
		(width 0.1651)
		(layer "In5.Cu")
		(net "85_5INCH_IN1_DN")
	)
	(segment
		(start 280.014934 22.176486)
		(end 281.260804 21.956268)
		(width 0.1651)
		(layer "In5.Cu")
		(net "85_5INCH_IN1_DN")
	)
	(segment
		(start 290.364418 15.51051)
		(end 291.475922 21.815298)
		(width 0.1651)
		(layer "In5.Cu")
		(net "85_5INCH_IN1_DN")
	)
	(segment
		(start 289.291014 22.02307)
		(end 289.693096 21.449538)
		(width 0.1651)
		(layer "In5.Cu")
		(net "85_5INCH_IN1_DN")
	)
	(segment
		(start 305.001422 15.419324)
		(end 306.01793 15.239746)
		(width 0.1651)
		(layer "In5.Cu")
		(net "85_5INCH_IN1_DN")
	)
	(segment
		(start 285.274004 21.97862)
		(end 285.676086 21.405088)
		(width 0.1651)
		(layer "In5.Cu")
		(net "85_5INCH_IN1_DN")
	)
	(segment
		(start 300.064424 22.197568)
		(end 301.310294 21.97735)
		(width 0.1651)
		(layer "In5.Cu")
		(net "85_5INCH_IN1_DN")
	)
	(segment
		(start 279.441148 21.774404)
		(end 280.014934 22.176486)
		(width 0.1651)
		(layer "In5.Cu")
		(net "85_5INCH_IN1_DN")
	)
	(segment
		(start 280.94813 15.428214)
		(end 281.965146 15.248636)
		(width 0.1651)
		(layer "In5.Cu")
		(net "85_5INCH_IN1_DN")
	)
	(segment
		(start 296.715688 15.80134)
		(end 296.983404 15.419324)
		(width 0.1651)
		(layer "In5.Cu")
		(net "85_5INCH_IN1_DN")
	)
	(segment
		(start 283.454348 21.796756)
		(end 284.028134 22.198838)
		(width 0.1651)
		(layer "In5.Cu")
		(net "85_5INCH_IN1_DN")
	)
	(segment
		(start 304.733706 15.80134)
		(end 305.001422 15.419324)
		(width 0.1651)
		(layer "In5.Cu")
		(net "85_5INCH_IN1_DN")
	)
	(segment
		(start 274.621498 18.467324)
		(end 274.912328 18.176494)
		(width 0.1651)
		(layer "In5.Cu")
		(net "85_5INCH_IN1_DN")
	)
	(segment
		(start 293.991538 15.242032)
		(end 294.373554 15.509748)
		(width 0.1651)
		(layer "In5.Cu")
		(net "85_5INCH_IN1_DN")
	)
	(segment
		(start 288.697924 15.804388)
		(end 288.96564 15.422372)
		(width 0.1651)
		(layer "In5.Cu")
		(net "85_5INCH_IN1_DN")
	)
	(segment
		(start 288.96564 15.422372)
		(end 289.982402 15.242794)
		(width 0.1651)
		(layer "In5.Cu")
		(net "85_5INCH_IN1_DN")
	)
	(segment
		(start 285.676086 21.405088)
		(end 284.688788 15.80515)
		(width 0.1651)
		(layer "In5.Cu")
		(net "85_5INCH_IN1_DN")
	)
	(segment
		(start 295.482518 21.799804)
		(end 296.05605 22.201886)
		(width 0.1651)
		(layer "In5.Cu")
		(net "85_5INCH_IN1_DN")
	)
	(segment
		(start 291.475922 21.815298)
		(end 292.049708 22.21738)
		(width 0.1651)
		(layer "In5.Cu")
		(net "85_5INCH_IN1_DN")
	)
	(segment
		(start 281.260804 21.956268)
		(end 281.662886 21.382736)
		(width 0.1651)
		(layer "In5.Cu")
		(net "85_5INCH_IN1_DN")
	)
	(segment
		(start 287.471358 21.841206)
		(end 288.045144 22.243288)
		(width 0.1651)
		(layer "In5.Cu")
		(net "85_5INCH_IN1_DN")
	)
	(segment
		(start 298.382182 15.507462)
		(end 299.490892 21.795486)
		(width 0.1651)
		(layer "In5.Cu")
		(net "85_5INCH_IN1_DN")
	)
	(segment
		(start 310.96204 18.169382)
		(end 311.25287 18.460212)
		(width 0.1651)
		(layer "In5.Cu")
		(net "85_5INCH_IN1_DN")
	)
	(segment
		(start 305.724306 21.419058)
		(end 304.733706 15.80134)
		(width 0.1651)
		(layer "In5.Cu")
		(net "85_5INCH_IN1_DN")
	)
	(segment
		(start 307.272436 18.169382)
		(end 310.96204 18.169382)
		(width 0.1651)
		(layer "In5.Cu")
		(net "85_5INCH_IN1_DN")
	)
	(segment
		(start 293.295578 21.997162)
		(end 293.69766 21.423376)
		(width 0.1651)
		(layer "In5.Cu")
		(net "85_5INCH_IN1_DN")
	)
	(segment
		(start 288.045144 22.243288)
		(end 289.291014 22.02307)
		(width 0.1651)
		(layer "In5.Cu")
		(net "85_5INCH_IN1_DN")
	)
	(segment
		(start 274.912328 18.176494)
		(end 278.689308 18.176494)
		(width 0.1651)
		(layer "In5.Cu")
		(net "85_5INCH_IN1_DN")
	)
	(segment
		(start 281.965146 15.248636)
		(end 282.347162 15.516606)
		(width 0.1651)
		(layer "In5.Cu")
		(net "85_5INCH_IN1_DN")
	)
	(segment
		(start 280.680414 15.81023)
		(end 280.94813 15.428214)
		(width 0.1651)
		(layer "In5.Cu")
		(net "85_5INCH_IN1_DN")
	)
	(segment
		(start 292.70706 15.803626)
		(end 292.974776 15.42161)
		(width 0.1651)
		(layer "In5.Cu")
		(net "85_5INCH_IN1_DN")
	)
	(segment
		(start 297.30192 21.981668)
		(end 297.704002 21.407882)
		(width 0.1651)
		(layer "In5.Cu")
		(net "85_5INCH_IN1_DN")
	)
	(segment
		(start 302.39208 15.511526)
		(end 303.502568 21.810726)
		(width 0.1651)
		(layer "In5.Cu")
		(net "85_5INCH_IN1_DN")
	)
	(segment
		(start 282.347162 15.516606)
		(end 283.454348 21.796756)
		(width 0.1651)
		(layer "In5.Cu")
		(net "85_5INCH_IN1_DN")
	)
	(segment
		(start 293.69766 21.423376)
		(end 292.70706 15.803626)
		(width 0.1651)
		(layer "In5.Cu")
		(net "85_5INCH_IN1_DN")
	)
	(segment
		(start 284.028134 22.198838)
		(end 285.274004 21.97862)
		(width 0.1651)
		(layer "In5.Cu")
		(net "85_5INCH_IN1_DN")
	)
	(segment
		(start 284.956504 15.423134)
		(end 285.973266 15.243556)
		(width 0.1651)
		(layer "In5.Cu")
		(net "85_5INCH_IN1_DN")
	)
	(segment
		(start 306.813204 17.847564)
		(end 307.272436 18.169382)
		(width 0.1651)
		(layer "In5.Cu")
		(net "85_5INCH_IN1_DN")
	)
	(segment
		(start 296.983404 15.419324)
		(end 298.000166 15.239746)
		(width 0.1651)
		(layer "In5.Cu")
		(net "85_5INCH_IN1_DN")
	)
	(segment
		(start 306.01793 15.239746)
		(end 306.400454 15.50797)
		(width 0.1651)
		(layer "In5.Cu")
		(net "85_5INCH_IN1_DN")
	)
	(segment
		(start 303.502568 21.810726)
		(end 304.076354 22.212808)
		(width 0.1651)
		(layer "In5.Cu")
		(net "85_5INCH_IN1_DN")
	)
	(segment
		(start 289.693096 21.449538)
		(end 288.697924 15.804388)
		(width 0.1651)
		(layer "In5.Cu")
		(net "85_5INCH_IN1_DN")
	)
	(segment
		(start 294.373554 15.509748)
		(end 295.482518 21.799804)
		(width 0.1651)
		(layer "In5.Cu")
		(net "85_5INCH_IN1_DN")
	)
	(segment
		(start 296.05605 22.201886)
		(end 297.30192 21.981668)
		(width 0.1651)
		(layer "In5.Cu")
		(net "85_5INCH_IN1_DN")
	)
	(segment
		(start 305.322224 21.99259)
		(end 305.724306 21.419058)
		(width 0.1651)
		(layer "In5.Cu")
		(net "85_5INCH_IN1_DN")
	)
	(segment
		(start 286.355282 15.511272)
		(end 287.471358 21.841206)
		(width 0.1651)
		(layer "In5.Cu")
		(net "85_5INCH_IN1_DN")
	)
	(segment
		(start 299.490892 21.795486)
		(end 300.064424 22.197568)
		(width 0.1651)
		(layer "In5.Cu")
		(net "85_5INCH_IN1_DN")
	)
	(segment
		(start 302.009556 15.243556)
		(end 302.39208 15.511526)
		(width 0.1651)
		(layer "In5.Cu")
		(net "85_5INCH_IN1_DN")
	)
	(segment
		(start 278.82723 18.292064)
		(end 279.441148 21.774404)
		(width 0.1651)
		(layer "In5.Cu")
		(net "85_5INCH_IN1_DN")
	)
	(segment
		(start 300.725078 15.80515)
		(end 300.992794 15.423134)
		(width 0.1651)
		(layer "In5.Cu")
		(net "85_5INCH_IN1_DN")
	)
	(segment
		(start 278.689308 18.176494)
		(end 278.82723 18.292064)
		(width 0.1651)
		(layer "In5.Cu")
		(net "85_5INCH_IN1_DN")
	)
	(segment
		(start 289.982402 15.242794)
		(end 290.364418 15.51051)
		(width 0.1651)
		(layer "In5.Cu")
		(net "85_5INCH_IN1_DN")
	)
	(segment
		(start 301.71263 21.403564)
		(end 300.725078 15.80515)
		(width 0.1651)
		(layer "In5.Cu")
		(net "85_5INCH_IN1_DN")
	)
	(segment
		(start 301.310294 21.97735)
		(end 301.71263 21.403564)
		(width 0.1651)
		(layer "In5.Cu")
		(net "85_5INCH_IN1_DN")
	)
	(segment
		(start 304.076354 22.212808)
		(end 305.322224 21.99259)
		(width 0.1651)
		(layer "In5.Cu")
		(net "85_5INCH_IN1_DN")
	)
	(segment
		(start 292.049708 22.21738)
		(end 293.295578 21.997162)
		(width 0.1651)
		(layer "In5.Cu")
		(net "85_5INCH_IN1_DN")
	)
	(segment
		(start 298.000166 15.239746)
		(end 298.382182 15.507462)
		(width 0.1651)
		(layer "In5.Cu")
		(net "85_5INCH_IN1_DN")
	)
	(segment
		(start 285.973266 15.243556)
		(end 286.355282 15.511272)
		(width 0.1651)
		(layer "In5.Cu")
		(net "85_5INCH_IN1_DN")
	)
	(segment
		(start 300.992794 15.423134)
		(end 302.009556 15.243556)
		(width 0.1651)
		(layer "In5.Cu")
		(net "85_5INCH_IN1_DN")
	)
	(segment
		(start 306.400454 15.50797)
		(end 306.813204 17.847564)
		(width 0.1651)
		(layer "In5.Cu")
		(net "85_5INCH_IN1_DN")
	)
	(segment
		(start 281.662886 21.382736)
		(end 280.680414 15.81023)
		(width 0.1651)
		(layer "In5.Cu")
		(net "85_5INCH_IN1_DN")
	)
	(segment
		(start 403.734524 17.785588)
		(end 404.415498 17.603724)
		(width 0.13462)
		(layer "F.Cu")
		(net "85_5INCH_IN3_DN")
	)
	(segment
		(start 441.727844 17.778476)
		(end 441.04687 17.596612)
		(width 0.13462)
		(layer "F.Cu")
		(net "85_5INCH_IN3_DN")
	)
	(segment
		(start 404.706328 17.894554)
		(end 408.585924 17.894554)
		(width 0.1651)
		(layer "In9.Cu")
		(net "85_5INCH_IN3_DN")
	)
	(segment
		(start 409.874974 21.87829)
		(end 410.89072 21.698712)
		(width 0.1651)
		(layer "In9.Cu")
		(net "85_5INCH_IN3_DN")
	)
	(segment
		(start 423.193464 21.357082)
		(end 422.202864 15.737332)
		(width 0.1651)
		(layer "In9.Cu")
		(net "85_5INCH_IN3_DN")
	)
	(segment
		(start 410.89072 21.698712)
		(end 411.15869 21.316442)
		(width 0.1651)
		(layer "In9.Cu")
		(net "85_5INCH_IN3_DN")
	)
	(segment
		(start 411.15869 21.316442)
		(end 410.176218 15.743936)
		(width 0.1651)
		(layer "In9.Cu")
		(net "85_5INCH_IN3_DN")
	)
	(segment
		(start 435.22011 21.352764)
		(end 434.22951 15.735046)
		(width 0.1651)
		(layer "In9.Cu")
		(net "85_5INCH_IN3_DN")
	)
	(segment
		(start 426.211492 15.735046)
		(end 426.61332 15.161768)
		(width 0.1651)
		(layer "In9.Cu")
		(net "85_5INCH_IN3_DN")
	)
	(segment
		(start 423.851578 14.943836)
		(end 424.42511 15.345664)
		(width 0.1651)
		(layer "In9.Cu")
		(net "85_5INCH_IN3_DN")
	)
	(segment
		(start 425.534074 21.63572)
		(end 425.91609 21.90369)
		(width 0.1651)
		(layer "In9.Cu")
		(net "85_5INCH_IN3_DN")
	)
	(segment
		(start 416.406838 15.347188)
		(end 417.522914 21.677122)
		(width 0.1651)
		(layer "In9.Cu")
		(net "85_5INCH_IN3_DN")
	)
	(segment
		(start 440.75604 17.887442)
		(end 441.04687 17.596612)
		(width 0.1651)
		(layer "In9.Cu")
		(net "85_5INCH_IN3_DN")
	)
	(segment
		(start 420.415974 15.346426)
		(end 421.527478 21.651214)
		(width 0.1651)
		(layer "In9.Cu")
		(net "85_5INCH_IN3_DN")
	)
	(segment
		(start 422.925494 21.739606)
		(end 423.193464 21.357082)
		(width 0.1651)
		(layer "In9.Cu")
		(net "85_5INCH_IN3_DN")
	)
	(segment
		(start 436.86476 17.68348)
		(end 437.15559 17.887442)
		(width 0.1651)
		(layer "In9.Cu")
		(net "85_5INCH_IN3_DN")
	)
	(segment
		(start 422.604692 15.164054)
		(end 423.851578 14.943836)
		(width 0.1651)
		(layer "In9.Cu")
		(net "85_5INCH_IN3_DN")
	)
	(segment
		(start 417.905184 21.945092)
		(end 418.92093 21.765514)
		(width 0.1651)
		(layer "In9.Cu")
		(net "85_5INCH_IN3_DN")
	)
	(segment
		(start 424.42511 15.345664)
		(end 425.534074 21.63572)
		(width 0.1651)
		(layer "In9.Cu")
		(net "85_5INCH_IN3_DN")
	)
	(segment
		(start 427.199806 21.341588)
		(end 426.211492 15.735046)
		(width 0.1651)
		(layer "In9.Cu")
		(net "85_5INCH_IN3_DN")
	)
	(segment
		(start 428.433738 15.343378)
		(end 429.542448 21.631402)
		(width 0.1651)
		(layer "In9.Cu")
		(net "85_5INCH_IN3_DN")
	)
	(segment
		(start 434.631338 15.161768)
		(end 435.878224 14.94155)
		(width 0.1651)
		(layer "In9.Cu")
		(net "85_5INCH_IN3_DN")
	)
	(segment
		(start 408.881072 18.14195)
		(end 409.492704 21.61032)
		(width 0.1651)
		(layer "In9.Cu")
		(net "85_5INCH_IN3_DN")
	)
	(segment
		(start 414.184592 15.738856)
		(end 414.58642 15.165578)
		(width 0.1651)
		(layer "In9.Cu")
		(net "85_5INCH_IN3_DN")
	)
	(segment
		(start 411.82544 14.95044)
		(end 412.398718 15.352522)
		(width 0.1651)
		(layer "In9.Cu")
		(net "85_5INCH_IN3_DN")
	)
	(segment
		(start 404.415498 17.603724)
		(end 404.706328 17.894554)
		(width 0.1651)
		(layer "In9.Cu")
		(net "85_5INCH_IN3_DN")
	)
	(segment
		(start 433.936394 21.914612)
		(end 434.95214 21.735034)
		(width 0.1651)
		(layer "In9.Cu")
		(net "85_5INCH_IN3_DN")
	)
	(segment
		(start 408.585924 17.894554)
		(end 408.881072 18.14195)
		(width 0.1651)
		(layer "In9.Cu")
		(net "85_5INCH_IN3_DN")
	)
	(segment
		(start 427.860206 14.94155)
		(end 428.433738 15.343378)
		(width 0.1651)
		(layer "In9.Cu")
		(net "85_5INCH_IN3_DN")
	)
	(segment
		(start 433.554124 21.646642)
		(end 433.936394 21.914612)
		(width 0.1651)
		(layer "In9.Cu")
		(net "85_5INCH_IN3_DN")
	)
	(segment
		(start 410.578046 15.170658)
		(end 411.82544 14.95044)
		(width 0.1651)
		(layer "In9.Cu")
		(net "85_5INCH_IN3_DN")
	)
	(segment
		(start 415.833306 14.94536)
		(end 416.406838 15.347188)
		(width 0.1651)
		(layer "In9.Cu")
		(net "85_5INCH_IN3_DN")
	)
	(segment
		(start 418.595556 15.164816)
		(end 419.842442 14.944598)
		(width 0.1651)
		(layer "In9.Cu")
		(net "85_5INCH_IN3_DN")
	)
	(segment
		(start 431.869596 14.94536)
		(end 432.443636 15.347442)
		(width 0.1651)
		(layer "In9.Cu")
		(net "85_5INCH_IN3_DN")
	)
	(segment
		(start 413.505904 21.632672)
		(end 413.888174 21.900642)
		(width 0.1651)
		(layer "In9.Cu")
		(net "85_5INCH_IN3_DN")
	)
	(segment
		(start 426.61332 15.161768)
		(end 427.860206 14.94155)
		(width 0.1651)
		(layer "In9.Cu")
		(net "85_5INCH_IN3_DN")
	)
	(segment
		(start 436.45201 15.343886)
		(end 436.86476 17.68348)
		(width 0.1651)
		(layer "In9.Cu")
		(net "85_5INCH_IN3_DN")
	)
	(segment
		(start 419.842442 14.944598)
		(end 420.415974 15.346426)
		(width 0.1651)
		(layer "In9.Cu")
		(net "85_5INCH_IN3_DN")
	)
	(segment
		(start 410.176218 15.743936)
		(end 410.578046 15.170658)
		(width 0.1651)
		(layer "In9.Cu")
		(net "85_5INCH_IN3_DN")
	)
	(segment
		(start 418.92093 21.765514)
		(end 419.1889 21.383244)
		(width 0.1651)
		(layer "In9.Cu")
		(net "85_5INCH_IN3_DN")
	)
	(segment
		(start 430.220882 15.73911)
		(end 430.62271 15.165578)
		(width 0.1651)
		(layer "In9.Cu")
		(net "85_5INCH_IN3_DN")
	)
	(segment
		(start 426.931836 21.724112)
		(end 427.199806 21.341588)
		(width 0.1651)
		(layer "In9.Cu")
		(net "85_5INCH_IN3_DN")
	)
	(segment
		(start 413.888174 21.900642)
		(end 414.90392 21.721064)
		(width 0.1651)
		(layer "In9.Cu")
		(net "85_5INCH_IN3_DN")
	)
	(segment
		(start 414.90392 21.721064)
		(end 415.17189 21.338794)
		(width 0.1651)
		(layer "In9.Cu")
		(net "85_5INCH_IN3_DN")
	)
	(segment
		(start 429.924464 21.899372)
		(end 430.94021 21.719794)
		(width 0.1651)
		(layer "In9.Cu")
		(net "85_5INCH_IN3_DN")
	)
	(segment
		(start 417.522914 21.677122)
		(end 417.905184 21.945092)
		(width 0.1651)
		(layer "In9.Cu")
		(net "85_5INCH_IN3_DN")
	)
	(segment
		(start 418.193728 15.738094)
		(end 418.595556 15.164816)
		(width 0.1651)
		(layer "In9.Cu")
		(net "85_5INCH_IN3_DN")
	)
	(segment
		(start 409.492704 21.61032)
		(end 409.874974 21.87829)
		(width 0.1651)
		(layer "In9.Cu")
		(net "85_5INCH_IN3_DN")
	)
	(segment
		(start 429.542448 21.631402)
		(end 429.924464 21.899372)
		(width 0.1651)
		(layer "In9.Cu")
		(net "85_5INCH_IN3_DN")
	)
	(segment
		(start 412.398718 15.352522)
		(end 413.505904 21.632672)
		(width 0.1651)
		(layer "In9.Cu")
		(net "85_5INCH_IN3_DN")
	)
	(segment
		(start 431.208434 21.33727)
		(end 430.220882 15.73911)
		(width 0.1651)
		(layer "In9.Cu")
		(net "85_5INCH_IN3_DN")
	)
	(segment
		(start 434.95214 21.735034)
		(end 435.22011 21.352764)
		(width 0.1651)
		(layer "In9.Cu")
		(net "85_5INCH_IN3_DN")
	)
	(segment
		(start 419.1889 21.383244)
		(end 418.193728 15.738094)
		(width 0.1651)
		(layer "In9.Cu")
		(net "85_5INCH_IN3_DN")
	)
	(segment
		(start 432.443636 15.347442)
		(end 433.554124 21.646642)
		(width 0.1651)
		(layer "In9.Cu")
		(net "85_5INCH_IN3_DN")
	)
	(segment
		(start 425.91609 21.90369)
		(end 426.931836 21.724112)
		(width 0.1651)
		(layer "In9.Cu")
		(net "85_5INCH_IN3_DN")
	)
	(segment
		(start 437.15559 17.887442)
		(end 440.75604 17.887442)
		(width 0.1651)
		(layer "In9.Cu")
		(net "85_5INCH_IN3_DN")
	)
	(segment
		(start 422.202864 15.737332)
		(end 422.604692 15.164054)
		(width 0.1651)
		(layer "In9.Cu")
		(net "85_5INCH_IN3_DN")
	)
	(segment
		(start 421.909748 21.919184)
		(end 422.925494 21.739606)
		(width 0.1651)
		(layer "In9.Cu")
		(net "85_5INCH_IN3_DN")
	)
	(segment
		(start 430.62271 15.165578)
		(end 431.869596 14.94536)
		(width 0.1651)
		(layer "In9.Cu")
		(net "85_5INCH_IN3_DN")
	)
	(segment
		(start 415.17189 21.338794)
		(end 414.184592 15.738856)
		(width 0.1651)
		(layer "In9.Cu")
		(net "85_5INCH_IN3_DN")
	)
	(segment
		(start 414.58642 15.165578)
		(end 415.833306 14.94536)
		(width 0.1651)
		(layer "In9.Cu")
		(net "85_5INCH_IN3_DN")
	)
	(segment
		(start 421.527478 21.651214)
		(end 421.909748 21.919184)
		(width 0.1651)
		(layer "In9.Cu")
		(net "85_5INCH_IN3_DN")
	)
	(segment
		(start 430.94021 21.719794)
		(end 431.208434 21.33727)
		(width 0.1651)
		(layer "In9.Cu")
		(net "85_5INCH_IN3_DN")
	)
	(segment
		(start 434.22951 15.735046)
		(end 434.631338 15.161768)
		(width 0.1651)
		(layer "In9.Cu")
		(net "85_5INCH_IN3_DN")
	)
	(segment
		(start 435.878224 14.94155)
		(end 436.45201 15.343886)
		(width 0.1651)
		(layer "In9.Cu")
		(net "85_5INCH_IN3_DN")
	)
	(segment
		(start 404.189692 -63.273432)
		(end 404.002494 -63.086234)
		(width 0.13208)
		(layer "F.Cu")
		(net "P12V_SSD14_PG_G1")
	)
	(segment
		(start 404.002494 -63.086234)
		(end 403.575266 -63.086234)
		(width 0.13208)
		(layer "F.Cu")
		(net "P12V_SSD14_PG_G1")
	)
	(segment
		(start 403.575266 -64.102234)
		(end 403.575266 -63.086234)
		(width 0.13208)
		(layer "F.Cu")
		(net "P12V_SSD14_PG_G1")
	)
	(segment
		(start 404.547578 -63.56223)
		(end 404.25878 -63.273432)
		(width 0.13208)
		(layer "F.Cu")
		(net "P12V_SSD14_PG_G1")
	)
	(segment
		(start 404.25878 -63.273432)
		(end 404.189692 -63.273432)
		(width 0.13208)
		(layer "F.Cu")
		(net "P12V_SSD14_PG_G1")
	)
	(segment
		(start 404.989538 -63.56223)
		(end 404.547578 -63.56223)
		(width 0.13208)
		(layer "F.Cu")
		(net "P12V_SSD14_PG_G1")
	)
	(via
		(at 404.25878 -63.273432)
		(size 0.508)
		(drill 0.254)
		(layers "F.Cu" "B.Cu")
		(net "P12V_SSD14_PG_G1")
	)
	(segment
		(start 401.194524 10.93978)
		(end 401.875498 11.121644)
		(width 0.13462)
		(layer "B.Cu")
		(net "85_10INCH_IN5_DP")
	)
	(segment
		(start 458.328268 10.965688)
		(end 457.647294 11.147552)
		(width 0.13462)
		(layer "B.Cu")
		(net "85_10INCH_IN5_DP")
	)
	(segment
		(start 425.103798 6.565392)
		(end 426.533818 14.675866)
		(width 0.1651)
		(layer "In13.Cu")
		(net "85_10INCH_IN5_DP")
	)
	(segment
		(start 406.475692 14.604746)
		(end 407.049224 15.006828)
		(width 0.1651)
		(layer "In13.Cu")
		(net "85_10INCH_IN5_DP")
	)
	(segment
		(start 428.353474 14.85773)
		(end 428.755556 14.284198)
		(width 0.1651)
		(layer "In13.Cu")
		(net "85_10INCH_IN5_DP")
	)
	(segment
		(start 439.47334 6.854698)
		(end 439.741056 6.472682)
		(width 0.1651)
		(layer "In13.Cu")
		(net "85_10INCH_IN5_DP")
	)
	(segment
		(start 432.366674 14.880082)
		(end 432.768756 14.30655)
		(width 0.1651)
		(layer "In13.Cu")
		(net "85_10INCH_IN5_DP")
	)
	(segment
		(start 408.685492 6.2992)
		(end 409.067508 6.566916)
		(width 0.1651)
		(layer "In13.Cu")
		(net "85_10INCH_IN5_DP")
	)
	(segment
		(start 402.166328 10.830814)
		(end 405.404828 10.830814)
		(width 0.1651)
		(layer "In13.Cu")
		(net "85_10INCH_IN5_DP")
	)
	(segment
		(start 422.528492 14.696948)
		(end 423.102278 15.09903)
		(width 0.1651)
		(layer "In13.Cu")
		(net "85_10INCH_IN5_DP")
	)
	(segment
		(start 405.404828 10.830814)
		(end 405.896572 11.322558)
		(width 0.1651)
		(layer "In13.Cu")
		(net "85_10INCH_IN5_DP")
	)
	(segment
		(start 411.410658 6.86435)
		(end 411.678374 6.482334)
		(width 0.1651)
		(layer "In13.Cu")
		(net "85_10INCH_IN5_DP")
	)
	(segment
		(start 415.089594 15.131288)
		(end 416.335464 14.91107)
		(width 0.1651)
		(layer "In13.Cu")
		(net "85_10INCH_IN5_DP")
	)
	(segment
		(start 421.095678 6.570218)
		(end 422.528492 14.696948)
		(width 0.1651)
		(layer "In13.Cu")
		(net "85_10INCH_IN5_DP")
	)
	(segment
		(start 423.437304 6.85927)
		(end 423.70502 6.477254)
		(width 0.1651)
		(layer "In13.Cu")
		(net "85_10INCH_IN5_DP")
	)
	(segment
		(start 419.6969 6.48208)
		(end 420.713662 6.302502)
		(width 0.1651)
		(layer "In13.Cu")
		(net "85_10INCH_IN5_DP")
	)
	(segment
		(start 451.506336 6.88721)
		(end 451.774052 6.505194)
		(width 0.1651)
		(layer "In13.Cu")
		(net "85_10INCH_IN5_DP")
	)
	(segment
		(start 414.516062 14.729206)
		(end 415.089594 15.131288)
		(width 0.1651)
		(layer "In13.Cu")
		(net "85_10INCH_IN5_DP")
	)
	(segment
		(start 452.410576 14.869414)
		(end 452.812658 14.295882)
		(width 0.1651)
		(layer "In13.Cu")
		(net "85_10INCH_IN5_DP")
	)
	(segment
		(start 446.57899 14.67231)
		(end 447.152776 15.074392)
		(width 0.1651)
		(layer "In13.Cu")
		(net "85_10INCH_IN5_DP")
	)
	(segment
		(start 430.547018 14.698218)
		(end 431.120804 15.1003)
		(width 0.1651)
		(layer "In13.Cu")
		(net "85_10INCH_IN5_DP")
	)
	(segment
		(start 447.760852 6.484366)
		(end 448.777614 6.304788)
		(width 0.1651)
		(layer "In13.Cu")
		(net "85_10INCH_IN5_DP")
	)
	(segment
		(start 436.785766 14.351)
		(end 435.46649 6.868414)
		(width 0.1651)
		(layer "In13.Cu")
		(net "85_10INCH_IN5_DP")
	)
	(segment
		(start 441.139834 6.56082)
		(end 442.572902 14.68882)
		(width 0.1651)
		(layer "In13.Cu")
		(net "85_10INCH_IN5_DP")
	)
	(segment
		(start 445.149732 6.565646)
		(end 446.57899 14.67231)
		(width 0.1651)
		(layer "In13.Cu")
		(net "85_10INCH_IN5_DP")
	)
	(segment
		(start 444.767716 6.29793)
		(end 445.149732 6.565646)
		(width 0.1651)
		(layer "In13.Cu")
		(net "85_10INCH_IN5_DP")
	)
	(segment
		(start 453.868028 10.534904)
		(end 454.32726 10.856722)
		(width 0.1651)
		(layer "In13.Cu")
		(net "85_10INCH_IN5_DP")
	)
	(segment
		(start 412.695136 6.302756)
		(end 413.077152 6.570472)
		(width 0.1651)
		(layer "In13.Cu")
		(net "85_10INCH_IN5_DP")
	)
	(segment
		(start 432.768756 14.30655)
		(end 431.458116 6.873748)
		(width 0.1651)
		(layer "In13.Cu")
		(net "85_10INCH_IN5_DP")
	)
	(segment
		(start 432.742594 6.312154)
		(end 433.124864 6.57987)
		(width 0.1651)
		(layer "In13.Cu")
		(net "85_10INCH_IN5_DP")
	)
	(segment
		(start 405.896572 11.322558)
		(end 406.475692 14.604746)
		(width 0.1651)
		(layer "In13.Cu")
		(net "85_10INCH_IN5_DP")
	)
	(segment
		(start 440.79033 14.325092)
		(end 439.47334 6.854698)
		(width 0.1651)
		(layer "In13.Cu")
		(net "85_10INCH_IN5_DP")
	)
	(segment
		(start 433.124864 6.57987)
		(end 434.564028 14.742668)
		(width 0.1651)
		(layer "In13.Cu")
		(net "85_10INCH_IN5_DP")
	)
	(segment
		(start 428.755556 14.284198)
		(end 427.44771 6.867144)
		(width 0.1651)
		(layer "In13.Cu")
		(net "85_10INCH_IN5_DP")
	)
	(segment
		(start 427.107604 15.077948)
		(end 428.353474 14.85773)
		(width 0.1651)
		(layer "In13.Cu")
		(net "85_10INCH_IN5_DP")
	)
	(segment
		(start 407.66873 6.478778)
		(end 408.685492 6.2992)
		(width 0.1651)
		(layer "In13.Cu")
		(net "85_10INCH_IN5_DP")
	)
	(segment
		(start 434.564028 14.742668)
		(end 435.137814 15.14475)
		(width 0.1651)
		(layer "In13.Cu")
		(net "85_10INCH_IN5_DP")
	)
	(segment
		(start 435.46649 6.868414)
		(end 435.734206 6.486398)
		(width 0.1651)
		(layer "In13.Cu")
		(net "85_10INCH_IN5_DP")
	)
	(segment
		(start 454.32726 10.856722)
		(end 457.356464 10.856722)
		(width 0.1651)
		(layer "In13.Cu")
		(net "85_10INCH_IN5_DP")
	)
	(segment
		(start 444.79464 14.297152)
		(end 443.483238 6.859524)
		(width 0.1651)
		(layer "In13.Cu")
		(net "85_10INCH_IN5_DP")
	)
	(segment
		(start 423.70502 6.477254)
		(end 424.721782 6.297676)
		(width 0.1651)
		(layer "In13.Cu")
		(net "85_10INCH_IN5_DP")
	)
	(segment
		(start 450.59092 14.68755)
		(end 451.164706 15.089632)
		(width 0.1651)
		(layer "In13.Cu")
		(net "85_10INCH_IN5_DP")
	)
	(segment
		(start 438.568592 14.71676)
		(end 439.142378 15.118842)
		(width 0.1651)
		(layer "In13.Cu")
		(net "85_10INCH_IN5_DP")
	)
	(segment
		(start 407.401014 6.860794)
		(end 407.66873 6.478778)
		(width 0.1651)
		(layer "In13.Cu")
		(net "85_10INCH_IN5_DP")
	)
	(segment
		(start 442.572902 14.68882)
		(end 443.146688 15.090902)
		(width 0.1651)
		(layer "In13.Cu")
		(net "85_10INCH_IN5_DP")
	)
	(segment
		(start 435.734206 6.486398)
		(end 436.750968 6.30682)
		(width 0.1651)
		(layer "In13.Cu")
		(net "85_10INCH_IN5_DP")
	)
	(segment
		(start 436.750968 6.30682)
		(end 437.132984 6.574536)
		(width 0.1651)
		(layer "In13.Cu")
		(net "85_10INCH_IN5_DP")
	)
	(segment
		(start 401.875498 11.121644)
		(end 402.166328 10.830814)
		(width 0.1651)
		(layer "In13.Cu")
		(net "85_10INCH_IN5_DP")
	)
	(segment
		(start 447.493136 6.866382)
		(end 447.760852 6.484366)
		(width 0.1651)
		(layer "In13.Cu")
		(net "85_10INCH_IN5_DP")
	)
	(segment
		(start 423.102278 15.09903)
		(end 424.348148 14.878812)
		(width 0.1651)
		(layer "In13.Cu")
		(net "85_10INCH_IN5_DP")
	)
	(segment
		(start 424.348148 14.878812)
		(end 424.75023 14.30528)
		(width 0.1651)
		(layer "In13.Cu")
		(net "85_10INCH_IN5_DP")
	)
	(segment
		(start 457.356464 10.856722)
		(end 457.647294 11.147552)
		(width 0.1651)
		(layer "In13.Cu")
		(net "85_10INCH_IN5_DP")
	)
	(segment
		(start 416.737546 14.337538)
		(end 415.421064 6.8707)
		(width 0.1651)
		(layer "In13.Cu")
		(net "85_10INCH_IN5_DP")
	)
	(segment
		(start 416.705542 6.309106)
		(end 417.087558 6.576822)
		(width 0.1651)
		(layer "In13.Cu")
		(net "85_10INCH_IN5_DP")
	)
	(segment
		(start 408.697176 14.212824)
		(end 407.401014 6.860794)
		(width 0.1651)
		(layer "In13.Cu")
		(net "85_10INCH_IN5_DP")
	)
	(segment
		(start 439.142378 15.118842)
		(end 440.388248 14.898624)
		(width 0.1651)
		(layer "In13.Cu")
		(net "85_10INCH_IN5_DP")
	)
	(segment
		(start 435.137814 15.14475)
		(end 436.383684 14.924532)
		(width 0.1651)
		(layer "In13.Cu")
		(net "85_10INCH_IN5_DP")
	)
	(segment
		(start 439.741056 6.472682)
		(end 440.757818 6.293104)
		(width 0.1651)
		(layer "In13.Cu")
		(net "85_10INCH_IN5_DP")
	)
	(segment
		(start 448.800982 14.280388)
		(end 447.493136 6.866382)
		(width 0.1651)
		(layer "In13.Cu")
		(net "85_10INCH_IN5_DP")
	)
	(segment
		(start 428.732188 6.30555)
		(end 429.114458 6.57352)
		(width 0.1651)
		(layer "In13.Cu")
		(net "85_10INCH_IN5_DP")
	)
	(segment
		(start 411.061916 15.027402)
		(end 412.307532 14.80693)
		(width 0.1651)
		(layer "In13.Cu")
		(net "85_10INCH_IN5_DP")
	)
	(segment
		(start 408.295094 14.78661)
		(end 408.697176 14.212824)
		(width 0.1651)
		(layer "In13.Cu")
		(net "85_10INCH_IN5_DP")
	)
	(segment
		(start 424.75023 14.30528)
		(end 423.437304 6.85927)
		(width 0.1651)
		(layer "In13.Cu")
		(net "85_10INCH_IN5_DP")
	)
	(segment
		(start 436.383684 14.924532)
		(end 436.785766 14.351)
		(width 0.1651)
		(layer "In13.Cu")
		(net "85_10INCH_IN5_DP")
	)
	(segment
		(start 443.750954 6.477508)
		(end 444.767716 6.29793)
		(width 0.1651)
		(layer "In13.Cu")
		(net "85_10INCH_IN5_DP")
	)
	(segment
		(start 449.160138 6.572758)
		(end 450.59092 14.68755)
		(width 0.1651)
		(layer "In13.Cu")
		(net "85_10INCH_IN5_DP")
	)
	(segment
		(start 453.173084 6.59384)
		(end 453.868028 10.534904)
		(width 0.1651)
		(layer "In13.Cu")
		(net "85_10INCH_IN5_DP")
	)
	(segment
		(start 412.709868 14.23289)
		(end 411.410658 6.86435)
		(width 0.1651)
		(layer "In13.Cu")
		(net "85_10INCH_IN5_DP")
	)
	(segment
		(start 412.307532 14.80693)
		(end 412.709868 14.23289)
		(width 0.1651)
		(layer "In13.Cu")
		(net "85_10INCH_IN5_DP")
	)
	(segment
		(start 411.678374 6.482334)
		(end 412.695136 6.302756)
		(width 0.1651)
		(layer "In13.Cu")
		(net "85_10INCH_IN5_DP")
	)
	(segment
		(start 407.049224 15.006828)
		(end 408.295094 14.78661)
		(width 0.1651)
		(layer "In13.Cu")
		(net "85_10INCH_IN5_DP")
	)
	(segment
		(start 448.777614 6.304788)
		(end 449.160138 6.572758)
		(width 0.1651)
		(layer "In13.Cu")
		(net "85_10INCH_IN5_DP")
	)
	(segment
		(start 419.101778 15.146528)
		(end 420.347648 14.92631)
		(width 0.1651)
		(layer "In13.Cu")
		(net "85_10INCH_IN5_DP")
	)
	(segment
		(start 409.067508 6.566916)
		(end 410.488638 14.625574)
		(width 0.1651)
		(layer "In13.Cu")
		(net "85_10INCH_IN5_DP")
	)
	(segment
		(start 420.713662 6.302502)
		(end 421.095678 6.570218)
		(width 0.1651)
		(layer "In13.Cu")
		(net "85_10INCH_IN5_DP")
	)
	(segment
		(start 424.721782 6.297676)
		(end 425.103798 6.565392)
		(width 0.1651)
		(layer "In13.Cu")
		(net "85_10INCH_IN5_DP")
	)
	(segment
		(start 415.68878 6.488684)
		(end 416.705542 6.309106)
		(width 0.1651)
		(layer "In13.Cu")
		(net "85_10INCH_IN5_DP")
	)
	(segment
		(start 451.774052 6.505194)
		(end 452.79056 6.325616)
		(width 0.1651)
		(layer "In13.Cu")
		(net "85_10INCH_IN5_DP")
	)
	(segment
		(start 448.398646 14.854174)
		(end 448.800982 14.280388)
		(width 0.1651)
		(layer "In13.Cu")
		(net "85_10INCH_IN5_DP")
	)
	(segment
		(start 420.74973 14.353286)
		(end 419.429184 6.864096)
		(width 0.1651)
		(layer "In13.Cu")
		(net "85_10INCH_IN5_DP")
	)
	(segment
		(start 418.527484 14.744446)
		(end 419.101778 15.146528)
		(width 0.1651)
		(layer "In13.Cu")
		(net "85_10INCH_IN5_DP")
	)
	(segment
		(start 410.488638 14.625574)
		(end 411.061916 15.027402)
		(width 0.1651)
		(layer "In13.Cu")
		(net "85_10INCH_IN5_DP")
	)
	(segment
		(start 444.392558 14.870684)
		(end 444.79464 14.297152)
		(width 0.1651)
		(layer "In13.Cu")
		(net "85_10INCH_IN5_DP")
	)
	(segment
		(start 431.120804 15.1003)
		(end 432.366674 14.880082)
		(width 0.1651)
		(layer "In13.Cu")
		(net "85_10INCH_IN5_DP")
	)
	(segment
		(start 416.335464 14.91107)
		(end 416.737546 14.337538)
		(width 0.1651)
		(layer "In13.Cu")
		(net "85_10INCH_IN5_DP")
	)
	(segment
		(start 451.164706 15.089632)
		(end 452.410576 14.869414)
		(width 0.1651)
		(layer "In13.Cu")
		(net "85_10INCH_IN5_DP")
	)
	(segment
		(start 440.388248 14.898624)
		(end 440.79033 14.325092)
		(width 0.1651)
		(layer "In13.Cu")
		(net "85_10INCH_IN5_DP")
	)
	(segment
		(start 431.458116 6.873748)
		(end 431.725832 6.491732)
		(width 0.1651)
		(layer "In13.Cu")
		(net "85_10INCH_IN5_DP")
	)
	(segment
		(start 431.725832 6.491732)
		(end 432.742594 6.312154)
		(width 0.1651)
		(layer "In13.Cu")
		(net "85_10INCH_IN5_DP")
	)
	(segment
		(start 427.715426 6.485128)
		(end 428.732188 6.30555)
		(width 0.1651)
		(layer "In13.Cu")
		(net "85_10INCH_IN5_DP")
	)
	(segment
		(start 415.421064 6.8707)
		(end 415.68878 6.488684)
		(width 0.1651)
		(layer "In13.Cu")
		(net "85_10INCH_IN5_DP")
	)
	(segment
		(start 420.347648 14.92631)
		(end 420.74973 14.353286)
		(width 0.1651)
		(layer "In13.Cu")
		(net "85_10INCH_IN5_DP")
	)
	(segment
		(start 417.087558 6.576822)
		(end 418.527484 14.744446)
		(width 0.1651)
		(layer "In13.Cu")
		(net "85_10INCH_IN5_DP")
	)
	(segment
		(start 429.114458 6.57352)
		(end 430.547018 14.698218)
		(width 0.1651)
		(layer "In13.Cu")
		(net "85_10INCH_IN5_DP")
	)
	(segment
		(start 447.152776 15.074392)
		(end 448.398646 14.854174)
		(width 0.1651)
		(layer "In13.Cu")
		(net "85_10INCH_IN5_DP")
	)
	(segment
		(start 437.132984 6.574536)
		(end 438.568592 14.71676)
		(width 0.1651)
		(layer "In13.Cu")
		(net "85_10INCH_IN5_DP")
	)
	(segment
		(start 426.533818 14.675866)
		(end 427.107604 15.077948)
		(width 0.1651)
		(layer "In13.Cu")
		(net "85_10INCH_IN5_DP")
	)
	(segment
		(start 443.483238 6.859524)
		(end 443.750954 6.477508)
		(width 0.1651)
		(layer "In13.Cu")
		(net "85_10INCH_IN5_DP")
	)
	(segment
		(start 419.429184 6.864096)
		(end 419.6969 6.48208)
		(width 0.1651)
		(layer "In13.Cu")
		(net "85_10INCH_IN5_DP")
	)
	(segment
		(start 413.077152 6.570472)
		(end 414.516062 14.729206)
		(width 0.1651)
		(layer "In13.Cu")
		(net "85_10INCH_IN5_DP")
	)
	(segment
		(start 443.146688 15.090902)
		(end 444.392558 14.870684)
		(width 0.1651)
		(layer "In13.Cu")
		(net "85_10INCH_IN5_DP")
	)
	(segment
		(start 452.79056 6.325616)
		(end 453.173084 6.59384)
		(width 0.1651)
		(layer "In13.Cu")
		(net "85_10INCH_IN5_DP")
	)
	(segment
		(start 440.757818 6.293104)
		(end 441.139834 6.56082)
		(width 0.1651)
		(layer "In13.Cu")
		(net "85_10INCH_IN5_DP")
	)
	(segment
		(start 427.44771 6.867144)
		(end 427.715426 6.485128)
		(width 0.1651)
		(layer "In13.Cu")
		(net "85_10INCH_IN5_DP")
	)
	(segment
		(start 452.812658 14.295882)
		(end 451.506336 6.88721)
		(width 0.1651)
		(layer "In13.Cu")
		(net "85_10INCH_IN5_DP")
	)
	(segment
		(start 401.194524 8.39978)
		(end 401.875498 8.581644)
		(width 0.13462)
		(layer "F.Cu")
		(net "85_10INCH_IN3_DP")
	)
	(segment
		(start 458.328268 8.425688)
		(end 457.647294 8.607552)
		(width 0.13462)
		(layer "F.Cu")
		(net "85_10INCH_IN3_DP")
	)
	(segment
		(start 441.270136 4.75996)
		(end 442.703204 12.88796)
		(width 0.1651)
		(layer "In9.Cu")
		(net "85_10INCH_IN3_DP")
	)
	(segment
		(start 449.29044 4.771644)
		(end 450.721222 12.88669)
		(width 0.1651)
		(layer "In9.Cu")
		(net "85_10INCH_IN3_DP")
	)
	(segment
		(start 417.21786 4.775962)
		(end 418.657786 12.943586)
		(width 0.1651)
		(layer "In9.Cu")
		(net "85_10INCH_IN3_DP")
	)
	(segment
		(start 421.22598 4.769358)
		(end 422.658794 12.896088)
		(width 0.1651)
		(layer "In9.Cu")
		(net "85_10INCH_IN3_DP")
	)
	(segment
		(start 412.437834 13.00607)
		(end 412.84017 12.43203)
		(width 0.1651)
		(layer "In9.Cu")
		(net "85_10INCH_IN3_DP")
	)
	(segment
		(start 423.835322 4.676394)
		(end 424.852084 4.496816)
		(width 0.1651)
		(layer "In9.Cu")
		(net "85_10INCH_IN3_DP")
	)
	(segment
		(start 415.819082 4.687824)
		(end 416.835844 4.508246)
		(width 0.1651)
		(layer "In9.Cu")
		(net "85_10INCH_IN3_DP")
	)
	(segment
		(start 436.916068 12.55014)
		(end 435.596792 5.067554)
		(width 0.1651)
		(layer "In9.Cu")
		(net "85_10INCH_IN3_DP")
	)
	(segment
		(start 444.898018 4.49707)
		(end 445.280034 4.764786)
		(width 0.1651)
		(layer "In9.Cu")
		(net "85_10INCH_IN3_DP")
	)
	(segment
		(start 405.404828 8.290814)
		(end 405.896572 8.782558)
		(width 0.1651)
		(layer "In9.Cu")
		(net "85_10INCH_IN3_DP")
	)
	(segment
		(start 411.808676 4.681474)
		(end 412.825438 4.501896)
		(width 0.1651)
		(layer "In9.Cu")
		(net "85_10INCH_IN3_DP")
	)
	(segment
		(start 452.920862 4.524756)
		(end 453.303386 4.79298)
		(width 0.1651)
		(layer "In9.Cu")
		(net "85_10INCH_IN3_DP")
	)
	(segment
		(start 412.84017 12.43203)
		(end 411.54096 5.06349)
		(width 0.1651)
		(layer "In9.Cu")
		(net "85_10INCH_IN3_DP")
	)
	(segment
		(start 423.567606 5.05841)
		(end 423.835322 4.676394)
		(width 0.1651)
		(layer "In9.Cu")
		(net "85_10INCH_IN3_DP")
	)
	(segment
		(start 410.61894 12.824714)
		(end 411.192218 13.226542)
		(width 0.1651)
		(layer "In9.Cu")
		(net "85_10INCH_IN3_DP")
	)
	(segment
		(start 406.605994 12.803632)
		(end 407.179526 13.205714)
		(width 0.1651)
		(layer "In9.Cu")
		(net "85_10INCH_IN3_DP")
	)
	(segment
		(start 436.513986 13.123672)
		(end 436.916068 12.55014)
		(width 0.1651)
		(layer "In9.Cu")
		(net "85_10INCH_IN3_DP")
	)
	(segment
		(start 408.827478 12.41171)
		(end 407.531316 5.059934)
		(width 0.1651)
		(layer "In9.Cu")
		(net "85_10INCH_IN3_DP")
	)
	(segment
		(start 435.864508 4.685538)
		(end 436.88127 4.50596)
		(width 0.1651)
		(layer "In9.Cu")
		(net "85_10INCH_IN3_DP")
	)
	(segment
		(start 415.219896 13.330174)
		(end 416.465766 13.109956)
		(width 0.1651)
		(layer "In9.Cu")
		(net "85_10INCH_IN3_DP")
	)
	(segment
		(start 402.166328 8.290814)
		(end 405.404828 8.290814)
		(width 0.1651)
		(layer "In9.Cu")
		(net "85_10INCH_IN3_DP")
	)
	(segment
		(start 407.531316 5.059934)
		(end 407.799032 4.677918)
		(width 0.1651)
		(layer "In9.Cu")
		(net "85_10INCH_IN3_DP")
	)
	(segment
		(start 428.483776 13.05687)
		(end 428.885858 12.483338)
		(width 0.1651)
		(layer "In9.Cu")
		(net "85_10INCH_IN3_DP")
	)
	(segment
		(start 401.875498 8.581644)
		(end 402.166328 8.290814)
		(width 0.1651)
		(layer "In9.Cu")
		(net "85_10INCH_IN3_DP")
	)
	(segment
		(start 423.23258 13.29817)
		(end 424.47845 13.077952)
		(width 0.1651)
		(layer "In9.Cu")
		(net "85_10INCH_IN3_DP")
	)
	(segment
		(start 442.703204 12.88796)
		(end 443.27699 13.290042)
		(width 0.1651)
		(layer "In9.Cu")
		(net "85_10INCH_IN3_DP")
	)
	(segment
		(start 405.896572 8.782558)
		(end 406.605994 12.803632)
		(width 0.1651)
		(layer "In9.Cu")
		(net "85_10INCH_IN3_DP")
	)
	(segment
		(start 443.61354 5.058664)
		(end 443.881256 4.676648)
		(width 0.1651)
		(layer "In9.Cu")
		(net "85_10INCH_IN3_DP")
	)
	(segment
		(start 411.54096 5.06349)
		(end 411.808676 4.681474)
		(width 0.1651)
		(layer "In9.Cu")
		(net "85_10INCH_IN3_DP")
	)
	(segment
		(start 414.646364 12.928092)
		(end 415.219896 13.330174)
		(width 0.1651)
		(layer "In9.Cu")
		(net "85_10INCH_IN3_DP")
	)
	(segment
		(start 411.192218 13.226542)
		(end 412.437834 13.00607)
		(width 0.1651)
		(layer "In9.Cu")
		(net "85_10INCH_IN3_DP")
	)
	(segment
		(start 407.179526 13.205714)
		(end 408.425396 12.985496)
		(width 0.1651)
		(layer "In9.Cu")
		(net "85_10INCH_IN3_DP")
	)
	(segment
		(start 445.280034 4.764786)
		(end 446.709292 12.87145)
		(width 0.1651)
		(layer "In9.Cu")
		(net "85_10INCH_IN3_DP")
	)
	(segment
		(start 420.880032 12.552426)
		(end 419.559486 5.063236)
		(width 0.1651)
		(layer "In9.Cu")
		(net "85_10INCH_IN3_DP")
	)
	(segment
		(start 451.295008 13.288772)
		(end 452.540878 13.068554)
		(width 0.1651)
		(layer "In9.Cu")
		(net "85_10INCH_IN3_DP")
	)
	(segment
		(start 426.66412 12.875006)
		(end 427.237906 13.277088)
		(width 0.1651)
		(layer "In9.Cu")
		(net "85_10INCH_IN3_DP")
	)
	(segment
		(start 422.658794 12.896088)
		(end 423.23258 13.29817)
		(width 0.1651)
		(layer "In9.Cu")
		(net "85_10INCH_IN3_DP")
	)
	(segment
		(start 432.899058 12.50569)
		(end 431.588418 5.072888)
		(width 0.1651)
		(layer "In9.Cu")
		(net "85_10INCH_IN3_DP")
	)
	(segment
		(start 419.23208 13.345668)
		(end 420.47795 13.12545)
		(width 0.1651)
		(layer "In9.Cu")
		(net "85_10INCH_IN3_DP")
	)
	(segment
		(start 443.881256 4.676648)
		(end 444.898018 4.49707)
		(width 0.1651)
		(layer "In9.Cu")
		(net "85_10INCH_IN3_DP")
	)
	(segment
		(start 432.872896 4.511294)
		(end 433.255166 4.77901)
		(width 0.1651)
		(layer "In9.Cu")
		(net "85_10INCH_IN3_DP")
	)
	(segment
		(start 453.303386 4.79298)
		(end 453.868028 7.994904)
		(width 0.1651)
		(layer "In9.Cu")
		(net "85_10INCH_IN3_DP")
	)
	(segment
		(start 453.868028 7.994904)
		(end 454.32726 8.316722)
		(width 0.1651)
		(layer "In9.Cu")
		(net "85_10INCH_IN3_DP")
	)
	(segment
		(start 412.825438 4.501896)
		(end 413.207454 4.769612)
		(width 0.1651)
		(layer "In9.Cu")
		(net "85_10INCH_IN3_DP")
	)
	(segment
		(start 457.356464 8.316722)
		(end 457.647294 8.607552)
		(width 0.1651)
		(layer "In9.Cu")
		(net "85_10INCH_IN3_DP")
	)
	(segment
		(start 424.852084 4.496816)
		(end 425.2341 4.764532)
		(width 0.1651)
		(layer "In9.Cu")
		(net "85_10INCH_IN3_DP")
	)
	(segment
		(start 448.528948 13.053314)
		(end 448.931284 12.479528)
		(width 0.1651)
		(layer "In9.Cu")
		(net "85_10INCH_IN3_DP")
	)
	(segment
		(start 452.540878 13.068554)
		(end 452.94296 12.495022)
		(width 0.1651)
		(layer "In9.Cu")
		(net "85_10INCH_IN3_DP")
	)
	(segment
		(start 440.920632 12.524232)
		(end 439.603642 5.053838)
		(width 0.1651)
		(layer "In9.Cu")
		(net "85_10INCH_IN3_DP")
	)
	(segment
		(start 428.885858 12.483338)
		(end 427.578012 5.066284)
		(width 0.1651)
		(layer "In9.Cu")
		(net "85_10INCH_IN3_DP")
	)
	(segment
		(start 439.871358 4.671822)
		(end 440.88812 4.492244)
		(width 0.1651)
		(layer "In9.Cu")
		(net "85_10INCH_IN3_DP")
	)
	(segment
		(start 443.27699 13.290042)
		(end 444.52286 13.069824)
		(width 0.1651)
		(layer "In9.Cu")
		(net "85_10INCH_IN3_DP")
	)
	(segment
		(start 452.94296 12.495022)
		(end 451.636638 5.08635)
		(width 0.1651)
		(layer "In9.Cu")
		(net "85_10INCH_IN3_DP")
	)
	(segment
		(start 448.907916 4.503674)
		(end 449.29044 4.771644)
		(width 0.1651)
		(layer "In9.Cu")
		(net "85_10INCH_IN3_DP")
	)
	(segment
		(start 416.835844 4.508246)
		(end 417.21786 4.775962)
		(width 0.1651)
		(layer "In9.Cu")
		(net "85_10INCH_IN3_DP")
	)
	(segment
		(start 448.931284 12.479528)
		(end 447.623438 5.065268)
		(width 0.1651)
		(layer "In9.Cu")
		(net "85_10INCH_IN3_DP")
	)
	(segment
		(start 454.32726 8.316722)
		(end 457.356464 8.316722)
		(width 0.1651)
		(layer "In9.Cu")
		(net "85_10INCH_IN3_DP")
	)
	(segment
		(start 447.283078 13.273532)
		(end 448.528948 13.053314)
		(width 0.1651)
		(layer "In9.Cu")
		(net "85_10INCH_IN3_DP")
	)
	(segment
		(start 425.2341 4.764532)
		(end 426.66412 12.875006)
		(width 0.1651)
		(layer "In9.Cu")
		(net "85_10INCH_IN3_DP")
	)
	(segment
		(start 439.603642 5.053838)
		(end 439.871358 4.671822)
		(width 0.1651)
		(layer "In9.Cu")
		(net "85_10INCH_IN3_DP")
	)
	(segment
		(start 451.636638 5.08635)
		(end 451.904354 4.704334)
		(width 0.1651)
		(layer "In9.Cu")
		(net "85_10INCH_IN3_DP")
	)
	(segment
		(start 447.891154 4.683252)
		(end 448.907916 4.503674)
		(width 0.1651)
		(layer "In9.Cu")
		(net "85_10INCH_IN3_DP")
	)
	(segment
		(start 450.721222 12.88669)
		(end 451.295008 13.288772)
		(width 0.1651)
		(layer "In9.Cu")
		(net "85_10INCH_IN3_DP")
	)
	(segment
		(start 438.698894 12.9159)
		(end 439.27268 13.317982)
		(width 0.1651)
		(layer "In9.Cu")
		(net "85_10INCH_IN3_DP")
	)
	(segment
		(start 424.880532 12.50442)
		(end 423.567606 5.05841)
		(width 0.1651)
		(layer "In9.Cu")
		(net "85_10INCH_IN3_DP")
	)
	(segment
		(start 431.251106 13.29944)
		(end 432.496976 13.079222)
		(width 0.1651)
		(layer "In9.Cu")
		(net "85_10INCH_IN3_DP")
	)
	(segment
		(start 429.24476 4.77266)
		(end 430.67732 12.897358)
		(width 0.1651)
		(layer "In9.Cu")
		(net "85_10INCH_IN3_DP")
	)
	(segment
		(start 407.799032 4.677918)
		(end 408.815794 4.49834)
		(width 0.1651)
		(layer "In9.Cu")
		(net "85_10INCH_IN3_DP")
	)
	(segment
		(start 424.47845 13.077952)
		(end 424.880532 12.50442)
		(width 0.1651)
		(layer "In9.Cu")
		(net "85_10INCH_IN3_DP")
	)
	(segment
		(start 432.496976 13.079222)
		(end 432.899058 12.50569)
		(width 0.1651)
		(layer "In9.Cu")
		(net "85_10INCH_IN3_DP")
	)
	(segment
		(start 420.47795 13.12545)
		(end 420.880032 12.552426)
		(width 0.1651)
		(layer "In9.Cu")
		(net "85_10INCH_IN3_DP")
	)
	(segment
		(start 433.255166 4.77901)
		(end 434.69433 12.941808)
		(width 0.1651)
		(layer "In9.Cu")
		(net "85_10INCH_IN3_DP")
	)
	(segment
		(start 444.52286 13.069824)
		(end 444.924942 12.496292)
		(width 0.1651)
		(layer "In9.Cu")
		(net "85_10INCH_IN3_DP")
	)
	(segment
		(start 447.623438 5.065268)
		(end 447.891154 4.683252)
		(width 0.1651)
		(layer "In9.Cu")
		(net "85_10INCH_IN3_DP")
	)
	(segment
		(start 413.207454 4.769612)
		(end 414.646364 12.928092)
		(width 0.1651)
		(layer "In9.Cu")
		(net "85_10INCH_IN3_DP")
	)
	(segment
		(start 440.51855 13.097764)
		(end 440.920632 12.524232)
		(width 0.1651)
		(layer "In9.Cu")
		(net "85_10INCH_IN3_DP")
	)
	(segment
		(start 418.657786 12.943586)
		(end 419.23208 13.345668)
		(width 0.1651)
		(layer "In9.Cu")
		(net "85_10INCH_IN3_DP")
	)
	(segment
		(start 430.67732 12.897358)
		(end 431.251106 13.29944)
		(width 0.1651)
		(layer "In9.Cu")
		(net "85_10INCH_IN3_DP")
	)
	(segment
		(start 440.88812 4.492244)
		(end 441.270136 4.75996)
		(width 0.1651)
		(layer "In9.Cu")
		(net "85_10INCH_IN3_DP")
	)
	(segment
		(start 437.263286 4.773676)
		(end 438.698894 12.9159)
		(width 0.1651)
		(layer "In9.Cu")
		(net "85_10INCH_IN3_DP")
	)
	(segment
		(start 434.69433 12.941808)
		(end 435.268116 13.34389)
		(width 0.1651)
		(layer "In9.Cu")
		(net "85_10INCH_IN3_DP")
	)
	(segment
		(start 427.237906 13.277088)
		(end 428.483776 13.05687)
		(width 0.1651)
		(layer "In9.Cu")
		(net "85_10INCH_IN3_DP")
	)
	(segment
		(start 420.843964 4.501642)
		(end 421.22598 4.769358)
		(width 0.1651)
		(layer "In9.Cu")
		(net "85_10INCH_IN3_DP")
	)
	(segment
		(start 408.425396 12.985496)
		(end 408.827478 12.41171)
		(width 0.1651)
		(layer "In9.Cu")
		(net "85_10INCH_IN3_DP")
	)
	(segment
		(start 439.27268 13.317982)
		(end 440.51855 13.097764)
		(width 0.1651)
		(layer "In9.Cu")
		(net "85_10INCH_IN3_DP")
	)
	(segment
		(start 444.924942 12.496292)
		(end 443.61354 5.058664)
		(width 0.1651)
		(layer "In9.Cu")
		(net "85_10INCH_IN3_DP")
	)
	(segment
		(start 427.578012 5.066284)
		(end 427.845728 4.684268)
		(width 0.1651)
		(layer "In9.Cu")
		(net "85_10INCH_IN3_DP")
	)
	(segment
		(start 435.268116 13.34389)
		(end 436.513986 13.123672)
		(width 0.1651)
		(layer "In9.Cu")
		(net "85_10INCH_IN3_DP")
	)
	(segment
		(start 416.867848 12.536424)
		(end 415.551366 5.06984)
		(width 0.1651)
		(layer "In9.Cu")
		(net "85_10INCH_IN3_DP")
	)
	(segment
		(start 419.559486 5.063236)
		(end 419.827202 4.68122)
		(width 0.1651)
		(layer "In9.Cu")
		(net "85_10INCH_IN3_DP")
	)
	(segment
		(start 408.815794 4.49834)
		(end 409.19781 4.766056)
		(width 0.1651)
		(layer "In9.Cu")
		(net "85_10INCH_IN3_DP")
	)
	(segment
		(start 409.19781 4.766056)
		(end 410.61894 12.824714)
		(width 0.1651)
		(layer "In9.Cu")
		(net "85_10INCH_IN3_DP")
	)
	(segment
		(start 428.86249 4.50469)
		(end 429.24476 4.77266)
		(width 0.1651)
		(layer "In9.Cu")
		(net "85_10INCH_IN3_DP")
	)
	(segment
		(start 446.709292 12.87145)
		(end 447.283078 13.273532)
		(width 0.1651)
		(layer "In9.Cu")
		(net "85_10INCH_IN3_DP")
	)
	(segment
		(start 451.904354 4.704334)
		(end 452.920862 4.524756)
		(width 0.1651)
		(layer "In9.Cu")
		(net "85_10INCH_IN3_DP")
	)
	(segment
		(start 431.856134 4.690872)
		(end 432.872896 4.511294)
		(width 0.1651)
		(layer "In9.Cu")
		(net "85_10INCH_IN3_DP")
	)
	(segment
		(start 435.596792 5.067554)
		(end 435.864508 4.685538)
		(width 0.1651)
		(layer "In9.Cu")
		(net "85_10INCH_IN3_DP")
	)
	(segment
		(start 436.88127 4.50596)
		(end 437.263286 4.773676)
		(width 0.1651)
		(layer "In9.Cu")
		(net "85_10INCH_IN3_DP")
	)
	(segment
		(start 431.588418 5.072888)
		(end 431.856134 4.690872)
		(width 0.1651)
		(layer "In9.Cu")
		(net "85_10INCH_IN3_DP")
	)
	(segment
		(start 416.465766 13.109956)
		(end 416.867848 12.536424)
		(width 0.1651)
		(layer "In9.Cu")
		(net "85_10INCH_IN3_DP")
	)
	(segment
		(start 427.845728 4.684268)
		(end 428.86249 4.50469)
		(width 0.1651)
		(layer "In9.Cu")
		(net "85_10INCH_IN3_DP")
	)
	(segment
		(start 415.551366 5.06984)
		(end 415.819082 4.687824)
		(width 0.1651)
		(layer "In9.Cu")
		(net "85_10INCH_IN3_DP")
	)
	(segment
		(start 419.827202 4.68122)
		(end 420.843964 4.501642)
		(width 0.1651)
		(layer "In9.Cu")
		(net "85_10INCH_IN3_DP")
	)
	(segment
		(start 446.57391 -71.908416)
		(end 446.57391 -72.366632)
		(width 0.13208)
		(layer "F.Cu")
		(net "P12V_SSD15_CO_MODE")
	)
	(segment
		(start 446.375536 -71.056754)
		(end 445.876426 -71.555864)
		(width 0.13208)
		(layer "F.Cu")
		(net "P12V_SSD15_CO_MODE")
	)
	(segment
		(start 446.221358 -71.555864)
		(end 446.57391 -71.908416)
		(width 0.13208)
		(layer "F.Cu")
		(net "P12V_SSD15_CO_MODE")
	)
	(segment
		(start 445.876426 -71.555864)
		(end 446.221358 -71.555864)
		(width 0.13208)
		(layer "F.Cu")
		(net "P12V_SSD15_CO_MODE")
	)
	(segment
		(start 446.375536 -70.479158)
		(end 446.375536 -71.056754)
		(width 0.13208)
		(layer "F.Cu")
		(net "P12V_SSD15_CO_MODE")
	)
	(segment
		(start 445.55791 -72.366632)
		(end 446.57391 -72.366632)
		(width 0.13208)
		(layer "F.Cu")
		(net "P12V_SSD15_CO_MODE")
	)
	(via
		(at 445.876426 -71.555864)
		(size 0.508)
		(drill 0.254)
		(layers "F.Cu" "B.Cu")
		(net "P12V_SSD15_CO_MODE")
	)
	(segment
		(start 339.091524 17.785588)
		(end 339.772498 17.603724)
		(width 0.13462)
		(layer "F.Cu")
		(net "85_5INCH_IN2_DP")
	)
	(segment
		(start 377.084844 17.778476)
		(end 376.40387 17.596612)
		(width 0.13462)
		(layer "F.Cu")
		(net "85_5INCH_IN2_DP")
	)
	(segment
		(start 371.80901 15.343886)
		(end 372.22176 17.68348)
		(width 0.1651)
		(layer "In7.Cu")
		(net "85_5INCH_IN2_DP")
	)
	(segment
		(start 343.942924 17.894554)
		(end 344.238072 18.14195)
		(width 0.1651)
		(layer "In7.Cu")
		(net "85_5INCH_IN2_DP")
	)
	(segment
		(start 355.772974 15.346426)
		(end 356.884478 21.651214)
		(width 0.1651)
		(layer "In7.Cu")
		(net "85_5INCH_IN2_DP")
	)
	(segment
		(start 345.533218 15.743936)
		(end 345.935046 15.170658)
		(width 0.1651)
		(layer "In7.Cu")
		(net "85_5INCH_IN2_DP")
	)
	(segment
		(start 366.29721 21.719794)
		(end 366.565434 21.33727)
		(width 0.1651)
		(layer "In7.Cu")
		(net "85_5INCH_IN2_DP")
	)
	(segment
		(start 363.217206 14.94155)
		(end 363.790738 15.343378)
		(width 0.1651)
		(layer "In7.Cu")
		(net "85_5INCH_IN2_DP")
	)
	(segment
		(start 369.58651 15.735046)
		(end 369.988338 15.161768)
		(width 0.1651)
		(layer "In7.Cu")
		(net "85_5INCH_IN2_DP")
	)
	(segment
		(start 346.51569 21.316442)
		(end 345.533218 15.743936)
		(width 0.1651)
		(layer "In7.Cu")
		(net "85_5INCH_IN2_DP")
	)
	(segment
		(start 365.577882 15.73911)
		(end 365.97971 15.165578)
		(width 0.1651)
		(layer "In7.Cu")
		(net "85_5INCH_IN2_DP")
	)
	(segment
		(start 345.935046 15.170658)
		(end 347.18244 14.95044)
		(width 0.1651)
		(layer "In7.Cu")
		(net "85_5INCH_IN2_DP")
	)
	(segment
		(start 361.27309 21.90369)
		(end 362.288836 21.724112)
		(width 0.1651)
		(layer "In7.Cu")
		(net "85_5INCH_IN2_DP")
	)
	(segment
		(start 376.11304 17.887442)
		(end 376.40387 17.596612)
		(width 0.1651)
		(layer "In7.Cu")
		(net "85_5INCH_IN2_DP")
	)
	(segment
		(start 370.30914 21.735034)
		(end 370.57711 21.352764)
		(width 0.1651)
		(layer "In7.Cu")
		(net "85_5INCH_IN2_DP")
	)
	(segment
		(start 356.884478 21.651214)
		(end 357.266748 21.919184)
		(width 0.1651)
		(layer "In7.Cu")
		(net "85_5INCH_IN2_DP")
	)
	(segment
		(start 371.235224 14.94155)
		(end 371.80901 15.343886)
		(width 0.1651)
		(layer "In7.Cu")
		(net "85_5INCH_IN2_DP")
	)
	(segment
		(start 372.51259 17.887442)
		(end 376.11304 17.887442)
		(width 0.1651)
		(layer "In7.Cu")
		(net "85_5INCH_IN2_DP")
	)
	(segment
		(start 363.790738 15.343378)
		(end 364.899448 21.631402)
		(width 0.1651)
		(layer "In7.Cu")
		(net "85_5INCH_IN2_DP")
	)
	(segment
		(start 347.18244 14.95044)
		(end 347.755718 15.352522)
		(width 0.1651)
		(layer "In7.Cu")
		(net "85_5INCH_IN2_DP")
	)
	(segment
		(start 368.911124 21.646642)
		(end 369.293394 21.914612)
		(width 0.1651)
		(layer "In7.Cu")
		(net "85_5INCH_IN2_DP")
	)
	(segment
		(start 359.78211 15.345664)
		(end 360.891074 21.63572)
		(width 0.1651)
		(layer "In7.Cu")
		(net "85_5INCH_IN2_DP")
	)
	(segment
		(start 360.891074 21.63572)
		(end 361.27309 21.90369)
		(width 0.1651)
		(layer "In7.Cu")
		(net "85_5INCH_IN2_DP")
	)
	(segment
		(start 369.293394 21.914612)
		(end 370.30914 21.735034)
		(width 0.1651)
		(layer "In7.Cu")
		(net "85_5INCH_IN2_DP")
	)
	(segment
		(start 344.849704 21.61032)
		(end 345.231974 21.87829)
		(width 0.1651)
		(layer "In7.Cu")
		(net "85_5INCH_IN2_DP")
	)
	(segment
		(start 351.190306 14.94536)
		(end 351.763838 15.347188)
		(width 0.1651)
		(layer "In7.Cu")
		(net "85_5INCH_IN2_DP")
	)
	(segment
		(start 349.245174 21.900642)
		(end 350.26092 21.721064)
		(width 0.1651)
		(layer "In7.Cu")
		(net "85_5INCH_IN2_DP")
	)
	(segment
		(start 372.22176 17.68348)
		(end 372.51259 17.887442)
		(width 0.1651)
		(layer "In7.Cu")
		(net "85_5INCH_IN2_DP")
	)
	(segment
		(start 355.199442 14.944598)
		(end 355.772974 15.346426)
		(width 0.1651)
		(layer "In7.Cu")
		(net "85_5INCH_IN2_DP")
	)
	(segment
		(start 349.541592 15.738856)
		(end 349.94342 15.165578)
		(width 0.1651)
		(layer "In7.Cu")
		(net "85_5INCH_IN2_DP")
	)
	(segment
		(start 361.568492 15.735046)
		(end 361.97032 15.161768)
		(width 0.1651)
		(layer "In7.Cu")
		(net "85_5INCH_IN2_DP")
	)
	(segment
		(start 339.772498 17.603724)
		(end 340.063328 17.894554)
		(width 0.1651)
		(layer "In7.Cu")
		(net "85_5INCH_IN2_DP")
	)
	(segment
		(start 347.755718 15.352522)
		(end 348.862904 21.632672)
		(width 0.1651)
		(layer "In7.Cu")
		(net "85_5INCH_IN2_DP")
	)
	(segment
		(start 370.57711 21.352764)
		(end 369.58651 15.735046)
		(width 0.1651)
		(layer "In7.Cu")
		(net "85_5INCH_IN2_DP")
	)
	(segment
		(start 354.27793 21.765514)
		(end 354.5459 21.383244)
		(width 0.1651)
		(layer "In7.Cu")
		(net "85_5INCH_IN2_DP")
	)
	(segment
		(start 352.879914 21.677122)
		(end 353.262184 21.945092)
		(width 0.1651)
		(layer "In7.Cu")
		(net "85_5INCH_IN2_DP")
	)
	(segment
		(start 345.231974 21.87829)
		(end 346.24772 21.698712)
		(width 0.1651)
		(layer "In7.Cu")
		(net "85_5INCH_IN2_DP")
	)
	(segment
		(start 346.24772 21.698712)
		(end 346.51569 21.316442)
		(width 0.1651)
		(layer "In7.Cu")
		(net "85_5INCH_IN2_DP")
	)
	(segment
		(start 364.899448 21.631402)
		(end 365.281464 21.899372)
		(width 0.1651)
		(layer "In7.Cu")
		(net "85_5INCH_IN2_DP")
	)
	(segment
		(start 353.550728 15.738094)
		(end 353.952556 15.164816)
		(width 0.1651)
		(layer "In7.Cu")
		(net "85_5INCH_IN2_DP")
	)
	(segment
		(start 361.97032 15.161768)
		(end 363.217206 14.94155)
		(width 0.1651)
		(layer "In7.Cu")
		(net "85_5INCH_IN2_DP")
	)
	(segment
		(start 348.862904 21.632672)
		(end 349.245174 21.900642)
		(width 0.1651)
		(layer "In7.Cu")
		(net "85_5INCH_IN2_DP")
	)
	(segment
		(start 362.288836 21.724112)
		(end 362.556806 21.341588)
		(width 0.1651)
		(layer "In7.Cu")
		(net "85_5INCH_IN2_DP")
	)
	(segment
		(start 366.565434 21.33727)
		(end 365.577882 15.73911)
		(width 0.1651)
		(layer "In7.Cu")
		(net "85_5INCH_IN2_DP")
	)
	(segment
		(start 367.800636 15.347442)
		(end 368.911124 21.646642)
		(width 0.1651)
		(layer "In7.Cu")
		(net "85_5INCH_IN2_DP")
	)
	(segment
		(start 340.063328 17.894554)
		(end 343.942924 17.894554)
		(width 0.1651)
		(layer "In7.Cu")
		(net "85_5INCH_IN2_DP")
	)
	(segment
		(start 354.5459 21.383244)
		(end 353.550728 15.738094)
		(width 0.1651)
		(layer "In7.Cu")
		(net "85_5INCH_IN2_DP")
	)
	(segment
		(start 353.262184 21.945092)
		(end 354.27793 21.765514)
		(width 0.1651)
		(layer "In7.Cu")
		(net "85_5INCH_IN2_DP")
	)
	(segment
		(start 358.550464 21.357082)
		(end 357.559864 15.737332)
		(width 0.1651)
		(layer "In7.Cu")
		(net "85_5INCH_IN2_DP")
	)
	(segment
		(start 350.26092 21.721064)
		(end 350.52889 21.338794)
		(width 0.1651)
		(layer "In7.Cu")
		(net "85_5INCH_IN2_DP")
	)
	(segment
		(start 353.952556 15.164816)
		(end 355.199442 14.944598)
		(width 0.1651)
		(layer "In7.Cu")
		(net "85_5INCH_IN2_DP")
	)
	(segment
		(start 357.961692 15.164054)
		(end 359.208578 14.943836)
		(width 0.1651)
		(layer "In7.Cu")
		(net "85_5INCH_IN2_DP")
	)
	(segment
		(start 369.988338 15.161768)
		(end 371.235224 14.94155)
		(width 0.1651)
		(layer "In7.Cu")
		(net "85_5INCH_IN2_DP")
	)
	(segment
		(start 362.556806 21.341588)
		(end 361.568492 15.735046)
		(width 0.1651)
		(layer "In7.Cu")
		(net "85_5INCH_IN2_DP")
	)
	(segment
		(start 350.52889 21.338794)
		(end 349.541592 15.738856)
		(width 0.1651)
		(layer "In7.Cu")
		(net "85_5INCH_IN2_DP")
	)
	(segment
		(start 357.559864 15.737332)
		(end 357.961692 15.164054)
		(width 0.1651)
		(layer "In7.Cu")
		(net "85_5INCH_IN2_DP")
	)
	(segment
		(start 367.226596 14.94536)
		(end 367.800636 15.347442)
		(width 0.1651)
		(layer "In7.Cu")
		(net "85_5INCH_IN2_DP")
	)
	(segment
		(start 365.97971 15.165578)
		(end 367.226596 14.94536)
		(width 0.1651)
		(layer "In7.Cu")
		(net "85_5INCH_IN2_DP")
	)
	(segment
		(start 365.281464 21.899372)
		(end 366.29721 21.719794)
		(width 0.1651)
		(layer "In7.Cu")
		(net "85_5INCH_IN2_DP")
	)
	(segment
		(start 357.266748 21.919184)
		(end 358.282494 21.739606)
		(width 0.1651)
		(layer "In7.Cu")
		(net "85_5INCH_IN2_DP")
	)
	(segment
		(start 344.238072 18.14195)
		(end 344.849704 21.61032)
		(width 0.1651)
		(layer "In7.Cu")
		(net "85_5INCH_IN2_DP")
	)
	(segment
		(start 349.94342 15.165578)
		(end 351.190306 14.94536)
		(width 0.1651)
		(layer "In7.Cu")
		(net "85_5INCH_IN2_DP")
	)
	(segment
		(start 359.208578 14.943836)
		(end 359.78211 15.345664)
		(width 0.1651)
		(layer "In7.Cu")
		(net "85_5INCH_IN2_DP")
	)
	(segment
		(start 351.763838 15.347188)
		(end 352.879914 21.677122)
		(width 0.1651)
		(layer "In7.Cu")
		(net "85_5INCH_IN2_DP")
	)
	(segment
		(start 358.282494 21.739606)
		(end 358.550464 21.357082)
		(width 0.1651)
		(layer "In7.Cu")
		(net "85_5INCH_IN2_DP")
	)
	(segment
		(start 394.37564 -67.96405)
		(end 394.198856 -67.787266)
		(width 0.13208)
		(layer "F.Cu")
		(net "P12V_SSD13_CO_GATE")
	)
	(segment
		(start 393.760452 -67.787266)
		(end 393.46124 -67.488054)
		(width 0.13208)
		(layer "F.Cu")
		(net "P12V_SSD13_CO_GATE")
	)
	(segment
		(start 393.798552 -67.150742)
		(end 393.798552 -66.72199)
		(width 0.13208)
		(layer "F.Cu")
		(net "P12V_SSD13_CO_GATE")
	)
	(segment
		(start 394.198856 -67.787266)
		(end 393.760452 -67.787266)
		(width 0.13208)
		(layer "F.Cu")
		(net "P12V_SSD13_CO_GATE")
	)
	(segment
		(start 394.37564 -68.479162)
		(end 394.37564 -67.96405)
		(width 0.13208)
		(layer "F.Cu")
		(net "P12V_SSD13_CO_GATE")
	)
	(segment
		(start 393.46124 -67.488054)
		(end 393.798552 -67.150742)
		(width 0.13208)
		(layer "F.Cu")
		(net "P12V_SSD13_CO_GATE")
	)
	(via
		(at 393.46124 -67.488054)
		(size 0.508)
		(drill 0.254)
		(layers "F.Cu" "B.Cu")
		(net "P12V_SSD13_CO_GATE")
	)
	(segment
		(start 421.375332 -68.479162)
		(end 421.375332 -68.244974)
		(width 0.13208)
		(layer "F.Cu")
		(net "P12V_SSD14_CO_DV_DT")
	)
	(segment
		(start 422.02735 -67.228212)
		(end 421.8305 -67.031362)
		(width 0.13208)
		(layer "F.Cu")
		(net "P12V_SSD14_CO_DV_DT")
	)
	(segment
		(start 421.375332 -68.244974)
		(end 422.02735 -67.592956)
		(width 0.13208)
		(layer "F.Cu")
		(net "P12V_SSD14_CO_DV_DT")
	)
	(segment
		(start 422.02735 -67.592956)
		(end 422.02735 -67.228212)
		(width 0.13208)
		(layer "F.Cu")
		(net "P12V_SSD14_CO_DV_DT")
	)
	(segment
		(start 421.8305 -67.031362)
		(end 421.8305 -66.72199)
		(width 0.13208)
		(layer "F.Cu")
		(net "P12V_SSD14_CO_DV_DT")
	)
	(via
		(at 422.02735 -67.592956)
		(size 0.508)
		(drill 0.254)
		(layers "F.Cu" "B.Cu")
		(net "P12V_SSD14_CO_DV_DT")
	)
	(segment
		(start 395.375384 -68.479162)
		(end 395.375384 -68.244974)
		(width 0.13208)
		(layer "F.Cu")
		(net "P12V_SSD13_CO_DV_DT")
	)
	(segment
		(start 395.375384 -68.244974)
		(end 396.027402 -67.592956)
		(width 0.13208)
		(layer "F.Cu")
		(net "P12V_SSD13_CO_DV_DT")
	)
	(segment
		(start 396.027402 -67.592956)
		(end 396.027402 -67.228212)
		(width 0.13208)
		(layer "F.Cu")
		(net "P12V_SSD13_CO_DV_DT")
	)
	(segment
		(start 396.027402 -67.228212)
		(end 395.830552 -67.031362)
		(width 0.13208)
		(layer "F.Cu")
		(net "P12V_SSD13_CO_DV_DT")
	)
	(segment
		(start 395.830552 -67.031362)
		(end 395.830552 -66.72199)
		(width 0.13208)
		(layer "F.Cu")
		(net "P12V_SSD13_CO_DV_DT")
	)
	(via
		(at 396.027402 -67.592956)
		(size 0.508)
		(drill 0.254)
		(layers "F.Cu" "B.Cu")
		(net "P12V_SSD13_CO_DV_DT")
	)
	(segment
		(start 252.653292 -67.537584)
		(end 252.653292 -67.077844)
		(width 0.13208)
		(layer "F.Cu")
		(net "P12V_SSD8_CO_EN")
	)
	(segment
		(start 252.653292 -67.847972)
		(end 252.653292 -67.537584)
		(width 0.13208)
		(layer "F.Cu")
		(net "P12V_SSD8_CO_EN")
	)
	(segment
		(start 252.775466 -68.479162)
		(end 252.775466 -67.970146)
		(width 0.13208)
		(layer "F.Cu")
		(net "P12V_SSD8_CO_EN")
	)
	(segment
		(start 252.714506 -67.01663)
		(end 252.714506 -66.72199)
		(width 0.13208)
		(layer "F.Cu")
		(net "P12V_SSD8_CO_EN")
	)
	(segment
		(start 252.653292 -67.077844)
		(end 252.714506 -67.01663)
		(width 0.13208)
		(layer "F.Cu")
		(net "P12V_SSD8_CO_EN")
	)
	(segment
		(start 252.775466 -67.970146)
		(end 252.653292 -67.847972)
		(width 0.13208)
		(layer "F.Cu")
		(net "P12V_SSD8_CO_EN")
	)
	(via
		(at 252.653292 -67.537584)
		(size 0.508)
		(drill 0.254)
		(layers "F.Cu" "B.Cu")
		(net "P12V_SSD8_CO_EN")
	)
	(segment
		(start 420.753286 -67.537584)
		(end 420.753286 -67.077844)
		(width 0.13208)
		(layer "F.Cu")
		(net "P12V_SSD14_CO_EN")
	)
	(segment
		(start 420.87546 -68.479162)
		(end 420.87546 -67.970146)
		(width 0.13208)
		(layer "F.Cu")
		(net "P12V_SSD14_CO_EN")
	)
	(segment
		(start 420.8145 -67.01663)
		(end 420.8145 -66.72199)
		(width 0.13208)
		(layer "F.Cu")
		(net "P12V_SSD14_CO_EN")
	)
	(segment
		(start 420.753286 -67.847972)
		(end 420.753286 -67.537584)
		(width 0.13208)
		(layer "F.Cu")
		(net "P12V_SSD14_CO_EN")
	)
	(segment
		(start 420.87546 -67.970146)
		(end 420.753286 -67.847972)
		(width 0.13208)
		(layer "F.Cu")
		(net "P12V_SSD14_CO_EN")
	)
	(segment
		(start 420.753286 -67.077844)
		(end 420.8145 -67.01663)
		(width 0.13208)
		(layer "F.Cu")
		(net "P12V_SSD14_CO_EN")
	)
	(via
		(at 420.753286 -67.537584)
		(size 0.508)
		(drill 0.254)
		(layers "F.Cu" "B.Cu")
		(net "P12V_SSD14_CO_EN")
	)
	(segment
		(start 420.22141 -71.555864)
		(end 419.876478 -71.555864)
		(width 0.13208)
		(layer "F.Cu")
		(net "P12V_SSD14_CO_MODE")
	)
	(segment
		(start 419.557962 -72.366632)
		(end 420.573962 -72.366632)
		(width 0.13208)
		(layer "F.Cu")
		(net "P12V_SSD14_CO_MODE")
	)
	(segment
		(start 420.573962 -71.908416)
		(end 420.22141 -71.555864)
		(width 0.13208)
		(layer "F.Cu")
		(net "P12V_SSD14_CO_MODE")
	)
	(segment
		(start 419.876478 -71.555864)
		(end 420.375588 -71.056754)
		(width 0.13208)
		(layer "F.Cu")
		(net "P12V_SSD14_CO_MODE")
	)
	(segment
		(start 420.573962 -72.366632)
		(end 420.573962 -71.908416)
		(width 0.13208)
		(layer "F.Cu")
		(net "P12V_SSD14_CO_MODE")
	)
	(segment
		(start 420.375588 -71.056754)
		(end 420.375588 -70.479158)
		(width 0.13208)
		(layer "F.Cu")
		(net "P12V_SSD14_CO_MODE")
	)
	(via
		(at 419.876478 -71.555864)
		(size 0.508)
		(drill 0.254)
		(layers "F.Cu" "B.Cu")
		(net "P12V_SSD14_CO_MODE")
	)
	(segment
		(start 330.77531 -68.479162)
		(end 330.77531 -67.970146)
		(width 0.13208)
		(layer "F.Cu")
		(net "P12V_SSD11_CO_EN")
	)
	(segment
		(start 330.77531 -67.970146)
		(end 330.653136 -67.847972)
		(width 0.13208)
		(layer "F.Cu")
		(net "P12V_SSD11_CO_EN")
	)
	(segment
		(start 330.653136 -67.537584)
		(end 330.653136 -67.077844)
		(width 0.13208)
		(layer "F.Cu")
		(net "P12V_SSD11_CO_EN")
	)
	(segment
		(start 330.653136 -67.847972)
		(end 330.653136 -67.537584)
		(width 0.13208)
		(layer "F.Cu")
		(net "P12V_SSD11_CO_EN")
	)
	(segment
		(start 330.653136 -67.077844)
		(end 330.71435 -67.01663)
		(width 0.13208)
		(layer "F.Cu")
		(net "P12V_SSD11_CO_EN")
	)
	(segment
		(start 330.71435 -67.01663)
		(end 330.71435 -66.72199)
		(width 0.13208)
		(layer "F.Cu")
		(net "P12V_SSD11_CO_EN")
	)
	(via
		(at 330.653136 -67.537584)
		(size 0.508)
		(drill 0.254)
		(layers "F.Cu" "B.Cu")
		(net "P12V_SSD11_CO_EN")
	)
	(segment
		(start 262.889492 -63.56223)
		(end 262.447532 -63.56223)
		(width 0.13208)
		(layer "F.Cu")
		(net "P12V_SSD9_PG_G1")
	)
	(segment
		(start 262.447532 -63.56223)
		(end 262.158734 -63.273432)
		(width 0.13208)
		(layer "F.Cu")
		(net "P12V_SSD9_PG_G1")
	)
	(segment
		(start 262.158734 -63.273432)
		(end 262.089646 -63.273432)
		(width 0.13208)
		(layer "F.Cu")
		(net "P12V_SSD9_PG_G1")
	)
	(segment
		(start 262.089646 -63.273432)
		(end 261.902448 -63.086234)
		(width 0.13208)
		(layer "F.Cu")
		(net "P12V_SSD9_PG_G1")
	)
	(segment
		(start 261.902448 -63.086234)
		(end 261.47522 -63.086234)
		(width 0.13208)
		(layer "F.Cu")
		(net "P12V_SSD9_PG_G1")
	)
	(segment
		(start 261.47522 -64.102234)
		(end 261.47522 -63.086234)
		(width 0.13208)
		(layer "F.Cu")
		(net "P12V_SSD9_PG_G1")
	)
	(via
		(at 262.158734 -63.273432)
		(size 0.508)
		(drill 0.254)
		(layers "F.Cu" "B.Cu")
		(net "P12V_SSD9_PG_G1")
	)
	(segment
		(start 277.776432 -71.555864)
		(end 278.121364 -71.555864)
		(width 0.13208)
		(layer "F.Cu")
		(net "P12V_SSD9_CO_MODE")
	)
	(segment
		(start 277.457916 -72.366632)
		(end 278.473916 -72.366632)
		(width 0.13208)
		(layer "F.Cu")
		(net "P12V_SSD9_CO_MODE")
	)
	(segment
		(start 278.275542 -71.056754)
		(end 278.275542 -70.479158)
		(width 0.13208)
		(layer "F.Cu")
		(net "P12V_SSD9_CO_MODE")
	)
	(segment
		(start 277.776432 -71.555864)
		(end 278.275542 -71.056754)
		(width 0.13208)
		(layer "F.Cu")
		(net "P12V_SSD9_CO_MODE")
	)
	(segment
		(start 278.121364 -71.555864)
		(end 278.473916 -71.908416)
		(width 0.13208)
		(layer "F.Cu")
		(net "P12V_SSD9_CO_MODE")
	)
	(segment
		(start 278.473916 -71.908416)
		(end 278.473916 -72.366632)
		(width 0.13208)
		(layer "F.Cu")
		(net "P12V_SSD9_CO_MODE")
	)
	(via
		(at 277.776432 -71.555864)
		(size 0.508)
		(drill 0.254)
		(layers "F.Cu" "B.Cu")
		(net "P12V_SSD9_CO_MODE")
	)
	(segment
		(start 278.714454 -67.01663)
		(end 278.714454 -66.72199)
		(width 0.13208)
		(layer "F.Cu")
		(net "P12V_SSD9_CO_EN")
	)
	(segment
		(start 278.65324 -67.077844)
		(end 278.714454 -67.01663)
		(width 0.13208)
		(layer "F.Cu")
		(net "P12V_SSD9_CO_EN")
	)
	(segment
		(start 278.775414 -67.970146)
		(end 278.65324 -67.847972)
		(width 0.13208)
		(layer "F.Cu")
		(net "P12V_SSD9_CO_EN")
	)
	(segment
		(start 278.65324 -67.847972)
		(end 278.65324 -67.537584)
		(width 0.13208)
		(layer "F.Cu")
		(net "P12V_SSD9_CO_EN")
	)
	(segment
		(start 278.775414 -68.479162)
		(end 278.775414 -67.970146)
		(width 0.13208)
		(layer "F.Cu")
		(net "P12V_SSD9_CO_EN")
	)
	(segment
		(start 278.65324 -67.537584)
		(end 278.65324 -67.077844)
		(width 0.13208)
		(layer "F.Cu")
		(net "P12V_SSD9_CO_EN")
	)
	(via
		(at 278.65324 -67.537584)
		(size 0.508)
		(drill 0.254)
		(layers "F.Cu" "B.Cu")
		(net "P12V_SSD9_CO_EN")
	)
	(segment
		(start 304.098706 -67.787266)
		(end 304.27549 -67.96405)
		(width 0.13208)
		(layer "F.Cu")
		(net "P12V_SSD10_CO_GATE")
	)
	(segment
		(start 303.36109 -67.488054)
		(end 303.660302 -67.787266)
		(width 0.13208)
		(layer "F.Cu")
		(net "P12V_SSD10_CO_GATE")
	)
	(segment
		(start 303.698402 -67.150742)
		(end 303.698402 -66.72199)
		(width 0.13208)
		(layer "F.Cu")
		(net "P12V_SSD10_CO_GATE")
	)
	(segment
		(start 303.660302 -67.787266)
		(end 304.098706 -67.787266)
		(width 0.13208)
		(layer "F.Cu")
		(net "P12V_SSD10_CO_GATE")
	)
	(segment
		(start 304.27549 -67.96405)
		(end 304.27549 -68.479162)
		(width 0.13208)
		(layer "F.Cu")
		(net "P12V_SSD10_CO_GATE")
	)
	(segment
		(start 303.36109 -67.488054)
		(end 303.698402 -67.150742)
		(width 0.13208)
		(layer "F.Cu")
		(net "P12V_SSD10_CO_GATE")
	)
	(via
		(at 303.36109 -67.488054)
		(size 0.508)
		(drill 0.254)
		(layers "F.Cu" "B.Cu")
		(net "P12V_SSD10_CO_GATE")
	)
	(segment
		(start 305.275234 -68.244974)
		(end 305.275234 -68.479162)
		(width 0.13208)
		(layer "F.Cu")
		(net "P12V_SSD10_CO_DV_DT")
	)
	(segment
		(start 305.927252 -67.592956)
		(end 305.927252 -67.228212)
		(width 0.13208)
		(layer "F.Cu")
		(net "P12V_SSD10_CO_DV_DT")
	)
	(segment
		(start 305.927252 -67.228212)
		(end 305.730402 -67.031362)
		(width 0.13208)
		(layer "F.Cu")
		(net "P12V_SSD10_CO_DV_DT")
	)
	(segment
		(start 305.927252 -67.592956)
		(end 305.275234 -68.244974)
		(width 0.13208)
		(layer "F.Cu")
		(net "P12V_SSD10_CO_DV_DT")
	)
	(segment
		(start 305.730402 -67.031362)
		(end 305.730402 -66.72199)
		(width 0.13208)
		(layer "F.Cu")
		(net "P12V_SSD10_CO_DV_DT")
	)
	(via
		(at 305.927252 -67.592956)
		(size 0.508)
		(drill 0.254)
		(layers "F.Cu" "B.Cu")
		(net "P12V_SSD10_CO_DV_DT")
	)
	(segment
		(start 239.838992 -60.920376)
		(end 239.412272 -60.493656)
		(width 0.13208)
		(layer "F.Cu")
		(net "P12V_SSD8_PG_G1")
	)
	(segment
		(start 239.550194 -61.651134)
		(end 239.550194 -61.209174)
		(width 0.13208)
		(layer "F.Cu")
		(net "P12V_SSD8_PG_G1")
	)
	(segment
		(start 239.400334 -60.152026)
		(end 239.412272 -60.163964)
		(width 0.13208)
		(layer "F.Cu")
		(net "P12V_SSD8_PG_G1")
	)
	(segment
		(start 238.28375 -60.152026)
		(end 239.400334 -60.152026)
		(width 0.13208)
		(layer "F.Cu")
		(net "P12V_SSD8_PG_G1")
	)
	(segment
		(start 239.412272 -60.493656)
		(end 239.412272 -60.163964)
		(width 0.13208)
		(layer "F.Cu")
		(net "P12V_SSD8_PG_G1")
	)
	(segment
		(start 239.550194 -61.209174)
		(end 239.838992 -60.920376)
		(width 0.13208)
		(layer "F.Cu")
		(net "P12V_SSD8_PG_G1")
	)
	(via
		(at 239.838992 -60.920376)
		(size 0.508)
		(drill 0.254)
		(layers "F.Cu" "B.Cu")
		(net "P12V_SSD8_PG_G1")
	)
	(segment
		(start 290.689284 -64.312292)
		(end 291.48786 -64.312292)
		(width 0.13208)
		(layer "F.Cu")
		(net "P12V_SSD10_PG_G2")
	)
	(segment
		(start 291.960046 -64.222122)
		(end 291.960046 -63.70193)
		(width 0.13208)
		(layer "F.Cu")
		(net "P12V_SSD10_PG_G2")
	)
	(segment
		(start 290.689284 -63.56223)
		(end 291.820346 -63.56223)
		(width 0.13208)
		(layer "F.Cu")
		(net "P12V_SSD10_PG_G2")
	)
	(segment
		(start 291.869876 -64.312292)
		(end 291.960046 -64.222122)
		(width 0.13208)
		(layer "F.Cu")
		(net "P12V_SSD10_PG_G2")
	)
	(segment
		(start 291.820346 -63.56223)
		(end 291.910262 -63.652146)
		(width 0.13208)
		(layer "F.Cu")
		(net "P12V_SSD10_PG_G2")
	)
	(segment
		(start 291.960046 -63.70193)
		(end 291.910262 -63.652146)
		(width 0.13208)
		(layer "F.Cu")
		(net "P12V_SSD10_PG_G2")
	)
	(segment
		(start 291.48786 -64.312292)
		(end 291.869876 -64.312292)
		(width 0.13208)
		(layer "F.Cu")
		(net "P12V_SSD10_PG_G2")
	)
	(via
		(at 291.48786 -64.312292)
		(size 0.508)
		(drill 0.254)
		(layers "F.Cu" "B.Cu")
		(net "P12V_SSD10_PG_G2")
	)
	(segment
		(start 265.960098 -64.496442)
		(end 265.332464 -65.124076)
		(width 0.13208)
		(layer "F.Cu")
		(net "P12V_SSD9_PG_G2")
	)
	(segment
		(start 265.910314 -63.652146)
		(end 265.960098 -63.70193)
		(width 0.13208)
		(layer "F.Cu")
		(net "P12V_SSD9_PG_G2")
	)
	(segment
		(start 265.332464 -65.124076)
		(end 264.689336 -65.124076)
		(width 0.13208)
		(layer "F.Cu")
		(net "P12V_SSD9_PG_G2")
	)
	(segment
		(start 264.689336 -65.124076)
		(end 264.689336 -64.312292)
		(width 0.13208)
		(layer "F.Cu")
		(net "P12V_SSD9_PG_G2")
	)
	(segment
		(start 265.910314 -63.652146)
		(end 265.820398 -63.56223)
		(width 0.13208)
		(layer "F.Cu")
		(net "P12V_SSD9_PG_G2")
	)
	(segment
		(start 265.960098 -63.70193)
		(end 265.960098 -64.496442)
		(width 0.13208)
		(layer "F.Cu")
		(net "P12V_SSD9_PG_G2")
	)
	(segment
		(start 265.820398 -63.56223)
		(end 264.689336 -63.56223)
		(width 0.13208)
		(layer "F.Cu")
		(net "P12V_SSD9_PG_G2")
	)
	(via
		(at 264.689336 -65.124076)
		(size 0.508)
		(drill 0.254)
		(layers "F.Cu" "B.Cu")
		(net "P12V_SSD9_PG_G2")
	)
	(segment
		(start 279.730454 -67.031362)
		(end 279.730454 -66.72199)
		(width 0.13208)
		(layer "F.Cu")
		(net "P12V_SSD9_CO_DV_DT")
	)
	(segment
		(start 279.927304 -67.592956)
		(end 279.275286 -68.244974)
		(width 0.13208)
		(layer "F.Cu")
		(net "P12V_SSD9_CO_DV_DT")
	)
	(segment
		(start 279.927304 -67.228212)
		(end 279.730454 -67.031362)
		(width 0.13208)
		(layer "F.Cu")
		(net "P12V_SSD9_CO_DV_DT")
	)
	(segment
		(start 279.927304 -67.592956)
		(end 279.927304 -67.228212)
		(width 0.13208)
		(layer "F.Cu")
		(net "P12V_SSD9_CO_DV_DT")
	)
	(segment
		(start 279.275286 -68.244974)
		(end 279.275286 -68.479162)
		(width 0.13208)
		(layer "F.Cu")
		(net "P12V_SSD9_CO_DV_DT")
	)
	(via
		(at 279.927304 -67.592956)
		(size 0.508)
		(drill 0.254)
		(layers "F.Cu" "B.Cu")
		(net "P12V_SSD9_CO_DV_DT")
	)
	(segment
		(start 330.275438 -68.479162)
		(end 330.275438 -67.96405)
		(width 0.13208)
		(layer "F.Cu")
		(net "P12V_SSD11_CO_GATE")
	)
	(segment
		(start 329.361038 -67.488054)
		(end 329.69835 -67.150742)
		(width 0.13208)
		(layer "F.Cu")
		(net "P12V_SSD11_CO_GATE")
	)
	(segment
		(start 329.66025 -67.787266)
		(end 329.361038 -67.488054)
		(width 0.13208)
		(layer "F.Cu")
		(net "P12V_SSD11_CO_GATE")
	)
	(segment
		(start 330.275438 -67.96405)
		(end 330.098654 -67.787266)
		(width 0.13208)
		(layer "F.Cu")
		(net "P12V_SSD11_CO_GATE")
	)
	(segment
		(start 330.098654 -67.787266)
		(end 329.66025 -67.787266)
		(width 0.13208)
		(layer "F.Cu")
		(net "P12V_SSD11_CO_GATE")
	)
	(segment
		(start 329.69835 -67.150742)
		(end 329.69835 -66.72199)
		(width 0.13208)
		(layer "F.Cu")
		(net "P12V_SSD11_CO_GATE")
	)
	(via
		(at 329.361038 -67.488054)
		(size 0.508)
		(drill 0.254)
		(layers "F.Cu" "B.Cu")
		(net "P12V_SSD11_CO_GATE")
	)
	(segment
		(start 239.550194 -63.450978)
		(end 239.550194 -64.58204)
		(width 0.13208)
		(layer "F.Cu")
		(net "P12V_SSD8_PG_G2")
	)
	(segment
		(start 238.800132 -63.450978)
		(end 237.988348 -63.450978)
		(width 0.13208)
		(layer "F.Cu")
		(net "P12V_SSD8_PG_G2")
	)
	(segment
		(start 237.988348 -63.450978)
		(end 237.988348 -64.094106)
		(width 0.13208)
		(layer "F.Cu")
		(net "P12V_SSD8_PG_G2")
	)
	(segment
		(start 239.410494 -64.72174)
		(end 239.460278 -64.671956)
		(width 0.13208)
		(layer "F.Cu")
		(net "P12V_SSD8_PG_G2")
	)
	(segment
		(start 239.550194 -64.58204)
		(end 239.460278 -64.671956)
		(width 0.13208)
		(layer "F.Cu")
		(net "P12V_SSD8_PG_G2")
	)
	(segment
		(start 238.615982 -64.72174)
		(end 239.410494 -64.72174)
		(width 0.13208)
		(layer "F.Cu")
		(net "P12V_SSD8_PG_G2")
	)
	(segment
		(start 237.988348 -64.094106)
		(end 238.615982 -64.72174)
		(width 0.13208)
		(layer "F.Cu")
		(net "P12V_SSD8_PG_G2")
	)
	(via
		(at 237.988348 -63.450978)
		(size 0.508)
		(drill 0.254)
		(layers "F.Cu" "B.Cu")
		(net "P12V_SSD8_PG_G2")
	)
	(segment
		(start 304.473864 -71.908416)
		(end 304.473864 -72.366632)
		(width 0.13208)
		(layer "F.Cu")
		(net "P12V_SSD10_CO_MODE")
	)
	(segment
		(start 304.27549 -71.056754)
		(end 304.27549 -70.479158)
		(width 0.13208)
		(layer "F.Cu")
		(net "P12V_SSD10_CO_MODE")
	)
	(segment
		(start 303.77638 -71.555864)
		(end 304.121312 -71.555864)
		(width 0.13208)
		(layer "F.Cu")
		(net "P12V_SSD10_CO_MODE")
	)
	(segment
		(start 303.77638 -71.555864)
		(end 304.27549 -71.056754)
		(width 0.13208)
		(layer "F.Cu")
		(net "P12V_SSD10_CO_MODE")
	)
	(segment
		(start 303.457864 -72.366632)
		(end 304.473864 -72.366632)
		(width 0.13208)
		(layer "F.Cu")
		(net "P12V_SSD10_CO_MODE")
	)
	(segment
		(start 304.121312 -71.555864)
		(end 304.473864 -71.908416)
		(width 0.13208)
		(layer "F.Cu")
		(net "P12V_SSD10_CO_MODE")
	)
	(via
		(at 303.77638 -71.555864)
		(size 0.508)
		(drill 0.254)
		(layers "F.Cu" "B.Cu")
		(net "P12V_SSD10_CO_MODE")
	)
	(segment
		(start 279.489916 -72.366632)
		(end 279.489916 -71.827898)
		(width 0.13208)
		(layer "F.Cu")
		(net "P12V_SSD9_CO_ILIMIT")
	)
	(segment
		(start 279.489916 -71.827898)
		(end 279.285446 -71.623428)
		(width 0.13208)
		(layer "F.Cu")
		(net "P12V_SSD9_CO_ILIMIT")
	)
	(segment
		(start 278.775414 -71.113396)
		(end 278.775414 -70.479158)
		(width 0.13208)
		(layer "F.Cu")
		(net "P12V_SSD9_CO_ILIMIT")
	)
	(segment
		(start 279.285446 -71.623428)
		(end 278.775414 -71.113396)
		(width 0.13208)
		(layer "F.Cu")
		(net "P12V_SSD9_CO_ILIMIT")
	)
	(via
		(at 279.285446 -71.623428)
		(size 0.508)
		(drill 0.254)
		(layers "F.Cu" "B.Cu")
		(net "P12V_SSD9_CO_ILIMIT")
	)
	(segment
		(start 330.12126 -71.555864)
		(end 329.776328 -71.555864)
		(width 0.13208)
		(layer "F.Cu")
		(net "P12V_SSD11_CO_MODE")
	)
	(segment
		(start 330.473812 -72.366632)
		(end 330.473812 -71.908416)
		(width 0.13208)
		(layer "F.Cu")
		(net "P12V_SSD11_CO_MODE")
	)
	(segment
		(start 330.275438 -71.056754)
		(end 330.275438 -70.479158)
		(width 0.13208)
		(layer "F.Cu")
		(net "P12V_SSD11_CO_MODE")
	)
	(segment
		(start 329.457812 -72.366632)
		(end 330.473812 -72.366632)
		(width 0.13208)
		(layer "F.Cu")
		(net "P12V_SSD11_CO_MODE")
	)
	(segment
		(start 329.776328 -71.555864)
		(end 330.275438 -71.056754)
		(width 0.13208)
		(layer "F.Cu")
		(net "P12V_SSD11_CO_MODE")
	)
	(segment
		(start 330.473812 -71.908416)
		(end 330.12126 -71.555864)
		(width 0.13208)
		(layer "F.Cu")
		(net "P12V_SSD11_CO_MODE")
	)
	(via
		(at 329.776328 -71.555864)
		(size 0.508)
		(drill 0.254)
		(layers "F.Cu" "B.Cu")
		(net "P12V_SSD11_CO_MODE")
	)
	(segment
		(start 253.489968 -71.827898)
		(end 253.285498 -71.623428)
		(width 0.13208)
		(layer "F.Cu")
		(net "P12V_SSD8_CO_ILIMIT")
	)
	(segment
		(start 252.775466 -71.113396)
		(end 252.775466 -70.479158)
		(width 0.13208)
		(layer "F.Cu")
		(net "P12V_SSD8_CO_ILIMIT")
	)
	(segment
		(start 253.285498 -71.623428)
		(end 252.775466 -71.113396)
		(width 0.13208)
		(layer "F.Cu")
		(net "P12V_SSD8_CO_ILIMIT")
	)
	(segment
		(start 253.489968 -72.366632)
		(end 253.489968 -71.827898)
		(width 0.13208)
		(layer "F.Cu")
		(net "P12V_SSD8_CO_ILIMIT")
	)
	(via
		(at 253.285498 -71.623428)
		(size 0.508)
		(drill 0.254)
		(layers "F.Cu" "B.Cu")
		(net "P12V_SSD8_CO_ILIMIT")
	)
	(segment
		(start 253.927356 -67.228212)
		(end 253.730506 -67.031362)
		(width 0.13208)
		(layer "F.Cu")
		(net "P12V_SSD8_CO_DV_DT")
	)
	(segment
		(start 253.275338 -68.244974)
		(end 253.927356 -67.592956)
		(width 0.13208)
		(layer "F.Cu")
		(net "P12V_SSD8_CO_DV_DT")
	)
	(segment
		(start 253.730506 -67.031362)
		(end 253.730506 -66.72199)
		(width 0.13208)
		(layer "F.Cu")
		(net "P12V_SSD8_CO_DV_DT")
	)
	(segment
		(start 253.275338 -68.479162)
		(end 253.275338 -68.244974)
		(width 0.13208)
		(layer "F.Cu")
		(net "P12V_SSD8_CO_DV_DT")
	)
	(segment
		(start 253.927356 -67.592956)
		(end 253.927356 -67.228212)
		(width 0.13208)
		(layer "F.Cu")
		(net "P12V_SSD8_CO_DV_DT")
	)
	(via
		(at 253.927356 -67.592956)
		(size 0.508)
		(drill 0.254)
		(layers "F.Cu" "B.Cu")
		(net "P12V_SSD8_CO_DV_DT")
	)
	(segment
		(start 278.275542 -68.479162)
		(end 278.275542 -67.96405)
		(width 0.13208)
		(layer "F.Cu")
		(net "P12V_SSD9_CO_GATE")
	)
	(segment
		(start 277.361142 -67.488054)
		(end 277.698454 -67.150742)
		(width 0.13208)
		(layer "F.Cu")
		(net "P12V_SSD9_CO_GATE")
	)
	(segment
		(start 278.098758 -67.787266)
		(end 277.660354 -67.787266)
		(width 0.13208)
		(layer "F.Cu")
		(net "P12V_SSD9_CO_GATE")
	)
	(segment
		(start 277.698454 -67.150742)
		(end 277.698454 -66.72199)
		(width 0.13208)
		(layer "F.Cu")
		(net "P12V_SSD9_CO_GATE")
	)
	(segment
		(start 278.275542 -67.96405)
		(end 278.098758 -67.787266)
		(width 0.13208)
		(layer "F.Cu")
		(net "P12V_SSD9_CO_GATE")
	)
	(segment
		(start 277.660354 -67.787266)
		(end 277.361142 -67.488054)
		(width 0.13208)
		(layer "F.Cu")
		(net "P12V_SSD9_CO_GATE")
	)
	(via
		(at 277.361142 -67.488054)
		(size 0.508)
		(drill 0.254)
		(layers "F.Cu" "B.Cu")
		(net "P12V_SSD9_CO_GATE")
	)
	(segment
		(start 251.361194 -67.488054)
		(end 251.698506 -67.150742)
		(width 0.13208)
		(layer "F.Cu")
		(net "P12V_SSD8_CO_GATE")
	)
	(segment
		(start 251.660406 -67.787266)
		(end 251.361194 -67.488054)
		(width 0.13208)
		(layer "F.Cu")
		(net "P12V_SSD8_CO_GATE")
	)
	(segment
		(start 251.698506 -67.150742)
		(end 251.698506 -66.72199)
		(width 0.13208)
		(layer "F.Cu")
		(net "P12V_SSD8_CO_GATE")
	)
	(segment
		(start 252.275594 -67.96405)
		(end 252.09881 -67.787266)
		(width 0.13208)
		(layer "F.Cu")
		(net "P12V_SSD8_CO_GATE")
	)
	(segment
		(start 252.275594 -68.479162)
		(end 252.275594 -67.96405)
		(width 0.13208)
		(layer "F.Cu")
		(net "P12V_SSD8_CO_GATE")
	)
	(segment
		(start 252.09881 -67.787266)
		(end 251.660406 -67.787266)
		(width 0.13208)
		(layer "F.Cu")
		(net "P12V_SSD8_CO_GATE")
	)
	(via
		(at 251.361194 -67.488054)
		(size 0.508)
		(drill 0.254)
		(layers "F.Cu" "B.Cu")
		(net "P12V_SSD8_CO_GATE")
	)
	(segment
		(start 395.927834 -35.876738)
		(end 394.955268 -35.876738)
		(width 0.13208)
		(layer "F.Cu")
		(net "PWRGD_P3V3_SSD14_D")
	)
	(segment
		(start 395.295882 -36.50996)
		(end 394.955268 -36.169346)
		(width 0.13208)
		(layer "F.Cu")
		(net "PWRGD_P3V3_SSD14_D")
	)
	(segment
		(start 395.36116 -37.201094)
		(end 395.295882 -37.135816)
		(width 0.13208)
		(layer "F.Cu")
		(net "PWRGD_P3V3_SSD14_D")
	)
	(segment
		(start 395.295882 -37.135816)
		(end 395.295882 -36.50996)
		(width 0.13208)
		(layer "F.Cu")
		(net "PWRGD_P3V3_SSD14_D")
	)
	(segment
		(start 394.955268 -36.169346)
		(end 394.955268 -35.876738)
		(width 0.13208)
		(layer "F.Cu")
		(net "PWRGD_P3V3_SSD14_D")
	)
	(via
		(at 395.295882 -36.50996)
		(size 0.508)
		(drill 0.254)
		(layers "F.Cu" "B.Cu")
		(net "PWRGD_P3V3_SSD14_D")
	)
	(segment
		(start 331.489812 -72.366632)
		(end 331.489812 -71.827898)
		(width 0.13208)
		(layer "F.Cu")
		(net "P12V_SSD11_CO_ILIMIT")
	)
	(segment
		(start 331.489812 -71.827898)
		(end 331.285342 -71.623428)
		(width 0.13208)
		(layer "F.Cu")
		(net "P12V_SSD11_CO_ILIMIT")
	)
	(segment
		(start 330.77531 -71.113396)
		(end 330.77531 -70.479158)
		(width 0.13208)
		(layer "F.Cu")
		(net "P12V_SSD11_CO_ILIMIT")
	)
	(segment
		(start 331.285342 -71.623428)
		(end 330.77531 -71.113396)
		(width 0.13208)
		(layer "F.Cu")
		(net "P12V_SSD11_CO_ILIMIT")
	)
	(via
		(at 331.285342 -71.623428)
		(size 0.508)
		(drill 0.254)
		(layers "F.Cu" "B.Cu")
		(net "P12V_SSD11_CO_ILIMIT")
	)
	(segment
		(start 369.295934 -36.50996)
		(end 368.95532 -36.169346)
		(width 0.13208)
		(layer "F.Cu")
		(net "PWRGD_P3V3_SSD13_D")
	)
	(segment
		(start 369.361212 -37.201094)
		(end 369.295934 -37.135816)
		(width 0.13208)
		(layer "F.Cu")
		(net "PWRGD_P3V3_SSD13_D")
	)
	(segment
		(start 368.95532 -36.169346)
		(end 368.95532 -35.876738)
		(width 0.13208)
		(layer "F.Cu")
		(net "PWRGD_P3V3_SSD13_D")
	)
	(segment
		(start 369.927886 -35.876738)
		(end 368.95532 -35.876738)
		(width 0.13208)
		(layer "F.Cu")
		(net "PWRGD_P3V3_SSD13_D")
	)
	(segment
		(start 369.295934 -37.135816)
		(end 369.295934 -36.50996)
		(width 0.13208)
		(layer "F.Cu")
		(net "PWRGD_P3V3_SSD13_D")
	)
	(via
		(at 369.295934 -36.50996)
		(size 0.508)
		(drill 0.254)
		(layers "F.Cu" "B.Cu")
		(net "PWRGD_P3V3_SSD13_D")
	)
	(segment
		(start 251.776484 -71.555864)
		(end 252.275594 -71.056754)
		(width 0.13208)
		(layer "F.Cu")
		(net "P12V_SSD8_CO_MODE")
	)
	(segment
		(start 252.473968 -72.366632)
		(end 252.473968 -71.908416)
		(width 0.13208)
		(layer "F.Cu")
		(net "P12V_SSD8_CO_MODE")
	)
	(segment
		(start 252.275594 -71.056754)
		(end 252.275594 -70.479158)
		(width 0.13208)
		(layer "F.Cu")
		(net "P12V_SSD8_CO_MODE")
	)
	(segment
		(start 251.457968 -72.366632)
		(end 252.473968 -72.366632)
		(width 0.13208)
		(layer "F.Cu")
		(net "P12V_SSD8_CO_MODE")
	)
	(segment
		(start 252.473968 -71.908416)
		(end 252.121416 -71.555864)
		(width 0.13208)
		(layer "F.Cu")
		(net "P12V_SSD8_CO_MODE")
	)
	(segment
		(start 252.121416 -71.555864)
		(end 251.776484 -71.555864)
		(width 0.13208)
		(layer "F.Cu")
		(net "P12V_SSD8_CO_MODE")
	)
	(via
		(at 251.776484 -71.555864)
		(size 0.508)
		(drill 0.254)
		(layers "F.Cu" "B.Cu")
		(net "P12V_SSD8_CO_MODE")
	)
	(segment
		(start 342.955372 -36.169346)
		(end 343.295986 -36.50996)
		(width 0.13208)
		(layer "F.Cu")
		(net "PWRGD_P3V3_SSD12_D")
	)
	(segment
		(start 343.295986 -36.50996)
		(end 343.295986 -37.135816)
		(width 0.13208)
		(layer "F.Cu")
		(net "PWRGD_P3V3_SSD12_D")
	)
	(segment
		(start 343.295986 -37.135816)
		(end 343.361264 -37.201094)
		(width 0.13208)
		(layer "F.Cu")
		(net "PWRGD_P3V3_SSD12_D")
	)
	(segment
		(start 343.927938 -35.876738)
		(end 342.955372 -35.876738)
		(width 0.13208)
		(layer "F.Cu")
		(net "PWRGD_P3V3_SSD12_D")
	)
	(segment
		(start 342.955372 -35.876738)
		(end 342.955372 -36.169346)
		(width 0.13208)
		(layer "F.Cu")
		(net "PWRGD_P3V3_SSD12_D")
	)
	(via
		(at 343.295986 -36.50996)
		(size 0.508)
		(drill 0.254)
		(layers "F.Cu" "B.Cu")
		(net "PWRGD_P3V3_SSD12_D")
	)
	(segment
		(start 287.475168 -64.102234)
		(end 287.475168 -63.086234)
		(width 0.13208)
		(layer "F.Cu")
		(net "P12V_SSD10_PG_G1")
	)
	(segment
		(start 288.158682 -63.273432)
		(end 288.089594 -63.273432)
		(width 0.13208)
		(layer "F.Cu")
		(net "P12V_SSD10_PG_G1")
	)
	(segment
		(start 288.44748 -63.56223)
		(end 288.158682 -63.273432)
		(width 0.13208)
		(layer "F.Cu")
		(net "P12V_SSD10_PG_G1")
	)
	(segment
		(start 287.902396 -63.086234)
		(end 287.475168 -63.086234)
		(width 0.13208)
		(layer "F.Cu")
		(net "P12V_SSD10_PG_G1")
	)
	(segment
		(start 288.88944 -63.56223)
		(end 288.44748 -63.56223)
		(width 0.13208)
		(layer "F.Cu")
		(net "P12V_SSD10_PG_G1")
	)
	(segment
		(start 288.089594 -63.273432)
		(end 287.902396 -63.086234)
		(width 0.13208)
		(layer "F.Cu")
		(net "P12V_SSD10_PG_G1")
	)
	(via
		(at 288.158682 -63.273432)
		(size 0.508)
		(drill 0.254)
		(layers "F.Cu" "B.Cu")
		(net "P12V_SSD10_PG_G1")
	)
	(segment
		(start 421.927782 -35.876738)
		(end 420.955216 -35.876738)
		(width 0.13208)
		(layer "F.Cu")
		(net "PWRGD_P3V3_SSD15_D")
	)
	(segment
		(start 421.29583 -36.50996)
		(end 420.955216 -36.169346)
		(width 0.13208)
		(layer "F.Cu")
		(net "PWRGD_P3V3_SSD15_D")
	)
	(segment
		(start 421.29583 -37.135816)
		(end 421.29583 -36.50996)
		(width 0.13208)
		(layer "F.Cu")
		(net "PWRGD_P3V3_SSD15_D")
	)
	(segment
		(start 421.361108 -37.201094)
		(end 421.29583 -37.135816)
		(width 0.13208)
		(layer "F.Cu")
		(net "PWRGD_P3V3_SSD15_D")
	)
	(segment
		(start 420.955216 -36.169346)
		(end 420.955216 -35.876738)
		(width 0.13208)
		(layer "F.Cu")
		(net "PWRGD_P3V3_SSD15_D")
	)
	(via
		(at 421.29583 -36.50996)
		(size 0.508)
		(drill 0.254)
		(layers "F.Cu" "B.Cu")
		(net "PWRGD_P3V3_SSD15_D")
	)
	(segment
		(start 317.91021 -63.652146)
		(end 317.820294 -63.56223)
		(width 0.13208)
		(layer "F.Cu")
		(net "P12V_SSD11_PG_G2")
	)
	(segment
		(start 316.689232 -65.124076)
		(end 317.33236 -65.124076)
		(width 0.13208)
		(layer "F.Cu")
		(net "P12V_SSD11_PG_G2")
	)
	(segment
		(start 317.820294 -63.56223)
		(end 316.689232 -63.56223)
		(width 0.13208)
		(layer "F.Cu")
		(net "P12V_SSD11_PG_G2")
	)
	(segment
		(start 317.959994 -63.70193)
		(end 317.91021 -63.652146)
		(width 0.13208)
		(layer "F.Cu")
		(net "P12V_SSD11_PG_G2")
	)
	(segment
		(start 316.689232 -64.312292)
		(end 316.689232 -65.124076)
		(width 0.13208)
		(layer "F.Cu")
		(net "P12V_SSD11_PG_G2")
	)
	(segment
		(start 317.33236 -65.124076)
		(end 317.959994 -64.496442)
		(width 0.13208)
		(layer "F.Cu")
		(net "P12V_SSD11_PG_G2")
	)
	(segment
		(start 317.959994 -64.496442)
		(end 317.959994 -63.70193)
		(width 0.13208)
		(layer "F.Cu")
		(net "P12V_SSD11_PG_G2")
	)
	(via
		(at 316.689232 -65.124076)
		(size 0.508)
		(drill 0.254)
		(layers "F.Cu" "B.Cu")
		(net "P12V_SSD11_PG_G2")
	)
	(segment
		(start 279.195784 -37.135816)
		(end 279.195784 -36.50996)
		(width 0.13208)
		(layer "F.Cu")
		(net "PWRGD_P3V3_SSD10_D")
	)
	(segment
		(start 279.827736 -35.876738)
		(end 278.85517 -35.876738)
		(width 0.13208)
		(layer "F.Cu")
		(net "PWRGD_P3V3_SSD10_D")
	)
	(segment
		(start 278.85517 -36.169346)
		(end 278.85517 -35.876738)
		(width 0.13208)
		(layer "F.Cu")
		(net "PWRGD_P3V3_SSD10_D")
	)
	(segment
		(start 279.195784 -36.50996)
		(end 278.85517 -36.169346)
		(width 0.13208)
		(layer "F.Cu")
		(net "PWRGD_P3V3_SSD10_D")
	)
	(segment
		(start 279.261062 -37.201094)
		(end 279.195784 -37.135816)
		(width 0.13208)
		(layer "F.Cu")
		(net "PWRGD_P3V3_SSD10_D")
	)
	(via
		(at 279.195784 -36.50996)
		(size 0.508)
		(drill 0.254)
		(layers "F.Cu" "B.Cu")
		(net "PWRGD_P3V3_SSD10_D")
	)
	(segment
		(start 313.475116 -64.102234)
		(end 313.475116 -63.086234)
		(width 0.13208)
		(layer "F.Cu")
		(net "P12V_SSD11_PG_G1")
	)
	(segment
		(start 314.447428 -63.56223)
		(end 314.15863 -63.273432)
		(width 0.13208)
		(layer "F.Cu")
		(net "P12V_SSD11_PG_G1")
	)
	(segment
		(start 314.089542 -63.273432)
		(end 313.902344 -63.086234)
		(width 0.13208)
		(layer "F.Cu")
		(net "P12V_SSD11_PG_G1")
	)
	(segment
		(start 314.15863 -63.273432)
		(end 314.089542 -63.273432)
		(width 0.13208)
		(layer "F.Cu")
		(net "P12V_SSD11_PG_G1")
	)
	(segment
		(start 313.902344 -63.086234)
		(end 313.475116 -63.086234)
		(width 0.13208)
		(layer "F.Cu")
		(net "P12V_SSD11_PG_G1")
	)
	(segment
		(start 314.889388 -63.56223)
		(end 314.447428 -63.56223)
		(width 0.13208)
		(layer "F.Cu")
		(net "P12V_SSD11_PG_G1")
	)
	(via
		(at 314.15863 -63.273432)
		(size 0.508)
		(drill 0.254)
		(layers "F.Cu" "B.Cu")
		(net "P12V_SSD11_PG_G1")
	)
	(segment
		(start 227.195888 -37.135816)
		(end 227.195888 -36.50996)
		(width 0.13208)
		(layer "F.Cu")
		(net "PWRGD_P3V3_SSD8_D")
	)
	(segment
		(start 227.195888 -36.50996)
		(end 226.855274 -36.169346)
		(width 0.13208)
		(layer "F.Cu")
		(net "PWRGD_P3V3_SSD8_D")
	)
	(segment
		(start 227.82784 -35.876738)
		(end 226.855274 -35.876738)
		(width 0.13208)
		(layer "F.Cu")
		(net "PWRGD_P3V3_SSD8_D")
	)
	(segment
		(start 227.261166 -37.201094)
		(end 227.195888 -37.135816)
		(width 0.13208)
		(layer "F.Cu")
		(net "PWRGD_P3V3_SSD8_D")
	)
	(segment
		(start 226.855274 -36.169346)
		(end 226.855274 -35.876738)
		(width 0.13208)
		(layer "F.Cu")
		(net "PWRGD_P3V3_SSD8_D")
	)
	(via
		(at 227.195888 -36.50996)
		(size 0.508)
		(drill 0.254)
		(layers "F.Cu" "B.Cu")
		(net "PWRGD_P3V3_SSD8_D")
	)
	(segment
		(start 304.775362 -67.970146)
		(end 304.653188 -67.847972)
		(width 0.13208)
		(layer "F.Cu")
		(net "P12V_SSD10_CO_EN")
	)
	(segment
		(start 304.775362 -68.479162)
		(end 304.775362 -67.970146)
		(width 0.13208)
		(layer "F.Cu")
		(net "P12V_SSD10_CO_EN")
	)
	(segment
		(start 304.653188 -67.537584)
		(end 304.653188 -67.077844)
		(width 0.13208)
		(layer "F.Cu")
		(net "P12V_SSD10_CO_EN")
	)
	(segment
		(start 304.714402 -67.01663)
		(end 304.714402 -66.72199)
		(width 0.13208)
		(layer "F.Cu")
		(net "P12V_SSD10_CO_EN")
	)
	(segment
		(start 304.653188 -67.077844)
		(end 304.714402 -67.01663)
		(width 0.13208)
		(layer "F.Cu")
		(net "P12V_SSD10_CO_EN")
	)
	(segment
		(start 304.653188 -67.847972)
		(end 304.653188 -67.537584)
		(width 0.13208)
		(layer "F.Cu")
		(net "P12V_SSD10_CO_EN")
	)
	(via
		(at 304.653188 -67.537584)
		(size 0.508)
		(drill 0.254)
		(layers "F.Cu" "B.Cu")
		(net "P12V_SSD10_CO_EN")
	)
	(segment
		(start 252.855222 -36.169346)
		(end 252.855222 -35.876738)
		(width 0.13208)
		(layer "F.Cu")
		(net "PWRGD_P3V3_SSD9_D")
	)
	(segment
		(start 253.195836 -36.50996)
		(end 252.855222 -36.169346)
		(width 0.13208)
		(layer "F.Cu")
		(net "PWRGD_P3V3_SSD9_D")
	)
	(segment
		(start 253.261114 -37.201094)
		(end 253.195836 -37.135816)
		(width 0.13208)
		(layer "F.Cu")
		(net "PWRGD_P3V3_SSD9_D")
	)
	(segment
		(start 253.195836 -37.135816)
		(end 253.195836 -36.50996)
		(width 0.13208)
		(layer "F.Cu")
		(net "PWRGD_P3V3_SSD9_D")
	)
	(segment
		(start 253.827788 -35.876738)
		(end 252.855222 -35.876738)
		(width 0.13208)
		(layer "F.Cu")
		(net "PWRGD_P3V3_SSD9_D")
	)
	(via
		(at 253.195836 -36.50996)
		(size 0.508)
		(drill 0.254)
		(layers "F.Cu" "B.Cu")
		(net "PWRGD_P3V3_SSD9_D")
	)
	(segment
		(start 331.275182 -68.479162)
		(end 331.275182 -68.244974)
		(width 0.13208)
		(layer "F.Cu")
		(net "P12V_SSD11_CO_DV_DT")
	)
	(segment
		(start 331.73035 -67.031362)
		(end 331.73035 -66.72199)
		(width 0.13208)
		(layer "F.Cu")
		(net "P12V_SSD11_CO_DV_DT")
	)
	(segment
		(start 331.9272 -67.592956)
		(end 331.9272 -67.228212)
		(width 0.13208)
		(layer "F.Cu")
		(net "P12V_SSD11_CO_DV_DT")
	)
	(segment
		(start 331.9272 -67.228212)
		(end 331.73035 -67.031362)
		(width 0.13208)
		(layer "F.Cu")
		(net "P12V_SSD11_CO_DV_DT")
	)
	(segment
		(start 331.275182 -68.244974)
		(end 331.9272 -67.592956)
		(width 0.13208)
		(layer "F.Cu")
		(net "P12V_SSD11_CO_DV_DT")
	)
	(via
		(at 331.9272 -67.592956)
		(size 0.508)
		(drill 0.254)
		(layers "F.Cu" "B.Cu")
		(net "P12V_SSD11_CO_DV_DT")
	)
	(segment
		(start 305.195732 -36.50996)
		(end 304.855118 -36.169346)
		(width 0.13208)
		(layer "F.Cu")
		(net "PWRGD_P3V3_SSD11_D")
	)
	(segment
		(start 305.195732 -37.135816)
		(end 305.195732 -36.50996)
		(width 0.13208)
		(layer "F.Cu")
		(net "PWRGD_P3V3_SSD11_D")
	)
	(segment
		(start 305.26101 -37.201094)
		(end 305.195732 -37.135816)
		(width 0.13208)
		(layer "F.Cu")
		(net "PWRGD_P3V3_SSD11_D")
	)
	(segment
		(start 305.827684 -35.876738)
		(end 304.855118 -35.876738)
		(width 0.13208)
		(layer "F.Cu")
		(net "PWRGD_P3V3_SSD11_D")
	)
	(segment
		(start 304.855118 -36.169346)
		(end 304.855118 -35.876738)
		(width 0.13208)
		(layer "F.Cu")
		(net "PWRGD_P3V3_SSD11_D")
	)
	(via
		(at 305.195732 -36.50996)
		(size 0.508)
		(drill 0.254)
		(layers "F.Cu" "B.Cu")
		(net "PWRGD_P3V3_SSD11_D")
	)
	(segment
		(start 149.23262 -65.124076)
		(end 149.860254 -64.496442)
		(width 0.13208)
		(layer "F.Cu")
		(net "P12V_SSD5_PG_G2")
	)
	(segment
		(start 149.720554 -63.56223)
		(end 149.81047 -63.652146)
		(width 0.13208)
		(layer "F.Cu")
		(net "P12V_SSD5_PG_G2")
	)
	(segment
		(start 148.589492 -64.312292)
		(end 148.589492 -65.124076)
		(width 0.13208)
		(layer "F.Cu")
		(net "P12V_SSD5_PG_G2")
	)
	(segment
		(start 148.589492 -63.56223)
		(end 149.720554 -63.56223)
		(width 0.13208)
		(layer "F.Cu")
		(net "P12V_SSD5_PG_G2")
	)
	(segment
		(start 149.860254 -64.496442)
		(end 149.860254 -63.70193)
		(width 0.13208)
		(layer "F.Cu")
		(net "P12V_SSD5_PG_G2")
	)
	(segment
		(start 149.860254 -63.70193)
		(end 149.81047 -63.652146)
		(width 0.13208)
		(layer "F.Cu")
		(net "P12V_SSD5_PG_G2")
	)
	(segment
		(start 148.589492 -65.124076)
		(end 149.23262 -65.124076)
		(width 0.13208)
		(layer "F.Cu")
		(net "P12V_SSD5_PG_G2")
	)
	(via
		(at 148.589492 -65.124076)
		(size 0.508)
		(drill 0.254)
		(layers "F.Cu" "B.Cu")
		(net "P12V_SSD5_PG_G2")
	)
	(segment
		(start 305.489864 -71.827898)
		(end 305.285394 -71.623428)
		(width 0.13208)
		(layer "F.Cu")
		(net "P12V_SSD10_CO_ILIMIT")
	)
	(segment
		(start 304.775362 -71.113396)
		(end 304.775362 -70.479158)
		(width 0.13208)
		(layer "F.Cu")
		(net "P12V_SSD10_CO_ILIMIT")
	)
	(segment
		(start 305.489864 -72.366632)
		(end 305.489864 -71.827898)
		(width 0.13208)
		(layer "F.Cu")
		(net "P12V_SSD10_CO_ILIMIT")
	)
	(segment
		(start 305.285394 -71.623428)
		(end 304.775362 -71.113396)
		(width 0.13208)
		(layer "F.Cu")
		(net "P12V_SSD10_CO_ILIMIT")
	)
	(via
		(at 305.285394 -71.623428)
		(size 0.508)
		(drill 0.254)
		(layers "F.Cu" "B.Cu")
		(net "P12V_SSD10_CO_ILIMIT")
	)
	(segment
		(start 136.755378 -36.169346)
		(end 137.095992 -36.50996)
		(width 0.13208)
		(layer "F.Cu")
		(net "PWRGD_P3V3_SSD5_D")
	)
	(segment
		(start 137.727944 -35.876738)
		(end 136.755378 -35.876738)
		(width 0.13208)
		(layer "F.Cu")
		(net "PWRGD_P3V3_SSD5_D")
	)
	(segment
		(start 136.755378 -35.876738)
		(end 136.755378 -36.169346)
		(width 0.13208)
		(layer "F.Cu")
		(net "PWRGD_P3V3_SSD5_D")
	)
	(segment
		(start 137.095992 -36.50996)
		(end 137.095992 -37.135816)
		(width 0.13208)
		(layer "F.Cu")
		(net "PWRGD_P3V3_SSD5_D")
	)
	(segment
		(start 137.095992 -37.135816)
		(end 137.16127 -37.201094)
		(width 0.13208)
		(layer "F.Cu")
		(net "PWRGD_P3V3_SSD5_D")
	)
	(via
		(at 137.095992 -36.50996)
		(size 0.508)
		(drill 0.254)
		(layers "F.Cu" "B.Cu")
		(net "PWRGD_P3V3_SSD5_D")
	)
	(segment
		(start 162.02152 -71.555864)
		(end 161.676588 -71.555864)
		(width 0.13208)
		(layer "F.Cu")
		(net "P12V_SSD5_CO_MODE")
	)
	(segment
		(start 161.358072 -72.366632)
		(end 162.374072 -72.366632)
		(width 0.13208)
		(layer "F.Cu")
		(net "P12V_SSD5_CO_MODE")
	)
	(segment
		(start 162.175698 -71.056754)
		(end 161.676588 -71.555864)
		(width 0.13208)
		(layer "F.Cu")
		(net "P12V_SSD5_CO_MODE")
	)
	(segment
		(start 162.374072 -72.366632)
		(end 162.374072 -71.908416)
		(width 0.13208)
		(layer "F.Cu")
		(net "P12V_SSD5_CO_MODE")
	)
	(segment
		(start 162.175698 -70.479158)
		(end 162.175698 -71.056754)
		(width 0.13208)
		(layer "F.Cu")
		(net "P12V_SSD5_CO_MODE")
	)
	(segment
		(start 162.374072 -71.908416)
		(end 162.02152 -71.555864)
		(width 0.13208)
		(layer "F.Cu")
		(net "P12V_SSD5_CO_MODE")
	)
	(via
		(at 161.676588 -71.555864)
		(size 0.508)
		(drill 0.254)
		(layers "F.Cu" "B.Cu")
		(net "P12V_SSD5_CO_MODE")
	)
	(segment
		(start 163.09594 -37.135816)
		(end 163.09594 -36.50996)
		(width 0.13208)
		(layer "F.Cu")
		(net "PWRGD_P3V3_SSD6_D")
	)
	(segment
		(start 163.09594 -36.50996)
		(end 162.755326 -36.169346)
		(width 0.13208)
		(layer "F.Cu")
		(net "PWRGD_P3V3_SSD6_D")
	)
	(segment
		(start 163.727892 -35.876738)
		(end 162.755326 -35.876738)
		(width 0.13208)
		(layer "F.Cu")
		(net "PWRGD_P3V3_SSD6_D")
	)
	(segment
		(start 162.755326 -36.169346)
		(end 162.755326 -35.876738)
		(width 0.13208)
		(layer "F.Cu")
		(net "PWRGD_P3V3_SSD6_D")
	)
	(segment
		(start 163.161218 -37.201094)
		(end 163.09594 -37.135816)
		(width 0.13208)
		(layer "F.Cu")
		(net "PWRGD_P3V3_SSD6_D")
	)
	(via
		(at 163.09594 -36.50996)
		(size 0.508)
		(drill 0.254)
		(layers "F.Cu" "B.Cu")
		(net "PWRGD_P3V3_SSD6_D")
	)
	(segment
		(start 111.727996 -35.878008)
		(end 111.727996 -35.876738)
		(width 0.13208)
		(layer "F.Cu")
		(net "PWRGD_P3V3_SSD4_D")
	)
	(segment
		(start 111.096044 -36.50996)
		(end 111.096044 -37.135816)
		(width 0.13208)
		(layer "F.Cu")
		(net "PWRGD_P3V3_SSD4_D")
	)
	(segment
		(start 110.75543 -35.876738)
		(end 110.75543 -36.169346)
		(width 0.13208)
		(layer "F.Cu")
		(net "PWRGD_P3V3_SSD4_D")
	)
	(segment
		(start 110.75543 -36.169346)
		(end 111.096044 -36.50996)
		(width 0.13208)
		(layer "F.Cu")
		(net "PWRGD_P3V3_SSD4_D")
	)
	(segment
		(start 111.096044 -37.135816)
		(end 111.161322 -37.201094)
		(width 0.13208)
		(layer "F.Cu")
		(net "PWRGD_P3V3_SSD4_D")
	)
	(segment
		(start 111.096044 -36.50996)
		(end 111.727996 -35.878008)
		(width 0.13208)
		(layer "F.Cu")
		(net "PWRGD_P3V3_SSD4_D")
	)
	(via
		(at 111.096044 -36.50996)
		(size 0.508)
		(drill 0.254)
		(layers "F.Cu" "B.Cu")
		(net "PWRGD_P3V3_SSD4_D")
	)
	(segment
		(start 136.553448 -67.847972)
		(end 136.553448 -67.537584)
		(width 0.13208)
		(layer "F.Cu")
		(net "P12V_SSD4_CO_EN")
	)
	(segment
		(start 136.675622 -68.479162)
		(end 136.675622 -67.970146)
		(width 0.13208)
		(layer "F.Cu")
		(net "P12V_SSD4_CO_EN")
	)
	(segment
		(start 136.614662 -67.01663)
		(end 136.614662 -66.72199)
		(width 0.13208)
		(layer "F.Cu")
		(net "P12V_SSD4_CO_EN")
	)
	(segment
		(start 136.553448 -67.077844)
		(end 136.614662 -67.01663)
		(width 0.13208)
		(layer "F.Cu")
		(net "P12V_SSD4_CO_EN")
	)
	(segment
		(start 136.553448 -67.537584)
		(end 136.553448 -67.077844)
		(width 0.13208)
		(layer "F.Cu")
		(net "P12V_SSD4_CO_EN")
	)
	(segment
		(start 136.675622 -67.970146)
		(end 136.553448 -67.847972)
		(width 0.13208)
		(layer "F.Cu")
		(net "P12V_SSD4_CO_EN")
	)
	(via
		(at 136.553448 -67.537584)
		(size 0.508)
		(drill 0.254)
		(layers "F.Cu" "B.Cu")
		(net "P12V_SSD4_CO_EN")
	)
	(segment
		(start 189.095888 -36.50996)
		(end 188.755274 -36.169346)
		(width 0.13208)
		(layer "F.Cu")
		(net "PWRGD_P3V3_SSD7_D")
	)
	(segment
		(start 189.72784 -35.876738)
		(end 188.755274 -35.876738)
		(width 0.13208)
		(layer "F.Cu")
		(net "PWRGD_P3V3_SSD7_D")
	)
	(segment
		(start 189.095888 -37.135816)
		(end 189.095888 -36.50996)
		(width 0.13208)
		(layer "F.Cu")
		(net "PWRGD_P3V3_SSD7_D")
	)
	(segment
		(start 188.755274 -36.169346)
		(end 188.755274 -35.876738)
		(width 0.13208)
		(layer "F.Cu")
		(net "PWRGD_P3V3_SSD7_D")
	)
	(segment
		(start 189.161166 -37.201094)
		(end 189.095888 -37.135816)
		(width 0.13208)
		(layer "F.Cu")
		(net "PWRGD_P3V3_SSD7_D")
	)
	(via
		(at 189.095888 -36.50996)
		(size 0.508)
		(drill 0.254)
		(layers "F.Cu" "B.Cu")
		(net "PWRGD_P3V3_SSD7_D")
	)
	(segment
		(start 188.614558 -67.01663)
		(end 188.614558 -66.72199)
		(width 0.13208)
		(layer "F.Cu")
		(net "P12V_SSD6_CO_EN")
	)
	(segment
		(start 188.553344 -67.847972)
		(end 188.553344 -67.537584)
		(width 0.13208)
		(layer "F.Cu")
		(net "P12V_SSD6_CO_EN")
	)
	(segment
		(start 188.553344 -67.537584)
		(end 188.553344 -67.077844)
		(width 0.13208)
		(layer "F.Cu")
		(net "P12V_SSD6_CO_EN")
	)
	(segment
		(start 188.675518 -67.970146)
		(end 188.553344 -67.847972)
		(width 0.13208)
		(layer "F.Cu")
		(net "P12V_SSD6_CO_EN")
	)
	(segment
		(start 188.675518 -68.479162)
		(end 188.675518 -67.970146)
		(width 0.13208)
		(layer "F.Cu")
		(net "P12V_SSD6_CO_EN")
	)
	(segment
		(start 188.553344 -67.077844)
		(end 188.614558 -67.01663)
		(width 0.13208)
		(layer "F.Cu")
		(net "P12V_SSD6_CO_EN")
	)
	(via
		(at 188.553344 -67.537584)
		(size 0.508)
		(drill 0.254)
		(layers "F.Cu" "B.Cu")
		(net "P12V_SSD6_CO_EN")
	)
	(segment
		(start 119.375428 -63.086234)
		(end 119.802656 -63.086234)
		(width 0.13208)
		(layer "F.Cu")
		(net "P12V_SSD4_PG_G1")
	)
	(segment
		(start 119.989854 -63.273432)
		(end 120.058942 -63.273432)
		(width 0.13208)
		(layer "F.Cu")
		(net "P12V_SSD4_PG_G1")
	)
	(segment
		(start 119.802656 -63.086234)
		(end 119.989854 -63.273432)
		(width 0.13208)
		(layer "F.Cu")
		(net "P12V_SSD4_PG_G1")
	)
	(segment
		(start 119.375428 -64.102234)
		(end 119.375428 -63.086234)
		(width 0.13208)
		(layer "F.Cu")
		(net "P12V_SSD4_PG_G1")
	)
	(segment
		(start 120.058942 -63.273432)
		(end 120.34774 -63.56223)
		(width 0.13208)
		(layer "F.Cu")
		(net "P12V_SSD4_PG_G1")
	)
	(segment
		(start 120.34774 -63.56223)
		(end 120.7897 -63.56223)
		(width 0.13208)
		(layer "F.Cu")
		(net "P12V_SSD4_PG_G1")
	)
	(via
		(at 120.058942 -63.273432)
		(size 0.508)
		(drill 0.254)
		(layers "F.Cu" "B.Cu")
		(net "P12V_SSD4_PG_G1")
	)
	(segment
		(start 161.59861 -67.150742)
		(end 161.59861 -66.72199)
		(width 0.13208)
		(layer "F.Cu")
		(net "P12V_SSD5_CO_GATE")
	)
	(segment
		(start 162.175698 -68.479162)
		(end 162.175698 -67.96405)
		(width 0.13208)
		(layer "F.Cu")
		(net "P12V_SSD5_CO_GATE")
	)
	(segment
		(start 161.261298 -67.488054)
		(end 161.59861 -67.150742)
		(width 0.13208)
		(layer "F.Cu")
		(net "P12V_SSD5_CO_GATE")
	)
	(segment
		(start 162.175698 -67.96405)
		(end 161.998914 -67.787266)
		(width 0.13208)
		(layer "F.Cu")
		(net "P12V_SSD5_CO_GATE")
	)
	(segment
		(start 161.998914 -67.787266)
		(end 161.56051 -67.787266)
		(width 0.13208)
		(layer "F.Cu")
		(net "P12V_SSD5_CO_GATE")
	)
	(segment
		(start 161.56051 -67.787266)
		(end 161.261298 -67.488054)
		(width 0.13208)
		(layer "F.Cu")
		(net "P12V_SSD5_CO_GATE")
	)
	(via
		(at 161.261298 -67.488054)
		(size 0.508)
		(drill 0.254)
		(layers "F.Cu" "B.Cu")
		(net "P12V_SSD5_CO_GATE")
	)
	(segment
		(start 214.675466 -71.113396)
		(end 214.675466 -70.479158)
		(width 0.13208)
		(layer "F.Cu")
		(net "P12V_SSD7_CO_ILIMIT")
	)
	(segment
		(start 215.389968 -71.827898)
		(end 215.185498 -71.623428)
		(width 0.13208)
		(layer "F.Cu")
		(net "P12V_SSD7_CO_ILIMIT")
	)
	(segment
		(start 215.389968 -72.366632)
		(end 215.389968 -71.827898)
		(width 0.13208)
		(layer "F.Cu")
		(net "P12V_SSD7_CO_ILIMIT")
	)
	(segment
		(start 215.185498 -71.623428)
		(end 214.675466 -71.113396)
		(width 0.13208)
		(layer "F.Cu")
		(net "P12V_SSD7_CO_ILIMIT")
	)
	(via
		(at 215.185498 -71.623428)
		(size 0.508)
		(drill 0.254)
		(layers "F.Cu" "B.Cu")
		(net "P12V_SSD7_CO_ILIMIT")
	)
	(segment
		(start 163.63061 -67.031362)
		(end 163.63061 -66.72199)
		(width 0.13208)
		(layer "F.Cu")
		(net "P12V_SSD5_CO_DV_DT")
	)
	(segment
		(start 163.82746 -67.592956)
		(end 163.82746 -67.228212)
		(width 0.13208)
		(layer "F.Cu")
		(net "P12V_SSD5_CO_DV_DT")
	)
	(segment
		(start 163.82746 -67.228212)
		(end 163.63061 -67.031362)
		(width 0.13208)
		(layer "F.Cu")
		(net "P12V_SSD5_CO_DV_DT")
	)
	(segment
		(start 163.175442 -68.244974)
		(end 163.175442 -68.479162)
		(width 0.13208)
		(layer "F.Cu")
		(net "P12V_SSD5_CO_DV_DT")
	)
	(segment
		(start 163.82746 -67.592956)
		(end 163.175442 -68.244974)
		(width 0.13208)
		(layer "F.Cu")
		(net "P12V_SSD5_CO_DV_DT")
	)
	(via
		(at 163.82746 -67.592956)
		(size 0.508)
		(drill 0.254)
		(layers "F.Cu" "B.Cu")
		(net "P12V_SSD5_CO_DV_DT")
	)
	(segment
		(start 358.369362 -117.327426)
		(end 358.369362 -117.943376)
		(width 0.13208)
		(layer "F.Cu")
		(net "PWRGD_P3V3_NIC6_D")
	)
	(segment
		(start 358.6353 -116.449348)
		(end 358.6353 -117.061488)
		(width 0.13208)
		(layer "F.Cu")
		(net "PWRGD_P3V3_NIC6_D")
	)
	(segment
		(start 359.385362 -117.943376)
		(end 358.369362 -117.943376)
		(width 0.13208)
		(layer "F.Cu")
		(net "PWRGD_P3V3_NIC6_D")
	)
	(segment
		(start 358.6353 -117.061488)
		(end 358.369362 -117.327426)
		(width 0.13208)
		(layer "F.Cu")
		(net "PWRGD_P3V3_NIC6_D")
	)
	(via
		(at 358.369362 -117.327426)
		(size 0.508)
		(drill 0.254)
		(layers "F.Cu" "B.Cu")
		(net "PWRGD_P3V3_NIC6_D")
	)
	(segment
		(start 335.146396 -118.76024)
		(end 335.412334 -119.026178)
		(width 0.13208)
		(layer "F.Cu")
		(net "PWRGD_P3V3_NIC5_D")
	)
	(segment
		(start 334.530446 -118.76024)
		(end 335.146396 -118.76024)
		(width 0.13208)
		(layer "F.Cu")
		(net "PWRGD_P3V3_NIC5_D")
	)
	(segment
		(start 334.530446 -119.77624)
		(end 334.530446 -118.76024)
		(width 0.13208)
		(layer "F.Cu")
		(net "PWRGD_P3V3_NIC5_D")
	)
	(segment
		(start 335.412334 -119.026178)
		(end 336.024474 -119.026178)
		(width 0.13208)
		(layer "F.Cu")
		(net "PWRGD_P3V3_NIC5_D")
	)
	(via
		(at 335.146396 -118.76024)
		(size 0.508)
		(drill 0.254)
		(layers "F.Cu" "B.Cu")
		(net "PWRGD_P3V3_NIC5_D")
	)
	(segment
		(start 215.827356 -67.592956)
		(end 215.827356 -67.228212)
		(width 0.13208)
		(layer "F.Cu")
		(net "P12V_SSD7_CO_DV_DT")
	)
	(segment
		(start 215.827356 -67.228212)
		(end 215.630506 -67.031362)
		(width 0.13208)
		(layer "F.Cu")
		(net "P12V_SSD7_CO_DV_DT")
	)
	(segment
		(start 215.630506 -67.031362)
		(end 215.630506 -66.72199)
		(width 0.13208)
		(layer "F.Cu")
		(net "P12V_SSD7_CO_DV_DT")
	)
	(segment
		(start 215.175338 -68.244974)
		(end 215.827356 -67.592956)
		(width 0.13208)
		(layer "F.Cu")
		(net "P12V_SSD7_CO_DV_DT")
	)
	(segment
		(start 215.175338 -68.479162)
		(end 215.175338 -68.244974)
		(width 0.13208)
		(layer "F.Cu")
		(net "P12V_SSD7_CO_DV_DT")
	)
	(via
		(at 215.827356 -67.592956)
		(size 0.508)
		(drill 0.254)
		(layers "F.Cu" "B.Cu")
		(net "P12V_SSD7_CO_DV_DT")
	)
	(segment
		(start 450.630544 -119.77624)
		(end 450.630544 -118.76024)
		(width 0.13208)
		(layer "F.Cu")
		(net "PWRGD_P3V3_NIC7_D")
	)
	(segment
		(start 450.630544 -118.76024)
		(end 451.246494 -118.76024)
		(width 0.13208)
		(layer "F.Cu")
		(net "PWRGD_P3V3_NIC7_D")
	)
	(segment
		(start 452.124572 -119.026178)
		(end 451.512432 -119.026178)
		(width 0.13208)
		(layer "F.Cu")
		(net "PWRGD_P3V3_NIC7_D")
	)
	(segment
		(start 451.512432 -119.026178)
		(end 451.246494 -118.76024)
		(width 0.13208)
		(layer "F.Cu")
		(net "PWRGD_P3V3_NIC7_D")
	)
	(via
		(at 451.246494 -118.76024)
		(size 0.508)
		(drill 0.254)
		(layers "F.Cu" "B.Cu")
		(net "PWRGD_P3V3_NIC7_D")
	)
	(segment
		(start 136.17575 -68.479162)
		(end 136.17575 -67.96405)
		(width 0.13208)
		(layer "F.Cu")
		(net "P12V_SSD4_CO_GATE")
	)
	(segment
		(start 135.560562 -67.787266)
		(end 135.26135 -67.488054)
		(width 0.13208)
		(layer "F.Cu")
		(net "P12V_SSD4_CO_GATE")
	)
	(segment
		(start 135.26135 -67.488054)
		(end 135.598662 -67.150742)
		(width 0.13208)
		(layer "F.Cu")
		(net "P12V_SSD4_CO_GATE")
	)
	(segment
		(start 136.17575 -67.96405)
		(end 135.998966 -67.787266)
		(width 0.13208)
		(layer "F.Cu")
		(net "P12V_SSD4_CO_GATE")
	)
	(segment
		(start 135.998966 -67.787266)
		(end 135.560562 -67.787266)
		(width 0.13208)
		(layer "F.Cu")
		(net "P12V_SSD4_CO_GATE")
	)
	(segment
		(start 135.598662 -67.150742)
		(end 135.598662 -66.72199)
		(width 0.13208)
		(layer "F.Cu")
		(net "P12V_SSD4_CO_GATE")
	)
	(via
		(at 135.26135 -67.488054)
		(size 0.508)
		(drill 0.254)
		(layers "F.Cu" "B.Cu")
		(net "P12V_SSD4_CO_GATE")
	)
	(segment
		(start 243.043202 -117.211348)
		(end 243.043202 -117.823488)
		(width 0.13208)
		(layer "F.Cu")
		(net "PWRGD_P3V3_NIC4_D")
	)
	(segment
		(start 243.793264 -118.705376)
		(end 242.777264 -118.705376)
		(width 0.13208)
		(layer "F.Cu")
		(net "PWRGD_P3V3_NIC4_D")
	)
	(segment
		(start 242.777264 -118.089426)
		(end 242.777264 -118.705376)
		(width 0.13208)
		(layer "F.Cu")
		(net "PWRGD_P3V3_NIC4_D")
	)
	(segment
		(start 243.043202 -117.823488)
		(end 242.777264 -118.089426)
		(width 0.13208)
		(layer "F.Cu")
		(net "PWRGD_P3V3_NIC4_D")
	)
	(via
		(at 242.777264 -118.089426)
		(size 0.508)
		(drill 0.254)
		(layers "F.Cu" "B.Cu")
		(net "PWRGD_P3V3_NIC4_D")
	)
	(segment
		(start 189.17539 -68.244974)
		(end 189.827408 -67.592956)
		(width 0.13208)
		(layer "F.Cu")
		(net "P12V_SSD6_CO_DV_DT")
	)
	(segment
		(start 189.17539 -68.479162)
		(end 189.17539 -68.244974)
		(width 0.13208)
		(layer "F.Cu")
		(net "P12V_SSD6_CO_DV_DT")
	)
	(segment
		(start 189.827408 -67.228212)
		(end 189.630558 -67.031362)
		(width 0.13208)
		(layer "F.Cu")
		(net "P12V_SSD6_CO_DV_DT")
	)
	(segment
		(start 189.827408 -67.592956)
		(end 189.827408 -67.228212)
		(width 0.13208)
		(layer "F.Cu")
		(net "P12V_SSD6_CO_DV_DT")
	)
	(segment
		(start 189.630558 -67.031362)
		(end 189.630558 -66.72199)
		(width 0.13208)
		(layer "F.Cu")
		(net "P12V_SSD6_CO_DV_DT")
	)
	(via
		(at 189.827408 -67.592956)
		(size 0.508)
		(drill 0.254)
		(layers "F.Cu" "B.Cu")
		(net "P12V_SSD6_CO_DV_DT")
	)
	(segment
		(start 10.84326 -117.211348)
		(end 10.84326 -117.823488)
		(width 0.13208)
		(layer "F.Cu")
		(net "PWRGD_P3V3_NIC0_D")
	)
	(segment
		(start 11.593322 -118.705376)
		(end 10.577322 -118.705376)
		(width 0.13208)
		(layer "F.Cu")
		(net "PWRGD_P3V3_NIC0_D")
	)
	(segment
		(start 10.577322 -118.705376)
		(end 10.577322 -118.089426)
		(width 0.13208)
		(layer "F.Cu")
		(net "PWRGD_P3V3_NIC0_D")
	)
	(segment
		(start 10.84326 -117.823488)
		(end 10.577322 -118.089426)
		(width 0.13208)
		(layer "F.Cu")
		(net "PWRGD_P3V3_NIC0_D")
	)
	(via
		(at 10.577322 -118.089426)
		(size 0.508)
		(drill 0.254)
		(layers "F.Cu" "B.Cu")
		(net "PWRGD_P3V3_NIC0_D")
	)
	(segment
		(start 145.802604 -63.086234)
		(end 145.375376 -63.086234)
		(width 0.13208)
		(layer "F.Cu")
		(net "P12V_SSD5_PG_G1")
	)
	(segment
		(start 146.789648 -63.56223)
		(end 146.347688 -63.56223)
		(width 0.13208)
		(layer "F.Cu")
		(net "P12V_SSD5_PG_G1")
	)
	(segment
		(start 146.347688 -63.56223)
		(end 146.05889 -63.273432)
		(width 0.13208)
		(layer "F.Cu")
		(net "P12V_SSD5_PG_G1")
	)
	(segment
		(start 145.989802 -63.273432)
		(end 145.802604 -63.086234)
		(width 0.13208)
		(layer "F.Cu")
		(net "P12V_SSD5_PG_G1")
	)
	(segment
		(start 145.375376 -64.102234)
		(end 145.375376 -63.086234)
		(width 0.13208)
		(layer "F.Cu")
		(net "P12V_SSD5_PG_G1")
	)
	(segment
		(start 146.05889 -63.273432)
		(end 145.989802 -63.273432)
		(width 0.13208)
		(layer "F.Cu")
		(net "P12V_SSD5_PG_G1")
	)
	(via
		(at 146.05889 -63.273432)
		(size 0.508)
		(drill 0.254)
		(layers "F.Cu" "B.Cu")
		(net "P12V_SSD5_PG_G1")
	)
	(segment
		(start 127.185166 -117.943376)
		(end 126.169166 -117.943376)
		(width 0.13208)
		(layer "F.Cu")
		(net "PWRGD_P3V3_NIC2_D")
	)
	(segment
		(start 126.435104 -116.449348)
		(end 126.435104 -117.061488)
		(width 0.13208)
		(layer "F.Cu")
		(net "PWRGD_P3V3_NIC2_D")
	)
	(segment
		(start 126.169166 -117.327426)
		(end 126.169166 -117.943376)
		(width 0.13208)
		(layer "F.Cu")
		(net "PWRGD_P3V3_NIC2_D")
	)
	(segment
		(start 126.435104 -117.061488)
		(end 126.169166 -117.327426)
		(width 0.13208)
		(layer "F.Cu")
		(net "PWRGD_P3V3_NIC2_D")
	)
	(via
		(at 126.169166 -117.327426)
		(size 0.508)
		(drill 0.254)
		(layers "F.Cu" "B.Cu")
		(net "PWRGD_P3V3_NIC2_D")
	)
	(segment
		(start 200.589388 -64.312292)
		(end 200.589388 -65.124076)
		(width 0.13208)
		(layer "F.Cu")
		(net "P12V_SSD7_PG_G2")
	)
	(segment
		(start 200.589388 -63.56223)
		(end 201.72045 -63.56223)
		(width 0.13208)
		(layer "F.Cu")
		(net "P12V_SSD7_PG_G2")
	)
	(segment
		(start 201.72045 -63.56223)
		(end 201.810366 -63.652146)
		(width 0.13208)
		(layer "F.Cu")
		(net "P12V_SSD7_PG_G2")
	)
	(segment
		(start 201.232516 -65.124076)
		(end 201.86015 -64.496442)
		(width 0.13208)
		(layer "F.Cu")
		(net "P12V_SSD7_PG_G2")
	)
	(segment
		(start 201.86015 -63.70193)
		(end 201.810366 -63.652146)
		(width 0.13208)
		(layer "F.Cu")
		(net "P12V_SSD7_PG_G2")
	)
	(segment
		(start 200.589388 -65.124076)
		(end 201.232516 -65.124076)
		(width 0.13208)
		(layer "F.Cu")
		(net "P12V_SSD7_PG_G2")
	)
	(segment
		(start 201.86015 -64.496442)
		(end 201.86015 -63.70193)
		(width 0.13208)
		(layer "F.Cu")
		(net "P12V_SSD7_PG_G2")
	)
	(via
		(at 200.589388 -65.124076)
		(size 0.508)
		(drill 0.254)
		(layers "F.Cu" "B.Cu")
		(net "P12V_SSD7_PG_G2")
	)
	(segment
		(start 103.212392 -119.026178)
		(end 102.946454 -118.76024)
		(width 0.13208)
		(layer "F.Cu")
		(net "PWRGD_P3V3_NIC1_D")
	)
	(segment
		(start 102.946454 -118.76024)
		(end 102.330504 -118.76024)
		(width 0.13208)
		(layer "F.Cu")
		(net "PWRGD_P3V3_NIC1_D")
	)
	(segment
		(start 102.330504 -119.77624)
		(end 102.330504 -118.76024)
		(width 0.13208)
		(layer "F.Cu")
		(net "PWRGD_P3V3_NIC1_D")
	)
	(segment
		(start 103.824532 -119.026178)
		(end 103.212392 -119.026178)
		(width 0.13208)
		(layer "F.Cu")
		(net "PWRGD_P3V3_NIC1_D")
	)
	(via
		(at 102.946454 -118.76024)
		(size 0.508)
		(drill 0.254)
		(layers "F.Cu" "B.Cu")
		(net "PWRGD_P3V3_NIC1_D")
	)
	(segment
		(start 162.61461 -67.01663)
		(end 162.61461 -66.72199)
		(width 0.13208)
		(layer "F.Cu")
		(net "P12V_SSD5_CO_EN")
	)
	(segment
		(start 162.553396 -67.847972)
		(end 162.67557 -67.970146)
		(width 0.13208)
		(layer "F.Cu")
		(net "P12V_SSD5_CO_EN")
	)
	(segment
		(start 162.553396 -67.077844)
		(end 162.61461 -67.01663)
		(width 0.13208)
		(layer "F.Cu")
		(net "P12V_SSD5_CO_EN")
	)
	(segment
		(start 162.553396 -67.537584)
		(end 162.553396 -67.077844)
		(width 0.13208)
		(layer "F.Cu")
		(net "P12V_SSD5_CO_EN")
	)
	(segment
		(start 162.553396 -67.537584)
		(end 162.553396 -67.847972)
		(width 0.13208)
		(layer "F.Cu")
		(net "P12V_SSD5_CO_EN")
	)
	(segment
		(start 162.67557 -67.970146)
		(end 162.67557 -68.479162)
		(width 0.13208)
		(layer "F.Cu")
		(net "P12V_SSD5_CO_EN")
	)
	(via
		(at 162.553396 -67.537584)
		(size 0.508)
		(drill 0.254)
		(layers "F.Cu" "B.Cu")
		(net "P12V_SSD5_CO_EN")
	)
	(segment
		(start 220.841316 -121.742962)
		(end 220.225366 -121.742962)
		(width 0.13208)
		(layer "F.Cu")
		(net "PWRGD_P3V3_NIC3_D")
	)
	(segment
		(start 221.107254 -122.0089)
		(end 220.841316 -121.742962)
		(width 0.13208)
		(layer "F.Cu")
		(net "PWRGD_P3V3_NIC3_D")
	)
	(segment
		(start 221.719394 -122.0089)
		(end 221.107254 -122.0089)
		(width 0.13208)
		(layer "F.Cu")
		(net "PWRGD_P3V3_NIC3_D")
	)
	(segment
		(start 220.225366 -122.758962)
		(end 220.225366 -121.742962)
		(width 0.13208)
		(layer "F.Cu")
		(net "PWRGD_P3V3_NIC3_D")
	)
	(via
		(at 220.841316 -121.742962)
		(size 0.508)
		(drill 0.254)
		(layers "F.Cu" "B.Cu")
		(net "PWRGD_P3V3_NIC3_D")
	)
	(segment
		(start 188.37402 -71.908416)
		(end 188.37402 -72.366632)
		(width 0.13208)
		(layer "F.Cu")
		(net "P12V_SSD6_CO_MODE")
	)
	(segment
		(start 187.35802 -72.366632)
		(end 188.37402 -72.366632)
		(width 0.13208)
		(layer "F.Cu")
		(net "P12V_SSD6_CO_MODE")
	)
	(segment
		(start 187.676536 -71.555864)
		(end 188.021468 -71.555864)
		(width 0.13208)
		(layer "F.Cu")
		(net "P12V_SSD6_CO_MODE")
	)
	(segment
		(start 188.021468 -71.555864)
		(end 188.37402 -71.908416)
		(width 0.13208)
		(layer "F.Cu")
		(net "P12V_SSD6_CO_MODE")
	)
	(segment
		(start 187.676536 -71.555864)
		(end 188.175646 -71.056754)
		(width 0.13208)
		(layer "F.Cu")
		(net "P12V_SSD6_CO_MODE")
	)
	(segment
		(start 188.175646 -71.056754)
		(end 188.175646 -70.479158)
		(width 0.13208)
		(layer "F.Cu")
		(net "P12V_SSD6_CO_MODE")
	)
	(via
		(at 187.676536 -71.555864)
		(size 0.508)
		(drill 0.254)
		(layers "F.Cu" "B.Cu")
		(net "P12V_SSD6_CO_MODE")
	)
	(segment
		(start 352.58375 -61.78042)
		(end 352.58375 -61.487812)
		(width 0.13208)
		(layer "F.Cu")
		(net "PWRGD_P12V_SSD12_D")
	)
	(segment
		(start 352.924364 -62.74689)
		(end 352.924364 -62.121034)
		(width 0.13208)
		(layer "F.Cu")
		(net "PWRGD_P12V_SSD12_D")
	)
	(segment
		(start 352.989642 -62.812168)
		(end 352.924364 -62.74689)
		(width 0.13208)
		(layer "F.Cu")
		(net "PWRGD_P12V_SSD12_D")
	)
	(segment
		(start 353.556316 -61.487812)
		(end 352.58375 -61.487812)
		(width 0.13208)
		(layer "F.Cu")
		(net "PWRGD_P12V_SSD12_D")
	)
	(segment
		(start 352.924364 -62.121034)
		(end 352.58375 -61.78042)
		(width 0.13208)
		(layer "F.Cu")
		(net "PWRGD_P12V_SSD12_D")
	)
	(via
		(at 352.924364 -62.121034)
		(size 0.508)
		(drill 0.254)
		(layers "F.Cu" "B.Cu")
		(net "PWRGD_P12V_SSD12_D")
	)
	(segment
		(start 137.185654 -71.623428)
		(end 136.675622 -71.113396)
		(width 0.13208)
		(layer "F.Cu")
		(net "P12V_SSD4_CO_ILIMIT")
	)
	(segment
		(start 137.390124 -71.827898)
		(end 137.185654 -71.623428)
		(width 0.13208)
		(layer "F.Cu")
		(net "P12V_SSD4_CO_ILIMIT")
	)
	(segment
		(start 136.675622 -71.113396)
		(end 136.675622 -70.479158)
		(width 0.13208)
		(layer "F.Cu")
		(net "P12V_SSD4_CO_ILIMIT")
	)
	(segment
		(start 137.390124 -72.366632)
		(end 137.390124 -71.827898)
		(width 0.13208)
		(layer "F.Cu")
		(net "P12V_SSD4_CO_ILIMIT")
	)
	(via
		(at 137.185654 -71.623428)
		(size 0.508)
		(drill 0.254)
		(layers "F.Cu" "B.Cu")
		(net "P12V_SSD4_CO_ILIMIT")
	)
	(segment
		(start 378.583698 -61.78042)
		(end 378.583698 -61.487812)
		(width 0.13208)
		(layer "F.Cu")
		(net "PWRGD_P12V_SSD13_D")
	)
	(segment
		(start 378.924312 -62.121034)
		(end 378.583698 -61.78042)
		(width 0.13208)
		(layer "F.Cu")
		(net "PWRGD_P12V_SSD13_D")
	)
	(segment
		(start 379.556264 -61.487812)
		(end 378.583698 -61.487812)
		(width 0.13208)
		(layer "F.Cu")
		(net "PWRGD_P12V_SSD13_D")
	)
	(segment
		(start 378.924312 -62.74689)
		(end 378.924312 -62.121034)
		(width 0.13208)
		(layer "F.Cu")
		(net "PWRGD_P12V_SSD13_D")
	)
	(segment
		(start 378.98959 -62.812168)
		(end 378.924312 -62.74689)
		(width 0.13208)
		(layer "F.Cu")
		(net "PWRGD_P12V_SSD13_D")
	)
	(via
		(at 378.924312 -62.121034)
		(size 0.508)
		(drill 0.254)
		(layers "F.Cu" "B.Cu")
		(net "PWRGD_P12V_SSD13_D")
	)
	(segment
		(start 213.99881 -67.787266)
		(end 214.175594 -67.96405)
		(width 0.13208)
		(layer "F.Cu")
		(net "P12V_SSD7_CO_GATE")
	)
	(segment
		(start 213.598506 -67.150742)
		(end 213.598506 -66.72199)
		(width 0.13208)
		(layer "F.Cu")
		(net "P12V_SSD7_CO_GATE")
	)
	(segment
		(start 213.261194 -67.488054)
		(end 213.598506 -67.150742)
		(width 0.13208)
		(layer "F.Cu")
		(net "P12V_SSD7_CO_GATE")
	)
	(segment
		(start 213.261194 -67.488054)
		(end 213.560406 -67.787266)
		(width 0.13208)
		(layer "F.Cu")
		(net "P12V_SSD7_CO_GATE")
	)
	(segment
		(start 214.175594 -67.96405)
		(end 214.175594 -68.479162)
		(width 0.13208)
		(layer "F.Cu")
		(net "P12V_SSD7_CO_GATE")
	)
	(segment
		(start 213.560406 -67.787266)
		(end 213.99881 -67.787266)
		(width 0.13208)
		(layer "F.Cu")
		(net "P12V_SSD7_CO_GATE")
	)
	(via
		(at 213.261194 -67.488054)
		(size 0.508)
		(drill 0.254)
		(layers "F.Cu" "B.Cu")
		(net "P12V_SSD7_CO_GATE")
	)
	(segment
		(start 404.583646 -61.78042)
		(end 404.583646 -61.487812)
		(width 0.13208)
		(layer "F.Cu")
		(net "PWRGD_P12V_SSD14_D")
	)
	(segment
		(start 404.92426 -62.121034)
		(end 404.583646 -61.78042)
		(width 0.13208)
		(layer "F.Cu")
		(net "PWRGD_P12V_SSD14_D")
	)
	(segment
		(start 404.989538 -62.812168)
		(end 404.92426 -62.74689)
		(width 0.13208)
		(layer "F.Cu")
		(net "PWRGD_P12V_SSD14_D")
	)
	(segment
		(start 404.92426 -62.74689)
		(end 404.92426 -62.121034)
		(width 0.13208)
		(layer "F.Cu")
		(net "PWRGD_P12V_SSD14_D")
	)
	(segment
		(start 405.556212 -61.487812)
		(end 404.583646 -61.487812)
		(width 0.13208)
		(layer "F.Cu")
		(net "PWRGD_P12V_SSD14_D")
	)
	(via
		(at 404.92426 -62.121034)
		(size 0.508)
		(drill 0.254)
		(layers "F.Cu" "B.Cu")
		(net "PWRGD_P12V_SSD14_D")
	)
	(segment
		(start 135.67664 -71.555864)
		(end 136.17575 -71.056754)
		(width 0.13208)
		(layer "F.Cu")
		(net "P12V_SSD4_CO_MODE")
	)
	(segment
		(start 136.021572 -71.555864)
		(end 135.67664 -71.555864)
		(width 0.13208)
		(layer "F.Cu")
		(net "P12V_SSD4_CO_MODE")
	)
	(segment
		(start 135.358124 -72.366632)
		(end 136.374124 -72.366632)
		(width 0.13208)
		(layer "F.Cu")
		(net "P12V_SSD4_CO_MODE")
	)
	(segment
		(start 136.374124 -72.366632)
		(end 136.374124 -71.908416)
		(width 0.13208)
		(layer "F.Cu")
		(net "P12V_SSD4_CO_MODE")
	)
	(segment
		(start 136.17575 -71.056754)
		(end 136.17575 -70.479158)
		(width 0.13208)
		(layer "F.Cu")
		(net "P12V_SSD4_CO_MODE")
	)
	(segment
		(start 136.374124 -71.908416)
		(end 136.021572 -71.555864)
		(width 0.13208)
		(layer "F.Cu")
		(net "P12V_SSD4_CO_MODE")
	)
	(via
		(at 135.67664 -71.555864)
		(size 0.508)
		(drill 0.254)
		(layers "F.Cu" "B.Cu")
		(net "P12V_SSD4_CO_MODE")
	)
	(segment
		(start 431.55616 -61.487812)
		(end 430.583594 -61.487812)
		(width 0.13208)
		(layer "F.Cu")
		(net "PWRGD_P12V_SSD15_D")
	)
	(segment
		(start 430.583594 -61.78042)
		(end 430.583594 -61.487812)
		(width 0.13208)
		(layer "F.Cu")
		(net "PWRGD_P12V_SSD15_D")
	)
	(segment
		(start 430.924208 -62.74689)
		(end 430.924208 -62.121034)
		(width 0.13208)
		(layer "F.Cu")
		(net "PWRGD_P12V_SSD15_D")
	)
	(segment
		(start 430.924208 -62.121034)
		(end 430.583594 -61.78042)
		(width 0.13208)
		(layer "F.Cu")
		(net "PWRGD_P12V_SSD15_D")
	)
	(segment
		(start 430.989486 -62.812168)
		(end 430.924208 -62.74689)
		(width 0.13208)
		(layer "F.Cu")
		(net "PWRGD_P12V_SSD15_D")
	)
	(via
		(at 430.924208 -62.121034)
		(size 0.508)
		(drill 0.254)
		(layers "F.Cu" "B.Cu")
		(net "PWRGD_P12V_SSD15_D")
	)
	(segment
		(start 197.375272 -64.102234)
		(end 197.375272 -63.086234)
		(width 0.13208)
		(layer "F.Cu")
		(net "P12V_SSD7_PG_G1")
	)
	(segment
		(start 197.8025 -63.086234)
		(end 197.375272 -63.086234)
		(width 0.13208)
		(layer "F.Cu")
		(net "P12V_SSD7_PG_G1")
	)
	(segment
		(start 198.789544 -63.56223)
		(end 198.347584 -63.56223)
		(width 0.13208)
		(layer "F.Cu")
		(net "P12V_SSD7_PG_G1")
	)
	(segment
		(start 198.347584 -63.56223)
		(end 198.058786 -63.273432)
		(width 0.13208)
		(layer "F.Cu")
		(net "P12V_SSD7_PG_G1")
	)
	(segment
		(start 197.989698 -63.273432)
		(end 197.8025 -63.086234)
		(width 0.13208)
		(layer "F.Cu")
		(net "P12V_SSD7_PG_G1")
	)
	(segment
		(start 198.058786 -63.273432)
		(end 197.989698 -63.273432)
		(width 0.13208)
		(layer "F.Cu")
		(net "P12V_SSD7_PG_G1")
	)
	(via
		(at 198.058786 -63.273432)
		(size 0.508)
		(drill 0.254)
		(layers "F.Cu" "B.Cu")
		(net "P12V_SSD7_PG_G1")
	)
	(segment
		(start 262.824214 -62.121034)
		(end 262.4836 -61.78042)
		(width 0.13208)
		(layer "F.Cu")
		(net "PWRGD_P12V_SSD9_D")
	)
	(segment
		(start 262.824214 -62.74689)
		(end 262.824214 -62.121034)
		(width 0.13208)
		(layer "F.Cu")
		(net "PWRGD_P12V_SSD9_D")
	)
	(segment
		(start 263.456166 -61.487812)
		(end 262.4836 -61.487812)
		(width 0.13208)
		(layer "F.Cu")
		(net "PWRGD_P12V_SSD9_D")
	)
	(segment
		(start 262.889492 -62.812168)
		(end 262.824214 -62.74689)
		(width 0.13208)
		(layer "F.Cu")
		(net "PWRGD_P12V_SSD9_D")
	)
	(segment
		(start 262.4836 -61.78042)
		(end 262.4836 -61.487812)
		(width 0.13208)
		(layer "F.Cu")
		(net "PWRGD_P12V_SSD9_D")
	)
	(via
		(at 262.824214 -62.121034)
		(size 0.508)
		(drill 0.254)
		(layers "F.Cu" "B.Cu")
		(net "PWRGD_P12V_SSD9_D")
	)
	(segment
		(start 241.624612 -62.217808)
		(end 241.624612 -61.245242)
		(width 0.13208)
		(layer "F.Cu")
		(net "PWRGD_P12V_SSD8_D")
	)
	(segment
		(start 240.300256 -61.651134)
		(end 240.365534 -61.585856)
		(width 0.13208)
		(layer "F.Cu")
		(net "PWRGD_P12V_SSD8_D")
	)
	(segment
		(start 241.332004 -61.245242)
		(end 241.624612 -61.245242)
		(width 0.13208)
		(layer "F.Cu")
		(net "PWRGD_P12V_SSD8_D")
	)
	(segment
		(start 240.365534 -61.585856)
		(end 240.99139 -61.585856)
		(width 0.13208)
		(layer "F.Cu")
		(net "PWRGD_P12V_SSD8_D")
	)
	(segment
		(start 240.99139 -61.585856)
		(end 241.332004 -61.245242)
		(width 0.13208)
		(layer "F.Cu")
		(net "PWRGD_P12V_SSD8_D")
	)
	(via
		(at 240.99139 -61.585856)
		(size 0.508)
		(drill 0.254)
		(layers "F.Cu" "B.Cu")
		(net "PWRGD_P12V_SSD8_D")
	)
	(segment
		(start 213.676484 -71.555864)
		(end 214.175594 -71.056754)
		(width 0.13208)
		(layer "F.Cu")
		(net "P12V_SSD7_CO_MODE")
	)
	(segment
		(start 213.357968 -72.366632)
		(end 214.373968 -72.366632)
		(width 0.13208)
		(layer "F.Cu")
		(net "P12V_SSD7_CO_MODE")
	)
	(segment
		(start 214.021416 -71.555864)
		(end 213.676484 -71.555864)
		(width 0.13208)
		(layer "F.Cu")
		(net "P12V_SSD7_CO_MODE")
	)
	(segment
		(start 214.175594 -71.056754)
		(end 214.175594 -70.479158)
		(width 0.13208)
		(layer "F.Cu")
		(net "P12V_SSD7_CO_MODE")
	)
	(segment
		(start 214.373968 -72.366632)
		(end 214.373968 -71.908416)
		(width 0.13208)
		(layer "F.Cu")
		(net "P12V_SSD7_CO_MODE")
	)
	(segment
		(start 214.373968 -71.908416)
		(end 214.021416 -71.555864)
		(width 0.13208)
		(layer "F.Cu")
		(net "P12V_SSD7_CO_MODE")
	)
	(via
		(at 213.676484 -71.555864)
		(size 0.508)
		(drill 0.254)
		(layers "F.Cu" "B.Cu")
		(net "P12V_SSD7_CO_MODE")
	)
	(segment
		(start 314.82411 -62.121034)
		(end 314.483496 -61.78042)
		(width 0.13208)
		(layer "F.Cu")
		(net "PWRGD_P12V_SSD11_D")
	)
	(segment
		(start 315.456062 -61.487812)
		(end 314.483496 -61.487812)
		(width 0.13208)
		(layer "F.Cu")
		(net "PWRGD_P12V_SSD11_D")
	)
	(segment
		(start 314.483496 -61.78042)
		(end 314.483496 -61.487812)
		(width 0.13208)
		(layer "F.Cu")
		(net "PWRGD_P12V_SSD11_D")
	)
	(segment
		(start 314.889388 -62.812168)
		(end 314.82411 -62.74689)
		(width 0.13208)
		(layer "F.Cu")
		(net "PWRGD_P12V_SSD11_D")
	)
	(segment
		(start 314.82411 -62.74689)
		(end 314.82411 -62.121034)
		(width 0.13208)
		(layer "F.Cu")
		(net "PWRGD_P12V_SSD11_D")
	)
	(via
		(at 314.82411 -62.121034)
		(size 0.508)
		(drill 0.254)
		(layers "F.Cu" "B.Cu")
		(net "PWRGD_P12V_SSD11_D")
	)
	(segment
		(start 214.675466 -67.970146)
		(end 214.675466 -68.479162)
		(width 0.13208)
		(layer "F.Cu")
		(net "P12V_SSD7_CO_EN")
	)
	(segment
		(start 214.553292 -67.537584)
		(end 214.553292 -67.077844)
		(width 0.13208)
		(layer "F.Cu")
		(net "P12V_SSD7_CO_EN")
	)
	(segment
		(start 214.614506 -67.01663)
		(end 214.614506 -66.72199)
		(width 0.13208)
		(layer "F.Cu")
		(net "P12V_SSD7_CO_EN")
	)
	(segment
		(start 214.553292 -67.537584)
		(end 214.553292 -67.847972)
		(width 0.13208)
		(layer "F.Cu")
		(net "P12V_SSD7_CO_EN")
	)
	(segment
		(start 214.553292 -67.077844)
		(end 214.614506 -67.01663)
		(width 0.13208)
		(layer "F.Cu")
		(net "P12V_SSD7_CO_EN")
	)
	(segment
		(start 214.553292 -67.847972)
		(end 214.675466 -67.970146)
		(width 0.13208)
		(layer "F.Cu")
		(net "P12V_SSD7_CO_EN")
	)
	(via
		(at 214.553292 -67.537584)
		(size 0.508)
		(drill 0.254)
		(layers "F.Cu" "B.Cu")
		(net "P12V_SSD7_CO_EN")
	)
	(segment
		(start 288.483548 -61.78042)
		(end 288.483548 -61.487812)
		(width 0.13208)
		(layer "F.Cu")
		(net "PWRGD_P12V_SSD10_D")
	)
	(segment
		(start 289.456114 -61.487812)
		(end 288.483548 -61.487812)
		(width 0.13208)
		(layer "F.Cu")
		(net "PWRGD_P12V_SSD10_D")
	)
	(segment
		(start 288.824162 -62.74689)
		(end 288.824162 -62.121034)
		(width 0.13208)
		(layer "F.Cu")
		(net "PWRGD_P12V_SSD10_D")
	)
	(segment
		(start 288.824162 -62.121034)
		(end 288.483548 -61.78042)
		(width 0.13208)
		(layer "F.Cu")
		(net "PWRGD_P12V_SSD10_D")
	)
	(segment
		(start 288.88944 -62.812168)
		(end 288.824162 -62.74689)
		(width 0.13208)
		(layer "F.Cu")
		(net "PWRGD_P12V_SSD10_D")
	)
	(via
		(at 288.824162 -62.121034)
		(size 0.508)
		(drill 0.254)
		(layers "F.Cu" "B.Cu")
		(net "PWRGD_P12V_SSD10_D")
	)
	(segment
		(start 187.560458 -67.787266)
		(end 187.261246 -67.488054)
		(width 0.13208)
		(layer "F.Cu")
		(net "P12V_SSD6_CO_GATE")
	)
	(segment
		(start 187.598558 -67.150742)
		(end 187.598558 -66.72199)
		(width 0.13208)
		(layer "F.Cu")
		(net "P12V_SSD6_CO_GATE")
	)
	(segment
		(start 187.261246 -67.488054)
		(end 187.598558 -67.150742)
		(width 0.13208)
		(layer "F.Cu")
		(net "P12V_SSD6_CO_GATE")
	)
	(segment
		(start 187.998862 -67.787266)
		(end 187.560458 -67.787266)
		(width 0.13208)
		(layer "F.Cu")
		(net "P12V_SSD6_CO_GATE")
	)
	(segment
		(start 188.175646 -68.479162)
		(end 188.175646 -67.96405)
		(width 0.13208)
		(layer "F.Cu")
		(net "P12V_SSD6_CO_GATE")
	)
	(segment
		(start 188.175646 -67.96405)
		(end 187.998862 -67.787266)
		(width 0.13208)
		(layer "F.Cu")
		(net "P12V_SSD6_CO_GATE")
	)
	(via
		(at 187.261246 -67.488054)
		(size 0.508)
		(drill 0.254)
		(layers "F.Cu" "B.Cu")
		(net "P12V_SSD6_CO_GATE")
	)
	(segment
		(start 120.724422 -62.121034)
		(end 120.724422 -62.74689)
		(width 0.13208)
		(layer "F.Cu")
		(net "PWRGD_P12V_SSD4_D")
	)
	(segment
		(start 120.383808 -61.487812)
		(end 120.383808 -61.78042)
		(width 0.13208)
		(layer "F.Cu")
		(net "PWRGD_P12V_SSD4_D")
	)
	(segment
		(start 120.724422 -62.74689)
		(end 120.7897 -62.812168)
		(width 0.13208)
		(layer "F.Cu")
		(net "PWRGD_P12V_SSD4_D")
	)
	(segment
		(start 121.356374 -61.487812)
		(end 120.383808 -61.487812)
		(width 0.13208)
		(layer "F.Cu")
		(net "PWRGD_P12V_SSD4_D")
	)
	(segment
		(start 120.383808 -61.78042)
		(end 120.724422 -62.121034)
		(width 0.13208)
		(layer "F.Cu")
		(net "PWRGD_P12V_SSD4_D")
	)
	(via
		(at 120.724422 -62.121034)
		(size 0.508)
		(drill 0.254)
		(layers "F.Cu" "B.Cu")
		(net "PWRGD_P12V_SSD4_D")
	)
	(segment
		(start 189.39002 -72.366632)
		(end 189.39002 -71.827898)
		(width 0.13208)
		(layer "F.Cu")
		(net "P12V_SSD6_CO_ILIMIT")
	)
	(segment
		(start 189.39002 -71.827898)
		(end 189.18555 -71.623428)
		(width 0.13208)
		(layer "F.Cu")
		(net "P12V_SSD6_CO_ILIMIT")
	)
	(segment
		(start 189.18555 -71.623428)
		(end 188.675518 -71.113396)
		(width 0.13208)
		(layer "F.Cu")
		(net "P12V_SSD6_CO_ILIMIT")
	)
	(segment
		(start 188.675518 -71.113396)
		(end 188.675518 -70.479158)
		(width 0.13208)
		(layer "F.Cu")
		(net "P12V_SSD6_CO_ILIMIT")
	)
	(via
		(at 189.18555 -71.623428)
		(size 0.508)
		(drill 0.254)
		(layers "F.Cu" "B.Cu")
		(net "P12V_SSD6_CO_ILIMIT")
	)
	(segment
		(start 146.72437 -62.121034)
		(end 146.72437 -62.74689)
		(width 0.13208)
		(layer "F.Cu")
		(net "PWRGD_P12V_SSD5_D")
	)
	(segment
		(start 146.383756 -61.487812)
		(end 146.383756 -61.78042)
		(width 0.13208)
		(layer "F.Cu")
		(net "PWRGD_P12V_SSD5_D")
	)
	(segment
		(start 147.356322 -61.487812)
		(end 146.383756 -61.487812)
		(width 0.13208)
		(layer "F.Cu")
		(net "PWRGD_P12V_SSD5_D")
	)
	(segment
		(start 146.72437 -62.74689)
		(end 146.789648 -62.812168)
		(width 0.13208)
		(layer "F.Cu")
		(net "PWRGD_P12V_SSD5_D")
	)
	(segment
		(start 146.383756 -61.78042)
		(end 146.72437 -62.121034)
		(width 0.13208)
		(layer "F.Cu")
		(net "PWRGD_P12V_SSD5_D")
	)
	(via
		(at 146.72437 -62.121034)
		(size 0.508)
		(drill 0.254)
		(layers "F.Cu" "B.Cu")
		(net "PWRGD_P12V_SSD5_D")
	)
	(segment
		(start 175.770032 -64.312292)
		(end 175.860202 -64.222122)
		(width 0.13208)
		(layer "F.Cu")
		(net "P12V_SSD6_PG_G2")
	)
	(segment
		(start 175.860202 -63.70193)
		(end 175.810418 -63.652146)
		(width 0.13208)
		(layer "F.Cu")
		(net "P12V_SSD6_PG_G2")
	)
	(segment
		(start 175.810418 -63.652146)
		(end 175.720502 -63.56223)
		(width 0.13208)
		(layer "F.Cu")
		(net "P12V_SSD6_PG_G2")
	)
	(segment
		(start 175.720502 -63.56223)
		(end 174.58944 -63.56223)
		(width 0.13208)
		(layer "F.Cu")
		(net "P12V_SSD6_PG_G2")
	)
	(segment
		(start 174.58944 -64.312292)
		(end 175.388016 -64.312292)
		(width 0.13208)
		(layer "F.Cu")
		(net "P12V_SSD6_PG_G2")
	)
	(segment
		(start 175.388016 -64.312292)
		(end 175.770032 -64.312292)
		(width 0.13208)
		(layer "F.Cu")
		(net "P12V_SSD6_PG_G2")
	)
	(segment
		(start 175.860202 -64.222122)
		(end 175.860202 -63.70193)
		(width 0.13208)
		(layer "F.Cu")
		(net "P12V_SSD6_PG_G2")
	)
	(via
		(at 175.388016 -64.312292)
		(size 0.508)
		(drill 0.254)
		(layers "F.Cu" "B.Cu")
		(net "P12V_SSD6_PG_G2")
	)
	(segment
		(start 172.724318 -62.121034)
		(end 172.383704 -61.78042)
		(width 0.13208)
		(layer "F.Cu")
		(net "PWRGD_P12V_SSD6_D")
	)
	(segment
		(start 172.724318 -62.74689)
		(end 172.724318 -62.121034)
		(width 0.13208)
		(layer "F.Cu")
		(net "PWRGD_P12V_SSD6_D")
	)
	(segment
		(start 173.35627 -61.487812)
		(end 172.383704 -61.487812)
		(width 0.13208)
		(layer "F.Cu")
		(net "PWRGD_P12V_SSD6_D")
	)
	(segment
		(start 172.383704 -61.78042)
		(end 172.383704 -61.487812)
		(width 0.13208)
		(layer "F.Cu")
		(net "PWRGD_P12V_SSD6_D")
	)
	(segment
		(start 172.789596 -62.812168)
		(end 172.724318 -62.74689)
		(width 0.13208)
		(layer "F.Cu")
		(net "PWRGD_P12V_SSD6_D")
	)
	(via
		(at 172.724318 -62.121034)
		(size 0.508)
		(drill 0.254)
		(layers "F.Cu" "B.Cu")
		(net "PWRGD_P12V_SSD6_D")
	)
	(segment
		(start 163.390072 -72.366632)
		(end 163.390072 -71.827898)
		(width 0.13208)
		(layer "F.Cu")
		(net "P12V_SSD5_CO_ILIMIT")
	)
	(segment
		(start 163.185602 -71.623428)
		(end 162.67557 -71.113396)
		(width 0.13208)
		(layer "F.Cu")
		(net "P12V_SSD5_CO_ILIMIT")
	)
	(segment
		(start 162.67557 -71.113396)
		(end 162.67557 -70.479158)
		(width 0.13208)
		(layer "F.Cu")
		(net "P12V_SSD5_CO_ILIMIT")
	)
	(segment
		(start 163.390072 -71.827898)
		(end 163.185602 -71.623428)
		(width 0.13208)
		(layer "F.Cu")
		(net "P12V_SSD5_CO_ILIMIT")
	)
	(via
		(at 163.185602 -71.623428)
		(size 0.508)
		(drill 0.254)
		(layers "F.Cu" "B.Cu")
		(net "P12V_SSD5_CO_ILIMIT")
	)
	(segment
		(start 199.356218 -61.487812)
		(end 198.383652 -61.487812)
		(width 0.13208)
		(layer "F.Cu")
		(net "PWRGD_P12V_SSD7_D")
	)
	(segment
		(start 198.383652 -61.78042)
		(end 198.383652 -61.487812)
		(width 0.13208)
		(layer "F.Cu")
		(net "PWRGD_P12V_SSD7_D")
	)
	(segment
		(start 198.789544 -62.812168)
		(end 198.724266 -62.74689)
		(width 0.13208)
		(layer "F.Cu")
		(net "PWRGD_P12V_SSD7_D")
	)
	(segment
		(start 198.724266 -62.121034)
		(end 198.383652 -61.78042)
		(width 0.13208)
		(layer "F.Cu")
		(net "PWRGD_P12V_SSD7_D")
	)
	(segment
		(start 198.724266 -62.74689)
		(end 198.724266 -62.121034)
		(width 0.13208)
		(layer "F.Cu")
		(net "PWRGD_P12V_SSD7_D")
	)
	(via
		(at 198.724266 -62.121034)
		(size 0.508)
		(drill 0.254)
		(layers "F.Cu" "B.Cu")
		(net "PWRGD_P12V_SSD7_D")
	)
	(segment
		(start 123.860306 -63.70193)
		(end 123.810522 -63.652146)
		(width 0.13208)
		(layer "F.Cu")
		(net "P12V_SSD4_PG_G2")
	)
	(segment
		(start 123.720606 -63.56223)
		(end 123.810522 -63.652146)
		(width 0.13208)
		(layer "F.Cu")
		(net "P12V_SSD4_PG_G2")
	)
	(segment
		(start 122.589544 -65.124076)
		(end 123.232672 -65.124076)
		(width 0.13208)
		(layer "F.Cu")
		(net "P12V_SSD4_PG_G2")
	)
	(segment
		(start 122.589544 -64.312292)
		(end 122.589544 -65.124076)
		(width 0.13208)
		(layer "F.Cu")
		(net "P12V_SSD4_PG_G2")
	)
	(segment
		(start 123.232672 -65.124076)
		(end 123.860306 -64.496442)
		(width 0.13208)
		(layer "F.Cu")
		(net "P12V_SSD4_PG_G2")
	)
	(segment
		(start 122.589544 -63.56223)
		(end 123.720606 -63.56223)
		(width 0.13208)
		(layer "F.Cu")
		(net "P12V_SSD4_PG_G2")
	)
	(segment
		(start 123.860306 -64.496442)
		(end 123.860306 -63.70193)
		(width 0.13208)
		(layer "F.Cu")
		(net "P12V_SSD4_PG_G2")
	)
	(via
		(at 122.589544 -65.124076)
		(size 0.508)
		(drill 0.254)
		(layers "F.Cu" "B.Cu")
		(net "P12V_SSD4_PG_G2")
	)
	(segment
		(start 172.347636 -63.56223)
		(end 172.058838 -63.273432)
		(width 0.13208)
		(layer "F.Cu")
		(net "P12V_SSD6_PG_G1")
	)
	(segment
		(start 172.058838 -63.273432)
		(end 171.98975 -63.273432)
		(width 0.13208)
		(layer "F.Cu")
		(net "P12V_SSD6_PG_G1")
	)
	(segment
		(start 171.802552 -63.086234)
		(end 171.375324 -63.086234)
		(width 0.13208)
		(layer "F.Cu")
		(net "P12V_SSD6_PG_G1")
	)
	(segment
		(start 171.98975 -63.273432)
		(end 171.802552 -63.086234)
		(width 0.13208)
		(layer "F.Cu")
		(net "P12V_SSD6_PG_G1")
	)
	(segment
		(start 171.375324 -64.102234)
		(end 171.375324 -63.086234)
		(width 0.13208)
		(layer "F.Cu")
		(net "P12V_SSD6_PG_G1")
	)
	(segment
		(start 172.789596 -63.56223)
		(end 172.347636 -63.56223)
		(width 0.13208)
		(layer "F.Cu")
		(net "P12V_SSD6_PG_G1")
	)
	(via
		(at 172.058838 -63.273432)
		(size 0.508)
		(drill 0.254)
		(layers "F.Cu" "B.Cu")
		(net "P12V_SSD6_PG_G1")
	)
	(segment
		(start 137.630662 -67.031362)
		(end 137.630662 -66.72199)
		(width 0.13208)
		(layer "F.Cu")
		(net "P12V_SSD4_CO_DV_DT")
	)
	(segment
		(start 137.827512 -67.228212)
		(end 137.630662 -67.031362)
		(width 0.13208)
		(layer "F.Cu")
		(net "P12V_SSD4_CO_DV_DT")
	)
	(segment
		(start 137.175494 -68.479162)
		(end 137.175494 -68.244974)
		(width 0.13208)
		(layer "F.Cu")
		(net "P12V_SSD4_CO_DV_DT")
	)
	(segment
		(start 137.827512 -67.592956)
		(end 137.827512 -67.228212)
		(width 0.13208)
		(layer "F.Cu")
		(net "P12V_SSD4_CO_DV_DT")
	)
	(segment
		(start 137.175494 -68.244974)
		(end 137.827512 -67.592956)
		(width 0.13208)
		(layer "F.Cu")
		(net "P12V_SSD4_CO_DV_DT")
	)
	(via
		(at 137.827512 -67.592956)
		(size 0.508)
		(drill 0.254)
		(layers "F.Cu" "B.Cu")
		(net "P12V_SSD4_CO_DV_DT")
	)
	(segment
		(start 448.869308 -49.548796)
		(end 448.869308 -48.8442)
		(width 0.13208)
		(layer "F.Cu")
		(net "SSD15_ADC_A0")
	)
	(segment
		(start 451.385686 -45.771816)
		(end 450.963538 -46.193964)
		(width 0.13208)
		(layer "F.Cu")
		(net "SSD15_ADC_A0")
	)
	(segment
		(start 451.385686 -45.695616)
		(end 451.57898 -45.88891)
		(width 0.13208)
		(layer "F.Cu")
		(net "SSD15_ADC_A0")
	)
	(segment
		(start 449.261992 -49.94148)
		(end 448.869308 -49.548796)
		(width 0.13208)
		(layer "F.Cu")
		(net "SSD15_ADC_A0")
	)
	(segment
		(start 450.283326 -49.94148)
		(end 449.261992 -49.94148)
		(width 0.13208)
		(layer "F.Cu")
		(net "SSD15_ADC_A0")
	)
	(segment
		(start 452.143622 -44.87291)
		(end 452.143622 -45.88891)
		(width 0.13208)
		(layer "F.Cu")
		(net "SSD15_ADC_A0")
	)
	(segment
		(start 451.57898 -45.88891)
		(end 452.143622 -45.88891)
		(width 0.13208)
		(layer "F.Cu")
		(net "SSD15_ADC_A0")
	)
	(segment
		(start 451.385686 -45.35424)
		(end 451.385686 -45.695616)
		(width 0.13208)
		(layer "F.Cu")
		(net "SSD15_ADC_A0")
	)
	(segment
		(start 451.385686 -45.695616)
		(end 451.385686 -45.771816)
		(width 0.13208)
		(layer "F.Cu")
		(net "SSD15_ADC_A0")
	)
	(segment
		(start 450.963538 -46.193964)
		(end 450.545962 -46.193964)
		(width 0.13208)
		(layer "F.Cu")
		(net "SSD15_ADC_A0")
	)
	(via
		(at 448.869308 -48.8442)
		(size 0.508)
		(drill 0.254)
		(layers "F.Cu" "B.Cu")
		(net "SSD15_ADC_A0")
	)
	(via
		(at 451.385686 -45.35424)
		(size 0.508)
		(drill 0.254)
		(layers "F.Cu" "B.Cu")
		(net "SSD15_ADC_A0")
	)
	(segment
		(start 450.47027 -46.269656)
		(end 450.47027 -47.243238)
		(width 0.13208)
		(layer "B.Cu")
		(net "SSD15_ADC_A0")
	)
	(segment
		(start 450.47027 -47.243238)
		(end 448.869308 -48.8442)
		(width 0.13208)
		(layer "B.Cu")
		(net "SSD15_ADC_A0")
	)
	(segment
		(start 451.385686 -45.35424)
		(end 450.47027 -46.269656)
		(width 0.13208)
		(layer "B.Cu")
		(net "SSD15_ADC_A0")
	)
	(segment
		(start 374.143778 -42.84091)
		(end 374.143778 -43.85691)
		(width 0.13208)
		(layer "F.Cu")
		(net "SSD12_ADC_A1")
	)
	(segment
		(start 374.143778 -43.85691)
		(end 373.401844 -43.85691)
		(width 0.13208)
		(layer "F.Cu")
		(net "SSD12_ADC_A1")
	)
	(segment
		(start 372.815612 -42.853102)
		(end 374.131586 -42.853102)
		(width 0.13208)
		(layer "F.Cu")
		(net "SSD12_ADC_A1")
	)
	(segment
		(start 372.546118 -44.712636)
		(end 372.546118 -45.693838)
		(width 0.13208)
		(layer "F.Cu")
		(net "SSD12_ADC_A1")
	)
	(segment
		(start 374.131586 -42.853102)
		(end 374.143778 -42.84091)
		(width 0.13208)
		(layer "F.Cu")
		(net "SSD12_ADC_A1")
	)
	(segment
		(start 373.401844 -43.85691)
		(end 372.546118 -44.712636)
		(width 0.13208)
		(layer "F.Cu")
		(net "SSD12_ADC_A1")
	)
	(via
		(at 373.401844 -43.85691)
		(size 0.508)
		(drill 0.254)
		(layers "F.Cu" "B.Cu")
		(net "SSD12_ADC_A1")
	)
	(segment
		(start 425.385738 -45.35424)
		(end 425.385738 -45.695616)
		(width 0.13208)
		(layer "F.Cu")
		(net "SSD14_ADC_A0")
	)
	(segment
		(start 426.739558 -50.504598)
		(end 424.727878 -50.504598)
		(width 0.13208)
		(layer "F.Cu")
		(net "SSD14_ADC_A0")
	)
	(segment
		(start 425.385738 -45.695616)
		(end 425.385738 -45.771816)
		(width 0.13208)
		(layer "F.Cu")
		(net "SSD14_ADC_A0")
	)
	(segment
		(start 423.141902 -51.098196)
		(end 422.853866 -50.81016)
		(width 0.13208)
		(layer "F.Cu")
		(net "SSD14_ADC_A0")
	)
	(segment
		(start 425.579032 -45.88891)
		(end 425.385738 -45.695616)
		(width 0.13208)
		(layer "F.Cu")
		(net "SSD14_ADC_A0")
	)
	(segment
		(start 422.853866 -48.859694)
		(end 422.86936 -48.8442)
		(width 0.13208)
		(layer "F.Cu")
		(net "SSD14_ADC_A0")
	)
	(segment
		(start 424.96359 -46.193964)
		(end 424.546014 -46.193964)
		(width 0.13208)
		(layer "F.Cu")
		(net "SSD14_ADC_A0")
	)
	(segment
		(start 422.853866 -50.81016)
		(end 422.853866 -48.859694)
		(width 0.13208)
		(layer "F.Cu")
		(net "SSD14_ADC_A0")
	)
	(segment
		(start 425.385738 -45.771816)
		(end 424.96359 -46.193964)
		(width 0.13208)
		(layer "F.Cu")
		(net "SSD14_ADC_A0")
	)
	(segment
		(start 424.727878 -50.504598)
		(end 424.13428 -51.098196)
		(width 0.13208)
		(layer "F.Cu")
		(net "SSD14_ADC_A0")
	)
	(segment
		(start 426.143674 -44.87291)
		(end 426.143674 -45.88891)
		(width 0.13208)
		(layer "F.Cu")
		(net "SSD14_ADC_A0")
	)
	(segment
		(start 426.143674 -45.88891)
		(end 425.579032 -45.88891)
		(width 0.13208)
		(layer "F.Cu")
		(net "SSD14_ADC_A0")
	)
	(segment
		(start 426.943774 -50.300382)
		(end 426.739558 -50.504598)
		(width 0.13208)
		(layer "F.Cu")
		(net "SSD14_ADC_A0")
	)
	(segment
		(start 426.943774 -49.95291)
		(end 426.943774 -50.300382)
		(width 0.13208)
		(layer "F.Cu")
		(net "SSD14_ADC_A0")
	)
	(segment
		(start 424.13428 -51.098196)
		(end 423.141902 -51.098196)
		(width 0.13208)
		(layer "F.Cu")
		(net "SSD14_ADC_A0")
	)
	(via
		(at 422.86936 -48.8442)
		(size 0.508)
		(drill 0.254)
		(layers "F.Cu" "B.Cu")
		(net "SSD14_ADC_A0")
	)
	(via
		(at 425.385738 -45.35424)
		(size 0.508)
		(drill 0.254)
		(layers "F.Cu" "B.Cu")
		(net "SSD14_ADC_A0")
	)
	(segment
		(start 424.470322 -46.269656)
		(end 424.470322 -47.243238)
		(width 0.13208)
		(layer "B.Cu")
		(net "SSD14_ADC_A0")
	)
	(segment
		(start 425.385738 -45.35424)
		(end 424.470322 -46.269656)
		(width 0.13208)
		(layer "B.Cu")
		(net "SSD14_ADC_A0")
	)
	(segment
		(start 424.470322 -47.243238)
		(end 422.86936 -48.8442)
		(width 0.13208)
		(layer "B.Cu")
		(net "SSD14_ADC_A0")
	)
	(segment
		(start 452.13143 -42.853102)
		(end 452.143622 -42.84091)
		(width 0.13208)
		(layer "F.Cu")
		(net "SSD15_ADC_A1")
	)
	(segment
		(start 451.401688 -43.85691)
		(end 450.545962 -44.712636)
		(width 0.13208)
		(layer "F.Cu")
		(net "SSD15_ADC_A1")
	)
	(segment
		(start 450.815456 -42.853102)
		(end 452.13143 -42.853102)
		(width 0.13208)
		(layer "F.Cu")
		(net "SSD15_ADC_A1")
	)
	(segment
		(start 452.143622 -42.84091)
		(end 452.143622 -43.85691)
		(width 0.13208)
		(layer "F.Cu")
		(net "SSD15_ADC_A1")
	)
	(segment
		(start 452.143622 -43.85691)
		(end 451.401688 -43.85691)
		(width 0.13208)
		(layer "F.Cu")
		(net "SSD15_ADC_A1")
	)
	(segment
		(start 450.545962 -44.712636)
		(end 450.545962 -45.693838)
		(width 0.13208)
		(layer "F.Cu")
		(net "SSD15_ADC_A1")
	)
	(via
		(at 451.401688 -43.85691)
		(size 0.508)
		(drill 0.254)
		(layers "F.Cu" "B.Cu")
		(net "SSD15_ADC_A1")
	)
	(segment
		(start 398.546066 -44.712636)
		(end 399.401792 -43.85691)
		(width 0.13208)
		(layer "F.Cu")
		(net "SSD13_ADC_A1")
	)
	(segment
		(start 400.143726 -42.84091)
		(end 400.143726 -43.85691)
		(width 0.13208)
		(layer "F.Cu")
		(net "SSD13_ADC_A1")
	)
	(segment
		(start 398.81556 -42.853102)
		(end 400.131534 -42.853102)
		(width 0.13208)
		(layer "F.Cu")
		(net "SSD13_ADC_A1")
	)
	(segment
		(start 398.546066 -45.693838)
		(end 398.546066 -44.712636)
		(width 0.13208)
		(layer "F.Cu")
		(net "SSD13_ADC_A1")
	)
	(segment
		(start 399.401792 -43.85691)
		(end 400.143726 -43.85691)
		(width 0.13208)
		(layer "F.Cu")
		(net "SSD13_ADC_A1")
	)
	(segment
		(start 400.131534 -42.853102)
		(end 400.143726 -42.84091)
		(width 0.13208)
		(layer "F.Cu")
		(net "SSD13_ADC_A1")
	)
	(via
		(at 399.401792 -43.85691)
		(size 0.508)
		(drill 0.254)
		(layers "F.Cu" "B.Cu")
		(net "SSD13_ADC_A1")
	)
	(segment
		(start 424.815508 -42.853102)
		(end 426.131482 -42.853102)
		(width 0.13208)
		(layer "F.Cu")
		(net "SSD14_ADC_A1")
	)
	(segment
		(start 425.40174 -43.85691)
		(end 424.546014 -44.712636)
		(width 0.13208)
		(layer "F.Cu")
		(net "SSD14_ADC_A1")
	)
	(segment
		(start 426.143674 -43.85691)
		(end 425.40174 -43.85691)
		(width 0.13208)
		(layer "F.Cu")
		(net "SSD14_ADC_A1")
	)
	(segment
		(start 426.131482 -42.853102)
		(end 426.143674 -42.84091)
		(width 0.13208)
		(layer "F.Cu")
		(net "SSD14_ADC_A1")
	)
	(segment
		(start 426.143674 -42.84091)
		(end 426.143674 -43.85691)
		(width 0.13208)
		(layer "F.Cu")
		(net "SSD14_ADC_A1")
	)
	(segment
		(start 424.546014 -44.712636)
		(end 424.546014 -45.693838)
		(width 0.13208)
		(layer "F.Cu")
		(net "SSD14_ADC_A1")
	)
	(via
		(at 425.40174 -43.85691)
		(size 0.508)
		(drill 0.254)
		(layers "F.Cu" "B.Cu")
		(net "SSD14_ADC_A1")
	)
	(segment
		(start 258.84378 -48.93691)
		(end 259.515102 -48.93691)
		(width 0.13208)
		(layer "F.Cu")
		(net "SSD8_ADC_A1")
	)
	(segment
		(start 256.44602 -44.712636)
		(end 257.301746 -43.85691)
		(width 0.13208)
		(layer "F.Cu")
		(net "SSD8_ADC_A1")
	)
	(segment
		(start 256.44602 -45.693838)
		(end 256.44602 -44.712636)
		(width 0.13208)
		(layer "F.Cu")
		(net "SSD8_ADC_A1")
	)
	(segment
		(start 257.301746 -43.85691)
		(end 258.04368 -43.85691)
		(width 0.13208)
		(layer "F.Cu")
		(net "SSD8_ADC_A1")
	)
	(segment
		(start 258.04368 -42.84091)
		(end 258.04368 -43.85691)
		(width 0.13208)
		(layer "F.Cu")
		(net "SSD8_ADC_A1")
	)
	(via
		(at 259.515102 -48.93691)
		(size 0.508)
		(drill 0.254)
		(layers "F.Cu" "B.Cu")
		(net "SSD8_ADC_A1")
	)
	(via
		(at 257.301746 -43.85691)
		(size 0.508)
		(drill 0.254)
		(layers "F.Cu" "B.Cu")
		(net "SSD8_ADC_A1")
	)
	(segment
		(start 259.515102 -48.93691)
		(end 258.492244 -47.914052)
		(width 0.15494)
		(layer "In5.Cu")
		(net "SSD8_ADC_A1")
	)
	(segment
		(start 258.336034 -43.85691)
		(end 257.301746 -43.85691)
		(width 0.15494)
		(layer "In5.Cu")
		(net "SSD8_ADC_A1")
	)
	(segment
		(start 258.492244 -47.914052)
		(end 258.492244 -44.01312)
		(width 0.15494)
		(layer "In5.Cu")
		(net "SSD8_ADC_A1")
	)
	(segment
		(start 258.492244 -44.01312)
		(end 258.336034 -43.85691)
		(width 0.15494)
		(layer "In5.Cu")
		(net "SSD8_ADC_A1")
	)
	(via
		(at 269.435072 -267.578078)
		(size 0.508)
		(drill 0.254)
		(layers "F.Cu" "B.Cu")
		(net "SPI_PEX2_SDIO2_R")
	)
	(via
		(at 247.392952 -231.149652)
		(size 0.508)
		(drill 0.254)
		(layers "F.Cu" "B.Cu")
		(net "SPI_PEX2_SDIO2_R")
	)
	(segment
		(start 247.392952 -230.517192)
		(end 247.392952 -231.149652)
		(width 0.13208)
		(layer "B.Cu")
		(net "SPI_PEX2_SDIO2_R")
	)
	(segment
		(start 268.344904 -292.065964)
		(end 268.0208 -291.74186)
		(width 0.13208)
		(layer "B.Cu")
		(net "SPI_PEX2_SDIO2_R")
	)
	(segment
		(start 247.499632 -229.997)
		(end 247.499632 -230.410512)
		(width 0.13208)
		(layer "B.Cu")
		(net "SPI_PEX2_SDIO2_R")
	)
	(segment
		(start 271.918938 -293.387272)
		(end 271.581626 -293.04996)
		(width 0.13208)
		(layer "B.Cu")
		(net "SPI_PEX2_SDIO2_R")
	)
	(segment
		(start 268.501622 -268.511528)
		(end 269.435072 -267.578078)
		(width 0.13208)
		(layer "B.Cu")
		(net "SPI_PEX2_SDIO2_R")
	)
	(segment
		(start 271.581626 -293.04996)
		(end 271.102582 -293.04996)
		(width 0.13208)
		(layer "B.Cu")
		(net "SPI_PEX2_SDIO2_R")
	)
	(segment
		(start 271.102582 -293.04996)
		(end 270.921988 -292.869366)
		(width 0.13208)
		(layer "B.Cu")
		(net "SPI_PEX2_SDIO2_R")
	)
	(segment
		(start 247.499632 -230.410512)
		(end 247.392952 -230.517192)
		(width 0.13208)
		(layer "B.Cu")
		(net "SPI_PEX2_SDIO2_R")
	)
	(segment
		(start 271.918938 -294.8051)
		(end 271.918938 -293.387272)
		(width 0.13208)
		(layer "B.Cu")
		(net "SPI_PEX2_SDIO2_R")
	)
	(segment
		(start 268.0208 -275.04517)
		(end 268.501622 -274.564348)
		(width 0.13208)
		(layer "B.Cu")
		(net "SPI_PEX2_SDIO2_R")
	)
	(segment
		(start 268.501622 -274.564348)
		(end 268.501622 -268.511528)
		(width 0.13208)
		(layer "B.Cu")
		(net "SPI_PEX2_SDIO2_R")
	)
	(segment
		(start 270.921988 -292.401244)
		(end 270.586708 -292.065964)
		(width 0.13208)
		(layer "B.Cu")
		(net "SPI_PEX2_SDIO2_R")
	)
	(segment
		(start 268.0208 -291.74186)
		(end 268.0208 -275.04517)
		(width 0.13208)
		(layer "B.Cu")
		(net "SPI_PEX2_SDIO2_R")
	)
	(segment
		(start 270.921988 -292.869366)
		(end 270.921988 -292.401244)
		(width 0.13208)
		(layer "B.Cu")
		(net "SPI_PEX2_SDIO2_R")
	)
	(segment
		(start 270.586708 -292.065964)
		(end 268.344904 -292.065964)
		(width 0.13208)
		(layer "B.Cu")
		(net "SPI_PEX2_SDIO2_R")
	)
	(segment
		(start 249.932952 -253.249176)
		(end 248.767092 -253.249176)
		(width 0.15494)
		(layer "In5.Cu")
		(net "SPI_PEX2_SDIO2_R")
	)
	(segment
		(start 248.767092 -252.352556)
		(end 249.932952 -252.352556)
		(width 0.15494)
		(layer "In5.Cu")
		(net "SPI_PEX2_SDIO2_R")
	)
	(segment
		(start 248.632472 -252.487176)
		(end 248.767092 -252.352556)
		(width 0.15494)
		(layer "In5.Cu")
		(net "SPI_PEX2_SDIO2_R")
	)
	(segment
		(start 249.932952 -254.145796)
		(end 250.067572 -254.011176)
		(width 0.15494)
		(layer "In5.Cu")
		(net "SPI_PEX2_SDIO2_R")
	)
	(segment
		(start 248.521728 -248.766076)
		(end 249.932952 -248.766076)
		(width 0.15494)
		(layer "In5.Cu")
		(net "SPI_PEX2_SDIO2_R")
	)
	(segment
		(start 248.97461 -254.272796)
		(end 249.10161 -254.145796)
		(width 0.15494)
		(layer "In5.Cu")
		(net "SPI_PEX2_SDIO2_R")
	)
	(segment
		(start 249.932952 -247.869456)
		(end 248.767092 -247.869456)
		(width 0.15494)
		(layer "In5.Cu")
		(net "SPI_PEX2_SDIO2_R")
	)
	(segment
		(start 248.767092 -247.869456)
		(end 248.632472 -247.734836)
		(width 0.15494)
		(layer "In5.Cu")
		(net "SPI_PEX2_SDIO2_R")
	)
	(segment
		(start 249.932952 -250.559316)
		(end 250.067572 -250.424696)
		(width 0.15494)
		(layer "In5.Cu")
		(net "SPI_PEX2_SDIO2_R")
	)
	(segment
		(start 248.97461 -260.93293)
		(end 248.97461 -254.272796)
		(width 0.15494)
		(layer "In5.Cu")
		(net "SPI_PEX2_SDIO2_R")
	)
	(segment
		(start 248.767092 -253.249176)
		(end 248.632472 -253.114556)
		(width 0.15494)
		(layer "In5.Cu")
		(net "SPI_PEX2_SDIO2_R")
	)
	(segment
		(start 250.067572 -249.797316)
		(end 249.932952 -249.662696)
		(width 0.15494)
		(layer "In5.Cu")
		(net "SPI_PEX2_SDIO2_R")
	)
	(segment
		(start 250.067572 -250.424696)
		(end 250.067572 -249.797316)
		(width 0.15494)
		(layer "In5.Cu")
		(net "SPI_PEX2_SDIO2_R")
	)
	(segment
		(start 269.435072 -267.578078)
		(end 265.698478 -267.578078)
		(width 0.15494)
		(layer "In5.Cu")
		(net "SPI_PEX2_SDIO2_R")
	)
	(segment
		(start 265.698478 -267.578078)
		(end 264.19302 -266.07262)
		(width 0.15494)
		(layer "In5.Cu")
		(net "SPI_PEX2_SDIO2_R")
	)
	(segment
		(start 248.632472 -253.114556)
		(end 248.632472 -252.487176)
		(width 0.15494)
		(layer "In5.Cu")
		(net "SPI_PEX2_SDIO2_R")
	)
	(segment
		(start 248.521728 -249.662696)
		(end 248.387108 -249.528076)
		(width 0.15494)
		(layer "In5.Cu")
		(net "SPI_PEX2_SDIO2_R")
	)
	(segment
		(start 249.10161 -254.145796)
		(end 249.932952 -254.145796)
		(width 0.15494)
		(layer "In5.Cu")
		(net "SPI_PEX2_SDIO2_R")
	)
	(segment
		(start 264.19302 -266.07262)
		(end 254.1143 -266.07262)
		(width 0.15494)
		(layer "In5.Cu")
		(net "SPI_PEX2_SDIO2_R")
	)
	(segment
		(start 249.932952 -249.662696)
		(end 248.521728 -249.662696)
		(width 0.15494)
		(layer "In5.Cu")
		(net "SPI_PEX2_SDIO2_R")
	)
	(segment
		(start 250.067572 -253.383796)
		(end 249.932952 -253.249176)
		(width 0.15494)
		(layer "In5.Cu")
		(net "SPI_PEX2_SDIO2_R")
	)
	(segment
		(start 249.932952 -248.766076)
		(end 250.067572 -248.631456)
		(width 0.15494)
		(layer "In5.Cu")
		(net "SPI_PEX2_SDIO2_R")
	)
	(segment
		(start 254.1143 -266.07262)
		(end 248.97461 -260.93293)
		(width 0.15494)
		(layer "In5.Cu")
		(net "SPI_PEX2_SDIO2_R")
	)
	(segment
		(start 249.932952 -252.352556)
		(end 250.067572 -252.217936)
		(width 0.15494)
		(layer "In5.Cu")
		(net "SPI_PEX2_SDIO2_R")
	)
	(segment
		(start 248.632472 -232.389172)
		(end 247.392952 -231.149652)
		(width 0.15494)
		(layer "In5.Cu")
		(net "SPI_PEX2_SDIO2_R")
	)
	(segment
		(start 248.632472 -251.321316)
		(end 248.632472 -250.693936)
		(width 0.15494)
		(layer "In5.Cu")
		(net "SPI_PEX2_SDIO2_R")
	)
	(segment
		(start 250.067572 -254.011176)
		(end 250.067572 -253.383796)
		(width 0.15494)
		(layer "In5.Cu")
		(net "SPI_PEX2_SDIO2_R")
	)
	(segment
		(start 250.067572 -252.217936)
		(end 250.067572 -251.590556)
		(width 0.15494)
		(layer "In5.Cu")
		(net "SPI_PEX2_SDIO2_R")
	)
	(segment
		(start 248.387108 -249.528076)
		(end 248.387108 -248.900696)
		(width 0.15494)
		(layer "In5.Cu")
		(net "SPI_PEX2_SDIO2_R")
	)
	(segment
		(start 250.067572 -248.631456)
		(end 250.067572 -248.004076)
		(width 0.15494)
		(layer "In5.Cu")
		(net "SPI_PEX2_SDIO2_R")
	)
	(segment
		(start 249.932952 -251.455936)
		(end 248.767092 -251.455936)
		(width 0.15494)
		(layer "In5.Cu")
		(net "SPI_PEX2_SDIO2_R")
	)
	(segment
		(start 248.632472 -247.734836)
		(end 248.632472 -232.389172)
		(width 0.15494)
		(layer "In5.Cu")
		(net "SPI_PEX2_SDIO2_R")
	)
	(segment
		(start 248.767092 -251.455936)
		(end 248.632472 -251.321316)
		(width 0.15494)
		(layer "In5.Cu")
		(net "SPI_PEX2_SDIO2_R")
	)
	(segment
		(start 248.387108 -248.900696)
		(end 248.521728 -248.766076)
		(width 0.15494)
		(layer "In5.Cu")
		(net "SPI_PEX2_SDIO2_R")
	)
	(segment
		(start 248.632472 -250.693936)
		(end 248.767092 -250.559316)
		(width 0.15494)
		(layer "In5.Cu")
		(net "SPI_PEX2_SDIO2_R")
	)
	(segment
		(start 250.067572 -248.004076)
		(end 249.932952 -247.869456)
		(width 0.15494)
		(layer "In5.Cu")
		(net "SPI_PEX2_SDIO2_R")
	)
	(segment
		(start 248.767092 -250.559316)
		(end 249.932952 -250.559316)
		(width 0.15494)
		(layer "In5.Cu")
		(net "SPI_PEX2_SDIO2_R")
	)
	(segment
		(start 250.067572 -251.590556)
		(end 249.932952 -251.455936)
		(width 0.15494)
		(layer "In5.Cu")
		(net "SPI_PEX2_SDIO2_R")
	)
	(via
		(at 271.237964 -266.963398)
		(size 0.508)
		(drill 0.254)
		(layers "F.Cu" "B.Cu")
		(net "SPI_PEX2_CLK_R")
	)
	(via
		(at 251.5362 -227.965)
		(size 0.508)
		(drill 0.254)
		(layers "F.Cu" "B.Cu")
		(net "SPI_PEX2_CLK_R")
	)
	(segment
		(start 270.846296 -290.1696)
		(end 271.453356 -290.77666)
		(width 0.13208)
		(layer "B.Cu")
		(net "SPI_PEX2_CLK_R")
	)
	(segment
		(start 271.237964 -267.733018)
		(end 270.0528 -268.918182)
		(width 0.13208)
		(layer "B.Cu")
		(net "SPI_PEX2_CLK_R")
	)
	(segment
		(start 271.237964 -266.963398)
		(end 271.237964 -267.733018)
		(width 0.13208)
		(layer "B.Cu")
		(net "SPI_PEX2_CLK_R")
	)
	(segment
		(start 252.235716 -228.664516)
		(end 252.235716 -229.827582)
		(width 0.13208)
		(layer "B.Cu")
		(net "SPI_PEX2_CLK_R")
	)
	(segment
		(start 251.5362 -227.965)
		(end 252.235716 -228.664516)
		(width 0.13208)
		(layer "B.Cu")
		(net "SPI_PEX2_CLK_R")
	)
	(segment
		(start 270.0528 -289.8902)
		(end 270.3322 -290.1696)
		(width 0.13208)
		(layer "B.Cu")
		(net "SPI_PEX2_CLK_R")
	)
	(segment
		(start 271.453356 -291.323014)
		(end 271.856962 -291.72662)
		(width 0.13208)
		(layer "B.Cu")
		(net "SPI_PEX2_CLK_R")
	)
	(segment
		(start 270.0528 -268.918182)
		(end 270.0528 -289.8902)
		(width 0.13208)
		(layer "B.Cu")
		(net "SPI_PEX2_CLK_R")
	)
	(segment
		(start 271.453356 -290.77666)
		(end 271.453356 -291.323014)
		(width 0.13208)
		(layer "B.Cu")
		(net "SPI_PEX2_CLK_R")
	)
	(segment
		(start 270.3322 -290.1696)
		(end 270.846296 -290.1696)
		(width 0.13208)
		(layer "B.Cu")
		(net "SPI_PEX2_CLK_R")
	)
	(segment
		(start 250.17349 -260.435852)
		(end 254.611378 -264.87374)
		(width 0.15494)
		(layer "In5.Cu")
		(net "SPI_PEX2_CLK_R")
	)
	(segment
		(start 254.611378 -264.87374)
		(end 267.36294 -264.87374)
		(width 0.15494)
		(layer "In5.Cu")
		(net "SPI_PEX2_CLK_R")
	)
	(segment
		(start 250.17349 -256.554732)
		(end 250.17349 -260.435852)
		(width 0.15494)
		(layer "In5.Cu")
		(net "SPI_PEX2_CLK_R")
	)
	(segment
		(start 252.3998 -228.8286)
		(end 252.3998 -250.830842)
		(width 0.15494)
		(layer "In5.Cu")
		(net "SPI_PEX2_CLK_R")
	)
	(segment
		(start 267.36294 -264.87374)
		(end 268.138148 -265.648948)
		(width 0.15494)
		(layer "In5.Cu")
		(net "SPI_PEX2_CLK_R")
	)
	(segment
		(start 268.138148 -265.648948)
		(end 269.923514 -265.648948)
		(width 0.15494)
		(layer "In5.Cu")
		(net "SPI_PEX2_CLK_R")
	)
	(segment
		(start 251.788422 -254.9398)
		(end 250.17349 -256.554732)
		(width 0.15494)
		(layer "In5.Cu")
		(net "SPI_PEX2_CLK_R")
	)
	(segment
		(start 269.923514 -265.648948)
		(end 271.237964 -266.963398)
		(width 0.15494)
		(layer "In5.Cu")
		(net "SPI_PEX2_CLK_R")
	)
	(segment
		(start 251.5362 -227.965)
		(end 252.3998 -228.8286)
		(width 0.15494)
		(layer "In5.Cu")
		(net "SPI_PEX2_CLK_R")
	)
	(segment
		(start 251.788422 -251.44222)
		(end 251.788422 -254.9398)
		(width 0.15494)
		(layer "In5.Cu")
		(net "SPI_PEX2_CLK_R")
	)
	(segment
		(start 252.3998 -250.830842)
		(end 251.788422 -251.44222)
		(width 0.15494)
		(layer "In5.Cu")
		(net "SPI_PEX2_CLK_R")
	)
	(via
		(at 255.197102 -221.332806)
		(size 0.508)
		(drill 0.254)
		(layers "F.Cu" "B.Cu")
		(net "SPI_PEX2_SDIO3_R")
	)
	(via
		(at 273.450558 -264.498328)
		(size 0.508)
		(drill 0.254)
		(layers "F.Cu" "B.Cu")
		(net "SPI_PEX2_SDIO3_R")
	)
	(segment
		(start 270.868394 -287.343342)
		(end 270.868394 -269.007844)
		(width 0.13208)
		(layer "B.Cu")
		(net "SPI_PEX2_SDIO3_R")
	)
	(segment
		(start 272.794984 -267.081254)
		(end 272.794984 -265.153902)
		(width 0.13208)
		(layer "B.Cu")
		(net "SPI_PEX2_SDIO3_R")
	)
	(segment
		(start 271.899888 -288.374836)
		(end 270.868394 -287.343342)
		(width 0.13208)
		(layer "B.Cu")
		(net "SPI_PEX2_SDIO3_R")
	)
	(segment
		(start 270.868394 -269.007844)
		(end 272.794984 -267.081254)
		(width 0.13208)
		(layer "B.Cu")
		(net "SPI_PEX2_SDIO3_R")
	)
	(segment
		(start 255.197102 -221.332806)
		(end 256.282952 -221.332806)
		(width 0.13208)
		(layer "B.Cu")
		(net "SPI_PEX2_SDIO3_R")
	)
	(segment
		(start 272.794984 -265.153902)
		(end 273.450558 -264.498328)
		(width 0.13208)
		(layer "B.Cu")
		(net "SPI_PEX2_SDIO3_R")
	)
	(segment
		(start 255.438402 -260.32333)
		(end 255.438402 -259.744972)
		(width 0.15494)
		(layer "In5.Cu")
		(net "SPI_PEX2_SDIO3_R")
	)
	(segment
		(start 254.94488 -256.70256)
		(end 254.195834 -256.70256)
		(width 0.15494)
		(layer "In5.Cu")
		(net "SPI_PEX2_SDIO3_R")
	)
	(segment
		(start 254.442976 -231.884728)
		(end 256.177796 -230.149908)
		(width 0.15494)
		(layer "In5.Cu")
		(net "SPI_PEX2_SDIO3_R")
	)
	(segment
		(start 273.450558 -264.498328)
		(end 273.450558 -264.052304)
		(width 0.15494)
		(layer "In5.Cu")
		(net "SPI_PEX2_SDIO3_R")
	)
	(segment
		(start 254.75311 -254.240284)
		(end 254.75311 -252.992636)
		(width 0.15494)
		(layer "In5.Cu")
		(net "SPI_PEX2_SDIO3_R")
	)
	(segment
		(start 255.29794 -257.828796)
		(end 255.29794 -257.05562)
		(width 0.15494)
		(layer "In5.Cu")
		(net "SPI_PEX2_SDIO3_R")
	)
	(segment
		(start 254.442976 -252.682502)
		(end 254.442976 -231.884728)
		(width 0.15494)
		(layer "In5.Cu")
		(net "SPI_PEX2_SDIO3_R")
	)
	(segment
		(start 264.434828 -258.112514)
		(end 264.434828 -260.574536)
		(width 0.15494)
		(layer "In5.Cu")
		(net "SPI_PEX2_SDIO3_R")
	)
	(segment
		(start 253.740158 -255.253236)
		(end 254.75311 -254.240284)
		(width 0.15494)
		(layer "In5.Cu")
		(net "SPI_PEX2_SDIO3_R")
	)
	(segment
		(start 264.300208 -260.709156)
		(end 261.009384 -260.709156)
		(width 0.15494)
		(layer "In5.Cu")
		(net "SPI_PEX2_SDIO3_R")
	)
	(segment
		(start 254.663448 -258.970018)
		(end 254.663448 -258.463288)
		(width 0.15494)
		(layer "In5.Cu")
		(net "SPI_PEX2_SDIO3_R")
	)
	(segment
		(start 260.872986 -260.845554)
		(end 255.960626 -260.845554)
		(width 0.15494)
		(layer "In5.Cu")
		(net "SPI_PEX2_SDIO3_R")
	)
	(segment
		(start 256.177796 -221.772988)
		(end 255.737614 -221.332806)
		(width 0.15494)
		(layer "In5.Cu")
		(net "SPI_PEX2_SDIO3_R")
	)
	(segment
		(start 264.434828 -260.574536)
		(end 264.300208 -260.709156)
		(width 0.15494)
		(layer "In5.Cu")
		(net "SPI_PEX2_SDIO3_R")
	)
	(segment
		(start 256.177796 -230.149908)
		(end 256.177796 -221.772988)
		(width 0.15494)
		(layer "In5.Cu")
		(net "SPI_PEX2_SDIO3_R")
	)
	(segment
		(start 254.195834 -256.70256)
		(end 253.740158 -256.246884)
		(width 0.15494)
		(layer "In5.Cu")
		(net "SPI_PEX2_SDIO3_R")
	)
	(segment
		(start 265.333988 -258.112514)
		(end 265.079988 -257.858514)
		(width 0.15494)
		(layer "In5.Cu")
		(net "SPI_PEX2_SDIO3_R")
	)
	(segment
		(start 255.438402 -259.744972)
		(end 254.663448 -258.970018)
		(width 0.15494)
		(layer "In5.Cu")
		(net "SPI_PEX2_SDIO3_R")
	)
	(segment
		(start 273.450558 -264.052304)
		(end 271.012666 -261.614412)
		(width 0.15494)
		(layer "In5.Cu")
		(net "SPI_PEX2_SDIO3_R")
	)
	(segment
		(start 265.333988 -260.841744)
		(end 265.333988 -258.112514)
		(width 0.15494)
		(layer "In5.Cu")
		(net "SPI_PEX2_SDIO3_R")
	)
	(segment
		(start 254.75311 -252.992636)
		(end 254.442976 -252.682502)
		(width 0.15494)
		(layer "In5.Cu")
		(net "SPI_PEX2_SDIO3_R")
	)
	(segment
		(start 254.663448 -258.463288)
		(end 255.29794 -257.828796)
		(width 0.15494)
		(layer "In5.Cu")
		(net "SPI_PEX2_SDIO3_R")
	)
	(segment
		(start 255.960626 -260.845554)
		(end 255.438402 -260.32333)
		(width 0.15494)
		(layer "In5.Cu")
		(net "SPI_PEX2_SDIO3_R")
	)
	(segment
		(start 265.079988 -257.858514)
		(end 264.688828 -257.858514)
		(width 0.15494)
		(layer "In5.Cu")
		(net "SPI_PEX2_SDIO3_R")
	)
	(segment
		(start 264.688828 -257.858514)
		(end 264.434828 -258.112514)
		(width 0.15494)
		(layer "In5.Cu")
		(net "SPI_PEX2_SDIO3_R")
	)
	(segment
		(start 253.740158 -256.246884)
		(end 253.740158 -255.253236)
		(width 0.15494)
		(layer "In5.Cu")
		(net "SPI_PEX2_SDIO3_R")
	)
	(segment
		(start 255.29794 -257.05562)
		(end 254.94488 -256.70256)
		(width 0.15494)
		(layer "In5.Cu")
		(net "SPI_PEX2_SDIO3_R")
	)
	(segment
		(start 261.009384 -260.709156)
		(end 260.872986 -260.845554)
		(width 0.15494)
		(layer "In5.Cu")
		(net "SPI_PEX2_SDIO3_R")
	)
	(segment
		(start 266.106656 -261.614412)
		(end 265.333988 -260.841744)
		(width 0.15494)
		(layer "In5.Cu")
		(net "SPI_PEX2_SDIO3_R")
	)
	(segment
		(start 271.012666 -261.614412)
		(end 266.106656 -261.614412)
		(width 0.15494)
		(layer "In5.Cu")
		(net "SPI_PEX2_SDIO3_R")
	)
	(segment
		(start 255.737614 -221.332806)
		(end 255.197102 -221.332806)
		(width 0.15494)
		(layer "In5.Cu")
		(net "SPI_PEX2_SDIO3_R")
	)
	(segment
		(start 284.043628 -42.84091)
		(end 284.043628 -43.85691)
		(width 0.13208)
		(layer "F.Cu")
		(net "SSD9_ADC_A1")
	)
	(segment
		(start 282.715462 -42.853102)
		(end 284.031436 -42.853102)
		(width 0.13208)
		(layer "F.Cu")
		(net "SSD9_ADC_A1")
	)
	(segment
		(start 282.445968 -44.712636)
		(end 283.301694 -43.85691)
		(width 0.13208)
		(layer "F.Cu")
		(net "SSD9_ADC_A1")
	)
	(segment
		(start 282.445968 -45.693838)
		(end 282.445968 -44.712636)
		(width 0.13208)
		(layer "F.Cu")
		(net "SSD9_ADC_A1")
	)
	(segment
		(start 284.031436 -42.853102)
		(end 284.043628 -42.84091)
		(width 0.13208)
		(layer "F.Cu")
		(net "SSD9_ADC_A1")
	)
	(segment
		(start 283.301694 -43.85691)
		(end 284.043628 -43.85691)
		(width 0.13208)
		(layer "F.Cu")
		(net "SSD9_ADC_A1")
	)
	(via
		(at 283.301694 -43.85691)
		(size 0.508)
		(drill 0.254)
		(layers "F.Cu" "B.Cu")
		(net "SSD9_ADC_A1")
	)
	(via
		(at 251.284994 -233.772456)
		(size 0.508)
		(drill 0.254)
		(layers "F.Cu" "B.Cu")
		(net "SPI_PEX2_CS_R_N")
	)
	(via
		(at 272.854928 -268.182344)
		(size 0.508)
		(drill 0.254)
		(layers "F.Cu" "B.Cu")
		(net "SPI_PEX2_CS_R_N")
	)
	(via
		(at 250.330716 -232.012236)
		(size 0.6604)
		(drill 0.3302)
		(layers "F.Cu" "B.Cu")
		(net "SPI_PEX2_CS_R_N")
	)
	(segment
		(start 251.284994 -233.772456)
		(end 250.900438 -233.3879)
		(width 0.13208)
		(layer "B.Cu")
		(net "SPI_PEX2_CS_R_N")
	)
	(segment
		(start 250.900438 -233.3879)
		(end 250.330716 -232.012236)
		(width 0.13208)
		(layer "B.Cu")
		(net "SPI_PEX2_CS_R_N")
	)
	(segment
		(start 271.88414 -271.28724)
		(end 272.854928 -270.316452)
		(width 0.13208)
		(layer "B.Cu")
		(net "SPI_PEX2_CS_R_N")
	)
	(segment
		(start 272.854928 -270.316452)
		(end 272.854928 -268.182344)
		(width 0.13208)
		(layer "B.Cu")
		(net "SPI_PEX2_CS_R_N")
	)
	(segment
		(start 250.330716 -232.012236)
		(end 250.330716 -229.827582)
		(width 0.13208)
		(layer "B.Cu")
		(net "SPI_PEX2_CS_R_N")
	)
	(segment
		(start 271.88414 -287.409128)
		(end 271.88414 -271.28724)
		(width 0.13208)
		(layer "B.Cu")
		(net "SPI_PEX2_CS_R_N")
	)
	(segment
		(start 272.849848 -288.374836)
		(end 271.88414 -287.409128)
		(width 0.13208)
		(layer "B.Cu")
		(net "SPI_PEX2_CS_R_N")
	)
	(segment
		(start 250.270518 -238.683292)
		(end 250.405138 -238.817912)
		(width 0.15494)
		(layer "In5.Cu")
		(net "SPI_PEX2_CS_R_N")
	)
	(segment
		(start 250.981464 -242.404392)
		(end 251.116084 -242.539012)
		(width 0.15494)
		(layer "In5.Cu")
		(net "SPI_PEX2_CS_R_N")
	)
	(segment
		(start 265.81608 -265.53668)
		(end 266.591288 -266.311888)
		(width 0.15494)
		(layer "In5.Cu")
		(net "SPI_PEX2_CS_R_N")
	)
	(segment
		(start 250.6726 -244.197632)
		(end 250.7996 -244.324632)
		(width 0.15494)
		(layer "In5.Cu")
		(net "SPI_PEX2_CS_R_N")
	)
	(segment
		(start 250.405138 -241.507772)
		(end 250.270518 -241.642392)
		(width 0.15494)
		(layer "In5.Cu")
		(net "SPI_PEX2_CS_R_N")
	)
	(segment
		(start 249.51055 -260.71068)
		(end 254.33655 -265.53668)
		(width 0.15494)
		(layer "In5.Cu")
		(net "SPI_PEX2_CS_R_N")
	)
	(segment
		(start 251.116084 -241.373152)
		(end 250.981464 -241.507772)
		(width 0.15494)
		(layer "In5.Cu")
		(net "SPI_PEX2_CS_R_N")
	)
	(segment
		(start 266.591288 -266.311888)
		(end 269.648432 -266.311888)
		(width 0.15494)
		(layer "In5.Cu")
		(net "SPI_PEX2_CS_R_N")
	)
	(segment
		(start 250.270518 -239.849152)
		(end 250.270518 -240.476532)
		(width 0.15494)
		(layer "In5.Cu")
		(net "SPI_PEX2_CS_R_N")
	)
	(segment
		(start 250.981464 -238.817912)
		(end 251.116084 -238.952532)
		(width 0.15494)
		(layer "In5.Cu")
		(net "SPI_PEX2_CS_R_N")
	)
	(segment
		(start 250.405138 -240.611152)
		(end 250.981464 -240.611152)
		(width 0.15494)
		(layer "In5.Cu")
		(net "SPI_PEX2_CS_R_N")
	)
	(segment
		(start 270.2814 -267.775182)
		(end 270.4084 -267.902182)
		(width 0.15494)
		(layer "In5.Cu")
		(net "SPI_PEX2_CS_R_N")
	)
	(segment
		(start 251.284994 -237.514892)
		(end 250.878594 -237.921292)
		(width 0.15494)
		(layer "In5.Cu")
		(net "SPI_PEX2_CS_R_N")
	)
	(segment
		(start 251.116084 -242.539012)
		(end 251.116084 -243.166392)
		(width 0.15494)
		(layer "In5.Cu")
		(net "SPI_PEX2_CS_R_N")
	)
	(segment
		(start 250.270518 -238.055912)
		(end 250.270518 -238.683292)
		(width 0.15494)
		(layer "In5.Cu")
		(net "SPI_PEX2_CS_R_N")
	)
	(segment
		(start 270.4084 -267.902182)
		(end 272.574766 -267.902182)
		(width 0.15494)
		(layer "In5.Cu")
		(net "SPI_PEX2_CS_R_N")
	)
	(segment
		(start 250.7996 -254.507746)
		(end 249.51055 -255.796796)
		(width 0.15494)
		(layer "In5.Cu")
		(net "SPI_PEX2_CS_R_N")
	)
	(segment
		(start 250.194318 -244.063012)
		(end 250.328938 -244.197632)
		(width 0.15494)
		(layer "In5.Cu")
		(net "SPI_PEX2_CS_R_N")
	)
	(segment
		(start 250.981464 -243.301012)
		(end 250.328938 -243.301012)
		(width 0.15494)
		(layer "In5.Cu")
		(net "SPI_PEX2_CS_R_N")
	)
	(segment
		(start 250.328938 -244.197632)
		(end 250.6726 -244.197632)
		(width 0.15494)
		(layer "In5.Cu")
		(net "SPI_PEX2_CS_R_N")
	)
	(segment
		(start 250.270518 -241.642392)
		(end 250.270518 -242.269772)
		(width 0.15494)
		(layer "In5.Cu")
		(net "SPI_PEX2_CS_R_N")
	)
	(segment
		(start 250.328938 -243.301012)
		(end 250.194318 -243.435632)
		(width 0.15494)
		(layer "In5.Cu")
		(net "SPI_PEX2_CS_R_N")
	)
	(segment
		(start 250.981464 -241.507772)
		(end 250.405138 -241.507772)
		(width 0.15494)
		(layer "In5.Cu")
		(net "SPI_PEX2_CS_R_N")
	)
	(segment
		(start 250.7996 -244.324632)
		(end 250.7996 -254.507746)
		(width 0.15494)
		(layer "In5.Cu")
		(net "SPI_PEX2_CS_R_N")
	)
	(segment
		(start 251.116084 -239.579912)
		(end 250.981464 -239.714532)
		(width 0.15494)
		(layer "In5.Cu")
		(net "SPI_PEX2_CS_R_N")
	)
	(segment
		(start 250.405138 -237.921292)
		(end 250.270518 -238.055912)
		(width 0.15494)
		(layer "In5.Cu")
		(net "SPI_PEX2_CS_R_N")
	)
	(segment
		(start 250.194318 -243.435632)
		(end 250.194318 -244.063012)
		(width 0.15494)
		(layer "In5.Cu")
		(net "SPI_PEX2_CS_R_N")
	)
	(segment
		(start 270.2814 -266.944856)
		(end 270.2814 -267.775182)
		(width 0.15494)
		(layer "In5.Cu")
		(net "SPI_PEX2_CS_R_N")
	)
	(segment
		(start 250.878594 -237.921292)
		(end 250.405138 -237.921292)
		(width 0.15494)
		(layer "In5.Cu")
		(net "SPI_PEX2_CS_R_N")
	)
	(segment
		(start 251.116084 -240.745772)
		(end 251.116084 -241.373152)
		(width 0.15494)
		(layer "In5.Cu")
		(net "SPI_PEX2_CS_R_N")
	)
	(segment
		(start 250.405138 -239.714532)
		(end 250.270518 -239.849152)
		(width 0.15494)
		(layer "In5.Cu")
		(net "SPI_PEX2_CS_R_N")
	)
	(segment
		(start 250.405138 -238.817912)
		(end 250.981464 -238.817912)
		(width 0.15494)
		(layer "In5.Cu")
		(net "SPI_PEX2_CS_R_N")
	)
	(segment
		(start 250.405138 -242.404392)
		(end 250.981464 -242.404392)
		(width 0.15494)
		(layer "In5.Cu")
		(net "SPI_PEX2_CS_R_N")
	)
	(segment
		(start 272.574766 -267.902182)
		(end 272.854928 -268.182344)
		(width 0.15494)
		(layer "In5.Cu")
		(net "SPI_PEX2_CS_R_N")
	)
	(segment
		(start 250.270518 -240.476532)
		(end 250.405138 -240.611152)
		(width 0.15494)
		(layer "In5.Cu")
		(net "SPI_PEX2_CS_R_N")
	)
	(segment
		(start 251.116084 -243.166392)
		(end 250.981464 -243.301012)
		(width 0.15494)
		(layer "In5.Cu")
		(net "SPI_PEX2_CS_R_N")
	)
	(segment
		(start 250.981464 -240.611152)
		(end 251.116084 -240.745772)
		(width 0.15494)
		(layer "In5.Cu")
		(net "SPI_PEX2_CS_R_N")
	)
	(segment
		(start 250.270518 -242.269772)
		(end 250.405138 -242.404392)
		(width 0.15494)
		(layer "In5.Cu")
		(net "SPI_PEX2_CS_R_N")
	)
	(segment
		(start 251.284994 -233.772456)
		(end 251.284994 -237.514892)
		(width 0.15494)
		(layer "In5.Cu")
		(net "SPI_PEX2_CS_R_N")
	)
	(segment
		(start 250.981464 -239.714532)
		(end 250.405138 -239.714532)
		(width 0.15494)
		(layer "In5.Cu")
		(net "SPI_PEX2_CS_R_N")
	)
	(segment
		(start 249.51055 -255.796796)
		(end 249.51055 -260.71068)
		(width 0.15494)
		(layer "In5.Cu")
		(net "SPI_PEX2_CS_R_N")
	)
	(segment
		(start 251.116084 -238.952532)
		(end 251.116084 -239.579912)
		(width 0.15494)
		(layer "In5.Cu")
		(net "SPI_PEX2_CS_R_N")
	)
	(segment
		(start 269.648432 -266.311888)
		(end 270.2814 -266.944856)
		(width 0.15494)
		(layer "In5.Cu")
		(net "SPI_PEX2_CS_R_N")
	)
	(segment
		(start 254.33655 -265.53668)
		(end 265.81608 -265.53668)
		(width 0.15494)
		(layer "In5.Cu")
		(net "SPI_PEX2_CS_R_N")
	)
	(via
		(at 268.531848 -264.250424)
		(size 0.508)
		(drill 0.254)
		(layers "F.Cu" "B.Cu")
		(net "SPI_PEX2_SDIO1_R")
	)
	(via
		(at 250.965716 -225.623882)
		(size 0.508)
		(drill 0.254)
		(layers "F.Cu" "B.Cu")
		(net "SPI_PEX2_SDIO1_R")
	)
	(segment
		(start 269.10538 -294.27678)
		(end 267.4366 -292.608)
		(width 0.13208)
		(layer "B.Cu")
		(net "SPI_PEX2_SDIO1_R")
	)
	(segment
		(start 269.536164 -295.037764)
		(end 269.10538 -294.60698)
		(width 0.13208)
		(layer "B.Cu")
		(net "SPI_PEX2_SDIO1_R")
	)
	(segment
		(start 270.967962 -296.475658)
		(end 270.967962 -296.164762)
		(width 0.13208)
		(layer "B.Cu")
		(net "SPI_PEX2_SDIO1_R")
	)
	(segment
		(start 269.840964 -295.037764)
		(end 269.536164 -295.037764)
		(width 0.13208)
		(layer "B.Cu")
		(net "SPI_PEX2_SDIO1_R")
	)
	(segment
		(start 250.965716 -224.341182)
		(end 250.965716 -225.623882)
		(width 0.13208)
		(layer "B.Cu")
		(net "SPI_PEX2_SDIO1_R")
	)
	(segment
		(start 270.967962 -296.164762)
		(end 269.840964 -295.037764)
		(width 0.13208)
		(layer "B.Cu")
		(net "SPI_PEX2_SDIO1_R")
	)
	(segment
		(start 269.10538 -294.60698)
		(end 269.10538 -294.27678)
		(width 0.13208)
		(layer "B.Cu")
		(net "SPI_PEX2_SDIO1_R")
	)
	(segment
		(start 267.4366 -292.608)
		(end 267.4366 -265.345672)
		(width 0.13208)
		(layer "B.Cu")
		(net "SPI_PEX2_SDIO1_R")
	)
	(segment
		(start 267.4366 -265.345672)
		(end 268.531848 -264.250424)
		(width 0.13208)
		(layer "B.Cu")
		(net "SPI_PEX2_SDIO1_R")
	)
	(segment
		(start 271.973548 -296.9514)
		(end 271.922748 -296.9006)
		(width 0.13208)
		(layer "B.Cu")
		(net "SPI_PEX2_SDIO1_R")
	)
	(segment
		(start 271.392904 -296.9006)
		(end 270.967962 -296.475658)
		(width 0.13208)
		(layer "B.Cu")
		(net "SPI_PEX2_SDIO1_R")
	)
	(segment
		(start 271.922748 -296.9006)
		(end 271.392904 -296.9006)
		(width 0.13208)
		(layer "B.Cu")
		(net "SPI_PEX2_SDIO1_R")
	)
	(segment
		(start 268.43609 -264.2108)
		(end 268.531848 -264.250424)
		(width 0.15494)
		(layer "In5.Cu")
		(net "SPI_PEX2_SDIO1_R")
	)
	(segment
		(start 253.06274 -227.720906)
		(end 253.06274 -251.463556)
		(width 0.15494)
		(layer "In5.Cu")
		(net "SPI_PEX2_SDIO1_R")
	)
	(segment
		(start 256.80416 -264.2108)
		(end 268.43609 -264.2108)
		(width 0.15494)
		(layer "In5.Cu")
		(net "SPI_PEX2_SDIO1_R")
	)
	(segment
		(start 250.965716 -225.623882)
		(end 253.06274 -227.720906)
		(width 0.15494)
		(layer "In5.Cu")
		(net "SPI_PEX2_SDIO1_R")
	)
	(segment
		(start 253.06274 -251.463556)
		(end 252.456696 -252.0696)
		(width 0.15494)
		(layer "In5.Cu")
		(net "SPI_PEX2_SDIO1_R")
	)
	(segment
		(start 252.456696 -252.0696)
		(end 252.456696 -259.863336)
		(width 0.15494)
		(layer "In5.Cu")
		(net "SPI_PEX2_SDIO1_R")
	)
	(segment
		(start 252.456696 -259.863336)
		(end 256.80416 -264.2108)
		(width 0.15494)
		(layer "In5.Cu")
		(net "SPI_PEX2_SDIO1_R")
	)
	(via
		(at 270.530066 -263.37768)
		(size 0.508)
		(drill 0.254)
		(layers "F.Cu" "B.Cu")
		(net "SPI_PEX2_SDIO0_R")
	)
	(via
		(at 253.571502 -225.62693)
		(size 0.508)
		(drill 0.254)
		(layers "F.Cu" "B.Cu")
		(net "SPI_PEX2_SDIO0_R")
	)
	(segment
		(start 271.973548 -295.79824)
		(end 271.080992 -294.905684)
		(width 0.13208)
		(layer "B.Cu")
		(net "SPI_PEX2_SDIO0_R")
	)
	(segment
		(start 253.480062 -225.62693)
		(end 252.870716 -225.017584)
		(width 0.13208)
		(layer "B.Cu")
		(net "SPI_PEX2_SDIO0_R")
	)
	(segment
		(start 267.988542 -265.919204)
		(end 270.530066 -263.37768)
		(width 0.13208)
		(layer "B.Cu")
		(net "SPI_PEX2_SDIO0_R")
	)
	(segment
		(start 270.635476 -294.004492)
		(end 269.417546 -294.004492)
		(width 0.13208)
		(layer "B.Cu")
		(net "SPI_PEX2_SDIO0_R")
	)
	(segment
		(start 271.080992 -294.450008)
		(end 270.635476 -294.004492)
		(width 0.13208)
		(layer "B.Cu")
		(net "SPI_PEX2_SDIO0_R")
	)
	(segment
		(start 253.571502 -225.62693)
		(end 253.480062 -225.62693)
		(width 0.13208)
		(layer "B.Cu")
		(net "SPI_PEX2_SDIO0_R")
	)
	(segment
		(start 267.697204 -292.28415)
		(end 267.697204 -271.966436)
		(width 0.13208)
		(layer "B.Cu")
		(net "SPI_PEX2_SDIO0_R")
	)
	(segment
		(start 267.988542 -271.675098)
		(end 267.988542 -265.919204)
		(width 0.13208)
		(layer "B.Cu")
		(net "SPI_PEX2_SDIO0_R")
	)
	(segment
		(start 252.870716 -225.017584)
		(end 252.870716 -224.341182)
		(width 0.13208)
		(layer "B.Cu")
		(net "SPI_PEX2_SDIO0_R")
	)
	(segment
		(start 267.697204 -271.966436)
		(end 267.988542 -271.675098)
		(width 0.13208)
		(layer "B.Cu")
		(net "SPI_PEX2_SDIO0_R")
	)
	(segment
		(start 271.080992 -294.905684)
		(end 271.080992 -294.450008)
		(width 0.13208)
		(layer "B.Cu")
		(net "SPI_PEX2_SDIO0_R")
	)
	(segment
		(start 269.417546 -294.004492)
		(end 267.697204 -292.28415)
		(width 0.13208)
		(layer "B.Cu")
		(net "SPI_PEX2_SDIO0_R")
	)
	(segment
		(start 256.889504 -263.537954)
		(end 270.369792 -263.537954)
		(width 0.15494)
		(layer "In5.Cu")
		(net "SPI_PEX2_SDIO0_R")
	)
	(segment
		(start 253.59868 -225.654108)
		(end 253.59868 -252.009656)
		(width 0.15494)
		(layer "In5.Cu")
		(net "SPI_PEX2_SDIO0_R")
	)
	(segment
		(start 253.571502 -225.62693)
		(end 253.59868 -225.654108)
		(width 0.15494)
		(layer "In5.Cu")
		(net "SPI_PEX2_SDIO0_R")
	)
	(segment
		(start 253.59868 -252.009656)
		(end 253.097284 -252.511052)
		(width 0.15494)
		(layer "In5.Cu")
		(net "SPI_PEX2_SDIO0_R")
	)
	(segment
		(start 253.097284 -259.745734)
		(end 256.889504 -263.537954)
		(width 0.15494)
		(layer "In5.Cu")
		(net "SPI_PEX2_SDIO0_R")
	)
	(segment
		(start 253.097284 -252.511052)
		(end 253.097284 -259.745734)
		(width 0.15494)
		(layer "In5.Cu")
		(net "SPI_PEX2_SDIO0_R")
	)
	(segment
		(start 270.369792 -263.537954)
		(end 270.530066 -263.37768)
		(width 0.15494)
		(layer "In5.Cu")
		(net "SPI_PEX2_SDIO0_R")
	)
	(segment
		(start 338.093812 -227.987098)
		(end 338.093812 -228.727)
		(width 0.13208)
		(layer "F.Cu")
		(net "JP_FPGA_DEBUG_N")
	)
	(segment
		(start 353.703636 -244.976142)
		(end 355.758496 -244.976142)
		(width 0.13208)
		(layer "F.Cu")
		(net "JP_FPGA_DEBUG_N")
	)
	(segment
		(start 355.758496 -244.976142)
		(end 356.124256 -245.341902)
		(width 0.13208)
		(layer "F.Cu")
		(net "JP_FPGA_DEBUG_N")
	)
	(via
		(at 338.093812 -228.727)
		(size 0.508)
		(drill 0.254)
		(layers "F.Cu" "B.Cu")
		(net "JP_FPGA_DEBUG_N")
	)
	(via
		(at 356.124256 -245.341902)
		(size 0.508)
		(drill 0.254)
		(layers "F.Cu" "B.Cu")
		(net "JP_FPGA_DEBUG_N")
	)
	(segment
		(start 356.124256 -244.139974)
		(end 356.124256 -245.341902)
		(width 0.13208)
		(layer "B.Cu")
		(net "JP_FPGA_DEBUG_N")
	)
	(segment
		(start 346.547694 -237.967774)
		(end 346.319348 -238.19612)
		(width 0.15494)
		(layer "In7.Cu")
		(net "JP_FPGA_DEBUG_N")
	)
	(segment
		(start 346.8878 -240.212118)
		(end 345.999562 -241.100356)
		(width 0.15494)
		(layer "In7.Cu")
		(net "JP_FPGA_DEBUG_N")
	)
	(segment
		(start 345.999562 -241.100356)
		(end 342.547448 -241.100356)
		(width 0.15494)
		(layer "In7.Cu")
		(net "JP_FPGA_DEBUG_N")
	)
	(segment
		(start 339.471 -233.507026)
		(end 338.616544 -232.65257)
		(width 0.15494)
		(layer "In7.Cu")
		(net "JP_FPGA_DEBUG_N")
	)
	(segment
		(start 346.319348 -238.19612)
		(end 346.319348 -238.780574)
		(width 0.15494)
		(layer "In7.Cu")
		(net "JP_FPGA_DEBUG_N")
	)
	(segment
		(start 356.124256 -242.76812)
		(end 351.32391 -237.967774)
		(width 0.15494)
		(layer "In7.Cu")
		(net "JP_FPGA_DEBUG_N")
	)
	(segment
		(start 346.8878 -239.349026)
		(end 346.8878 -240.212118)
		(width 0.15494)
		(layer "In7.Cu")
		(net "JP_FPGA_DEBUG_N")
	)
	(segment
		(start 338.616544 -232.65257)
		(end 338.616544 -229.249732)
		(width 0.15494)
		(layer "In7.Cu")
		(net "JP_FPGA_DEBUG_N")
	)
	(segment
		(start 356.124256 -245.341902)
		(end 356.124256 -242.76812)
		(width 0.15494)
		(layer "In7.Cu")
		(net "JP_FPGA_DEBUG_N")
	)
	(segment
		(start 351.32391 -237.967774)
		(end 346.547694 -237.967774)
		(width 0.15494)
		(layer "In7.Cu")
		(net "JP_FPGA_DEBUG_N")
	)
	(segment
		(start 342.547448 -241.100356)
		(end 339.471 -238.023908)
		(width 0.15494)
		(layer "In7.Cu")
		(net "JP_FPGA_DEBUG_N")
	)
	(segment
		(start 346.319348 -238.780574)
		(end 346.8878 -239.349026)
		(width 0.15494)
		(layer "In7.Cu")
		(net "JP_FPGA_DEBUG_N")
	)
	(segment
		(start 339.471 -238.023908)
		(end 339.471 -233.507026)
		(width 0.15494)
		(layer "In7.Cu")
		(net "JP_FPGA_DEBUG_N")
	)
	(segment
		(start 338.616544 -229.249732)
		(end 338.093812 -228.727)
		(width 0.15494)
		(layer "In7.Cu")
		(net "JP_FPGA_DEBUG_N")
	)
	(segment
		(start 306.880768 -50.93716)
		(end 306.753768 -50.81016)
		(width 0.13208)
		(layer "F.Cu")
		(net "SSD10_ADC_A0")
	)
	(segment
		(start 309.28564 -45.695616)
		(end 309.478934 -45.88891)
		(width 0.13208)
		(layer "F.Cu")
		(net "SSD10_ADC_A0")
	)
	(segment
		(start 309.28564 -45.35424)
		(end 309.28564 -45.695616)
		(width 0.13208)
		(layer "F.Cu")
		(net "SSD10_ADC_A0")
	)
	(segment
		(start 306.753768 -48.859694)
		(end 306.769262 -48.8442)
		(width 0.13208)
		(layer "F.Cu")
		(net "SSD10_ADC_A0")
	)
	(segment
		(start 308.195218 -50.93716)
		(end 306.880768 -50.93716)
		(width 0.13208)
		(layer "F.Cu")
		(net "SSD10_ADC_A0")
	)
	(segment
		(start 310.843676 -50.277014)
		(end 310.616092 -50.504598)
		(width 0.13208)
		(layer "F.Cu")
		(net "SSD10_ADC_A0")
	)
	(segment
		(start 308.445916 -46.193964)
		(end 308.863492 -46.193964)
		(width 0.13208)
		(layer "F.Cu")
		(net "SSD10_ADC_A0")
	)
	(segment
		(start 308.863492 -46.193964)
		(end 309.28564 -45.771816)
		(width 0.13208)
		(layer "F.Cu")
		(net "SSD10_ADC_A0")
	)
	(segment
		(start 308.62778 -50.504598)
		(end 308.195218 -50.93716)
		(width 0.13208)
		(layer "F.Cu")
		(net "SSD10_ADC_A0")
	)
	(segment
		(start 306.753768 -50.81016)
		(end 306.753768 -48.859694)
		(width 0.13208)
		(layer "F.Cu")
		(net "SSD10_ADC_A0")
	)
	(segment
		(start 310.043576 -44.87291)
		(end 310.043576 -45.88891)
		(width 0.13208)
		(layer "F.Cu")
		(net "SSD10_ADC_A0")
	)
	(segment
		(start 309.28564 -45.771816)
		(end 309.28564 -45.695616)
		(width 0.13208)
		(layer "F.Cu")
		(net "SSD10_ADC_A0")
	)
	(segment
		(start 310.616092 -50.504598)
		(end 308.62778 -50.504598)
		(width 0.13208)
		(layer "F.Cu")
		(net "SSD10_ADC_A0")
	)
	(segment
		(start 309.478934 -45.88891)
		(end 310.043576 -45.88891)
		(width 0.13208)
		(layer "F.Cu")
		(net "SSD10_ADC_A0")
	)
	(segment
		(start 310.843676 -49.95291)
		(end 310.843676 -50.277014)
		(width 0.13208)
		(layer "F.Cu")
		(net "SSD10_ADC_A0")
	)
	(via
		(at 309.28564 -45.35424)
		(size 0.508)
		(drill 0.254)
		(layers "F.Cu" "B.Cu")
		(net "SSD10_ADC_A0")
	)
	(via
		(at 306.769262 -48.8442)
		(size 0.508)
		(drill 0.254)
		(layers "F.Cu" "B.Cu")
		(net "SSD10_ADC_A0")
	)
	(segment
		(start 309.28564 -45.35424)
		(end 308.370224 -46.269656)
		(width 0.13208)
		(layer "B.Cu")
		(net "SSD10_ADC_A0")
	)
	(segment
		(start 308.370224 -46.269656)
		(end 308.370224 -47.243238)
		(width 0.13208)
		(layer "B.Cu")
		(net "SSD10_ADC_A0")
	)
	(segment
		(start 308.370224 -47.243238)
		(end 306.769262 -48.8442)
		(width 0.13208)
		(layer "B.Cu")
		(net "SSD10_ADC_A0")
	)
	(segment
		(start 335.285588 -45.35424)
		(end 335.285588 -45.695616)
		(width 0.13208)
		(layer "F.Cu")
		(net "SSD11_ADC_A0")
	)
	(segment
		(start 334.86344 -46.193964)
		(end 334.445864 -46.193964)
		(width 0.13208)
		(layer "F.Cu")
		(net "SSD11_ADC_A0")
	)
	(segment
		(start 336.043524 -45.88891)
		(end 335.478882 -45.88891)
		(width 0.13208)
		(layer "F.Cu")
		(net "SSD11_ADC_A0")
	)
	(segment
		(start 332.76921 -49.548796)
		(end 332.76921 -48.8442)
		(width 0.13208)
		(layer "F.Cu")
		(net "SSD11_ADC_A0")
	)
	(segment
		(start 333.161894 -49.94148)
		(end 332.76921 -49.548796)
		(width 0.13208)
		(layer "F.Cu")
		(net "SSD11_ADC_A0")
	)
	(segment
		(start 334.183228 -49.94148)
		(end 333.161894 -49.94148)
		(width 0.13208)
		(layer "F.Cu")
		(net "SSD11_ADC_A0")
	)
	(segment
		(start 335.285588 -45.771816)
		(end 334.86344 -46.193964)
		(width 0.13208)
		(layer "F.Cu")
		(net "SSD11_ADC_A0")
	)
	(segment
		(start 335.478882 -45.88891)
		(end 335.285588 -45.695616)
		(width 0.13208)
		(layer "F.Cu")
		(net "SSD11_ADC_A0")
	)
	(segment
		(start 335.285588 -45.695616)
		(end 335.285588 -45.771816)
		(width 0.13208)
		(layer "F.Cu")
		(net "SSD11_ADC_A0")
	)
	(segment
		(start 336.043524 -44.87291)
		(end 336.043524 -45.88891)
		(width 0.13208)
		(layer "F.Cu")
		(net "SSD11_ADC_A0")
	)
	(via
		(at 332.76921 -48.8442)
		(size 0.508)
		(drill 0.254)
		(layers "F.Cu" "B.Cu")
		(net "SSD11_ADC_A0")
	)
	(via
		(at 335.285588 -45.35424)
		(size 0.508)
		(drill 0.254)
		(layers "F.Cu" "B.Cu")
		(net "SSD11_ADC_A0")
	)
	(segment
		(start 334.370172 -47.243238)
		(end 332.76921 -48.8442)
		(width 0.13208)
		(layer "B.Cu")
		(net "SSD11_ADC_A0")
	)
	(segment
		(start 335.285588 -45.35424)
		(end 334.370172 -46.269656)
		(width 0.13208)
		(layer "B.Cu")
		(net "SSD11_ADC_A0")
	)
	(segment
		(start 334.370172 -46.269656)
		(end 334.370172 -47.243238)
		(width 0.13208)
		(layer "B.Cu")
		(net "SSD11_ADC_A0")
	)
	(segment
		(start 334.445864 -44.712636)
		(end 335.30159 -43.85691)
		(width 0.13208)
		(layer "F.Cu")
		(net "SSD11_ADC_A1")
	)
	(segment
		(start 336.031332 -42.853102)
		(end 336.043524 -42.84091)
		(width 0.13208)
		(layer "F.Cu")
		(net "SSD11_ADC_A1")
	)
	(segment
		(start 336.043524 -42.84091)
		(end 336.043524 -43.85691)
		(width 0.13208)
		(layer "F.Cu")
		(net "SSD11_ADC_A1")
	)
	(segment
		(start 335.30159 -43.85691)
		(end 336.043524 -43.85691)
		(width 0.13208)
		(layer "F.Cu")
		(net "SSD11_ADC_A1")
	)
	(segment
		(start 334.445864 -45.693838)
		(end 334.445864 -44.712636)
		(width 0.13208)
		(layer "F.Cu")
		(net "SSD11_ADC_A1")
	)
	(segment
		(start 334.715358 -42.853102)
		(end 336.031332 -42.853102)
		(width 0.13208)
		(layer "F.Cu")
		(net "SSD11_ADC_A1")
	)
	(via
		(at 335.30159 -43.85691)
		(size 0.508)
		(drill 0.254)
		(layers "F.Cu" "B.Cu")
		(net "SSD11_ADC_A1")
	)
	(segment
		(start 309.301642 -43.85691)
		(end 310.043576 -43.85691)
		(width 0.13208)
		(layer "F.Cu")
		(net "SSD10_ADC_A1")
	)
	(segment
		(start 310.031384 -42.853102)
		(end 310.043576 -42.84091)
		(width 0.13208)
		(layer "F.Cu")
		(net "SSD10_ADC_A1")
	)
	(segment
		(start 308.445916 -45.693838)
		(end 308.445916 -44.712636)
		(width 0.13208)
		(layer "F.Cu")
		(net "SSD10_ADC_A1")
	)
	(segment
		(start 308.71541 -42.853102)
		(end 310.031384 -42.853102)
		(width 0.13208)
		(layer "F.Cu")
		(net "SSD10_ADC_A1")
	)
	(segment
		(start 308.445916 -44.712636)
		(end 309.301642 -43.85691)
		(width 0.13208)
		(layer "F.Cu")
		(net "SSD10_ADC_A1")
	)
	(segment
		(start 310.043576 -42.84091)
		(end 310.043576 -43.85691)
		(width 0.13208)
		(layer "F.Cu")
		(net "SSD10_ADC_A1")
	)
	(via
		(at 309.301642 -43.85691)
		(size 0.508)
		(drill 0.254)
		(layers "F.Cu" "B.Cu")
		(net "SSD10_ADC_A1")
	)
	(segment
		(start 322.019168 -229.952296)
		(end 322.728844 -229.952296)
		(width 0.13208)
		(layer "F.Cu")
		(net "FPGA_DEBUG_LED")
	)
	(via
		(at 322.728844 -229.952296)
		(size 0.508)
		(drill 0.254)
		(layers "F.Cu" "B.Cu")
		(net "FPGA_DEBUG_LED")
	)
	(segment
		(start 322.767198 -229.913942)
		(end 322.728844 -229.952296)
		(width 0.13208)
		(layer "B.Cu")
		(net "FPGA_DEBUG_LED")
	)
	(segment
		(start 324.140068 -229.913942)
		(end 322.767198 -229.913942)
		(width 0.13208)
		(layer "B.Cu")
		(net "FPGA_DEBUG_LED")
	)
	(segment
		(start 363.433106 -245.248684)
		(end 363.433106 -243.063776)
		(width 0.13208)
		(layer "F.Cu")
		(net "JP_FPGA_LED")
	)
	(segment
		(start 363.433106 -243.063776)
		(end 364.713774 -241.783108)
		(width 0.13208)
		(layer "F.Cu")
		(net "JP_FPGA_LED")
	)
	(segment
		(start 338.893912 -224.786952)
		(end 338.494116 -225.186748)
		(width 0.13208)
		(layer "F.Cu")
		(net "JP_FPGA_LED")
	)
	(via
		(at 363.433106 -245.248684)
		(size 0.508)
		(drill 0.254)
		(layers "F.Cu" "B.Cu")
		(net "JP_FPGA_LED")
	)
	(via
		(at 338.494116 -225.186748)
		(size 0.4572)
		(drill 0.254)
		(layers "F.Cu" "B.Cu")
		(net "JP_FPGA_LED")
	)
	(segment
		(start 338.891626 -225.584258)
		(end 338.494116 -225.186748)
		(width 0.0889)
		(layer "In5.Cu")
		(net "JP_FPGA_LED")
	)
	(segment
		(start 336.77987 -236.710982)
		(end 336.77987 -236.101128)
		(width 0.15494)
		(layer "In5.Cu")
		(net "JP_FPGA_LED")
	)
	(segment
		(start 359.342944 -241.158522)
		(end 340.03742 -241.158522)
		(width 0.15494)
		(layer "In5.Cu")
		(net "JP_FPGA_LED")
	)
	(segment
		(start 338.891626 -227.292154)
		(end 338.891626 -226.953064)
		(width 0.15494)
		(layer "In5.Cu")
		(net "JP_FPGA_LED")
	)
	(segment
		(start 337.532472 -233.334306)
		(end 337.532472 -228.651308)
		(width 0.15494)
		(layer "In5.Cu")
		(net "JP_FPGA_LED")
	)
	(segment
		(start 340.03742 -241.158522)
		(end 336.75701 -237.878112)
		(width 0.15494)
		(layer "In5.Cu")
		(net "JP_FPGA_LED")
	)
	(segment
		(start 336.77987 -236.101128)
		(end 336.44713 -235.768388)
		(width 0.15494)
		(layer "In5.Cu")
		(net "JP_FPGA_LED")
	)
	(segment
		(start 338.891626 -226.953064)
		(end 338.891626 -225.584258)
		(width 0.0889)
		(layer "In5.Cu")
		(net "JP_FPGA_LED")
	)
	(segment
		(start 336.44713 -234.419648)
		(end 337.532472 -233.334306)
		(width 0.15494)
		(layer "In5.Cu")
		(net "JP_FPGA_LED")
	)
	(segment
		(start 337.532472 -228.651308)
		(end 338.891626 -227.292154)
		(width 0.15494)
		(layer "In5.Cu")
		(net "JP_FPGA_LED")
	)
	(segment
		(start 336.75701 -237.878112)
		(end 336.75701 -236.733842)
		(width 0.15494)
		(layer "In5.Cu")
		(net "JP_FPGA_LED")
	)
	(segment
		(start 363.433106 -245.248684)
		(end 359.342944 -241.158522)
		(width 0.15494)
		(layer "In5.Cu")
		(net "JP_FPGA_LED")
	)
	(segment
		(start 336.44713 -235.768388)
		(end 336.44713 -234.419648)
		(width 0.15494)
		(layer "In5.Cu")
		(net "JP_FPGA_LED")
	)
	(segment
		(start 336.75701 -236.733842)
		(end 336.77987 -236.710982)
		(width 0.15494)
		(layer "In5.Cu")
		(net "JP_FPGA_LED")
	)
	(segment
		(start 365.367316 -246.859552)
		(end 368.253518 -246.859552)
		(width 0.508)
		(layer "F.Cu")
		(net "P3V3_LED")
	)
	(segment
		(start 373.092726 -258.691126)
		(end 373.092726 -257.548888)
		(width 0.4572)
		(layer "F.Cu")
		(net "P3V3_LED")
	)
	(segment
		(start 235.618274 -202.760834)
		(end 234.663488 -202.760834)
		(width 0.508)
		(layer "F.Cu")
		(net "P3V3_LED")
	)
	(segment
		(start 365.513874 -243.251482)
		(end 365.513874 -241.783108)
		(width 0.4572)
		(layer "F.Cu")
		(net "P3V3_LED")
	)
	(segment
		(start 325.511414 -229.926642)
		(end 326.007476 -230.422704)
		(width 0.4572)
		(layer "F.Cu")
		(net "P3V3_LED")
	)
	(segment
		(start 140.892784 -258.691126)
		(end 140.892784 -257.548888)
		(width 0.4572)
		(layer "F.Cu")
		(net "P3V3_LED")
	)
	(segment
		(start 368.634264 -246.478806)
		(end 368.634264 -244.31371)
		(width 0.508)
		(layer "F.Cu")
		(net "P3V3_LED")
	)
	(segment
		(start 256.992628 -257.548888)
		(end 256.992628 -258.214114)
		(width 0.508)
		(layer "F.Cu")
		(net "P3V3_LED")
	)
	(segment
		(start 368.253518 -246.859552)
		(end 368.634264 -246.478806)
		(width 0.508)
		(layer "F.Cu")
		(net "P3V3_LED")
	)
	(segment
		(start 364.303818 -247.92305)
		(end 365.367316 -246.859552)
		(width 0.508)
		(layer "F.Cu")
		(net "P3V3_LED")
	)
	(segment
		(start 24.792686 -258.691126)
		(end 24.792686 -257.548888)
		(width 0.4572)
		(layer "F.Cu")
		(net "P3V3_LED")
	)
	(segment
		(start 325.130668 -229.926642)
		(end 325.511414 -229.926642)
		(width 0.4572)
		(layer "F.Cu")
		(net "P3V3_LED")
	)
	(segment
		(start 368.634264 -244.31371)
		(end 368.153442 -243.832888)
		(width 0.508)
		(layer "F.Cu")
		(net "P3V3_LED")
	)
	(segment
		(start 368.153442 -243.832888)
		(end 366.09528 -243.832888)
		(width 0.508)
		(layer "F.Cu")
		(net "P3V3_LED")
	)
	(segment
		(start 363.264196 -247.92305)
		(end 364.303818 -247.92305)
		(width 0.508)
		(layer "F.Cu")
		(net "P3V3_LED")
	)
	(segment
		(start 366.09528 -243.832888)
		(end 365.513874 -243.251482)
		(width 0.508)
		(layer "F.Cu")
		(net "P3V3_LED")
	)
	(via
		(at 140.268452 -243.611908)
		(size 0.508)
		(drill 0.254)
		(layers "F.Cu" "B.Cu")
		(net "P3V3_LED")
	)
	(via
		(at 24.792686 -258.691126)
		(size 0.508)
		(drill 0.254)
		(layers "F.Cu" "B.Cu")
		(net "P3V3_LED")
	)
	(via
		(at 234.663488 -202.760834)
		(size 0.508)
		(drill 0.254)
		(layers "F.Cu" "B.Cu")
		(net "P3V3_LED")
	)
	(via
		(at 255.784858 -201.415142)
		(size 0.508)
		(drill 0.254)
		(layers "F.Cu" "B.Cu")
		(net "P3V3_LED")
	)
	(via
		(at 326.007476 -230.422704)
		(size 0.508)
		(drill 0.254)
		(layers "F.Cu" "B.Cu")
		(net "P3V3_LED")
	)
	(via
		(at 365.513874 -243.251482)
		(size 0.508)
		(drill 0.254)
		(layers "F.Cu" "B.Cu")
		(net "P3V3_LED")
	)
	(via
		(at 256.992628 -258.214114)
		(size 0.508)
		(drill 0.254)
		(layers "F.Cu" "B.Cu")
		(net "P3V3_LED")
	)
	(via
		(at 140.892784 -258.691126)
		(size 0.508)
		(drill 0.254)
		(layers "F.Cu" "B.Cu")
		(net "P3V3_LED")
	)
	(via
		(at 329.654408 -257.67665)
		(size 0.508)
		(drill 0.254)
		(layers "F.Cu" "B.Cu")
		(net "P3V3_LED")
	)
	(via
		(at 373.092726 -258.691126)
		(size 0.508)
		(drill 0.254)
		(layers "F.Cu" "B.Cu")
		(net "P3V3_LED")
	)
	(via
		(at 257.261868 -231.31399)
		(size 0.508)
		(drill 0.254)
		(layers "F.Cu" "B.Cu")
		(net "P3V3_LED")
	)
	(via
		(at 266.77493 -226.3394)
		(size 0.508)
		(drill 0.254)
		(layers "F.Cu" "B.Cu")
		(net "P3V3_LED")
	)
	(segment
		(start 325.498714 -229.913942)
		(end 326.007476 -230.422704)
		(width 0.4572)
		(layer "B.Cu")
		(net "P3V3_LED")
	)
	(segment
		(start 324.940168 -229.913942)
		(end 325.498714 -229.913942)
		(width 0.4572)
		(layer "B.Cu")
		(net "P3V3_LED")
	)
	(segment
		(start 261.852918 -235.389166)
		(end 259.199634 -235.389166)
		(width 0.508)
		(layer "In5.Cu")
		(net "P3V3_LED")
	)
	(segment
		(start 255.631188 -204.892148)
		(end 255.631188 -201.568812)
		(width 0.508)
		(layer "In5.Cu")
		(net "P3V3_LED")
	)
	(segment
		(start 256.897886 -233.087418)
		(end 256.897886 -231.677972)
		(width 0.508)
		(layer "In5.Cu")
		(net "P3V3_LED")
	)
	(segment
		(start 255.422146 -214.669878)
		(end 255.422146 -213.766654)
		(width 0.508)
		(layer "In5.Cu")
		(net "P3V3_LED")
	)
	(segment
		(start 256.897886 -249.123454)
		(end 256.897886 -248.548652)
		(width 0.508)
		(layer "In5.Cu")
		(net "P3V3_LED")
	)
	(segment
		(start 266.77493 -226.3394)
		(end 266.77493 -227.2538)
		(width 0.508)
		(layer "In5.Cu")
		(net "P3V3_LED")
	)
	(segment
		(start 255.556004 -253.972314)
		(end 255.556004 -250.465336)
		(width 0.508)
		(layer "In5.Cu")
		(net "P3V3_LED")
	)
	(segment
		(start 255.631188 -201.568812)
		(end 255.784858 -201.415142)
		(width 0.508)
		(layer "In5.Cu")
		(net "P3V3_LED")
	)
	(segment
		(start 255.556004 -250.465336)
		(end 256.897886 -249.123454)
		(width 0.508)
		(layer "In5.Cu")
		(net "P3V3_LED")
	)
	(segment
		(start 260.770878 -227.80498)
		(end 257.261868 -231.31399)
		(width 0.508)
		(layer "In5.Cu")
		(net "P3V3_LED")
	)
	(segment
		(start 258.53263 -215.883744)
		(end 258.02463 -215.375744)
		(width 0.508)
		(layer "In5.Cu")
		(net "P3V3_LED")
	)
	(segment
		(start 256.198116 -205.459076)
		(end 255.631188 -204.892148)
		(width 0.508)
		(layer "In5.Cu")
		(net "P3V3_LED")
	)
	(segment
		(start 266.39393 -225.9584)
		(end 260.022086 -225.9584)
		(width 0.508)
		(layer "In5.Cu")
		(net "P3V3_LED")
	)
	(segment
		(start 260.022086 -225.9584)
		(end 259.668264 -225.604578)
		(width 0.508)
		(layer "In5.Cu")
		(net "P3V3_LED")
	)
	(segment
		(start 256.992628 -258.214114)
		(end 256.992628 -255.408938)
		(width 0.508)
		(layer "In5.Cu")
		(net "P3V3_LED")
	)
	(segment
		(start 263.534144 -246.348758)
		(end 263.534144 -237.070392)
		(width 0.508)
		(layer "In5.Cu")
		(net "P3V3_LED")
	)
	(segment
		(start 259.668264 -225.604578)
		(end 259.668264 -224.810574)
		(width 0.508)
		(layer "In5.Cu")
		(net "P3V3_LED")
	)
	(segment
		(start 266.22375 -227.80498)
		(end 260.770878 -227.80498)
		(width 0.508)
		(layer "In5.Cu")
		(net "P3V3_LED")
	)
	(segment
		(start 259.199634 -235.389166)
		(end 256.897886 -233.087418)
		(width 0.508)
		(layer "In5.Cu")
		(net "P3V3_LED")
	)
	(segment
		(start 258.02463 -215.375744)
		(end 256.128012 -215.375744)
		(width 0.508)
		(layer "In5.Cu")
		(net "P3V3_LED")
	)
	(segment
		(start 261.977632 -247.90527)
		(end 263.534144 -246.348758)
		(width 0.508)
		(layer "In5.Cu")
		(net "P3V3_LED")
	)
	(segment
		(start 256.897886 -248.548652)
		(end 257.541268 -247.90527)
		(width 0.508)
		(layer "In5.Cu")
		(net "P3V3_LED")
	)
	(segment
		(start 256.128012 -215.375744)
		(end 255.422146 -214.669878)
		(width 0.508)
		(layer "In5.Cu")
		(net "P3V3_LED")
	)
	(segment
		(start 263.534144 -237.070392)
		(end 261.852918 -235.389166)
		(width 0.508)
		(layer "In5.Cu")
		(net "P3V3_LED")
	)
	(segment
		(start 257.541268 -247.90527)
		(end 261.977632 -247.90527)
		(width 0.508)
		(layer "In5.Cu")
		(net "P3V3_LED")
	)
	(segment
		(start 266.77493 -227.2538)
		(end 266.22375 -227.80498)
		(width 0.508)
		(layer "In5.Cu")
		(net "P3V3_LED")
	)
	(segment
		(start 255.422146 -213.766654)
		(end 256.198116 -212.990684)
		(width 0.508)
		(layer "In5.Cu")
		(net "P3V3_LED")
	)
	(segment
		(start 256.198116 -212.990684)
		(end 256.198116 -205.459076)
		(width 0.508)
		(layer "In5.Cu")
		(net "P3V3_LED")
	)
	(segment
		(start 259.668264 -224.810574)
		(end 259.667502 -224.809812)
		(width 0.508)
		(layer "In5.Cu")
		(net "P3V3_LED")
	)
	(segment
		(start 266.77493 -226.3394)
		(end 266.39393 -225.9584)
		(width 0.508)
		(layer "In5.Cu")
		(net "P3V3_LED")
	)
	(segment
		(start 258.53263 -217.711782)
		(end 258.53263 -215.883744)
		(width 0.508)
		(layer "In5.Cu")
		(net "P3V3_LED")
	)
	(segment
		(start 259.667502 -224.809812)
		(end 259.667502 -218.846654)
		(width 0.508)
		(layer "In5.Cu")
		(net "P3V3_LED")
	)
	(segment
		(start 256.992628 -255.408938)
		(end 255.556004 -253.972314)
		(width 0.508)
		(layer "In5.Cu")
		(net "P3V3_LED")
	)
	(segment
		(start 256.897886 -231.677972)
		(end 257.261868 -231.31399)
		(width 0.508)
		(layer "In5.Cu")
		(net "P3V3_LED")
	)
	(segment
		(start 259.667502 -218.846654)
		(end 258.53263 -217.711782)
		(width 0.508)
		(layer "In5.Cu")
		(net "P3V3_LED")
	)
	(segment
		(start 373.092726 -255.361186)
		(end 368.930428 -251.198888)
		(width 0.4572)
		(layer "In7.Cu")
		(net "P3V3_LED")
	)
	(segment
		(start 373.092726 -258.691126)
		(end 373.092726 -255.361186)
		(width 0.4572)
		(layer "In7.Cu")
		(net "P3V3_LED")
	)
	(segment
		(start 368.930428 -251.198888)
		(end 368.930428 -246.668036)
		(width 0.4572)
		(layer "In7.Cu")
		(net "P3V3_LED")
	)
	(segment
		(start 368.930428 -246.668036)
		(end 365.513874 -243.251482)
		(width 0.4572)
		(layer "In7.Cu")
		(net "P3V3_LED")
	)
	(segment
		(start 324.485 -251.688854)
		(end 324.485 -237.668054)
		(width 0.508)
		(layer "In9.Cu")
		(net "P3V3_LED")
	)
	(segment
		(start 324.485 -237.668054)
		(end 324.9549 -237.198154)
		(width 0.508)
		(layer "In9.Cu")
		(net "P3V3_LED")
	)
	(segment
		(start 139.359132 -247.540526)
		(end 140.268452 -246.631206)
		(width 0.508)
		(layer "In9.Cu")
		(net "P3V3_LED")
	)
	(segment
		(start 141.051026 -255.196594)
		(end 139.359132 -253.5047)
		(width 0.508)
		(layer "In9.Cu")
		(net "P3V3_LED")
	)
	(segment
		(start 140.268452 -246.631206)
		(end 140.268452 -243.611908)
		(width 0.508)
		(layer "In9.Cu")
		(net "P3V3_LED")
	)
	(segment
		(start 329.654408 -256.858262)
		(end 324.485 -251.688854)
		(width 0.508)
		(layer "In9.Cu")
		(net "P3V3_LED")
	)
	(segment
		(start 324.9549 -237.198154)
		(end 325.9963 -237.198154)
		(width 0.508)
		(layer "In9.Cu")
		(net "P3V3_LED")
	)
	(segment
		(start 139.359132 -253.5047)
		(end 139.359132 -247.540526)
		(width 0.508)
		(layer "In9.Cu")
		(net "P3V3_LED")
	)
	(segment
		(start 326.801734 -236.39272)
		(end 326.801734 -231.216962)
		(width 0.508)
		(layer "In9.Cu")
		(net "P3V3_LED")
	)
	(segment
		(start 140.892784 -258.691126)
		(end 141.051026 -258.532884)
		(width 0.508)
		(layer "In9.Cu")
		(net "P3V3_LED")
	)
	(segment
		(start 326.801734 -231.216962)
		(end 326.007476 -230.422704)
		(width 0.508)
		(layer "In9.Cu")
		(net "P3V3_LED")
	)
	(segment
		(start 329.654408 -257.67665)
		(end 329.654408 -256.858262)
		(width 0.508)
		(layer "In9.Cu")
		(net "P3V3_LED")
	)
	(segment
		(start 325.9963 -237.198154)
		(end 326.801734 -236.39272)
		(width 0.508)
		(layer "In9.Cu")
		(net "P3V3_LED")
	)
	(segment
		(start 141.051026 -258.532884)
		(end 141.051026 -255.196594)
		(width 0.508)
		(layer "In9.Cu")
		(net "P3V3_LED")
	)
	(segment
		(start 138.772646 -256.570988)
		(end 140.892784 -258.691126)
		(width 0.508)
		(layer "In13.Cu")
		(net "P3V3_LED")
	)
	(segment
		(start 44.993306 -269.045182)
		(end 52.404264 -261.634224)
		(width 0.508)
		(layer "In13.Cu")
		(net "P3V3_LED")
	)
	(segment
		(start 111.434626 -248.86412)
		(end 122.399552 -248.86412)
		(width 0.508)
		(layer "In13.Cu")
		(net "P3V3_LED")
	)
	(segment
		(start 250.410218 -254.359156)
		(end 254.060198 -258.009136)
		(width 0.508)
		(layer "In13.Cu")
		(net "P3V3_LED")
	)
	(segment
		(start 29.671772 -260.49478)
		(end 31.214568 -260.49478)
		(width 0.508)
		(layer "In13.Cu")
		(net "P3V3_LED")
	)
	(segment
		(start 172.890942 -246.246142)
		(end 179.47767 -252.83287)
		(width 0.508)
		(layer "In13.Cu")
		(net "P3V3_LED")
	)
	(segment
		(start 25.418034 -259.316474)
		(end 28.493466 -259.316474)
		(width 0.508)
		(layer "In13.Cu")
		(net "P3V3_LED")
	)
	(segment
		(start 98.664522 -261.634224)
		(end 111.434626 -248.86412)
		(width 0.508)
		(layer "In13.Cu")
		(net "P3V3_LED")
	)
	(segment
		(start 190.213996 -251.51715)
		(end 219.43695 -251.51715)
		(width 0.508)
		(layer "In13.Cu")
		(net "P3V3_LED")
	)
	(segment
		(start 122.399552 -248.86412)
		(end 123.345194 -248.859802)
		(width 0.508)
		(layer "In13.Cu")
		(net "P3V3_LED")
	)
	(segment
		(start 231.635554 -253.322074)
		(end 232.672636 -254.359156)
		(width 0.508)
		(layer "In13.Cu")
		(net "P3V3_LED")
	)
	(segment
		(start 219.43695 -251.51715)
		(end 221.241874 -253.322074)
		(width 0.508)
		(layer "In13.Cu")
		(net "P3V3_LED")
	)
	(segment
		(start 232.672636 -254.359156)
		(end 250.410218 -254.359156)
		(width 0.508)
		(layer "In13.Cu")
		(net "P3V3_LED")
	)
	(segment
		(start 28.493466 -259.316474)
		(end 29.671772 -260.49478)
		(width 0.508)
		(layer "In13.Cu")
		(net "P3V3_LED")
	)
	(segment
		(start 256.24282 -258.214114)
		(end 256.992628 -258.214114)
		(width 0.508)
		(layer "In13.Cu")
		(net "P3V3_LED")
	)
	(segment
		(start 142.579344 -245.9228)
		(end 150.115778 -245.9228)
		(width 0.508)
		(layer "In13.Cu")
		(net "P3V3_LED")
	)
	(segment
		(start 37.37991 -269.045182)
		(end 44.993306 -269.045182)
		(width 0.508)
		(layer "In13.Cu")
		(net "P3V3_LED")
	)
	(segment
		(start 24.792686 -258.691126)
		(end 25.418034 -259.316474)
		(width 0.508)
		(layer "In13.Cu")
		(net "P3V3_LED")
	)
	(segment
		(start 221.241874 -253.322074)
		(end 231.635554 -253.322074)
		(width 0.508)
		(layer "In13.Cu")
		(net "P3V3_LED")
	)
	(segment
		(start 140.268452 -243.611908)
		(end 142.579344 -245.9228)
		(width 0.508)
		(layer "In13.Cu")
		(net "P3V3_LED")
	)
	(segment
		(start 254.060198 -258.009136)
		(end 254.36322 -258.134612)
		(width 0.508)
		(layer "In13.Cu")
		(net "P3V3_LED")
	)
	(segment
		(start 137.209022 -255.695196)
		(end 138.084814 -256.570988)
		(width 0.508)
		(layer "In13.Cu")
		(net "P3V3_LED")
	)
	(segment
		(start 254.36322 -258.134612)
		(end 254.88519 -258.134612)
		(width 0.508)
		(layer "In13.Cu")
		(net "P3V3_LED")
	)
	(segment
		(start 138.084814 -256.570988)
		(end 138.772646 -256.570988)
		(width 0.508)
		(layer "In13.Cu")
		(net "P3V3_LED")
	)
	(segment
		(start 123.345194 -248.859802)
		(end 125.23597 -248.859802)
		(width 0.508)
		(layer "In13.Cu")
		(net "P3V3_LED")
	)
	(segment
		(start 31.214568 -260.49478)
		(end 34.113978 -263.39419)
		(width 0.508)
		(layer "In13.Cu")
		(net "P3V3_LED")
	)
	(segment
		(start 150.43912 -246.246142)
		(end 172.890942 -246.246142)
		(width 0.508)
		(layer "In13.Cu")
		(net "P3V3_LED")
	)
	(segment
		(start 179.47767 -252.83287)
		(end 188.898276 -252.83287)
		(width 0.508)
		(layer "In13.Cu")
		(net "P3V3_LED")
	)
	(segment
		(start 34.113978 -263.39419)
		(end 34.113978 -265.77925)
		(width 0.508)
		(layer "In13.Cu")
		(net "P3V3_LED")
	)
	(segment
		(start 135.190738 -247.992138)
		(end 137.209022 -250.010422)
		(width 0.508)
		(layer "In13.Cu")
		(net "P3V3_LED")
	)
	(segment
		(start 125.23597 -248.859802)
		(end 126.103634 -247.992138)
		(width 0.508)
		(layer "In13.Cu")
		(net "P3V3_LED")
	)
	(segment
		(start 34.113978 -265.77925)
		(end 37.37991 -269.045182)
		(width 0.508)
		(layer "In13.Cu")
		(net "P3V3_LED")
	)
	(segment
		(start 52.404264 -261.634224)
		(end 98.664522 -261.634224)
		(width 0.508)
		(layer "In13.Cu")
		(net "P3V3_LED")
	)
	(segment
		(start 255.030224 -257.989578)
		(end 256.018284 -257.989578)
		(width 0.508)
		(layer "In13.Cu")
		(net "P3V3_LED")
	)
	(segment
		(start 188.898276 -252.83287)
		(end 190.213996 -251.51715)
		(width 0.508)
		(layer "In13.Cu")
		(net "P3V3_LED")
	)
	(segment
		(start 150.115778 -245.9228)
		(end 150.43912 -246.246142)
		(width 0.508)
		(layer "In13.Cu")
		(net "P3V3_LED")
	)
	(segment
		(start 256.018284 -257.989578)
		(end 256.24282 -258.214114)
		(width 0.508)
		(layer "In13.Cu")
		(net "P3V3_LED")
	)
	(segment
		(start 254.88519 -258.134612)
		(end 255.030224 -257.989578)
		(width 0.508)
		(layer "In13.Cu")
		(net "P3V3_LED")
	)
	(segment
		(start 126.103634 -247.992138)
		(end 135.190738 -247.992138)
		(width 0.508)
		(layer "In13.Cu")
		(net "P3V3_LED")
	)
	(segment
		(start 137.209022 -250.010422)
		(end 137.209022 -255.695196)
		(width 0.508)
		(layer "In13.Cu")
		(net "P3V3_LED")
	)
	(segment
		(start 237.246414 -199.799956)
		(end 236.8296 -200.21677)
		(width 0.508)
		(layer "In15.Cu")
		(net "P3V3_LED")
	)
	(segment
		(start 351.267014 -242.735608)
		(end 336.706718 -257.295904)
		(width 0.508)
		(layer "In15.Cu")
		(net "P3V3_LED")
	)
	(segment
		(start 321.14617 -230.19766)
		(end 322.285868 -231.337358)
		(width 0.4572)
		(layer "In15.Cu")
		(net "P3V3_LED")
	)
	(segment
		(start 255.265682 -201.415142)
		(end 254.89154 -201.041)
		(width 0.508)
		(layer "In15.Cu")
		(net "P3V3_LED")
	)
	(segment
		(start 248.758456 -199.513444)
		(end 248.134124 -198.889112)
		(width 0.508)
		(layer "In15.Cu")
		(net "P3V3_LED")
	)
	(segment
		(start 248.134124 -198.889112)
		(end 245.231666 -198.889112)
		(width 0.508)
		(layer "In15.Cu")
		(net "P3V3_LED")
	)
	(segment
		(start 336.706718 -257.295904)
		(end 330.035154 -257.295904)
		(width 0.508)
		(layer "In15.Cu")
		(net "P3V3_LED")
	)
	(segment
		(start 323.947282 -230.422704)
		(end 326.007476 -230.422704)
		(width 0.4572)
		(layer "In15.Cu")
		(net "P3V3_LED")
	)
	(segment
		(start 239.901222 -197.386194)
		(end 238.003588 -199.283828)
		(width 0.508)
		(layer "In15.Cu")
		(net "P3V3_LED")
	)
	(segment
		(start 245.231666 -198.889112)
		(end 243.728748 -197.386194)
		(width 0.508)
		(layer "In15.Cu")
		(net "P3V3_LED")
	)
	(segment
		(start 330.035154 -257.295904)
		(end 329.654408 -257.67665)
		(width 0.508)
		(layer "In15.Cu")
		(net "P3V3_LED")
	)
	(segment
		(start 364.998 -242.735608)
		(end 351.267014 -242.735608)
		(width 0.508)
		(layer "In15.Cu")
		(net "P3V3_LED")
	)
	(segment
		(start 323.032628 -231.337358)
		(end 323.947282 -230.422704)
		(width 0.4572)
		(layer "In15.Cu")
		(net "P3V3_LED")
	)
	(segment
		(start 271.97939 -231.31399)
		(end 290.47821 -231.31399)
		(width 0.4572)
		(layer "In15.Cu")
		(net "P3V3_LED")
	)
	(segment
		(start 255.784858 -201.415142)
		(end 255.265682 -201.415142)
		(width 0.508)
		(layer "In15.Cu")
		(net "P3V3_LED")
	)
	(segment
		(start 322.285868 -231.337358)
		(end 323.032628 -231.337358)
		(width 0.4572)
		(layer "In15.Cu")
		(net "P3V3_LED")
	)
	(segment
		(start 254.89154 -201.041)
		(end 250.192794 -201.041)
		(width 0.508)
		(layer "In15.Cu")
		(net "P3V3_LED")
	)
	(segment
		(start 236.8296 -200.594722)
		(end 234.663488 -202.760834)
		(width 0.508)
		(layer "In15.Cu")
		(net "P3V3_LED")
	)
	(segment
		(start 291.59454 -230.19766)
		(end 321.14617 -230.19766)
		(width 0.4572)
		(layer "In15.Cu")
		(net "P3V3_LED")
	)
	(segment
		(start 236.8296 -200.21677)
		(end 236.8296 -200.594722)
		(width 0.508)
		(layer "In15.Cu")
		(net "P3V3_LED")
	)
	(segment
		(start 238.003588 -199.283828)
		(end 237.246414 -199.799956)
		(width 0.508)
		(layer "In15.Cu")
		(net "P3V3_LED")
	)
	(segment
		(start 365.513874 -243.251482)
		(end 364.998 -242.735608)
		(width 0.508)
		(layer "In15.Cu")
		(net "P3V3_LED")
	)
	(segment
		(start 243.728748 -197.386194)
		(end 239.901222 -197.386194)
		(width 0.508)
		(layer "In15.Cu")
		(net "P3V3_LED")
	)
	(segment
		(start 250.192794 -201.041)
		(end 248.758456 -199.606662)
		(width 0.508)
		(layer "In15.Cu")
		(net "P3V3_LED")
	)
	(segment
		(start 290.47821 -231.31399)
		(end 291.59454 -230.19766)
		(width 0.4572)
		(layer "In15.Cu")
		(net "P3V3_LED")
	)
	(segment
		(start 248.758456 -199.606662)
		(end 248.758456 -199.513444)
		(width 0.508)
		(layer "In15.Cu")
		(net "P3V3_LED")
	)
	(segment
		(start 266.77493 -226.3394)
		(end 267.0048 -226.3394)
		(width 0.4572)
		(layer "In15.Cu")
		(net "P3V3_LED")
	)
	(segment
		(start 267.0048 -226.3394)
		(end 271.97939 -231.31399)
		(width 0.4572)
		(layer "In15.Cu")
		(net "P3V3_LED")
	)
	(segment
		(start 194.557904 -50.504598)
		(end 192.527936 -50.504598)
		(width 0.13208)
		(layer "F.Cu")
		(net "SSD6_ADC_A0")
	)
	(segment
		(start 193.37909 -45.88891)
		(end 193.185796 -45.695616)
		(width 0.13208)
		(layer "F.Cu")
		(net "SSD6_ADC_A0")
	)
	(segment
		(start 193.943732 -44.87291)
		(end 193.943732 -45.88891)
		(width 0.13208)
		(layer "F.Cu")
		(net "SSD6_ADC_A0")
	)
	(segment
		(start 194.743832 -50.31867)
		(end 194.557904 -50.504598)
		(width 0.13208)
		(layer "F.Cu")
		(net "SSD6_ADC_A0")
	)
	(segment
		(start 193.185796 -45.35424)
		(end 193.185796 -45.695616)
		(width 0.13208)
		(layer "F.Cu")
		(net "SSD6_ADC_A0")
	)
	(segment
		(start 192.527936 -50.504598)
		(end 192.095374 -50.93716)
		(width 0.13208)
		(layer "F.Cu")
		(net "SSD6_ADC_A0")
	)
	(segment
		(start 192.095374 -50.93716)
		(end 190.780924 -50.93716)
		(width 0.13208)
		(layer "F.Cu")
		(net "SSD6_ADC_A0")
	)
	(segment
		(start 193.943732 -45.88891)
		(end 193.37909 -45.88891)
		(width 0.13208)
		(layer "F.Cu")
		(net "SSD6_ADC_A0")
	)
	(segment
		(start 190.653924 -50.81016)
		(end 190.653924 -48.859694)
		(width 0.13208)
		(layer "F.Cu")
		(net "SSD6_ADC_A0")
	)
	(segment
		(start 193.185796 -45.771816)
		(end 192.763648 -46.193964)
		(width 0.13208)
		(layer "F.Cu")
		(net "SSD6_ADC_A0")
	)
	(segment
		(start 193.185796 -45.695616)
		(end 193.185796 -45.771816)
		(width 0.13208)
		(layer "F.Cu")
		(net "SSD6_ADC_A0")
	)
	(segment
		(start 190.653924 -48.859694)
		(end 190.669418 -48.8442)
		(width 0.13208)
		(layer "F.Cu")
		(net "SSD6_ADC_A0")
	)
	(segment
		(start 192.763648 -46.193964)
		(end 192.346072 -46.193964)
		(width 0.13208)
		(layer "F.Cu")
		(net "SSD6_ADC_A0")
	)
	(segment
		(start 194.743832 -49.95291)
		(end 194.743832 -50.31867)
		(width 0.13208)
		(layer "F.Cu")
		(net "SSD6_ADC_A0")
	)
	(segment
		(start 190.780924 -50.93716)
		(end 190.653924 -50.81016)
		(width 0.13208)
		(layer "F.Cu")
		(net "SSD6_ADC_A0")
	)
	(via
		(at 193.185796 -45.35424)
		(size 0.508)
		(drill 0.254)
		(layers "F.Cu" "B.Cu")
		(net "SSD6_ADC_A0")
	)
	(via
		(at 190.669418 -48.8442)
		(size 0.508)
		(drill 0.254)
		(layers "F.Cu" "B.Cu")
		(net "SSD6_ADC_A0")
	)
	(segment
		(start 192.27038 -47.243238)
		(end 190.669418 -48.8442)
		(width 0.13208)
		(layer "B.Cu")
		(net "SSD6_ADC_A0")
	)
	(segment
		(start 192.27038 -46.269656)
		(end 192.27038 -47.243238)
		(width 0.13208)
		(layer "B.Cu")
		(net "SSD6_ADC_A0")
	)
	(segment
		(start 193.185796 -45.35424)
		(end 192.27038 -46.269656)
		(width 0.13208)
		(layer "B.Cu")
		(net "SSD6_ADC_A0")
	)
	(segment
		(start 225.867722 -214.304118)
		(end 225.467926 -213.904322)
		(width 0.13208)
		(layer "F.Cu")
		(net "FM_SYS_THROTTLE_R1")
	)
	(via
		(at 225.467926 -213.904322)
		(size 0.4572)
		(drill 0.254)
		(layers "F.Cu" "B.Cu")
		(net "FM_SYS_THROTTLE_R1")
	)
	(via
		(at 217.675968 -210.579716)
		(size 0.6604)
		(drill 0.3302)
		(layers "F.Cu" "B.Cu")
		(net "FM_SYS_THROTTLE_R1")
	)
	(segment
		(start 225.467926 -213.904322)
		(end 225.467926 -213.813136)
		(width 0.0889)
		(layer "B.Cu")
		(net "FM_SYS_THROTTLE_R1")
	)
	(segment
		(start 224.398332 -212.743542)
		(end 220.39326 -212.743542)
		(width 0.13208)
		(layer "B.Cu")
		(net "FM_SYS_THROTTLE_R1")
	)
	(segment
		(start 220.39326 -212.743542)
		(end 218.229434 -210.579716)
		(width 0.13208)
		(layer "B.Cu")
		(net "FM_SYS_THROTTLE_R1")
	)
	(segment
		(start 218.229434 -210.579716)
		(end 217.675968 -210.579716)
		(width 0.13208)
		(layer "B.Cu")
		(net "FM_SYS_THROTTLE_R1")
	)
	(segment
		(start 215.880442 -210.164426)
		(end 217.260678 -210.164426)
		(width 0.13208)
		(layer "B.Cu")
		(net "FM_SYS_THROTTLE_R1")
	)
	(segment
		(start 217.260678 -210.164426)
		(end 217.675968 -210.579716)
		(width 0.13208)
		(layer "B.Cu")
		(net "FM_SYS_THROTTLE_R1")
	)
	(segment
		(start 225.467926 -213.813136)
		(end 224.398332 -212.743542)
		(width 0.0889)
		(layer "B.Cu")
		(net "FM_SYS_THROTTLE_R1")
	)
	(segment
		(start 219.94368 -45.88891)
		(end 219.379038 -45.88891)
		(width 0.13208)
		(layer "F.Cu")
		(net "SSD7_ADC_A0")
	)
	(segment
		(start 217.06205 -49.94148)
		(end 216.669366 -49.548796)
		(width 0.13208)
		(layer "F.Cu")
		(net "SSD7_ADC_A0")
	)
	(segment
		(start 218.083384 -49.94148)
		(end 217.06205 -49.94148)
		(width 0.13208)
		(layer "F.Cu")
		(net "SSD7_ADC_A0")
	)
	(segment
		(start 219.185744 -45.771816)
		(end 218.763596 -46.193964)
		(width 0.13208)
		(layer "F.Cu")
		(net "SSD7_ADC_A0")
	)
	(segment
		(start 219.185744 -45.35424)
		(end 219.185744 -45.695616)
		(width 0.13208)
		(layer "F.Cu")
		(net "SSD7_ADC_A0")
	)
	(segment
		(start 219.94368 -44.87291)
		(end 219.94368 -45.88891)
		(width 0.13208)
		(layer "F.Cu")
		(net "SSD7_ADC_A0")
	)
	(segment
		(start 219.379038 -45.88891)
		(end 219.185744 -45.695616)
		(width 0.13208)
		(layer "F.Cu")
		(net "SSD7_ADC_A0")
	)
	(segment
		(start 216.669366 -49.548796)
		(end 216.669366 -48.8442)
		(width 0.13208)
		(layer "F.Cu")
		(net "SSD7_ADC_A0")
	)
	(segment
		(start 218.763596 -46.193964)
		(end 218.34602 -46.193964)
		(width 0.13208)
		(layer "F.Cu")
		(net "SSD7_ADC_A0")
	)
	(segment
		(start 219.185744 -45.695616)
		(end 219.185744 -45.771816)
		(width 0.13208)
		(layer "F.Cu")
		(net "SSD7_ADC_A0")
	)
	(via
		(at 219.185744 -45.35424)
		(size 0.508)
		(drill 0.254)
		(layers "F.Cu" "B.Cu")
		(net "SSD7_ADC_A0")
	)
	(via
		(at 216.669366 -48.8442)
		(size 0.508)
		(drill 0.254)
		(layers "F.Cu" "B.Cu")
		(net "SSD7_ADC_A0")
	)
	(segment
		(start 218.270328 -47.243238)
		(end 216.669366 -48.8442)
		(width 0.13208)
		(layer "B.Cu")
		(net "SSD7_ADC_A0")
	)
	(segment
		(start 219.185744 -45.35424)
		(end 218.270328 -46.269656)
		(width 0.13208)
		(layer "B.Cu")
		(net "SSD7_ADC_A0")
	)
	(segment
		(start 218.270328 -46.269656)
		(end 218.270328 -47.243238)
		(width 0.13208)
		(layer "B.Cu")
		(net "SSD7_ADC_A0")
	)
	(segment
		(start 77.085698 -45.771816)
		(end 76.66355 -46.193964)
		(width 0.13208)
		(layer "F.Cu")
		(net "SSD2_ADC_A0")
	)
	(segment
		(start 77.085698 -45.695616)
		(end 77.085698 -45.771816)
		(width 0.13208)
		(layer "F.Cu")
		(net "SSD2_ADC_A0")
	)
	(segment
		(start 76.077064 -49.315878)
		(end 76.406756 -48.986186)
		(width 0.13208)
		(layer "F.Cu")
		(net "SSD2_ADC_A0")
	)
	(segment
		(start 77.278992 -45.88891)
		(end 77.843634 -45.88891)
		(width 0.13208)
		(layer "F.Cu")
		(net "SSD2_ADC_A0")
	)
	(segment
		(start 76.077064 -49.856644)
		(end 76.077064 -49.315878)
		(width 0.13208)
		(layer "F.Cu")
		(net "SSD2_ADC_A0")
	)
	(segment
		(start 77.085698 -45.695616)
		(end 77.278992 -45.88891)
		(width 0.13208)
		(layer "F.Cu")
		(net "SSD2_ADC_A0")
	)
	(segment
		(start 77.843634 -44.87291)
		(end 77.843634 -45.88891)
		(width 0.13208)
		(layer "F.Cu")
		(net "SSD2_ADC_A0")
	)
	(segment
		(start 76.66355 -46.193964)
		(end 76.245974 -46.193964)
		(width 0.13208)
		(layer "F.Cu")
		(net "SSD2_ADC_A0")
	)
	(segment
		(start 77.085698 -45.35424)
		(end 77.085698 -45.695616)
		(width 0.13208)
		(layer "F.Cu")
		(net "SSD2_ADC_A0")
	)
	(via
		(at 77.085698 -45.35424)
		(size 0.508)
		(drill 0.254)
		(layers "F.Cu" "B.Cu")
		(net "SSD2_ADC_A0")
	)
	(via
		(at 76.406756 -48.986186)
		(size 0.508)
		(drill 0.254)
		(layers "F.Cu" "B.Cu")
		(net "SSD2_ADC_A0")
	)
	(segment
		(start 77.074014 -48.986186)
		(end 77.955902 -48.104298)
		(width 0.13208)
		(layer "B.Cu")
		(net "SSD2_ADC_A0")
	)
	(segment
		(start 77.955902 -46.224444)
		(end 77.085698 -45.35424)
		(width 0.13208)
		(layer "B.Cu")
		(net "SSD2_ADC_A0")
	)
	(segment
		(start 76.406756 -48.986186)
		(end 77.074014 -48.986186)
		(width 0.13208)
		(layer "B.Cu")
		(net "SSD2_ADC_A0")
	)
	(segment
		(start 77.955902 -48.104298)
		(end 77.955902 -46.224444)
		(width 0.13208)
		(layer "B.Cu")
		(net "SSD2_ADC_A0")
	)
	(segment
		(start 103.27894 -45.88891)
		(end 103.085646 -45.695616)
		(width 0.13208)
		(layer "F.Cu")
		(net "SSD3_ADC_A0")
	)
	(segment
		(start 103.085646 -45.695616)
		(end 103.085646 -45.771816)
		(width 0.13208)
		(layer "F.Cu")
		(net "SSD3_ADC_A0")
	)
	(segment
		(start 100.961952 -49.94148)
		(end 100.569268 -49.548796)
		(width 0.13208)
		(layer "F.Cu")
		(net "SSD3_ADC_A0")
	)
	(segment
		(start 103.843582 -45.88891)
		(end 103.27894 -45.88891)
		(width 0.13208)
		(layer "F.Cu")
		(net "SSD3_ADC_A0")
	)
	(segment
		(start 102.663498 -46.193964)
		(end 102.245922 -46.193964)
		(width 0.13208)
		(layer "F.Cu")
		(net "SSD3_ADC_A0")
	)
	(segment
		(start 103.085646 -45.771816)
		(end 102.663498 -46.193964)
		(width 0.13208)
		(layer "F.Cu")
		(net "SSD3_ADC_A0")
	)
	(segment
		(start 103.843582 -44.87291)
		(end 103.843582 -45.88891)
		(width 0.13208)
		(layer "F.Cu")
		(net "SSD3_ADC_A0")
	)
	(segment
		(start 101.983286 -49.94148)
		(end 100.961952 -49.94148)
		(width 0.13208)
		(layer "F.Cu")
		(net "SSD3_ADC_A0")
	)
	(segment
		(start 103.085646 -45.35424)
		(end 103.085646 -45.695616)
		(width 0.13208)
		(layer "F.Cu")
		(net "SSD3_ADC_A0")
	)
	(segment
		(start 100.569268 -49.548796)
		(end 100.569268 -48.8442)
		(width 0.13208)
		(layer "F.Cu")
		(net "SSD3_ADC_A0")
	)
	(via
		(at 103.085646 -45.35424)
		(size 0.508)
		(drill 0.254)
		(layers "F.Cu" "B.Cu")
		(net "SSD3_ADC_A0")
	)
	(via
		(at 100.569268 -48.8442)
		(size 0.508)
		(drill 0.254)
		(layers "F.Cu" "B.Cu")
		(net "SSD3_ADC_A0")
	)
	(segment
		(start 103.085646 -45.35424)
		(end 102.17023 -46.269656)
		(width 0.13208)
		(layer "B.Cu")
		(net "SSD3_ADC_A0")
	)
	(segment
		(start 102.17023 -46.269656)
		(end 102.17023 -47.243238)
		(width 0.13208)
		(layer "B.Cu")
		(net "SSD3_ADC_A0")
	)
	(segment
		(start 102.17023 -47.243238)
		(end 100.569268 -48.8442)
		(width 0.13208)
		(layer "B.Cu")
		(net "SSD3_ADC_A0")
	)
	(segment
		(start 120.632982 -121.103136)
		(end 120.309132 -120.779286)
		(width 0.13208)
		(layer "F.Cu")
		(net "P3V3_CO_MODE")
	)
	(segment
		(start 119.572532 -120.011698)
		(end 120.118632 -120.011698)
		(width 0.13208)
		(layer "F.Cu")
		(net "P3V3_CO_MODE")
	)
	(segment
		(start 121.041922 -121.103136)
		(end 120.632982 -121.103136)
		(width 0.13208)
		(layer "F.Cu")
		(net "P3V3_CO_MODE")
	)
	(segment
		(start 120.309132 -120.202198)
		(end 120.309132 -120.779286)
		(width 0.13208)
		(layer "F.Cu")
		(net "P3V3_CO_MODE")
	)
	(segment
		(start 121.041922 -120.087136)
		(end 121.041922 -121.103136)
		(width 0.13208)
		(layer "F.Cu")
		(net "P3V3_CO_MODE")
	)
	(segment
		(start 120.118632 -120.011698)
		(end 120.309132 -120.202198)
		(width 0.13208)
		(layer "F.Cu")
		(net "P3V3_CO_MODE")
	)
	(via
		(at 120.309132 -120.779286)
		(size 0.508)
		(drill 0.254)
		(layers "F.Cu" "B.Cu")
		(net "P3V3_CO_MODE")
	)
	(segment
		(start 125.34519 -110.322868)
		(end 124.32919 -110.322868)
		(width 0.13208)
		(layer "F.Cu")
		(net "P3V3_PG_G1")
	)
	(segment
		(start 123.56719 -109.579918)
		(end 124.32919 -109.579918)
		(width 0.13208)
		(layer "F.Cu")
		(net "P3V3_PG_G1")
	)
	(segment
		(start 124.32919 -109.579918)
		(end 124.32919 -110.322868)
		(width 0.13208)
		(layer "F.Cu")
		(net "P3V3_PG_G1")
	)
	(segment
		(start 123.31319 -109.325918)
		(end 123.56719 -109.579918)
		(width 0.13208)
		(layer "F.Cu")
		(net "P3V3_PG_G1")
	)
	(segment
		(start 123.31319 -108.82884)
		(end 123.31319 -109.325918)
		(width 0.13208)
		(layer "F.Cu")
		(net "P3V3_PG_G1")
	)
	(via
		(at 124.32919 -109.579918)
		(size 0.508)
		(drill 0.254)
		(layers "F.Cu" "B.Cu")
		(net "P3V3_PG_G1")
	)
	(segment
		(start 116.703094 -120.34647)
		(end 116.45011 -120.093486)
		(width 0.13208)
		(layer "F.Cu")
		(net "P3V3_CO_GATE")
	)
	(segment
		(start 117.572536 -120.011698)
		(end 117.037866 -120.011698)
		(width 0.13208)
		(layer "F.Cu")
		(net "P3V3_CO_GATE")
	)
	(segment
		(start 117.037866 -120.011698)
		(end 116.703094 -120.34647)
		(width 0.13208)
		(layer "F.Cu")
		(net "P3V3_CO_GATE")
	)
	(segment
		(start 116.45011 -120.093486)
		(end 116.000276 -120.093486)
		(width 0.13208)
		(layer "F.Cu")
		(net "P3V3_CO_GATE")
	)
	(via
		(at 116.703094 -120.34647)
		(size 0.508)
		(drill 0.254)
		(layers "F.Cu" "B.Cu")
		(net "P3V3_CO_GATE")
	)
	(segment
		(start 121.041922 -119.071136)
		(end 120.747282 -119.071136)
		(width 0.13208)
		(layer "F.Cu")
		(net "P3V3_CO_ILIMIT")
	)
	(segment
		(start 120.306592 -119.511826)
		(end 119.572532 -119.511826)
		(width 0.13208)
		(layer "F.Cu")
		(net "P3V3_CO_ILIMIT")
	)
	(segment
		(start 120.309132 -119.509286)
		(end 120.306592 -119.511826)
		(width 0.13208)
		(layer "F.Cu")
		(net "P3V3_CO_ILIMIT")
	)
	(segment
		(start 120.747282 -119.071136)
		(end 120.309132 -119.509286)
		(width 0.13208)
		(layer "F.Cu")
		(net "P3V3_CO_ILIMIT")
	)
	(via
		(at 120.309132 -119.509286)
		(size 0.508)
		(drill 0.254)
		(layers "F.Cu" "B.Cu")
		(net "P3V3_CO_ILIMIT")
	)
	(segment
		(start 123.31319 -110.322868)
		(end 122.29719 -110.322868)
		(width 0.13208)
		(layer "F.Cu")
		(net "PWRGD_P3V3_D")
	)
	(segment
		(start 122.563128 -108.82884)
		(end 122.563128 -109.44098)
		(width 0.13208)
		(layer "F.Cu")
		(net "PWRGD_P3V3_D")
	)
	(segment
		(start 122.29719 -109.706918)
		(end 122.29719 -110.322868)
		(width 0.13208)
		(layer "F.Cu")
		(net "PWRGD_P3V3_D")
	)
	(segment
		(start 122.563128 -109.44098)
		(end 122.29719 -109.706918)
		(width 0.13208)
		(layer "F.Cu")
		(net "PWRGD_P3V3_D")
	)
	(via
		(at 122.29719 -109.706918)
		(size 0.508)
		(drill 0.254)
		(layers "F.Cu" "B.Cu")
		(net "PWRGD_P3V3_D")
	)
	(segment
		(start 116.778278 -117.73408)
		(end 117.128036 -118.083838)
		(width 0.13208)
		(layer "F.Cu")
		(net "P3V3_CO_DV_DT")
	)
	(segment
		(start 116.450872 -118.061486)
		(end 116.000276 -118.061486)
		(width 0.13208)
		(layer "F.Cu")
		(net "P3V3_CO_DV_DT")
	)
	(segment
		(start 117.277388 -119.011954)
		(end 117.572536 -119.011954)
		(width 0.13208)
		(layer "F.Cu")
		(net "P3V3_CO_DV_DT")
	)
	(segment
		(start 117.128036 -118.083838)
		(end 117.128036 -118.862602)
		(width 0.13208)
		(layer "F.Cu")
		(net "P3V3_CO_DV_DT")
	)
	(segment
		(start 117.128036 -118.862602)
		(end 117.277388 -119.011954)
		(width 0.13208)
		(layer "F.Cu")
		(net "P3V3_CO_DV_DT")
	)
	(segment
		(start 116.778278 -117.73408)
		(end 116.450872 -118.061486)
		(width 0.13208)
		(layer "F.Cu")
		(net "P3V3_CO_DV_DT")
	)
	(via
		(at 116.778278 -117.73408)
		(size 0.508)
		(drill 0.254)
		(layers "F.Cu" "B.Cu")
		(net "P3V3_CO_DV_DT")
	)
	(segment
		(start 116.394484 -119.047006)
		(end 116.364004 -119.077486)
		(width 0.13208)
		(layer "F.Cu")
		(net "P3V3_CO_EN")
	)
	(segment
		(start 116.364004 -119.077486)
		(end 116.000276 -119.077486)
		(width 0.13208)
		(layer "F.Cu")
		(net "P3V3_CO_EN")
	)
	(segment
		(start 117.155976 -119.511826)
		(end 116.691156 -119.047006)
		(width 0.13208)
		(layer "F.Cu")
		(net "P3V3_CO_EN")
	)
	(segment
		(start 116.691156 -119.047006)
		(end 116.394484 -119.047006)
		(width 0.13208)
		(layer "F.Cu")
		(net "P3V3_CO_EN")
	)
	(segment
		(start 117.572536 -119.511826)
		(end 117.155976 -119.511826)
		(width 0.13208)
		(layer "F.Cu")
		(net "P3V3_CO_EN")
	)
	(via
		(at 116.691156 -119.047006)
		(size 0.508)
		(drill 0.254)
		(layers "F.Cu" "B.Cu")
		(net "P3V3_CO_EN")
	)
	(segment
		(start 124.063252 -107.028996)
		(end 124.063252 -106.277918)
		(width 0.13208)
		(layer "F.Cu")
		(net "P3V3_PG_G2")
	)
	(segment
		(start 124.07519 -106.26598)
		(end 124.07519 -105.534968)
		(width 0.13208)
		(layer "F.Cu")
		(net "P3V3_PG_G2")
	)
	(segment
		(start 124.07519 -105.534968)
		(end 123.44019 -105.534968)
		(width 0.13208)
		(layer "F.Cu")
		(net "P3V3_PG_G2")
	)
	(segment
		(start 124.063252 -106.277918)
		(end 124.07519 -106.26598)
		(width 0.13208)
		(layer "F.Cu")
		(net "P3V3_PG_G2")
	)
	(segment
		(start 123.44019 -105.534968)
		(end 123.31319 -105.661968)
		(width 0.13208)
		(layer "F.Cu")
		(net "P3V3_PG_G2")
	)
	(segment
		(start 123.31319 -105.661968)
		(end 123.31319 -107.028996)
		(width 0.13208)
		(layer "F.Cu")
		(net "P3V3_PG_G2")
	)
	(via
		(at 124.063252 -106.277918)
		(size 0.508)
		(drill 0.254)
		(layers "F.Cu" "B.Cu")
		(net "P3V3_PG_G2")
	)
	(segment
		(start 64.07785 -115.283742)
		(end 65.979294 -115.283742)
		(width 0.13208)
		(layer "F.Cu")
		(net "RST_SMB_NIC1_MUX_ISO_R_N")
	)
	(segment
		(start 67.227958 -114.035078)
		(end 68.65747 -114.035078)
		(width 0.13208)
		(layer "F.Cu")
		(net "RST_SMB_NIC1_MUX_ISO_R_N")
	)
	(segment
		(start 66.681604 -114.581432)
		(end 67.227958 -114.035078)
		(width 0.13208)
		(layer "F.Cu")
		(net "RST_SMB_NIC1_MUX_ISO_R_N")
	)
	(segment
		(start 65.979294 -115.283742)
		(end 66.681604 -114.581432)
		(width 0.13208)
		(layer "F.Cu")
		(net "RST_SMB_NIC1_MUX_ISO_R_N")
	)
	(via
		(at 66.681604 -114.581432)
		(size 0.508)
		(drill 0.254)
		(layers "F.Cu" "B.Cu")
		(net "RST_SMB_NIC1_MUX_ISO_R_N")
	)
	(segment
		(start 56.62422 -62.121034)
		(end 56.283606 -61.78042)
		(width 0.13208)
		(layer "F.Cu")
		(net "PWRGD_P12V_SSD2_D")
	)
	(segment
		(start 56.62422 -62.74689)
		(end 56.62422 -62.121034)
		(width 0.13208)
		(layer "F.Cu")
		(net "PWRGD_P12V_SSD2_D")
	)
	(segment
		(start 57.256172 -61.487812)
		(end 56.283606 -61.487812)
		(width 0.13208)
		(layer "F.Cu")
		(net "PWRGD_P12V_SSD2_D")
	)
	(segment
		(start 56.689498 -62.812168)
		(end 56.62422 -62.74689)
		(width 0.13208)
		(layer "F.Cu")
		(net "PWRGD_P12V_SSD2_D")
	)
	(segment
		(start 56.283606 -61.78042)
		(end 56.283606 -61.487812)
		(width 0.13208)
		(layer "F.Cu")
		(net "PWRGD_P12V_SSD2_D")
	)
	(via
		(at 56.62422 -62.121034)
		(size 0.508)
		(drill 0.254)
		(layers "F.Cu" "B.Cu")
		(net "PWRGD_P12V_SSD2_D")
	)
	(segment
		(start 99.28987 -71.827898)
		(end 99.0854 -71.623428)
		(width 0.13208)
		(layer "F.Cu")
		(net "P12V_SSD3_CO_ILIMIT")
	)
	(segment
		(start 99.0854 -71.623428)
		(end 98.575368 -71.113396)
		(width 0.13208)
		(layer "F.Cu")
		(net "P12V_SSD3_CO_ILIMIT")
	)
	(segment
		(start 98.575368 -71.113396)
		(end 98.575368 -70.479158)
		(width 0.13208)
		(layer "F.Cu")
		(net "P12V_SSD3_CO_ILIMIT")
	)
	(segment
		(start 99.28987 -72.366632)
		(end 99.28987 -71.827898)
		(width 0.13208)
		(layer "F.Cu")
		(net "P12V_SSD3_CO_ILIMIT")
	)
	(via
		(at 99.0854 -71.623428)
		(size 0.508)
		(drill 0.254)
		(layers "F.Cu" "B.Cu")
		(net "P12V_SSD3_CO_ILIMIT")
	)
	(segment
		(start 20.575524 -68.479162)
		(end 20.575524 -67.970146)
		(width 0.13208)
		(layer "F.Cu")
		(net "P12V_SSD0_CO_EN")
	)
	(segment
		(start 20.514564 -67.01663)
		(end 20.514564 -66.72199)
		(width 0.13208)
		(layer "F.Cu")
		(net "P12V_SSD0_CO_EN")
	)
	(segment
		(start 20.575524 -67.970146)
		(end 20.45335 -67.847972)
		(width 0.13208)
		(layer "F.Cu")
		(net "P12V_SSD0_CO_EN")
	)
	(segment
		(start 20.45335 -67.077844)
		(end 20.514564 -67.01663)
		(width 0.13208)
		(layer "F.Cu")
		(net "P12V_SSD0_CO_EN")
	)
	(segment
		(start 20.45335 -67.537584)
		(end 20.45335 -67.077844)
		(width 0.13208)
		(layer "F.Cu")
		(net "P12V_SSD0_CO_EN")
	)
	(segment
		(start 20.45335 -67.847972)
		(end 20.45335 -67.537584)
		(width 0.13208)
		(layer "F.Cu")
		(net "P12V_SSD0_CO_EN")
	)
	(via
		(at 20.45335 -67.537584)
		(size 0.508)
		(drill 0.254)
		(layers "F.Cu" "B.Cu")
		(net "P12V_SSD0_CO_EN")
	)
	(segment
		(start 72.453246 -67.077844)
		(end 72.51446 -67.01663)
		(width 0.13208)
		(layer "F.Cu")
		(net "P12V_SSD2_CO_EN")
	)
	(segment
		(start 72.453246 -67.537584)
		(end 72.453246 -67.077844)
		(width 0.13208)
		(layer "F.Cu")
		(net "P12V_SSD2_CO_EN")
	)
	(segment
		(start 72.57542 -67.970146)
		(end 72.453246 -67.847972)
		(width 0.13208)
		(layer "F.Cu")
		(net "P12V_SSD2_CO_EN")
	)
	(segment
		(start 72.51446 -67.01663)
		(end 72.51446 -66.72199)
		(width 0.13208)
		(layer "F.Cu")
		(net "P12V_SSD2_CO_EN")
	)
	(segment
		(start 72.453246 -67.847972)
		(end 72.453246 -67.537584)
		(width 0.13208)
		(layer "F.Cu")
		(net "P12V_SSD2_CO_EN")
	)
	(segment
		(start 72.57542 -68.479162)
		(end 72.57542 -67.970146)
		(width 0.13208)
		(layer "F.Cu")
		(net "P12V_SSD2_CO_EN")
	)
	(via
		(at 72.453246 -67.537584)
		(size 0.508)
		(drill 0.254)
		(layers "F.Cu" "B.Cu")
		(net "P12V_SSD2_CO_EN")
	)
	(segment
		(start 350.093788 -211.18703)
		(end 350.567498 -210.71332)
		(width 0.13208)
		(layer "F.Cu")
		(net "PU_FPGA_SN")
	)
	(segment
		(start 350.567498 -210.71332)
		(end 350.567498 -208.60512)
		(width 0.13208)
		(layer "F.Cu")
		(net "PU_FPGA_SN")
	)
	(segment
		(start 352.16338 -207.009238)
		(end 353.691952 -207.009238)
		(width 0.13208)
		(layer "F.Cu")
		(net "PU_FPGA_SN")
	)
	(segment
		(start 351.55886 -207.613758)
		(end 352.16338 -207.009238)
		(width 0.13208)
		(layer "F.Cu")
		(net "PU_FPGA_SN")
	)
	(segment
		(start 353.691952 -207.009238)
		(end 354.212398 -206.488792)
		(width 0.13208)
		(layer "F.Cu")
		(net "PU_FPGA_SN")
	)
	(segment
		(start 350.567498 -208.60512)
		(end 351.55886 -207.613758)
		(width 0.13208)
		(layer "F.Cu")
		(net "PU_FPGA_SN")
	)
	(segment
		(start 354.212398 -206.488792)
		(end 354.212398 -205.550516)
		(width 0.13208)
		(layer "F.Cu")
		(net "PU_FPGA_SN")
	)
	(via
		(at 351.55886 -207.613758)
		(size 0.762)
		(drill 0.381)
		(layers "F.Cu" "B.Cu")
		(net "PU_FPGA_SN")
	)
	(segment
		(start 59.760104 -63.70193)
		(end 59.71032 -63.652146)
		(width 0.13208)
		(layer "F.Cu")
		(net "P12V_SSD2_PG_G2")
	)
	(segment
		(start 58.489342 -64.312292)
		(end 59.287918 -64.312292)
		(width 0.13208)
		(layer "F.Cu")
		(net "P12V_SSD2_PG_G2")
	)
	(segment
		(start 59.287918 -64.312292)
		(end 59.669934 -64.312292)
		(width 0.13208)
		(layer "F.Cu")
		(net "P12V_SSD2_PG_G2")
	)
	(segment
		(start 59.620404 -63.56223)
		(end 59.71032 -63.652146)
		(width 0.13208)
		(layer "F.Cu")
		(net "P12V_SSD2_PG_G2")
	)
	(segment
		(start 58.489342 -63.56223)
		(end 59.620404 -63.56223)
		(width 0.13208)
		(layer "F.Cu")
		(net "P12V_SSD2_PG_G2")
	)
	(segment
		(start 59.760104 -64.222122)
		(end 59.760104 -63.70193)
		(width 0.13208)
		(layer "F.Cu")
		(net "P12V_SSD2_PG_G2")
	)
	(segment
		(start 59.669934 -64.312292)
		(end 59.760104 -64.222122)
		(width 0.13208)
		(layer "F.Cu")
		(net "P12V_SSD2_PG_G2")
	)
	(via
		(at 59.287918 -64.312292)
		(size 0.508)
		(drill 0.254)
		(layers "F.Cu" "B.Cu")
		(net "P12V_SSD2_PG_G2")
	)
	(segment
		(start 46.514512 -67.01663)
		(end 46.514512 -66.72199)
		(width 0.13208)
		(layer "F.Cu")
		(net "P12V_SSD1_CO_EN")
	)
	(segment
		(start 46.453298 -67.537584)
		(end 46.453298 -67.077844)
		(width 0.13208)
		(layer "F.Cu")
		(net "P12V_SSD1_CO_EN")
	)
	(segment
		(start 46.453298 -67.077844)
		(end 46.514512 -67.01663)
		(width 0.13208)
		(layer "F.Cu")
		(net "P12V_SSD1_CO_EN")
	)
	(segment
		(start 46.575472 -67.970146)
		(end 46.453298 -67.847972)
		(width 0.13208)
		(layer "F.Cu")
		(net "P12V_SSD1_CO_EN")
	)
	(segment
		(start 46.453298 -67.847972)
		(end 46.453298 -67.537584)
		(width 0.13208)
		(layer "F.Cu")
		(net "P12V_SSD1_CO_EN")
	)
	(segment
		(start 46.575472 -68.479162)
		(end 46.575472 -67.970146)
		(width 0.13208)
		(layer "F.Cu")
		(net "P12V_SSD1_CO_EN")
	)
	(via
		(at 46.453298 -67.537584)
		(size 0.508)
		(drill 0.254)
		(layers "F.Cu" "B.Cu")
		(net "P12V_SSD1_CO_EN")
	)
	(segment
		(start 224.267776 -216.704164)
		(end 223.86798 -216.304368)
		(width 0.13208)
		(layer "F.Cu")
		(net "USB_DEBUG_RST_BTN_R_N")
	)
	(via
		(at 223.86798 -216.304368)
		(size 0.4572)
		(drill 0.254)
		(layers "F.Cu" "B.Cu")
		(net "USB_DEBUG_RST_BTN_R_N")
	)
	(via
		(at 210.52409 -217.14968)
		(size 0.6604)
		(drill 0.3302)
		(layers "F.Cu" "B.Cu")
		(net "USB_DEBUG_RST_BTN_R_N")
	)
	(via
		(at 211.665058 -217.31224)
		(size 0.508)
		(drill 0.254)
		(layers "F.Cu" "B.Cu")
		(net "USB_DEBUG_RST_BTN_R_N")
	)
	(segment
		(start 210.067398 -215.77173)
		(end 210.196684 -215.642444)
		(width 0.13208)
		(layer "B.Cu")
		(net "USB_DEBUG_RST_BTN_R_N")
	)
	(segment
		(start 210.52409 -217.14968)
		(end 210.52409 -217.307414)
		(width 0.13208)
		(layer "B.Cu")
		(net "USB_DEBUG_RST_BTN_R_N")
	)
	(segment
		(start 211.126832 -217.910156)
		(end 211.126832 -218.285822)
		(width 0.13208)
		(layer "B.Cu")
		(net "USB_DEBUG_RST_BTN_R_N")
	)
	(segment
		(start 211.76107 -217.408252)
		(end 211.76107 -218.120722)
		(width 0.13208)
		(layer "B.Cu")
		(net "USB_DEBUG_RST_BTN_R_N")
	)
	(segment
		(start 210.067398 -216.692988)
		(end 210.067398 -215.77173)
		(width 0.13208)
		(layer "B.Cu")
		(net "USB_DEBUG_RST_BTN_R_N")
	)
	(segment
		(start 211.126832 -218.285822)
		(end 211.149946 -218.308936)
		(width 0.13208)
		(layer "B.Cu")
		(net "USB_DEBUG_RST_BTN_R_N")
	)
	(segment
		(start 210.52409 -217.307414)
		(end 211.126832 -217.910156)
		(width 0.13208)
		(layer "B.Cu")
		(net "USB_DEBUG_RST_BTN_R_N")
	)
	(segment
		(start 211.665058 -217.31224)
		(end 211.76107 -217.408252)
		(width 0.13208)
		(layer "B.Cu")
		(net "USB_DEBUG_RST_BTN_R_N")
	)
	(segment
		(start 210.52409 -217.14968)
		(end 210.067398 -216.692988)
		(width 0.13208)
		(layer "B.Cu")
		(net "USB_DEBUG_RST_BTN_R_N")
	)
	(segment
		(start 211.76107 -218.120722)
		(end 211.572856 -218.308936)
		(width 0.13208)
		(layer "B.Cu")
		(net "USB_DEBUG_RST_BTN_R_N")
	)
	(segment
		(start 211.572856 -218.308936)
		(end 211.149946 -218.308936)
		(width 0.13208)
		(layer "B.Cu")
		(net "USB_DEBUG_RST_BTN_R_N")
	)
	(segment
		(start 216.601294 -217.5002)
		(end 222.672148 -217.5002)
		(width 0.15494)
		(layer "In15.Cu")
		(net "USB_DEBUG_RST_BTN_R_N")
	)
	(segment
		(start 222.672148 -217.5002)
		(end 223.86798 -216.304368)
		(width 0.15494)
		(layer "In15.Cu")
		(net "USB_DEBUG_RST_BTN_R_N")
	)
	(segment
		(start 212.123274 -217.770456)
		(end 216.331038 -217.770456)
		(width 0.15494)
		(layer "In15.Cu")
		(net "USB_DEBUG_RST_BTN_R_N")
	)
	(segment
		(start 216.331038 -217.770456)
		(end 216.601294 -217.5002)
		(width 0.15494)
		(layer "In15.Cu")
		(net "USB_DEBUG_RST_BTN_R_N")
	)
	(segment
		(start 211.665058 -217.31224)
		(end 212.123274 -217.770456)
		(width 0.15494)
		(layer "In15.Cu")
		(net "USB_DEBUG_RST_BTN_R_N")
	)
	(segment
		(start 7.760208 -64.496442)
		(end 7.760208 -63.70193)
		(width 0.13208)
		(layer "F.Cu")
		(net "P12V_SSD0_PG_G2")
	)
	(segment
		(start 7.132574 -65.124076)
		(end 7.760208 -64.496442)
		(width 0.13208)
		(layer "F.Cu")
		(net "P12V_SSD0_PG_G2")
	)
	(segment
		(start 7.710424 -63.652146)
		(end 7.620508 -63.56223)
		(width 0.13208)
		(layer "F.Cu")
		(net "P12V_SSD0_PG_G2")
	)
	(segment
		(start 7.620508 -63.56223)
		(end 6.489446 -63.56223)
		(width 0.13208)
		(layer "F.Cu")
		(net "P12V_SSD0_PG_G2")
	)
	(segment
		(start 7.760208 -63.70193)
		(end 7.710424 -63.652146)
		(width 0.13208)
		(layer "F.Cu")
		(net "P12V_SSD0_PG_G2")
	)
	(segment
		(start 6.489446 -64.312292)
		(end 6.489446 -65.124076)
		(width 0.13208)
		(layer "F.Cu")
		(net "P12V_SSD0_PG_G2")
	)
	(segment
		(start 6.489446 -65.124076)
		(end 7.132574 -65.124076)
		(width 0.13208)
		(layer "F.Cu")
		(net "P12V_SSD0_PG_G2")
	)
	(via
		(at 6.489446 -65.124076)
		(size 0.508)
		(drill 0.254)
		(layers "F.Cu" "B.Cu")
		(net "P12V_SSD0_PG_G2")
	)
	(segment
		(start 30.624272 -62.74689)
		(end 30.624272 -62.121034)
		(width 0.13208)
		(layer "F.Cu")
		(net "PWRGD_P12V_SSD1_D")
	)
	(segment
		(start 30.68955 -62.812168)
		(end 30.624272 -62.74689)
		(width 0.13208)
		(layer "F.Cu")
		(net "PWRGD_P12V_SSD1_D")
	)
	(segment
		(start 30.283658 -61.78042)
		(end 30.283658 -61.487812)
		(width 0.13208)
		(layer "F.Cu")
		(net "PWRGD_P12V_SSD1_D")
	)
	(segment
		(start 30.624272 -62.121034)
		(end 30.283658 -61.78042)
		(width 0.13208)
		(layer "F.Cu")
		(net "PWRGD_P12V_SSD1_D")
	)
	(segment
		(start 31.256224 -61.487812)
		(end 30.283658 -61.487812)
		(width 0.13208)
		(layer "F.Cu")
		(net "PWRGD_P12V_SSD1_D")
	)
	(via
		(at 30.624272 -62.121034)
		(size 0.508)
		(drill 0.254)
		(layers "F.Cu" "B.Cu")
		(net "PWRGD_P12V_SSD1_D")
	)
	(segment
		(start 97.921318 -71.555864)
		(end 97.576386 -71.555864)
		(width 0.13208)
		(layer "F.Cu")
		(net "P12V_SSD3_CO_MODE")
	)
	(segment
		(start 98.27387 -72.366632)
		(end 98.27387 -71.908416)
		(width 0.13208)
		(layer "F.Cu")
		(net "P12V_SSD3_CO_MODE")
	)
	(segment
		(start 98.075496 -71.056754)
		(end 98.075496 -70.479158)
		(width 0.13208)
		(layer "F.Cu")
		(net "P12V_SSD3_CO_MODE")
	)
	(segment
		(start 97.576386 -71.555864)
		(end 98.075496 -71.056754)
		(width 0.13208)
		(layer "F.Cu")
		(net "P12V_SSD3_CO_MODE")
	)
	(segment
		(start 97.25787 -72.366632)
		(end 98.27387 -72.366632)
		(width 0.13208)
		(layer "F.Cu")
		(net "P12V_SSD3_CO_MODE")
	)
	(segment
		(start 98.27387 -71.908416)
		(end 97.921318 -71.555864)
		(width 0.13208)
		(layer "F.Cu")
		(net "P12V_SSD3_CO_MODE")
	)
	(via
		(at 97.576386 -71.555864)
		(size 0.508)
		(drill 0.254)
		(layers "F.Cu" "B.Cu")
		(net "P12V_SSD3_CO_MODE")
	)
	(segment
		(start 55.275226 -64.102234)
		(end 55.275226 -63.086234)
		(width 0.13208)
		(layer "F.Cu")
		(net "P12V_SSD2_PG_G1")
	)
	(segment
		(start 56.247538 -63.56223)
		(end 55.95874 -63.273432)
		(width 0.13208)
		(layer "F.Cu")
		(net "P12V_SSD2_PG_G1")
	)
	(segment
		(start 55.889652 -63.273432)
		(end 55.702454 -63.086234)
		(width 0.13208)
		(layer "F.Cu")
		(net "P12V_SSD2_PG_G1")
	)
	(segment
		(start 55.95874 -63.273432)
		(end 55.889652 -63.273432)
		(width 0.13208)
		(layer "F.Cu")
		(net "P12V_SSD2_PG_G1")
	)
	(segment
		(start 55.702454 -63.086234)
		(end 55.275226 -63.086234)
		(width 0.13208)
		(layer "F.Cu")
		(net "P12V_SSD2_PG_G1")
	)
	(segment
		(start 56.689498 -63.56223)
		(end 56.247538 -63.56223)
		(width 0.13208)
		(layer "F.Cu")
		(net "P12V_SSD2_PG_G1")
	)
	(via
		(at 55.95874 -63.273432)
		(size 0.508)
		(drill 0.254)
		(layers "F.Cu" "B.Cu")
		(net "P12V_SSD2_PG_G1")
	)
	(segment
		(start 45.460412 -67.787266)
		(end 45.1612 -67.488054)
		(width 0.13208)
		(layer "F.Cu")
		(net "P12V_SSD1_CO_GATE")
	)
	(segment
		(start 45.498512 -67.150742)
		(end 45.498512 -66.72199)
		(width 0.13208)
		(layer "F.Cu")
		(net "P12V_SSD1_CO_GATE")
	)
	(segment
		(start 45.898816 -67.787266)
		(end 45.460412 -67.787266)
		(width 0.13208)
		(layer "F.Cu")
		(net "P12V_SSD1_CO_GATE")
	)
	(segment
		(start 45.1612 -67.488054)
		(end 45.498512 -67.150742)
		(width 0.13208)
		(layer "F.Cu")
		(net "P12V_SSD1_CO_GATE")
	)
	(segment
		(start 46.0756 -67.96405)
		(end 45.898816 -67.787266)
		(width 0.13208)
		(layer "F.Cu")
		(net "P12V_SSD1_CO_GATE")
	)
	(segment
		(start 46.0756 -68.479162)
		(end 46.0756 -67.96405)
		(width 0.13208)
		(layer "F.Cu")
		(net "P12V_SSD1_CO_GATE")
	)
	(via
		(at 45.1612 -67.488054)
		(size 0.508)
		(drill 0.254)
		(layers "F.Cu" "B.Cu")
		(net "P12V_SSD1_CO_GATE")
	)
	(segment
		(start 33.760156 -63.70193)
		(end 33.710372 -63.652146)
		(width 0.13208)
		(layer "F.Cu")
		(net "P12V_SSD1_PG_G2")
	)
	(segment
		(start 33.710372 -63.652146)
		(end 33.620456 -63.56223)
		(width 0.13208)
		(layer "F.Cu")
		(net "P12V_SSD1_PG_G2")
	)
	(segment
		(start 33.132522 -65.124076)
		(end 33.760156 -64.496442)
		(width 0.13208)
		(layer "F.Cu")
		(net "P12V_SSD1_PG_G2")
	)
	(segment
		(start 32.489394 -65.124076)
		(end 33.132522 -65.124076)
		(width 0.13208)
		(layer "F.Cu")
		(net "P12V_SSD1_PG_G2")
	)
	(segment
		(start 32.489394 -64.312292)
		(end 32.489394 -65.124076)
		(width 0.13208)
		(layer "F.Cu")
		(net "P12V_SSD1_PG_G2")
	)
	(segment
		(start 33.620456 -63.56223)
		(end 32.489394 -63.56223)
		(width 0.13208)
		(layer "F.Cu")
		(net "P12V_SSD1_PG_G2")
	)
	(segment
		(start 33.760156 -64.496442)
		(end 33.760156 -63.70193)
		(width 0.13208)
		(layer "F.Cu")
		(net "P12V_SSD1_PG_G2")
	)
	(via
		(at 32.489394 -65.124076)
		(size 0.508)
		(drill 0.254)
		(layers "F.Cu" "B.Cu")
		(net "P12V_SSD1_PG_G2")
	)
	(segment
		(start 99.727258 -67.592956)
		(end 99.727258 -67.228212)
		(width 0.13208)
		(layer "F.Cu")
		(net "P12V_SSD3_CO_DV_DT")
	)
	(segment
		(start 99.530408 -67.031362)
		(end 99.530408 -66.72199)
		(width 0.13208)
		(layer "F.Cu")
		(net "P12V_SSD3_CO_DV_DT")
	)
	(segment
		(start 99.07524 -68.244974)
		(end 99.727258 -67.592956)
		(width 0.13208)
		(layer "F.Cu")
		(net "P12V_SSD3_CO_DV_DT")
	)
	(segment
		(start 99.727258 -67.228212)
		(end 99.530408 -67.031362)
		(width 0.13208)
		(layer "F.Cu")
		(net "P12V_SSD3_CO_DV_DT")
	)
	(segment
		(start 99.07524 -68.479162)
		(end 99.07524 -68.244974)
		(width 0.13208)
		(layer "F.Cu")
		(net "P12V_SSD3_CO_DV_DT")
	)
	(via
		(at 99.727258 -67.592956)
		(size 0.508)
		(drill 0.254)
		(layers "F.Cu" "B.Cu")
		(net "P12V_SSD3_CO_DV_DT")
	)
	(segment
		(start 97.460308 -67.787266)
		(end 97.161096 -67.488054)
		(width 0.13208)
		(layer "F.Cu")
		(net "P12V_SSD3_CO_GATE")
	)
	(segment
		(start 97.161096 -67.488054)
		(end 97.498408 -67.150742)
		(width 0.13208)
		(layer "F.Cu")
		(net "P12V_SSD3_CO_GATE")
	)
	(segment
		(start 98.075496 -67.96405)
		(end 97.898712 -67.787266)
		(width 0.13208)
		(layer "F.Cu")
		(net "P12V_SSD3_CO_GATE")
	)
	(segment
		(start 98.075496 -68.479162)
		(end 98.075496 -67.96405)
		(width 0.13208)
		(layer "F.Cu")
		(net "P12V_SSD3_CO_GATE")
	)
	(segment
		(start 97.498408 -67.150742)
		(end 97.498408 -66.72199)
		(width 0.13208)
		(layer "F.Cu")
		(net "P12V_SSD3_CO_GATE")
	)
	(segment
		(start 97.898712 -67.787266)
		(end 97.460308 -67.787266)
		(width 0.13208)
		(layer "F.Cu")
		(net "P12V_SSD3_CO_GATE")
	)
	(via
		(at 97.161096 -67.488054)
		(size 0.508)
		(drill 0.254)
		(layers "F.Cu" "B.Cu")
		(net "P12V_SSD3_CO_GATE")
	)
	(segment
		(start 85.132418 -65.124076)
		(end 85.760052 -64.496442)
		(width 0.13208)
		(layer "F.Cu")
		(net "P12V_SSD3_PG_G2")
	)
	(segment
		(start 85.760052 -64.496442)
		(end 85.760052 -63.70193)
		(width 0.13208)
		(layer "F.Cu")
		(net "P12V_SSD3_PG_G2")
	)
	(segment
		(start 85.760052 -63.70193)
		(end 85.710268 -63.652146)
		(width 0.13208)
		(layer "F.Cu")
		(net "P12V_SSD3_PG_G2")
	)
	(segment
		(start 84.48929 -65.124076)
		(end 85.132418 -65.124076)
		(width 0.13208)
		(layer "F.Cu")
		(net "P12V_SSD3_PG_G2")
	)
	(segment
		(start 84.48929 -63.56223)
		(end 85.620352 -63.56223)
		(width 0.13208)
		(layer "F.Cu")
		(net "P12V_SSD3_PG_G2")
	)
	(segment
		(start 84.48929 -64.312292)
		(end 84.48929 -65.124076)
		(width 0.13208)
		(layer "F.Cu")
		(net "P12V_SSD3_PG_G2")
	)
	(segment
		(start 85.620352 -63.56223)
		(end 85.710268 -63.652146)
		(width 0.13208)
		(layer "F.Cu")
		(net "P12V_SSD3_PG_G2")
	)
	(via
		(at 84.48929 -65.124076)
		(size 0.508)
		(drill 0.254)
		(layers "F.Cu" "B.Cu")
		(net "P12V_SSD3_PG_G2")
	)
	(segment
		(start 20.075652 -71.056754)
		(end 20.075652 -70.479158)
		(width 0.13208)
		(layer "F.Cu")
		(net "P12V_SSD0_CO_MODE")
	)
	(segment
		(start 19.258026 -72.366632)
		(end 20.274026 -72.366632)
		(width 0.13208)
		(layer "F.Cu")
		(net "P12V_SSD0_CO_MODE")
	)
	(segment
		(start 20.274026 -71.908416)
		(end 19.921474 -71.555864)
		(width 0.13208)
		(layer "F.Cu")
		(net "P12V_SSD0_CO_MODE")
	)
	(segment
		(start 19.576542 -71.555864)
		(end 20.075652 -71.056754)
		(width 0.13208)
		(layer "F.Cu")
		(net "P12V_SSD0_CO_MODE")
	)
	(segment
		(start 20.274026 -72.366632)
		(end 20.274026 -71.908416)
		(width 0.13208)
		(layer "F.Cu")
		(net "P12V_SSD0_CO_MODE")
	)
	(segment
		(start 19.921474 -71.555864)
		(end 19.576542 -71.555864)
		(width 0.13208)
		(layer "F.Cu")
		(net "P12V_SSD0_CO_MODE")
	)
	(via
		(at 19.576542 -71.555864)
		(size 0.508)
		(drill 0.254)
		(layers "F.Cu" "B.Cu")
		(net "P12V_SSD0_CO_MODE")
	)
	(segment
		(start 73.289922 -72.366632)
		(end 73.289922 -71.827898)
		(width 0.13208)
		(layer "F.Cu")
		(net "P12V_SSD2_CO_ILIMIT")
	)
	(segment
		(start 72.57542 -71.113396)
		(end 72.57542 -70.479158)
		(width 0.13208)
		(layer "F.Cu")
		(net "P12V_SSD2_CO_ILIMIT")
	)
	(segment
		(start 73.289922 -71.827898)
		(end 73.085452 -71.623428)
		(width 0.13208)
		(layer "F.Cu")
		(net "P12V_SSD2_CO_ILIMIT")
	)
	(segment
		(start 73.085452 -71.623428)
		(end 72.57542 -71.113396)
		(width 0.13208)
		(layer "F.Cu")
		(net "P12V_SSD2_CO_ILIMIT")
	)
	(via
		(at 73.085452 -71.623428)
		(size 0.508)
		(drill 0.254)
		(layers "F.Cu" "B.Cu")
		(net "P12V_SSD2_CO_ILIMIT")
	)
	(segment
		(start 71.257922 -72.366632)
		(end 72.273922 -72.366632)
		(width 0.13208)
		(layer "F.Cu")
		(net "P12V_SSD2_CO_MODE")
	)
	(segment
		(start 72.273922 -72.366632)
		(end 72.273922 -71.908416)
		(width 0.13208)
		(layer "F.Cu")
		(net "P12V_SSD2_CO_MODE")
	)
	(segment
		(start 72.273922 -71.908416)
		(end 71.92137 -71.555864)
		(width 0.13208)
		(layer "F.Cu")
		(net "P12V_SSD2_CO_MODE")
	)
	(segment
		(start 71.92137 -71.555864)
		(end 71.576438 -71.555864)
		(width 0.13208)
		(layer "F.Cu")
		(net "P12V_SSD2_CO_MODE")
	)
	(segment
		(start 72.075548 -71.056754)
		(end 72.075548 -70.479158)
		(width 0.13208)
		(layer "F.Cu")
		(net "P12V_SSD2_CO_MODE")
	)
	(segment
		(start 71.576438 -71.555864)
		(end 72.075548 -71.056754)
		(width 0.13208)
		(layer "F.Cu")
		(net "P12V_SSD2_CO_MODE")
	)
	(via
		(at 71.576438 -71.555864)
		(size 0.508)
		(drill 0.254)
		(layers "F.Cu" "B.Cu")
		(net "P12V_SSD2_CO_MODE")
	)
	(segment
		(start 3.702558 -63.086234)
		(end 3.27533 -63.086234)
		(width 0.13208)
		(layer "F.Cu")
		(net "P12V_SSD0_PG_G1")
	)
	(segment
		(start 4.247642 -63.56223)
		(end 3.958844 -63.273432)
		(width 0.13208)
		(layer "F.Cu")
		(net "P12V_SSD0_PG_G1")
	)
	(segment
		(start 3.27533 -64.102234)
		(end 3.27533 -63.086234)
		(width 0.13208)
		(layer "F.Cu")
		(net "P12V_SSD0_PG_G1")
	)
	(segment
		(start 3.889756 -63.273432)
		(end 3.702558 -63.086234)
		(width 0.13208)
		(layer "F.Cu")
		(net "P12V_SSD0_PG_G1")
	)
	(segment
		(start 3.958844 -63.273432)
		(end 3.889756 -63.273432)
		(width 0.13208)
		(layer "F.Cu")
		(net "P12V_SSD0_PG_G1")
	)
	(segment
		(start 4.689602 -63.56223)
		(end 4.247642 -63.56223)
		(width 0.13208)
		(layer "F.Cu")
		(net "P12V_SSD0_PG_G1")
	)
	(via
		(at 3.958844 -63.273432)
		(size 0.508)
		(drill 0.254)
		(layers "F.Cu" "B.Cu")
		(net "P12V_SSD0_PG_G1")
	)
	(segment
		(start 83.25612 -61.487812)
		(end 82.283554 -61.487812)
		(width 0.13208)
		(layer "F.Cu")
		(net "PWRGD_P12V_SSD3_D")
	)
	(segment
		(start 82.283554 -61.78042)
		(end 82.283554 -61.487812)
		(width 0.13208)
		(layer "F.Cu")
		(net "PWRGD_P12V_SSD3_D")
	)
	(segment
		(start 82.624168 -62.121034)
		(end 82.283554 -61.78042)
		(width 0.13208)
		(layer "F.Cu")
		(net "PWRGD_P12V_SSD3_D")
	)
	(segment
		(start 82.689446 -62.812168)
		(end 82.624168 -62.74689)
		(width 0.13208)
		(layer "F.Cu")
		(net "PWRGD_P12V_SSD3_D")
	)
	(segment
		(start 82.624168 -62.74689)
		(end 82.624168 -62.121034)
		(width 0.13208)
		(layer "F.Cu")
		(net "PWRGD_P12V_SSD3_D")
	)
	(via
		(at 82.624168 -62.121034)
		(size 0.508)
		(drill 0.254)
		(layers "F.Cu" "B.Cu")
		(net "PWRGD_P12V_SSD3_D")
	)
	(segment
		(start 21.290026 -72.366632)
		(end 21.290026 -71.827898)
		(width 0.13208)
		(layer "F.Cu")
		(net "P12V_SSD0_CO_ILIMIT")
	)
	(segment
		(start 21.290026 -71.827898)
		(end 21.085556 -71.623428)
		(width 0.13208)
		(layer "F.Cu")
		(net "P12V_SSD0_CO_ILIMIT")
	)
	(segment
		(start 20.575524 -71.113396)
		(end 20.575524 -70.479158)
		(width 0.13208)
		(layer "F.Cu")
		(net "P12V_SSD0_CO_ILIMIT")
	)
	(segment
		(start 21.085556 -71.623428)
		(end 20.575524 -71.113396)
		(width 0.13208)
		(layer "F.Cu")
		(net "P12V_SSD0_CO_ILIMIT")
	)
	(via
		(at 21.085556 -71.623428)
		(size 0.508)
		(drill 0.254)
		(layers "F.Cu" "B.Cu")
		(net "P12V_SSD0_CO_ILIMIT")
	)
	(segment
		(start 73.72731 -67.592956)
		(end 73.72731 -67.228212)
		(width 0.13208)
		(layer "F.Cu")
		(net "P12V_SSD2_CO_DV_DT")
	)
	(segment
		(start 73.075292 -68.479162)
		(end 73.075292 -68.244974)
		(width 0.13208)
		(layer "F.Cu")
		(net "P12V_SSD2_CO_DV_DT")
	)
	(segment
		(start 73.075292 -68.244974)
		(end 73.72731 -67.592956)
		(width 0.13208)
		(layer "F.Cu")
		(net "P12V_SSD2_CO_DV_DT")
	)
	(segment
		(start 73.72731 -67.228212)
		(end 73.53046 -67.031362)
		(width 0.13208)
		(layer "F.Cu")
		(net "P12V_SSD2_CO_DV_DT")
	)
	(segment
		(start 73.53046 -67.031362)
		(end 73.53046 -66.72199)
		(width 0.13208)
		(layer "F.Cu")
		(net "P12V_SSD2_CO_DV_DT")
	)
	(via
		(at 73.72731 -67.592956)
		(size 0.508)
		(drill 0.254)
		(layers "F.Cu" "B.Cu")
		(net "P12V_SSD2_CO_DV_DT")
	)
	(segment
		(start 21.727414 -67.228212)
		(end 21.530564 -67.031362)
		(width 0.13208)
		(layer "F.Cu")
		(net "P12V_SSD0_CO_DV_DT")
	)
	(segment
		(start 21.075396 -68.244974)
		(end 21.727414 -67.592956)
		(width 0.13208)
		(layer "F.Cu")
		(net "P12V_SSD0_CO_DV_DT")
	)
	(segment
		(start 21.530564 -67.031362)
		(end 21.530564 -66.72199)
		(width 0.13208)
		(layer "F.Cu")
		(net "P12V_SSD0_CO_DV_DT")
	)
	(segment
		(start 21.075396 -68.479162)
		(end 21.075396 -68.244974)
		(width 0.13208)
		(layer "F.Cu")
		(net "P12V_SSD0_CO_DV_DT")
	)
	(segment
		(start 21.727414 -67.592956)
		(end 21.727414 -67.228212)
		(width 0.13208)
		(layer "F.Cu")
		(net "P12V_SSD0_CO_DV_DT")
	)
	(via
		(at 21.727414 -67.592956)
		(size 0.508)
		(drill 0.254)
		(layers "F.Cu" "B.Cu")
		(net "P12V_SSD0_CO_DV_DT")
	)
	(segment
		(start 46.0756 -71.056754)
		(end 46.0756 -70.479158)
		(width 0.13208)
		(layer "F.Cu")
		(net "P12V_SSD1_CO_MODE")
	)
	(segment
		(start 46.273974 -72.366632)
		(end 46.273974 -71.908416)
		(width 0.13208)
		(layer "F.Cu")
		(net "P12V_SSD1_CO_MODE")
	)
	(segment
		(start 45.257974 -72.366632)
		(end 46.273974 -72.366632)
		(width 0.13208)
		(layer "F.Cu")
		(net "P12V_SSD1_CO_MODE")
	)
	(segment
		(start 45.57649 -71.555864)
		(end 46.0756 -71.056754)
		(width 0.13208)
		(layer "F.Cu")
		(net "P12V_SSD1_CO_MODE")
	)
	(segment
		(start 45.921422 -71.555864)
		(end 45.57649 -71.555864)
		(width 0.13208)
		(layer "F.Cu")
		(net "P12V_SSD1_CO_MODE")
	)
	(segment
		(start 46.273974 -71.908416)
		(end 45.921422 -71.555864)
		(width 0.13208)
		(layer "F.Cu")
		(net "P12V_SSD1_CO_MODE")
	)
	(via
		(at 45.57649 -71.555864)
		(size 0.508)
		(drill 0.254)
		(layers "F.Cu" "B.Cu")
		(net "P12V_SSD1_CO_MODE")
	)
	(segment
		(start 47.075344 -68.479162)
		(end 47.075344 -68.244974)
		(width 0.13208)
		(layer "F.Cu")
		(net "P12V_SSD1_CO_DV_DT")
	)
	(segment
		(start 47.727362 -67.228212)
		(end 47.530512 -67.031362)
		(width 0.13208)
		(layer "F.Cu")
		(net "P12V_SSD1_CO_DV_DT")
	)
	(segment
		(start 47.727362 -67.592956)
		(end 47.727362 -67.228212)
		(width 0.13208)
		(layer "F.Cu")
		(net "P12V_SSD1_CO_DV_DT")
	)
	(segment
		(start 47.530512 -67.031362)
		(end 47.530512 -66.72199)
		(width 0.13208)
		(layer "F.Cu")
		(net "P12V_SSD1_CO_DV_DT")
	)
	(segment
		(start 47.075344 -68.244974)
		(end 47.727362 -67.592956)
		(width 0.13208)
		(layer "F.Cu")
		(net "P12V_SSD1_CO_DV_DT")
	)
	(via
		(at 47.727362 -67.592956)
		(size 0.508)
		(drill 0.254)
		(layers "F.Cu" "B.Cu")
		(net "P12V_SSD1_CO_DV_DT")
	)
	(segment
		(start 47.289974 -72.366632)
		(end 47.289974 -71.827898)
		(width 0.13208)
		(layer "F.Cu")
		(net "P12V_SSD1_CO_ILIMIT")
	)
	(segment
		(start 46.575472 -71.113396)
		(end 46.575472 -70.479158)
		(width 0.13208)
		(layer "F.Cu")
		(net "P12V_SSD1_CO_ILIMIT")
	)
	(segment
		(start 47.085504 -71.623428)
		(end 46.575472 -71.113396)
		(width 0.13208)
		(layer "F.Cu")
		(net "P12V_SSD1_CO_ILIMIT")
	)
	(segment
		(start 47.289974 -71.827898)
		(end 47.085504 -71.623428)
		(width 0.13208)
		(layer "F.Cu")
		(net "P12V_SSD1_CO_ILIMIT")
	)
	(via
		(at 47.085504 -71.623428)
		(size 0.508)
		(drill 0.254)
		(layers "F.Cu" "B.Cu")
		(net "P12V_SSD1_CO_ILIMIT")
	)
	(segment
		(start 98.453194 -67.077844)
		(end 98.514408 -67.01663)
		(width 0.13208)
		(layer "F.Cu")
		(net "P12V_SSD3_CO_EN")
	)
	(segment
		(start 98.575368 -68.479162)
		(end 98.575368 -67.970146)
		(width 0.13208)
		(layer "F.Cu")
		(net "P12V_SSD3_CO_EN")
	)
	(segment
		(start 98.575368 -67.970146)
		(end 98.453194 -67.847972)
		(width 0.13208)
		(layer "F.Cu")
		(net "P12V_SSD3_CO_EN")
	)
	(segment
		(start 98.514408 -67.01663)
		(end 98.514408 -66.72199)
		(width 0.13208)
		(layer "F.Cu")
		(net "P12V_SSD3_CO_EN")
	)
	(segment
		(start 98.453194 -67.537584)
		(end 98.453194 -67.077844)
		(width 0.13208)
		(layer "F.Cu")
		(net "P12V_SSD3_CO_EN")
	)
	(segment
		(start 98.453194 -67.847972)
		(end 98.453194 -67.537584)
		(width 0.13208)
		(layer "F.Cu")
		(net "P12V_SSD3_CO_EN")
	)
	(via
		(at 98.453194 -67.537584)
		(size 0.508)
		(drill 0.254)
		(layers "F.Cu" "B.Cu")
		(net "P12V_SSD3_CO_EN")
	)
	(segment
		(start 82.247486 -63.56223)
		(end 81.958688 -63.273432)
		(width 0.13208)
		(layer "F.Cu")
		(net "P12V_SSD3_PG_G1")
	)
	(segment
		(start 81.275174 -64.102234)
		(end 81.275174 -63.086234)
		(width 0.13208)
		(layer "F.Cu")
		(net "P12V_SSD3_PG_G1")
	)
	(segment
		(start 81.8896 -63.273432)
		(end 81.702402 -63.086234)
		(width 0.13208)
		(layer "F.Cu")
		(net "P12V_SSD3_PG_G1")
	)
	(segment
		(start 81.958688 -63.273432)
		(end 81.8896 -63.273432)
		(width 0.13208)
		(layer "F.Cu")
		(net "P12V_SSD3_PG_G1")
	)
	(segment
		(start 82.689446 -63.56223)
		(end 82.247486 -63.56223)
		(width 0.13208)
		(layer "F.Cu")
		(net "P12V_SSD3_PG_G1")
	)
	(segment
		(start 81.702402 -63.086234)
		(end 81.275174 -63.086234)
		(width 0.13208)
		(layer "F.Cu")
		(net "P12V_SSD3_PG_G1")
	)
	(via
		(at 81.958688 -63.273432)
		(size 0.508)
		(drill 0.254)
		(layers "F.Cu" "B.Cu")
		(net "P12V_SSD3_PG_G1")
	)
	(segment
		(start 5.256276 -61.487812)
		(end 4.28371 -61.487812)
		(width 0.13208)
		(layer "F.Cu")
		(net "PWRGD_P12V_SSD0_D")
	)
	(segment
		(start 4.28371 -61.78042)
		(end 4.28371 -61.487812)
		(width 0.13208)
		(layer "F.Cu")
		(net "PWRGD_P12V_SSD0_D")
	)
	(segment
		(start 4.689602 -62.812168)
		(end 4.624324 -62.74689)
		(width 0.13208)
		(layer "F.Cu")
		(net "PWRGD_P12V_SSD0_D")
	)
	(segment
		(start 4.624324 -62.74689)
		(end 4.624324 -62.121034)
		(width 0.13208)
		(layer "F.Cu")
		(net "PWRGD_P12V_SSD0_D")
	)
	(segment
		(start 4.624324 -62.121034)
		(end 4.28371 -61.78042)
		(width 0.13208)
		(layer "F.Cu")
		(net "PWRGD_P12V_SSD0_D")
	)
	(via
		(at 4.624324 -62.121034)
		(size 0.508)
		(drill 0.254)
		(layers "F.Cu" "B.Cu")
		(net "PWRGD_P12V_SSD0_D")
	)
	(segment
		(start 370.759482 -261.207758)
		(end 371.428518 -261.207758)
		(width 0.13208)
		(layer "F.Cu")
		(net "PEX3_SYS_ERR_FPGA")
	)
	(segment
		(start 338.093812 -221.58706)
		(end 337.694016 -221.986856)
		(width 0.13208)
		(layer "F.Cu")
		(net "PEX3_SYS_ERR_FPGA")
	)
	(via
		(at 370.759482 -261.207758)
		(size 0.508)
		(drill 0.254)
		(layers "F.Cu" "B.Cu")
		(net "PEX3_SYS_ERR_FPGA")
	)
	(via
		(at 337.694016 -221.986856)
		(size 0.4572)
		(drill 0.254)
		(layers "F.Cu" "B.Cu")
		(net "PEX3_SYS_ERR_FPGA")
	)
	(segment
		(start 346.44711 -240.041176)
		(end 346.44711 -239.438434)
		(width 0.15494)
		(layer "In7.Cu")
		(net "PEX3_SYS_ERR_FPGA")
	)
	(segment
		(start 339.694012 -227.0506)
		(end 339.694012 -227.324158)
		(width 0.15494)
		(layer "In7.Cu")
		(net "PEX3_SYS_ERR_FPGA")
	)
	(segment
		(start 340.487 -233.38917)
		(end 340.487 -237.249716)
		(width 0.15494)
		(layer "In7.Cu")
		(net "PEX3_SYS_ERR_FPGA")
	)
	(segment
		(start 339.506306 -222.386906)
		(end 339.694012 -222.574612)
		(width 0.0889)
		(layer "In7.Cu")
		(net "PEX3_SYS_ERR_FPGA")
	)
	(segment
		(start 346.173044 -237.511082)
		(end 351.578164 -237.511082)
		(width 0.15494)
		(layer "In7.Cu")
		(net "PEX3_SYS_ERR_FPGA")
	)
	(segment
		(start 360.559096 -246.827802)
		(end 360.781854 -247.050306)
		(width 0.15494)
		(layer "In7.Cu")
		(net "PEX3_SYS_ERR_FPGA")
	)
	(segment
		(start 339.694012 -222.574612)
		(end 339.694012 -227.0506)
		(width 0.0889)
		(layer "In7.Cu")
		(net "PEX3_SYS_ERR_FPGA")
	)
	(segment
		(start 337.694016 -221.986856)
		(end 338.094066 -222.386906)
		(width 0.0889)
		(layer "In7.Cu")
		(net "PEX3_SYS_ERR_FPGA")
	)
	(segment
		(start 339.852254 -232.754424)
		(end 340.487 -233.38917)
		(width 0.15494)
		(layer "In7.Cu")
		(net "PEX3_SYS_ERR_FPGA")
	)
	(segment
		(start 351.578164 -237.511082)
		(end 360.559096 -246.492014)
		(width 0.15494)
		(layer "In7.Cu")
		(net "PEX3_SYS_ERR_FPGA")
	)
	(segment
		(start 360.781854 -247.050306)
		(end 367.887504 -254.15621)
		(width 0.15494)
		(layer "In7.Cu")
		(net "PEX3_SYS_ERR_FPGA")
	)
	(segment
		(start 339.694012 -227.324158)
		(end 339.852254 -227.4824)
		(width 0.15494)
		(layer "In7.Cu")
		(net "PEX3_SYS_ERR_FPGA")
	)
	(segment
		(start 345.876626 -240.61166)
		(end 346.44711 -240.041176)
		(width 0.15494)
		(layer "In7.Cu")
		(net "PEX3_SYS_ERR_FPGA")
	)
	(segment
		(start 345.908122 -237.776004)
		(end 346.173044 -237.511082)
		(width 0.15494)
		(layer "In7.Cu")
		(net "PEX3_SYS_ERR_FPGA")
	)
	(segment
		(start 346.44711 -239.438434)
		(end 345.908122 -238.899446)
		(width 0.15494)
		(layer "In7.Cu")
		(net "PEX3_SYS_ERR_FPGA")
	)
	(segment
		(start 340.487 -237.249716)
		(end 343.848944 -240.61166)
		(width 0.15494)
		(layer "In7.Cu")
		(net "PEX3_SYS_ERR_FPGA")
	)
	(segment
		(start 338.094066 -222.386906)
		(end 339.506306 -222.386906)
		(width 0.0889)
		(layer "In7.Cu")
		(net "PEX3_SYS_ERR_FPGA")
	)
	(segment
		(start 339.852254 -227.4824)
		(end 339.852254 -232.754424)
		(width 0.15494)
		(layer "In7.Cu")
		(net "PEX3_SYS_ERR_FPGA")
	)
	(segment
		(start 367.887504 -254.15621)
		(end 367.887504 -259.16128)
		(width 0.15494)
		(layer "In7.Cu")
		(net "PEX3_SYS_ERR_FPGA")
	)
	(segment
		(start 367.887504 -259.16128)
		(end 369.933982 -261.207758)
		(width 0.15494)
		(layer "In7.Cu")
		(net "PEX3_SYS_ERR_FPGA")
	)
	(segment
		(start 369.933982 -261.207758)
		(end 370.759482 -261.207758)
		(width 0.15494)
		(layer "In7.Cu")
		(net "PEX3_SYS_ERR_FPGA")
	)
	(segment
		(start 345.908122 -238.899446)
		(end 345.908122 -237.776004)
		(width 0.15494)
		(layer "In7.Cu")
		(net "PEX3_SYS_ERR_FPGA")
	)
	(segment
		(start 343.848944 -240.61166)
		(end 345.876626 -240.61166)
		(width 0.15494)
		(layer "In7.Cu")
		(net "PEX3_SYS_ERR_FPGA")
	)
	(segment
		(start 360.559096 -246.492014)
		(end 360.559096 -246.827802)
		(width 0.15494)
		(layer "In7.Cu")
		(net "PEX3_SYS_ERR_FPGA")
	)
	(segment
		(start 30.24759 -63.56223)
		(end 30.68955 -63.56223)
		(width 0.13208)
		(layer "F.Cu")
		(net "P12V_SSD1_PG_G1")
	)
	(segment
		(start 29.958792 -63.273432)
		(end 30.24759 -63.56223)
		(width 0.13208)
		(layer "F.Cu")
		(net "P12V_SSD1_PG_G1")
	)
	(segment
		(start 29.889704 -63.273432)
		(end 29.958792 -63.273432)
		(width 0.13208)
		(layer "F.Cu")
		(net "P12V_SSD1_PG_G1")
	)
	(segment
		(start 29.275278 -63.086234)
		(end 29.702506 -63.086234)
		(width 0.13208)
		(layer "F.Cu")
		(net "P12V_SSD1_PG_G1")
	)
	(segment
		(start 29.275278 -64.102234)
		(end 29.275278 -63.086234)
		(width 0.13208)
		(layer "F.Cu")
		(net "P12V_SSD1_PG_G1")
	)
	(segment
		(start 29.702506 -63.086234)
		(end 29.889704 -63.273432)
		(width 0.13208)
		(layer "F.Cu")
		(net "P12V_SSD1_PG_G1")
	)
	(via
		(at 29.958792 -63.273432)
		(size 0.508)
		(drill 0.254)
		(layers "F.Cu" "B.Cu")
		(net "P12V_SSD1_PG_G1")
	)
	(segment
		(start 8.884158 -159.844994)
		(end 9.29005 -159.439102)
		(width 0.254)
		(layer "F.Cu")
		(net "P12V_NIC0_CO_FLTB")
	)
	(segment
		(start 9.29005 -159.439102)
		(end 10.019284 -159.439102)
		(width 0.254)
		(layer "F.Cu")
		(net "P12V_NIC0_CO_FLTB")
	)
	(segment
		(start 8.449818 -159.844994)
		(end 8.884158 -159.844994)
		(width 0.254)
		(layer "F.Cu")
		(net "P12V_NIC0_CO_FLTB")
	)
	(segment
		(start 10.494772 -158.963614)
		(end 10.494772 -158.705042)
		(width 0.254)
		(layer "F.Cu")
		(net "P12V_NIC0_CO_FLTB")
	)
	(segment
		(start 10.019284 -159.439102)
		(end 10.494772 -158.963614)
		(width 0.254)
		(layer "F.Cu")
		(net "P12V_NIC0_CO_FLTB")
	)
	(via
		(at 9.29005 -159.439102)
		(size 0.508)
		(drill 0.254)
		(layers "F.Cu" "B.Cu")
		(net "P12V_NIC0_CO_FLTB")
	)
	(segment
		(start 19.498564 -67.150742)
		(end 19.498564 -66.72199)
		(width 0.13208)
		(layer "F.Cu")
		(net "P12V_SSD0_CO_GATE")
	)
	(segment
		(start 19.161252 -67.488054)
		(end 19.498564 -67.150742)
		(width 0.13208)
		(layer "F.Cu")
		(net "P12V_SSD0_CO_GATE")
	)
	(segment
		(start 19.898868 -67.787266)
		(end 19.460464 -67.787266)
		(width 0.13208)
		(layer "F.Cu")
		(net "P12V_SSD0_CO_GATE")
	)
	(segment
		(start 20.075652 -68.479162)
		(end 20.075652 -67.96405)
		(width 0.13208)
		(layer "F.Cu")
		(net "P12V_SSD0_CO_GATE")
	)
	(segment
		(start 20.075652 -67.96405)
		(end 19.898868 -67.787266)
		(width 0.13208)
		(layer "F.Cu")
		(net "P12V_SSD0_CO_GATE")
	)
	(segment
		(start 19.460464 -67.787266)
		(end 19.161252 -67.488054)
		(width 0.13208)
		(layer "F.Cu")
		(net "P12V_SSD0_CO_GATE")
	)
	(via
		(at 19.161252 -67.488054)
		(size 0.508)
		(drill 0.254)
		(layers "F.Cu" "B.Cu")
		(net "P12V_SSD0_CO_GATE")
	)
	(segment
		(start 248.821448 -218.079828)
		(end 248.821448 -217.350848)
		(width 0.13208)
		(layer "F.Cu")
		(net "PEX2_SYS_ERR_FPGA")
	)
	(segment
		(start 252.278134 -219.146628)
		(end 249.888248 -219.146628)
		(width 0.13208)
		(layer "F.Cu")
		(net "PEX2_SYS_ERR_FPGA")
	)
	(segment
		(start 253.024386 -222.699072)
		(end 253.024386 -219.89288)
		(width 0.13208)
		(layer "F.Cu")
		(net "PEX2_SYS_ERR_FPGA")
	)
	(segment
		(start 254.357378 -261.207758)
		(end 253.5174 -260.36778)
		(width 0.13208)
		(layer "F.Cu")
		(net "PEX2_SYS_ERR_FPGA")
	)
	(segment
		(start 252.926088 -257.199384)
		(end 252.926088 -247.981216)
		(width 0.13208)
		(layer "F.Cu")
		(net "PEX2_SYS_ERR_FPGA")
	)
	(segment
		(start 253.5174 -259.58673)
		(end 253.210568 -258.845558)
		(width 0.13208)
		(layer "F.Cu")
		(net "PEX2_SYS_ERR_FPGA")
	)
	(segment
		(start 252.610366 -233.816144)
		(end 252.610366 -226.955096)
		(width 0.13208)
		(layer "F.Cu")
		(net "PEX2_SYS_ERR_FPGA")
	)
	(segment
		(start 255.32842 -261.207758)
		(end 254.357378 -261.207758)
		(width 0.13208)
		(layer "F.Cu")
		(net "PEX2_SYS_ERR_FPGA")
	)
	(segment
		(start 253.024386 -219.89288)
		(end 252.278134 -219.146628)
		(width 0.13208)
		(layer "F.Cu")
		(net "PEX2_SYS_ERR_FPGA")
	)
	(segment
		(start 252.610366 -226.955096)
		(end 251.92736 -226.27209)
		(width 0.13208)
		(layer "F.Cu")
		(net "PEX2_SYS_ERR_FPGA")
	)
	(segment
		(start 253.5174 -260.36778)
		(end 253.5174 -259.58673)
		(width 0.13208)
		(layer "F.Cu")
		(net "PEX2_SYS_ERR_FPGA")
	)
	(segment
		(start 248.821448 -217.350848)
		(end 249.286014 -216.886282)
		(width 0.13208)
		(layer "F.Cu")
		(net "PEX2_SYS_ERR_FPGA")
	)
	(segment
		(start 249.286014 -216.886282)
		(end 249.750326 -216.886282)
		(width 0.13208)
		(layer "F.Cu")
		(net "PEX2_SYS_ERR_FPGA")
	)
	(segment
		(start 253.210568 -258.845558)
		(end 253.210568 -257.483864)
		(width 0.13208)
		(layer "F.Cu")
		(net "PEX2_SYS_ERR_FPGA")
	)
	(segment
		(start 253.210568 -257.483864)
		(end 252.926088 -257.199384)
		(width 0.13208)
		(layer "F.Cu")
		(net "PEX2_SYS_ERR_FPGA")
	)
	(segment
		(start 251.92736 -226.27209)
		(end 251.92736 -223.796098)
		(width 0.13208)
		(layer "F.Cu")
		(net "PEX2_SYS_ERR_FPGA")
	)
	(segment
		(start 250.980956 -246.036084)
		(end 250.980956 -235.445554)
		(width 0.13208)
		(layer "F.Cu")
		(net "PEX2_SYS_ERR_FPGA")
	)
	(segment
		(start 249.888248 -219.146628)
		(end 248.821448 -218.079828)
		(width 0.13208)
		(layer "F.Cu")
		(net "PEX2_SYS_ERR_FPGA")
	)
	(segment
		(start 338.893912 -221.58706)
		(end 338.494116 -221.986856)
		(width 0.13208)
		(layer "F.Cu")
		(net "PEX2_SYS_ERR_FPGA")
	)
	(segment
		(start 252.926088 -247.981216)
		(end 250.980956 -246.036084)
		(width 0.13208)
		(layer "F.Cu")
		(net "PEX2_SYS_ERR_FPGA")
	)
	(segment
		(start 250.980956 -235.445554)
		(end 252.610366 -233.816144)
		(width 0.13208)
		(layer "F.Cu")
		(net "PEX2_SYS_ERR_FPGA")
	)
	(segment
		(start 251.92736 -223.796098)
		(end 253.024386 -222.699072)
		(width 0.13208)
		(layer "F.Cu")
		(net "PEX2_SYS_ERR_FPGA")
	)
	(via
		(at 257.383026 -199.625966)
		(size 0.508)
		(drill 0.254)
		(layers "F.Cu" "B.Cu")
		(net "PEX2_SYS_ERR_FPGA")
	)
	(via
		(at 249.750326 -216.886282)
		(size 0.508)
		(drill 0.254)
		(layers "F.Cu" "B.Cu")
		(net "PEX2_SYS_ERR_FPGA")
	)
	(via
		(at 338.494116 -221.986856)
		(size 0.4572)
		(drill 0.254)
		(layers "F.Cu" "B.Cu")
		(net "PEX2_SYS_ERR_FPGA")
	)
	(segment
		(start 250.16079 -217.296746)
		(end 249.750326 -216.886282)
		(width 0.15494)
		(layer "In5.Cu")
		(net "PEX2_SYS_ERR_FPGA")
	)
	(segment
		(start 254.441706 -201.90841)
		(end 254.441706 -206.801974)
		(width 0.15494)
		(layer "In5.Cu")
		(net "PEX2_SYS_ERR_FPGA")
	)
	(segment
		(start 252.902212 -214.99703)
		(end 252.902212 -216.207086)
		(width 0.15494)
		(layer "In5.Cu")
		(net "PEX2_SYS_ERR_FPGA")
	)
	(segment
		(start 251.812552 -217.296746)
		(end 250.16079 -217.296746)
		(width 0.15494)
		(layer "In5.Cu")
		(net "PEX2_SYS_ERR_FPGA")
	)
	(segment
		(start 257.383026 -199.625966)
		(end 256.72415 -199.625966)
		(width 0.15494)
		(layer "In5.Cu")
		(net "PEX2_SYS_ERR_FPGA")
	)
	(segment
		(start 254.441706 -206.801974)
		(end 255.3462 -207.706468)
		(width 0.15494)
		(layer "In5.Cu")
		(net "PEX2_SYS_ERR_FPGA")
	)
	(segment
		(start 255.3462 -207.706468)
		(end 255.3462 -212.553042)
		(width 0.15494)
		(layer "In5.Cu")
		(net "PEX2_SYS_ERR_FPGA")
	)
	(segment
		(start 252.902212 -216.207086)
		(end 251.812552 -217.296746)
		(width 0.15494)
		(layer "In5.Cu")
		(net "PEX2_SYS_ERR_FPGA")
	)
	(segment
		(start 256.72415 -199.625966)
		(end 254.441706 -201.90841)
		(width 0.15494)
		(layer "In5.Cu")
		(net "PEX2_SYS_ERR_FPGA")
	)
	(segment
		(start 255.3462 -212.553042)
		(end 252.902212 -214.99703)
		(width 0.15494)
		(layer "In5.Cu")
		(net "PEX2_SYS_ERR_FPGA")
	)
	(segment
		(start 278.38781 -211.56041)
		(end 319.445132 -211.56041)
		(width 0.15494)
		(layer "In13.Cu")
		(net "PEX2_SYS_ERR_FPGA")
	)
	(segment
		(start 327.1012 -214.623142)
		(end 328.275188 -215.79713)
		(width 0.15494)
		(layer "In13.Cu")
		(net "PEX2_SYS_ERR_FPGA")
	)
	(segment
		(start 331.050392 -217.715592)
		(end 332.31455 -218.97975)
		(width 0.15494)
		(layer "In13.Cu")
		(net "PEX2_SYS_ERR_FPGA")
	)
	(segment
		(start 319.445132 -211.56041)
		(end 321.524122 -213.6394)
		(width 0.15494)
		(layer "In13.Cu")
		(net "PEX2_SYS_ERR_FPGA")
	)
	(segment
		(start 257.383026 -199.625966)
		(end 259.762498 -199.625966)
		(width 0.15494)
		(layer "In13.Cu")
		(net "PEX2_SYS_ERR_FPGA")
	)
	(segment
		(start 266.719558 -199.892158)
		(end 278.38781 -211.56041)
		(width 0.15494)
		(layer "In13.Cu")
		(net "PEX2_SYS_ERR_FPGA")
	)
	(segment
		(start 329.806046 -217.715592)
		(end 331.050392 -217.715592)
		(width 0.15494)
		(layer "In13.Cu")
		(net "PEX2_SYS_ERR_FPGA")
	)
	(segment
		(start 328.74966 -215.79713)
		(end 329.03287 -216.08034)
		(width 0.15494)
		(layer "In13.Cu")
		(net "PEX2_SYS_ERR_FPGA")
	)
	(segment
		(start 263.812528 -199.892158)
		(end 266.719558 -199.892158)
		(width 0.15494)
		(layer "In13.Cu")
		(net "PEX2_SYS_ERR_FPGA")
	)
	(segment
		(start 332.31455 -218.97975)
		(end 332.31455 -220.339666)
		(width 0.15494)
		(layer "In13.Cu")
		(net "PEX2_SYS_ERR_FPGA")
	)
	(segment
		(start 329.03287 -216.094818)
		(end 329.164696 -216.226644)
		(width 0.15494)
		(layer "In13.Cu")
		(net "PEX2_SYS_ERR_FPGA")
	)
	(segment
		(start 326.618854 -213.6394)
		(end 327.1012 -214.121746)
		(width 0.15494)
		(layer "In13.Cu")
		(net "PEX2_SYS_ERR_FPGA")
	)
	(segment
		(start 334.417924 -221.586806)
		(end 335.0006 -221.586806)
		(width 0.15494)
		(layer "In13.Cu")
		(net "PEX2_SYS_ERR_FPGA")
	)
	(segment
		(start 328.275188 -215.79713)
		(end 328.74966 -215.79713)
		(width 0.15494)
		(layer "In13.Cu")
		(net "PEX2_SYS_ERR_FPGA")
	)
	(segment
		(start 338.094066 -221.586806)
		(end 338.494116 -221.986856)
		(width 0.0889)
		(layer "In13.Cu")
		(net "PEX2_SYS_ERR_FPGA")
	)
	(segment
		(start 327.1012 -214.121746)
		(end 327.1012 -214.623142)
		(width 0.15494)
		(layer "In13.Cu")
		(net "PEX2_SYS_ERR_FPGA")
	)
	(segment
		(start 332.31455 -220.339666)
		(end 332.65999 -220.685106)
		(width 0.15494)
		(layer "In13.Cu")
		(net "PEX2_SYS_ERR_FPGA")
	)
	(segment
		(start 329.164696 -216.226644)
		(end 329.164696 -217.074242)
		(width 0.15494)
		(layer "In13.Cu")
		(net "PEX2_SYS_ERR_FPGA")
	)
	(segment
		(start 261.107936 -198.280528)
		(end 262.200898 -198.280528)
		(width 0.15494)
		(layer "In13.Cu")
		(net "PEX2_SYS_ERR_FPGA")
	)
	(segment
		(start 335.0006 -221.586806)
		(end 338.094066 -221.586806)
		(width 0.0889)
		(layer "In13.Cu")
		(net "PEX2_SYS_ERR_FPGA")
	)
	(segment
		(start 321.524122 -213.6394)
		(end 326.618854 -213.6394)
		(width 0.15494)
		(layer "In13.Cu")
		(net "PEX2_SYS_ERR_FPGA")
	)
	(segment
		(start 333.516224 -220.685106)
		(end 334.417924 -221.586806)
		(width 0.15494)
		(layer "In13.Cu")
		(net "PEX2_SYS_ERR_FPGA")
	)
	(segment
		(start 329.164696 -217.074242)
		(end 329.806046 -217.715592)
		(width 0.15494)
		(layer "In13.Cu")
		(net "PEX2_SYS_ERR_FPGA")
	)
	(segment
		(start 259.762498 -199.625966)
		(end 261.107936 -198.280528)
		(width 0.15494)
		(layer "In13.Cu")
		(net "PEX2_SYS_ERR_FPGA")
	)
	(segment
		(start 329.03287 -216.08034)
		(end 329.03287 -216.094818)
		(width 0.15494)
		(layer "In13.Cu")
		(net "PEX2_SYS_ERR_FPGA")
	)
	(segment
		(start 332.65999 -220.685106)
		(end 333.516224 -220.685106)
		(width 0.15494)
		(layer "In13.Cu")
		(net "PEX2_SYS_ERR_FPGA")
	)
	(segment
		(start 262.200898 -198.280528)
		(end 263.812528 -199.892158)
		(width 0.15494)
		(layer "In13.Cu")
		(net "PEX2_SYS_ERR_FPGA")
	)
	(via
		(at 105.38714 -114.028474)
		(size 0.508)
		(drill 0.254)
		(layers "F.Cu" "B.Cu")
		(net "P12V_NIC1_CO_AVIN_PD")
	)
	(segment
		(start 71.161148 -67.488054)
		(end 71.49846 -67.150742)
		(width 0.13208)
		(layer "F.Cu")
		(net "P12V_SSD2_CO_GATE")
	)
	(segment
		(start 71.898764 -67.787266)
		(end 71.46036 -67.787266)
		(width 0.13208)
		(layer "F.Cu")
		(net "P12V_SSD2_CO_GATE")
	)
	(segment
		(start 72.075548 -68.479162)
		(end 72.075548 -67.96405)
		(width 0.13208)
		(layer "F.Cu")
		(net "P12V_SSD2_CO_GATE")
	)
	(segment
		(start 71.46036 -67.787266)
		(end 71.161148 -67.488054)
		(width 0.13208)
		(layer "F.Cu")
		(net "P12V_SSD2_CO_GATE")
	)
	(segment
		(start 72.075548 -67.96405)
		(end 71.898764 -67.787266)
		(width 0.13208)
		(layer "F.Cu")
		(net "P12V_SSD2_CO_GATE")
	)
	(segment
		(start 71.49846 -67.150742)
		(end 71.49846 -66.72199)
		(width 0.13208)
		(layer "F.Cu")
		(net "P12V_SSD2_CO_GATE")
	)
	(via
		(at 71.161148 -67.488054)
		(size 0.508)
		(drill 0.254)
		(layers "F.Cu" "B.Cu")
		(net "P12V_SSD2_CO_GATE")
	)
	(via
		(at 232.814622 -119.16156)
		(size 0.508)
		(drill 0.254)
		(layers "F.Cu" "B.Cu")
		(net "P12V_NIC3_CO_OV_FB")
	)
	(segment
		(start 128.88341 -160.327848)
		(end 128.88341 -161.569146)
		(width 0.254)
		(layer "F.Cu")
		(net "P12V_NIC2_CO_ISET")
	)
	(segment
		(start 128.88341 -159.967168)
		(end 128.594612 -159.67837)
		(width 0.254)
		(layer "F.Cu")
		(net "P12V_NIC2_CO_ISET")
	)
	(segment
		(start 128.88341 -161.569146)
		(end 128.848612 -161.603944)
		(width 0.254)
		(layer "F.Cu")
		(net "P12V_NIC2_CO_ISET")
	)
	(segment
		(start 128.594612 -159.67837)
		(end 128.594612 -159.531812)
		(width 0.254)
		(layer "F.Cu")
		(net "P12V_NIC2_CO_ISET")
	)
	(segment
		(start 128.594612 -159.531812)
		(end 128.594612 -158.705042)
		(width 0.254)
		(layer "F.Cu")
		(net "P12V_NIC2_CO_ISET")
	)
	(segment
		(start 128.88341 -160.327848)
		(end 128.88341 -159.967168)
		(width 0.254)
		(layer "F.Cu")
		(net "P12V_NIC2_CO_ISET")
	)
	(via
		(at 128.594612 -159.531812)
		(size 0.508)
		(drill 0.254)
		(layers "F.Cu" "B.Cu")
		(net "P12V_NIC2_CO_ISET")
	)
	(segment
		(start 111.271812 -113.568734)
		(end 111.276892 -113.563654)
		(width 0.254)
		(layer "F.Cu")
		(net "P12V_NIC1_CO_SS")
	)
	(segment
		(start 111.276892 -113.563654)
		(end 111.911892 -113.563654)
		(width 0.254)
		(layer "F.Cu")
		(net "P12V_NIC1_CO_SS")
	)
	(segment
		(start 109.814868 -112.385094)
		(end 110.993428 -113.563654)
		(width 0.254)
		(layer "F.Cu")
		(net "P12V_NIC1_CO_SS")
	)
	(segment
		(start 109.01299 -112.285526)
		(end 109.574584 -112.285526)
		(width 0.254)
		(layer "F.Cu")
		(net "P12V_NIC1_CO_SS")
	)
	(segment
		(start 110.993428 -113.563654)
		(end 111.266732 -113.563654)
		(width 0.254)
		(layer "F.Cu")
		(net "P12V_NIC1_CO_SS")
	)
	(segment
		(start 111.266732 -113.563654)
		(end 111.271812 -113.568734)
		(width 0.254)
		(layer "F.Cu")
		(net "P12V_NIC1_CO_SS")
	)
	(segment
		(start 109.574584 -112.285526)
		(end 109.814868 -112.385094)
		(width 0.254)
		(layer "F.Cu")
		(net "P12V_NIC1_CO_SS")
	)
	(via
		(at 111.271812 -113.568734)
		(size 0.508)
		(drill 0.254)
		(layers "F.Cu" "B.Cu")
		(net "P12V_NIC1_CO_SS")
	)
	(via
		(at 125.36932 -156.69387)
		(size 0.508)
		(drill 0.254)
		(layers "F.Cu" "B.Cu")
		(net "P12V_NIC2_CO_OV_FB")
	)
	(segment
		(start 11.983466 -160.968944)
		(end 11.732768 -161.219642)
		(width 0.254)
		(layer "F.Cu")
		(net "P12V_NIC0_CO_ISET_R")
	)
	(segment
		(start 11.732768 -161.219642)
		(end 11.732768 -161.603944)
		(width 0.254)
		(layer "F.Cu")
		(net "P12V_NIC0_CO_ISET_R")
	)
	(segment
		(start 11.983466 -160.327848)
		(end 11.983466 -160.968944)
		(width 0.254)
		(layer "F.Cu")
		(net "P12V_NIC0_CO_ISET_R")
	)
	(via
		(at 11.983466 -160.968944)
		(size 0.508)
		(drill 0.254)
		(layers "F.Cu" "B.Cu")
		(net "P12V_NIC0_CO_ISET_R")
	)
	(segment
		(start 125.419612 -160.965896)
		(end 125.419612 -161.603944)
		(width 0.254)
		(layer "F.Cu")
		(net "P12V_NIC2_CO_IMON_VR")
	)
	(segment
		(start 127.094488 -159.172148)
		(end 125.419612 -160.847024)
		(width 0.254)
		(layer "F.Cu")
		(net "P12V_NIC2_CO_IMON_VR")
	)
	(segment
		(start 125.419612 -160.847024)
		(end 125.419612 -160.965896)
		(width 0.254)
		(layer "F.Cu")
		(net "P12V_NIC2_CO_IMON_VR")
	)
	(segment
		(start 127.094488 -158.705042)
		(end 127.094488 -159.172148)
		(width 0.254)
		(layer "F.Cu")
		(net "P12V_NIC2_CO_IMON_VR")
	)
	(via
		(at 125.419612 -160.965896)
		(size 0.508)
		(drill 0.254)
		(layers "F.Cu" "B.Cu")
		(net "P12V_NIC2_CO_IMON_VR")
	)
	(via
		(at 10.251948 -155.079192)
		(size 0.508)
		(drill 0.254)
		(layers "F.Cu" "B.Cu")
		(net "P12V_NIC0_CO_AVIN_PD")
	)
	(segment
		(start 235.2929 -117.436392)
		(end 236.967776 -119.111268)
		(width 0.254)
		(layer "F.Cu")
		(net "P12V_NIC3_CO_IMON_VR")
	)
	(segment
		(start 234.825794 -117.436392)
		(end 235.2929 -117.436392)
		(width 0.254)
		(layer "F.Cu")
		(net "P12V_NIC3_CO_IMON_VR")
	)
	(segment
		(start 236.967776 -119.111268)
		(end 237.086648 -119.111268)
		(width 0.254)
		(layer "F.Cu")
		(net "P12V_NIC3_CO_IMON_VR")
	)
	(segment
		(start 237.086648 -119.111268)
		(end 237.724696 -119.111268)
		(width 0.254)
		(layer "F.Cu")
		(net "P12V_NIC3_CO_IMON_VR")
	)
	(via
		(at 237.086648 -119.111268)
		(size 0.508)
		(drill 0.254)
		(layers "F.Cu" "B.Cu")
		(net "P12V_NIC3_CO_IMON_VR")
	)
	(segment
		(start 126.816612 -160.968944)
		(end 126.811532 -160.963864)
		(width 0.254)
		(layer "F.Cu")
		(net "P12V_NIC2_CO_SS")
	)
	(segment
		(start 126.816612 -160.68548)
		(end 127.995172 -159.50692)
		(width 0.254)
		(layer "F.Cu")
		(net "P12V_NIC2_CO_SS")
	)
	(segment
		(start 126.816612 -161.603944)
		(end 126.816612 -160.968944)
		(width 0.254)
		(layer "F.Cu")
		(net "P12V_NIC2_CO_SS")
	)
	(segment
		(start 126.811532 -160.963864)
		(end 126.816612 -160.958784)
		(width 0.254)
		(layer "F.Cu")
		(net "P12V_NIC2_CO_SS")
	)
	(segment
		(start 127.995172 -159.50692)
		(end 128.09474 -159.266636)
		(width 0.254)
		(layer "F.Cu")
		(net "P12V_NIC2_CO_SS")
	)
	(segment
		(start 128.09474 -159.266636)
		(end 128.09474 -158.705042)
		(width 0.254)
		(layer "F.Cu")
		(net "P12V_NIC2_CO_SS")
	)
	(segment
		(start 126.816612 -160.958784)
		(end 126.816612 -160.68548)
		(width 0.254)
		(layer "F.Cu")
		(net "P12V_NIC2_CO_SS")
	)
	(via
		(at 126.811532 -160.963864)
		(size 0.508)
		(drill 0.254)
		(layers "F.Cu" "B.Cu")
		(net "P12V_NIC2_CO_SS")
	)
	(via
		(at 126.351792 -155.079192)
		(size 0.508)
		(drill 0.254)
		(layers "F.Cu" "B.Cu")
		(net "P12V_NIC2_CO_AVIN_PD")
	)
	(segment
		(start 127.832612 -161.219642)
		(end 128.08331 -160.968944)
		(width 0.254)
		(layer "F.Cu")
		(net "P12V_NIC2_CO_ISET_R")
	)
	(segment
		(start 128.08331 -160.968944)
		(end 128.08331 -160.327848)
		(width 0.254)
		(layer "F.Cu")
		(net "P12V_NIC2_CO_ISET_R")
	)
	(segment
		(start 127.832612 -161.603944)
		(end 127.832612 -161.219642)
		(width 0.254)
		(layer "F.Cu")
		(net "P12V_NIC2_CO_ISET_R")
	)
	(via
		(at 128.08331 -160.968944)
		(size 0.508)
		(drill 0.254)
		(layers "F.Cu" "B.Cu")
		(net "P12V_NIC2_CO_ISET_R")
	)
	(segment
		(start 237.022894 -114.666268)
		(end 237.724696 -114.666268)
		(width 0.13208)
		(layer "F.Cu")
		(net "P12V_NIC3_CO_TIMER")
	)
	(segment
		(start 237.022894 -114.666268)
		(end 236.570774 -114.666268)
		(width 0.13208)
		(layer "F.Cu")
		(net "P12V_NIC3_CO_TIMER")
	)
	(segment
		(start 235.800646 -115.436396)
		(end 234.825794 -115.436396)
		(width 0.13208)
		(layer "F.Cu")
		(net "P12V_NIC3_CO_TIMER")
	)
	(segment
		(start 236.570774 -114.666268)
		(end 235.800646 -115.436396)
		(width 0.13208)
		(layer "F.Cu")
		(net "P12V_NIC3_CO_TIMER")
	)
	(via
		(at 237.022894 -114.666268)
		(size 0.508)
		(drill 0.254)
		(layers "F.Cu" "B.Cu")
		(net "P12V_NIC3_CO_TIMER")
	)
	(segment
		(start 8.974328 -157.812994)
		(end 9.221724 -158.06039)
		(width 0.13208)
		(layer "F.Cu")
		(net "PWRGD_P12V_NIC0_CO")
	)
	(segment
		(start 9.477248 -157.804866)
		(end 10.094722 -157.804866)
		(width 0.13208)
		(layer "F.Cu")
		(net "PWRGD_P12V_NIC0_CO")
	)
	(segment
		(start 8.449818 -158.828994)
		(end 8.449818 -157.812994)
		(width 0.13208)
		(layer "F.Cu")
		(net "PWRGD_P12V_NIC0_CO")
	)
	(segment
		(start 8.449818 -157.812994)
		(end 8.974328 -157.812994)
		(width 0.13208)
		(layer "F.Cu")
		(net "PWRGD_P12V_NIC0_CO")
	)
	(segment
		(start 9.221724 -158.06039)
		(end 9.477248 -157.804866)
		(width 0.13208)
		(layer "F.Cu")
		(net "PWRGD_P12V_NIC0_CO")
	)
	(via
		(at 9.221724 -158.06039)
		(size 0.508)
		(drill 0.254)
		(layers "F.Cu" "B.Cu")
		(net "PWRGD_P12V_NIC0_CO")
	)
	(segment
		(start 237.089696 -117.714268)
		(end 237.724696 -117.714268)
		(width 0.254)
		(layer "F.Cu")
		(net "P12V_NIC3_CO_SS")
	)
	(segment
		(start 236.806232 -117.714268)
		(end 237.079536 -117.714268)
		(width 0.254)
		(layer "F.Cu")
		(net "P12V_NIC3_CO_SS")
	)
	(segment
		(start 237.084616 -117.719348)
		(end 237.089696 -117.714268)
		(width 0.254)
		(layer "F.Cu")
		(net "P12V_NIC3_CO_SS")
	)
	(segment
		(start 235.387388 -116.43614)
		(end 235.627672 -116.535708)
		(width 0.254)
		(layer "F.Cu")
		(net "P12V_NIC3_CO_SS")
	)
	(segment
		(start 237.079536 -117.714268)
		(end 237.084616 -117.719348)
		(width 0.254)
		(layer "F.Cu")
		(net "P12V_NIC3_CO_SS")
	)
	(segment
		(start 234.825794 -116.43614)
		(end 235.387388 -116.43614)
		(width 0.254)
		(layer "F.Cu")
		(net "P12V_NIC3_CO_SS")
	)
	(segment
		(start 235.627672 -116.535708)
		(end 236.806232 -117.714268)
		(width 0.254)
		(layer "F.Cu")
		(net "P12V_NIC3_CO_SS")
	)
	(via
		(at 237.084616 -117.719348)
		(size 0.508)
		(drill 0.254)
		(layers "F.Cu" "B.Cu")
		(net "P12V_NIC3_CO_SS")
	)
	(segment
		(start 332.507844 -222.38716)
		(end 332.001368 -222.893636)
		(width 0.13208)
		(layer "F.Cu")
		(net "PEX1_SYS_ERR_FPGA")
	)
	(segment
		(start 334.09382 -222.38716)
		(end 332.507844 -222.38716)
		(width 0.13208)
		(layer "F.Cu")
		(net "PEX1_SYS_ERR_FPGA")
	)
	(segment
		(start 131.953 -261.207758)
		(end 139.228576 -261.207758)
		(width 0.13208)
		(layer "F.Cu")
		(net "PEX1_SYS_ERR_FPGA")
	)
	(segment
		(start 332.001368 -222.893636)
		(end 331.65796 -222.893636)
		(width 0.13208)
		(layer "F.Cu")
		(net "PEX1_SYS_ERR_FPGA")
	)
	(via
		(at 131.953 -261.207758)
		(size 0.508)
		(drill 0.254)
		(layers "F.Cu" "B.Cu")
		(net "PEX1_SYS_ERR_FPGA")
	)
	(via
		(at 129.45491 -209.426048)
		(size 0.508)
		(drill 0.254)
		(layers "F.Cu" "B.Cu")
		(net "PEX1_SYS_ERR_FPGA")
	)
	(via
		(at 331.65796 -222.893636)
		(size 0.508)
		(drill 0.254)
		(layers "F.Cu" "B.Cu")
		(net "PEX1_SYS_ERR_FPGA")
	)
	(segment
		(start 131.93141 -245.331996)
		(end 128.255522 -241.656108)
		(width 0.15494)
		(layer "In5.Cu")
		(net "PEX1_SYS_ERR_FPGA")
	)
	(segment
		(start 129.2606 -209.620358)
		(end 129.45491 -209.426048)
		(width 0.15494)
		(layer "In5.Cu")
		(net "PEX1_SYS_ERR_FPGA")
	)
	(segment
		(start 131.93141 -261.186168)
		(end 131.93141 -245.331996)
		(width 0.15494)
		(layer "In5.Cu")
		(net "PEX1_SYS_ERR_FPGA")
	)
	(segment
		(start 129.2606 -219.802202)
		(end 129.2606 -209.620358)
		(width 0.15494)
		(layer "In5.Cu")
		(net "PEX1_SYS_ERR_FPGA")
	)
	(segment
		(start 131.953 -261.207758)
		(end 131.93141 -261.186168)
		(width 0.15494)
		(layer "In5.Cu")
		(net "PEX1_SYS_ERR_FPGA")
	)
	(segment
		(start 128.255522 -241.656108)
		(end 128.255522 -220.80728)
		(width 0.15494)
		(layer "In5.Cu")
		(net "PEX1_SYS_ERR_FPGA")
	)
	(segment
		(start 128.255522 -220.80728)
		(end 129.2606 -219.802202)
		(width 0.15494)
		(layer "In5.Cu")
		(net "PEX1_SYS_ERR_FPGA")
	)
	(segment
		(start 158.965646 -209.7532)
		(end 147.189698 -209.7532)
		(width 0.15494)
		(layer "In13.Cu")
		(net "PEX1_SYS_ERR_FPGA")
	)
	(segment
		(start 137.287 -209.4738)
		(end 134.112762 -209.4738)
		(width 0.15494)
		(layer "In13.Cu")
		(net "PEX1_SYS_ERR_FPGA")
	)
	(segment
		(start 163.747196 -205.007464)
		(end 163.718494 -205.007464)
		(width 0.15494)
		(layer "In13.Cu")
		(net "PEX1_SYS_ERR_FPGA")
	)
	(segment
		(start 145.741898 -208.3054)
		(end 143.5862 -208.3054)
		(width 0.15494)
		(layer "In13.Cu")
		(net "PEX1_SYS_ERR_FPGA")
	)
	(segment
		(start 325.348092 -217.816176)
		(end 322.334128 -216.565988)
		(width 0.15494)
		(layer "In13.Cu")
		(net "PEX1_SYS_ERR_FPGA")
	)
	(segment
		(start 132.505196 -210.058)
		(end 131.819396 -209.3722)
		(width 0.15494)
		(layer "In13.Cu")
		(net "PEX1_SYS_ERR_FPGA")
	)
	(segment
		(start 129.508758 -209.3722)
		(end 129.45491 -209.426048)
		(width 0.15494)
		(layer "In13.Cu")
		(net "PEX1_SYS_ERR_FPGA")
	)
	(segment
		(start 297.055286 -213.39937)
		(end 297.05427 -213.401656)
		(width 0.15494)
		(layer "In13.Cu")
		(net "PEX1_SYS_ERR_FPGA")
	)
	(segment
		(start 222.81769 -201.679302)
		(end 221.55531 -201.679302)
		(width 0.15494)
		(layer "In13.Cu")
		(net "PEX1_SYS_ERR_FPGA")
	)
	(segment
		(start 278.869902 -216.252044)
		(end 269.119858 -206.502)
		(width 0.15494)
		(layer "In13.Cu")
		(net "PEX1_SYS_ERR_FPGA")
	)
	(segment
		(start 294.203882 -216.252044)
		(end 278.869902 -216.252044)
		(width 0.15494)
		(layer "In13.Cu")
		(net "PEX1_SYS_ERR_FPGA")
	)
	(segment
		(start 137.58926 -209.77606)
		(end 137.287 -209.4738)
		(width 0.15494)
		(layer "In13.Cu")
		(net "PEX1_SYS_ERR_FPGA")
	)
	(segment
		(start 142.11554 -209.77606)
		(end 137.58926 -209.77606)
		(width 0.15494)
		(layer "In13.Cu")
		(net "PEX1_SYS_ERR_FPGA")
	)
	(segment
		(start 260.00202 -205.403958)
		(end 257.315462 -202.7174)
		(width 0.15494)
		(layer "In13.Cu")
		(net "PEX1_SYS_ERR_FPGA")
	)
	(segment
		(start 134.112762 -209.4738)
		(end 133.528562 -210.058)
		(width 0.15494)
		(layer "In13.Cu")
		(net "PEX1_SYS_ERR_FPGA")
	)
	(segment
		(start 211.582 -201.803)
		(end 207.137 -201.803)
		(width 0.15494)
		(layer "In13.Cu")
		(net "PEX1_SYS_ERR_FPGA")
	)
	(segment
		(start 326.934576 -217.816176)
		(end 325.348092 -217.816176)
		(width 0.15494)
		(layer "In13.Cu")
		(net "PEX1_SYS_ERR_FPGA")
	)
	(segment
		(start 164.368734 -204.385926)
		(end 163.747196 -205.007464)
		(width 0.15494)
		(layer "In13.Cu")
		(net "PEX1_SYS_ERR_FPGA")
	)
	(segment
		(start 321.576954 -216.565988)
		(end 318.410336 -213.39937)
		(width 0.15494)
		(layer "In13.Cu")
		(net "PEX1_SYS_ERR_FPGA")
	)
	(segment
		(start 327.829926 -219.350082)
		(end 327.829926 -218.711526)
		(width 0.15494)
		(layer "In13.Cu")
		(net "PEX1_SYS_ERR_FPGA")
	)
	(segment
		(start 264.821924 -206.502)
		(end 263.723882 -205.403958)
		(width 0.15494)
		(layer "In13.Cu")
		(net "PEX1_SYS_ERR_FPGA")
	)
	(segment
		(start 163.718494 -205.007464)
		(end 159.110426 -209.615532)
		(width 0.15494)
		(layer "In13.Cu")
		(net "PEX1_SYS_ERR_FPGA")
	)
	(segment
		(start 228.76383 -202.096624)
		(end 223.235012 -202.096624)
		(width 0.15494)
		(layer "In13.Cu")
		(net "PEX1_SYS_ERR_FPGA")
	)
	(segment
		(start 247.334024 -201.597768)
		(end 244.897656 -199.1614)
		(width 0.15494)
		(layer "In13.Cu")
		(net "PEX1_SYS_ERR_FPGA")
	)
	(segment
		(start 143.5862 -208.3054)
		(end 142.11554 -209.77606)
		(width 0.15494)
		(layer "In13.Cu")
		(net "PEX1_SYS_ERR_FPGA")
	)
	(segment
		(start 220.542612 -202.692)
		(end 217.3478 -202.692)
		(width 0.15494)
		(layer "In13.Cu")
		(net "PEX1_SYS_ERR_FPGA")
	)
	(segment
		(start 327.829926 -218.711526)
		(end 326.934576 -217.816176)
		(width 0.15494)
		(layer "In13.Cu")
		(net "PEX1_SYS_ERR_FPGA")
	)
	(segment
		(start 244.897656 -199.1614)
		(end 243.1796 -199.1614)
		(width 0.15494)
		(layer "In13.Cu")
		(net "PEX1_SYS_ERR_FPGA")
	)
	(segment
		(start 216.122504 -203.917296)
		(end 213.696296 -203.917296)
		(width 0.15494)
		(layer "In13.Cu")
		(net "PEX1_SYS_ERR_FPGA")
	)
	(segment
		(start 322.334128 -216.565988)
		(end 321.576954 -216.565988)
		(width 0.15494)
		(layer "In13.Cu")
		(net "PEX1_SYS_ERR_FPGA")
	)
	(segment
		(start 133.528562 -210.058)
		(end 132.505196 -210.058)
		(width 0.15494)
		(layer "In13.Cu")
		(net "PEX1_SYS_ERR_FPGA")
	)
	(segment
		(start 331.65796 -222.893636)
		(end 331.172312 -222.692468)
		(width 0.15494)
		(layer "In13.Cu")
		(net "PEX1_SYS_ERR_FPGA")
	)
	(segment
		(start 217.3478 -202.692)
		(end 216.122504 -203.917296)
		(width 0.15494)
		(layer "In13.Cu")
		(net "PEX1_SYS_ERR_FPGA")
	)
	(segment
		(start 204.554074 -204.385926)
		(end 164.368734 -204.385926)
		(width 0.15494)
		(layer "In13.Cu")
		(net "PEX1_SYS_ERR_FPGA")
	)
	(segment
		(start 230.528114 -200.33234)
		(end 228.76383 -202.096624)
		(width 0.15494)
		(layer "In13.Cu")
		(net "PEX1_SYS_ERR_FPGA")
	)
	(segment
		(start 236.167168 -200.33234)
		(end 230.528114 -200.33234)
		(width 0.15494)
		(layer "In13.Cu")
		(net "PEX1_SYS_ERR_FPGA")
	)
	(segment
		(start 254.351536 -202.7174)
		(end 253.231904 -201.597768)
		(width 0.15494)
		(layer "In13.Cu")
		(net "PEX1_SYS_ERR_FPGA")
	)
	(segment
		(start 221.55531 -201.679302)
		(end 220.542612 -202.692)
		(width 0.15494)
		(layer "In13.Cu")
		(net "PEX1_SYS_ERR_FPGA")
	)
	(segment
		(start 242.720876 -198.702676)
		(end 237.796832 -198.702676)
		(width 0.15494)
		(layer "In13.Cu")
		(net "PEX1_SYS_ERR_FPGA")
	)
	(segment
		(start 269.119858 -206.502)
		(end 264.821924 -206.502)
		(width 0.15494)
		(layer "In13.Cu")
		(net "PEX1_SYS_ERR_FPGA")
	)
	(segment
		(start 243.1796 -199.1614)
		(end 242.720876 -198.702676)
		(width 0.15494)
		(layer "In13.Cu")
		(net "PEX1_SYS_ERR_FPGA")
	)
	(segment
		(start 237.796832 -198.702676)
		(end 236.167168 -200.33234)
		(width 0.15494)
		(layer "In13.Cu")
		(net "PEX1_SYS_ERR_FPGA")
	)
	(segment
		(start 159.103314 -209.615532)
		(end 158.965646 -209.7532)
		(width 0.15494)
		(layer "In13.Cu")
		(net "PEX1_SYS_ERR_FPGA")
	)
	(segment
		(start 223.235012 -202.096624)
		(end 222.81769 -201.679302)
		(width 0.15494)
		(layer "In13.Cu")
		(net "PEX1_SYS_ERR_FPGA")
	)
	(segment
		(start 213.696296 -203.917296)
		(end 211.582 -201.803)
		(width 0.15494)
		(layer "In13.Cu")
		(net "PEX1_SYS_ERR_FPGA")
	)
	(segment
		(start 159.110426 -209.615532)
		(end 159.103314 -209.615532)
		(width 0.15494)
		(layer "In13.Cu")
		(net "PEX1_SYS_ERR_FPGA")
	)
	(segment
		(start 147.189698 -209.7532)
		(end 145.741898 -208.3054)
		(width 0.15494)
		(layer "In13.Cu")
		(net "PEX1_SYS_ERR_FPGA")
	)
	(segment
		(start 131.819396 -209.3722)
		(end 129.508758 -209.3722)
		(width 0.15494)
		(layer "In13.Cu")
		(net "PEX1_SYS_ERR_FPGA")
	)
	(segment
		(start 318.410336 -213.39937)
		(end 297.055286 -213.39937)
		(width 0.15494)
		(layer "In13.Cu")
		(net "PEX1_SYS_ERR_FPGA")
	)
	(segment
		(start 297.05427 -213.401656)
		(end 294.203882 -216.252044)
		(width 0.15494)
		(layer "In13.Cu")
		(net "PEX1_SYS_ERR_FPGA")
	)
	(segment
		(start 257.315462 -202.7174)
		(end 254.351536 -202.7174)
		(width 0.15494)
		(layer "In13.Cu")
		(net "PEX1_SYS_ERR_FPGA")
	)
	(segment
		(start 331.172312 -222.692468)
		(end 327.829926 -219.350082)
		(width 0.15494)
		(layer "In13.Cu")
		(net "PEX1_SYS_ERR_FPGA")
	)
	(segment
		(start 253.231904 -201.597768)
		(end 247.334024 -201.597768)
		(width 0.15494)
		(layer "In13.Cu")
		(net "PEX1_SYS_ERR_FPGA")
	)
	(segment
		(start 263.723882 -205.403958)
		(end 260.00202 -205.403958)
		(width 0.15494)
		(layer "In13.Cu")
		(net "PEX1_SYS_ERR_FPGA")
	)
	(segment
		(start 207.137 -201.803)
		(end 204.554074 -204.385926)
		(width 0.15494)
		(layer "In13.Cu")
		(net "PEX1_SYS_ERR_FPGA")
	)
	(segment
		(start 237.340394 -116.698268)
		(end 237.724696 -116.698268)
		(width 0.254)
		(layer "F.Cu")
		(net "P12V_NIC3_CO_ISET_R")
	)
	(segment
		(start 237.089696 -116.44757)
		(end 237.340394 -116.698268)
		(width 0.254)
		(layer "F.Cu")
		(net "P12V_NIC3_CO_ISET_R")
	)
	(segment
		(start 236.4486 -116.44757)
		(end 237.089696 -116.44757)
		(width 0.254)
		(layer "F.Cu")
		(net "P12V_NIC3_CO_ISET_R")
	)
	(via
		(at 237.089696 -116.44757)
		(size 0.508)
		(drill 0.254)
		(layers "F.Cu" "B.Cu")
		(net "P12V_NIC3_CO_ISET_R")
	)
	(segment
		(start 111.877094 -111.496856)
		(end 110.635796 -111.496856)
		(width 0.254)
		(layer "F.Cu")
		(net "P12V_NIC1_CO_ISET")
	)
	(segment
		(start 111.911892 -111.531654)
		(end 111.877094 -111.496856)
		(width 0.254)
		(layer "F.Cu")
		(net "P12V_NIC1_CO_ISET")
	)
	(segment
		(start 110.292896 -111.496856)
		(end 110.635796 -111.496856)
		(width 0.254)
		(layer "F.Cu")
		(net "P12V_NIC1_CO_ISET")
	)
	(segment
		(start 109.01299 -111.785654)
		(end 109.83976 -111.785654)
		(width 0.254)
		(layer "F.Cu")
		(net "P12V_NIC1_CO_ISET")
	)
	(segment
		(start 110.004098 -111.785654)
		(end 110.292896 -111.496856)
		(width 0.254)
		(layer "F.Cu")
		(net "P12V_NIC1_CO_ISET")
	)
	(segment
		(start 109.83976 -111.785654)
		(end 110.004098 -111.785654)
		(width 0.254)
		(layer "F.Cu")
		(net "P12V_NIC1_CO_ISET")
	)
	(via
		(at 109.83976 -111.785654)
		(size 0.508)
		(drill 0.254)
		(layers "F.Cu" "B.Cu")
		(net "P12V_NIC1_CO_ISET")
	)
	(segment
		(start 12.676886 -160.327594)
		(end 12.67714 -160.327848)
		(width 0.254)
		(layer "F.Cu")
		(net "P12V_NIC0_CO_ISET")
	)
	(segment
		(start 12.494768 -158.705042)
		(end 12.494768 -159.531812)
		(width 0.254)
		(layer "F.Cu")
		(net "P12V_NIC0_CO_ISET")
	)
	(segment
		(start 12.494768 -159.887666)
		(end 12.676886 -160.327594)
		(width 0.254)
		(layer "F.Cu")
		(net "P12V_NIC0_CO_ISET")
	)
	(segment
		(start 12.783566 -160.327848)
		(end 12.783566 -161.569146)
		(width 0.254)
		(layer "F.Cu")
		(net "P12V_NIC0_CO_ISET")
	)
	(segment
		(start 12.67714 -160.327848)
		(end 12.783566 -160.327848)
		(width 0.254)
		(layer "F.Cu")
		(net "P12V_NIC0_CO_ISET")
	)
	(segment
		(start 12.494768 -159.531812)
		(end 12.494768 -159.887666)
		(width 0.254)
		(layer "F.Cu")
		(net "P12V_NIC0_CO_ISET")
	)
	(segment
		(start 12.783566 -161.569146)
		(end 12.748768 -161.603944)
		(width 0.254)
		(layer "F.Cu")
		(net "P12V_NIC0_CO_ISET")
	)
	(via
		(at 12.494768 -159.531812)
		(size 0.508)
		(drill 0.254)
		(layers "F.Cu" "B.Cu")
		(net "P12V_NIC0_CO_ISET")
	)
	(segment
		(start 111.911892 -107.848654)
		(end 111.911892 -108.737654)
		(width 0.13208)
		(layer "F.Cu")
		(net "P12V_NIC1_CO_EN")
	)
	(segment
		(start 108.987844 -109.785658)
		(end 109.51337 -109.785658)
		(width 0.13208)
		(layer "F.Cu")
		(net "P12V_NIC1_CO_EN")
	)
	(segment
		(start 109.51337 -109.785658)
		(end 109.79658 -109.502448)
		(width 0.13208)
		(layer "F.Cu")
		(net "P12V_NIC1_CO_EN")
	)
	(segment
		(start 110.721394 -109.502448)
		(end 110.8456 -109.626654)
		(width 0.13208)
		(layer "F.Cu")
		(net "P12V_NIC1_CO_EN")
	)
	(segment
		(start 109.79658 -109.502448)
		(end 110.721394 -109.502448)
		(width 0.13208)
		(layer "F.Cu")
		(net "P12V_NIC1_CO_EN")
	)
	(segment
		(start 110.8456 -109.626654)
		(end 111.911892 -109.626654)
		(width 0.13208)
		(layer "F.Cu")
		(net "P12V_NIC1_CO_EN")
	)
	(segment
		(start 111.911892 -108.737654)
		(end 111.911892 -109.626654)
		(width 0.13208)
		(layer "F.Cu")
		(net "P12V_NIC1_CO_EN")
	)
	(via
		(at 109.79658 -109.502448)
		(size 0.508)
		(drill 0.254)
		(layers "F.Cu" "B.Cu")
		(net "P12V_NIC1_CO_EN")
	)
	(via
		(at 107.001818 -115.010946)
		(size 0.508)
		(drill 0.254)
		(layers "F.Cu" "B.Cu")
		(net "P12V_NIC1_CO_OV_FB")
	)
	(segment
		(start 110.75797 -110.515654)
		(end 111.21009 -110.515654)
		(width 0.13208)
		(layer "F.Cu")
		(net "P12V_NIC1_CO_TIMER")
	)
	(segment
		(start 109.987842 -111.285782)
		(end 110.75797 -110.515654)
		(width 0.13208)
		(layer "F.Cu")
		(net "P12V_NIC1_CO_TIMER")
	)
	(segment
		(start 111.21009 -110.515654)
		(end 111.911892 -110.515654)
		(width 0.13208)
		(layer "F.Cu")
		(net "P12V_NIC1_CO_TIMER")
	)
	(segment
		(start 109.01299 -111.285782)
		(end 109.987842 -111.285782)
		(width 0.13208)
		(layer "F.Cu")
		(net "P12V_NIC1_CO_TIMER")
	)
	(via
		(at 111.21009 -110.515654)
		(size 0.508)
		(drill 0.254)
		(layers "F.Cu" "B.Cu")
		(net "P12V_NIC1_CO_TIMER")
	)
	(segment
		(start 109.480096 -113.285778)
		(end 111.154972 -114.960654)
		(width 0.254)
		(layer "F.Cu")
		(net "P12V_NIC1_CO_IMON_VR")
	)
	(segment
		(start 109.01299 -113.285778)
		(end 109.480096 -113.285778)
		(width 0.254)
		(layer "F.Cu")
		(net "P12V_NIC1_CO_IMON_VR")
	)
	(segment
		(start 111.273844 -114.960654)
		(end 111.911892 -114.960654)
		(width 0.254)
		(layer "F.Cu")
		(net "P12V_NIC1_CO_IMON_VR")
	)
	(segment
		(start 111.154972 -114.960654)
		(end 111.273844 -114.960654)
		(width 0.254)
		(layer "F.Cu")
		(net "P12V_NIC1_CO_IMON_VR")
	)
	(via
		(at 111.273844 -114.960654)
		(size 0.508)
		(drill 0.254)
		(layers "F.Cu" "B.Cu")
		(net "P12V_NIC1_CO_IMON_VR")
	)
	(segment
		(start 14.777974 -160.413446)
		(end 14.777974 -159.488632)
		(width 0.13208)
		(layer "F.Cu")
		(net "P12V_NIC0_CO_EN")
	)
	(segment
		(start 14.653768 -160.537652)
		(end 14.777974 -160.413446)
		(width 0.13208)
		(layer "F.Cu")
		(net "P12V_NIC0_CO_EN")
	)
	(segment
		(start 14.494764 -159.205422)
		(end 14.494764 -158.679896)
		(width 0.13208)
		(layer "F.Cu")
		(net "P12V_NIC0_CO_EN")
	)
	(segment
		(start 15.542768 -161.603944)
		(end 14.653768 -161.603944)
		(width 0.13208)
		(layer "F.Cu")
		(net "P12V_NIC0_CO_EN")
	)
	(segment
		(start 14.777974 -159.488632)
		(end 14.494764 -159.205422)
		(width 0.13208)
		(layer "F.Cu")
		(net "P12V_NIC0_CO_EN")
	)
	(segment
		(start 14.653768 -161.603944)
		(end 14.653768 -160.537652)
		(width 0.13208)
		(layer "F.Cu")
		(net "P12V_NIC0_CO_EN")
	)
	(segment
		(start 16.431768 -161.603944)
		(end 15.542768 -161.603944)
		(width 0.13208)
		(layer "F.Cu")
		(net "P12V_NIC0_CO_EN")
	)
	(via
		(at 14.777974 -159.488632)
		(size 0.508)
		(drill 0.254)
		(layers "F.Cu" "B.Cu")
		(net "P12V_NIC0_CO_EN")
	)
	(via
		(at 358.946958 -275.411184)
		(size 0.508)
		(drill 0.254)
		(layers "F.Cu" "B.Cu")
		(net "SW_P12V_P0V8_PEX3_FLT")
	)
	(via
		(at 359.66527 -277.644352)
		(size 0.508)
		(drill 0.254)
		(layers "F.Cu" "B.Cu")
		(net "SW_P12V_P0V8_PEX3_FLT")
	)
	(via
		(at 359.66527 -276.933152)
		(size 0.508)
		(drill 0.254)
		(layers "F.Cu" "B.Cu")
		(net "SW_P12V_P0V8_PEX3_FLT")
	)
	(via
		(at 353.743514 -275.392896)
		(size 0.508)
		(drill 0.254)
		(layers "F.Cu" "B.Cu")
		(net "SW_P12V_P0V8_PEX3_FLT")
	)
	(via
		(at 360.396536 -282.091638)
		(size 0.508)
		(drill 0.254)
		(layers "F.Cu" "B.Cu")
		(net "SW_P12V_P0V8_PEX3_FLT")
	)
	(via
		(at 357.041958 -276.046184)
		(size 0.508)
		(drill 0.254)
		(layers "F.Cu" "B.Cu")
		(net "SW_P12V_P0V8_PEX3_FLT")
	)
	(via
		(at 358.311958 -275.411184)
		(size 0.508)
		(drill 0.254)
		(layers "F.Cu" "B.Cu")
		(net "SW_P12V_P0V8_PEX3_FLT")
	)
	(via
		(at 360.371136 -281.431238)
		(size 0.508)
		(drill 0.254)
		(layers "F.Cu" "B.Cu")
		(net "SW_P12V_P0V8_PEX3_FLT")
	)
	(via
		(at 353.108514 -275.392896)
		(size 0.508)
		(drill 0.254)
		(layers "F.Cu" "B.Cu")
		(net "SW_P12V_P0V8_PEX3_FLT")
	)
	(via
		(at 353.743514 -276.662896)
		(size 0.508)
		(drill 0.254)
		(layers "F.Cu" "B.Cu")
		(net "SW_P12V_P0V8_PEX3_FLT")
	)
	(via
		(at 359.304336 -282.167838)
		(size 0.508)
		(drill 0.254)
		(layers "F.Cu" "B.Cu")
		(net "SW_P12V_P0V8_PEX3_FLT")
	)
	(via
		(at 360.96448 -284.175454)
		(size 0.508)
		(drill 0.254)
		(layers "F.Cu" "B.Cu")
		(net "SW_P12V_P0V8_PEX3_FLT")
	)
	(via
		(at 352.803968 -284.175454)
		(size 0.508)
		(drill 0.254)
		(layers "F.Cu" "B.Cu")
		(net "SW_P12V_P0V8_PEX3_FLT")
	)
	(via
		(at 351.143824 -282.904438)
		(size 0.508)
		(drill 0.254)
		(layers "F.Cu" "B.Cu")
		(net "SW_P12V_P0V8_PEX3_FLT")
	)
	(via
		(at 351.677224 -281.786838)
		(size 0.508)
		(drill 0.254)
		(layers "F.Cu" "B.Cu")
		(net "SW_P12V_P0V8_PEX3_FLT")
	)
	(via
		(at 357.676958 -276.046184)
		(size 0.508)
		(drill 0.254)
		(layers "F.Cu" "B.Cu")
		(net "SW_P12V_P0V8_PEX3_FLT")
	)
	(via
		(at 351.143824 -282.167838)
		(size 0.508)
		(drill 0.254)
		(layers "F.Cu" "B.Cu")
		(net "SW_P12V_P0V8_PEX3_FLT")
	)
	(via
		(at 353.108514 -276.027896)
		(size 0.508)
		(drill 0.254)
		(layers "F.Cu" "B.Cu")
		(net "SW_P12V_P0V8_PEX3_FLT")
	)
	(via
		(at 359.304336 -282.904438)
		(size 0.508)
		(drill 0.254)
		(layers "F.Cu" "B.Cu")
		(net "SW_P12V_P0V8_PEX3_FLT")
	)
	(via
		(at 357.041958 -275.411184)
		(size 0.508)
		(drill 0.254)
		(layers "F.Cu" "B.Cu")
		(net "SW_P12V_P0V8_PEX3_FLT")
	)
	(via
		(at 353.108514 -274.757896)
		(size 0.508)
		(drill 0.254)
		(layers "F.Cu" "B.Cu")
		(net "SW_P12V_P0V8_PEX3_FLT")
	)
	(via
		(at 359.304336 -281.431238)
		(size 0.508)
		(drill 0.254)
		(layers "F.Cu" "B.Cu")
		(net "SW_P12V_P0V8_PEX3_FLT")
	)
	(via
		(at 360.96448 -283.489654)
		(size 0.508)
		(drill 0.254)
		(layers "F.Cu" "B.Cu")
		(net "SW_P12V_P0V8_PEX3_FLT")
	)
	(via
		(at 358.311958 -276.046184)
		(size 0.508)
		(drill 0.254)
		(layers "F.Cu" "B.Cu")
		(net "SW_P12V_P0V8_PEX3_FLT")
	)
	(via
		(at 359.863136 -282.548838)
		(size 0.508)
		(drill 0.254)
		(layers "F.Cu" "B.Cu")
		(net "SW_P12V_P0V8_PEX3_FLT")
	)
	(via
		(at 361.688126 -282.866592)
		(size 0.508)
		(drill 0.254)
		(layers "F.Cu" "B.Cu")
		(net "SW_P12V_P0V8_PEX3_FLT")
	)
	(via
		(at 354.162614 -282.866592)
		(size 0.508)
		(drill 0.254)
		(layers "F.Cu" "B.Cu")
		(net "SW_P12V_P0V8_PEX3_FLT")
	)
	(via
		(at 351.143824 -281.431238)
		(size 0.508)
		(drill 0.254)
		(layers "F.Cu" "B.Cu")
		(net "SW_P12V_P0V8_PEX3_FLT")
	)
	(via
		(at 353.743514 -274.757896)
		(size 0.508)
		(drill 0.254)
		(layers "F.Cu" "B.Cu")
		(net "SW_P12V_P0V8_PEX3_FLT")
	)
	(via
		(at 352.666554 -277.634192)
		(size 0.508)
		(drill 0.254)
		(layers "F.Cu" "B.Cu")
		(net "SW_P12V_P0V8_PEX3_FLT")
	)
	(via
		(at 351.702624 -282.548838)
		(size 0.508)
		(drill 0.254)
		(layers "F.Cu" "B.Cu")
		(net "SW_P12V_P0V8_PEX3_FLT")
	)
	(via
		(at 352.236024 -282.091638)
		(size 0.508)
		(drill 0.254)
		(layers "F.Cu" "B.Cu")
		(net "SW_P12V_P0V8_PEX3_FLT")
	)
	(via
		(at 358.946958 -276.046184)
		(size 0.508)
		(drill 0.254)
		(layers "F.Cu" "B.Cu")
		(net "SW_P12V_P0V8_PEX3_FLT")
	)
	(via
		(at 357.676958 -275.411184)
		(size 0.508)
		(drill 0.254)
		(layers "F.Cu" "B.Cu")
		(net "SW_P12V_P0V8_PEX3_FLT")
	)
	(via
		(at 352.803968 -283.489654)
		(size 0.508)
		(drill 0.254)
		(layers "F.Cu" "B.Cu")
		(net "SW_P12V_P0V8_PEX3_FLT")
	)
	(via
		(at 359.837736 -281.786838)
		(size 0.508)
		(drill 0.254)
		(layers "F.Cu" "B.Cu")
		(net "SW_P12V_P0V8_PEX3_FLT")
	)
	(via
		(at 360.595926 -282.866592)
		(size 0.508)
		(drill 0.254)
		(layers "F.Cu" "B.Cu")
		(net "SW_P12V_P0V8_PEX3_FLT")
	)
	(via
		(at 352.210624 -281.431238)
		(size 0.508)
		(drill 0.254)
		(layers "F.Cu" "B.Cu")
		(net "SW_P12V_P0V8_PEX3_FLT")
	)
	(via
		(at 362.323126 -282.866592)
		(size 0.508)
		(drill 0.254)
		(layers "F.Cu" "B.Cu")
		(net "SW_P12V_P0V8_PEX3_FLT")
	)
	(via
		(at 359.581958 -276.046184)
		(size 0.508)
		(drill 0.254)
		(layers "F.Cu" "B.Cu")
		(net "SW_P12V_P0V8_PEX3_FLT")
	)
	(via
		(at 352.684842 -276.88286)
		(size 0.508)
		(drill 0.254)
		(layers "F.Cu" "B.Cu")
		(net "SW_P12V_P0V8_PEX3_FLT")
	)
	(via
		(at 353.589844 -277.556722)
		(size 0.508)
		(drill 0.254)
		(layers "F.Cu" "B.Cu")
		(net "SW_P12V_P0V8_PEX3_FLT")
	)
	(via
		(at 353.743514 -276.027896)
		(size 0.508)
		(drill 0.254)
		(layers "F.Cu" "B.Cu")
		(net "SW_P12V_P0V8_PEX3_FLT")
	)
	(via
		(at 352.435414 -282.866592)
		(size 0.508)
		(drill 0.254)
		(layers "F.Cu" "B.Cu")
		(net "SW_P12V_P0V8_PEX3_FLT")
	)
	(via
		(at 353.527614 -282.866592)
		(size 0.508)
		(drill 0.254)
		(layers "F.Cu" "B.Cu")
		(net "SW_P12V_P0V8_PEX3_FLT")
	)
	(via
		(at 359.581958 -275.411184)
		(size 0.508)
		(drill 0.254)
		(layers "F.Cu" "B.Cu")
		(net "SW_P12V_P0V8_PEX3_FLT")
	)
	(segment
		(start 129.864612 -160.902142)
		(end 129.864612 -161.603944)
		(width 0.13208)
		(layer "F.Cu")
		(net "P12V_NIC2_CO_TIMER")
	)
	(segment
		(start 129.864612 -160.450022)
		(end 129.864612 -160.902142)
		(width 0.13208)
		(layer "F.Cu")
		(net "P12V_NIC2_CO_TIMER")
	)
	(segment
		(start 129.094484 -159.679894)
		(end 129.864612 -160.450022)
		(width 0.13208)
		(layer "F.Cu")
		(net "P12V_NIC2_CO_TIMER")
	)
	(segment
		(start 129.094484 -158.705042)
		(end 129.094484 -159.679894)
		(width 0.13208)
		(layer "F.Cu")
		(net "P12V_NIC2_CO_TIMER")
	)
	(via
		(at 129.864612 -160.902142)
		(size 0.508)
		(drill 0.254)
		(layers "F.Cu" "B.Cu")
		(net "P12V_NIC2_CO_TIMER")
	)
	(segment
		(start 108.120942 -115.306094)
		(end 108.120942 -115.830604)
		(width 0.13208)
		(layer "F.Cu")
		(net "PWRGD_P12V_NIC1_CO")
	)
	(segment
		(start 108.112814 -114.1857)
		(end 108.112814 -114.803174)
		(width 0.13208)
		(layer "F.Cu")
		(net "PWRGD_P12V_NIC1_CO")
	)
	(segment
		(start 109.136942 -115.830604)
		(end 108.120942 -115.830604)
		(width 0.13208)
		(layer "F.Cu")
		(net "PWRGD_P12V_NIC1_CO")
	)
	(segment
		(start 108.368338 -115.058698)
		(end 108.120942 -115.306094)
		(width 0.13208)
		(layer "F.Cu")
		(net "PWRGD_P12V_NIC1_CO")
	)
	(segment
		(start 108.112814 -114.803174)
		(end 108.368338 -115.058698)
		(width 0.13208)
		(layer "F.Cu")
		(net "PWRGD_P12V_NIC1_CO")
	)
	(via
		(at 108.368338 -115.058698)
		(size 0.508)
		(drill 0.254)
		(layers "F.Cu" "B.Cu")
		(net "PWRGD_P12V_NIC1_CO")
	)
	(segment
		(start 235.965746 -119.546878)
		(end 235.965746 -119.981218)
		(width 0.254)
		(layer "F.Cu")
		(net "P12V_NIC3_CO_FLTB")
	)
	(segment
		(start 235.559854 -119.140986)
		(end 235.965746 -119.546878)
		(width 0.254)
		(layer "F.Cu")
		(net "P12V_NIC3_CO_FLTB")
	)
	(segment
		(start 234.825794 -117.936264)
		(end 235.084366 -117.936264)
		(width 0.254)
		(layer "F.Cu")
		(net "P12V_NIC3_CO_FLTB")
	)
	(segment
		(start 235.559854 -118.411752)
		(end 235.559854 -119.140986)
		(width 0.254)
		(layer "F.Cu")
		(net "P12V_NIC3_CO_FLTB")
	)
	(segment
		(start 235.084366 -117.936264)
		(end 235.559854 -118.411752)
		(width 0.254)
		(layer "F.Cu")
		(net "P12V_NIC3_CO_FLTB")
	)
	(via
		(at 235.559854 -119.140986)
		(size 0.508)
		(drill 0.254)
		(layers "F.Cu" "B.Cu")
		(net "P12V_NIC3_CO_FLTB")
	)
	(segment
		(start 130.877818 -159.488632)
		(end 130.594608 -159.205422)
		(width 0.13208)
		(layer "F.Cu")
		(net "P12V_NIC2_CO_EN")
	)
	(segment
		(start 130.594608 -159.205422)
		(end 130.594608 -158.679896)
		(width 0.13208)
		(layer "F.Cu")
		(net "P12V_NIC2_CO_EN")
	)
	(segment
		(start 130.753612 -161.603944)
		(end 130.753612 -160.537652)
		(width 0.13208)
		(layer "F.Cu")
		(net "P12V_NIC2_CO_EN")
	)
	(segment
		(start 130.877818 -160.413446)
		(end 130.877818 -159.488632)
		(width 0.13208)
		(layer "F.Cu")
		(net "P12V_NIC2_CO_EN")
	)
	(segment
		(start 130.753612 -160.537652)
		(end 130.877818 -160.413446)
		(width 0.13208)
		(layer "F.Cu")
		(net "P12V_NIC2_CO_EN")
	)
	(segment
		(start 131.642612 -161.603944)
		(end 130.753612 -161.603944)
		(width 0.13208)
		(layer "F.Cu")
		(net "P12V_NIC2_CO_EN")
	)
	(segment
		(start 132.531612 -161.603944)
		(end 131.642612 -161.603944)
		(width 0.13208)
		(layer "F.Cu")
		(net "P12V_NIC2_CO_EN")
	)
	(via
		(at 130.877818 -159.488632)
		(size 0.508)
		(drill 0.254)
		(layers "F.Cu" "B.Cu")
		(net "P12V_NIC2_CO_EN")
	)
	(via
		(at 231.199944 -118.179088)
		(size 0.508)
		(drill 0.254)
		(layers "F.Cu" "B.Cu")
		(net "P12V_NIC3_CO_AVIN_PD")
	)
	(segment
		(start 233.933746 -119.456708)
		(end 234.181142 -119.209312)
		(width 0.13208)
		(layer "F.Cu")
		(net "PWRGD_P12V_NIC3_CO")
	)
	(segment
		(start 233.933746 -119.981218)
		(end 233.933746 -119.456708)
		(width 0.13208)
		(layer "F.Cu")
		(net "PWRGD_P12V_NIC3_CO")
	)
	(segment
		(start 234.181142 -119.209312)
		(end 233.925618 -118.953788)
		(width 0.13208)
		(layer "F.Cu")
		(net "PWRGD_P12V_NIC3_CO")
	)
	(segment
		(start 233.925618 -118.953788)
		(end 233.925618 -118.336314)
		(width 0.13208)
		(layer "F.Cu")
		(net "PWRGD_P12V_NIC3_CO")
	)
	(segment
		(start 234.949746 -119.981218)
		(end 233.933746 -119.981218)
		(width 0.13208)
		(layer "F.Cu")
		(net "PWRGD_P12V_NIC3_CO")
	)
	(via
		(at 234.181142 -119.209312)
		(size 0.508)
		(drill 0.254)
		(layers "F.Cu" "B.Cu")
		(net "PWRGD_P12V_NIC3_CO")
	)
	(segment
		(start 10.716768 -160.68548)
		(end 11.895328 -159.50692)
		(width 0.254)
		(layer "F.Cu")
		(net "P12V_NIC0_CO_SS")
	)
	(segment
		(start 10.711688 -160.963864)
		(end 10.716768 -160.958784)
		(width 0.254)
		(layer "F.Cu")
		(net "P12V_NIC0_CO_SS")
	)
	(segment
		(start 10.716768 -160.968944)
		(end 10.711688 -160.963864)
		(width 0.254)
		(layer "F.Cu")
		(net "P12V_NIC0_CO_SS")
	)
	(segment
		(start 11.994896 -159.266636)
		(end 11.994896 -158.705042)
		(width 0.254)
		(layer "F.Cu")
		(net "P12V_NIC0_CO_SS")
	)
	(segment
		(start 11.895328 -159.50692)
		(end 11.994896 -159.266636)
		(width 0.254)
		(layer "F.Cu")
		(net "P12V_NIC0_CO_SS")
	)
	(segment
		(start 10.716768 -161.603944)
		(end 10.716768 -160.968944)
		(width 0.254)
		(layer "F.Cu")
		(net "P12V_NIC0_CO_SS")
	)
	(segment
		(start 10.716768 -160.958784)
		(end 10.716768 -160.68548)
		(width 0.254)
		(layer "F.Cu")
		(net "P12V_NIC0_CO_SS")
	)
	(via
		(at 10.711688 -160.963864)
		(size 0.508)
		(drill 0.254)
		(layers "F.Cu" "B.Cu")
		(net "P12V_NIC0_CO_SS")
	)
	(segment
		(start 125.577092 -157.804866)
		(end 126.194566 -157.804866)
		(width 0.13208)
		(layer "F.Cu")
		(net "PWRGD_P12V_NIC2_CO")
	)
	(segment
		(start 125.321568 -158.06039)
		(end 125.074172 -157.812994)
		(width 0.13208)
		(layer "F.Cu")
		(net "PWRGD_P12V_NIC2_CO")
	)
	(segment
		(start 125.321568 -158.06039)
		(end 125.577092 -157.804866)
		(width 0.13208)
		(layer "F.Cu")
		(net "PWRGD_P12V_NIC2_CO")
	)
	(segment
		(start 125.074172 -157.812994)
		(end 124.549662 -157.812994)
		(width 0.13208)
		(layer "F.Cu")
		(net "PWRGD_P12V_NIC2_CO")
	)
	(segment
		(start 124.549662 -158.828994)
		(end 124.549662 -157.812994)
		(width 0.13208)
		(layer "F.Cu")
		(net "PWRGD_P12V_NIC2_CO")
	)
	(via
		(at 125.321568 -158.06039)
		(size 0.508)
		(drill 0.254)
		(layers "F.Cu" "B.Cu")
		(net "PWRGD_P12V_NIC2_CO")
	)
	(segment
		(start 110.635796 -112.296956)
		(end 111.276892 -112.296956)
		(width 0.254)
		(layer "F.Cu")
		(net "P12V_NIC1_CO_ISET_R")
	)
	(segment
		(start 111.52759 -112.547654)
		(end 111.911892 -112.547654)
		(width 0.254)
		(layer "F.Cu")
		(net "P12V_NIC1_CO_ISET_R")
	)
	(segment
		(start 111.276892 -112.296956)
		(end 111.52759 -112.547654)
		(width 0.254)
		(layer "F.Cu")
		(net "P12V_NIC1_CO_ISET_R")
	)
	(via
		(at 111.276892 -112.296956)
		(size 0.508)
		(drill 0.254)
		(layers "F.Cu" "B.Cu")
		(net "P12V_NIC1_CO_ISET_R")
	)
	(segment
		(start 237.724696 -112.888268)
		(end 237.724696 -113.777268)
		(width 0.13208)
		(layer "F.Cu")
		(net "P12V_NIC3_CO_EN")
	)
	(segment
		(start 237.724696 -111.999268)
		(end 237.724696 -112.888268)
		(width 0.13208)
		(layer "F.Cu")
		(net "P12V_NIC3_CO_EN")
	)
	(segment
		(start 235.326174 -113.936272)
		(end 234.800648 -113.936272)
		(width 0.13208)
		(layer "F.Cu")
		(net "P12V_NIC3_CO_EN")
	)
	(segment
		(start 236.658404 -113.777268)
		(end 236.534198 -113.653062)
		(width 0.13208)
		(layer "F.Cu")
		(net "P12V_NIC3_CO_EN")
	)
	(segment
		(start 237.724696 -113.777268)
		(end 236.658404 -113.777268)
		(width 0.13208)
		(layer "F.Cu")
		(net "P12V_NIC3_CO_EN")
	)
	(segment
		(start 235.609384 -113.653062)
		(end 235.326174 -113.936272)
		(width 0.13208)
		(layer "F.Cu")
		(net "P12V_NIC3_CO_EN")
	)
	(segment
		(start 236.534198 -113.653062)
		(end 235.609384 -113.653062)
		(width 0.13208)
		(layer "F.Cu")
		(net "P12V_NIC3_CO_EN")
	)
	(via
		(at 235.609384 -113.653062)
		(size 0.508)
		(drill 0.254)
		(layers "F.Cu" "B.Cu")
		(net "P12V_NIC3_CO_EN")
	)
	(segment
		(start 236.4486 -115.64747)
		(end 237.689898 -115.64747)
		(width 0.254)
		(layer "F.Cu")
		(net "P12V_NIC3_CO_ISET")
	)
	(segment
		(start 236.1057 -115.64747)
		(end 235.816902 -115.936268)
		(width 0.254)
		(layer "F.Cu")
		(net "P12V_NIC3_CO_ISET")
	)
	(segment
		(start 237.689898 -115.64747)
		(end 237.724696 -115.682268)
		(width 0.254)
		(layer "F.Cu")
		(net "P12V_NIC3_CO_ISET")
	)
	(segment
		(start 235.816902 -115.936268)
		(end 235.652564 -115.936268)
		(width 0.254)
		(layer "F.Cu")
		(net "P12V_NIC3_CO_ISET")
	)
	(segment
		(start 235.652564 -115.936268)
		(end 234.825794 -115.936268)
		(width 0.254)
		(layer "F.Cu")
		(net "P12V_NIC3_CO_ISET")
	)
	(segment
		(start 236.4486 -115.64747)
		(end 236.1057 -115.64747)
		(width 0.254)
		(layer "F.Cu")
		(net "P12V_NIC3_CO_ISET")
	)
	(via
		(at 235.652564 -115.936268)
		(size 0.508)
		(drill 0.254)
		(layers "F.Cu" "B.Cu")
		(net "P12V_NIC3_CO_ISET")
	)
	(via
		(at 9.269476 -156.69387)
		(size 0.508)
		(drill 0.254)
		(layers "F.Cu" "B.Cu")
		(net "P12V_NIC0_CO_OV_FB")
	)
	(segment
		(start 109.74705 -114.261138)
		(end 109.74705 -114.990372)
		(width 0.254)
		(layer "F.Cu")
		(net "P12V_NIC1_CO_FLTB")
	)
	(segment
		(start 109.01299 -113.78565)
		(end 109.271562 -113.78565)
		(width 0.254)
		(layer "F.Cu")
		(net "P12V_NIC1_CO_FLTB")
	)
	(segment
		(start 110.152942 -115.396264)
		(end 110.152942 -115.830604)
		(width 0.254)
		(layer "F.Cu")
		(net "P12V_NIC1_CO_FLTB")
	)
	(segment
		(start 109.271562 -113.78565)
		(end 109.74705 -114.261138)
		(width 0.254)
		(layer "F.Cu")
		(net "P12V_NIC1_CO_FLTB")
	)
	(segment
		(start 109.74705 -114.990372)
		(end 110.152942 -115.396264)
		(width 0.254)
		(layer "F.Cu")
		(net "P12V_NIC1_CO_FLTB")
	)
	(via
		(at 109.74705 -114.990372)
		(size 0.508)
		(drill 0.254)
		(layers "F.Cu" "B.Cu")
		(net "P12V_NIC1_CO_FLTB")
	)
	(segment
		(start 9.319768 -160.847024)
		(end 9.319768 -160.965896)
		(width 0.254)
		(layer "F.Cu")
		(net "P12V_NIC0_CO_IMON_VR")
	)
	(segment
		(start 10.994644 -158.705042)
		(end 10.994644 -159.172148)
		(width 0.254)
		(layer "F.Cu")
		(net "P12V_NIC0_CO_IMON_VR")
	)
	(segment
		(start 10.994644 -159.172148)
		(end 9.319768 -160.847024)
		(width 0.254)
		(layer "F.Cu")
		(net "P12V_NIC0_CO_IMON_VR")
	)
	(segment
		(start 9.319768 -160.965896)
		(end 9.319768 -161.603944)
		(width 0.254)
		(layer "F.Cu")
		(net "P12V_NIC0_CO_IMON_VR")
	)
	(via
		(at 9.319768 -160.965896)
		(size 0.508)
		(drill 0.254)
		(layers "F.Cu" "B.Cu")
		(net "P12V_NIC0_CO_IMON_VR")
	)
	(segment
		(start 124.549662 -159.844994)
		(end 124.984002 -159.844994)
		(width 0.254)
		(layer "F.Cu")
		(net "P12V_NIC2_CO_FLTB")
	)
	(segment
		(start 125.389894 -159.439102)
		(end 126.119128 -159.439102)
		(width 0.254)
		(layer "F.Cu")
		(net "P12V_NIC2_CO_FLTB")
	)
	(segment
		(start 126.594616 -158.963614)
		(end 126.594616 -158.705042)
		(width 0.254)
		(layer "F.Cu")
		(net "P12V_NIC2_CO_FLTB")
	)
	(segment
		(start 124.984002 -159.844994)
		(end 125.389894 -159.439102)
		(width 0.254)
		(layer "F.Cu")
		(net "P12V_NIC2_CO_FLTB")
	)
	(segment
		(start 126.119128 -159.439102)
		(end 126.594616 -158.963614)
		(width 0.254)
		(layer "F.Cu")
		(net "P12V_NIC2_CO_FLTB")
	)
	(via
		(at 125.389894 -159.439102)
		(size 0.508)
		(drill 0.254)
		(layers "F.Cu" "B.Cu")
		(net "P12V_NIC2_CO_FLTB")
	)
	(segment
		(start 13.764768 -160.450022)
		(end 12.99464 -159.679894)
		(width 0.13208)
		(layer "F.Cu")
		(net "P12V_NIC0_CO_TIMER")
	)
	(segment
		(start 13.764768 -160.902142)
		(end 13.764768 -161.603944)
		(width 0.13208)
		(layer "F.Cu")
		(net "P12V_NIC0_CO_TIMER")
	)
	(segment
		(start 13.764768 -160.902142)
		(end 13.764768 -160.450022)
		(width 0.13208)
		(layer "F.Cu")
		(net "P12V_NIC0_CO_TIMER")
	)
	(segment
		(start 12.99464 -159.679894)
		(end 12.99464 -158.705042)
		(width 0.13208)
		(layer "F.Cu")
		(net "P12V_NIC0_CO_TIMER")
	)
	(via
		(at 13.764768 -160.902142)
		(size 0.508)
		(drill 0.254)
		(layers "F.Cu" "B.Cu")
		(net "P12V_NIC0_CO_TIMER")
	)
	(segment
		(start 80.782414 -31.44139)
		(end 80.667352 -31.719266)
		(width 0.13208)
		(layer "F.Cu")
		(net "P3V3_SSD3_CO_EN")
	)
	(segment
		(start 80.782414 -30.875732)
		(end 80.782414 -31.44139)
		(width 0.13208)
		(layer "F.Cu")
		(net "P3V3_SSD3_CO_EN")
	)
	(segment
		(start 80.667352 -32.25927)
		(end 80.828388 -32.420306)
		(width 0.13208)
		(layer "F.Cu")
		(net "P3V3_SSD3_CO_EN")
	)
	(segment
		(start 80.667352 -31.719266)
		(end 80.667352 -32.25927)
		(width 0.13208)
		(layer "F.Cu")
		(net "P3V3_SSD3_CO_EN")
	)
	(via
		(at 80.667352 -31.719266)
		(size 0.508)
		(drill 0.254)
		(layers "F.Cu" "B.Cu")
		(net "P3V3_SSD3_CO_EN")
	)
	(segment
		(start 71.646796 -38.49116)
		(end 71.646796 -37.47516)
		(width 0.13208)
		(layer "F.Cu")
		(net "P3V3_SSD3_PG_G1")
	)
	(segment
		(start 72.619108 -37.951156)
		(end 72.33031 -37.662358)
		(width 0.13208)
		(layer "F.Cu")
		(net "P3V3_SSD3_PG_G1")
	)
	(segment
		(start 72.261222 -37.662358)
		(end 72.074024 -37.47516)
		(width 0.13208)
		(layer "F.Cu")
		(net "P3V3_SSD3_PG_G1")
	)
	(segment
		(start 72.074024 -37.47516)
		(end 71.646796 -37.47516)
		(width 0.13208)
		(layer "F.Cu")
		(net "P3V3_SSD3_PG_G1")
	)
	(segment
		(start 72.33031 -37.662358)
		(end 72.261222 -37.662358)
		(width 0.13208)
		(layer "F.Cu")
		(net "P3V3_SSD3_PG_G1")
	)
	(segment
		(start 73.061068 -37.951156)
		(end 72.619108 -37.951156)
		(width 0.13208)
		(layer "F.Cu")
		(net "P3V3_SSD3_PG_G1")
	)
	(via
		(at 72.33031 -37.662358)
		(size 0.508)
		(drill 0.254)
		(layers "F.Cu" "B.Cu")
		(net "P3V3_SSD3_PG_G1")
	)
	(segment
		(start 81.472786 -28.139136)
		(end 82.049874 -28.139136)
		(width 0.13208)
		(layer "F.Cu")
		(net "P3V3_SSD3_CO_MODE")
	)
	(segment
		(start 82.049874 -28.139136)
		(end 82.373724 -27.815286)
		(width 0.13208)
		(layer "F.Cu")
		(net "P3V3_SSD3_CO_MODE")
	)
	(segment
		(start 81.282286 -28.329636)
		(end 81.472786 -28.139136)
		(width 0.13208)
		(layer "F.Cu")
		(net "P3V3_SSD3_CO_MODE")
	)
	(segment
		(start 81.282286 -28.875736)
		(end 81.282286 -28.329636)
		(width 0.13208)
		(layer "F.Cu")
		(net "P3V3_SSD3_CO_MODE")
	)
	(segment
		(start 81.357724 -27.406346)
		(end 82.373724 -27.406346)
		(width 0.13208)
		(layer "F.Cu")
		(net "P3V3_SSD3_CO_MODE")
	)
	(segment
		(start 82.373724 -27.815286)
		(end 82.373724 -27.406346)
		(width 0.13208)
		(layer "F.Cu")
		(net "P3V3_SSD3_CO_MODE")
	)
	(via
		(at 82.049874 -28.139136)
		(size 0.508)
		(drill 0.254)
		(layers "F.Cu" "B.Cu")
		(net "P3V3_SSD3_CO_MODE")
	)
	(segment
		(start 54.782466 -30.875732)
		(end 54.782466 -31.44139)
		(width 0.13208)
		(layer "F.Cu")
		(net "P3V3_SSD2_CO_EN")
	)
	(segment
		(start 54.782466 -31.44139)
		(end 54.667404 -31.719266)
		(width 0.13208)
		(layer "F.Cu")
		(net "P3V3_SSD2_CO_EN")
	)
	(segment
		(start 54.667404 -32.25927)
		(end 54.856126 -32.447992)
		(width 0.13208)
		(layer "F.Cu")
		(net "P3V3_SSD2_CO_EN")
	)
	(segment
		(start 54.667404 -31.719266)
		(end 54.667404 -32.25927)
		(width 0.13208)
		(layer "F.Cu")
		(net "P3V3_SSD2_CO_EN")
	)
	(via
		(at 54.667404 -31.719266)
		(size 0.508)
		(drill 0.254)
		(layers "F.Cu" "B.Cu")
		(net "P3V3_SSD2_CO_EN")
	)
	(segment
		(start 5.67309 -42.824654)
		(end 5.260086 -43.237658)
		(width 0.13208)
		(layer "F.Cu")
		(net "P3V3_SSD0_CO_GATE")
	)
	(segment
		(start 5.67309 -42.347134)
		(end 5.67309 -42.824654)
		(width 0.13208)
		(layer "F.Cu")
		(net "P3V3_SSD0_CO_GATE")
	)
	(segment
		(start 4.797298 -42.084498)
		(end 5.059934 -42.347134)
		(width 0.13208)
		(layer "F.Cu")
		(net "P3V3_SSD0_CO_GATE")
	)
	(segment
		(start 5.059934 -42.347134)
		(end 5.67309 -42.347134)
		(width 0.13208)
		(layer "F.Cu")
		(net "P3V3_SSD0_CO_GATE")
	)
	(segment
		(start 4.797298 -41.665398)
		(end 4.797298 -42.084498)
		(width 0.13208)
		(layer "F.Cu")
		(net "P3V3_SSD0_CO_GATE")
	)
	(via
		(at 5.67309 -42.347134)
		(size 0.508)
		(drill 0.254)
		(layers "F.Cu" "B.Cu")
		(net "P3V3_SSD0_CO_GATE")
	)
	(segment
		(start 79.988664 -31.567882)
		(end 79.380588 -31.567882)
		(width 0.13208)
		(layer "F.Cu")
		(net "P3V3_SSD3_CO_DV_DT")
	)
	(segment
		(start 80.282542 -31.274004)
		(end 79.988664 -31.567882)
		(width 0.13208)
		(layer "F.Cu")
		(net "P3V3_SSD3_CO_DV_DT")
	)
	(segment
		(start 79.388716 -31.57601)
		(end 79.388716 -32.39135)
		(width 0.13208)
		(layer "F.Cu")
		(net "P3V3_SSD3_CO_DV_DT")
	)
	(segment
		(start 79.388716 -32.39135)
		(end 79.332074 -32.447992)
		(width 0.13208)
		(layer "F.Cu")
		(net "P3V3_SSD3_CO_DV_DT")
	)
	(segment
		(start 80.282542 -30.875732)
		(end 80.282542 -31.274004)
		(width 0.13208)
		(layer "F.Cu")
		(net "P3V3_SSD3_CO_DV_DT")
	)
	(segment
		(start 79.380588 -31.567882)
		(end 79.388716 -31.57601)
		(width 0.13208)
		(layer "F.Cu")
		(net "P3V3_SSD3_CO_DV_DT")
	)
	(via
		(at 79.380588 -31.567882)
		(size 0.508)
		(drill 0.254)
		(layers "F.Cu" "B.Cu")
		(net "P3V3_SSD3_CO_DV_DT")
	)
	(segment
		(start 103.073454 -120.79224)
		(end 102.330504 -120.79224)
		(width 0.13208)
		(layer "F.Cu")
		(net "P3V3_NIC1_PG_G1")
	)
	(segment
		(start 103.824532 -119.77624)
		(end 103.327454 -119.77624)
		(width 0.13208)
		(layer "F.Cu")
		(net "P3V3_NIC1_PG_G1")
	)
	(segment
		(start 102.330504 -121.80824)
		(end 102.330504 -120.79224)
		(width 0.13208)
		(layer "F.Cu")
		(net "P3V3_NIC1_PG_G1")
	)
	(segment
		(start 103.073454 -120.03024)
		(end 103.073454 -120.79224)
		(width 0.13208)
		(layer "F.Cu")
		(net "P3V3_NIC1_PG_G1")
	)
	(segment
		(start 103.327454 -119.77624)
		(end 103.073454 -120.03024)
		(width 0.13208)
		(layer "F.Cu")
		(net "P3V3_NIC1_PG_G1")
	)
	(via
		(at 103.073454 -120.79224)
		(size 0.508)
		(drill 0.254)
		(layers "F.Cu" "B.Cu")
		(net "P3V3_NIC1_PG_G1")
	)
	(segment
		(start 54.779926 -28.139136)
		(end 54.782466 -28.141676)
		(width 0.13208)
		(layer "F.Cu")
		(net "P3V3_SSD2_CO_ILIMIT")
	)
	(segment
		(start 54.341776 -27.700986)
		(end 54.779926 -28.139136)
		(width 0.13208)
		(layer "F.Cu")
		(net "P3V3_SSD2_CO_ILIMIT")
	)
	(segment
		(start 54.341776 -27.406346)
		(end 54.341776 -27.700986)
		(width 0.13208)
		(layer "F.Cu")
		(net "P3V3_SSD2_CO_ILIMIT")
	)
	(segment
		(start 54.782466 -28.141676)
		(end 54.782466 -28.875736)
		(width 0.13208)
		(layer "F.Cu")
		(net "P3V3_SSD2_CO_ILIMIT")
	)
	(via
		(at 54.779926 -28.139136)
		(size 0.508)
		(drill 0.254)
		(layers "F.Cu" "B.Cu")
		(net "P3V3_SSD2_CO_ILIMIT")
	)
	(segment
		(start 54.282594 -30.875732)
		(end 54.282594 -31.274004)
		(width 0.13208)
		(layer "F.Cu")
		(net "P3V3_SSD2_CO_DV_DT")
	)
	(segment
		(start 53.388768 -31.996634)
		(end 53.840126 -32.447992)
		(width 0.13208)
		(layer "F.Cu")
		(net "P3V3_SSD2_CO_DV_DT")
	)
	(segment
		(start 54.282594 -31.274004)
		(end 53.988716 -31.567882)
		(width 0.13208)
		(layer "F.Cu")
		(net "P3V3_SSD2_CO_DV_DT")
	)
	(segment
		(start 53.38064 -31.567882)
		(end 53.388768 -31.57601)
		(width 0.13208)
		(layer "F.Cu")
		(net "P3V3_SSD2_CO_DV_DT")
	)
	(segment
		(start 53.388768 -31.57601)
		(end 53.388768 -31.996634)
		(width 0.13208)
		(layer "F.Cu")
		(net "P3V3_SSD2_CO_DV_DT")
	)
	(segment
		(start 53.988716 -31.567882)
		(end 53.38064 -31.567882)
		(width 0.13208)
		(layer "F.Cu")
		(net "P3V3_SSD2_CO_DV_DT")
	)
	(via
		(at 53.38064 -31.567882)
		(size 0.508)
		(drill 0.254)
		(layers "F.Cu" "B.Cu")
		(net "P3V3_SSD2_CO_DV_DT")
	)
	(segment
		(start 89.502234 -116.416836)
		(end 89.0524 -116.416836)
		(width 0.13208)
		(layer "F.Cu")
		(net "P3V3_NIC1_CO_GATE")
	)
	(segment
		(start 89.755218 -116.66982)
		(end 89.502234 -116.416836)
		(width 0.13208)
		(layer "F.Cu")
		(net "P3V3_NIC1_CO_GATE")
	)
	(segment
		(start 90.62466 -116.335048)
		(end 90.08999 -116.335048)
		(width 0.13208)
		(layer "F.Cu")
		(net "P3V3_NIC1_CO_GATE")
	)
	(segment
		(start 90.08999 -116.335048)
		(end 89.755218 -116.66982)
		(width 0.13208)
		(layer "F.Cu")
		(net "P3V3_NIC1_CO_GATE")
	)
	(via
		(at 89.755218 -116.66982)
		(size 0.508)
		(drill 0.254)
		(layers "F.Cu" "B.Cu")
		(net "P3V3_NIC1_CO_GATE")
	)
	(segment
		(start 27.988768 -31.567882)
		(end 27.380692 -31.567882)
		(width 0.13208)
		(layer "F.Cu")
		(net "P3V3_SSD1_CO_DV_DT")
	)
	(segment
		(start 27.38882 -31.57601)
		(end 27.38882 -32.39135)
		(width 0.13208)
		(layer "F.Cu")
		(net "P3V3_SSD1_CO_DV_DT")
	)
	(segment
		(start 28.282646 -30.875732)
		(end 28.282646 -31.274004)
		(width 0.13208)
		(layer "F.Cu")
		(net "P3V3_SSD1_CO_DV_DT")
	)
	(segment
		(start 27.380692 -31.567882)
		(end 27.38882 -31.57601)
		(width 0.13208)
		(layer "F.Cu")
		(net "P3V3_SSD1_CO_DV_DT")
	)
	(segment
		(start 28.282646 -31.274004)
		(end 27.988768 -31.567882)
		(width 0.13208)
		(layer "F.Cu")
		(net "P3V3_SSD1_CO_DV_DT")
	)
	(segment
		(start 27.38882 -32.39135)
		(end 27.332178 -32.447992)
		(width 0.13208)
		(layer "F.Cu")
		(net "P3V3_SSD1_CO_DV_DT")
	)
	(via
		(at 27.380692 -31.567882)
		(size 0.508)
		(drill 0.254)
		(layers "F.Cu" "B.Cu")
		(net "P3V3_SSD1_CO_DV_DT")
	)
	(segment
		(start 15.42288 -113.302034)
		(end 14.695678 -113.302034)
		(width 0.13208)
		(layer "F.Cu")
		(net "P3V3_NIC0_CO_ILIMIT")
	)
	(segment
		(start 16.041116 -114.695478)
		(end 16.041116 -113.92027)
		(width 0.13208)
		(layer "F.Cu")
		(net "P3V3_NIC0_CO_ILIMIT")
	)
	(segment
		(start 16.041116 -113.92027)
		(end 15.42288 -113.302034)
		(width 0.13208)
		(layer "F.Cu")
		(net "P3V3_NIC0_CO_ILIMIT")
	)
	(segment
		(start 14.670786 -113.277142)
		(end 14.695678 -113.302034)
		(width 0.13208)
		(layer "F.Cu")
		(net "P3V3_NIC0_CO_ILIMIT")
	)
	(segment
		(start 14.670786 -112.539526)
		(end 14.670786 -113.277142)
		(width 0.13208)
		(layer "F.Cu")
		(net "P3V3_NIC0_CO_ILIMIT")
	)
	(via
		(at 14.695678 -113.302034)
		(size 0.508)
		(drill 0.254)
		(layers "F.Cu" "B.Cu")
		(net "P3V3_NIC0_CO_ILIMIT")
	)
	(segment
		(start 5.564886 -38.928802)
		(end 5.888736 -38.604952)
		(width 0.13208)
		(layer "F.Cu")
		(net "P3V3_SSD0_CO_MODE")
	)
	(segment
		(start 4.872736 -38.196012)
		(end 5.888736 -38.196012)
		(width 0.13208)
		(layer "F.Cu")
		(net "P3V3_SSD0_CO_MODE")
	)
	(segment
		(start 5.888736 -38.604952)
		(end 5.888736 -38.196012)
		(width 0.13208)
		(layer "F.Cu")
		(net "P3V3_SSD0_CO_MODE")
	)
	(segment
		(start 4.987798 -38.928802)
		(end 4.797298 -39.119302)
		(width 0.13208)
		(layer "F.Cu")
		(net "P3V3_SSD0_CO_MODE")
	)
	(segment
		(start 4.797298 -39.119302)
		(end 4.797298 -39.665402)
		(width 0.13208)
		(layer "F.Cu")
		(net "P3V3_SSD0_CO_MODE")
	)
	(segment
		(start 5.564886 -38.928802)
		(end 4.987798 -38.928802)
		(width 0.13208)
		(layer "F.Cu")
		(net "P3V3_SSD0_CO_MODE")
	)
	(via
		(at 5.564886 -38.928802)
		(size 0.508)
		(drill 0.254)
		(layers "F.Cu" "B.Cu")
		(net "P3V3_SSD0_CO_MODE")
	)
	(segment
		(start 73.566274 -7.183374)
		(end 73.280524 -6.897624)
		(width 0.13208)
		(layer "F.Cu")
		(net "SMB_LM75_2_SDA")
	)
	(segment
		(start 73.280524 -6.897624)
		(end 72.883776 -6.897624)
		(width 0.13208)
		(layer "F.Cu")
		(net "SMB_LM75_2_SDA")
	)
	(segment
		(start 74.919586 -7.469632)
		(end 73.852532 -7.469632)
		(width 0.13208)
		(layer "F.Cu")
		(net "SMB_LM75_2_SDA")
	)
	(segment
		(start 73.852532 -7.469632)
		(end 73.566274 -7.183374)
		(width 0.13208)
		(layer "F.Cu")
		(net "SMB_LM75_2_SDA")
	)
	(via
		(at 73.566274 -7.183374)
		(size 0.508)
		(drill 0.254)
		(layers "F.Cu" "B.Cu")
		(net "SMB_LM75_2_SDA")
	)
	(segment
		(start 15.686786 -112.539526)
		(end 16.702786 -112.539526)
		(width 0.13208)
		(layer "F.Cu")
		(net "P3V3_NIC0_CO_MODE")
	)
	(segment
		(start 16.697198 -113.77803)
		(end 16.697198 -113.183162)
		(width 0.13208)
		(layer "F.Cu")
		(net "P3V3_NIC0_CO_MODE")
	)
	(segment
		(start 16.540988 -114.695478)
		(end 16.540988 -113.93424)
		(width 0.13208)
		(layer "F.Cu")
		(net "P3V3_NIC0_CO_MODE")
	)
	(segment
		(start 16.702786 -113.177574)
		(end 16.697198 -113.183162)
		(width 0.13208)
		(layer "F.Cu")
		(net "P3V3_NIC0_CO_MODE")
	)
	(segment
		(start 16.540988 -113.93424)
		(end 16.697198 -113.77803)
		(width 0.13208)
		(layer "F.Cu")
		(net "P3V3_NIC0_CO_MODE")
	)
	(segment
		(start 16.702786 -112.539526)
		(end 16.702786 -113.177574)
		(width 0.13208)
		(layer "F.Cu")
		(net "P3V3_NIC0_CO_MODE")
	)
	(via
		(at 16.697198 -113.183162)
		(size 0.508)
		(drill 0.254)
		(layers "F.Cu" "B.Cu")
		(net "P3V3_NIC0_CO_MODE")
	)
	(segment
		(start 3.702558 -68.166234)
		(end 3.27533 -68.166234)
		(width 0.13208)
		(layer "F.Cu")
		(net "P3V3_SSD0_PG_G1")
	)
	(segment
		(start 4.247642 -68.64223)
		(end 3.958844 -68.353432)
		(width 0.13208)
		(layer "F.Cu")
		(net "P3V3_SSD0_PG_G1")
	)
	(segment
		(start 4.689602 -68.64223)
		(end 4.247642 -68.64223)
		(width 0.13208)
		(layer "F.Cu")
		(net "P3V3_SSD0_PG_G1")
	)
	(segment
		(start 3.889756 -68.353432)
		(end 3.702558 -68.166234)
		(width 0.13208)
		(layer "F.Cu")
		(net "P3V3_SSD0_PG_G1")
	)
	(segment
		(start 3.958844 -68.353432)
		(end 3.889756 -68.353432)
		(width 0.13208)
		(layer "F.Cu")
		(net "P3V3_SSD0_PG_G1")
	)
	(segment
		(start 3.27533 -69.182234)
		(end 3.27533 -68.166234)
		(width 0.13208)
		(layer "F.Cu")
		(net "P3V3_SSD0_PG_G1")
	)
	(via
		(at 3.958844 -68.353432)
		(size 0.508)
		(drill 0.254)
		(layers "F.Cu" "B.Cu")
		(net "P3V3_SSD0_PG_G1")
	)
	(segment
		(start 93.361256 -116.525548)
		(end 93.361256 -117.102636)
		(width 0.13208)
		(layer "F.Cu")
		(net "P3V3_NIC1_CO_MODE")
	)
	(segment
		(start 93.685106 -117.426486)
		(end 94.094046 -117.426486)
		(width 0.13208)
		(layer "F.Cu")
		(net "P3V3_NIC1_CO_MODE")
	)
	(segment
		(start 93.361256 -117.102636)
		(end 93.685106 -117.426486)
		(width 0.13208)
		(layer "F.Cu")
		(net "P3V3_NIC1_CO_MODE")
	)
	(segment
		(start 94.094046 -116.410486)
		(end 94.094046 -117.426486)
		(width 0.13208)
		(layer "F.Cu")
		(net "P3V3_NIC1_CO_MODE")
	)
	(segment
		(start 92.624656 -116.335048)
		(end 93.170756 -116.335048)
		(width 0.13208)
		(layer "F.Cu")
		(net "P3V3_NIC1_CO_MODE")
	)
	(segment
		(start 93.170756 -116.335048)
		(end 93.361256 -116.525548)
		(width 0.13208)
		(layer "F.Cu")
		(net "P3V3_NIC1_CO_MODE")
	)
	(via
		(at 93.361256 -117.102636)
		(size 0.508)
		(drill 0.254)
		(layers "F.Cu" "B.Cu")
		(net "P3V3_NIC1_CO_MODE")
	)
	(segment
		(start 48.860964 -38.701218)
		(end 50.080418 -38.701218)
		(width 0.13208)
		(layer "F.Cu")
		(net "P3V3_SSD2_PG_G2")
	)
	(segment
		(start 49.992026 -37.951156)
		(end 50.081942 -38.041072)
		(width 0.13208)
		(layer "F.Cu")
		(net "P3V3_SSD2_PG_G2")
	)
	(segment
		(start 50.080418 -38.701218)
		(end 50.081942 -38.702742)
		(width 0.13208)
		(layer "F.Cu")
		(net "P3V3_SSD2_PG_G2")
	)
	(segment
		(start 48.860964 -37.951156)
		(end 49.992026 -37.951156)
		(width 0.13208)
		(layer "F.Cu")
		(net "P3V3_SSD2_PG_G2")
	)
	(segment
		(start 50.081942 -38.702742)
		(end 50.081942 -38.041072)
		(width 0.13208)
		(layer "F.Cu")
		(net "P3V3_SSD2_PG_G2")
	)
	(via
		(at 50.081942 -38.702742)
		(size 0.508)
		(drill 0.254)
		(layers "F.Cu" "B.Cu")
		(net "P3V3_SSD2_PG_G2")
	)
	(segment
		(start 80.21955 -3.659632)
		(end 81.74736 -3.659632)
		(width 0.13208)
		(layer "F.Cu")
		(net "LM75_2_A2")
	)
	(segment
		(start 82.634074 -2.998724)
		(end 82.634074 -4.014724)
		(width 0.13208)
		(layer "F.Cu")
		(net "LM75_2_A2")
	)
	(segment
		(start 82.102452 -4.014724)
		(end 82.634074 -4.014724)
		(width 0.13208)
		(layer "F.Cu")
		(net "LM75_2_A2")
	)
	(segment
		(start 81.74736 -3.659632)
		(end 82.102452 -4.014724)
		(width 0.13208)
		(layer "F.Cu")
		(net "LM75_2_A2")
	)
	(via
		(at 81.74736 -3.659632)
		(size 0.508)
		(drill 0.254)
		(layers "F.Cu" "B.Cu")
		(net "LM75_2_A2")
	)
	(segment
		(start 106.991404 -119.77624)
		(end 105.624376 -119.77624)
		(width 0.13208)
		(layer "F.Cu")
		(net "P3V3_NIC1_PG_G2")
	)
	(segment
		(start 106.387392 -120.53824)
		(end 107.118404 -120.53824)
		(width 0.13208)
		(layer "F.Cu")
		(net "P3V3_NIC1_PG_G2")
	)
	(segment
		(start 107.118404 -120.53824)
		(end 107.118404 -119.90324)
		(width 0.13208)
		(layer "F.Cu")
		(net "P3V3_NIC1_PG_G2")
	)
	(segment
		(start 106.375454 -120.526302)
		(end 106.387392 -120.53824)
		(width 0.13208)
		(layer "F.Cu")
		(net "P3V3_NIC1_PG_G2")
	)
	(segment
		(start 107.118404 -119.90324)
		(end 106.991404 -119.77624)
		(width 0.13208)
		(layer "F.Cu")
		(net "P3V3_NIC1_PG_G2")
	)
	(segment
		(start 105.624376 -120.526302)
		(end 106.375454 -120.526302)
		(width 0.13208)
		(layer "F.Cu")
		(net "P3V3_NIC1_PG_G2")
	)
	(via
		(at 106.375454 -120.526302)
		(size 0.508)
		(drill 0.254)
		(layers "F.Cu" "B.Cu")
		(net "P3V3_NIC1_PG_G2")
	)
	(segment
		(start 46.074076 -37.47516)
		(end 45.646848 -37.47516)
		(width 0.13208)
		(layer "F.Cu")
		(net "P3V3_SSD2_PG_G1")
	)
	(segment
		(start 46.61916 -37.951156)
		(end 46.330362 -37.662358)
		(width 0.13208)
		(layer "F.Cu")
		(net "P3V3_SSD2_PG_G1")
	)
	(segment
		(start 47.06112 -37.951156)
		(end 46.61916 -37.951156)
		(width 0.13208)
		(layer "F.Cu")
		(net "P3V3_SSD2_PG_G1")
	)
	(segment
		(start 45.646848 -38.49116)
		(end 45.646848 -37.47516)
		(width 0.13208)
		(layer "F.Cu")
		(net "P3V3_SSD2_PG_G1")
	)
	(segment
		(start 46.261274 -37.662358)
		(end 46.074076 -37.47516)
		(width 0.13208)
		(layer "F.Cu")
		(net "P3V3_SSD2_PG_G1")
	)
	(segment
		(start 46.330362 -37.662358)
		(end 46.261274 -37.662358)
		(width 0.13208)
		(layer "F.Cu")
		(net "P3V3_SSD2_PG_G1")
	)
	(via
		(at 46.330362 -37.662358)
		(size 0.508)
		(drill 0.254)
		(layers "F.Cu" "B.Cu")
		(net "P3V3_SSD2_PG_G1")
	)
	(segment
		(start 370.598446 -7.02183)
		(end 370.288566 -6.71195)
		(width 0.13208)
		(layer "F.Cu")
		(net "SMB_LM75_3_SCL")
	)
	(segment
		(start 370.280438 -6.703822)
		(end 369.48364 -6.703822)
		(width 0.13208)
		(layer "F.Cu")
		(net "SMB_LM75_3_SCL")
	)
	(segment
		(start 370.288566 -6.71195)
		(end 370.280438 -6.703822)
		(width 0.13208)
		(layer "F.Cu")
		(net "SMB_LM75_3_SCL")
	)
	(segment
		(start 371.51945 -7.02183)
		(end 370.598446 -7.02183)
		(width 0.13208)
		(layer "F.Cu")
		(net "SMB_LM75_3_SCL")
	)
	(via
		(at 370.288566 -6.71195)
		(size 0.508)
		(drill 0.254)
		(layers "F.Cu" "B.Cu")
		(net "SMB_LM75_3_SCL")
	)
	(segment
		(start 89.830402 -114.05743)
		(end 89.502996 -114.384836)
		(width 0.13208)
		(layer "F.Cu")
		(net "P3V3_NIC1_CO_DV_DT")
	)
	(segment
		(start 89.830402 -114.356642)
		(end 89.830402 -114.05743)
		(width 0.13208)
		(layer "F.Cu")
		(net "P3V3_NIC1_CO_DV_DT")
	)
	(segment
		(start 90.62466 -115.1509)
		(end 89.830402 -114.356642)
		(width 0.13208)
		(layer "F.Cu")
		(net "P3V3_NIC1_CO_DV_DT")
	)
	(segment
		(start 90.62466 -115.335304)
		(end 90.62466 -115.1509)
		(width 0.13208)
		(layer "F.Cu")
		(net "P3V3_NIC1_CO_DV_DT")
	)
	(segment
		(start 89.502996 -114.384836)
		(end 89.0524 -114.384836)
		(width 0.13208)
		(layer "F.Cu")
		(net "P3V3_NIC1_CO_DV_DT")
	)
	(via
		(at 89.830402 -114.05743)
		(size 0.508)
		(drill 0.254)
		(layers "F.Cu" "B.Cu")
		(net "P3V3_NIC1_CO_DV_DT")
	)
	(segment
		(start 28.782518 -28.141676)
		(end 28.779978 -28.139136)
		(width 0.13208)
		(layer "F.Cu")
		(net "P3V3_SSD1_CO_ILIMIT")
	)
	(segment
		(start 28.341828 -27.700986)
		(end 28.341828 -27.406346)
		(width 0.13208)
		(layer "F.Cu")
		(net "P3V3_SSD1_CO_ILIMIT")
	)
	(segment
		(start 28.782518 -28.875736)
		(end 28.782518 -28.141676)
		(width 0.13208)
		(layer "F.Cu")
		(net "P3V3_SSD1_CO_ILIMIT")
	)
	(segment
		(start 28.779978 -28.139136)
		(end 28.341828 -27.700986)
		(width 0.13208)
		(layer "F.Cu")
		(net "P3V3_SSD1_CO_ILIMIT")
	)
	(via
		(at 28.779978 -28.139136)
		(size 0.508)
		(drill 0.254)
		(layers "F.Cu" "B.Cu")
		(net "P3V3_SSD1_CO_ILIMIT")
	)
	(segment
		(start 378.702316 -4.836922)
		(end 378.347224 -4.48183)
		(width 0.13208)
		(layer "F.Cu")
		(net "LM75_3_A2")
	)
	(segment
		(start 379.233938 -3.820922)
		(end 379.233938 -4.836922)
		(width 0.13208)
		(layer "F.Cu")
		(net "LM75_3_A2")
	)
	(segment
		(start 379.233938 -4.836922)
		(end 378.702316 -4.836922)
		(width 0.13208)
		(layer "F.Cu")
		(net "LM75_3_A2")
	)
	(segment
		(start 378.347224 -4.48183)
		(end 376.819414 -4.48183)
		(width 0.13208)
		(layer "F.Cu")
		(net "LM75_3_A2")
	)
	(via
		(at 378.347224 -4.48183)
		(size 0.508)
		(drill 0.254)
		(layers "F.Cu" "B.Cu")
		(net "LM75_3_A2")
	)
	(segment
		(start 15.804896 -117.678454)
		(end 16.041116 -117.442234)
		(width 0.13208)
		(layer "F.Cu")
		(net "P3V3_NIC0_CO_EN")
	)
	(segment
		(start 16.041116 -116.695474)
		(end 16.041116 -117.442234)
		(width 0.13208)
		(layer "F.Cu")
		(net "P3V3_NIC0_CO_EN")
	)
	(segment
		(start 15.804896 -118.740936)
		(end 15.804896 -117.678454)
		(width 0.13208)
		(layer "F.Cu")
		(net "P3V3_NIC0_CO_EN")
	)
	(via
		(at 16.041116 -117.442234)
		(size 0.508)
		(drill 0.254)
		(layers "F.Cu" "B.Cu")
		(net "P3V3_NIC0_CO_EN")
	)
	(segment
		(start 81.409286 -31.664402)
		(end 81.94294 -31.664402)
		(width 0.13208)
		(layer "F.Cu")
		(net "P3V3_SSD3_CO_GATE")
	)
	(segment
		(start 81.872074 -32.076898)
		(end 81.872074 -32.447992)
		(width 0.13208)
		(layer "F.Cu")
		(net "P3V3_SSD3_CO_GATE")
	)
	(segment
		(start 81.282286 -30.875732)
		(end 81.282286 -31.537402)
		(width 0.13208)
		(layer "F.Cu")
		(net "P3V3_SSD3_CO_GATE")
	)
	(segment
		(start 81.94294 -31.664402)
		(end 81.94294 -32.006032)
		(width 0.13208)
		(layer "F.Cu")
		(net "P3V3_SSD3_CO_GATE")
	)
	(segment
		(start 81.94294 -32.006032)
		(end 81.872074 -32.076898)
		(width 0.13208)
		(layer "F.Cu")
		(net "P3V3_SSD3_CO_GATE")
	)
	(segment
		(start 81.282286 -31.537402)
		(end 81.409286 -31.664402)
		(width 0.13208)
		(layer "F.Cu")
		(net "P3V3_SSD3_CO_GATE")
	)
	(via
		(at 81.94294 -31.664402)
		(size 0.508)
		(drill 0.254)
		(layers "F.Cu" "B.Cu")
		(net "P3V3_SSD3_CO_GATE")
	)
	(segment
		(start 377.980702 -5.75183)
		(end 378.081794 -5.852922)
		(width 0.13208)
		(layer "F.Cu")
		(net "LM75_3_A1")
	)
	(segment
		(start 378.603002 -5.852922)
		(end 379.233938 -5.852922)
		(width 0.13208)
		(layer "F.Cu")
		(net "LM75_3_A1")
	)
	(segment
		(start 379.233938 -6.868922)
		(end 379.233938 -5.852922)
		(width 0.13208)
		(layer "F.Cu")
		(net "LM75_3_A1")
	)
	(segment
		(start 376.819414 -5.75183)
		(end 377.980702 -5.75183)
		(width 0.13208)
		(layer "F.Cu")
		(net "LM75_3_A1")
	)
	(segment
		(start 378.081794 -5.852922)
		(end 378.603002 -5.852922)
		(width 0.13208)
		(layer "F.Cu")
		(net "LM75_3_A1")
	)
	(via
		(at 378.603002 -5.852922)
		(size 0.508)
		(drill 0.254)
		(layers "F.Cu" "B.Cu")
		(net "LM75_3_A1")
	)
	(segment
		(start 12.609322 -118.705376)
		(end 12.609322 -117.962426)
		(width 0.13208)
		(layer "F.Cu")
		(net "P3V3_NIC0_PG_G1")
	)
	(segment
		(start 11.593322 -117.708426)
		(end 11.847322 -117.962426)
		(width 0.13208)
		(layer "F.Cu")
		(net "P3V3_NIC0_PG_G1")
	)
	(segment
		(start 13.625322 -118.705376)
		(end 12.609322 -118.705376)
		(width 0.13208)
		(layer "F.Cu")
		(net "P3V3_NIC0_PG_G1")
	)
	(segment
		(start 11.593322 -117.211348)
		(end 11.593322 -117.708426)
		(width 0.13208)
		(layer "F.Cu")
		(net "P3V3_NIC0_PG_G1")
	)
	(segment
		(start 11.847322 -117.962426)
		(end 12.609322 -117.962426)
		(width 0.13208)
		(layer "F.Cu")
		(net "P3V3_NIC0_PG_G1")
	)
	(via
		(at 12.609322 -117.962426)
		(size 0.508)
		(drill 0.254)
		(layers "F.Cu" "B.Cu")
		(net "P3V3_NIC0_PG_G1")
	)
	(segment
		(start 28.782518 -31.44139)
		(end 28.667456 -31.719266)
		(width 0.13208)
		(layer "F.Cu")
		(net "P3V3_SSD1_CO_EN")
	)
	(segment
		(start 28.667456 -32.25927)
		(end 28.667456 -31.719266)
		(width 0.13208)
		(layer "F.Cu")
		(net "P3V3_SSD1_CO_EN")
	)
	(segment
		(start 28.856178 -32.447992)
		(end 28.667456 -32.25927)
		(width 0.13208)
		(layer "F.Cu")
		(net "P3V3_SSD1_CO_EN")
	)
	(segment
		(start 28.782518 -30.875732)
		(end 28.782518 -31.44139)
		(width 0.13208)
		(layer "F.Cu")
		(net "P3V3_SSD1_CO_EN")
	)
	(via
		(at 28.667456 -31.719266)
		(size 0.508)
		(drill 0.254)
		(layers "F.Cu" "B.Cu")
		(net "P3V3_SSD1_CO_EN")
	)
	(segment
		(start 15.541244 -116.695474)
		(end 15.541244 -117.358668)
		(width 0.13208)
		(layer "F.Cu")
		(net "P3V3_NIC0_CO_DV_DT")
	)
	(segment
		(start 14.788896 -118.740936)
		(end 14.788896 -118.111016)
		(width 0.13208)
		(layer "F.Cu")
		(net "P3V3_NIC0_CO_DV_DT")
	)
	(segment
		(start 15.541244 -117.358668)
		(end 14.788896 -118.111016)
		(width 0.13208)
		(layer "F.Cu")
		(net "P3V3_NIC0_CO_DV_DT")
	)
	(via
		(at 14.788896 -118.111016)
		(size 0.508)
		(drill 0.254)
		(layers "F.Cu" "B.Cu")
		(net "P3V3_NIC0_CO_DV_DT")
	)
	(segment
		(start 80.779874 -28.139136)
		(end 80.341724 -27.700986)
		(width 0.13208)
		(layer "F.Cu")
		(net "P3V3_SSD3_CO_ILIMIT")
	)
	(segment
		(start 80.782414 -28.141676)
		(end 80.779874 -28.139136)
		(width 0.13208)
		(layer "F.Cu")
		(net "P3V3_SSD3_CO_ILIMIT")
	)
	(segment
		(start 80.341724 -27.700986)
		(end 80.341724 -27.406346)
		(width 0.13208)
		(layer "F.Cu")
		(net "P3V3_SSD3_CO_ILIMIT")
	)
	(segment
		(start 80.782414 -28.875736)
		(end 80.782414 -28.141676)
		(width 0.13208)
		(layer "F.Cu")
		(net "P3V3_SSD3_CO_ILIMIT")
	)
	(via
		(at 80.779874 -28.139136)
		(size 0.508)
		(drill 0.254)
		(layers "F.Cu" "B.Cu")
		(net "P3V3_SSD3_CO_ILIMIT")
	)
	(segment
		(start 82.003138 -5.030724)
		(end 81.48193 -5.030724)
		(width 0.13208)
		(layer "F.Cu")
		(net "LM75_2_A1")
	)
	(segment
		(start 82.634074 -6.046724)
		(end 82.634074 -5.030724)
		(width 0.13208)
		(layer "F.Cu")
		(net "LM75_2_A1")
	)
	(segment
		(start 82.634074 -5.030724)
		(end 82.003138 -5.030724)
		(width 0.13208)
		(layer "F.Cu")
		(net "LM75_2_A1")
	)
	(segment
		(start 81.380838 -4.929632)
		(end 80.21955 -4.929632)
		(width 0.13208)
		(layer "F.Cu")
		(net "LM75_2_A1")
	)
	(segment
		(start 81.48193 -5.030724)
		(end 81.380838 -4.929632)
		(width 0.13208)
		(layer "F.Cu")
		(net "LM75_2_A1")
	)
	(via
		(at 82.003138 -5.030724)
		(size 0.508)
		(drill 0.254)
		(layers "F.Cu" "B.Cu")
		(net "LM75_2_A1")
	)
	(segment
		(start 93.358716 -115.835176)
		(end 93.361256 -115.832636)
		(width 0.13208)
		(layer "F.Cu")
		(net "P3V3_NIC1_CO_ILIMIT")
	)
	(segment
		(start 93.799406 -115.394486)
		(end 94.094046 -115.394486)
		(width 0.13208)
		(layer "F.Cu")
		(net "P3V3_NIC1_CO_ILIMIT")
	)
	(segment
		(start 92.624656 -115.835176)
		(end 93.358716 -115.835176)
		(width 0.13208)
		(layer "F.Cu")
		(net "P3V3_NIC1_CO_ILIMIT")
	)
	(segment
		(start 93.361256 -115.832636)
		(end 93.799406 -115.394486)
		(width 0.13208)
		(layer "F.Cu")
		(net "P3V3_NIC1_CO_ILIMIT")
	)
	(via
		(at 93.361256 -115.832636)
		(size 0.508)
		(drill 0.254)
		(layers "F.Cu" "B.Cu")
		(net "P3V3_NIC1_CO_ILIMIT")
	)
	(segment
		(start 29.943044 -31.664402)
		(end 29.943044 -32.006032)
		(width 0.13208)
		(layer "F.Cu")
		(net "P3V3_SSD1_CO_GATE")
	)
	(segment
		(start 29.28239 -30.875732)
		(end 29.28239 -31.537402)
		(width 0.13208)
		(layer "F.Cu")
		(net "P3V3_SSD1_CO_GATE")
	)
	(segment
		(start 29.872178 -32.076898)
		(end 29.872178 -32.447992)
		(width 0.13208)
		(layer "F.Cu")
		(net "P3V3_SSD1_CO_GATE")
	)
	(segment
		(start 29.943044 -32.006032)
		(end 29.872178 -32.076898)
		(width 0.13208)
		(layer "F.Cu")
		(net "P3V3_SSD1_CO_GATE")
	)
	(segment
		(start 29.40939 -31.664402)
		(end 29.943044 -31.664402)
		(width 0.13208)
		(layer "F.Cu")
		(net "P3V3_SSD1_CO_GATE")
	)
	(segment
		(start 29.28239 -31.537402)
		(end 29.40939 -31.664402)
		(width 0.13208)
		(layer "F.Cu")
		(net "P3V3_SSD1_CO_GATE")
	)
	(via
		(at 29.943044 -31.664402)
		(size 0.508)
		(drill 0.254)
		(layers "F.Cu" "B.Cu")
		(net "P3V3_SSD1_CO_GATE")
	)
	(segment
		(start 71.555864 -7.903972)
		(end 71.555864 -6.409436)
		(width 0.13208)
		(layer "F.Cu")
		(net "SMB_LM75_2_SCL")
	)
	(segment
		(start 72.305164 -8.653272)
		(end 71.555864 -7.903972)
		(width 0.13208)
		(layer "F.Cu")
		(net "SMB_LM75_2_SCL")
	)
	(segment
		(start 71.555864 -6.409436)
		(end 72.083676 -5.881624)
		(width 0.13208)
		(layer "F.Cu")
		(net "SMB_LM75_2_SCL")
	)
	(segment
		(start 72.083676 -5.881624)
		(end 73.680574 -5.881624)
		(width 0.13208)
		(layer "F.Cu")
		(net "SMB_LM75_2_SCL")
	)
	(segment
		(start 369.573302 -10.888472)
		(end 369.573302 -10.954512)
		(width 0.13208)
		(layer "F.Cu")
		(net "SMB_LM75_2_SCL")
	)
	(segment
		(start 73.680574 -5.881624)
		(end 73.688702 -5.889752)
		(width 0.13208)
		(layer "F.Cu")
		(net "SMB_LM75_2_SCL")
	)
	(segment
		(start 369.411504 -10.726674)
		(end 369.573302 -10.888472)
		(width 0.13208)
		(layer "F.Cu")
		(net "SMB_LM75_2_SCL")
	)
	(segment
		(start 73.998582 -6.199632)
		(end 73.688702 -5.889752)
		(width 0.13208)
		(layer "F.Cu")
		(net "SMB_LM75_2_SCL")
	)
	(segment
		(start 74.919586 -6.199632)
		(end 73.998582 -6.199632)
		(width 0.13208)
		(layer "F.Cu")
		(net "SMB_LM75_2_SCL")
	)
	(segment
		(start 369.411504 -9.955022)
		(end 369.411504 -10.726674)
		(width 0.13208)
		(layer "F.Cu")
		(net "SMB_LM75_2_SCL")
	)
	(via
		(at 73.688702 -5.889752)
		(size 0.508)
		(drill 0.254)
		(layers "F.Cu" "B.Cu")
		(net "SMB_LM75_2_SCL")
	)
	(via
		(at 369.573302 -10.954512)
		(size 0.508)
		(drill 0.254)
		(layers "F.Cu" "B.Cu")
		(net "SMB_LM75_2_SCL")
	)
	(via
		(at 72.305164 -8.653272)
		(size 0.508)
		(drill 0.254)
		(layers "F.Cu" "B.Cu")
		(net "SMB_LM75_2_SCL")
	)
	(segment
		(start 166.307516 -18.0086)
		(end 165.774116 -17.4752)
		(width 0.15494)
		(layer "In15.Cu")
		(net "SMB_LM75_2_SCL")
	)
	(segment
		(start 154.672792 -17.9705)
		(end 140.4112 -17.9705)
		(width 0.15494)
		(layer "In15.Cu")
		(net "SMB_LM75_2_SCL")
	)
	(segment
		(start 100.8634 -23.7998)
		(end 95.0722 -18.0086)
		(width 0.15494)
		(layer "In15.Cu")
		(net "SMB_LM75_2_SCL")
	)
	(segment
		(start 159.257746 -18.290286)
		(end 158.92526 -17.9578)
		(width 0.15494)
		(layer "In15.Cu")
		(net "SMB_LM75_2_SCL")
	)
	(segment
		(start 72.76973 -8.188706)
		(end 72.305164 -8.653272)
		(width 0.15494)
		(layer "In15.Cu")
		(net "SMB_LM75_2_SCL")
	)
	(segment
		(start 305.8668 -17.4498)
		(end 305.054 -18.2626)
		(width 0.15494)
		(layer "In15.Cu")
		(net "SMB_LM75_2_SCL")
	)
	(segment
		(start 308.0512 -17.9705)
		(end 307.5305 -17.4498)
		(width 0.15494)
		(layer "In15.Cu")
		(net "SMB_LM75_2_SCL")
	)
	(segment
		(start 368.283744 -18.3388)
		(end 365.6584 -18.3388)
		(width 0.15494)
		(layer "In15.Cu")
		(net "SMB_LM75_2_SCL")
	)
	(segment
		(start 364.134654 -18.0086)
		(end 363.728254 -18.415)
		(width 0.15494)
		(layer "In15.Cu")
		(net "SMB_LM75_2_SCL")
	)
	(segment
		(start 91.287854 -18.415)
		(end 90.322654 -17.4498)
		(width 0.15494)
		(layer "In15.Cu")
		(net "SMB_LM75_2_SCL")
	)
	(segment
		(start 163.49599 -17.4752)
		(end 162.680904 -18.290286)
		(width 0.15494)
		(layer "In15.Cu")
		(net "SMB_LM75_2_SCL")
	)
	(segment
		(start 185.359548 -18.288)
		(end 185.029348 -17.9578)
		(width 0.15494)
		(layer "In15.Cu")
		(net "SMB_LM75_2_SCL")
	)
	(segment
		(start 347.5482 -23.749)
		(end 332.85557 -23.749)
		(width 0.15494)
		(layer "In15.Cu")
		(net "SMB_LM75_2_SCL")
	)
	(segment
		(start 188.597286 -18.288)
		(end 185.359548 -18.288)
		(width 0.15494)
		(layer "In15.Cu")
		(net "SMB_LM75_2_SCL")
	)
	(segment
		(start 180.589936 -18.0086)
		(end 166.307516 -18.0086)
		(width 0.15494)
		(layer "In15.Cu")
		(net "SMB_LM75_2_SCL")
	)
	(segment
		(start 369.573302 -17.049242)
		(end 368.283744 -18.3388)
		(width 0.15494)
		(layer "In15.Cu")
		(net "SMB_LM75_2_SCL")
	)
	(segment
		(start 361.461304 -18.415)
		(end 360.902504 -17.8562)
		(width 0.15494)
		(layer "In15.Cu")
		(net "SMB_LM75_2_SCL")
	)
	(segment
		(start 209.651346 -18.3388)
		(end 207.5942 -18.3388)
		(width 0.15494)
		(layer "In15.Cu")
		(net "SMB_LM75_2_SCL")
	)
	(segment
		(start 128.524 -17.8562)
		(end 119.481854 -17.8562)
		(width 0.15494)
		(layer "In15.Cu")
		(net "SMB_LM75_2_SCL")
	)
	(segment
		(start 165.774116 -17.4752)
		(end 163.49599 -17.4752)
		(width 0.15494)
		(layer "In15.Cu")
		(net "SMB_LM75_2_SCL")
	)
	(segment
		(start 353.441 -17.8562)
		(end 347.5482 -23.749)
		(width 0.15494)
		(layer "In15.Cu")
		(net "SMB_LM75_2_SCL")
	)
	(segment
		(start 307.5305 -17.4498)
		(end 305.8668 -17.4498)
		(width 0.15494)
		(layer "In15.Cu")
		(net "SMB_LM75_2_SCL")
	)
	(segment
		(start 327.202546 -18.095976)
		(end 325.972424 -18.095976)
		(width 0.15494)
		(layer "In15.Cu")
		(net "SMB_LM75_2_SCL")
	)
	(segment
		(start 234.468924 -16.740124)
		(end 216.134442 -16.740124)
		(width 0.15494)
		(layer "In15.Cu")
		(net "SMB_LM75_2_SCL")
	)
	(segment
		(start 113.538254 -23.7998)
		(end 100.8634 -23.7998)
		(width 0.15494)
		(layer "In15.Cu")
		(net "SMB_LM75_2_SCL")
	)
	(segment
		(start 133.58622 -18.4404)
		(end 133.17982 -18.034)
		(width 0.15494)
		(layer "In15.Cu")
		(net "SMB_LM75_2_SCL")
	)
	(segment
		(start 271.526 -18.4404)
		(end 271.0053 -17.9197)
		(width 0.15494)
		(layer "In15.Cu")
		(net "SMB_LM75_2_SCL")
	)
	(segment
		(start 301.192946 -17.9578)
		(end 299.8978 -17.9578)
		(width 0.15494)
		(layer "In15.Cu")
		(net "SMB_LM75_2_SCL")
	)
	(segment
		(start 332.85557 -23.749)
		(end 327.202546 -18.095976)
		(width 0.15494)
		(layer "In15.Cu")
		(net "SMB_LM75_2_SCL")
	)
	(segment
		(start 247.8024 -18.3896)
		(end 245.66753 -18.3896)
		(width 0.15494)
		(layer "In15.Cu")
		(net "SMB_LM75_2_SCL")
	)
	(segment
		(start 360.902504 -17.8562)
		(end 353.441 -17.8562)
		(width 0.15494)
		(layer "In15.Cu")
		(net "SMB_LM75_2_SCL")
	)
	(segment
		(start 137.494518 -17.4752)
		(end 136.529318 -18.4404)
		(width 0.15494)
		(layer "In15.Cu")
		(net "SMB_LM75_2_SCL")
	)
	(segment
		(start 299.4406 -18.415)
		(end 297.611546 -18.415)
		(width 0.15494)
		(layer "In15.Cu")
		(net "SMB_LM75_2_SCL")
	)
	(segment
		(start 93.4212 -18.415)
		(end 91.287854 -18.415)
		(width 0.15494)
		(layer "In15.Cu")
		(net "SMB_LM75_2_SCL")
	)
	(segment
		(start 136.529318 -18.4404)
		(end 133.58622 -18.4404)
		(width 0.15494)
		(layer "In15.Cu")
		(net "SMB_LM75_2_SCL")
	)
	(segment
		(start 157.454854 -18.3896)
		(end 155.091892 -18.3896)
		(width 0.15494)
		(layer "In15.Cu")
		(net "SMB_LM75_2_SCL")
	)
	(segment
		(start 207.1751 -17.9197)
		(end 192.2018 -17.9197)
		(width 0.15494)
		(layer "In15.Cu")
		(net "SMB_LM75_2_SCL")
	)
	(segment
		(start 325.6026 -18.4658)
		(end 323.463666 -18.4658)
		(width 0.15494)
		(layer "In15.Cu")
		(net "SMB_LM75_2_SCL")
	)
	(segment
		(start 189.410086 -17.4752)
		(end 188.597286 -18.288)
		(width 0.15494)
		(layer "In15.Cu")
		(net "SMB_LM75_2_SCL")
	)
	(segment
		(start 249.526806 -18.4404)
		(end 249.069606 -17.9832)
		(width 0.15494)
		(layer "In15.Cu")
		(net "SMB_LM75_2_SCL")
	)
	(segment
		(start 83.439 -17.4498)
		(end 74.177906 -8.188706)
		(width 0.15494)
		(layer "In15.Cu")
		(net "SMB_LM75_2_SCL")
	)
	(segment
		(start 119.481854 -17.8562)
		(end 113.538254 -23.7998)
		(width 0.15494)
		(layer "In15.Cu")
		(net "SMB_LM75_2_SCL")
	)
	(segment
		(start 297.611546 -18.415)
		(end 297.167046 -17.9705)
		(width 0.15494)
		(layer "In15.Cu")
		(net "SMB_LM75_2_SCL")
	)
	(segment
		(start 216.134442 -16.740124)
		(end 214.561166 -18.3134)
		(width 0.15494)
		(layer "In15.Cu")
		(net "SMB_LM75_2_SCL")
	)
	(segment
		(start 158.92526 -17.9578)
		(end 157.886654 -17.9578)
		(width 0.15494)
		(layer "In15.Cu")
		(net "SMB_LM75_2_SCL")
	)
	(segment
		(start 365.3282 -18.0086)
		(end 364.134654 -18.0086)
		(width 0.15494)
		(layer "In15.Cu")
		(net "SMB_LM75_2_SCL")
	)
	(segment
		(start 299.8978 -17.9578)
		(end 299.4406 -18.415)
		(width 0.15494)
		(layer "In15.Cu")
		(net "SMB_LM75_2_SCL")
	)
	(segment
		(start 162.680904 -18.290286)
		(end 159.257746 -18.290286)
		(width 0.15494)
		(layer "In15.Cu")
		(net "SMB_LM75_2_SCL")
	)
	(segment
		(start 271.0053 -17.9197)
		(end 256.159 -17.9197)
		(width 0.15494)
		(layer "In15.Cu")
		(net "SMB_LM75_2_SCL")
	)
	(segment
		(start 74.177906 -8.188706)
		(end 72.76973 -8.188706)
		(width 0.15494)
		(layer "In15.Cu")
		(net "SMB_LM75_2_SCL")
	)
	(segment
		(start 140.4112 -17.9705)
		(end 139.9159 -17.4752)
		(width 0.15494)
		(layer "In15.Cu")
		(net "SMB_LM75_2_SCL")
	)
	(segment
		(start 305.054 -18.2626)
		(end 301.497746 -18.2626)
		(width 0.15494)
		(layer "In15.Cu")
		(net "SMB_LM75_2_SCL")
	)
	(segment
		(start 95.0722 -18.0086)
		(end 93.8276 -18.0086)
		(width 0.15494)
		(layer "In15.Cu")
		(net "SMB_LM75_2_SCL")
	)
	(segment
		(start 249.069606 -17.9832)
		(end 248.2088 -17.9832)
		(width 0.15494)
		(layer "In15.Cu")
		(net "SMB_LM75_2_SCL")
	)
	(segment
		(start 281.6225 -17.4498)
		(end 279.632664 -17.4498)
		(width 0.15494)
		(layer "In15.Cu")
		(net "SMB_LM75_2_SCL")
	)
	(segment
		(start 90.322654 -17.4498)
		(end 83.439 -17.4498)
		(width 0.15494)
		(layer "In15.Cu")
		(net "SMB_LM75_2_SCL")
	)
	(segment
		(start 301.497746 -18.2626)
		(end 301.192946 -17.9578)
		(width 0.15494)
		(layer "In15.Cu")
		(net "SMB_LM75_2_SCL")
	)
	(segment
		(start 255.7145 -17.4752)
		(end 253.675388 -17.4752)
		(width 0.15494)
		(layer "In15.Cu")
		(net "SMB_LM75_2_SCL")
	)
	(segment
		(start 279.632664 -17.4498)
		(end 278.769064 -18.3134)
		(width 0.15494)
		(layer "In15.Cu")
		(net "SMB_LM75_2_SCL")
	)
	(segment
		(start 129.159 -18.4912)
		(end 128.524 -17.8562)
		(width 0.15494)
		(layer "In15.Cu")
		(net "SMB_LM75_2_SCL")
	)
	(segment
		(start 323.463666 -18.4658)
		(end 322.968366 -17.9705)
		(width 0.15494)
		(layer "In15.Cu")
		(net "SMB_LM75_2_SCL")
	)
	(segment
		(start 256.159 -17.9197)
		(end 255.7145 -17.4752)
		(width 0.15494)
		(layer "In15.Cu")
		(net "SMB_LM75_2_SCL")
	)
	(segment
		(start 93.8276 -18.0086)
		(end 93.4212 -18.415)
		(width 0.15494)
		(layer "In15.Cu")
		(net "SMB_LM75_2_SCL")
	)
	(segment
		(start 253.675388 -17.4752)
		(end 252.710188 -18.4404)
		(width 0.15494)
		(layer "In15.Cu")
		(net "SMB_LM75_2_SCL")
	)
	(segment
		(start 363.728254 -18.415)
		(end 361.461304 -18.415)
		(width 0.15494)
		(layer "In15.Cu")
		(net "SMB_LM75_2_SCL")
	)
	(segment
		(start 192.2018 -17.9197)
		(end 191.7573 -17.4752)
		(width 0.15494)
		(layer "In15.Cu")
		(net "SMB_LM75_2_SCL")
	)
	(segment
		(start 365.6584 -18.3388)
		(end 365.3282 -18.0086)
		(width 0.15494)
		(layer "In15.Cu")
		(net "SMB_LM75_2_SCL")
	)
	(segment
		(start 183.387746 -18.4404)
		(end 181.021736 -18.4404)
		(width 0.15494)
		(layer "In15.Cu")
		(net "SMB_LM75_2_SCL")
	)
	(segment
		(start 209.981546 -18.0086)
		(end 209.651346 -18.3388)
		(width 0.15494)
		(layer "In15.Cu")
		(net "SMB_LM75_2_SCL")
	)
	(segment
		(start 181.021736 -18.4404)
		(end 180.589936 -18.0086)
		(width 0.15494)
		(layer "In15.Cu")
		(net "SMB_LM75_2_SCL")
	)
	(segment
		(start 245.26113 -17.9832)
		(end 235.712 -17.9832)
		(width 0.15494)
		(layer "In15.Cu")
		(net "SMB_LM75_2_SCL")
	)
	(segment
		(start 139.9159 -17.4752)
		(end 137.494518 -17.4752)
		(width 0.15494)
		(layer "In15.Cu")
		(net "SMB_LM75_2_SCL")
	)
	(segment
		(start 185.029348 -17.9578)
		(end 183.870346 -17.9578)
		(width 0.15494)
		(layer "In15.Cu")
		(net "SMB_LM75_2_SCL")
	)
	(segment
		(start 235.712 -17.9832)
		(end 234.468924 -16.740124)
		(width 0.15494)
		(layer "In15.Cu")
		(net "SMB_LM75_2_SCL")
	)
	(segment
		(start 214.561166 -18.3134)
		(end 211.3788 -18.3134)
		(width 0.15494)
		(layer "In15.Cu")
		(net "SMB_LM75_2_SCL")
	)
	(segment
		(start 282.1432 -17.9705)
		(end 281.6225 -17.4498)
		(width 0.15494)
		(layer "In15.Cu")
		(net "SMB_LM75_2_SCL")
	)
	(segment
		(start 275.691854 -18.3134)
		(end 275.387054 -18.0086)
		(width 0.15494)
		(layer "In15.Cu")
		(net "SMB_LM75_2_SCL")
	)
	(segment
		(start 183.870346 -17.9578)
		(end 183.387746 -18.4404)
		(width 0.15494)
		(layer "In15.Cu")
		(net "SMB_LM75_2_SCL")
	)
	(segment
		(start 369.573302 -10.954512)
		(end 369.573302 -17.049242)
		(width 0.15494)
		(layer "In15.Cu")
		(net "SMB_LM75_2_SCL")
	)
	(segment
		(start 273.558 -18.4404)
		(end 271.526 -18.4404)
		(width 0.15494)
		(layer "In15.Cu")
		(net "SMB_LM75_2_SCL")
	)
	(segment
		(start 275.387054 -18.0086)
		(end 273.9898 -18.0086)
		(width 0.15494)
		(layer "In15.Cu")
		(net "SMB_LM75_2_SCL")
	)
	(segment
		(start 245.66753 -18.3896)
		(end 245.26113 -17.9832)
		(width 0.15494)
		(layer "In15.Cu")
		(net "SMB_LM75_2_SCL")
	)
	(segment
		(start 157.886654 -17.9578)
		(end 157.454854 -18.3896)
		(width 0.15494)
		(layer "In15.Cu")
		(net "SMB_LM75_2_SCL")
	)
	(segment
		(start 191.7573 -17.4752)
		(end 189.410086 -17.4752)
		(width 0.15494)
		(layer "In15.Cu")
		(net "SMB_LM75_2_SCL")
	)
	(segment
		(start 133.17982 -18.034)
		(end 131.927854 -18.034)
		(width 0.15494)
		(layer "In15.Cu")
		(net "SMB_LM75_2_SCL")
	)
	(segment
		(start 325.972424 -18.095976)
		(end 325.6026 -18.4658)
		(width 0.15494)
		(layer "In15.Cu")
		(net "SMB_LM75_2_SCL")
	)
	(segment
		(start 273.9898 -18.0086)
		(end 273.558 -18.4404)
		(width 0.15494)
		(layer "In15.Cu")
		(net "SMB_LM75_2_SCL")
	)
	(segment
		(start 297.167046 -17.9705)
		(end 282.1432 -17.9705)
		(width 0.15494)
		(layer "In15.Cu")
		(net "SMB_LM75_2_SCL")
	)
	(segment
		(start 211.074 -18.0086)
		(end 209.981546 -18.0086)
		(width 0.15494)
		(layer "In15.Cu")
		(net "SMB_LM75_2_SCL")
	)
	(segment
		(start 155.091892 -18.3896)
		(end 154.672792 -17.9705)
		(width 0.15494)
		(layer "In15.Cu")
		(net "SMB_LM75_2_SCL")
	)
	(segment
		(start 211.3788 -18.3134)
		(end 211.074 -18.0086)
		(width 0.15494)
		(layer "In15.Cu")
		(net "SMB_LM75_2_SCL")
	)
	(segment
		(start 131.470654 -18.4912)
		(end 129.159 -18.4912)
		(width 0.15494)
		(layer "In15.Cu")
		(net "SMB_LM75_2_SCL")
	)
	(segment
		(start 207.5942 -18.3388)
		(end 207.1751 -17.9197)
		(width 0.15494)
		(layer "In15.Cu")
		(net "SMB_LM75_2_SCL")
	)
	(segment
		(start 252.710188 -18.4404)
		(end 249.526806 -18.4404)
		(width 0.15494)
		(layer "In15.Cu")
		(net "SMB_LM75_2_SCL")
	)
	(segment
		(start 131.927854 -18.034)
		(end 131.470654 -18.4912)
		(width 0.15494)
		(layer "In15.Cu")
		(net "SMB_LM75_2_SCL")
	)
	(segment
		(start 322.968366 -17.9705)
		(end 308.0512 -17.9705)
		(width 0.15494)
		(layer "In15.Cu")
		(net "SMB_LM75_2_SCL")
	)
	(segment
		(start 248.2088 -17.9832)
		(end 247.8024 -18.3896)
		(width 0.15494)
		(layer "In15.Cu")
		(net "SMB_LM75_2_SCL")
	)
	(segment
		(start 278.769064 -18.3134)
		(end 275.691854 -18.3134)
		(width 0.15494)
		(layer "In15.Cu")
		(net "SMB_LM75_2_SCL")
	)
	(segment
		(start 89.416128 -115.400836)
		(end 89.0524 -115.400836)
		(width 0.13208)
		(layer "F.Cu")
		(net "P3V3_NIC1_CO_EN")
	)
	(segment
		(start 90.2081 -115.835176)
		(end 89.74328 -115.370356)
		(width 0.13208)
		(layer "F.Cu")
		(net "P3V3_NIC1_CO_EN")
	)
	(segment
		(start 89.74328 -115.370356)
		(end 89.446608 -115.370356)
		(width 0.13208)
		(layer "F.Cu")
		(net "P3V3_NIC1_CO_EN")
	)
	(segment
		(start 89.446608 -115.370356)
		(end 89.416128 -115.400836)
		(width 0.13208)
		(layer "F.Cu")
		(net "P3V3_NIC1_CO_EN")
	)
	(segment
		(start 90.62466 -115.835176)
		(end 90.2081 -115.835176)
		(width 0.13208)
		(layer "F.Cu")
		(net "P3V3_NIC1_CO_EN")
	)
	(via
		(at 89.74328 -115.370356)
		(size 0.508)
		(drill 0.254)
		(layers "F.Cu" "B.Cu")
		(net "P3V3_NIC1_CO_EN")
	)
	(segment
		(start 29.28239 -28.875736)
		(end 29.28239 -28.329636)
		(width 0.13208)
		(layer "F.Cu")
		(net "P3V3_SSD1_CO_MODE")
	)
	(segment
		(start 29.357828 -27.406346)
		(end 30.373828 -27.406346)
		(width 0.13208)
		(layer "F.Cu")
		(net "P3V3_SSD1_CO_MODE")
	)
	(segment
		(start 29.28239 -28.329636)
		(end 29.47289 -28.139136)
		(width 0.13208)
		(layer "F.Cu")
		(net "P3V3_SSD1_CO_MODE")
	)
	(segment
		(start 29.47289 -28.139136)
		(end 30.049978 -28.139136)
		(width 0.13208)
		(layer "F.Cu")
		(net "P3V3_SSD1_CO_MODE")
	)
	(segment
		(start 30.049978 -28.139136)
		(end 30.373828 -27.815286)
		(width 0.13208)
		(layer "F.Cu")
		(net "P3V3_SSD1_CO_MODE")
	)
	(segment
		(start 30.373828 -27.815286)
		(end 30.373828 -27.406346)
		(width 0.13208)
		(layer "F.Cu")
		(net "P3V3_SSD1_CO_MODE")
	)
	(via
		(at 30.049978 -28.139136)
		(size 0.508)
		(drill 0.254)
		(layers "F.Cu" "B.Cu")
		(net "P3V3_SSD1_CO_MODE")
	)
	(segment
		(start 82.227928 -7.062724)
		(end 82.634074 -7.062724)
		(width 0.13208)
		(layer "F.Cu")
		(net "LM75_2_A0")
	)
	(segment
		(start 81.816702 -6.651498)
		(end 82.227928 -7.062724)
		(width 0.13208)
		(layer "F.Cu")
		(net "LM75_2_A0")
	)
	(segment
		(start 82.634074 -8.078724)
		(end 82.634074 -7.062724)
		(width 0.13208)
		(layer "F.Cu")
		(net "LM75_2_A0")
	)
	(segment
		(start 80.21955 -6.199632)
		(end 81.364836 -6.199632)
		(width 0.13208)
		(layer "F.Cu")
		(net "LM75_2_A0")
	)
	(segment
		(start 81.364836 -6.199632)
		(end 81.816702 -6.651498)
		(width 0.13208)
		(layer "F.Cu")
		(net "LM75_2_A0")
	)
	(via
		(at 81.816702 -6.651498)
		(size 0.508)
		(drill 0.254)
		(layers "F.Cu" "B.Cu")
		(net "LM75_2_A0")
	)
	(segment
		(start 4.244086 -42.893234)
		(end 4.397502 -42.739818)
		(width 0.13208)
		(layer "F.Cu")
		(net "P3V3_SSD0_CO_EN")
	)
	(segment
		(start 4.397502 -42.401998)
		(end 4.297426 -42.16019)
		(width 0.13208)
		(layer "F.Cu")
		(net "P3V3_SSD0_CO_EN")
	)
	(segment
		(start 4.397502 -42.739818)
		(end 4.397502 -42.401998)
		(width 0.13208)
		(layer "F.Cu")
		(net "P3V3_SSD0_CO_EN")
	)
	(segment
		(start 4.297426 -42.16019)
		(end 4.297426 -41.665398)
		(width 0.13208)
		(layer "F.Cu")
		(net "P3V3_SSD0_CO_EN")
	)
	(segment
		(start 4.244086 -43.237658)
		(end 4.244086 -42.893234)
		(width 0.13208)
		(layer "F.Cu")
		(net "P3V3_SSD0_CO_EN")
	)
	(via
		(at 4.397502 -42.401998)
		(size 0.508)
		(drill 0.254)
		(layers "F.Cu" "B.Cu")
		(net "P3V3_SSD0_CO_EN")
	)
	(segment
		(start 370.452396 -8.29183)
		(end 370.166138 -8.005572)
		(width 0.13208)
		(layer "F.Cu")
		(net "SMB_LM75_3_SDA")
	)
	(segment
		(start 371.51945 -8.29183)
		(end 370.452396 -8.29183)
		(width 0.13208)
		(layer "F.Cu")
		(net "SMB_LM75_3_SDA")
	)
	(segment
		(start 370.166138 -8.005572)
		(end 369.880388 -7.719822)
		(width 0.13208)
		(layer "F.Cu")
		(net "SMB_LM75_3_SDA")
	)
	(segment
		(start 369.880388 -7.719822)
		(end 369.48364 -7.719822)
		(width 0.13208)
		(layer "F.Cu")
		(net "SMB_LM75_3_SDA")
	)
	(via
		(at 370.166138 -8.005572)
		(size 0.508)
		(drill 0.254)
		(layers "F.Cu" "B.Cu")
		(net "SMB_LM75_3_SDA")
	)
	(segment
		(start 17.18818 -117.778276)
		(end 17.18818 -118.063772)
		(width 0.13208)
		(layer "F.Cu")
		(net "P3V3_NIC0_CO_GATE")
	)
	(segment
		(start 16.820896 -118.740936)
		(end 17.18818 -118.373652)
		(width 0.13208)
		(layer "F.Cu")
		(net "P3V3_NIC0_CO_GATE")
	)
	(segment
		(start 16.540988 -116.695474)
		(end 16.540988 -117.131084)
		(width 0.13208)
		(layer "F.Cu")
		(net "P3V3_NIC0_CO_GATE")
	)
	(segment
		(start 17.18818 -118.373652)
		(end 17.18818 -118.063772)
		(width 0.13208)
		(layer "F.Cu")
		(net "P3V3_NIC0_CO_GATE")
	)
	(segment
		(start 16.540988 -117.131084)
		(end 17.18818 -117.778276)
		(width 0.13208)
		(layer "F.Cu")
		(net "P3V3_NIC0_CO_GATE")
	)
	(via
		(at 17.18818 -118.063772)
		(size 0.508)
		(drill 0.254)
		(layers "F.Cu" "B.Cu")
		(net "P3V3_NIC0_CO_GATE")
	)
	(segment
		(start 4.28371 -66.86042)
		(end 4.28371 -66.567812)
		(width 0.13208)
		(layer "F.Cu")
		(net "PWRGD_P3V3_SSD0_D")
	)
	(segment
		(start 4.624324 -67.201034)
		(end 4.28371 -66.86042)
		(width 0.13208)
		(layer "F.Cu")
		(net "PWRGD_P3V3_SSD0_D")
	)
	(segment
		(start 4.624324 -67.82689)
		(end 4.624324 -67.201034)
		(width 0.13208)
		(layer "F.Cu")
		(net "PWRGD_P3V3_SSD0_D")
	)
	(segment
		(start 5.256276 -66.567812)
		(end 4.28371 -66.567812)
		(width 0.13208)
		(layer "F.Cu")
		(net "PWRGD_P3V3_SSD0_D")
	)
	(segment
		(start 4.689602 -67.892168)
		(end 4.624324 -67.82689)
		(width 0.13208)
		(layer "F.Cu")
		(net "PWRGD_P3V3_SSD0_D")
	)
	(via
		(at 4.624324 -67.201034)
		(size 0.508)
		(drill 0.254)
		(layers "F.Cu" "B.Cu")
		(net "PWRGD_P3V3_SSD0_D")
	)
	(segment
		(start 379.233938 -8.900922)
		(end 379.233938 -7.884922)
		(width 0.13208)
		(layer "F.Cu")
		(net "LM75_3_A0")
	)
	(segment
		(start 379.233938 -7.884922)
		(end 378.827792 -7.884922)
		(width 0.13208)
		(layer "F.Cu")
		(net "LM75_3_A0")
	)
	(segment
		(start 378.827792 -7.884922)
		(end 378.416566 -7.473696)
		(width 0.13208)
		(layer "F.Cu")
		(net "LM75_3_A0")
	)
	(segment
		(start 378.416566 -7.473696)
		(end 377.9647 -7.02183)
		(width 0.13208)
		(layer "F.Cu")
		(net "LM75_3_A0")
	)
	(segment
		(start 377.9647 -7.02183)
		(end 376.819414 -7.02183)
		(width 0.13208)
		(layer "F.Cu")
		(net "LM75_3_A0")
	)
	(via
		(at 378.416566 -7.473696)
		(size 0.508)
		(drill 0.254)
		(layers "F.Cu" "B.Cu")
		(net "LM75_3_A0")
	)
	(segment
		(start 12.355322 -113.917476)
		(end 11.77417 -113.917476)
		(width 0.13208)
		(layer "F.Cu")
		(net "P3V3_NIC0_PG_G2")
	)
	(segment
		(start 12.343384 -114.660426)
		(end 12.343384 -115.411504)
		(width 0.13208)
		(layer "F.Cu")
		(net "P3V3_NIC0_PG_G2")
	)
	(segment
		(start 12.343384 -114.660426)
		(end 12.355322 -114.648488)
		(width 0.13208)
		(layer "F.Cu")
		(net "P3V3_NIC0_PG_G2")
	)
	(segment
		(start 11.77417 -113.917476)
		(end 11.593322 -114.098324)
		(width 0.13208)
		(layer "F.Cu")
		(net "P3V3_NIC0_PG_G2")
	)
	(segment
		(start 12.355322 -114.648488)
		(end 12.355322 -113.917476)
		(width 0.13208)
		(layer "F.Cu")
		(net "P3V3_NIC0_PG_G2")
	)
	(segment
		(start 11.593322 -114.098324)
		(end 11.593322 -115.411504)
		(width 0.13208)
		(layer "F.Cu")
		(net "P3V3_NIC0_PG_G2")
	)
	(via
		(at 12.343384 -114.660426)
		(size 0.508)
		(drill 0.254)
		(layers "F.Cu" "B.Cu")
		(net "P3V3_NIC0_PG_G2")
	)
	(segment
		(start 46.995842 -36.50996)
		(end 46.655228 -36.169346)
		(width 0.13208)
		(layer "F.Cu")
		(net "PWRGD_P3V3_SSD2_D")
	)
	(segment
		(start 46.655228 -36.169346)
		(end 46.655228 -35.876738)
		(width 0.13208)
		(layer "F.Cu")
		(net "PWRGD_P3V3_SSD2_D")
	)
	(segment
		(start 47.627794 -35.876738)
		(end 46.655228 -35.876738)
		(width 0.13208)
		(layer "F.Cu")
		(net "PWRGD_P3V3_SSD2_D")
	)
	(segment
		(start 46.995842 -37.135816)
		(end 46.995842 -36.50996)
		(width 0.13208)
		(layer "F.Cu")
		(net "PWRGD_P3V3_SSD2_D")
	)
	(segment
		(start 47.06112 -37.201094)
		(end 46.995842 -37.135816)
		(width 0.13208)
		(layer "F.Cu")
		(net "PWRGD_P3V3_SSD2_D")
	)
	(via
		(at 46.995842 -36.50996)
		(size 0.508)
		(drill 0.254)
		(layers "F.Cu" "B.Cu")
		(net "PWRGD_P3V3_SSD2_D")
	)
	(segment
		(start 3.655314 -42.250614)
		(end 3.797554 -42.108374)
		(width 0.13208)
		(layer "F.Cu")
		(net "P3V3_SSD0_CO_DV_DT")
	)
	(segment
		(start 3.110738 -42.686478)
		(end 3.110738 -42.250614)
		(width 0.13208)
		(layer "F.Cu")
		(net "P3V3_SSD0_CO_DV_DT")
	)
	(segment
		(start 3.797554 -42.108374)
		(end 3.797554 -41.665398)
		(width 0.13208)
		(layer "F.Cu")
		(net "P3V3_SSD0_CO_DV_DT")
	)
	(segment
		(start 3.228086 -43.237658)
		(end 3.228086 -42.803826)
		(width 0.13208)
		(layer "F.Cu")
		(net "P3V3_SSD0_CO_DV_DT")
	)
	(segment
		(start 3.228086 -42.803826)
		(end 3.110738 -42.686478)
		(width 0.13208)
		(layer "F.Cu")
		(net "P3V3_SSD0_CO_DV_DT")
	)
	(segment
		(start 3.110738 -42.250614)
		(end 3.655314 -42.250614)
		(width 0.13208)
		(layer "F.Cu")
		(net "P3V3_SSD0_CO_DV_DT")
	)
	(via
		(at 3.110738 -42.250614)
		(size 0.508)
		(drill 0.254)
		(layers "F.Cu" "B.Cu")
		(net "P3V3_SSD0_CO_DV_DT")
	)
	(segment
		(start 4.297426 -39.665402)
		(end 4.297426 -38.931342)
		(width 0.13208)
		(layer "F.Cu")
		(net "P3V3_SSD0_CO_ILIMIT")
	)
	(segment
		(start 4.297426 -38.931342)
		(end 4.294886 -38.928802)
		(width 0.13208)
		(layer "F.Cu")
		(net "P3V3_SSD0_CO_ILIMIT")
	)
	(segment
		(start 3.856736 -38.490652)
		(end 3.856736 -38.196012)
		(width 0.13208)
		(layer "F.Cu")
		(net "P3V3_SSD0_CO_ILIMIT")
	)
	(segment
		(start 4.294886 -38.928802)
		(end 3.856736 -38.490652)
		(width 0.13208)
		(layer "F.Cu")
		(net "P3V3_SSD0_CO_ILIMIT")
	)
	(via
		(at 4.294886 -38.928802)
		(size 0.508)
		(drill 0.254)
		(layers "F.Cu" "B.Cu")
		(net "P3V3_SSD0_CO_ILIMIT")
	)
	(segment
		(start 24.081994 -38.702742)
		(end 24.081994 -38.041072)
		(width 0.13208)
		(layer "F.Cu")
		(net "P3V3_SSD1_PG_G2")
	)
	(segment
		(start 22.861016 -38.701218)
		(end 24.08047 -38.701218)
		(width 0.13208)
		(layer "F.Cu")
		(net "P3V3_SSD1_PG_G2")
	)
	(segment
		(start 24.08047 -38.701218)
		(end 24.081994 -38.702742)
		(width 0.13208)
		(layer "F.Cu")
		(net "P3V3_SSD1_PG_G2")
	)
	(segment
		(start 23.992078 -37.951156)
		(end 24.081994 -38.041072)
		(width 0.13208)
		(layer "F.Cu")
		(net "P3V3_SSD1_PG_G2")
	)
	(segment
		(start 22.861016 -37.951156)
		(end 23.992078 -37.951156)
		(width 0.13208)
		(layer "F.Cu")
		(net "P3V3_SSD1_PG_G2")
	)
	(via
		(at 24.081994 -38.702742)
		(size 0.508)
		(drill 0.254)
		(layers "F.Cu" "B.Cu")
		(net "P3V3_SSD1_PG_G2")
	)
	(segment
		(start 55.942992 -32.006032)
		(end 55.872126 -32.076898)
		(width 0.13208)
		(layer "F.Cu")
		(net "P3V3_SSD2_CO_GATE")
	)
	(segment
		(start 55.942992 -31.664402)
		(end 55.942992 -32.006032)
		(width 0.13208)
		(layer "F.Cu")
		(net "P3V3_SSD2_CO_GATE")
	)
	(segment
		(start 55.282338 -30.875732)
		(end 55.282338 -31.537402)
		(width 0.13208)
		(layer "F.Cu")
		(net "P3V3_SSD2_CO_GATE")
	)
	(segment
		(start 55.282338 -31.537402)
		(end 55.409338 -31.664402)
		(width 0.13208)
		(layer "F.Cu")
		(net "P3V3_SSD2_CO_GATE")
	)
	(segment
		(start 55.409338 -31.664402)
		(end 55.942992 -31.664402)
		(width 0.13208)
		(layer "F.Cu")
		(net "P3V3_SSD2_CO_GATE")
	)
	(segment
		(start 55.872126 -32.076898)
		(end 55.872126 -32.447992)
		(width 0.13208)
		(layer "F.Cu")
		(net "P3V3_SSD2_CO_GATE")
	)
	(via
		(at 55.942992 -31.664402)
		(size 0.508)
		(drill 0.254)
		(layers "F.Cu" "B.Cu")
		(net "P3V3_SSD2_CO_GATE")
	)
	(segment
		(start 56.373776 -27.815286)
		(end 56.373776 -27.406346)
		(width 0.13208)
		(layer "F.Cu")
		(net "P3V3_SSD2_CO_MODE")
	)
	(segment
		(start 56.049926 -28.139136)
		(end 56.373776 -27.815286)
		(width 0.13208)
		(layer "F.Cu")
		(net "P3V3_SSD2_CO_MODE")
	)
	(segment
		(start 55.357776 -27.406346)
		(end 56.373776 -27.406346)
		(width 0.13208)
		(layer "F.Cu")
		(net "P3V3_SSD2_CO_MODE")
	)
	(segment
		(start 55.472838 -28.139136)
		(end 56.049926 -28.139136)
		(width 0.13208)
		(layer "F.Cu")
		(net "P3V3_SSD2_CO_MODE")
	)
	(segment
		(start 55.282338 -28.329636)
		(end 55.472838 -28.139136)
		(width 0.13208)
		(layer "F.Cu")
		(net "P3V3_SSD2_CO_MODE")
	)
	(segment
		(start 55.282338 -28.875736)
		(end 55.282338 -28.329636)
		(width 0.13208)
		(layer "F.Cu")
		(net "P3V3_SSD2_CO_MODE")
	)
	(via
		(at 56.049926 -28.139136)
		(size 0.508)
		(drill 0.254)
		(layers "F.Cu" "B.Cu")
		(net "P3V3_SSD2_CO_MODE")
	)
	(segment
		(start 20.619212 -37.951156)
		(end 20.330414 -37.662358)
		(width 0.13208)
		(layer "F.Cu")
		(net "P3V3_SSD1_PG_G1")
	)
	(segment
		(start 20.261326 -37.662358)
		(end 20.074128 -37.47516)
		(width 0.13208)
		(layer "F.Cu")
		(net "P3V3_SSD1_PG_G1")
	)
	(segment
		(start 21.061172 -37.951156)
		(end 20.619212 -37.951156)
		(width 0.13208)
		(layer "F.Cu")
		(net "P3V3_SSD1_PG_G1")
	)
	(segment
		(start 20.074128 -37.47516)
		(end 19.6469 -37.47516)
		(width 0.13208)
		(layer "F.Cu")
		(net "P3V3_SSD1_PG_G1")
	)
	(segment
		(start 19.6469 -38.49116)
		(end 19.6469 -37.47516)
		(width 0.13208)
		(layer "F.Cu")
		(net "P3V3_SSD1_PG_G1")
	)
	(segment
		(start 20.330414 -37.662358)
		(end 20.261326 -37.662358)
		(width 0.13208)
		(layer "F.Cu")
		(net "P3V3_SSD1_PG_G1")
	)
	(via
		(at 20.330414 -37.662358)
		(size 0.508)
		(drill 0.254)
		(layers "F.Cu" "B.Cu")
		(net "P3V3_SSD1_PG_G1")
	)
	(segment
		(start 75.991974 -37.951156)
		(end 74.860912 -37.951156)
		(width 0.13208)
		(layer "F.Cu")
		(net "P3V3_SSD3_PG_G2")
	)
	(segment
		(start 76.08189 -38.041072)
		(end 75.991974 -37.951156)
		(width 0.13208)
		(layer "F.Cu")
		(net "P3V3_SSD3_PG_G2")
	)
	(segment
		(start 76.08189 -38.702742)
		(end 76.08189 -38.041072)
		(width 0.13208)
		(layer "F.Cu")
		(net "P3V3_SSD3_PG_G2")
	)
	(segment
		(start 76.08189 -38.702742)
		(end 76.080366 -38.701218)
		(width 0.13208)
		(layer "F.Cu")
		(net "P3V3_SSD3_PG_G2")
	)
	(segment
		(start 76.080366 -38.701218)
		(end 74.860912 -38.701218)
		(width 0.13208)
		(layer "F.Cu")
		(net "P3V3_SSD3_PG_G2")
	)
	(via
		(at 76.08189 -38.702742)
		(size 0.508)
		(drill 0.254)
		(layers "F.Cu" "B.Cu")
		(net "P3V3_SSD3_PG_G2")
	)
	(segment
		(start 7.760208 -68.78193)
		(end 7.710424 -68.732146)
		(width 0.13208)
		(layer "F.Cu")
		(net "P3V3_SSD0_PG_G2")
	)
	(segment
		(start 7.710424 -68.732146)
		(end 7.620508 -68.64223)
		(width 0.13208)
		(layer "F.Cu")
		(net "P3V3_SSD0_PG_G2")
	)
	(segment
		(start 7.132574 -70.204076)
		(end 7.760208 -69.576442)
		(width 0.13208)
		(layer "F.Cu")
		(net "P3V3_SSD0_PG_G2")
	)
	(segment
		(start 7.760208 -69.576442)
		(end 7.760208 -68.78193)
		(width 0.13208)
		(layer "F.Cu")
		(net "P3V3_SSD0_PG_G2")
	)
	(segment
		(start 7.620508 -68.64223)
		(end 6.489446 -68.64223)
		(width 0.13208)
		(layer "F.Cu")
		(net "P3V3_SSD0_PG_G2")
	)
	(segment
		(start 6.489446 -69.392292)
		(end 6.489446 -70.204076)
		(width 0.13208)
		(layer "F.Cu")
		(net "P3V3_SSD0_PG_G2")
	)
	(segment
		(start 6.489446 -70.204076)
		(end 7.132574 -70.204076)
		(width 0.13208)
		(layer "F.Cu")
		(net "P3V3_SSD0_PG_G2")
	)
	(via
		(at 6.489446 -70.204076)
		(size 0.508)
		(drill 0.254)
		(layers "F.Cu" "B.Cu")
		(net "P3V3_SSD0_PG_G2")
	)
	(segment
		(start 73.627742 -35.876738)
		(end 72.655176 -35.876738)
		(width 0.13208)
		(layer "F.Cu")
		(net "PWRGD_P3V3_SSD3_D")
	)
	(segment
		(start 72.99579 -36.50996)
		(end 72.655176 -36.169346)
		(width 0.13208)
		(layer "F.Cu")
		(net "PWRGD_P3V3_SSD3_D")
	)
	(segment
		(start 72.655176 -36.169346)
		(end 72.655176 -35.876738)
		(width 0.13208)
		(layer "F.Cu")
		(net "PWRGD_P3V3_SSD3_D")
	)
	(segment
		(start 72.99579 -37.135816)
		(end 72.99579 -36.50996)
		(width 0.13208)
		(layer "F.Cu")
		(net "PWRGD_P3V3_SSD3_D")
	)
	(segment
		(start 73.061068 -37.201094)
		(end 72.99579 -37.135816)
		(width 0.13208)
		(layer "F.Cu")
		(net "PWRGD_P3V3_SSD3_D")
	)
	(via
		(at 72.99579 -36.50996)
		(size 0.508)
		(drill 0.254)
		(layers "F.Cu" "B.Cu")
		(net "PWRGD_P3V3_SSD3_D")
	)
	(segment
		(start 21.627846 -35.876738)
		(end 20.65528 -35.876738)
		(width 0.13208)
		(layer "F.Cu")
		(net "PWRGD_P3V3_SSD1_D")
	)
	(segment
		(start 20.995894 -37.135816)
		(end 20.995894 -36.50996)
		(width 0.13208)
		(layer "F.Cu")
		(net "PWRGD_P3V3_SSD1_D")
	)
	(segment
		(start 20.65528 -36.169346)
		(end 20.65528 -35.876738)
		(width 0.13208)
		(layer "F.Cu")
		(net "PWRGD_P3V3_SSD1_D")
	)
	(segment
		(start 21.061172 -37.201094)
		(end 20.995894 -37.135816)
		(width 0.13208)
		(layer "F.Cu")
		(net "PWRGD_P3V3_SSD1_D")
	)
	(segment
		(start 20.995894 -36.50996)
		(end 20.65528 -36.169346)
		(width 0.13208)
		(layer "F.Cu")
		(net "PWRGD_P3V3_SSD1_D")
	)
	(via
		(at 20.995894 -36.50996)
		(size 0.508)
		(drill 0.254)
		(layers "F.Cu" "B.Cu")
		(net "PWRGD_P3V3_SSD1_D")
	)
	(via
		(at 257.529838 -229.8573)
		(size 0.6604)
		(drill 0.3302)
		(layers "F.Cu" "B.Cu")
		(net "SPI_PEX2_CS_MUX_N")
	)
	(segment
		(start 255.25857 -232.289096)
		(end 257.025394 -230.522272)
		(width 0.13208)
		(layer "B.Cu")
		(net "SPI_PEX2_CS_MUX_N")
	)
	(segment
		(start 257.025394 -230.361744)
		(end 257.529838 -229.8573)
		(width 0.13208)
		(layer "B.Cu")
		(net "SPI_PEX2_CS_MUX_N")
	)
	(segment
		(start 253.005336 -232.289096)
		(end 255.25857 -232.289096)
		(width 0.13208)
		(layer "B.Cu")
		(net "SPI_PEX2_CS_MUX_N")
	)
	(segment
		(start 257.025394 -230.522272)
		(end 257.025394 -230.361744)
		(width 0.13208)
		(layer "B.Cu")
		(net "SPI_PEX2_CS_MUX_N")
	)
	(segment
		(start 251.600716 -230.884476)
		(end 253.005336 -232.289096)
		(width 0.13208)
		(layer "B.Cu")
		(net "SPI_PEX2_CS_MUX_N")
	)
	(segment
		(start 257.529838 -229.8573)
		(end 257.529838 -228.668834)
		(width 0.13208)
		(layer "B.Cu")
		(net "SPI_PEX2_CS_MUX_N")
	)
	(segment
		(start 251.600716 -229.827582)
		(end 251.600716 -230.884476)
		(width 0.13208)
		(layer "B.Cu")
		(net "SPI_PEX2_CS_MUX_N")
	)
	(via
		(at 254.552704 -222.326962)
		(size 0.6604)
		(drill 0.3302)
		(layers "F.Cu" "B.Cu")
		(net "SPI_PEX2_SDIO0_MUX")
	)
	(segment
		(start 254.140716 -223.692212)
		(end 254.552704 -223.280224)
		(width 0.13208)
		(layer "B.Cu")
		(net "SPI_PEX2_SDIO0_MUX")
	)
	(segment
		(start 254.552704 -221.939358)
		(end 254.552704 -222.326962)
		(width 0.13208)
		(layer "B.Cu")
		(net "SPI_PEX2_SDIO0_MUX")
	)
	(segment
		(start 254.198628 -221.585282)
		(end 254.552704 -221.939358)
		(width 0.13208)
		(layer "B.Cu")
		(net "SPI_PEX2_SDIO0_MUX")
	)
	(segment
		(start 254.198628 -221.081092)
		(end 254.198628 -221.585282)
		(width 0.13208)
		(layer "B.Cu")
		(net "SPI_PEX2_SDIO0_MUX")
	)
	(segment
		(start 254.552704 -223.280224)
		(end 254.552704 -222.326962)
		(width 0.13208)
		(layer "B.Cu")
		(net "SPI_PEX2_SDIO0_MUX")
	)
	(segment
		(start 254.140716 -224.341182)
		(end 254.140716 -223.692212)
		(width 0.13208)
		(layer "B.Cu")
		(net "SPI_PEX2_SDIO0_MUX")
	)
	(via
		(at 247.17502 -223.561148)
		(size 0.6604)
		(drill 0.3302)
		(layers "F.Cu" "B.Cu")
		(net "SPI_PEX2_CLK_MUX")
	)
	(segment
		(start 247.17502 -225.208592)
		(end 247.449594 -225.483166)
		(width 0.13208)
		(layer "B.Cu")
		(net "SPI_PEX2_CLK_MUX")
	)
	(segment
		(start 251.718572 -226.910646)
		(end 253.505716 -228.69779)
		(width 0.13208)
		(layer "B.Cu")
		(net "SPI_PEX2_CLK_MUX")
	)
	(segment
		(start 247.449594 -225.483166)
		(end 247.449594 -225.846386)
		(width 0.13208)
		(layer "B.Cu")
		(net "SPI_PEX2_CLK_MUX")
	)
	(segment
		(start 247.17502 -222.040958)
		(end 247.17502 -223.561148)
		(width 0.13208)
		(layer "B.Cu")
		(net "SPI_PEX2_CLK_MUX")
	)
	(segment
		(start 247.17502 -223.561148)
		(end 247.17502 -225.208592)
		(width 0.13208)
		(layer "B.Cu")
		(net "SPI_PEX2_CLK_MUX")
	)
	(segment
		(start 248.522744 -226.910646)
		(end 251.718572 -226.910646)
		(width 0.13208)
		(layer "B.Cu")
		(net "SPI_PEX2_CLK_MUX")
	)
	(segment
		(start 247.988074 -226.375976)
		(end 248.522744 -226.910646)
		(width 0.13208)
		(layer "B.Cu")
		(net "SPI_PEX2_CLK_MUX")
	)
	(segment
		(start 247.449594 -225.846386)
		(end 247.979184 -226.375976)
		(width 0.13208)
		(layer "B.Cu")
		(net "SPI_PEX2_CLK_MUX")
	)
	(segment
		(start 247.979184 -226.375976)
		(end 247.988074 -226.375976)
		(width 0.13208)
		(layer "B.Cu")
		(net "SPI_PEX2_CLK_MUX")
	)
	(segment
		(start 253.505716 -228.69779)
		(end 253.505716 -229.827582)
		(width 0.13208)
		(layer "B.Cu")
		(net "SPI_PEX2_CLK_MUX")
	)
	(segment
		(start 263.90981 -344.772488)
		(end 263.90981 -344.32113)
		(width 0.13208)
		(layer "F.Cu")
		(net "HSC_D_OC_R")
	)
	(segment
		(start 263.904984 -347.622114)
		(end 263.904984 -347.596968)
		(width 0.13208)
		(layer "F.Cu")
		(net "HSC_D_OC_R")
	)
	(segment
		(start 264.287254 -348.004384)
		(end 263.904984 -347.622114)
		(width 0.13208)
		(layer "F.Cu")
		(net "HSC_D_OC_R")
	)
	(segment
		(start 263.897364 -345.76893)
		(end 263.895332 -345.766898)
		(width 0.13208)
		(layer "F.Cu")
		(net "HSC_D_OC_R")
	)
	(segment
		(start 263.895332 -345.766898)
		(end 263.90981 -345.75242)
		(width 0.13208)
		(layer "F.Cu")
		(net "HSC_D_OC_R")
	)
	(segment
		(start 205.791816 -356.021894)
		(end 205.754732 -355.98481)
		(width 0.13208)
		(layer "F.Cu")
		(net "HSC_D_OC_R")
	)
	(segment
		(start 205.754732 -355.98481)
		(end 205.754732 -354.967794)
		(width 0.13208)
		(layer "F.Cu")
		(net "HSC_D_OC_R")
	)
	(segment
		(start 261.877048 -350.670876)
		(end 263.838436 -350.670876)
		(width 0.13208)
		(layer "F.Cu")
		(net "HSC_D_OC_R")
	)
	(segment
		(start 261.695692 -341.49284)
		(end 261.002526 -341.49284)
		(width 0.13208)
		(layer "F.Cu")
		(net "HSC_D_OC_R")
	)
	(segment
		(start 263.904984 -346.719906)
		(end 263.897364 -346.712286)
		(width 0.13208)
		(layer "F.Cu")
		(net "HSC_D_OC_R")
	)
	(segment
		(start 264.541762 -348.167452)
		(end 264.378694 -348.004384)
		(width 0.13208)
		(layer "F.Cu")
		(net "HSC_D_OC_R")
	)
	(segment
		(start 205.791816 -356.021894)
		(end 205.791816 -356.811326)
		(width 0.13208)
		(layer "F.Cu")
		(net "HSC_D_OC_R")
	)
	(segment
		(start 258.925314 -349.773494)
		(end 260.979666 -349.773494)
		(width 0.13208)
		(layer "F.Cu")
		(net "HSC_D_OC_R")
	)
	(segment
		(start 260.979666 -349.773494)
		(end 261.877048 -350.670876)
		(width 0.13208)
		(layer "F.Cu")
		(net "HSC_D_OC_R")
	)
	(segment
		(start 263.569196 -343.980516)
		(end 262.357108 -343.980516)
		(width 0.13208)
		(layer "F.Cu")
		(net "HSC_D_OC_R")
	)
	(segment
		(start 263.897364 -346.712286)
		(end 263.897364 -345.76893)
		(width 0.13208)
		(layer "F.Cu")
		(net "HSC_D_OC_R")
	)
	(segment
		(start 263.838436 -350.670876)
		(end 264.541762 -349.96755)
		(width 0.13208)
		(layer "F.Cu")
		(net "HSC_D_OC_R")
	)
	(segment
		(start 264.378694 -348.004384)
		(end 264.287254 -348.004384)
		(width 0.13208)
		(layer "F.Cu")
		(net "HSC_D_OC_R")
	)
	(segment
		(start 261.932166 -343.555574)
		(end 261.932166 -341.729314)
		(width 0.13208)
		(layer "F.Cu")
		(net "HSC_D_OC_R")
	)
	(segment
		(start 262.357108 -343.980516)
		(end 261.932166 -343.555574)
		(width 0.13208)
		(layer "F.Cu")
		(net "HSC_D_OC_R")
	)
	(segment
		(start 264.541762 -349.96755)
		(end 264.541762 -348.167452)
		(width 0.13208)
		(layer "F.Cu")
		(net "HSC_D_OC_R")
	)
	(segment
		(start 263.90981 -345.75242)
		(end 263.90981 -344.772488)
		(width 0.13208)
		(layer "F.Cu")
		(net "HSC_D_OC_R")
	)
	(segment
		(start 261.932166 -341.729314)
		(end 261.695692 -341.49284)
		(width 0.13208)
		(layer "F.Cu")
		(net "HSC_D_OC_R")
	)
	(segment
		(start 263.90981 -344.32113)
		(end 263.569196 -343.980516)
		(width 0.13208)
		(layer "F.Cu")
		(net "HSC_D_OC_R")
	)
	(segment
		(start 263.904984 -347.596968)
		(end 263.904984 -346.719906)
		(width 0.13208)
		(layer "F.Cu")
		(net "HSC_D_OC_R")
	)
	(via
		(at 258.925314 -349.773494)
		(size 0.508)
		(drill 0.254)
		(layers "F.Cu" "B.Cu")
		(net "HSC_D_OC_R")
	)
	(via
		(at 205.791816 -356.021894)
		(size 0.508)
		(drill 0.254)
		(layers "F.Cu" "B.Cu")
		(net "HSC_D_OC_R")
	)
	(segment
		(start 205.791816 -356.021894)
		(end 205.791816 -354.50272)
		(width 0.13208)
		(layer "B.Cu")
		(net "HSC_D_OC_R")
	)
	(segment
		(start 223.30283 -344.29065)
		(end 251.169678 -344.29065)
		(width 0.13208)
		(layer "B.Cu")
		(net "HSC_D_OC_R")
	)
	(segment
		(start 255.193038 -346.895166)
		(end 256.651506 -346.895166)
		(width 0.13208)
		(layer "B.Cu")
		(net "HSC_D_OC_R")
	)
	(segment
		(start 203.697332 -352.408236)
		(end 203.697332 -348.865952)
		(width 0.13208)
		(layer "B.Cu")
		(net "HSC_D_OC_R")
	)
	(segment
		(start 251.169678 -344.29065)
		(end 252.65888 -345.779852)
		(width 0.13208)
		(layer "B.Cu")
		(net "HSC_D_OC_R")
	)
	(segment
		(start 205.791816 -354.50272)
		(end 203.697332 -352.408236)
		(width 0.13208)
		(layer "B.Cu")
		(net "HSC_D_OC_R")
	)
	(segment
		(start 209.859118 -342.704166)
		(end 221.716346 -342.704166)
		(width 0.13208)
		(layer "B.Cu")
		(net "HSC_D_OC_R")
	)
	(segment
		(start 258.925314 -349.168974)
		(end 258.925314 -349.773494)
		(width 0.13208)
		(layer "B.Cu")
		(net "HSC_D_OC_R")
	)
	(segment
		(start 252.65888 -345.779852)
		(end 254.077724 -345.779852)
		(width 0.13208)
		(layer "B.Cu")
		(net "HSC_D_OC_R")
	)
	(segment
		(start 256.651506 -346.895166)
		(end 258.925314 -349.168974)
		(width 0.13208)
		(layer "B.Cu")
		(net "HSC_D_OC_R")
	)
	(segment
		(start 221.716346 -342.704166)
		(end 223.30283 -344.29065)
		(width 0.13208)
		(layer "B.Cu")
		(net "HSC_D_OC_R")
	)
	(segment
		(start 254.077724 -345.779852)
		(end 255.193038 -346.895166)
		(width 0.13208)
		(layer "B.Cu")
		(net "HSC_D_OC_R")
	)
	(segment
		(start 203.697332 -348.865952)
		(end 209.859118 -342.704166)
		(width 0.13208)
		(layer "B.Cu")
		(net "HSC_D_OC_R")
	)
	(segment
		(start 185.97118 -411.062932)
		(end 185.97118 -411.99181)
		(width 0.13208)
		(layer "F.Cu")
		(net "HSC_UV_N")
	)
	(segment
		(start 186.196732 -410.070554)
		(end 186.196732 -410.83738)
		(width 0.13208)
		(layer "F.Cu")
		(net "HSC_UV_N")
	)
	(segment
		(start 186.196732 -410.83738)
		(end 185.996072 -411.03804)
		(width 0.13208)
		(layer "F.Cu")
		(net "HSC_UV_N")
	)
	(segment
		(start 185.996072 -411.03804)
		(end 185.97118 -411.062932)
		(width 0.13208)
		(layer "F.Cu")
		(net "HSC_UV_N")
	)
	(segment
		(start 186.98337 -411.99181)
		(end 185.97118 -411.99181)
		(width 0.13208)
		(layer "F.Cu")
		(net "HSC_UV_N")
	)
	(via
		(at 185.996072 -411.03804)
		(size 0.508)
		(drill 0.254)
		(layers "F.Cu" "B.Cu")
		(net "HSC_UV_N")
	)
	(segment
		(start 253.783846 -275.450046)
		(end 253.783846 -261.036816)
		(width 0.13208)
		(layer "F.Cu")
		(net "HSC_D_OC_BUF_R_N")
	)
	(segment
		(start 244.976142 -229.359714)
		(end 245.103396 -229.23246)
		(width 0.13208)
		(layer "F.Cu")
		(net "HSC_D_OC_BUF_R_N")
	)
	(segment
		(start 236.837982 -328.60742)
		(end 245.571772 -328.60742)
		(width 0.13208)
		(layer "F.Cu")
		(net "HSC_D_OC_BUF_R_N")
	)
	(segment
		(start 205.200504 -348.098618)
		(end 206.045816 -348.098618)
		(width 0.13208)
		(layer "F.Cu")
		(net "HSC_D_OC_BUF_R_N")
	)
	(segment
		(start 253.783846 -261.036816)
		(end 253.23292 -260.48589)
		(width 0.13208)
		(layer "F.Cu")
		(net "HSC_D_OC_BUF_R_N")
	)
	(segment
		(start 253.23292 -259.64388)
		(end 252.926088 -258.902962)
		(width 0.13208)
		(layer "F.Cu")
		(net "HSC_D_OC_BUF_R_N")
	)
	(segment
		(start 254.7493 -217.32367)
		(end 261.1501 -217.32367)
		(width 0.13208)
		(layer "F.Cu")
		(net "HSC_D_OC_BUF_R_N")
	)
	(segment
		(start 245.571772 -328.60742)
		(end 250.189238 -323.989954)
		(width 0.13208)
		(layer "F.Cu")
		(net "HSC_D_OC_BUF_R_N")
	)
	(segment
		(start 245.103396 -229.23246)
		(end 245.103396 -220.50375)
		(width 0.13208)
		(layer "F.Cu")
		(net "HSC_D_OC_BUF_R_N")
	)
	(segment
		(start 322.92671 -215.423496)
		(end 322.932044 -215.42883)
		(width 0.13208)
		(layer "F.Cu")
		(net "HSC_D_OC_BUF_R_N")
	)
	(segment
		(start 204.761592 -349.302832)
		(end 204.761592 -348.53753)
		(width 0.13208)
		(layer "F.Cu")
		(net "HSC_D_OC_BUF_R_N")
	)
	(segment
		(start 233.528108 -331.917294)
		(end 236.837982 -328.60742)
		(width 0.13208)
		(layer "F.Cu")
		(net "HSC_D_OC_BUF_R_N")
	)
	(segment
		(start 252.5268 -248.075958)
		(end 250.203462 -245.75262)
		(width 0.13208)
		(layer "F.Cu")
		(net "HSC_D_OC_BUF_R_N")
	)
	(segment
		(start 261.1501 -217.32367)
		(end 261.597902 -216.875868)
		(width 0.13208)
		(layer "F.Cu")
		(net "HSC_D_OC_BUF_R_N")
	)
	(segment
		(start 257.696462 -279.362662)
		(end 253.783846 -275.450046)
		(width 0.13208)
		(layer "F.Cu")
		(net "HSC_D_OC_BUF_R_N")
	)
	(segment
		(start 250.203462 -235.382054)
		(end 244.869462 -230.048054)
		(width 0.13208)
		(layer "F.Cu")
		(net "HSC_D_OC_BUF_R_N")
	)
	(segment
		(start 322.932044 -215.42883)
		(end 323.493384 -215.42883)
		(width 0.13208)
		(layer "F.Cu")
		(net "HSC_D_OC_BUF_R_N")
	)
	(segment
		(start 204.761592 -348.53753)
		(end 205.200504 -348.098618)
		(width 0.13208)
		(layer "F.Cu")
		(net "HSC_D_OC_BUF_R_N")
	)
	(segment
		(start 251.488956 -216.3318)
		(end 251.576078 -216.418922)
		(width 0.13208)
		(layer "F.Cu")
		(net "HSC_D_OC_BUF_R_N")
	)
	(segment
		(start 245.360952 -220.246194)
		(end 246.042688 -220.246194)
		(width 0.13208)
		(layer "F.Cu")
		(net "HSC_D_OC_BUF_R_N")
	)
	(segment
		(start 261.597902 -216.875868)
		(end 261.597902 -215.194388)
		(width 0.13208)
		(layer "F.Cu")
		(net "HSC_D_OC_BUF_R_N")
	)
	(segment
		(start 252.926088 -258.902962)
		(end 252.926088 -257.601974)
		(width 0.13208)
		(layer "F.Cu")
		(net "HSC_D_OC_BUF_R_N")
	)
	(segment
		(start 322.485766 -215.423496)
		(end 322.92671 -215.423496)
		(width 0.13208)
		(layer "F.Cu")
		(net "HSC_D_OC_BUF_R_N")
	)
	(segment
		(start 244.869462 -230.048054)
		(end 244.869462 -229.617016)
		(width 0.13208)
		(layer "F.Cu")
		(net "HSC_D_OC_BUF_R_N")
	)
	(segment
		(start 206.045816 -348.098618)
		(end 222.22714 -331.917294)
		(width 0.13208)
		(layer "F.Cu")
		(net "HSC_D_OC_BUF_R_N")
	)
	(segment
		(start 252.5268 -257.202686)
		(end 252.5268 -248.075958)
		(width 0.13208)
		(layer "F.Cu")
		(net "HSC_D_OC_BUF_R_N")
	)
	(segment
		(start 245.103396 -220.50375)
		(end 245.360952 -220.246194)
		(width 0.13208)
		(layer "F.Cu")
		(net "HSC_D_OC_BUF_R_N")
	)
	(segment
		(start 252.273054 -307.747924)
		(end 257.696462 -302.324516)
		(width 0.13208)
		(layer "F.Cu")
		(net "HSC_D_OC_BUF_R_N")
	)
	(segment
		(start 248.490486 -216.972642)
		(end 249.131328 -216.3318)
		(width 0.13208)
		(layer "F.Cu")
		(net "HSC_D_OC_BUF_R_N")
	)
	(segment
		(start 252.926088 -257.601974)
		(end 252.5268 -257.202686)
		(width 0.13208)
		(layer "F.Cu")
		(net "HSC_D_OC_BUF_R_N")
	)
	(segment
		(start 252.273054 -318.958722)
		(end 252.273054 -307.747924)
		(width 0.13208)
		(layer "F.Cu")
		(net "HSC_D_OC_BUF_R_N")
	)
	(segment
		(start 248.490486 -217.798396)
		(end 248.490486 -216.972642)
		(width 0.13208)
		(layer "F.Cu")
		(net "HSC_D_OC_BUF_R_N")
	)
	(segment
		(start 222.22714 -331.917294)
		(end 233.528108 -331.917294)
		(width 0.13208)
		(layer "F.Cu")
		(net "HSC_D_OC_BUF_R_N")
	)
	(segment
		(start 251.576078 -216.418922)
		(end 253.844552 -216.418922)
		(width 0.13208)
		(layer "F.Cu")
		(net "HSC_D_OC_BUF_R_N")
	)
	(segment
		(start 250.203462 -245.75262)
		(end 250.203462 -235.382054)
		(width 0.13208)
		(layer "F.Cu")
		(net "HSC_D_OC_BUF_R_N")
	)
	(segment
		(start 253.23292 -260.48589)
		(end 253.23292 -259.64388)
		(width 0.13208)
		(layer "F.Cu")
		(net "HSC_D_OC_BUF_R_N")
	)
	(segment
		(start 253.844552 -216.418922)
		(end 254.7493 -217.32367)
		(width 0.13208)
		(layer "F.Cu")
		(net "HSC_D_OC_BUF_R_N")
	)
	(segment
		(start 204.761592 -349.912432)
		(end 204.761592 -349.302832)
		(width 0.13208)
		(layer "F.Cu")
		(net "HSC_D_OC_BUF_R_N")
	)
	(segment
		(start 246.042688 -220.246194)
		(end 248.490486 -217.798396)
		(width 0.13208)
		(layer "F.Cu")
		(net "HSC_D_OC_BUF_R_N")
	)
	(segment
		(start 250.189238 -323.989954)
		(end 252.273054 -318.958722)
		(width 0.13208)
		(layer "F.Cu")
		(net "HSC_D_OC_BUF_R_N")
	)
	(segment
		(start 257.696462 -302.324516)
		(end 257.696462 -279.362662)
		(width 0.13208)
		(layer "F.Cu")
		(net "HSC_D_OC_BUF_R_N")
	)
	(segment
		(start 249.131328 -216.3318)
		(end 251.488956 -216.3318)
		(width 0.13208)
		(layer "F.Cu")
		(net "HSC_D_OC_BUF_R_N")
	)
	(segment
		(start 244.869462 -229.617016)
		(end 244.976142 -229.359714)
		(width 0.13208)
		(layer "F.Cu")
		(net "HSC_D_OC_BUF_R_N")
	)
	(via
		(at 261.597902 -216.875868)
		(size 0.762)
		(drill 0.381)
		(layers "F.Cu" "B.Cu")
		(net "HSC_D_OC_BUF_R_N")
	)
	(via
		(at 204.761592 -349.302832)
		(size 0.508)
		(drill 0.254)
		(layers "F.Cu" "B.Cu")
		(net "HSC_D_OC_BUF_R_N")
	)
	(via
		(at 322.485766 -215.423496)
		(size 0.508)
		(drill 0.254)
		(layers "F.Cu" "B.Cu")
		(net "HSC_D_OC_BUF_R_N")
	)
	(via
		(at 251.576078 -216.418922)
		(size 0.508)
		(drill 0.254)
		(layers "F.Cu" "B.Cu")
		(net "HSC_D_OC_BUF_R_N")
	)
	(segment
		(start 211.075778 -342.988646)
		(end 221.59849 -342.988646)
		(width 0.13208)
		(layer "B.Cu")
		(net "HSC_D_OC_BUF_R_N")
	)
	(segment
		(start 256.97053 -347.616526)
		(end 256.97053 -350.59874)
		(width 0.13208)
		(layer "B.Cu")
		(net "HSC_D_OC_BUF_R_N")
	)
	(segment
		(start 251.051822 -344.57513)
		(end 252.541024 -346.064332)
		(width 0.13208)
		(layer "B.Cu")
		(net "HSC_D_OC_BUF_R_N")
	)
	(segment
		(start 253.459742 -354.109528)
		(end 252.85192 -354.109528)
		(width 0.13208)
		(layer "B.Cu")
		(net "HSC_D_OC_BUF_R_N")
	)
	(segment
		(start 253.959868 -346.064332)
		(end 255.075182 -347.179646)
		(width 0.13208)
		(layer "B.Cu")
		(net "HSC_D_OC_BUF_R_N")
	)
	(segment
		(start 204.761592 -349.302832)
		(end 211.075778 -342.988646)
		(width 0.13208)
		(layer "B.Cu")
		(net "HSC_D_OC_BUF_R_N")
	)
	(segment
		(start 221.59849 -342.988646)
		(end 223.184974 -344.57513)
		(width 0.13208)
		(layer "B.Cu")
		(net "HSC_D_OC_BUF_R_N")
	)
	(segment
		(start 256.97053 -350.59874)
		(end 253.459742 -354.109528)
		(width 0.13208)
		(layer "B.Cu")
		(net "HSC_D_OC_BUF_R_N")
	)
	(segment
		(start 252.834648 -354.1268)
		(end 252.41885 -354.1268)
		(width 0.13208)
		(layer "B.Cu")
		(net "HSC_D_OC_BUF_R_N")
	)
	(segment
		(start 256.53365 -347.179646)
		(end 256.97053 -347.616526)
		(width 0.13208)
		(layer "B.Cu")
		(net "HSC_D_OC_BUF_R_N")
	)
	(segment
		(start 223.184974 -344.57513)
		(end 251.051822 -344.57513)
		(width 0.13208)
		(layer "B.Cu")
		(net "HSC_D_OC_BUF_R_N")
	)
	(segment
		(start 252.85192 -354.109528)
		(end 252.834648 -354.1268)
		(width 0.13208)
		(layer "B.Cu")
		(net "HSC_D_OC_BUF_R_N")
	)
	(segment
		(start 252.541024 -346.064332)
		(end 253.959868 -346.064332)
		(width 0.13208)
		(layer "B.Cu")
		(net "HSC_D_OC_BUF_R_N")
	)
	(segment
		(start 255.075182 -347.179646)
		(end 256.53365 -347.179646)
		(width 0.13208)
		(layer "B.Cu")
		(net "HSC_D_OC_BUF_R_N")
	)
	(segment
		(start 256.656586 -215.47963)
		(end 256.086356 -214.9094)
		(width 0.15494)
		(layer "In15.Cu")
		(net "HSC_D_OC_BUF_R_N")
	)
	(segment
		(start 286.595566 -218.08567)
		(end 266.436856 -218.08567)
		(width 0.15494)
		(layer "In15.Cu")
		(net "HSC_D_OC_BUF_R_N")
	)
	(segment
		(start 291.691568 -212.989668)
		(end 286.595566 -218.08567)
		(width 0.15494)
		(layer "In15.Cu")
		(net "HSC_D_OC_BUF_R_N")
	)
	(segment
		(start 261.422388 -217.527632)
		(end 260.309614 -216.414858)
		(width 0.15494)
		(layer "In15.Cu")
		(net "HSC_D_OC_BUF_R_N")
	)
	(segment
		(start 262.725662 -217.527632)
		(end 261.422388 -217.527632)
		(width 0.15494)
		(layer "In15.Cu")
		(net "HSC_D_OC_BUF_R_N")
	)
	(segment
		(start 259.04063 -216.414858)
		(end 258.105402 -215.47963)
		(width 0.15494)
		(layer "In15.Cu")
		(net "HSC_D_OC_BUF_R_N")
	)
	(segment
		(start 260.309614 -216.414858)
		(end 259.04063 -216.414858)
		(width 0.15494)
		(layer "In15.Cu")
		(net "HSC_D_OC_BUF_R_N")
	)
	(segment
		(start 258.105402 -215.47963)
		(end 256.656586 -215.47963)
		(width 0.15494)
		(layer "In15.Cu")
		(net "HSC_D_OC_BUF_R_N")
	)
	(segment
		(start 265.758422 -217.407236)
		(end 262.846058 -217.407236)
		(width 0.15494)
		(layer "In15.Cu")
		(net "HSC_D_OC_BUF_R_N")
	)
	(segment
		(start 262.846058 -217.407236)
		(end 262.725662 -217.527632)
		(width 0.15494)
		(layer "In15.Cu")
		(net "HSC_D_OC_BUF_R_N")
	)
	(segment
		(start 320.051938 -212.989668)
		(end 291.691568 -212.989668)
		(width 0.15494)
		(layer "In15.Cu")
		(net "HSC_D_OC_BUF_R_N")
	)
	(segment
		(start 266.436856 -218.08567)
		(end 265.758422 -217.407236)
		(width 0.15494)
		(layer "In15.Cu")
		(net "HSC_D_OC_BUF_R_N")
	)
	(segment
		(start 256.086356 -214.9094)
		(end 253.0856 -214.9094)
		(width 0.15494)
		(layer "In15.Cu")
		(net "HSC_D_OC_BUF_R_N")
	)
	(segment
		(start 322.485766 -215.423496)
		(end 320.051938 -212.989668)
		(width 0.15494)
		(layer "In15.Cu")
		(net "HSC_D_OC_BUF_R_N")
	)
	(segment
		(start 253.0856 -214.9094)
		(end 251.576078 -216.418922)
		(width 0.15494)
		(layer "In15.Cu")
		(net "HSC_D_OC_BUF_R_N")
	)
	(segment
		(start 204.761592 -350.712532)
		(end 204.761592 -351.46361)
		(width 0.13208)
		(layer "F.Cu")
		(net "HSC_D_OC_BUF_N")
	)
	(segment
		(start 204.761592 -350.712532)
		(end 205.777592 -350.712532)
		(width 0.13208)
		(layer "F.Cu")
		(net "HSC_D_OC_BUF_N")
	)
	(segment
		(start 204.804772 -352.51771)
		(end 204.804772 -351.50679)
		(width 0.13208)
		(layer "F.Cu")
		(net "HSC_D_OC_BUF_N")
	)
	(segment
		(start 204.804772 -351.50679)
		(end 204.761592 -351.46361)
		(width 0.13208)
		(layer "F.Cu")
		(net "HSC_D_OC_BUF_N")
	)
	(via
		(at 204.761592 -351.46361)
		(size 0.508)
		(drill 0.254)
		(layers "F.Cu" "B.Cu")
		(net "HSC_D_OC_BUF_N")
	)
	(segment
		(start 336.493866 -217.587068)
		(end 336.093816 -217.187018)
		(width 0.13208)
		(layer "F.Cu")
		(net "Net_1180")
	)
	(via
		(at 336.093816 -217.187018)
		(size 0.4572)
		(drill 0.254)
		(layers "F.Cu" "B.Cu")
		(net "Net_1180")
	)
	(segment
		(start 334.89392 -218.387168)
		(end 334.494124 -217.987372)
		(width 0.13208)
		(layer "F.Cu")
		(net "Net_1184")
	)
	(via
		(at 334.494124 -217.987372)
		(size 0.4572)
		(drill 0.254)
		(layers "F.Cu" "B.Cu")
		(net "Net_1184")
	)
	(segment
		(start 334.09382 -216.786968)
		(end 333.694024 -217.186764)
		(width 0.13208)
		(layer "F.Cu")
		(net "Net_1192")
	)
	(via
		(at 333.694024 -217.186764)
		(size 0.4572)
		(drill 0.254)
		(layers "F.Cu" "B.Cu")
		(net "Net_1192")
	)
	(segment
		(start 172.994066 -35.264852)
		(end 172.384466 -35.264852)
		(width 0.13208)
		(layer "F.Cu")
		(net "RST_SMB_SSD6_ISO_N")
	)
	(segment
		(start 173.00194 -33.249362)
		(end 172.994066 -33.257236)
		(width 0.13208)
		(layer "F.Cu")
		(net "RST_SMB_SSD6_ISO_N")
	)
	(segment
		(start 171.495212 -35.137852)
		(end 171.495212 -34.732468)
		(width 0.13208)
		(layer "F.Cu")
		(net "RST_SMB_SSD6_ISO_N")
	)
	(segment
		(start 172.994066 -33.257236)
		(end 172.994066 -34.248852)
		(width 0.13208)
		(layer "F.Cu")
		(net "RST_SMB_SSD6_ISO_N")
	)
	(segment
		(start 171.622212 -35.264852)
		(end 171.495212 -35.137852)
		(width 0.13208)
		(layer "F.Cu")
		(net "RST_SMB_SSD6_ISO_N")
	)
	(segment
		(start 172.994066 -34.248852)
		(end 172.994066 -35.264852)
		(width 0.13208)
		(layer "F.Cu")
		(net "RST_SMB_SSD6_ISO_N")
	)
	(segment
		(start 172.384466 -35.264852)
		(end 171.622212 -35.264852)
		(width 0.13208)
		(layer "F.Cu")
		(net "RST_SMB_SSD6_ISO_N")
	)
	(via
		(at 172.384466 -35.264852)
		(size 0.508)
		(drill 0.254)
		(layers "F.Cu" "B.Cu")
		(net "RST_SMB_SSD6_ISO_N")
	)
	(segment
		(start 202.04303 -90.6653)
		(end 203.559918 -90.6653)
		(width 0.13208)
		(layer "F.Cu")
		(net "IRQ_SSD_LED_IOEXP_R_N")
	)
	(segment
		(start 205.231746 -88.993472)
		(end 206.223108 -88.993472)
		(width 0.13208)
		(layer "F.Cu")
		(net "IRQ_SSD_LED_IOEXP_R_N")
	)
	(segment
		(start 225.067622 -214.304118)
		(end 224.667826 -213.904322)
		(width 0.13208)
		(layer "F.Cu")
		(net "IRQ_SSD_LED_IOEXP_R_N")
	)
	(segment
		(start 203.559918 -90.6653)
		(end 205.231746 -88.993472)
		(width 0.13208)
		(layer "F.Cu")
		(net "IRQ_SSD_LED_IOEXP_R_N")
	)
	(via
		(at 229.321614 -178.73091)
		(size 0.508)
		(drill 0.254)
		(layers "F.Cu" "B.Cu")
		(net "IRQ_SSD_LED_IOEXP_R_N")
	)
	(via
		(at 224.667826 -213.904322)
		(size 0.4572)
		(drill 0.254)
		(layers "F.Cu" "B.Cu")
		(net "IRQ_SSD_LED_IOEXP_R_N")
	)
	(via
		(at 209.21218 -180.477668)
		(size 0.508)
		(drill 0.254)
		(layers "F.Cu" "B.Cu")
		(net "IRQ_SSD_LED_IOEXP_R_N")
	)
	(via
		(at 202.04303 -90.6653)
		(size 0.508)
		(drill 0.254)
		(layers "F.Cu" "B.Cu")
		(net "IRQ_SSD_LED_IOEXP_R_N")
	)
	(segment
		(start 199.582532 -103.098854)
		(end 199.582532 -93.125798)
		(width 0.15494)
		(layer "In5.Cu")
		(net "IRQ_SSD_LED_IOEXP_R_N")
	)
	(segment
		(start 205.667102 -131.930902)
		(end 205.667102 -129.645156)
		(width 0.15494)
		(layer "In5.Cu")
		(net "IRQ_SSD_LED_IOEXP_R_N")
	)
	(segment
		(start 209.804 -136.0678)
		(end 205.667102 -131.930902)
		(width 0.15494)
		(layer "In5.Cu")
		(net "IRQ_SSD_LED_IOEXP_R_N")
	)
	(segment
		(start 202.80122 -106.317542)
		(end 199.582532 -103.098854)
		(width 0.15494)
		(layer "In5.Cu")
		(net "IRQ_SSD_LED_IOEXP_R_N")
	)
	(segment
		(start 205.667102 -129.645156)
		(end 202.80122 -126.779274)
		(width 0.15494)
		(layer "In5.Cu")
		(net "IRQ_SSD_LED_IOEXP_R_N")
	)
	(segment
		(start 209.21218 -180.477668)
		(end 209.804 -179.885848)
		(width 0.15494)
		(layer "In5.Cu")
		(net "IRQ_SSD_LED_IOEXP_R_N")
	)
	(segment
		(start 202.80122 -126.779274)
		(end 202.80122 -106.317542)
		(width 0.15494)
		(layer "In5.Cu")
		(net "IRQ_SSD_LED_IOEXP_R_N")
	)
	(segment
		(start 209.804 -179.885848)
		(end 209.804 -136.0678)
		(width 0.15494)
		(layer "In5.Cu")
		(net "IRQ_SSD_LED_IOEXP_R_N")
	)
	(segment
		(start 199.582532 -93.125798)
		(end 202.04303 -90.6653)
		(width 0.15494)
		(layer "In5.Cu")
		(net "IRQ_SSD_LED_IOEXP_R_N")
	)
	(segment
		(start 233.753914 -204.206602)
		(end 233.175556 -204.78496)
		(width 0.15494)
		(layer "In7.Cu")
		(net "IRQ_SSD_LED_IOEXP_R_N")
	)
	(segment
		(start 240.1316 -197.157594)
		(end 239.968532 -197.320662)
		(width 0.15494)
		(layer "In7.Cu")
		(net "IRQ_SSD_LED_IOEXP_R_N")
	)
	(segment
		(start 237.786164 -199.50303)
		(end 235.137706 -202.151488)
		(width 0.15494)
		(layer "In7.Cu")
		(net "IRQ_SSD_LED_IOEXP_R_N")
	)
	(segment
		(start 234.42422 -202.151488)
		(end 233.753914 -202.821794)
		(width 0.15494)
		(layer "In7.Cu")
		(net "IRQ_SSD_LED_IOEXP_R_N")
	)
	(segment
		(start 233.695494 -184.233058)
		(end 240.1316 -190.669164)
		(width 0.15494)
		(layer "In7.Cu")
		(net "IRQ_SSD_LED_IOEXP_R_N")
	)
	(segment
		(start 230.461312 -207.713326)
		(end 229.37343 -208.801208)
		(width 0.15494)
		(layer "In7.Cu")
		(net "IRQ_SSD_LED_IOEXP_R_N")
	)
	(segment
		(start 240.1316 -190.669164)
		(end 240.1316 -197.157594)
		(width 0.15494)
		(layer "In7.Cu")
		(net "IRQ_SSD_LED_IOEXP_R_N")
	)
	(segment
		(start 233.753914 -202.821794)
		(end 233.753914 -204.206602)
		(width 0.15494)
		(layer "In7.Cu")
		(net "IRQ_SSD_LED_IOEXP_R_N")
	)
	(segment
		(start 229.321614 -181.388258)
		(end 230.395526 -182.46217)
		(width 0.15494)
		(layer "In7.Cu")
		(net "IRQ_SSD_LED_IOEXP_R_N")
	)
	(segment
		(start 225.066098 -210.11769)
		(end 225.066098 -211.248498)
		(width 0.15494)
		(layer "In7.Cu")
		(net "IRQ_SSD_LED_IOEXP_R_N")
	)
	(segment
		(start 239.968532 -197.322186)
		(end 237.787688 -199.50303)
		(width 0.15494)
		(layer "In7.Cu")
		(net "IRQ_SSD_LED_IOEXP_R_N")
	)
	(segment
		(start 226.38258 -208.801208)
		(end 225.066098 -210.11769)
		(width 0.15494)
		(layer "In7.Cu")
		(net "IRQ_SSD_LED_IOEXP_R_N")
	)
	(segment
		(start 233.175556 -204.78496)
		(end 231.145588 -204.78496)
		(width 0.15494)
		(layer "In7.Cu")
		(net "IRQ_SSD_LED_IOEXP_R_N")
	)
	(segment
		(start 232.865168 -182.46217)
		(end 233.695494 -183.292496)
		(width 0.15494)
		(layer "In7.Cu")
		(net "IRQ_SSD_LED_IOEXP_R_N")
	)
	(segment
		(start 239.968532 -197.320662)
		(end 239.968532 -197.322186)
		(width 0.15494)
		(layer "In7.Cu")
		(net "IRQ_SSD_LED_IOEXP_R_N")
	)
	(segment
		(start 231.145588 -204.78496)
		(end 230.461312 -205.469236)
		(width 0.15494)
		(layer "In7.Cu")
		(net "IRQ_SSD_LED_IOEXP_R_N")
	)
	(segment
		(start 233.695494 -183.292496)
		(end 233.695494 -184.233058)
		(width 0.15494)
		(layer "In7.Cu")
		(net "IRQ_SSD_LED_IOEXP_R_N")
	)
	(segment
		(start 224.667826 -213.457028)
		(end 224.667826 -213.904322)
		(width 0.15494)
		(layer "In7.Cu")
		(net "IRQ_SSD_LED_IOEXP_R_N")
	)
	(segment
		(start 237.787688 -199.50303)
		(end 237.786164 -199.50303)
		(width 0.15494)
		(layer "In7.Cu")
		(net "IRQ_SSD_LED_IOEXP_R_N")
	)
	(segment
		(start 229.321614 -178.73091)
		(end 229.321614 -181.388258)
		(width 0.15494)
		(layer "In7.Cu")
		(net "IRQ_SSD_LED_IOEXP_R_N")
	)
	(segment
		(start 225.53422 -211.71662)
		(end 225.53422 -212.590634)
		(width 0.15494)
		(layer "In7.Cu")
		(net "IRQ_SSD_LED_IOEXP_R_N")
	)
	(segment
		(start 225.53422 -212.590634)
		(end 224.667826 -213.457028)
		(width 0.15494)
		(layer "In7.Cu")
		(net "IRQ_SSD_LED_IOEXP_R_N")
	)
	(segment
		(start 225.066098 -211.248498)
		(end 225.53422 -211.71662)
		(width 0.15494)
		(layer "In7.Cu")
		(net "IRQ_SSD_LED_IOEXP_R_N")
	)
	(segment
		(start 229.37343 -208.801208)
		(end 226.38258 -208.801208)
		(width 0.15494)
		(layer "In7.Cu")
		(net "IRQ_SSD_LED_IOEXP_R_N")
	)
	(segment
		(start 230.461312 -205.469236)
		(end 230.461312 -207.713326)
		(width 0.15494)
		(layer "In7.Cu")
		(net "IRQ_SSD_LED_IOEXP_R_N")
	)
	(segment
		(start 230.395526 -182.46217)
		(end 232.865168 -182.46217)
		(width 0.15494)
		(layer "In7.Cu")
		(net "IRQ_SSD_LED_IOEXP_R_N")
	)
	(segment
		(start 235.137706 -202.151488)
		(end 234.42422 -202.151488)
		(width 0.15494)
		(layer "In7.Cu")
		(net "IRQ_SSD_LED_IOEXP_R_N")
	)
	(segment
		(start 211.636864 -181.946042)
		(end 211.636864 -180.787294)
		(width 0.15494)
		(layer "In13.Cu")
		(net "IRQ_SSD_LED_IOEXP_R_N")
	)
	(segment
		(start 223.447102 -181.845712)
		(end 220.72346 -184.569354)
		(width 0.15494)
		(layer "In13.Cu")
		(net "IRQ_SSD_LED_IOEXP_R_N")
	)
	(segment
		(start 211.636864 -180.787294)
		(end 211.327238 -180.477668)
		(width 0.15494)
		(layer "In13.Cu")
		(net "IRQ_SSD_LED_IOEXP_R_N")
	)
	(segment
		(start 226.750626 -181.301898)
		(end 224.94748 -181.301898)
		(width 0.15494)
		(layer "In13.Cu")
		(net "IRQ_SSD_LED_IOEXP_R_N")
	)
	(segment
		(start 224.403666 -181.845712)
		(end 223.447102 -181.845712)
		(width 0.15494)
		(layer "In13.Cu")
		(net "IRQ_SSD_LED_IOEXP_R_N")
	)
	(segment
		(start 224.94748 -181.301898)
		(end 224.403666 -181.845712)
		(width 0.15494)
		(layer "In13.Cu")
		(net "IRQ_SSD_LED_IOEXP_R_N")
	)
	(segment
		(start 220.72346 -184.569354)
		(end 214.260176 -184.569354)
		(width 0.15494)
		(layer "In13.Cu")
		(net "IRQ_SSD_LED_IOEXP_R_N")
	)
	(segment
		(start 214.260176 -184.569354)
		(end 211.636864 -181.946042)
		(width 0.15494)
		(layer "In13.Cu")
		(net "IRQ_SSD_LED_IOEXP_R_N")
	)
	(segment
		(start 229.321614 -178.73091)
		(end 226.750626 -181.301898)
		(width 0.15494)
		(layer "In13.Cu")
		(net "IRQ_SSD_LED_IOEXP_R_N")
	)
	(segment
		(start 211.327238 -180.477668)
		(end 209.21218 -180.477668)
		(width 0.15494)
		(layer "In13.Cu")
		(net "IRQ_SSD_LED_IOEXP_R_N")
	)
	(segment
		(start 166.468298 -36.10991)
		(end 166.41064 -36.167568)
		(width 0.13208)
		(layer "F.Cu")
		(net "RST_SMB_SSD6_N")
	)
	(segment
		(start 168.596564 -36.10991)
		(end 166.468298 -36.10991)
		(width 0.13208)
		(layer "F.Cu")
		(net "RST_SMB_SSD6_N")
	)
	(segment
		(start 166.41064 -36.453572)
		(end 166.89324 -36.453572)
		(width 0.13208)
		(layer "F.Cu")
		(net "RST_SMB_SSD6_N")
	)
	(segment
		(start 170.2308 -35.649154)
		(end 170.2308 -36.6776)
		(width 0.13208)
		(layer "F.Cu")
		(net "RST_SMB_SSD6_N")
	)
	(segment
		(start 170.1038 -36.8046)
		(end 169.291254 -36.8046)
		(width 0.13208)
		(layer "F.Cu")
		(net "RST_SMB_SSD6_N")
	)
	(segment
		(start 166.89324 -36.453572)
		(end 166.98214 -36.542472)
		(width 0.13208)
		(layer "F.Cu")
		(net "RST_SMB_SSD6_N")
	)
	(segment
		(start 170.064176 -35.48253)
		(end 170.2308 -35.649154)
		(width 0.13208)
		(layer "F.Cu")
		(net "RST_SMB_SSD6_N")
	)
	(segment
		(start 169.291254 -36.8046)
		(end 168.596564 -36.10991)
		(width 0.13208)
		(layer "F.Cu")
		(net "RST_SMB_SSD6_N")
	)
	(segment
		(start 170.2308 -36.6776)
		(end 170.1038 -36.8046)
		(width 0.13208)
		(layer "F.Cu")
		(net "RST_SMB_SSD6_N")
	)
	(segment
		(start 169.695368 -35.48253)
		(end 170.064176 -35.48253)
		(width 0.13208)
		(layer "F.Cu")
		(net "RST_SMB_SSD6_N")
	)
	(segment
		(start 166.41064 -36.167568)
		(end 166.41064 -36.453572)
		(width 0.13208)
		(layer "F.Cu")
		(net "RST_SMB_SSD6_N")
	)
	(segment
		(start 166.98214 -36.542472)
		(end 166.98214 -37.025072)
		(width 0.13208)
		(layer "F.Cu")
		(net "RST_SMB_SSD6_N")
	)
	(via
		(at 166.41064 -36.453572)
		(size 0.508)
		(drill 0.254)
		(layers "F.Cu" "B.Cu")
		(net "RST_SMB_SSD6_N")
	)
	(segment
		(start 147.001992 -32.449262)
		(end 147.001992 -32.083502)
		(width 0.13208)
		(layer "F.Cu")
		(net "RST_SMB_SSD5_ISO_R_N")
	)
	(segment
		(start 152.764998 -23.589996)
		(end 150.501096 -23.589996)
		(width 0.13208)
		(layer "F.Cu")
		(net "RST_SMB_SSD5_ISO_R_N")
	)
	(segment
		(start 147.001992 -32.083502)
		(end 147.308316 -31.777178)
		(width 0.13208)
		(layer "F.Cu")
		(net "RST_SMB_SSD5_ISO_R_N")
	)
	(segment
		(start 150.501096 -23.589996)
		(end 149.932898 -24.158194)
		(width 0.13208)
		(layer "F.Cu")
		(net "RST_SMB_SSD5_ISO_R_N")
	)
	(via
		(at 147.308316 -31.777178)
		(size 0.508)
		(drill 0.254)
		(layers "F.Cu" "B.Cu")
		(net "RST_SMB_SSD5_ISO_R_N")
	)
	(via
		(at 149.932898 -24.158194)
		(size 0.508)
		(drill 0.254)
		(layers "F.Cu" "B.Cu")
		(net "RST_SMB_SSD5_ISO_R_N")
	)
	(segment
		(start 149.932898 -27.02306)
		(end 149.932898 -24.158194)
		(width 0.15494)
		(layer "In5.Cu")
		(net "RST_SMB_SSD5_ISO_R_N")
	)
	(segment
		(start 147.308316 -29.647642)
		(end 149.932898 -27.02306)
		(width 0.15494)
		(layer "In5.Cu")
		(net "RST_SMB_SSD5_ISO_R_N")
	)
	(segment
		(start 147.308316 -31.777178)
		(end 147.308316 -29.647642)
		(width 0.15494)
		(layer "In5.Cu")
		(net "RST_SMB_SSD5_ISO_R_N")
	)
	(segment
		(start 353.201986 -32.083502)
		(end 353.50831 -31.777178)
		(width 0.13208)
		(layer "F.Cu")
		(net "RST_SMB_SSD12_ISO_R_N")
	)
	(segment
		(start 353.201986 -32.449262)
		(end 353.201986 -32.083502)
		(width 0.13208)
		(layer "F.Cu")
		(net "RST_SMB_SSD12_ISO_R_N")
	)
	(segment
		(start 356.70109 -23.589996)
		(end 356.132892 -24.158194)
		(width 0.13208)
		(layer "F.Cu")
		(net "RST_SMB_SSD12_ISO_R_N")
	)
	(segment
		(start 358.964992 -23.589996)
		(end 356.70109 -23.589996)
		(width 0.13208)
		(layer "F.Cu")
		(net "RST_SMB_SSD12_ISO_R_N")
	)
	(via
		(at 353.50831 -31.777178)
		(size 0.508)
		(drill 0.254)
		(layers "F.Cu" "B.Cu")
		(net "RST_SMB_SSD12_ISO_R_N")
	)
	(via
		(at 356.132892 -24.158194)
		(size 0.508)
		(drill 0.254)
		(layers "F.Cu" "B.Cu")
		(net "RST_SMB_SSD12_ISO_R_N")
	)
	(segment
		(start 353.50831 -31.777178)
		(end 353.50831 -29.571188)
		(width 0.15494)
		(layer "In5.Cu")
		(net "RST_SMB_SSD12_ISO_R_N")
	)
	(segment
		(start 353.50831 -29.571188)
		(end 356.132892 -26.946606)
		(width 0.15494)
		(layer "In5.Cu")
		(net "RST_SMB_SSD12_ISO_R_N")
	)
	(segment
		(start 356.132892 -26.946606)
		(end 356.132892 -24.158194)
		(width 0.15494)
		(layer "In5.Cu")
		(net "RST_SMB_SSD12_ISO_R_N")
	)
	(segment
		(start 405.201882 -32.449262)
		(end 405.201882 -32.083502)
		(width 0.13208)
		(layer "F.Cu")
		(net "RST_SMB_SSD14_ISO_R_N")
	)
	(segment
		(start 410.964888 -23.589996)
		(end 408.700986 -23.589996)
		(width 0.13208)
		(layer "F.Cu")
		(net "RST_SMB_SSD14_ISO_R_N")
	)
	(segment
		(start 408.700986 -23.589996)
		(end 408.132788 -24.158194)
		(width 0.13208)
		(layer "F.Cu")
		(net "RST_SMB_SSD14_ISO_R_N")
	)
	(segment
		(start 405.201882 -32.083502)
		(end 405.508206 -31.777178)
		(width 0.13208)
		(layer "F.Cu")
		(net "RST_SMB_SSD14_ISO_R_N")
	)
	(via
		(at 405.508206 -31.777178)
		(size 0.508)
		(drill 0.254)
		(layers "F.Cu" "B.Cu")
		(net "RST_SMB_SSD14_ISO_R_N")
	)
	(via
		(at 408.132788 -24.158194)
		(size 0.508)
		(drill 0.254)
		(layers "F.Cu" "B.Cu")
		(net "RST_SMB_SSD14_ISO_R_N")
	)
	(segment
		(start 405.508206 -31.777178)
		(end 405.508206 -29.616908)
		(width 0.15494)
		(layer "In5.Cu")
		(net "RST_SMB_SSD14_ISO_R_N")
	)
	(segment
		(start 405.508206 -29.616908)
		(end 408.132788 -26.992326)
		(width 0.15494)
		(layer "In5.Cu")
		(net "RST_SMB_SSD14_ISO_R_N")
	)
	(segment
		(start 408.132788 -26.992326)
		(end 408.132788 -24.158194)
		(width 0.15494)
		(layer "In5.Cu")
		(net "RST_SMB_SSD14_ISO_R_N")
	)
	(segment
		(start 146.384518 -35.264852)
		(end 146.994118 -35.264852)
		(width 0.13208)
		(layer "F.Cu")
		(net "RST_SMB_SSD5_ISO_N")
	)
	(segment
		(start 146.994118 -34.248852)
		(end 146.994118 -35.264852)
		(width 0.13208)
		(layer "F.Cu")
		(net "RST_SMB_SSD5_ISO_N")
	)
	(segment
		(start 145.622264 -35.264852)
		(end 146.384518 -35.264852)
		(width 0.13208)
		(layer "F.Cu")
		(net "RST_SMB_SSD5_ISO_N")
	)
	(segment
		(start 147.001992 -33.249362)
		(end 146.994118 -33.257236)
		(width 0.13208)
		(layer "F.Cu")
		(net "RST_SMB_SSD5_ISO_N")
	)
	(segment
		(start 145.495264 -34.732468)
		(end 145.495264 -35.137852)
		(width 0.13208)
		(layer "F.Cu")
		(net "RST_SMB_SSD5_ISO_N")
	)
	(segment
		(start 145.495264 -35.137852)
		(end 145.622264 -35.264852)
		(width 0.13208)
		(layer "F.Cu")
		(net "RST_SMB_SSD5_ISO_N")
	)
	(segment
		(start 146.994118 -33.257236)
		(end 146.994118 -34.248852)
		(width 0.13208)
		(layer "F.Cu")
		(net "RST_SMB_SSD5_ISO_N")
	)
	(via
		(at 146.384518 -35.264852)
		(size 0.508)
		(drill 0.254)
		(layers "F.Cu" "B.Cu")
		(net "RST_SMB_SSD5_ISO_N")
	)
	(segment
		(start 237.101888 -32.083502)
		(end 237.408212 -31.777178)
		(width 0.13208)
		(layer "F.Cu")
		(net "RST_SMB_SSD8_ISO_R_N")
	)
	(segment
		(start 242.864894 -23.589996)
		(end 240.600992 -23.589996)
		(width 0.13208)
		(layer "F.Cu")
		(net "RST_SMB_SSD8_ISO_R_N")
	)
	(segment
		(start 237.101888 -32.449262)
		(end 237.101888 -32.083502)
		(width 0.13208)
		(layer "F.Cu")
		(net "RST_SMB_SSD8_ISO_R_N")
	)
	(segment
		(start 240.600992 -23.589996)
		(end 240.032794 -24.158194)
		(width 0.13208)
		(layer "F.Cu")
		(net "RST_SMB_SSD8_ISO_R_N")
	)
	(via
		(at 240.032794 -24.158194)
		(size 0.508)
		(drill 0.254)
		(layers "F.Cu" "B.Cu")
		(net "RST_SMB_SSD8_ISO_R_N")
	)
	(via
		(at 237.408212 -31.777178)
		(size 0.508)
		(drill 0.254)
		(layers "F.Cu" "B.Cu")
		(net "RST_SMB_SSD8_ISO_R_N")
	)
	(segment
		(start 237.408212 -31.777178)
		(end 237.408212 -29.5783)
		(width 0.15494)
		(layer "In5.Cu")
		(net "RST_SMB_SSD8_ISO_R_N")
	)
	(segment
		(start 240.032794 -26.953718)
		(end 240.032794 -24.158194)
		(width 0.15494)
		(layer "In5.Cu")
		(net "RST_SMB_SSD8_ISO_R_N")
	)
	(segment
		(start 237.408212 -29.5783)
		(end 240.032794 -26.953718)
		(width 0.15494)
		(layer "In5.Cu")
		(net "RST_SMB_SSD8_ISO_R_N")
	)
	(segment
		(start 140.982192 -36.542472)
		(end 140.982192 -37.025072)
		(width 0.13208)
		(layer "F.Cu")
		(net "RST_SMB_SSD5_N")
	)
	(segment
		(start 140.410692 -36.167568)
		(end 140.46835 -36.10991)
		(width 0.13208)
		(layer "F.Cu")
		(net "RST_SMB_SSD5_N")
	)
	(segment
		(start 144.2212 -36.6268)
		(end 144.2212 -35.639502)
		(width 0.13208)
		(layer "F.Cu")
		(net "RST_SMB_SSD5_N")
	)
	(segment
		(start 140.410692 -36.453572)
		(end 140.893292 -36.453572)
		(width 0.13208)
		(layer "F.Cu")
		(net "RST_SMB_SSD5_N")
	)
	(segment
		(start 140.893292 -36.453572)
		(end 140.982192 -36.542472)
		(width 0.13208)
		(layer "F.Cu")
		(net "RST_SMB_SSD5_N")
	)
	(segment
		(start 144.064228 -35.48253)
		(end 143.69542 -35.48253)
		(width 0.13208)
		(layer "F.Cu")
		(net "RST_SMB_SSD5_N")
	)
	(segment
		(start 140.46835 -36.10991)
		(end 142.637256 -36.10991)
		(width 0.13208)
		(layer "F.Cu")
		(net "RST_SMB_SSD5_N")
	)
	(segment
		(start 144.0942 -36.7538)
		(end 144.2212 -36.6268)
		(width 0.13208)
		(layer "F.Cu")
		(net "RST_SMB_SSD5_N")
	)
	(segment
		(start 142.637256 -36.10991)
		(end 143.281146 -36.7538)
		(width 0.13208)
		(layer "F.Cu")
		(net "RST_SMB_SSD5_N")
	)
	(segment
		(start 140.410692 -36.453572)
		(end 140.410692 -36.167568)
		(width 0.13208)
		(layer "F.Cu")
		(net "RST_SMB_SSD5_N")
	)
	(segment
		(start 144.2212 -35.639502)
		(end 144.064228 -35.48253)
		(width 0.13208)
		(layer "F.Cu")
		(net "RST_SMB_SSD5_N")
	)
	(segment
		(start 143.281146 -36.7538)
		(end 144.0942 -36.7538)
		(width 0.13208)
		(layer "F.Cu")
		(net "RST_SMB_SSD5_N")
	)
	(via
		(at 140.410692 -36.453572)
		(size 0.508)
		(drill 0.254)
		(layers "F.Cu" "B.Cu")
		(net "RST_SMB_SSD5_N")
	)
	(segment
		(start 263.101836 -32.449262)
		(end 263.101836 -32.083502)
		(width 0.13208)
		(layer "F.Cu")
		(net "RST_SMB_SSD9_ISO_R_N")
	)
	(segment
		(start 263.101836 -32.083502)
		(end 263.40816 -31.777178)
		(width 0.13208)
		(layer "F.Cu")
		(net "RST_SMB_SSD9_ISO_R_N")
	)
	(segment
		(start 266.60094 -23.589996)
		(end 266.032742 -24.158194)
		(width 0.13208)
		(layer "F.Cu")
		(net "RST_SMB_SSD9_ISO_R_N")
	)
	(segment
		(start 268.864842 -23.589996)
		(end 266.60094 -23.589996)
		(width 0.13208)
		(layer "F.Cu")
		(net "RST_SMB_SSD9_ISO_R_N")
	)
	(via
		(at 263.40816 -31.777178)
		(size 0.508)
		(drill 0.254)
		(layers "F.Cu" "B.Cu")
		(net "RST_SMB_SSD9_ISO_R_N")
	)
	(via
		(at 266.032742 -24.158194)
		(size 0.508)
		(drill 0.254)
		(layers "F.Cu" "B.Cu")
		(net "RST_SMB_SSD9_ISO_R_N")
	)
	(segment
		(start 263.40816 -31.777178)
		(end 263.40816 -29.60116)
		(width 0.15494)
		(layer "In5.Cu")
		(net "RST_SMB_SSD9_ISO_R_N")
	)
	(segment
		(start 263.40816 -29.60116)
		(end 266.032742 -26.976578)
		(width 0.15494)
		(layer "In5.Cu")
		(net "RST_SMB_SSD9_ISO_R_N")
	)
	(segment
		(start 266.032742 -26.976578)
		(end 266.032742 -24.158194)
		(width 0.15494)
		(layer "In5.Cu")
		(net "RST_SMB_SSD9_ISO_R_N")
	)
	(segment
		(start 210.7946 -85.810344)
		(end 211.572094 -85.810344)
		(width 0.13208)
		(layer "F.Cu")
		(net "IRQ_SSD_LED_IOEXP_N")
	)
	(segment
		(start 210.68919 -85.915754)
		(end 210.7946 -85.810344)
		(width 0.13208)
		(layer "F.Cu")
		(net "IRQ_SSD_LED_IOEXP_N")
	)
	(segment
		(start 207.023208 -90.103452)
		(end 207.022446 -90.104214)
		(width 0.13208)
		(layer "F.Cu")
		(net "IRQ_SSD_LED_IOEXP_N")
	)
	(segment
		(start 209.351372 -88.993472)
		(end 210.68919 -87.655654)
		(width 0.13208)
		(layer "F.Cu")
		(net "IRQ_SSD_LED_IOEXP_N")
	)
	(segment
		(start 210.68919 -87.655654)
		(end 210.68919 -85.915754)
		(width 0.13208)
		(layer "F.Cu")
		(net "IRQ_SSD_LED_IOEXP_N")
	)
	(segment
		(start 207.023208 -88.993472)
		(end 207.023208 -90.103452)
		(width 0.13208)
		(layer "F.Cu")
		(net "IRQ_SSD_LED_IOEXP_N")
	)
	(segment
		(start 207.023208 -88.993472)
		(end 209.351372 -88.993472)
		(width 0.13208)
		(layer "F.Cu")
		(net "IRQ_SSD_LED_IOEXP_N")
	)
	(via
		(at 210.68919 -87.655654)
		(size 0.508)
		(drill 0.254)
		(layers "F.Cu" "B.Cu")
		(net "IRQ_SSD_LED_IOEXP_N")
	)
	(segment
		(start 121.002044 -32.449262)
		(end 121.002044 -32.083502)
		(width 0.13208)
		(layer "F.Cu")
		(net "RST_SMB_SSD4_ISO_R_N")
	)
	(segment
		(start 121.002044 -32.083502)
		(end 121.308368 -31.777178)
		(width 0.13208)
		(layer "F.Cu")
		(net "RST_SMB_SSD4_ISO_R_N")
	)
	(segment
		(start 126.76505 -23.589996)
		(end 124.501148 -23.589996)
		(width 0.13208)
		(layer "F.Cu")
		(net "RST_SMB_SSD4_ISO_R_N")
	)
	(segment
		(start 124.501148 -23.589996)
		(end 123.93295 -24.158194)
		(width 0.13208)
		(layer "F.Cu")
		(net "RST_SMB_SSD4_ISO_R_N")
	)
	(via
		(at 121.308368 -31.777178)
		(size 0.508)
		(drill 0.254)
		(layers "F.Cu" "B.Cu")
		(net "RST_SMB_SSD4_ISO_R_N")
	)
	(via
		(at 123.93295 -24.158194)
		(size 0.508)
		(drill 0.254)
		(layers "F.Cu" "B.Cu")
		(net "RST_SMB_SSD4_ISO_R_N")
	)
	(segment
		(start 121.308368 -31.777178)
		(end 121.308368 -29.465778)
		(width 0.15494)
		(layer "In5.Cu")
		(net "RST_SMB_SSD4_ISO_R_N")
	)
	(segment
		(start 123.93295 -26.841196)
		(end 123.93295 -24.158194)
		(width 0.15494)
		(layer "In5.Cu")
		(net "RST_SMB_SSD4_ISO_R_N")
	)
	(segment
		(start 121.308368 -29.465778)
		(end 123.93295 -26.841196)
		(width 0.15494)
		(layer "In5.Cu")
		(net "RST_SMB_SSD4_ISO_R_N")
	)
	(segment
		(start 379.201934 -32.449262)
		(end 379.201934 -32.083502)
		(width 0.13208)
		(layer "F.Cu")
		(net "RST_SMB_SSD13_ISO_R_N")
	)
	(segment
		(start 384.96494 -23.589996)
		(end 382.701038 -23.589996)
		(width 0.13208)
		(layer "F.Cu")
		(net "RST_SMB_SSD13_ISO_R_N")
	)
	(segment
		(start 382.701038 -23.589996)
		(end 382.13284 -24.158194)
		(width 0.13208)
		(layer "F.Cu")
		(net "RST_SMB_SSD13_ISO_R_N")
	)
	(segment
		(start 379.201934 -32.083502)
		(end 379.508258 -31.777178)
		(width 0.13208)
		(layer "F.Cu")
		(net "RST_SMB_SSD13_ISO_R_N")
	)
	(via
		(at 382.13284 -24.158194)
		(size 0.508)
		(drill 0.254)
		(layers "F.Cu" "B.Cu")
		(net "RST_SMB_SSD13_ISO_R_N")
	)
	(via
		(at 379.508258 -31.777178)
		(size 0.508)
		(drill 0.254)
		(layers "F.Cu" "B.Cu")
		(net "RST_SMB_SSD13_ISO_R_N")
	)
	(segment
		(start 382.13284 -26.977086)
		(end 382.13284 -24.158194)
		(width 0.15494)
		(layer "In5.Cu")
		(net "RST_SMB_SSD13_ISO_R_N")
	)
	(segment
		(start 379.508258 -29.601668)
		(end 382.13284 -26.977086)
		(width 0.15494)
		(layer "In5.Cu")
		(net "RST_SMB_SSD13_ISO_R_N")
	)
	(segment
		(start 379.508258 -31.777178)
		(end 379.508258 -29.601668)
		(width 0.15494)
		(layer "In5.Cu")
		(net "RST_SMB_SSD13_ISO_R_N")
	)
	(segment
		(start 318.600836 -23.589996)
		(end 318.032638 -24.158194)
		(width 0.13208)
		(layer "F.Cu")
		(net "RST_SMB_SSD11_ISO_R_N")
	)
	(segment
		(start 315.101732 -32.083502)
		(end 315.408056 -31.777178)
		(width 0.13208)
		(layer "F.Cu")
		(net "RST_SMB_SSD11_ISO_R_N")
	)
	(segment
		(start 320.864738 -23.589996)
		(end 318.600836 -23.589996)
		(width 0.13208)
		(layer "F.Cu")
		(net "RST_SMB_SSD11_ISO_R_N")
	)
	(segment
		(start 315.101732 -32.449262)
		(end 315.101732 -32.083502)
		(width 0.13208)
		(layer "F.Cu")
		(net "RST_SMB_SSD11_ISO_R_N")
	)
	(via
		(at 315.408056 -31.777178)
		(size 0.508)
		(drill 0.254)
		(layers "F.Cu" "B.Cu")
		(net "RST_SMB_SSD11_ISO_R_N")
	)
	(via
		(at 318.032638 -24.158194)
		(size 0.508)
		(drill 0.254)
		(layers "F.Cu" "B.Cu")
		(net "RST_SMB_SSD11_ISO_R_N")
	)
	(segment
		(start 315.408056 -29.601668)
		(end 318.032638 -26.977086)
		(width 0.15494)
		(layer "In5.Cu")
		(net "RST_SMB_SSD11_ISO_R_N")
	)
	(segment
		(start 315.408056 -31.777178)
		(end 315.408056 -29.601668)
		(width 0.15494)
		(layer "In5.Cu")
		(net "RST_SMB_SSD11_ISO_R_N")
	)
	(segment
		(start 318.032638 -26.977086)
		(end 318.032638 -24.158194)
		(width 0.15494)
		(layer "In5.Cu")
		(net "RST_SMB_SSD11_ISO_R_N")
	)
	(segment
		(start 243.35613 -211.014564)
		(end 243.505228 -211.163662)
		(width 0.13208)
		(layer "F.Cu")
		(net "JTAG_BIC_TDO_R")
	)
	(segment
		(start 253.08179 -206.862934)
		(end 253.08179 -207.299814)
		(width 0.13208)
		(layer "F.Cu")
		(net "JTAG_BIC_TDO_R")
	)
	(segment
		(start 253.233174 -206.71155)
		(end 253.08179 -206.862934)
		(width 0.13208)
		(layer "F.Cu")
		(net "JTAG_BIC_TDO_R")
	)
	(segment
		(start 243.186712 -211.014564)
		(end 243.35613 -211.014564)
		(width 0.13208)
		(layer "F.Cu")
		(net "JTAG_BIC_TDO_R")
	)
	(segment
		(start 242.884706 -210.712558)
		(end 243.186712 -211.014564)
		(width 0.13208)
		(layer "F.Cu")
		(net "JTAG_BIC_TDO_R")
	)
	(segment
		(start 254.685546 -206.71155)
		(end 253.233174 -206.71155)
		(width 0.13208)
		(layer "F.Cu")
		(net "JTAG_BIC_TDO_R")
	)
	(segment
		(start 253.08179 -207.299814)
		(end 252.884432 -207.497172)
		(width 0.13208)
		(layer "F.Cu")
		(net "JTAG_BIC_TDO_R")
	)
	(segment
		(start 252.884432 -207.497172)
		(end 252.488954 -207.497172)
		(width 0.13208)
		(layer "F.Cu")
		(net "JTAG_BIC_TDO_R")
	)
	(via
		(at 253.08179 -207.299814)
		(size 0.508)
		(drill 0.254)
		(layers "F.Cu" "B.Cu")
		(net "JTAG_BIC_TDO_R")
	)
	(via
		(at 242.884706 -210.712558)
		(size 0.508)
		(drill 0.254)
		(layers "F.Cu" "B.Cu")
		(net "JTAG_BIC_TDO_R")
	)
	(segment
		(start 243.935758 -210.712558)
		(end 242.884706 -210.712558)
		(width 0.15494)
		(layer "In15.Cu")
		(net "JTAG_BIC_TDO_R")
	)
	(segment
		(start 250.097798 -209.789014)
		(end 247.995186 -209.789014)
		(width 0.15494)
		(layer "In15.Cu")
		(net "JTAG_BIC_TDO_R")
	)
	(segment
		(start 246.5832 -211.201)
		(end 244.4242 -211.201)
		(width 0.15494)
		(layer "In15.Cu")
		(net "JTAG_BIC_TDO_R")
	)
	(segment
		(start 244.4242 -211.201)
		(end 243.935758 -210.712558)
		(width 0.15494)
		(layer "In15.Cu")
		(net "JTAG_BIC_TDO_R")
	)
	(segment
		(start 252.586998 -207.299814)
		(end 250.097798 -209.789014)
		(width 0.15494)
		(layer "In15.Cu")
		(net "JTAG_BIC_TDO_R")
	)
	(segment
		(start 253.08179 -207.299814)
		(end 252.586998 -207.299814)
		(width 0.15494)
		(layer "In15.Cu")
		(net "JTAG_BIC_TDO_R")
	)
	(segment
		(start 247.995186 -209.789014)
		(end 246.5832 -211.201)
		(width 0.15494)
		(layer "In15.Cu")
		(net "JTAG_BIC_TDO_R")
	)
	(segment
		(start 121.002044 -33.249362)
		(end 120.99417 -33.257236)
		(width 0.13208)
		(layer "F.Cu")
		(net "RST_SMB_SSD4_ISO_N")
	)
	(segment
		(start 120.99417 -34.248852)
		(end 120.99417 -35.264852)
		(width 0.13208)
		(layer "F.Cu")
		(net "RST_SMB_SSD4_ISO_N")
	)
	(segment
		(start 120.38457 -35.264852)
		(end 119.622316 -35.264852)
		(width 0.13208)
		(layer "F.Cu")
		(net "RST_SMB_SSD4_ISO_N")
	)
	(segment
		(start 119.622316 -35.264852)
		(end 119.495316 -35.137852)
		(width 0.13208)
		(layer "F.Cu")
		(net "RST_SMB_SSD4_ISO_N")
	)
	(segment
		(start 120.99417 -35.264852)
		(end 120.38457 -35.264852)
		(width 0.13208)
		(layer "F.Cu")
		(net "RST_SMB_SSD4_ISO_N")
	)
	(segment
		(start 119.495316 -35.137852)
		(end 119.495316 -34.732468)
		(width 0.13208)
		(layer "F.Cu")
		(net "RST_SMB_SSD4_ISO_N")
	)
	(segment
		(start 120.99417 -33.257236)
		(end 120.99417 -34.248852)
		(width 0.13208)
		(layer "F.Cu")
		(net "RST_SMB_SSD4_ISO_N")
	)
	(via
		(at 120.38457 -35.264852)
		(size 0.508)
		(drill 0.254)
		(layers "F.Cu" "B.Cu")
		(net "RST_SMB_SSD4_ISO_N")
	)
	(segment
		(start 289.101784 -32.083502)
		(end 289.408108 -31.777178)
		(width 0.13208)
		(layer "F.Cu")
		(net "RST_SMB_SSD10_ISO_R_N")
	)
	(segment
		(start 292.600888 -23.589996)
		(end 292.03269 -24.158194)
		(width 0.13208)
		(layer "F.Cu")
		(net "RST_SMB_SSD10_ISO_R_N")
	)
	(segment
		(start 294.86479 -23.589996)
		(end 292.600888 -23.589996)
		(width 0.13208)
		(layer "F.Cu")
		(net "RST_SMB_SSD10_ISO_R_N")
	)
	(segment
		(start 289.101784 -32.449262)
		(end 289.101784 -32.083502)
		(width 0.13208)
		(layer "F.Cu")
		(net "RST_SMB_SSD10_ISO_R_N")
	)
	(via
		(at 289.408108 -31.777178)
		(size 0.508)
		(drill 0.254)
		(layers "F.Cu" "B.Cu")
		(net "RST_SMB_SSD10_ISO_R_N")
	)
	(via
		(at 292.03269 -24.158194)
		(size 0.508)
		(drill 0.254)
		(layers "F.Cu" "B.Cu")
		(net "RST_SMB_SSD10_ISO_R_N")
	)
	(segment
		(start 289.408108 -29.639768)
		(end 292.03269 -27.015186)
		(width 0.15494)
		(layer "In5.Cu")
		(net "RST_SMB_SSD10_ISO_R_N")
	)
	(segment
		(start 289.408108 -31.777178)
		(end 289.408108 -29.639768)
		(width 0.15494)
		(layer "In5.Cu")
		(net "RST_SMB_SSD10_ISO_R_N")
	)
	(segment
		(start 292.03269 -27.015186)
		(end 292.03269 -24.158194)
		(width 0.15494)
		(layer "In5.Cu")
		(net "RST_SMB_SSD10_ISO_R_N")
	)
	(segment
		(start 114.982244 -36.542472)
		(end 114.893344 -36.453572)
		(width 0.13208)
		(layer "F.Cu")
		(net "RST_SMB_SSD4_N")
	)
	(segment
		(start 114.410744 -36.453572)
		(end 114.410744 -36.167568)
		(width 0.13208)
		(layer "F.Cu")
		(net "RST_SMB_SSD4_N")
	)
	(segment
		(start 114.468402 -36.10991)
		(end 116.551964 -36.10991)
		(width 0.13208)
		(layer "F.Cu")
		(net "RST_SMB_SSD4_N")
	)
	(segment
		(start 118.237 -35.65525)
		(end 118.06428 -35.48253)
		(width 0.13208)
		(layer "F.Cu")
		(net "RST_SMB_SSD4_N")
	)
	(segment
		(start 117.221254 -36.7792)
		(end 118.0846 -36.7792)
		(width 0.13208)
		(layer "F.Cu")
		(net "RST_SMB_SSD4_N")
	)
	(segment
		(start 116.551964 -36.10991)
		(end 117.221254 -36.7792)
		(width 0.13208)
		(layer "F.Cu")
		(net "RST_SMB_SSD4_N")
	)
	(segment
		(start 114.982244 -37.025072)
		(end 114.982244 -36.542472)
		(width 0.13208)
		(layer "F.Cu")
		(net "RST_SMB_SSD4_N")
	)
	(segment
		(start 118.237 -36.6268)
		(end 118.237 -35.65525)
		(width 0.13208)
		(layer "F.Cu")
		(net "RST_SMB_SSD4_N")
	)
	(segment
		(start 114.410744 -36.167568)
		(end 114.468402 -36.10991)
		(width 0.13208)
		(layer "F.Cu")
		(net "RST_SMB_SSD4_N")
	)
	(segment
		(start 118.06428 -35.48253)
		(end 117.695472 -35.48253)
		(width 0.13208)
		(layer "F.Cu")
		(net "RST_SMB_SSD4_N")
	)
	(segment
		(start 118.0846 -36.7792)
		(end 118.237 -36.6268)
		(width 0.13208)
		(layer "F.Cu")
		(net "RST_SMB_SSD4_N")
	)
	(segment
		(start 114.893344 -36.453572)
		(end 114.410744 -36.453572)
		(width 0.13208)
		(layer "F.Cu")
		(net "RST_SMB_SSD4_N")
	)
	(via
		(at 114.410744 -36.453572)
		(size 0.508)
		(drill 0.254)
		(layers "F.Cu" "B.Cu")
		(net "RST_SMB_SSD4_N")
	)
	(segment
		(start 436.964836 -23.589996)
		(end 434.700934 -23.589996)
		(width 0.13208)
		(layer "F.Cu")
		(net "RST_SMB_SSD15_ISO_R_N")
	)
	(segment
		(start 434.700934 -23.589996)
		(end 434.132736 -24.158194)
		(width 0.13208)
		(layer "F.Cu")
		(net "RST_SMB_SSD15_ISO_R_N")
	)
	(segment
		(start 431.20183 -32.449262)
		(end 431.20183 -32.083502)
		(width 0.13208)
		(layer "F.Cu")
		(net "RST_SMB_SSD15_ISO_R_N")
	)
	(segment
		(start 431.20183 -32.083502)
		(end 431.508154 -31.777178)
		(width 0.13208)
		(layer "F.Cu")
		(net "RST_SMB_SSD15_ISO_R_N")
	)
	(via
		(at 434.132736 -24.158194)
		(size 0.508)
		(drill 0.254)
		(layers "F.Cu" "B.Cu")
		(net "RST_SMB_SSD15_ISO_R_N")
	)
	(via
		(at 431.508154 -31.777178)
		(size 0.508)
		(drill 0.254)
		(layers "F.Cu" "B.Cu")
		(net "RST_SMB_SSD15_ISO_R_N")
	)
	(segment
		(start 431.508154 -29.642308)
		(end 434.132736 -27.017726)
		(width 0.15494)
		(layer "In5.Cu")
		(net "RST_SMB_SSD15_ISO_R_N")
	)
	(segment
		(start 431.508154 -31.777178)
		(end 431.508154 -29.642308)
		(width 0.15494)
		(layer "In5.Cu")
		(net "RST_SMB_SSD15_ISO_R_N")
	)
	(segment
		(start 434.132736 -27.017726)
		(end 434.132736 -24.158194)
		(width 0.15494)
		(layer "In5.Cu")
		(net "RST_SMB_SSD15_ISO_R_N")
	)
	(segment
		(start 82.90179 -32.083502)
		(end 83.208114 -31.777178)
		(width 0.13208)
		(layer "F.Cu")
		(net "RST_SMB_SSD3_ISO_R_N")
	)
	(segment
		(start 88.664796 -23.589996)
		(end 86.400894 -23.589996)
		(width 0.13208)
		(layer "F.Cu")
		(net "RST_SMB_SSD3_ISO_R_N")
	)
	(segment
		(start 86.400894 -23.589996)
		(end 85.832696 -24.158194)
		(width 0.13208)
		(layer "F.Cu")
		(net "RST_SMB_SSD3_ISO_R_N")
	)
	(segment
		(start 82.90179 -32.449262)
		(end 82.90179 -32.083502)
		(width 0.13208)
		(layer "F.Cu")
		(net "RST_SMB_SSD3_ISO_R_N")
	)
	(via
		(at 85.832696 -24.158194)
		(size 0.508)
		(drill 0.254)
		(layers "F.Cu" "B.Cu")
		(net "RST_SMB_SSD3_ISO_R_N")
	)
	(via
		(at 83.208114 -31.777178)
		(size 0.508)
		(drill 0.254)
		(layers "F.Cu" "B.Cu")
		(net "RST_SMB_SSD3_ISO_R_N")
	)
	(segment
		(start 83.208114 -31.777178)
		(end 83.208114 -29.647134)
		(width 0.15494)
		(layer "In5.Cu")
		(net "RST_SMB_SSD3_ISO_R_N")
	)
	(segment
		(start 85.832696 -27.022552)
		(end 85.832696 -24.158194)
		(width 0.15494)
		(layer "In5.Cu")
		(net "RST_SMB_SSD3_ISO_R_N")
	)
	(segment
		(start 83.208114 -29.647134)
		(end 85.832696 -27.022552)
		(width 0.15494)
		(layer "In5.Cu")
		(net "RST_SMB_SSD3_ISO_R_N")
	)
	(segment
		(start 252.287532 -197.661022)
		(end 252.287532 -198.95693)
		(width 0.13208)
		(layer "F.Cu")
		(net "JTAG_BIC_TCK_R1")
	)
	(segment
		(start 250.94946 -195.973446)
		(end 250.94946 -196.59727)
		(width 0.13208)
		(layer "F.Cu")
		(net "JTAG_BIC_TCK_R1")
	)
	(segment
		(start 251.617226 -196.990716)
		(end 252.287532 -197.661022)
		(width 0.13208)
		(layer "F.Cu")
		(net "JTAG_BIC_TCK_R1")
	)
	(segment
		(start 250.94946 -196.59727)
		(end 251.342906 -196.990716)
		(width 0.13208)
		(layer "F.Cu")
		(net "JTAG_BIC_TCK_R1")
	)
	(segment
		(start 251.342906 -196.990716)
		(end 251.617226 -196.990716)
		(width 0.13208)
		(layer "F.Cu")
		(net "JTAG_BIC_TCK_R1")
	)
	(via
		(at 250.94946 -196.59727)
		(size 0.508)
		(drill 0.254)
		(layers "F.Cu" "B.Cu")
		(net "JTAG_BIC_TCK_R1")
	)
	(segment
		(start 253.99746 -195.973446)
		(end 253.99746 -196.766434)
		(width 0.13208)
		(layer "F.Cu")
		(net "JTAG_BIC_TMS_R1")
	)
	(segment
		(start 253.99746 -197.351396)
		(end 254.23749 -197.591426)
		(width 0.13208)
		(layer "F.Cu")
		(net "JTAG_BIC_TMS_R1")
	)
	(segment
		(start 254.23749 -197.591426)
		(end 254.23749 -198.95693)
		(width 0.13208)
		(layer "F.Cu")
		(net "JTAG_BIC_TMS_R1")
	)
	(segment
		(start 253.99746 -196.766434)
		(end 253.99746 -197.351396)
		(width 0.13208)
		(layer "F.Cu")
		(net "JTAG_BIC_TMS_R1")
	)
	(via
		(at 253.99746 -196.766434)
		(size 0.508)
		(drill 0.254)
		(layers "F.Cu" "B.Cu")
		(net "JTAG_BIC_TMS_R1")
	)
	(segment
		(start 82.893916 -34.248852)
		(end 82.893916 -35.264852)
		(width 0.13208)
		(layer "F.Cu")
		(net "RST_SMB_SSD3_ISO_N")
	)
	(segment
		(start 82.284316 -35.264852)
		(end 81.522062 -35.264852)
		(width 0.13208)
		(layer "F.Cu")
		(net "RST_SMB_SSD3_ISO_N")
	)
	(segment
		(start 82.90179 -33.249362)
		(end 82.893916 -33.257236)
		(width 0.13208)
		(layer "F.Cu")
		(net "RST_SMB_SSD3_ISO_N")
	)
	(segment
		(start 81.395062 -35.137852)
		(end 81.395062 -34.732468)
		(width 0.13208)
		(layer "F.Cu")
		(net "RST_SMB_SSD3_ISO_N")
	)
	(segment
		(start 82.893916 -33.257236)
		(end 82.893916 -34.248852)
		(width 0.13208)
		(layer "F.Cu")
		(net "RST_SMB_SSD3_ISO_N")
	)
	(segment
		(start 81.522062 -35.264852)
		(end 81.395062 -35.137852)
		(width 0.13208)
		(layer "F.Cu")
		(net "RST_SMB_SSD3_ISO_N")
	)
	(segment
		(start 82.893916 -35.264852)
		(end 82.284316 -35.264852)
		(width 0.13208)
		(layer "F.Cu")
		(net "RST_SMB_SSD3_ISO_N")
	)
	(via
		(at 82.284316 -35.264852)
		(size 0.508)
		(drill 0.254)
		(layers "F.Cu" "B.Cu")
		(net "RST_SMB_SSD3_ISO_N")
	)
	(segment
		(start 76.79309 -36.453572)
		(end 76.31049 -36.453572)
		(width 0.13208)
		(layer "F.Cu")
		(net "RST_SMB_SSD3_N")
	)
	(segment
		(start 76.88199 -37.025072)
		(end 76.88199 -36.542472)
		(width 0.13208)
		(layer "F.Cu")
		(net "RST_SMB_SSD3_N")
	)
	(segment
		(start 76.368148 -36.10991)
		(end 78.47711 -36.10991)
		(width 0.13208)
		(layer "F.Cu")
		(net "RST_SMB_SSD3_N")
	)
	(segment
		(start 78.47711 -36.10991)
		(end 79.1718 -36.8046)
		(width 0.13208)
		(layer "F.Cu")
		(net "RST_SMB_SSD3_N")
	)
	(segment
		(start 76.88199 -36.542472)
		(end 76.79309 -36.453572)
		(width 0.13208)
		(layer "F.Cu")
		(net "RST_SMB_SSD3_N")
	)
	(segment
		(start 79.908146 -36.8046)
		(end 80.1116 -36.601146)
		(width 0.13208)
		(layer "F.Cu")
		(net "RST_SMB_SSD3_N")
	)
	(segment
		(start 76.31049 -36.167568)
		(end 76.368148 -36.10991)
		(width 0.13208)
		(layer "F.Cu")
		(net "RST_SMB_SSD3_N")
	)
	(segment
		(start 80.1116 -35.630104)
		(end 79.964026 -35.48253)
		(width 0.13208)
		(layer "F.Cu")
		(net "RST_SMB_SSD3_N")
	)
	(segment
		(start 76.31049 -36.453572)
		(end 76.31049 -36.167568)
		(width 0.13208)
		(layer "F.Cu")
		(net "RST_SMB_SSD3_N")
	)
	(segment
		(start 80.1116 -36.601146)
		(end 80.1116 -35.630104)
		(width 0.13208)
		(layer "F.Cu")
		(net "RST_SMB_SSD3_N")
	)
	(segment
		(start 79.1718 -36.8046)
		(end 79.908146 -36.8046)
		(width 0.13208)
		(layer "F.Cu")
		(net "RST_SMB_SSD3_N")
	)
	(segment
		(start 79.964026 -35.48253)
		(end 79.595218 -35.48253)
		(width 0.13208)
		(layer "F.Cu")
		(net "RST_SMB_SSD3_N")
	)
	(via
		(at 76.31049 -36.453572)
		(size 0.508)
		(drill 0.254)
		(layers "F.Cu" "B.Cu")
		(net "RST_SMB_SSD3_N")
	)
	(segment
		(start 256.717546 -204.077316)
		(end 256.315972 -203.675742)
		(width 0.13208)
		(layer "F.Cu")
		(net "JTAG_BIC_TDI_R1")
	)
	(segment
		(start 254.887476 -203.92009)
		(end 254.887476 -204.79893)
		(width 0.13208)
		(layer "F.Cu")
		(net "JTAG_BIC_TDI_R1")
	)
	(segment
		(start 255.131824 -203.675742)
		(end 254.887476 -203.92009)
		(width 0.13208)
		(layer "F.Cu")
		(net "JTAG_BIC_TDI_R1")
	)
	(segment
		(start 256.315972 -203.675742)
		(end 255.131824 -203.675742)
		(width 0.13208)
		(layer "F.Cu")
		(net "JTAG_BIC_TDI_R1")
	)
	(segment
		(start 256.717546 -206.71155)
		(end 256.717546 -204.077316)
		(width 0.13208)
		(layer "F.Cu")
		(net "JTAG_BIC_TDI_R1")
	)
	(via
		(at 256.717546 -204.077316)
		(size 0.508)
		(drill 0.254)
		(layers "F.Cu" "B.Cu")
		(net "JTAG_BIC_TDI_R1")
	)
	(segment
		(start 60.400946 -23.589996)
		(end 59.832748 -24.158194)
		(width 0.13208)
		(layer "F.Cu")
		(net "RST_SMB_SSD2_ISO_R_N")
	)
	(segment
		(start 62.664848 -23.589996)
		(end 60.400946 -23.589996)
		(width 0.13208)
		(layer "F.Cu")
		(net "RST_SMB_SSD2_ISO_R_N")
	)
	(segment
		(start 56.901842 -32.449262)
		(end 56.901842 -32.083502)
		(width 0.13208)
		(layer "F.Cu")
		(net "RST_SMB_SSD2_ISO_R_N")
	)
	(segment
		(start 56.901842 -32.083502)
		(end 57.208166 -31.777178)
		(width 0.13208)
		(layer "F.Cu")
		(net "RST_SMB_SSD2_ISO_R_N")
	)
	(via
		(at 57.208166 -31.777178)
		(size 0.508)
		(drill 0.254)
		(layers "F.Cu" "B.Cu")
		(net "RST_SMB_SSD2_ISO_R_N")
	)
	(via
		(at 59.832748 -24.158194)
		(size 0.508)
		(drill 0.254)
		(layers "F.Cu" "B.Cu")
		(net "RST_SMB_SSD2_ISO_R_N")
	)
	(segment
		(start 59.832748 -27.02306)
		(end 59.832748 -24.158194)
		(width 0.15494)
		(layer "In5.Cu")
		(net "RST_SMB_SSD2_ISO_R_N")
	)
	(segment
		(start 57.208166 -31.777178)
		(end 57.208166 -29.647642)
		(width 0.15494)
		(layer "In5.Cu")
		(net "RST_SMB_SSD2_ISO_R_N")
	)
	(segment
		(start 57.208166 -29.647642)
		(end 59.832748 -27.02306)
		(width 0.15494)
		(layer "In5.Cu")
		(net "RST_SMB_SSD2_ISO_R_N")
	)
	(segment
		(start 55.522114 -35.264852)
		(end 56.284368 -35.264852)
		(width 0.13208)
		(layer "F.Cu")
		(net "RST_SMB_SSD2_ISO_N")
	)
	(segment
		(start 55.395114 -35.137852)
		(end 55.522114 -35.264852)
		(width 0.13208)
		(layer "F.Cu")
		(net "RST_SMB_SSD2_ISO_N")
	)
	(segment
		(start 56.284368 -35.264852)
		(end 56.893968 -35.264852)
		(width 0.13208)
		(layer "F.Cu")
		(net "RST_SMB_SSD2_ISO_N")
	)
	(segment
		(start 55.395114 -34.732468)
		(end 55.395114 -35.137852)
		(width 0.13208)
		(layer "F.Cu")
		(net "RST_SMB_SSD2_ISO_N")
	)
	(segment
		(start 56.901842 -33.249362)
		(end 56.893968 -33.257236)
		(width 0.13208)
		(layer "F.Cu")
		(net "RST_SMB_SSD2_ISO_N")
	)
	(segment
		(start 56.893968 -34.248852)
		(end 56.893968 -35.264852)
		(width 0.13208)
		(layer "F.Cu")
		(net "RST_SMB_SSD2_ISO_N")
	)
	(segment
		(start 56.893968 -33.257236)
		(end 56.893968 -34.248852)
		(width 0.13208)
		(layer "F.Cu")
		(net "RST_SMB_SSD2_ISO_N")
	)
	(via
		(at 56.284368 -35.264852)
		(size 0.508)
		(drill 0.254)
		(layers "F.Cu" "B.Cu")
		(net "RST_SMB_SSD2_ISO_N")
	)
	(segment
		(start 54.1274 -36.601654)
		(end 53.924454 -36.8046)
		(width 0.13208)
		(layer "F.Cu")
		(net "RST_SMB_SSD2_N")
	)
	(segment
		(start 53.924454 -36.8046)
		(end 53.1876 -36.8046)
		(width 0.13208)
		(layer "F.Cu")
		(net "RST_SMB_SSD2_N")
	)
	(segment
		(start 50.310542 -36.167568)
		(end 50.310542 -36.453572)
		(width 0.13208)
		(layer "F.Cu")
		(net "RST_SMB_SSD2_N")
	)
	(segment
		(start 52.49291 -36.10991)
		(end 50.3682 -36.10991)
		(width 0.13208)
		(layer "F.Cu")
		(net "RST_SMB_SSD2_N")
	)
	(segment
		(start 53.964078 -35.48253)
		(end 54.1274 -35.645852)
		(width 0.13208)
		(layer "F.Cu")
		(net "RST_SMB_SSD2_N")
	)
	(segment
		(start 53.1876 -36.8046)
		(end 52.49291 -36.10991)
		(width 0.13208)
		(layer "F.Cu")
		(net "RST_SMB_SSD2_N")
	)
	(segment
		(start 50.882042 -36.542472)
		(end 50.882042 -37.025072)
		(width 0.13208)
		(layer "F.Cu")
		(net "RST_SMB_SSD2_N")
	)
	(segment
		(start 50.3682 -36.10991)
		(end 50.310542 -36.167568)
		(width 0.13208)
		(layer "F.Cu")
		(net "RST_SMB_SSD2_N")
	)
	(segment
		(start 54.1274 -35.645852)
		(end 54.1274 -36.601654)
		(width 0.13208)
		(layer "F.Cu")
		(net "RST_SMB_SSD2_N")
	)
	(segment
		(start 53.59527 -35.48253)
		(end 53.964078 -35.48253)
		(width 0.13208)
		(layer "F.Cu")
		(net "RST_SMB_SSD2_N")
	)
	(segment
		(start 50.310542 -36.453572)
		(end 50.793142 -36.453572)
		(width 0.13208)
		(layer "F.Cu")
		(net "RST_SMB_SSD2_N")
	)
	(segment
		(start 50.793142 -36.453572)
		(end 50.882042 -36.542472)
		(width 0.13208)
		(layer "F.Cu")
		(net "RST_SMB_SSD2_N")
	)
	(via
		(at 50.310542 -36.453572)
		(size 0.508)
		(drill 0.254)
		(layers "F.Cu" "B.Cu")
		(net "RST_SMB_SSD2_N")
	)
	(segment
		(start 221.387162 -178.958494)
		(end 220.97238 -178.958494)
		(width 0.13208)
		(layer "F.Cu")
		(net "RST_FW_BIC_PLTRST_N")
	)
	(segment
		(start 221.86773 -179.439062)
		(end 221.387162 -178.958494)
		(width 0.13208)
		(layer "F.Cu")
		(net "RST_FW_BIC_PLTRST_N")
	)
	(segment
		(start 220.431868 -174.04842)
		(end 220.848936 -174.04842)
		(width 0.13208)
		(layer "F.Cu")
		(net "RST_FW_BIC_PLTRST_N")
	)
	(segment
		(start 220.09862 -174.381668)
		(end 220.431868 -174.04842)
		(width 0.13208)
		(layer "F.Cu")
		(net "RST_FW_BIC_PLTRST_N")
	)
	(segment
		(start 219.8878 -175.467518)
		(end 220.09862 -175.256698)
		(width 0.13208)
		(layer "F.Cu")
		(net "RST_FW_BIC_PLTRST_N")
	)
	(segment
		(start 219.8878 -178.432206)
		(end 219.8878 -175.467518)
		(width 0.13208)
		(layer "F.Cu")
		(net "RST_FW_BIC_PLTRST_N")
	)
	(segment
		(start 220.414088 -178.958494)
		(end 219.8878 -178.432206)
		(width 0.13208)
		(layer "F.Cu")
		(net "RST_FW_BIC_PLTRST_N")
	)
	(segment
		(start 221.86773 -180.826156)
		(end 221.86773 -179.439062)
		(width 0.13208)
		(layer "F.Cu")
		(net "RST_FW_BIC_PLTRST_N")
	)
	(segment
		(start 222.186754 -181.14518)
		(end 221.86773 -180.826156)
		(width 0.13208)
		(layer "F.Cu")
		(net "RST_FW_BIC_PLTRST_N")
	)
	(segment
		(start 220.09862 -175.256698)
		(end 220.09862 -174.381668)
		(width 0.13208)
		(layer "F.Cu")
		(net "RST_FW_BIC_PLTRST_N")
	)
	(segment
		(start 222.961454 -181.14518)
		(end 222.186754 -181.14518)
		(width 0.13208)
		(layer "F.Cu")
		(net "RST_FW_BIC_PLTRST_N")
	)
	(segment
		(start 220.97238 -178.958494)
		(end 220.414088 -178.958494)
		(width 0.13208)
		(layer "F.Cu")
		(net "RST_FW_BIC_PLTRST_N")
	)
	(via
		(at 220.97238 -178.958494)
		(size 0.762)
		(drill 0.381)
		(layers "F.Cu" "B.Cu")
		(net "RST_FW_BIC_PLTRST_N")
	)
	(segment
		(start 34.400998 -23.589996)
		(end 33.8328 -24.158194)
		(width 0.13208)
		(layer "F.Cu")
		(net "RST_SMB_SSD1_ISO_R_N")
	)
	(segment
		(start 30.901894 -32.449262)
		(end 30.901894 -32.083502)
		(width 0.13208)
		(layer "F.Cu")
		(net "RST_SMB_SSD1_ISO_R_N")
	)
	(segment
		(start 36.6649 -23.589996)
		(end 34.400998 -23.589996)
		(width 0.13208)
		(layer "F.Cu")
		(net "RST_SMB_SSD1_ISO_R_N")
	)
	(segment
		(start 30.901894 -32.083502)
		(end 31.208218 -31.777178)
		(width 0.13208)
		(layer "F.Cu")
		(net "RST_SMB_SSD1_ISO_R_N")
	)
	(via
		(at 31.208218 -31.777178)
		(size 0.508)
		(drill 0.254)
		(layers "F.Cu" "B.Cu")
		(net "RST_SMB_SSD1_ISO_R_N")
	)
	(via
		(at 33.8328 -24.158194)
		(size 0.508)
		(drill 0.254)
		(layers "F.Cu" "B.Cu")
		(net "RST_SMB_SSD1_ISO_R_N")
	)
	(segment
		(start 31.208218 -29.647642)
		(end 33.8328 -27.02306)
		(width 0.15494)
		(layer "In5.Cu")
		(net "RST_SMB_SSD1_ISO_R_N")
	)
	(segment
		(start 33.8328 -27.02306)
		(end 33.8328 -24.158194)
		(width 0.15494)
		(layer "In5.Cu")
		(net "RST_SMB_SSD1_ISO_R_N")
	)
	(segment
		(start 31.208218 -31.777178)
		(end 31.208218 -29.647642)
		(width 0.15494)
		(layer "In5.Cu")
		(net "RST_SMB_SSD1_ISO_R_N")
	)
	(segment
		(start 379.201934 -33.249362)
		(end 379.19406 -33.257236)
		(width 0.13208)
		(layer "F.Cu")
		(net "RST_SMB_SSD13_ISO_N")
	)
	(segment
		(start 378.58446 -35.264852)
		(end 379.19406 -35.264852)
		(width 0.13208)
		(layer "F.Cu")
		(net "RST_SMB_SSD13_ISO_N")
	)
	(segment
		(start 379.19406 -33.257236)
		(end 379.19406 -34.248852)
		(width 0.13208)
		(layer "F.Cu")
		(net "RST_SMB_SSD13_ISO_N")
	)
	(segment
		(start 377.695206 -34.732468)
		(end 377.695206 -35.137852)
		(width 0.13208)
		(layer "F.Cu")
		(net "RST_SMB_SSD13_ISO_N")
	)
	(segment
		(start 377.695206 -35.137852)
		(end 377.822206 -35.264852)
		(width 0.13208)
		(layer "F.Cu")
		(net "RST_SMB_SSD13_ISO_N")
	)
	(segment
		(start 379.19406 -34.248852)
		(end 379.19406 -35.264852)
		(width 0.13208)
		(layer "F.Cu")
		(net "RST_SMB_SSD13_ISO_N")
	)
	(segment
		(start 377.822206 -35.264852)
		(end 378.58446 -35.264852)
		(width 0.13208)
		(layer "F.Cu")
		(net "RST_SMB_SSD13_ISO_N")
	)
	(via
		(at 378.58446 -35.264852)
		(size 0.508)
		(drill 0.254)
		(layers "F.Cu" "B.Cu")
		(net "RST_SMB_SSD13_ISO_N")
	)
	(segment
		(start 400.829018 -36.10991)
		(end 398.66824 -36.10991)
		(width 0.13208)
		(layer "F.Cu")
		(net "RST_SMB_SSD14_N")
	)
	(segment
		(start 402.255482 -36.7792)
		(end 401.498308 -36.7792)
		(width 0.13208)
		(layer "F.Cu")
		(net "RST_SMB_SSD14_N")
	)
	(segment
		(start 399.182082 -37.025072)
		(end 399.182082 -36.542472)
		(width 0.13208)
		(layer "F.Cu")
		(net "RST_SMB_SSD14_N")
	)
	(segment
		(start 402.4376 -35.656012)
		(end 402.4376 -36.597082)
		(width 0.13208)
		(layer "F.Cu")
		(net "RST_SMB_SSD14_N")
	)
	(segment
		(start 402.264118 -35.48253)
		(end 402.4376 -35.656012)
		(width 0.13208)
		(layer "F.Cu")
		(net "RST_SMB_SSD14_N")
	)
	(segment
		(start 401.89531 -35.48253)
		(end 402.264118 -35.48253)
		(width 0.13208)
		(layer "F.Cu")
		(net "RST_SMB_SSD14_N")
	)
	(segment
		(start 399.182082 -36.542472)
		(end 399.093182 -36.453572)
		(width 0.13208)
		(layer "F.Cu")
		(net "RST_SMB_SSD14_N")
	)
	(segment
		(start 398.66824 -36.10991)
		(end 398.610582 -36.167568)
		(width 0.13208)
		(layer "F.Cu")
		(net "RST_SMB_SSD14_N")
	)
	(segment
		(start 401.498308 -36.7792)
		(end 400.829018 -36.10991)
		(width 0.13208)
		(layer "F.Cu")
		(net "RST_SMB_SSD14_N")
	)
	(segment
		(start 398.610582 -36.167568)
		(end 398.610582 -36.453572)
		(width 0.13208)
		(layer "F.Cu")
		(net "RST_SMB_SSD14_N")
	)
	(segment
		(start 399.093182 -36.453572)
		(end 398.610582 -36.453572)
		(width 0.13208)
		(layer "F.Cu")
		(net "RST_SMB_SSD14_N")
	)
	(segment
		(start 402.4376 -36.597082)
		(end 402.255482 -36.7792)
		(width 0.13208)
		(layer "F.Cu")
		(net "RST_SMB_SSD14_N")
	)
	(via
		(at 398.610582 -36.453572)
		(size 0.508)
		(drill 0.254)
		(layers "F.Cu" "B.Cu")
		(net "RST_SMB_SSD14_N")
	)
	(segment
		(start 30.89402 -34.248852)
		(end 30.89402 -35.264852)
		(width 0.13208)
		(layer "F.Cu")
		(net "RST_SMB_SSD1_ISO_N")
	)
	(segment
		(start 29.395166 -34.732468)
		(end 29.395166 -35.137852)
		(width 0.13208)
		(layer "F.Cu")
		(net "RST_SMB_SSD1_ISO_N")
	)
	(segment
		(start 29.522166 -35.264852)
		(end 30.28442 -35.264852)
		(width 0.13208)
		(layer "F.Cu")
		(net "RST_SMB_SSD1_ISO_N")
	)
	(segment
		(start 30.89402 -33.257236)
		(end 30.89402 -34.248852)
		(width 0.13208)
		(layer "F.Cu")
		(net "RST_SMB_SSD1_ISO_N")
	)
	(segment
		(start 29.395166 -35.137852)
		(end 29.522166 -35.264852)
		(width 0.13208)
		(layer "F.Cu")
		(net "RST_SMB_SSD1_ISO_N")
	)
	(segment
		(start 30.28442 -35.264852)
		(end 30.89402 -35.264852)
		(width 0.13208)
		(layer "F.Cu")
		(net "RST_SMB_SSD1_ISO_N")
	)
	(segment
		(start 30.901894 -33.249362)
		(end 30.89402 -33.257236)
		(width 0.13208)
		(layer "F.Cu")
		(net "RST_SMB_SSD1_ISO_N")
	)
	(via
		(at 30.28442 -35.264852)
		(size 0.508)
		(drill 0.254)
		(layers "F.Cu" "B.Cu")
		(net "RST_SMB_SSD1_ISO_N")
	)
	(segment
		(start 256.510536 -36.167568)
		(end 256.510536 -36.453572)
		(width 0.13208)
		(layer "F.Cu")
		(net "RST_SMB_SSD9_N")
	)
	(segment
		(start 260.1595 -36.7792)
		(end 259.385054 -36.7792)
		(width 0.13208)
		(layer "F.Cu")
		(net "RST_SMB_SSD9_N")
	)
	(segment
		(start 260.35 -35.668458)
		(end 260.35 -36.5887)
		(width 0.13208)
		(layer "F.Cu")
		(net "RST_SMB_SSD9_N")
	)
	(segment
		(start 260.35 -36.5887)
		(end 260.1595 -36.7792)
		(width 0.13208)
		(layer "F.Cu")
		(net "RST_SMB_SSD9_N")
	)
	(segment
		(start 256.993136 -36.453572)
		(end 257.082036 -36.542472)
		(width 0.13208)
		(layer "F.Cu")
		(net "RST_SMB_SSD9_N")
	)
	(segment
		(start 260.164072 -35.48253)
		(end 260.35 -35.668458)
		(width 0.13208)
		(layer "F.Cu")
		(net "RST_SMB_SSD9_N")
	)
	(segment
		(start 258.715764 -36.10991)
		(end 256.568194 -36.10991)
		(width 0.13208)
		(layer "F.Cu")
		(net "RST_SMB_SSD9_N")
	)
	(segment
		(start 256.568194 -36.10991)
		(end 256.510536 -36.167568)
		(width 0.13208)
		(layer "F.Cu")
		(net "RST_SMB_SSD9_N")
	)
	(segment
		(start 259.795264 -35.48253)
		(end 260.164072 -35.48253)
		(width 0.13208)
		(layer "F.Cu")
		(net "RST_SMB_SSD9_N")
	)
	(segment
		(start 256.510536 -36.453572)
		(end 256.993136 -36.453572)
		(width 0.13208)
		(layer "F.Cu")
		(net "RST_SMB_SSD9_N")
	)
	(segment
		(start 257.082036 -36.542472)
		(end 257.082036 -37.025072)
		(width 0.13208)
		(layer "F.Cu")
		(net "RST_SMB_SSD9_N")
	)
	(segment
		(start 259.385054 -36.7792)
		(end 258.715764 -36.10991)
		(width 0.13208)
		(layer "F.Cu")
		(net "RST_SMB_SSD9_N")
	)
	(via
		(at 256.510536 -36.453572)
		(size 0.508)
		(drill 0.254)
		(layers "F.Cu" "B.Cu")
		(net "RST_SMB_SSD9_N")
	)
	(segment
		(start 28.1432 -35.6616)
		(end 27.96413 -35.48253)
		(width 0.13208)
		(layer "F.Cu")
		(net "RST_SMB_SSD1_N")
	)
	(segment
		(start 24.310594 -36.167568)
		(end 24.368252 -36.10991)
		(width 0.13208)
		(layer "F.Cu")
		(net "RST_SMB_SSD1_N")
	)
	(segment
		(start 24.882094 -37.025072)
		(end 24.882094 -36.542472)
		(width 0.13208)
		(layer "F.Cu")
		(net "RST_SMB_SSD1_N")
	)
	(segment
		(start 24.882094 -36.542472)
		(end 24.793194 -36.453572)
		(width 0.13208)
		(layer "F.Cu")
		(net "RST_SMB_SSD1_N")
	)
	(segment
		(start 28.1432 -36.620958)
		(end 28.1432 -35.6616)
		(width 0.13208)
		(layer "F.Cu")
		(net "RST_SMB_SSD1_N")
	)
	(segment
		(start 27.178 -36.8046)
		(end 27.959558 -36.8046)
		(width 0.13208)
		(layer "F.Cu")
		(net "RST_SMB_SSD1_N")
	)
	(segment
		(start 27.96413 -35.48253)
		(end 27.595322 -35.48253)
		(width 0.13208)
		(layer "F.Cu")
		(net "RST_SMB_SSD1_N")
	)
	(segment
		(start 24.368252 -36.10991)
		(end 26.48331 -36.10991)
		(width 0.13208)
		(layer "F.Cu")
		(net "RST_SMB_SSD1_N")
	)
	(segment
		(start 24.793194 -36.453572)
		(end 24.310594 -36.453572)
		(width 0.13208)
		(layer "F.Cu")
		(net "RST_SMB_SSD1_N")
	)
	(segment
		(start 27.959558 -36.8046)
		(end 28.1432 -36.620958)
		(width 0.13208)
		(layer "F.Cu")
		(net "RST_SMB_SSD1_N")
	)
	(segment
		(start 24.310594 -36.453572)
		(end 24.310594 -36.167568)
		(width 0.13208)
		(layer "F.Cu")
		(net "RST_SMB_SSD1_N")
	)
	(segment
		(start 26.48331 -36.10991)
		(end 27.178 -36.8046)
		(width 0.13208)
		(layer "F.Cu")
		(net "RST_SMB_SSD1_N")
	)
	(via
		(at 24.310594 -36.453572)
		(size 0.508)
		(drill 0.254)
		(layers "F.Cu" "B.Cu")
		(net "RST_SMB_SSD1_N")
	)
	(segment
		(start 315.101732 -33.249362)
		(end 315.093858 -33.257236)
		(width 0.13208)
		(layer "F.Cu")
		(net "RST_SMB_SSD11_ISO_N")
	)
	(segment
		(start 315.093858 -33.257236)
		(end 315.093858 -34.248852)
		(width 0.13208)
		(layer "F.Cu")
		(net "RST_SMB_SSD11_ISO_N")
	)
	(segment
		(start 315.093858 -34.248852)
		(end 315.093858 -35.264852)
		(width 0.13208)
		(layer "F.Cu")
		(net "RST_SMB_SSD11_ISO_N")
	)
	(segment
		(start 313.595004 -34.732468)
		(end 313.595004 -35.137852)
		(width 0.13208)
		(layer "F.Cu")
		(net "RST_SMB_SSD11_ISO_N")
	)
	(segment
		(start 313.595004 -35.137852)
		(end 313.722004 -35.264852)
		(width 0.13208)
		(layer "F.Cu")
		(net "RST_SMB_SSD11_ISO_N")
	)
	(segment
		(start 313.722004 -35.264852)
		(end 314.484258 -35.264852)
		(width 0.13208)
		(layer "F.Cu")
		(net "RST_SMB_SSD11_ISO_N")
	)
	(segment
		(start 314.484258 -35.264852)
		(end 315.093858 -35.264852)
		(width 0.13208)
		(layer "F.Cu")
		(net "RST_SMB_SSD11_ISO_N")
	)
	(via
		(at 314.484258 -35.264852)
		(size 0.508)
		(drill 0.254)
		(layers "F.Cu" "B.Cu")
		(net "RST_SMB_SSD11_ISO_N")
	)
	(segment
		(start 4.243832 -72.156828)
		(end 3.760978 -71.673974)
		(width 0.13208)
		(layer "F.Cu")
		(net "RST_SMB_SSD0_N")
	)
	(segment
		(start 4.84505 -72.156828)
		(end 4.243832 -72.156828)
		(width 0.13208)
		(layer "F.Cu")
		(net "RST_SMB_SSD0_N")
	)
	(segment
		(start 3.26898 -72.165972)
		(end 2.91719 -72.165972)
		(width 0.13208)
		(layer "F.Cu")
		(net "RST_SMB_SSD0_N")
	)
	(segment
		(start 3.760978 -71.673974)
		(end 3.26898 -72.165972)
		(width 0.13208)
		(layer "F.Cu")
		(net "RST_SMB_SSD0_N")
	)
	(via
		(at 3.760978 -71.673974)
		(size 0.508)
		(drill 0.254)
		(layers "F.Cu" "B.Cu")
		(net "RST_SMB_SSD0_N")
	)
	(segment
		(start 230.510588 -36.453572)
		(end 230.510588 -36.167568)
		(width 0.13208)
		(layer "F.Cu")
		(net "RST_SMB_SSD8_N")
	)
	(segment
		(start 231.082088 -36.542472)
		(end 230.993188 -36.453572)
		(width 0.13208)
		(layer "F.Cu")
		(net "RST_SMB_SSD8_N")
	)
	(segment
		(start 230.510588 -36.167568)
		(end 230.568246 -36.10991)
		(width 0.13208)
		(layer "F.Cu")
		(net "RST_SMB_SSD8_N")
	)
	(segment
		(start 234.315 -36.6522)
		(end 234.315 -35.633406)
		(width 0.13208)
		(layer "F.Cu")
		(net "RST_SMB_SSD8_N")
	)
	(segment
		(start 231.082088 -37.025072)
		(end 231.082088 -36.542472)
		(width 0.13208)
		(layer "F.Cu")
		(net "RST_SMB_SSD8_N")
	)
	(segment
		(start 233.374946 -36.7792)
		(end 234.188 -36.7792)
		(width 0.13208)
		(layer "F.Cu")
		(net "RST_SMB_SSD8_N")
	)
	(segment
		(start 232.705656 -36.10991)
		(end 233.374946 -36.7792)
		(width 0.13208)
		(layer "F.Cu")
		(net "RST_SMB_SSD8_N")
	)
	(segment
		(start 234.188 -36.7792)
		(end 234.315 -36.6522)
		(width 0.13208)
		(layer "F.Cu")
		(net "RST_SMB_SSD8_N")
	)
	(segment
		(start 230.993188 -36.453572)
		(end 230.510588 -36.453572)
		(width 0.13208)
		(layer "F.Cu")
		(net "RST_SMB_SSD8_N")
	)
	(segment
		(start 234.315 -35.633406)
		(end 234.164124 -35.48253)
		(width 0.13208)
		(layer "F.Cu")
		(net "RST_SMB_SSD8_N")
	)
	(segment
		(start 234.164124 -35.48253)
		(end 233.795316 -35.48253)
		(width 0.13208)
		(layer "F.Cu")
		(net "RST_SMB_SSD8_N")
	)
	(segment
		(start 230.568246 -36.10991)
		(end 232.705656 -36.10991)
		(width 0.13208)
		(layer "F.Cu")
		(net "RST_SMB_SSD8_N")
	)
	(via
		(at 230.510588 -36.453572)
		(size 0.508)
		(drill 0.254)
		(layers "F.Cu" "B.Cu")
		(net "RST_SMB_SSD8_N")
	)
	(segment
		(start 353.201986 -33.249362)
		(end 353.194112 -33.257236)
		(width 0.13208)
		(layer "F.Cu")
		(net "RST_SMB_SSD12_ISO_N")
	)
	(segment
		(start 351.695258 -34.732468)
		(end 351.695258 -35.137852)
		(width 0.13208)
		(layer "F.Cu")
		(net "RST_SMB_SSD12_ISO_N")
	)
	(segment
		(start 351.695258 -35.137852)
		(end 351.822258 -35.264852)
		(width 0.13208)
		(layer "F.Cu")
		(net "RST_SMB_SSD12_ISO_N")
	)
	(segment
		(start 352.584512 -35.264852)
		(end 353.194112 -35.264852)
		(width 0.13208)
		(layer "F.Cu")
		(net "RST_SMB_SSD12_ISO_N")
	)
	(segment
		(start 353.194112 -33.257236)
		(end 353.194112 -34.248852)
		(width 0.13208)
		(layer "F.Cu")
		(net "RST_SMB_SSD12_ISO_N")
	)
	(segment
		(start 353.194112 -34.248852)
		(end 353.194112 -35.264852)
		(width 0.13208)
		(layer "F.Cu")
		(net "RST_SMB_SSD12_ISO_N")
	)
	(segment
		(start 351.822258 -35.264852)
		(end 352.584512 -35.264852)
		(width 0.13208)
		(layer "F.Cu")
		(net "RST_SMB_SSD12_ISO_N")
	)
	(via
		(at 352.584512 -35.264852)
		(size 0.508)
		(drill 0.254)
		(layers "F.Cu" "B.Cu")
		(net "RST_SMB_SSD12_ISO_N")
	)
	(segment
		(start 10.664952 -23.589996)
		(end 5.301996 -23.589996)
		(width 0.13208)
		(layer "F.Cu")
		(net "RST_SMB_SSD0_ISO_R_N")
	)
	(segment
		(start 9.176004 -71.117714)
		(end 9.427718 -71.117714)
		(width 0.13208)
		(layer "F.Cu")
		(net "RST_SMB_SSD0_ISO_R_N")
	)
	(segment
		(start 8.85063 -71.443088)
		(end 9.176004 -71.117714)
		(width 0.13208)
		(layer "F.Cu")
		(net "RST_SMB_SSD0_ISO_R_N")
	)
	(segment
		(start 5.301996 -23.589996)
		(end 4.572 -22.86)
		(width 0.13208)
		(layer "F.Cu")
		(net "RST_SMB_SSD0_ISO_R_N")
	)
	(via
		(at 9.427718 -71.117714)
		(size 0.508)
		(drill 0.254)
		(layers "F.Cu" "B.Cu")
		(net "RST_SMB_SSD0_ISO_R_N")
	)
	(via
		(at 4.572 -22.86)
		(size 0.508)
		(drill 0.254)
		(layers "F.Cu" "B.Cu")
		(net "RST_SMB_SSD0_ISO_R_N")
	)
	(segment
		(start 2.032 -24.257)
		(end 2.032 -23.6728)
		(width 0.15494)
		(layer "In5.Cu")
		(net "RST_SMB_SSD0_ISO_R_N")
	)
	(segment
		(start 1.600962 -71.832216)
		(end 1.600962 -70.271386)
		(width 0.15494)
		(layer "In5.Cu")
		(net "RST_SMB_SSD0_ISO_R_N")
	)
	(segment
		(start 1.600962 -66.726562)
		(end 1.600962 -27.228038)
		(width 0.15494)
		(layer "In5.Cu")
		(net "RST_SMB_SSD0_ISO_R_N")
	)
	(segment
		(start 2.032 -23.6728)
		(end 2.8448 -22.86)
		(width 0.15494)
		(layer "In5.Cu")
		(net "RST_SMB_SSD0_ISO_R_N")
	)
	(segment
		(start 3.682746 -73.914)
		(end 1.600962 -71.832216)
		(width 0.15494)
		(layer "In5.Cu")
		(net "RST_SMB_SSD0_ISO_R_N")
	)
	(segment
		(start 6.999224 -73.914)
		(end 3.682746 -73.914)
		(width 0.15494)
		(layer "In5.Cu")
		(net "RST_SMB_SSD0_ISO_R_N")
	)
	(segment
		(start 2.271014 -69.601334)
		(end 2.271014 -67.396614)
		(width 0.15494)
		(layer "In5.Cu")
		(net "RST_SMB_SSD0_ISO_R_N")
	)
	(segment
		(start 9.427718 -71.117714)
		(end 9.427718 -71.485506)
		(width 0.15494)
		(layer "In5.Cu")
		(net "RST_SMB_SSD0_ISO_R_N")
	)
	(segment
		(start 1.600962 -27.228038)
		(end 2.6162 -26.2128)
		(width 0.15494)
		(layer "In5.Cu")
		(net "RST_SMB_SSD0_ISO_R_N")
	)
	(segment
		(start 2.6162 -24.8412)
		(end 2.032 -24.257)
		(width 0.15494)
		(layer "In5.Cu")
		(net "RST_SMB_SSD0_ISO_R_N")
	)
	(segment
		(start 1.600962 -70.271386)
		(end 2.271014 -69.601334)
		(width 0.15494)
		(layer "In5.Cu")
		(net "RST_SMB_SSD0_ISO_R_N")
	)
	(segment
		(start 2.6162 -26.2128)
		(end 2.6162 -24.8412)
		(width 0.15494)
		(layer "In5.Cu")
		(net "RST_SMB_SSD0_ISO_R_N")
	)
	(segment
		(start 2.8448 -22.86)
		(end 4.572 -22.86)
		(width 0.15494)
		(layer "In5.Cu")
		(net "RST_SMB_SSD0_ISO_R_N")
	)
	(segment
		(start 9.427718 -71.485506)
		(end 6.999224 -73.914)
		(width 0.15494)
		(layer "In5.Cu")
		(net "RST_SMB_SSD0_ISO_R_N")
	)
	(segment
		(start 2.271014 -67.396614)
		(end 1.600962 -66.726562)
		(width 0.15494)
		(layer "In5.Cu")
		(net "RST_SMB_SSD0_ISO_R_N")
	)
	(segment
		(start 373.093234 -36.453572)
		(end 372.610634 -36.453572)
		(width 0.13208)
		(layer "F.Cu")
		(net "RST_SMB_SSD13_N")
	)
	(segment
		(start 372.610634 -36.167568)
		(end 372.668292 -36.10991)
		(width 0.13208)
		(layer "F.Cu")
		(net "RST_SMB_SSD13_N")
	)
	(segment
		(start 376.26417 -35.48253)
		(end 375.895362 -35.48253)
		(width 0.13208)
		(layer "F.Cu")
		(net "RST_SMB_SSD13_N")
	)
	(segment
		(start 375.412 -36.7792)
		(end 376.259598 -36.7792)
		(width 0.13208)
		(layer "F.Cu")
		(net "RST_SMB_SSD13_N")
	)
	(segment
		(start 373.182134 -37.025072)
		(end 373.182134 -36.542472)
		(width 0.13208)
		(layer "F.Cu")
		(net "RST_SMB_SSD13_N")
	)
	(segment
		(start 373.182134 -36.542472)
		(end 373.093234 -36.453572)
		(width 0.13208)
		(layer "F.Cu")
		(net "RST_SMB_SSD13_N")
	)
	(segment
		(start 374.74271 -36.10991)
		(end 375.412 -36.7792)
		(width 0.13208)
		(layer "F.Cu")
		(net "RST_SMB_SSD13_N")
	)
	(segment
		(start 372.668292 -36.10991)
		(end 374.74271 -36.10991)
		(width 0.13208)
		(layer "F.Cu")
		(net "RST_SMB_SSD13_N")
	)
	(segment
		(start 372.610634 -36.453572)
		(end 372.610634 -36.167568)
		(width 0.13208)
		(layer "F.Cu")
		(net "RST_SMB_SSD13_N")
	)
	(segment
		(start 376.4026 -36.636198)
		(end 376.4026 -35.62096)
		(width 0.13208)
		(layer "F.Cu")
		(net "RST_SMB_SSD13_N")
	)
	(segment
		(start 376.259598 -36.7792)
		(end 376.4026 -36.636198)
		(width 0.13208)
		(layer "F.Cu")
		(net "RST_SMB_SSD13_N")
	)
	(segment
		(start 376.4026 -35.62096)
		(end 376.26417 -35.48253)
		(width 0.13208)
		(layer "F.Cu")
		(net "RST_SMB_SSD13_N")
	)
	(via
		(at 372.610634 -36.453572)
		(size 0.508)
		(drill 0.254)
		(layers "F.Cu" "B.Cu")
		(net "RST_SMB_SSD13_N")
	)
	(segment
		(start 261.722108 -35.264852)
		(end 262.484362 -35.264852)
		(width 0.13208)
		(layer "F.Cu")
		(net "RST_SMB_SSD9_ISO_N")
	)
	(segment
		(start 263.093962 -34.248852)
		(end 263.093962 -35.264852)
		(width 0.13208)
		(layer "F.Cu")
		(net "RST_SMB_SSD9_ISO_N")
	)
	(segment
		(start 261.595108 -34.732468)
		(end 261.595108 -35.137852)
		(width 0.13208)
		(layer "F.Cu")
		(net "RST_SMB_SSD9_ISO_N")
	)
	(segment
		(start 261.595108 -35.137852)
		(end 261.722108 -35.264852)
		(width 0.13208)
		(layer "F.Cu")
		(net "RST_SMB_SSD9_ISO_N")
	)
	(segment
		(start 262.484362 -35.264852)
		(end 263.093962 -35.264852)
		(width 0.13208)
		(layer "F.Cu")
		(net "RST_SMB_SSD9_ISO_N")
	)
	(segment
		(start 263.093962 -33.257236)
		(end 263.093962 -34.248852)
		(width 0.13208)
		(layer "F.Cu")
		(net "RST_SMB_SSD9_ISO_N")
	)
	(segment
		(start 263.101836 -33.249362)
		(end 263.093962 -33.257236)
		(width 0.13208)
		(layer "F.Cu")
		(net "RST_SMB_SSD9_ISO_N")
	)
	(via
		(at 262.484362 -35.264852)
		(size 0.508)
		(drill 0.254)
		(layers "F.Cu" "B.Cu")
		(net "RST_SMB_SSD9_ISO_N")
	)
	(segment
		(start 8.05053 -73.475088)
		(end 8.05053 -72.459088)
		(width 0.13208)
		(layer "F.Cu")
		(net "RST_SMB_SSD0_ISO_N")
	)
	(segment
		(start 7.395464 -71.406766)
		(end 6.644894 -71.406766)
		(width 0.13208)
		(layer "F.Cu")
		(net "RST_SMB_SSD0_ISO_N")
	)
	(segment
		(start 8.014208 -71.406766)
		(end 7.395464 -71.406766)
		(width 0.13208)
		(layer "F.Cu")
		(net "RST_SMB_SSD0_ISO_N")
	)
	(segment
		(start 8.05053 -72.459088)
		(end 8.05053 -71.443088)
		(width 0.13208)
		(layer "F.Cu")
		(net "RST_SMB_SSD0_ISO_N")
	)
	(segment
		(start 8.05053 -71.443088)
		(end 8.014208 -71.406766)
		(width 0.13208)
		(layer "F.Cu")
		(net "RST_SMB_SSD0_ISO_N")
	)
	(via
		(at 7.395464 -71.406766)
		(size 0.508)
		(drill 0.254)
		(layers "F.Cu" "B.Cu")
		(net "RST_SMB_SSD0_ISO_N")
	)
	(segment
		(start 282.568142 -36.10991)
		(end 282.510484 -36.167568)
		(width 0.13208)
		(layer "F.Cu")
		(net "RST_SMB_SSD10_N")
	)
	(segment
		(start 286.16402 -35.48253)
		(end 286.3342 -35.65271)
		(width 0.13208)
		(layer "F.Cu")
		(net "RST_SMB_SSD10_N")
	)
	(segment
		(start 282.993084 -36.453572)
		(end 283.081984 -36.542472)
		(width 0.13208)
		(layer "F.Cu")
		(net "RST_SMB_SSD10_N")
	)
	(segment
		(start 285.795212 -35.48253)
		(end 286.16402 -35.48253)
		(width 0.13208)
		(layer "F.Cu")
		(net "RST_SMB_SSD10_N")
	)
	(segment
		(start 285.165546 -36.7538)
		(end 284.521656 -36.10991)
		(width 0.13208)
		(layer "F.Cu")
		(net "RST_SMB_SSD10_N")
	)
	(segment
		(start 283.081984 -36.542472)
		(end 283.081984 -37.025072)
		(width 0.13208)
		(layer "F.Cu")
		(net "RST_SMB_SSD10_N")
	)
	(segment
		(start 282.510484 -36.167568)
		(end 282.510484 -36.453572)
		(width 0.13208)
		(layer "F.Cu")
		(net "RST_SMB_SSD10_N")
	)
	(segment
		(start 284.521656 -36.10991)
		(end 282.568142 -36.10991)
		(width 0.13208)
		(layer "F.Cu")
		(net "RST_SMB_SSD10_N")
	)
	(segment
		(start 282.510484 -36.453572)
		(end 282.993084 -36.453572)
		(width 0.13208)
		(layer "F.Cu")
		(net "RST_SMB_SSD10_N")
	)
	(segment
		(start 286.3342 -35.65271)
		(end 286.3342 -36.579048)
		(width 0.13208)
		(layer "F.Cu")
		(net "RST_SMB_SSD10_N")
	)
	(segment
		(start 286.3342 -36.579048)
		(end 286.159448 -36.7538)
		(width 0.13208)
		(layer "F.Cu")
		(net "RST_SMB_SSD10_N")
	)
	(segment
		(start 286.159448 -36.7538)
		(end 285.165546 -36.7538)
		(width 0.13208)
		(layer "F.Cu")
		(net "RST_SMB_SSD10_N")
	)
	(via
		(at 282.510484 -36.453572)
		(size 0.508)
		(drill 0.254)
		(layers "F.Cu" "B.Cu")
		(net "RST_SMB_SSD10_N")
	)
	(segment
		(start 425.18203 -37.025072)
		(end 425.18203 -36.542472)
		(width 0.13208)
		(layer "F.Cu")
		(net "RST_SMB_SSD15_N")
	)
	(segment
		(start 428.259494 -36.83)
		(end 428.4218 -36.667694)
		(width 0.13208)
		(layer "F.Cu")
		(net "RST_SMB_SSD15_N")
	)
	(segment
		(start 428.264066 -35.48253)
		(end 427.895258 -35.48253)
		(width 0.13208)
		(layer "F.Cu")
		(net "RST_SMB_SSD15_N")
	)
	(segment
		(start 428.4218 -35.640264)
		(end 428.264066 -35.48253)
		(width 0.13208)
		(layer "F.Cu")
		(net "RST_SMB_SSD15_N")
	)
	(segment
		(start 427.5074 -36.83)
		(end 428.259494 -36.83)
		(width 0.13208)
		(layer "F.Cu")
		(net "RST_SMB_SSD15_N")
	)
	(segment
		(start 428.4218 -36.667694)
		(end 428.4218 -35.640264)
		(width 0.13208)
		(layer "F.Cu")
		(net "RST_SMB_SSD15_N")
	)
	(segment
		(start 424.61053 -36.453572)
		(end 424.61053 -36.167568)
		(width 0.13208)
		(layer "F.Cu")
		(net "RST_SMB_SSD15_N")
	)
	(segment
		(start 424.668188 -36.10991)
		(end 426.78731 -36.10991)
		(width 0.13208)
		(layer "F.Cu")
		(net "RST_SMB_SSD15_N")
	)
	(segment
		(start 426.78731 -36.10991)
		(end 427.5074 -36.83)
		(width 0.13208)
		(layer "F.Cu")
		(net "RST_SMB_SSD15_N")
	)
	(segment
		(start 424.61053 -36.167568)
		(end 424.668188 -36.10991)
		(width 0.13208)
		(layer "F.Cu")
		(net "RST_SMB_SSD15_N")
	)
	(segment
		(start 425.18203 -36.542472)
		(end 425.09313 -36.453572)
		(width 0.13208)
		(layer "F.Cu")
		(net "RST_SMB_SSD15_N")
	)
	(segment
		(start 425.09313 -36.453572)
		(end 424.61053 -36.453572)
		(width 0.13208)
		(layer "F.Cu")
		(net "RST_SMB_SSD15_N")
	)
	(via
		(at 424.61053 -36.453572)
		(size 0.508)
		(drill 0.254)
		(layers "F.Cu" "B.Cu")
		(net "RST_SMB_SSD15_N")
	)
	(segment
		(start 347.182186 -37.025072)
		(end 347.182186 -36.542472)
		(width 0.13208)
		(layer "F.Cu")
		(net "RST_SMB_SSD12_N")
	)
	(segment
		(start 346.610686 -36.167568)
		(end 346.610686 -36.453572)
		(width 0.13208)
		(layer "F.Cu")
		(net "RST_SMB_SSD12_N")
	)
	(segment
		(start 348.75851 -36.10991)
		(end 346.668344 -36.10991)
		(width 0.13208)
		(layer "F.Cu")
		(net "RST_SMB_SSD12_N")
	)
	(segment
		(start 350.264222 -35.48253)
		(end 350.4184 -35.636708)
		(width 0.13208)
		(layer "F.Cu")
		(net "RST_SMB_SSD12_N")
	)
	(segment
		(start 350.2914 -36.7538)
		(end 349.4024 -36.7538)
		(width 0.13208)
		(layer "F.Cu")
		(net "RST_SMB_SSD12_N")
	)
	(segment
		(start 346.668344 -36.10991)
		(end 346.610686 -36.167568)
		(width 0.13208)
		(layer "F.Cu")
		(net "RST_SMB_SSD12_N")
	)
	(segment
		(start 349.895414 -35.48253)
		(end 350.264222 -35.48253)
		(width 0.13208)
		(layer "F.Cu")
		(net "RST_SMB_SSD12_N")
	)
	(segment
		(start 350.4184 -36.6268)
		(end 350.2914 -36.7538)
		(width 0.13208)
		(layer "F.Cu")
		(net "RST_SMB_SSD12_N")
	)
	(segment
		(start 349.4024 -36.7538)
		(end 348.75851 -36.10991)
		(width 0.13208)
		(layer "F.Cu")
		(net "RST_SMB_SSD12_N")
	)
	(segment
		(start 347.182186 -36.542472)
		(end 347.093286 -36.453572)
		(width 0.13208)
		(layer "F.Cu")
		(net "RST_SMB_SSD12_N")
	)
	(segment
		(start 347.093286 -36.453572)
		(end 346.610686 -36.453572)
		(width 0.13208)
		(layer "F.Cu")
		(net "RST_SMB_SSD12_N")
	)
	(segment
		(start 350.4184 -35.636708)
		(end 350.4184 -36.6268)
		(width 0.13208)
		(layer "F.Cu")
		(net "RST_SMB_SSD12_N")
	)
	(via
		(at 346.610686 -36.453572)
		(size 0.508)
		(drill 0.254)
		(layers "F.Cu" "B.Cu")
		(net "RST_SMB_SSD12_N")
	)
	(segment
		(start 405.194008 -33.257236)
		(end 405.194008 -34.248852)
		(width 0.13208)
		(layer "F.Cu")
		(net "RST_SMB_SSD14_ISO_N")
	)
	(segment
		(start 404.584408 -35.264852)
		(end 403.822154 -35.264852)
		(width 0.13208)
		(layer "F.Cu")
		(net "RST_SMB_SSD14_ISO_N")
	)
	(segment
		(start 403.822154 -35.264852)
		(end 403.695154 -35.137852)
		(width 0.13208)
		(layer "F.Cu")
		(net "RST_SMB_SSD14_ISO_N")
	)
	(segment
		(start 403.695154 -35.137852)
		(end 403.695154 -34.732468)
		(width 0.13208)
		(layer "F.Cu")
		(net "RST_SMB_SSD14_ISO_N")
	)
	(segment
		(start 405.201882 -33.249362)
		(end 405.194008 -33.257236)
		(width 0.13208)
		(layer "F.Cu")
		(net "RST_SMB_SSD14_ISO_N")
	)
	(segment
		(start 405.194008 -34.248852)
		(end 405.194008 -35.264852)
		(width 0.13208)
		(layer "F.Cu")
		(net "RST_SMB_SSD14_ISO_N")
	)
	(segment
		(start 405.194008 -35.264852)
		(end 404.584408 -35.264852)
		(width 0.13208)
		(layer "F.Cu")
		(net "RST_SMB_SSD14_ISO_N")
	)
	(via
		(at 404.584408 -35.264852)
		(size 0.508)
		(drill 0.254)
		(layers "F.Cu" "B.Cu")
		(net "RST_SMB_SSD14_ISO_N")
	)
	(segment
		(start 312.163968 -35.48253)
		(end 311.79516 -35.48253)
		(width 0.13208)
		(layer "F.Cu")
		(net "RST_SMB_SSD11_N")
	)
	(segment
		(start 309.081932 -36.542472)
		(end 308.993032 -36.453572)
		(width 0.13208)
		(layer "F.Cu")
		(net "RST_SMB_SSD11_N")
	)
	(segment
		(start 312.3438 -36.620196)
		(end 312.3438 -35.662362)
		(width 0.13208)
		(layer "F.Cu")
		(net "RST_SMB_SSD11_N")
	)
	(segment
		(start 309.081932 -37.025072)
		(end 309.081932 -36.542472)
		(width 0.13208)
		(layer "F.Cu")
		(net "RST_SMB_SSD11_N")
	)
	(segment
		(start 312.3438 -35.662362)
		(end 312.163968 -35.48253)
		(width 0.13208)
		(layer "F.Cu")
		(net "RST_SMB_SSD11_N")
	)
	(segment
		(start 311.353454 -36.8046)
		(end 312.159396 -36.8046)
		(width 0.13208)
		(layer "F.Cu")
		(net "RST_SMB_SSD11_N")
	)
	(segment
		(start 308.56809 -36.10991)
		(end 310.658764 -36.10991)
		(width 0.13208)
		(layer "F.Cu")
		(net "RST_SMB_SSD11_N")
	)
	(segment
		(start 312.159396 -36.8046)
		(end 312.3438 -36.620196)
		(width 0.13208)
		(layer "F.Cu")
		(net "RST_SMB_SSD11_N")
	)
	(segment
		(start 310.658764 -36.10991)
		(end 311.353454 -36.8046)
		(width 0.13208)
		(layer "F.Cu")
		(net "RST_SMB_SSD11_N")
	)
	(segment
		(start 308.510432 -36.453572)
		(end 308.510432 -36.167568)
		(width 0.13208)
		(layer "F.Cu")
		(net "RST_SMB_SSD11_N")
	)
	(segment
		(start 308.993032 -36.453572)
		(end 308.510432 -36.453572)
		(width 0.13208)
		(layer "F.Cu")
		(net "RST_SMB_SSD11_N")
	)
	(segment
		(start 308.510432 -36.167568)
		(end 308.56809 -36.10991)
		(width 0.13208)
		(layer "F.Cu")
		(net "RST_SMB_SSD11_N")
	)
	(via
		(at 308.510432 -36.453572)
		(size 0.508)
		(drill 0.254)
		(layers "F.Cu" "B.Cu")
		(net "RST_SMB_SSD11_N")
	)
	(segment
		(start 289.101784 -33.249362)
		(end 289.09391 -33.257236)
		(width 0.13208)
		(layer "F.Cu")
		(net "RST_SMB_SSD10_ISO_N")
	)
	(segment
		(start 287.722056 -35.264852)
		(end 288.48431 -35.264852)
		(width 0.13208)
		(layer "F.Cu")
		(net "RST_SMB_SSD10_ISO_N")
	)
	(segment
		(start 287.595056 -34.732468)
		(end 287.595056 -35.137852)
		(width 0.13208)
		(layer "F.Cu")
		(net "RST_SMB_SSD10_ISO_N")
	)
	(segment
		(start 287.595056 -35.137852)
		(end 287.722056 -35.264852)
		(width 0.13208)
		(layer "F.Cu")
		(net "RST_SMB_SSD10_ISO_N")
	)
	(segment
		(start 288.48431 -35.264852)
		(end 289.09391 -35.264852)
		(width 0.13208)
		(layer "F.Cu")
		(net "RST_SMB_SSD10_ISO_N")
	)
	(segment
		(start 289.09391 -33.257236)
		(end 289.09391 -34.248852)
		(width 0.13208)
		(layer "F.Cu")
		(net "RST_SMB_SSD10_ISO_N")
	)
	(segment
		(start 289.09391 -34.248852)
		(end 289.09391 -35.264852)
		(width 0.13208)
		(layer "F.Cu")
		(net "RST_SMB_SSD10_ISO_N")
	)
	(via
		(at 288.48431 -35.264852)
		(size 0.508)
		(drill 0.254)
		(layers "F.Cu" "B.Cu")
		(net "RST_SMB_SSD10_ISO_N")
	)
	(segment
		(start 221.130114 -84.215478)
		(end 221.590108 -84.675472)
		(width 0.13208)
		(layer "F.Cu")
		(net "SSD15_LED")
	)
	(segment
		(start 219.21216 -83.85556)
		(end 219.572078 -84.215478)
		(width 0.13208)
		(layer "F.Cu")
		(net "SSD15_LED")
	)
	(segment
		(start 218.467178 -83.110578)
		(end 219.21216 -83.85556)
		(width 0.13208)
		(layer "F.Cu")
		(net "SSD15_LED")
	)
	(segment
		(start 219.572078 -84.215478)
		(end 221.130114 -84.215478)
		(width 0.13208)
		(layer "F.Cu")
		(net "SSD15_LED")
	)
	(segment
		(start 217.422222 -83.110578)
		(end 218.467178 -83.110578)
		(width 0.13208)
		(layer "F.Cu")
		(net "SSD15_LED")
	)
	(via
		(at 219.21216 -83.85556)
		(size 0.508)
		(drill 0.254)
		(layers "F.Cu" "B.Cu")
		(net "SSD15_LED")
	)
	(segment
		(start 235.72216 -35.264852)
		(end 236.484414 -35.264852)
		(width 0.13208)
		(layer "F.Cu")
		(net "RST_SMB_SSD8_ISO_N")
	)
	(segment
		(start 235.59516 -34.732468)
		(end 235.59516 -35.137852)
		(width 0.13208)
		(layer "F.Cu")
		(net "RST_SMB_SSD8_ISO_N")
	)
	(segment
		(start 237.094014 -34.248852)
		(end 237.094014 -35.264852)
		(width 0.13208)
		(layer "F.Cu")
		(net "RST_SMB_SSD8_ISO_N")
	)
	(segment
		(start 235.59516 -35.137852)
		(end 235.72216 -35.264852)
		(width 0.13208)
		(layer "F.Cu")
		(net "RST_SMB_SSD8_ISO_N")
	)
	(segment
		(start 237.101888 -33.249362)
		(end 237.094014 -33.257236)
		(width 0.13208)
		(layer "F.Cu")
		(net "RST_SMB_SSD8_ISO_N")
	)
	(segment
		(start 237.094014 -33.257236)
		(end 237.094014 -34.248852)
		(width 0.13208)
		(layer "F.Cu")
		(net "RST_SMB_SSD8_ISO_N")
	)
	(segment
		(start 236.484414 -35.264852)
		(end 237.094014 -35.264852)
		(width 0.13208)
		(layer "F.Cu")
		(net "RST_SMB_SSD8_ISO_N")
	)
	(via
		(at 236.484414 -35.264852)
		(size 0.508)
		(drill 0.254)
		(layers "F.Cu" "B.Cu")
		(net "RST_SMB_SSD8_ISO_N")
	)
	(segment
		(start 221.426024 -83.495388)
		(end 221.590108 -83.659472)
		(width 0.13208)
		(layer "F.Cu")
		(net "SSD14_LED")
	)
	(segment
		(start 220.402404 -83.493864)
		(end 220.705172 -83.493864)
		(width 0.13208)
		(layer "F.Cu")
		(net "SSD14_LED")
	)
	(segment
		(start 220.706696 -83.495388)
		(end 220.960696 -83.495388)
		(width 0.13208)
		(layer "F.Cu")
		(net "SSD14_LED")
	)
	(segment
		(start 220.960696 -83.495388)
		(end 221.426024 -83.495388)
		(width 0.13208)
		(layer "F.Cu")
		(net "SSD14_LED")
	)
	(segment
		(start 219.9132 -83.00466)
		(end 220.402404 -83.493864)
		(width 0.13208)
		(layer "F.Cu")
		(net "SSD14_LED")
	)
	(segment
		(start 218.282266 -82.460592)
		(end 218.826334 -83.00466)
		(width 0.13208)
		(layer "F.Cu")
		(net "SSD14_LED")
	)
	(segment
		(start 217.422222 -82.460592)
		(end 218.282266 -82.460592)
		(width 0.13208)
		(layer "F.Cu")
		(net "SSD14_LED")
	)
	(segment
		(start 220.705172 -83.493864)
		(end 220.706696 -83.495388)
		(width 0.13208)
		(layer "F.Cu")
		(net "SSD14_LED")
	)
	(segment
		(start 218.826334 -83.00466)
		(end 219.9132 -83.00466)
		(width 0.13208)
		(layer "F.Cu")
		(net "SSD14_LED")
	)
	(via
		(at 220.960696 -83.495388)
		(size 0.508)
		(drill 0.254)
		(layers "F.Cu" "B.Cu")
		(net "SSD14_LED")
	)
	(segment
		(start 366.569498 -254.385572)
		(end 366.569498 -256.016252)
		(width 0.13208)
		(layer "F.Cu")
		(net "PWR_EN_PEX_R1")
	)
	(segment
		(start 366.569498 -256.016252)
		(end 365.980726 -256.605024)
		(width 0.13208)
		(layer "F.Cu")
		(net "PWR_EN_PEX_R1")
	)
	(segment
		(start 365.980726 -256.605024)
		(end 365.980726 -257.658108)
		(width 0.13208)
		(layer "F.Cu")
		(net "PWR_EN_PEX_R1")
	)
	(via
		(at 365.980726 -256.605024)
		(size 0.508)
		(drill 0.254)
		(layers "F.Cu" "B.Cu")
		(net "PWR_EN_PEX_R1")
	)
	(segment
		(start 339.693758 -220.78696)
		(end 339.293962 -221.186756)
		(width 0.381)
		(layer "F.Cu")
		(net "P3V3_FPGA_VCCIO5")
	)
	(segment
		(start 335.693766 -223.987106)
		(end 335.29397 -224.386902)
		(width 0.381)
		(layer "F.Cu")
		(net "P3V3_FPGA_VCCIO5")
	)
	(segment
		(start 339.693758 -221.58706)
		(end 339.293962 -221.986856)
		(width 0.381)
		(layer "F.Cu")
		(net "P3V3_FPGA_VCCIO5")
	)
	(via
		(at 329.302364 -229.481126)
		(size 0.6604)
		(drill 0.3302)
		(layers "F.Cu" "B.Cu")
		(net "P3V3_FPGA_VCCIO5")
	)
	(via
		(at 339.293962 -221.186756)
		(size 0.4572)
		(drill 0.254)
		(layers "F.Cu" "B.Cu")
		(net "P3V3_FPGA_VCCIO5")
	)
	(via
		(at 329.937364 -228.50094)
		(size 0.508)
		(drill 0.254)
		(layers "F.Cu" "B.Cu")
		(net "P3V3_FPGA_VCCIO5")
	)
	(via
		(at 334.163162 -225.937318)
		(size 0.6604)
		(drill 0.3302)
		(layers "F.Cu" "B.Cu")
		(net "P3V3_FPGA_VCCIO5")
	)
	(via
		(at 339.293962 -221.986856)
		(size 0.4572)
		(drill 0.254)
		(layers "F.Cu" "B.Cu")
		(net "P3V3_FPGA_VCCIO5")
	)
	(via
		(at 335.29397 -224.386902)
		(size 0.4572)
		(drill 0.254)
		(layers "F.Cu" "B.Cu")
		(net "P3V3_FPGA_VCCIO5")
	)
	(via
		(at 329.302364 -228.50094)
		(size 0.508)
		(drill 0.254)
		(layers "F.Cu" "B.Cu")
		(net "P3V3_FPGA_VCCIO5")
	)
	(via
		(at 330.17333 -227.72243)
		(size 0.6604)
		(drill 0.3302)
		(layers "F.Cu" "B.Cu")
		(net "P3V3_FPGA_VCCIO5")
	)
	(segment
		(start 329.302364 -228.50094)
		(end 329.302364 -229.481126)
		(width 0.13208)
		(layer "B.Cu")
		(net "P3V3_FPGA_VCCIO5")
	)
	(segment
		(start 366.638586 -261.373874)
		(end 366.630712 -261.366)
		(width 0.13208)
		(layer "F.Cu")
		(net "PWR_EN_PEX_BUF")
	)
	(segment
		(start 366.638586 -262.721344)
		(end 366.638586 -261.373874)
		(width 0.13208)
		(layer "F.Cu")
		(net "PWR_EN_PEX_BUF")
	)
	(segment
		(start 366.630712 -261.366)
		(end 366.630712 -259.858256)
		(width 0.13208)
		(layer "F.Cu")
		(net "PWR_EN_PEX_BUF")
	)
	(via
		(at 366.630712 -261.366)
		(size 0.762)
		(drill 0.381)
		(layers "F.Cu" "B.Cu")
		(net "PWR_EN_PEX_BUF")
	)
	(segment
		(start 339.693758 -219.187014)
		(end 339.293962 -218.787218)
		(width 0.381)
		(layer "F.Cu")
		(net "P3V3_FPGA_VCCIO4")
	)
	(segment
		(start 335.693766 -219.187014)
		(end 335.29397 -218.787218)
		(width 0.381)
		(layer "F.Cu")
		(net "P3V3_FPGA_VCCIO4")
	)
	(segment
		(start 339.693758 -219.987114)
		(end 339.293962 -220.38691)
		(width 0.381)
		(layer "F.Cu")
		(net "P3V3_FPGA_VCCIO4")
	)
	(via
		(at 339.293962 -220.38691)
		(size 0.4572)
		(drill 0.254)
		(layers "F.Cu" "B.Cu")
		(net "P3V3_FPGA_VCCIO4")
	)
	(via
		(at 338.379562 -219.599764)
		(size 0.6604)
		(drill 0.3302)
		(layers "F.Cu" "B.Cu")
		(net "P3V3_FPGA_VCCIO4")
	)
	(via
		(at 332.77175 -219.417646)
		(size 0.6604)
		(drill 0.3302)
		(layers "F.Cu" "B.Cu")
		(net "P3V3_FPGA_VCCIO4")
	)
	(via
		(at 339.293962 -218.787218)
		(size 0.4572)
		(drill 0.254)
		(layers "F.Cu" "B.Cu")
		(net "P3V3_FPGA_VCCIO4")
	)
	(via
		(at 335.29397 -218.787218)
		(size 0.4572)
		(drill 0.254)
		(layers "F.Cu" "B.Cu")
		(net "P3V3_FPGA_VCCIO4")
	)
	(via
		(at 336.877152 -219.608908)
		(size 0.6604)
		(drill 0.3302)
		(layers "F.Cu" "B.Cu")
		(net "P3V3_FPGA_VCCIO4")
	)
	(segment
		(start 221.590108 -82.643472)
		(end 219.450158 -82.643472)
		(width 0.13208)
		(layer "F.Cu")
		(net "SSD13_LED")
	)
	(segment
		(start 219.450158 -82.643472)
		(end 219.230956 -82.42427)
		(width 0.13208)
		(layer "F.Cu")
		(net "SSD13_LED")
	)
	(segment
		(start 219.230956 -82.42427)
		(end 218.617038 -81.810352)
		(width 0.13208)
		(layer "F.Cu")
		(net "SSD13_LED")
	)
	(segment
		(start 218.617038 -81.810352)
		(end 217.422222 -81.810352)
		(width 0.13208)
		(layer "F.Cu")
		(net "SSD13_LED")
	)
	(via
		(at 219.230956 -82.42427)
		(size 0.508)
		(drill 0.254)
		(layers "F.Cu" "B.Cu")
		(net "SSD13_LED")
	)
	(segment
		(start 335.693766 -214.387176)
		(end 335.29397 -213.98738)
		(width 0.381)
		(layer "F.Cu")
		(net "P3V3_FPGA_VCCIO3")
	)
	(segment
		(start 339.693758 -217.587068)
		(end 339.293962 -217.187272)
		(width 0.381)
		(layer "F.Cu")
		(net "P3V3_FPGA_VCCIO3")
	)
	(segment
		(start 339.693758 -218.387168)
		(end 339.293962 -217.987372)
		(width 0.381)
		(layer "F.Cu")
		(net "P3V3_FPGA_VCCIO3")
	)
	(via
		(at 334.036416 -216.459054)
		(size 0.6604)
		(drill 0.3302)
		(layers "F.Cu" "B.Cu")
		(net "P3V3_FPGA_VCCIO3")
	)
	(via
		(at 339.293962 -217.187272)
		(size 0.4572)
		(drill 0.254)
		(layers "F.Cu" "B.Cu")
		(net "P3V3_FPGA_VCCIO3")
	)
	(via
		(at 332.912212 -217.673174)
		(size 0.6604)
		(drill 0.3302)
		(layers "F.Cu" "B.Cu")
		(net "P3V3_FPGA_VCCIO3")
	)
	(via
		(at 335.29397 -213.98738)
		(size 0.4572)
		(drill 0.254)
		(layers "F.Cu" "B.Cu")
		(net "P3V3_FPGA_VCCIO3")
	)
	(via
		(at 339.293962 -217.987372)
		(size 0.4572)
		(drill 0.254)
		(layers "F.Cu" "B.Cu")
		(net "P3V3_FPGA_VCCIO3")
	)
	(via
		(at 333.339186 -214.830152)
		(size 0.6604)
		(drill 0.3302)
		(layers "F.Cu" "B.Cu")
		(net "P3V3_FPGA_VCCIO3")
	)
	(segment
		(start 335.28254 -213.98738)
		(end 335.29397 -213.98738)
		(width 0.254)
		(layer "B.Cu")
		(net "P3V3_FPGA_VCCIO3")
	)
	(segment
		(start 334.889094 -213.593934)
		(end 335.28254 -213.98738)
		(width 0.254)
		(layer "B.Cu")
		(net "P3V3_FPGA_VCCIO3")
	)
	(segment
		(start 358.400096 -209.279236)
		(end 359.016046 -209.279236)
		(width 0.13208)
		(layer "F.Cu")
		(net "PWRGD_P1V2_AUX_FPGA_R")
	)
	(segment
		(start 243.8273 -185.829702)
		(end 243.8273 -186.481212)
		(width 0.13208)
		(layer "F.Cu")
		(net "PWRGD_P1V2_AUX_FPGA_R")
	)
	(via
		(at 359.016046 -209.279236)
		(size 0.508)
		(drill 0.254)
		(layers "F.Cu" "B.Cu")
		(net "PWRGD_P1V2_AUX_FPGA_R")
	)
	(via
		(at 243.8273 -186.481212)
		(size 0.508)
		(drill 0.254)
		(layers "F.Cu" "B.Cu")
		(net "PWRGD_P1V2_AUX_FPGA_R")
	)
	(segment
		(start 252.470158 -186.965082)
		(end 252.916436 -186.518804)
		(width 0.15494)
		(layer "In15.Cu")
		(net "PWRGD_P1V2_AUX_FPGA_R")
	)
	(segment
		(start 355.21646 -192.131188)
		(end 355.24567 -192.174876)
		(width 0.15494)
		(layer "In15.Cu")
		(net "PWRGD_P1V2_AUX_FPGA_R")
	)
	(segment
		(start 332.86573 -190.051182)
		(end 341.25281 -190.051182)
		(width 0.15494)
		(layer "In15.Cu")
		(net "PWRGD_P1V2_AUX_FPGA_R")
	)
	(segment
		(start 355.24567 -192.174876)
		(end 355.24567 -199.260968)
		(width 0.15494)
		(layer "In15.Cu")
		(net "PWRGD_P1V2_AUX_FPGA_R")
	)
	(segment
		(start 344.89644 -189.024768)
		(end 352.11004 -189.024768)
		(width 0.15494)
		(layer "In15.Cu")
		(net "PWRGD_P1V2_AUX_FPGA_R")
	)
	(segment
		(start 343.987628 -189.93358)
		(end 344.89644 -189.024768)
		(width 0.15494)
		(layer "In15.Cu")
		(net "PWRGD_P1V2_AUX_FPGA_R")
	)
	(segment
		(start 252.916436 -186.518804)
		(end 259.681472 -186.518804)
		(width 0.15494)
		(layer "In15.Cu")
		(net "PWRGD_P1V2_AUX_FPGA_R")
	)
	(segment
		(start 330.043282 -187.228734)
		(end 332.86573 -190.051182)
		(width 0.15494)
		(layer "In15.Cu")
		(net "PWRGD_P1V2_AUX_FPGA_R")
	)
	(segment
		(start 244.31117 -186.965082)
		(end 252.470158 -186.965082)
		(width 0.15494)
		(layer "In15.Cu")
		(net "PWRGD_P1V2_AUX_FPGA_R")
	)
	(segment
		(start 283.221684 -185.00979)
		(end 285.811722 -187.599828)
		(width 0.15494)
		(layer "In15.Cu")
		(net "PWRGD_P1V2_AUX_FPGA_R")
	)
	(segment
		(start 300.950884 -187.228734)
		(end 330.043282 -187.228734)
		(width 0.15494)
		(layer "In15.Cu")
		(net "PWRGD_P1V2_AUX_FPGA_R")
	)
	(segment
		(start 261.190486 -185.00979)
		(end 283.221684 -185.00979)
		(width 0.15494)
		(layer "In15.Cu")
		(net "PWRGD_P1V2_AUX_FPGA_R")
	)
	(segment
		(start 341.370412 -189.93358)
		(end 343.987628 -189.93358)
		(width 0.15494)
		(layer "In15.Cu")
		(net "PWRGD_P1V2_AUX_FPGA_R")
	)
	(segment
		(start 352.11004 -189.024768)
		(end 355.21646 -192.131188)
		(width 0.15494)
		(layer "In15.Cu")
		(net "PWRGD_P1V2_AUX_FPGA_R")
	)
	(segment
		(start 259.681472 -186.518804)
		(end 261.190486 -185.00979)
		(width 0.15494)
		(layer "In15.Cu")
		(net "PWRGD_P1V2_AUX_FPGA_R")
	)
	(segment
		(start 341.25281 -190.051182)
		(end 341.370412 -189.93358)
		(width 0.15494)
		(layer "In15.Cu")
		(net "PWRGD_P1V2_AUX_FPGA_R")
	)
	(segment
		(start 359.016046 -203.031344)
		(end 359.016046 -209.279236)
		(width 0.15494)
		(layer "In15.Cu")
		(net "PWRGD_P1V2_AUX_FPGA_R")
	)
	(segment
		(start 300.57979 -187.599828)
		(end 300.950884 -187.228734)
		(width 0.15494)
		(layer "In15.Cu")
		(net "PWRGD_P1V2_AUX_FPGA_R")
	)
	(segment
		(start 355.24567 -199.260968)
		(end 359.016046 -203.031344)
		(width 0.15494)
		(layer "In15.Cu")
		(net "PWRGD_P1V2_AUX_FPGA_R")
	)
	(segment
		(start 285.811722 -187.599828)
		(end 300.57979 -187.599828)
		(width 0.15494)
		(layer "In15.Cu")
		(net "PWRGD_P1V2_AUX_FPGA_R")
	)
	(segment
		(start 243.8273 -186.481212)
		(end 244.31117 -186.965082)
		(width 0.15494)
		(layer "In15.Cu")
		(net "PWRGD_P1V2_AUX_FPGA_R")
	)
	(segment
		(start 344.49385 -216.786968)
		(end 344.893646 -216.387172)
		(width 0.381)
		(layer "F.Cu")
		(net "P3V3_FPGA_VCCIO2")
	)
	(segment
		(start 338.893912 -213.587076)
		(end 338.494116 -213.18728)
		(width 0.381)
		(layer "F.Cu")
		(net "P3V3_FPGA_VCCIO2")
	)
	(segment
		(start 346.093796 -213.587076)
		(end 346.493592 -213.18728)
		(width 0.381)
		(layer "F.Cu")
		(net "P3V3_FPGA_VCCIO2")
	)
	(segment
		(start 342.893904 -216.786968)
		(end 343.2937 -216.387172)
		(width 0.381)
		(layer "F.Cu")
		(net "P3V3_FPGA_VCCIO2")
	)
	(segment
		(start 342.093804 -216.786968)
		(end 341.694008 -216.387172)
		(width 0.381)
		(layer "F.Cu")
		(net "P3V3_FPGA_VCCIO2")
	)
	(segment
		(start 342.093804 -213.587076)
		(end 341.694008 -213.18728)
		(width 0.381)
		(layer "F.Cu")
		(net "P3V3_FPGA_VCCIO2")
	)
	(segment
		(start 354.212398 -204.750416)
		(end 354.212398 -204.127862)
		(width 0.13208)
		(layer "F.Cu")
		(net "P3V3_FPGA_VCCIO2")
	)
	(segment
		(start 340.493858 -216.786968)
		(end 340.094062 -216.387172)
		(width 0.381)
		(layer "F.Cu")
		(net "P3V3_FPGA_VCCIO2")
	)
	(segment
		(start 341.293958 -216.786968)
		(end 340.894162 -216.387172)
		(width 0.381)
		(layer "F.Cu")
		(net "P3V3_FPGA_VCCIO2")
	)
	(segment
		(start 343.69375 -216.786968)
		(end 344.093546 -216.387172)
		(width 0.381)
		(layer "F.Cu")
		(net "P3V3_FPGA_VCCIO2")
	)
	(via
		(at 332.914498 -210.872324)
		(size 0.508)
		(drill 0.254)
		(layers "F.Cu" "B.Cu")
		(net "P3V3_FPGA_VCCIO2")
	)
	(via
		(at 354.212398 -204.127862)
		(size 0.508)
		(drill 0.254)
		(layers "F.Cu" "B.Cu")
		(net "P3V3_FPGA_VCCIO2")
	)
	(via
		(at 331.121512 -213.627716)
		(size 0.6604)
		(drill 0.3302)
		(layers "F.Cu" "B.Cu")
		(net "P3V3_FPGA_VCCIO2")
	)
	(via
		(at 344.893646 -216.387172)
		(size 0.4572)
		(drill 0.254)
		(layers "F.Cu" "B.Cu")
		(net "P3V3_FPGA_VCCIO2")
	)
	(via
		(at 342.46185 -215.689434)
		(size 0.6604)
		(drill 0.3302)
		(layers "F.Cu" "B.Cu")
		(net "P3V3_FPGA_VCCIO2")
	)
	(via
		(at 340.094062 -216.387172)
		(size 0.4572)
		(drill 0.254)
		(layers "F.Cu" "B.Cu")
		(net "P3V3_FPGA_VCCIO2")
	)
	(via
		(at 332.914498 -210.237324)
		(size 0.508)
		(drill 0.254)
		(layers "F.Cu" "B.Cu")
		(net "P3V3_FPGA_VCCIO2")
	)
	(via
		(at 341.694008 -216.387172)
		(size 0.4572)
		(drill 0.254)
		(layers "F.Cu" "B.Cu")
		(net "P3V3_FPGA_VCCIO2")
	)
	(via
		(at 338.494116 -213.18728)
		(size 0.4572)
		(drill 0.254)
		(layers "F.Cu" "B.Cu")
		(net "P3V3_FPGA_VCCIO2")
	)
	(via
		(at 333.064358 -212.739478)
		(size 0.6604)
		(drill 0.3302)
		(layers "F.Cu" "B.Cu")
		(net "P3V3_FPGA_VCCIO2")
	)
	(via
		(at 341.694008 -213.18728)
		(size 0.4572)
		(drill 0.254)
		(layers "F.Cu" "B.Cu")
		(net "P3V3_FPGA_VCCIO2")
	)
	(via
		(at 346.493592 -213.18728)
		(size 0.4572)
		(drill 0.254)
		(layers "F.Cu" "B.Cu")
		(net "P3V3_FPGA_VCCIO2")
	)
	(via
		(at 344.093546 -216.387172)
		(size 0.4572)
		(drill 0.254)
		(layers "F.Cu" "B.Cu")
		(net "P3V3_FPGA_VCCIO2")
	)
	(via
		(at 340.894162 -216.387172)
		(size 0.4572)
		(drill 0.254)
		(layers "F.Cu" "B.Cu")
		(net "P3V3_FPGA_VCCIO2")
	)
	(via
		(at 343.2937 -216.387172)
		(size 0.4572)
		(drill 0.254)
		(layers "F.Cu" "B.Cu")
		(net "P3V3_FPGA_VCCIO2")
	)
	(via
		(at 332.914498 -211.507324)
		(size 0.508)
		(drill 0.254)
		(layers "F.Cu" "B.Cu")
		(net "P3V3_FPGA_VCCIO2")
	)
	(segment
		(start 346.093796 -213.587076)
		(end 346.154248 -213.587076)
		(width 0.254)
		(layer "B.Cu")
		(net "P3V3_FPGA_VCCIO2")
	)
	(segment
		(start 331.829664 -212.919564)
		(end 331.121512 -213.627716)
		(width 0.13208)
		(layer "B.Cu")
		(net "P3V3_FPGA_VCCIO2")
	)
	(segment
		(start 346.154248 -213.587076)
		(end 346.493592 -213.247732)
		(width 0.254)
		(layer "B.Cu")
		(net "P3V3_FPGA_VCCIO2")
	)
	(segment
		(start 346.493592 -213.247732)
		(end 346.493592 -213.18728)
		(width 0.254)
		(layer "B.Cu")
		(net "P3V3_FPGA_VCCIO2")
	)
	(segment
		(start 342.093804 -213.587076)
		(end 341.694008 -213.18728)
		(width 0.254)
		(layer "B.Cu")
		(net "P3V3_FPGA_VCCIO2")
	)
	(segment
		(start 338.093812 -212.786976)
		(end 338.494116 -213.18728)
		(width 0.254)
		(layer "B.Cu")
		(net "P3V3_FPGA_VCCIO2")
	)
	(segment
		(start 153.780998 -24.189944)
		(end 152.764998 -24.189944)
		(width 0.13208)
		(layer "F.Cu")
		(net "SSD5_LED_ISO_R_N")
	)
	(segment
		(start 163.985702 -24.75865)
		(end 163.350702 -24.75865)
		(width 0.13208)
		(layer "F.Cu")
		(net "SSD5_LED_ISO_R_N")
	)
	(via
		(at 163.350702 -24.75865)
		(size 0.508)
		(drill 0.254)
		(layers "F.Cu" "B.Cu")
		(net "SSD5_LED_ISO_R_N")
	)
	(via
		(at 153.780998 -24.189944)
		(size 0.508)
		(drill 0.254)
		(layers "F.Cu" "B.Cu")
		(net "SSD5_LED_ISO_R_N")
	)
	(segment
		(start 157.223714 -23.486364)
		(end 157.96895 -24.2316)
		(width 0.15494)
		(layer "In5.Cu")
		(net "SSD5_LED_ISO_R_N")
	)
	(segment
		(start 157.96895 -24.2316)
		(end 159.28975 -24.2316)
		(width 0.15494)
		(layer "In5.Cu")
		(net "SSD5_LED_ISO_R_N")
	)
	(segment
		(start 159.28975 -24.2316)
		(end 159.56915 -24.511)
		(width 0.15494)
		(layer "In5.Cu")
		(net "SSD5_LED_ISO_R_N")
	)
	(segment
		(start 155.861512 -23.486364)
		(end 157.223714 -23.486364)
		(width 0.15494)
		(layer "In5.Cu")
		(net "SSD5_LED_ISO_R_N")
	)
	(segment
		(start 163.103052 -24.511)
		(end 163.350702 -24.75865)
		(width 0.15494)
		(layer "In5.Cu")
		(net "SSD5_LED_ISO_R_N")
	)
	(segment
		(start 155.157932 -24.189944)
		(end 155.861512 -23.486364)
		(width 0.15494)
		(layer "In5.Cu")
		(net "SSD5_LED_ISO_R_N")
	)
	(segment
		(start 153.780998 -24.189944)
		(end 155.157932 -24.189944)
		(width 0.15494)
		(layer "In5.Cu")
		(net "SSD5_LED_ISO_R_N")
	)
	(segment
		(start 159.56915 -24.511)
		(end 163.103052 -24.511)
		(width 0.15494)
		(layer "In5.Cu")
		(net "SSD5_LED_ISO_R_N")
	)
	(segment
		(start 345.29395 -220.78696)
		(end 345.693746 -221.186756)
		(width 0.381)
		(layer "F.Cu")
		(net "P3V3_FPGA_VCCIO1")
	)
	(segment
		(start 345.29395 -217.587068)
		(end 345.693746 -217.187272)
		(width 0.381)
		(layer "F.Cu")
		(net "P3V3_FPGA_VCCIO1")
	)
	(segment
		(start 347.693742 -219.187014)
		(end 348.093538 -218.787218)
		(width 0.381)
		(layer "F.Cu")
		(net "P3V3_FPGA_VCCIO1")
	)
	(segment
		(start 349.293942 -214.387176)
		(end 349.693738 -213.98738)
		(width 0.381)
		(layer "F.Cu")
		(net "P3V3_FPGA_VCCIO1")
	)
	(segment
		(start 345.29395 -221.58706)
		(end 345.693746 -221.986856)
		(width 0.381)
		(layer "F.Cu")
		(net "P3V3_FPGA_VCCIO1")
	)
	(segment
		(start 345.29395 -218.387168)
		(end 345.693746 -217.987372)
		(width 0.381)
		(layer "F.Cu")
		(net "P3V3_FPGA_VCCIO1")
	)
	(segment
		(start 349.293942 -223.987106)
		(end 349.693738 -224.386902)
		(width 0.381)
		(layer "F.Cu")
		(net "P3V3_FPGA_VCCIO1")
	)
	(segment
		(start 345.29395 -219.987114)
		(end 345.693746 -220.38691)
		(width 0.381)
		(layer "F.Cu")
		(net "P3V3_FPGA_VCCIO1")
	)
	(segment
		(start 345.29395 -219.187014)
		(end 345.693746 -218.787218)
		(width 0.381)
		(layer "F.Cu")
		(net "P3V3_FPGA_VCCIO1")
	)
	(via
		(at 345.693746 -221.986856)
		(size 0.4572)
		(drill 0.254)
		(layers "F.Cu" "B.Cu")
		(net "P3V3_FPGA_VCCIO1")
	)
	(via
		(at 345.693746 -221.186756)
		(size 0.4572)
		(drill 0.254)
		(layers "F.Cu" "B.Cu")
		(net "P3V3_FPGA_VCCIO1")
	)
	(via
		(at 351.573338 -217.214958)
		(size 0.6604)
		(drill 0.3302)
		(layers "F.Cu" "B.Cu")
		(net "P3V3_FPGA_VCCIO1")
	)
	(via
		(at 345.693746 -217.987372)
		(size 0.4572)
		(drill 0.254)
		(layers "F.Cu" "B.Cu")
		(net "P3V3_FPGA_VCCIO1")
	)
	(via
		(at 353.394264 -217.893646)
		(size 0.508)
		(drill 0.254)
		(layers "F.Cu" "B.Cu")
		(net "P3V3_FPGA_VCCIO1")
	)
	(via
		(at 352.908616 -215.151208)
		(size 0.6604)
		(drill 0.3302)
		(layers "F.Cu" "B.Cu")
		(net "P3V3_FPGA_VCCIO1")
	)
	(via
		(at 352.675952 -217.886788)
		(size 0.508)
		(drill 0.254)
		(layers "F.Cu" "B.Cu")
		(net "P3V3_FPGA_VCCIO1")
	)
	(via
		(at 350.13646 -219.672662)
		(size 0.6604)
		(drill 0.3302)
		(layers "F.Cu" "B.Cu")
		(net "P3V3_FPGA_VCCIO1")
	)
	(via
		(at 349.693738 -224.386902)
		(size 0.4572)
		(drill 0.254)
		(layers "F.Cu" "B.Cu")
		(net "P3V3_FPGA_VCCIO1")
	)
	(via
		(at 348.093538 -218.787218)
		(size 0.4572)
		(drill 0.254)
		(layers "F.Cu" "B.Cu")
		(net "P3V3_FPGA_VCCIO1")
	)
	(via
		(at 345.693746 -217.187272)
		(size 0.4572)
		(drill 0.254)
		(layers "F.Cu" "B.Cu")
		(net "P3V3_FPGA_VCCIO1")
	)
	(via
		(at 345.693746 -220.38691)
		(size 0.4572)
		(drill 0.254)
		(layers "F.Cu" "B.Cu")
		(net "P3V3_FPGA_VCCIO1")
	)
	(via
		(at 345.693746 -218.787218)
		(size 0.4572)
		(drill 0.254)
		(layers "F.Cu" "B.Cu")
		(net "P3V3_FPGA_VCCIO1")
	)
	(via
		(at 349.693738 -213.98738)
		(size 0.4572)
		(drill 0.254)
		(layers "F.Cu" "B.Cu")
		(net "P3V3_FPGA_VCCIO1")
	)
	(segment
		(start 165.47084 -25.211786)
		(end 166.374064 -25.211786)
		(width 0.13208)
		(layer "F.Cu")
		(net "SSD5_LED_ISO_N")
	)
	(segment
		(start 163.985702 -25.55875)
		(end 165.123876 -25.55875)
		(width 0.13208)
		(layer "F.Cu")
		(net "SSD5_LED_ISO_N")
	)
	(segment
		(start 165.123876 -25.55875)
		(end 165.47084 -25.211786)
		(width 0.13208)
		(layer "F.Cu")
		(net "SSD5_LED_ISO_N")
	)
	(segment
		(start 163.985702 -26.692098)
		(end 163.985702 -25.55875)
		(width 0.13208)
		(layer "F.Cu")
		(net "SSD5_LED_ISO_N")
	)
	(via
		(at 165.123876 -25.55875)
		(size 0.508)
		(drill 0.254)
		(layers "F.Cu" "B.Cu")
		(net "SSD5_LED_ISO_N")
	)
	(segment
		(start 356.5271 -209.279236)
		(end 357.599996 -209.279236)
		(width 0.13208)
		(layer "F.Cu")
		(net "PWRGD_P1V2_AUX_FPGA")
	)
	(segment
		(start 346.893896 -217.587068)
		(end 347.293692 -217.187272)
		(width 0.13208)
		(layer "F.Cu")
		(net "PWRGD_P1V2_AUX_FPGA")
	)
	(segment
		(start 355.617526 -210.18881)
		(end 356.5271 -209.279236)
		(width 0.13208)
		(layer "F.Cu")
		(net "PWRGD_P1V2_AUX_FPGA")
	)
	(via
		(at 355.617526 -210.18881)
		(size 0.508)
		(drill 0.254)
		(layers "F.Cu" "B.Cu")
		(net "PWRGD_P1V2_AUX_FPGA")
	)
	(via
		(at 347.293692 -217.187272)
		(size 0.4572)
		(drill 0.254)
		(layers "F.Cu" "B.Cu")
		(net "PWRGD_P1V2_AUX_FPGA")
	)
	(segment
		(start 353.885754 -212.368892)
		(end 354.9523 -212.368892)
		(width 0.15494)
		(layer "In9.Cu")
		(net "PWRGD_P1V2_AUX_FPGA")
	)
	(segment
		(start 349.296228 -215.747092)
		(end 349.296228 -214.62238)
		(width 0.0889)
		(layer "In9.Cu")
		(net "PWRGD_P1V2_AUX_FPGA")
	)
	(segment
		(start 347.696028 -216.784936)
		(end 347.696028 -216.222326)
		(width 0.0889)
		(layer "In9.Cu")
		(net "PWRGD_P1V2_AUX_FPGA")
	)
	(segment
		(start 347.933518 -215.984836)
		(end 349.058484 -215.984836)
		(width 0.0889)
		(layer "In9.Cu")
		(net "PWRGD_P1V2_AUX_FPGA")
	)
	(segment
		(start 351.869756 -214.38489)
		(end 353.885754 -212.368892)
		(width 0.15494)
		(layer "In9.Cu")
		(net "PWRGD_P1V2_AUX_FPGA")
	)
	(segment
		(start 347.696028 -216.222326)
		(end 347.933518 -215.984836)
		(width 0.0889)
		(layer "In9.Cu")
		(net "PWRGD_P1V2_AUX_FPGA")
	)
	(segment
		(start 349.533718 -214.38489)
		(end 351.869756 -214.38489)
		(width 0.0889)
		(layer "In9.Cu")
		(net "PWRGD_P1V2_AUX_FPGA")
	)
	(segment
		(start 347.293692 -217.187272)
		(end 347.696028 -216.784936)
		(width 0.0889)
		(layer "In9.Cu")
		(net "PWRGD_P1V2_AUX_FPGA")
	)
	(segment
		(start 349.296228 -214.62238)
		(end 349.533718 -214.38489)
		(width 0.0889)
		(layer "In9.Cu")
		(net "PWRGD_P1V2_AUX_FPGA")
	)
	(segment
		(start 354.9523 -212.368892)
		(end 355.617526 -211.703666)
		(width 0.15494)
		(layer "In9.Cu")
		(net "PWRGD_P1V2_AUX_FPGA")
	)
	(segment
		(start 355.617526 -211.703666)
		(end 355.617526 -210.18881)
		(width 0.15494)
		(layer "In9.Cu")
		(net "PWRGD_P1V2_AUX_FPGA")
	)
	(segment
		(start 349.058484 -215.984836)
		(end 349.296228 -215.747092)
		(width 0.0889)
		(layer "In9.Cu")
		(net "PWRGD_P1V2_AUX_FPGA")
	)
	(segment
		(start 342.093804 -222.38716)
		(end 341.694008 -222.786956)
		(width 0.381)
		(layer "F.Cu")
		(net "P3V3_FPGA_VCCIO0")
	)
	(segment
		(start 338.893912 -226.387152)
		(end 338.494116 -226.786948)
		(width 0.381)
		(layer "F.Cu")
		(net "P3V3_FPGA_VCCIO0")
	)
	(segment
		(start 341.293958 -223.187006)
		(end 340.894162 -223.586802)
		(width 0.381)
		(layer "F.Cu")
		(net "P3V3_FPGA_VCCIO0")
	)
	(segment
		(start 343.69375 -223.187006)
		(end 344.093546 -223.586802)
		(width 0.381)
		(layer "F.Cu")
		(net "P3V3_FPGA_VCCIO0")
	)
	(segment
		(start 342.893904 -222.38716)
		(end 343.2937 -222.786956)
		(width 0.381)
		(layer "F.Cu")
		(net "P3V3_FPGA_VCCIO0")
	)
	(segment
		(start 346.093796 -226.387152)
		(end 346.493592 -226.786948)
		(width 0.381)
		(layer "F.Cu")
		(net "P3V3_FPGA_VCCIO0")
	)
	(segment
		(start 342.893904 -226.387152)
		(end 343.2937 -226.786948)
		(width 0.381)
		(layer "F.Cu")
		(net "P3V3_FPGA_VCCIO0")
	)
	(segment
		(start 340.493858 -222.38716)
		(end 340.094062 -222.786956)
		(width 0.381)
		(layer "F.Cu")
		(net "P3V3_FPGA_VCCIO0")
	)
	(segment
		(start 344.49385 -222.38716)
		(end 344.893646 -222.786956)
		(width 0.381)
		(layer "F.Cu")
		(net "P3V3_FPGA_VCCIO0")
	)
	(via
		(at 352.673666 -226.802442)
		(size 0.508)
		(drill 0.254)
		(layers "F.Cu" "B.Cu")
		(net "P3V3_FPGA_VCCIO0")
	)
	(via
		(at 352.233738 -227.723192)
		(size 0.6604)
		(drill 0.3302)
		(layers "F.Cu" "B.Cu")
		(net "P3V3_FPGA_VCCIO0")
	)
	(via
		(at 344.893646 -222.786956)
		(size 0.4572)
		(drill 0.254)
		(layers "F.Cu" "B.Cu")
		(net "P3V3_FPGA_VCCIO0")
	)
	(via
		(at 342.426036 -227.654612)
		(size 0.6604)
		(drill 0.3302)
		(layers "F.Cu" "B.Cu")
		(net "P3V3_FPGA_VCCIO0")
	)
	(via
		(at 340.894162 -223.586802)
		(size 0.4572)
		(drill 0.254)
		(layers "F.Cu" "B.Cu")
		(net "P3V3_FPGA_VCCIO0")
	)
	(via
		(at 346.493592 -226.786948)
		(size 0.4572)
		(drill 0.254)
		(layers "F.Cu" "B.Cu")
		(net "P3V3_FPGA_VCCIO0")
	)
	(via
		(at 343.2937 -226.786948)
		(size 0.4572)
		(drill 0.254)
		(layers "F.Cu" "B.Cu")
		(net "P3V3_FPGA_VCCIO0")
	)
	(via
		(at 343.2937 -222.786956)
		(size 0.4572)
		(drill 0.254)
		(layers "F.Cu" "B.Cu")
		(net "P3V3_FPGA_VCCIO0")
	)
	(via
		(at 338.494116 -226.786948)
		(size 0.4572)
		(drill 0.254)
		(layers "F.Cu" "B.Cu")
		(net "P3V3_FPGA_VCCIO0")
	)
	(via
		(at 342.43518 -223.546416)
		(size 0.6604)
		(drill 0.3302)
		(layers "F.Cu" "B.Cu")
		(net "P3V3_FPGA_VCCIO0")
	)
	(via
		(at 340.094062 -222.786956)
		(size 0.4572)
		(drill 0.254)
		(layers "F.Cu" "B.Cu")
		(net "P3V3_FPGA_VCCIO0")
	)
	(via
		(at 352.038666 -226.802442)
		(size 0.508)
		(drill 0.254)
		(layers "F.Cu" "B.Cu")
		(net "P3V3_FPGA_VCCIO0")
	)
	(via
		(at 344.093546 -223.586802)
		(size 0.4572)
		(drill 0.254)
		(layers "F.Cu" "B.Cu")
		(net "P3V3_FPGA_VCCIO0")
	)
	(via
		(at 353.308666 -226.802442)
		(size 0.508)
		(drill 0.254)
		(layers "F.Cu" "B.Cu")
		(net "P3V3_FPGA_VCCIO0")
	)
	(via
		(at 341.694008 -222.786956)
		(size 0.4572)
		(drill 0.254)
		(layers "F.Cu" "B.Cu")
		(net "P3V3_FPGA_VCCIO0")
	)
	(segment
		(start 343.2937 -226.786948)
		(end 342.426036 -227.654612)
		(width 0.13208)
		(layer "B.Cu")
		(net "P3V3_FPGA_VCCIO0")
	)
	(segment
		(start 338.893912 -226.387152)
		(end 338.823808 -226.387152)
		(width 0.254)
		(layer "B.Cu")
		(net "P3V3_FPGA_VCCIO0")
	)
	(segment
		(start 346.893896 -226.387152)
		(end 346.833444 -226.387152)
		(width 0.254)
		(layer "B.Cu")
		(net "P3V3_FPGA_VCCIO0")
	)
	(segment
		(start 342.893904 -226.387152)
		(end 343.2937 -226.786948)
		(width 0.254)
		(layer "B.Cu")
		(net "P3V3_FPGA_VCCIO0")
	)
	(segment
		(start 338.823808 -226.387152)
		(end 338.494116 -226.716844)
		(width 0.254)
		(layer "B.Cu")
		(net "P3V3_FPGA_VCCIO0")
	)
	(segment
		(start 346.493592 -226.727004)
		(end 346.493592 -226.786948)
		(width 0.254)
		(layer "B.Cu")
		(net "P3V3_FPGA_VCCIO0")
	)
	(segment
		(start 346.833444 -226.387152)
		(end 346.493592 -226.727004)
		(width 0.254)
		(layer "B.Cu")
		(net "P3V3_FPGA_VCCIO0")
	)
	(segment
		(start 338.494116 -226.716844)
		(end 338.494116 -226.786948)
		(width 0.254)
		(layer "B.Cu")
		(net "P3V3_FPGA_VCCIO0")
	)
	(segment
		(start 127.78105 -24.189944)
		(end 126.76505 -24.189944)
		(width 0.13208)
		(layer "F.Cu")
		(net "SSD4_LED_ISO_R_N")
	)
	(segment
		(start 137.985754 -24.75865)
		(end 137.350754 -24.75865)
		(width 0.13208)
		(layer "F.Cu")
		(net "SSD4_LED_ISO_R_N")
	)
	(via
		(at 137.350754 -24.75865)
		(size 0.508)
		(drill 0.254)
		(layers "F.Cu" "B.Cu")
		(net "SSD4_LED_ISO_R_N")
	)
	(via
		(at 127.78105 -24.189944)
		(size 0.508)
		(drill 0.254)
		(layers "F.Cu" "B.Cu")
		(net "SSD4_LED_ISO_R_N")
	)
	(segment
		(start 129.157984 -24.189944)
		(end 129.861564 -23.486364)
		(width 0.15494)
		(layer "In5.Cu")
		(net "SSD4_LED_ISO_R_N")
	)
	(segment
		(start 133.289802 -24.2316)
		(end 133.569202 -24.511)
		(width 0.15494)
		(layer "In5.Cu")
		(net "SSD4_LED_ISO_R_N")
	)
	(segment
		(start 131.223766 -23.486364)
		(end 131.969002 -24.2316)
		(width 0.15494)
		(layer "In5.Cu")
		(net "SSD4_LED_ISO_R_N")
	)
	(segment
		(start 131.969002 -24.2316)
		(end 133.289802 -24.2316)
		(width 0.15494)
		(layer "In5.Cu")
		(net "SSD4_LED_ISO_R_N")
	)
	(segment
		(start 133.569202 -24.511)
		(end 137.103104 -24.511)
		(width 0.15494)
		(layer "In5.Cu")
		(net "SSD4_LED_ISO_R_N")
	)
	(segment
		(start 129.861564 -23.486364)
		(end 131.223766 -23.486364)
		(width 0.15494)
		(layer "In5.Cu")
		(net "SSD4_LED_ISO_R_N")
	)
	(segment
		(start 127.78105 -24.189944)
		(end 129.157984 -24.189944)
		(width 0.15494)
		(layer "In5.Cu")
		(net "SSD4_LED_ISO_R_N")
	)
	(segment
		(start 137.103104 -24.511)
		(end 137.350754 -24.75865)
		(width 0.15494)
		(layer "In5.Cu")
		(net "SSD4_LED_ISO_R_N")
	)
	(segment
		(start 219.872052 -81.160366)
		(end 220.339158 -81.627472)
		(width 0.13208)
		(layer "F.Cu")
		(net "SSD12_LED")
	)
	(segment
		(start 217.422222 -81.160366)
		(end 219.872052 -81.160366)
		(width 0.13208)
		(layer "F.Cu")
		(net "SSD12_LED")
	)
	(segment
		(start 220.339158 -81.627472)
		(end 220.960696 -81.627472)
		(width 0.13208)
		(layer "F.Cu")
		(net "SSD12_LED")
	)
	(segment
		(start 220.960696 -81.627472)
		(end 221.590108 -81.627472)
		(width 0.13208)
		(layer "F.Cu")
		(net "SSD12_LED")
	)
	(via
		(at 220.960696 -81.627472)
		(size 0.508)
		(drill 0.254)
		(layers "F.Cu" "B.Cu")
		(net "SSD12_LED")
	)
	(segment
		(start 341.293958 -218.387168)
		(end 340.894162 -217.987372)
		(width 0.381)
		(layer "F.Cu")
		(net "P3V3_VCC_FPGA_CORE")
	)
	(segment
		(start 342.893904 -220.78696)
		(end 343.2937 -221.186756)
		(width 0.381)
		(layer "F.Cu")
		(net "P3V3_VCC_FPGA_CORE")
	)
	(segment
		(start 343.69375 -218.387168)
		(end 344.093546 -217.987372)
		(width 0.381)
		(layer "F.Cu")
		(net "P3V3_VCC_FPGA_CORE")
	)
	(segment
		(start 341.293958 -220.78696)
		(end 340.894162 -221.186756)
		(width 0.381)
		(layer "F.Cu")
		(net "P3V3_VCC_FPGA_CORE")
	)
	(segment
		(start 342.893904 -219.987114)
		(end 343.2937 -220.38691)
		(width 0.381)
		(layer "F.Cu")
		(net "P3V3_VCC_FPGA_CORE")
	)
	(segment
		(start 342.093804 -219.187014)
		(end 341.694008 -218.787218)
		(width 0.381)
		(layer "F.Cu")
		(net "P3V3_VCC_FPGA_CORE")
	)
	(segment
		(start 342.093804 -218.387168)
		(end 341.694008 -217.987372)
		(width 0.381)
		(layer "F.Cu")
		(net "P3V3_VCC_FPGA_CORE")
	)
	(segment
		(start 343.69375 -220.78696)
		(end 344.093546 -221.186756)
		(width 0.381)
		(layer "F.Cu")
		(net "P3V3_VCC_FPGA_CORE")
	)
	(segment
		(start 342.893904 -219.187014)
		(end 343.2937 -218.787218)
		(width 0.381)
		(layer "F.Cu")
		(net "P3V3_VCC_FPGA_CORE")
	)
	(segment
		(start 342.893904 -218.387168)
		(end 343.2937 -217.987372)
		(width 0.381)
		(layer "F.Cu")
		(net "P3V3_VCC_FPGA_CORE")
	)
	(segment
		(start 342.093804 -219.987114)
		(end 341.694008 -220.38691)
		(width 0.381)
		(layer "F.Cu")
		(net "P3V3_VCC_FPGA_CORE")
	)
	(segment
		(start 342.093804 -220.78696)
		(end 341.694008 -221.186756)
		(width 0.381)
		(layer "F.Cu")
		(net "P3V3_VCC_FPGA_CORE")
	)
	(via
		(at 340.894162 -217.987372)
		(size 0.4572)
		(drill 0.254)
		(layers "F.Cu" "B.Cu")
		(net "P3V3_VCC_FPGA_CORE")
	)
	(via
		(at 343.2937 -218.787218)
		(size 0.4572)
		(drill 0.254)
		(layers "F.Cu" "B.Cu")
		(net "P3V3_VCC_FPGA_CORE")
	)
	(via
		(at 353.106228 -221.85884)
		(size 0.508)
		(drill 0.254)
		(layers "F.Cu" "B.Cu")
		(net "P3V3_VCC_FPGA_CORE")
	)
	(via
		(at 343.2937 -217.987372)
		(size 0.4572)
		(drill 0.254)
		(layers "F.Cu" "B.Cu")
		(net "P3V3_VCC_FPGA_CORE")
	)
	(via
		(at 341.694008 -221.186756)
		(size 0.4572)
		(drill 0.254)
		(layers "F.Cu" "B.Cu")
		(net "P3V3_VCC_FPGA_CORE")
	)
	(via
		(at 352.026982 -225.194876)
		(size 0.6604)
		(drill 0.3302)
		(layers "F.Cu" "B.Cu")
		(net "P3V3_VCC_FPGA_CORE")
	)
	(via
		(at 344.093546 -221.186756)
		(size 0.4572)
		(drill 0.254)
		(layers "F.Cu" "B.Cu")
		(net "P3V3_VCC_FPGA_CORE")
	)
	(via
		(at 353.508056 -225.330512)
		(size 0.6604)
		(drill 0.3302)
		(layers "F.Cu" "B.Cu")
		(net "P3V3_VCC_FPGA_CORE")
	)
	(via
		(at 343.2937 -220.38691)
		(size 0.4572)
		(drill 0.254)
		(layers "F.Cu" "B.Cu")
		(net "P3V3_VCC_FPGA_CORE")
	)
	(via
		(at 341.694008 -220.38691)
		(size 0.4572)
		(drill 0.254)
		(layers "F.Cu" "B.Cu")
		(net "P3V3_VCC_FPGA_CORE")
	)
	(via
		(at 343.2937 -221.186756)
		(size 0.4572)
		(drill 0.254)
		(layers "F.Cu" "B.Cu")
		(net "P3V3_VCC_FPGA_CORE")
	)
	(via
		(at 352.445828 -221.865698)
		(size 0.508)
		(drill 0.254)
		(layers "F.Cu" "B.Cu")
		(net "P3V3_VCC_FPGA_CORE")
	)
	(via
		(at 351.881694 -222.42145)
		(size 0.6604)
		(drill 0.3302)
		(layers "F.Cu" "B.Cu")
		(net "P3V3_VCC_FPGA_CORE")
	)
	(via
		(at 344.093546 -217.987372)
		(size 0.4572)
		(drill 0.254)
		(layers "F.Cu" "B.Cu")
		(net "P3V3_VCC_FPGA_CORE")
	)
	(via
		(at 340.894162 -221.186756)
		(size 0.4572)
		(drill 0.254)
		(layers "F.Cu" "B.Cu")
		(net "P3V3_VCC_FPGA_CORE")
	)
	(via
		(at 341.694008 -218.787218)
		(size 0.4572)
		(drill 0.254)
		(layers "F.Cu" "B.Cu")
		(net "P3V3_VCC_FPGA_CORE")
	)
	(via
		(at 341.694008 -217.987372)
		(size 0.4572)
		(drill 0.254)
		(layers "F.Cu" "B.Cu")
		(net "P3V3_VCC_FPGA_CORE")
	)
	(segment
		(start 139.123928 -25.55875)
		(end 139.470892 -25.211786)
		(width 0.13208)
		(layer "F.Cu")
		(net "SSD4_LED_ISO_N")
	)
	(segment
		(start 137.985754 -25.55875)
		(end 139.123928 -25.55875)
		(width 0.13208)
		(layer "F.Cu")
		(net "SSD4_LED_ISO_N")
	)
	(segment
		(start 139.470892 -25.211786)
		(end 140.374116 -25.211786)
		(width 0.13208)
		(layer "F.Cu")
		(net "SSD4_LED_ISO_N")
	)
	(segment
		(start 137.985754 -26.692098)
		(end 137.985754 -25.55875)
		(width 0.13208)
		(layer "F.Cu")
		(net "SSD4_LED_ISO_N")
	)
	(via
		(at 139.123928 -25.55875)
		(size 0.508)
		(drill 0.254)
		(layers "F.Cu" "B.Cu")
		(net "SSD4_LED_ISO_N")
	)
	(segment
		(start 89.680796 -24.189944)
		(end 88.664796 -24.189944)
		(width 0.13208)
		(layer "F.Cu")
		(net "SSD3_LED_ISO_R_N")
	)
	(segment
		(start 99.8855 -24.75865)
		(end 99.2505 -24.75865)
		(width 0.13208)
		(layer "F.Cu")
		(net "SSD3_LED_ISO_R_N")
	)
	(via
		(at 99.2505 -24.75865)
		(size 0.508)
		(drill 0.254)
		(layers "F.Cu" "B.Cu")
		(net "SSD3_LED_ISO_R_N")
	)
	(via
		(at 89.680796 -24.189944)
		(size 0.508)
		(drill 0.254)
		(layers "F.Cu" "B.Cu")
		(net "SSD3_LED_ISO_R_N")
	)
	(segment
		(start 91.05773 -24.189944)
		(end 91.76131 -23.486364)
		(width 0.15494)
		(layer "In5.Cu")
		(net "SSD3_LED_ISO_R_N")
	)
	(segment
		(start 91.76131 -23.486364)
		(end 93.123512 -23.486364)
		(width 0.15494)
		(layer "In5.Cu")
		(net "SSD3_LED_ISO_R_N")
	)
	(segment
		(start 93.123512 -23.486364)
		(end 93.868748 -24.2316)
		(width 0.15494)
		(layer "In5.Cu")
		(net "SSD3_LED_ISO_R_N")
	)
	(segment
		(start 98.97745 -24.4856)
		(end 99.2505 -24.75865)
		(width 0.15494)
		(layer "In5.Cu")
		(net "SSD3_LED_ISO_R_N")
	)
	(segment
		(start 95.189548 -24.2316)
		(end 95.443548 -24.4856)
		(width 0.15494)
		(layer "In5.Cu")
		(net "SSD3_LED_ISO_R_N")
	)
	(segment
		(start 95.443548 -24.4856)
		(end 98.97745 -24.4856)
		(width 0.15494)
		(layer "In5.Cu")
		(net "SSD3_LED_ISO_R_N")
	)
	(segment
		(start 89.680796 -24.189944)
		(end 91.05773 -24.189944)
		(width 0.15494)
		(layer "In5.Cu")
		(net "SSD3_LED_ISO_R_N")
	)
	(segment
		(start 93.868748 -24.2316)
		(end 95.189548 -24.2316)
		(width 0.15494)
		(layer "In5.Cu")
		(net "SSD3_LED_ISO_R_N")
	)
	(segment
		(start 99.8855 -25.55875)
		(end 101.023674 -25.55875)
		(width 0.13208)
		(layer "F.Cu")
		(net "SSD3_LED_ISO_N")
	)
	(segment
		(start 101.370638 -25.211786)
		(end 102.273862 -25.211786)
		(width 0.13208)
		(layer "F.Cu")
		(net "SSD3_LED_ISO_N")
	)
	(segment
		(start 101.023674 -25.55875)
		(end 101.370638 -25.211786)
		(width 0.13208)
		(layer "F.Cu")
		(net "SSD3_LED_ISO_N")
	)
	(segment
		(start 99.8855 -26.692098)
		(end 99.8855 -25.55875)
		(width 0.13208)
		(layer "F.Cu")
		(net "SSD3_LED_ISO_N")
	)
	(via
		(at 101.023674 -25.55875)
		(size 0.508)
		(drill 0.254)
		(layers "F.Cu" "B.Cu")
		(net "SSD3_LED_ISO_N")
	)
	(segment
		(start 221.064836 -80.611472)
		(end 220.963744 -80.51038)
		(width 0.13208)
		(layer "F.Cu")
		(net "SSD11_LED")
	)
	(segment
		(start 221.590108 -80.611472)
		(end 221.064836 -80.611472)
		(width 0.13208)
		(layer "F.Cu")
		(net "SSD11_LED")
	)
	(segment
		(start 220.963744 -80.51038)
		(end 219.31122 -80.51038)
		(width 0.13208)
		(layer "F.Cu")
		(net "SSD11_LED")
	)
	(segment
		(start 219.31122 -80.51038)
		(end 217.422222 -80.51038)
		(width 0.13208)
		(layer "F.Cu")
		(net "SSD11_LED")
	)
	(via
		(at 219.31122 -80.51038)
		(size 0.508)
		(drill 0.254)
		(layers "F.Cu" "B.Cu")
		(net "SSD11_LED")
	)
	(segment
		(start 198.994014 -33.257236)
		(end 198.994014 -34.248852)
		(width 0.13208)
		(layer "F.Cu")
		(net "RST_SMB_SSD7_ISO_N")
	)
	(segment
		(start 197.62216 -35.264852)
		(end 197.49516 -35.137852)
		(width 0.13208)
		(layer "F.Cu")
		(net "RST_SMB_SSD7_ISO_N")
	)
	(segment
		(start 198.994014 -34.248852)
		(end 198.994014 -35.264852)
		(width 0.13208)
		(layer "F.Cu")
		(net "RST_SMB_SSD7_ISO_N")
	)
	(segment
		(start 198.994014 -35.264852)
		(end 198.384414 -35.264852)
		(width 0.13208)
		(layer "F.Cu")
		(net "RST_SMB_SSD7_ISO_N")
	)
	(segment
		(start 198.384414 -35.264852)
		(end 197.62216 -35.264852)
		(width 0.13208)
		(layer "F.Cu")
		(net "RST_SMB_SSD7_ISO_N")
	)
	(segment
		(start 197.49516 -35.137852)
		(end 197.49516 -34.732468)
		(width 0.13208)
		(layer "F.Cu")
		(net "RST_SMB_SSD7_ISO_N")
	)
	(segment
		(start 199.001888 -33.249362)
		(end 198.994014 -33.257236)
		(width 0.13208)
		(layer "F.Cu")
		(net "RST_SMB_SSD7_ISO_N")
	)
	(via
		(at 198.384414 -35.264852)
		(size 0.508)
		(drill 0.254)
		(layers "F.Cu" "B.Cu")
		(net "RST_SMB_SSD7_ISO_N")
	)
	(segment
		(start 73.885552 -24.75865)
		(end 73.250552 -24.75865)
		(width 0.13208)
		(layer "F.Cu")
		(net "SSD2_LED_ISO_R_N")
	)
	(segment
		(start 63.680848 -24.189944)
		(end 62.664848 -24.189944)
		(width 0.13208)
		(layer "F.Cu")
		(net "SSD2_LED_ISO_R_N")
	)
	(via
		(at 73.250552 -24.75865)
		(size 0.508)
		(drill 0.254)
		(layers "F.Cu" "B.Cu")
		(net "SSD2_LED_ISO_R_N")
	)
	(via
		(at 63.680848 -24.189944)
		(size 0.508)
		(drill 0.254)
		(layers "F.Cu" "B.Cu")
		(net "SSD2_LED_ISO_R_N")
	)
	(segment
		(start 67.8688 -24.2316)
		(end 69.1896 -24.2316)
		(width 0.15494)
		(layer "In5.Cu")
		(net "SSD2_LED_ISO_R_N")
	)
	(segment
		(start 73.002902 -24.511)
		(end 73.250552 -24.75865)
		(width 0.15494)
		(layer "In5.Cu")
		(net "SSD2_LED_ISO_R_N")
	)
	(segment
		(start 69.469 -24.511)
		(end 73.002902 -24.511)
		(width 0.15494)
		(layer "In5.Cu")
		(net "SSD2_LED_ISO_R_N")
	)
	(segment
		(start 67.123564 -23.486364)
		(end 67.8688 -24.2316)
		(width 0.15494)
		(layer "In5.Cu")
		(net "SSD2_LED_ISO_R_N")
	)
	(segment
		(start 63.680848 -24.189944)
		(end 65.057782 -24.189944)
		(width 0.15494)
		(layer "In5.Cu")
		(net "SSD2_LED_ISO_R_N")
	)
	(segment
		(start 65.761362 -23.486364)
		(end 67.123564 -23.486364)
		(width 0.15494)
		(layer "In5.Cu")
		(net "SSD2_LED_ISO_R_N")
	)
	(segment
		(start 65.057782 -24.189944)
		(end 65.761362 -23.486364)
		(width 0.15494)
		(layer "In5.Cu")
		(net "SSD2_LED_ISO_R_N")
	)
	(segment
		(start 69.1896 -24.2316)
		(end 69.469 -24.511)
		(width 0.15494)
		(layer "In5.Cu")
		(net "SSD2_LED_ISO_R_N")
	)
	(segment
		(start 431.20183 -33.249362)
		(end 431.193956 -33.257236)
		(width 0.13208)
		(layer "F.Cu")
		(net "RST_SMB_SSD15_ISO_N")
	)
	(segment
		(start 429.822102 -35.264852)
		(end 430.584356 -35.264852)
		(width 0.13208)
		(layer "F.Cu")
		(net "RST_SMB_SSD15_ISO_N")
	)
	(segment
		(start 431.193956 -34.248852)
		(end 431.193956 -35.264852)
		(width 0.13208)
		(layer "F.Cu")
		(net "RST_SMB_SSD15_ISO_N")
	)
	(segment
		(start 429.695102 -34.732468)
		(end 429.695102 -35.137852)
		(width 0.13208)
		(layer "F.Cu")
		(net "RST_SMB_SSD15_ISO_N")
	)
	(segment
		(start 429.695102 -35.137852)
		(end 429.822102 -35.264852)
		(width 0.13208)
		(layer "F.Cu")
		(net "RST_SMB_SSD15_ISO_N")
	)
	(segment
		(start 430.584356 -35.264852)
		(end 431.193956 -35.264852)
		(width 0.13208)
		(layer "F.Cu")
		(net "RST_SMB_SSD15_ISO_N")
	)
	(segment
		(start 431.193956 -33.257236)
		(end 431.193956 -34.248852)
		(width 0.13208)
		(layer "F.Cu")
		(net "RST_SMB_SSD15_ISO_N")
	)
	(via
		(at 430.584356 -35.264852)
		(size 0.508)
		(drill 0.254)
		(layers "F.Cu" "B.Cu")
		(net "RST_SMB_SSD15_ISO_N")
	)
	(segment
		(start 76.273914 -25.211786)
		(end 75.37069 -25.211786)
		(width 0.13208)
		(layer "F.Cu")
		(net "SSD2_LED_ISO_N")
	)
	(segment
		(start 75.023726 -25.55875)
		(end 73.885552 -25.55875)
		(width 0.13208)
		(layer "F.Cu")
		(net "SSD2_LED_ISO_N")
	)
	(segment
		(start 73.885552 -26.692098)
		(end 73.885552 -25.55875)
		(width 0.13208)
		(layer "F.Cu")
		(net "SSD2_LED_ISO_N")
	)
	(segment
		(start 75.37069 -25.211786)
		(end 75.023726 -25.55875)
		(width 0.13208)
		(layer "F.Cu")
		(net "SSD2_LED_ISO_N")
	)
	(via
		(at 75.023726 -25.55875)
		(size 0.508)
		(drill 0.254)
		(layers "F.Cu" "B.Cu")
		(net "SSD2_LED_ISO_N")
	)
	(segment
		(start 351.132902 -144.723104)
		(end 351.330006 -144.526)
		(width 0.13208)
		(layer "F.Cu")
		(net "RST_PEX_NIC7_PERST_N")
	)
	(segment
		(start 350.11741 -144.723104)
		(end 351.132902 -144.723104)
		(width 0.13208)
		(layer "F.Cu")
		(net "RST_PEX_NIC7_PERST_N")
	)
	(segment
		(start 350.11741 -144.101312)
		(end 350.11741 -144.723104)
		(width 0.13208)
		(layer "F.Cu")
		(net "RST_PEX_NIC7_PERST_N")
	)
	(segment
		(start 349.91802 -143.901922)
		(end 350.11741 -144.101312)
		(width 0.13208)
		(layer "F.Cu")
		(net "RST_PEX_NIC7_PERST_N")
	)
	(segment
		(start 349.000064 -143.901922)
		(end 349.91802 -143.901922)
		(width 0.13208)
		(layer "F.Cu")
		(net "RST_PEX_NIC7_PERST_N")
	)
	(segment
		(start 351.330006 -144.526)
		(end 351.832164 -144.526)
		(width 0.13208)
		(layer "F.Cu")
		(net "RST_PEX_NIC7_PERST_N")
	)
	(via
		(at 350.11741 -144.723104)
		(size 0.508)
		(drill 0.254)
		(layers "F.Cu" "B.Cu")
		(net "RST_PEX_NIC7_PERST_N")
	)
	(segment
		(start 351.5741 -143.251936)
		(end 351.832164 -143.51)
		(width 0.13208)
		(layer "F.Cu")
		(net "NIC7_PEX_PWR_EN")
	)
	(segment
		(start 349.000064 -143.251936)
		(end 350.11741 -143.251936)
		(width 0.13208)
		(layer "F.Cu")
		(net "NIC7_PEX_PWR_EN")
	)
	(segment
		(start 350.11741 -143.251936)
		(end 351.5741 -143.251936)
		(width 0.13208)
		(layer "F.Cu")
		(net "NIC7_PEX_PWR_EN")
	)
	(via
		(at 350.11741 -143.251936)
		(size 0.508)
		(drill 0.254)
		(layers "F.Cu" "B.Cu")
		(net "NIC7_PEX_PWR_EN")
	)
	(segment
		(start 350.11741 -179.153312)
		(end 350.11741 -179.775104)
		(width 0.13208)
		(layer "F.Cu")
		(net "RST_PEX_NIC4_PERST_N")
	)
	(segment
		(start 351.330006 -179.578)
		(end 353.42195 -179.578)
		(width 0.13208)
		(layer "F.Cu")
		(net "RST_PEX_NIC4_PERST_N")
	)
	(segment
		(start 349.000064 -178.953922)
		(end 349.91802 -178.953922)
		(width 0.13208)
		(layer "F.Cu")
		(net "RST_PEX_NIC4_PERST_N")
	)
	(segment
		(start 351.132902 -179.775104)
		(end 351.330006 -179.578)
		(width 0.13208)
		(layer "F.Cu")
		(net "RST_PEX_NIC4_PERST_N")
	)
	(segment
		(start 349.91802 -178.953922)
		(end 350.11741 -179.153312)
		(width 0.13208)
		(layer "F.Cu")
		(net "RST_PEX_NIC4_PERST_N")
	)
	(segment
		(start 350.11741 -179.775104)
		(end 351.132902 -179.775104)
		(width 0.13208)
		(layer "F.Cu")
		(net "RST_PEX_NIC4_PERST_N")
	)
	(via
		(at 350.11741 -179.775104)
		(size 0.508)
		(drill 0.254)
		(layers "F.Cu" "B.Cu")
		(net "RST_PEX_NIC4_PERST_N")
	)
	(segment
		(start 218.434158 -79.860394)
		(end 218.69908 -79.595472)
		(width 0.13208)
		(layer "F.Cu")
		(net "SSD10_LED")
	)
	(segment
		(start 218.69908 -79.595472)
		(end 220.960696 -79.595472)
		(width 0.13208)
		(layer "F.Cu")
		(net "SSD10_LED")
	)
	(segment
		(start 217.422222 -79.860394)
		(end 218.434158 -79.860394)
		(width 0.13208)
		(layer "F.Cu")
		(net "SSD10_LED")
	)
	(segment
		(start 220.960696 -79.595472)
		(end 221.590108 -79.595472)
		(width 0.13208)
		(layer "F.Cu")
		(net "SSD10_LED")
	)
	(via
		(at 220.960696 -79.595472)
		(size 0.508)
		(drill 0.254)
		(layers "F.Cu" "B.Cu")
		(net "SSD10_LED")
	)
	(segment
		(start 351.832164 -178.562)
		(end 353.42195 -178.562)
		(width 0.13208)
		(layer "F.Cu")
		(net "NIC4_PEX_PWR_EN")
	)
	(segment
		(start 349.000064 -178.303936)
		(end 350.11741 -178.303936)
		(width 0.13208)
		(layer "F.Cu")
		(net "NIC4_PEX_PWR_EN")
	)
	(segment
		(start 351.5741 -178.303936)
		(end 351.832164 -178.562)
		(width 0.13208)
		(layer "F.Cu")
		(net "NIC4_PEX_PWR_EN")
	)
	(segment
		(start 350.11741 -178.303936)
		(end 351.5741 -178.303936)
		(width 0.13208)
		(layer "F.Cu")
		(net "NIC4_PEX_PWR_EN")
	)
	(via
		(at 350.11741 -178.303936)
		(size 0.508)
		(drill 0.254)
		(layers "F.Cu" "B.Cu")
		(net "NIC4_PEX_PWR_EN")
	)
	(segment
		(start 47.885604 -24.75865)
		(end 47.250604 -24.75865)
		(width 0.13208)
		(layer "F.Cu")
		(net "SSD1_LED_ISO_R_N")
	)
	(segment
		(start 37.6809 -24.189944)
		(end 36.6649 -24.189944)
		(width 0.13208)
		(layer "F.Cu")
		(net "SSD1_LED_ISO_R_N")
	)
	(via
		(at 47.250604 -24.75865)
		(size 0.508)
		(drill 0.254)
		(layers "F.Cu" "B.Cu")
		(net "SSD1_LED_ISO_R_N")
	)
	(via
		(at 37.6809 -24.189944)
		(size 0.508)
		(drill 0.254)
		(layers "F.Cu" "B.Cu")
		(net "SSD1_LED_ISO_R_N")
	)
	(segment
		(start 42.071036 -24.384)
		(end 46.875954 -24.384)
		(width 0.15494)
		(layer "In5.Cu")
		(net "SSD1_LED_ISO_R_N")
	)
	(segment
		(start 39.761414 -23.486364)
		(end 41.1734 -23.486364)
		(width 0.15494)
		(layer "In5.Cu")
		(net "SSD1_LED_ISO_R_N")
	)
	(segment
		(start 46.875954 -24.384)
		(end 47.250604 -24.75865)
		(width 0.15494)
		(layer "In5.Cu")
		(net "SSD1_LED_ISO_R_N")
	)
	(segment
		(start 37.6809 -24.189944)
		(end 39.057834 -24.189944)
		(width 0.15494)
		(layer "In5.Cu")
		(net "SSD1_LED_ISO_R_N")
	)
	(segment
		(start 41.1734 -23.486364)
		(end 42.071036 -24.384)
		(width 0.15494)
		(layer "In5.Cu")
		(net "SSD1_LED_ISO_R_N")
	)
	(segment
		(start 39.057834 -24.189944)
		(end 39.761414 -23.486364)
		(width 0.15494)
		(layer "In5.Cu")
		(net "SSD1_LED_ISO_R_N")
	)
	(segment
		(start 375.793 -177.19802)
		(end 376.40895 -177.19802)
		(width 0.13208)
		(layer "F.Cu")
		(net "RST_PEX_NIC3_PERST_N")
	)
	(segment
		(start 373.611902 -175.016922)
		(end 375.793 -177.19802)
		(width 0.13208)
		(layer "F.Cu")
		(net "RST_PEX_NIC3_PERST_N")
	)
	(segment
		(start 372.114064 -175.016922)
		(end 373.611902 -175.016922)
		(width 0.13208)
		(layer "F.Cu")
		(net "RST_PEX_NIC3_PERST_N")
	)
	(via
		(at 375.793 -177.19802)
		(size 0.508)
		(drill 0.254)
		(layers "F.Cu" "B.Cu")
		(net "RST_PEX_NIC3_PERST_N")
	)
	(segment
		(start 49.370742 -25.211786)
		(end 50.273966 -25.211786)
		(width 0.13208)
		(layer "F.Cu")
		(net "SSD1_LED_ISO_N")
	)
	(segment
		(start 47.885604 -25.55875)
		(end 49.023778 -25.55875)
		(width 0.13208)
		(layer "F.Cu")
		(net "SSD1_LED_ISO_N")
	)
	(segment
		(start 49.023778 -25.55875)
		(end 49.370742 -25.211786)
		(width 0.13208)
		(layer "F.Cu")
		(net "SSD1_LED_ISO_N")
	)
	(segment
		(start 47.885604 -26.692098)
		(end 47.885604 -25.55875)
		(width 0.13208)
		(layer "F.Cu")
		(net "SSD1_LED_ISO_N")
	)
	(via
		(at 49.023778 -25.55875)
		(size 0.508)
		(drill 0.254)
		(layers "F.Cu" "B.Cu")
		(net "SSD1_LED_ISO_N")
	)
	(segment
		(start 375.793 -175.16602)
		(end 376.40895 -175.16602)
		(width 0.13208)
		(layer "F.Cu")
		(net "NIC3_PEX_PWR_EN")
	)
	(segment
		(start 375.42978 -174.8028)
		(end 375.793 -175.16602)
		(width 0.13208)
		(layer "F.Cu")
		(net "NIC3_PEX_PWR_EN")
	)
	(segment
		(start 372.114064 -174.366936)
		(end 373.883936 -174.366936)
		(width 0.13208)
		(layer "F.Cu")
		(net "NIC3_PEX_PWR_EN")
	)
	(segment
		(start 373.883936 -174.366936)
		(end 374.3198 -174.8028)
		(width 0.13208)
		(layer "F.Cu")
		(net "NIC3_PEX_PWR_EN")
	)
	(segment
		(start 374.3198 -174.8028)
		(end 375.42978 -174.8028)
		(width 0.13208)
		(layer "F.Cu")
		(net "NIC3_PEX_PWR_EN")
	)
	(via
		(at 375.793 -175.16602)
		(size 0.508)
		(drill 0.254)
		(layers "F.Cu" "B.Cu")
		(net "NIC3_PEX_PWR_EN")
	)
	(segment
		(start 2.796794 -20.24888)
		(end 3.120644 -20.24888)
		(width 0.13208)
		(layer "F.Cu")
		(net "SSD0_LED_ISO_N")
	)
	(segment
		(start 2.796794 -19.137122)
		(end 2.796794 -20.24888)
		(width 0.13208)
		(layer "F.Cu")
		(net "SSD0_LED_ISO_N")
	)
	(segment
		(start 2.231644 -20.917662)
		(end 3.247644 -20.917662)
		(width 0.13208)
		(layer "F.Cu")
		(net "SSD0_LED_ISO_N")
	)
	(segment
		(start 3.247644 -20.37588)
		(end 3.247644 -20.917662)
		(width 0.13208)
		(layer "F.Cu")
		(net "SSD0_LED_ISO_N")
	)
	(segment
		(start 3.120644 -20.24888)
		(end 3.247644 -20.37588)
		(width 0.13208)
		(layer "F.Cu")
		(net "SSD0_LED_ISO_N")
	)
	(via
		(at 2.796794 -20.24888)
		(size 0.508)
		(drill 0.254)
		(layers "F.Cu" "B.Cu")
		(net "SSD0_LED_ISO_N")
	)
	(segment
		(start 377.229624 -196.733922)
		(end 376.432064 -196.733922)
		(width 0.13208)
		(layer "F.Cu")
		(net "RST_PEX_NIC2_PERST_N")
	)
	(segment
		(start 378.869702 -198.374)
		(end 377.229624 -196.733922)
		(width 0.13208)
		(layer "F.Cu")
		(net "RST_PEX_NIC2_PERST_N")
	)
	(segment
		(start 380.85395 -198.374)
		(end 380.238 -198.374)
		(width 0.13208)
		(layer "F.Cu")
		(net "RST_PEX_NIC2_PERST_N")
	)
	(segment
		(start 380.238 -198.374)
		(end 378.869702 -198.374)
		(width 0.13208)
		(layer "F.Cu")
		(net "RST_PEX_NIC2_PERST_N")
	)
	(via
		(at 380.238 -198.374)
		(size 0.508)
		(drill 0.254)
		(layers "F.Cu" "B.Cu")
		(net "RST_PEX_NIC2_PERST_N")
	)
	(segment
		(start 3.247644 -22.327362)
		(end 3.247644 -21.717762)
		(width 0.13208)
		(layer "F.Cu")
		(net "SSD0_LED_ISO_R_N")
	)
	(segment
		(start 5.110226 -24.189944)
		(end 3.247644 -22.327362)
		(width 0.13208)
		(layer "F.Cu")
		(net "SSD0_LED_ISO_R_N")
	)
	(segment
		(start 10.664952 -24.189944)
		(end 5.110226 -24.189944)
		(width 0.13208)
		(layer "F.Cu")
		(net "SSD0_LED_ISO_R_N")
	)
	(via
		(at 3.247644 -22.327362)
		(size 0.508)
		(drill 0.254)
		(layers "F.Cu" "B.Cu")
		(net "SSD0_LED_ISO_R_N")
	)
	(segment
		(start 380.85395 -196.342)
		(end 380.190756 -196.342)
		(width 0.13208)
		(layer "F.Cu")
		(net "NIC2_PEX_PWR_EN")
	)
	(segment
		(start 379.932692 -196.083936)
		(end 376.432064 -196.083936)
		(width 0.13208)
		(layer "F.Cu")
		(net "NIC2_PEX_PWR_EN")
	)
	(segment
		(start 380.190756 -196.342)
		(end 379.932692 -196.083936)
		(width 0.13208)
		(layer "F.Cu")
		(net "NIC2_PEX_PWR_EN")
	)
	(via
		(at 380.190756 -196.342)
		(size 0.508)
		(drill 0.254)
		(layers "F.Cu" "B.Cu")
		(net "NIC2_PEX_PWR_EN")
	)
	(segment
		(start 219.31122 -78.579472)
		(end 218.680284 -79.210408)
		(width 0.13208)
		(layer "F.Cu")
		(net "SSD9_LED")
	)
	(segment
		(start 221.590108 -78.579472)
		(end 219.31122 -78.579472)
		(width 0.13208)
		(layer "F.Cu")
		(net "SSD9_LED")
	)
	(segment
		(start 218.680284 -79.210408)
		(end 217.422222 -79.210408)
		(width 0.13208)
		(layer "F.Cu")
		(net "SSD9_LED")
	)
	(via
		(at 219.31122 -78.579472)
		(size 0.508)
		(drill 0.254)
		(layers "F.Cu" "B.Cu")
		(net "SSD9_LED")
	)
	(via
		(at 302.369474 -225.773742)
		(size 0.6604)
		(drill 0.3302)
		(layers "F.Cu" "B.Cu")
		(net "RST_GPU_PERST_2_R_N")
	)
	(segment
		(start 301.88789 -224.279968)
		(end 301.88789 -225.292158)
		(width 0.13208)
		(layer "B.Cu")
		(net "RST_GPU_PERST_2_R_N")
	)
	(segment
		(start 301.88789 -225.292158)
		(end 302.369474 -225.773742)
		(width 0.13208)
		(layer "B.Cu")
		(net "RST_GPU_PERST_2_R_N")
	)
	(segment
		(start 302.369474 -225.773742)
		(end 302.369474 -227.520754)
		(width 0.13208)
		(layer "B.Cu")
		(net "RST_GPU_PERST_2_R_N")
	)
	(segment
		(start 301.607474 -223.999552)
		(end 301.88789 -224.279968)
		(width 0.13208)
		(layer "B.Cu")
		(net "RST_GPU_PERST_2_R_N")
	)
	(segment
		(start 379.147578 -209.55)
		(end 377.5075 -207.909922)
		(width 0.13208)
		(layer "F.Cu")
		(net "RST_PEX_NIC0_PERST_N")
	)
	(segment
		(start 377.5075 -207.909922)
		(end 376.432064 -207.909922)
		(width 0.13208)
		(layer "F.Cu")
		(net "RST_PEX_NIC0_PERST_N")
	)
	(segment
		(start 380.85395 -209.55)
		(end 379.79096 -209.55)
		(width 0.13208)
		(layer "F.Cu")
		(net "RST_PEX_NIC0_PERST_N")
	)
	(segment
		(start 379.79096 -209.55)
		(end 379.147578 -209.55)
		(width 0.13208)
		(layer "F.Cu")
		(net "RST_PEX_NIC0_PERST_N")
	)
	(via
		(at 379.79096 -209.55)
		(size 0.508)
		(drill 0.254)
		(layers "F.Cu" "B.Cu")
		(net "RST_PEX_NIC0_PERST_N")
	)
	(segment
		(start 379.93066 -207.259936)
		(end 380.188724 -207.518)
		(width 0.13208)
		(layer "F.Cu")
		(net "NIC0_PEX_PWR_EN")
	)
	(segment
		(start 376.432064 -207.259936)
		(end 379.93066 -207.259936)
		(width 0.13208)
		(layer "F.Cu")
		(net "NIC0_PEX_PWR_EN")
	)
	(segment
		(start 380.188724 -207.518)
		(end 380.85395 -207.518)
		(width 0.13208)
		(layer "F.Cu")
		(net "NIC0_PEX_PWR_EN")
	)
	(via
		(at 380.188724 -207.518)
		(size 0.508)
		(drill 0.254)
		(layers "F.Cu" "B.Cu")
		(net "NIC0_PEX_PWR_EN")
	)
	(segment
		(start 375.92 -187.833)
		(end 374.279922 -186.192922)
		(width 0.13208)
		(layer "F.Cu")
		(net "RST_PEX_NIC1_PERST_N")
	)
	(segment
		(start 376.53595 -187.833)
		(end 375.92 -187.833)
		(width 0.13208)
		(layer "F.Cu")
		(net "RST_PEX_NIC1_PERST_N")
	)
	(segment
		(start 374.279922 -186.192922)
		(end 372.114064 -186.192922)
		(width 0.13208)
		(layer "F.Cu")
		(net "RST_PEX_NIC1_PERST_N")
	)
	(via
		(at 375.92 -187.833)
		(size 0.508)
		(drill 0.254)
		(layers "F.Cu" "B.Cu")
		(net "RST_PEX_NIC1_PERST_N")
	)
	(segment
		(start 375.661936 -185.542936)
		(end 375.92 -185.801)
		(width 0.13208)
		(layer "F.Cu")
		(net "NIC1_PEX_PWR_EN")
	)
	(segment
		(start 372.114064 -185.542936)
		(end 375.661936 -185.542936)
		(width 0.13208)
		(layer "F.Cu")
		(net "NIC1_PEX_PWR_EN")
	)
	(segment
		(start 375.92 -185.801)
		(end 376.53595 -185.801)
		(width 0.13208)
		(layer "F.Cu")
		(net "NIC1_PEX_PWR_EN")
	)
	(via
		(at 375.92 -185.801)
		(size 0.508)
		(drill 0.254)
		(layers "F.Cu" "B.Cu")
		(net "NIC1_PEX_PWR_EN")
	)
	(segment
		(start 448.18554 -26.692098)
		(end 448.18554 -25.55875)
		(width 0.13208)
		(layer "F.Cu")
		(net "SSD15_LED_ISO_N")
	)
	(segment
		(start 449.670678 -25.211786)
		(end 450.573902 -25.211786)
		(width 0.13208)
		(layer "F.Cu")
		(net "SSD15_LED_ISO_N")
	)
	(segment
		(start 449.323714 -25.55875)
		(end 449.670678 -25.211786)
		(width 0.13208)
		(layer "F.Cu")
		(net "SSD15_LED_ISO_N")
	)
	(segment
		(start 448.18554 -25.55875)
		(end 449.323714 -25.55875)
		(width 0.13208)
		(layer "F.Cu")
		(net "SSD15_LED_ISO_N")
	)
	(via
		(at 449.323714 -25.55875)
		(size 0.508)
		(drill 0.254)
		(layers "F.Cu" "B.Cu")
		(net "SSD15_LED_ISO_N")
	)
	(segment
		(start 422.185592 -26.692098)
		(end 422.185592 -25.55875)
		(width 0.13208)
		(layer "F.Cu")
		(net "SSD14_LED_ISO_N")
	)
	(segment
		(start 422.185592 -25.55875)
		(end 423.323766 -25.55875)
		(width 0.13208)
		(layer "F.Cu")
		(net "SSD14_LED_ISO_N")
	)
	(segment
		(start 423.323766 -25.55875)
		(end 423.67073 -25.211786)
		(width 0.13208)
		(layer "F.Cu")
		(net "SSD14_LED_ISO_N")
	)
	(segment
		(start 423.67073 -25.211786)
		(end 424.573954 -25.211786)
		(width 0.13208)
		(layer "F.Cu")
		(net "SSD14_LED_ISO_N")
	)
	(via
		(at 423.323766 -25.55875)
		(size 0.508)
		(drill 0.254)
		(layers "F.Cu" "B.Cu")
		(net "SSD14_LED_ISO_N")
	)
	(segment
		(start 94.005654 -241.887502)
		(end 94.132908 -241.760248)
		(width 0.13208)
		(layer "F.Cu")
		(net "PEX_ADC_ALERT_N")
	)
	(segment
		(start 249.104404 -277.536656)
		(end 249.104404 -277.941786)
		(width 0.13208)
		(layer "F.Cu")
		(net "PEX_ADC_ALERT_N")
	)
	(segment
		(start 232.854246 -277.536656)
		(end 232.245916 -277.536656)
		(width 0.13208)
		(layer "F.Cu")
		(net "PEX_ADC_ALERT_N")
	)
	(segment
		(start 463.475324 -277.6601)
		(end 463.475324 -278.06523)
		(width 0.13208)
		(layer "F.Cu")
		(net "PEX_ADC_ALERT_N")
	)
	(segment
		(start 251.599446 -261.943342)
		(end 251.599446 -276.443948)
		(width 0.13208)
		(layer "F.Cu")
		(net "PEX_ADC_ALERT_N")
	)
	(segment
		(start 94.132908 -242.776248)
		(end 94.005654 -242.648994)
		(width 0.13208)
		(layer "F.Cu")
		(net "PEX_ADC_ALERT_N")
	)
	(segment
		(start 462.866994 -277.6601)
		(end 462.865724 -277.65883)
		(width 0.13208)
		(layer "F.Cu")
		(net "PEX_ADC_ALERT_N")
	)
	(segment
		(start 232.244646 -278.551386)
		(end 232.854246 -277.941786)
		(width 0.13208)
		(layer "F.Cu")
		(net "PEX_ADC_ALERT_N")
	)
	(segment
		(start 463.475324 -277.6601)
		(end 462.866994 -277.6601)
		(width 0.13208)
		(layer "F.Cu")
		(net "PEX_ADC_ALERT_N")
	)
	(segment
		(start 249.104404 -277.941786)
		(end 248.494804 -278.551386)
		(width 0.13208)
		(layer "F.Cu")
		(net "PEX_ADC_ALERT_N")
	)
	(segment
		(start 94.005654 -242.648994)
		(end 94.005654 -242.239546)
		(width 0.13208)
		(layer "F.Cu")
		(net "PEX_ADC_ALERT_N")
	)
	(segment
		(start 463.475324 -278.06523)
		(end 462.865724 -278.67483)
		(width 0.13208)
		(layer "F.Cu")
		(net "PEX_ADC_ALERT_N")
	)
	(segment
		(start 248.496074 -277.536656)
		(end 249.104404 -277.536656)
		(width 0.13208)
		(layer "F.Cu")
		(net "PEX_ADC_ALERT_N")
	)
	(segment
		(start 251.04852 -261.392416)
		(end 251.599446 -261.943342)
		(width 0.13208)
		(layer "F.Cu")
		(net "PEX_ADC_ALERT_N")
	)
	(segment
		(start 251.01296 -260.087872)
		(end 251.04852 -260.123432)
		(width 0.13208)
		(layer "F.Cu")
		(net "PEX_ADC_ALERT_N")
	)
	(segment
		(start 17.185386 -275.248624)
		(end 17.82445 -275.248624)
		(width 0.13208)
		(layer "F.Cu")
		(net "PEX_ADC_ALERT_N")
	)
	(segment
		(start 248.494804 -277.535386)
		(end 248.496074 -277.536656)
		(width 0.13208)
		(layer "F.Cu")
		(net "PEX_ADC_ALERT_N")
	)
	(segment
		(start 94.132908 -241.760248)
		(end 94.705678 -241.760248)
		(width 0.13208)
		(layer "F.Cu")
		(net "PEX_ADC_ALERT_N")
	)
	(segment
		(start 223.467676 -212.704172)
		(end 223.06788 -212.304376)
		(width 0.13208)
		(layer "F.Cu")
		(net "PEX_ADC_ALERT_N")
	)
	(segment
		(start 250.506738 -277.536656)
		(end 249.104404 -277.536656)
		(width 0.13208)
		(layer "F.Cu")
		(net "PEX_ADC_ALERT_N")
	)
	(segment
		(start 232.245916 -277.536656)
		(end 232.244646 -277.535386)
		(width 0.13208)
		(layer "F.Cu")
		(net "PEX_ADC_ALERT_N")
	)
	(segment
		(start 251.04852 -260.123432)
		(end 251.04852 -261.392416)
		(width 0.13208)
		(layer "F.Cu")
		(net "PEX_ADC_ALERT_N")
	)
	(segment
		(start 232.854246 -277.941786)
		(end 232.854246 -277.536656)
		(width 0.13208)
		(layer "F.Cu")
		(net "PEX_ADC_ALERT_N")
	)
	(segment
		(start 17.185386 -276.264624)
		(end 17.185386 -275.248624)
		(width 0.13208)
		(layer "F.Cu")
		(net "PEX_ADC_ALERT_N")
	)
	(segment
		(start 251.599446 -276.443948)
		(end 250.506738 -277.536656)
		(width 0.13208)
		(layer "F.Cu")
		(net "PEX_ADC_ALERT_N")
	)
	(segment
		(start 17.82445 -275.248624)
		(end 18.329148 -274.743926)
		(width 0.13208)
		(layer "F.Cu")
		(net "PEX_ADC_ALERT_N")
	)
	(segment
		(start 94.705678 -242.776248)
		(end 94.132908 -242.776248)
		(width 0.13208)
		(layer "F.Cu")
		(net "PEX_ADC_ALERT_N")
	)
	(segment
		(start 94.005654 -242.239546)
		(end 94.005654 -241.887502)
		(width 0.13208)
		(layer "F.Cu")
		(net "PEX_ADC_ALERT_N")
	)
	(segment
		(start 18.329148 -243.228114)
		(end 19.388328 -242.168934)
		(width 0.13208)
		(layer "F.Cu")
		(net "PEX_ADC_ALERT_N")
	)
	(segment
		(start 18.329148 -274.743926)
		(end 18.329148 -243.228114)
		(width 0.13208)
		(layer "F.Cu")
		(net "PEX_ADC_ALERT_N")
	)
	(via
		(at 223.06788 -212.304376)
		(size 0.4572)
		(drill 0.254)
		(layers "F.Cu" "B.Cu")
		(net "PEX_ADC_ALERT_N")
	)
	(via
		(at 463.475324 -277.6601)
		(size 0.508)
		(drill 0.254)
		(layers "F.Cu" "B.Cu")
		(net "PEX_ADC_ALERT_N")
	)
	(via
		(at 251.01296 -260.087872)
		(size 0.508)
		(drill 0.254)
		(layers "F.Cu" "B.Cu")
		(net "PEX_ADC_ALERT_N")
	)
	(via
		(at 232.854246 -277.536656)
		(size 0.508)
		(drill 0.254)
		(layers "F.Cu" "B.Cu")
		(net "PEX_ADC_ALERT_N")
	)
	(via
		(at 249.104404 -277.536656)
		(size 0.508)
		(drill 0.254)
		(layers "F.Cu" "B.Cu")
		(net "PEX_ADC_ALERT_N")
	)
	(via
		(at 223.259904 -252.48108)
		(size 0.508)
		(drill 0.254)
		(layers "F.Cu" "B.Cu")
		(net "PEX_ADC_ALERT_N")
	)
	(via
		(at 19.388328 -242.168934)
		(size 0.508)
		(drill 0.254)
		(layers "F.Cu" "B.Cu")
		(net "PEX_ADC_ALERT_N")
	)
	(via
		(at 96.674178 -199.880728)
		(size 0.508)
		(drill 0.254)
		(layers "F.Cu" "B.Cu")
		(net "PEX_ADC_ALERT_N")
	)
	(via
		(at 94.005654 -242.239546)
		(size 0.508)
		(drill 0.254)
		(layers "F.Cu" "B.Cu")
		(net "PEX_ADC_ALERT_N")
	)
	(segment
		(start 221.812866 -219.885006)
		(end 221.812866 -217.131646)
		(width 0.15494)
		(layer "In5.Cu")
		(net "PEX_ADC_ALERT_N")
	)
	(segment
		(start 94.005654 -242.239546)
		(end 95.74403 -240.50117)
		(width 0.15494)
		(layer "In5.Cu")
		(net "PEX_ADC_ALERT_N")
	)
	(segment
		(start 223.468184 -234.335574)
		(end 223.1898 -234.05719)
		(width 0.15494)
		(layer "In5.Cu")
		(net "PEX_ADC_ALERT_N")
	)
	(segment
		(start 221.63786 -226.942396)
		(end 221.63786 -225.828352)
		(width 0.15494)
		(layer "In5.Cu")
		(net "PEX_ADC_ALERT_N")
	)
	(segment
		(start 220.69044 -214.681816)
		(end 223.06788 -212.304376)
		(width 0.15494)
		(layer "In5.Cu")
		(net "PEX_ADC_ALERT_N")
	)
	(segment
		(start 221.812866 -217.131646)
		(end 220.69044 -216.00922)
		(width 0.15494)
		(layer "In5.Cu")
		(net "PEX_ADC_ALERT_N")
	)
	(segment
		(start 95.74403 -240.50117)
		(end 95.74403 -211.688172)
		(width 0.15494)
		(layer "In5.Cu")
		(net "PEX_ADC_ALERT_N")
	)
	(segment
		(start 95.74403 -211.688172)
		(end 95.9612 -211.471002)
		(width 0.15494)
		(layer "In5.Cu")
		(net "PEX_ADC_ALERT_N")
	)
	(segment
		(start 223.468184 -252.2728)
		(end 223.468184 -234.335574)
		(width 0.15494)
		(layer "In5.Cu")
		(net "PEX_ADC_ALERT_N")
	)
	(segment
		(start 221.63786 -225.828352)
		(end 221.17812 -225.368612)
		(width 0.15494)
		(layer "In5.Cu")
		(net "PEX_ADC_ALERT_N")
	)
	(segment
		(start 95.9612 -211.471002)
		(end 95.9612 -200.593706)
		(width 0.15494)
		(layer "In5.Cu")
		(net "PEX_ADC_ALERT_N")
	)
	(segment
		(start 223.1898 -228.494336)
		(end 221.63786 -226.942396)
		(width 0.15494)
		(layer "In5.Cu")
		(net "PEX_ADC_ALERT_N")
	)
	(segment
		(start 223.1898 -234.05719)
		(end 223.1898 -228.494336)
		(width 0.15494)
		(layer "In5.Cu")
		(net "PEX_ADC_ALERT_N")
	)
	(segment
		(start 95.9612 -200.593706)
		(end 96.674178 -199.880728)
		(width 0.15494)
		(layer "In5.Cu")
		(net "PEX_ADC_ALERT_N")
	)
	(segment
		(start 220.69044 -216.00922)
		(end 220.69044 -214.681816)
		(width 0.15494)
		(layer "In5.Cu")
		(net "PEX_ADC_ALERT_N")
	)
	(segment
		(start 221.17812 -220.519752)
		(end 221.812866 -219.885006)
		(width 0.15494)
		(layer "In5.Cu")
		(net "PEX_ADC_ALERT_N")
	)
	(segment
		(start 223.259904 -252.48108)
		(end 223.468184 -252.2728)
		(width 0.15494)
		(layer "In5.Cu")
		(net "PEX_ADC_ALERT_N")
	)
	(segment
		(start 221.17812 -225.368612)
		(end 221.17812 -220.519752)
		(width 0.15494)
		(layer "In5.Cu")
		(net "PEX_ADC_ALERT_N")
	)
	(segment
		(start 245.951502 -276.438614)
		(end 242.779042 -276.438614)
		(width 0.15494)
		(layer "In9.Cu")
		(net "PEX_ADC_ALERT_N")
	)
	(segment
		(start 247.691402 -277.536656)
		(end 247.243346 -277.0886)
		(width 0.15494)
		(layer "In9.Cu")
		(net "PEX_ADC_ALERT_N")
	)
	(segment
		(start 246.601488 -277.0886)
		(end 245.951502 -276.438614)
		(width 0.15494)
		(layer "In9.Cu")
		(net "PEX_ADC_ALERT_N")
	)
	(segment
		(start 241.244628 -274.9042)
		(end 235.486702 -274.9042)
		(width 0.15494)
		(layer "In9.Cu")
		(net "PEX_ADC_ALERT_N")
	)
	(segment
		(start 249.104404 -277.536656)
		(end 247.691402 -277.536656)
		(width 0.15494)
		(layer "In9.Cu")
		(net "PEX_ADC_ALERT_N")
	)
	(segment
		(start 247.243346 -277.0886)
		(end 246.601488 -277.0886)
		(width 0.15494)
		(layer "In9.Cu")
		(net "PEX_ADC_ALERT_N")
	)
	(segment
		(start 235.486702 -274.9042)
		(end 232.854246 -277.536656)
		(width 0.15494)
		(layer "In9.Cu")
		(net "PEX_ADC_ALERT_N")
	)
	(segment
		(start 242.779042 -276.438614)
		(end 241.244628 -274.9042)
		(width 0.15494)
		(layer "In9.Cu")
		(net "PEX_ADC_ALERT_N")
	)
	(segment
		(start 224.410778 -253.631954)
		(end 223.259904 -252.48108)
		(width 0.15494)
		(layer "In11.Cu")
		(net "PEX_ADC_ALERT_N")
	)
	(segment
		(start 228.558598 -253.631954)
		(end 224.410778 -253.631954)
		(width 0.15494)
		(layer "In11.Cu")
		(net "PEX_ADC_ALERT_N")
	)
	(segment
		(start 234.827826 -253.741936)
		(end 232.503472 -251.417582)
		(width 0.15494)
		(layer "In11.Cu")
		(net "PEX_ADC_ALERT_N")
	)
	(segment
		(start 244.667024 -253.741936)
		(end 234.827826 -253.741936)
		(width 0.15494)
		(layer "In11.Cu")
		(net "PEX_ADC_ALERT_N")
	)
	(segment
		(start 228.993446 -251.882148)
		(end 228.993446 -253.197106)
		(width 0.15494)
		(layer "In11.Cu")
		(net "PEX_ADC_ALERT_N")
	)
	(segment
		(start 232.503472 -251.417582)
		(end 229.458012 -251.417582)
		(width 0.15494)
		(layer "In11.Cu")
		(net "PEX_ADC_ALERT_N")
	)
	(segment
		(start 251.01296 -260.087872)
		(end 244.667024 -253.741936)
		(width 0.15494)
		(layer "In11.Cu")
		(net "PEX_ADC_ALERT_N")
	)
	(segment
		(start 228.993446 -253.197106)
		(end 228.558598 -253.631954)
		(width 0.15494)
		(layer "In11.Cu")
		(net "PEX_ADC_ALERT_N")
	)
	(segment
		(start 229.458012 -251.417582)
		(end 228.993446 -251.882148)
		(width 0.15494)
		(layer "In11.Cu")
		(net "PEX_ADC_ALERT_N")
	)
	(segment
		(start 269.663672 -261.03326)
		(end 271.865852 -258.83108)
		(width 0.15494)
		(layer "In13.Cu")
		(net "PEX_ADC_ALERT_N")
	)
	(segment
		(start 323.997828 -257.745992)
		(end 324.32117 -257.745992)
		(width 0.15494)
		(layer "In13.Cu")
		(net "PEX_ADC_ALERT_N")
	)
	(segment
		(start 378.127514 -244.856)
		(end 379.499114 -243.4844)
		(width 0.15494)
		(layer "In13.Cu")
		(net "PEX_ADC_ALERT_N")
	)
	(segment
		(start 328.089514 -257.746246)
		(end 329.2475 -256.58826)
		(width 0.15494)
		(layer "In13.Cu")
		(net "PEX_ADC_ALERT_N")
	)
	(segment
		(start 347.69552 -247.8151)
		(end 352.546666 -247.8151)
		(width 0.15494)
		(layer "In13.Cu")
		(net "PEX_ADC_ALERT_N")
	)
	(segment
		(start 257.390392 -260.535674)
		(end 257.738626 -260.535674)
		(width 0.15494)
		(layer "In13.Cu")
		(net "PEX_ADC_ALERT_N")
	)
	(segment
		(start 343.47658 -252.03404)
		(end 347.69552 -247.8151)
		(width 0.15494)
		(layer "In13.Cu")
		(net "PEX_ADC_ALERT_N")
	)
	(segment
		(start 416.987736 -238.81461)
		(end 421.618664 -238.81461)
		(width 0.15494)
		(layer "In13.Cu")
		(net "PEX_ADC_ALERT_N")
	)
	(segment
		(start 339.395054 -256.58826)
		(end 343.47658 -252.506734)
		(width 0.15494)
		(layer "In13.Cu")
		(net "PEX_ADC_ALERT_N")
	)
	(segment
		(start 309.617618 -261.4041)
		(end 312.627518 -258.3942)
		(width 0.15494)
		(layer "In13.Cu")
		(net "PEX_ADC_ALERT_N")
	)
	(segment
		(start 387.84022 -240.157)
		(end 388.9502 -240.157)
		(width 0.15494)
		(layer "In13.Cu")
		(net "PEX_ADC_ALERT_N")
	)
	(segment
		(start 416.102546 -239.6998)
		(end 416.987736 -238.81461)
		(width 0.15494)
		(layer "In13.Cu")
		(net "PEX_ADC_ALERT_N")
	)
	(segment
		(start 271.865852 -258.83108)
		(end 298.378626 -258.83108)
		(width 0.15494)
		(layer "In13.Cu")
		(net "PEX_ADC_ALERT_N")
	)
	(segment
		(start 385.160012 -242.680236)
		(end 386.057648 -241.7826)
		(width 0.15494)
		(layer "In13.Cu")
		(net "PEX_ADC_ALERT_N")
	)
	(segment
		(start 421.618664 -238.81461)
		(end 423.850054 -241.046)
		(width 0.15494)
		(layer "In13.Cu")
		(net "PEX_ADC_ALERT_N")
	)
	(segment
		(start 389.4074 -239.6998)
		(end 416.102546 -239.6998)
		(width 0.15494)
		(layer "In13.Cu")
		(net "PEX_ADC_ALERT_N")
	)
	(segment
		(start 370.694458 -242.2144)
		(end 371.506242 -242.550696)
		(width 0.15494)
		(layer "In13.Cu")
		(net "PEX_ADC_ALERT_N")
	)
	(segment
		(start 387.71322 -240.284)
		(end 387.84022 -240.157)
		(width 0.15494)
		(layer "In13.Cu")
		(net "PEX_ADC_ALERT_N")
	)
	(segment
		(start 381.362204 -243.4844)
		(end 381.912876 -244.035072)
		(width 0.15494)
		(layer "In13.Cu")
		(net "PEX_ADC_ALERT_N")
	)
	(segment
		(start 258.7117 -259.5626)
		(end 260.477 -259.5626)
		(width 0.15494)
		(layer "In13.Cu")
		(net "PEX_ADC_ALERT_N")
	)
	(segment
		(start 300.951646 -261.4041)
		(end 309.617618 -261.4041)
		(width 0.15494)
		(layer "In13.Cu")
		(net "PEX_ADC_ALERT_N")
	)
	(segment
		(start 260.477 -259.5626)
		(end 261.0612 -260.1468)
		(width 0.15494)
		(layer "In13.Cu")
		(net "PEX_ADC_ALERT_N")
	)
	(segment
		(start 386.057648 -241.7826)
		(end 387.3246 -241.7826)
		(width 0.15494)
		(layer "In13.Cu")
		(net "PEX_ADC_ALERT_N")
	)
	(segment
		(start 379.499114 -243.4844)
		(end 381.362204 -243.4844)
		(width 0.15494)
		(layer "In13.Cu")
		(net "PEX_ADC_ALERT_N")
	)
	(segment
		(start 454.36028 -253.67488)
		(end 457.560934 -253.67488)
		(width 0.15494)
		(layer "In13.Cu")
		(net "PEX_ADC_ALERT_N")
	)
	(segment
		(start 358.147366 -242.2144)
		(end 370.694458 -242.2144)
		(width 0.15494)
		(layer "In13.Cu")
		(net "PEX_ADC_ALERT_N")
	)
	(segment
		(start 324.32117 -257.745992)
		(end 324.321424 -257.746246)
		(width 0.15494)
		(layer "In13.Cu")
		(net "PEX_ADC_ALERT_N")
	)
	(segment
		(start 381.912876 -244.035072)
		(end 384.132074 -244.035072)
		(width 0.15494)
		(layer "In13.Cu")
		(net "PEX_ADC_ALERT_N")
	)
	(segment
		(start 343.47658 -252.506734)
		(end 343.47658 -252.03404)
		(width 0.15494)
		(layer "In13.Cu")
		(net "PEX_ADC_ALERT_N")
	)
	(segment
		(start 371.506242 -242.550696)
		(end 373.811546 -244.856)
		(width 0.15494)
		(layer "In13.Cu")
		(net "PEX_ADC_ALERT_N")
	)
	(segment
		(start 464.235038 -276.900386)
		(end 463.475324 -277.6601)
		(width 0.15494)
		(layer "In13.Cu")
		(net "PEX_ADC_ALERT_N")
	)
	(segment
		(start 457.560934 -253.67488)
		(end 464.235038 -260.348984)
		(width 0.15494)
		(layer "In13.Cu")
		(net "PEX_ADC_ALERT_N")
	)
	(segment
		(start 266.73175 -261.03326)
		(end 269.663672 -261.03326)
		(width 0.15494)
		(layer "In13.Cu")
		(net "PEX_ADC_ALERT_N")
	)
	(segment
		(start 265.84529 -260.1468)
		(end 266.73175 -261.03326)
		(width 0.15494)
		(layer "In13.Cu")
		(net "PEX_ADC_ALERT_N")
	)
	(segment
		(start 324.321424 -257.746246)
		(end 328.089514 -257.746246)
		(width 0.15494)
		(layer "In13.Cu")
		(net "PEX_ADC_ALERT_N")
	)
	(segment
		(start 423.850054 -241.046)
		(end 441.7314 -241.046)
		(width 0.15494)
		(layer "In13.Cu")
		(net "PEX_ADC_ALERT_N")
	)
	(segment
		(start 329.2475 -256.58826)
		(end 339.395054 -256.58826)
		(width 0.15494)
		(layer "In13.Cu")
		(net "PEX_ADC_ALERT_N")
	)
	(segment
		(start 464.235038 -260.348984)
		(end 464.235038 -276.900386)
		(width 0.15494)
		(layer "In13.Cu")
		(net "PEX_ADC_ALERT_N")
	)
	(segment
		(start 251.01296 -260.087872)
		(end 252.821948 -261.89686)
		(width 0.15494)
		(layer "In13.Cu")
		(net "PEX_ADC_ALERT_N")
	)
	(segment
		(start 256.029206 -261.89686)
		(end 257.390392 -260.535674)
		(width 0.15494)
		(layer "In13.Cu")
		(net "PEX_ADC_ALERT_N")
	)
	(segment
		(start 323.997574 -257.746246)
		(end 323.997828 -257.745992)
		(width 0.15494)
		(layer "In13.Cu")
		(net "PEX_ADC_ALERT_N")
	)
	(segment
		(start 257.738626 -260.535674)
		(end 258.7117 -259.5626)
		(width 0.15494)
		(layer "In13.Cu")
		(net "PEX_ADC_ALERT_N")
	)
	(segment
		(start 312.627518 -258.3942)
		(end 323.29247 -258.3942)
		(width 0.15494)
		(layer "In13.Cu")
		(net "PEX_ADC_ALERT_N")
	)
	(segment
		(start 323.29247 -258.3942)
		(end 323.940424 -257.746246)
		(width 0.15494)
		(layer "In13.Cu")
		(net "PEX_ADC_ALERT_N")
	)
	(segment
		(start 298.378626 -258.83108)
		(end 300.951646 -261.4041)
		(width 0.15494)
		(layer "In13.Cu")
		(net "PEX_ADC_ALERT_N")
	)
	(segment
		(start 252.821948 -261.89686)
		(end 256.029206 -261.89686)
		(width 0.15494)
		(layer "In13.Cu")
		(net "PEX_ADC_ALERT_N")
	)
	(segment
		(start 373.811546 -244.856)
		(end 378.127514 -244.856)
		(width 0.15494)
		(layer "In13.Cu")
		(net "PEX_ADC_ALERT_N")
	)
	(segment
		(start 441.7314 -241.046)
		(end 454.36028 -253.67488)
		(width 0.15494)
		(layer "In13.Cu")
		(net "PEX_ADC_ALERT_N")
	)
	(segment
		(start 385.160012 -243.007134)
		(end 385.160012 -242.680236)
		(width 0.15494)
		(layer "In13.Cu")
		(net "PEX_ADC_ALERT_N")
	)
	(segment
		(start 261.0612 -260.1468)
		(end 265.84529 -260.1468)
		(width 0.15494)
		(layer "In13.Cu")
		(net "PEX_ADC_ALERT_N")
	)
	(segment
		(start 352.546666 -247.8151)
		(end 358.147366 -242.2144)
		(width 0.15494)
		(layer "In13.Cu")
		(net "PEX_ADC_ALERT_N")
	)
	(segment
		(start 384.132074 -244.035072)
		(end 385.160012 -243.007134)
		(width 0.15494)
		(layer "In13.Cu")
		(net "PEX_ADC_ALERT_N")
	)
	(segment
		(start 388.9502 -240.157)
		(end 389.4074 -239.6998)
		(width 0.15494)
		(layer "In13.Cu")
		(net "PEX_ADC_ALERT_N")
	)
	(segment
		(start 387.3246 -241.7826)
		(end 387.71322 -241.39398)
		(width 0.15494)
		(layer "In13.Cu")
		(net "PEX_ADC_ALERT_N")
	)
	(segment
		(start 323.940424 -257.746246)
		(end 323.997574 -257.746246)
		(width 0.15494)
		(layer "In13.Cu")
		(net "PEX_ADC_ALERT_N")
	)
	(segment
		(start 387.71322 -241.39398)
		(end 387.71322 -240.284)
		(width 0.15494)
		(layer "In13.Cu")
		(net "PEX_ADC_ALERT_N")
	)
	(segment
		(start 108.640372 -200.4314)
		(end 106.327702 -198.11873)
		(width 0.15494)
		(layer "In15.Cu")
		(net "PEX_ADC_ALERT_N")
	)
	(segment
		(start 209.532474 -213.797134)
		(end 207.378554 -211.643214)
		(width 0.15494)
		(layer "In15.Cu")
		(net "PEX_ADC_ALERT_N")
	)
	(segment
		(start 163.853622 -221.384622)
		(end 159.980884 -217.511884)
		(width 0.15494)
		(layer "In15.Cu")
		(net "PEX_ADC_ALERT_N")
	)
	(segment
		(start 93.358208 -241.5921)
		(end 19.965162 -241.5921)
		(width 0.15494)
		(layer "In15.Cu")
		(net "PEX_ADC_ALERT_N")
	)
	(segment
		(start 19.965162 -241.5921)
		(end 19.388328 -242.168934)
		(width 0.15494)
		(layer "In15.Cu")
		(net "PEX_ADC_ALERT_N")
	)
	(segment
		(start 207.378554 -211.643214)
		(end 204.334618 -211.643214)
		(width 0.15494)
		(layer "In15.Cu")
		(net "PEX_ADC_ALERT_N")
	)
	(segment
		(start 109.60354 -200.4314)
		(end 108.640372 -200.4314)
		(width 0.15494)
		(layer "In15.Cu")
		(net "PEX_ADC_ALERT_N")
	)
	(segment
		(start 223.06788 -212.304376)
		(end 221.6658 -213.706456)
		(width 0.15494)
		(layer "In15.Cu")
		(net "PEX_ADC_ALERT_N")
	)
	(segment
		(start 94.005654 -242.239546)
		(end 93.358208 -241.5921)
		(width 0.15494)
		(layer "In15.Cu")
		(net "PEX_ADC_ALERT_N")
	)
	(segment
		(start 140.805662 -217.511884)
		(end 140.360146 -217.9574)
		(width 0.15494)
		(layer "In15.Cu")
		(net "PEX_ADC_ALERT_N")
	)
	(segment
		(start 209.933794 -213.797134)
		(end 209.532474 -213.797134)
		(width 0.15494)
		(layer "In15.Cu")
		(net "PEX_ADC_ALERT_N")
	)
	(segment
		(start 123.636786 -214.202264)
		(end 123.636786 -210.506564)
		(width 0.15494)
		(layer "In15.Cu")
		(net "PEX_ADC_ALERT_N")
	)
	(segment
		(start 113.332006 -204.159866)
		(end 109.60354 -200.4314)
		(width 0.15494)
		(layer "In15.Cu")
		(net "PEX_ADC_ALERT_N")
	)
	(segment
		(start 130.28168 -217.68308)
		(end 127.117602 -217.68308)
		(width 0.15494)
		(layer "In15.Cu")
		(net "PEX_ADC_ALERT_N")
	)
	(segment
		(start 213.233254 -213.706456)
		(end 212.154008 -212.62721)
		(width 0.15494)
		(layer "In15.Cu")
		(net "PEX_ADC_ALERT_N")
	)
	(segment
		(start 127.117602 -217.68308)
		(end 123.636786 -214.202264)
		(width 0.15494)
		(layer "In15.Cu")
		(net "PEX_ADC_ALERT_N")
	)
	(segment
		(start 159.980884 -217.511884)
		(end 140.805662 -217.511884)
		(width 0.15494)
		(layer "In15.Cu")
		(net "PEX_ADC_ALERT_N")
	)
	(segment
		(start 117.290088 -204.159866)
		(end 113.332006 -204.159866)
		(width 0.15494)
		(layer "In15.Cu")
		(net "PEX_ADC_ALERT_N")
	)
	(segment
		(start 204.334618 -211.643214)
		(end 194.59321 -221.384622)
		(width 0.15494)
		(layer "In15.Cu")
		(net "PEX_ADC_ALERT_N")
	)
	(segment
		(start 210.2612 -213.469728)
		(end 209.933794 -213.797134)
		(width 0.15494)
		(layer "In15.Cu")
		(net "PEX_ADC_ALERT_N")
	)
	(segment
		(start 106.327702 -198.11873)
		(end 98.83267 -198.11873)
		(width 0.15494)
		(layer "In15.Cu")
		(net "PEX_ADC_ALERT_N")
	)
	(segment
		(start 130.556 -217.9574)
		(end 130.28168 -217.68308)
		(width 0.15494)
		(layer "In15.Cu")
		(net "PEX_ADC_ALERT_N")
	)
	(segment
		(start 140.360146 -217.9574)
		(end 130.556 -217.9574)
		(width 0.15494)
		(layer "In15.Cu")
		(net "PEX_ADC_ALERT_N")
	)
	(segment
		(start 212.154008 -212.62721)
		(end 210.566254 -212.62721)
		(width 0.15494)
		(layer "In15.Cu")
		(net "PEX_ADC_ALERT_N")
	)
	(segment
		(start 123.636786 -210.506564)
		(end 117.290088 -204.159866)
		(width 0.15494)
		(layer "In15.Cu")
		(net "PEX_ADC_ALERT_N")
	)
	(segment
		(start 221.6658 -213.706456)
		(end 213.233254 -213.706456)
		(width 0.15494)
		(layer "In15.Cu")
		(net "PEX_ADC_ALERT_N")
	)
	(segment
		(start 194.59321 -221.384622)
		(end 163.853622 -221.384622)
		(width 0.15494)
		(layer "In15.Cu")
		(net "PEX_ADC_ALERT_N")
	)
	(segment
		(start 98.83267 -198.11873)
		(end 97.070672 -199.880728)
		(width 0.15494)
		(layer "In15.Cu")
		(net "PEX_ADC_ALERT_N")
	)
	(segment
		(start 210.566254 -212.62721)
		(end 210.2612 -212.932264)
		(width 0.15494)
		(layer "In15.Cu")
		(net "PEX_ADC_ALERT_N")
	)
	(segment
		(start 210.2612 -212.932264)
		(end 210.2612 -213.469728)
		(width 0.15494)
		(layer "In15.Cu")
		(net "PEX_ADC_ALERT_N")
	)
	(segment
		(start 97.070672 -199.880728)
		(end 96.674178 -199.880728)
		(width 0.15494)
		(layer "In15.Cu")
		(net "PEX_ADC_ALERT_N")
	)
	(segment
		(start 448.18554 -24.75865)
		(end 447.55054 -24.75865)
		(width 0.13208)
		(layer "F.Cu")
		(net "SSD15_LED_ISO_R_N")
	)
	(segment
		(start 437.980836 -24.189944)
		(end 436.964836 -24.189944)
		(width 0.13208)
		(layer "F.Cu")
		(net "SSD15_LED_ISO_R_N")
	)
	(via
		(at 437.980836 -24.189944)
		(size 0.508)
		(drill 0.254)
		(layers "F.Cu" "B.Cu")
		(net "SSD15_LED_ISO_R_N")
	)
	(via
		(at 447.55054 -24.75865)
		(size 0.508)
		(drill 0.254)
		(layers "F.Cu" "B.Cu")
		(net "SSD15_LED_ISO_R_N")
	)
	(segment
		(start 443.626748 -24.364188)
		(end 447.156078 -24.364188)
		(width 0.15494)
		(layer "In5.Cu")
		(net "SSD15_LED_ISO_R_N")
	)
	(segment
		(start 442.460888 -24.08047)
		(end 443.34303 -24.08047)
		(width 0.15494)
		(layer "In5.Cu")
		(net "SSD15_LED_ISO_R_N")
	)
	(segment
		(start 447.156078 -24.364188)
		(end 447.55054 -24.75865)
		(width 0.15494)
		(layer "In5.Cu")
		(net "SSD15_LED_ISO_R_N")
	)
	(segment
		(start 441.866782 -23.486364)
		(end 442.460888 -24.08047)
		(width 0.15494)
		(layer "In5.Cu")
		(net "SSD15_LED_ISO_R_N")
	)
	(segment
		(start 439.35777 -24.189944)
		(end 440.06135 -23.486364)
		(width 0.15494)
		(layer "In5.Cu")
		(net "SSD15_LED_ISO_R_N")
	)
	(segment
		(start 437.980836 -24.189944)
		(end 439.35777 -24.189944)
		(width 0.15494)
		(layer "In5.Cu")
		(net "SSD15_LED_ISO_R_N")
	)
	(segment
		(start 440.06135 -23.486364)
		(end 441.866782 -23.486364)
		(width 0.15494)
		(layer "In5.Cu")
		(net "SSD15_LED_ISO_R_N")
	)
	(segment
		(start 443.34303 -24.08047)
		(end 443.626748 -24.364188)
		(width 0.15494)
		(layer "In5.Cu")
		(net "SSD15_LED_ISO_R_N")
	)
	(segment
		(start 422.185592 -24.75865)
		(end 421.550592 -24.75865)
		(width 0.13208)
		(layer "F.Cu")
		(net "SSD14_LED_ISO_R_N")
	)
	(segment
		(start 411.980888 -24.189944)
		(end 410.964888 -24.189944)
		(width 0.13208)
		(layer "F.Cu")
		(net "SSD14_LED_ISO_R_N")
	)
	(via
		(at 421.550592 -24.75865)
		(size 0.508)
		(drill 0.254)
		(layers "F.Cu" "B.Cu")
		(net "SSD14_LED_ISO_R_N")
	)
	(via
		(at 411.980888 -24.189944)
		(size 0.508)
		(drill 0.254)
		(layers "F.Cu" "B.Cu")
		(net "SSD14_LED_ISO_R_N")
	)
	(segment
		(start 417.434268 -24.364188)
		(end 421.15613 -24.364188)
		(width 0.15494)
		(layer "In5.Cu")
		(net "SSD14_LED_ISO_R_N")
	)
	(segment
		(start 411.980888 -24.189944)
		(end 413.357822 -24.189944)
		(width 0.15494)
		(layer "In5.Cu")
		(net "SSD14_LED_ISO_R_N")
	)
	(segment
		(start 413.357822 -24.189944)
		(end 414.061402 -23.486364)
		(width 0.15494)
		(layer "In5.Cu")
		(net "SSD14_LED_ISO_R_N")
	)
	(segment
		(start 421.15613 -24.364188)
		(end 421.550592 -24.75865)
		(width 0.15494)
		(layer "In5.Cu")
		(net "SSD14_LED_ISO_R_N")
	)
	(segment
		(start 416.535108 -24.115268)
		(end 417.185348 -24.115268)
		(width 0.15494)
		(layer "In5.Cu")
		(net "SSD14_LED_ISO_R_N")
	)
	(segment
		(start 415.906204 -23.486364)
		(end 416.535108 -24.115268)
		(width 0.15494)
		(layer "In5.Cu")
		(net "SSD14_LED_ISO_R_N")
	)
	(segment
		(start 417.185348 -24.115268)
		(end 417.434268 -24.364188)
		(width 0.15494)
		(layer "In5.Cu")
		(net "SSD14_LED_ISO_R_N")
	)
	(segment
		(start 414.061402 -23.486364)
		(end 415.906204 -23.486364)
		(width 0.15494)
		(layer "In5.Cu")
		(net "SSD14_LED_ISO_R_N")
	)
	(segment
		(start 359.980992 -24.189944)
		(end 358.964992 -24.189944)
		(width 0.13208)
		(layer "F.Cu")
		(net "SSD12_LED_ISO_R_N")
	)
	(segment
		(start 370.185696 -24.75865)
		(end 369.550696 -24.75865)
		(width 0.13208)
		(layer "F.Cu")
		(net "SSD12_LED_ISO_R_N")
	)
	(via
		(at 359.980992 -24.189944)
		(size 0.508)
		(drill 0.254)
		(layers "F.Cu" "B.Cu")
		(net "SSD12_LED_ISO_R_N")
	)
	(via
		(at 369.550696 -24.75865)
		(size 0.508)
		(drill 0.254)
		(layers "F.Cu" "B.Cu")
		(net "SSD12_LED_ISO_R_N")
	)
	(segment
		(start 359.980992 -24.189944)
		(end 361.357926 -24.189944)
		(width 0.15494)
		(layer "In5.Cu")
		(net "SSD12_LED_ISO_R_N")
	)
	(segment
		(start 364.506764 -24.115268)
		(end 365.162084 -24.115268)
		(width 0.15494)
		(layer "In5.Cu")
		(net "SSD12_LED_ISO_R_N")
	)
	(segment
		(start 365.162084 -24.115268)
		(end 365.411004 -24.364188)
		(width 0.15494)
		(layer "In5.Cu")
		(net "SSD12_LED_ISO_R_N")
	)
	(segment
		(start 362.061506 -23.486364)
		(end 363.87786 -23.486364)
		(width 0.15494)
		(layer "In5.Cu")
		(net "SSD12_LED_ISO_R_N")
	)
	(segment
		(start 369.156234 -24.364188)
		(end 369.550696 -24.75865)
		(width 0.15494)
		(layer "In5.Cu")
		(net "SSD12_LED_ISO_R_N")
	)
	(segment
		(start 361.357926 -24.189944)
		(end 362.061506 -23.486364)
		(width 0.15494)
		(layer "In5.Cu")
		(net "SSD12_LED_ISO_R_N")
	)
	(segment
		(start 365.411004 -24.364188)
		(end 369.156234 -24.364188)
		(width 0.15494)
		(layer "In5.Cu")
		(net "SSD12_LED_ISO_R_N")
	)
	(segment
		(start 363.87786 -23.486364)
		(end 364.506764 -24.115268)
		(width 0.15494)
		(layer "In5.Cu")
		(net "SSD12_LED_ISO_R_N")
	)
	(segment
		(start 223.622108 -81.627472)
		(end 223.006158 -81.627472)
		(width 0.13208)
		(layer "F.Cu")
		(net "SSD12_LED_R")
	)
	(segment
		(start 373.524018 -27.411934)
		(end 373.524018 -26.319734)
		(width 0.13208)
		(layer "F.Cu")
		(net "SSD12_LED_R")
	)
	(segment
		(start 223.006158 -81.627472)
		(end 222.390208 -81.627472)
		(width 0.13208)
		(layer "F.Cu")
		(net "SSD12_LED_R")
	)
	(via
		(at 379.548644 -94.665546)
		(size 0.508)
		(drill 0.254)
		(layers "F.Cu" "B.Cu")
		(net "SSD12_LED_R")
	)
	(via
		(at 373.524018 -26.319734)
		(size 0.508)
		(drill 0.254)
		(layers "F.Cu" "B.Cu")
		(net "SSD12_LED_R")
	)
	(via
		(at 223.006158 -81.627472)
		(size 0.508)
		(drill 0.254)
		(layers "F.Cu" "B.Cu")
		(net "SSD12_LED_R")
	)
	(segment
		(start 373.544338 -31.232856)
		(end 373.544338 -32.150812)
		(width 0.15494)
		(layer "In5.Cu")
		(net "SSD12_LED_R")
	)
	(segment
		(start 382.987296 -68.376292)
		(end 382.987296 -91.226894)
		(width 0.15494)
		(layer "In5.Cu")
		(net "SSD12_LED_R")
	)
	(segment
		(start 382.987296 -91.226894)
		(end 379.548644 -94.665546)
		(width 0.15494)
		(layer "In5.Cu")
		(net "SSD12_LED_R")
	)
	(segment
		(start 374.602248 -30.174946)
		(end 373.544338 -31.232856)
		(width 0.15494)
		(layer "In5.Cu")
		(net "SSD12_LED_R")
	)
	(segment
		(start 373.544338 -32.150812)
		(end 386.38861 -44.995084)
		(width 0.15494)
		(layer "In5.Cu")
		(net "SSD12_LED_R")
	)
	(segment
		(start 373.524018 -26.319734)
		(end 374.602248 -27.397964)
		(width 0.15494)
		(layer "In5.Cu")
		(net "SSD12_LED_R")
	)
	(segment
		(start 386.38861 -64.974978)
		(end 382.987296 -68.376292)
		(width 0.15494)
		(layer "In5.Cu")
		(net "SSD12_LED_R")
	)
	(segment
		(start 374.602248 -27.397964)
		(end 374.602248 -30.174946)
		(width 0.15494)
		(layer "In5.Cu")
		(net "SSD12_LED_R")
	)
	(segment
		(start 386.38861 -44.995084)
		(end 386.38861 -64.974978)
		(width 0.15494)
		(layer "In5.Cu")
		(net "SSD12_LED_R")
	)
	(segment
		(start 228.168454 -74.5236)
		(end 236.9058 -74.5236)
		(width 0.15494)
		(layer "In15.Cu")
		(net "SSD12_LED_R")
	)
	(segment
		(start 224.838768 -81.111598)
		(end 225.39071 -81.111598)
		(width 0.15494)
		(layer "In15.Cu")
		(net "SSD12_LED_R")
	)
	(segment
		(start 281.025854 -85.4456)
		(end 283.083254 -87.503)
		(width 0.15494)
		(layer "In15.Cu")
		(net "SSD12_LED_R")
	)
	(segment
		(start 243.3574 -76.4286)
		(end 243.9924 -77.0636)
		(width 0.15494)
		(layer "In15.Cu")
		(net "SSD12_LED_R")
	)
	(segment
		(start 361.746546 -95.6056)
		(end 378.60859 -95.6056)
		(width 0.15494)
		(layer "In15.Cu")
		(net "SSD12_LED_R")
	)
	(segment
		(start 226.35718 -76.334874)
		(end 228.168454 -74.5236)
		(width 0.15494)
		(layer "In15.Cu")
		(net "SSD12_LED_R")
	)
	(segment
		(start 346.8116 -94.8944)
		(end 361.035346 -94.8944)
		(width 0.15494)
		(layer "In15.Cu")
		(net "SSD12_LED_R")
	)
	(segment
		(start 311.732422 -87.408258)
		(end 316.23 -87.408258)
		(width 0.15494)
		(layer "In15.Cu")
		(net "SSD12_LED_R")
	)
	(segment
		(start 361.035346 -94.8944)
		(end 361.746546 -95.6056)
		(width 0.15494)
		(layer "In15.Cu")
		(net "SSD12_LED_R")
	)
	(segment
		(start 378.60859 -95.6056)
		(end 379.548644 -94.665546)
		(width 0.15494)
		(layer "In15.Cu")
		(net "SSD12_LED_R")
	)
	(segment
		(start 257.447034 -80.333088)
		(end 268.166088 -80.333088)
		(width 0.15494)
		(layer "In15.Cu")
		(net "SSD12_LED_R")
	)
	(segment
		(start 330.88961 -88.6968)
		(end 331.19441 -89.0016)
		(width 0.15494)
		(layer "In15.Cu")
		(net "SSD12_LED_R")
	)
	(segment
		(start 224.322894 -81.627472)
		(end 224.838768 -81.111598)
		(width 0.15494)
		(layer "In15.Cu")
		(net "SSD12_LED_R")
	)
	(segment
		(start 252.7554 -77.0636)
		(end 253.8222 -78.1304)
		(width 0.15494)
		(layer "In15.Cu")
		(net "SSD12_LED_R")
	)
	(segment
		(start 331.19441 -89.0016)
		(end 333.0956 -89.0016)
		(width 0.15494)
		(layer "In15.Cu")
		(net "SSD12_LED_R")
	)
	(segment
		(start 333.0956 -89.0016)
		(end 333.4766 -89.3826)
		(width 0.15494)
		(layer "In15.Cu")
		(net "SSD12_LED_R")
	)
	(segment
		(start 273.2786 -85.4456)
		(end 281.025854 -85.4456)
		(width 0.15494)
		(layer "In15.Cu")
		(net "SSD12_LED_R")
	)
	(segment
		(start 283.083254 -87.503)
		(end 311.63768 -87.503)
		(width 0.15494)
		(layer "In15.Cu")
		(net "SSD12_LED_R")
	)
	(segment
		(start 339.953346 -91.6686)
		(end 343.5858 -91.6686)
		(width 0.15494)
		(layer "In15.Cu")
		(net "SSD12_LED_R")
	)
	(segment
		(start 316.604142 -87.7824)
		(end 328.772266 -87.7824)
		(width 0.15494)
		(layer "In15.Cu")
		(net "SSD12_LED_R")
	)
	(segment
		(start 225.39071 -81.111598)
		(end 226.35718 -80.145128)
		(width 0.15494)
		(layer "In15.Cu")
		(net "SSD12_LED_R")
	)
	(segment
		(start 311.63768 -87.503)
		(end 311.732422 -87.408258)
		(width 0.15494)
		(layer "In15.Cu")
		(net "SSD12_LED_R")
	)
	(segment
		(start 268.166088 -80.333088)
		(end 273.2786 -85.4456)
		(width 0.15494)
		(layer "In15.Cu")
		(net "SSD12_LED_R")
	)
	(segment
		(start 329.686666 -88.6968)
		(end 330.88961 -88.6968)
		(width 0.15494)
		(layer "In15.Cu")
		(net "SSD12_LED_R")
	)
	(segment
		(start 328.772266 -87.7824)
		(end 329.686666 -88.6968)
		(width 0.15494)
		(layer "In15.Cu")
		(net "SSD12_LED_R")
	)
	(segment
		(start 333.4766 -89.3826)
		(end 337.667346 -89.3826)
		(width 0.15494)
		(layer "In15.Cu")
		(net "SSD12_LED_R")
	)
	(segment
		(start 255.244346 -78.1304)
		(end 257.447034 -80.333088)
		(width 0.15494)
		(layer "In15.Cu")
		(net "SSD12_LED_R")
	)
	(segment
		(start 223.006158 -81.627472)
		(end 224.322894 -81.627472)
		(width 0.15494)
		(layer "In15.Cu")
		(net "SSD12_LED_R")
	)
	(segment
		(start 226.35718 -80.145128)
		(end 226.35718 -76.334874)
		(width 0.15494)
		(layer "In15.Cu")
		(net "SSD12_LED_R")
	)
	(segment
		(start 243.9924 -77.0636)
		(end 252.7554 -77.0636)
		(width 0.15494)
		(layer "In15.Cu")
		(net "SSD12_LED_R")
	)
	(segment
		(start 236.9058 -74.5236)
		(end 238.8108 -76.4286)
		(width 0.15494)
		(layer "In15.Cu")
		(net "SSD12_LED_R")
	)
	(segment
		(start 337.667346 -89.3826)
		(end 339.953346 -91.6686)
		(width 0.15494)
		(layer "In15.Cu")
		(net "SSD12_LED_R")
	)
	(segment
		(start 343.5858 -91.6686)
		(end 346.8116 -94.8944)
		(width 0.15494)
		(layer "In15.Cu")
		(net "SSD12_LED_R")
	)
	(segment
		(start 238.8108 -76.4286)
		(end 243.3574 -76.4286)
		(width 0.15494)
		(layer "In15.Cu")
		(net "SSD12_LED_R")
	)
	(segment
		(start 253.8222 -78.1304)
		(end 255.244346 -78.1304)
		(width 0.15494)
		(layer "In15.Cu")
		(net "SSD12_LED_R")
	)
	(segment
		(start 316.23 -87.408258)
		(end 316.604142 -87.7824)
		(width 0.15494)
		(layer "In15.Cu")
		(net "SSD12_LED_R")
	)
	(segment
		(start 323.417692 -95.8469)
		(end 323.706744 -95.8469)
		(width 0.13208)
		(layer "F.Cu")
		(net "NIC_ADC_ALERT_N")
	)
	(segment
		(start 366.507776 -153.1112)
		(end 365.491776 -153.1112)
		(width 0.13208)
		(layer "F.Cu")
		(net "NIC_ADC_ALERT_N")
	)
	(segment
		(start 219.477844 -96.79305)
		(end 219.477844 -97.536)
		(width 0.13208)
		(layer "F.Cu")
		(net "NIC_ADC_ALERT_N")
	)
	(segment
		(start 91.056714 -95.801942)
		(end 91.461844 -95.801942)
		(width 0.13208)
		(layer "F.Cu")
		(net "NIC_ADC_ALERT_N")
	)
	(segment
		(start 219.223844 -96.53905)
		(end 219.477844 -96.79305)
		(width 0.13208)
		(layer "F.Cu")
		(net "NIC_ADC_ALERT_N")
	)
	(segment
		(start 323.256656 -96.410272)
		(end 323.256656 -96.007936)
		(width 0.13208)
		(layer "F.Cu")
		(net "NIC_ADC_ALERT_N")
	)
	(segment
		(start 91.055444 -96.411542)
		(end 91.056714 -96.410272)
		(width 0.13208)
		(layer "F.Cu")
		(net "NIC_ADC_ALERT_N")
	)
	(segment
		(start 323.256656 -96.007936)
		(end 323.417692 -95.8469)
		(width 0.13208)
		(layer "F.Cu")
		(net "NIC_ADC_ALERT_N")
	)
	(segment
		(start 439.761884 -95.801942)
		(end 439.356754 -95.801942)
		(width 0.13208)
		(layer "F.Cu")
		(net "NIC_ADC_ALERT_N")
	)
	(segment
		(start 249.391678 -153.1112)
		(end 250.407678 -153.1112)
		(width 0.13208)
		(layer "F.Cu")
		(net "NIC_ADC_ALERT_N")
	)
	(segment
		(start 224.267776 -215.104218)
		(end 223.86798 -214.704422)
		(width 0.13208)
		(layer "F.Cu")
		(net "NIC_ADC_ALERT_N")
	)
	(segment
		(start 17.191736 -153.1112)
		(end 17.191736 -153.831798)
		(width 0.13208)
		(layer "F.Cu")
		(net "NIC_ADC_ALERT_N")
	)
	(segment
		(start 440.371484 -96.411542)
		(end 439.761884 -95.801942)
		(width 0.13208)
		(layer "F.Cu")
		(net "NIC_ADC_ALERT_N")
	)
	(segment
		(start 323.255386 -96.411542)
		(end 323.256656 -96.410272)
		(width 0.13208)
		(layer "F.Cu")
		(net "NIC_ADC_ALERT_N")
	)
	(segment
		(start 133.29158 -153.1112)
		(end 133.29158 -153.831798)
		(width 0.13208)
		(layer "F.Cu")
		(net "NIC_ADC_ALERT_N")
	)
	(segment
		(start 439.356754 -96.410272)
		(end 439.355484 -96.411542)
		(width 0.13208)
		(layer "F.Cu")
		(net "NIC_ADC_ALERT_N")
	)
	(segment
		(start 18.207736 -153.1112)
		(end 17.191736 -153.1112)
		(width 0.13208)
		(layer "F.Cu")
		(net "NIC_ADC_ALERT_N")
	)
	(segment
		(start 133.29158 -153.1112)
		(end 134.30758 -153.1112)
		(width 0.13208)
		(layer "F.Cu")
		(net "NIC_ADC_ALERT_N")
	)
	(segment
		(start 91.461844 -95.801942)
		(end 92.071444 -96.411542)
		(width 0.13208)
		(layer "F.Cu")
		(net "NIC_ADC_ALERT_N")
	)
	(segment
		(start 365.491776 -153.1112)
		(end 365.491776 -153.831798)
		(width 0.13208)
		(layer "F.Cu")
		(net "NIC_ADC_ALERT_N")
	)
	(segment
		(start 91.056714 -96.410272)
		(end 91.056714 -95.801942)
		(width 0.13208)
		(layer "F.Cu")
		(net "NIC_ADC_ALERT_N")
	)
	(segment
		(start 219.477844 -97.536)
		(end 219.477844 -98.15195)
		(width 0.13208)
		(layer "F.Cu")
		(net "NIC_ADC_ALERT_N")
	)
	(segment
		(start 219.477844 -98.15195)
		(end 219.223844 -98.40595)
		(width 0.13208)
		(layer "F.Cu")
		(net "NIC_ADC_ALERT_N")
	)
	(segment
		(start 323.706744 -95.8469)
		(end 324.271386 -96.411542)
		(width 0.13208)
		(layer "F.Cu")
		(net "NIC_ADC_ALERT_N")
	)
	(segment
		(start 249.391678 -153.1112)
		(end 249.391678 -153.831798)
		(width 0.13208)
		(layer "F.Cu")
		(net "NIC_ADC_ALERT_N")
	)
	(segment
		(start 439.356754 -95.801942)
		(end 439.356754 -96.410272)
		(width 0.13208)
		(layer "F.Cu")
		(net "NIC_ADC_ALERT_N")
	)
	(via
		(at 249.391678 -153.831798)
		(size 0.508)
		(drill 0.254)
		(layers "F.Cu" "B.Cu")
		(net "NIC_ADC_ALERT_N")
	)
	(via
		(at 235.890816 -172.786294)
		(size 0.508)
		(drill 0.254)
		(layers "F.Cu" "B.Cu")
		(net "NIC_ADC_ALERT_N")
	)
	(via
		(at 17.191736 -153.831798)
		(size 0.508)
		(drill 0.254)
		(layers "F.Cu" "B.Cu")
		(net "NIC_ADC_ALERT_N")
	)
	(via
		(at 25.416764 -97.021904)
		(size 0.508)
		(drill 0.254)
		(layers "F.Cu" "B.Cu")
		(net "NIC_ADC_ALERT_N")
	)
	(via
		(at 91.056714 -95.801942)
		(size 0.508)
		(drill 0.254)
		(layers "F.Cu" "B.Cu")
		(net "NIC_ADC_ALERT_N")
	)
	(via
		(at 242.449604 -169.334434)
		(size 0.508)
		(drill 0.254)
		(layers "F.Cu" "B.Cu")
		(net "NIC_ADC_ALERT_N")
	)
	(via
		(at 133.29158 -153.831798)
		(size 0.508)
		(drill 0.254)
		(layers "F.Cu" "B.Cu")
		(net "NIC_ADC_ALERT_N")
	)
	(via
		(at 446.775078 -137.931144)
		(size 0.508)
		(drill 0.254)
		(layers "F.Cu" "B.Cu")
		(net "NIC_ADC_ALERT_N")
	)
	(via
		(at 365.491776 -153.831798)
		(size 0.508)
		(drill 0.254)
		(layers "F.Cu" "B.Cu")
		(net "NIC_ADC_ALERT_N")
	)
	(via
		(at 323.706744 -95.8469)
		(size 0.508)
		(drill 0.254)
		(layers "F.Cu" "B.Cu")
		(net "NIC_ADC_ALERT_N")
	)
	(via
		(at 219.477844 -97.536)
		(size 0.508)
		(drill 0.254)
		(layers "F.Cu" "B.Cu")
		(net "NIC_ADC_ALERT_N")
	)
	(via
		(at 439.356754 -95.801942)
		(size 0.508)
		(drill 0.254)
		(layers "F.Cu" "B.Cu")
		(net "NIC_ADC_ALERT_N")
	)
	(via
		(at 223.86798 -214.704422)
		(size 0.4572)
		(drill 0.254)
		(layers "F.Cu" "B.Cu")
		(net "NIC_ADC_ALERT_N")
	)
	(via
		(at 370.386356 -103.182674)
		(size 0.508)
		(drill 0.254)
		(layers "F.Cu" "B.Cu")
		(net "NIC_ADC_ALERT_N")
	)
	(via
		(at 113.874042 -96.429322)
		(size 0.508)
		(drill 0.254)
		(layers "F.Cu" "B.Cu")
		(net "NIC_ADC_ALERT_N")
	)
	(segment
		(start 349.10776 -102.23246)
		(end 342.3539 -95.4786)
		(width 0.13208)
		(layer "B.Cu")
		(net "NIC_ADC_ALERT_N")
	)
	(segment
		(start 338.159598 -95.4786)
		(end 337.8962 -95.215202)
		(width 0.13208)
		(layer "B.Cu")
		(net "NIC_ADC_ALERT_N")
	)
	(segment
		(start 337.8962 -95.215202)
		(end 326.99579 -95.215202)
		(width 0.13208)
		(layer "B.Cu")
		(net "NIC_ADC_ALERT_N")
	)
	(segment
		(start 325.079868 -94.473776)
		(end 323.706744 -95.8469)
		(width 0.13208)
		(layer "B.Cu")
		(net "NIC_ADC_ALERT_N")
	)
	(segment
		(start 361.93603 -102.23246)
		(end 349.10776 -102.23246)
		(width 0.13208)
		(layer "B.Cu")
		(net "NIC_ADC_ALERT_N")
	)
	(segment
		(start 342.3539 -95.4786)
		(end 338.159598 -95.4786)
		(width 0.13208)
		(layer "B.Cu")
		(net "NIC_ADC_ALERT_N")
	)
	(segment
		(start 326.254364 -94.473776)
		(end 325.079868 -94.473776)
		(width 0.13208)
		(layer "B.Cu")
		(net "NIC_ADC_ALERT_N")
	)
	(segment
		(start 326.99579 -95.215202)
		(end 326.254364 -94.473776)
		(width 0.13208)
		(layer "B.Cu")
		(net "NIC_ADC_ALERT_N")
	)
	(segment
		(start 362.886244 -103.182674)
		(end 361.93603 -102.23246)
		(width 0.13208)
		(layer "B.Cu")
		(net "NIC_ADC_ALERT_N")
	)
	(segment
		(start 370.386356 -103.182674)
		(end 362.886244 -103.182674)
		(width 0.13208)
		(layer "B.Cu")
		(net "NIC_ADC_ALERT_N")
	)
	(segment
		(start 24.331168 -151.792178)
		(end 22.933406 -153.18994)
		(width 0.15494)
		(layer "In5.Cu")
		(net "NIC_ADC_ALERT_N")
	)
	(segment
		(start 430.835308 -107.903264)
		(end 430.835308 -101.057202)
		(width 0.15494)
		(layer "In5.Cu")
		(net "NIC_ADC_ALERT_N")
	)
	(segment
		(start 446.775078 -137.52449)
		(end 445.791336 -136.540748)
		(width 0.15494)
		(layer "In5.Cu")
		(net "NIC_ADC_ALERT_N")
	)
	(segment
		(start 370.987066 -103.783384)
		(end 370.987066 -110.471712)
		(width 0.15494)
		(layer "In5.Cu")
		(net "NIC_ADC_ALERT_N")
	)
	(segment
		(start 370.987066 -110.471712)
		(end 373.018812 -112.503458)
		(width 0.15494)
		(layer "In5.Cu")
		(net "NIC_ADC_ALERT_N")
	)
	(segment
		(start 235.890816 -172.786294)
		(end 236.6772 -171.99991)
		(width 0.15494)
		(layer "In5.Cu")
		(net "NIC_ADC_ALERT_N")
	)
	(segment
		(start 436.617872 -95.274638)
		(end 438.82945 -95.274638)
		(width 0.15494)
		(layer "In5.Cu")
		(net "NIC_ADC_ALERT_N")
	)
	(segment
		(start 437.190134 -128.256538)
		(end 437.190134 -119.100346)
		(width 0.15494)
		(layer "In5.Cu")
		(net "NIC_ADC_ALERT_N")
	)
	(segment
		(start 445.791336 -136.540748)
		(end 444.624206 -136.540748)
		(width 0.15494)
		(layer "In5.Cu")
		(net "NIC_ADC_ALERT_N")
	)
	(segment
		(start 370.804186 -153.100786)
		(end 365.89208 -153.100786)
		(width 0.15494)
		(layer "In5.Cu")
		(net "NIC_ADC_ALERT_N")
	)
	(segment
		(start 437.792876 -129.708656)
		(end 437.190134 -128.256538)
		(width 0.15494)
		(layer "In5.Cu")
		(net "NIC_ADC_ALERT_N")
	)
	(segment
		(start 438.82945 -95.274638)
		(end 439.356754 -95.801942)
		(width 0.15494)
		(layer "In5.Cu")
		(net "NIC_ADC_ALERT_N")
	)
	(segment
		(start 373.018812 -112.503458)
		(end 373.018812 -150.88616)
		(width 0.15494)
		(layer "In5.Cu")
		(net "NIC_ADC_ALERT_N")
	)
	(segment
		(start 365.89208 -153.100786)
		(end 365.491776 -153.50109)
		(width 0.15494)
		(layer "In5.Cu")
		(net "NIC_ADC_ALERT_N")
	)
	(segment
		(start 434.68036 -111.748316)
		(end 430.835308 -107.903264)
		(width 0.15494)
		(layer "In5.Cu")
		(net "NIC_ADC_ALERT_N")
	)
	(segment
		(start 236.6772 -171.60875)
		(end 236.8042 -171.48175)
		(width 0.15494)
		(layer "In5.Cu")
		(net "NIC_ADC_ALERT_N")
	)
	(segment
		(start 370.386356 -103.182674)
		(end 370.987066 -103.783384)
		(width 0.15494)
		(layer "In5.Cu")
		(net "NIC_ADC_ALERT_N")
	)
	(segment
		(start 25.416764 -97.021904)
		(end 24.331168 -98.1075)
		(width 0.15494)
		(layer "In5.Cu")
		(net "NIC_ADC_ALERT_N")
	)
	(segment
		(start 444.624206 -136.540748)
		(end 437.792876 -129.708656)
		(width 0.15494)
		(layer "In5.Cu")
		(net "NIC_ADC_ALERT_N")
	)
	(segment
		(start 22.933406 -153.18994)
		(end 17.833594 -153.18994)
		(width 0.15494)
		(layer "In5.Cu")
		(net "NIC_ADC_ALERT_N")
	)
	(segment
		(start 373.018812 -150.88616)
		(end 370.804186 -153.100786)
		(width 0.15494)
		(layer "In5.Cu")
		(net "NIC_ADC_ALERT_N")
	)
	(segment
		(start 365.491776 -153.50109)
		(end 365.491776 -153.831798)
		(width 0.15494)
		(layer "In5.Cu")
		(net "NIC_ADC_ALERT_N")
	)
	(segment
		(start 240.302288 -171.48175)
		(end 242.449604 -169.334434)
		(width 0.15494)
		(layer "In5.Cu")
		(net "NIC_ADC_ALERT_N")
	)
	(segment
		(start 434.68036 -116.590572)
		(end 434.68036 -111.748316)
		(width 0.15494)
		(layer "In5.Cu")
		(net "NIC_ADC_ALERT_N")
	)
	(segment
		(start 437.190134 -119.100346)
		(end 434.68036 -116.590572)
		(width 0.15494)
		(layer "In5.Cu")
		(net "NIC_ADC_ALERT_N")
	)
	(segment
		(start 236.8042 -171.48175)
		(end 240.302288 -171.48175)
		(width 0.15494)
		(layer "In5.Cu")
		(net "NIC_ADC_ALERT_N")
	)
	(segment
		(start 236.6772 -171.99991)
		(end 236.6772 -171.60875)
		(width 0.15494)
		(layer "In5.Cu")
		(net "NIC_ADC_ALERT_N")
	)
	(segment
		(start 430.835308 -101.057202)
		(end 436.617872 -95.274638)
		(width 0.15494)
		(layer "In5.Cu")
		(net "NIC_ADC_ALERT_N")
	)
	(segment
		(start 17.833594 -153.18994)
		(end 17.191736 -153.831798)
		(width 0.15494)
		(layer "In5.Cu")
		(net "NIC_ADC_ALERT_N")
	)
	(segment
		(start 24.331168 -98.1075)
		(end 24.331168 -151.792178)
		(width 0.15494)
		(layer "In5.Cu")
		(net "NIC_ADC_ALERT_N")
	)
	(segment
		(start 446.775078 -137.931144)
		(end 446.775078 -137.52449)
		(width 0.15494)
		(layer "In5.Cu")
		(net "NIC_ADC_ALERT_N")
	)
	(segment
		(start 105.830624 -92.9386)
		(end 111.163354 -92.9386)
		(width 0.15494)
		(layer "In7.Cu")
		(net "NIC_ADC_ALERT_N")
	)
	(segment
		(start 114.381788 -96.937068)
		(end 114.381788 -98.304604)
		(width 0.15494)
		(layer "In7.Cu")
		(net "NIC_ADC_ALERT_N")
	)
	(segment
		(start 244.663976 -167.120062)
		(end 242.449604 -169.334434)
		(width 0.15494)
		(layer "In7.Cu")
		(net "NIC_ADC_ALERT_N")
	)
	(segment
		(start 229.109016 -205.82128)
		(end 229.109016 -205.119224)
		(width 0.15494)
		(layer "In7.Cu")
		(net "NIC_ADC_ALERT_N")
	)
	(segment
		(start 228.7778 -192.50787)
		(end 228.7778 -182.319168)
		(width 0.15494)
		(layer "In7.Cu")
		(net "NIC_ADC_ALERT_N")
	)
	(segment
		(start 224.060512 -210.711288)
		(end 224.060512 -209.873088)
		(width 0.15494)
		(layer "In7.Cu")
		(net "NIC_ADC_ALERT_N")
	)
	(segment
		(start 256.791714 -158.090108)
		(end 256.791714 -163.143946)
		(width 0.15494)
		(layer "In7.Cu")
		(net "NIC_ADC_ALERT_N")
	)
	(segment
		(start 252.815598 -167.120062)
		(end 244.663976 -167.120062)
		(width 0.15494)
		(layer "In7.Cu")
		(net "NIC_ADC_ALERT_N")
	)
	(segment
		(start 104.879648 -91.987624)
		(end 105.830624 -92.9386)
		(width 0.15494)
		(layer "In7.Cu")
		(net "NIC_ADC_ALERT_N")
	)
	(segment
		(start 123.15952 -118.1608)
		(end 123.15952 -145.8214)
		(width 0.15494)
		(layer "In7.Cu")
		(net "NIC_ADC_ALERT_N")
	)
	(segment
		(start 231.499918 -173.122082)
		(end 234.616752 -173.122082)
		(width 0.15494)
		(layer "In7.Cu")
		(net "NIC_ADC_ALERT_N")
	)
	(segment
		(start 121.99112 -150.714964)
		(end 123.467622 -152.191466)
		(width 0.15494)
		(layer "In7.Cu")
		(net "NIC_ADC_ALERT_N")
	)
	(segment
		(start 115.278916 -99.201732)
		(end 115.279424 -99.201732)
		(width 0.15494)
		(layer "In7.Cu")
		(net "NIC_ADC_ALERT_N")
	)
	(segment
		(start 100.909882 -83.5152)
		(end 102.082346 -83.5152)
		(width 0.15494)
		(layer "In7.Cu")
		(net "NIC_ADC_ALERT_N")
	)
	(segment
		(start 230.438452 -176.588928)
		(end 230.438452 -174.183548)
		(width 0.15494)
		(layer "In7.Cu")
		(net "NIC_ADC_ALERT_N")
	)
	(segment
		(start 112.2934 -94.068646)
		(end 112.2934 -94.84868)
		(width 0.15494)
		(layer "In7.Cu")
		(net "NIC_ADC_ALERT_N")
	)
	(segment
		(start 256.791714 -163.143946)
		(end 252.815598 -167.120062)
		(width 0.15494)
		(layer "In7.Cu")
		(net "NIC_ADC_ALERT_N")
	)
	(segment
		(start 91.056714 -95.801942)
		(end 91.056714 -95.378778)
		(width 0.15494)
		(layer "In7.Cu")
		(net "NIC_ADC_ALERT_N")
	)
	(segment
		(start 249.731784 -153.831798)
		(end 250.7361 -154.836114)
		(width 0.15494)
		(layer "In7.Cu")
		(net "NIC_ADC_ALERT_N")
	)
	(segment
		(start 114.381788 -98.304604)
		(end 115.278916 -99.201732)
		(width 0.15494)
		(layer "In7.Cu")
		(net "NIC_ADC_ALERT_N")
	)
	(segment
		(start 253.53772 -154.836114)
		(end 256.791714 -158.090108)
		(width 0.15494)
		(layer "In7.Cu")
		(net "NIC_ADC_ALERT_N")
	)
	(segment
		(start 113.874042 -96.429322)
		(end 114.381788 -96.937068)
		(width 0.15494)
		(layer "In7.Cu")
		(net "NIC_ADC_ALERT_N")
	)
	(segment
		(start 249.391678 -153.831798)
		(end 249.731784 -153.831798)
		(width 0.15494)
		(layer "In7.Cu")
		(net "NIC_ADC_ALERT_N")
	)
	(segment
		(start 224.060512 -209.873088)
		(end 226.1616 -207.772)
		(width 0.15494)
		(layer "In7.Cu")
		(net "NIC_ADC_ALERT_N")
	)
	(segment
		(start 230.2256 -202.5396)
		(end 229.9716 -202.2856)
		(width 0.15494)
		(layer "In7.Cu")
		(net "NIC_ADC_ALERT_N")
	)
	(segment
		(start 223.86798 -214.01278)
		(end 222.631 -212.7758)
		(width 0.15494)
		(layer "In7.Cu")
		(net "NIC_ADC_ALERT_N")
	)
	(segment
		(start 91.056714 -95.378778)
		(end 99.02952 -87.405972)
		(width 0.15494)
		(layer "In7.Cu")
		(net "NIC_ADC_ALERT_N")
	)
	(segment
		(start 229.109016 -205.119224)
		(end 230.2256 -204.00264)
		(width 0.15494)
		(layer "In7.Cu")
		(net "NIC_ADC_ALERT_N")
	)
	(segment
		(start 235.890562 -172.78604)
		(end 235.890816 -172.786294)
		(width 0.15494)
		(layer "In7.Cu")
		(net "NIC_ADC_ALERT_N")
	)
	(segment
		(start 115.279424 -99.201732)
		(end 117.25656 -101.178868)
		(width 0.15494)
		(layer "In7.Cu")
		(net "NIC_ADC_ALERT_N")
	)
	(segment
		(start 131.137152 -154.994864)
		(end 132.576824 -154.994864)
		(width 0.15494)
		(layer "In7.Cu")
		(net "NIC_ADC_ALERT_N")
	)
	(segment
		(start 226.1616 -207.772)
		(end 227.158296 -207.772)
		(width 0.15494)
		(layer "In7.Cu")
		(net "NIC_ADC_ALERT_N")
	)
	(segment
		(start 123.467622 -152.191466)
		(end 128.333754 -152.191466)
		(width 0.15494)
		(layer "In7.Cu")
		(net "NIC_ADC_ALERT_N")
	)
	(segment
		(start 228.37394 -192.91173)
		(end 228.7778 -192.50787)
		(width 0.15494)
		(layer "In7.Cu")
		(net "NIC_ADC_ALERT_N")
	)
	(segment
		(start 133.29158 -154.280108)
		(end 133.29158 -153.831798)
		(width 0.15494)
		(layer "In7.Cu")
		(net "NIC_ADC_ALERT_N")
	)
	(segment
		(start 112.2934 -94.84868)
		(end 113.874042 -96.429322)
		(width 0.15494)
		(layer "In7.Cu")
		(net "NIC_ADC_ALERT_N")
	)
	(segment
		(start 102.082346 -83.5152)
		(end 102.8192 -84.252054)
		(width 0.15494)
		(layer "In7.Cu")
		(net "NIC_ADC_ALERT_N")
	)
	(segment
		(start 223.86798 -214.704422)
		(end 223.86798 -214.01278)
		(width 0.15494)
		(layer "In7.Cu")
		(net "NIC_ADC_ALERT_N")
	)
	(segment
		(start 132.576824 -154.994864)
		(end 133.29158 -154.280108)
		(width 0.15494)
		(layer "In7.Cu")
		(net "NIC_ADC_ALERT_N")
	)
	(segment
		(start 102.8192 -88.011)
		(end 104.879648 -90.071448)
		(width 0.15494)
		(layer "In7.Cu")
		(net "NIC_ADC_ALERT_N")
	)
	(segment
		(start 117.25656 -101.178868)
		(end 117.25656 -112.25784)
		(width 0.15494)
		(layer "In7.Cu")
		(net "NIC_ADC_ALERT_N")
	)
	(segment
		(start 111.163354 -92.9386)
		(end 112.2934 -94.068646)
		(width 0.15494)
		(layer "In7.Cu")
		(net "NIC_ADC_ALERT_N")
	)
	(segment
		(start 99.02952 -87.405972)
		(end 99.02952 -85.395562)
		(width 0.15494)
		(layer "In7.Cu")
		(net "NIC_ADC_ALERT_N")
	)
	(segment
		(start 230.2256 -204.00264)
		(end 230.2256 -202.5396)
		(width 0.15494)
		(layer "In7.Cu")
		(net "NIC_ADC_ALERT_N")
	)
	(segment
		(start 227.612956 -181.154324)
		(end 227.612956 -179.414424)
		(width 0.15494)
		(layer "In7.Cu")
		(net "NIC_ADC_ALERT_N")
	)
	(segment
		(start 104.879648 -90.071448)
		(end 104.879648 -91.987624)
		(width 0.15494)
		(layer "In7.Cu")
		(net "NIC_ADC_ALERT_N")
	)
	(segment
		(start 229.9716 -198.671942)
		(end 228.37394 -197.074282)
		(width 0.15494)
		(layer "In7.Cu")
		(net "NIC_ADC_ALERT_N")
	)
	(segment
		(start 128.333754 -152.191466)
		(end 131.137152 -154.994864)
		(width 0.15494)
		(layer "In7.Cu")
		(net "NIC_ADC_ALERT_N")
	)
	(segment
		(start 222.631 -212.1408)
		(end 224.060512 -210.711288)
		(width 0.15494)
		(layer "In7.Cu")
		(net "NIC_ADC_ALERT_N")
	)
	(segment
		(start 121.99112 -146.9898)
		(end 121.99112 -150.714964)
		(width 0.15494)
		(layer "In7.Cu")
		(net "NIC_ADC_ALERT_N")
	)
	(segment
		(start 230.438452 -174.183548)
		(end 231.499918 -173.122082)
		(width 0.15494)
		(layer "In7.Cu")
		(net "NIC_ADC_ALERT_N")
	)
	(segment
		(start 250.7361 -154.836114)
		(end 253.53772 -154.836114)
		(width 0.15494)
		(layer "In7.Cu")
		(net "NIC_ADC_ALERT_N")
	)
	(segment
		(start 102.8192 -84.252054)
		(end 102.8192 -88.011)
		(width 0.15494)
		(layer "In7.Cu")
		(net "NIC_ADC_ALERT_N")
	)
	(segment
		(start 228.7778 -182.319168)
		(end 227.612956 -181.154324)
		(width 0.15494)
		(layer "In7.Cu")
		(net "NIC_ADC_ALERT_N")
	)
	(segment
		(start 99.02952 -85.395562)
		(end 100.909882 -83.5152)
		(width 0.15494)
		(layer "In7.Cu")
		(net "NIC_ADC_ALERT_N")
	)
	(segment
		(start 123.15952 -145.8214)
		(end 121.99112 -146.9898)
		(width 0.15494)
		(layer "In7.Cu")
		(net "NIC_ADC_ALERT_N")
	)
	(segment
		(start 117.25656 -112.25784)
		(end 123.15952 -118.1608)
		(width 0.15494)
		(layer "In7.Cu")
		(net "NIC_ADC_ALERT_N")
	)
	(segment
		(start 234.952794 -172.78604)
		(end 235.890562 -172.78604)
		(width 0.15494)
		(layer "In7.Cu")
		(net "NIC_ADC_ALERT_N")
	)
	(segment
		(start 227.158296 -207.772)
		(end 229.109016 -205.82128)
		(width 0.15494)
		(layer "In7.Cu")
		(net "NIC_ADC_ALERT_N")
	)
	(segment
		(start 228.37394 -197.074282)
		(end 228.37394 -192.91173)
		(width 0.15494)
		(layer "In7.Cu")
		(net "NIC_ADC_ALERT_N")
	)
	(segment
		(start 229.9716 -202.2856)
		(end 229.9716 -198.671942)
		(width 0.15494)
		(layer "In7.Cu")
		(net "NIC_ADC_ALERT_N")
	)
	(segment
		(start 234.616752 -173.122082)
		(end 234.952794 -172.78604)
		(width 0.15494)
		(layer "In7.Cu")
		(net "NIC_ADC_ALERT_N")
	)
	(segment
		(start 222.631 -212.7758)
		(end 222.631 -212.1408)
		(width 0.15494)
		(layer "In7.Cu")
		(net "NIC_ADC_ALERT_N")
	)
	(segment
		(start 227.612956 -179.414424)
		(end 230.438452 -176.588928)
		(width 0.15494)
		(layer "In7.Cu")
		(net "NIC_ADC_ALERT_N")
	)
	(segment
		(start 237.860586 -146.338544)
		(end 238.594138 -145.604992)
		(width 0.15494)
		(layer "In9.Cu")
		(net "NIC_ADC_ALERT_N")
	)
	(segment
		(start 249.045476 -154.316684)
		(end 248.252234 -155.109926)
		(width 0.15494)
		(layer "In9.Cu")
		(net "NIC_ADC_ALERT_N")
	)
	(segment
		(start 242.570254 -156.0576)
		(end 241.899186 -155.386532)
		(width 0.15494)
		(layer "In9.Cu")
		(net "NIC_ADC_ALERT_N")
	)
	(segment
		(start 241.899186 -155.386532)
		(end 241.899186 -154.662632)
		(width 0.15494)
		(layer "In9.Cu")
		(net "NIC_ADC_ALERT_N")
	)
	(segment
		(start 240.080546 -104.76865)
		(end 236.947202 -104.76865)
		(width 0.15494)
		(layer "In9.Cu")
		(net "NIC_ADC_ALERT_N")
	)
	(segment
		(start 242.946428 -113.706402)
		(end 242.946428 -107.634532)
		(width 0.15494)
		(layer "In9.Cu")
		(net "NIC_ADC_ALERT_N")
	)
	(segment
		(start 220.716348 -98.366834)
		(end 220.024198 -98.366834)
		(width 0.15494)
		(layer "In9.Cu")
		(net "NIC_ADC_ALERT_N")
	)
	(segment
		(start 242.5573 -114.09553)
		(end 242.946428 -113.706402)
		(width 0.15494)
		(layer "In9.Cu")
		(net "NIC_ADC_ALERT_N")
	)
	(segment
		(start 248.252234 -155.109926)
		(end 247.485154 -155.109926)
		(width 0.15494)
		(layer "In9.Cu")
		(net "NIC_ADC_ALERT_N")
	)
	(segment
		(start 242.946682 -117.217952)
		(end 242.946682 -115.551966)
		(width 0.15494)
		(layer "In9.Cu")
		(net "NIC_ADC_ALERT_N")
	)
	(segment
		(start 236.181392 -140.050012)
		(end 236.181392 -129.615946)
		(width 0.15494)
		(layer "In9.Cu")
		(net "NIC_ADC_ALERT_N")
	)
	(segment
		(start 241.899186 -154.662632)
		(end 237.860586 -150.624032)
		(width 0.15494)
		(layer "In9.Cu")
		(net "NIC_ADC_ALERT_N")
	)
	(segment
		(start 221.082616 -98.000566)
		(end 220.716348 -98.366834)
		(width 0.15494)
		(layer "In9.Cu")
		(net "NIC_ADC_ALERT_N")
	)
	(segment
		(start 219.477844 -97.82048)
		(end 219.477844 -97.536)
		(width 0.15494)
		(layer "In9.Cu")
		(net "NIC_ADC_ALERT_N")
	)
	(segment
		(start 237.860586 -150.624032)
		(end 237.860586 -146.338544)
		(width 0.15494)
		(layer "In9.Cu")
		(net "NIC_ADC_ALERT_N")
	)
	(segment
		(start 238.594138 -121.570496)
		(end 242.946682 -117.217952)
		(width 0.15494)
		(layer "In9.Cu")
		(net "NIC_ADC_ALERT_N")
	)
	(segment
		(start 232.381552 -100.203)
		(end 231.04983 -100.203)
		(width 0.15494)
		(layer "In9.Cu")
		(net "NIC_ADC_ALERT_N")
	)
	(segment
		(start 242.946682 -115.551966)
		(end 242.5573 -115.162584)
		(width 0.15494)
		(layer "In9.Cu")
		(net "NIC_ADC_ALERT_N")
	)
	(segment
		(start 238.594138 -145.604992)
		(end 238.594138 -142.462758)
		(width 0.15494)
		(layer "In9.Cu")
		(net "NIC_ADC_ALERT_N")
	)
	(segment
		(start 246.53748 -156.0576)
		(end 242.570254 -156.0576)
		(width 0.15494)
		(layer "In9.Cu")
		(net "NIC_ADC_ALERT_N")
	)
	(segment
		(start 242.5573 -115.162584)
		(end 242.5573 -114.09553)
		(width 0.15494)
		(layer "In9.Cu")
		(net "NIC_ADC_ALERT_N")
	)
	(segment
		(start 236.181392 -129.615946)
		(end 238.594138 -127.2032)
		(width 0.15494)
		(layer "In9.Cu")
		(net "NIC_ADC_ALERT_N")
	)
	(segment
		(start 249.391678 -153.831798)
		(end 249.045476 -154.178)
		(width 0.15494)
		(layer "In9.Cu")
		(net "NIC_ADC_ALERT_N")
	)
	(segment
		(start 231.04983 -100.203)
		(end 228.62032 -97.77349)
		(width 0.15494)
		(layer "In9.Cu")
		(net "NIC_ADC_ALERT_N")
	)
	(segment
		(start 228.62032 -97.77349)
		(end 228.62032 -97.177098)
		(width 0.15494)
		(layer "In9.Cu")
		(net "NIC_ADC_ALERT_N")
	)
	(segment
		(start 249.045476 -154.178)
		(end 249.045476 -154.316684)
		(width 0.15494)
		(layer "In9.Cu")
		(net "NIC_ADC_ALERT_N")
	)
	(segment
		(start 227.98024 -96.537018)
		(end 221.381574 -96.537018)
		(width 0.15494)
		(layer "In9.Cu")
		(net "NIC_ADC_ALERT_N")
	)
	(segment
		(start 242.946428 -107.634532)
		(end 240.080546 -104.76865)
		(width 0.15494)
		(layer "In9.Cu")
		(net "NIC_ADC_ALERT_N")
	)
	(segment
		(start 236.947202 -104.76865)
		(end 232.381552 -100.203)
		(width 0.15494)
		(layer "In9.Cu")
		(net "NIC_ADC_ALERT_N")
	)
	(segment
		(start 221.381574 -96.537018)
		(end 221.082616 -96.835976)
		(width 0.15494)
		(layer "In9.Cu")
		(net "NIC_ADC_ALERT_N")
	)
	(segment
		(start 238.594138 -142.462758)
		(end 236.181392 -140.050012)
		(width 0.15494)
		(layer "In9.Cu")
		(net "NIC_ADC_ALERT_N")
	)
	(segment
		(start 247.485154 -155.109926)
		(end 246.53748 -156.0576)
		(width 0.15494)
		(layer "In9.Cu")
		(net "NIC_ADC_ALERT_N")
	)
	(segment
		(start 238.594138 -127.2032)
		(end 238.594138 -121.570496)
		(width 0.15494)
		(layer "In9.Cu")
		(net "NIC_ADC_ALERT_N")
	)
	(segment
		(start 220.024198 -98.366834)
		(end 219.477844 -97.82048)
		(width 0.15494)
		(layer "In9.Cu")
		(net "NIC_ADC_ALERT_N")
	)
	(segment
		(start 221.082616 -96.835976)
		(end 221.082616 -98.000566)
		(width 0.15494)
		(layer "In9.Cu")
		(net "NIC_ADC_ALERT_N")
	)
	(segment
		(start 228.62032 -97.177098)
		(end 227.98024 -96.537018)
		(width 0.15494)
		(layer "In9.Cu")
		(net "NIC_ADC_ALERT_N")
	)
	(segment
		(start 387.166612 -139.172188)
		(end 389.883396 -139.172188)
		(width 0.15494)
		(layer "In13.Cu")
		(net "NIC_ADC_ALERT_N")
	)
	(segment
		(start 394.533628 -136.616694)
		(end 397.860774 -139.94384)
		(width 0.15494)
		(layer "In13.Cu")
		(net "NIC_ADC_ALERT_N")
	)
	(segment
		(start 365.491776 -153.831798)
		(end 366.034828 -153.288746)
		(width 0.15494)
		(layer "In13.Cu")
		(net "NIC_ADC_ALERT_N")
	)
	(segment
		(start 404.810976 -136.70661)
		(end 406.911556 -136.70661)
		(width 0.15494)
		(layer "In13.Cu")
		(net "NIC_ADC_ALERT_N")
	)
	(segment
		(start 443.177422 -141.5288)
		(end 446.775078 -137.931144)
		(width 0.15494)
		(layer "In13.Cu")
		(net "NIC_ADC_ALERT_N")
	)
	(segment
		(start 401.573746 -139.94384)
		(end 404.810976 -136.70661)
		(width 0.15494)
		(layer "In13.Cu")
		(net "NIC_ADC_ALERT_N")
	)
	(segment
		(start 392.43889 -136.616694)
		(end 394.533628 -136.616694)
		(width 0.15494)
		(layer "In13.Cu")
		(net "NIC_ADC_ALERT_N")
	)
	(segment
		(start 411.733746 -141.5288)
		(end 443.177422 -141.5288)
		(width 0.15494)
		(layer "In13.Cu")
		(net "NIC_ADC_ALERT_N")
	)
	(segment
		(start 373.050054 -153.288746)
		(end 387.166612 -139.172188)
		(width 0.15494)
		(layer "In13.Cu")
		(net "NIC_ADC_ALERT_N")
	)
	(segment
		(start 397.860774 -139.94384)
		(end 401.573746 -139.94384)
		(width 0.15494)
		(layer "In13.Cu")
		(net "NIC_ADC_ALERT_N")
	)
	(segment
		(start 389.883396 -139.172188)
		(end 392.43889 -136.616694)
		(width 0.15494)
		(layer "In13.Cu")
		(net "NIC_ADC_ALERT_N")
	)
	(segment
		(start 406.911556 -136.70661)
		(end 411.733746 -141.5288)
		(width 0.15494)
		(layer "In13.Cu")
		(net "NIC_ADC_ALERT_N")
	)
	(segment
		(start 366.034828 -153.288746)
		(end 373.050054 -153.288746)
		(width 0.15494)
		(layer "In13.Cu")
		(net "NIC_ADC_ALERT_N")
	)
	(segment
		(start 267.868654 -93.0402)
		(end 267.589254 -93.3196)
		(width 0.15494)
		(layer "In15.Cu")
		(net "NIC_ADC_ALERT_N")
	)
	(segment
		(start 31.689294 -90.749374)
		(end 25.416764 -97.021904)
		(width 0.15494)
		(layer "In15.Cu")
		(net "NIC_ADC_ALERT_N")
	)
	(segment
		(start 249.391678 -153.831798)
		(end 249.391678 -154.139646)
		(width 0.15494)
		(layer "In15.Cu")
		(net "NIC_ADC_ALERT_N")
	)
	(segment
		(start 196.522086 -139.905486)
		(end 195.199 -138.5824)
		(width 0.15494)
		(layer "In15.Cu")
		(net "NIC_ADC_ALERT_N")
	)
	(segment
		(start 74.82078 -90.749374)
		(end 31.689294 -90.749374)
		(width 0.15494)
		(layer "In15.Cu")
		(net "NIC_ADC_ALERT_N")
	)
	(segment
		(start 244.1194 -151.7904)
		(end 239.1156 -151.7904)
		(width 0.15494)
		(layer "In15.Cu")
		(net "NIC_ADC_ALERT_N")
	)
	(segment
		(start 103.553006 -92.743528)
		(end 101.500178 -90.6907)
		(width 0.15494)
		(layer "In15.Cu")
		(net "NIC_ADC_ALERT_N")
	)
	(segment
		(start 111.99876 -94.070424)
		(end 110.671864 -92.743528)
		(width 0.15494)
		(layer "In15.Cu")
		(net "NIC_ADC_ALERT_N")
	)
	(segment
		(start 237.821724 -150.496524)
		(end 237.821724 -147.260056)
		(width 0.15494)
		(layer "In15.Cu")
		(net "NIC_ADC_ALERT_N")
	)
	(segment
		(start 181.000146 -139.4206)
		(end 180.412898 -139.4206)
		(width 0.15494)
		(layer "In15.Cu")
		(net "NIC_ADC_ALERT_N")
	)
	(segment
		(start 310.862726 -93.311726)
		(end 310.0578 -92.5068)
		(width 0.15494)
		(layer "In15.Cu")
		(net "NIC_ADC_ALERT_N")
	)
	(segment
		(start 233.357928 -101.333046)
		(end 232.5751 -100.550218)
		(width 0.15494)
		(layer "In15.Cu")
		(net "NIC_ADC_ALERT_N")
	)
	(segment
		(start 277.0632 -93.0402)
		(end 267.868654 -93.0402)
		(width 0.15494)
		(layer "In15.Cu")
		(net "NIC_ADC_ALERT_N")
	)
	(segment
		(start 84.321904 -94.054676)
		(end 78.126082 -94.054676)
		(width 0.15494)
		(layer "In15.Cu")
		(net "NIC_ADC_ALERT_N")
	)
	(segment
		(start 110.671864 -92.743528)
		(end 103.553006 -92.743528)
		(width 0.15494)
		(layer "In15.Cu")
		(net "NIC_ADC_ALERT_N")
	)
	(segment
		(start 249.033284 -101.333046)
		(end 233.357928 -101.333046)
		(width 0.15494)
		(layer "In15.Cu")
		(net "NIC_ADC_ALERT_N")
	)
	(segment
		(start 322.013072 -93.311726)
		(end 310.862726 -93.311726)
		(width 0.15494)
		(layer "In15.Cu")
		(net "NIC_ADC_ALERT_N")
	)
	(segment
		(start 249.391678 -154.139646)
		(end 248.464324 -155.067)
		(width 0.15494)
		(layer "In15.Cu")
		(net "NIC_ADC_ALERT_N")
	)
	(segment
		(start 140.31468 -153.20772)
		(end 133.609334 -153.20772)
		(width 0.15494)
		(layer "In15.Cu")
		(net "NIC_ADC_ALERT_N")
	)
	(segment
		(start 237.1852 -136.245346)
		(end 235.026454 -134.0866)
		(width 0.15494)
		(layer "In15.Cu")
		(net "NIC_ADC_ALERT_N")
	)
	(segment
		(start 221.886272 -100.550218)
		(end 219.477844 -98.14179)
		(width 0.15494)
		(layer "In15.Cu")
		(net "NIC_ADC_ALERT_N")
	)
	(segment
		(start 267.589254 -93.3196)
		(end 257.04673 -93.3196)
		(width 0.15494)
		(layer "In15.Cu")
		(net "NIC_ADC_ALERT_N")
	)
	(segment
		(start 219.477844 -98.14179)
		(end 219.477844 -97.536)
		(width 0.15494)
		(layer "In15.Cu")
		(net "NIC_ADC_ALERT_N")
	)
	(segment
		(start 152.153366 -143.09217)
		(end 150.43023 -143.09217)
		(width 0.15494)
		(layer "In15.Cu")
		(net "NIC_ADC_ALERT_N")
	)
	(segment
		(start 277.5966 -92.5068)
		(end 277.0632 -93.0402)
		(width 0.15494)
		(layer "In15.Cu")
		(net "NIC_ADC_ALERT_N")
	)
	(segment
		(start 211.817712 -139.905486)
		(end 196.522086 -139.905486)
		(width 0.15494)
		(layer "In15.Cu")
		(net "NIC_ADC_ALERT_N")
	)
	(segment
		(start 111.99876 -94.55404)
		(end 111.99876 -94.070424)
		(width 0.15494)
		(layer "In15.Cu")
		(net "NIC_ADC_ALERT_N")
	)
	(segment
		(start 248.464324 -155.067)
		(end 247.167146 -155.067)
		(width 0.15494)
		(layer "In15.Cu")
		(net "NIC_ADC_ALERT_N")
	)
	(segment
		(start 158.578804 -136.666732)
		(end 152.153366 -143.09217)
		(width 0.15494)
		(layer "In15.Cu")
		(net "NIC_ADC_ALERT_N")
	)
	(segment
		(start 235.026454 -134.0866)
		(end 217.636598 -134.0866)
		(width 0.15494)
		(layer "In15.Cu")
		(net "NIC_ADC_ALERT_N")
	)
	(segment
		(start 177.901854 -136.6266)
		(end 172.583094 -136.6266)
		(width 0.15494)
		(layer "In15.Cu")
		(net "NIC_ADC_ALERT_N")
	)
	(segment
		(start 168.762934 -138.881866)
		(end 168.173654 -139.471146)
		(width 0.15494)
		(layer "In15.Cu")
		(net "NIC_ADC_ALERT_N")
	)
	(segment
		(start 232.5751 -100.550218)
		(end 221.886272 -100.550218)
		(width 0.15494)
		(layer "In15.Cu")
		(net "NIC_ADC_ALERT_N")
	)
	(segment
		(start 180.0098 -138.734546)
		(end 177.901854 -136.6266)
		(width 0.15494)
		(layer "In15.Cu")
		(net "NIC_ADC_ALERT_N")
	)
	(segment
		(start 101.500178 -90.6907)
		(end 87.68588 -90.6907)
		(width 0.15494)
		(layer "In15.Cu")
		(net "NIC_ADC_ALERT_N")
	)
	(segment
		(start 237.821724 -147.260056)
		(end 237.1852 -146.623532)
		(width 0.15494)
		(layer "In15.Cu")
		(net "NIC_ADC_ALERT_N")
	)
	(segment
		(start 257.04673 -93.3196)
		(end 249.033284 -101.333046)
		(width 0.15494)
		(layer "In15.Cu")
		(net "NIC_ADC_ALERT_N")
	)
	(segment
		(start 181.838346 -138.5824)
		(end 181.000146 -139.4206)
		(width 0.15494)
		(layer "In15.Cu")
		(net "NIC_ADC_ALERT_N")
	)
	(segment
		(start 237.1852 -146.623532)
		(end 237.1852 -136.245346)
		(width 0.15494)
		(layer "In15.Cu")
		(net "NIC_ADC_ALERT_N")
	)
	(segment
		(start 167.296846 -139.471146)
		(end 164.492432 -136.666732)
		(width 0.15494)
		(layer "In15.Cu")
		(net "NIC_ADC_ALERT_N")
	)
	(segment
		(start 180.0098 -139.017502)
		(end 180.0098 -138.734546)
		(width 0.15494)
		(layer "In15.Cu")
		(net "NIC_ADC_ALERT_N")
	)
	(segment
		(start 246.4054 -154.0764)
		(end 244.1194 -151.7904)
		(width 0.15494)
		(layer "In15.Cu")
		(net "NIC_ADC_ALERT_N")
	)
	(segment
		(start 150.43023 -143.09217)
		(end 140.31468 -153.20772)
		(width 0.15494)
		(layer "In15.Cu")
		(net "NIC_ADC_ALERT_N")
	)
	(segment
		(start 133.29158 -153.525474)
		(end 133.29158 -153.831798)
		(width 0.15494)
		(layer "In15.Cu")
		(net "NIC_ADC_ALERT_N")
	)
	(segment
		(start 323.706744 -95.8469)
		(end 323.706744 -95.005398)
		(width 0.15494)
		(layer "In15.Cu")
		(net "NIC_ADC_ALERT_N")
	)
	(segment
		(start 310.0578 -92.5068)
		(end 277.5966 -92.5068)
		(width 0.15494)
		(layer "In15.Cu")
		(net "NIC_ADC_ALERT_N")
	)
	(segment
		(start 239.1156 -151.7904)
		(end 237.821724 -150.496524)
		(width 0.15494)
		(layer "In15.Cu")
		(net "NIC_ADC_ALERT_N")
	)
	(segment
		(start 247.167146 -155.067)
		(end 246.4054 -154.305254)
		(width 0.15494)
		(layer "In15.Cu")
		(net "NIC_ADC_ALERT_N")
	)
	(segment
		(start 195.199 -138.5824)
		(end 181.838346 -138.5824)
		(width 0.15494)
		(layer "In15.Cu")
		(net "NIC_ADC_ALERT_N")
	)
	(segment
		(start 87.68588 -90.6907)
		(end 84.321904 -94.054676)
		(width 0.15494)
		(layer "In15.Cu")
		(net "NIC_ADC_ALERT_N")
	)
	(segment
		(start 113.874042 -96.429322)
		(end 111.99876 -94.55404)
		(width 0.15494)
		(layer "In15.Cu")
		(net "NIC_ADC_ALERT_N")
	)
	(segment
		(start 180.412898 -139.4206)
		(end 180.0098 -139.017502)
		(width 0.15494)
		(layer "In15.Cu")
		(net "NIC_ADC_ALERT_N")
	)
	(segment
		(start 164.492432 -136.666732)
		(end 158.578804 -136.666732)
		(width 0.15494)
		(layer "In15.Cu")
		(net "NIC_ADC_ALERT_N")
	)
	(segment
		(start 168.173654 -139.471146)
		(end 167.296846 -139.471146)
		(width 0.15494)
		(layer "In15.Cu")
		(net "NIC_ADC_ALERT_N")
	)
	(segment
		(start 246.4054 -154.305254)
		(end 246.4054 -154.0764)
		(width 0.15494)
		(layer "In15.Cu")
		(net "NIC_ADC_ALERT_N")
	)
	(segment
		(start 133.609334 -153.20772)
		(end 133.29158 -153.525474)
		(width 0.15494)
		(layer "In15.Cu")
		(net "NIC_ADC_ALERT_N")
	)
	(segment
		(start 323.706744 -95.005398)
		(end 322.013072 -93.311726)
		(width 0.15494)
		(layer "In15.Cu")
		(net "NIC_ADC_ALERT_N")
	)
	(segment
		(start 172.583094 -136.6266)
		(end 170.327828 -138.881866)
		(width 0.15494)
		(layer "In15.Cu")
		(net "NIC_ADC_ALERT_N")
	)
	(segment
		(start 217.636598 -134.0866)
		(end 211.817712 -139.905486)
		(width 0.15494)
		(layer "In15.Cu")
		(net "NIC_ADC_ALERT_N")
	)
	(segment
		(start 78.126082 -94.054676)
		(end 74.82078 -90.749374)
		(width 0.15494)
		(layer "In15.Cu")
		(net "NIC_ADC_ALERT_N")
	)
	(segment
		(start 170.327828 -138.881866)
		(end 168.762934 -138.881866)
		(width 0.15494)
		(layer "In15.Cu")
		(net "NIC_ADC_ALERT_N")
	)
	(segment
		(start 385.98094 -24.189944)
		(end 384.96494 -24.189944)
		(width 0.13208)
		(layer "F.Cu")
		(net "SSD13_LED_ISO_R_N")
	)
	(segment
		(start 396.185644 -24.75865)
		(end 395.550644 -24.75865)
		(width 0.13208)
		(layer "F.Cu")
		(net "SSD13_LED_ISO_R_N")
	)
	(via
		(at 385.98094 -24.189944)
		(size 0.508)
		(drill 0.254)
		(layers "F.Cu" "B.Cu")
		(net "SSD13_LED_ISO_R_N")
	)
	(via
		(at 395.550644 -24.75865)
		(size 0.508)
		(drill 0.254)
		(layers "F.Cu" "B.Cu")
		(net "SSD13_LED_ISO_R_N")
	)
	(segment
		(start 385.98094 -24.189944)
		(end 387.357874 -24.189944)
		(width 0.15494)
		(layer "In5.Cu")
		(net "SSD13_LED_ISO_R_N")
	)
	(segment
		(start 391.122408 -24.115268)
		(end 391.371328 -24.364188)
		(width 0.15494)
		(layer "In5.Cu")
		(net "SSD13_LED_ISO_R_N")
	)
	(segment
		(start 389.83158 -23.486364)
		(end 390.460484 -24.115268)
		(width 0.15494)
		(layer "In5.Cu")
		(net "SSD13_LED_ISO_R_N")
	)
	(segment
		(start 391.371328 -24.364188)
		(end 395.156182 -24.364188)
		(width 0.15494)
		(layer "In5.Cu")
		(net "SSD13_LED_ISO_R_N")
	)
	(segment
		(start 388.061454 -23.486364)
		(end 389.83158 -23.486364)
		(width 0.15494)
		(layer "In5.Cu")
		(net "SSD13_LED_ISO_R_N")
	)
	(segment
		(start 387.357874 -24.189944)
		(end 388.061454 -23.486364)
		(width 0.15494)
		(layer "In5.Cu")
		(net "SSD13_LED_ISO_R_N")
	)
	(segment
		(start 395.156182 -24.364188)
		(end 395.550644 -24.75865)
		(width 0.15494)
		(layer "In5.Cu")
		(net "SSD13_LED_ISO_R_N")
	)
	(segment
		(start 390.460484 -24.115268)
		(end 391.122408 -24.115268)
		(width 0.15494)
		(layer "In5.Cu")
		(net "SSD13_LED_ISO_R_N")
	)
	(segment
		(start 240.637822 -42.66565)
		(end 232.779062 -42.66565)
		(width 0.13208)
		(layer "F.Cu")
		(net "SSD_8_15_ADC_ALERT_N")
	)
	(segment
		(start 311.357518 -46.90491)
		(end 310.843676 -46.90491)
		(width 0.13208)
		(layer "F.Cu")
		(net "SSD_8_15_ADC_ALERT_N")
	)
	(segment
		(start 401.64385 -47.091092)
		(end 401.457668 -46.90491)
		(width 0.13208)
		(layer "F.Cu")
		(net "SSD_8_15_ADC_ALERT_N")
	)
	(segment
		(start 259.543804 -47.441612)
		(end 260.4008 -46.584616)
		(width 0.13208)
		(layer "F.Cu")
		(net "SSD_8_15_ADC_ALERT_N")
	)
	(segment
		(start 337.543648 -47.091092)
		(end 337.357466 -46.90491)
		(width 0.13208)
		(layer "F.Cu")
		(net "SSD_8_15_ADC_ALERT_N")
	)
	(segment
		(start 311.358026 -47.92091)
		(end 311.5437 -47.735236)
		(width 0.13208)
		(layer "F.Cu")
		(net "SSD_8_15_ADC_ALERT_N")
	)
	(segment
		(start 260.4008 -42.8752)
		(end 259.715 -42.1894)
		(width 0.13208)
		(layer "F.Cu")
		(net "SSD_8_15_ADC_ALERT_N")
	)
	(segment
		(start 427.457616 -46.90491)
		(end 426.943774 -46.90491)
		(width 0.13208)
		(layer "F.Cu")
		(net "SSD_8_15_ADC_ALERT_N")
	)
	(segment
		(start 259.357622 -46.90491)
		(end 258.84378 -46.90491)
		(width 0.13208)
		(layer "F.Cu")
		(net "SSD_8_15_ADC_ALERT_N")
	)
	(segment
		(start 401.458176 -47.92091)
		(end 401.64385 -47.735236)
		(width 0.13208)
		(layer "F.Cu")
		(net "SSD_8_15_ADC_ALERT_N")
	)
	(segment
		(start 374.943878 -47.92091)
		(end 375.458228 -47.92091)
		(width 0.13208)
		(layer "F.Cu")
		(net "SSD_8_15_ADC_ALERT_N")
	)
	(segment
		(start 310.843676 -47.92091)
		(end 311.358026 -47.92091)
		(width 0.13208)
		(layer "F.Cu")
		(net "SSD_8_15_ADC_ALERT_N")
	)
	(segment
		(start 284.843728 -47.92091)
		(end 285.358078 -47.92091)
		(width 0.13208)
		(layer "F.Cu")
		(net "SSD_8_15_ADC_ALERT_N")
	)
	(segment
		(start 427.458124 -47.92091)
		(end 427.643798 -47.735236)
		(width 0.13208)
		(layer "F.Cu")
		(net "SSD_8_15_ADC_ALERT_N")
	)
	(segment
		(start 453.643746 -47.441612)
		(end 453.643746 -47.091092)
		(width 0.13208)
		(layer "F.Cu")
		(net "SSD_8_15_ADC_ALERT_N")
	)
	(segment
		(start 427.643798 -47.441612)
		(end 427.643798 -47.091092)
		(width 0.13208)
		(layer "F.Cu")
		(net "SSD_8_15_ADC_ALERT_N")
	)
	(segment
		(start 375.643902 -47.091092)
		(end 375.45772 -46.90491)
		(width 0.13208)
		(layer "F.Cu")
		(net "SSD_8_15_ADC_ALERT_N")
	)
	(segment
		(start 453.643746 -47.735236)
		(end 453.643746 -47.441612)
		(width 0.13208)
		(layer "F.Cu")
		(net "SSD_8_15_ADC_ALERT_N")
	)
	(segment
		(start 375.643902 -47.735236)
		(end 375.643902 -47.441612)
		(width 0.13208)
		(layer "F.Cu")
		(net "SSD_8_15_ADC_ALERT_N")
	)
	(segment
		(start 311.5437 -47.735236)
		(end 311.5437 -47.441612)
		(width 0.13208)
		(layer "F.Cu")
		(net "SSD_8_15_ADC_ALERT_N")
	)
	(segment
		(start 285.543752 -47.091092)
		(end 285.35757 -46.90491)
		(width 0.13208)
		(layer "F.Cu")
		(net "SSD_8_15_ADC_ALERT_N")
	)
	(segment
		(start 258.84378 -47.92091)
		(end 259.35813 -47.92091)
		(width 0.13208)
		(layer "F.Cu")
		(net "SSD_8_15_ADC_ALERT_N")
	)
	(segment
		(start 375.45772 -46.90491)
		(end 374.943878 -46.90491)
		(width 0.13208)
		(layer "F.Cu")
		(net "SSD_8_15_ADC_ALERT_N")
	)
	(segment
		(start 257.489706 -40.624506)
		(end 253.777496 -40.624506)
		(width 0.13208)
		(layer "F.Cu")
		(net "SSD_8_15_ADC_ALERT_N")
	)
	(segment
		(start 401.64385 -47.441612)
		(end 401.64385 -47.091092)
		(width 0.13208)
		(layer "F.Cu")
		(net "SSD_8_15_ADC_ALERT_N")
	)
	(segment
		(start 259.35813 -47.92091)
		(end 259.543804 -47.735236)
		(width 0.13208)
		(layer "F.Cu")
		(net "SSD_8_15_ADC_ALERT_N")
	)
	(segment
		(start 336.843624 -47.92091)
		(end 337.357974 -47.92091)
		(width 0.13208)
		(layer "F.Cu")
		(net "SSD_8_15_ADC_ALERT_N")
	)
	(segment
		(start 242.962938 -40.340534)
		(end 240.637822 -42.66565)
		(width 0.13208)
		(layer "F.Cu")
		(net "SSD_8_15_ADC_ALERT_N")
	)
	(segment
		(start 253.777496 -40.624506)
		(end 253.493524 -40.340534)
		(width 0.13208)
		(layer "F.Cu")
		(net "SSD_8_15_ADC_ALERT_N")
	)
	(segment
		(start 453.457564 -46.90491)
		(end 452.943722 -46.90491)
		(width 0.13208)
		(layer "F.Cu")
		(net "SSD_8_15_ADC_ALERT_N")
	)
	(segment
		(start 401.457668 -46.90491)
		(end 400.943826 -46.90491)
		(width 0.13208)
		(layer "F.Cu")
		(net "SSD_8_15_ADC_ALERT_N")
	)
	(segment
		(start 259.543804 -47.735236)
		(end 259.543804 -47.441612)
		(width 0.13208)
		(layer "F.Cu")
		(net "SSD_8_15_ADC_ALERT_N")
	)
	(segment
		(start 452.943722 -47.92091)
		(end 453.458072 -47.92091)
		(width 0.13208)
		(layer "F.Cu")
		(net "SSD_8_15_ADC_ALERT_N")
	)
	(segment
		(start 375.643902 -47.441612)
		(end 375.643902 -47.091092)
		(width 0.13208)
		(layer "F.Cu")
		(net "SSD_8_15_ADC_ALERT_N")
	)
	(segment
		(start 259.543804 -47.441612)
		(end 259.543804 -47.091092)
		(width 0.13208)
		(layer "F.Cu")
		(net "SSD_8_15_ADC_ALERT_N")
	)
	(segment
		(start 311.5437 -47.441612)
		(end 311.5437 -47.091092)
		(width 0.13208)
		(layer "F.Cu")
		(net "SSD_8_15_ADC_ALERT_N")
	)
	(segment
		(start 401.64385 -47.735236)
		(end 401.64385 -47.441612)
		(width 0.13208)
		(layer "F.Cu")
		(net "SSD_8_15_ADC_ALERT_N")
	)
	(segment
		(start 259.715 -42.1894)
		(end 259.0546 -42.1894)
		(width 0.13208)
		(layer "F.Cu")
		(net "SSD_8_15_ADC_ALERT_N")
	)
	(segment
		(start 337.543648 -47.735236)
		(end 337.543648 -47.441612)
		(width 0.13208)
		(layer "F.Cu")
		(net "SSD_8_15_ADC_ALERT_N")
	)
	(segment
		(start 285.543752 -47.735236)
		(end 285.543752 -47.441612)
		(width 0.13208)
		(layer "F.Cu")
		(net "SSD_8_15_ADC_ALERT_N")
	)
	(segment
		(start 285.35757 -46.90491)
		(end 284.843728 -46.90491)
		(width 0.13208)
		(layer "F.Cu")
		(net "SSD_8_15_ADC_ALERT_N")
	)
	(segment
		(start 337.357466 -46.90491)
		(end 336.843624 -46.90491)
		(width 0.13208)
		(layer "F.Cu")
		(net "SSD_8_15_ADC_ALERT_N")
	)
	(segment
		(start 223.06788 -214.704422)
		(end 223.467676 -214.304626)
		(width 0.13208)
		(layer "F.Cu")
		(net "SSD_8_15_ADC_ALERT_N")
	)
	(segment
		(start 223.467676 -214.304626)
		(end 223.467676 -214.304118)
		(width 0.13208)
		(layer "F.Cu")
		(net "SSD_8_15_ADC_ALERT_N")
	)
	(segment
		(start 260.4008 -46.584616)
		(end 260.4008 -42.8752)
		(width 0.13208)
		(layer "F.Cu")
		(net "SSD_8_15_ADC_ALERT_N")
	)
	(segment
		(start 311.5437 -47.091092)
		(end 311.357518 -46.90491)
		(width 0.13208)
		(layer "F.Cu")
		(net "SSD_8_15_ADC_ALERT_N")
	)
	(segment
		(start 427.643798 -47.735236)
		(end 427.643798 -47.441612)
		(width 0.13208)
		(layer "F.Cu")
		(net "SSD_8_15_ADC_ALERT_N")
	)
	(segment
		(start 253.493524 -40.340534)
		(end 242.962938 -40.340534)
		(width 0.13208)
		(layer "F.Cu")
		(net "SSD_8_15_ADC_ALERT_N")
	)
	(segment
		(start 337.357974 -47.92091)
		(end 337.543648 -47.735236)
		(width 0.13208)
		(layer "F.Cu")
		(net "SSD_8_15_ADC_ALERT_N")
	)
	(segment
		(start 375.458228 -47.92091)
		(end 375.643902 -47.735236)
		(width 0.13208)
		(layer "F.Cu")
		(net "SSD_8_15_ADC_ALERT_N")
	)
	(segment
		(start 259.543804 -47.091092)
		(end 259.357622 -46.90491)
		(width 0.13208)
		(layer "F.Cu")
		(net "SSD_8_15_ADC_ALERT_N")
	)
	(segment
		(start 427.643798 -47.091092)
		(end 427.457616 -46.90491)
		(width 0.13208)
		(layer "F.Cu")
		(net "SSD_8_15_ADC_ALERT_N")
	)
	(segment
		(start 453.643746 -47.091092)
		(end 453.457564 -46.90491)
		(width 0.13208)
		(layer "F.Cu")
		(net "SSD_8_15_ADC_ALERT_N")
	)
	(segment
		(start 337.543648 -47.441612)
		(end 337.543648 -47.091092)
		(width 0.13208)
		(layer "F.Cu")
		(net "SSD_8_15_ADC_ALERT_N")
	)
	(segment
		(start 285.543752 -47.441612)
		(end 285.543752 -47.091092)
		(width 0.13208)
		(layer "F.Cu")
		(net "SSD_8_15_ADC_ALERT_N")
	)
	(segment
		(start 426.943774 -47.92091)
		(end 427.458124 -47.92091)
		(width 0.13208)
		(layer "F.Cu")
		(net "SSD_8_15_ADC_ALERT_N")
	)
	(segment
		(start 453.458072 -47.92091)
		(end 453.643746 -47.735236)
		(width 0.13208)
		(layer "F.Cu")
		(net "SSD_8_15_ADC_ALERT_N")
	)
	(segment
		(start 259.0546 -42.1894)
		(end 257.489706 -40.624506)
		(width 0.13208)
		(layer "F.Cu")
		(net "SSD_8_15_ADC_ALERT_N")
	)
	(segment
		(start 285.358078 -47.92091)
		(end 285.543752 -47.735236)
		(width 0.13208)
		(layer "F.Cu")
		(net "SSD_8_15_ADC_ALERT_N")
	)
	(segment
		(start 400.943826 -47.92091)
		(end 401.458176 -47.92091)
		(width 0.13208)
		(layer "F.Cu")
		(net "SSD_8_15_ADC_ALERT_N")
	)
	(via
		(at 223.06788 -214.704422)
		(size 0.4572)
		(drill 0.254)
		(layers "F.Cu" "B.Cu")
		(net "SSD_8_15_ADC_ALERT_N")
	)
	(via
		(at 311.5437 -47.441612)
		(size 0.508)
		(drill 0.254)
		(layers "F.Cu" "B.Cu")
		(net "SSD_8_15_ADC_ALERT_N")
	)
	(via
		(at 375.643902 -47.441612)
		(size 0.508)
		(drill 0.254)
		(layers "F.Cu" "B.Cu")
		(net "SSD_8_15_ADC_ALERT_N")
	)
	(via
		(at 427.643798 -47.441612)
		(size 0.508)
		(drill 0.254)
		(layers "F.Cu" "B.Cu")
		(net "SSD_8_15_ADC_ALERT_N")
	)
	(via
		(at 259.543804 -47.441612)
		(size 0.508)
		(drill 0.254)
		(layers "F.Cu" "B.Cu")
		(net "SSD_8_15_ADC_ALERT_N")
	)
	(via
		(at 453.643746 -47.441612)
		(size 0.508)
		(drill 0.254)
		(layers "F.Cu" "B.Cu")
		(net "SSD_8_15_ADC_ALERT_N")
	)
	(via
		(at 337.543648 -47.441612)
		(size 0.508)
		(drill 0.254)
		(layers "F.Cu" "B.Cu")
		(net "SSD_8_15_ADC_ALERT_N")
	)
	(via
		(at 285.543752 -47.441612)
		(size 0.508)
		(drill 0.254)
		(layers "F.Cu" "B.Cu")
		(net "SSD_8_15_ADC_ALERT_N")
	)
	(via
		(at 232.779062 -42.66565)
		(size 0.508)
		(drill 0.254)
		(layers "F.Cu" "B.Cu")
		(net "SSD_8_15_ADC_ALERT_N")
	)
	(via
		(at 401.64385 -47.441612)
		(size 0.508)
		(drill 0.254)
		(layers "F.Cu" "B.Cu")
		(net "SSD_8_15_ADC_ALERT_N")
	)
	(segment
		(start 282.74264 -49.598834)
		(end 284.899862 -47.441612)
		(width 0.13208)
		(layer "B.Cu")
		(net "SSD_8_15_ADC_ALERT_N")
	)
	(segment
		(start 365.624364 -49.479708)
		(end 373.605806 -49.479708)
		(width 0.13208)
		(layer "B.Cu")
		(net "SSD_8_15_ADC_ALERT_N")
	)
	(segment
		(start 425.64431 -49.4411)
		(end 427.643798 -47.441612)
		(width 0.13208)
		(layer "B.Cu")
		(net "SSD_8_15_ADC_ALERT_N")
	)
	(segment
		(start 401.64385 -47.441612)
		(end 402.092668 -47.89043)
		(width 0.13208)
		(layer "B.Cu")
		(net "SSD_8_15_ADC_ALERT_N")
	)
	(segment
		(start 442.03493 -47.89043)
		(end 428.092616 -47.89043)
		(width 0.13208)
		(layer "B.Cu")
		(net "SSD_8_15_ADC_ALERT_N")
	)
	(segment
		(start 443.614556 -49.470056)
		(end 442.03493 -47.89043)
		(width 0.13208)
		(layer "B.Cu")
		(net "SSD_8_15_ADC_ALERT_N")
	)
	(segment
		(start 364.035086 -47.89043)
		(end 365.624364 -49.479708)
		(width 0.13208)
		(layer "B.Cu")
		(net "SSD_8_15_ADC_ALERT_N")
	)
	(segment
		(start 303.11725 -49.484788)
		(end 309.500524 -49.484788)
		(width 0.13208)
		(layer "B.Cu")
		(net "SSD_8_15_ADC_ALERT_N")
	)
	(segment
		(start 391.681208 -49.554638)
		(end 398.79016 -49.554638)
		(width 0.13208)
		(layer "B.Cu")
		(net "SSD_8_15_ADC_ALERT_N")
	)
	(segment
		(start 285.97987 -47.87773)
		(end 301.510192 -47.87773)
		(width 0.13208)
		(layer "B.Cu")
		(net "SSD_8_15_ADC_ALERT_N")
	)
	(segment
		(start 275.538692 -47.90313)
		(end 277.234396 -49.598834)
		(width 0.13208)
		(layer "B.Cu")
		(net "SSD_8_15_ADC_ALERT_N")
	)
	(segment
		(start 375.643902 -47.441612)
		(end 389.568182 -47.441612)
		(width 0.13208)
		(layer "B.Cu")
		(net "SSD_8_15_ADC_ALERT_N")
	)
	(segment
		(start 284.899862 -47.441612)
		(end 285.543752 -47.441612)
		(width 0.13208)
		(layer "B.Cu")
		(net "SSD_8_15_ADC_ALERT_N")
	)
	(segment
		(start 389.568182 -47.441612)
		(end 391.681208 -49.554638)
		(width 0.13208)
		(layer "B.Cu")
		(net "SSD_8_15_ADC_ALERT_N")
	)
	(segment
		(start 260.005322 -47.90313)
		(end 275.538692 -47.90313)
		(width 0.13208)
		(layer "B.Cu")
		(net "SSD_8_15_ADC_ALERT_N")
	)
	(segment
		(start 285.543752 -47.441612)
		(end 285.97987 -47.87773)
		(width 0.13208)
		(layer "B.Cu")
		(net "SSD_8_15_ADC_ALERT_N")
	)
	(segment
		(start 309.500524 -49.484788)
		(end 311.5437 -47.441612)
		(width 0.13208)
		(layer "B.Cu")
		(net "SSD_8_15_ADC_ALERT_N")
	)
	(segment
		(start 453.643746 -47.441612)
		(end 453.150986 -47.441612)
		(width 0.13208)
		(layer "B.Cu")
		(net "SSD_8_15_ADC_ALERT_N")
	)
	(segment
		(start 416.034982 -47.89043)
		(end 417.585652 -49.4411)
		(width 0.13208)
		(layer "B.Cu")
		(net "SSD_8_15_ADC_ALERT_N")
	)
	(segment
		(start 259.543804 -47.441612)
		(end 260.005322 -47.90313)
		(width 0.13208)
		(layer "B.Cu")
		(net "SSD_8_15_ADC_ALERT_N")
	)
	(segment
		(start 402.092668 -47.89043)
		(end 416.034982 -47.89043)
		(width 0.13208)
		(layer "B.Cu")
		(net "SSD_8_15_ADC_ALERT_N")
	)
	(segment
		(start 417.585652 -49.4411)
		(end 425.64431 -49.4411)
		(width 0.13208)
		(layer "B.Cu")
		(net "SSD_8_15_ADC_ALERT_N")
	)
	(segment
		(start 428.092616 -47.89043)
		(end 427.643798 -47.441612)
		(width 0.13208)
		(layer "B.Cu")
		(net "SSD_8_15_ADC_ALERT_N")
	)
	(segment
		(start 398.79016 -49.554638)
		(end 400.903186 -47.441612)
		(width 0.13208)
		(layer "B.Cu")
		(net "SSD_8_15_ADC_ALERT_N")
	)
	(segment
		(start 337.992466 -47.89043)
		(end 364.035086 -47.89043)
		(width 0.13208)
		(layer "B.Cu")
		(net "SSD_8_15_ADC_ALERT_N")
	)
	(segment
		(start 311.5437 -47.441612)
		(end 311.992518 -47.89043)
		(width 0.13208)
		(layer "B.Cu")
		(net "SSD_8_15_ADC_ALERT_N")
	)
	(segment
		(start 327.504806 -49.460404)
		(end 335.524856 -49.460404)
		(width 0.13208)
		(layer "B.Cu")
		(net "SSD_8_15_ADC_ALERT_N")
	)
	(segment
		(start 453.150986 -47.441612)
		(end 451.122542 -49.470056)
		(width 0.13208)
		(layer "B.Cu")
		(net "SSD_8_15_ADC_ALERT_N")
	)
	(segment
		(start 400.903186 -47.441612)
		(end 401.64385 -47.441612)
		(width 0.13208)
		(layer "B.Cu")
		(net "SSD_8_15_ADC_ALERT_N")
	)
	(segment
		(start 373.605806 -49.479708)
		(end 375.643902 -47.441612)
		(width 0.13208)
		(layer "B.Cu")
		(net "SSD_8_15_ADC_ALERT_N")
	)
	(segment
		(start 337.543648 -47.441612)
		(end 337.992466 -47.89043)
		(width 0.13208)
		(layer "B.Cu")
		(net "SSD_8_15_ADC_ALERT_N")
	)
	(segment
		(start 311.992518 -47.89043)
		(end 325.934832 -47.89043)
		(width 0.13208)
		(layer "B.Cu")
		(net "SSD_8_15_ADC_ALERT_N")
	)
	(segment
		(start 301.510192 -47.87773)
		(end 303.11725 -49.484788)
		(width 0.13208)
		(layer "B.Cu")
		(net "SSD_8_15_ADC_ALERT_N")
	)
	(segment
		(start 451.122542 -49.470056)
		(end 443.614556 -49.470056)
		(width 0.13208)
		(layer "B.Cu")
		(net "SSD_8_15_ADC_ALERT_N")
	)
	(segment
		(start 277.234396 -49.598834)
		(end 282.74264 -49.598834)
		(width 0.13208)
		(layer "B.Cu")
		(net "SSD_8_15_ADC_ALERT_N")
	)
	(segment
		(start 325.934832 -47.89043)
		(end 327.504806 -49.460404)
		(width 0.13208)
		(layer "B.Cu")
		(net "SSD_8_15_ADC_ALERT_N")
	)
	(segment
		(start 335.524856 -49.460404)
		(end 337.543648 -47.441612)
		(width 0.13208)
		(layer "B.Cu")
		(net "SSD_8_15_ADC_ALERT_N")
	)
	(segment
		(start 242.443 -102.10927)
		(end 236.831124 -96.497394)
		(width 0.15494)
		(layer "In7.Cu")
		(net "SSD_8_15_ADC_ALERT_N")
	)
	(segment
		(start 242.443 -116.687854)
		(end 242.443 -102.10927)
		(width 0.15494)
		(layer "In7.Cu")
		(net "SSD_8_15_ADC_ALERT_N")
	)
	(segment
		(start 243.3066 -117.551454)
		(end 242.443 -116.687854)
		(width 0.15494)
		(layer "In7.Cu")
		(net "SSD_8_15_ADC_ALERT_N")
	)
	(segment
		(start 230.968042 -96.497394)
		(end 230.407464 -95.936816)
		(width 0.15494)
		(layer "In7.Cu")
		(net "SSD_8_15_ADC_ALERT_N")
	)
	(segment
		(start 226.9236 -170.255946)
		(end 227.168964 -170.010582)
		(width 0.15494)
		(layer "In7.Cu")
		(net "SSD_8_15_ADC_ALERT_N")
	)
	(segment
		(start 234.816904 -126.719838)
		(end 242.664742 -118.872)
		(width 0.15494)
		(layer "In7.Cu")
		(net "SSD_8_15_ADC_ALERT_N")
	)
	(segment
		(start 230.967788 -94.974664)
		(end 230.967788 -92.161106)
		(width 0.15494)
		(layer "In7.Cu")
		(net "SSD_8_15_ADC_ALERT_N")
	)
	(segment
		(start 224.5106 -165.175946)
		(end 224.5106 -158.2928)
		(width 0.15494)
		(layer "In7.Cu")
		(net "SSD_8_15_ADC_ALERT_N")
	)
	(segment
		(start 227.61702 -192.65519)
		(end 228.06152 -192.21069)
		(width 0.15494)
		(layer "In7.Cu")
		(net "SSD_8_15_ADC_ALERT_N")
	)
	(segment
		(start 222.911924 -208.634076)
		(end 224.05975 -208.634076)
		(width 0.15494)
		(layer "In7.Cu")
		(net "SSD_8_15_ADC_ALERT_N")
	)
	(segment
		(start 232.999788 -126.719838)
		(end 234.816904 -126.719838)
		(width 0.15494)
		(layer "In7.Cu")
		(net "SSD_8_15_ADC_ALERT_N")
	)
	(segment
		(start 224.5106 -158.2928)
		(end 221.026482 -154.808682)
		(width 0.15494)
		(layer "In7.Cu")
		(net "SSD_8_15_ADC_ALERT_N")
	)
	(segment
		(start 226.3394 -178.3842)
		(end 226.9236 -177.8)
		(width 0.15494)
		(layer "In7.Cu")
		(net "SSD_8_15_ADC_ALERT_N")
	)
	(segment
		(start 227.338128 -79.6036)
		(end 227.338128 -72.124824)
		(width 0.15494)
		(layer "In7.Cu")
		(net "SSD_8_15_ADC_ALERT_N")
	)
	(segment
		(start 226.9236 -177.8)
		(end 226.9236 -170.255946)
		(width 0.15494)
		(layer "In7.Cu")
		(net "SSD_8_15_ADC_ALERT_N")
	)
	(segment
		(start 221.026482 -154.808682)
		(end 221.026482 -141.733016)
		(width 0.15494)
		(layer "In7.Cu")
		(net "SSD_8_15_ADC_ALERT_N")
	)
	(segment
		(start 225.988626 -206.7052)
		(end 226.5934 -206.7052)
		(width 0.15494)
		(layer "In7.Cu")
		(net "SSD_8_15_ADC_ALERT_N")
	)
	(segment
		(start 232.779062 -70.569074)
		(end 232.779062 -42.66565)
		(width 0.15494)
		(layer "In7.Cu")
		(net "SSD_8_15_ADC_ALERT_N")
	)
	(segment
		(start 229.847394 -82.112866)
		(end 227.338128 -79.6036)
		(width 0.15494)
		(layer "In7.Cu")
		(net "SSD_8_15_ADC_ALERT_N")
	)
	(segment
		(start 243.3066 -118.491)
		(end 243.3066 -117.551454)
		(width 0.15494)
		(layer "In7.Cu")
		(net "SSD_8_15_ADC_ALERT_N")
	)
	(segment
		(start 227.168964 -170.010582)
		(end 227.168964 -167.83431)
		(width 0.15494)
		(layer "In7.Cu")
		(net "SSD_8_15_ADC_ALERT_N")
	)
	(segment
		(start 229.396544 -90.589862)
		(end 229.396544 -88.458294)
		(width 0.15494)
		(layer "In7.Cu")
		(net "SSD_8_15_ADC_ALERT_N")
	)
	(segment
		(start 226.400614 -181.65572)
		(end 226.3394 -181.594506)
		(width 0.15494)
		(layer "In7.Cu")
		(net "SSD_8_15_ADC_ALERT_N")
	)
	(segment
		(start 229.847394 -88.007444)
		(end 229.847394 -82.112866)
		(width 0.15494)
		(layer "In7.Cu")
		(net "SSD_8_15_ADC_ALERT_N")
	)
	(segment
		(start 228.10597 -71.356982)
		(end 231.991154 -71.356982)
		(width 0.15494)
		(layer "In7.Cu")
		(net "SSD_8_15_ADC_ALERT_N")
	)
	(segment
		(start 230.407464 -95.534988)
		(end 230.967788 -94.974664)
		(width 0.15494)
		(layer "In7.Cu")
		(net "SSD_8_15_ADC_ALERT_N")
	)
	(segment
		(start 228.067616 -203.097384)
		(end 229.2096 -201.9554)
		(width 0.15494)
		(layer "In7.Cu")
		(net "SSD_8_15_ADC_ALERT_N")
	)
	(segment
		(start 227.168964 -167.83431)
		(end 224.5106 -165.175946)
		(width 0.15494)
		(layer "In7.Cu")
		(net "SSD_8_15_ADC_ALERT_N")
	)
	(segment
		(start 227.338128 -72.124824)
		(end 228.10597 -71.356982)
		(width 0.15494)
		(layer "In7.Cu")
		(net "SSD_8_15_ADC_ALERT_N")
	)
	(segment
		(start 227.61702 -197.568566)
		(end 227.61702 -192.65519)
		(width 0.15494)
		(layer "In7.Cu")
		(net "SSD_8_15_ADC_ALERT_N")
	)
	(segment
		(start 223.563434 -139.196064)
		(end 223.563434 -136.156192)
		(width 0.15494)
		(layer "In7.Cu")
		(net "SSD_8_15_ADC_ALERT_N")
	)
	(segment
		(start 229.396544 -88.458294)
		(end 229.847394 -88.007444)
		(width 0.15494)
		(layer "In7.Cu")
		(net "SSD_8_15_ADC_ALERT_N")
	)
	(segment
		(start 242.664742 -118.872)
		(end 242.9256 -118.872)
		(width 0.15494)
		(layer "In7.Cu")
		(net "SSD_8_15_ADC_ALERT_N")
	)
	(segment
		(start 226.3394 -181.594506)
		(end 226.3394 -178.3842)
		(width 0.15494)
		(layer "In7.Cu")
		(net "SSD_8_15_ADC_ALERT_N")
	)
	(segment
		(start 242.9256 -118.872)
		(end 243.3066 -118.491)
		(width 0.15494)
		(layer "In7.Cu")
		(net "SSD_8_15_ADC_ALERT_N")
	)
	(segment
		(start 227.076 -204.663802)
		(end 228.067616 -203.672186)
		(width 0.15494)
		(layer "In7.Cu")
		(net "SSD_8_15_ADC_ALERT_N")
	)
	(segment
		(start 221.026482 -141.733016)
		(end 223.563434 -139.196064)
		(width 0.15494)
		(layer "In7.Cu")
		(net "SSD_8_15_ADC_ALERT_N")
	)
	(segment
		(start 231.991154 -71.356982)
		(end 232.779062 -70.569074)
		(width 0.15494)
		(layer "In7.Cu")
		(net "SSD_8_15_ADC_ALERT_N")
	)
	(segment
		(start 226.5934 -206.7052)
		(end 227.076 -206.2226)
		(width 0.15494)
		(layer "In7.Cu")
		(net "SSD_8_15_ADC_ALERT_N")
	)
	(segment
		(start 228.06152 -183.374284)
		(end 226.400614 -181.713378)
		(width 0.15494)
		(layer "In7.Cu")
		(net "SSD_8_15_ADC_ALERT_N")
	)
	(segment
		(start 227.076 -206.2226)
		(end 227.076 -204.663802)
		(width 0.15494)
		(layer "In7.Cu")
		(net "SSD_8_15_ADC_ALERT_N")
	)
	(segment
		(start 221.7674 -213.403942)
		(end 221.7674 -209.7786)
		(width 0.15494)
		(layer "In7.Cu")
		(net "SSD_8_15_ADC_ALERT_N")
	)
	(segment
		(start 230.967788 -92.161106)
		(end 229.396544 -90.589862)
		(width 0.15494)
		(layer "In7.Cu")
		(net "SSD_8_15_ADC_ALERT_N")
	)
	(segment
		(start 223.06788 -214.704422)
		(end 221.7674 -213.403942)
		(width 0.15494)
		(layer "In7.Cu")
		(net "SSD_8_15_ADC_ALERT_N")
	)
	(segment
		(start 226.400614 -181.713378)
		(end 226.400614 -181.65572)
		(width 0.15494)
		(layer "In7.Cu")
		(net "SSD_8_15_ADC_ALERT_N")
	)
	(segment
		(start 236.831124 -96.497394)
		(end 230.968042 -96.497394)
		(width 0.15494)
		(layer "In7.Cu")
		(net "SSD_8_15_ADC_ALERT_N")
	)
	(segment
		(start 228.067616 -203.672186)
		(end 228.067616 -203.097384)
		(width 0.15494)
		(layer "In7.Cu")
		(net "SSD_8_15_ADC_ALERT_N")
	)
	(segment
		(start 229.2096 -199.161146)
		(end 227.61702 -197.568566)
		(width 0.15494)
		(layer "In7.Cu")
		(net "SSD_8_15_ADC_ALERT_N")
	)
	(segment
		(start 229.2096 -201.9554)
		(end 229.2096 -199.161146)
		(width 0.15494)
		(layer "In7.Cu")
		(net "SSD_8_15_ADC_ALERT_N")
	)
	(segment
		(start 221.7674 -209.7786)
		(end 222.911924 -208.634076)
		(width 0.15494)
		(layer "In7.Cu")
		(net "SSD_8_15_ADC_ALERT_N")
	)
	(segment
		(start 223.563434 -136.156192)
		(end 232.999788 -126.719838)
		(width 0.15494)
		(layer "In7.Cu")
		(net "SSD_8_15_ADC_ALERT_N")
	)
	(segment
		(start 228.06152 -192.21069)
		(end 228.06152 -183.374284)
		(width 0.15494)
		(layer "In7.Cu")
		(net "SSD_8_15_ADC_ALERT_N")
	)
	(segment
		(start 224.05975 -208.634076)
		(end 225.988626 -206.7052)
		(width 0.15494)
		(layer "In7.Cu")
		(net "SSD_8_15_ADC_ALERT_N")
	)
	(segment
		(start 230.407464 -95.936816)
		(end 230.407464 -95.534988)
		(width 0.15494)
		(layer "In7.Cu")
		(net "SSD_8_15_ADC_ALERT_N")
	)
	(segment
		(start 397.323818 -25.55875)
		(end 397.670782 -25.211786)
		(width 0.13208)
		(layer "F.Cu")
		(net "SSD13_LED_ISO_N")
	)
	(segment
		(start 397.670782 -25.211786)
		(end 398.574006 -25.211786)
		(width 0.13208)
		(layer "F.Cu")
		(net "SSD13_LED_ISO_N")
	)
	(segment
		(start 396.185644 -26.692098)
		(end 396.185644 -25.55875)
		(width 0.13208)
		(layer "F.Cu")
		(net "SSD13_LED_ISO_N")
	)
	(segment
		(start 396.185644 -25.55875)
		(end 397.323818 -25.55875)
		(width 0.13208)
		(layer "F.Cu")
		(net "SSD13_LED_ISO_N")
	)
	(via
		(at 397.323818 -25.55875)
		(size 0.508)
		(drill 0.254)
		(layers "F.Cu" "B.Cu")
		(net "SSD13_LED_ISO_N")
	)
	(segment
		(start 223.006158 -78.579472)
		(end 222.390208 -78.579472)
		(width 0.13208)
		(layer "F.Cu")
		(net "SSD9_LED_R")
	)
	(segment
		(start 223.622108 -78.579472)
		(end 223.006158 -78.579472)
		(width 0.13208)
		(layer "F.Cu")
		(net "SSD9_LED_R")
	)
	(segment
		(start 283.423868 -27.411934)
		(end 283.423868 -26.319734)
		(width 0.13208)
		(layer "F.Cu")
		(net "SSD9_LED_R")
	)
	(via
		(at 223.006158 -78.579472)
		(size 0.508)
		(drill 0.254)
		(layers "F.Cu" "B.Cu")
		(net "SSD9_LED_R")
	)
	(via
		(at 301.750984 -84.325968)
		(size 0.508)
		(drill 0.254)
		(layers "F.Cu" "B.Cu")
		(net "SSD9_LED_R")
	)
	(via
		(at 283.423868 -26.319734)
		(size 0.508)
		(drill 0.254)
		(layers "F.Cu" "B.Cu")
		(net "SSD9_LED_R")
	)
	(segment
		(start 296.24782 -44.954444)
		(end 283.423868 -32.130492)
		(width 0.15494)
		(layer "In5.Cu")
		(net "SSD9_LED_R")
	)
	(segment
		(start 283.423868 -32.130492)
		(end 283.423868 -31.278576)
		(width 0.15494)
		(layer "In5.Cu")
		(net "SSD9_LED_R")
	)
	(segment
		(start 296.24782 -73.446132)
		(end 296.24782 -44.954444)
		(width 0.15494)
		(layer "In5.Cu")
		(net "SSD9_LED_R")
	)
	(segment
		(start 283.423868 -31.278576)
		(end 284.508702 -30.193742)
		(width 0.15494)
		(layer "In5.Cu")
		(net "SSD9_LED_R")
	)
	(segment
		(start 301.750984 -84.325968)
		(end 300.97984 -83.554824)
		(width 0.15494)
		(layer "In5.Cu")
		(net "SSD9_LED_R")
	)
	(segment
		(start 284.508702 -30.193742)
		(end 284.508702 -27.404568)
		(width 0.15494)
		(layer "In5.Cu")
		(net "SSD9_LED_R")
	)
	(segment
		(start 284.508702 -27.404568)
		(end 283.423868 -26.319734)
		(width 0.15494)
		(layer "In5.Cu")
		(net "SSD9_LED_R")
	)
	(segment
		(start 300.97984 -78.178152)
		(end 296.24782 -73.446132)
		(width 0.15494)
		(layer "In5.Cu")
		(net "SSD9_LED_R")
	)
	(segment
		(start 300.97984 -83.554824)
		(end 300.97984 -78.178152)
		(width 0.15494)
		(layer "In5.Cu")
		(net "SSD9_LED_R")
	)
	(segment
		(start 299.479462 -84.062062)
		(end 301.487078 -84.062062)
		(width 0.15494)
		(layer "In15.Cu")
		(net "SSD9_LED_R")
	)
	(segment
		(start 260.1214 -77.47)
		(end 263.4742 -77.47)
		(width 0.15494)
		(layer "In15.Cu")
		(net "SSD9_LED_R")
	)
	(segment
		(start 253.111254 -75.8952)
		(end 254.01397 -76.797916)
		(width 0.15494)
		(layer "In15.Cu")
		(net "SSD9_LED_R")
	)
	(segment
		(start 264.6934 -78.6892)
		(end 267.4874 -78.6892)
		(width 0.15494)
		(layer "In15.Cu")
		(net "SSD9_LED_R")
	)
	(segment
		(start 263.4742 -77.47)
		(end 264.6934 -78.6892)
		(width 0.15494)
		(layer "In15.Cu")
		(net "SSD9_LED_R")
	)
	(segment
		(start 275.894546 -79.375)
		(end 294.7924 -79.375)
		(width 0.15494)
		(layer "In15.Cu")
		(net "SSD9_LED_R")
	)
	(segment
		(start 259.449316 -76.797916)
		(end 260.1214 -77.47)
		(width 0.15494)
		(layer "In15.Cu")
		(net "SSD9_LED_R")
	)
	(segment
		(start 294.7924 -79.375)
		(end 299.479462 -84.062062)
		(width 0.15494)
		(layer "In15.Cu")
		(net "SSD9_LED_R")
	)
	(segment
		(start 224.4598 -76.0222)
		(end 227.3554 -73.1266)
		(width 0.15494)
		(layer "In15.Cu")
		(net "SSD9_LED_R")
	)
	(segment
		(start 223.333056 -78.579472)
		(end 224.4598 -77.452728)
		(width 0.15494)
		(layer "In15.Cu")
		(net "SSD9_LED_R")
	)
	(segment
		(start 254.01397 -76.797916)
		(end 259.449316 -76.797916)
		(width 0.15494)
		(layer "In15.Cu")
		(net "SSD9_LED_R")
	)
	(segment
		(start 274.446746 -77.9272)
		(end 275.894546 -79.375)
		(width 0.15494)
		(layer "In15.Cu")
		(net "SSD9_LED_R")
	)
	(segment
		(start 239.242854 -75.2602)
		(end 243.8146 -75.2602)
		(width 0.15494)
		(layer "In15.Cu")
		(net "SSD9_LED_R")
	)
	(segment
		(start 227.3554 -73.1266)
		(end 237.109254 -73.1266)
		(width 0.15494)
		(layer "In15.Cu")
		(net "SSD9_LED_R")
	)
	(segment
		(start 224.4598 -77.452728)
		(end 224.4598 -76.0222)
		(width 0.15494)
		(layer "In15.Cu")
		(net "SSD9_LED_R")
	)
	(segment
		(start 237.109254 -73.1266)
		(end 239.242854 -75.2602)
		(width 0.15494)
		(layer "In15.Cu")
		(net "SSD9_LED_R")
	)
	(segment
		(start 243.8146 -75.2602)
		(end 244.4496 -75.8952)
		(width 0.15494)
		(layer "In15.Cu")
		(net "SSD9_LED_R")
	)
	(segment
		(start 244.4496 -75.8952)
		(end 253.111254 -75.8952)
		(width 0.15494)
		(layer "In15.Cu")
		(net "SSD9_LED_R")
	)
	(segment
		(start 223.006158 -78.579472)
		(end 223.333056 -78.579472)
		(width 0.15494)
		(layer "In15.Cu")
		(net "SSD9_LED_R")
	)
	(segment
		(start 268.2494 -77.9272)
		(end 274.446746 -77.9272)
		(width 0.15494)
		(layer "In15.Cu")
		(net "SSD9_LED_R")
	)
	(segment
		(start 267.4874 -78.6892)
		(end 268.2494 -77.9272)
		(width 0.15494)
		(layer "In15.Cu")
		(net "SSD9_LED_R")
	)
	(segment
		(start 301.487078 -84.062062)
		(end 301.750984 -84.325968)
		(width 0.15494)
		(layer "In15.Cu")
		(net "SSD9_LED_R")
	)
	(segment
		(start 371.32387 -25.55875)
		(end 371.670834 -25.211786)
		(width 0.13208)
		(layer "F.Cu")
		(net "SSD12_LED_ISO_N")
	)
	(segment
		(start 370.185696 -25.55875)
		(end 371.32387 -25.55875)
		(width 0.13208)
		(layer "F.Cu")
		(net "SSD12_LED_ISO_N")
	)
	(segment
		(start 370.185696 -26.692098)
		(end 370.185696 -25.55875)
		(width 0.13208)
		(layer "F.Cu")
		(net "SSD12_LED_ISO_N")
	)
	(segment
		(start 371.670834 -25.211786)
		(end 372.574058 -25.211786)
		(width 0.13208)
		(layer "F.Cu")
		(net "SSD12_LED_ISO_N")
	)
	(via
		(at 371.32387 -25.55875)
		(size 0.508)
		(drill 0.254)
		(layers "F.Cu" "B.Cu")
		(net "SSD12_LED_ISO_N")
	)
	(segment
		(start 257.42392 -27.411934)
		(end 257.42392 -26.319734)
		(width 0.13208)
		(layer "F.Cu")
		(net "SSD8_LED_R")
	)
	(segment
		(start 223.006158 -77.563472)
		(end 222.390208 -77.563472)
		(width 0.13208)
		(layer "F.Cu")
		(net "SSD8_LED_R")
	)
	(segment
		(start 223.622108 -77.563472)
		(end 223.006158 -77.563472)
		(width 0.13208)
		(layer "F.Cu")
		(net "SSD8_LED_R")
	)
	(via
		(at 257.42392 -26.319734)
		(size 0.508)
		(drill 0.254)
		(layers "F.Cu" "B.Cu")
		(net "SSD8_LED_R")
	)
	(via
		(at 277.743412 -78.81747)
		(size 0.508)
		(drill 0.254)
		(layers "F.Cu" "B.Cu")
		(net "SSD8_LED_R")
	)
	(via
		(at 223.006158 -77.563472)
		(size 0.508)
		(drill 0.254)
		(layers "F.Cu" "B.Cu")
		(net "SSD8_LED_R")
	)
	(segment
		(start 258.501388 -27.397202)
		(end 258.501388 -30.208728)
		(width 0.15494)
		(layer "In5.Cu")
		(net "SSD8_LED_R")
	)
	(segment
		(start 273.032982 -77.93101)
		(end 276.856952 -77.93101)
		(width 0.15494)
		(layer "In5.Cu")
		(net "SSD8_LED_R")
	)
	(segment
		(start 270.308832 -75.20686)
		(end 273.032982 -77.93101)
		(width 0.15494)
		(layer "In5.Cu")
		(net "SSD8_LED_R")
	)
	(segment
		(start 257.42392 -26.319734)
		(end 258.501388 -27.397202)
		(width 0.15494)
		(layer "In5.Cu")
		(net "SSD8_LED_R")
	)
	(segment
		(start 257.42392 -32.130492)
		(end 270.308832 -45.015404)
		(width 0.15494)
		(layer "In5.Cu")
		(net "SSD8_LED_R")
	)
	(segment
		(start 258.501388 -30.208728)
		(end 257.42392 -31.286196)
		(width 0.15494)
		(layer "In5.Cu")
		(net "SSD8_LED_R")
	)
	(segment
		(start 276.856952 -77.93101)
		(end 277.743412 -78.81747)
		(width 0.15494)
		(layer "In5.Cu")
		(net "SSD8_LED_R")
	)
	(segment
		(start 257.42392 -31.286196)
		(end 257.42392 -32.130492)
		(width 0.15494)
		(layer "In5.Cu")
		(net "SSD8_LED_R")
	)
	(segment
		(start 270.308832 -45.015404)
		(end 270.308832 -75.20686)
		(width 0.15494)
		(layer "In5.Cu")
		(net "SSD8_LED_R")
	)
	(segment
		(start 237.887256 -72.74814)
		(end 239.992916 -74.8538)
		(width 0.15494)
		(layer "In15.Cu")
		(net "SSD8_LED_R")
	)
	(segment
		(start 268.0462 -77.5462)
		(end 274.5994 -77.5462)
		(width 0.15494)
		(layer "In15.Cu")
		(net "SSD8_LED_R")
	)
	(segment
		(start 223.451674 -77.563472)
		(end 223.7994 -77.215746)
		(width 0.15494)
		(layer "In15.Cu")
		(net "SSD8_LED_R")
	)
	(segment
		(start 275.87067 -78.81747)
		(end 277.743412 -78.81747)
		(width 0.15494)
		(layer "In15.Cu")
		(net "SSD8_LED_R")
	)
	(segment
		(start 223.006158 -77.563472)
		(end 223.451674 -77.563472)
		(width 0.15494)
		(layer "In15.Cu")
		(net "SSD8_LED_R")
	)
	(segment
		(start 274.5994 -77.5462)
		(end 275.87067 -78.81747)
		(width 0.15494)
		(layer "In15.Cu")
		(net "SSD8_LED_R")
	)
	(segment
		(start 260.502146 -77.089)
		(end 263.753854 -77.089)
		(width 0.15494)
		(layer "In15.Cu")
		(net "SSD8_LED_R")
	)
	(segment
		(start 239.992916 -74.8538)
		(end 244.493542 -74.8538)
		(width 0.15494)
		(layer "In15.Cu")
		(net "SSD8_LED_R")
	)
	(segment
		(start 223.7994 -75.971654)
		(end 227.022914 -72.74814)
		(width 0.15494)
		(layer "In15.Cu")
		(net "SSD8_LED_R")
	)
	(segment
		(start 223.7994 -77.215746)
		(end 223.7994 -75.971654)
		(width 0.15494)
		(layer "In15.Cu")
		(net "SSD8_LED_R")
	)
	(segment
		(start 264.947654 -78.2828)
		(end 267.3096 -78.2828)
		(width 0.15494)
		(layer "In15.Cu")
		(net "SSD8_LED_R")
	)
	(segment
		(start 259.9436 -76.149454)
		(end 259.9436 -76.530454)
		(width 0.15494)
		(layer "In15.Cu")
		(net "SSD8_LED_R")
	)
	(segment
		(start 253.662688 -75.786234)
		(end 259.58038 -75.786234)
		(width 0.15494)
		(layer "In15.Cu")
		(net "SSD8_LED_R")
	)
	(segment
		(start 259.9436 -76.530454)
		(end 260.502146 -77.089)
		(width 0.15494)
		(layer "In15.Cu")
		(net "SSD8_LED_R")
	)
	(segment
		(start 227.022914 -72.74814)
		(end 237.887256 -72.74814)
		(width 0.15494)
		(layer "In15.Cu")
		(net "SSD8_LED_R")
	)
	(segment
		(start 253.36627 -75.489816)
		(end 253.662688 -75.786234)
		(width 0.15494)
		(layer "In15.Cu")
		(net "SSD8_LED_R")
	)
	(segment
		(start 245.129558 -75.489816)
		(end 253.36627 -75.489816)
		(width 0.15494)
		(layer "In15.Cu")
		(net "SSD8_LED_R")
	)
	(segment
		(start 267.3096 -78.2828)
		(end 268.0462 -77.5462)
		(width 0.15494)
		(layer "In15.Cu")
		(net "SSD8_LED_R")
	)
	(segment
		(start 263.753854 -77.089)
		(end 264.947654 -78.2828)
		(width 0.15494)
		(layer "In15.Cu")
		(net "SSD8_LED_R")
	)
	(segment
		(start 259.58038 -75.786234)
		(end 259.9436 -76.149454)
		(width 0.15494)
		(layer "In15.Cu")
		(net "SSD8_LED_R")
	)
	(segment
		(start 244.493542 -74.8538)
		(end 245.129558 -75.489816)
		(width 0.15494)
		(layer "In15.Cu")
		(net "SSD8_LED_R")
	)
	(segment
		(start 105.343706 -47.441612)
		(end 105.343706 -47.091092)
		(width 0.13208)
		(layer "F.Cu")
		(net "SSD_0_7_ADC_ALERT_N")
	)
	(segment
		(start 105.158032 -47.92091)
		(end 105.343706 -47.735236)
		(width 0.13208)
		(layer "F.Cu")
		(net "SSD_0_7_ADC_ALERT_N")
	)
	(segment
		(start 223.06788 -215.504268)
		(end 223.467676 -215.104472)
		(width 0.13208)
		(layer "F.Cu")
		(net "SSD_0_7_ADC_ALERT_N")
	)
	(segment
		(start 221.443804 -47.735236)
		(end 221.25813 -47.92091)
		(width 0.13208)
		(layer "F.Cu")
		(net "SSD_0_7_ADC_ALERT_N")
	)
	(segment
		(start 169.443908 -47.441612)
		(end 169.443908 -47.735236)
		(width 0.13208)
		(layer "F.Cu")
		(net "SSD_0_7_ADC_ALERT_N")
	)
	(segment
		(start 105.343706 -47.735236)
		(end 105.343706 -47.441612)
		(width 0.13208)
		(layer "F.Cu")
		(net "SSD_0_7_ADC_ALERT_N")
	)
	(segment
		(start 169.443908 -47.735236)
		(end 169.258234 -47.92091)
		(width 0.13208)
		(layer "F.Cu")
		(net "SSD_0_7_ADC_ALERT_N")
	)
	(segment
		(start 194.743832 -47.92091)
		(end 195.258182 -47.92091)
		(width 0.13208)
		(layer "F.Cu")
		(net "SSD_0_7_ADC_ALERT_N")
	)
	(segment
		(start 169.258234 -47.92091)
		(end 168.743884 -47.92091)
		(width 0.13208)
		(layer "F.Cu")
		(net "SSD_0_7_ADC_ALERT_N")
	)
	(segment
		(start 195.443856 -47.441612)
		(end 195.443856 -47.091092)
		(width 0.13208)
		(layer "F.Cu")
		(net "SSD_0_7_ADC_ALERT_N")
	)
	(segment
		(start 220.74378 -46.90491)
		(end 221.257622 -46.90491)
		(width 0.13208)
		(layer "F.Cu")
		(net "SSD_0_7_ADC_ALERT_N")
	)
	(segment
		(start 53.34381 -47.735236)
		(end 53.158136 -47.92091)
		(width 0.13208)
		(layer "F.Cu")
		(net "SSD_0_7_ADC_ALERT_N")
	)
	(segment
		(start 143.257778 -46.90491)
		(end 143.44396 -47.091092)
		(width 0.13208)
		(layer "F.Cu")
		(net "SSD_0_7_ADC_ALERT_N")
	)
	(segment
		(start 223.467676 -215.104472)
		(end 223.467676 -215.104218)
		(width 0.13208)
		(layer "F.Cu")
		(net "SSD_0_7_ADC_ALERT_N")
	)
	(segment
		(start 27.343862 -47.441612)
		(end 27.343862 -47.735236)
		(width 0.13208)
		(layer "F.Cu")
		(net "SSD_0_7_ADC_ALERT_N")
	)
	(segment
		(start 104.643682 -47.92091)
		(end 105.158032 -47.92091)
		(width 0.13208)
		(layer "F.Cu")
		(net "SSD_0_7_ADC_ALERT_N")
	)
	(segment
		(start 195.257674 -46.90491)
		(end 194.743832 -46.90491)
		(width 0.13208)
		(layer "F.Cu")
		(net "SSD_0_7_ADC_ALERT_N")
	)
	(segment
		(start 143.44396 -47.735236)
		(end 143.258286 -47.92091)
		(width 0.13208)
		(layer "F.Cu")
		(net "SSD_0_7_ADC_ALERT_N")
	)
	(segment
		(start 53.157628 -46.90491)
		(end 53.34381 -47.091092)
		(width 0.13208)
		(layer "F.Cu")
		(net "SSD_0_7_ADC_ALERT_N")
	)
	(segment
		(start 169.443908 -47.091092)
		(end 169.443908 -47.441612)
		(width 0.13208)
		(layer "F.Cu")
		(net "SSD_0_7_ADC_ALERT_N")
	)
	(segment
		(start 79.343758 -47.735236)
		(end 79.343758 -47.441612)
		(width 0.13208)
		(layer "F.Cu")
		(net "SSD_0_7_ADC_ALERT_N")
	)
	(segment
		(start 27.343862 -47.735236)
		(end 27.158188 -47.92091)
		(width 0.13208)
		(layer "F.Cu")
		(net "SSD_0_7_ADC_ALERT_N")
	)
	(segment
		(start 143.258286 -47.92091)
		(end 142.743936 -47.92091)
		(width 0.13208)
		(layer "F.Cu")
		(net "SSD_0_7_ADC_ALERT_N")
	)
	(segment
		(start 79.158084 -47.92091)
		(end 79.343758 -47.735236)
		(width 0.13208)
		(layer "F.Cu")
		(net "SSD_0_7_ADC_ALERT_N")
	)
	(segment
		(start 195.258182 -47.92091)
		(end 195.443856 -47.735236)
		(width 0.13208)
		(layer "F.Cu")
		(net "SSD_0_7_ADC_ALERT_N")
	)
	(segment
		(start 27.343862 -47.091092)
		(end 27.343862 -47.441612)
		(width 0.13208)
		(layer "F.Cu")
		(net "SSD_0_7_ADC_ALERT_N")
	)
	(segment
		(start 53.34381 -47.091092)
		(end 53.34381 -47.441612)
		(width 0.13208)
		(layer "F.Cu")
		(net "SSD_0_7_ADC_ALERT_N")
	)
	(segment
		(start 221.443804 -47.441612)
		(end 221.443804 -47.735236)
		(width 0.13208)
		(layer "F.Cu")
		(net "SSD_0_7_ADC_ALERT_N")
	)
	(segment
		(start 221.25813 -47.92091)
		(end 220.74378 -47.92091)
		(width 0.13208)
		(layer "F.Cu")
		(net "SSD_0_7_ADC_ALERT_N")
	)
	(segment
		(start 105.157524 -46.90491)
		(end 104.643682 -46.90491)
		(width 0.13208)
		(layer "F.Cu")
		(net "SSD_0_7_ADC_ALERT_N")
	)
	(segment
		(start 221.443804 -47.091092)
		(end 221.443804 -47.441612)
		(width 0.13208)
		(layer "F.Cu")
		(net "SSD_0_7_ADC_ALERT_N")
	)
	(segment
		(start 27.158188 -47.92091)
		(end 26.643838 -47.92091)
		(width 0.13208)
		(layer "F.Cu")
		(net "SSD_0_7_ADC_ALERT_N")
	)
	(segment
		(start 79.343758 -47.091092)
		(end 79.157576 -46.90491)
		(width 0.13208)
		(layer "F.Cu")
		(net "SSD_0_7_ADC_ALERT_N")
	)
	(segment
		(start 195.443856 -47.091092)
		(end 195.257674 -46.90491)
		(width 0.13208)
		(layer "F.Cu")
		(net "SSD_0_7_ADC_ALERT_N")
	)
	(segment
		(start 79.157576 -46.90491)
		(end 78.643734 -46.90491)
		(width 0.13208)
		(layer "F.Cu")
		(net "SSD_0_7_ADC_ALERT_N")
	)
	(segment
		(start 53.158136 -47.92091)
		(end 52.643786 -47.92091)
		(width 0.13208)
		(layer "F.Cu")
		(net "SSD_0_7_ADC_ALERT_N")
	)
	(segment
		(start 27.15768 -46.90491)
		(end 27.343862 -47.091092)
		(width 0.13208)
		(layer "F.Cu")
		(net "SSD_0_7_ADC_ALERT_N")
	)
	(segment
		(start 79.343758 -47.441612)
		(end 79.343758 -47.091092)
		(width 0.13208)
		(layer "F.Cu")
		(net "SSD_0_7_ADC_ALERT_N")
	)
	(segment
		(start 105.343706 -47.091092)
		(end 105.157524 -46.90491)
		(width 0.13208)
		(layer "F.Cu")
		(net "SSD_0_7_ADC_ALERT_N")
	)
	(segment
		(start 142.743936 -46.90491)
		(end 143.257778 -46.90491)
		(width 0.13208)
		(layer "F.Cu")
		(net "SSD_0_7_ADC_ALERT_N")
	)
	(segment
		(start 221.257622 -46.90491)
		(end 221.443804 -47.091092)
		(width 0.13208)
		(layer "F.Cu")
		(net "SSD_0_7_ADC_ALERT_N")
	)
	(segment
		(start 53.34381 -47.441612)
		(end 53.34381 -47.735236)
		(width 0.13208)
		(layer "F.Cu")
		(net "SSD_0_7_ADC_ALERT_N")
	)
	(segment
		(start 168.743884 -46.90491)
		(end 169.257726 -46.90491)
		(width 0.13208)
		(layer "F.Cu")
		(net "SSD_0_7_ADC_ALERT_N")
	)
	(segment
		(start 26.643838 -46.90491)
		(end 27.15768 -46.90491)
		(width 0.13208)
		(layer "F.Cu")
		(net "SSD_0_7_ADC_ALERT_N")
	)
	(segment
		(start 52.643786 -46.90491)
		(end 53.157628 -46.90491)
		(width 0.13208)
		(layer "F.Cu")
		(net "SSD_0_7_ADC_ALERT_N")
	)
	(segment
		(start 143.44396 -47.441612)
		(end 143.44396 -47.735236)
		(width 0.13208)
		(layer "F.Cu")
		(net "SSD_0_7_ADC_ALERT_N")
	)
	(segment
		(start 78.643734 -47.92091)
		(end 79.158084 -47.92091)
		(width 0.13208)
		(layer "F.Cu")
		(net "SSD_0_7_ADC_ALERT_N")
	)
	(segment
		(start 169.257726 -46.90491)
		(end 169.443908 -47.091092)
		(width 0.13208)
		(layer "F.Cu")
		(net "SSD_0_7_ADC_ALERT_N")
	)
	(segment
		(start 143.44396 -47.091092)
		(end 143.44396 -47.441612)
		(width 0.13208)
		(layer "F.Cu")
		(net "SSD_0_7_ADC_ALERT_N")
	)
	(segment
		(start 195.443856 -47.735236)
		(end 195.443856 -47.441612)
		(width 0.13208)
		(layer "F.Cu")
		(net "SSD_0_7_ADC_ALERT_N")
	)
	(via
		(at 27.343862 -47.441612)
		(size 0.508)
		(drill 0.254)
		(layers "F.Cu" "B.Cu")
		(net "SSD_0_7_ADC_ALERT_N")
	)
	(via
		(at 53.34381 -47.441612)
		(size 0.508)
		(drill 0.254)
		(layers "F.Cu" "B.Cu")
		(net "SSD_0_7_ADC_ALERT_N")
	)
	(via
		(at 195.443856 -47.441612)
		(size 0.508)
		(drill 0.254)
		(layers "F.Cu" "B.Cu")
		(net "SSD_0_7_ADC_ALERT_N")
	)
	(via
		(at 221.443804 -47.441612)
		(size 0.508)
		(drill 0.254)
		(layers "F.Cu" "B.Cu")
		(net "SSD_0_7_ADC_ALERT_N")
	)
	(via
		(at 169.443908 -47.441612)
		(size 0.508)
		(drill 0.254)
		(layers "F.Cu" "B.Cu")
		(net "SSD_0_7_ADC_ALERT_N")
	)
	(via
		(at 143.44396 -47.441612)
		(size 0.508)
		(drill 0.254)
		(layers "F.Cu" "B.Cu")
		(net "SSD_0_7_ADC_ALERT_N")
	)
	(via
		(at 223.06788 -215.504268)
		(size 0.4572)
		(drill 0.254)
		(layers "F.Cu" "B.Cu")
		(net "SSD_0_7_ADC_ALERT_N")
	)
	(via
		(at 105.343706 -47.441612)
		(size 0.508)
		(drill 0.254)
		(layers "F.Cu" "B.Cu")
		(net "SSD_0_7_ADC_ALERT_N")
	)
	(via
		(at 79.343758 -47.441612)
		(size 0.508)
		(drill 0.254)
		(layers "F.Cu" "B.Cu")
		(net "SSD_0_7_ADC_ALERT_N")
	)
	(via
		(at 226.883214 -178.982624)
		(size 0.508)
		(drill 0.254)
		(layers "F.Cu" "B.Cu")
		(net "SSD_0_7_ADC_ALERT_N")
	)
	(segment
		(start 159.420052 -49.457356)
		(end 167.428164 -49.457356)
		(width 0.13208)
		(layer "B.Cu")
		(net "SSD_0_7_ADC_ALERT_N")
	)
	(segment
		(start 157.840426 -47.87773)
		(end 159.420052 -49.457356)
		(width 0.13208)
		(layer "B.Cu")
		(net "SSD_0_7_ADC_ALERT_N")
	)
	(segment
		(start 170.254422 -47.87773)
		(end 183.840374 -47.87773)
		(width 0.13208)
		(layer "B.Cu")
		(net "SSD_0_7_ADC_ALERT_N")
	)
	(segment
		(start 43.36796 -49.505362)
		(end 51.28006 -49.505362)
		(width 0.13208)
		(layer "B.Cu")
		(net "SSD_0_7_ADC_ALERT_N")
	)
	(segment
		(start 167.428164 -49.457356)
		(end 169.443908 -47.441612)
		(width 0.13208)
		(layer "B.Cu")
		(net "SSD_0_7_ADC_ALERT_N")
	)
	(segment
		(start 77.210412 -49.574958)
		(end 79.343758 -47.441612)
		(width 0.13208)
		(layer "B.Cu")
		(net "SSD_0_7_ADC_ALERT_N")
	)
	(segment
		(start 28.154376 -47.87773)
		(end 41.740328 -47.87773)
		(width 0.13208)
		(layer "B.Cu")
		(net "SSD_0_7_ADC_ALERT_N")
	)
	(segment
		(start 67.734942 -47.89043)
		(end 69.41947 -49.574958)
		(width 0.13208)
		(layer "B.Cu")
		(net "SSD_0_7_ADC_ALERT_N")
	)
	(segment
		(start 105.343706 -47.441612)
		(end 105.792524 -47.89043)
		(width 0.13208)
		(layer "B.Cu")
		(net "SSD_0_7_ADC_ALERT_N")
	)
	(segment
		(start 27.343862 -47.441612)
		(end 27.79268 -47.89043)
		(width 0.13208)
		(layer "B.Cu")
		(net "SSD_0_7_ADC_ALERT_N")
	)
	(segment
		(start 27.79268 -47.89043)
		(end 28.141676 -47.89043)
		(width 0.13208)
		(layer "B.Cu")
		(net "SSD_0_7_ADC_ALERT_N")
	)
	(segment
		(start 69.41947 -49.574958)
		(end 77.210412 -49.574958)
		(width 0.13208)
		(layer "B.Cu")
		(net "SSD_0_7_ADC_ALERT_N")
	)
	(segment
		(start 106.15422 -47.87773)
		(end 131.840478 -47.87773)
		(width 0.13208)
		(layer "B.Cu")
		(net "SSD_0_7_ADC_ALERT_N")
	)
	(segment
		(start 95.31985 -49.457356)
		(end 103.327962 -49.457356)
		(width 0.13208)
		(layer "B.Cu")
		(net "SSD_0_7_ADC_ALERT_N")
	)
	(segment
		(start 79.343758 -47.441612)
		(end 79.779876 -47.87773)
		(width 0.13208)
		(layer "B.Cu")
		(net "SSD_0_7_ADC_ALERT_N")
	)
	(segment
		(start 195.443856 -47.441612)
		(end 195.892674 -47.89043)
		(width 0.13208)
		(layer "B.Cu")
		(net "SSD_0_7_ADC_ALERT_N")
	)
	(segment
		(start 103.327962 -49.457356)
		(end 105.343706 -47.441612)
		(width 0.13208)
		(layer "B.Cu")
		(net "SSD_0_7_ADC_ALERT_N")
	)
	(segment
		(start 196.24167 -47.89043)
		(end 196.25437 -47.87773)
		(width 0.13208)
		(layer "B.Cu")
		(net "SSD_0_7_ADC_ALERT_N")
	)
	(segment
		(start 211.477606 -49.515014)
		(end 219.370402 -49.515014)
		(width 0.13208)
		(layer "B.Cu")
		(net "SSD_0_7_ADC_ALERT_N")
	)
	(segment
		(start 93.740224 -47.87773)
		(end 95.31985 -49.457356)
		(width 0.13208)
		(layer "B.Cu")
		(net "SSD_0_7_ADC_ALERT_N")
	)
	(segment
		(start 41.740328 -47.87773)
		(end 43.36796 -49.505362)
		(width 0.13208)
		(layer "B.Cu")
		(net "SSD_0_7_ADC_ALERT_N")
	)
	(segment
		(start 185.43905 -49.476406)
		(end 193.409062 -49.476406)
		(width 0.13208)
		(layer "B.Cu")
		(net "SSD_0_7_ADC_ALERT_N")
	)
	(segment
		(start 53.34381 -47.441612)
		(end 53.792628 -47.89043)
		(width 0.13208)
		(layer "B.Cu")
		(net "SSD_0_7_ADC_ALERT_N")
	)
	(segment
		(start 53.792628 -47.89043)
		(end 67.734942 -47.89043)
		(width 0.13208)
		(layer "B.Cu")
		(net "SSD_0_7_ADC_ALERT_N")
	)
	(segment
		(start 105.792524 -47.89043)
		(end 106.14152 -47.89043)
		(width 0.13208)
		(layer "B.Cu")
		(net "SSD_0_7_ADC_ALERT_N")
	)
	(segment
		(start 209.840322 -47.87773)
		(end 211.477606 -49.515014)
		(width 0.13208)
		(layer "B.Cu")
		(net "SSD_0_7_ADC_ALERT_N")
	)
	(segment
		(start 143.44396 -47.441612)
		(end 143.880078 -47.87773)
		(width 0.13208)
		(layer "B.Cu")
		(net "SSD_0_7_ADC_ALERT_N")
	)
	(segment
		(start 195.892674 -47.89043)
		(end 196.24167 -47.89043)
		(width 0.13208)
		(layer "B.Cu")
		(net "SSD_0_7_ADC_ALERT_N")
	)
	(segment
		(start 106.14152 -47.89043)
		(end 106.15422 -47.87773)
		(width 0.13208)
		(layer "B.Cu")
		(net "SSD_0_7_ADC_ALERT_N")
	)
	(segment
		(start 143.880078 -47.87773)
		(end 157.840426 -47.87773)
		(width 0.13208)
		(layer "B.Cu")
		(net "SSD_0_7_ADC_ALERT_N")
	)
	(segment
		(start 183.840374 -47.87773)
		(end 185.43905 -49.476406)
		(width 0.13208)
		(layer "B.Cu")
		(net "SSD_0_7_ADC_ALERT_N")
	)
	(segment
		(start 51.28006 -49.505362)
		(end 53.34381 -47.441612)
		(width 0.13208)
		(layer "B.Cu")
		(net "SSD_0_7_ADC_ALERT_N")
	)
	(segment
		(start 133.410452 -49.447704)
		(end 141.437868 -49.447704)
		(width 0.13208)
		(layer "B.Cu")
		(net "SSD_0_7_ADC_ALERT_N")
	)
	(segment
		(start 169.443908 -47.441612)
		(end 169.892726 -47.89043)
		(width 0.13208)
		(layer "B.Cu")
		(net "SSD_0_7_ADC_ALERT_N")
	)
	(segment
		(start 28.141676 -47.89043)
		(end 28.154376 -47.87773)
		(width 0.13208)
		(layer "B.Cu")
		(net "SSD_0_7_ADC_ALERT_N")
	)
	(segment
		(start 79.779876 -47.87773)
		(end 93.740224 -47.87773)
		(width 0.13208)
		(layer "B.Cu")
		(net "SSD_0_7_ADC_ALERT_N")
	)
	(segment
		(start 141.437868 -49.447704)
		(end 143.44396 -47.441612)
		(width 0.13208)
		(layer "B.Cu")
		(net "SSD_0_7_ADC_ALERT_N")
	)
	(segment
		(start 196.25437 -47.87773)
		(end 209.840322 -47.87773)
		(width 0.13208)
		(layer "B.Cu")
		(net "SSD_0_7_ADC_ALERT_N")
	)
	(segment
		(start 169.892726 -47.89043)
		(end 170.241722 -47.89043)
		(width 0.13208)
		(layer "B.Cu")
		(net "SSD_0_7_ADC_ALERT_N")
	)
	(segment
		(start 219.370402 -49.515014)
		(end 221.443804 -47.441612)
		(width 0.13208)
		(layer "B.Cu")
		(net "SSD_0_7_ADC_ALERT_N")
	)
	(segment
		(start 131.840478 -47.87773)
		(end 133.410452 -49.447704)
		(width 0.13208)
		(layer "B.Cu")
		(net "SSD_0_7_ADC_ALERT_N")
	)
	(segment
		(start 193.409062 -49.476406)
		(end 195.443856 -47.441612)
		(width 0.13208)
		(layer "B.Cu")
		(net "SSD_0_7_ADC_ALERT_N")
	)
	(segment
		(start 170.241722 -47.89043)
		(end 170.254422 -47.87773)
		(width 0.13208)
		(layer "B.Cu")
		(net "SSD_0_7_ADC_ALERT_N")
	)
	(segment
		(start 220.989906 -75.547474)
		(end 218.40571 -78.13167)
		(width 0.15494)
		(layer "In5.Cu")
		(net "SSD_0_7_ADC_ALERT_N")
	)
	(segment
		(start 221.880176 -168.8084)
		(end 222.57131 -169.499534)
		(width 0.15494)
		(layer "In5.Cu")
		(net "SSD_0_7_ADC_ALERT_N")
	)
	(segment
		(start 215.3412 -94.7674)
		(end 215.3412 -100.302822)
		(width 0.15494)
		(layer "In5.Cu")
		(net "SSD_0_7_ADC_ALERT_N")
	)
	(segment
		(start 213.355682 -107.193334)
		(end 220.1672 -114.004852)
		(width 0.15494)
		(layer "In5.Cu")
		(net "SSD_0_7_ADC_ALERT_N")
	)
	(segment
		(start 215.3412 -100.302822)
		(end 213.355682 -105.096056)
		(width 0.15494)
		(layer "In5.Cu")
		(net "SSD_0_7_ADC_ALERT_N")
	)
	(segment
		(start 212.29574 -139.11326)
		(end 212.29574 -161.199322)
		(width 0.15494)
		(layer "In5.Cu")
		(net "SSD_0_7_ADC_ALERT_N")
	)
	(segment
		(start 221.443804 -47.441612)
		(end 222.356426 -48.354234)
		(width 0.15494)
		(layer "In5.Cu")
		(net "SSD_0_7_ADC_ALERT_N")
	)
	(segment
		(start 220.989906 -65.522094)
		(end 220.989906 -75.547474)
		(width 0.15494)
		(layer "In5.Cu")
		(net "SSD_0_7_ADC_ALERT_N")
	)
	(segment
		(start 222.57131 -169.720006)
		(end 223.4692 -170.617896)
		(width 0.15494)
		(layer "In5.Cu")
		(net "SSD_0_7_ADC_ALERT_N")
	)
	(segment
		(start 221.337632 -65.174368)
		(end 220.989906 -65.522094)
		(width 0.15494)
		(layer "In5.Cu")
		(net "SSD_0_7_ADC_ALERT_N")
	)
	(segment
		(start 212.29574 -161.199322)
		(end 219.904818 -168.8084)
		(width 0.15494)
		(layer "In5.Cu")
		(net "SSD_0_7_ADC_ALERT_N")
	)
	(segment
		(start 218.40571 -78.13167)
		(end 218.40571 -91.70289)
		(width 0.15494)
		(layer "In5.Cu")
		(net "SSD_0_7_ADC_ALERT_N")
	)
	(segment
		(start 221.337632 -63.581788)
		(end 221.337632 -65.174368)
		(width 0.15494)
		(layer "In5.Cu")
		(net "SSD_0_7_ADC_ALERT_N")
	)
	(segment
		(start 223.4692 -177.162206)
		(end 225.289618 -178.982624)
		(width 0.15494)
		(layer "In5.Cu")
		(net "SSD_0_7_ADC_ALERT_N")
	)
	(segment
		(start 213.355682 -105.096056)
		(end 213.355682 -107.193334)
		(width 0.15494)
		(layer "In5.Cu")
		(net "SSD_0_7_ADC_ALERT_N")
	)
	(segment
		(start 218.40571 -91.70289)
		(end 215.3412 -94.7674)
		(width 0.15494)
		(layer "In5.Cu")
		(net "SSD_0_7_ADC_ALERT_N")
	)
	(segment
		(start 219.904818 -168.8084)
		(end 221.880176 -168.8084)
		(width 0.15494)
		(layer "In5.Cu")
		(net "SSD_0_7_ADC_ALERT_N")
	)
	(segment
		(start 222.57131 -169.499534)
		(end 222.57131 -169.720006)
		(width 0.15494)
		(layer "In5.Cu")
		(net "SSD_0_7_ADC_ALERT_N")
	)
	(segment
		(start 222.356426 -48.354234)
		(end 222.356426 -62.562994)
		(width 0.15494)
		(layer "In5.Cu")
		(net "SSD_0_7_ADC_ALERT_N")
	)
	(segment
		(start 222.356426 -62.562994)
		(end 221.337632 -63.581788)
		(width 0.15494)
		(layer "In5.Cu")
		(net "SSD_0_7_ADC_ALERT_N")
	)
	(segment
		(start 220.1672 -131.2418)
		(end 212.29574 -139.11326)
		(width 0.15494)
		(layer "In5.Cu")
		(net "SSD_0_7_ADC_ALERT_N")
	)
	(segment
		(start 223.4692 -170.617896)
		(end 223.4692 -177.162206)
		(width 0.15494)
		(layer "In5.Cu")
		(net "SSD_0_7_ADC_ALERT_N")
	)
	(segment
		(start 225.289618 -178.982624)
		(end 226.883214 -178.982624)
		(width 0.15494)
		(layer "In5.Cu")
		(net "SSD_0_7_ADC_ALERT_N")
	)
	(segment
		(start 220.1672 -114.004852)
		(end 220.1672 -131.2418)
		(width 0.15494)
		(layer "In5.Cu")
		(net "SSD_0_7_ADC_ALERT_N")
	)
	(segment
		(start 223.467676 -209.766916)
		(end 223.467676 -210.796124)
		(width 0.15494)
		(layer "In7.Cu")
		(net "SSD_0_7_ADC_ALERT_N")
	)
	(segment
		(start 228.416866 -204.338936)
		(end 228.061266 -204.694536)
		(width 0.15494)
		(layer "In7.Cu")
		(net "SSD_0_7_ADC_ALERT_N")
	)
	(segment
		(start 228.061266 -206.075534)
		(end 226.941634 -207.195166)
		(width 0.15494)
		(layer "In7.Cu")
		(net "SSD_0_7_ADC_ALERT_N")
	)
	(segment
		(start 226.883214 -181.28234)
		(end 228.41966 -182.818786)
		(width 0.15494)
		(layer "In7.Cu")
		(net "SSD_0_7_ADC_ALERT_N")
	)
	(segment
		(start 228.0158 -192.76314)
		(end 228.0158 -197.3834)
		(width 0.15494)
		(layer "In7.Cu")
		(net "SSD_0_7_ADC_ALERT_N")
	)
	(segment
		(start 228.41966 -192.35928)
		(end 228.0158 -192.76314)
		(width 0.15494)
		(layer "In7.Cu")
		(net "SSD_0_7_ADC_ALERT_N")
	)
	(segment
		(start 229.7684 -202.9968)
		(end 229.7684 -203.85913)
		(width 0.15494)
		(layer "In7.Cu")
		(net "SSD_0_7_ADC_ALERT_N")
	)
	(segment
		(start 229.288594 -204.338936)
		(end 228.416866 -204.338936)
		(width 0.15494)
		(layer "In7.Cu")
		(net "SSD_0_7_ADC_ALERT_N")
	)
	(segment
		(start 223.46539 -215.106758)
		(end 223.06788 -215.504268)
		(width 0.0889)
		(layer "In7.Cu")
		(net "SSD_0_7_ADC_ALERT_N")
	)
	(segment
		(start 229.5906 -202.819)
		(end 229.7684 -202.9968)
		(width 0.15494)
		(layer "In7.Cu")
		(net "SSD_0_7_ADC_ALERT_N")
	)
	(segment
		(start 229.5906 -198.9582)
		(end 229.5906 -202.819)
		(width 0.15494)
		(layer "In7.Cu")
		(net "SSD_0_7_ADC_ALERT_N")
	)
	(segment
		(start 228.061266 -204.694536)
		(end 228.061266 -206.075534)
		(width 0.15494)
		(layer "In7.Cu")
		(net "SSD_0_7_ADC_ALERT_N")
	)
	(segment
		(start 222.25 -212.0138)
		(end 222.25 -213.0552)
		(width 0.15494)
		(layer "In7.Cu")
		(net "SSD_0_7_ADC_ALERT_N")
	)
	(segment
		(start 226.941634 -207.195166)
		(end 226.039426 -207.195166)
		(width 0.15494)
		(layer "In7.Cu")
		(net "SSD_0_7_ADC_ALERT_N")
	)
	(segment
		(start 222.25 -213.0552)
		(end 223.46539 -214.27059)
		(width 0.15494)
		(layer "In7.Cu")
		(net "SSD_0_7_ADC_ALERT_N")
	)
	(segment
		(start 229.7684 -203.85913)
		(end 229.288594 -204.338936)
		(width 0.15494)
		(layer "In7.Cu")
		(net "SSD_0_7_ADC_ALERT_N")
	)
	(segment
		(start 228.0158 -197.3834)
		(end 229.5906 -198.9582)
		(width 0.15494)
		(layer "In7.Cu")
		(net "SSD_0_7_ADC_ALERT_N")
	)
	(segment
		(start 223.46539 -214.27059)
		(end 223.46539 -215.106758)
		(width 0.0889)
		(layer "In7.Cu")
		(net "SSD_0_7_ADC_ALERT_N")
	)
	(segment
		(start 223.467676 -210.796124)
		(end 222.25 -212.0138)
		(width 0.15494)
		(layer "In7.Cu")
		(net "SSD_0_7_ADC_ALERT_N")
	)
	(segment
		(start 226.039426 -207.195166)
		(end 223.467676 -209.766916)
		(width 0.15494)
		(layer "In7.Cu")
		(net "SSD_0_7_ADC_ALERT_N")
	)
	(segment
		(start 226.883214 -178.982624)
		(end 226.883214 -181.28234)
		(width 0.15494)
		(layer "In7.Cu")
		(net "SSD_0_7_ADC_ALERT_N")
	)
	(segment
		(start 228.41966 -182.818786)
		(end 228.41966 -192.35928)
		(width 0.15494)
		(layer "In7.Cu")
		(net "SSD_0_7_ADC_ALERT_N")
	)
	(segment
		(start 222.390208 -80.611472)
		(end 223.006158 -80.611472)
		(width 0.13208)
		(layer "F.Cu")
		(net "SSD11_LED_R")
	)
	(segment
		(start 335.423764 -27.411934)
		(end 335.423764 -26.319734)
		(width 0.13208)
		(layer "F.Cu")
		(net "SSD11_LED_R")
	)
	(segment
		(start 223.006158 -80.611472)
		(end 223.622108 -80.611472)
		(width 0.13208)
		(layer "F.Cu")
		(net "SSD11_LED_R")
	)
	(via
		(at 223.006158 -80.611472)
		(size 0.508)
		(drill 0.254)
		(layers "F.Cu" "B.Cu")
		(net "SSD11_LED_R")
	)
	(via
		(at 335.423764 -26.319734)
		(size 0.508)
		(drill 0.254)
		(layers "F.Cu" "B.Cu")
		(net "SSD11_LED_R")
	)
	(via
		(at 352.513138 -93.14434)
		(size 0.508)
		(drill 0.254)
		(layers "F.Cu" "B.Cu")
		(net "SSD11_LED_R")
	)
	(segment
		(start 342.930988 -75.398884)
		(end 342.930988 -69.210174)
		(width 0.15494)
		(layer "In5.Cu")
		(net "SSD11_LED_R")
	)
	(segment
		(start 335.396586 -31.284672)
		(end 336.506312 -30.174946)
		(width 0.15494)
		(layer "In5.Cu")
		(net "SSD11_LED_R")
	)
	(segment
		(start 351.777554 -80.821276)
		(end 348.35338 -80.821276)
		(width 0.15494)
		(layer "In5.Cu")
		(net "SSD11_LED_R")
	)
	(segment
		(start 340.89594 -40.872156)
		(end 335.396586 -35.372802)
		(width 0.15494)
		(layer "In5.Cu")
		(net "SSD11_LED_R")
	)
	(segment
		(start 352.838258 -92.083636)
		(end 352.838258 -81.88198)
		(width 0.15494)
		(layer "In5.Cu")
		(net "SSD11_LED_R")
	)
	(segment
		(start 336.506312 -30.174946)
		(end 336.506312 -27.402282)
		(width 0.15494)
		(layer "In5.Cu")
		(net "SSD11_LED_R")
	)
	(segment
		(start 348.35338 -80.821276)
		(end 342.930988 -75.398884)
		(width 0.15494)
		(layer "In5.Cu")
		(net "SSD11_LED_R")
	)
	(segment
		(start 336.506312 -27.402282)
		(end 335.423764 -26.319734)
		(width 0.15494)
		(layer "In5.Cu")
		(net "SSD11_LED_R")
	)
	(segment
		(start 352.838258 -81.88198)
		(end 351.777554 -80.821276)
		(width 0.15494)
		(layer "In5.Cu")
		(net "SSD11_LED_R")
	)
	(segment
		(start 352.513138 -93.14434)
		(end 352.513138 -92.408756)
		(width 0.15494)
		(layer "In5.Cu")
		(net "SSD11_LED_R")
	)
	(segment
		(start 352.513138 -92.408756)
		(end 352.838258 -92.083636)
		(width 0.15494)
		(layer "In5.Cu")
		(net "SSD11_LED_R")
	)
	(segment
		(start 342.930988 -69.210174)
		(end 340.89594 -67.175126)
		(width 0.15494)
		(layer "In5.Cu")
		(net "SSD11_LED_R")
	)
	(segment
		(start 335.396586 -35.372802)
		(end 335.396586 -31.284672)
		(width 0.15494)
		(layer "In5.Cu")
		(net "SSD11_LED_R")
	)
	(segment
		(start 340.89594 -67.175126)
		(end 340.89594 -40.872156)
		(width 0.15494)
		(layer "In5.Cu")
		(net "SSD11_LED_R")
	)
	(segment
		(start 243.5098 -76.0476)
		(end 244.1448 -76.6826)
		(width 0.15494)
		(layer "In15.Cu")
		(net "SSD11_LED_R")
	)
	(segment
		(start 329.082146 -87.4014)
		(end 329.767946 -88.0872)
		(width 0.15494)
		(layer "In15.Cu")
		(net "SSD11_LED_R")
	)
	(segment
		(start 281.2542 -85.0646)
		(end 283.3116 -87.122)
		(width 0.15494)
		(layer "In15.Cu")
		(net "SSD11_LED_R")
	)
	(segment
		(start 225.298254 -80.111092)
		(end 225.99904 -79.410306)
		(width 0.15494)
		(layer "In15.Cu")
		(net "SSD11_LED_R")
	)
	(segment
		(start 223.506538 -80.111092)
		(end 225.298254 -80.111092)
		(width 0.15494)
		(layer "In15.Cu")
		(net "SSD11_LED_R")
	)
	(segment
		(start 268.299946 -79.9592)
		(end 273.405346 -85.0646)
		(width 0.15494)
		(layer "In15.Cu")
		(net "SSD11_LED_R")
	)
	(segment
		(start 237.032546 -74.1426)
		(end 238.937546 -76.0476)
		(width 0.15494)
		(layer "In15.Cu")
		(net "SSD11_LED_R")
	)
	(segment
		(start 351.974658 -93.648022)
		(end 352.47834 -93.14434)
		(width 0.15494)
		(layer "In15.Cu")
		(net "SSD11_LED_R")
	)
	(segment
		(start 263.0678 -79.121)
		(end 263.906 -79.9592)
		(width 0.15494)
		(layer "In15.Cu")
		(net "SSD11_LED_R")
	)
	(segment
		(start 343.814146 -89.1032)
		(end 347.372686 -92.66174)
		(width 0.15494)
		(layer "In15.Cu")
		(net "SSD11_LED_R")
	)
	(segment
		(start 253.948946 -77.7494)
		(end 259.1816 -77.7494)
		(width 0.15494)
		(layer "In15.Cu")
		(net "SSD11_LED_R")
	)
	(segment
		(start 283.3116 -87.122)
		(end 307.7718 -87.122)
		(width 0.15494)
		(layer "In15.Cu")
		(net "SSD11_LED_R")
	)
	(segment
		(start 273.405346 -85.0646)
		(end 281.2542 -85.0646)
		(width 0.15494)
		(layer "In15.Cu")
		(net "SSD11_LED_R")
	)
	(segment
		(start 252.882146 -76.6826)
		(end 253.948946 -77.7494)
		(width 0.15494)
		(layer "In15.Cu")
		(net "SSD11_LED_R")
	)
	(segment
		(start 225.99904 -75.93076)
		(end 227.7872 -74.1426)
		(width 0.15494)
		(layer "In15.Cu")
		(net "SSD11_LED_R")
	)
	(segment
		(start 227.7872 -74.1426)
		(end 237.032546 -74.1426)
		(width 0.15494)
		(layer "In15.Cu")
		(net "SSD11_LED_R")
	)
	(segment
		(start 347.616018 -92.66174)
		(end 348.6023 -93.648022)
		(width 0.15494)
		(layer "In15.Cu")
		(net "SSD11_LED_R")
	)
	(segment
		(start 316.128654 -86.3346)
		(end 317.195454 -87.4014)
		(width 0.15494)
		(layer "In15.Cu")
		(net "SSD11_LED_R")
	)
	(segment
		(start 259.1816 -77.7494)
		(end 260.5532 -79.121)
		(width 0.15494)
		(layer "In15.Cu")
		(net "SSD11_LED_R")
	)
	(segment
		(start 307.7718 -87.122)
		(end 308.5592 -86.3346)
		(width 0.15494)
		(layer "In15.Cu")
		(net "SSD11_LED_R")
	)
	(segment
		(start 332.231746 -87.4522)
		(end 337.654138 -87.4522)
		(width 0.15494)
		(layer "In15.Cu")
		(net "SSD11_LED_R")
	)
	(segment
		(start 329.767946 -88.0872)
		(end 331.596746 -88.0872)
		(width 0.15494)
		(layer "In15.Cu")
		(net "SSD11_LED_R")
	)
	(segment
		(start 225.99904 -79.410306)
		(end 225.99904 -75.93076)
		(width 0.15494)
		(layer "In15.Cu")
		(net "SSD11_LED_R")
	)
	(segment
		(start 317.195454 -87.4014)
		(end 329.082146 -87.4014)
		(width 0.15494)
		(layer "In15.Cu")
		(net "SSD11_LED_R")
	)
	(segment
		(start 263.906 -79.9592)
		(end 268.299946 -79.9592)
		(width 0.15494)
		(layer "In15.Cu")
		(net "SSD11_LED_R")
	)
	(segment
		(start 352.47834 -93.14434)
		(end 352.513138 -93.14434)
		(width 0.15494)
		(layer "In15.Cu")
		(net "SSD11_LED_R")
	)
	(segment
		(start 331.596746 -88.0872)
		(end 332.231746 -87.4522)
		(width 0.15494)
		(layer "In15.Cu")
		(net "SSD11_LED_R")
	)
	(segment
		(start 308.5592 -86.3346)
		(end 316.128654 -86.3346)
		(width 0.15494)
		(layer "In15.Cu")
		(net "SSD11_LED_R")
	)
	(segment
		(start 347.372686 -92.66174)
		(end 347.616018 -92.66174)
		(width 0.15494)
		(layer "In15.Cu")
		(net "SSD11_LED_R")
	)
	(segment
		(start 223.006158 -80.611472)
		(end 223.506538 -80.111092)
		(width 0.15494)
		(layer "In15.Cu")
		(net "SSD11_LED_R")
	)
	(segment
		(start 260.5532 -79.121)
		(end 263.0678 -79.121)
		(width 0.15494)
		(layer "In15.Cu")
		(net "SSD11_LED_R")
	)
	(segment
		(start 348.6023 -93.648022)
		(end 351.974658 -93.648022)
		(width 0.15494)
		(layer "In15.Cu")
		(net "SSD11_LED_R")
	)
	(segment
		(start 238.937546 -76.0476)
		(end 243.5098 -76.0476)
		(width 0.15494)
		(layer "In15.Cu")
		(net "SSD11_LED_R")
	)
	(segment
		(start 339.305138 -89.1032)
		(end 343.814146 -89.1032)
		(width 0.15494)
		(layer "In15.Cu")
		(net "SSD11_LED_R")
	)
	(segment
		(start 337.654138 -87.4522)
		(end 339.305138 -89.1032)
		(width 0.15494)
		(layer "In15.Cu")
		(net "SSD11_LED_R")
	)
	(segment
		(start 244.1448 -76.6826)
		(end 252.882146 -76.6826)
		(width 0.15494)
		(layer "In15.Cu")
		(net "SSD11_LED_R")
	)
	(segment
		(start 306.085494 -25.55875)
		(end 307.223668 -25.55875)
		(width 0.13208)
		(layer "F.Cu")
		(net "SSD10_LED_ISO_N")
	)
	(segment
		(start 306.085494 -26.692098)
		(end 306.085494 -25.55875)
		(width 0.13208)
		(layer "F.Cu")
		(net "SSD10_LED_ISO_N")
	)
	(segment
		(start 307.570632 -25.211786)
		(end 308.473856 -25.211786)
		(width 0.13208)
		(layer "F.Cu")
		(net "SSD10_LED_ISO_N")
	)
	(segment
		(start 307.223668 -25.55875)
		(end 307.570632 -25.211786)
		(width 0.13208)
		(layer "F.Cu")
		(net "SSD10_LED_ISO_N")
	)
	(via
		(at 307.223668 -25.55875)
		(size 0.508)
		(drill 0.254)
		(layers "F.Cu" "B.Cu")
		(net "SSD10_LED_ISO_N")
	)
	(segment
		(start 353.196398 -204.750416)
		(end 353.196398 -204.134466)
		(width 0.13208)
		(layer "F.Cu")
		(net "FM_PFR_LED_BLUE_R")
	)
	(segment
		(start 229.437438 -61.799978)
		(end 227.592636 -61.799978)
		(width 0.13208)
		(layer "F.Cu")
		(net "FM_PFR_LED_BLUE_R")
	)
	(via
		(at 353.196398 -204.134466)
		(size 0.508)
		(drill 0.254)
		(layers "F.Cu" "B.Cu")
		(net "FM_PFR_LED_BLUE_R")
	)
	(via
		(at 366.532414 -92.366592)
		(size 0.508)
		(drill 0.254)
		(layers "F.Cu" "B.Cu")
		(net "FM_PFR_LED_BLUE_R")
	)
	(via
		(at 225.023172 -73.533)
		(size 0.508)
		(drill 0.254)
		(layers "F.Cu" "B.Cu")
		(net "FM_PFR_LED_BLUE_R")
	)
	(via
		(at 227.592636 -61.799978)
		(size 0.508)
		(drill 0.254)
		(layers "F.Cu" "B.Cu")
		(net "FM_PFR_LED_BLUE_R")
	)
	(segment
		(start 226.444048 -63.74511)
		(end 226.444048 -65.494662)
		(width 0.15494)
		(layer "In5.Cu")
		(net "FM_PFR_LED_BLUE_R")
	)
	(segment
		(start 225.673666 -68.778628)
		(end 225.673666 -72.882506)
		(width 0.15494)
		(layer "In5.Cu")
		(net "FM_PFR_LED_BLUE_R")
	)
	(segment
		(start 226.139502 -68.312792)
		(end 225.673666 -68.778628)
		(width 0.15494)
		(layer "In5.Cu")
		(net "FM_PFR_LED_BLUE_R")
	)
	(segment
		(start 226.444048 -65.494662)
		(end 226.139502 -65.799208)
		(width 0.15494)
		(layer "In5.Cu")
		(net "FM_PFR_LED_BLUE_R")
	)
	(segment
		(start 227.592636 -62.248542)
		(end 227.66782 -62.323726)
		(width 0.15494)
		(layer "In5.Cu")
		(net "FM_PFR_LED_BLUE_R")
	)
	(segment
		(start 225.673666 -72.882506)
		(end 225.023172 -73.533)
		(width 0.15494)
		(layer "In5.Cu")
		(net "FM_PFR_LED_BLUE_R")
	)
	(segment
		(start 227.66782 -62.323726)
		(end 227.66782 -62.521338)
		(width 0.15494)
		(layer "In5.Cu")
		(net "FM_PFR_LED_BLUE_R")
	)
	(segment
		(start 227.592636 -61.799978)
		(end 227.592636 -62.248542)
		(width 0.15494)
		(layer "In5.Cu")
		(net "FM_PFR_LED_BLUE_R")
	)
	(segment
		(start 227.66782 -62.521338)
		(end 226.444048 -63.74511)
		(width 0.15494)
		(layer "In5.Cu")
		(net "FM_PFR_LED_BLUE_R")
	)
	(segment
		(start 226.139502 -65.799208)
		(end 226.139502 -68.312792)
		(width 0.15494)
		(layer "In5.Cu")
		(net "FM_PFR_LED_BLUE_R")
	)
	(segment
		(start 367.8428 -92.8116)
		(end 367.8428 -102.489)
		(width 0.15494)
		(layer "In9.Cu")
		(net "FM_PFR_LED_BLUE_R")
	)
	(segment
		(start 353.4156 -123.213368)
		(end 352.425 -124.203968)
		(width 0.15494)
		(layer "In9.Cu")
		(net "FM_PFR_LED_BLUE_R")
	)
	(segment
		(start 352.679 -169.19194)
		(end 354.3046 -170.81754)
		(width 0.15494)
		(layer "In9.Cu")
		(net "FM_PFR_LED_BLUE_R")
	)
	(segment
		(start 354.1268 -153.9494)
		(end 354.1268 -156.6926)
		(width 0.15494)
		(layer "In9.Cu")
		(net "FM_PFR_LED_BLUE_R")
	)
	(segment
		(start 354.3046 -170.81754)
		(end 354.3046 -187.502546)
		(width 0.15494)
		(layer "In9.Cu")
		(net "FM_PFR_LED_BLUE_R")
	)
	(segment
		(start 366.532414 -92.366592)
		(end 367.397792 -92.366592)
		(width 0.15494)
		(layer "In9.Cu")
		(net "FM_PFR_LED_BLUE_R")
	)
	(segment
		(start 354.1268 -156.6926)
		(end 353.949 -156.8704)
		(width 0.15494)
		(layer "In9.Cu")
		(net "FM_PFR_LED_BLUE_R")
	)
	(segment
		(start 354.3046 -187.502546)
		(end 356.87 -190.067946)
		(width 0.15494)
		(layer "In9.Cu")
		(net "FM_PFR_LED_BLUE_R")
	)
	(segment
		(start 367.397792 -92.366592)
		(end 367.8428 -92.8116)
		(width 0.15494)
		(layer "In9.Cu")
		(net "FM_PFR_LED_BLUE_R")
	)
	(segment
		(start 353.4156 -116.9162)
		(end 353.4156 -123.213368)
		(width 0.15494)
		(layer "In9.Cu")
		(net "FM_PFR_LED_BLUE_R")
	)
	(segment
		(start 367.8428 -102.489)
		(end 353.4156 -116.9162)
		(width 0.15494)
		(layer "In9.Cu")
		(net "FM_PFR_LED_BLUE_R")
	)
	(segment
		(start 353.6188 -153.4414)
		(end 354.1268 -153.9494)
		(width 0.15494)
		(layer "In9.Cu")
		(net "FM_PFR_LED_BLUE_R")
	)
	(segment
		(start 353.6188 -149.4028)
		(end 353.6188 -153.4414)
		(width 0.15494)
		(layer "In9.Cu")
		(net "FM_PFR_LED_BLUE_R")
	)
	(segment
		(start 352.425 -148.209)
		(end 353.6188 -149.4028)
		(width 0.15494)
		(layer "In9.Cu")
		(net "FM_PFR_LED_BLUE_R")
	)
	(segment
		(start 356.87 -190.067946)
		(end 356.87 -197.516496)
		(width 0.15494)
		(layer "In9.Cu")
		(net "FM_PFR_LED_BLUE_R")
	)
	(segment
		(start 353.949 -159.7152)
		(end 352.679 -160.9852)
		(width 0.15494)
		(layer "In9.Cu")
		(net "FM_PFR_LED_BLUE_R")
	)
	(segment
		(start 353.196398 -201.190098)
		(end 353.196398 -204.134466)
		(width 0.15494)
		(layer "In9.Cu")
		(net "FM_PFR_LED_BLUE_R")
	)
	(segment
		(start 352.425 -124.203968)
		(end 352.425 -148.209)
		(width 0.15494)
		(layer "In9.Cu")
		(net "FM_PFR_LED_BLUE_R")
	)
	(segment
		(start 353.949 -156.8704)
		(end 353.949 -159.7152)
		(width 0.15494)
		(layer "In9.Cu")
		(net "FM_PFR_LED_BLUE_R")
	)
	(segment
		(start 356.87 -197.516496)
		(end 353.196398 -201.190098)
		(width 0.15494)
		(layer "In9.Cu")
		(net "FM_PFR_LED_BLUE_R")
	)
	(segment
		(start 352.679 -160.9852)
		(end 352.679 -169.19194)
		(width 0.15494)
		(layer "In9.Cu")
		(net "FM_PFR_LED_BLUE_R")
	)
	(segment
		(start 248.285254 -71.9328)
		(end 250.548902 -71.9328)
		(width 0.15494)
		(layer "In15.Cu")
		(net "FM_PFR_LED_BLUE_R")
	)
	(segment
		(start 250.548902 -71.9328)
		(end 251.371862 -72.75576)
		(width 0.15494)
		(layer "In15.Cu")
		(net "FM_PFR_LED_BLUE_R")
	)
	(segment
		(start 225.023172 -73.533)
		(end 226.584002 -71.97217)
		(width 0.15494)
		(layer "In15.Cu")
		(net "FM_PFR_LED_BLUE_R")
	)
	(segment
		(start 272.487898 -72.75576)
		(end 276.008338 -76.2762)
		(width 0.15494)
		(layer "In15.Cu")
		(net "FM_PFR_LED_BLUE_R")
	)
	(segment
		(start 362.9152 -90.227658)
		(end 364.229142 -91.5416)
		(width 0.15494)
		(layer "In15.Cu")
		(net "FM_PFR_LED_BLUE_R")
	)
	(segment
		(start 251.371862 -72.75576)
		(end 272.487898 -72.75576)
		(width 0.15494)
		(layer "In15.Cu")
		(net "FM_PFR_LED_BLUE_R")
	)
	(segment
		(start 355.675946 -79.2734)
		(end 362.9152 -86.512654)
		(width 0.15494)
		(layer "In15.Cu")
		(net "FM_PFR_LED_BLUE_R")
	)
	(segment
		(start 364.229142 -91.5416)
		(end 365.707422 -91.5416)
		(width 0.15494)
		(layer "In15.Cu")
		(net "FM_PFR_LED_BLUE_R")
	)
	(segment
		(start 247.193054 -73.025)
		(end 248.285254 -71.9328)
		(width 0.15494)
		(layer "In15.Cu")
		(net "FM_PFR_LED_BLUE_R")
	)
	(segment
		(start 344.093546 -76.1238)
		(end 347.243146 -79.2734)
		(width 0.15494)
		(layer "In15.Cu")
		(net "FM_PFR_LED_BLUE_R")
	)
	(segment
		(start 239.177576 -73.025)
		(end 247.193054 -73.025)
		(width 0.15494)
		(layer "In15.Cu")
		(net "FM_PFR_LED_BLUE_R")
	)
	(segment
		(start 365.707422 -91.5416)
		(end 366.532414 -92.366592)
		(width 0.15494)
		(layer "In15.Cu")
		(net "FM_PFR_LED_BLUE_R")
	)
	(segment
		(start 323.342254 -76.7842)
		(end 335.381854 -76.7842)
		(width 0.15494)
		(layer "In15.Cu")
		(net "FM_PFR_LED_BLUE_R")
	)
	(segment
		(start 347.243146 -79.2734)
		(end 355.675946 -79.2734)
		(width 0.15494)
		(layer "In15.Cu")
		(net "FM_PFR_LED_BLUE_R")
	)
	(segment
		(start 335.381854 -76.7842)
		(end 336.042254 -76.1238)
		(width 0.15494)
		(layer "In15.Cu")
		(net "FM_PFR_LED_BLUE_R")
	)
	(segment
		(start 238.124746 -71.97217)
		(end 239.177576 -73.025)
		(width 0.15494)
		(layer "In15.Cu")
		(net "FM_PFR_LED_BLUE_R")
	)
	(segment
		(start 311.775348 -74.918316)
		(end 321.47637 -74.918316)
		(width 0.15494)
		(layer "In15.Cu")
		(net "FM_PFR_LED_BLUE_R")
	)
	(segment
		(start 310.620664 -76.073)
		(end 311.775348 -74.918316)
		(width 0.15494)
		(layer "In15.Cu")
		(net "FM_PFR_LED_BLUE_R")
	)
	(segment
		(start 336.042254 -76.1238)
		(end 344.093546 -76.1238)
		(width 0.15494)
		(layer "In15.Cu")
		(net "FM_PFR_LED_BLUE_R")
	)
	(segment
		(start 298.1198 -76.073)
		(end 310.620664 -76.073)
		(width 0.15494)
		(layer "In15.Cu")
		(net "FM_PFR_LED_BLUE_R")
	)
	(segment
		(start 226.584002 -71.97217)
		(end 238.124746 -71.97217)
		(width 0.15494)
		(layer "In15.Cu")
		(net "FM_PFR_LED_BLUE_R")
	)
	(segment
		(start 321.47637 -74.918316)
		(end 323.342254 -76.7842)
		(width 0.15494)
		(layer "In15.Cu")
		(net "FM_PFR_LED_BLUE_R")
	)
	(segment
		(start 276.008338 -76.2762)
		(end 297.9166 -76.2762)
		(width 0.15494)
		(layer "In15.Cu")
		(net "FM_PFR_LED_BLUE_R")
	)
	(segment
		(start 297.9166 -76.2762)
		(end 298.1198 -76.073)
		(width 0.15494)
		(layer "In15.Cu")
		(net "FM_PFR_LED_BLUE_R")
	)
	(segment
		(start 362.9152 -86.512654)
		(end 362.9152 -90.227658)
		(width 0.15494)
		(layer "In15.Cu")
		(net "FM_PFR_LED_BLUE_R")
	)
	(segment
		(start 334.473804 -25.211786)
		(end 333.57058 -25.211786)
		(width 0.13208)
		(layer "F.Cu")
		(net "SSD11_LED_ISO_N")
	)
	(segment
		(start 333.57058 -25.211786)
		(end 333.223616 -25.55875)
		(width 0.13208)
		(layer "F.Cu")
		(net "SSD11_LED_ISO_N")
	)
	(segment
		(start 332.085442 -26.692098)
		(end 332.085442 -25.55875)
		(width 0.13208)
		(layer "F.Cu")
		(net "SSD11_LED_ISO_N")
	)
	(segment
		(start 333.223616 -25.55875)
		(end 332.085442 -25.55875)
		(width 0.13208)
		(layer "F.Cu")
		(net "SSD11_LED_ISO_N")
	)
	(via
		(at 333.223616 -25.55875)
		(size 0.508)
		(drill 0.254)
		(layers "F.Cu" "B.Cu")
		(net "SSD11_LED_ISO_N")
	)
	(segment
		(start 425.523914 -27.411934)
		(end 425.523914 -26.319734)
		(width 0.13208)
		(layer "F.Cu")
		(net "SSD14_LED_R")
	)
	(segment
		(start 223.006158 -83.659472)
		(end 222.390208 -83.659472)
		(width 0.13208)
		(layer "F.Cu")
		(net "SSD14_LED_R")
	)
	(segment
		(start 223.622108 -83.659472)
		(end 223.006158 -83.659472)
		(width 0.13208)
		(layer "F.Cu")
		(net "SSD14_LED_R")
	)
	(via
		(at 425.523914 -26.319734)
		(size 0.508)
		(drill 0.254)
		(layers "F.Cu" "B.Cu")
		(net "SSD14_LED_R")
	)
	(via
		(at 415.686494 -87.140288)
		(size 0.508)
		(drill 0.254)
		(layers "F.Cu" "B.Cu")
		(net "SSD14_LED_R")
	)
	(via
		(at 223.006158 -83.659472)
		(size 0.508)
		(drill 0.254)
		(layers "F.Cu" "B.Cu")
		(net "SSD14_LED_R")
	)
	(segment
		(start 429.421544 -76.161392)
		(end 431.02784 -76.161392)
		(width 0.15494)
		(layer "In5.Cu")
		(net "SSD14_LED_R")
	)
	(segment
		(start 438.429146 -68.760086)
		(end 438.429146 -45.035724)
		(width 0.15494)
		(layer "In5.Cu")
		(net "SSD14_LED_R")
	)
	(segment
		(start 425.537376 -32.143954)
		(end 425.537376 -31.256732)
		(width 0.15494)
		(layer "In5.Cu")
		(net "SSD14_LED_R")
	)
	(segment
		(start 431.02784 -76.161392)
		(end 438.429146 -68.760086)
		(width 0.15494)
		(layer "In5.Cu")
		(net "SSD14_LED_R")
	)
	(segment
		(start 425.537376 -31.256732)
		(end 426.60697 -30.187138)
		(width 0.15494)
		(layer "In5.Cu")
		(net "SSD14_LED_R")
	)
	(segment
		(start 418.442648 -87.140288)
		(end 429.421544 -76.161392)
		(width 0.15494)
		(layer "In5.Cu")
		(net "SSD14_LED_R")
	)
	(segment
		(start 426.60697 -27.40279)
		(end 425.523914 -26.319734)
		(width 0.15494)
		(layer "In5.Cu")
		(net "SSD14_LED_R")
	)
	(segment
		(start 438.429146 -45.035724)
		(end 425.537376 -32.143954)
		(width 0.15494)
		(layer "In5.Cu")
		(net "SSD14_LED_R")
	)
	(segment
		(start 426.60697 -30.187138)
		(end 426.60697 -27.40279)
		(width 0.15494)
		(layer "In5.Cu")
		(net "SSD14_LED_R")
	)
	(segment
		(start 415.686494 -87.140288)
		(end 418.442648 -87.140288)
		(width 0.15494)
		(layer "In5.Cu")
		(net "SSD14_LED_R")
	)
	(segment
		(start 333.8576 -90.1446)
		(end 336.1436 -92.4306)
		(width 0.15494)
		(layer "In15.Cu")
		(net "SSD14_LED_R")
	)
	(segment
		(start 245.25986 -87.22106)
		(end 248.613422 -90.574622)
		(width 0.15494)
		(layer "In15.Cu")
		(net "SSD14_LED_R")
	)
	(segment
		(start 342.927432 -92.4306)
		(end 346.34551 -95.848678)
		(width 0.15494)
		(layer "In15.Cu")
		(net "SSD14_LED_R")
	)
	(segment
		(start 412.543244 -87.949786)
		(end 413.352742 -87.140288)
		(width 0.15494)
		(layer "In15.Cu")
		(net "SSD14_LED_R")
	)
	(segment
		(start 314.333636 -88.6714)
		(end 327.0758 -88.6714)
		(width 0.15494)
		(layer "In15.Cu")
		(net "SSD14_LED_R")
	)
	(segment
		(start 227.07346 -81.644744)
		(end 227.07346 -77.142086)
		(width 0.15494)
		(layer "In15.Cu")
		(net "SSD14_LED_R")
	)
	(segment
		(start 243.0526 -77.1906)
		(end 245.25986 -79.39786)
		(width 0.15494)
		(layer "In15.Cu")
		(net "SSD14_LED_R")
	)
	(segment
		(start 328.549 -90.1446)
		(end 333.8576 -90.1446)
		(width 0.15494)
		(layer "In15.Cu")
		(net "SSD14_LED_R")
	)
	(segment
		(start 413.352742 -87.140288)
		(end 415.686494 -87.140288)
		(width 0.15494)
		(layer "In15.Cu")
		(net "SSD14_LED_R")
	)
	(segment
		(start 236.5502 -75.3872)
		(end 238.3536 -77.1906)
		(width 0.15494)
		(layer "In15.Cu")
		(net "SSD14_LED_R")
	)
	(segment
		(start 275.209254 -89.027)
		(end 276.377654 -87.8586)
		(width 0.15494)
		(layer "In15.Cu")
		(net "SSD14_LED_R")
	)
	(segment
		(start 312.099452 -88.9)
		(end 314.105036 -88.9)
		(width 0.15494)
		(layer "In15.Cu")
		(net "SSD14_LED_R")
	)
	(segment
		(start 391.592054 -92.329)
		(end 393.531852 -90.389202)
		(width 0.15494)
		(layer "In15.Cu")
		(net "SSD14_LED_R")
	)
	(segment
		(start 266.962636 -88.1126)
		(end 271.678654 -88.1126)
		(width 0.15494)
		(layer "In15.Cu")
		(net "SSD14_LED_R")
	)
	(segment
		(start 346.34551 -95.848678)
		(end 360.5022 -95.848678)
		(width 0.15494)
		(layer "In15.Cu")
		(net "SSD14_LED_R")
	)
	(segment
		(start 362.697522 -98.044)
		(end 367.690146 -98.044)
		(width 0.15494)
		(layer "In15.Cu")
		(net "SSD14_LED_R")
	)
	(segment
		(start 223.006158 -83.659472)
		(end 223.53143 -83.1342)
		(width 0.15494)
		(layer "In15.Cu")
		(net "SSD14_LED_R")
	)
	(segment
		(start 282.204922 -88.555322)
		(end 311.754774 -88.555322)
		(width 0.15494)
		(layer "In15.Cu")
		(net "SSD14_LED_R")
	)
	(segment
		(start 271.678654 -88.1126)
		(end 272.593054 -89.027)
		(width 0.15494)
		(layer "In15.Cu")
		(net "SSD14_LED_R")
	)
	(segment
		(start 254.865124 -90.574622)
		(end 255.599946 -89.8398)
		(width 0.15494)
		(layer "In15.Cu")
		(net "SSD14_LED_R")
	)
	(segment
		(start 327.0758 -88.6714)
		(end 328.549 -90.1446)
		(width 0.15494)
		(layer "In15.Cu")
		(net "SSD14_LED_R")
	)
	(segment
		(start 227.07346 -77.142086)
		(end 228.828346 -75.3872)
		(width 0.15494)
		(layer "In15.Cu")
		(net "SSD14_LED_R")
	)
	(segment
		(start 402.041614 -87.949786)
		(end 412.543244 -87.949786)
		(width 0.15494)
		(layer "In15.Cu")
		(net "SSD14_LED_R")
	)
	(segment
		(start 276.377654 -87.8586)
		(end 281.5082 -87.8586)
		(width 0.15494)
		(layer "In15.Cu")
		(net "SSD14_LED_R")
	)
	(segment
		(start 369.087146 -96.647)
		(end 379.5268 -96.647)
		(width 0.15494)
		(layer "In15.Cu")
		(net "SSD14_LED_R")
	)
	(segment
		(start 245.25986 -79.39786)
		(end 245.25986 -87.22106)
		(width 0.15494)
		(layer "In15.Cu")
		(net "SSD14_LED_R")
	)
	(segment
		(start 272.593054 -89.027)
		(end 275.209254 -89.027)
		(width 0.15494)
		(layer "In15.Cu")
		(net "SSD14_LED_R")
	)
	(segment
		(start 248.613422 -90.574622)
		(end 254.865124 -90.574622)
		(width 0.15494)
		(layer "In15.Cu")
		(net "SSD14_LED_R")
	)
	(segment
		(start 311.754774 -88.555322)
		(end 312.099452 -88.9)
		(width 0.15494)
		(layer "In15.Cu")
		(net "SSD14_LED_R")
	)
	(segment
		(start 367.690146 -98.044)
		(end 369.087146 -96.647)
		(width 0.15494)
		(layer "In15.Cu")
		(net "SSD14_LED_R")
	)
	(segment
		(start 238.3536 -77.1906)
		(end 243.0526 -77.1906)
		(width 0.15494)
		(layer "In15.Cu")
		(net "SSD14_LED_R")
	)
	(segment
		(start 223.53143 -83.1342)
		(end 225.584004 -83.1342)
		(width 0.15494)
		(layer "In15.Cu")
		(net "SSD14_LED_R")
	)
	(segment
		(start 393.531852 -90.389202)
		(end 399.602198 -90.389202)
		(width 0.15494)
		(layer "In15.Cu")
		(net "SSD14_LED_R")
	)
	(segment
		(start 265.235436 -89.8398)
		(end 266.962636 -88.1126)
		(width 0.15494)
		(layer "In15.Cu")
		(net "SSD14_LED_R")
	)
	(segment
		(start 379.5268 -96.647)
		(end 383.8448 -92.329)
		(width 0.15494)
		(layer "In15.Cu")
		(net "SSD14_LED_R")
	)
	(segment
		(start 228.828346 -75.3872)
		(end 236.5502 -75.3872)
		(width 0.15494)
		(layer "In15.Cu")
		(net "SSD14_LED_R")
	)
	(segment
		(start 399.602198 -90.389202)
		(end 402.041614 -87.949786)
		(width 0.15494)
		(layer "In15.Cu")
		(net "SSD14_LED_R")
	)
	(segment
		(start 225.584004 -83.1342)
		(end 227.07346 -81.644744)
		(width 0.15494)
		(layer "In15.Cu")
		(net "SSD14_LED_R")
	)
	(segment
		(start 360.5022 -95.848678)
		(end 362.697522 -98.044)
		(width 0.15494)
		(layer "In15.Cu")
		(net "SSD14_LED_R")
	)
	(segment
		(start 314.105036 -88.9)
		(end 314.333636 -88.6714)
		(width 0.15494)
		(layer "In15.Cu")
		(net "SSD14_LED_R")
	)
	(segment
		(start 281.5082 -87.8586)
		(end 282.204922 -88.555322)
		(width 0.15494)
		(layer "In15.Cu")
		(net "SSD14_LED_R")
	)
	(segment
		(start 336.1436 -92.4306)
		(end 342.927432 -92.4306)
		(width 0.15494)
		(layer "In15.Cu")
		(net "SSD14_LED_R")
	)
	(segment
		(start 383.8448 -92.329)
		(end 391.592054 -92.329)
		(width 0.15494)
		(layer "In15.Cu")
		(net "SSD14_LED_R")
	)
	(segment
		(start 255.599946 -89.8398)
		(end 265.235436 -89.8398)
		(width 0.15494)
		(layer "In15.Cu")
		(net "SSD14_LED_R")
	)
	(segment
		(start 321.880738 -24.189944)
		(end 320.864738 -24.189944)
		(width 0.13208)
		(layer "F.Cu")
		(net "SSD11_LED_ISO_R_N")
	)
	(segment
		(start 332.085442 -24.75865)
		(end 331.450442 -24.75865)
		(width 0.13208)
		(layer "F.Cu")
		(net "SSD11_LED_ISO_R_N")
	)
	(via
		(at 321.880738 -24.189944)
		(size 0.508)
		(drill 0.254)
		(layers "F.Cu" "B.Cu")
		(net "SSD11_LED_ISO_R_N")
	)
	(via
		(at 331.450442 -24.75865)
		(size 0.508)
		(drill 0.254)
		(layers "F.Cu" "B.Cu")
		(net "SSD11_LED_ISO_R_N")
	)
	(segment
		(start 327.046082 -24.115268)
		(end 327.400158 -24.364188)
		(width 0.15494)
		(layer "In5.Cu")
		(net "SSD11_LED_ISO_R_N")
	)
	(segment
		(start 321.880738 -24.189944)
		(end 323.257672 -24.189944)
		(width 0.15494)
		(layer "In5.Cu")
		(net "SSD11_LED_ISO_R_N")
	)
	(segment
		(start 325.780654 -23.486364)
		(end 326.409558 -24.115268)
		(width 0.15494)
		(layer "In5.Cu")
		(net "SSD11_LED_ISO_R_N")
	)
	(segment
		(start 323.257672 -24.189944)
		(end 323.961252 -23.486364)
		(width 0.15494)
		(layer "In5.Cu")
		(net "SSD11_LED_ISO_R_N")
	)
	(segment
		(start 326.409558 -24.115268)
		(end 327.046082 -24.115268)
		(width 0.15494)
		(layer "In5.Cu")
		(net "SSD11_LED_ISO_R_N")
	)
	(segment
		(start 323.961252 -23.486364)
		(end 325.780654 -23.486364)
		(width 0.15494)
		(layer "In5.Cu")
		(net "SSD11_LED_ISO_R_N")
	)
	(segment
		(start 327.400158 -24.364188)
		(end 331.05598 -24.364188)
		(width 0.15494)
		(layer "In5.Cu")
		(net "SSD11_LED_ISO_R_N")
	)
	(segment
		(start 331.05598 -24.364188)
		(end 331.450442 -24.75865)
		(width 0.15494)
		(layer "In5.Cu")
		(net "SSD11_LED_ISO_R_N")
	)
	(segment
		(start 223.006158 -84.675472)
		(end 222.390208 -84.675472)
		(width 0.13208)
		(layer "F.Cu")
		(net "SSD15_LED_R")
	)
	(segment
		(start 223.622108 -84.675472)
		(end 223.006158 -84.675472)
		(width 0.13208)
		(layer "F.Cu")
		(net "SSD15_LED_R")
	)
	(segment
		(start 451.523862 -27.411934)
		(end 451.523862 -26.319734)
		(width 0.13208)
		(layer "F.Cu")
		(net "SSD15_LED_R")
	)
	(via
		(at 451.523862 -26.319734)
		(size 0.508)
		(drill 0.254)
		(layers "F.Cu" "B.Cu")
		(net "SSD15_LED_R")
	)
	(via
		(at 429.560228 -90.682064)
		(size 0.508)
		(drill 0.254)
		(layers "F.Cu" "B.Cu")
		(net "SSD15_LED_R")
	)
	(via
		(at 223.006158 -84.675472)
		(size 0.508)
		(drill 0.254)
		(layers "F.Cu" "B.Cu")
		(net "SSD15_LED_R")
	)
	(segment
		(start 451.537324 -31.249366)
		(end 452.6026 -30.18409)
		(width 0.15494)
		(layer "In5.Cu")
		(net "SSD15_LED_R")
	)
	(segment
		(start 452.6026 -27.398472)
		(end 451.523862 -26.319734)
		(width 0.15494)
		(layer "In5.Cu")
		(net "SSD15_LED_R")
	)
	(segment
		(start 457.42225 -71.247254)
		(end 457.42225 -37.914072)
		(width 0.15494)
		(layer "In5.Cu")
		(net "SSD15_LED_R")
	)
	(segment
		(start 457.42225 -37.914072)
		(end 451.537324 -32.029146)
		(width 0.15494)
		(layer "In5.Cu")
		(net "SSD15_LED_R")
	)
	(segment
		(start 439.054494 -78.68031)
		(end 457.113894 -78.68031)
		(width 0.15494)
		(layer "In5.Cu")
		(net "SSD15_LED_R")
	)
	(segment
		(start 451.537324 -32.029146)
		(end 451.537324 -31.249366)
		(width 0.15494)
		(layer "In5.Cu")
		(net "SSD15_LED_R")
	)
	(segment
		(start 457.113894 -78.68031)
		(end 459.411832 -76.382372)
		(width 0.15494)
		(layer "In5.Cu")
		(net "SSD15_LED_R")
	)
	(segment
		(start 459.411832 -76.382372)
		(end 459.411832 -73.236836)
		(width 0.15494)
		(layer "In5.Cu")
		(net "SSD15_LED_R")
	)
	(segment
		(start 459.411832 -73.236836)
		(end 457.42225 -71.247254)
		(width 0.15494)
		(layer "In5.Cu")
		(net "SSD15_LED_R")
	)
	(segment
		(start 429.560228 -90.682064)
		(end 432.698398 -87.543894)
		(width 0.15494)
		(layer "In5.Cu")
		(net "SSD15_LED_R")
	)
	(segment
		(start 432.698398 -85.036406)
		(end 439.054494 -78.68031)
		(width 0.15494)
		(layer "In5.Cu")
		(net "SSD15_LED_R")
	)
	(segment
		(start 432.698398 -87.543894)
		(end 432.698398 -85.036406)
		(width 0.15494)
		(layer "In5.Cu")
		(net "SSD15_LED_R")
	)
	(segment
		(start 452.6026 -30.18409)
		(end 452.6026 -27.398472)
		(width 0.15494)
		(layer "In5.Cu")
		(net "SSD15_LED_R")
	)
	(segment
		(start 415.239454 -88.348312)
		(end 424.98772 -88.348312)
		(width 0.15494)
		(layer "In15.Cu")
		(net "SSD15_LED_R")
	)
	(segment
		(start 399.821146 -90.7796)
		(end 402.29282 -88.307926)
		(width 0.15494)
		(layer "In15.Cu")
		(net "SSD15_LED_R")
	)
	(segment
		(start 244.8306 -79.629254)
		(end 244.8306 -87.376254)
		(width 0.15494)
		(layer "In15.Cu")
		(net "SSD15_LED_R")
	)
	(segment
		(start 225.9076 -84.1756)
		(end 227.4316 -82.6516)
		(width 0.15494)
		(layer "In15.Cu")
		(net "SSD15_LED_R")
	)
	(segment
		(start 255.143 -91.0082)
		(end 255.845564 -90.305636)
		(width 0.15494)
		(layer "In15.Cu")
		(net "SSD15_LED_R")
	)
	(segment
		(start 346.056458 -96.2406)
		(end 360.0196 -96.2406)
		(width 0.15494)
		(layer "In15.Cu")
		(net "SSD15_LED_R")
	)
	(segment
		(start 414.485582 -87.59444)
		(end 415.239454 -88.348312)
		(width 0.15494)
		(layer "In15.Cu")
		(net "SSD15_LED_R")
	)
	(segment
		(start 227.4316 -82.6516)
		(end 227.4316 -77.4954)
		(width 0.15494)
		(layer "In15.Cu")
		(net "SSD15_LED_R")
	)
	(segment
		(start 391.6934 -92.7608)
		(end 393.6746 -90.7796)
		(width 0.15494)
		(layer "In15.Cu")
		(net "SSD15_LED_R")
	)
	(segment
		(start 393.6746 -90.7796)
		(end 399.821146 -90.7796)
		(width 0.15494)
		(layer "In15.Cu")
		(net "SSD15_LED_R")
	)
	(segment
		(start 329.082654 -91.2368)
		(end 330.9874 -91.2368)
		(width 0.15494)
		(layer "In15.Cu")
		(net "SSD15_LED_R")
	)
	(segment
		(start 255.845564 -90.305636)
		(end 265.54811 -90.305636)
		(width 0.15494)
		(layer "In15.Cu")
		(net "SSD15_LED_R")
	)
	(segment
		(start 379.679454 -97.1296)
		(end 384.048254 -92.7608)
		(width 0.15494)
		(layer "In15.Cu")
		(net "SSD15_LED_R")
	)
	(segment
		(start 367.8428 -98.4504)
		(end 369.1636 -97.1296)
		(width 0.15494)
		(layer "In15.Cu")
		(net "SSD15_LED_R")
	)
	(segment
		(start 330.9874 -91.2368)
		(end 331.089 -91.1352)
		(width 0.15494)
		(layer "In15.Cu")
		(net "SSD15_LED_R")
	)
	(segment
		(start 311.912254 -89.281)
		(end 314.273946 -89.281)
		(width 0.15494)
		(layer "In15.Cu")
		(net "SSD15_LED_R")
	)
	(segment
		(start 227.4316 -77.4954)
		(end 229.1334 -75.7936)
		(width 0.15494)
		(layer "In15.Cu")
		(net "SSD15_LED_R")
	)
	(segment
		(start 242.772946 -77.5716)
		(end 244.8306 -79.629254)
		(width 0.15494)
		(layer "In15.Cu")
		(net "SSD15_LED_R")
	)
	(segment
		(start 362.2294 -98.4504)
		(end 367.8428 -98.4504)
		(width 0.15494)
		(layer "In15.Cu")
		(net "SSD15_LED_R")
	)
	(segment
		(start 265.54811 -90.305636)
		(end 267.360146 -88.4936)
		(width 0.15494)
		(layer "In15.Cu")
		(net "SSD15_LED_R")
	)
	(segment
		(start 412.810706 -88.307926)
		(end 413.524192 -87.59444)
		(width 0.15494)
		(layer "In15.Cu")
		(net "SSD15_LED_R")
	)
	(segment
		(start 276.5298 -88.2904)
		(end 281.330654 -88.2904)
		(width 0.15494)
		(layer "In15.Cu")
		(net "SSD15_LED_R")
	)
	(segment
		(start 314.502546 -89.0524)
		(end 326.898254 -89.0524)
		(width 0.15494)
		(layer "In15.Cu")
		(net "SSD15_LED_R")
	)
	(segment
		(start 248.462546 -91.0082)
		(end 255.143 -91.0082)
		(width 0.15494)
		(layer "In15.Cu")
		(net "SSD15_LED_R")
	)
	(segment
		(start 402.29282 -88.307926)
		(end 412.810706 -88.307926)
		(width 0.15494)
		(layer "In15.Cu")
		(net "SSD15_LED_R")
	)
	(segment
		(start 272.3134 -89.4334)
		(end 275.3868 -89.4334)
		(width 0.15494)
		(layer "In15.Cu")
		(net "SSD15_LED_R")
	)
	(segment
		(start 334.289654 -91.1352)
		(end 335.960974 -92.80652)
		(width 0.15494)
		(layer "In15.Cu")
		(net "SSD15_LED_R")
	)
	(segment
		(start 427.321472 -90.682064)
		(end 429.560228 -90.682064)
		(width 0.15494)
		(layer "In15.Cu")
		(net "SSD15_LED_R")
	)
	(segment
		(start 244.8306 -87.376254)
		(end 248.462546 -91.0082)
		(width 0.15494)
		(layer "In15.Cu")
		(net "SSD15_LED_R")
	)
	(segment
		(start 281.991054 -88.9508)
		(end 311.582054 -88.9508)
		(width 0.15494)
		(layer "In15.Cu")
		(net "SSD15_LED_R")
	)
	(segment
		(start 229.1334 -75.7936)
		(end 236.346746 -75.7936)
		(width 0.15494)
		(layer "In15.Cu")
		(net "SSD15_LED_R")
	)
	(segment
		(start 413.524192 -87.59444)
		(end 414.485582 -87.59444)
		(width 0.15494)
		(layer "In15.Cu")
		(net "SSD15_LED_R")
	)
	(segment
		(start 271.3736 -88.4936)
		(end 272.3134 -89.4334)
		(width 0.15494)
		(layer "In15.Cu")
		(net "SSD15_LED_R")
	)
	(segment
		(start 267.360146 -88.4936)
		(end 271.3736 -88.4936)
		(width 0.15494)
		(layer "In15.Cu")
		(net "SSD15_LED_R")
	)
	(segment
		(start 326.898254 -89.0524)
		(end 329.082654 -91.2368)
		(width 0.15494)
		(layer "In15.Cu")
		(net "SSD15_LED_R")
	)
	(segment
		(start 223.006158 -84.675472)
		(end 223.50603 -84.1756)
		(width 0.15494)
		(layer "In15.Cu")
		(net "SSD15_LED_R")
	)
	(segment
		(start 311.582054 -88.9508)
		(end 311.912254 -89.281)
		(width 0.15494)
		(layer "In15.Cu")
		(net "SSD15_LED_R")
	)
	(segment
		(start 342.622378 -92.80652)
		(end 346.056458 -96.2406)
		(width 0.15494)
		(layer "In15.Cu")
		(net "SSD15_LED_R")
	)
	(segment
		(start 223.50603 -84.1756)
		(end 225.9076 -84.1756)
		(width 0.15494)
		(layer "In15.Cu")
		(net "SSD15_LED_R")
	)
	(segment
		(start 369.1636 -97.1296)
		(end 379.679454 -97.1296)
		(width 0.15494)
		(layer "In15.Cu")
		(net "SSD15_LED_R")
	)
	(segment
		(start 275.3868 -89.4334)
		(end 276.5298 -88.2904)
		(width 0.15494)
		(layer "In15.Cu")
		(net "SSD15_LED_R")
	)
	(segment
		(start 281.330654 -88.2904)
		(end 281.991054 -88.9508)
		(width 0.15494)
		(layer "In15.Cu")
		(net "SSD15_LED_R")
	)
	(segment
		(start 335.960974 -92.80652)
		(end 342.622378 -92.80652)
		(width 0.15494)
		(layer "In15.Cu")
		(net "SSD15_LED_R")
	)
	(segment
		(start 238.124746 -77.5716)
		(end 242.772946 -77.5716)
		(width 0.15494)
		(layer "In15.Cu")
		(net "SSD15_LED_R")
	)
	(segment
		(start 424.98772 -88.348312)
		(end 427.321472 -90.682064)
		(width 0.15494)
		(layer "In15.Cu")
		(net "SSD15_LED_R")
	)
	(segment
		(start 360.0196 -96.2406)
		(end 362.2294 -98.4504)
		(width 0.15494)
		(layer "In15.Cu")
		(net "SSD15_LED_R")
	)
	(segment
		(start 384.048254 -92.7608)
		(end 391.6934 -92.7608)
		(width 0.15494)
		(layer "In15.Cu")
		(net "SSD15_LED_R")
	)
	(segment
		(start 331.089 -91.1352)
		(end 334.289654 -91.1352)
		(width 0.15494)
		(layer "In15.Cu")
		(net "SSD15_LED_R")
	)
	(segment
		(start 236.346746 -75.7936)
		(end 238.124746 -77.5716)
		(width 0.15494)
		(layer "In15.Cu")
		(net "SSD15_LED_R")
	)
	(segment
		(start 314.273946 -89.281)
		(end 314.502546 -89.0524)
		(width 0.15494)
		(layer "In15.Cu")
		(net "SSD15_LED_R")
	)
	(segment
		(start 295.88079 -24.189944)
		(end 294.86479 -24.189944)
		(width 0.13208)
		(layer "F.Cu")
		(net "SSD10_LED_ISO_R_N")
	)
	(segment
		(start 306.085494 -24.75865)
		(end 305.450494 -24.75865)
		(width 0.13208)
		(layer "F.Cu")
		(net "SSD10_LED_ISO_R_N")
	)
	(via
		(at 305.450494 -24.75865)
		(size 0.508)
		(drill 0.254)
		(layers "F.Cu" "B.Cu")
		(net "SSD10_LED_ISO_R_N")
	)
	(via
		(at 295.88079 -24.189944)
		(size 0.508)
		(drill 0.254)
		(layers "F.Cu" "B.Cu")
		(net "SSD10_LED_ISO_R_N")
	)
	(segment
		(start 299.727366 -23.486364)
		(end 300.35627 -24.115268)
		(width 0.15494)
		(layer "In5.Cu")
		(net "SSD10_LED_ISO_R_N")
	)
	(segment
		(start 300.35627 -24.115268)
		(end 301.046134 -24.115268)
		(width 0.15494)
		(layer "In5.Cu")
		(net "SSD10_LED_ISO_R_N")
	)
	(segment
		(start 295.88079 -24.189944)
		(end 297.257724 -24.189944)
		(width 0.15494)
		(layer "In5.Cu")
		(net "SSD10_LED_ISO_R_N")
	)
	(segment
		(start 297.961304 -23.486364)
		(end 299.727366 -23.486364)
		(width 0.15494)
		(layer "In5.Cu")
		(net "SSD10_LED_ISO_R_N")
	)
	(segment
		(start 305.056032 -24.364188)
		(end 305.450494 -24.75865)
		(width 0.15494)
		(layer "In5.Cu")
		(net "SSD10_LED_ISO_R_N")
	)
	(segment
		(start 301.40021 -24.364188)
		(end 305.056032 -24.364188)
		(width 0.15494)
		(layer "In5.Cu")
		(net "SSD10_LED_ISO_R_N")
	)
	(segment
		(start 301.046134 -24.115268)
		(end 301.40021 -24.364188)
		(width 0.15494)
		(layer "In5.Cu")
		(net "SSD10_LED_ISO_R_N")
	)
	(segment
		(start 297.257724 -24.189944)
		(end 297.961304 -23.486364)
		(width 0.15494)
		(layer "In5.Cu")
		(net "SSD10_LED_ISO_R_N")
	)
	(segment
		(start 229.437438 -61.20003)
		(end 226.984814 -61.20003)
		(width 0.13208)
		(layer "F.Cu")
		(net "FM_PFR_LED_AMBER_R")
	)
	(segment
		(start 352.12909 -204.756766)
		(end 352.12909 -204.140816)
		(width 0.13208)
		(layer "F.Cu")
		(net "FM_PFR_LED_AMBER_R")
	)
	(segment
		(start 226.984814 -61.20003)
		(end 226.411282 -61.773562)
		(width 0.13208)
		(layer "F.Cu")
		(net "FM_PFR_LED_AMBER_R")
	)
	(via
		(at 352.12909 -204.140816)
		(size 0.508)
		(drill 0.254)
		(layers "F.Cu" "B.Cu")
		(net "FM_PFR_LED_AMBER_R")
	)
	(via
		(at 367.260124 -92.97162)
		(size 0.508)
		(drill 0.254)
		(layers "F.Cu" "B.Cu")
		(net "FM_PFR_LED_AMBER_R")
	)
	(via
		(at 225.058986 -72.299576)
		(size 0.508)
		(drill 0.254)
		(layers "F.Cu" "B.Cu")
		(net "FM_PFR_LED_AMBER_R")
	)
	(via
		(at 226.411282 -61.773562)
		(size 0.508)
		(drill 0.254)
		(layers "F.Cu" "B.Cu")
		(net "FM_PFR_LED_AMBER_R")
	)
	(segment
		(start 226.486466 -63.147702)
		(end 226.059746 -63.574422)
		(width 0.15494)
		(layer "In5.Cu")
		(net "FM_PFR_LED_AMBER_R")
	)
	(segment
		(start 226.411282 -62.222126)
		(end 226.486466 -62.29731)
		(width 0.15494)
		(layer "In5.Cu")
		(net "FM_PFR_LED_AMBER_R")
	)
	(segment
		(start 225.6282 -66.647822)
		(end 224.305114 -67.970908)
		(width 0.15494)
		(layer "In5.Cu")
		(net "FM_PFR_LED_AMBER_R")
	)
	(segment
		(start 226.059746 -63.574422)
		(end 226.059746 -65.253616)
		(width 0.15494)
		(layer "In5.Cu")
		(net "FM_PFR_LED_AMBER_R")
	)
	(segment
		(start 226.059746 -65.253616)
		(end 225.6282 -65.685162)
		(width 0.15494)
		(layer "In5.Cu")
		(net "FM_PFR_LED_AMBER_R")
	)
	(segment
		(start 225.6282 -65.685162)
		(end 225.6282 -66.647822)
		(width 0.15494)
		(layer "In5.Cu")
		(net "FM_PFR_LED_AMBER_R")
	)
	(segment
		(start 226.411282 -61.773562)
		(end 226.411282 -62.222126)
		(width 0.15494)
		(layer "In5.Cu")
		(net "FM_PFR_LED_AMBER_R")
	)
	(segment
		(start 226.486466 -62.29731)
		(end 226.486466 -63.147702)
		(width 0.15494)
		(layer "In5.Cu")
		(net "FM_PFR_LED_AMBER_R")
	)
	(segment
		(start 224.305114 -67.970908)
		(end 224.305114 -71.545704)
		(width 0.15494)
		(layer "In5.Cu")
		(net "FM_PFR_LED_AMBER_R")
	)
	(segment
		(start 224.305114 -71.545704)
		(end 225.058986 -72.299576)
		(width 0.15494)
		(layer "In5.Cu")
		(net "FM_PFR_LED_AMBER_R")
	)
	(segment
		(start 352.12909 -201.409046)
		(end 352.12909 -204.140816)
		(width 0.15494)
		(layer "In9.Cu")
		(net "FM_PFR_LED_AMBER_R")
	)
	(segment
		(start 367.260124 -92.97162)
		(end 367.260124 -102.51059)
		(width 0.15494)
		(layer "In9.Cu")
		(net "FM_PFR_LED_AMBER_R")
	)
	(segment
		(start 353.7458 -154.076654)
		(end 353.7458 -156.5402)
		(width 0.15494)
		(layer "In9.Cu")
		(net "FM_PFR_LED_AMBER_R")
	)
	(segment
		(start 356.4128 -190.2714)
		(end 356.4128 -197.071742)
		(width 0.15494)
		(layer "In9.Cu")
		(net "FM_PFR_LED_AMBER_R")
	)
	(segment
		(start 353.0346 -116.736114)
		(end 353.0346 -122.935746)
		(width 0.15494)
		(layer "In9.Cu")
		(net "FM_PFR_LED_AMBER_R")
	)
	(segment
		(start 353.0346 -122.935746)
		(end 352.053398 -123.916948)
		(width 0.15494)
		(layer "In9.Cu")
		(net "FM_PFR_LED_AMBER_R")
	)
	(segment
		(start 352.7552 -158.2928)
		(end 352.7552 -160.1216)
		(width 0.15494)
		(layer "In9.Cu")
		(net "FM_PFR_LED_AMBER_R")
	)
	(segment
		(start 353.8728 -187.7314)
		(end 356.4128 -190.2714)
		(width 0.15494)
		(layer "In9.Cu")
		(net "FM_PFR_LED_AMBER_R")
	)
	(segment
		(start 352.053398 -123.916948)
		(end 352.053398 -148.523452)
		(width 0.15494)
		(layer "In9.Cu")
		(net "FM_PFR_LED_AMBER_R")
	)
	(segment
		(start 352.7552 -160.1216)
		(end 352.2726 -160.6042)
		(width 0.15494)
		(layer "In9.Cu")
		(net "FM_PFR_LED_AMBER_R")
	)
	(segment
		(start 353.2632 -157.0228)
		(end 353.2632 -157.7848)
		(width 0.15494)
		(layer "In9.Cu")
		(net "FM_PFR_LED_AMBER_R")
	)
	(segment
		(start 353.7458 -156.5402)
		(end 353.2632 -157.0228)
		(width 0.15494)
		(layer "In9.Cu")
		(net "FM_PFR_LED_AMBER_R")
	)
	(segment
		(start 352.2726 -169.443146)
		(end 353.8728 -171.043346)
		(width 0.15494)
		(layer "In9.Cu")
		(net "FM_PFR_LED_AMBER_R")
	)
	(segment
		(start 367.260124 -102.51059)
		(end 353.0346 -116.736114)
		(width 0.15494)
		(layer "In9.Cu")
		(net "FM_PFR_LED_AMBER_R")
	)
	(segment
		(start 353.2632 -157.7848)
		(end 352.7552 -158.2928)
		(width 0.15494)
		(layer "In9.Cu")
		(net "FM_PFR_LED_AMBER_R")
	)
	(segment
		(start 356.4128 -197.071742)
		(end 352.12909 -201.409046)
		(width 0.15494)
		(layer "In9.Cu")
		(net "FM_PFR_LED_AMBER_R")
	)
	(segment
		(start 352.053398 -148.523452)
		(end 353.2378 -149.707854)
		(width 0.15494)
		(layer "In9.Cu")
		(net "FM_PFR_LED_AMBER_R")
	)
	(segment
		(start 353.8728 -171.043346)
		(end 353.8728 -187.7314)
		(width 0.15494)
		(layer "In9.Cu")
		(net "FM_PFR_LED_AMBER_R")
	)
	(segment
		(start 353.2378 -153.568654)
		(end 353.7458 -154.076654)
		(width 0.15494)
		(layer "In9.Cu")
		(net "FM_PFR_LED_AMBER_R")
	)
	(segment
		(start 352.2726 -160.6042)
		(end 352.2726 -169.443146)
		(width 0.15494)
		(layer "In9.Cu")
		(net "FM_PFR_LED_AMBER_R")
	)
	(segment
		(start 353.2378 -149.707854)
		(end 353.2378 -153.568654)
		(width 0.15494)
		(layer "In9.Cu")
		(net "FM_PFR_LED_AMBER_R")
	)
	(segment
		(start 311.60085 -74.504296)
		(end 321.722496 -74.504296)
		(width 0.15494)
		(layer "In15.Cu")
		(net "FM_PFR_LED_AMBER_R")
	)
	(segment
		(start 335.915 -75.7174)
		(end 344.3732 -75.7174)
		(width 0.15494)
		(layer "In15.Cu")
		(net "FM_PFR_LED_AMBER_R")
	)
	(segment
		(start 363.323632 -89.943432)
		(end 364.49254 -91.11234)
		(width 0.15494)
		(layer "In15.Cu")
		(net "FM_PFR_LED_AMBER_R")
	)
	(segment
		(start 238.273336 -71.61403)
		(end 239.252506 -72.5932)
		(width 0.15494)
		(layer "In15.Cu")
		(net "FM_PFR_LED_AMBER_R")
	)
	(segment
		(start 367.260124 -92.381578)
		(end 367.260124 -92.97162)
		(width 0.15494)
		(layer "In15.Cu")
		(net "FM_PFR_LED_AMBER_R")
	)
	(segment
		(start 225.058986 -72.299576)
		(end 225.744532 -71.61403)
		(width 0.15494)
		(layer "In15.Cu")
		(net "FM_PFR_LED_AMBER_R")
	)
	(segment
		(start 225.744532 -71.61403)
		(end 238.273336 -71.61403)
		(width 0.15494)
		(layer "In15.Cu")
		(net "FM_PFR_LED_AMBER_R")
	)
	(segment
		(start 250.810522 -71.5518)
		(end 251.656342 -72.39762)
		(width 0.15494)
		(layer "In15.Cu")
		(net "FM_PFR_LED_AMBER_R")
	)
	(segment
		(start 297.687746 -75.8952)
		(end 297.890946 -75.692)
		(width 0.15494)
		(layer "In15.Cu")
		(net "FM_PFR_LED_AMBER_R")
	)
	(segment
		(start 365.990886 -91.11234)
		(end 367.260124 -92.381578)
		(width 0.15494)
		(layer "In15.Cu")
		(net "FM_PFR_LED_AMBER_R")
	)
	(segment
		(start 297.890946 -75.692)
		(end 310.413146 -75.692)
		(width 0.15494)
		(layer "In15.Cu")
		(net "FM_PFR_LED_AMBER_R")
	)
	(segment
		(start 310.413146 -75.692)
		(end 311.60085 -74.504296)
		(width 0.15494)
		(layer "In15.Cu")
		(net "FM_PFR_LED_AMBER_R")
	)
	(segment
		(start 344.3732 -75.7174)
		(end 347.472 -78.8162)
		(width 0.15494)
		(layer "In15.Cu")
		(net "FM_PFR_LED_AMBER_R")
	)
	(segment
		(start 323.6214 -76.4032)
		(end 335.2292 -76.4032)
		(width 0.15494)
		(layer "In15.Cu")
		(net "FM_PFR_LED_AMBER_R")
	)
	(segment
		(start 248.1072 -71.5518)
		(end 250.810522 -71.5518)
		(width 0.15494)
		(layer "In15.Cu")
		(net "FM_PFR_LED_AMBER_R")
	)
	(segment
		(start 276.2758 -75.8952)
		(end 297.687746 -75.8952)
		(width 0.15494)
		(layer "In15.Cu")
		(net "FM_PFR_LED_AMBER_R")
	)
	(segment
		(start 347.472 -78.8162)
		(end 355.841808 -78.8162)
		(width 0.15494)
		(layer "In15.Cu")
		(net "FM_PFR_LED_AMBER_R")
	)
	(segment
		(start 364.49254 -91.11234)
		(end 365.990886 -91.11234)
		(width 0.15494)
		(layer "In15.Cu")
		(net "FM_PFR_LED_AMBER_R")
	)
	(segment
		(start 272.77822 -72.39762)
		(end 276.2758 -75.8952)
		(width 0.15494)
		(layer "In15.Cu")
		(net "FM_PFR_LED_AMBER_R")
	)
	(segment
		(start 251.656342 -72.39762)
		(end 272.77822 -72.39762)
		(width 0.15494)
		(layer "In15.Cu")
		(net "FM_PFR_LED_AMBER_R")
	)
	(segment
		(start 239.252506 -72.5932)
		(end 247.0658 -72.5932)
		(width 0.15494)
		(layer "In15.Cu")
		(net "FM_PFR_LED_AMBER_R")
	)
	(segment
		(start 321.722496 -74.504296)
		(end 323.6214 -76.4032)
		(width 0.15494)
		(layer "In15.Cu")
		(net "FM_PFR_LED_AMBER_R")
	)
	(segment
		(start 247.0658 -72.5932)
		(end 248.1072 -71.5518)
		(width 0.15494)
		(layer "In15.Cu")
		(net "FM_PFR_LED_AMBER_R")
	)
	(segment
		(start 363.323632 -86.298024)
		(end 363.323632 -89.943432)
		(width 0.15494)
		(layer "In15.Cu")
		(net "FM_PFR_LED_AMBER_R")
	)
	(segment
		(start 355.841808 -78.8162)
		(end 363.323632 -86.298024)
		(width 0.15494)
		(layer "In15.Cu")
		(net "FM_PFR_LED_AMBER_R")
	)
	(segment
		(start 335.2292 -76.4032)
		(end 335.915 -75.7174)
		(width 0.15494)
		(layer "In15.Cu")
		(net "FM_PFR_LED_AMBER_R")
	)
	(segment
		(start 254.085598 -24.75865)
		(end 253.450598 -24.75865)
		(width 0.13208)
		(layer "F.Cu")
		(net "SSD8_LED_ISO_R_N")
	)
	(segment
		(start 243.880894 -24.189944)
		(end 242.864894 -24.189944)
		(width 0.13208)
		(layer "F.Cu")
		(net "SSD8_LED_ISO_R_N")
	)
	(via
		(at 253.450598 -24.75865)
		(size 0.508)
		(drill 0.254)
		(layers "F.Cu" "B.Cu")
		(net "SSD8_LED_ISO_R_N")
	)
	(via
		(at 243.880894 -24.189944)
		(size 0.508)
		(drill 0.254)
		(layers "F.Cu" "B.Cu")
		(net "SSD8_LED_ISO_R_N")
	)
	(segment
		(start 247.72747 -23.486364)
		(end 245.961408 -23.486364)
		(width 0.15494)
		(layer "In5.Cu")
		(net "SSD8_LED_ISO_R_N")
	)
	(segment
		(start 245.961408 -23.486364)
		(end 245.257828 -24.189944)
		(width 0.15494)
		(layer "In5.Cu")
		(net "SSD8_LED_ISO_R_N")
	)
	(segment
		(start 249.046238 -24.115268)
		(end 248.356374 -24.115268)
		(width 0.15494)
		(layer "In5.Cu")
		(net "SSD8_LED_ISO_R_N")
	)
	(segment
		(start 253.056136 -24.364188)
		(end 249.400314 -24.364188)
		(width 0.15494)
		(layer "In5.Cu")
		(net "SSD8_LED_ISO_R_N")
	)
	(segment
		(start 245.257828 -24.189944)
		(end 243.880894 -24.189944)
		(width 0.15494)
		(layer "In5.Cu")
		(net "SSD8_LED_ISO_R_N")
	)
	(segment
		(start 249.400314 -24.364188)
		(end 249.046238 -24.115268)
		(width 0.15494)
		(layer "In5.Cu")
		(net "SSD8_LED_ISO_R_N")
	)
	(segment
		(start 253.450598 -24.75865)
		(end 253.056136 -24.364188)
		(width 0.15494)
		(layer "In5.Cu")
		(net "SSD8_LED_ISO_R_N")
	)
	(segment
		(start 248.356374 -24.115268)
		(end 247.72747 -23.486364)
		(width 0.15494)
		(layer "In5.Cu")
		(net "SSD8_LED_ISO_R_N")
	)
	(segment
		(start 223.006158 -82.643472)
		(end 222.390208 -82.643472)
		(width 0.13208)
		(layer "F.Cu")
		(net "SSD13_LED_R")
	)
	(segment
		(start 399.523966 -27.411934)
		(end 399.523966 -26.319734)
		(width 0.13208)
		(layer "F.Cu")
		(net "SSD13_LED_R")
	)
	(segment
		(start 223.622108 -82.643472)
		(end 223.006158 -82.643472)
		(width 0.13208)
		(layer "F.Cu")
		(net "SSD13_LED_R")
	)
	(via
		(at 407.915364 -87.323676)
		(size 0.508)
		(drill 0.254)
		(layers "F.Cu" "B.Cu")
		(net "SSD13_LED_R")
	)
	(via
		(at 223.006158 -82.643472)
		(size 0.508)
		(drill 0.254)
		(layers "F.Cu" "B.Cu")
		(net "SSD13_LED_R")
	)
	(via
		(at 399.523966 -26.319734)
		(size 0.508)
		(drill 0.254)
		(layers "F.Cu" "B.Cu")
		(net "SSD13_LED_R")
	)
	(segment
		(start 399.523966 -31.34995)
		(end 400.6215 -30.252416)
		(width 0.15494)
		(layer "In5.Cu")
		(net "SSD13_LED_R")
	)
	(segment
		(start 412.429198 -64.32296)
		(end 412.429198 -44.908724)
		(width 0.15494)
		(layer "In5.Cu")
		(net "SSD13_LED_R")
	)
	(segment
		(start 400.6215 -27.417268)
		(end 399.523966 -26.319734)
		(width 0.15494)
		(layer "In5.Cu")
		(net "SSD13_LED_R")
	)
	(segment
		(start 400.6215 -30.252416)
		(end 400.6215 -27.417268)
		(width 0.15494)
		(layer "In5.Cu")
		(net "SSD13_LED_R")
	)
	(segment
		(start 406.977088 -69.77507)
		(end 412.429198 -64.32296)
		(width 0.15494)
		(layer "In5.Cu")
		(net "SSD13_LED_R")
	)
	(segment
		(start 407.915364 -86.471252)
		(end 406.977088 -85.532976)
		(width 0.15494)
		(layer "In5.Cu")
		(net "SSD13_LED_R")
	)
	(segment
		(start 407.915364 -87.323676)
		(end 407.915364 -86.471252)
		(width 0.15494)
		(layer "In5.Cu")
		(net "SSD13_LED_R")
	)
	(segment
		(start 406.977088 -85.532976)
		(end 406.977088 -69.77507)
		(width 0.15494)
		(layer "In5.Cu")
		(net "SSD13_LED_R")
	)
	(segment
		(start 412.429198 -44.908724)
		(end 399.523966 -32.003492)
		(width 0.15494)
		(layer "In5.Cu")
		(net "SSD13_LED_R")
	)
	(segment
		(start 399.523966 -32.003492)
		(end 399.523966 -31.34995)
		(width 0.15494)
		(layer "In5.Cu")
		(net "SSD13_LED_R")
	)
	(segment
		(start 315.7728 -87.8332)
		(end 311.866534 -87.8332)
		(width 0.15494)
		(layer "In15.Cu")
		(net "SSD13_LED_R")
	)
	(segment
		(start 316.1284 -88.1888)
		(end 315.7728 -87.8332)
		(width 0.15494)
		(layer "In15.Cu")
		(net "SSD13_LED_R")
	)
	(segment
		(start 407.68524 -87.5538)
		(end 401.777454 -87.5538)
		(width 0.15494)
		(layer "In15.Cu")
		(net "SSD13_LED_R")
	)
	(segment
		(start 223.525842 -82.123788)
		(end 223.006158 -82.643472)
		(width 0.15494)
		(layer "In15.Cu")
		(net "SSD13_LED_R")
	)
	(segment
		(start 226.71532 -76.73848)
		(end 226.71532 -80.654906)
		(width 0.15494)
		(layer "In15.Cu")
		(net "SSD13_LED_R")
	)
	(segment
		(start 334.010254 -89.7636)
		(end 328.7776 -89.7636)
		(width 0.15494)
		(layer "In15.Cu")
		(net "SSD13_LED_R")
	)
	(segment
		(start 238.607854 -76.8096)
		(end 236.728254 -74.93)
		(width 0.15494)
		(layer "In15.Cu")
		(net "SSD13_LED_R")
	)
	(segment
		(start 346.634054 -95.3008)
		(end 343.382854 -92.0496)
		(width 0.15494)
		(layer "In15.Cu")
		(net "SSD13_LED_R")
	)
	(segment
		(start 327.2028 -88.1888)
		(end 316.1284 -88.1888)
		(width 0.15494)
		(layer "In15.Cu")
		(net "SSD13_LED_R")
	)
	(segment
		(start 361.518454 -96.1136)
		(end 360.705654 -95.3008)
		(width 0.15494)
		(layer "In15.Cu")
		(net "SSD13_LED_R")
	)
	(segment
		(start 393.336018 -90.025982)
		(end 391.4394 -91.9226)
		(width 0.15494)
		(layer "In15.Cu")
		(net "SSD13_LED_R")
	)
	(segment
		(start 379.37059 -96.1136)
		(end 361.518454 -96.1136)
		(width 0.15494)
		(layer "In15.Cu")
		(net "SSD13_LED_R")
	)
	(segment
		(start 243.2304 -76.8096)
		(end 238.607854 -76.8096)
		(width 0.15494)
		(layer "In15.Cu")
		(net "SSD13_LED_R")
	)
	(segment
		(start 391.4394 -91.9226)
		(end 383.56159 -91.9226)
		(width 0.15494)
		(layer "In15.Cu")
		(net "SSD13_LED_R")
	)
	(segment
		(start 226.71532 -80.654906)
		(end 225.246438 -82.123788)
		(width 0.15494)
		(layer "In15.Cu")
		(net "SSD13_LED_R")
	)
	(segment
		(start 343.382854 -92.0496)
		(end 336.296254 -92.0496)
		(width 0.15494)
		(layer "In15.Cu")
		(net "SSD13_LED_R")
	)
	(segment
		(start 280.8732 -85.8266)
		(end 273.101054 -85.8266)
		(width 0.15494)
		(layer "In15.Cu")
		(net "SSD13_LED_R")
	)
	(segment
		(start 228.5238 -74.93)
		(end 226.71532 -76.73848)
		(width 0.15494)
		(layer "In15.Cu")
		(net "SSD13_LED_R")
	)
	(segment
		(start 255.8796 -79.2734)
		(end 253.872238 -79.2734)
		(width 0.15494)
		(layer "In15.Cu")
		(net "SSD13_LED_R")
	)
	(segment
		(start 257.327908 -80.721708)
		(end 255.8796 -79.2734)
		(width 0.15494)
		(layer "In15.Cu")
		(net "SSD13_LED_R")
	)
	(segment
		(start 360.705654 -95.3008)
		(end 346.634054 -95.3008)
		(width 0.15494)
		(layer "In15.Cu")
		(net "SSD13_LED_R")
	)
	(segment
		(start 273.101054 -85.8266)
		(end 267.996162 -80.721708)
		(width 0.15494)
		(layer "In15.Cu")
		(net "SSD13_LED_R")
	)
	(segment
		(start 225.246438 -82.123788)
		(end 223.525842 -82.123788)
		(width 0.15494)
		(layer "In15.Cu")
		(net "SSD13_LED_R")
	)
	(segment
		(start 383.56159 -91.9226)
		(end 379.37059 -96.1136)
		(width 0.15494)
		(layer "In15.Cu")
		(net "SSD13_LED_R")
	)
	(segment
		(start 267.996162 -80.721708)
		(end 257.327908 -80.721708)
		(width 0.15494)
		(layer "In15.Cu")
		(net "SSD13_LED_R")
	)
	(segment
		(start 401.777454 -87.5538)
		(end 399.305272 -90.025982)
		(width 0.15494)
		(layer "In15.Cu")
		(net "SSD13_LED_R")
	)
	(segment
		(start 253.872238 -79.2734)
		(end 252.023118 -77.42428)
		(width 0.15494)
		(layer "In15.Cu")
		(net "SSD13_LED_R")
	)
	(segment
		(start 243.84508 -77.42428)
		(end 243.2304 -76.8096)
		(width 0.15494)
		(layer "In15.Cu")
		(net "SSD13_LED_R")
	)
	(segment
		(start 236.728254 -74.93)
		(end 228.5238 -74.93)
		(width 0.15494)
		(layer "In15.Cu")
		(net "SSD13_LED_R")
	)
	(segment
		(start 311.866534 -87.8332)
		(end 311.601358 -88.098376)
		(width 0.15494)
		(layer "In15.Cu")
		(net "SSD13_LED_R")
	)
	(segment
		(start 407.915364 -87.323676)
		(end 407.68524 -87.5538)
		(width 0.15494)
		(layer "In15.Cu")
		(net "SSD13_LED_R")
	)
	(segment
		(start 252.023118 -77.42428)
		(end 243.84508 -77.42428)
		(width 0.15494)
		(layer "In15.Cu")
		(net "SSD13_LED_R")
	)
	(segment
		(start 328.7776 -89.7636)
		(end 327.2028 -88.1888)
		(width 0.15494)
		(layer "In15.Cu")
		(net "SSD13_LED_R")
	)
	(segment
		(start 399.305272 -90.025982)
		(end 393.336018 -90.025982)
		(width 0.15494)
		(layer "In15.Cu")
		(net "SSD13_LED_R")
	)
	(segment
		(start 311.601358 -88.098376)
		(end 283.144976 -88.098376)
		(width 0.15494)
		(layer "In15.Cu")
		(net "SSD13_LED_R")
	)
	(segment
		(start 336.296254 -92.0496)
		(end 334.010254 -89.7636)
		(width 0.15494)
		(layer "In15.Cu")
		(net "SSD13_LED_R")
	)
	(segment
		(start 283.144976 -88.098376)
		(end 280.8732 -85.8266)
		(width 0.15494)
		(layer "In15.Cu")
		(net "SSD13_LED_R")
	)
	(segment
		(start 255.570736 -25.211786)
		(end 256.47396 -25.211786)
		(width 0.13208)
		(layer "F.Cu")
		(net "SSD8_LED_ISO_N")
	)
	(segment
		(start 254.085598 -25.55875)
		(end 255.223772 -25.55875)
		(width 0.13208)
		(layer "F.Cu")
		(net "SSD8_LED_ISO_N")
	)
	(segment
		(start 254.085598 -26.692098)
		(end 254.085598 -25.55875)
		(width 0.13208)
		(layer "F.Cu")
		(net "SSD8_LED_ISO_N")
	)
	(segment
		(start 255.223772 -25.55875)
		(end 255.570736 -25.211786)
		(width 0.13208)
		(layer "F.Cu")
		(net "SSD8_LED_ISO_N")
	)
	(via
		(at 255.223772 -25.55875)
		(size 0.508)
		(drill 0.254)
		(layers "F.Cu" "B.Cu")
		(net "SSD8_LED_ISO_N")
	)
	(segment
		(start 280.085546 -25.55875)
		(end 281.22372 -25.55875)
		(width 0.13208)
		(layer "F.Cu")
		(net "SSD9_LED_ISO_N")
	)
	(segment
		(start 281.22372 -25.55875)
		(end 281.570684 -25.211786)
		(width 0.13208)
		(layer "F.Cu")
		(net "SSD9_LED_ISO_N")
	)
	(segment
		(start 281.570684 -25.211786)
		(end 282.473908 -25.211786)
		(width 0.13208)
		(layer "F.Cu")
		(net "SSD9_LED_ISO_N")
	)
	(segment
		(start 280.085546 -26.692098)
		(end 280.085546 -25.55875)
		(width 0.13208)
		(layer "F.Cu")
		(net "SSD9_LED_ISO_N")
	)
	(via
		(at 281.22372 -25.55875)
		(size 0.508)
		(drill 0.254)
		(layers "F.Cu" "B.Cu")
		(net "SSD9_LED_ISO_N")
	)
	(segment
		(start 269.880842 -24.189944)
		(end 268.864842 -24.189944)
		(width 0.13208)
		(layer "F.Cu")
		(net "SSD9_LED_ISO_R_N")
	)
	(segment
		(start 280.085546 -24.75865)
		(end 279.450546 -24.75865)
		(width 0.13208)
		(layer "F.Cu")
		(net "SSD9_LED_ISO_R_N")
	)
	(via
		(at 269.880842 -24.189944)
		(size 0.508)
		(drill 0.254)
		(layers "F.Cu" "B.Cu")
		(net "SSD9_LED_ISO_R_N")
	)
	(via
		(at 279.450546 -24.75865)
		(size 0.508)
		(drill 0.254)
		(layers "F.Cu" "B.Cu")
		(net "SSD9_LED_ISO_R_N")
	)
	(segment
		(start 275.400262 -24.364188)
		(end 279.056084 -24.364188)
		(width 0.15494)
		(layer "In5.Cu")
		(net "SSD9_LED_ISO_R_N")
	)
	(segment
		(start 271.961356 -23.486364)
		(end 273.727418 -23.486364)
		(width 0.15494)
		(layer "In5.Cu")
		(net "SSD9_LED_ISO_R_N")
	)
	(segment
		(start 273.727418 -23.486364)
		(end 274.356322 -24.115268)
		(width 0.15494)
		(layer "In5.Cu")
		(net "SSD9_LED_ISO_R_N")
	)
	(segment
		(start 269.880842 -24.189944)
		(end 271.257776 -24.189944)
		(width 0.15494)
		(layer "In5.Cu")
		(net "SSD9_LED_ISO_R_N")
	)
	(segment
		(start 271.257776 -24.189944)
		(end 271.961356 -23.486364)
		(width 0.15494)
		(layer "In5.Cu")
		(net "SSD9_LED_ISO_R_N")
	)
	(segment
		(start 279.056084 -24.364188)
		(end 279.450546 -24.75865)
		(width 0.15494)
		(layer "In5.Cu")
		(net "SSD9_LED_ISO_R_N")
	)
	(segment
		(start 274.356322 -24.115268)
		(end 275.046186 -24.115268)
		(width 0.15494)
		(layer "In5.Cu")
		(net "SSD9_LED_ISO_R_N")
	)
	(segment
		(start 275.046186 -24.115268)
		(end 275.400262 -24.364188)
		(width 0.15494)
		(layer "In5.Cu")
		(net "SSD9_LED_ISO_R_N")
	)
	(segment
		(start 309.423816 -27.411934)
		(end 309.423816 -26.319734)
		(width 0.13208)
		(layer "F.Cu")
		(net "SSD10_LED_R")
	)
	(segment
		(start 222.390208 -79.595472)
		(end 223.006158 -79.595472)
		(width 0.13208)
		(layer "F.Cu")
		(net "SSD10_LED_R")
	)
	(segment
		(start 223.006158 -79.595472)
		(end 223.622108 -79.595472)
		(width 0.13208)
		(layer "F.Cu")
		(net "SSD10_LED_R")
	)
	(via
		(at 309.423816 -26.319734)
		(size 0.508)
		(drill 0.254)
		(layers "F.Cu" "B.Cu")
		(net "SSD10_LED_R")
	)
	(via
		(at 319.024 -86.487)
		(size 0.508)
		(drill 0.254)
		(layers "F.Cu" "B.Cu")
		(net "SSD10_LED_R")
	)
	(via
		(at 223.006158 -79.595472)
		(size 0.508)
		(drill 0.254)
		(layers "F.Cu" "B.Cu")
		(net "SSD10_LED_R")
	)
	(segment
		(start 318.643 -86.487)
		(end 319.024 -86.487)
		(width 0.15494)
		(layer "In5.Cu")
		(net "SSD10_LED_R")
	)
	(segment
		(start 310.52897 -27.424888)
		(end 310.52897 -30.180534)
		(width 0.15494)
		(layer "In5.Cu")
		(net "SSD10_LED_R")
	)
	(segment
		(start 322.268088 -44.896786)
		(end 322.268088 -66.15684)
		(width 0.15494)
		(layer "In5.Cu")
		(net "SSD10_LED_R")
	)
	(segment
		(start 319.406524 -83.310476)
		(end 318.516 -84.201)
		(width 0.15494)
		(layer "In5.Cu")
		(net "SSD10_LED_R")
	)
	(segment
		(start 309.423816 -26.319734)
		(end 310.52897 -27.424888)
		(width 0.15494)
		(layer "In5.Cu")
		(net "SSD10_LED_R")
	)
	(segment
		(start 318.516 -84.201)
		(end 318.516 -86.36)
		(width 0.15494)
		(layer "In5.Cu")
		(net "SSD10_LED_R")
	)
	(segment
		(start 323.730112 -81.303368)
		(end 321.723004 -83.310476)
		(width 0.15494)
		(layer "In5.Cu")
		(net "SSD10_LED_R")
	)
	(segment
		(start 310.52897 -30.180534)
		(end 309.423816 -31.285688)
		(width 0.15494)
		(layer "In5.Cu")
		(net "SSD10_LED_R")
	)
	(segment
		(start 318.516 -86.36)
		(end 318.643 -86.487)
		(width 0.15494)
		(layer "In5.Cu")
		(net "SSD10_LED_R")
	)
	(segment
		(start 321.723004 -83.310476)
		(end 319.406524 -83.310476)
		(width 0.15494)
		(layer "In5.Cu")
		(net "SSD10_LED_R")
	)
	(segment
		(start 322.268088 -66.15684)
		(end 323.730112 -67.618864)
		(width 0.15494)
		(layer "In5.Cu")
		(net "SSD10_LED_R")
	)
	(segment
		(start 323.730112 -67.618864)
		(end 323.730112 -81.303368)
		(width 0.15494)
		(layer "In5.Cu")
		(net "SSD10_LED_R")
	)
	(segment
		(start 309.423816 -31.285688)
		(end 309.423816 -32.052514)
		(width 0.15494)
		(layer "In5.Cu")
		(net "SSD10_LED_R")
	)
	(segment
		(start 309.423816 -32.052514)
		(end 322.268088 -44.896786)
		(width 0.15494)
		(layer "In5.Cu")
		(net "SSD10_LED_R")
	)
	(segment
		(start 259.385054 -77.3176)
		(end 259.943854 -77.8764)
		(width 0.15494)
		(layer "In15.Cu")
		(net "SSD10_LED_R")
	)
	(segment
		(start 312.119772 -85.9282)
		(end 317.538354 -85.9282)
		(width 0.15494)
		(layer "In15.Cu")
		(net "SSD10_LED_R")
	)
	(segment
		(start 223.006158 -79.595472)
		(end 224.236788 -79.595472)
		(width 0.15494)
		(layer "In15.Cu")
		(net "SSD10_LED_R")
	)
	(segment
		(start 253.0094 -76.3016)
		(end 254.0254 -77.3176)
		(width 0.15494)
		(layer "In15.Cu")
		(net "SSD10_LED_R")
	)
	(segment
		(start 254.0254 -77.3176)
		(end 259.385054 -77.3176)
		(width 0.15494)
		(layer "In15.Cu")
		(net "SSD10_LED_R")
	)
	(segment
		(start 267.6144 -79.0702)
		(end 268.3764 -78.3082)
		(width 0.15494)
		(layer "In15.Cu")
		(net "SSD10_LED_R")
	)
	(segment
		(start 227.355908 -73.659238)
		(end 237.057438 -73.659238)
		(width 0.15494)
		(layer "In15.Cu")
		(net "SSD10_LED_R")
	)
	(segment
		(start 259.943854 -77.8764)
		(end 262.407146 -77.8764)
		(width 0.15494)
		(layer "In15.Cu")
		(net "SSD10_LED_R")
	)
	(segment
		(start 302.06696 -85.367876)
		(end 311.559448 -85.367876)
		(width 0.15494)
		(layer "In15.Cu")
		(net "SSD10_LED_R")
	)
	(segment
		(start 224.73666 -79.0956)
		(end 225.2472 -79.0956)
		(width 0.15494)
		(layer "In15.Cu")
		(net "SSD10_LED_R")
	)
	(segment
		(start 294.538146 -79.756)
		(end 299.491146 -84.709)
		(width 0.15494)
		(layer "In15.Cu")
		(net "SSD10_LED_R")
	)
	(segment
		(start 263.600946 -79.0702)
		(end 267.6144 -79.0702)
		(width 0.15494)
		(layer "In15.Cu")
		(net "SSD10_LED_R")
	)
	(segment
		(start 318.097154 -86.487)
		(end 319.024 -86.487)
		(width 0.15494)
		(layer "In15.Cu")
		(net "SSD10_LED_R")
	)
	(segment
		(start 262.407146 -77.8764)
		(end 263.600946 -79.0702)
		(width 0.15494)
		(layer "In15.Cu")
		(net "SSD10_LED_R")
	)
	(segment
		(start 237.057438 -73.659238)
		(end 239.0648 -75.6666)
		(width 0.15494)
		(layer "In15.Cu")
		(net "SSD10_LED_R")
	)
	(segment
		(start 224.236788 -79.595472)
		(end 224.73666 -79.0956)
		(width 0.15494)
		(layer "In15.Cu")
		(net "SSD10_LED_R")
	)
	(segment
		(start 244.271546 -76.3016)
		(end 253.0094 -76.3016)
		(width 0.15494)
		(layer "In15.Cu")
		(net "SSD10_LED_R")
	)
	(segment
		(start 243.636546 -75.6666)
		(end 244.271546 -76.3016)
		(width 0.15494)
		(layer "In15.Cu")
		(net "SSD10_LED_R")
	)
	(segment
		(start 274.269454 -78.3082)
		(end 275.717254 -79.756)
		(width 0.15494)
		(layer "In15.Cu")
		(net "SSD10_LED_R")
	)
	(segment
		(start 311.559448 -85.367876)
		(end 312.119772 -85.9282)
		(width 0.15494)
		(layer "In15.Cu")
		(net "SSD10_LED_R")
	)
	(segment
		(start 299.491146 -84.709)
		(end 301.408084 -84.709)
		(width 0.15494)
		(layer "In15.Cu")
		(net "SSD10_LED_R")
	)
	(segment
		(start 275.717254 -79.756)
		(end 294.538146 -79.756)
		(width 0.15494)
		(layer "In15.Cu")
		(net "SSD10_LED_R")
	)
	(segment
		(start 301.408084 -84.709)
		(end 302.06696 -85.367876)
		(width 0.15494)
		(layer "In15.Cu")
		(net "SSD10_LED_R")
	)
	(segment
		(start 225.2472 -79.0956)
		(end 225.6028 -78.74)
		(width 0.15494)
		(layer "In15.Cu")
		(net "SSD10_LED_R")
	)
	(segment
		(start 225.6028 -78.74)
		(end 225.6028 -75.412346)
		(width 0.15494)
		(layer "In15.Cu")
		(net "SSD10_LED_R")
	)
	(segment
		(start 225.6028 -75.412346)
		(end 227.355908 -73.659238)
		(width 0.15494)
		(layer "In15.Cu")
		(net "SSD10_LED_R")
	)
	(segment
		(start 268.3764 -78.3082)
		(end 274.269454 -78.3082)
		(width 0.15494)
		(layer "In15.Cu")
		(net "SSD10_LED_R")
	)
	(segment
		(start 239.0648 -75.6666)
		(end 243.636546 -75.6666)
		(width 0.15494)
		(layer "In15.Cu")
		(net "SSD10_LED_R")
	)
	(segment
		(start 317.538354 -85.9282)
		(end 318.097154 -86.487)
		(width 0.15494)
		(layer "In15.Cu")
		(net "SSD10_LED_R")
	)
	(segment
		(start 215.985598 -24.75865)
		(end 215.350598 -24.75865)
		(width 0.13208)
		(layer "F.Cu")
		(net "SSD7_LED_ISO_R_N")
	)
	(segment
		(start 205.780894 -24.189944)
		(end 204.764894 -24.189944)
		(width 0.13208)
		(layer "F.Cu")
		(net "SSD7_LED_ISO_R_N")
	)
	(via
		(at 215.350598 -24.75865)
		(size 0.508)
		(drill 0.254)
		(layers "F.Cu" "B.Cu")
		(net "SSD7_LED_ISO_R_N")
	)
	(via
		(at 205.780894 -24.189944)
		(size 0.508)
		(drill 0.254)
		(layers "F.Cu" "B.Cu")
		(net "SSD7_LED_ISO_R_N")
	)
	(segment
		(start 210.582002 -24.4602)
		(end 215.052148 -24.4602)
		(width 0.15494)
		(layer "In5.Cu")
		(net "SSD7_LED_ISO_R_N")
	)
	(segment
		(start 215.052148 -24.4602)
		(end 215.350598 -24.75865)
		(width 0.15494)
		(layer "In5.Cu")
		(net "SSD7_LED_ISO_R_N")
	)
	(segment
		(start 207.157828 -24.189944)
		(end 207.861408 -23.486364)
		(width 0.15494)
		(layer "In5.Cu")
		(net "SSD7_LED_ISO_R_N")
	)
	(segment
		(start 205.780894 -24.189944)
		(end 207.157828 -24.189944)
		(width 0.15494)
		(layer "In5.Cu")
		(net "SSD7_LED_ISO_R_N")
	)
	(segment
		(start 209.608166 -23.486364)
		(end 210.582002 -24.4602)
		(width 0.15494)
		(layer "In5.Cu")
		(net "SSD7_LED_ISO_R_N")
	)
	(segment
		(start 207.861408 -23.486364)
		(end 209.608166 -23.486364)
		(width 0.15494)
		(layer "In5.Cu")
		(net "SSD7_LED_ISO_R_N")
	)
	(segment
		(start 345.29395 -224.786952)
		(end 345.693746 -225.186748)
		(width 0.13208)
		(layer "F.Cu")
		(net "PU_FPGA_PROGRAMN")
	)
	(via
		(at 345.693746 -225.186748)
		(size 0.4572)
		(drill 0.254)
		(layers "F.Cu" "B.Cu")
		(net "PU_FPGA_PROGRAMN")
	)
	(via
		(at 352.489262 -231.807766)
		(size 0.508)
		(drill 0.254)
		(layers "F.Cu" "B.Cu")
		(net "PU_FPGA_PROGRAMN")
	)
	(segment
		(start 352.11893 -233.15295)
		(end 352.11893 -232.178098)
		(width 0.13208)
		(layer "B.Cu")
		(net "PU_FPGA_PROGRAMN")
	)
	(segment
		(start 352.11893 -232.178098)
		(end 352.489262 -231.807766)
		(width 0.13208)
		(layer "B.Cu")
		(net "PU_FPGA_PROGRAMN")
	)
	(segment
		(start 347.393006 -228.161088)
		(end 346.402914 -228.161088)
		(width 0.15494)
		(layer "In5.Cu")
		(net "PU_FPGA_PROGRAMN")
	)
	(segment
		(start 346.04706 -227.32238)
		(end 346.091256 -227.278184)
		(width 0.15494)
		(layer "In5.Cu")
		(net "PU_FPGA_PROGRAMN")
	)
	(segment
		(start 346.402914 -228.161088)
		(end 346.04706 -227.805234)
		(width 0.15494)
		(layer "In5.Cu")
		(net "PU_FPGA_PROGRAMN")
	)
	(segment
		(start 351.039684 -231.807766)
		(end 347.393006 -228.161088)
		(width 0.15494)
		(layer "In5.Cu")
		(net "PU_FPGA_PROGRAMN")
	)
	(segment
		(start 346.04706 -227.805234)
		(end 346.04706 -227.32238)
		(width 0.15494)
		(layer "In5.Cu")
		(net "PU_FPGA_PROGRAMN")
	)
	(segment
		(start 352.489262 -231.807766)
		(end 351.039684 -231.807766)
		(width 0.15494)
		(layer "In5.Cu")
		(net "PU_FPGA_PROGRAMN")
	)
	(segment
		(start 346.091256 -225.584258)
		(end 345.693746 -225.186748)
		(width 0.0889)
		(layer "In5.Cu")
		(net "PU_FPGA_PROGRAMN")
	)
	(segment
		(start 346.091256 -227.04552)
		(end 346.091256 -225.584258)
		(width 0.0889)
		(layer "In5.Cu")
		(net "PU_FPGA_PROGRAMN")
	)
	(segment
		(start 346.091256 -227.278184)
		(end 346.091256 -227.04552)
		(width 0.15494)
		(layer "In5.Cu")
		(net "PU_FPGA_PROGRAMN")
	)
	(segment
		(start 217.470736 -25.211786)
		(end 218.37396 -25.211786)
		(width 0.13208)
		(layer "F.Cu")
		(net "SSD7_LED_ISO_N")
	)
	(segment
		(start 215.985598 -25.55875)
		(end 217.123772 -25.55875)
		(width 0.13208)
		(layer "F.Cu")
		(net "SSD7_LED_ISO_N")
	)
	(segment
		(start 217.123772 -25.55875)
		(end 217.470736 -25.211786)
		(width 0.13208)
		(layer "F.Cu")
		(net "SSD7_LED_ISO_N")
	)
	(segment
		(start 215.985598 -26.692098)
		(end 215.985598 -25.55875)
		(width 0.13208)
		(layer "F.Cu")
		(net "SSD7_LED_ISO_N")
	)
	(via
		(at 217.123772 -25.55875)
		(size 0.508)
		(drill 0.254)
		(layers "F.Cu" "B.Cu")
		(net "SSD7_LED_ISO_N")
	)
	(segment
		(start 179.780946 -24.189944)
		(end 178.764946 -24.189944)
		(width 0.13208)
		(layer "F.Cu")
		(net "SSD6_LED_ISO_R_N")
	)
	(segment
		(start 189.98565 -24.75865)
		(end 189.35065 -24.75865)
		(width 0.13208)
		(layer "F.Cu")
		(net "SSD6_LED_ISO_R_N")
	)
	(via
		(at 179.780946 -24.189944)
		(size 0.508)
		(drill 0.254)
		(layers "F.Cu" "B.Cu")
		(net "SSD6_LED_ISO_R_N")
	)
	(via
		(at 189.35065 -24.75865)
		(size 0.508)
		(drill 0.254)
		(layers "F.Cu" "B.Cu")
		(net "SSD6_LED_ISO_R_N")
	)
	(segment
		(start 183.608218 -23.486364)
		(end 184.582054 -24.4602)
		(width 0.15494)
		(layer "In5.Cu")
		(net "SSD6_LED_ISO_R_N")
	)
	(segment
		(start 181.15788 -24.189944)
		(end 181.86146 -23.486364)
		(width 0.15494)
		(layer "In5.Cu")
		(net "SSD6_LED_ISO_R_N")
	)
	(segment
		(start 189.0522 -24.4602)
		(end 189.35065 -24.75865)
		(width 0.15494)
		(layer "In5.Cu")
		(net "SSD6_LED_ISO_R_N")
	)
	(segment
		(start 179.780946 -24.189944)
		(end 181.15788 -24.189944)
		(width 0.15494)
		(layer "In5.Cu")
		(net "SSD6_LED_ISO_R_N")
	)
	(segment
		(start 184.582054 -24.4602)
		(end 189.0522 -24.4602)
		(width 0.15494)
		(layer "In5.Cu")
		(net "SSD6_LED_ISO_R_N")
	)
	(segment
		(start 181.86146 -23.486364)
		(end 183.608218 -23.486364)
		(width 0.15494)
		(layer "In5.Cu")
		(net "SSD6_LED_ISO_R_N")
	)
	(segment
		(start 193.323972 -27.411934)
		(end 193.323972 -26.319734)
		(width 0.13208)
		(layer "F.Cu")
		(net "SSD6_LED_R")
	)
	(segment
		(start 205.918308 -78.579472)
		(end 206.223108 -78.579472)
		(width 0.13208)
		(layer "F.Cu")
		(net "SSD6_LED_R")
	)
	(segment
		(start 205.29042 -78.579472)
		(end 205.604364 -78.893416)
		(width 0.13208)
		(layer "F.Cu")
		(net "SSD6_LED_R")
	)
	(segment
		(start 204.991208 -78.579472)
		(end 205.29042 -78.579472)
		(width 0.13208)
		(layer "F.Cu")
		(net "SSD6_LED_R")
	)
	(segment
		(start 205.604364 -78.893416)
		(end 205.918308 -78.579472)
		(width 0.13208)
		(layer "F.Cu")
		(net "SSD6_LED_R")
	)
	(via
		(at 205.604364 -78.893416)
		(size 0.508)
		(drill 0.254)
		(layers "F.Cu" "B.Cu")
		(net "SSD6_LED_R")
	)
	(via
		(at 193.323972 -26.319734)
		(size 0.508)
		(drill 0.254)
		(layers "F.Cu" "B.Cu")
		(net "SSD6_LED_R")
	)
	(segment
		(start 193.323972 -26.319734)
		(end 194.607688 -27.60345)
		(width 0.15494)
		(layer "In5.Cu")
		(net "SSD6_LED_R")
	)
	(segment
		(start 194.607688 -33.304988)
		(end 206.178404 -44.875704)
		(width 0.15494)
		(layer "In5.Cu")
		(net "SSD6_LED_R")
	)
	(segment
		(start 206.178404 -78.319376)
		(end 205.604364 -78.893416)
		(width 0.15494)
		(layer "In5.Cu")
		(net "SSD6_LED_R")
	)
	(segment
		(start 194.607688 -27.60345)
		(end 194.607688 -33.304988)
		(width 0.15494)
		(layer "In5.Cu")
		(net "SSD6_LED_R")
	)
	(segment
		(start 206.178404 -44.875704)
		(end 206.178404 -78.319376)
		(width 0.15494)
		(layer "In5.Cu")
		(net "SSD6_LED_R")
	)
	(segment
		(start 189.98565 -26.692098)
		(end 189.98565 -25.55875)
		(width 0.13208)
		(layer "F.Cu")
		(net "SSD6_LED_ISO_N")
	)
	(segment
		(start 191.123824 -25.55875)
		(end 191.470788 -25.211786)
		(width 0.13208)
		(layer "F.Cu")
		(net "SSD6_LED_ISO_N")
	)
	(segment
		(start 189.98565 -25.55875)
		(end 191.123824 -25.55875)
		(width 0.13208)
		(layer "F.Cu")
		(net "SSD6_LED_ISO_N")
	)
	(segment
		(start 191.470788 -25.211786)
		(end 192.374012 -25.211786)
		(width 0.13208)
		(layer "F.Cu")
		(net "SSD6_LED_ISO_N")
	)
	(via
		(at 191.123824 -25.55875)
		(size 0.508)
		(drill 0.254)
		(layers "F.Cu" "B.Cu")
		(net "SSD6_LED_ISO_N")
	)
	(segment
		(start 205.61046 -81.627472)
		(end 204.991208 -81.627472)
		(width 0.13208)
		(layer "F.Cu")
		(net "SSD3_LED_R")
	)
	(segment
		(start 206.223108 -81.627472)
		(end 205.61046 -81.627472)
		(width 0.13208)
		(layer "F.Cu")
		(net "SSD3_LED_R")
	)
	(segment
		(start 103.223822 -27.411934)
		(end 103.223822 -26.319734)
		(width 0.13208)
		(layer "F.Cu")
		(net "SSD3_LED_R")
	)
	(via
		(at 103.223822 -26.319734)
		(size 0.508)
		(drill 0.254)
		(layers "F.Cu" "B.Cu")
		(net "SSD3_LED_R")
	)
	(via
		(at 131.988052 -79.843884)
		(size 0.508)
		(drill 0.254)
		(layers "F.Cu" "B.Cu")
		(net "SSD3_LED_R")
	)
	(via
		(at 205.61046 -81.627472)
		(size 0.508)
		(drill 0.254)
		(layers "F.Cu" "B.Cu")
		(net "SSD3_LED_R")
	)
	(segment
		(start 104.700832 -27.796744)
		(end 103.223822 -26.319734)
		(width 0.15494)
		(layer "In5.Cu")
		(net "SSD3_LED_R")
	)
	(segment
		(start 131.988052 -79.460852)
		(end 125.977142 -73.449942)
		(width 0.15494)
		(layer "In5.Cu")
		(net "SSD3_LED_R")
	)
	(segment
		(start 104.700832 -31.620714)
		(end 104.700832 -27.796744)
		(width 0.15494)
		(layer "In5.Cu")
		(net "SSD3_LED_R")
	)
	(segment
		(start 125.977142 -73.449942)
		(end 125.977142 -69.426074)
		(width 0.15494)
		(layer "In5.Cu")
		(net "SSD3_LED_R")
	)
	(segment
		(start 103.30434 -33.017206)
		(end 104.700832 -31.620714)
		(width 0.15494)
		(layer "In5.Cu")
		(net "SSD3_LED_R")
	)
	(segment
		(start 131.988052 -79.843884)
		(end 131.988052 -79.460852)
		(width 0.15494)
		(layer "In5.Cu")
		(net "SSD3_LED_R")
	)
	(segment
		(start 109.4232 -52.8828)
		(end 109.4232 -41.3512)
		(width 0.15494)
		(layer "In5.Cu")
		(net "SSD3_LED_R")
	)
	(segment
		(start 125.977142 -69.426074)
		(end 120.604026 -64.052958)
		(width 0.15494)
		(layer "In5.Cu")
		(net "SSD3_LED_R")
	)
	(segment
		(start 109.4232 -41.3512)
		(end 103.30434 -35.23234)
		(width 0.15494)
		(layer "In5.Cu")
		(net "SSD3_LED_R")
	)
	(segment
		(start 103.30434 -35.23234)
		(end 103.30434 -33.017206)
		(width 0.15494)
		(layer "In5.Cu")
		(net "SSD3_LED_R")
	)
	(segment
		(start 120.604026 -64.052958)
		(end 119.831104 -64.052958)
		(width 0.15494)
		(layer "In5.Cu")
		(net "SSD3_LED_R")
	)
	(segment
		(start 119.180102 -63.401956)
		(end 119.180102 -62.639702)
		(width 0.15494)
		(layer "In5.Cu")
		(net "SSD3_LED_R")
	)
	(segment
		(start 119.180102 -62.639702)
		(end 109.4232 -52.8828)
		(width 0.15494)
		(layer "In5.Cu")
		(net "SSD3_LED_R")
	)
	(segment
		(start 119.831104 -64.052958)
		(end 119.180102 -63.401956)
		(width 0.15494)
		(layer "In5.Cu")
		(net "SSD3_LED_R")
	)
	(segment
		(start 186.4487 -79.6798)
		(end 195.1228 -79.6798)
		(width 0.15494)
		(layer "In15.Cu")
		(net "SSD3_LED_R")
	)
	(segment
		(start 195.992496 -80.549496)
		(end 204.532484 -80.549496)
		(width 0.15494)
		(layer "In15.Cu")
		(net "SSD3_LED_R")
	)
	(segment
		(start 132.980684 -80.836516)
		(end 185.291984 -80.836516)
		(width 0.15494)
		(layer "In15.Cu")
		(net "SSD3_LED_R")
	)
	(segment
		(start 185.291984 -80.836516)
		(end 186.4487 -79.6798)
		(width 0.15494)
		(layer "In15.Cu")
		(net "SSD3_LED_R")
	)
	(segment
		(start 195.1228 -79.6798)
		(end 195.992496 -80.549496)
		(width 0.15494)
		(layer "In15.Cu")
		(net "SSD3_LED_R")
	)
	(segment
		(start 204.532484 -80.549496)
		(end 205.61046 -81.627472)
		(width 0.15494)
		(layer "In15.Cu")
		(net "SSD3_LED_R")
	)
	(segment
		(start 131.988052 -79.843884)
		(end 132.980684 -80.836516)
		(width 0.15494)
		(layer "In15.Cu")
		(net "SSD3_LED_R")
	)
	(segment
		(start 206.223108 -79.595472)
		(end 206.10576 -79.71282)
		(width 0.13208)
		(layer "F.Cu")
		(net "SSD5_LED_R")
	)
	(segment
		(start 205.610206 -79.71282)
		(end 205.108556 -79.71282)
		(width 0.13208)
		(layer "F.Cu")
		(net "SSD5_LED_R")
	)
	(segment
		(start 205.108556 -79.71282)
		(end 204.991208 -79.595472)
		(width 0.13208)
		(layer "F.Cu")
		(net "SSD5_LED_R")
	)
	(segment
		(start 206.10576 -79.71282)
		(end 205.610206 -79.71282)
		(width 0.13208)
		(layer "F.Cu")
		(net "SSD5_LED_R")
	)
	(segment
		(start 167.324024 -27.411934)
		(end 167.324024 -26.319734)
		(width 0.13208)
		(layer "F.Cu")
		(net "SSD5_LED_R")
	)
	(via
		(at 182.457852 -77.539088)
		(size 0.508)
		(drill 0.254)
		(layers "F.Cu" "B.Cu")
		(net "SSD5_LED_R")
	)
	(via
		(at 167.324024 -26.319734)
		(size 0.508)
		(drill 0.254)
		(layers "F.Cu" "B.Cu")
		(net "SSD5_LED_R")
	)
	(via
		(at 205.610206 -79.71282)
		(size 0.508)
		(drill 0.254)
		(layers "F.Cu" "B.Cu")
		(net "SSD5_LED_R")
	)
	(segment
		(start 168.5798 -33.182052)
		(end 168.5798 -27.57551)
		(width 0.15494)
		(layer "In5.Cu")
		(net "SSD5_LED_R")
	)
	(segment
		(start 180.1241 -75.205336)
		(end 180.1241 -44.726352)
		(width 0.15494)
		(layer "In5.Cu")
		(net "SSD5_LED_R")
	)
	(segment
		(start 182.457852 -77.539088)
		(end 180.1241 -75.205336)
		(width 0.15494)
		(layer "In5.Cu")
		(net "SSD5_LED_R")
	)
	(segment
		(start 180.1241 -44.726352)
		(end 168.5798 -33.182052)
		(width 0.15494)
		(layer "In5.Cu")
		(net "SSD5_LED_R")
	)
	(segment
		(start 168.5798 -27.57551)
		(end 167.324024 -26.319734)
		(width 0.15494)
		(layer "In5.Cu")
		(net "SSD5_LED_R")
	)
	(segment
		(start 182.457852 -77.539088)
		(end 195.713858 -77.539088)
		(width 0.15494)
		(layer "In15.Cu")
		(net "SSD5_LED_R")
	)
	(segment
		(start 197.88759 -79.71282)
		(end 205.610206 -79.71282)
		(width 0.15494)
		(layer "In15.Cu")
		(net "SSD5_LED_R")
	)
	(segment
		(start 195.713858 -77.539088)
		(end 197.88759 -79.71282)
		(width 0.15494)
		(layer "In15.Cu")
		(net "SSD5_LED_R")
	)
	(segment
		(start 204.991208 -80.611472)
		(end 205.61046 -80.611472)
		(width 0.13208)
		(layer "F.Cu")
		(net "SSD4_LED_R")
	)
	(segment
		(start 205.61046 -80.611472)
		(end 206.223108 -80.611472)
		(width 0.13208)
		(layer "F.Cu")
		(net "SSD4_LED_R")
	)
	(segment
		(start 141.324076 -27.411934)
		(end 141.324076 -26.319734)
		(width 0.13208)
		(layer "F.Cu")
		(net "SSD4_LED_R")
	)
	(via
		(at 150.5966 -78.707234)
		(size 0.508)
		(drill 0.254)
		(layers "F.Cu" "B.Cu")
		(net "SSD4_LED_R")
	)
	(via
		(at 141.324076 -26.319734)
		(size 0.508)
		(drill 0.254)
		(layers "F.Cu" "B.Cu")
		(net "SSD4_LED_R")
	)
	(via
		(at 205.61046 -80.611472)
		(size 0.508)
		(drill 0.254)
		(layers "F.Cu" "B.Cu")
		(net "SSD4_LED_R")
	)
	(segment
		(start 150.5966 -78.707234)
		(end 154.26944 -75.034394)
		(width 0.15494)
		(layer "In5.Cu")
		(net "SSD4_LED_R")
	)
	(segment
		(start 154.26944 -75.034394)
		(end 154.26944 -44.781216)
		(width 0.15494)
		(layer "In5.Cu")
		(net "SSD4_LED_R")
	)
	(segment
		(start 142.886684 -27.882342)
		(end 141.324076 -26.319734)
		(width 0.15494)
		(layer "In5.Cu")
		(net "SSD4_LED_R")
	)
	(segment
		(start 142.886684 -33.39846)
		(end 142.886684 -27.882342)
		(width 0.15494)
		(layer "In5.Cu")
		(net "SSD4_LED_R")
	)
	(segment
		(start 154.26944 -44.781216)
		(end 142.886684 -33.39846)
		(width 0.15494)
		(layer "In5.Cu")
		(net "SSD4_LED_R")
	)
	(segment
		(start 197.767956 -80.07096)
		(end 197.739 -80.07096)
		(width 0.15494)
		(layer "In15.Cu")
		(net "SSD4_LED_R")
	)
	(segment
		(start 187.724542 -77.897228)
		(end 186.8932 -78.72857)
		(width 0.15494)
		(layer "In15.Cu")
		(net "SSD4_LED_R")
	)
	(segment
		(start 186.8932 -78.72857)
		(end 183.140604 -78.72857)
		(width 0.15494)
		(layer "In15.Cu")
		(net "SSD4_LED_R")
	)
	(segment
		(start 195.565268 -77.897228)
		(end 187.724542 -77.897228)
		(width 0.15494)
		(layer "In15.Cu")
		(net "SSD4_LED_R")
	)
	(segment
		(start 205.210664 -80.211676)
		(end 204.701394 -80.211676)
		(width 0.15494)
		(layer "In15.Cu")
		(net "SSD4_LED_R")
	)
	(segment
		(start 183.119268 -78.707234)
		(end 150.5966 -78.707234)
		(width 0.15494)
		(layer "In15.Cu")
		(net "SSD4_LED_R")
	)
	(segment
		(start 183.140604 -78.72857)
		(end 183.119268 -78.707234)
		(width 0.15494)
		(layer "In15.Cu")
		(net "SSD4_LED_R")
	)
	(segment
		(start 204.681074 -80.191356)
		(end 197.888352 -80.191356)
		(width 0.15494)
		(layer "In15.Cu")
		(net "SSD4_LED_R")
	)
	(segment
		(start 197.739 -80.07096)
		(end 195.565268 -77.897228)
		(width 0.15494)
		(layer "In15.Cu")
		(net "SSD4_LED_R")
	)
	(segment
		(start 197.888352 -80.191356)
		(end 197.767956 -80.07096)
		(width 0.15494)
		(layer "In15.Cu")
		(net "SSD4_LED_R")
	)
	(segment
		(start 205.61046 -80.611472)
		(end 205.210664 -80.211676)
		(width 0.15494)
		(layer "In15.Cu")
		(net "SSD4_LED_R")
	)
	(segment
		(start 204.701394 -80.211676)
		(end 204.681074 -80.191356)
		(width 0.15494)
		(layer "In15.Cu")
		(net "SSD4_LED_R")
	)
	(segment
		(start 204.991208 -77.563472)
		(end 205.61046 -77.563472)
		(width 0.13208)
		(layer "F.Cu")
		(net "SSD7_LED_R")
	)
	(segment
		(start 205.61046 -77.563472)
		(end 206.223108 -77.563472)
		(width 0.13208)
		(layer "F.Cu")
		(net "SSD7_LED_R")
	)
	(segment
		(start 219.32392 -27.411934)
		(end 219.32392 -26.319734)
		(width 0.13208)
		(layer "F.Cu")
		(net "SSD7_LED_R")
	)
	(via
		(at 205.61046 -77.563472)
		(size 0.508)
		(drill 0.254)
		(layers "F.Cu" "B.Cu")
		(net "SSD7_LED_R")
	)
	(via
		(at 219.32392 -26.319734)
		(size 0.508)
		(drill 0.254)
		(layers "F.Cu" "B.Cu")
		(net "SSD7_LED_R")
	)
	(via
		(at 223.294448 -76.801726)
		(size 0.508)
		(drill 0.254)
		(layers "F.Cu" "B.Cu")
		(net "SSD7_LED_R")
	)
	(segment
		(start 224.525078 -73.526142)
		(end 223.7232 -72.724264)
		(width 0.15494)
		(layer "In5.Cu")
		(net "SSD7_LED_R")
	)
	(segment
		(start 224.6122 -63.7032)
		(end 224.6122 -40.7924)
		(width 0.15494)
		(layer "In5.Cu")
		(net "SSD7_LED_R")
	)
	(segment
		(start 219.3798 -35.56)
		(end 219.3798 -31.197296)
		(width 0.15494)
		(layer "In5.Cu")
		(net "SSD7_LED_R")
	)
	(segment
		(start 223.7232 -64.5922)
		(end 224.6122 -63.7032)
		(width 0.15494)
		(layer "In5.Cu")
		(net "SSD7_LED_R")
	)
	(segment
		(start 219.3798 -31.197296)
		(end 220.401134 -30.175962)
		(width 0.15494)
		(layer "In5.Cu")
		(net "SSD7_LED_R")
	)
	(segment
		(start 220.401134 -30.175962)
		(end 220.401134 -27.396948)
		(width 0.15494)
		(layer "In5.Cu")
		(net "SSD7_LED_R")
	)
	(segment
		(start 223.294448 -76.801726)
		(end 224.525078 -75.571096)
		(width 0.15494)
		(layer "In5.Cu")
		(net "SSD7_LED_R")
	)
	(segment
		(start 220.401134 -27.396948)
		(end 219.32392 -26.319734)
		(width 0.15494)
		(layer "In5.Cu")
		(net "SSD7_LED_R")
	)
	(segment
		(start 224.525078 -75.571096)
		(end 224.525078 -73.526142)
		(width 0.15494)
		(layer "In5.Cu")
		(net "SSD7_LED_R")
	)
	(segment
		(start 224.6122 -40.7924)
		(end 219.3798 -35.56)
		(width 0.15494)
		(layer "In5.Cu")
		(net "SSD7_LED_R")
	)
	(segment
		(start 223.7232 -72.724264)
		(end 223.7232 -64.5922)
		(width 0.15494)
		(layer "In5.Cu")
		(net "SSD7_LED_R")
	)
	(segment
		(start 207.450182 -75.72375)
		(end 205.61046 -77.563472)
		(width 0.15494)
		(layer "In15.Cu")
		(net "SSD7_LED_R")
	)
	(segment
		(start 222.216472 -75.72375)
		(end 207.450182 -75.72375)
		(width 0.15494)
		(layer "In15.Cu")
		(net "SSD7_LED_R")
	)
	(segment
		(start 223.294448 -76.801726)
		(end 222.216472 -75.72375)
		(width 0.15494)
		(layer "In15.Cu")
		(net "SSD7_LED_R")
	)
	(segment
		(start 205.61046 -82.643472)
		(end 206.223108 -82.643472)
		(width 0.13208)
		(layer "F.Cu")
		(net "SSD2_LED_R")
	)
	(segment
		(start 77.223874 -27.411934)
		(end 77.223874 -26.319734)
		(width 0.13208)
		(layer "F.Cu")
		(net "SSD2_LED_R")
	)
	(segment
		(start 204.991208 -82.643472)
		(end 205.61046 -82.643472)
		(width 0.13208)
		(layer "F.Cu")
		(net "SSD2_LED_R")
	)
	(via
		(at 91.281504 -73.810368)
		(size 0.508)
		(drill 0.254)
		(layers "F.Cu" "B.Cu")
		(net "SSD2_LED_R")
	)
	(via
		(at 205.61046 -82.643472)
		(size 0.508)
		(drill 0.254)
		(layers "F.Cu" "B.Cu")
		(net "SSD2_LED_R")
	)
	(via
		(at 77.223874 -26.319734)
		(size 0.508)
		(drill 0.254)
		(layers "F.Cu" "B.Cu")
		(net "SSD2_LED_R")
	)
	(segment
		(start 90.8812 -73.410064)
		(end 91.281504 -73.810368)
		(width 0.15494)
		(layer "In5.Cu")
		(net "SSD2_LED_R")
	)
	(segment
		(start 78.786482 -27.882342)
		(end 78.786482 -33.39846)
		(width 0.15494)
		(layer "In5.Cu")
		(net "SSD2_LED_R")
	)
	(segment
		(start 77.223874 -26.319734)
		(end 78.786482 -27.882342)
		(width 0.15494)
		(layer "In5.Cu")
		(net "SSD2_LED_R")
	)
	(segment
		(start 90.8812 -45.493178)
		(end 90.8812 -73.410064)
		(width 0.15494)
		(layer "In5.Cu")
		(net "SSD2_LED_R")
	)
	(segment
		(start 78.786482 -33.39846)
		(end 90.8812 -45.493178)
		(width 0.15494)
		(layer "In5.Cu")
		(net "SSD2_LED_R")
	)
	(segment
		(start 122.741182 -81.194656)
		(end 204.161644 -81.194656)
		(width 0.15494)
		(layer "In15.Cu")
		(net "SSD2_LED_R")
	)
	(segment
		(start 104.307894 -77.872336)
		(end 105.963466 -79.527908)
		(width 0.15494)
		(layer "In15.Cu")
		(net "SSD2_LED_R")
	)
	(segment
		(start 95.343472 -77.872336)
		(end 104.307894 -77.872336)
		(width 0.15494)
		(layer "In15.Cu")
		(net "SSD2_LED_R")
	)
	(segment
		(start 204.161644 -81.194656)
		(end 205.61046 -82.643472)
		(width 0.15494)
		(layer "In15.Cu")
		(net "SSD2_LED_R")
	)
	(segment
		(start 105.963466 -79.527908)
		(end 121.074434 -79.527908)
		(width 0.15494)
		(layer "In15.Cu")
		(net "SSD2_LED_R")
	)
	(segment
		(start 121.074434 -79.527908)
		(end 122.741182 -81.194656)
		(width 0.15494)
		(layer "In15.Cu")
		(net "SSD2_LED_R")
	)
	(segment
		(start 91.281504 -73.810368)
		(end 95.343472 -77.872336)
		(width 0.15494)
		(layer "In15.Cu")
		(net "SSD2_LED_R")
	)
	(segment
		(start 137.643362 -190.232792)
		(end 137.643362 -188.939678)
		(width 0.13208)
		(layer "F.Cu")
		(net "RST_FT4232_R_N")
	)
	(segment
		(start 96.15932 -201.509376)
		(end 96.131888 -201.509376)
		(width 0.13208)
		(layer "F.Cu")
		(net "RST_FT4232_R_N")
	)
	(segment
		(start 445.54775 -237.5154)
		(end 443.6364 -237.5154)
		(width 0.13208)
		(layer "F.Cu")
		(net "RST_FT4232_R_N")
	)
	(segment
		(start 139.620244 -186.962796)
		(end 142.157196 -186.962796)
		(width 0.13208)
		(layer "F.Cu")
		(net "RST_FT4232_R_N")
	)
	(segment
		(start 386.569966 -226.876864)
		(end 388.11835 -228.425248)
		(width 0.13208)
		(layer "F.Cu")
		(net "RST_FT4232_R_N")
	)
	(segment
		(start 388.11835 -228.425248)
		(end 388.11835 -229.38994)
		(width 0.13208)
		(layer "F.Cu")
		(net "RST_FT4232_R_N")
	)
	(segment
		(start 119.2022 -203.073)
		(end 110.988856 -203.073)
		(width 0.13208)
		(layer "F.Cu")
		(net "RST_FT4232_R_N")
	)
	(segment
		(start 138.945366 -190.718948)
		(end 138.129518 -190.718948)
		(width 0.13208)
		(layer "F.Cu")
		(net "RST_FT4232_R_N")
	)
	(segment
		(start 109.871256 -204.1906)
		(end 98.840544 -204.1906)
		(width 0.13208)
		(layer "F.Cu")
		(net "RST_FT4232_R_N")
	)
	(segment
		(start 142.305024 -197.129146)
		(end 142.305024 -194.078606)
		(width 0.13208)
		(layer "F.Cu")
		(net "RST_FT4232_R_N")
	)
	(segment
		(start 137.643362 -188.939678)
		(end 139.620244 -186.962796)
		(width 0.13208)
		(layer "F.Cu")
		(net "RST_FT4232_R_N")
	)
	(segment
		(start 388.11835 -229.38994)
		(end 388.03199 -229.4763)
		(width 0.13208)
		(layer "F.Cu")
		(net "RST_FT4232_R_N")
	)
	(segment
		(start 98.840544 -204.1906)
		(end 96.15932 -201.509376)
		(width 0.13208)
		(layer "F.Cu")
		(net "RST_FT4232_R_N")
	)
	(segment
		(start 388.03199 -229.4763)
		(end 387.35381 -229.4763)
		(width 0.13208)
		(layer "F.Cu")
		(net "RST_FT4232_R_N")
	)
	(segment
		(start 142.157196 -186.962796)
		(end 143.0528 -187.8584)
		(width 0.13208)
		(layer "F.Cu")
		(net "RST_FT4232_R_N")
	)
	(segment
		(start 374.392444 -218.910154)
		(end 379.924564 -218.910154)
		(width 0.13208)
		(layer "F.Cu")
		(net "RST_FT4232_R_N")
	)
	(segment
		(start 374.266206 -218.783916)
		(end 374.392444 -218.910154)
		(width 0.13208)
		(layer "F.Cu")
		(net "RST_FT4232_R_N")
	)
	(segment
		(start 110.988856 -203.073)
		(end 109.871256 -204.1906)
		(width 0.13208)
		(layer "F.Cu")
		(net "RST_FT4232_R_N")
	)
	(segment
		(start 386.569966 -225.555556)
		(end 386.569966 -226.876864)
		(width 0.13208)
		(layer "F.Cu")
		(net "RST_FT4232_R_N")
	)
	(segment
		(start 138.129518 -190.718948)
		(end 137.643362 -190.232792)
		(width 0.13208)
		(layer "F.Cu")
		(net "RST_FT4232_R_N")
	)
	(segment
		(start 142.305024 -194.078606)
		(end 138.945366 -190.718948)
		(width 0.13208)
		(layer "F.Cu")
		(net "RST_FT4232_R_N")
	)
	(segment
		(start 379.924564 -218.910154)
		(end 386.569966 -225.555556)
		(width 0.13208)
		(layer "F.Cu")
		(net "RST_FT4232_R_N")
	)
	(via
		(at 374.266206 -218.783916)
		(size 0.508)
		(drill 0.254)
		(layers "F.Cu" "B.Cu")
		(net "RST_FT4232_R_N")
	)
	(via
		(at 350.882712 -206.320898)
		(size 0.508)
		(drill 0.254)
		(layers "F.Cu" "B.Cu")
		(net "RST_FT4232_R_N")
	)
	(via
		(at 143.0528 -187.8584)
		(size 0.508)
		(drill 0.254)
		(layers "F.Cu" "B.Cu")
		(net "RST_FT4232_R_N")
	)
	(via
		(at 443.6364 -237.5154)
		(size 0.508)
		(drill 0.254)
		(layers "F.Cu" "B.Cu")
		(net "RST_FT4232_R_N")
	)
	(via
		(at 119.2022 -203.073)
		(size 0.508)
		(drill 0.254)
		(layers "F.Cu" "B.Cu")
		(net "RST_FT4232_R_N")
	)
	(via
		(at 376.007122 -232.353104)
		(size 0.508)
		(drill 0.254)
		(layers "F.Cu" "B.Cu")
		(net "RST_FT4232_R_N")
	)
	(segment
		(start 364.505494 -218.624404)
		(end 360.390948 -214.509858)
		(width 0.13208)
		(layer "B.Cu")
		(net "RST_FT4232_R_N")
	)
	(segment
		(start 131.500626 -192.281048)
		(end 131.618736 -192.162938)
		(width 0.13208)
		(layer "B.Cu")
		(net "RST_FT4232_R_N")
	)
	(segment
		(start 131.500626 -192.965832)
		(end 131.500626 -192.281048)
		(width 0.13208)
		(layer "B.Cu")
		(net "RST_FT4232_R_N")
	)
	(segment
		(start 134.393178 -192.162938)
		(end 134.963916 -191.5922)
		(width 0.13208)
		(layer "B.Cu")
		(net "RST_FT4232_R_N")
	)
	(segment
		(start 351.197418 -207.339184)
		(end 351.197418 -206.635604)
		(width 0.13208)
		(layer "B.Cu")
		(net "RST_FT4232_R_N")
	)
	(segment
		(start 131.083558 -193.3829)
		(end 131.500626 -192.965832)
		(width 0.13208)
		(layer "B.Cu")
		(net "RST_FT4232_R_N")
	)
	(segment
		(start 131.618736 -192.162938)
		(end 134.393178 -192.162938)
		(width 0.13208)
		(layer "B.Cu")
		(net "RST_FT4232_R_N")
	)
	(segment
		(start 374.266206 -218.783916)
		(end 374.106694 -218.624404)
		(width 0.13208)
		(layer "B.Cu")
		(net "RST_FT4232_R_N")
	)
	(segment
		(start 137.943336 -191.5922)
		(end 140.985494 -188.550042)
		(width 0.13208)
		(layer "B.Cu")
		(net "RST_FT4232_R_N")
	)
	(segment
		(start 360.390948 -206.248)
		(end 359.17378 -205.030832)
		(width 0.13208)
		(layer "B.Cu")
		(net "RST_FT4232_R_N")
	)
	(segment
		(start 129.619502 -193.3829)
		(end 131.083558 -193.3829)
		(width 0.13208)
		(layer "B.Cu")
		(net "RST_FT4232_R_N")
	)
	(segment
		(start 374.106694 -218.624404)
		(end 364.505494 -218.624404)
		(width 0.13208)
		(layer "B.Cu")
		(net "RST_FT4232_R_N")
	)
	(segment
		(start 351.197418 -206.635604)
		(end 350.882712 -206.320898)
		(width 0.13208)
		(layer "B.Cu")
		(net "RST_FT4232_R_N")
	)
	(segment
		(start 129.084324 -196.902832)
		(end 129.084324 -193.918078)
		(width 0.13208)
		(layer "B.Cu")
		(net "RST_FT4232_R_N")
	)
	(segment
		(start 359.17378 -205.030832)
		(end 352.172778 -205.030832)
		(width 0.13208)
		(layer "B.Cu")
		(net "RST_FT4232_R_N")
	)
	(segment
		(start 121.728738 -200.546462)
		(end 128.065784 -197.921372)
		(width 0.13208)
		(layer "B.Cu")
		(net "RST_FT4232_R_N")
	)
	(segment
		(start 129.084324 -193.918078)
		(end 129.619502 -193.3829)
		(width 0.13208)
		(layer "B.Cu")
		(net "RST_FT4232_R_N")
	)
	(segment
		(start 119.2022 -203.073)
		(end 121.728738 -200.546462)
		(width 0.13208)
		(layer "B.Cu")
		(net "RST_FT4232_R_N")
	)
	(segment
		(start 142.361158 -188.550042)
		(end 143.0528 -187.8584)
		(width 0.13208)
		(layer "B.Cu")
		(net "RST_FT4232_R_N")
	)
	(segment
		(start 352.172778 -205.030832)
		(end 350.882712 -206.320898)
		(width 0.13208)
		(layer "B.Cu")
		(net "RST_FT4232_R_N")
	)
	(segment
		(start 140.985494 -188.550042)
		(end 142.361158 -188.550042)
		(width 0.13208)
		(layer "B.Cu")
		(net "RST_FT4232_R_N")
	)
	(segment
		(start 360.390948 -214.509858)
		(end 360.390948 -206.248)
		(width 0.13208)
		(layer "B.Cu")
		(net "RST_FT4232_R_N")
	)
	(segment
		(start 134.963916 -191.5922)
		(end 137.943336 -191.5922)
		(width 0.13208)
		(layer "B.Cu")
		(net "RST_FT4232_R_N")
	)
	(segment
		(start 128.065784 -197.921372)
		(end 129.084324 -196.902832)
		(width 0.13208)
		(layer "B.Cu")
		(net "RST_FT4232_R_N")
	)
	(segment
		(start 376.007122 -232.353104)
		(end 375.569734 -231.915716)
		(width 0.15494)
		(layer "In5.Cu")
		(net "RST_FT4232_R_N")
	)
	(segment
		(start 375.569734 -231.915716)
		(end 375.569734 -220.087444)
		(width 0.15494)
		(layer "In5.Cu")
		(net "RST_FT4232_R_N")
	)
	(segment
		(start 375.569734 -220.087444)
		(end 374.266206 -218.783916)
		(width 0.15494)
		(layer "In5.Cu")
		(net "RST_FT4232_R_N")
	)
	(segment
		(start 231.177084 -180.988462)
		(end 229.209346 -180.988462)
		(width 0.15494)
		(layer "In13.Cu")
		(net "RST_FT4232_R_N")
	)
	(segment
		(start 376.007122 -232.353104)
		(end 383.371852 -232.353104)
		(width 0.15494)
		(layer "In13.Cu")
		(net "RST_FT4232_R_N")
	)
	(segment
		(start 251.157994 -180.311806)
		(end 251.15774 -180.31206)
		(width 0.15494)
		(layer "In13.Cu")
		(net "RST_FT4232_R_N")
	)
	(segment
		(start 220.974412 -185.044334)
		(end 211.866734 -185.044334)
		(width 0.15494)
		(layer "In13.Cu")
		(net "RST_FT4232_R_N")
	)
	(segment
		(start 227.840032 -182.357776)
		(end 223.66097 -182.357776)
		(width 0.15494)
		(layer "In13.Cu")
		(net "RST_FT4232_R_N")
	)
	(segment
		(start 423.773346 -237.5154)
		(end 443.6364 -237.5154)
		(width 0.15494)
		(layer "In13.Cu")
		(net "RST_FT4232_R_N")
	)
	(segment
		(start 231.888538 -180.277008)
		(end 231.177084 -180.988462)
		(width 0.15494)
		(layer "In13.Cu")
		(net "RST_FT4232_R_N")
	)
	(segment
		(start 326.41794 -201.12101)
		(end 322.63715 -204.9018)
		(width 0.15494)
		(layer "In13.Cu")
		(net "RST_FT4232_R_N")
	)
	(segment
		(start 251.15774 -180.31206)
		(end 250.89866 -180.31206)
		(width 0.15494)
		(layer "In13.Cu")
		(net "RST_FT4232_R_N")
	)
	(segment
		(start 209.1944 -182.372)
		(end 202.692 -182.372)
		(width 0.15494)
		(layer "In13.Cu")
		(net "RST_FT4232_R_N")
	)
	(segment
		(start 418.794946 -232.537)
		(end 423.773346 -237.5154)
		(width 0.15494)
		(layer "In13.Cu")
		(net "RST_FT4232_R_N")
	)
	(segment
		(start 147.520914 -189.253114)
		(end 146.1262 -187.8584)
		(width 0.15494)
		(layer "In13.Cu")
		(net "RST_FT4232_R_N")
	)
	(segment
		(start 350.07169 -205.062836)
		(end 335.5594 -205.062836)
		(width 0.15494)
		(layer "In13.Cu")
		(net "RST_FT4232_R_N")
	)
	(segment
		(start 250.863608 -180.277008)
		(end 231.888538 -180.277008)
		(width 0.15494)
		(layer "In13.Cu")
		(net "RST_FT4232_R_N")
	)
	(segment
		(start 322.63715 -204.9018)
		(end 299.044106 -204.9018)
		(width 0.15494)
		(layer "In13.Cu")
		(net "RST_FT4232_R_N")
	)
	(segment
		(start 196.707252 -188.356748)
		(end 187.448444 -188.356748)
		(width 0.15494)
		(layer "In13.Cu")
		(net "RST_FT4232_R_N")
	)
	(segment
		(start 263.938512 -188.058806)
		(end 259.285486 -188.058806)
		(width 0.15494)
		(layer "In13.Cu")
		(net "RST_FT4232_R_N")
	)
	(segment
		(start 335.05013 -202.20813)
		(end 333.96301 -201.12101)
		(width 0.15494)
		(layer "In13.Cu")
		(net "RST_FT4232_R_N")
	)
	(segment
		(start 251.538486 -180.311806)
		(end 251.157994 -180.311806)
		(width 0.15494)
		(layer "In13.Cu")
		(net "RST_FT4232_R_N")
	)
	(segment
		(start 250.89866 -180.31206)
		(end 250.863608 -180.277008)
		(width 0.15494)
		(layer "In13.Cu")
		(net "RST_FT4232_R_N")
	)
	(segment
		(start 280.790904 -204.911198)
		(end 263.938512 -188.058806)
		(width 0.15494)
		(layer "In13.Cu")
		(net "RST_FT4232_R_N")
	)
	(segment
		(start 415.3154 -232.537)
		(end 418.794946 -232.537)
		(width 0.15494)
		(layer "In13.Cu")
		(net "RST_FT4232_R_N")
	)
	(segment
		(start 383.371852 -232.353104)
		(end 384.089148 -233.0704)
		(width 0.15494)
		(layer "In13.Cu")
		(net "RST_FT4232_R_N")
	)
	(segment
		(start 335.5594 -205.0542)
		(end 335.05013 -204.54493)
		(width 0.15494)
		(layer "In13.Cu")
		(net "RST_FT4232_R_N")
	)
	(segment
		(start 229.209346 -180.988462)
		(end 227.840032 -182.357776)
		(width 0.15494)
		(layer "In13.Cu")
		(net "RST_FT4232_R_N")
	)
	(segment
		(start 202.692 -182.372)
		(end 196.707252 -188.356748)
		(width 0.15494)
		(layer "In13.Cu")
		(net "RST_FT4232_R_N")
	)
	(segment
		(start 146.1262 -187.8584)
		(end 143.0528 -187.8584)
		(width 0.15494)
		(layer "In13.Cu")
		(net "RST_FT4232_R_N")
	)
	(segment
		(start 414.782 -233.0704)
		(end 415.3154 -232.537)
		(width 0.15494)
		(layer "In13.Cu")
		(net "RST_FT4232_R_N")
	)
	(segment
		(start 350.882712 -206.320898)
		(end 350.882712 -205.873858)
		(width 0.15494)
		(layer "In13.Cu")
		(net "RST_FT4232_R_N")
	)
	(segment
		(start 223.66097 -182.357776)
		(end 220.974412 -185.044334)
		(width 0.15494)
		(layer "In13.Cu")
		(net "RST_FT4232_R_N")
	)
	(segment
		(start 333.96301 -201.12101)
		(end 326.41794 -201.12101)
		(width 0.15494)
		(layer "In13.Cu")
		(net "RST_FT4232_R_N")
	)
	(segment
		(start 335.05013 -204.54493)
		(end 335.05013 -202.20813)
		(width 0.15494)
		(layer "In13.Cu")
		(net "RST_FT4232_R_N")
	)
	(segment
		(start 384.089148 -233.0704)
		(end 414.782 -233.0704)
		(width 0.15494)
		(layer "In13.Cu")
		(net "RST_FT4232_R_N")
	)
	(segment
		(start 335.5594 -205.062836)
		(end 335.5594 -205.0542)
		(width 0.15494)
		(layer "In13.Cu")
		(net "RST_FT4232_R_N")
	)
	(segment
		(start 299.044106 -204.9018)
		(end 299.034708 -204.911198)
		(width 0.15494)
		(layer "In13.Cu")
		(net "RST_FT4232_R_N")
	)
	(segment
		(start 350.882712 -205.873858)
		(end 350.07169 -205.062836)
		(width 0.15494)
		(layer "In13.Cu")
		(net "RST_FT4232_R_N")
	)
	(segment
		(start 259.285486 -188.058806)
		(end 251.538486 -180.311806)
		(width 0.15494)
		(layer "In13.Cu")
		(net "RST_FT4232_R_N")
	)
	(segment
		(start 186.552078 -189.253114)
		(end 147.520914 -189.253114)
		(width 0.15494)
		(layer "In13.Cu")
		(net "RST_FT4232_R_N")
	)
	(segment
		(start 211.866734 -185.044334)
		(end 209.1944 -182.372)
		(width 0.15494)
		(layer "In13.Cu")
		(net "RST_FT4232_R_N")
	)
	(segment
		(start 299.034708 -204.911198)
		(end 280.790904 -204.911198)
		(width 0.15494)
		(layer "In13.Cu")
		(net "RST_FT4232_R_N")
	)
	(segment
		(start 187.448444 -188.356748)
		(end 186.552078 -189.253114)
		(width 0.15494)
		(layer "In13.Cu")
		(net "RST_FT4232_R_N")
	)
	(segment
		(start 1.846834 -16.936974)
		(end 1.846834 -18.029174)
		(width 0.13208)
		(layer "F.Cu")
		(net "SSD0_LED_R")
	)
	(segment
		(start 206.223108 -84.675472)
		(end 205.61046 -84.675472)
		(width 0.13208)
		(layer "F.Cu")
		(net "SSD0_LED_R")
	)
	(segment
		(start 205.61046 -84.675472)
		(end 204.991208 -84.675472)
		(width 0.13208)
		(layer "F.Cu")
		(net "SSD0_LED_R")
	)
	(via
		(at 205.61046 -84.675472)
		(size 0.508)
		(drill 0.254)
		(layers "F.Cu" "B.Cu")
		(net "SSD0_LED_R")
	)
	(via
		(at 1.846834 -18.029174)
		(size 0.508)
		(drill 0.254)
		(layers "F.Cu" "B.Cu")
		(net "SSD0_LED_R")
	)
	(via
		(at 41.781984 -78.58887)
		(size 0.508)
		(drill 0.254)
		(layers "F.Cu" "B.Cu")
		(net "SSD0_LED_R")
	)
	(segment
		(start 38.4556 -75.262486)
		(end 38.4556 -46.000162)
		(width 0.15494)
		(layer "In5.Cu")
		(net "SSD0_LED_R")
	)
	(segment
		(start 18.918174 -18.029174)
		(end 1.846834 -18.029174)
		(width 0.15494)
		(layer "In5.Cu")
		(net "SSD0_LED_R")
	)
	(segment
		(start 26.2636 -33.808162)
		(end 26.2636 -28.188412)
		(width 0.15494)
		(layer "In5.Cu")
		(net "SSD0_LED_R")
	)
	(segment
		(start 20.193 -19.304)
		(end 18.918174 -18.029174)
		(width 0.15494)
		(layer "In5.Cu")
		(net "SSD0_LED_R")
	)
	(segment
		(start 41.781984 -78.58887)
		(end 38.4556 -75.262486)
		(width 0.15494)
		(layer "In5.Cu")
		(net "SSD0_LED_R")
	)
	(segment
		(start 38.4556 -46.000162)
		(end 26.2636 -33.808162)
		(width 0.15494)
		(layer "In5.Cu")
		(net "SSD0_LED_R")
	)
	(segment
		(start 26.2636 -28.188412)
		(end 20.193 -22.117812)
		(width 0.15494)
		(layer "In5.Cu")
		(net "SSD0_LED_R")
	)
	(segment
		(start 20.193 -22.117812)
		(end 20.193 -19.304)
		(width 0.15494)
		(layer "In5.Cu")
		(net "SSD0_LED_R")
	)
	(segment
		(start 196.397118 -81.943702)
		(end 199.612758 -85.159342)
		(width 0.15494)
		(layer "In15.Cu")
		(net "SSD0_LED_R")
	)
	(segment
		(start 41.781984 -78.58887)
		(end 63.45047 -78.58887)
		(width 0.15494)
		(layer "In15.Cu")
		(net "SSD0_LED_R")
	)
	(segment
		(start 194.535298 -81.943702)
		(end 196.397118 -81.943702)
		(width 0.15494)
		(layer "In15.Cu")
		(net "SSD0_LED_R")
	)
	(segment
		(start 70.681342 -79.752444)
		(end 71.735696 -78.69809)
		(width 0.15494)
		(layer "In15.Cu")
		(net "SSD0_LED_R")
	)
	(segment
		(start 123.565666 -83.0326)
		(end 193.4464 -83.0326)
		(width 0.15494)
		(layer "In15.Cu")
		(net "SSD0_LED_R")
	)
	(segment
		(start 193.4464 -83.0326)
		(end 194.535298 -81.943702)
		(width 0.15494)
		(layer "In15.Cu")
		(net "SSD0_LED_R")
	)
	(segment
		(start 199.612758 -85.159342)
		(end 205.12659 -85.159342)
		(width 0.15494)
		(layer "In15.Cu")
		(net "SSD0_LED_R")
	)
	(segment
		(start 205.12659 -85.159342)
		(end 205.61046 -84.675472)
		(width 0.15494)
		(layer "In15.Cu")
		(net "SSD0_LED_R")
	)
	(segment
		(start 104.120188 -78.69809)
		(end 105.745026 -80.322928)
		(width 0.15494)
		(layer "In15.Cu")
		(net "SSD0_LED_R")
	)
	(segment
		(start 120.855994 -80.322928)
		(end 123.565666 -83.0326)
		(width 0.15494)
		(layer "In15.Cu")
		(net "SSD0_LED_R")
	)
	(segment
		(start 105.745026 -80.322928)
		(end 120.855994 -80.322928)
		(width 0.15494)
		(layer "In15.Cu")
		(net "SSD0_LED_R")
	)
	(segment
		(start 64.614044 -79.752444)
		(end 70.681342 -79.752444)
		(width 0.15494)
		(layer "In15.Cu")
		(net "SSD0_LED_R")
	)
	(segment
		(start 63.45047 -78.58887)
		(end 64.614044 -79.752444)
		(width 0.15494)
		(layer "In15.Cu")
		(net "SSD0_LED_R")
	)
	(segment
		(start 71.735696 -78.69809)
		(end 104.120188 -78.69809)
		(width 0.15494)
		(layer "In15.Cu")
		(net "SSD0_LED_R")
	)
	(segment
		(start 349.293942 -212.786976)
		(end 349.693738 -212.38718)
		(width 0.13208)
		(layer "F.Cu")
		(net "RST_FT4232_N")
	)
	(via
		(at 349.693738 -212.38718)
		(size 0.4572)
		(drill 0.254)
		(layers "F.Cu" "B.Cu")
		(net "RST_FT4232_N")
	)
	(via
		(at 350.896174 -209.65541)
		(size 0.6604)
		(drill 0.3302)
		(layers "F.Cu" "B.Cu")
		(net "RST_FT4232_N")
	)
	(segment
		(start 349.693738 -212.38718)
		(end 349.693738 -210.857846)
		(width 0.13208)
		(layer "B.Cu")
		(net "RST_FT4232_N")
	)
	(segment
		(start 350.896174 -209.65541)
		(end 351.197418 -209.354166)
		(width 0.13208)
		(layer "B.Cu")
		(net "RST_FT4232_N")
	)
	(segment
		(start 351.197418 -209.354166)
		(end 351.197418 -208.139284)
		(width 0.13208)
		(layer "B.Cu")
		(net "RST_FT4232_N")
	)
	(segment
		(start 349.693738 -210.857846)
		(end 350.896174 -209.65541)
		(width 0.13208)
		(layer "B.Cu")
		(net "RST_FT4232_N")
	)
	(segment
		(start 204.991208 -83.659472)
		(end 205.268322 -83.936586)
		(width 0.13208)
		(layer "F.Cu")
		(net "SSD1_LED_R")
	)
	(segment
		(start 205.268322 -83.936586)
		(end 205.602078 -83.936586)
		(width 0.13208)
		(layer "F.Cu")
		(net "SSD1_LED_R")
	)
	(segment
		(start 205.945994 -83.936586)
		(end 206.223108 -83.659472)
		(width 0.13208)
		(layer "F.Cu")
		(net "SSD1_LED_R")
	)
	(segment
		(start 205.602078 -83.936586)
		(end 205.945994 -83.936586)
		(width 0.13208)
		(layer "F.Cu")
		(net "SSD1_LED_R")
	)
	(segment
		(start 51.223926 -27.411934)
		(end 51.223926 -26.319734)
		(width 0.13208)
		(layer "F.Cu")
		(net "SSD1_LED_R")
	)
	(via
		(at 65.530222 -78.230476)
		(size 0.508)
		(drill 0.254)
		(layers "F.Cu" "B.Cu")
		(net "SSD1_LED_R")
	)
	(via
		(at 51.223926 -26.319734)
		(size 0.508)
		(drill 0.254)
		(layers "F.Cu" "B.Cu")
		(net "SSD1_LED_R")
	)
	(via
		(at 205.602078 -83.936586)
		(size 0.508)
		(drill 0.254)
		(layers "F.Cu" "B.Cu")
		(net "SSD1_LED_R")
	)
	(segment
		(start 64.3128 -75.677014)
		(end 64.3128 -45.052742)
		(width 0.15494)
		(layer "In5.Cu")
		(net "SSD1_LED_R")
	)
	(segment
		(start 65.530222 -76.894436)
		(end 64.3128 -75.677014)
		(width 0.15494)
		(layer "In5.Cu")
		(net "SSD1_LED_R")
	)
	(segment
		(start 52.786534 -27.882342)
		(end 51.223926 -26.319734)
		(width 0.15494)
		(layer "In5.Cu")
		(net "SSD1_LED_R")
	)
	(segment
		(start 64.3128 -45.052742)
		(end 52.786534 -33.526476)
		(width 0.15494)
		(layer "In5.Cu")
		(net "SSD1_LED_R")
	)
	(segment
		(start 52.786534 -33.526476)
		(end 52.786534 -27.882342)
		(width 0.15494)
		(layer "In5.Cu")
		(net "SSD1_LED_R")
	)
	(segment
		(start 65.530222 -78.230476)
		(end 65.530222 -76.894436)
		(width 0.15494)
		(layer "In5.Cu")
		(net "SSD1_LED_R")
	)
	(segment
		(start 122.592592 -81.552796)
		(end 196.512942 -81.552796)
		(width 0.15494)
		(layer "In15.Cu")
		(net "SSD1_LED_R")
	)
	(segment
		(start 104.159304 -78.230476)
		(end 105.814876 -79.886048)
		(width 0.15494)
		(layer "In15.Cu")
		(net "SSD1_LED_R")
	)
	(segment
		(start 120.925844 -79.886048)
		(end 122.592592 -81.552796)
		(width 0.15494)
		(layer "In15.Cu")
		(net "SSD1_LED_R")
	)
	(segment
		(start 105.814876 -79.886048)
		(end 120.925844 -79.886048)
		(width 0.15494)
		(layer "In15.Cu")
		(net "SSD1_LED_R")
	)
	(segment
		(start 65.530222 -78.230476)
		(end 104.159304 -78.230476)
		(width 0.15494)
		(layer "In15.Cu")
		(net "SSD1_LED_R")
	)
	(segment
		(start 198.896732 -83.936586)
		(end 205.602078 -83.936586)
		(width 0.15494)
		(layer "In15.Cu")
		(net "SSD1_LED_R")
	)
	(segment
		(start 196.512942 -81.552796)
		(end 198.896732 -83.936586)
		(width 0.15494)
		(layer "In15.Cu")
		(net "SSD1_LED_R")
	)
	(segment
		(start 57.66435 -139.6238)
		(end 56.987948 -140.300202)
		(width 0.13208)
		(layer "F.Cu")
		(net "RST_SMB_NIC0_MUX_ISO_R_N")
	)
	(segment
		(start 52.209192 -141.36497)
		(end 50.64252 -141.36497)
		(width 0.13208)
		(layer "F.Cu")
		(net "RST_SMB_NIC0_MUX_ISO_R_N")
	)
	(segment
		(start 56.987948 -140.300202)
		(end 55.81269 -140.300202)
		(width 0.13208)
		(layer "F.Cu")
		(net "RST_SMB_NIC0_MUX_ISO_R_N")
	)
	(segment
		(start 55.245 -140.867892)
		(end 54.304438 -140.867892)
		(width 0.13208)
		(layer "F.Cu")
		(net "RST_SMB_NIC0_MUX_ISO_R_N")
	)
	(segment
		(start 52.70627 -140.867892)
		(end 52.209192 -141.36497)
		(width 0.13208)
		(layer "F.Cu")
		(net "RST_SMB_NIC0_MUX_ISO_R_N")
	)
	(segment
		(start 55.81269 -140.300202)
		(end 55.245 -140.867892)
		(width 0.13208)
		(layer "F.Cu")
		(net "RST_SMB_NIC0_MUX_ISO_R_N")
	)
	(segment
		(start 54.304438 -140.867892)
		(end 52.70627 -140.867892)
		(width 0.13208)
		(layer "F.Cu")
		(net "RST_SMB_NIC0_MUX_ISO_R_N")
	)
	(via
		(at 54.304438 -140.867892)
		(size 0.762)
		(drill 0.381)
		(layers "F.Cu" "B.Cu")
		(net "RST_SMB_NIC0_MUX_ISO_R_N")
	)
	(segment
		(start 183.987948 -128.201674)
		(end 183.350916 -128.201674)
		(width 0.13208)
		(layer "F.Cu")
		(net "RST_SMB_NIC_MUX_R_N")
	)
	(segment
		(start 222.160846 -138.505184)
		(end 212.353144 -128.697482)
		(width 0.13208)
		(layer "F.Cu")
		(net "RST_SMB_NIC_MUX_R_N")
	)
	(segment
		(start 212.353144 -128.697482)
		(end 211.650326 -128.697482)
		(width 0.13208)
		(layer "F.Cu")
		(net "RST_SMB_NIC_MUX_R_N")
	)
	(segment
		(start 181.664102 -128.697482)
		(end 175.741584 -134.62)
		(width 0.13208)
		(layer "F.Cu")
		(net "RST_SMB_NIC_MUX_R_N")
	)
	(segment
		(start 175.741584 -134.62)
		(end 173.376844 -134.62)
		(width 0.13208)
		(layer "F.Cu")
		(net "RST_SMB_NIC_MUX_R_N")
	)
	(segment
		(start 224.514664 -204.04201)
		(end 224.514664 -203.40701)
		(width 0.13208)
		(layer "F.Cu")
		(net "RST_SMB_NIC_MUX_R_N")
	)
	(segment
		(start 182.855108 -128.697482)
		(end 181.664102 -128.697482)
		(width 0.13208)
		(layer "F.Cu")
		(net "RST_SMB_NIC_MUX_R_N")
	)
	(segment
		(start 183.350916 -128.201674)
		(end 182.855108 -128.697482)
		(width 0.13208)
		(layer "F.Cu")
		(net "RST_SMB_NIC_MUX_R_N")
	)
	(via
		(at 64.646048 -111.334042)
		(size 0.508)
		(drill 0.254)
		(layers "F.Cu" "B.Cu")
		(net "RST_SMB_NIC_MUX_R_N")
	)
	(via
		(at 180.745892 -111.334042)
		(size 0.508)
		(drill 0.254)
		(layers "F.Cu" "B.Cu")
		(net "RST_SMB_NIC_MUX_R_N")
	)
	(via
		(at 224.514664 -203.40701)
		(size 0.508)
		(drill 0.254)
		(layers "F.Cu" "B.Cu")
		(net "RST_SMB_NIC_MUX_R_N")
	)
	(via
		(at 223.30029 -160.668208)
		(size 0.508)
		(drill 0.254)
		(layers "F.Cu" "B.Cu")
		(net "RST_SMB_NIC_MUX_R_N")
	)
	(via
		(at 254.732282 -158.120334)
		(size 0.508)
		(drill 0.254)
		(layers "F.Cu" "B.Cu")
		(net "RST_SMB_NIC_MUX_R_N")
	)
	(via
		(at 181.023768 -90.621866)
		(size 0.508)
		(drill 0.254)
		(layers "F.Cu" "B.Cu")
		(net "RST_SMB_NIC_MUX_R_N")
	)
	(via
		(at 289.476942 -134.62)
		(size 0.508)
		(drill 0.254)
		(layers "F.Cu" "B.Cu")
		(net "RST_SMB_NIC_MUX_R_N")
	)
	(via
		(at 173.376844 -134.62)
		(size 0.508)
		(drill 0.254)
		(layers "F.Cu" "B.Cu")
		(net "RST_SMB_NIC_MUX_R_N")
	)
	(via
		(at 405.57704 -134.62)
		(size 0.508)
		(drill 0.254)
		(layers "F.Cu" "B.Cu")
		(net "RST_SMB_NIC_MUX_R_N")
	)
	(via
		(at 57.277 -134.62)
		(size 0.508)
		(drill 0.254)
		(layers "F.Cu" "B.Cu")
		(net "RST_SMB_NIC_MUX_R_N")
	)
	(via
		(at 222.160846 -138.505184)
		(size 0.508)
		(drill 0.254)
		(layers "F.Cu" "B.Cu")
		(net "RST_SMB_NIC_MUX_R_N")
	)
	(via
		(at 211.650326 -128.697482)
		(size 0.508)
		(drill 0.254)
		(layers "F.Cu" "B.Cu")
		(net "RST_SMB_NIC_MUX_R_N")
	)
	(via
		(at 296.84599 -111.334042)
		(size 0.508)
		(drill 0.254)
		(layers "F.Cu" "B.Cu")
		(net "RST_SMB_NIC_MUX_R_N")
	)
	(via
		(at 183.987948 -128.201674)
		(size 0.508)
		(drill 0.254)
		(layers "F.Cu" "B.Cu")
		(net "RST_SMB_NIC_MUX_R_N")
	)
	(via
		(at 412.946088 -111.334042)
		(size 0.508)
		(drill 0.254)
		(layers "F.Cu" "B.Cu")
		(net "RST_SMB_NIC_MUX_R_N")
	)
	(segment
		(start 288.206942 -135.89)
		(end 289.476942 -134.62)
		(width 0.13208)
		(layer "B.Cu")
		(net "RST_SMB_NIC_MUX_R_N")
	)
	(segment
		(start 413.976566 -111.334042)
		(end 412.946088 -111.334042)
		(width 0.13208)
		(layer "B.Cu")
		(net "RST_SMB_NIC_MUX_R_N")
	)
	(segment
		(start 288.206942 -136.25195)
		(end 288.206942 -135.89)
		(width 0.13208)
		(layer "B.Cu")
		(net "RST_SMB_NIC_MUX_R_N")
	)
	(segment
		(start 56.007 -135.89)
		(end 57.277 -134.62)
		(width 0.13208)
		(layer "B.Cu")
		(net "RST_SMB_NIC_MUX_R_N")
	)
	(segment
		(start 181.77637 -91.374468)
		(end 181.77637 -101.066092)
		(width 0.13208)
		(layer "B.Cu")
		(net "RST_SMB_NIC_MUX_R_N")
	)
	(segment
		(start 182.843678 -102.1334)
		(end 182.843678 -104.872536)
		(width 0.13208)
		(layer "B.Cu")
		(net "RST_SMB_NIC_MUX_R_N")
	)
	(segment
		(start 404.30704 -135.89)
		(end 405.57704 -134.62)
		(width 0.13208)
		(layer "B.Cu")
		(net "RST_SMB_NIC_MUX_R_N")
	)
	(segment
		(start 181.023768 -90.621866)
		(end 181.77637 -91.374468)
		(width 0.13208)
		(layer "B.Cu")
		(net "RST_SMB_NIC_MUX_R_N")
	)
	(segment
		(start 404.30704 -136.25195)
		(end 404.30704 -135.89)
		(width 0.13208)
		(layer "B.Cu")
		(net "RST_SMB_NIC_MUX_R_N")
	)
	(segment
		(start 181.77637 -101.066092)
		(end 182.843678 -102.1334)
		(width 0.13208)
		(layer "B.Cu")
		(net "RST_SMB_NIC_MUX_R_N")
	)
	(segment
		(start 180.745892 -111.334042)
		(end 181.77637 -111.334042)
		(width 0.13208)
		(layer "B.Cu")
		(net "RST_SMB_NIC_MUX_R_N")
	)
	(segment
		(start 297.876468 -111.334042)
		(end 296.84599 -111.334042)
		(width 0.13208)
		(layer "B.Cu")
		(net "RST_SMB_NIC_MUX_R_N")
	)
	(segment
		(start 172.106844 -135.89)
		(end 173.376844 -134.62)
		(width 0.13208)
		(layer "B.Cu")
		(net "RST_SMB_NIC_MUX_R_N")
	)
	(segment
		(start 172.106844 -136.25195)
		(end 172.106844 -135.89)
		(width 0.13208)
		(layer "B.Cu")
		(net "RST_SMB_NIC_MUX_R_N")
	)
	(segment
		(start 181.77637 -105.939844)
		(end 181.77637 -111.334042)
		(width 0.13208)
		(layer "B.Cu")
		(net "RST_SMB_NIC_MUX_R_N")
	)
	(segment
		(start 182.843678 -104.872536)
		(end 181.77637 -105.939844)
		(width 0.13208)
		(layer "B.Cu")
		(net "RST_SMB_NIC_MUX_R_N")
	)
	(segment
		(start 65.676526 -111.334042)
		(end 64.646048 -111.334042)
		(width 0.13208)
		(layer "B.Cu")
		(net "RST_SMB_NIC_MUX_R_N")
	)
	(segment
		(start 56.007 -136.25195)
		(end 56.007 -135.89)
		(width 0.13208)
		(layer "B.Cu")
		(net "RST_SMB_NIC_MUX_R_N")
	)
	(segment
		(start 224.782634 -180.144166)
		(end 223.40697 -181.51983)
		(width 0.15494)
		(layer "In7.Cu")
		(net "RST_SMB_NIC_MUX_R_N")
	)
	(segment
		(start 218.43746 -140.489178)
		(end 218.43746 -153.520648)
		(width 0.15494)
		(layer "In7.Cu")
		(net "RST_SMB_NIC_MUX_R_N")
	)
	(segment
		(start 225.6282 -168.021254)
		(end 225.6282 -177.367438)
		(width 0.15494)
		(layer "In7.Cu")
		(net "RST_SMB_NIC_MUX_R_N")
	)
	(segment
		(start 223.40697 -181.51983)
		(end 223.40697 -185.33237)
		(width 0.15494)
		(layer "In7.Cu")
		(net "RST_SMB_NIC_MUX_R_N")
	)
	(segment
		(start 226.3394 -192.1256)
		(end 226.3394 -196.697346)
		(width 0.15494)
		(layer "In7.Cu")
		(net "RST_SMB_NIC_MUX_R_N")
	)
	(segment
		(start 220.421454 -138.505184)
		(end 218.43746 -140.489178)
		(width 0.15494)
		(layer "In7.Cu")
		(net "RST_SMB_NIC_MUX_R_N")
	)
	(segment
		(start 225.6282 -177.367438)
		(end 224.782634 -178.213004)
		(width 0.15494)
		(layer "In7.Cu")
		(net "RST_SMB_NIC_MUX_R_N")
	)
	(segment
		(start 225.1964 -197.840346)
		(end 225.1964 -200.5076)
		(width 0.15494)
		(layer "In7.Cu")
		(net "RST_SMB_NIC_MUX_R_N")
	)
	(segment
		(start 226.695 -191.77)
		(end 226.3394 -192.1256)
		(width 0.15494)
		(layer "In7.Cu")
		(net "RST_SMB_NIC_MUX_R_N")
	)
	(segment
		(start 225.0948 -202.826874)
		(end 224.514664 -203.40701)
		(width 0.15494)
		(layer "In7.Cu")
		(net "RST_SMB_NIC_MUX_R_N")
	)
	(segment
		(start 224.782634 -178.213004)
		(end 224.782634 -180.144166)
		(width 0.15494)
		(layer "In7.Cu")
		(net "RST_SMB_NIC_MUX_R_N")
	)
	(segment
		(start 224.0788 -186.0042)
		(end 225.6028 -186.0042)
		(width 0.15494)
		(layer "In7.Cu")
		(net "RST_SMB_NIC_MUX_R_N")
	)
	(segment
		(start 223.40697 -185.33237)
		(end 224.0788 -186.0042)
		(width 0.15494)
		(layer "In7.Cu")
		(net "RST_SMB_NIC_MUX_R_N")
	)
	(segment
		(start 225.1964 -200.5076)
		(end 224.7646 -200.9394)
		(width 0.15494)
		(layer "In7.Cu")
		(net "RST_SMB_NIC_MUX_R_N")
	)
	(segment
		(start 223.30029 -160.668208)
		(end 223.30029 -165.693344)
		(width 0.15494)
		(layer "In7.Cu")
		(net "RST_SMB_NIC_MUX_R_N")
	)
	(segment
		(start 225.6028 -186.0042)
		(end 226.695 -187.0964)
		(width 0.15494)
		(layer "In7.Cu")
		(net "RST_SMB_NIC_MUX_R_N")
	)
	(segment
		(start 222.160846 -138.505184)
		(end 220.421454 -138.505184)
		(width 0.15494)
		(layer "In7.Cu")
		(net "RST_SMB_NIC_MUX_R_N")
	)
	(segment
		(start 225.0948 -202.184)
		(end 225.0948 -202.826874)
		(width 0.15494)
		(layer "In7.Cu")
		(net "RST_SMB_NIC_MUX_R_N")
	)
	(segment
		(start 223.30029 -158.383478)
		(end 223.30029 -160.668208)
		(width 0.15494)
		(layer "In7.Cu")
		(net "RST_SMB_NIC_MUX_R_N")
	)
	(segment
		(start 218.43746 -153.520648)
		(end 223.30029 -158.383478)
		(width 0.15494)
		(layer "In7.Cu")
		(net "RST_SMB_NIC_MUX_R_N")
	)
	(segment
		(start 226.3394 -196.697346)
		(end 225.1964 -197.840346)
		(width 0.15494)
		(layer "In7.Cu")
		(net "RST_SMB_NIC_MUX_R_N")
	)
	(segment
		(start 224.7646 -200.9394)
		(end 224.7646 -201.8538)
		(width 0.15494)
		(layer "In7.Cu")
		(net "RST_SMB_NIC_MUX_R_N")
	)
	(segment
		(start 223.30029 -165.693344)
		(end 225.6282 -168.021254)
		(width 0.15494)
		(layer "In7.Cu")
		(net "RST_SMB_NIC_MUX_R_N")
	)
	(segment
		(start 226.695 -187.0964)
		(end 226.695 -191.77)
		(width 0.15494)
		(layer "In7.Cu")
		(net "RST_SMB_NIC_MUX_R_N")
	)
	(segment
		(start 224.7646 -201.8538)
		(end 225.0948 -202.184)
		(width 0.15494)
		(layer "In7.Cu")
		(net "RST_SMB_NIC_MUX_R_N")
	)
	(segment
		(start 64.160908 -111.334042)
		(end 58.216038 -117.278912)
		(width 0.15494)
		(layer "In9.Cu")
		(net "RST_SMB_NIC_MUX_R_N")
	)
	(segment
		(start 173.376844 -134.62)
		(end 172.974 -134.217156)
		(width 0.15494)
		(layer "In9.Cu")
		(net "RST_SMB_NIC_MUX_R_N")
	)
	(segment
		(start 407.971498 -132.225542)
		(end 407.971498 -116.308632)
		(width 0.15494)
		(layer "In9.Cu")
		(net "RST_SMB_NIC_MUX_R_N")
	)
	(segment
		(start 58.216038 -132.695442)
		(end 57.277 -133.63448)
		(width 0.15494)
		(layer "In9.Cu")
		(net "RST_SMB_NIC_MUX_R_N")
	)
	(segment
		(start 57.277 -133.63448)
		(end 57.277 -134.62)
		(width 0.15494)
		(layer "In9.Cu")
		(net "RST_SMB_NIC_MUX_R_N")
	)
	(segment
		(start 172.974 -134.217156)
		(end 172.974 -119.105934)
		(width 0.15494)
		(layer "In9.Cu")
		(net "RST_SMB_NIC_MUX_R_N")
	)
	(segment
		(start 291.8714 -132.225542)
		(end 289.476942 -134.62)
		(width 0.15494)
		(layer "In9.Cu")
		(net "RST_SMB_NIC_MUX_R_N")
	)
	(segment
		(start 291.8714 -116.308632)
		(end 291.8714 -132.225542)
		(width 0.15494)
		(layer "In9.Cu")
		(net "RST_SMB_NIC_MUX_R_N")
	)
	(segment
		(start 172.974 -119.105934)
		(end 180.745892 -111.334042)
		(width 0.15494)
		(layer "In9.Cu")
		(net "RST_SMB_NIC_MUX_R_N")
	)
	(segment
		(start 405.57704 -134.62)
		(end 407.971498 -132.225542)
		(width 0.15494)
		(layer "In9.Cu")
		(net "RST_SMB_NIC_MUX_R_N")
	)
	(segment
		(start 58.216038 -117.278912)
		(end 58.216038 -132.695442)
		(width 0.15494)
		(layer "In9.Cu")
		(net "RST_SMB_NIC_MUX_R_N")
	)
	(segment
		(start 64.646048 -111.334042)
		(end 64.160908 -111.334042)
		(width 0.15494)
		(layer "In9.Cu")
		(net "RST_SMB_NIC_MUX_R_N")
	)
	(segment
		(start 296.84599 -111.334042)
		(end 291.8714 -116.308632)
		(width 0.15494)
		(layer "In9.Cu")
		(net "RST_SMB_NIC_MUX_R_N")
	)
	(segment
		(start 407.971498 -116.308632)
		(end 412.946088 -111.334042)
		(width 0.15494)
		(layer "In9.Cu")
		(net "RST_SMB_NIC_MUX_R_N")
	)
	(segment
		(start 396.252192 -131.780026)
		(end 397.174974 -131.780026)
		(width 0.15494)
		(layer "In13.Cu")
		(net "RST_SMB_NIC_MUX_R_N")
	)
	(segment
		(start 253.915418 -163.009326)
		(end 253.273052 -163.651692)
		(width 0.15494)
		(layer "In13.Cu")
		(net "RST_SMB_NIC_MUX_R_N")
	)
	(segment
		(start 386.935218 -131.13639)
		(end 395.608556 -131.13639)
		(width 0.15494)
		(layer "In13.Cu")
		(net "RST_SMB_NIC_MUX_R_N")
	)
	(segment
		(start 296.897298 -137.816844)
		(end 317.71844 -137.816844)
		(width 0.15494)
		(layer "In13.Cu")
		(net "RST_SMB_NIC_MUX_R_N")
	)
	(segment
		(start 223.30029 -162.006026)
		(end 223.30029 -160.668208)
		(width 0.15494)
		(layer "In13.Cu")
		(net "RST_SMB_NIC_MUX_R_N")
	)
	(segment
		(start 355.538278 -130.468878)
		(end 379.175264 -130.468878)
		(width 0.15494)
		(layer "In13.Cu")
		(net "RST_SMB_NIC_MUX_R_N")
	)
	(segment
		(start 384.931158 -129.13233)
		(end 386.935218 -131.13639)
		(width 0.15494)
		(layer "In13.Cu")
		(net "RST_SMB_NIC_MUX_R_N")
	)
	(segment
		(start 404.663148 -133.706108)
		(end 405.57704 -134.62)
		(width 0.15494)
		(layer "In13.Cu")
		(net "RST_SMB_NIC_MUX_R_N")
	)
	(segment
		(start 404.663148 -129.594864)
		(end 404.663148 -133.706108)
		(width 0.15494)
		(layer "In13.Cu")
		(net "RST_SMB_NIC_MUX_R_N")
	)
	(segment
		(start 209.049366 -127.493776)
		(end 210.253072 -128.697482)
		(width 0.15494)
		(layer "In13.Cu")
		(net "RST_SMB_NIC_MUX_R_N")
	)
	(segment
		(start 403.532594 -128.46431)
		(end 404.663148 -129.594864)
		(width 0.15494)
		(layer "In13.Cu")
		(net "RST_SMB_NIC_MUX_R_N")
	)
	(segment
		(start 379.175264 -130.468878)
		(end 380.511812 -129.13233)
		(width 0.15494)
		(layer "In13.Cu")
		(net "RST_SMB_NIC_MUX_R_N")
	)
	(segment
		(start 318.38646 -137.148824)
		(end 348.858332 -137.148824)
		(width 0.15494)
		(layer "In13.Cu")
		(net "RST_SMB_NIC_MUX_R_N")
	)
	(segment
		(start 293.700454 -134.62)
		(end 296.897298 -137.816844)
		(width 0.15494)
		(layer "In13.Cu")
		(net "RST_SMB_NIC_MUX_R_N")
	)
	(segment
		(start 397.174974 -131.780026)
		(end 400.49069 -128.46431)
		(width 0.15494)
		(layer "In13.Cu")
		(net "RST_SMB_NIC_MUX_R_N")
	)
	(segment
		(start 188.424566 -128.815084)
		(end 189.745874 -127.493776)
		(width 0.15494)
		(layer "In13.Cu")
		(net "RST_SMB_NIC_MUX_R_N")
	)
	(segment
		(start 348.858332 -137.148824)
		(end 355.538278 -130.468878)
		(width 0.15494)
		(layer "In13.Cu")
		(net "RST_SMB_NIC_MUX_R_N")
	)
	(segment
		(start 183.987948 -128.201674)
		(end 184.601358 -128.815084)
		(width 0.15494)
		(layer "In13.Cu")
		(net "RST_SMB_NIC_MUX_R_N")
	)
	(segment
		(start 395.608556 -131.13639)
		(end 396.252192 -131.780026)
		(width 0.15494)
		(layer "In13.Cu")
		(net "RST_SMB_NIC_MUX_R_N")
	)
	(segment
		(start 224.945956 -163.651692)
		(end 223.30029 -162.006026)
		(width 0.15494)
		(layer "In13.Cu")
		(net "RST_SMB_NIC_MUX_R_N")
	)
	(segment
		(start 380.511812 -129.13233)
		(end 384.931158 -129.13233)
		(width 0.15494)
		(layer "In13.Cu")
		(net "RST_SMB_NIC_MUX_R_N")
	)
	(segment
		(start 400.49069 -128.46431)
		(end 403.532594 -128.46431)
		(width 0.15494)
		(layer "In13.Cu")
		(net "RST_SMB_NIC_MUX_R_N")
	)
	(segment
		(start 253.915418 -158.937198)
		(end 253.915418 -163.009326)
		(width 0.15494)
		(layer "In13.Cu")
		(net "RST_SMB_NIC_MUX_R_N")
	)
	(segment
		(start 184.601358 -128.815084)
		(end 188.424566 -128.815084)
		(width 0.15494)
		(layer "In13.Cu")
		(net "RST_SMB_NIC_MUX_R_N")
	)
	(segment
		(start 289.476942 -134.62)
		(end 293.700454 -134.62)
		(width 0.15494)
		(layer "In13.Cu")
		(net "RST_SMB_NIC_MUX_R_N")
	)
	(segment
		(start 253.273052 -163.651692)
		(end 224.945956 -163.651692)
		(width 0.15494)
		(layer "In13.Cu")
		(net "RST_SMB_NIC_MUX_R_N")
	)
	(segment
		(start 317.71844 -137.816844)
		(end 318.38646 -137.148824)
		(width 0.15494)
		(layer "In13.Cu")
		(net "RST_SMB_NIC_MUX_R_N")
	)
	(segment
		(start 210.253072 -128.697482)
		(end 211.650326 -128.697482)
		(width 0.15494)
		(layer "In13.Cu")
		(net "RST_SMB_NIC_MUX_R_N")
	)
	(segment
		(start 189.745874 -127.493776)
		(end 209.049366 -127.493776)
		(width 0.15494)
		(layer "In13.Cu")
		(net "RST_SMB_NIC_MUX_R_N")
	)
	(segment
		(start 254.732282 -158.120334)
		(end 253.915418 -158.937198)
		(width 0.15494)
		(layer "In13.Cu")
		(net "RST_SMB_NIC_MUX_R_N")
	)
	(segment
		(start 108.230924 -95.65132)
		(end 114.68735 -102.107746)
		(width 0.15494)
		(layer "In15.Cu")
		(net "RST_SMB_NIC_MUX_R_N")
	)
	(segment
		(start 180.695092 -90.29319)
		(end 181.023768 -90.621866)
		(width 0.15494)
		(layer "In15.Cu")
		(net "RST_SMB_NIC_MUX_R_N")
	)
	(segment
		(start 286.378142 -137.7188)
		(end 282.993846 -137.7188)
		(width 0.15494)
		(layer "In15.Cu")
		(net "RST_SMB_NIC_MUX_R_N")
	)
	(segment
		(start 100.780088 -92.42806)
		(end 104.003348 -95.65132)
		(width 0.15494)
		(layer "In15.Cu")
		(net "RST_SMB_NIC_MUX_R_N")
	)
	(segment
		(start 65.729358 -101.285548)
		(end 68.843906 -98.171)
		(width 0.15494)
		(layer "In15.Cu")
		(net "RST_SMB_NIC_MUX_R_N")
	)
	(segment
		(start 256.6162 -157.9626)
		(end 254.890016 -157.9626)
		(width 0.15494)
		(layer "In15.Cu")
		(net "RST_SMB_NIC_MUX_R_N")
	)
	(segment
		(start 270.51 -144.0688)
		(end 256.6162 -157.9626)
		(width 0.15494)
		(layer "In15.Cu")
		(net "RST_SMB_NIC_MUX_R_N")
	)
	(segment
		(start 270.51 -140.081254)
		(end 270.51 -144.0688)
		(width 0.15494)
		(layer "In15.Cu")
		(net "RST_SMB_NIC_MUX_R_N")
	)
	(segment
		(start 114.68735 -102.107746)
		(end 144.602454 -102.107746)
		(width 0.15494)
		(layer "In15.Cu")
		(net "RST_SMB_NIC_MUX_R_N")
	)
	(segment
		(start 282.993846 -137.7188)
		(end 280.047446 -134.7724)
		(width 0.15494)
		(layer "In15.Cu")
		(net "RST_SMB_NIC_MUX_R_N")
	)
	(segment
		(start 275.818854 -134.7724)
		(end 270.51 -140.081254)
		(width 0.15494)
		(layer "In15.Cu")
		(net "RST_SMB_NIC_MUX_R_N")
	)
	(segment
		(start 289.476942 -134.62)
		(end 286.378142 -137.7188)
		(width 0.15494)
		(layer "In15.Cu")
		(net "RST_SMB_NIC_MUX_R_N")
	)
	(segment
		(start 68.843906 -98.171)
		(end 75.0824 -98.171)
		(width 0.15494)
		(layer "In15.Cu")
		(net "RST_SMB_NIC_MUX_R_N")
	)
	(segment
		(start 64.646048 -111.334042)
		(end 65.729358 -110.250732)
		(width 0.15494)
		(layer "In15.Cu")
		(net "RST_SMB_NIC_MUX_R_N")
	)
	(segment
		(start 83.777582 -97.537778)
		(end 88.8873 -92.42806)
		(width 0.15494)
		(layer "In15.Cu")
		(net "RST_SMB_NIC_MUX_R_N")
	)
	(segment
		(start 88.8873 -92.42806)
		(end 100.780088 -92.42806)
		(width 0.15494)
		(layer "In15.Cu")
		(net "RST_SMB_NIC_MUX_R_N")
	)
	(segment
		(start 75.0824 -98.171)
		(end 75.715622 -97.537778)
		(width 0.15494)
		(layer "In15.Cu")
		(net "RST_SMB_NIC_MUX_R_N")
	)
	(segment
		(start 156.41701 -90.29319)
		(end 180.695092 -90.29319)
		(width 0.15494)
		(layer "In15.Cu")
		(net "RST_SMB_NIC_MUX_R_N")
	)
	(segment
		(start 280.047446 -134.7724)
		(end 275.818854 -134.7724)
		(width 0.15494)
		(layer "In15.Cu")
		(net "RST_SMB_NIC_MUX_R_N")
	)
	(segment
		(start 254.890016 -157.9626)
		(end 254.732282 -158.120334)
		(width 0.15494)
		(layer "In15.Cu")
		(net "RST_SMB_NIC_MUX_R_N")
	)
	(segment
		(start 144.602454 -102.107746)
		(end 156.41701 -90.29319)
		(width 0.15494)
		(layer "In15.Cu")
		(net "RST_SMB_NIC_MUX_R_N")
	)
	(segment
		(start 104.003348 -95.65132)
		(end 108.230924 -95.65132)
		(width 0.15494)
		(layer "In15.Cu")
		(net "RST_SMB_NIC_MUX_R_N")
	)
	(segment
		(start 65.729358 -110.250732)
		(end 65.729358 -101.285548)
		(width 0.15494)
		(layer "In15.Cu")
		(net "RST_SMB_NIC_MUX_R_N")
	)
	(segment
		(start 75.715622 -97.537778)
		(end 83.777582 -97.537778)
		(width 0.15494)
		(layer "In15.Cu")
		(net "RST_SMB_NIC_MUX_R_N")
	)
	(segment
		(start 234.297474 -207.99425)
		(end 234.13466 -207.831436)
		(width 0.13208)
		(layer "F.Cu")
		(net "PD_BIC_ENTEST")
	)
	(segment
		(start 234.297474 -211.447126)
		(end 234.297474 -208.612232)
		(width 0.13208)
		(layer "F.Cu")
		(net "PD_BIC_ENTEST")
	)
	(segment
		(start 233.9086 -212.663278)
		(end 233.9086 -211.836)
		(width 0.13208)
		(layer "F.Cu")
		(net "PD_BIC_ENTEST")
	)
	(segment
		(start 234.297474 -208.612232)
		(end 234.297474 -207.99425)
		(width 0.13208)
		(layer "F.Cu")
		(net "PD_BIC_ENTEST")
	)
	(segment
		(start 233.9086 -211.836)
		(end 234.297474 -211.447126)
		(width 0.13208)
		(layer "F.Cu")
		(net "PD_BIC_ENTEST")
	)
	(segment
		(start 234.13466 -207.831436)
		(end 234.13466 -207.42021)
		(width 0.13208)
		(layer "F.Cu")
		(net "PD_BIC_ENTEST")
	)
	(segment
		(start 233.867706 -212.704172)
		(end 233.9086 -212.663278)
		(width 0.13208)
		(layer "F.Cu")
		(net "PD_BIC_ENTEST")
	)
	(via
		(at 234.297474 -208.612232)
		(size 0.762)
		(drill 0.381)
		(layers "F.Cu" "B.Cu")
		(net "PD_BIC_ENTEST")
	)
	(segment
		(start 342.893904 -224.786952)
		(end 343.2937 -225.186748)
		(width 0.13208)
		(layer "F.Cu")
		(net "SMB_MB_BMC_ISO_FPGA_SDA")
	)
	(segment
		(start 323.05371 -232.397046)
		(end 323.487796 -232.397046)
		(width 0.13208)
		(layer "F.Cu")
		(net "SMB_MB_BMC_ISO_FPGA_SDA")
	)
	(segment
		(start 323.487796 -232.397046)
		(end 323.6976 -232.187242)
		(width 0.13208)
		(layer "F.Cu")
		(net "SMB_MB_BMC_ISO_FPGA_SDA")
	)
	(via
		(at 323.6976 -232.187242)
		(size 0.508)
		(drill 0.254)
		(layers "F.Cu" "B.Cu")
		(net "SMB_MB_BMC_ISO_FPGA_SDA")
	)
	(via
		(at 343.2937 -225.186748)
		(size 0.4572)
		(drill 0.254)
		(layers "F.Cu" "B.Cu")
		(net "SMB_MB_BMC_ISO_FPGA_SDA")
	)
	(segment
		(start 343.2937 -225.186748)
		(end 343.170764 -224.890076)
		(width 0.0889)
		(layer "In5.Cu")
		(net "SMB_MB_BMC_ISO_FPGA_SDA")
	)
	(segment
		(start 343.170764 -224.890076)
		(end 342.522302 -224.241614)
		(width 0.0889)
		(layer "In5.Cu")
		(net "SMB_MB_BMC_ISO_FPGA_SDA")
	)
	(segment
		(start 338.894166 -222.623888)
		(end 338.894166 -224.61601)
		(width 0.0889)
		(layer "In5.Cu")
		(net "SMB_MB_BMC_ISO_FPGA_SDA")
	)
	(segment
		(start 337.29168 -225.826828)
		(end 337.29168 -226.932744)
		(width 0.0889)
		(layer "In5.Cu")
		(net "SMB_MB_BMC_ISO_FPGA_SDA")
	)
	(segment
		(start 337.53425 -225.584258)
		(end 337.29168 -225.826828)
		(width 0.0889)
		(layer "In5.Cu")
		(net "SMB_MB_BMC_ISO_FPGA_SDA")
	)
	(segment
		(start 333.91221 -232.187242)
		(end 323.6976 -232.187242)
		(width 0.15494)
		(layer "In5.Cu")
		(net "SMB_MB_BMC_ISO_FPGA_SDA")
	)
	(segment
		(start 339.13064 -222.387414)
		(end 338.894166 -222.623888)
		(width 0.0889)
		(layer "In5.Cu")
		(net "SMB_MB_BMC_ISO_FPGA_SDA")
	)
	(segment
		(start 337.29168 -226.932744)
		(end 337.29168 -227.196396)
		(width 0.15494)
		(layer "In5.Cu")
		(net "SMB_MB_BMC_ISO_FPGA_SDA")
	)
	(segment
		(start 342.043004 -222.387414)
		(end 339.13064 -222.387414)
		(width 0.0889)
		(layer "In5.Cu")
		(net "SMB_MB_BMC_ISO_FPGA_SDA")
	)
	(segment
		(start 338.725256 -224.78492)
		(end 338.29244 -224.78492)
		(width 0.0889)
		(layer "In5.Cu")
		(net "SMB_MB_BMC_ISO_FPGA_SDA")
	)
	(segment
		(start 338.091526 -224.985834)
		(end 338.091526 -225.351594)
		(width 0.0889)
		(layer "In5.Cu")
		(net "SMB_MB_BMC_ISO_FPGA_SDA")
	)
	(segment
		(start 335.739232 -228.748844)
		(end 335.739232 -230.36022)
		(width 0.15494)
		(layer "In5.Cu")
		(net "SMB_MB_BMC_ISO_FPGA_SDA")
	)
	(segment
		(start 338.091526 -225.351594)
		(end 337.858862 -225.584258)
		(width 0.0889)
		(layer "In5.Cu")
		(net "SMB_MB_BMC_ISO_FPGA_SDA")
	)
	(segment
		(start 342.522302 -224.241614)
		(end 342.522302 -222.866712)
		(width 0.0889)
		(layer "In5.Cu")
		(net "SMB_MB_BMC_ISO_FPGA_SDA")
	)
	(segment
		(start 342.522302 -222.866712)
		(end 342.043004 -222.387414)
		(width 0.0889)
		(layer "In5.Cu")
		(net "SMB_MB_BMC_ISO_FPGA_SDA")
	)
	(segment
		(start 337.29168 -227.196396)
		(end 335.739232 -228.748844)
		(width 0.15494)
		(layer "In5.Cu")
		(net "SMB_MB_BMC_ISO_FPGA_SDA")
	)
	(segment
		(start 338.29244 -224.78492)
		(end 338.091526 -224.985834)
		(width 0.0889)
		(layer "In5.Cu")
		(net "SMB_MB_BMC_ISO_FPGA_SDA")
	)
	(segment
		(start 335.739232 -230.36022)
		(end 333.91221 -232.187242)
		(width 0.15494)
		(layer "In5.Cu")
		(net "SMB_MB_BMC_ISO_FPGA_SDA")
	)
	(segment
		(start 338.894166 -224.61601)
		(end 338.725256 -224.78492)
		(width 0.0889)
		(layer "In5.Cu")
		(net "SMB_MB_BMC_ISO_FPGA_SDA")
	)
	(segment
		(start 337.858862 -225.584258)
		(end 337.53425 -225.584258)
		(width 0.0889)
		(layer "In5.Cu")
		(net "SMB_MB_BMC_ISO_FPGA_SDA")
	)
	(segment
		(start 323.549772 -233.414824)
		(end 323.76618 -233.631232)
		(width 0.13208)
		(layer "F.Cu")
		(net "SMB_MB_BMC_ISO_FPGA_SCL")
	)
	(segment
		(start 342.893904 -225.587052)
		(end 343.2937 -225.986848)
		(width 0.13208)
		(layer "F.Cu")
		(net "SMB_MB_BMC_ISO_FPGA_SCL")
	)
	(segment
		(start 323.05371 -233.414824)
		(end 323.549772 -233.414824)
		(width 0.13208)
		(layer "F.Cu")
		(net "SMB_MB_BMC_ISO_FPGA_SCL")
	)
	(via
		(at 323.76618 -233.631232)
		(size 0.508)
		(drill 0.254)
		(layers "F.Cu" "B.Cu")
		(net "SMB_MB_BMC_ISO_FPGA_SCL")
	)
	(via
		(at 343.2937 -225.986848)
		(size 0.4572)
		(drill 0.254)
		(layers "F.Cu" "B.Cu")
		(net "SMB_MB_BMC_ISO_FPGA_SCL")
	)
	(segment
		(start 333.830422 -232.602278)
		(end 332.96098 -233.47172)
		(width 0.13208)
		(layer "B.Cu")
		(net "SMB_MB_BMC_ISO_FPGA_SCL")
	)
	(segment
		(start 340.861142 -230.329232)
		(end 340.419436 -230.770938)
		(width 0.13208)
		(layer "B.Cu")
		(net "SMB_MB_BMC_ISO_FPGA_SCL")
	)
	(segment
		(start 337.693254 -232.602278)
		(end 333.830422 -232.602278)
		(width 0.13208)
		(layer "B.Cu")
		(net "SMB_MB_BMC_ISO_FPGA_SCL")
	)
	(segment
		(start 340.704678 -225.584766)
		(end 340.493096 -225.796348)
		(width 0.0889)
		(layer "B.Cu")
		(net "SMB_MB_BMC_ISO_FPGA_SCL")
	)
	(segment
		(start 326.939402 -232.817162)
		(end 325.067168 -232.817162)
		(width 0.13208)
		(layer "B.Cu")
		(net "SMB_MB_BMC_ISO_FPGA_SCL")
	)
	(segment
		(start 340.861142 -227.466144)
		(end 340.861142 -230.329232)
		(width 0.13208)
		(layer "B.Cu")
		(net "SMB_MB_BMC_ISO_FPGA_SCL")
	)
	(segment
		(start 340.419436 -230.770938)
		(end 339.524594 -230.770938)
		(width 0.13208)
		(layer "B.Cu")
		(net "SMB_MB_BMC_ISO_FPGA_SCL")
	)
	(segment
		(start 339.524594 -230.770938)
		(end 337.693254 -232.602278)
		(width 0.13208)
		(layer "B.Cu")
		(net "SMB_MB_BMC_ISO_FPGA_SCL")
	)
	(segment
		(start 342.891618 -225.584766)
		(end 340.704678 -225.584766)
		(width 0.0889)
		(layer "B.Cu")
		(net "SMB_MB_BMC_ISO_FPGA_SCL")
	)
	(segment
		(start 340.493096 -225.796348)
		(end 340.493096 -227.098098)
		(width 0.0889)
		(layer "B.Cu")
		(net "SMB_MB_BMC_ISO_FPGA_SCL")
	)
	(segment
		(start 327.59396 -233.47172)
		(end 326.939402 -232.817162)
		(width 0.13208)
		(layer "B.Cu")
		(net "SMB_MB_BMC_ISO_FPGA_SCL")
	)
	(segment
		(start 332.96098 -233.47172)
		(end 327.59396 -233.47172)
		(width 0.13208)
		(layer "B.Cu")
		(net "SMB_MB_BMC_ISO_FPGA_SCL")
	)
	(segment
		(start 343.2937 -225.986848)
		(end 342.891618 -225.584766)
		(width 0.0889)
		(layer "B.Cu")
		(net "SMB_MB_BMC_ISO_FPGA_SCL")
	)
	(segment
		(start 324.253098 -233.631232)
		(end 323.76618 -233.631232)
		(width 0.13208)
		(layer "B.Cu")
		(net "SMB_MB_BMC_ISO_FPGA_SCL")
	)
	(segment
		(start 325.067168 -232.817162)
		(end 324.253098 -233.631232)
		(width 0.13208)
		(layer "B.Cu")
		(net "SMB_MB_BMC_ISO_FPGA_SCL")
	)
	(segment
		(start 340.493096 -227.098098)
		(end 340.861142 -227.466144)
		(width 0.13208)
		(layer "B.Cu")
		(net "SMB_MB_BMC_ISO_FPGA_SCL")
	)
	(segment
		(start 198.40194 -404.513288)
		(end 198.40194 -405.194516)
		(width 0.13208)
		(layer "F.Cu")
		(net "MB_HSC_ISO_D2_EN")
	)
	(segment
		(start 198.40194 -405.194516)
		(end 198.388986 -405.20747)
		(width 0.13208)
		(layer "F.Cu")
		(net "MB_HSC_ISO_D2_EN")
	)
	(segment
		(start 198.388986 -405.20747)
		(end 198.388986 -405.95804)
		(width 0.13208)
		(layer "F.Cu")
		(net "MB_HSC_ISO_D2_EN")
	)
	(via
		(at 198.40194 -405.194516)
		(size 0.508)
		(drill 0.254)
		(layers "F.Cu" "B.Cu")
		(net "MB_HSC_ISO_D2_EN")
	)
	(segment
		(start 204.830426 -363.770672)
		(end 204.830426 -364.885986)
		(width 0.13208)
		(layer "F.Cu")
		(net "HSC_P12V_EN")
	)
	(segment
		(start 198.405496 -402.222462)
		(end 198.40194 -402.226018)
		(width 0.13208)
		(layer "F.Cu")
		(net "HSC_P12V_EN")
	)
	(segment
		(start 198.40194 -402.226018)
		(end 198.40194 -403.713188)
		(width 0.13208)
		(layer "F.Cu")
		(net "HSC_P12V_EN")
	)
	(segment
		(start 206.274416 -362.326682)
		(end 204.830426 -363.770672)
		(width 0.13208)
		(layer "F.Cu")
		(net "HSC_P12V_EN")
	)
	(segment
		(start 198.40194 -403.713188)
		(end 197.366382 -403.713188)
		(width 0.13208)
		(layer "F.Cu")
		(net "HSC_P12V_EN")
	)
	(via
		(at 198.405496 -402.222462)
		(size 0.508)
		(drill 0.254)
		(layers "F.Cu" "B.Cu")
		(net "HSC_P12V_EN")
	)
	(via
		(at 206.274416 -362.326682)
		(size 0.508)
		(drill 0.254)
		(layers "F.Cu" "B.Cu")
		(net "HSC_P12V_EN")
	)
	(via
		(at 188.09462 -387.124702)
		(size 0.762)
		(drill 0.254)
		(layers "F.Cu" "B.Cu")
		(net "HSC_P12V_EN")
	)
	(via
		(at 253.6444 -348.8436)
		(size 0.508)
		(drill 0.254)
		(layers "F.Cu" "B.Cu")
		(net "HSC_P12V_EN")
	)
	(segment
		(start 200.2028 -365.094266)
		(end 196.76237 -365.094266)
		(width 0.13208)
		(layer "B.Cu")
		(net "HSC_P12V_EN")
	)
	(segment
		(start 204.321156 -363.45622)
		(end 203.562712 -363.45622)
		(width 0.13208)
		(layer "B.Cu")
		(net "HSC_P12V_EN")
	)
	(segment
		(start 204.777086 -363.00029)
		(end 204.321156 -363.45622)
		(width 0.13208)
		(layer "B.Cu")
		(net "HSC_P12V_EN")
	)
	(segment
		(start 206.274416 -362.326682)
		(end 205.600808 -363.00029)
		(width 0.13208)
		(layer "B.Cu")
		(net "HSC_P12V_EN")
	)
	(segment
		(start 201.286618 -364.010448)
		(end 200.2028 -365.094266)
		(width 0.13208)
		(layer "B.Cu")
		(net "HSC_P12V_EN")
	)
	(segment
		(start 203.562712 -363.45622)
		(end 203.182728 -363.076236)
		(width 0.13208)
		(layer "B.Cu")
		(net "HSC_P12V_EN")
	)
	(segment
		(start 196.76237 -365.094266)
		(end 190.744856 -371.11178)
		(width 0.13208)
		(layer "B.Cu")
		(net "HSC_P12V_EN")
	)
	(segment
		(start 188.094366 -374.915684)
		(end 188.094366 -387.124448)
		(width 0.13208)
		(layer "B.Cu")
		(net "HSC_P12V_EN")
	)
	(segment
		(start 190.744856 -371.11178)
		(end 190.744856 -372.265194)
		(width 0.13208)
		(layer "B.Cu")
		(net "HSC_P12V_EN")
	)
	(segment
		(start 202.629008 -363.076236)
		(end 201.694796 -364.010448)
		(width 0.13208)
		(layer "B.Cu")
		(net "HSC_P12V_EN")
	)
	(segment
		(start 203.182728 -363.076236)
		(end 202.629008 -363.076236)
		(width 0.13208)
		(layer "B.Cu")
		(net "HSC_P12V_EN")
	)
	(segment
		(start 252.41885 -348.8436)
		(end 253.6444 -348.8436)
		(width 0.13208)
		(layer "B.Cu")
		(net "HSC_P12V_EN")
	)
	(segment
		(start 204.773276 -362.99648)
		(end 204.777086 -363.00029)
		(width 0.13208)
		(layer "B.Cu")
		(net "HSC_P12V_EN")
	)
	(segment
		(start 204.773276 -361.988608)
		(end 204.773276 -362.99648)
		(width 0.13208)
		(layer "B.Cu")
		(net "HSC_P12V_EN")
	)
	(segment
		(start 205.600808 -363.00029)
		(end 204.777086 -363.00029)
		(width 0.13208)
		(layer "B.Cu")
		(net "HSC_P12V_EN")
	)
	(segment
		(start 190.744856 -372.265194)
		(end 188.094366 -374.915684)
		(width 0.13208)
		(layer "B.Cu")
		(net "HSC_P12V_EN")
	)
	(segment
		(start 201.694796 -364.010448)
		(end 201.286618 -364.010448)
		(width 0.13208)
		(layer "B.Cu")
		(net "HSC_P12V_EN")
	)
	(segment
		(start 188.094366 -387.124448)
		(end 188.09462 -387.124702)
		(width 0.13208)
		(layer "B.Cu")
		(net "HSC_P12V_EN")
	)
	(segment
		(start 248.618756 -346.72397)
		(end 253.404116 -346.72397)
		(width 0.15494)
		(layer "In5.Cu")
		(net "HSC_P12V_EN")
	)
	(segment
		(start 206.274416 -362.326682)
		(end 208.27873 -360.322368)
		(width 0.15494)
		(layer "In5.Cu")
		(net "HSC_P12V_EN")
	)
	(segment
		(start 208.27873 -360.322368)
		(end 220.321886 -360.322368)
		(width 0.15494)
		(layer "In5.Cu")
		(net "HSC_P12V_EN")
	)
	(segment
		(start 253.404116 -346.72397)
		(end 254.3048 -347.624654)
		(width 0.15494)
		(layer "In5.Cu")
		(net "HSC_P12V_EN")
	)
	(segment
		(start 196.540374 -402.222462)
		(end 198.405496 -402.222462)
		(width 0.15494)
		(layer "In5.Cu")
		(net "HSC_P12V_EN")
	)
	(segment
		(start 220.321886 -360.322368)
		(end 235.417614 -345.22664)
		(width 0.15494)
		(layer "In5.Cu")
		(net "HSC_P12V_EN")
	)
	(segment
		(start 247.121426 -345.22664)
		(end 248.618756 -346.72397)
		(width 0.15494)
		(layer "In5.Cu")
		(net "HSC_P12V_EN")
	)
	(segment
		(start 188.09462 -393.776708)
		(end 196.540374 -402.222462)
		(width 0.15494)
		(layer "In5.Cu")
		(net "HSC_P12V_EN")
	)
	(segment
		(start 235.417614 -345.22664)
		(end 247.121426 -345.22664)
		(width 0.15494)
		(layer "In5.Cu")
		(net "HSC_P12V_EN")
	)
	(segment
		(start 254.3048 -347.624654)
		(end 254.3048 -348.1832)
		(width 0.15494)
		(layer "In5.Cu")
		(net "HSC_P12V_EN")
	)
	(segment
		(start 188.09462 -387.124702)
		(end 188.09462 -393.776708)
		(width 0.15494)
		(layer "In5.Cu")
		(net "HSC_P12V_EN")
	)
	(segment
		(start 254.3048 -348.1832)
		(end 253.6444 -348.8436)
		(width 0.15494)
		(layer "In5.Cu")
		(net "HSC_P12V_EN")
	)
	(segment
		(start 333.09433 -222.907606)
		(end 332.677262 -222.907606)
		(width 0.13208)
		(layer "F.Cu")
		(net "PEX0_SYS_ERR_FPGA")
	)
	(segment
		(start 334.89392 -222.38716)
		(end 334.49768 -222.7834)
		(width 0.13208)
		(layer "F.Cu")
		(net "PEX0_SYS_ERR_FPGA")
	)
	(segment
		(start 23.128478 -261.207758)
		(end 22.50948 -261.207758)
		(width 0.13208)
		(layer "F.Cu")
		(net "PEX0_SYS_ERR_FPGA")
	)
	(segment
		(start 22.50948 -261.207758)
		(end 22.424898 -261.123176)
		(width 0.13208)
		(layer "F.Cu")
		(net "PEX0_SYS_ERR_FPGA")
	)
	(segment
		(start 334.49768 -222.7834)
		(end 333.218536 -222.7834)
		(width 0.13208)
		(layer "F.Cu")
		(net "PEX0_SYS_ERR_FPGA")
	)
	(segment
		(start 22.424898 -261.123176)
		(end 22.424898 -260.740398)
		(width 0.13208)
		(layer "F.Cu")
		(net "PEX0_SYS_ERR_FPGA")
	)
	(segment
		(start 333.218536 -222.7834)
		(end 333.09433 -222.907606)
		(width 0.13208)
		(layer "F.Cu")
		(net "PEX0_SYS_ERR_FPGA")
	)
	(via
		(at 30.5435 -192.745614)
		(size 0.508)
		(drill 0.254)
		(layers "F.Cu" "B.Cu")
		(net "PEX0_SYS_ERR_FPGA")
	)
	(via
		(at 22.424898 -260.740398)
		(size 0.508)
		(drill 0.254)
		(layers "F.Cu" "B.Cu")
		(net "PEX0_SYS_ERR_FPGA")
	)
	(via
		(at 332.677262 -222.907606)
		(size 0.508)
		(drill 0.254)
		(layers "F.Cu" "B.Cu")
		(net "PEX0_SYS_ERR_FPGA")
	)
	(segment
		(start 21.024596 -259.340096)
		(end 21.024596 -246.99849)
		(width 0.15494)
		(layer "In5.Cu")
		(net "PEX0_SYS_ERR_FPGA")
	)
	(segment
		(start 31.915862 -227.076)
		(end 32.5882 -227.076)
		(width 0.15494)
		(layer "In5.Cu")
		(net "PEX0_SYS_ERR_FPGA")
	)
	(segment
		(start 35.389058 -217.430858)
		(end 33.03778 -215.07958)
		(width 0.15494)
		(layer "In5.Cu")
		(net "PEX0_SYS_ERR_FPGA")
	)
	(segment
		(start 33.03778 -203.952348)
		(end 32.210248 -203.124816)
		(width 0.15494)
		(layer "In5.Cu")
		(net "PEX0_SYS_ERR_FPGA")
	)
	(segment
		(start 33.03778 -215.07958)
		(end 33.03778 -203.952348)
		(width 0.15494)
		(layer "In5.Cu")
		(net "PEX0_SYS_ERR_FPGA")
	)
	(segment
		(start 21.024596 -246.99849)
		(end 24.922988 -243.100098)
		(width 0.15494)
		(layer "In5.Cu")
		(net "PEX0_SYS_ERR_FPGA")
	)
	(segment
		(start 35.389058 -224.275142)
		(end 35.389058 -217.430858)
		(width 0.15494)
		(layer "In5.Cu")
		(net "PEX0_SYS_ERR_FPGA")
	)
	(segment
		(start 24.922988 -234.068874)
		(end 31.915862 -227.076)
		(width 0.15494)
		(layer "In5.Cu")
		(net "PEX0_SYS_ERR_FPGA")
	)
	(segment
		(start 32.5882 -227.076)
		(end 35.389058 -224.275142)
		(width 0.15494)
		(layer "In5.Cu")
		(net "PEX0_SYS_ERR_FPGA")
	)
	(segment
		(start 32.210248 -194.412362)
		(end 30.5435 -192.745614)
		(width 0.15494)
		(layer "In5.Cu")
		(net "PEX0_SYS_ERR_FPGA")
	)
	(segment
		(start 24.922988 -243.100098)
		(end 24.922988 -234.068874)
		(width 0.15494)
		(layer "In5.Cu")
		(net "PEX0_SYS_ERR_FPGA")
	)
	(segment
		(start 22.424898 -260.740398)
		(end 21.024596 -259.340096)
		(width 0.15494)
		(layer "In5.Cu")
		(net "PEX0_SYS_ERR_FPGA")
	)
	(segment
		(start 32.210248 -203.124816)
		(end 32.210248 -194.412362)
		(width 0.15494)
		(layer "In5.Cu")
		(net "PEX0_SYS_ERR_FPGA")
	)
	(segment
		(start 332.677262 -222.555562)
		(end 332.605888 -222.484188)
		(width 0.15494)
		(layer "In13.Cu")
		(net "PEX0_SYS_ERR_FPGA")
	)
	(segment
		(start 246.072406 -186.635136)
		(end 245.31447 -185.8772)
		(width 0.15494)
		(layer "In13.Cu")
		(net "PEX0_SYS_ERR_FPGA")
	)
	(segment
		(start 105.156 -186.1566)
		(end 104.18953 -185.19013)
		(width 0.15494)
		(layer "In13.Cu")
		(net "PEX0_SYS_ERR_FPGA")
	)
	(segment
		(start 324.880732 -215.687148)
		(end 323.950584 -214.757)
		(width 0.15494)
		(layer "In13.Cu")
		(net "PEX0_SYS_ERR_FPGA")
	)
	(segment
		(start 140.717524 -188.617352)
		(end 137.300462 -185.20029)
		(width 0.15494)
		(layer "In13.Cu")
		(net "PEX0_SYS_ERR_FPGA")
	)
	(segment
		(start 255.297432 -197.174612)
		(end 253.363984 -195.241164)
		(width 0.15494)
		(layer "In13.Cu")
		(net "PEX0_SYS_ERR_FPGA")
	)
	(segment
		(start 255.339342 -199.189594)
		(end 255.339342 -198.443596)
		(width 0.15494)
		(layer "In13.Cu")
		(net "PEX0_SYS_ERR_FPGA")
	)
	(segment
		(start 323.950584 -214.757)
		(end 321.341242 -214.757)
		(width 0.15494)
		(layer "In13.Cu")
		(net "PEX0_SYS_ERR_FPGA")
	)
	(segment
		(start 218.5924 -189.611)
		(end 217.678 -189.611)
		(width 0.15494)
		(layer "In13.Cu")
		(net "PEX0_SYS_ERR_FPGA")
	)
	(segment
		(start 277.466298 -212.47989)
		(end 266.185142 -201.198734)
		(width 0.15494)
		(layer "In13.Cu")
		(net "PEX0_SYS_ERR_FPGA")
	)
	(segment
		(start 109.213396 -186.1566)
		(end 105.156 -186.1566)
		(width 0.15494)
		(layer "In13.Cu")
		(net "PEX0_SYS_ERR_FPGA")
	)
	(segment
		(start 326.864726 -215.687148)
		(end 326.403462 -215.687148)
		(width 0.15494)
		(layer "In13.Cu")
		(net "PEX0_SYS_ERR_FPGA")
	)
	(segment
		(start 321.341242 -214.757)
		(end 319.064132 -212.47989)
		(width 0.15494)
		(layer "In13.Cu")
		(net "PEX0_SYS_ERR_FPGA")
	)
	(segment
		(start 216.027 -187.198)
		(end 215.519 -186.69)
		(width 0.15494)
		(layer "In13.Cu")
		(net "PEX0_SYS_ERR_FPGA")
	)
	(segment
		(start 242.095274 -185.8772)
		(end 241.916204 -186.05627)
		(width 0.15494)
		(layer "In13.Cu")
		(net "PEX0_SYS_ERR_FPGA")
	)
	(segment
		(start 38.098984 -185.19013)
		(end 30.5435 -192.745614)
		(width 0.15494)
		(layer "In13.Cu")
		(net "PEX0_SYS_ERR_FPGA")
	)
	(segment
		(start 326.08901 -216.0016)
		(end 325.639684 -216.0016)
		(width 0.15494)
		(layer "In13.Cu")
		(net "PEX0_SYS_ERR_FPGA")
	)
	(segment
		(start 330.689204 -220.54185)
		(end 330.689204 -219.985844)
		(width 0.15494)
		(layer "In13.Cu")
		(net "PEX0_SYS_ERR_FPGA")
	)
	(segment
		(start 326.403462 -215.687148)
		(end 326.08901 -216.0016)
		(width 0.15494)
		(layer "In13.Cu")
		(net "PEX0_SYS_ERR_FPGA")
	)
	(segment
		(start 265.901932 -200.872598)
		(end 265.859006 -200.872598)
		(width 0.15494)
		(layer "In13.Cu")
		(net "PEX0_SYS_ERR_FPGA")
	)
	(segment
		(start 216.027 -187.96)
		(end 216.027 -187.198)
		(width 0.15494)
		(layer "In13.Cu")
		(net "PEX0_SYS_ERR_FPGA")
	)
	(segment
		(start 265.859006 -200.872598)
		(end 265.804904 -200.818496)
		(width 0.15494)
		(layer "In13.Cu")
		(net "PEX0_SYS_ERR_FPGA")
	)
	(segment
		(start 215.519 -186.69)
		(end 199.238362 -186.69)
		(width 0.15494)
		(layer "In13.Cu")
		(net "PEX0_SYS_ERR_FPGA")
	)
	(segment
		(start 245.31447 -185.8772)
		(end 242.095274 -185.8772)
		(width 0.15494)
		(layer "In13.Cu")
		(net "PEX0_SYS_ERR_FPGA")
	)
	(segment
		(start 199.238362 -186.69)
		(end 195.739004 -190.189358)
		(width 0.15494)
		(layer "In13.Cu")
		(net "PEX0_SYS_ERR_FPGA")
	)
	(segment
		(start 222.14713 -186.05627)
		(end 218.5924 -189.611)
		(width 0.15494)
		(layer "In13.Cu")
		(net "PEX0_SYS_ERR_FPGA")
	)
	(segment
		(start 110.169706 -185.20029)
		(end 109.213396 -186.1566)
		(width 0.15494)
		(layer "In13.Cu")
		(net "PEX0_SYS_ERR_FPGA")
	)
	(segment
		(start 319.064132 -212.47989)
		(end 277.466298 -212.47989)
		(width 0.15494)
		(layer "In13.Cu")
		(net "PEX0_SYS_ERR_FPGA")
	)
	(segment
		(start 104.18953 -185.19013)
		(end 38.098984 -185.19013)
		(width 0.15494)
		(layer "In13.Cu")
		(net "PEX0_SYS_ERR_FPGA")
	)
	(segment
		(start 255.297432 -198.401686)
		(end 255.297432 -197.174612)
		(width 0.15494)
		(layer "In13.Cu")
		(net "PEX0_SYS_ERR_FPGA")
	)
	(segment
		(start 147.73275 -190.189358)
		(end 146.160744 -188.617352)
		(width 0.15494)
		(layer "In13.Cu")
		(net "PEX0_SYS_ERR_FPGA")
	)
	(segment
		(start 251.050552 -186.635136)
		(end 246.072406 -186.635136)
		(width 0.15494)
		(layer "In13.Cu")
		(net "PEX0_SYS_ERR_FPGA")
	)
	(segment
		(start 137.300462 -185.20029)
		(end 110.169706 -185.20029)
		(width 0.15494)
		(layer "In13.Cu")
		(net "PEX0_SYS_ERR_FPGA")
	)
	(segment
		(start 253.363984 -195.241164)
		(end 253.363984 -188.948568)
		(width 0.15494)
		(layer "In13.Cu")
		(net "PEX0_SYS_ERR_FPGA")
	)
	(segment
		(start 217.678 -189.611)
		(end 216.027 -187.96)
		(width 0.15494)
		(layer "In13.Cu")
		(net "PEX0_SYS_ERR_FPGA")
	)
	(segment
		(start 146.160744 -188.617352)
		(end 140.717524 -188.617352)
		(width 0.15494)
		(layer "In13.Cu")
		(net "PEX0_SYS_ERR_FPGA")
	)
	(segment
		(start 332.605888 -222.458534)
		(end 330.689204 -220.54185)
		(width 0.15494)
		(layer "In13.Cu")
		(net "PEX0_SYS_ERR_FPGA")
	)
	(segment
		(start 327.2536 -216.076022)
		(end 326.864726 -215.687148)
		(width 0.15494)
		(layer "In13.Cu")
		(net "PEX0_SYS_ERR_FPGA")
	)
	(segment
		(start 253.363984 -188.948568)
		(end 251.050552 -186.635136)
		(width 0.15494)
		(layer "In13.Cu")
		(net "PEX0_SYS_ERR_FPGA")
	)
	(segment
		(start 332.677262 -222.907606)
		(end 332.677262 -222.555562)
		(width 0.15494)
		(layer "In13.Cu")
		(net "PEX0_SYS_ERR_FPGA")
	)
	(segment
		(start 325.639684 -216.0016)
		(end 324.880732 -215.687148)
		(width 0.15494)
		(layer "In13.Cu")
		(net "PEX0_SYS_ERR_FPGA")
	)
	(segment
		(start 256.968244 -200.818496)
		(end 255.339342 -199.189594)
		(width 0.15494)
		(layer "In13.Cu")
		(net "PEX0_SYS_ERR_FPGA")
	)
	(segment
		(start 265.804904 -200.818496)
		(end 256.968244 -200.818496)
		(width 0.15494)
		(layer "In13.Cu")
		(net "PEX0_SYS_ERR_FPGA")
	)
	(segment
		(start 241.916204 -186.05627)
		(end 222.14713 -186.05627)
		(width 0.15494)
		(layer "In13.Cu")
		(net "PEX0_SYS_ERR_FPGA")
	)
	(segment
		(start 195.739004 -190.189358)
		(end 147.73275 -190.189358)
		(width 0.15494)
		(layer "In13.Cu")
		(net "PEX0_SYS_ERR_FPGA")
	)
	(segment
		(start 327.2536 -216.55024)
		(end 327.2536 -216.076022)
		(width 0.15494)
		(layer "In13.Cu")
		(net "PEX0_SYS_ERR_FPGA")
	)
	(segment
		(start 255.339342 -198.443596)
		(end 255.297432 -198.401686)
		(width 0.15494)
		(layer "In13.Cu")
		(net "PEX0_SYS_ERR_FPGA")
	)
	(segment
		(start 266.185142 -201.155808)
		(end 265.901932 -200.872598)
		(width 0.15494)
		(layer "In13.Cu")
		(net "PEX0_SYS_ERR_FPGA")
	)
	(segment
		(start 330.689204 -219.985844)
		(end 327.2536 -216.55024)
		(width 0.15494)
		(layer "In13.Cu")
		(net "PEX0_SYS_ERR_FPGA")
	)
	(segment
		(start 266.185142 -201.198734)
		(end 266.185142 -201.155808)
		(width 0.15494)
		(layer "In13.Cu")
		(net "PEX0_SYS_ERR_FPGA")
	)
	(segment
		(start 332.605888 -222.484188)
		(end 332.605888 -222.458534)
		(width 0.15494)
		(layer "In13.Cu")
		(net "PEX0_SYS_ERR_FPGA")
	)
	(segment
		(start 227.467668 -216.704164)
		(end 227.067618 -216.304114)
		(width 0.13208)
		(layer "F.Cu")
		(net "RST_BIC_I2C6_MUX_N")
	)
	(via
		(at 221.95663 -217.316304)
		(size 0.6604)
		(drill 0.3302)
		(layers "F.Cu" "B.Cu")
		(net "RST_BIC_I2C6_MUX_N")
	)
	(via
		(at 227.067618 -216.304114)
		(size 0.4572)
		(drill 0.254)
		(layers "F.Cu" "B.Cu")
		(net "RST_BIC_I2C6_MUX_N")
	)
	(segment
		(start 214.854536 -215.95969)
		(end 214.854536 -216.270586)
		(width 0.13208)
		(layer "B.Cu")
		(net "RST_BIC_I2C6_MUX_N")
	)
	(segment
		(start 214.854536 -216.270586)
		(end 214.335106 -215.751156)
		(width 0.13208)
		(layer "B.Cu")
		(net "RST_BIC_I2C6_MUX_N")
	)
	(segment
		(start 220.02369 -216.096088)
		(end 218.051634 -216.096088)
		(width 0.13208)
		(layer "B.Cu")
		(net "RST_BIC_I2C6_MUX_N")
	)
	(segment
		(start 217.691208 -215.735662)
		(end 215.078564 -215.735662)
		(width 0.13208)
		(layer "B.Cu")
		(net "RST_BIC_I2C6_MUX_N")
	)
	(segment
		(start 221.243906 -217.316304)
		(end 220.02369 -216.096088)
		(width 0.13208)
		(layer "B.Cu")
		(net "RST_BIC_I2C6_MUX_N")
	)
	(segment
		(start 222.572326 -216.700608)
		(end 226.671124 -216.700608)
		(width 0.0889)
		(layer "B.Cu")
		(net "RST_BIC_I2C6_MUX_N")
	)
	(segment
		(start 221.95663 -217.316304)
		(end 222.572326 -216.700608)
		(width 0.13208)
		(layer "B.Cu")
		(net "RST_BIC_I2C6_MUX_N")
	)
	(segment
		(start 215.078564 -215.735662)
		(end 214.854536 -215.95969)
		(width 0.13208)
		(layer "B.Cu")
		(net "RST_BIC_I2C6_MUX_N")
	)
	(segment
		(start 226.671124 -216.700608)
		(end 227.067618 -216.304114)
		(width 0.0889)
		(layer "B.Cu")
		(net "RST_BIC_I2C6_MUX_N")
	)
	(segment
		(start 214.335106 -215.751156)
		(end 214.335106 -215.272874)
		(width 0.13208)
		(layer "B.Cu")
		(net "RST_BIC_I2C6_MUX_N")
	)
	(segment
		(start 221.95663 -217.316304)
		(end 221.243906 -217.316304)
		(width 0.13208)
		(layer "B.Cu")
		(net "RST_BIC_I2C6_MUX_N")
	)
	(segment
		(start 218.051634 -216.096088)
		(end 217.691208 -215.735662)
		(width 0.13208)
		(layer "B.Cu")
		(net "RST_BIC_I2C6_MUX_N")
	)
	(segment
		(start 220.176344 -213.226142)
		(end 219.522802 -212.5726)
		(width 0.13208)
		(layer "F.Cu")
		(net "RST_BIC_I2C9_SSD_MUX1_N")
	)
	(segment
		(start 214.84844 -212.20049)
		(end 214.854536 -212.206586)
		(width 0.13208)
		(layer "F.Cu")
		(net "RST_BIC_I2C9_SSD_MUX1_N")
	)
	(segment
		(start 218.491562 -210.68157)
		(end 215.764364 -210.68157)
		(width 0.13208)
		(layer "F.Cu")
		(net "RST_BIC_I2C9_SSD_MUX1_N")
	)
	(segment
		(start 219.522802 -212.5726)
		(end 218.846146 -212.5726)
		(width 0.13208)
		(layer "F.Cu")
		(net "RST_BIC_I2C9_SSD_MUX1_N")
	)
	(segment
		(start 215.764364 -210.68157)
		(end 215.230202 -211.215732)
		(width 0.13208)
		(layer "F.Cu")
		(net "RST_BIC_I2C9_SSD_MUX1_N")
	)
	(segment
		(start 218.846146 -211.036154)
		(end 218.491562 -210.68157)
		(width 0.13208)
		(layer "F.Cu")
		(net "RST_BIC_I2C9_SSD_MUX1_N")
	)
	(segment
		(start 222.289878 -213.504272)
		(end 222.011748 -213.226142)
		(width 0.13208)
		(layer "F.Cu")
		(net "RST_BIC_I2C9_SSD_MUX1_N")
	)
	(segment
		(start 215.230202 -211.215732)
		(end 214.84844 -211.215732)
		(width 0.13208)
		(layer "F.Cu")
		(net "RST_BIC_I2C9_SSD_MUX1_N")
	)
	(segment
		(start 214.84844 -211.215732)
		(end 214.84844 -212.20049)
		(width 0.13208)
		(layer "F.Cu")
		(net "RST_BIC_I2C9_SSD_MUX1_N")
	)
	(segment
		(start 218.846146 -212.5726)
		(end 218.846146 -211.036154)
		(width 0.13208)
		(layer "F.Cu")
		(net "RST_BIC_I2C9_SSD_MUX1_N")
	)
	(segment
		(start 223.467676 -213.504272)
		(end 222.289878 -213.504272)
		(width 0.13208)
		(layer "F.Cu")
		(net "RST_BIC_I2C9_SSD_MUX1_N")
	)
	(segment
		(start 222.011748 -213.226142)
		(end 220.176344 -213.226142)
		(width 0.13208)
		(layer "F.Cu")
		(net "RST_BIC_I2C9_SSD_MUX1_N")
	)
	(via
		(at 218.846146 -212.5726)
		(size 0.762)
		(drill 0.381)
		(layers "F.Cu" "B.Cu")
		(net "RST_BIC_I2C9_SSD_MUX1_N")
	)
	(segment
		(start 219.64904 -213.595712)
		(end 219.233242 -213.179914)
		(width 0.13208)
		(layer "F.Cu")
		(net "RST_BIC_I2C9_SSD_MUX0_N")
	)
	(segment
		(start 218.108276 -212.679026)
		(end 217.635836 -212.206586)
		(width 0.13208)
		(layer "F.Cu")
		(net "RST_BIC_I2C9_SSD_MUX0_N")
	)
	(segment
		(start 223.871536 -213.907878)
		(end 224.267776 -214.304118)
		(width 0.13208)
		(layer "F.Cu")
		(net "RST_BIC_I2C9_SSD_MUX0_N")
	)
	(segment
		(start 219.869512 -213.816184)
		(end 221.663768 -213.816184)
		(width 0.13208)
		(layer "F.Cu")
		(net "RST_BIC_I2C9_SSD_MUX0_N")
	)
	(segment
		(start 223.122744 -213.907878)
		(end 223.871536 -213.907878)
		(width 0.13208)
		(layer "F.Cu")
		(net "RST_BIC_I2C9_SSD_MUX0_N")
	)
	(segment
		(start 221.663768 -213.816184)
		(end 221.947232 -214.099648)
		(width 0.13208)
		(layer "F.Cu")
		(net "RST_BIC_I2C9_SSD_MUX0_N")
	)
	(segment
		(start 222.930974 -214.099648)
		(end 223.122744 -213.907878)
		(width 0.13208)
		(layer "F.Cu")
		(net "RST_BIC_I2C9_SSD_MUX0_N")
	)
	(segment
		(start 219.233242 -213.179914)
		(end 218.425014 -213.179914)
		(width 0.13208)
		(layer "F.Cu")
		(net "RST_BIC_I2C9_SSD_MUX0_N")
	)
	(segment
		(start 217.627962 -212.198712)
		(end 217.635836 -212.206586)
		(width 0.13208)
		(layer "F.Cu")
		(net "RST_BIC_I2C9_SSD_MUX0_N")
	)
	(segment
		(start 217.627962 -211.193126)
		(end 217.627962 -212.198712)
		(width 0.13208)
		(layer "F.Cu")
		(net "RST_BIC_I2C9_SSD_MUX0_N")
	)
	(segment
		(start 219.64904 -213.595712)
		(end 219.869512 -213.816184)
		(width 0.13208)
		(layer "F.Cu")
		(net "RST_BIC_I2C9_SSD_MUX0_N")
	)
	(segment
		(start 218.108276 -212.863176)
		(end 218.108276 -212.679026)
		(width 0.13208)
		(layer "F.Cu")
		(net "RST_BIC_I2C9_SSD_MUX0_N")
	)
	(segment
		(start 218.425014 -213.179914)
		(end 218.108276 -212.863176)
		(width 0.13208)
		(layer "F.Cu")
		(net "RST_BIC_I2C9_SSD_MUX0_N")
	)
	(segment
		(start 221.947232 -214.099648)
		(end 222.930974 -214.099648)
		(width 0.13208)
		(layer "F.Cu")
		(net "RST_BIC_I2C9_SSD_MUX0_N")
	)
	(via
		(at 219.64904 -213.595712)
		(size 0.762)
		(drill 0.381)
		(layers "F.Cu" "B.Cu")
		(net "RST_BIC_I2C9_SSD_MUX0_N")
	)
	(segment
		(start 226.667568 -216.704164)
		(end 226.267772 -216.304368)
		(width 0.13208)
		(layer "F.Cu")
		(net "BIC_UART_BIC_SEL")
	)
	(via
		(at 222.293434 -215.921844)
		(size 0.6604)
		(drill 0.3302)
		(layers "F.Cu" "B.Cu")
		(net "BIC_UART_BIC_SEL")
	)
	(via
		(at 226.267772 -216.304368)
		(size 0.4572)
		(drill 0.254)
		(layers "F.Cu" "B.Cu")
		(net "BIC_UART_BIC_SEL")
	)
	(segment
		(start 220.449902 -215.921844)
		(end 222.293434 -215.921844)
		(width 0.13208)
		(layer "B.Cu")
		(net "BIC_UART_BIC_SEL")
	)
	(segment
		(start 222.903542 -215.908128)
		(end 225.871532 -215.908128)
		(width 0.0889)
		(layer "B.Cu")
		(net "BIC_UART_BIC_SEL")
	)
	(segment
		(start 225.871532 -215.908128)
		(end 226.267772 -216.304368)
		(width 0.0889)
		(layer "B.Cu")
		(net "BIC_UART_BIC_SEL")
	)
	(segment
		(start 217.635836 -215.254586)
		(end 217.967052 -214.92337)
		(width 0.13208)
		(layer "B.Cu")
		(net "BIC_UART_BIC_SEL")
	)
	(segment
		(start 222.293434 -215.921844)
		(end 222.889826 -215.921844)
		(width 0.13208)
		(layer "B.Cu")
		(net "BIC_UART_BIC_SEL")
	)
	(segment
		(start 219.451428 -214.92337)
		(end 220.449902 -215.921844)
		(width 0.13208)
		(layer "B.Cu")
		(net "BIC_UART_BIC_SEL")
	)
	(segment
		(start 217.967052 -214.92337)
		(end 219.451428 -214.92337)
		(width 0.13208)
		(layer "B.Cu")
		(net "BIC_UART_BIC_SEL")
	)
	(segment
		(start 222.889826 -215.921844)
		(end 222.903542 -215.908128)
		(width 0.13208)
		(layer "B.Cu")
		(net "BIC_UART_BIC_SEL")
	)
	(segment
		(start 350.140016 -228.033326)
		(end 350.140016 -228.740462)
		(width 0.13208)
		(layer "F.Cu")
		(net "BIC_FORCE_THROTTLE_R_N")
	)
	(segment
		(start 350.140016 -228.740462)
		(end 351.784412 -230.384858)
		(width 0.13208)
		(layer "F.Cu")
		(net "BIC_FORCE_THROTTLE_R_N")
	)
	(segment
		(start 352.371152 -236.291374)
		(end 352.639884 -236.022642)
		(width 0.13208)
		(layer "F.Cu")
		(net "BIC_FORCE_THROTTLE_R_N")
	)
	(segment
		(start 351.22485 -236.291374)
		(end 352.371152 -236.291374)
		(width 0.13208)
		(layer "F.Cu")
		(net "BIC_FORCE_THROTTLE_R_N")
	)
	(segment
		(start 350.093788 -227.987098)
		(end 350.140016 -228.033326)
		(width 0.13208)
		(layer "F.Cu")
		(net "BIC_FORCE_THROTTLE_R_N")
	)
	(segment
		(start 351.784412 -235.341668)
		(end 351.956624 -235.51388)
		(width 0.13208)
		(layer "F.Cu")
		(net "BIC_FORCE_THROTTLE_R_N")
	)
	(segment
		(start 351.956624 -235.51388)
		(end 352.639884 -235.51388)
		(width 0.13208)
		(layer "F.Cu")
		(net "BIC_FORCE_THROTTLE_R_N")
	)
	(segment
		(start 352.639884 -236.022642)
		(end 352.639884 -235.51388)
		(width 0.13208)
		(layer "F.Cu")
		(net "BIC_FORCE_THROTTLE_R_N")
	)
	(segment
		(start 351.784412 -230.384858)
		(end 351.784412 -235.341668)
		(width 0.13208)
		(layer "F.Cu")
		(net "BIC_FORCE_THROTTLE_R_N")
	)
	(via
		(at 225.711512 -233.182668)
		(size 0.508)
		(drill 0.254)
		(layers "F.Cu" "B.Cu")
		(net "BIC_FORCE_THROTTLE_R_N")
	)
	(via
		(at 226.401122 -252.572012)
		(size 0.508)
		(drill 0.254)
		(layers "F.Cu" "B.Cu")
		(net "BIC_FORCE_THROTTLE_R_N")
	)
	(via
		(at 351.22485 -236.291374)
		(size 0.508)
		(drill 0.254)
		(layers "F.Cu" "B.Cu")
		(net "BIC_FORCE_THROTTLE_R_N")
	)
	(segment
		(start 225.237548 -232.708704)
		(end 225.237548 -231.758744)
		(width 0.13208)
		(layer "B.Cu")
		(net "BIC_FORCE_THROTTLE_R_N")
	)
	(segment
		(start 225.237548 -231.758744)
		(end 225.370644 -231.625648)
		(width 0.13208)
		(layer "B.Cu")
		(net "BIC_FORCE_THROTTLE_R_N")
	)
	(segment
		(start 225.711512 -233.182668)
		(end 225.237548 -232.708704)
		(width 0.13208)
		(layer "B.Cu")
		(net "BIC_FORCE_THROTTLE_R_N")
	)
	(segment
		(start 225.711512 -234.638342)
		(end 225.711512 -233.182668)
		(width 0.15494)
		(layer "In5.Cu")
		(net "BIC_FORCE_THROTTLE_R_N")
	)
	(segment
		(start 225.3742 -251.54509)
		(end 225.3742 -234.975654)
		(width 0.15494)
		(layer "In5.Cu")
		(net "BIC_FORCE_THROTTLE_R_N")
	)
	(segment
		(start 225.3742 -234.975654)
		(end 225.711512 -234.638342)
		(width 0.15494)
		(layer "In5.Cu")
		(net "BIC_FORCE_THROTTLE_R_N")
	)
	(segment
		(start 226.401122 -252.572012)
		(end 225.3742 -251.54509)
		(width 0.15494)
		(layer "In5.Cu")
		(net "BIC_FORCE_THROTTLE_R_N")
	)
	(segment
		(start 257.27152 -255.6002)
		(end 269.4686 -255.6002)
		(width 0.15494)
		(layer "In15.Cu")
		(net "BIC_FORCE_THROTTLE_R_N")
	)
	(segment
		(start 270.002 -256.1336)
		(end 273.725386 -256.1336)
		(width 0.15494)
		(layer "In15.Cu")
		(net "BIC_FORCE_THROTTLE_R_N")
	)
	(segment
		(start 303.613058 -257.963924)
		(end 315.32703 -257.963924)
		(width 0.15494)
		(layer "In15.Cu")
		(net "BIC_FORCE_THROTTLE_R_N")
	)
	(segment
		(start 269.4686 -255.6002)
		(end 270.002 -256.1336)
		(width 0.15494)
		(layer "In15.Cu")
		(net "BIC_FORCE_THROTTLE_R_N")
	)
	(segment
		(start 351.257362 -236.323886)
		(end 351.22485 -236.291374)
		(width 0.15494)
		(layer "In15.Cu")
		(net "BIC_FORCE_THROTTLE_R_N")
	)
	(segment
		(start 302.922432 -257.273298)
		(end 303.613058 -257.963924)
		(width 0.15494)
		(layer "In15.Cu")
		(net "BIC_FORCE_THROTTLE_R_N")
	)
	(segment
		(start 329.099926 -257.060954)
		(end 329.399646 -256.761234)
		(width 0.15494)
		(layer "In15.Cu")
		(net "BIC_FORCE_THROTTLE_R_N")
	)
	(segment
		(start 273.725386 -256.1336)
		(end 274.865084 -257.273298)
		(width 0.15494)
		(layer "In15.Cu")
		(net "BIC_FORCE_THROTTLE_R_N")
	)
	(segment
		(start 315.32703 -257.963924)
		(end 316.23 -257.060954)
		(width 0.15494)
		(layer "In15.Cu")
		(net "BIC_FORCE_THROTTLE_R_N")
	)
	(segment
		(start 351.257362 -240.945162)
		(end 351.257362 -236.323886)
		(width 0.15494)
		(layer "In15.Cu")
		(net "BIC_FORCE_THROTTLE_R_N")
	)
	(segment
		(start 316.23 -257.060954)
		(end 329.099926 -257.060954)
		(width 0.15494)
		(layer "In15.Cu")
		(net "BIC_FORCE_THROTTLE_R_N")
	)
	(segment
		(start 335.44129 -256.761234)
		(end 351.257362 -240.945162)
		(width 0.15494)
		(layer "In15.Cu")
		(net "BIC_FORCE_THROTTLE_R_N")
	)
	(segment
		(start 226.401122 -252.572012)
		(end 228.74351 -254.9144)
		(width 0.15494)
		(layer "In15.Cu")
		(net "BIC_FORCE_THROTTLE_R_N")
	)
	(segment
		(start 228.74351 -254.9144)
		(end 256.030476 -254.9144)
		(width 0.15494)
		(layer "In15.Cu")
		(net "BIC_FORCE_THROTTLE_R_N")
	)
	(segment
		(start 256.350008 -255.233932)
		(end 256.905252 -255.233932)
		(width 0.15494)
		(layer "In15.Cu")
		(net "BIC_FORCE_THROTTLE_R_N")
	)
	(segment
		(start 256.030476 -254.9144)
		(end 256.350008 -255.233932)
		(width 0.15494)
		(layer "In15.Cu")
		(net "BIC_FORCE_THROTTLE_R_N")
	)
	(segment
		(start 274.865084 -257.273298)
		(end 302.922432 -257.273298)
		(width 0.15494)
		(layer "In15.Cu")
		(net "BIC_FORCE_THROTTLE_R_N")
	)
	(segment
		(start 256.905252 -255.233932)
		(end 257.27152 -255.6002)
		(width 0.15494)
		(layer "In15.Cu")
		(net "BIC_FORCE_THROTTLE_R_N")
	)
	(segment
		(start 329.399646 -256.761234)
		(end 335.44129 -256.761234)
		(width 0.15494)
		(layer "In15.Cu")
		(net "BIC_FORCE_THROTTLE_R_N")
	)
	(segment
		(start 194.932808 -409.191968)
		(end 194.932808 -409.896818)
		(width 0.13208)
		(layer "F.Cu")
		(net "SMB_ALERT_HSC_N")
	)
	(segment
		(start 195.163694 -408.961082)
		(end 194.932808 -409.191968)
		(width 0.13208)
		(layer "F.Cu")
		(net "SMB_ALERT_HSC_N")
	)
	(segment
		(start 194.889628 -408.687016)
		(end 195.163694 -408.961082)
		(width 0.13208)
		(layer "F.Cu")
		(net "SMB_ALERT_HSC_N")
	)
	(segment
		(start 194.889628 -407.58364)
		(end 194.889628 -408.687016)
		(width 0.13208)
		(layer "F.Cu")
		(net "SMB_ALERT_HSC_N")
	)
	(via
		(at 195.163694 -408.961082)
		(size 0.508)
		(drill 0.254)
		(layers "F.Cu" "B.Cu")
		(net "SMB_ALERT_HSC_N")
	)
	(segment
		(start 193.939668 -405.133556)
		(end 193.939668 -403.907244)
		(width 0.13208)
		(layer "F.Cu")
		(net "HSC_ALERT1_R_N")
	)
	(via
		(at 199.058276 -358.388158)
		(size 0.508)
		(drill 0.254)
		(layers "F.Cu" "B.Cu")
		(net "HSC_ALERT1_R_N")
	)
	(via
		(at 193.939668 -403.907244)
		(size 0.508)
		(drill 0.254)
		(layers "F.Cu" "B.Cu")
		(net "HSC_ALERT1_R_N")
	)
	(via
		(at 275.336 -388.5184)
		(size 0.508)
		(drill 0.254)
		(layers "F.Cu" "B.Cu")
		(net "HSC_ALERT1_R_N")
	)
	(via
		(at 202.518772 -373.695468)
		(size 0.508)
		(drill 0.254)
		(layers "F.Cu" "B.Cu")
		(net "HSC_ALERT1_R_N")
	)
	(via
		(at 253.655322 -355.160834)
		(size 0.508)
		(drill 0.254)
		(layers "F.Cu" "B.Cu")
		(net "HSC_ALERT1_R_N")
	)
	(segment
		(start 276.064218 -388.5184)
		(end 275.336 -388.5184)
		(width 0.13208)
		(layer "B.Cu")
		(net "HSC_ALERT1_R_N")
	)
	(segment
		(start 276.53361 -389.498078)
		(end 276.53361 -388.987792)
		(width 0.13208)
		(layer "B.Cu")
		(net "HSC_ALERT1_R_N")
	)
	(segment
		(start 203.22794 -372.9863)
		(end 202.518772 -373.695468)
		(width 0.13208)
		(layer "B.Cu")
		(net "HSC_ALERT1_R_N")
	)
	(segment
		(start 203.014326 -371.088666)
		(end 203.22794 -371.30228)
		(width 0.13208)
		(layer "B.Cu")
		(net "HSC_ALERT1_R_N")
	)
	(segment
		(start 252.411484 -355.160834)
		(end 253.655322 -355.160834)
		(width 0.13208)
		(layer "B.Cu")
		(net "HSC_ALERT1_R_N")
	)
	(segment
		(start 203.22794 -371.30228)
		(end 203.22794 -372.9863)
		(width 0.13208)
		(layer "B.Cu")
		(net "HSC_ALERT1_R_N")
	)
	(segment
		(start 276.53361 -390.463278)
		(end 276.53361 -389.498078)
		(width 0.13208)
		(layer "B.Cu")
		(net "HSC_ALERT1_R_N")
	)
	(segment
		(start 276.53361 -388.987792)
		(end 276.064218 -388.5184)
		(width 0.13208)
		(layer "B.Cu")
		(net "HSC_ALERT1_R_N")
	)
	(segment
		(start 200.379838 -373.695468)
		(end 198.438262 -371.753892)
		(width 0.15494)
		(layer "In5.Cu")
		(net "HSC_ALERT1_R_N")
	)
	(segment
		(start 202.518772 -373.695468)
		(end 200.379838 -373.695468)
		(width 0.15494)
		(layer "In5.Cu")
		(net "HSC_ALERT1_R_N")
	)
	(segment
		(start 187.579 -393.767818)
		(end 193.939668 -400.128486)
		(width 0.15494)
		(layer "In5.Cu")
		(net "HSC_ALERT1_R_N")
	)
	(segment
		(start 198.438262 -371.753892)
		(end 191.97828 -371.753892)
		(width 0.15494)
		(layer "In5.Cu")
		(net "HSC_ALERT1_R_N")
	)
	(segment
		(start 191.97828 -371.753892)
		(end 187.579 -376.153172)
		(width 0.15494)
		(layer "In5.Cu")
		(net "HSC_ALERT1_R_N")
	)
	(segment
		(start 187.579 -376.153172)
		(end 187.579 -393.767818)
		(width 0.15494)
		(layer "In5.Cu")
		(net "HSC_ALERT1_R_N")
	)
	(segment
		(start 193.939668 -400.128486)
		(end 193.939668 -403.907244)
		(width 0.15494)
		(layer "In5.Cu")
		(net "HSC_ALERT1_R_N")
	)
	(segment
		(start 193.9036 -365.2012)
		(end 193.9036 -363.274864)
		(width 0.15494)
		(layer "In7.Cu")
		(net "HSC_ALERT1_R_N")
	)
	(segment
		(start 202.518772 -373.695468)
		(end 200.805288 -373.695468)
		(width 0.15494)
		(layer "In7.Cu")
		(net "HSC_ALERT1_R_N")
	)
	(segment
		(start 196.280786 -369.170966)
		(end 196.280786 -368.791236)
		(width 0.15494)
		(layer "In7.Cu")
		(net "HSC_ALERT1_R_N")
	)
	(segment
		(start 198.198994 -360.485182)
		(end 199.058276 -359.6259)
		(width 0.15494)
		(layer "In7.Cu")
		(net "HSC_ALERT1_R_N")
	)
	(segment
		(start 199.058276 -359.6259)
		(end 199.058276 -358.388158)
		(width 0.15494)
		(layer "In7.Cu")
		(net "HSC_ALERT1_R_N")
	)
	(segment
		(start 193.9036 -363.274864)
		(end 196.693282 -360.485182)
		(width 0.15494)
		(layer "In7.Cu")
		(net "HSC_ALERT1_R_N")
	)
	(segment
		(start 200.805288 -373.695468)
		(end 196.280786 -369.170966)
		(width 0.15494)
		(layer "In7.Cu")
		(net "HSC_ALERT1_R_N")
	)
	(segment
		(start 196.280786 -368.791236)
		(end 194.0306 -366.54105)
		(width 0.15494)
		(layer "In7.Cu")
		(net "HSC_ALERT1_R_N")
	)
	(segment
		(start 194.0306 -365.3282)
		(end 193.9036 -365.2012)
		(width 0.15494)
		(layer "In7.Cu")
		(net "HSC_ALERT1_R_N")
	)
	(segment
		(start 196.693282 -360.485182)
		(end 198.198994 -360.485182)
		(width 0.15494)
		(layer "In7.Cu")
		(net "HSC_ALERT1_R_N")
	)
	(segment
		(start 194.0306 -366.54105)
		(end 194.0306 -365.3282)
		(width 0.15494)
		(layer "In7.Cu")
		(net "HSC_ALERT1_R_N")
	)
	(segment
		(start 274.955 -388.5184)
		(end 275.336 -388.5184)
		(width 0.15494)
		(layer "In9.Cu")
		(net "HSC_ALERT1_R_N")
	)
	(segment
		(start 263.615424 -356.34676)
		(end 269.89786 -362.629196)
		(width 0.15494)
		(layer "In9.Cu")
		(net "HSC_ALERT1_R_N")
	)
	(segment
		(start 277.676864 -375.601992)
		(end 277.676864 -382.499616)
		(width 0.15494)
		(layer "In9.Cu")
		(net "HSC_ALERT1_R_N")
	)
	(segment
		(start 253.655322 -355.160834)
		(end 253.655322 -352.665792)
		(width 0.15494)
		(layer "In9.Cu")
		(net "HSC_ALERT1_R_N")
	)
	(segment
		(start 272.765012 -372.021354)
		(end 274.096226 -372.021354)
		(width 0.15494)
		(layer "In9.Cu")
		(net "HSC_ALERT1_R_N")
	)
	(segment
		(start 254.987806 -351.333308)
		(end 262.937498 -351.333308)
		(width 0.15494)
		(layer "In9.Cu")
		(net "HSC_ALERT1_R_N")
	)
	(segment
		(start 274.591018 -385.585462)
		(end 274.591018 -388.154418)
		(width 0.15494)
		(layer "In9.Cu")
		(net "HSC_ALERT1_R_N")
	)
	(segment
		(start 277.676864 -382.499616)
		(end 274.591018 -385.585462)
		(width 0.15494)
		(layer "In9.Cu")
		(net "HSC_ALERT1_R_N")
	)
	(segment
		(start 274.096226 -372.021354)
		(end 277.676864 -375.601992)
		(width 0.15494)
		(layer "In9.Cu")
		(net "HSC_ALERT1_R_N")
	)
	(segment
		(start 263.615424 -352.011234)
		(end 263.615424 -356.34676)
		(width 0.15494)
		(layer "In9.Cu")
		(net "HSC_ALERT1_R_N")
	)
	(segment
		(start 274.591018 -388.154418)
		(end 274.955 -388.5184)
		(width 0.15494)
		(layer "In9.Cu")
		(net "HSC_ALERT1_R_N")
	)
	(segment
		(start 253.655322 -352.665792)
		(end 254.987806 -351.333308)
		(width 0.15494)
		(layer "In9.Cu")
		(net "HSC_ALERT1_R_N")
	)
	(segment
		(start 262.937498 -351.333308)
		(end 263.615424 -352.011234)
		(width 0.15494)
		(layer "In9.Cu")
		(net "HSC_ALERT1_R_N")
	)
	(segment
		(start 269.89786 -362.629196)
		(end 269.89786 -369.154202)
		(width 0.15494)
		(layer "In9.Cu")
		(net "HSC_ALERT1_R_N")
	)
	(segment
		(start 269.89786 -369.154202)
		(end 272.765012 -372.021354)
		(width 0.15494)
		(layer "In9.Cu")
		(net "HSC_ALERT1_R_N")
	)
	(segment
		(start 250.596654 -358.5464)
		(end 247.370854 -358.5464)
		(width 0.15494)
		(layer "In11.Cu")
		(net "HSC_ALERT1_R_N")
	)
	(segment
		(start 253.655322 -355.160834)
		(end 253.655322 -355.487732)
		(width 0.15494)
		(layer "In11.Cu")
		(net "HSC_ALERT1_R_N")
	)
	(segment
		(start 214.811864 -360.315256)
		(end 211.840064 -357.343456)
		(width 0.15494)
		(layer "In11.Cu")
		(net "HSC_ALERT1_R_N")
	)
	(segment
		(start 237.287054 -360.2736)
		(end 236.321854 -361.2388)
		(width 0.15494)
		(layer "In11.Cu")
		(net "HSC_ALERT1_R_N")
	)
	(segment
		(start 200.689464 -356.75697)
		(end 199.058276 -358.388158)
		(width 0.15494)
		(layer "In11.Cu")
		(net "HSC_ALERT1_R_N")
	)
	(segment
		(start 245.643654 -360.2736)
		(end 237.287054 -360.2736)
		(width 0.15494)
		(layer "In11.Cu")
		(net "HSC_ALERT1_R_N")
	)
	(segment
		(start 224.998788 -361.2388)
		(end 224.075244 -360.315256)
		(width 0.15494)
		(layer "In11.Cu")
		(net "HSC_ALERT1_R_N")
	)
	(segment
		(start 203.192634 -357.343456)
		(end 202.606148 -356.75697)
		(width 0.15494)
		(layer "In11.Cu")
		(net "HSC_ALERT1_R_N")
	)
	(segment
		(start 224.075244 -360.315256)
		(end 214.811864 -360.315256)
		(width 0.15494)
		(layer "In11.Cu")
		(net "HSC_ALERT1_R_N")
	)
	(segment
		(start 202.606148 -356.75697)
		(end 200.689464 -356.75697)
		(width 0.15494)
		(layer "In11.Cu")
		(net "HSC_ALERT1_R_N")
	)
	(segment
		(start 211.840064 -357.343456)
		(end 203.192634 -357.343456)
		(width 0.15494)
		(layer "In11.Cu")
		(net "HSC_ALERT1_R_N")
	)
	(segment
		(start 236.321854 -361.2388)
		(end 224.998788 -361.2388)
		(width 0.15494)
		(layer "In11.Cu")
		(net "HSC_ALERT1_R_N")
	)
	(segment
		(start 247.370854 -358.5464)
		(end 245.643654 -360.2736)
		(width 0.15494)
		(layer "In11.Cu")
		(net "HSC_ALERT1_R_N")
	)
	(segment
		(start 253.655322 -355.487732)
		(end 250.596654 -358.5464)
		(width 0.15494)
		(layer "In11.Cu")
		(net "HSC_ALERT1_R_N")
	)
	(segment
		(start 225.212656 -209.732118)
		(end 224.741486 -210.203288)
		(width 0.13208)
		(layer "F.Cu")
		(net "RST_SMB_FPGA_N")
	)
	(segment
		(start 224.514664 -207.673194)
		(end 224.514664 -207.42021)
		(width 0.13208)
		(layer "F.Cu")
		(net "RST_SMB_FPGA_N")
	)
	(segment
		(start 225.212656 -208.371186)
		(end 224.514664 -207.673194)
		(width 0.13208)
		(layer "F.Cu")
		(net "RST_SMB_FPGA_N")
	)
	(segment
		(start 225.212656 -209.732118)
		(end 225.212656 -208.371186)
		(width 0.13208)
		(layer "F.Cu")
		(net "RST_SMB_FPGA_N")
	)
	(segment
		(start 225.874072 -212.697822)
		(end 225.867722 -212.704172)
		(width 0.13208)
		(layer "F.Cu")
		(net "RST_SMB_FPGA_N")
	)
	(segment
		(start 224.741486 -210.203288)
		(end 224.741486 -210.56854)
		(width 0.13208)
		(layer "F.Cu")
		(net "RST_SMB_FPGA_N")
	)
	(segment
		(start 225.874072 -211.701126)
		(end 225.874072 -212.697822)
		(width 0.13208)
		(layer "F.Cu")
		(net "RST_SMB_FPGA_N")
	)
	(segment
		(start 224.741486 -210.56854)
		(end 225.874072 -211.701126)
		(width 0.13208)
		(layer "F.Cu")
		(net "RST_SMB_FPGA_N")
	)
	(via
		(at 225.212656 -209.732118)
		(size 0.762)
		(drill 0.381)
		(layers "F.Cu" "B.Cu")
		(net "RST_SMB_FPGA_N")
	)
	(segment
		(start 214.136986 -210.67522)
		(end 213.719918 -210.258152)
		(width 0.13208)
		(layer "F.Cu")
		(net "RST_SSD_LED_IOEXP_R_N")
	)
	(segment
		(start 209.163158 -85.691472)
		(end 210.44408 -84.41055)
		(width 0.13208)
		(layer "F.Cu")
		(net "RST_SSD_LED_IOEXP_R_N")
	)
	(segment
		(start 213.719918 -210.174586)
		(end 213.719918 -209.342482)
		(width 0.13208)
		(layer "F.Cu")
		(net "RST_SSD_LED_IOEXP_R_N")
	)
	(segment
		(start 210.44408 -84.41055)
		(end 211.572094 -84.41055)
		(width 0.13208)
		(layer "F.Cu")
		(net "RST_SSD_LED_IOEXP_R_N")
	)
	(segment
		(start 215.70061 -210.232244)
		(end 215.638634 -210.232244)
		(width 0.13208)
		(layer "F.Cu")
		(net "RST_SSD_LED_IOEXP_R_N")
	)
	(segment
		(start 215.638634 -210.232244)
		(end 215.195658 -210.67522)
		(width 0.13208)
		(layer "F.Cu")
		(net "RST_SSD_LED_IOEXP_R_N")
	)
	(segment
		(start 216.798652 -210.232244)
		(end 215.70061 -210.232244)
		(width 0.13208)
		(layer "F.Cu")
		(net "RST_SSD_LED_IOEXP_R_N")
	)
	(segment
		(start 216.854024 -210.176872)
		(end 216.798652 -210.232244)
		(width 0.13208)
		(layer "F.Cu")
		(net "RST_SSD_LED_IOEXP_R_N")
	)
	(segment
		(start 204.991208 -85.691472)
		(end 209.163158 -85.691472)
		(width 0.13208)
		(layer "F.Cu")
		(net "RST_SSD_LED_IOEXP_R_N")
	)
	(segment
		(start 215.195658 -210.67522)
		(end 214.136986 -210.67522)
		(width 0.13208)
		(layer "F.Cu")
		(net "RST_SSD_LED_IOEXP_R_N")
	)
	(segment
		(start 214.74049 -90.467688)
		(end 214.74049 -86.089744)
		(width 0.13208)
		(layer "F.Cu")
		(net "RST_SSD_LED_IOEXP_R_N")
	)
	(segment
		(start 214.74049 -86.089744)
		(end 213.061296 -84.41055)
		(width 0.13208)
		(layer "F.Cu")
		(net "RST_SSD_LED_IOEXP_R_N")
	)
	(segment
		(start 215.078056 -208.798668)
		(end 215.448896 -209.169508)
		(width 0.13208)
		(layer "F.Cu")
		(net "RST_SSD_LED_IOEXP_R_N")
	)
	(segment
		(start 213.719918 -210.258152)
		(end 213.719918 -210.174586)
		(width 0.13208)
		(layer "F.Cu")
		(net "RST_SSD_LED_IOEXP_R_N")
	)
	(segment
		(start 213.719918 -209.342482)
		(end 214.263732 -208.798668)
		(width 0.13208)
		(layer "F.Cu")
		(net "RST_SSD_LED_IOEXP_R_N")
	)
	(segment
		(start 214.263732 -208.798668)
		(end 215.078056 -208.798668)
		(width 0.13208)
		(layer "F.Cu")
		(net "RST_SSD_LED_IOEXP_R_N")
	)
	(segment
		(start 213.061296 -84.41055)
		(end 211.572094 -84.41055)
		(width 0.13208)
		(layer "F.Cu")
		(net "RST_SSD_LED_IOEXP_R_N")
	)
	(via
		(at 214.74049 -90.467688)
		(size 0.508)
		(drill 0.254)
		(layers "F.Cu" "B.Cu")
		(net "RST_SSD_LED_IOEXP_R_N")
	)
	(via
		(at 215.448896 -209.169508)
		(size 0.508)
		(drill 0.254)
		(layers "F.Cu" "B.Cu")
		(net "RST_SSD_LED_IOEXP_R_N")
	)
	(segment
		(start 219.15374 -198.971916)
		(end 218.31808 -199.807576)
		(width 0.15494)
		(layer "In7.Cu")
		(net "RST_SSD_LED_IOEXP_R_N")
	)
	(segment
		(start 215.47709 -209.141314)
		(end 215.448896 -209.169508)
		(width 0.15494)
		(layer "In7.Cu")
		(net "RST_SSD_LED_IOEXP_R_N")
	)
	(segment
		(start 214.8078 -132.588)
		(end 214.8078 -153.143458)
		(width 0.15494)
		(layer "In7.Cu")
		(net "RST_SSD_LED_IOEXP_R_N")
	)
	(segment
		(start 209.9818 -123.2662)
		(end 210.5152 -123.7996)
		(width 0.15494)
		(layer "In7.Cu")
		(net "RST_SSD_LED_IOEXP_R_N")
	)
	(segment
		(start 220.1926 -195.8848)
		(end 219.15374 -196.92366)
		(width 0.15494)
		(layer "In7.Cu")
		(net "RST_SSD_LED_IOEXP_R_N")
	)
	(segment
		(start 218.634564 -185.218324)
		(end 220.1672 -186.75096)
		(width 0.15494)
		(layer "In7.Cu")
		(net "RST_SSD_LED_IOEXP_R_N")
	)
	(segment
		(start 218.31808 -199.807576)
		(end 218.31808 -200.382378)
		(width 0.15494)
		(layer "In7.Cu")
		(net "RST_SSD_LED_IOEXP_R_N")
	)
	(segment
		(start 214.74049 -101.08311)
		(end 214.72652 -101.09708)
		(width 0.15494)
		(layer "In7.Cu")
		(net "RST_SSD_LED_IOEXP_R_N")
	)
	(segment
		(start 214.72652 -101.127306)
		(end 212.542628 -103.311198)
		(width 0.15494)
		(layer "In7.Cu")
		(net "RST_SSD_LED_IOEXP_R_N")
	)
	(segment
		(start 219.4814 -168.503346)
		(end 218.781884 -169.202862)
		(width 0.15494)
		(layer "In7.Cu")
		(net "RST_SSD_LED_IOEXP_R_N")
	)
	(segment
		(start 216.9668 -207.42656)
		(end 215.47709 -208.91627)
		(width 0.15494)
		(layer "In7.Cu")
		(net "RST_SSD_LED_IOEXP_R_N")
	)
	(segment
		(start 219.15374 -196.92366)
		(end 219.15374 -198.971916)
		(width 0.15494)
		(layer "In7.Cu")
		(net "RST_SSD_LED_IOEXP_R_N")
	)
	(segment
		(start 219.4814 -157.817058)
		(end 219.4814 -168.503346)
		(width 0.15494)
		(layer "In7.Cu")
		(net "RST_SSD_LED_IOEXP_R_N")
	)
	(segment
		(start 220.1672 -186.75096)
		(end 220.1672 -191.4144)
		(width 0.15494)
		(layer "In7.Cu")
		(net "RST_SSD_LED_IOEXP_R_N")
	)
	(segment
		(start 220.1926 -195.097146)
		(end 220.1926 -195.8848)
		(width 0.15494)
		(layer "In7.Cu")
		(net "RST_SSD_LED_IOEXP_R_N")
	)
	(segment
		(start 218.634564 -176.358804)
		(end 218.634564 -185.218324)
		(width 0.15494)
		(layer "In7.Cu")
		(net "RST_SSD_LED_IOEXP_R_N")
	)
	(segment
		(start 216.9668 -205.105)
		(end 216.9668 -207.42656)
		(width 0.15494)
		(layer "In7.Cu")
		(net "RST_SSD_LED_IOEXP_R_N")
	)
	(segment
		(start 218.771724 -173.55693)
		(end 218.334082 -173.994572)
		(width 0.15494)
		(layer "In7.Cu")
		(net "RST_SSD_LED_IOEXP_R_N")
	)
	(segment
		(start 219.2528 -194.157346)
		(end 220.1926 -195.097146)
		(width 0.15494)
		(layer "In7.Cu")
		(net "RST_SSD_LED_IOEXP_R_N")
	)
	(segment
		(start 218.781884 -172.41647)
		(end 218.771724 -172.42663)
		(width 0.15494)
		(layer "In7.Cu")
		(net "RST_SSD_LED_IOEXP_R_N")
	)
	(segment
		(start 220.1672 -191.4144)
		(end 219.2528 -192.3288)
		(width 0.15494)
		(layer "In7.Cu")
		(net "RST_SSD_LED_IOEXP_R_N")
	)
	(segment
		(start 210.5152 -123.7996)
		(end 210.5152 -128.2954)
		(width 0.15494)
		(layer "In7.Cu")
		(net "RST_SSD_LED_IOEXP_R_N")
	)
	(segment
		(start 218.31808 -200.382378)
		(end 218.386914 -200.548494)
		(width 0.15494)
		(layer "In7.Cu")
		(net "RST_SSD_LED_IOEXP_R_N")
	)
	(segment
		(start 218.781884 -169.202862)
		(end 218.781884 -172.41647)
		(width 0.15494)
		(layer "In7.Cu")
		(net "RST_SSD_LED_IOEXP_R_N")
	)
	(segment
		(start 218.694 -200.85558)
		(end 218.694 -203.3778)
		(width 0.15494)
		(layer "In7.Cu")
		(net "RST_SSD_LED_IOEXP_R_N")
	)
	(segment
		(start 214.72652 -101.09708)
		(end 214.72652 -101.127306)
		(width 0.15494)
		(layer "In7.Cu")
		(net "RST_SSD_LED_IOEXP_R_N")
	)
	(segment
		(start 214.8078 -153.143458)
		(end 219.4814 -157.817058)
		(width 0.15494)
		(layer "In7.Cu")
		(net "RST_SSD_LED_IOEXP_R_N")
	)
	(segment
		(start 214.74049 -90.467688)
		(end 214.74049 -101.08311)
		(width 0.15494)
		(layer "In7.Cu")
		(net "RST_SSD_LED_IOEXP_R_N")
	)
	(segment
		(start 215.47709 -208.91627)
		(end 215.47709 -209.141314)
		(width 0.15494)
		(layer "In7.Cu")
		(net "RST_SSD_LED_IOEXP_R_N")
	)
	(segment
		(start 218.386914 -200.548494)
		(end 218.694 -200.85558)
		(width 0.15494)
		(layer "In7.Cu")
		(net "RST_SSD_LED_IOEXP_R_N")
	)
	(segment
		(start 212.542628 -103.311198)
		(end 212.542628 -119.359172)
		(width 0.15494)
		(layer "In7.Cu")
		(net "RST_SSD_LED_IOEXP_R_N")
	)
	(segment
		(start 209.9818 -121.92)
		(end 209.9818 -123.2662)
		(width 0.15494)
		(layer "In7.Cu")
		(net "RST_SSD_LED_IOEXP_R_N")
	)
	(segment
		(start 219.2528 -192.3288)
		(end 219.2528 -194.157346)
		(width 0.15494)
		(layer "In7.Cu")
		(net "RST_SSD_LED_IOEXP_R_N")
	)
	(segment
		(start 210.5152 -128.2954)
		(end 214.8078 -132.588)
		(width 0.15494)
		(layer "In7.Cu")
		(net "RST_SSD_LED_IOEXP_R_N")
	)
	(segment
		(start 212.542628 -119.359172)
		(end 209.9818 -121.92)
		(width 0.15494)
		(layer "In7.Cu")
		(net "RST_SSD_LED_IOEXP_R_N")
	)
	(segment
		(start 218.334082 -173.994572)
		(end 218.334082 -176.058322)
		(width 0.15494)
		(layer "In7.Cu")
		(net "RST_SSD_LED_IOEXP_R_N")
	)
	(segment
		(start 218.334082 -176.058322)
		(end 218.634564 -176.358804)
		(width 0.15494)
		(layer "In7.Cu")
		(net "RST_SSD_LED_IOEXP_R_N")
	)
	(segment
		(start 218.771724 -172.42663)
		(end 218.771724 -173.55693)
		(width 0.15494)
		(layer "In7.Cu")
		(net "RST_SSD_LED_IOEXP_R_N")
	)
	(segment
		(start 218.694 -203.3778)
		(end 216.9668 -205.105)
		(width 0.15494)
		(layer "In7.Cu")
		(net "RST_SSD_LED_IOEXP_R_N")
	)
	(segment
		(start 202.500992 -23.589996)
		(end 201.932794 -24.158194)
		(width 0.13208)
		(layer "F.Cu")
		(net "RST_SMB_SSD7_ISO_R_N")
	)
	(segment
		(start 204.764894 -23.589996)
		(end 202.500992 -23.589996)
		(width 0.13208)
		(layer "F.Cu")
		(net "RST_SMB_SSD7_ISO_R_N")
	)
	(segment
		(start 199.001888 -32.449262)
		(end 199.001888 -32.083502)
		(width 0.13208)
		(layer "F.Cu")
		(net "RST_SMB_SSD7_ISO_R_N")
	)
	(segment
		(start 199.001888 -32.083502)
		(end 199.308212 -31.777178)
		(width 0.13208)
		(layer "F.Cu")
		(net "RST_SMB_SSD7_ISO_R_N")
	)
	(via
		(at 199.308212 -31.777178)
		(size 0.508)
		(drill 0.254)
		(layers "F.Cu" "B.Cu")
		(net "RST_SMB_SSD7_ISO_R_N")
	)
	(via
		(at 201.932794 -24.158194)
		(size 0.508)
		(drill 0.254)
		(layers "F.Cu" "B.Cu")
		(net "RST_SMB_SSD7_ISO_R_N")
	)
	(segment
		(start 199.308212 -31.777178)
		(end 199.308212 -29.520642)
		(width 0.15494)
		(layer "In5.Cu")
		(net "RST_SMB_SSD7_ISO_R_N")
	)
	(segment
		(start 199.308212 -29.520642)
		(end 201.932794 -26.89606)
		(width 0.15494)
		(layer "In5.Cu")
		(net "RST_SMB_SSD7_ISO_R_N")
	)
	(segment
		(start 201.932794 -26.89606)
		(end 201.932794 -24.158194)
		(width 0.15494)
		(layer "In5.Cu")
		(net "RST_SMB_SSD7_ISO_R_N")
	)
	(segment
		(start 218.859354 -210.176872)
		(end 217.654124 -210.176872)
		(width 0.13208)
		(layer "F.Cu")
		(net "RST_SSD_LED_IOEXP_N")
	)
	(segment
		(start 220.802454 -209.996786)
		(end 220.74759 -209.941922)
		(width 0.13208)
		(layer "F.Cu")
		(net "RST_SSD_LED_IOEXP_N")
	)
	(segment
		(start 220.74759 -209.941922)
		(end 219.094304 -209.941922)
		(width 0.13208)
		(layer "F.Cu")
		(net "RST_SSD_LED_IOEXP_N")
	)
	(segment
		(start 220.802454 -212.224874)
		(end 220.802454 -209.996786)
		(width 0.13208)
		(layer "F.Cu")
		(net "RST_SSD_LED_IOEXP_N")
	)
	(segment
		(start 223.869504 -213.106)
		(end 224.267776 -213.504272)
		(width 0.13208)
		(layer "F.Cu")
		(net "RST_SSD_LED_IOEXP_N")
	)
	(segment
		(start 223.117664 -213.106)
		(end 223.869504 -213.106)
		(width 0.13208)
		(layer "F.Cu")
		(net "RST_SSD_LED_IOEXP_N")
	)
	(segment
		(start 222.598488 -212.586824)
		(end 223.117664 -213.106)
		(width 0.13208)
		(layer "F.Cu")
		(net "RST_SSD_LED_IOEXP_N")
	)
	(segment
		(start 220.440504 -212.586824)
		(end 222.598488 -212.586824)
		(width 0.13208)
		(layer "F.Cu")
		(net "RST_SSD_LED_IOEXP_N")
	)
	(segment
		(start 220.440504 -212.586824)
		(end 220.802454 -212.224874)
		(width 0.13208)
		(layer "F.Cu")
		(net "RST_SSD_LED_IOEXP_N")
	)
	(segment
		(start 219.094304 -209.941922)
		(end 218.859354 -210.176872)
		(width 0.13208)
		(layer "F.Cu")
		(net "RST_SSD_LED_IOEXP_N")
	)
	(via
		(at 220.440504 -212.586824)
		(size 0.762)
		(drill 0.381)
		(layers "F.Cu" "B.Cu")
		(net "RST_SSD_LED_IOEXP_N")
	)
	(segment
		(start 192.893188 -36.453572)
		(end 192.410588 -36.453572)
		(width 0.13208)
		(layer "F.Cu")
		(net "RST_SMB_SSD7_N")
	)
	(segment
		(start 196.215 -36.6268)
		(end 196.088 -36.7538)
		(width 0.13208)
		(layer "F.Cu")
		(net "RST_SMB_SSD7_N")
	)
	(segment
		(start 196.215 -35.633406)
		(end 196.215 -36.6268)
		(width 0.13208)
		(layer "F.Cu")
		(net "RST_SMB_SSD7_N")
	)
	(segment
		(start 195.224146 -36.7538)
		(end 194.580256 -36.10991)
		(width 0.13208)
		(layer "F.Cu")
		(net "RST_SMB_SSD7_N")
	)
	(segment
		(start 194.580256 -36.10991)
		(end 192.468246 -36.10991)
		(width 0.13208)
		(layer "F.Cu")
		(net "RST_SMB_SSD7_N")
	)
	(segment
		(start 192.982088 -36.542472)
		(end 192.893188 -36.453572)
		(width 0.13208)
		(layer "F.Cu")
		(net "RST_SMB_SSD7_N")
	)
	(segment
		(start 196.064124 -35.48253)
		(end 196.215 -35.633406)
		(width 0.13208)
		(layer "F.Cu")
		(net "RST_SMB_SSD7_N")
	)
	(segment
		(start 192.468246 -36.10991)
		(end 192.410588 -36.167568)
		(width 0.13208)
		(layer "F.Cu")
		(net "RST_SMB_SSD7_N")
	)
	(segment
		(start 195.695316 -35.48253)
		(end 196.064124 -35.48253)
		(width 0.13208)
		(layer "F.Cu")
		(net "RST_SMB_SSD7_N")
	)
	(segment
		(start 192.410588 -36.167568)
		(end 192.410588 -36.453572)
		(width 0.13208)
		(layer "F.Cu")
		(net "RST_SMB_SSD7_N")
	)
	(segment
		(start 192.982088 -37.025072)
		(end 192.982088 -36.542472)
		(width 0.13208)
		(layer "F.Cu")
		(net "RST_SMB_SSD7_N")
	)
	(segment
		(start 196.088 -36.7538)
		(end 195.224146 -36.7538)
		(width 0.13208)
		(layer "F.Cu")
		(net "RST_SMB_SSD7_N")
	)
	(via
		(at 192.410588 -36.453572)
		(size 0.508)
		(drill 0.254)
		(layers "F.Cu" "B.Cu")
		(net "RST_SMB_SSD7_N")
	)
	(segment
		(start 173.00194 -32.449262)
		(end 173.00194 -32.083502)
		(width 0.13208)
		(layer "F.Cu")
		(net "RST_SMB_SSD6_ISO_R_N")
	)
	(segment
		(start 176.501044 -23.589996)
		(end 175.932846 -24.158194)
		(width 0.13208)
		(layer "F.Cu")
		(net "RST_SMB_SSD6_ISO_R_N")
	)
	(segment
		(start 178.764946 -23.589996)
		(end 176.501044 -23.589996)
		(width 0.13208)
		(layer "F.Cu")
		(net "RST_SMB_SSD6_ISO_R_N")
	)
	(segment
		(start 173.00194 -32.083502)
		(end 173.308264 -31.777178)
		(width 0.13208)
		(layer "F.Cu")
		(net "RST_SMB_SSD6_ISO_R_N")
	)
	(via
		(at 173.308264 -31.777178)
		(size 0.508)
		(drill 0.254)
		(layers "F.Cu" "B.Cu")
		(net "RST_SMB_SSD6_ISO_R_N")
	)
	(via
		(at 175.932846 -24.158194)
		(size 0.508)
		(drill 0.254)
		(layers "F.Cu" "B.Cu")
		(net "RST_SMB_SSD6_ISO_R_N")
	)
	(segment
		(start 173.308264 -29.510482)
		(end 175.932846 -26.8859)
		(width 0.15494)
		(layer "In5.Cu")
		(net "RST_SMB_SSD6_ISO_R_N")
	)
	(segment
		(start 175.932846 -26.8859)
		(end 175.932846 -24.158194)
		(width 0.15494)
		(layer "In5.Cu")
		(net "RST_SMB_SSD6_ISO_R_N")
	)
	(segment
		(start 173.308264 -31.777178)
		(end 173.308264 -29.510482)
		(width 0.15494)
		(layer "In5.Cu")
		(net "RST_SMB_SSD6_ISO_R_N")
	)
	(segment
		(start 273.799808 -282.599892)
		(end 273.324828 -282.124912)
		(width 0.13208)
		(layer "F.Cu")
		(net "Net_1355")
	)
	(via
		(at 273.324828 -282.124912)
		(size 0.4064)
		(drill 0.2032)
		(layers "F.Cu" "B.Cu")
		(net "Net_1355")
	)
	(segment
		(start 154.850084 -288.299906)
		(end 154.375104 -287.824926)
		(width 0.13208)
		(layer "F.Cu")
		(net "Net_1357")
	)
	(via
		(at 154.375104 -287.824926)
		(size 0.4064)
		(drill 0.2032)
		(layers "F.Cu" "B.Cu")
		(net "Net_1357")
	)
	(segment
		(start 192.850008 -297.79976)
		(end 193.324988 -298.27474)
		(width 0.127)
		(layer "F.Cu")
		(net "Net_1358")
	)
	(via
		(at 193.324988 -298.27474)
		(size 0.4064)
		(drill 0.2032)
		(layers "F.Cu" "B.Cu")
		(net "Net_1358")
	)
	(segment
		(start 275.699728 -280.699718)
		(end 275.224748 -280.224738)
		(width 0.13208)
		(layer "F.Cu")
		(net "Net_1359")
	)
	(via
		(at 275.224748 -280.224738)
		(size 0.4064)
		(drill 0.2032)
		(layers "F.Cu" "B.Cu")
		(net "Net_1359")
	)
	(segment
		(start 389.899906 -280.699718)
		(end 389.424926 -280.224738)
		(width 0.13208)
		(layer "F.Cu")
		(net "Net_1361")
	)
	(via
		(at 389.424926 -280.224738)
		(size 0.4064)
		(drill 0.2032)
		(layers "F.Cu" "B.Cu")
		(net "Net_1361")
	)
	(segment
		(start 154.850084 -282.599892)
		(end 154.375104 -282.124912)
		(width 0.13208)
		(layer "F.Cu")
		(net "Net_1363")
	)
	(via
		(at 154.375104 -282.124912)
		(size 0.4064)
		(drill 0.2032)
		(layers "F.Cu" "B.Cu")
		(net "Net_1363")
	)
	(segment
		(start 190.950088 -291.149786)
		(end 190.475108 -291.624766)
		(width 0.13208)
		(layer "F.Cu")
		(net "Net_1364")
	)
	(via
		(at 190.475108 -291.624766)
		(size 0.4064)
		(drill 0.2032)
		(layers "F.Cu" "B.Cu")
		(net "Net_1364")
	)
	(segment
		(start 391.799826 -283.549852)
		(end 391.324846 -283.074872)
		(width 0.13208)
		(layer "F.Cu")
		(net "Net_1365")
	)
	(via
		(at 391.324846 -283.074872)
		(size 0.4064)
		(drill 0.2032)
		(layers "F.Cu" "B.Cu")
		(net "Net_1365")
	)
	(segment
		(start 276.649688 -283.549852)
		(end 276.174708 -283.074872)
		(width 0.13208)
		(layer "F.Cu")
		(net "Net_1368")
	)
	(via
		(at 276.174708 -283.074872)
		(size 0.4064)
		(drill 0.2032)
		(layers "F.Cu" "B.Cu")
		(net "Net_1368")
	)
	(segment
		(start 153.89987 -287.349946)
		(end 153.42489 -286.874966)
		(width 0.13208)
		(layer "F.Cu")
		(net "Net_1370")
	)
	(via
		(at 153.42489 -286.874966)
		(size 0.4064)
		(drill 0.2032)
		(layers "F.Cu" "B.Cu")
		(net "Net_1370")
	)
	(segment
		(start 190.950088 -293.04996)
		(end 190.475108 -293.52494)
		(width 0.13208)
		(layer "F.Cu")
		(net "Net_1374")
	)
	(via
		(at 190.475108 -293.52494)
		(size 0.4064)
		(drill 0.2032)
		(layers "F.Cu" "B.Cu")
		(net "Net_1374")
	)
	(segment
		(start 389.899906 -282.599892)
		(end 389.424926 -282.124912)
		(width 0.13208)
		(layer "F.Cu")
		(net "Net_1376")
	)
	(via
		(at 389.424926 -282.124912)
		(size 0.4064)
		(drill 0.2032)
		(layers "F.Cu" "B.Cu")
		(net "Net_1376")
	)
	(segment
		(start 193.799968 -299.699934)
		(end 194.274948 -300.174914)
		(width 0.127)
		(layer "F.Cu")
		(net "Net_1377")
	)
	(via
		(at 194.274948 -300.174914)
		(size 0.4064)
		(drill 0.2032)
		(layers "F.Cu" "B.Cu")
		(net "Net_1377")
	)
	(segment
		(start 390.849866 -282.599892)
		(end 390.374886 -282.124912)
		(width 0.13208)
		(layer "F.Cu")
		(net "Net_1378")
	)
	(via
		(at 390.374886 -282.124912)
		(size 0.4064)
		(drill 0.2032)
		(layers "F.Cu" "B.Cu")
		(net "Net_1378")
	)
	(segment
		(start 154.850084 -273.099784)
		(end 154.375104 -272.624804)
		(width 0.13208)
		(layer "F.Cu")
		(net "Net_1380")
	)
	(via
		(at 154.375104 -272.624804)
		(size 0.4064)
		(drill 0.2032)
		(layers "F.Cu" "B.Cu")
		(net "Net_1380")
	)
	(segment
		(start 152.94991 -287.349946)
		(end 152.47493 -286.874966)
		(width 0.13208)
		(layer "F.Cu")
		(net "Net_1382")
	)
	(via
		(at 152.47493 -286.874966)
		(size 0.4064)
		(drill 0.2032)
		(layers "F.Cu" "B.Cu")
		(net "Net_1382")
	)
	(segment
		(start 192.850008 -299.699934)
		(end 193.324988 -300.174914)
		(width 0.127)
		(layer "F.Cu")
		(net "Net_1384")
	)
	(via
		(at 193.324988 -300.174914)
		(size 0.4064)
		(drill 0.2032)
		(layers "F.Cu" "B.Cu")
		(net "Net_1384")
	)
	(segment
		(start 193.799968 -290.199826)
		(end 194.274948 -290.674806)
		(width 0.13208)
		(layer "F.Cu")
		(net "Net_1385")
	)
	(via
		(at 194.274948 -290.674806)
		(size 0.4064)
		(drill 0.2032)
		(layers "F.Cu" "B.Cu")
		(net "Net_1385")
	)
	(segment
		(start 153.89987 -289.249866)
		(end 153.42489 -288.774886)
		(width 0.13208)
		(layer "F.Cu")
		(net "Net_1386")
	)
	(via
		(at 153.42489 -288.774886)
		(size 0.4064)
		(drill 0.2032)
		(layers "F.Cu" "B.Cu")
		(net "Net_1386")
	)
	(segment
		(start 269.999714 -279.749758)
		(end 269.524734 -279.274778)
		(width 0.13208)
		(layer "F.Cu")
		(net "Net_1387")
	)
	(via
		(at 269.524734 -279.274778)
		(size 0.4064)
		(drill 0.2032)
		(layers "F.Cu" "B.Cu")
		(net "Net_1387")
	)
	(segment
		(start 193.799968 -292.099746)
		(end 194.274948 -292.574726)
		(width 0.13208)
		(layer "F.Cu")
		(net "Net_1388")
	)
	(via
		(at 194.274948 -292.574726)
		(size 0.4064)
		(drill 0.2032)
		(layers "F.Cu" "B.Cu")
		(net "Net_1388")
	)
	(segment
		(start 153.89987 -281.649932)
		(end 153.42489 -281.174952)
		(width 0.13208)
		(layer "F.Cu")
		(net "Net_1389")
	)
	(via
		(at 153.42489 -281.174952)
		(size 0.4064)
		(drill 0.2032)
		(layers "F.Cu" "B.Cu")
		(net "Net_1389")
	)
	(segment
		(start 273.799808 -279.749758)
		(end 273.324828 -279.274778)
		(width 0.13208)
		(layer "F.Cu")
		(net "Net_1391")
	)
	(via
		(at 273.324828 -279.274778)
		(size 0.4064)
		(drill 0.2032)
		(layers "F.Cu" "B.Cu")
		(net "Net_1391")
	)
	(segment
		(start 427.89983 -293.99992)
		(end 427.42485 -293.52494)
		(width 0.13208)
		(layer "F.Cu")
		(net "Net_1393")
	)
	(via
		(at 427.42485 -293.52494)
		(size 0.4064)
		(drill 0.2032)
		(layers "F.Cu" "B.Cu")
		(net "Net_1393")
	)
	(segment
		(start 390.849866 -277.849838)
		(end 390.374886 -277.374858)
		(width 0.13208)
		(layer "F.Cu")
		(net "Net_1395")
	)
	(via
		(at 390.374886 -277.374858)
		(size 0.4064)
		(drill 0.2032)
		(layers "F.Cu" "B.Cu")
		(net "Net_1395")
	)
	(segment
		(start 272.374868 -277.374858)
		(end 272.849848 -277.849838)
		(width 0.13208)
		(layer "F.Cu")
		(net "Net_1396")
	)
	(via
		(at 272.374868 -277.374858)
		(size 0.4064)
		(drill 0.2032)
		(layers "F.Cu" "B.Cu")
		(net "Net_1396")
	)
	(segment
		(start 191.900048 -293.04996)
		(end 191.425068 -293.52494)
		(width 0.13208)
		(layer "F.Cu")
		(net "Net_1397")
	)
	(via
		(at 191.425068 -293.52494)
		(size 0.4064)
		(drill 0.2032)
		(layers "F.Cu" "B.Cu")
		(net "Net_1397")
	)
	(segment
		(start 153.89987 -283.549852)
		(end 153.42489 -283.074872)
		(width 0.13208)
		(layer "F.Cu")
		(net "Net_1398")
	)
	(via
		(at 153.42489 -283.074872)
		(size 0.4064)
		(drill 0.2032)
		(layers "F.Cu" "B.Cu")
		(net "Net_1398")
	)
	(segment
		(start 192.850008 -292.099746)
		(end 193.324988 -292.574726)
		(width 0.13208)
		(layer "F.Cu")
		(net "Net_1399")
	)
	(via
		(at 193.324988 -292.574726)
		(size 0.4064)
		(drill 0.2032)
		(layers "F.Cu" "B.Cu")
		(net "Net_1399")
	)
	(segment
		(start 159.599884 -274.999958)
		(end 159.124904 -274.524978)
		(width 0.13208)
		(layer "F.Cu")
		(net "Net_1400")
	)
	(via
		(at 159.124904 -274.524978)
		(size 0.4064)
		(drill 0.2032)
		(layers "F.Cu" "B.Cu")
		(net "Net_1400")
	)
	(segment
		(start 270.949928 -278.799798)
		(end 270.474948 -278.324818)
		(width 0.13208)
		(layer "F.Cu")
		(net "Net_1402")
	)
	(via
		(at 270.474948 -278.324818)
		(size 0.4064)
		(drill 0.2032)
		(layers "F.Cu" "B.Cu")
		(net "Net_1402")
	)
	(segment
		(start 191.900048 -296.8498)
		(end 191.425068 -297.32478)
		(width 0.127)
		(layer "F.Cu")
		(net "Net_1403")
	)
	(via
		(at 191.425068 -297.32478)
		(size 0.4064)
		(drill 0.2032)
		(layers "F.Cu" "B.Cu")
		(net "Net_1403")
	)
	(segment
		(start 387.999986 -274.999958)
		(end 387.525006 -274.524978)
		(width 0.13208)
		(layer "F.Cu")
		(net "Net_1404")
	)
	(via
		(at 387.525006 -274.524978)
		(size 0.4064)
		(drill 0.2032)
		(layers "F.Cu" "B.Cu")
		(net "Net_1404")
	)
	(segment
		(start 429.800004 -298.74972)
		(end 430.274984 -298.27474)
		(width 0.13208)
		(layer "F.Cu")
		(net "Net_1405")
	)
	(via
		(at 430.274984 -298.27474)
		(size 0.4064)
		(drill 0.2032)
		(layers "F.Cu" "B.Cu")
		(net "Net_1405")
	)
	(segment
		(start 190.950088 -289.249866)
		(end 190.475108 -289.724846)
		(width 0.13208)
		(layer "F.Cu")
		(net "Net_1406")
	)
	(via
		(at 190.475108 -289.724846)
		(size 0.4064)
		(drill 0.2032)
		(layers "F.Cu" "B.Cu")
		(net "Net_1406")
	)
	(segment
		(start 385.149852 -281.649932)
		(end 384.674872 -281.174952)
		(width 0.13208)
		(layer "F.Cu")
		(net "Net_1408")
	)
	(via
		(at 384.674872 -281.174952)
		(size 0.4064)
		(drill 0.2032)
		(layers "F.Cu" "B.Cu")
		(net "Net_1408")
	)
	(segment
		(start 429.800004 -300.649894)
		(end 430.274984 -300.174914)
		(width 0.13208)
		(layer "F.Cu")
		(net "Net_1409")
	)
	(via
		(at 430.274984 -300.174914)
		(size 0.4064)
		(drill 0.2032)
		(layers "F.Cu" "B.Cu")
		(net "Net_1409")
	)
	(segment
		(start 152.94991 -283.549852)
		(end 152.47493 -283.074872)
		(width 0.13208)
		(layer "F.Cu")
		(net "Net_1411")
	)
	(via
		(at 152.47493 -283.074872)
		(size 0.4064)
		(drill 0.2032)
		(layers "F.Cu" "B.Cu")
		(net "Net_1411")
	)
	(segment
		(start 385.149852 -289.249866)
		(end 384.674872 -288.774886)
		(width 0.13208)
		(layer "F.Cu")
		(net "Net_1413")
	)
	(via
		(at 384.674872 -288.774886)
		(size 0.4064)
		(drill 0.2032)
		(layers "F.Cu" "B.Cu")
		(net "Net_1413")
	)
	(segment
		(start 271.899888 -280.699718)
		(end 271.424908 -280.224738)
		(width 0.13208)
		(layer "F.Cu")
		(net "Net_1416")
	)
	(via
		(at 271.424908 -280.224738)
		(size 0.4064)
		(drill 0.2032)
		(layers "F.Cu" "B.Cu")
		(net "Net_1416")
	)
	(segment
		(start 193.799968 -297.79976)
		(end 194.274948 -298.27474)
		(width 0.127)
		(layer "F.Cu")
		(net "Net_1417")
	)
	(via
		(at 194.274948 -298.27474)
		(size 0.4064)
		(drill 0.2032)
		(layers "F.Cu" "B.Cu")
		(net "Net_1417")
	)
	(segment
		(start 158.649924 -273.099784)
		(end 158.174944 -272.624804)
		(width 0.13208)
		(layer "F.Cu")
		(net "Net_1418")
	)
	(via
		(at 158.174944 -272.624804)
		(size 0.4064)
		(drill 0.2032)
		(layers "F.Cu" "B.Cu")
		(net "Net_1418")
	)
	(segment
		(start 190.950088 -296.8498)
		(end 190.475108 -297.32478)
		(width 0.127)
		(layer "F.Cu")
		(net "Net_1421")
	)
	(via
		(at 190.475108 -297.32478)
		(size 0.4064)
		(drill 0.2032)
		(layers "F.Cu" "B.Cu")
		(net "Net_1421")
	)
	(segment
		(start 152.94991 -285.449772)
		(end 152.47493 -284.974792)
		(width 0.13208)
		(layer "F.Cu")
		(net "Net_1422")
	)
	(via
		(at 152.47493 -284.974792)
		(size 0.4064)
		(drill 0.2032)
		(layers "F.Cu" "B.Cu")
		(net "Net_1422")
	)
	(segment
		(start 386.099812 -276.899878)
		(end 385.624832 -276.424898)
		(width 0.13208)
		(layer "F.Cu")
		(net "Net_1423")
	)
	(via
		(at 385.624832 -276.424898)
		(size 0.4064)
		(drill 0.2032)
		(layers "F.Cu" "B.Cu")
		(net "Net_1423")
	)
	(segment
		(start 391.799826 -275.949918)
		(end 391.324846 -275.474938)
		(width 0.13208)
		(layer "F.Cu")
		(net "Net_1424")
	)
	(via
		(at 391.324846 -275.474938)
		(size 0.4064)
		(drill 0.2032)
		(layers "F.Cu" "B.Cu")
		(net "Net_1424")
	)
	(segment
		(start 152.94991 -281.649932)
		(end 152.47493 -281.174952)
		(width 0.13208)
		(layer "F.Cu")
		(net "Net_1426")
	)
	(via
		(at 152.47493 -281.174952)
		(size 0.4064)
		(drill 0.2032)
		(layers "F.Cu" "B.Cu")
		(net "Net_1426")
	)
	(segment
		(start 387.050026 -278.799798)
		(end 386.575046 -278.324818)
		(width 0.13208)
		(layer "F.Cu")
		(net "Net_1428")
	)
	(via
		(at 386.575046 -278.324818)
		(size 0.4064)
		(drill 0.2032)
		(layers "F.Cu" "B.Cu")
		(net "Net_1428")
	)
	(segment
		(start 387.999986 -284.499812)
		(end 387.525006 -284.024832)
		(width 0.13208)
		(layer "F.Cu")
		(net "Net_1430")
	)
	(via
		(at 387.525006 -284.024832)
		(size 0.4064)
		(drill 0.2032)
		(layers "F.Cu" "B.Cu")
		(net "Net_1430")
	)
	(segment
		(start 192.850008 -290.199826)
		(end 193.324988 -290.674806)
		(width 0.13208)
		(layer "F.Cu")
		(net "Net_1432")
	)
	(via
		(at 193.324988 -290.674806)
		(size 0.4064)
		(drill 0.2032)
		(layers "F.Cu" "B.Cu")
		(net "Net_1432")
	)
	(segment
		(start 387.050026 -277.849838)
		(end 386.575046 -277.374858)
		(width 0.13208)
		(layer "F.Cu")
		(net "Net_1434")
	)
	(via
		(at 386.575046 -277.374858)
		(size 0.4064)
		(drill 0.2032)
		(layers "F.Cu" "B.Cu")
		(net "Net_1434")
	)
	(segment
		(start 386.099812 -281.649932)
		(end 385.624832 -281.174952)
		(width 0.13208)
		(layer "F.Cu")
		(net "Net_1435")
	)
	(via
		(at 385.624832 -281.174952)
		(size 0.4064)
		(drill 0.2032)
		(layers "F.Cu" "B.Cu")
		(net "Net_1435")
	)
	(segment
		(start 428.84979 -292.099746)
		(end 428.37481 -291.624766)
		(width 0.13208)
		(layer "F.Cu")
		(net "Net_1438")
	)
	(via
		(at 428.37481 -291.624766)
		(size 0.4064)
		(drill 0.2032)
		(layers "F.Cu" "B.Cu")
		(net "Net_1438")
	)
	(segment
		(start 269.049754 -279.749758)
		(end 268.574774 -279.274778)
		(width 0.13208)
		(layer "F.Cu")
		(net "Net_1439")
	)
	(via
		(at 268.574774 -279.274778)
		(size 0.4064)
		(drill 0.2032)
		(layers "F.Cu" "B.Cu")
		(net "Net_1439")
	)
	(segment
		(start 391.799826 -280.699718)
		(end 391.324846 -280.224738)
		(width 0.13208)
		(layer "F.Cu")
		(net "Net_1440")
	)
	(via
		(at 391.324846 -280.224738)
		(size 0.4064)
		(drill 0.2032)
		(layers "F.Cu" "B.Cu")
		(net "Net_1440")
	)
	(segment
		(start 387.050026 -288.299906)
		(end 386.575046 -287.824926)
		(width 0.13208)
		(layer "F.Cu")
		(net "Net_1441")
	)
	(via
		(at 386.575046 -287.824926)
		(size 0.4064)
		(drill 0.2032)
		(layers "F.Cu" "B.Cu")
		(net "Net_1441")
	)
	(segment
		(start 386.099812 -289.249866)
		(end 385.624832 -288.774886)
		(width 0.13208)
		(layer "F.Cu")
		(net "Net_1443")
	)
	(via
		(at 385.624832 -288.774886)
		(size 0.4064)
		(drill 0.2032)
		(layers "F.Cu" "B.Cu")
		(net "Net_1443")
	)
	(segment
		(start 427.89983 -290.199826)
		(end 427.42485 -289.724846)
		(width 0.13208)
		(layer "F.Cu")
		(net "Net_1444")
	)
	(via
		(at 427.42485 -289.724846)
		(size 0.4064)
		(drill 0.2032)
		(layers "F.Cu" "B.Cu")
		(net "Net_1444")
	)
	(segment
		(start 389.899906 -279.749758)
		(end 389.424926 -279.274778)
		(width 0.13208)
		(layer "F.Cu")
		(net "Net_1446")
	)
	(via
		(at 389.424926 -279.274778)
		(size 0.4064)
		(drill 0.2032)
		(layers "F.Cu" "B.Cu")
		(net "Net_1446")
	)
	(segment
		(start 429.800004 -294.94988)
		(end 430.274984 -294.4749)
		(width 0.13208)
		(layer "F.Cu")
		(net "Net_1447")
	)
	(via
		(at 430.274984 -294.4749)
		(size 0.4064)
		(drill 0.2032)
		(layers "F.Cu" "B.Cu")
		(net "Net_1447")
	)
	(segment
		(start 275.699728 -283.549852)
		(end 275.224748 -283.074872)
		(width 0.13208)
		(layer "F.Cu")
		(net "Net_1449")
	)
	(via
		(at 275.224748 -283.074872)
		(size 0.4064)
		(drill 0.2032)
		(layers "F.Cu" "B.Cu")
		(net "Net_1449")
	)
	(segment
		(start 387.999986 -280.699718)
		(end 387.525006 -280.224738)
		(width 0.13208)
		(layer "F.Cu")
		(net "Net_1450")
	)
	(via
		(at 387.525006 -280.224738)
		(size 0.4064)
		(drill 0.2032)
		(layers "F.Cu" "B.Cu")
		(net "Net_1450")
	)
	(segment
		(start 430.749964 -300.649894)
		(end 431.224944 -300.174914)
		(width 0.13208)
		(layer "F.Cu")
		(net "Net_1451")
	)
	(via
		(at 431.224944 -300.174914)
		(size 0.4064)
		(drill 0.2032)
		(layers "F.Cu" "B.Cu")
		(net "Net_1451")
	)
	(segment
		(start 388.949946 -278.799798)
		(end 388.474966 -278.324818)
		(width 0.13208)
		(layer "F.Cu")
		(net "Net_1452")
	)
	(via
		(at 388.474966 -278.324818)
		(size 0.4064)
		(drill 0.2032)
		(layers "F.Cu" "B.Cu")
		(net "Net_1452")
	)
	(segment
		(start 269.999714 -276.899878)
		(end 269.524734 -276.424898)
		(width 0.13208)
		(layer "F.Cu")
		(net "Net_1454")
	)
	(via
		(at 269.524734 -276.424898)
		(size 0.4064)
		(drill 0.2032)
		(layers "F.Cu" "B.Cu")
		(net "Net_1454")
	)
	(segment
		(start 385.149852 -276.899878)
		(end 384.674872 -276.424898)
		(width 0.13208)
		(layer "F.Cu")
		(net "Net_1455")
	)
	(via
		(at 384.674872 -276.424898)
		(size 0.4064)
		(drill 0.2032)
		(layers "F.Cu" "B.Cu")
		(net "Net_1455")
	)
	(segment
		(start 427.89983 -297.79976)
		(end 427.42485 -297.32478)
		(width 0.127)
		(layer "F.Cu")
		(net "Net_1456")
	)
	(via
		(at 427.42485 -297.32478)
		(size 0.4064)
		(drill 0.2032)
		(layers "F.Cu" "B.Cu")
		(net "Net_1456")
	)
	(segment
		(start 269.049754 -276.899878)
		(end 268.574774 -276.424898)
		(width 0.13208)
		(layer "F.Cu")
		(net "Net_1457")
	)
	(via
		(at 268.574774 -276.424898)
		(size 0.4064)
		(drill 0.2032)
		(layers "F.Cu" "B.Cu")
		(net "Net_1457")
	)
	(segment
		(start 387.999986 -279.749758)
		(end 387.525006 -279.274778)
		(width 0.13208)
		(layer "F.Cu")
		(net "Net_1458")
	)
	(via
		(at 387.525006 -279.274778)
		(size 0.4064)
		(drill 0.2032)
		(layers "F.Cu" "B.Cu")
		(net "Net_1458")
	)
	(segment
		(start 390.849866 -274.049744)
		(end 390.374886 -273.574764)
		(width 0.13208)
		(layer "F.Cu")
		(net "Net_1459")
	)
	(via
		(at 390.374886 -273.574764)
		(size 0.4064)
		(drill 0.2032)
		(layers "F.Cu" "B.Cu")
		(net "Net_1459")
	)
	(segment
		(start 430.749964 -289.249866)
		(end 431.224944 -288.774886)
		(width 0.13208)
		(layer "F.Cu")
		(net "Net_1461")
	)
	(via
		(at 431.224944 -288.774886)
		(size 0.4064)
		(drill 0.2032)
		(layers "F.Cu" "B.Cu")
		(net "Net_1461")
	)
	(segment
		(start 430.749964 -294.94988)
		(end 431.224944 -294.4749)
		(width 0.13208)
		(layer "F.Cu")
		(net "Net_1464")
	)
	(via
		(at 431.224944 -294.4749)
		(size 0.4064)
		(drill 0.2032)
		(layers "F.Cu" "B.Cu")
		(net "Net_1464")
	)
	(segment
		(start 388.949946 -277.849838)
		(end 388.474966 -277.374858)
		(width 0.13208)
		(layer "F.Cu")
		(net "Net_1465")
	)
	(via
		(at 388.474966 -277.374858)
		(size 0.4064)
		(drill 0.2032)
		(layers "F.Cu" "B.Cu")
		(net "Net_1465")
	)
	(segment
		(start 390.849866 -278.799798)
		(end 390.374886 -278.324818)
		(width 0.13208)
		(layer "F.Cu")
		(net "Net_1466")
	)
	(via
		(at 390.374886 -278.324818)
		(size 0.4064)
		(drill 0.2032)
		(layers "F.Cu" "B.Cu")
		(net "Net_1466")
	)
	(segment
		(start 430.749964 -302.549814)
		(end 431.224944 -302.074834)
		(width 0.13208)
		(layer "F.Cu")
		(net "Net_1467")
	)
	(via
		(at 431.224944 -302.074834)
		(size 0.4064)
		(drill 0.2032)
		(layers "F.Cu" "B.Cu")
		(net "Net_1467")
	)
	(segment
		(start 386.099812 -279.749758)
		(end 385.624832 -279.274778)
		(width 0.13208)
		(layer "F.Cu")
		(net "Net_1469")
	)
	(via
		(at 385.624832 -279.274778)
		(size 0.4064)
		(drill 0.2032)
		(layers "F.Cu" "B.Cu")
		(net "Net_1469")
	)
	(segment
		(start 427.89983 -301.599854)
		(end 427.42485 -301.124874)
		(width 0.127)
		(layer "F.Cu")
		(net "Net_1470")
	)
	(via
		(at 427.42485 -301.124874)
		(size 0.4064)
		(drill 0.2032)
		(layers "F.Cu" "B.Cu")
		(net "Net_1470")
	)
	(segment
		(start 385.149852 -287.349946)
		(end 384.674872 -286.874966)
		(width 0.13208)
		(layer "F.Cu")
		(net "Net_1472")
	)
	(via
		(at 384.674872 -286.874966)
		(size 0.4064)
		(drill 0.2032)
		(layers "F.Cu" "B.Cu")
		(net "Net_1472")
	)
	(segment
		(start 428.84979 -293.99992)
		(end 428.37481 -293.52494)
		(width 0.13208)
		(layer "F.Cu")
		(net "Net_1473")
	)
	(via
		(at 428.37481 -293.52494)
		(size 0.4064)
		(drill 0.2032)
		(layers "F.Cu" "B.Cu")
		(net "Net_1473")
	)
	(segment
		(start 388.949946 -273.099784)
		(end 388.474966 -272.624804)
		(width 0.13208)
		(layer "F.Cu")
		(net "Net_1475")
	)
	(via
		(at 388.474966 -272.624804)
		(size 0.4064)
		(drill 0.2032)
		(layers "F.Cu" "B.Cu")
		(net "Net_1475")
	)
	(segment
		(start 428.84979 -299.699934)
		(end 428.37481 -299.224954)
		(width 0.127)
		(layer "F.Cu")
		(net "Net_1476")
	)
	(via
		(at 428.37481 -299.224954)
		(size 0.4064)
		(drill 0.2032)
		(layers "F.Cu" "B.Cu")
		(net "Net_1476")
	)
	(segment
		(start 391.799826 -274.999958)
		(end 391.324846 -274.524978)
		(width 0.13208)
		(layer "F.Cu")
		(net "Net_1477")
	)
	(via
		(at 391.324846 -274.524978)
		(size 0.4064)
		(drill 0.2032)
		(layers "F.Cu" "B.Cu")
		(net "Net_1477")
	)
	(segment
		(start 430.749964 -291.149786)
		(end 431.224944 -290.674806)
		(width 0.13208)
		(layer "F.Cu")
		(net "Net_1480")
	)
	(via
		(at 431.224944 -290.674806)
		(size 0.4064)
		(drill 0.2032)
		(layers "F.Cu" "B.Cu")
		(net "Net_1480")
	)
	(segment
		(start 392.749786 -283.549852)
		(end 392.274806 -283.074872)
		(width 0.13208)
		(layer "F.Cu")
		(net "Net_1481")
	)
	(via
		(at 392.274806 -283.074872)
		(size 0.4064)
		(drill 0.2032)
		(layers "F.Cu" "B.Cu")
		(net "Net_1481")
	)
	(segment
		(start 387.050026 -284.499812)
		(end 386.575046 -284.024832)
		(width 0.13208)
		(layer "F.Cu")
		(net "Net_1482")
	)
	(via
		(at 386.575046 -284.024832)
		(size 0.4064)
		(drill 0.2032)
		(layers "F.Cu" "B.Cu")
		(net "Net_1482")
	)
	(segment
		(start 429.800004 -302.549814)
		(end 430.274984 -302.074834)
		(width 0.13208)
		(layer "F.Cu")
		(net "Net_1483")
	)
	(via
		(at 430.274984 -302.074834)
		(size 0.4064)
		(drill 0.2032)
		(layers "F.Cu" "B.Cu")
		(net "Net_1483")
	)
	(segment
		(start 385.149852 -283.549852)
		(end 384.674872 -283.074872)
		(width 0.13208)
		(layer "F.Cu")
		(net "Net_1485")
	)
	(via
		(at 384.674872 -283.074872)
		(size 0.4064)
		(drill 0.2032)
		(layers "F.Cu" "B.Cu")
		(net "Net_1485")
	)
	(segment
		(start 427.89983 -303.499774)
		(end 427.42485 -303.024794)
		(width 0.127)
		(layer "F.Cu")
		(net "Net_1486")
	)
	(via
		(at 427.42485 -303.024794)
		(size 0.4064)
		(drill 0.2032)
		(layers "F.Cu" "B.Cu")
		(net "Net_1486")
	)
	(segment
		(start 387.050026 -286.399732)
		(end 386.575046 -285.924752)
		(width 0.13208)
		(layer "F.Cu")
		(net "Net_1487")
	)
	(via
		(at 386.575046 -285.924752)
		(size 0.4064)
		(drill 0.2032)
		(layers "F.Cu" "B.Cu")
		(net "Net_1487")
	)
	(segment
		(start 389.899906 -275.949918)
		(end 389.424926 -275.474938)
		(width 0.13208)
		(layer "F.Cu")
		(net "Net_1489")
	)
	(via
		(at 389.424926 -275.474938)
		(size 0.4064)
		(drill 0.2032)
		(layers "F.Cu" "B.Cu")
		(net "Net_1489")
	)
	(segment
		(start 427.89983 -299.699934)
		(end 427.42485 -299.224954)
		(width 0.127)
		(layer "F.Cu")
		(net "Net_1490")
	)
	(via
		(at 427.42485 -299.224954)
		(size 0.4064)
		(drill 0.2032)
		(layers "F.Cu" "B.Cu")
		(net "Net_1490")
	)
	(segment
		(start 385.149852 -285.449772)
		(end 384.674872 -284.974792)
		(width 0.13208)
		(layer "F.Cu")
		(net "Net_1491")
	)
	(via
		(at 384.674872 -284.974792)
		(size 0.4064)
		(drill 0.2032)
		(layers "F.Cu" "B.Cu")
		(net "Net_1491")
	)
	(segment
		(start 389.899906 -274.999958)
		(end 389.424926 -274.524978)
		(width 0.13208)
		(layer "F.Cu")
		(net "Net_1492")
	)
	(via
		(at 389.424926 -274.524978)
		(size 0.4064)
		(drill 0.2032)
		(layers "F.Cu" "B.Cu")
		(net "Net_1492")
	)
	(segment
		(start 386.099812 -287.349946)
		(end 385.624832 -286.874966)
		(width 0.13208)
		(layer "F.Cu")
		(net "Net_1493")
	)
	(via
		(at 385.624832 -286.874966)
		(size 0.4064)
		(drill 0.2032)
		(layers "F.Cu" "B.Cu")
		(net "Net_1493")
	)
	(segment
		(start 429.800004 -291.149786)
		(end 430.274984 -290.674806)
		(width 0.13208)
		(layer "F.Cu")
		(net "Net_1494")
	)
	(via
		(at 430.274984 -290.674806)
		(size 0.4064)
		(drill 0.2032)
		(layers "F.Cu" "B.Cu")
		(net "Net_1494")
	)
	(segment
		(start 386.099812 -285.449772)
		(end 385.624832 -284.974792)
		(width 0.13208)
		(layer "F.Cu")
		(net "Net_1495")
	)
	(via
		(at 385.624832 -284.974792)
		(size 0.4064)
		(drill 0.2032)
		(layers "F.Cu" "B.Cu")
		(net "Net_1495")
	)
	(segment
		(start 428.84979 -297.79976)
		(end 428.37481 -297.32478)
		(width 0.127)
		(layer "F.Cu")
		(net "Net_1496")
	)
	(via
		(at 428.37481 -297.32478)
		(size 0.4064)
		(drill 0.2032)
		(layers "F.Cu" "B.Cu")
		(net "Net_1496")
	)
	(segment
		(start 390.849866 -273.099784)
		(end 390.374886 -272.624804)
		(width 0.13208)
		(layer "F.Cu")
		(net "Net_1497")
	)
	(via
		(at 390.374886 -272.624804)
		(size 0.4064)
		(drill 0.2032)
		(layers "F.Cu" "B.Cu")
		(net "Net_1497")
	)
	(segment
		(start 387.999986 -275.949918)
		(end 387.525006 -275.474938)
		(width 0.13208)
		(layer "F.Cu")
		(net "Net_1498")
	)
	(via
		(at 387.525006 -275.474938)
		(size 0.4064)
		(drill 0.2032)
		(layers "F.Cu" "B.Cu")
		(net "Net_1498")
	)
	(segment
		(start 430.749964 -293.04996)
		(end 431.224944 -292.57498)
		(width 0.13208)
		(layer "F.Cu")
		(net "Net_1499")
	)
	(via
		(at 431.224944 -292.57498)
		(size 0.4064)
		(drill 0.2032)
		(layers "F.Cu" "B.Cu")
		(net "Net_1499")
	)
	(segment
		(start 428.84979 -303.499774)
		(end 428.37481 -303.024794)
		(width 0.127)
		(layer "F.Cu")
		(net "Net_1501")
	)
	(via
		(at 428.37481 -303.024794)
		(size 0.4064)
		(drill 0.2032)
		(layers "F.Cu" "B.Cu")
		(net "Net_1501")
	)
	(segment
		(start 387.999986 -286.399732)
		(end 387.525006 -285.924752)
		(width 0.13208)
		(layer "F.Cu")
		(net "Net_1502")
	)
	(via
		(at 387.525006 -285.924752)
		(size 0.4064)
		(drill 0.2032)
		(layers "F.Cu" "B.Cu")
		(net "Net_1502")
	)
	(segment
		(start 387.050026 -273.099784)
		(end 386.575046 -272.624804)
		(width 0.13208)
		(layer "F.Cu")
		(net "Net_1503")
	)
	(via
		(at 386.575046 -272.624804)
		(size 0.4064)
		(drill 0.2032)
		(layers "F.Cu" "B.Cu")
		(net "Net_1503")
	)
	(segment
		(start 428.84979 -290.199826)
		(end 428.37481 -289.724846)
		(width 0.13208)
		(layer "F.Cu")
		(net "Net_1504")
	)
	(via
		(at 428.37481 -289.724846)
		(size 0.4064)
		(drill 0.2032)
		(layers "F.Cu" "B.Cu")
		(net "Net_1504")
	)
	(segment
		(start 387.999986 -282.599892)
		(end 387.525006 -282.124912)
		(width 0.13208)
		(layer "F.Cu")
		(net "Net_1505")
	)
	(via
		(at 387.525006 -282.124912)
		(size 0.4064)
		(drill 0.2032)
		(layers "F.Cu" "B.Cu")
		(net "Net_1505")
	)
	(segment
		(start 428.84979 -301.599854)
		(end 428.37481 -301.124874)
		(width 0.127)
		(layer "F.Cu")
		(net "Net_1506")
	)
	(via
		(at 428.37481 -301.124874)
		(size 0.4064)
		(drill 0.2032)
		(layers "F.Cu" "B.Cu")
		(net "Net_1506")
	)
	(segment
		(start 386.099812 -283.549852)
		(end 385.624832 -283.074872)
		(width 0.13208)
		(layer "F.Cu")
		(net "Net_1507")
	)
	(via
		(at 385.624832 -283.074872)
		(size 0.4064)
		(drill 0.2032)
		(layers "F.Cu" "B.Cu")
		(net "Net_1507")
	)
	(segment
		(start 429.800004 -293.04996)
		(end 430.274984 -292.57498)
		(width 0.13208)
		(layer "F.Cu")
		(net "Net_1508")
	)
	(via
		(at 430.274984 -292.57498)
		(size 0.4064)
		(drill 0.2032)
		(layers "F.Cu" "B.Cu")
		(net "Net_1508")
	)
	(segment
		(start 427.89983 -292.099746)
		(end 427.42485 -291.624766)
		(width 0.13208)
		(layer "F.Cu")
		(net "Net_1509")
	)
	(via
		(at 427.42485 -291.624766)
		(size 0.4064)
		(drill 0.2032)
		(layers "F.Cu" "B.Cu")
		(net "Net_1509")
	)
	(segment
		(start 429.800004 -289.249866)
		(end 430.274984 -288.774886)
		(width 0.13208)
		(layer "F.Cu")
		(net "Net_1510")
	)
	(via
		(at 430.274984 -288.774886)
		(size 0.4064)
		(drill 0.2032)
		(layers "F.Cu" "B.Cu")
		(net "Net_1510")
	)
	(segment
		(start 430.749964 -298.74972)
		(end 431.224944 -298.27474)
		(width 0.13208)
		(layer "F.Cu")
		(net "Net_1511")
	)
	(via
		(at 431.224944 -298.27474)
		(size 0.4064)
		(drill 0.2032)
		(layers "F.Cu" "B.Cu")
		(net "Net_1511")
	)
	(segment
		(start 388.949946 -274.049744)
		(end 388.474966 -273.574764)
		(width 0.13208)
		(layer "F.Cu")
		(net "Net_1512")
	)
	(via
		(at 388.474966 -273.574764)
		(size 0.4064)
		(drill 0.2032)
		(layers "F.Cu" "B.Cu")
		(net "Net_1512")
	)
	(segment
		(start 387.050026 -282.599892)
		(end 386.575046 -282.124912)
		(width 0.13208)
		(layer "F.Cu")
		(net "Net_1513")
	)
	(via
		(at 386.575046 -282.124912)
		(size 0.4064)
		(drill 0.2032)
		(layers "F.Cu" "B.Cu")
		(net "Net_1513")
	)
	(segment
		(start 425.99991 -297.79976)
		(end 426.47489 -298.27474)
		(width 0.127)
		(layer "F.Cu")
		(net "Net_1514")
	)
	(via
		(at 426.47489 -298.27474)
		(size 0.4064)
		(drill 0.2032)
		(layers "F.Cu" "B.Cu")
		(net "Net_1514")
	)
	(segment
		(start 423.15003 -289.249866)
		(end 422.67505 -289.724846)
		(width 0.13208)
		(layer "F.Cu")
		(net "Net_1515")
	)
	(via
		(at 422.67505 -289.724846)
		(size 0.4064)
		(drill 0.2032)
		(layers "F.Cu" "B.Cu")
		(net "Net_1515")
	)
	(segment
		(start 425.04995 -292.099746)
		(end 425.52493 -292.574726)
		(width 0.13208)
		(layer "F.Cu")
		(net "Net_1516")
	)
	(via
		(at 425.52493 -292.574726)
		(size 0.4064)
		(drill 0.2032)
		(layers "F.Cu" "B.Cu")
		(net "Net_1516")
	)
	(segment
		(start 425.99991 -290.199826)
		(end 426.47489 -290.674806)
		(width 0.13208)
		(layer "F.Cu")
		(net "Net_1517")
	)
	(via
		(at 426.47489 -290.674806)
		(size 0.4064)
		(drill 0.2032)
		(layers "F.Cu" "B.Cu")
		(net "Net_1517")
	)
	(segment
		(start 425.04995 -299.699934)
		(end 425.52493 -300.174914)
		(width 0.127)
		(layer "F.Cu")
		(net "Net_1521")
	)
	(via
		(at 425.52493 -300.174914)
		(size 0.4064)
		(drill 0.2032)
		(layers "F.Cu" "B.Cu")
		(net "Net_1521")
	)
	(segment
		(start 197.600062 -300.649894)
		(end 198.075042 -300.174914)
		(width 0.13208)
		(layer "F.Cu")
		(net "Net_1524")
	)
	(via
		(at 198.075042 -300.174914)
		(size 0.4064)
		(drill 0.2032)
		(layers "F.Cu" "B.Cu")
		(net "Net_1524")
	)
	(segment
		(start 425.04995 -290.199826)
		(end 425.52493 -290.674806)
		(width 0.13208)
		(layer "F.Cu")
		(net "Net_1525")
	)
	(via
		(at 425.52493 -290.674806)
		(size 0.4064)
		(drill 0.2032)
		(layers "F.Cu" "B.Cu")
		(net "Net_1525")
	)
	(segment
		(start 425.04995 -297.79976)
		(end 425.52493 -298.27474)
		(width 0.127)
		(layer "F.Cu")
		(net "Net_1527")
	)
	(via
		(at 425.52493 -298.27474)
		(size 0.4064)
		(drill 0.2032)
		(layers "F.Cu" "B.Cu")
		(net "Net_1527")
	)
	(segment
		(start 275.699728 -274.999958)
		(end 275.224748 -274.524978)
		(width 0.13208)
		(layer "F.Cu")
		(net "Net_1528")
	)
	(via
		(at 275.224748 -274.524978)
		(size 0.4064)
		(drill 0.2032)
		(layers "F.Cu" "B.Cu")
		(net "Net_1528")
	)
	(segment
		(start 198.550022 -294.94988)
		(end 199.025002 -294.4749)
		(width 0.13208)
		(layer "F.Cu")
		(net "Net_1529")
	)
	(via
		(at 199.025002 -294.4749)
		(size 0.4064)
		(drill 0.2032)
		(layers "F.Cu" "B.Cu")
		(net "Net_1529")
	)
	(segment
		(start 195.699888 -292.099746)
		(end 195.224908 -291.624766)
		(width 0.13208)
		(layer "F.Cu")
		(net "Net_1531")
	)
	(via
		(at 195.224908 -291.624766)
		(size 0.4064)
		(drill 0.2032)
		(layers "F.Cu" "B.Cu")
		(net "Net_1531")
	)
	(segment
		(start 425.99991 -301.599854)
		(end 426.47489 -302.074834)
		(width 0.127)
		(layer "F.Cu")
		(net "Net_1532")
	)
	(via
		(at 426.47489 -302.074834)
		(size 0.4064)
		(drill 0.2032)
		(layers "F.Cu" "B.Cu")
		(net "Net_1532")
	)
	(segment
		(start 274.749768 -273.099784)
		(end 274.274788 -272.624804)
		(width 0.13208)
		(layer "F.Cu")
		(net "Net_1534")
	)
	(via
		(at 274.274788 -272.624804)
		(size 0.4064)
		(drill 0.2032)
		(layers "F.Cu" "B.Cu")
		(net "Net_1534")
	)
	(segment
		(start 270.949928 -273.099784)
		(end 270.474948 -272.624804)
		(width 0.13208)
		(layer "F.Cu")
		(net "Net_1536")
	)
	(via
		(at 270.474948 -272.624804)
		(size 0.4064)
		(drill 0.2032)
		(layers "F.Cu" "B.Cu")
		(net "Net_1536")
	)
	(segment
		(start 423.15003 -293.04996)
		(end 422.67505 -293.52494)
		(width 0.13208)
		(layer "F.Cu")
		(net "Net_1537")
	)
	(via
		(at 422.67505 -293.52494)
		(size 0.4064)
		(drill 0.2032)
		(layers "F.Cu" "B.Cu")
		(net "Net_1537")
	)
	(segment
		(start 272.374868 -272.624804)
		(end 272.849848 -273.099784)
		(width 0.13208)
		(layer "F.Cu")
		(net "Net_1539")
	)
	(via
		(at 272.374868 -272.624804)
		(size 0.4064)
		(drill 0.2032)
		(layers "F.Cu" "B.Cu")
		(net "Net_1539")
	)
	(segment
		(start 423.15003 -291.149786)
		(end 422.67505 -291.624766)
		(width 0.13208)
		(layer "F.Cu")
		(net "Net_1541")
	)
	(via
		(at 422.67505 -291.624766)
		(size 0.4064)
		(drill 0.2032)
		(layers "F.Cu" "B.Cu")
		(net "Net_1541")
	)
	(segment
		(start 195.699888 -299.699934)
		(end 195.224908 -299.224954)
		(width 0.127)
		(layer "F.Cu")
		(net "Net_1543")
	)
	(via
		(at 195.224908 -299.224954)
		(size 0.4064)
		(drill 0.2032)
		(layers "F.Cu" "B.Cu")
		(net "Net_1543")
	)
	(segment
		(start 424.09999 -293.04996)
		(end 423.62501 -293.52494)
		(width 0.13208)
		(layer "F.Cu")
		(net "Net_1544")
	)
	(via
		(at 423.62501 -293.52494)
		(size 0.4064)
		(drill 0.2032)
		(layers "F.Cu" "B.Cu")
		(net "Net_1544")
	)
	(segment
		(start 273.799808 -274.999958)
		(end 273.324828 -274.524978)
		(width 0.13208)
		(layer "F.Cu")
		(net "Net_1545")
	)
	(via
		(at 273.324828 -274.524978)
		(size 0.4064)
		(drill 0.2032)
		(layers "F.Cu" "B.Cu")
		(net "Net_1545")
	)
	(segment
		(start 198.550022 -300.649894)
		(end 199.025002 -300.174914)
		(width 0.13208)
		(layer "F.Cu")
		(net "Net_1546")
	)
	(via
		(at 199.025002 -300.174914)
		(size 0.4064)
		(drill 0.2032)
		(layers "F.Cu" "B.Cu")
		(net "Net_1546")
	)
	(segment
		(start 424.09999 -296.8498)
		(end 423.62501 -297.32478)
		(width 0.127)
		(layer "F.Cu")
		(net "Net_1547")
	)
	(via
		(at 423.62501 -297.32478)
		(size 0.4064)
		(drill 0.2032)
		(layers "F.Cu" "B.Cu")
		(net "Net_1547")
	)
	(segment
		(start 314.649866 -294.94988)
		(end 315.124846 -294.4749)
		(width 0.13208)
		(layer "F.Cu")
		(net "Net_1548")
	)
	(via
		(at 315.124846 -294.4749)
		(size 0.4064)
		(drill 0.2032)
		(layers "F.Cu" "B.Cu")
		(net "Net_1548")
	)
	(segment
		(start 196.649848 -290.199826)
		(end 196.174868 -289.724846)
		(width 0.13208)
		(layer "F.Cu")
		(net "Net_1550")
	)
	(via
		(at 196.174868 -289.724846)
		(size 0.4064)
		(drill 0.2032)
		(layers "F.Cu" "B.Cu")
		(net "Net_1550")
	)
	(segment
		(start 273.799808 -275.949918)
		(end 273.324828 -275.474938)
		(width 0.13208)
		(layer "F.Cu")
		(net "Net_1552")
	)
	(via
		(at 273.324828 -275.474938)
		(size 0.4064)
		(drill 0.2032)
		(layers "F.Cu" "B.Cu")
		(net "Net_1552")
	)
	(segment
		(start 195.699888 -290.199826)
		(end 195.224908 -289.724846)
		(width 0.13208)
		(layer "F.Cu")
		(net "Net_1553")
	)
	(via
		(at 195.224908 -289.724846)
		(size 0.4064)
		(drill 0.2032)
		(layers "F.Cu" "B.Cu")
		(net "Net_1553")
	)
	(segment
		(start 425.99991 -292.099746)
		(end 426.47489 -292.574726)
		(width 0.13208)
		(layer "F.Cu")
		(net "Net_1555")
	)
	(via
		(at 426.47489 -292.574726)
		(size 0.4064)
		(drill 0.2032)
		(layers "F.Cu" "B.Cu")
		(net "Net_1555")
	)
	(segment
		(start 312.749692 -293.99992)
		(end 312.274712 -293.52494)
		(width 0.13208)
		(layer "F.Cu")
		(net "Net_1556")
	)
	(via
		(at 312.274712 -293.52494)
		(size 0.4064)
		(drill 0.2032)
		(layers "F.Cu" "B.Cu")
		(net "Net_1556")
	)
	(segment
		(start 195.699888 -293.99992)
		(end 195.224908 -293.52494)
		(width 0.13208)
		(layer "F.Cu")
		(net "Net_1557")
	)
	(via
		(at 195.224908 -293.52494)
		(size 0.4064)
		(drill 0.2032)
		(layers "F.Cu" "B.Cu")
		(net "Net_1557")
	)
	(segment
		(start 423.15003 -296.8498)
		(end 422.67505 -297.32478)
		(width 0.127)
		(layer "F.Cu")
		(net "Net_1558")
	)
	(via
		(at 422.67505 -297.32478)
		(size 0.4064)
		(drill 0.2032)
		(layers "F.Cu" "B.Cu")
		(net "Net_1558")
	)
	(segment
		(start 271.899888 -274.999958)
		(end 271.424908 -274.524978)
		(width 0.13208)
		(layer "F.Cu")
		(net "Net_1559")
	)
	(via
		(at 271.424908 -274.524978)
		(size 0.4064)
		(drill 0.2032)
		(layers "F.Cu" "B.Cu")
		(net "Net_1559")
	)
	(segment
		(start 311.799732 -299.699934)
		(end 311.324752 -299.224954)
		(width 0.127)
		(layer "F.Cu")
		(net "Net_1562")
	)
	(via
		(at 311.324752 -299.224954)
		(size 0.4064)
		(drill 0.2032)
		(layers "F.Cu" "B.Cu")
		(net "Net_1562")
	)
	(segment
		(start 425.04995 -301.599854)
		(end 425.52493 -302.074834)
		(width 0.127)
		(layer "F.Cu")
		(net "Net_1563")
	)
	(via
		(at 425.52493 -302.074834)
		(size 0.4064)
		(drill 0.2032)
		(layers "F.Cu" "B.Cu")
		(net "Net_1563")
	)
	(segment
		(start 313.699906 -298.74972)
		(end 314.174886 -298.27474)
		(width 0.13208)
		(layer "F.Cu")
		(net "Net_1564")
	)
	(via
		(at 314.174886 -298.27474)
		(size 0.4064)
		(drill 0.2032)
		(layers "F.Cu" "B.Cu")
		(net "Net_1564")
	)
	(segment
		(start 269.999714 -289.249866)
		(end 269.524734 -288.774886)
		(width 0.13208)
		(layer "F.Cu")
		(net "Net_1565")
	)
	(via
		(at 269.524734 -288.774886)
		(size 0.4064)
		(drill 0.2032)
		(layers "F.Cu" "B.Cu")
		(net "Net_1565")
	)
	(segment
		(start 195.699888 -297.79976)
		(end 195.224908 -297.32478)
		(width 0.127)
		(layer "F.Cu")
		(net "Net_1567")
	)
	(via
		(at 195.224908 -297.32478)
		(size 0.4064)
		(drill 0.2032)
		(layers "F.Cu" "B.Cu")
		(net "Net_1567")
	)
	(segment
		(start 425.99991 -299.699934)
		(end 426.47489 -300.174914)
		(width 0.127)
		(layer "F.Cu")
		(net "Net_1568")
	)
	(via
		(at 426.47489 -300.174914)
		(size 0.4064)
		(drill 0.2032)
		(layers "F.Cu" "B.Cu")
		(net "Net_1568")
	)
	(segment
		(start 313.699906 -294.94988)
		(end 314.174886 -294.4749)
		(width 0.13208)
		(layer "F.Cu")
		(net "Net_1569")
	)
	(via
		(at 314.174886 -294.4749)
		(size 0.4064)
		(drill 0.2032)
		(layers "F.Cu" "B.Cu")
		(net "Net_1569")
	)
	(segment
		(start 269.999714 -285.449772)
		(end 269.524734 -284.974792)
		(width 0.13208)
		(layer "F.Cu")
		(net "Net_1570")
	)
	(via
		(at 269.524734 -284.974792)
		(size 0.4064)
		(drill 0.2032)
		(layers "F.Cu" "B.Cu")
		(net "Net_1570")
	)
	(segment
		(start 312.749692 -303.499774)
		(end 312.274712 -303.024794)
		(width 0.127)
		(layer "F.Cu")
		(net "Net_1572")
	)
	(via
		(at 312.274712 -303.024794)
		(size 0.4064)
		(drill 0.2032)
		(layers "F.Cu" "B.Cu")
		(net "Net_1572")
	)
	(segment
		(start 198.550022 -291.149786)
		(end 199.025002 -290.674806)
		(width 0.13208)
		(layer "F.Cu")
		(net "Net_1573")
	)
	(via
		(at 199.025002 -290.674806)
		(size 0.4064)
		(drill 0.2032)
		(layers "F.Cu" "B.Cu")
		(net "Net_1573")
	)
	(segment
		(start 313.699906 -291.149786)
		(end 314.174886 -290.674806)
		(width 0.13208)
		(layer "F.Cu")
		(net "Net_1574")
	)
	(via
		(at 314.174886 -290.674806)
		(size 0.4064)
		(drill 0.2032)
		(layers "F.Cu" "B.Cu")
		(net "Net_1574")
	)
	(segment
		(start 312.749692 -301.599854)
		(end 312.274712 -301.124874)
		(width 0.127)
		(layer "F.Cu")
		(net "Net_1575")
	)
	(via
		(at 312.274712 -301.124874)
		(size 0.4064)
		(drill 0.2032)
		(layers "F.Cu" "B.Cu")
		(net "Net_1575")
	)
	(segment
		(start 311.799732 -303.499774)
		(end 311.324752 -303.024794)
		(width 0.127)
		(layer "F.Cu")
		(net "Net_1577")
	)
	(via
		(at 311.324752 -303.024794)
		(size 0.4064)
		(drill 0.2032)
		(layers "F.Cu" "B.Cu")
		(net "Net_1577")
	)
	(segment
		(start 269.049754 -285.449772)
		(end 268.574774 -284.974792)
		(width 0.13208)
		(layer "F.Cu")
		(net "Net_1578")
	)
	(via
		(at 268.574774 -284.974792)
		(size 0.4064)
		(drill 0.2032)
		(layers "F.Cu" "B.Cu")
		(net "Net_1578")
	)
	(segment
		(start 196.649848 -297.79976)
		(end 196.174868 -297.32478)
		(width 0.127)
		(layer "F.Cu")
		(net "Net_1579")
	)
	(via
		(at 196.174868 -297.32478)
		(size 0.4064)
		(drill 0.2032)
		(layers "F.Cu" "B.Cu")
		(net "Net_1579")
	)
	(segment
		(start 312.749692 -299.699934)
		(end 312.274712 -299.224954)
		(width 0.127)
		(layer "F.Cu")
		(net "Net_1581")
	)
	(via
		(at 312.274712 -299.224954)
		(size 0.4064)
		(drill 0.2032)
		(layers "F.Cu" "B.Cu")
		(net "Net_1581")
	)
	(segment
		(start 313.699906 -302.549814)
		(end 314.174886 -302.074834)
		(width 0.13208)
		(layer "F.Cu")
		(net "Net_1582")
	)
	(via
		(at 314.174886 -302.074834)
		(size 0.4064)
		(drill 0.2032)
		(layers "F.Cu" "B.Cu")
		(net "Net_1582")
	)
	(segment
		(start 270.949928 -288.299906)
		(end 270.474948 -287.824926)
		(width 0.13208)
		(layer "F.Cu")
		(net "Net_1583")
	)
	(via
		(at 270.474948 -287.824926)
		(size 0.4064)
		(drill 0.2032)
		(layers "F.Cu" "B.Cu")
		(net "Net_1583")
	)
	(segment
		(start 197.600062 -298.74972)
		(end 198.075042 -298.27474)
		(width 0.13208)
		(layer "F.Cu")
		(net "Net_1584")
	)
	(via
		(at 198.075042 -298.27474)
		(size 0.4064)
		(drill 0.2032)
		(layers "F.Cu" "B.Cu")
		(net "Net_1584")
	)
	(segment
		(start 314.649866 -302.549814)
		(end 315.124846 -302.074834)
		(width 0.13208)
		(layer "F.Cu")
		(net "Net_1585")
	)
	(via
		(at 315.124846 -302.074834)
		(size 0.4064)
		(drill 0.2032)
		(layers "F.Cu" "B.Cu")
		(net "Net_1585")
	)
	(segment
		(start 197.600062 -291.149786)
		(end 198.075042 -290.674806)
		(width 0.13208)
		(layer "F.Cu")
		(net "Net_1586")
	)
	(via
		(at 198.075042 -290.674806)
		(size 0.4064)
		(drill 0.2032)
		(layers "F.Cu" "B.Cu")
		(net "Net_1586")
	)
	(segment
		(start 197.600062 -293.04996)
		(end 198.075042 -292.57498)
		(width 0.13208)
		(layer "F.Cu")
		(net "Net_1587")
	)
	(via
		(at 198.075042 -292.57498)
		(size 0.4064)
		(drill 0.2032)
		(layers "F.Cu" "B.Cu")
		(net "Net_1587")
	)
	(segment
		(start 269.999714 -281.649932)
		(end 269.524734 -281.174952)
		(width 0.13208)
		(layer "F.Cu")
		(net "Net_1588")
	)
	(via
		(at 269.524734 -281.174952)
		(size 0.4064)
		(drill 0.2032)
		(layers "F.Cu" "B.Cu")
		(net "Net_1588")
	)
	(segment
		(start 311.799732 -301.599854)
		(end 311.324752 -301.124874)
		(width 0.127)
		(layer "F.Cu")
		(net "Net_1589")
	)
	(via
		(at 311.324752 -301.124874)
		(size 0.4064)
		(drill 0.2032)
		(layers "F.Cu" "B.Cu")
		(net "Net_1589")
	)
	(segment
		(start 269.049754 -289.249866)
		(end 268.574774 -288.774886)
		(width 0.13208)
		(layer "F.Cu")
		(net "Net_1590")
	)
	(via
		(at 268.574774 -288.774886)
		(size 0.4064)
		(drill 0.2032)
		(layers "F.Cu" "B.Cu")
		(net "Net_1590")
	)
	(segment
		(start 198.550022 -293.04996)
		(end 199.025002 -292.57498)
		(width 0.13208)
		(layer "F.Cu")
		(net "Net_1591")
	)
	(via
		(at 199.025002 -292.57498)
		(size 0.4064)
		(drill 0.2032)
		(layers "F.Cu" "B.Cu")
		(net "Net_1591")
	)
	(segment
		(start 311.799732 -293.99992)
		(end 311.324752 -293.52494)
		(width 0.13208)
		(layer "F.Cu")
		(net "Net_1592")
	)
	(via
		(at 311.324752 -293.52494)
		(size 0.4064)
		(drill 0.2032)
		(layers "F.Cu" "B.Cu")
		(net "Net_1592")
	)
	(segment
		(start 269.999714 -287.349946)
		(end 269.524734 -286.874966)
		(width 0.13208)
		(layer "F.Cu")
		(net "Net_1593")
	)
	(via
		(at 269.524734 -286.874966)
		(size 0.4064)
		(drill 0.2032)
		(layers "F.Cu" "B.Cu")
		(net "Net_1593")
	)
	(segment
		(start 314.649866 -291.149786)
		(end 315.124846 -290.674806)
		(width 0.13208)
		(layer "F.Cu")
		(net "Net_1594")
	)
	(via
		(at 315.124846 -290.674806)
		(size 0.4064)
		(drill 0.2032)
		(layers "F.Cu" "B.Cu")
		(net "Net_1594")
	)
	(segment
		(start 312.749692 -292.099746)
		(end 312.274712 -291.624766)
		(width 0.13208)
		(layer "F.Cu")
		(net "Net_1595")
	)
	(via
		(at 312.274712 -291.624766)
		(size 0.4064)
		(drill 0.2032)
		(layers "F.Cu" "B.Cu")
		(net "Net_1595")
	)
	(segment
		(start 313.699906 -300.649894)
		(end 314.174886 -300.174914)
		(width 0.13208)
		(layer "F.Cu")
		(net "Net_1597")
	)
	(via
		(at 314.174886 -300.174914)
		(size 0.4064)
		(drill 0.2032)
		(layers "F.Cu" "B.Cu")
		(net "Net_1597")
	)
	(segment
		(start 269.049754 -287.349946)
		(end 268.574774 -286.874966)
		(width 0.13208)
		(layer "F.Cu")
		(net "Net_1598")
	)
	(via
		(at 268.574774 -286.874966)
		(size 0.4064)
		(drill 0.2032)
		(layers "F.Cu" "B.Cu")
		(net "Net_1598")
	)
	(segment
		(start 196.649848 -303.499774)
		(end 196.174868 -303.024794)
		(width 0.127)
		(layer "F.Cu")
		(net "Net_1599")
	)
	(via
		(at 196.174868 -303.024794)
		(size 0.4064)
		(drill 0.2032)
		(layers "F.Cu" "B.Cu")
		(net "Net_1599")
	)
	(segment
		(start 269.049754 -281.649932)
		(end 268.574774 -281.174952)
		(width 0.13208)
		(layer "F.Cu")
		(net "Net_1600")
	)
	(via
		(at 268.574774 -281.174952)
		(size 0.4064)
		(drill 0.2032)
		(layers "F.Cu" "B.Cu")
		(net "Net_1600")
	)
	(segment
		(start 312.749692 -290.199826)
		(end 312.274712 -289.724846)
		(width 0.13208)
		(layer "F.Cu")
		(net "Net_1601")
	)
	(via
		(at 312.274712 -289.724846)
		(size 0.4064)
		(drill 0.2032)
		(layers "F.Cu" "B.Cu")
		(net "Net_1601")
	)
	(segment
		(start 270.949928 -284.499812)
		(end 270.474948 -284.024832)
		(width 0.13208)
		(layer "F.Cu")
		(net "Net_1602")
	)
	(via
		(at 270.474948 -284.024832)
		(size 0.4064)
		(drill 0.2032)
		(layers "F.Cu" "B.Cu")
		(net "Net_1602")
	)
	(segment
		(start 196.649848 -293.99992)
		(end 196.174868 -293.52494)
		(width 0.13208)
		(layer "F.Cu")
		(net "Net_1603")
	)
	(via
		(at 196.174868 -293.52494)
		(size 0.4064)
		(drill 0.2032)
		(layers "F.Cu" "B.Cu")
		(net "Net_1603")
	)
	(segment
		(start 314.649866 -300.649894)
		(end 315.124846 -300.174914)
		(width 0.13208)
		(layer "F.Cu")
		(net "Net_1604")
	)
	(via
		(at 315.124846 -300.174914)
		(size 0.4064)
		(drill 0.2032)
		(layers "F.Cu" "B.Cu")
		(net "Net_1604")
	)
	(segment
		(start 270.949928 -282.599892)
		(end 270.474948 -282.124912)
		(width 0.13208)
		(layer "F.Cu")
		(net "Net_1605")
	)
	(via
		(at 270.474948 -282.124912)
		(size 0.4064)
		(drill 0.2032)
		(layers "F.Cu" "B.Cu")
		(net "Net_1605")
	)
	(segment
		(start 195.699888 -303.499774)
		(end 195.224908 -303.024794)
		(width 0.127)
		(layer "F.Cu")
		(net "Net_1606")
	)
	(via
		(at 195.224908 -303.024794)
		(size 0.4064)
		(drill 0.2032)
		(layers "F.Cu" "B.Cu")
		(net "Net_1606")
	)
	(segment
		(start 311.799732 -290.199826)
		(end 311.324752 -289.724846)
		(width 0.13208)
		(layer "F.Cu")
		(net "Net_1607")
	)
	(via
		(at 311.324752 -289.724846)
		(size 0.4064)
		(drill 0.2032)
		(layers "F.Cu" "B.Cu")
		(net "Net_1607")
	)
	(segment
		(start 311.799732 -297.79976)
		(end 311.324752 -297.32478)
		(width 0.127)
		(layer "F.Cu")
		(net "Net_1609")
	)
	(via
		(at 311.324752 -297.32478)
		(size 0.4064)
		(drill 0.2032)
		(layers "F.Cu" "B.Cu")
		(net "Net_1609")
	)
	(segment
		(start 198.550022 -298.74972)
		(end 199.025002 -298.27474)
		(width 0.13208)
		(layer "F.Cu")
		(net "Net_1610")
	)
	(via
		(at 199.025002 -298.27474)
		(size 0.4064)
		(drill 0.2032)
		(layers "F.Cu" "B.Cu")
		(net "Net_1610")
	)
	(segment
		(start 274.749768 -274.049744)
		(end 274.274788 -273.574764)
		(width 0.13208)
		(layer "F.Cu")
		(net "Net_1611")
	)
	(via
		(at 274.274788 -273.574764)
		(size 0.4064)
		(drill 0.2032)
		(layers "F.Cu" "B.Cu")
		(net "Net_1611")
	)
	(segment
		(start 196.649848 -292.099746)
		(end 196.174868 -291.624766)
		(width 0.13208)
		(layer "F.Cu")
		(net "Net_1613")
	)
	(via
		(at 196.174868 -291.624766)
		(size 0.4064)
		(drill 0.2032)
		(layers "F.Cu" "B.Cu")
		(net "Net_1613")
	)
	(segment
		(start 271.899888 -284.499812)
		(end 271.424908 -284.024832)
		(width 0.13208)
		(layer "F.Cu")
		(net "Net_1614")
	)
	(via
		(at 271.424908 -284.024832)
		(size 0.4064)
		(drill 0.2032)
		(layers "F.Cu" "B.Cu")
		(net "Net_1614")
	)
	(segment
		(start 314.649866 -293.04996)
		(end 315.124846 -292.57498)
		(width 0.13208)
		(layer "F.Cu")
		(net "Net_1616")
	)
	(via
		(at 315.124846 -292.57498)
		(size 0.4064)
		(drill 0.2032)
		(layers "F.Cu" "B.Cu")
		(net "Net_1616")
	)
	(segment
		(start 271.899888 -275.949918)
		(end 271.424908 -275.474938)
		(width 0.13208)
		(layer "F.Cu")
		(net "Net_1617")
	)
	(via
		(at 271.424908 -275.474938)
		(size 0.4064)
		(drill 0.2032)
		(layers "F.Cu" "B.Cu")
		(net "Net_1617")
	)
	(segment
		(start 196.649848 -301.599854)
		(end 196.174868 -301.124874)
		(width 0.127)
		(layer "F.Cu")
		(net "Net_1618")
	)
	(via
		(at 196.174868 -301.124874)
		(size 0.4064)
		(drill 0.2032)
		(layers "F.Cu" "B.Cu")
		(net "Net_1618")
	)
	(segment
		(start 197.600062 -302.549814)
		(end 198.075042 -302.074834)
		(width 0.13208)
		(layer "F.Cu")
		(net "Net_1621")
	)
	(via
		(at 198.075042 -302.074834)
		(size 0.4064)
		(drill 0.2032)
		(layers "F.Cu" "B.Cu")
		(net "Net_1621")
	)
	(segment
		(start 313.699906 -289.249866)
		(end 314.174886 -288.774886)
		(width 0.13208)
		(layer "F.Cu")
		(net "Net_1622")
	)
	(via
		(at 314.174886 -288.774886)
		(size 0.4064)
		(drill 0.2032)
		(layers "F.Cu" "B.Cu")
		(net "Net_1622")
	)
	(segment
		(start 271.899888 -282.599892)
		(end 271.424908 -282.124912)
		(width 0.13208)
		(layer "F.Cu")
		(net "Net_1623")
	)
	(via
		(at 271.424908 -282.124912)
		(size 0.4064)
		(drill 0.2032)
		(layers "F.Cu" "B.Cu")
		(net "Net_1623")
	)
	(segment
		(start 312.749692 -297.79976)
		(end 312.274712 -297.32478)
		(width 0.127)
		(layer "F.Cu")
		(net "Net_1625")
	)
	(via
		(at 312.274712 -297.32478)
		(size 0.4064)
		(drill 0.2032)
		(layers "F.Cu" "B.Cu")
		(net "Net_1625")
	)
	(segment
		(start 271.899888 -286.399732)
		(end 271.424908 -285.924752)
		(width 0.13208)
		(layer "F.Cu")
		(net "Net_1626")
	)
	(via
		(at 271.424908 -285.924752)
		(size 0.4064)
		(drill 0.2032)
		(layers "F.Cu" "B.Cu")
		(net "Net_1626")
	)
	(segment
		(start 197.600062 -294.94988)
		(end 198.075042 -294.4749)
		(width 0.13208)
		(layer "F.Cu")
		(net "Net_1627")
	)
	(via
		(at 198.075042 -294.4749)
		(size 0.4064)
		(drill 0.2032)
		(layers "F.Cu" "B.Cu")
		(net "Net_1627")
	)
	(segment
		(start 196.649848 -299.699934)
		(end 196.174868 -299.224954)
		(width 0.127)
		(layer "F.Cu")
		(net "Net_1628")
	)
	(via
		(at 196.174868 -299.224954)
		(size 0.4064)
		(drill 0.2032)
		(layers "F.Cu" "B.Cu")
		(net "Net_1628")
	)
	(segment
		(start 269.999714 -283.549852)
		(end 269.524734 -283.074872)
		(width 0.13208)
		(layer "F.Cu")
		(net "Net_1629")
	)
	(via
		(at 269.524734 -283.074872)
		(size 0.4064)
		(drill 0.2032)
		(layers "F.Cu" "B.Cu")
		(net "Net_1629")
	)
	(segment
		(start 195.699888 -301.599854)
		(end 195.224908 -301.124874)
		(width 0.127)
		(layer "F.Cu")
		(net "Net_1631")
	)
	(via
		(at 195.224908 -301.124874)
		(size 0.4064)
		(drill 0.2032)
		(layers "F.Cu" "B.Cu")
		(net "Net_1631")
	)
	(segment
		(start 311.799732 -292.099746)
		(end 311.324752 -291.624766)
		(width 0.13208)
		(layer "F.Cu")
		(net "Net_1632")
	)
	(via
		(at 311.324752 -291.624766)
		(size 0.4064)
		(drill 0.2032)
		(layers "F.Cu" "B.Cu")
		(net "Net_1632")
	)
	(segment
		(start 269.049754 -283.549852)
		(end 268.574774 -283.074872)
		(width 0.13208)
		(layer "F.Cu")
		(net "Net_1633")
	)
	(via
		(at 268.574774 -283.074872)
		(size 0.4064)
		(drill 0.2032)
		(layers "F.Cu" "B.Cu")
		(net "Net_1633")
	)
	(segment
		(start 198.550022 -302.549814)
		(end 199.025002 -302.074834)
		(width 0.13208)
		(layer "F.Cu")
		(net "Net_1634")
	)
	(via
		(at 199.025002 -302.074834)
		(size 0.4064)
		(drill 0.2032)
		(layers "F.Cu" "B.Cu")
		(net "Net_1634")
	)
	(segment
		(start 313.699906 -293.04996)
		(end 314.174886 -292.57498)
		(width 0.13208)
		(layer "F.Cu")
		(net "Net_1635")
	)
	(via
		(at 314.174886 -292.57498)
		(size 0.4064)
		(drill 0.2032)
		(layers "F.Cu" "B.Cu")
		(net "Net_1635")
	)
	(segment
		(start 314.649866 -298.74972)
		(end 315.124846 -298.27474)
		(width 0.13208)
		(layer "F.Cu")
		(net "Net_1636")
	)
	(via
		(at 315.124846 -298.27474)
		(size 0.4064)
		(drill 0.2032)
		(layers "F.Cu" "B.Cu")
		(net "Net_1636")
	)
	(segment
		(start 272.374868 -273.574764)
		(end 272.849848 -274.049744)
		(width 0.13208)
		(layer "F.Cu")
		(net "Net_1637")
	)
	(via
		(at 272.374868 -273.574764)
		(size 0.4064)
		(drill 0.2032)
		(layers "F.Cu" "B.Cu")
		(net "Net_1637")
	)
	(segment
		(start 314.649866 -289.249866)
		(end 315.124846 -288.774886)
		(width 0.13208)
		(layer "F.Cu")
		(net "Net_1639")
	)
	(via
		(at 315.124846 -288.774886)
		(size 0.4064)
		(drill 0.2032)
		(layers "F.Cu" "B.Cu")
		(net "Net_1639")
	)
	(segment
		(start 159.599884 -280.699718)
		(end 159.124904 -280.224738)
		(width 0.13208)
		(layer "F.Cu")
		(net "Net_1641")
	)
	(via
		(at 159.124904 -280.224738)
		(size 0.4064)
		(drill 0.2032)
		(layers "F.Cu" "B.Cu")
		(net "Net_1641")
	)
	(segment
		(start 270.949928 -286.399732)
		(end 270.474948 -285.924752)
		(width 0.13208)
		(layer "F.Cu")
		(net "Net_1642")
	)
	(via
		(at 270.474948 -285.924752)
		(size 0.4064)
		(drill 0.2032)
		(layers "F.Cu" "B.Cu")
		(net "Net_1642")
	)
	(segment
		(start 275.699728 -275.949918)
		(end 275.224748 -275.474938)
		(width 0.13208)
		(layer "F.Cu")
		(net "Net_1644")
	)
	(via
		(at 275.224748 -275.474938)
		(size 0.4064)
		(drill 0.2032)
		(layers "F.Cu" "B.Cu")
		(net "Net_1644")
	)
	(segment
		(start 153.89987 -276.899878)
		(end 153.42489 -276.424898)
		(width 0.13208)
		(layer "F.Cu")
		(net "Net_1645")
	)
	(via
		(at 153.42489 -276.424898)
		(size 0.4064)
		(drill 0.2032)
		(layers "F.Cu" "B.Cu")
		(net "Net_1645")
	)
	(segment
		(start 158.649924 -278.799798)
		(end 158.174944 -278.324818)
		(width 0.13208)
		(layer "F.Cu")
		(net "Net_1646")
	)
	(via
		(at 158.174944 -278.324818)
		(size 0.4064)
		(drill 0.2032)
		(layers "F.Cu" "B.Cu")
		(net "Net_1646")
	)
	(segment
		(start 155.800044 -279.749758)
		(end 155.325064 -279.274778)
		(width 0.13208)
		(layer "F.Cu")
		(net "Net_1647")
	)
	(via
		(at 155.325064 -279.274778)
		(size 0.4064)
		(drill 0.2032)
		(layers "F.Cu" "B.Cu")
		(net "Net_1647")
	)
	(segment
		(start 152.94991 -276.899878)
		(end 152.47493 -276.424898)
		(width 0.13208)
		(layer "F.Cu")
		(net "Net_1648")
	)
	(via
		(at 152.47493 -276.424898)
		(size 0.4064)
		(drill 0.2032)
		(layers "F.Cu" "B.Cu")
		(net "Net_1648")
	)
	(segment
		(start 158.649924 -277.849838)
		(end 158.174944 -277.374858)
		(width 0.13208)
		(layer "F.Cu")
		(net "Net_1651")
	)
	(via
		(at 158.174944 -277.374858)
		(size 0.4064)
		(drill 0.2032)
		(layers "F.Cu" "B.Cu")
		(net "Net_1651")
	)
	(segment
		(start 153.89987 -279.749758)
		(end 153.42489 -279.274778)
		(width 0.13208)
		(layer "F.Cu")
		(net "Net_1653")
	)
	(via
		(at 153.42489 -279.274778)
		(size 0.4064)
		(drill 0.2032)
		(layers "F.Cu" "B.Cu")
		(net "Net_1653")
	)
	(segment
		(start 157.699964 -279.749758)
		(end 157.224984 -279.274778)
		(width 0.13208)
		(layer "F.Cu")
		(net "Net_1656")
	)
	(via
		(at 157.224984 -279.274778)
		(size 0.4064)
		(drill 0.2032)
		(layers "F.Cu" "B.Cu")
		(net "Net_1656")
	)
	(segment
		(start 307.049932 -296.8498)
		(end 306.574952 -297.32478)
		(width 0.127)
		(layer "F.Cu")
		(net "Net_1657")
	)
	(via
		(at 306.574952 -297.32478)
		(size 0.4064)
		(drill 0.2032)
		(layers "F.Cu" "B.Cu")
		(net "Net_1657")
	)
	(segment
		(start 309.899812 -290.199826)
		(end 310.374792 -290.674806)
		(width 0.13208)
		(layer "F.Cu")
		(net "Net_1659")
	)
	(via
		(at 310.374792 -290.674806)
		(size 0.4064)
		(drill 0.2032)
		(layers "F.Cu" "B.Cu")
		(net "Net_1659")
	)
	(segment
		(start 155.800044 -280.699718)
		(end 155.325064 -280.224738)
		(width 0.13208)
		(layer "F.Cu")
		(net "Net_1664")
	)
	(via
		(at 155.325064 -280.224738)
		(size 0.4064)
		(drill 0.2032)
		(layers "F.Cu" "B.Cu")
		(net "Net_1664")
	)
	(segment
		(start 160.549844 -283.549852)
		(end 160.074864 -283.074872)
		(width 0.13208)
		(layer "F.Cu")
		(net "Net_1666")
	)
	(via
		(at 160.074864 -283.074872)
		(size 0.4064)
		(drill 0.2032)
		(layers "F.Cu" "B.Cu")
		(net "Net_1666")
	)
	(segment
		(start 157.699964 -282.599892)
		(end 157.224984 -282.124912)
		(width 0.13208)
		(layer "F.Cu")
		(net "Net_1668")
	)
	(via
		(at 157.224984 -282.124912)
		(size 0.4064)
		(drill 0.2032)
		(layers "F.Cu" "B.Cu")
		(net "Net_1668")
	)
	(segment
		(start 309.899812 -301.599854)
		(end 310.374792 -302.074834)
		(width 0.127)
		(layer "F.Cu")
		(net "Net_1669")
	)
	(via
		(at 310.374792 -302.074834)
		(size 0.4064)
		(drill 0.2032)
		(layers "F.Cu" "B.Cu")
		(net "Net_1669")
	)
	(segment
		(start 156.750004 -277.849838)
		(end 156.275024 -277.374858)
		(width 0.13208)
		(layer "F.Cu")
		(net "Net_1672")
	)
	(via
		(at 156.275024 -277.374858)
		(size 0.4064)
		(drill 0.2032)
		(layers "F.Cu" "B.Cu")
		(net "Net_1672")
	)
	(segment
		(start 309.899812 -292.099746)
		(end 310.374792 -292.574726)
		(width 0.13208)
		(layer "F.Cu")
		(net "Net_1673")
	)
	(via
		(at 310.374792 -292.574726)
		(size 0.4064)
		(drill 0.2032)
		(layers "F.Cu" "B.Cu")
		(net "Net_1673")
	)
	(segment
		(start 152.94991 -279.749758)
		(end 152.47493 -279.274778)
		(width 0.13208)
		(layer "F.Cu")
		(net "Net_1676")
	)
	(via
		(at 152.47493 -279.274778)
		(size 0.4064)
		(drill 0.2032)
		(layers "F.Cu" "B.Cu")
		(net "Net_1676")
	)
	(segment
		(start 307.049932 -289.249866)
		(end 306.574952 -289.724846)
		(width 0.13208)
		(layer "F.Cu")
		(net "Net_1679")
	)
	(via
		(at 306.574952 -289.724846)
		(size 0.4064)
		(drill 0.2032)
		(layers "F.Cu" "B.Cu")
		(net "Net_1679")
	)
	(segment
		(start 157.699964 -280.699718)
		(end 157.224984 -280.224738)
		(width 0.13208)
		(layer "F.Cu")
		(net "Net_1680")
	)
	(via
		(at 157.224984 -280.224738)
		(size 0.4064)
		(drill 0.2032)
		(layers "F.Cu" "B.Cu")
		(net "Net_1680")
	)
	(segment
		(start 308.949852 -299.699934)
		(end 309.424832 -300.174914)
		(width 0.127)
		(layer "F.Cu")
		(net "Net_1681")
	)
	(via
		(at 309.424832 -300.174914)
		(size 0.4064)
		(drill 0.2032)
		(layers "F.Cu" "B.Cu")
		(net "Net_1681")
	)
	(segment
		(start 156.750004 -278.799798)
		(end 156.275024 -278.324818)
		(width 0.13208)
		(layer "F.Cu")
		(net "Net_1682")
	)
	(via
		(at 156.275024 -278.324818)
		(size 0.4064)
		(drill 0.2032)
		(layers "F.Cu" "B.Cu")
		(net "Net_1682")
	)
	(segment
		(start 307.999892 -293.04996)
		(end 307.524912 -293.52494)
		(width 0.13208)
		(layer "F.Cu")
		(net "Net_1683")
	)
	(via
		(at 307.524912 -293.52494)
		(size 0.4064)
		(drill 0.2032)
		(layers "F.Cu" "B.Cu")
		(net "Net_1683")
	)
	(segment
		(start 154.850084 -278.799798)
		(end 154.375104 -278.324818)
		(width 0.13208)
		(layer "F.Cu")
		(net "Net_1684")
	)
	(via
		(at 154.375104 -278.324818)
		(size 0.4064)
		(drill 0.2032)
		(layers "F.Cu" "B.Cu")
		(net "Net_1684")
	)
	(segment
		(start 154.850084 -277.849838)
		(end 154.375104 -277.374858)
		(width 0.13208)
		(layer "F.Cu")
		(net "Net_1686")
	)
	(via
		(at 154.375104 -277.374858)
		(size 0.4064)
		(drill 0.2032)
		(layers "F.Cu" "B.Cu")
		(net "Net_1686")
	)
	(segment
		(start 158.649924 -282.599892)
		(end 158.174944 -282.124912)
		(width 0.13208)
		(layer "F.Cu")
		(net "Net_1688")
	)
	(via
		(at 158.174944 -282.124912)
		(size 0.4064)
		(drill 0.2032)
		(layers "F.Cu" "B.Cu")
		(net "Net_1688")
	)
	(segment
		(start 159.599884 -283.549852)
		(end 159.124904 -283.074872)
		(width 0.13208)
		(layer "F.Cu")
		(net "Net_1690")
	)
	(via
		(at 159.124904 -283.074872)
		(size 0.4064)
		(drill 0.2032)
		(layers "F.Cu" "B.Cu")
		(net "Net_1690")
	)
	(segment
		(start 309.899812 -297.79976)
		(end 310.374792 -298.27474)
		(width 0.127)
		(layer "F.Cu")
		(net "Net_1692")
	)
	(via
		(at 310.374792 -298.27474)
		(size 0.4064)
		(drill 0.2032)
		(layers "F.Cu" "B.Cu")
		(net "Net_1692")
	)
	(segment
		(start 307.049932 -291.149786)
		(end 306.574952 -291.624766)
		(width 0.13208)
		(layer "F.Cu")
		(net "Net_1693")
	)
	(via
		(at 306.574952 -291.624766)
		(size 0.4064)
		(drill 0.2032)
		(layers "F.Cu" "B.Cu")
		(net "Net_1693")
	)
	(segment
		(start 309.899812 -299.699934)
		(end 310.374792 -300.174914)
		(width 0.127)
		(layer "F.Cu")
		(net "Net_1694")
	)
	(via
		(at 310.374792 -300.174914)
		(size 0.4064)
		(drill 0.2032)
		(layers "F.Cu" "B.Cu")
		(net "Net_1694")
	)
	(segment
		(start 307.049932 -293.04996)
		(end 306.574952 -293.52494)
		(width 0.13208)
		(layer "F.Cu")
		(net "Net_1695")
	)
	(via
		(at 306.574952 -293.52494)
		(size 0.4064)
		(drill 0.2032)
		(layers "F.Cu" "B.Cu")
		(net "Net_1695")
	)
	(segment
		(start 307.999892 -296.8498)
		(end 307.524912 -297.32478)
		(width 0.127)
		(layer "F.Cu")
		(net "Net_1700")
	)
	(via
		(at 307.524912 -297.32478)
		(size 0.4064)
		(drill 0.2032)
		(layers "F.Cu" "B.Cu")
		(net "Net_1700")
	)
	(segment
		(start 308.949852 -297.79976)
		(end 309.424832 -298.27474)
		(width 0.127)
		(layer "F.Cu")
		(net "Net_1701")
	)
	(via
		(at 309.424832 -298.27474)
		(size 0.4064)
		(drill 0.2032)
		(layers "F.Cu" "B.Cu")
		(net "Net_1701")
	)
	(segment
		(start 308.949852 -292.099746)
		(end 309.424832 -292.574726)
		(width 0.13208)
		(layer "F.Cu")
		(net "Net_1703")
	)
	(via
		(at 309.424832 -292.574726)
		(size 0.4064)
		(drill 0.2032)
		(layers "F.Cu" "B.Cu")
		(net "Net_1703")
	)
	(segment
		(start 308.949852 -290.199826)
		(end 309.424832 -290.674806)
		(width 0.13208)
		(layer "F.Cu")
		(net "Net_1704")
	)
	(via
		(at 309.424832 -290.674806)
		(size 0.4064)
		(drill 0.2032)
		(layers "F.Cu" "B.Cu")
		(net "Net_1704")
	)
	(segment
		(start 308.949852 -301.599854)
		(end 309.424832 -302.074834)
		(width 0.127)
		(layer "F.Cu")
		(net "Net_1705")
	)
	(via
		(at 309.424832 -302.074834)
		(size 0.4064)
		(drill 0.2032)
		(layers "F.Cu" "B.Cu")
		(net "Net_1705")
	)
	(segment
		(start 155.800044 -282.599892)
		(end 155.325064 -282.124912)
		(width 0.13208)
		(layer "F.Cu")
		(net "Net_1706")
	)
	(via
		(at 155.325064 -282.124912)
		(size 0.4064)
		(drill 0.2032)
		(layers "F.Cu" "B.Cu")
		(net "Net_1706")
	)
	(segment
		(start 155.800044 -275.949918)
		(end 155.325064 -275.474938)
		(width 0.13208)
		(layer "F.Cu")
		(net "Net_1707")
	)
	(via
		(at 155.325064 -275.474938)
		(size 0.4064)
		(drill 0.2032)
		(layers "F.Cu" "B.Cu")
		(net "Net_1707")
	)
	(segment
		(start 155.800044 -274.999958)
		(end 155.325064 -274.524978)
		(width 0.13208)
		(layer "F.Cu")
		(net "Net_1708")
	)
	(via
		(at 155.325064 -274.524978)
		(size 0.4064)
		(drill 0.2032)
		(layers "F.Cu" "B.Cu")
		(net "Net_1708")
	)
	(segment
		(start 154.850084 -286.399732)
		(end 154.375104 -285.924752)
		(width 0.13208)
		(layer "F.Cu")
		(net "Net_1709")
	)
	(via
		(at 154.375104 -285.924752)
		(size 0.4064)
		(drill 0.2032)
		(layers "F.Cu" "B.Cu")
		(net "Net_1709")
	)
	(segment
		(start 152.94991 -289.249866)
		(end 152.47493 -288.774886)
		(width 0.13208)
		(layer "F.Cu")
		(net "Net_1710")
	)
	(via
		(at 152.47493 -288.774886)
		(size 0.4064)
		(drill 0.2032)
		(layers "F.Cu" "B.Cu")
		(net "Net_1710")
	)
	(segment
		(start 153.89987 -285.449772)
		(end 153.42489 -284.974792)
		(width 0.13208)
		(layer "F.Cu")
		(net "Net_1711")
	)
	(via
		(at 153.42489 -284.974792)
		(size 0.4064)
		(drill 0.2032)
		(layers "F.Cu" "B.Cu")
		(net "Net_1711")
	)
	(segment
		(start 155.800044 -286.399732)
		(end 155.325064 -285.924752)
		(width 0.13208)
		(layer "F.Cu")
		(net "Net_1712")
	)
	(via
		(at 155.325064 -285.924752)
		(size 0.4064)
		(drill 0.2032)
		(layers "F.Cu" "B.Cu")
		(net "Net_1712")
	)
	(segment
		(start 159.599884 -275.949918)
		(end 159.124904 -275.474938)
		(width 0.13208)
		(layer "F.Cu")
		(net "Net_1713")
	)
	(via
		(at 159.124904 -275.474938)
		(size 0.4064)
		(drill 0.2032)
		(layers "F.Cu" "B.Cu")
		(net "Net_1713")
	)
	(segment
		(start 274.749768 -277.849838)
		(end 274.274788 -277.374858)
		(width 0.13208)
		(layer "F.Cu")
		(net "Net_1716")
	)
	(via
		(at 274.274788 -277.374858)
		(size 0.4064)
		(drill 0.2032)
		(layers "F.Cu" "B.Cu")
		(net "Net_1716")
	)
	(segment
		(start 158.649924 -274.049744)
		(end 158.174944 -273.574764)
		(width 0.13208)
		(layer "F.Cu")
		(net "Net_1717")
	)
	(via
		(at 158.174944 -273.574764)
		(size 0.4064)
		(drill 0.2032)
		(layers "F.Cu" "B.Cu")
		(net "Net_1717")
	)
	(segment
		(start 156.750004 -274.049744)
		(end 156.275024 -273.574764)
		(width 0.13208)
		(layer "F.Cu")
		(net "Net_1719")
	)
	(via
		(at 156.275024 -273.574764)
		(size 0.4064)
		(drill 0.2032)
		(layers "F.Cu" "B.Cu")
		(net "Net_1719")
	)
	(segment
		(start 274.749768 -282.599892)
		(end 274.274788 -282.124912)
		(width 0.13208)
		(layer "F.Cu")
		(net "Net_1720")
	)
	(via
		(at 274.274788 -282.124912)
		(size 0.4064)
		(drill 0.2032)
		(layers "F.Cu" "B.Cu")
		(net "Net_1720")
	)
	(segment
		(start 157.699964 -274.999958)
		(end 157.224984 -274.524978)
		(width 0.13208)
		(layer "F.Cu")
		(net "Net_1721")
	)
	(via
		(at 157.224984 -274.524978)
		(size 0.4064)
		(drill 0.2032)
		(layers "F.Cu" "B.Cu")
		(net "Net_1721")
	)
	(segment
		(start 272.374868 -278.324818)
		(end 272.849848 -278.799798)
		(width 0.13208)
		(layer "F.Cu")
		(net "Net_1722")
	)
	(via
		(at 272.374868 -278.324818)
		(size 0.4064)
		(drill 0.2032)
		(layers "F.Cu" "B.Cu")
		(net "Net_1722")
	)
	(segment
		(start 156.750004 -273.099784)
		(end 156.275024 -272.624804)
		(width 0.13208)
		(layer "F.Cu")
		(net "Net_1723")
	)
	(via
		(at 156.275024 -272.624804)
		(size 0.4064)
		(drill 0.2032)
		(layers "F.Cu" "B.Cu")
		(net "Net_1723")
	)
	(segment
		(start 157.699964 -275.949918)
		(end 157.224984 -275.474938)
		(width 0.13208)
		(layer "F.Cu")
		(net "Net_1725")
	)
	(via
		(at 157.224984 -275.474938)
		(size 0.4064)
		(drill 0.2032)
		(layers "F.Cu" "B.Cu")
		(net "Net_1725")
	)
	(segment
		(start 385.149852 -279.749758)
		(end 384.674872 -279.274778)
		(width 0.13208)
		(layer "F.Cu")
		(net "Net_1728")
	)
	(via
		(at 384.674872 -279.274778)
		(size 0.4064)
		(drill 0.2032)
		(layers "F.Cu" "B.Cu")
		(net "Net_1728")
	)
	(segment
		(start 270.949928 -277.849838)
		(end 270.474948 -277.374858)
		(width 0.13208)
		(layer "F.Cu")
		(net "Net_1729")
	)
	(via
		(at 270.474948 -277.374858)
		(size 0.4064)
		(drill 0.2032)
		(layers "F.Cu" "B.Cu")
		(net "Net_1729")
	)
	(segment
		(start 271.899888 -279.749758)
		(end 271.424908 -279.274778)
		(width 0.13208)
		(layer "F.Cu")
		(net "Net_1733")
	)
	(via
		(at 271.424908 -279.274778)
		(size 0.4064)
		(drill 0.2032)
		(layers "F.Cu" "B.Cu")
		(net "Net_1733")
	)
	(segment
		(start 154.850084 -284.499812)
		(end 154.375104 -284.024832)
		(width 0.13208)
		(layer "F.Cu")
		(net "Net_1734")
	)
	(via
		(at 154.375104 -284.024832)
		(size 0.4064)
		(drill 0.2032)
		(layers "F.Cu" "B.Cu")
		(net "Net_1734")
	)
	(segment
		(start 274.749768 -278.799798)
		(end 274.274788 -278.324818)
		(width 0.13208)
		(layer "F.Cu")
		(net "Net_1735")
	)
	(via
		(at 274.274788 -278.324818)
		(size 0.4064)
		(drill 0.2032)
		(layers "F.Cu" "B.Cu")
		(net "Net_1735")
	)
	(segment
		(start 273.799808 -280.699718)
		(end 273.324828 -280.224738)
		(width 0.13208)
		(layer "F.Cu")
		(net "Net_1736")
	)
	(via
		(at 273.324828 -280.224738)
		(size 0.4064)
		(drill 0.2032)
		(layers "F.Cu" "B.Cu")
		(net "Net_1736")
	)
	(segment
		(start 155.800044 -284.499812)
		(end 155.325064 -284.024832)
		(width 0.13208)
		(layer "F.Cu")
		(net "Net_1737")
	)
	(via
		(at 155.325064 -284.024832)
		(size 0.4064)
		(drill 0.2032)
		(layers "F.Cu" "B.Cu")
		(net "Net_1737")
	)
	(segment
		(start 336.44205 -169.703496)
		(end 336.44205 -170.053)
		(width 0.13208)
		(layer "F.Cu")
		(net "SSD10_PEX_PWR_EN_R")
	)
	(segment
		(start 338.893912 -218.387168)
		(end 338.494116 -217.987372)
		(width 0.13208)
		(layer "F.Cu")
		(net "SSD10_PEX_PWR_EN_R")
	)
	(segment
		(start 337.67395 -170.053)
		(end 336.44205 -170.053)
		(width 0.13208)
		(layer "F.Cu")
		(net "SSD10_PEX_PWR_EN_R")
	)
	(segment
		(start 326.489314 -172.4152)
		(end 326.782684 -172.70857)
		(width 0.13208)
		(layer "F.Cu")
		(net "SSD10_PEX_PWR_EN_R")
	)
	(segment
		(start 330.967588 -169.576496)
		(end 336.31505 -169.576496)
		(width 0.13208)
		(layer "F.Cu")
		(net "SSD10_PEX_PWR_EN_R")
	)
	(segment
		(start 326.3646 -172.4152)
		(end 326.489314 -172.4152)
		(width 0.13208)
		(layer "F.Cu")
		(net "SSD10_PEX_PWR_EN_R")
	)
	(segment
		(start 336.44205 -170.053)
		(end 336.44205 -171.069)
		(width 0.13208)
		(layer "F.Cu")
		(net "SSD10_PEX_PWR_EN_R")
	)
	(segment
		(start 336.31505 -169.576496)
		(end 336.44205 -169.703496)
		(width 0.13208)
		(layer "F.Cu")
		(net "SSD10_PEX_PWR_EN_R")
	)
	(segment
		(start 327.835514 -172.70857)
		(end 330.967588 -169.576496)
		(width 0.13208)
		(layer "F.Cu")
		(net "SSD10_PEX_PWR_EN_R")
	)
	(segment
		(start 326.782684 -172.70857)
		(end 327.835514 -172.70857)
		(width 0.13208)
		(layer "F.Cu")
		(net "SSD10_PEX_PWR_EN_R")
	)
	(via
		(at 338.494116 -217.987372)
		(size 0.4572)
		(drill 0.254)
		(layers "F.Cu" "B.Cu")
		(net "SSD10_PEX_PWR_EN_R")
	)
	(via
		(at 326.3646 -172.4152)
		(size 0.508)
		(drill 0.254)
		(layers "F.Cu" "B.Cu")
		(net "SSD10_PEX_PWR_EN_R")
	)
	(segment
		(start 325.861426 -217.365326)
		(end 326.312022 -217.815922)
		(width 0.15494)
		(layer "In5.Cu")
		(net "SSD10_PEX_PWR_EN_R")
	)
	(segment
		(start 338.078826 -218.402662)
		(end 338.494116 -217.987372)
		(width 0.0889)
		(layer "In5.Cu")
		(net "SSD10_PEX_PWR_EN_R")
	)
	(segment
		(start 329.366118 -219.289376)
		(end 333.262732 -219.289376)
		(width 0.15494)
		(layer "In5.Cu")
		(net "SSD10_PEX_PWR_EN_R")
	)
	(segment
		(start 326.864472 -217.815922)
		(end 327.853294 -218.804744)
		(width 0.15494)
		(layer "In5.Cu")
		(net "SSD10_PEX_PWR_EN_R")
	)
	(segment
		(start 326.517 -185.853578)
		(end 323.441568 -188.92901)
		(width 0.15494)
		(layer "In5.Cu")
		(net "SSD10_PEX_PWR_EN_R")
	)
	(segment
		(start 333.566262 -219.592906)
		(end 337.590892 -219.592906)
		(width 0.15494)
		(layer "In5.Cu")
		(net "SSD10_PEX_PWR_EN_R")
	)
	(segment
		(start 323.113146 -214.466678)
		(end 325.861426 -217.214958)
		(width 0.15494)
		(layer "In5.Cu")
		(net "SSD10_PEX_PWR_EN_R")
	)
	(segment
		(start 323.441568 -199.729598)
		(end 323.113146 -200.05802)
		(width 0.15494)
		(layer "In5.Cu")
		(net "SSD10_PEX_PWR_EN_R")
	)
	(segment
		(start 326.3646 -172.4152)
		(end 326.20204 -172.57776)
		(width 0.15494)
		(layer "In5.Cu")
		(net "SSD10_PEX_PWR_EN_R")
	)
	(segment
		(start 325.861426 -217.214958)
		(end 325.861426 -217.365326)
		(width 0.15494)
		(layer "In5.Cu")
		(net "SSD10_PEX_PWR_EN_R")
	)
	(segment
		(start 333.262732 -219.289376)
		(end 333.566262 -219.592906)
		(width 0.15494)
		(layer "In5.Cu")
		(net "SSD10_PEX_PWR_EN_R")
	)
	(segment
		(start 323.441568 -188.92901)
		(end 323.441568 -199.729598)
		(width 0.15494)
		(layer "In5.Cu")
		(net "SSD10_PEX_PWR_EN_R")
	)
	(segment
		(start 338.078826 -219.104972)
		(end 338.078826 -218.927934)
		(width 0.15494)
		(layer "In5.Cu")
		(net "SSD10_PEX_PWR_EN_R")
	)
	(segment
		(start 338.078826 -218.927934)
		(end 338.078826 -218.402662)
		(width 0.0889)
		(layer "In5.Cu")
		(net "SSD10_PEX_PWR_EN_R")
	)
	(segment
		(start 337.590892 -219.592906)
		(end 338.078826 -219.104972)
		(width 0.15494)
		(layer "In5.Cu")
		(net "SSD10_PEX_PWR_EN_R")
	)
	(segment
		(start 326.20204 -179.56784)
		(end 326.517 -179.8828)
		(width 0.15494)
		(layer "In5.Cu")
		(net "SSD10_PEX_PWR_EN_R")
	)
	(segment
		(start 326.517 -179.8828)
		(end 326.517 -185.853578)
		(width 0.15494)
		(layer "In5.Cu")
		(net "SSD10_PEX_PWR_EN_R")
	)
	(segment
		(start 327.853294 -218.804744)
		(end 328.881486 -218.804744)
		(width 0.15494)
		(layer "In5.Cu")
		(net "SSD10_PEX_PWR_EN_R")
	)
	(segment
		(start 326.20204 -172.57776)
		(end 326.20204 -179.56784)
		(width 0.15494)
		(layer "In5.Cu")
		(net "SSD10_PEX_PWR_EN_R")
	)
	(segment
		(start 323.113146 -200.05802)
		(end 323.113146 -214.466678)
		(width 0.15494)
		(layer "In5.Cu")
		(net "SSD10_PEX_PWR_EN_R")
	)
	(segment
		(start 328.881486 -218.804744)
		(end 329.366118 -219.289376)
		(width 0.15494)
		(layer "In5.Cu")
		(net "SSD10_PEX_PWR_EN_R")
	)
	(segment
		(start 326.312022 -217.815922)
		(end 326.864472 -217.815922)
		(width 0.15494)
		(layer "In5.Cu")
		(net "SSD10_PEX_PWR_EN_R")
	)
	(segment
		(start 361.58805 -190.246)
		(end 363.474 -190.246)
		(width 0.13208)
		(layer "F.Cu")
		(net "PRSNT_SSD2_FPGA_PCA9555_N")
	)
	(segment
		(start 363.626908 -190.093092)
		(end 365.133382 -190.093092)
		(width 0.13208)
		(layer "F.Cu")
		(net "PRSNT_SSD2_FPGA_PCA9555_N")
	)
	(segment
		(start 365.133382 -190.093092)
		(end 366.263936 -190.093092)
		(width 0.13208)
		(layer "F.Cu")
		(net "PRSNT_SSD2_FPGA_PCA9555_N")
	)
	(segment
		(start 363.474 -190.246)
		(end 363.626908 -190.093092)
		(width 0.13208)
		(layer "F.Cu")
		(net "PRSNT_SSD2_FPGA_PCA9555_N")
	)
	(via
		(at 365.133382 -190.093092)
		(size 0.508)
		(drill 0.254)
		(layers "F.Cu" "B.Cu")
		(net "PRSNT_SSD2_FPGA_PCA9555_N")
	)
	(segment
		(start 230.846884 -143.265398)
		(end 230.846884 -142.271496)
		(width 0.1778)
		(layer "F.Cu")
		(net "P3V3_CLK_GEN_VDDXTAL_CK440_PEX")
	)
	(via
		(at 223.109028 -140.955268)
		(size 0.508)
		(drill 0.254)
		(layers "F.Cu" "B.Cu")
		(net "P3V3_CLK_GEN_VDDXTAL_CK440_PEX")
	)
	(via
		(at 230.846884 -142.271496)
		(size 0.508)
		(drill 0.254)
		(layers "F.Cu" "B.Cu")
		(net "P3V3_CLK_GEN_VDDXTAL_CK440_PEX")
	)
	(segment
		(start 223.109028 -140.955268)
		(end 222.999046 -141.06525)
		(width 0.508)
		(layer "B.Cu")
		(net "P3V3_CLK_GEN_VDDXTAL_CK440_PEX")
	)
	(segment
		(start 222.999046 -141.06525)
		(end 222.999046 -142.357602)
		(width 0.508)
		(layer "B.Cu")
		(net "P3V3_CLK_GEN_VDDXTAL_CK440_PEX")
	)
	(segment
		(start 230.01478 -140.197586)
		(end 230.01478 -141.439392)
		(width 0.508)
		(layer "In5.Cu")
		(net "P3V3_CLK_GEN_VDDXTAL_CK440_PEX")
	)
	(segment
		(start 223.109028 -140.955268)
		(end 225.694494 -138.369802)
		(width 0.508)
		(layer "In5.Cu")
		(net "P3V3_CLK_GEN_VDDXTAL_CK440_PEX")
	)
	(segment
		(start 225.694494 -138.369802)
		(end 228.186996 -138.369802)
		(width 0.508)
		(layer "In5.Cu")
		(net "P3V3_CLK_GEN_VDDXTAL_CK440_PEX")
	)
	(segment
		(start 228.186996 -138.369802)
		(end 230.01478 -140.197586)
		(width 0.508)
		(layer "In5.Cu")
		(net "P3V3_CLK_GEN_VDDXTAL_CK440_PEX")
	)
	(segment
		(start 230.01478 -141.439392)
		(end 230.846884 -142.271496)
		(width 0.508)
		(layer "In5.Cu")
		(net "P3V3_CLK_GEN_VDDXTAL_CK440_PEX")
	)
	(segment
		(start 376.432064 -206.510128)
		(end 376.440192 -206.502)
		(width 0.13208)
		(layer "F.Cu")
		(net "PRSNT_NIC0_FPGA_PCA9555_N")
	)
	(segment
		(start 380.19863 -205.486)
		(end 380.85395 -205.486)
		(width 0.13208)
		(layer "F.Cu")
		(net "PRSNT_NIC0_FPGA_PCA9555_N")
	)
	(segment
		(start 378.206 -206.502)
		(end 379.222 -205.486)
		(width 0.13208)
		(layer "F.Cu")
		(net "PRSNT_NIC0_FPGA_PCA9555_N")
	)
	(segment
		(start 379.222 -205.486)
		(end 380.19863 -205.486)
		(width 0.13208)
		(layer "F.Cu")
		(net "PRSNT_NIC0_FPGA_PCA9555_N")
	)
	(segment
		(start 376.440192 -206.502)
		(end 378.206 -206.502)
		(width 0.13208)
		(layer "F.Cu")
		(net "PRSNT_NIC0_FPGA_PCA9555_N")
	)
	(via
		(at 380.19863 -205.486)
		(size 0.508)
		(drill 0.254)
		(layers "F.Cu" "B.Cu")
		(net "PRSNT_NIC0_FPGA_PCA9555_N")
	)
	(segment
		(start 377.7107 -205.590902)
		(end 378.464064 -204.837538)
		(width 0.13208)
		(layer "F.Cu")
		(net "PRSNT_NIC0_FPGA_R_N")
	)
	(segment
		(start 358.41305 -216.408)
		(end 359.029 -216.408)
		(width 0.13208)
		(layer "F.Cu")
		(net "PRSNT_NIC0_FPGA_R_N")
	)
	(segment
		(start 381.65405 -205.00086)
		(end 381.65405 -205.486)
		(width 0.13208)
		(layer "F.Cu")
		(net "PRSNT_NIC0_FPGA_R_N")
	)
	(segment
		(start 381.490728 -204.837538)
		(end 381.65405 -205.00086)
		(width 0.13208)
		(layer "F.Cu")
		(net "PRSNT_NIC0_FPGA_R_N")
	)
	(segment
		(start 378.464064 -204.837538)
		(end 381.490728 -204.837538)
		(width 0.13208)
		(layer "F.Cu")
		(net "PRSNT_NIC0_FPGA_R_N")
	)
	(via
		(at 359.029 -216.408)
		(size 0.508)
		(drill 0.254)
		(layers "F.Cu" "B.Cu")
		(net "PRSNT_NIC0_FPGA_R_N")
	)
	(via
		(at 377.7107 -205.590902)
		(size 0.508)
		(drill 0.254)
		(layers "F.Cu" "B.Cu")
		(net "PRSNT_NIC0_FPGA_R_N")
	)
	(segment
		(start 377.7107 -205.590902)
		(end 366.893602 -216.408)
		(width 0.15494)
		(layer "In7.Cu")
		(net "PRSNT_NIC0_FPGA_R_N")
	)
	(segment
		(start 366.893602 -216.408)
		(end 359.029 -216.408)
		(width 0.15494)
		(layer "In7.Cu")
		(net "PRSNT_NIC0_FPGA_R_N")
	)
	(via
		(at 227.145596 -143.52016)
		(size 0.6604)
		(drill 0.3302)
		(layers "F.Cu" "B.Cu")
		(net "P3V3_CLK_GEN_VDDPT_CK440_PEX")
	)
	(via
		(at 224.41535 -140.873226)
		(size 0.6604)
		(drill 0.3302)
		(layers "F.Cu" "B.Cu")
		(net "P3V3_CLK_GEN_VDDPT_CK440_PEX")
	)
	(via
		(at 228.449378 -142.244826)
		(size 0.508)
		(drill 0.254)
		(layers "F.Cu" "B.Cu")
		(net "P3V3_CLK_GEN_VDDPT_CK440_PEX")
	)
	(via
		(at 226.129596 -143.52016)
		(size 0.6604)
		(drill 0.3302)
		(layers "F.Cu" "B.Cu")
		(net "P3V3_CLK_GEN_VDDPT_CK440_PEX")
	)
	(segment
		(start 228.60762 -142.144242)
		(end 228.29901 -142.452852)
		(width 0.381)
		(layer "B.Cu")
		(net "P3V3_CLK_GEN_VDDPT_CK440_PEX")
	)
	(segment
		(start 225.242628 -141.700504)
		(end 224.41535 -140.873226)
		(width 0.13208)
		(layer "B.Cu")
		(net "P3V3_CLK_GEN_VDDPT_CK440_PEX")
	)
	(segment
		(start 228.29901 -142.452852)
		(end 228.29901 -143.415004)
		(width 0.381)
		(layer "B.Cu")
		(net "P3V3_CLK_GEN_VDDPT_CK440_PEX")
	)
	(segment
		(start 225.567748 -141.700504)
		(end 225.242628 -141.700504)
		(width 0.13208)
		(layer "B.Cu")
		(net "P3V3_CLK_GEN_VDDPT_CK440_PEX")
	)
	(segment
		(start 226.047046 -142.179802)
		(end 225.567748 -141.700504)
		(width 0.13208)
		(layer "B.Cu")
		(net "P3V3_CLK_GEN_VDDPT_CK440_PEX")
	)
	(segment
		(start 365.90605 -207.899)
		(end 367.538 -207.899)
		(width 0.13208)
		(layer "F.Cu")
		(net "PRSNT_SSD1_FPGA_PCA9555_N")
	)
	(segment
		(start 367.538 -207.899)
		(end 368.848894 -209.209894)
		(width 0.13208)
		(layer "F.Cu")
		(net "PRSNT_SSD1_FPGA_PCA9555_N")
	)
	(segment
		(start 368.848894 -209.209894)
		(end 370.581936 -209.209894)
		(width 0.13208)
		(layer "F.Cu")
		(net "PRSNT_SSD1_FPGA_PCA9555_N")
	)
	(via
		(at 367.538 -207.899)
		(size 0.508)
		(drill 0.254)
		(layers "F.Cu" "B.Cu")
		(net "PRSNT_SSD1_FPGA_PCA9555_N")
	)
	(segment
		(start 226.09683 -144.01546)
		(end 225.474276 -144.01546)
		(width 0.2032)
		(layer "F.Cu")
		(net "P3V3_CLK_GEN_VDDA25M_CK440_PEX")
	)
	(segment
		(start 225.474276 -144.01546)
		(end 225.403918 -143.945102)
		(width 0.2032)
		(layer "F.Cu")
		(net "P3V3_CLK_GEN_VDDA25M_CK440_PEX")
	)
	(via
		(at 221.555056 -143.89862)
		(size 0.6604)
		(drill 0.3302)
		(layers "F.Cu" "B.Cu")
		(net "P3V3_CLK_GEN_VDDA25M_CK440_PEX")
	)
	(via
		(at 221.555056 -141.86662)
		(size 0.6604)
		(drill 0.3302)
		(layers "F.Cu" "B.Cu")
		(net "P3V3_CLK_GEN_VDDA25M_CK440_PEX")
	)
	(via
		(at 225.403918 -143.945102)
		(size 0.508)
		(drill 0.254)
		(layers "F.Cu" "B.Cu")
		(net "P3V3_CLK_GEN_VDDA25M_CK440_PEX")
	)
	(via
		(at 221.555056 -142.88262)
		(size 0.6604)
		(drill 0.3302)
		(layers "F.Cu" "B.Cu")
		(net "P3V3_CLK_GEN_VDDA25M_CK440_PEX")
	)
	(segment
		(start 225.164904 -145.169128)
		(end 225.164904 -144.660112)
		(width 0.381)
		(layer "B.Cu")
		(net "P3V3_CLK_GEN_VDDA25M_CK440_PEX")
	)
	(segment
		(start 225.403918 -144.421098)
		(end 225.403918 -143.945102)
		(width 0.381)
		(layer "B.Cu")
		(net "P3V3_CLK_GEN_VDDA25M_CK440_PEX")
	)
	(segment
		(start 225.164904 -144.660112)
		(end 225.403918 -144.421098)
		(width 0.381)
		(layer "B.Cu")
		(net "P3V3_CLK_GEN_VDDA25M_CK440_PEX")
	)
	(segment
		(start 224.554542 -181.649116)
		(end 224.22231 -181.316884)
		(width 0.13208)
		(layer "F.Cu")
		(net "RST_BIC_BUF_RSMRST_N_BUF")
	)
	(segment
		(start 223.744028 -181.795166)
		(end 222.961454 -181.795166)
		(width 0.13208)
		(layer "F.Cu")
		(net "RST_BIC_BUF_RSMRST_N_BUF")
	)
	(segment
		(start 224.22231 -181.316884)
		(end 223.744028 -181.795166)
		(width 0.13208)
		(layer "F.Cu")
		(net "RST_BIC_BUF_RSMRST_N_BUF")
	)
	(segment
		(start 222.942658 -181.813962)
		(end 222.961454 -181.795166)
		(width 0.13208)
		(layer "F.Cu")
		(net "RST_BIC_BUF_RSMRST_N_BUF")
	)
	(segment
		(start 224.456244 -183.58358)
		(end 224.456244 -182.51678)
		(width 0.13208)
		(layer "F.Cu")
		(net "RST_BIC_BUF_RSMRST_N_BUF")
	)
	(segment
		(start 224.554542 -182.418482)
		(end 224.554542 -181.649116)
		(width 0.13208)
		(layer "F.Cu")
		(net "RST_BIC_BUF_RSMRST_N_BUF")
	)
	(segment
		(start 224.456244 -182.51678)
		(end 224.554542 -182.418482)
		(width 0.13208)
		(layer "F.Cu")
		(net "RST_BIC_BUF_RSMRST_N_BUF")
	)
	(segment
		(start 222.942658 -183.40324)
		(end 222.942658 -181.813962)
		(width 0.13208)
		(layer "F.Cu")
		(net "RST_BIC_BUF_RSMRST_N_BUF")
	)
	(via
		(at 224.22231 -181.316884)
		(size 0.762)
		(drill 0.381)
		(layers "F.Cu" "B.Cu")
		(net "RST_BIC_BUF_RSMRST_N_BUF")
	)
	(segment
		(start 235.690664 -204.84211)
		(end 235.690664 -206.11211)
		(width 0.13208)
		(layer "F.Cu")
		(net "RST_BIC_SRST_BIC_N")
	)
	(segment
		(start 233.867706 -214.304118)
		(end 234.267502 -213.904322)
		(width 0.13208)
		(layer "F.Cu")
		(net "RST_BIC_SRST_BIC_N")
	)
	(segment
		(start 235.690664 -206.11211)
		(end 235.406692 -206.11211)
		(width 0.13208)
		(layer "F.Cu")
		(net "RST_BIC_SRST_BIC_N")
	)
	(segment
		(start 235.007912 -206.51089)
		(end 235.007912 -207.501236)
		(width 0.13208)
		(layer "F.Cu")
		(net "RST_BIC_SRST_BIC_N")
	)
	(segment
		(start 235.406692 -206.11211)
		(end 235.007912 -206.51089)
		(width 0.13208)
		(layer "F.Cu")
		(net "RST_BIC_SRST_BIC_N")
	)
	(via
		(at 235.007912 -207.501236)
		(size 0.508)
		(drill 0.254)
		(layers "F.Cu" "B.Cu")
		(net "RST_BIC_SRST_BIC_N")
	)
	(via
		(at 235.678218 -209.062574)
		(size 0.6604)
		(drill 0.3302)
		(layers "F.Cu" "B.Cu")
		(net "RST_BIC_SRST_BIC_N")
	)
	(via
		(at 234.267502 -213.904322)
		(size 0.4572)
		(drill 0.254)
		(layers "F.Cu" "B.Cu")
		(net "RST_BIC_SRST_BIC_N")
	)
	(segment
		(start 234.267502 -213.904322)
		(end 234.267502 -213.543134)
		(width 0.13208)
		(layer "B.Cu")
		(net "RST_BIC_SRST_BIC_N")
	)
	(segment
		(start 234.667298 -211.635848)
		(end 235.61802 -210.685126)
		(width 0.13208)
		(layer "B.Cu")
		(net "RST_BIC_SRST_BIC_N")
	)
	(segment
		(start 235.61802 -210.685126)
		(end 235.61802 -209.185002)
		(width 0.13208)
		(layer "B.Cu")
		(net "RST_BIC_SRST_BIC_N")
	)
	(segment
		(start 235.678218 -209.124804)
		(end 235.678218 -209.062574)
		(width 0.13208)
		(layer "B.Cu")
		(net "RST_BIC_SRST_BIC_N")
	)
	(segment
		(start 234.631738 -213.178898)
		(end 234.631738 -212.057488)
		(width 0.13208)
		(layer "B.Cu")
		(net "RST_BIC_SRST_BIC_N")
	)
	(segment
		(start 234.631738 -212.057488)
		(end 234.667298 -212.021928)
		(width 0.13208)
		(layer "B.Cu")
		(net "RST_BIC_SRST_BIC_N")
	)
	(segment
		(start 234.267502 -213.543134)
		(end 234.631738 -213.178898)
		(width 0.13208)
		(layer "B.Cu")
		(net "RST_BIC_SRST_BIC_N")
	)
	(segment
		(start 234.667298 -212.021928)
		(end 234.667298 -211.635848)
		(width 0.13208)
		(layer "B.Cu")
		(net "RST_BIC_SRST_BIC_N")
	)
	(segment
		(start 235.61802 -209.185002)
		(end 235.678218 -209.124804)
		(width 0.13208)
		(layer "B.Cu")
		(net "RST_BIC_SRST_BIC_N")
	)
	(segment
		(start 235.007912 -207.501236)
		(end 235.007912 -207.671924)
		(width 0.13208)
		(layer "B.Cu")
		(net "RST_BIC_SRST_BIC_N")
	)
	(segment
		(start 235.007912 -207.671924)
		(end 235.678218 -208.34223)
		(width 0.13208)
		(layer "B.Cu")
		(net "RST_BIC_SRST_BIC_N")
	)
	(segment
		(start 235.678218 -208.34223)
		(end 235.678218 -209.062574)
		(width 0.13208)
		(layer "B.Cu")
		(net "RST_BIC_SRST_BIC_N")
	)
	(segment
		(start 368.28222 -211.963)
		(end 367.792 -211.963)
		(width 0.13208)
		(layer "F.Cu")
		(net "PRSNT_SSD0_FPGA_PCA9555_N")
	)
	(segment
		(start 367.792 -211.963)
		(end 365.90605 -211.963)
		(width 0.13208)
		(layer "F.Cu")
		(net "PRSNT_SSD0_FPGA_PCA9555_N")
	)
	(segment
		(start 368.435128 -211.810092)
		(end 368.28222 -211.963)
		(width 0.13208)
		(layer "F.Cu")
		(net "PRSNT_SSD0_FPGA_PCA9555_N")
	)
	(segment
		(start 370.581936 -211.810092)
		(end 368.435128 -211.810092)
		(width 0.13208)
		(layer "F.Cu")
		(net "PRSNT_SSD0_FPGA_PCA9555_N")
	)
	(via
		(at 367.792 -211.963)
		(size 0.508)
		(drill 0.254)
		(layers "F.Cu" "B.Cu")
		(net "PRSNT_SSD0_FPGA_PCA9555_N")
	)
	(segment
		(start 233.509312 -173.49089)
		(end 234.040172 -172.96003)
		(width 0.13208)
		(layer "F.Cu")
		(net "RST_BIC_SRST_N")
	)
	(segment
		(start 233.509312 -174.147988)
		(end 233.509312 -173.49089)
		(width 0.13208)
		(layer "F.Cu")
		(net "RST_BIC_SRST_N")
	)
	(segment
		(start 233.919522 -174.558198)
		(end 233.509312 -174.147988)
		(width 0.13208)
		(layer "F.Cu")
		(net "RST_BIC_SRST_N")
	)
	(segment
		(start 234.932728 -174.558198)
		(end 233.919522 -174.558198)
		(width 0.13208)
		(layer "F.Cu")
		(net "RST_BIC_SRST_N")
	)
	(segment
		(start 235.056172 -172.96003)
		(end 234.040172 -172.96003)
		(width 0.13208)
		(layer "F.Cu")
		(net "RST_BIC_SRST_N")
	)
	(via
		(at 233.509312 -174.147988)
		(size 0.762)
		(drill 0.381)
		(layers "F.Cu" "B.Cu")
		(net "RST_BIC_SRST_N")
	)
	(segment
		(start 130.878326 -199.52589)
		(end 130.878326 -198.573136)
		(width 0.13208)
		(layer "F.Cu")
		(net "NIC7_CLK_EN_R_N")
	)
	(segment
		(start 130.702304 -199.701912)
		(end 130.878326 -199.52589)
		(width 0.13208)
		(layer "F.Cu")
		(net "NIC7_CLK_EN_R_N")
	)
	(segment
		(start 130.71729 -197.391782)
		(end 130.71729 -196.668898)
		(width 0.13208)
		(layer "F.Cu")
		(net "NIC7_CLK_EN_R_N")
	)
	(segment
		(start 130.71729 -198.4121)
		(end 130.71729 -197.391782)
		(width 0.13208)
		(layer "F.Cu")
		(net "NIC7_CLK_EN_R_N")
	)
	(segment
		(start 130.71729 -196.668898)
		(end 130.441954 -196.393562)
		(width 0.13208)
		(layer "F.Cu")
		(net "NIC7_CLK_EN_R_N")
	)
	(segment
		(start 358.41305 -214.376)
		(end 359.029 -214.376)
		(width 0.13208)
		(layer "F.Cu")
		(net "NIC7_CLK_EN_R_N")
	)
	(segment
		(start 130.878326 -198.573136)
		(end 130.71729 -198.4121)
		(width 0.13208)
		(layer "F.Cu")
		(net "NIC7_CLK_EN_R_N")
	)
	(via
		(at 128.178814 -200.441306)
		(size 0.508)
		(drill 0.254)
		(layers "F.Cu" "B.Cu")
		(net "NIC7_CLK_EN_R_N")
	)
	(via
		(at 359.029 -214.376)
		(size 0.508)
		(drill 0.254)
		(layers "F.Cu" "B.Cu")
		(net "NIC7_CLK_EN_R_N")
	)
	(via
		(at 130.441954 -196.393562)
		(size 0.508)
		(drill 0.254)
		(layers "F.Cu" "B.Cu")
		(net "NIC7_CLK_EN_R_N")
	)
	(segment
		(start 129.474214 -196.393562)
		(end 127.46355 -198.404226)
		(width 0.15494)
		(layer "In5.Cu")
		(net "NIC7_CLK_EN_R_N")
	)
	(segment
		(start 130.441954 -196.393562)
		(end 129.474214 -196.393562)
		(width 0.15494)
		(layer "In5.Cu")
		(net "NIC7_CLK_EN_R_N")
	)
	(segment
		(start 127.46355 -199.726042)
		(end 128.178814 -200.441306)
		(width 0.15494)
		(layer "In5.Cu")
		(net "NIC7_CLK_EN_R_N")
	)
	(segment
		(start 127.46355 -198.404226)
		(end 127.46355 -199.726042)
		(width 0.15494)
		(layer "In5.Cu")
		(net "NIC7_CLK_EN_R_N")
	)
	(segment
		(start 341.723472 -191.91732)
		(end 341.370412 -191.91732)
		(width 0.15494)
		(layer "In15.Cu")
		(net "NIC7_CLK_EN_R_N")
	)
	(segment
		(start 259.910834 -187.017152)
		(end 253.34468 -187.017152)
		(width 0.15494)
		(layer "In15.Cu")
		(net "NIC7_CLK_EN_R_N")
	)
	(segment
		(start 237.451138 -184.28843)
		(end 236.902498 -184.83707)
		(width 0.15494)
		(layer "In15.Cu")
		(net "NIC7_CLK_EN_R_N")
	)
	(segment
		(start 211.70265 -184.425082)
		(end 210.726274 -183.448706)
		(width 0.15494)
		(layer "In15.Cu")
		(net "NIC7_CLK_EN_R_N")
	)
	(segment
		(start 150.2664 -201.0664)
		(end 148.8694 -202.4634)
		(width 0.15494)
		(layer "In15.Cu")
		(net "NIC7_CLK_EN_R_N")
	)
	(segment
		(start 358.10571 -213.62797)
		(end 358.10571 -205.309724)
		(width 0.15494)
		(layer "In15.Cu")
		(net "NIC7_CLK_EN_R_N")
	)
	(segment
		(start 326.559926 -187.586874)
		(end 301.099474 -187.586874)
		(width 0.15494)
		(layer "In15.Cu")
		(net "NIC7_CLK_EN_R_N")
	)
	(segment
		(start 181.243478 -183.448706)
		(end 170.992038 -193.700146)
		(width 0.15494)
		(layer "In15.Cu")
		(net "NIC7_CLK_EN_R_N")
	)
	(segment
		(start 300.72838 -187.957968)
		(end 285.663132 -187.957968)
		(width 0.15494)
		(layer "In15.Cu")
		(net "NIC7_CLK_EN_R_N")
	)
	(segment
		(start 146.939 -202.947778)
		(end 129.350516 -202.947778)
		(width 0.15494)
		(layer "In15.Cu")
		(net "NIC7_CLK_EN_R_N")
	)
	(segment
		(start 261.560056 -185.36793)
		(end 259.910834 -187.017152)
		(width 0.15494)
		(layer "In15.Cu")
		(net "NIC7_CLK_EN_R_N")
	)
	(segment
		(start 253.03861 -187.323222)
		(end 241.101118 -187.323222)
		(width 0.15494)
		(layer "In15.Cu")
		(net "NIC7_CLK_EN_R_N")
	)
	(segment
		(start 341.370412 -191.91732)
		(end 340.402672 -190.94958)
		(width 0.15494)
		(layer "In15.Cu")
		(net "NIC7_CLK_EN_R_N")
	)
	(segment
		(start 338.09559 -191.321182)
		(end 330.294234 -191.321182)
		(width 0.15494)
		(layer "In15.Cu")
		(net "NIC7_CLK_EN_R_N")
	)
	(segment
		(start 210.726274 -183.448706)
		(end 181.243478 -183.448706)
		(width 0.15494)
		(layer "In15.Cu")
		(net "NIC7_CLK_EN_R_N")
	)
	(segment
		(start 344.439494 -194.633342)
		(end 341.723472 -191.91732)
		(width 0.15494)
		(layer "In15.Cu")
		(net "NIC7_CLK_EN_R_N")
	)
	(segment
		(start 344.439494 -196.44487)
		(end 344.439494 -194.633342)
		(width 0.15494)
		(layer "In15.Cu")
		(net "NIC7_CLK_EN_R_N")
	)
	(segment
		(start 301.099474 -187.586874)
		(end 300.72838 -187.957968)
		(width 0.15494)
		(layer "In15.Cu")
		(net "NIC7_CLK_EN_R_N")
	)
	(segment
		(start 359.029 -214.376)
		(end 358.85374 -214.376)
		(width 0.15494)
		(layer "In15.Cu")
		(net "NIC7_CLK_EN_R_N")
	)
	(segment
		(start 253.34468 -187.017152)
		(end 253.03861 -187.323222)
		(width 0.15494)
		(layer "In15.Cu")
		(net "NIC7_CLK_EN_R_N")
	)
	(segment
		(start 150.2664 -199.3646)
		(end 150.2664 -201.0664)
		(width 0.15494)
		(layer "In15.Cu")
		(net "NIC7_CLK_EN_R_N")
	)
	(segment
		(start 238.066326 -184.28843)
		(end 237.451138 -184.28843)
		(width 0.15494)
		(layer "In15.Cu")
		(net "NIC7_CLK_EN_R_N")
	)
	(segment
		(start 330.294234 -191.321182)
		(end 326.559926 -187.586874)
		(width 0.15494)
		(layer "In15.Cu")
		(net "NIC7_CLK_EN_R_N")
	)
	(segment
		(start 225.809048 -184.425082)
		(end 211.70265 -184.425082)
		(width 0.15494)
		(layer "In15.Cu")
		(net "NIC7_CLK_EN_R_N")
	)
	(segment
		(start 147.423378 -202.4634)
		(end 146.939 -202.947778)
		(width 0.15494)
		(layer "In15.Cu")
		(net "NIC7_CLK_EN_R_N")
	)
	(segment
		(start 155.930854 -193.700146)
		(end 150.2664 -199.3646)
		(width 0.15494)
		(layer "In15.Cu")
		(net "NIC7_CLK_EN_R_N")
	)
	(segment
		(start 236.902498 -184.83707)
		(end 226.221036 -184.83707)
		(width 0.15494)
		(layer "In15.Cu")
		(net "NIC7_CLK_EN_R_N")
	)
	(segment
		(start 241.101118 -187.323222)
		(end 238.066326 -184.28843)
		(width 0.15494)
		(layer "In15.Cu")
		(net "NIC7_CLK_EN_R_N")
	)
	(segment
		(start 352.533204 -199.737218)
		(end 347.731842 -199.737218)
		(width 0.15494)
		(layer "In15.Cu")
		(net "NIC7_CLK_EN_R_N")
	)
	(segment
		(start 129.350516 -202.947778)
		(end 127.854456 -201.451718)
		(width 0.15494)
		(layer "In15.Cu")
		(net "NIC7_CLK_EN_R_N")
	)
	(segment
		(start 347.731842 -199.737218)
		(end 344.439494 -196.44487)
		(width 0.15494)
		(layer "In15.Cu")
		(net "NIC7_CLK_EN_R_N")
	)
	(segment
		(start 127.854456 -201.451718)
		(end 127.854456 -200.765664)
		(width 0.15494)
		(layer "In15.Cu")
		(net "NIC7_CLK_EN_R_N")
	)
	(segment
		(start 127.854456 -200.765664)
		(end 128.178814 -200.441306)
		(width 0.15494)
		(layer "In15.Cu")
		(net "NIC7_CLK_EN_R_N")
	)
	(segment
		(start 340.402672 -190.94958)
		(end 338.467192 -190.94958)
		(width 0.15494)
		(layer "In15.Cu")
		(net "NIC7_CLK_EN_R_N")
	)
	(segment
		(start 148.8694 -202.4634)
		(end 147.423378 -202.4634)
		(width 0.15494)
		(layer "In15.Cu")
		(net "NIC7_CLK_EN_R_N")
	)
	(segment
		(start 283.073094 -185.36793)
		(end 261.560056 -185.36793)
		(width 0.15494)
		(layer "In15.Cu")
		(net "NIC7_CLK_EN_R_N")
	)
	(segment
		(start 338.467192 -190.94958)
		(end 338.09559 -191.321182)
		(width 0.15494)
		(layer "In15.Cu")
		(net "NIC7_CLK_EN_R_N")
	)
	(segment
		(start 358.85374 -214.376)
		(end 358.10571 -213.62797)
		(width 0.15494)
		(layer "In15.Cu")
		(net "NIC7_CLK_EN_R_N")
	)
	(segment
		(start 170.992038 -193.700146)
		(end 155.930854 -193.700146)
		(width 0.15494)
		(layer "In15.Cu")
		(net "NIC7_CLK_EN_R_N")
	)
	(segment
		(start 285.663132 -187.957968)
		(end 283.073094 -185.36793)
		(width 0.15494)
		(layer "In15.Cu")
		(net "NIC7_CLK_EN_R_N")
	)
	(segment
		(start 226.221036 -184.83707)
		(end 225.809048 -184.425082)
		(width 0.15494)
		(layer "In15.Cu")
		(net "NIC7_CLK_EN_R_N")
	)
	(segment
		(start 358.10571 -205.309724)
		(end 352.533204 -199.737218)
		(width 0.15494)
		(layer "In15.Cu")
		(net "NIC7_CLK_EN_R_N")
	)
	(segment
		(start 325.26605 -305.046126)
		(end 325.26605 -304.437034)
		(width 0.13208)
		(layer "F.Cu")
		(net "PEX2_EXT_GPIO_LATCH_N")
	)
	(segment
		(start 325.26605 -305.674522)
		(end 325.26605 -305.046126)
		(width 0.13208)
		(layer "F.Cu")
		(net "PEX2_EXT_GPIO_LATCH_N")
	)
	(segment
		(start 325.26605 -304.437034)
		(end 325.265542 -304.436526)
		(width 0.13208)
		(layer "F.Cu")
		(net "PEX2_EXT_GPIO_LATCH_N")
	)
	(segment
		(start 303.724818 -308.724808)
		(end 303.249838 -309.199788)
		(width 0.13208)
		(layer "F.Cu")
		(net "PEX2_EXT_GPIO_LATCH_N")
	)
	(via
		(at 323.43598 -304.197004)
		(size 0.6604)
		(drill 0.3302)
		(layers "F.Cu" "B.Cu")
		(net "PEX2_EXT_GPIO_LATCH_N")
	)
	(via
		(at 325.26605 -305.046126)
		(size 0.508)
		(drill 0.254)
		(layers "F.Cu" "B.Cu")
		(net "PEX2_EXT_GPIO_LATCH_N")
	)
	(via
		(at 303.724818 -308.724808)
		(size 0.4064)
		(drill 0.2032)
		(layers "F.Cu" "B.Cu")
		(net "PEX2_EXT_GPIO_LATCH_N")
	)
	(segment
		(start 321.674998 -305.340766)
		(end 321.674998 -304.68951)
		(width 0.13208)
		(layer "B.Cu")
		(net "PEX2_EXT_GPIO_LATCH_N")
	)
	(segment
		(start 304.199798 -309.199788)
		(end 305.197256 -309.199788)
		(width 0.13208)
		(layer "B.Cu")
		(net "PEX2_EXT_GPIO_LATCH_N")
	)
	(segment
		(start 305.197256 -309.199788)
		(end 305.685444 -308.7116)
		(width 0.13208)
		(layer "B.Cu")
		(net "PEX2_EXT_GPIO_LATCH_N")
	)
	(segment
		(start 303.724818 -308.724808)
		(end 304.199798 -309.199788)
		(width 0.13208)
		(layer "B.Cu")
		(net "PEX2_EXT_GPIO_LATCH_N")
	)
	(segment
		(start 325.26605 -304.696368)
		(end 325.26605 -305.046126)
		(width 0.13208)
		(layer "B.Cu")
		(net "PEX2_EXT_GPIO_LATCH_N")
	)
	(segment
		(start 321.674998 -304.68951)
		(end 322.167504 -304.197004)
		(width 0.13208)
		(layer "B.Cu")
		(net "PEX2_EXT_GPIO_LATCH_N")
	)
	(segment
		(start 324.766686 -304.197004)
		(end 325.26605 -304.696368)
		(width 0.13208)
		(layer "B.Cu")
		(net "PEX2_EXT_GPIO_LATCH_N")
	)
	(segment
		(start 318.304164 -308.7116)
		(end 321.674998 -305.340766)
		(width 0.13208)
		(layer "B.Cu")
		(net "PEX2_EXT_GPIO_LATCH_N")
	)
	(segment
		(start 305.685444 -308.7116)
		(end 318.304164 -308.7116)
		(width 0.13208)
		(layer "B.Cu")
		(net "PEX2_EXT_GPIO_LATCH_N")
	)
	(segment
		(start 322.167504 -304.197004)
		(end 323.43598 -304.197004)
		(width 0.13208)
		(layer "B.Cu")
		(net "PEX2_EXT_GPIO_LATCH_N")
	)
	(segment
		(start 323.43598 -304.197004)
		(end 324.766686 -304.197004)
		(width 0.13208)
		(layer "B.Cu")
		(net "PEX2_EXT_GPIO_LATCH_N")
	)
	(segment
		(start 218.563444 -183.55818)
		(end 217.928444 -183.55818)
		(width 0.13208)
		(layer "F.Cu")
		(net "RST_BIC_SRST_R_N")
	)
	(segment
		(start 230.95331 -172.15993)
		(end 231.767126 -172.15993)
		(width 0.13208)
		(layer "F.Cu")
		(net "RST_BIC_SRST_R_N")
	)
	(segment
		(start 231.969564 -171.957492)
		(end 233.50855 -171.957492)
		(width 0.13208)
		(layer "F.Cu")
		(net "RST_BIC_SRST_R_N")
	)
	(segment
		(start 218.353894 -172.15993)
		(end 230.95331 -172.15993)
		(width 0.13208)
		(layer "F.Cu")
		(net "RST_BIC_SRST_R_N")
	)
	(segment
		(start 233.710988 -172.15993)
		(end 234.040172 -172.15993)
		(width 0.13208)
		(layer "F.Cu")
		(net "RST_BIC_SRST_R_N")
	)
	(segment
		(start 235.690664 -203.430886)
		(end 235.690664 -204.04201)
		(width 0.13208)
		(layer "F.Cu")
		(net "RST_BIC_SRST_R_N")
	)
	(segment
		(start 231.767126 -172.15993)
		(end 231.969564 -171.957492)
		(width 0.13208)
		(layer "F.Cu")
		(net "RST_BIC_SRST_R_N")
	)
	(segment
		(start 218.298014 -172.21581)
		(end 218.353894 -172.15993)
		(width 0.13208)
		(layer "F.Cu")
		(net "RST_BIC_SRST_R_N")
	)
	(segment
		(start 233.50855 -171.957492)
		(end 233.710988 -172.15993)
		(width 0.13208)
		(layer "F.Cu")
		(net "RST_BIC_SRST_R_N")
	)
	(via
		(at 235.690664 -203.430886)
		(size 0.508)
		(drill 0.254)
		(layers "F.Cu" "B.Cu")
		(net "RST_BIC_SRST_R_N")
	)
	(via
		(at 230.95331 -172.15993)
		(size 0.508)
		(drill 0.254)
		(layers "F.Cu" "B.Cu")
		(net "RST_BIC_SRST_R_N")
	)
	(via
		(at 217.928444 -183.55818)
		(size 0.508)
		(drill 0.254)
		(layers "F.Cu" "B.Cu")
		(net "RST_BIC_SRST_R_N")
	)
	(via
		(at 218.298014 -172.21581)
		(size 0.508)
		(drill 0.254)
		(layers "F.Cu" "B.Cu")
		(net "RST_BIC_SRST_R_N")
	)
	(segment
		(start 232.6894 -178.72456)
		(end 232.6894 -182.88)
		(width 0.15494)
		(layer "In5.Cu")
		(net "RST_BIC_SRST_R_N")
	)
	(segment
		(start 230.95331 -176.98847)
		(end 232.6894 -178.72456)
		(width 0.15494)
		(layer "In5.Cu")
		(net "RST_BIC_SRST_R_N")
	)
	(segment
		(start 218.579192 -182.907432)
		(end 217.928444 -183.55818)
		(width 0.15494)
		(layer "In5.Cu")
		(net "RST_BIC_SRST_R_N")
	)
	(segment
		(start 218.298014 -172.21581)
		(end 217.98788 -172.525944)
		(width 0.15494)
		(layer "In5.Cu")
		(net "RST_BIC_SRST_R_N")
	)
	(segment
		(start 217.98788 -176.324768)
		(end 218.579192 -176.91608)
		(width 0.15494)
		(layer "In5.Cu")
		(net "RST_BIC_SRST_R_N")
	)
	(segment
		(start 217.98788 -172.525944)
		(end 217.98788 -176.324768)
		(width 0.15494)
		(layer "In5.Cu")
		(net "RST_BIC_SRST_R_N")
	)
	(segment
		(start 218.579192 -176.91608)
		(end 218.579192 -182.907432)
		(width 0.15494)
		(layer "In5.Cu")
		(net "RST_BIC_SRST_R_N")
	)
	(segment
		(start 240.7793 -196.024246)
		(end 235.690664 -201.112882)
		(width 0.15494)
		(layer "In5.Cu")
		(net "RST_BIC_SRST_R_N")
	)
	(segment
		(start 230.95331 -172.15993)
		(end 230.95331 -176.98847)
		(width 0.15494)
		(layer "In5.Cu")
		(net "RST_BIC_SRST_R_N")
	)
	(segment
		(start 240.7793 -190.9699)
		(end 240.7793 -196.024246)
		(width 0.15494)
		(layer "In5.Cu")
		(net "RST_BIC_SRST_R_N")
	)
	(segment
		(start 232.6894 -182.88)
		(end 240.7793 -190.9699)
		(width 0.15494)
		(layer "In5.Cu")
		(net "RST_BIC_SRST_R_N")
	)
	(segment
		(start 235.690664 -201.112882)
		(end 235.690664 -203.430886)
		(width 0.15494)
		(layer "In5.Cu")
		(net "RST_BIC_SRST_R_N")
	)
	(segment
		(start 224.575116 -228.78923)
		(end 224.575116 -227.695252)
		(width 0.13208)
		(layer "F.Cu")
		(net "REV_ID2")
	)
	(segment
		(start 224.575116 -227.678488)
		(end 226.267518 -225.986086)
		(width 0.13208)
		(layer "F.Cu")
		(net "REV_ID2")
	)
	(segment
		(start 226.267518 -224.304098)
		(end 226.667568 -223.904048)
		(width 0.13208)
		(layer "F.Cu")
		(net "REV_ID2")
	)
	(segment
		(start 219.615512 -231.016556)
		(end 219.615512 -230.601012)
		(width 0.13208)
		(layer "F.Cu")
		(net "REV_ID2")
	)
	(segment
		(start 226.267518 -225.986086)
		(end 226.267518 -224.304098)
		(width 0.13208)
		(layer "F.Cu")
		(net "REV_ID2")
	)
	(segment
		(start 220.448124 -229.7684)
		(end 223.595946 -229.7684)
		(width 0.13208)
		(layer "F.Cu")
		(net "REV_ID2")
	)
	(segment
		(start 220.631512 -231.016556)
		(end 219.615512 -231.016556)
		(width 0.13208)
		(layer "F.Cu")
		(net "REV_ID2")
	)
	(segment
		(start 219.615512 -230.601012)
		(end 220.448124 -229.7684)
		(width 0.13208)
		(layer "F.Cu")
		(net "REV_ID2")
	)
	(segment
		(start 224.575116 -227.695252)
		(end 224.575116 -227.678488)
		(width 0.13208)
		(layer "F.Cu")
		(net "REV_ID2")
	)
	(segment
		(start 223.595946 -229.7684)
		(end 224.575116 -228.78923)
		(width 0.13208)
		(layer "F.Cu")
		(net "REV_ID2")
	)
	(via
		(at 224.575116 -227.695252)
		(size 0.762)
		(drill 0.381)
		(layers "F.Cu" "B.Cu")
		(net "REV_ID2")
	)
	(segment
		(start 220.41612 -184.053226)
		(end 221.164658 -184.053226)
		(width 0.13208)
		(layer "F.Cu")
		(net "RST_BIC_BUF_RSMRST_N")
	)
	(segment
		(start 219.363544 -184.406794)
		(end 219.713048 -184.756298)
		(width 0.13208)
		(layer "F.Cu")
		(net "RST_BIC_BUF_RSMRST_N")
	)
	(segment
		(start 219.363544 -183.55818)
		(end 219.363544 -184.406794)
		(width 0.13208)
		(layer "F.Cu")
		(net "RST_BIC_BUF_RSMRST_N")
	)
	(segment
		(start 219.713048 -184.756298)
		(end 220.41612 -184.053226)
		(width 0.13208)
		(layer "F.Cu")
		(net "RST_BIC_BUF_RSMRST_N")
	)
	(via
		(at 219.713048 -184.756298)
		(size 0.762)
		(drill 0.381)
		(layers "F.Cu" "B.Cu")
		(net "RST_BIC_BUF_RSMRST_N")
	)
	(segment
		(start 333.144622 -164.332666)
		(end 329.936602 -167.540686)
		(width 0.13208)
		(layer "F.Cu")
		(net "RST_PEX_SSD11_PERST_R_N")
	)
	(segment
		(start 336.153506 -164.332666)
		(end 333.144622 -164.332666)
		(width 0.13208)
		(layer "F.Cu")
		(net "RST_PEX_SSD11_PERST_R_N")
	)
	(segment
		(start 337.67395 -164.973)
		(end 336.44205 -164.973)
		(width 0.13208)
		(layer "F.Cu")
		(net "RST_PEX_SSD11_PERST_R_N")
	)
	(segment
		(start 336.44205 -164.973)
		(end 336.44205 -164.62121)
		(width 0.13208)
		(layer "F.Cu")
		(net "RST_PEX_SSD11_PERST_R_N")
	)
	(segment
		(start 336.493866 -213.587076)
		(end 336.093816 -213.187026)
		(width 0.13208)
		(layer "F.Cu")
		(net "RST_PEX_SSD11_PERST_R_N")
	)
	(segment
		(start 336.44205 -164.62121)
		(end 336.153506 -164.332666)
		(width 0.13208)
		(layer "F.Cu")
		(net "RST_PEX_SSD11_PERST_R_N")
	)
	(via
		(at 329.936602 -167.540686)
		(size 0.508)
		(drill 0.254)
		(layers "F.Cu" "B.Cu")
		(net "RST_PEX_SSD11_PERST_R_N")
	)
	(via
		(at 336.093816 -213.187026)
		(size 0.4572)
		(drill 0.254)
		(layers "F.Cu" "B.Cu")
		(net "RST_PEX_SSD11_PERST_R_N")
	)
	(segment
		(start 332.635352 -211.883752)
		(end 332.89113 -211.98967)
		(width 0.15494)
		(layer "In5.Cu")
		(net "RST_PEX_SSD11_PERST_R_N")
	)
	(segment
		(start 329.936602 -167.540686)
		(end 329.517756 -167.959532)
		(width 0.15494)
		(layer "In5.Cu")
		(net "RST_PEX_SSD11_PERST_R_N")
	)
	(segment
		(start 325.755254 -206.172054)
		(end 328.429874 -208.846674)
		(width 0.15494)
		(layer "In5.Cu")
		(net "RST_PEX_SSD11_PERST_R_N")
	)
	(segment
		(start 325.755254 -201.80681)
		(end 325.755254 -206.172054)
		(width 0.15494)
		(layer "In5.Cu")
		(net "RST_PEX_SSD11_PERST_R_N")
	)
	(segment
		(start 328.429874 -208.846674)
		(end 331.14234 -208.846674)
		(width 0.15494)
		(layer "In5.Cu")
		(net "RST_PEX_SSD11_PERST_R_N")
	)
	(segment
		(start 332.89113 -211.98967)
		(end 333.502 -211.98967)
		(width 0.15494)
		(layer "In5.Cu")
		(net "RST_PEX_SSD11_PERST_R_N")
	)
	(segment
		(start 329.517756 -198.044308)
		(end 325.755254 -201.80681)
		(width 0.15494)
		(layer "In5.Cu")
		(net "RST_PEX_SSD11_PERST_R_N")
	)
	(segment
		(start 335.6864 -212.1662)
		(end 335.6864 -212.77961)
		(width 0.0889)
		(layer "In5.Cu")
		(net "RST_PEX_SSD11_PERST_R_N")
	)
	(segment
		(start 331.14234 -208.846674)
		(end 332.253082 -209.957416)
		(width 0.15494)
		(layer "In5.Cu")
		(net "RST_PEX_SSD11_PERST_R_N")
	)
	(segment
		(start 335.50987 -211.98967)
		(end 335.6864 -212.1662)
		(width 0.0889)
		(layer "In5.Cu")
		(net "RST_PEX_SSD11_PERST_R_N")
	)
	(segment
		(start 332.253082 -211.501482)
		(end 332.635352 -211.883752)
		(width 0.15494)
		(layer "In5.Cu")
		(net "RST_PEX_SSD11_PERST_R_N")
	)
	(segment
		(start 329.517756 -167.959532)
		(end 329.517756 -198.044308)
		(width 0.15494)
		(layer "In5.Cu")
		(net "RST_PEX_SSD11_PERST_R_N")
	)
	(segment
		(start 332.253082 -209.957416)
		(end 332.253082 -211.501482)
		(width 0.15494)
		(layer "In5.Cu")
		(net "RST_PEX_SSD11_PERST_R_N")
	)
	(segment
		(start 333.502 -211.98967)
		(end 335.50987 -211.98967)
		(width 0.0889)
		(layer "In5.Cu")
		(net "RST_PEX_SSD11_PERST_R_N")
	)
	(segment
		(start 335.6864 -212.77961)
		(end 336.093816 -213.187026)
		(width 0.0889)
		(layer "In5.Cu")
		(net "RST_PEX_SSD11_PERST_R_N")
	)
	(segment
		(start 358.41305 -217.424)
		(end 359.029 -217.424)
		(width 0.13208)
		(layer "F.Cu")
		(net "RST_NIC7_PERST_R_N")
	)
	(segment
		(start 429.649636 -84.476336)
		(end 428.347632 -84.476336)
		(width 0.13208)
		(layer "F.Cu")
		(net "RST_NIC7_PERST_R_N")
	)
	(via
		(at 416.610038 -95.17126)
		(size 0.508)
		(drill 0.254)
		(layers "F.Cu" "B.Cu")
		(net "RST_NIC7_PERST_R_N")
	)
	(via
		(at 428.347632 -84.476336)
		(size 0.508)
		(drill 0.254)
		(layers "F.Cu" "B.Cu")
		(net "RST_NIC7_PERST_R_N")
	)
	(via
		(at 357.592376 -104.402382)
		(size 0.508)
		(drill 0.254)
		(layers "F.Cu" "B.Cu")
		(net "RST_NIC7_PERST_R_N")
	)
	(via
		(at 359.029 -217.424)
		(size 0.508)
		(drill 0.254)
		(layers "F.Cu" "B.Cu")
		(net "RST_NIC7_PERST_R_N")
	)
	(segment
		(start 416.610038 -93.867986)
		(end 416.610038 -95.17126)
		(width 0.15494)
		(layer "In5.Cu")
		(net "RST_NIC7_PERST_R_N")
	)
	(segment
		(start 421.006016 -89.472008)
		(end 416.610038 -93.867986)
		(width 0.15494)
		(layer "In5.Cu")
		(net "RST_NIC7_PERST_R_N")
	)
	(segment
		(start 427.744636 -85.079332)
		(end 421.836342 -85.079332)
		(width 0.15494)
		(layer "In5.Cu")
		(net "RST_NIC7_PERST_R_N")
	)
	(segment
		(start 421.836342 -85.079332)
		(end 421.006016 -85.909658)
		(width 0.15494)
		(layer "In5.Cu")
		(net "RST_NIC7_PERST_R_N")
	)
	(segment
		(start 421.006016 -85.909658)
		(end 421.006016 -89.472008)
		(width 0.15494)
		(layer "In5.Cu")
		(net "RST_NIC7_PERST_R_N")
	)
	(segment
		(start 428.347632 -84.476336)
		(end 427.744636 -85.079332)
		(width 0.15494)
		(layer "In5.Cu")
		(net "RST_NIC7_PERST_R_N")
	)
	(segment
		(start 357.691182 -164.5158)
		(end 356.123494 -164.5158)
		(width 0.15494)
		(layer "In7.Cu")
		(net "RST_NIC7_PERST_R_N")
	)
	(segment
		(start 354.99675 -124.626116)
		(end 354.99675 -121.723404)
		(width 0.15494)
		(layer "In7.Cu")
		(net "RST_NIC7_PERST_R_N")
	)
	(segment
		(start 359.029 -217.424)
		(end 368.890804 -217.424)
		(width 0.15494)
		(layer "In7.Cu")
		(net "RST_NIC7_PERST_R_N")
	)
	(segment
		(start 356.87 -119.850154)
		(end 356.87 -105.124758)
		(width 0.15494)
		(layer "In7.Cu")
		(net "RST_NIC7_PERST_R_N")
	)
	(segment
		(start 352.6282 -140.162026)
		(end 352.6282 -126.994666)
		(width 0.15494)
		(layer "In7.Cu")
		(net "RST_NIC7_PERST_R_N")
	)
	(segment
		(start 373.79148 -180.152548)
		(end 373.8626 -180.081428)
		(width 0.15494)
		(layer "In7.Cu")
		(net "RST_NIC7_PERST_R_N")
	)
	(segment
		(start 369.871752 -170.4594)
		(end 364.127542 -164.71519)
		(width 0.15494)
		(layer "In7.Cu")
		(net "RST_NIC7_PERST_R_N")
	)
	(segment
		(start 352.336354 -142.085568)
		(end 352.336354 -141.236192)
		(width 0.15494)
		(layer "In7.Cu")
		(net "RST_NIC7_PERST_R_N")
	)
	(segment
		(start 378.079 -209.47761)
		(end 377.842018 -209.240628)
		(width 0.15494)
		(layer "In7.Cu")
		(net "RST_NIC7_PERST_R_N")
	)
	(segment
		(start 356.87 -105.124758)
		(end 357.592376 -104.402382)
		(width 0.15494)
		(layer "In7.Cu")
		(net "RST_NIC7_PERST_R_N")
	)
	(segment
		(start 377.113038 -203.605892)
		(end 377.113038 -189.87135)
		(width 0.15494)
		(layer "In7.Cu")
		(net "RST_NIC7_PERST_R_N")
	)
	(segment
		(start 373.5832 -171.699682)
		(end 373.478298 -171.59478)
		(width 0.15494)
		(layer "In7.Cu")
		(net "RST_NIC7_PERST_R_N")
	)
	(segment
		(start 376.42292 -182.804054)
		(end 376.067066 -182.4482)
		(width 0.15494)
		(layer "In7.Cu")
		(net "RST_NIC7_PERST_R_N")
	)
	(segment
		(start 354.99675 -121.723404)
		(end 356.87 -119.850154)
		(width 0.15494)
		(layer "In7.Cu")
		(net "RST_NIC7_PERST_R_N")
	)
	(segment
		(start 356.123494 -164.5158)
		(end 352.646488 -161.038794)
		(width 0.15494)
		(layer "In7.Cu")
		(net "RST_NIC7_PERST_R_N")
	)
	(segment
		(start 373.478298 -170.86326)
		(end 373.074438 -170.4594)
		(width 0.15494)
		(layer "In7.Cu")
		(net "RST_NIC7_PERST_R_N")
	)
	(segment
		(start 352.083624 -142.338298)
		(end 352.336354 -142.085568)
		(width 0.15494)
		(layer "In7.Cu")
		(net "RST_NIC7_PERST_R_N")
	)
	(segment
		(start 352.083624 -142.545816)
		(end 352.083624 -142.338298)
		(width 0.15494)
		(layer "In7.Cu")
		(net "RST_NIC7_PERST_R_N")
	)
	(segment
		(start 377.113038 -189.87135)
		(end 376.554492 -189.312804)
		(width 0.15494)
		(layer "In7.Cu")
		(net "RST_NIC7_PERST_R_N")
	)
	(segment
		(start 374.3452 -182.4482)
		(end 373.79148 -181.89448)
		(width 0.15494)
		(layer "In7.Cu")
		(net "RST_NIC7_PERST_R_N")
	)
	(segment
		(start 375.99112 -210.323684)
		(end 377.736608 -210.323684)
		(width 0.15494)
		(layer "In7.Cu")
		(net "RST_NIC7_PERST_R_N")
	)
	(segment
		(start 364.127542 -164.71519)
		(end 357.890572 -164.71519)
		(width 0.15494)
		(layer "In7.Cu")
		(net "RST_NIC7_PERST_R_N")
	)
	(segment
		(start 351.9932 -142.63624)
		(end 352.083624 -142.545816)
		(width 0.15494)
		(layer "In7.Cu")
		(net "RST_NIC7_PERST_R_N")
	)
	(segment
		(start 352.646488 -160.04032)
		(end 351.9932 -159.387032)
		(width 0.15494)
		(layer "In7.Cu")
		(net "RST_NIC7_PERST_R_N")
	)
	(segment
		(start 377.842018 -209.240628)
		(end 377.842018 -207.26146)
		(width 0.15494)
		(layer "In7.Cu")
		(net "RST_NIC7_PERST_R_N")
	)
	(segment
		(start 377.842018 -207.26146)
		(end 378.2822 -206.821278)
		(width 0.15494)
		(layer "In7.Cu")
		(net "RST_NIC7_PERST_R_N")
	)
	(segment
		(start 373.074438 -170.4594)
		(end 369.871752 -170.4594)
		(width 0.15494)
		(layer "In7.Cu")
		(net "RST_NIC7_PERST_R_N")
	)
	(segment
		(start 373.8626 -180.081428)
		(end 373.8626 -179.1462)
		(width 0.15494)
		(layer "In7.Cu")
		(net "RST_NIC7_PERST_R_N")
	)
	(segment
		(start 352.366834 -141.205712)
		(end 352.366834 -140.423392)
		(width 0.15494)
		(layer "In7.Cu")
		(net "RST_NIC7_PERST_R_N")
	)
	(segment
		(start 373.79148 -181.89448)
		(end 373.79148 -180.152548)
		(width 0.15494)
		(layer "In7.Cu")
		(net "RST_NIC7_PERST_R_N")
	)
	(segment
		(start 378.079 -209.981292)
		(end 378.079 -209.47761)
		(width 0.15494)
		(layer "In7.Cu")
		(net "RST_NIC7_PERST_R_N")
	)
	(segment
		(start 376.067066 -182.4482)
		(end 374.3452 -182.4482)
		(width 0.15494)
		(layer "In7.Cu")
		(net "RST_NIC7_PERST_R_N")
	)
	(segment
		(start 368.890804 -217.424)
		(end 375.99112 -210.323684)
		(width 0.15494)
		(layer "In7.Cu")
		(net "RST_NIC7_PERST_R_N")
	)
	(segment
		(start 352.366834 -140.423392)
		(end 352.6282 -140.162026)
		(width 0.15494)
		(layer "In7.Cu")
		(net "RST_NIC7_PERST_R_N")
	)
	(segment
		(start 377.736608 -210.323684)
		(end 378.079 -209.981292)
		(width 0.15494)
		(layer "In7.Cu")
		(net "RST_NIC7_PERST_R_N")
	)
	(segment
		(start 351.9932 -159.387032)
		(end 351.9932 -142.63624)
		(width 0.15494)
		(layer "In7.Cu")
		(net "RST_NIC7_PERST_R_N")
	)
	(segment
		(start 373.478298 -171.59478)
		(end 373.478298 -170.86326)
		(width 0.15494)
		(layer "In7.Cu")
		(net "RST_NIC7_PERST_R_N")
	)
	(segment
		(start 378.2822 -206.821278)
		(end 378.2822 -204.775054)
		(width 0.15494)
		(layer "In7.Cu")
		(net "RST_NIC7_PERST_R_N")
	)
	(segment
		(start 357.890572 -164.71519)
		(end 357.691182 -164.5158)
		(width 0.15494)
		(layer "In7.Cu")
		(net "RST_NIC7_PERST_R_N")
	)
	(segment
		(start 352.336354 -141.236192)
		(end 352.366834 -141.205712)
		(width 0.15494)
		(layer "In7.Cu")
		(net "RST_NIC7_PERST_R_N")
	)
	(segment
		(start 373.8626 -179.1462)
		(end 373.5832 -178.8668)
		(width 0.15494)
		(layer "In7.Cu")
		(net "RST_NIC7_PERST_R_N")
	)
	(segment
		(start 376.554492 -189.284102)
		(end 376.42292 -189.15253)
		(width 0.15494)
		(layer "In7.Cu")
		(net "RST_NIC7_PERST_R_N")
	)
	(segment
		(start 352.646488 -161.038794)
		(end 352.646488 -160.04032)
		(width 0.15494)
		(layer "In7.Cu")
		(net "RST_NIC7_PERST_R_N")
	)
	(segment
		(start 376.42292 -189.15253)
		(end 376.42292 -182.804054)
		(width 0.15494)
		(layer "In7.Cu")
		(net "RST_NIC7_PERST_R_N")
	)
	(segment
		(start 378.2822 -204.775054)
		(end 377.113038 -203.605892)
		(width 0.15494)
		(layer "In7.Cu")
		(net "RST_NIC7_PERST_R_N")
	)
	(segment
		(start 352.6282 -126.994666)
		(end 354.99675 -124.626116)
		(width 0.15494)
		(layer "In7.Cu")
		(net "RST_NIC7_PERST_R_N")
	)
	(segment
		(start 376.554492 -189.312804)
		(end 376.554492 -189.284102)
		(width 0.15494)
		(layer "In7.Cu")
		(net "RST_NIC7_PERST_R_N")
	)
	(segment
		(start 373.5832 -178.8668)
		(end 373.5832 -171.699682)
		(width 0.15494)
		(layer "In7.Cu")
		(net "RST_NIC7_PERST_R_N")
	)
	(segment
		(start 372.951502 -104.55783)
		(end 375.901204 -101.608128)
		(width 0.15494)
		(layer "In13.Cu")
		(net "RST_NIC7_PERST_R_N")
	)
	(segment
		(start 397.47698 -96.359472)
		(end 399.452592 -94.38386)
		(width 0.15494)
		(layer "In13.Cu")
		(net "RST_NIC7_PERST_R_N")
	)
	(segment
		(start 383.879598 -92.456)
		(end 390.852914 -92.456)
		(width 0.15494)
		(layer "In13.Cu")
		(net "RST_NIC7_PERST_R_N")
	)
	(segment
		(start 394.756386 -96.359472)
		(end 397.47698 -96.359472)
		(width 0.15494)
		(layer "In13.Cu")
		(net "RST_NIC7_PERST_R_N")
	)
	(segment
		(start 390.852914 -92.456)
		(end 394.756386 -96.359472)
		(width 0.15494)
		(layer "In13.Cu")
		(net "RST_NIC7_PERST_R_N")
	)
	(segment
		(start 357.592376 -104.402382)
		(end 357.747824 -104.55783)
		(width 0.15494)
		(layer "In13.Cu")
		(net "RST_NIC7_PERST_R_N")
	)
	(segment
		(start 399.452592 -94.38386)
		(end 415.822638 -94.38386)
		(width 0.15494)
		(layer "In13.Cu")
		(net "RST_NIC7_PERST_R_N")
	)
	(segment
		(start 415.822638 -94.38386)
		(end 416.610038 -95.17126)
		(width 0.15494)
		(layer "In13.Cu")
		(net "RST_NIC7_PERST_R_N")
	)
	(segment
		(start 375.901204 -101.608128)
		(end 375.901204 -100.434394)
		(width 0.15494)
		(layer "In13.Cu")
		(net "RST_NIC7_PERST_R_N")
	)
	(segment
		(start 375.901204 -100.434394)
		(end 383.879598 -92.456)
		(width 0.15494)
		(layer "In13.Cu")
		(net "RST_NIC7_PERST_R_N")
	)
	(segment
		(start 357.747824 -104.55783)
		(end 372.951502 -104.55783)
		(width 0.15494)
		(layer "In13.Cu")
		(net "RST_NIC7_PERST_R_N")
	)
	(segment
		(start 221.647512 -231.016556)
		(end 221.647512 -230.601012)
		(width 0.13208)
		(layer "F.Cu")
		(net "REV_ID1")
	)
	(segment
		(start 223.704658 -230.3018)
		(end 225.210116 -228.796342)
		(width 0.13208)
		(layer "F.Cu")
		(net "REV_ID1")
	)
	(segment
		(start 225.210116 -227.445824)
		(end 226.667568 -225.988372)
		(width 0.13208)
		(layer "F.Cu")
		(net "REV_ID1")
	)
	(segment
		(start 226.667568 -225.988372)
		(end 226.667568 -224.704148)
		(width 0.13208)
		(layer "F.Cu")
		(net "REV_ID1")
	)
	(segment
		(start 221.647512 -230.601012)
		(end 221.946724 -230.3018)
		(width 0.13208)
		(layer "F.Cu")
		(net "REV_ID1")
	)
	(segment
		(start 225.210116 -228.796342)
		(end 225.210116 -227.445824)
		(width 0.13208)
		(layer "F.Cu")
		(net "REV_ID1")
	)
	(segment
		(start 221.946724 -230.3018)
		(end 223.704658 -230.3018)
		(width 0.13208)
		(layer "F.Cu")
		(net "REV_ID1")
	)
	(segment
		(start 222.663512 -231.016556)
		(end 221.647512 -231.016556)
		(width 0.13208)
		(layer "F.Cu")
		(net "REV_ID1")
	)
	(via
		(at 225.210116 -228.796342)
		(size 0.762)
		(drill 0.381)
		(layers "F.Cu" "B.Cu")
		(net "REV_ID1")
	)
	(segment
		(start 340.992206 -145.201894)
		(end 343.149936 -145.201894)
		(width 0.13208)
		(layer "F.Cu")
		(net "PRSNT_SSD15_FPGA_PCA9555_N")
	)
	(segment
		(start 338.47405 -143.891)
		(end 339.681312 -143.891)
		(width 0.13208)
		(layer "F.Cu")
		(net "PRSNT_SSD15_FPGA_PCA9555_N")
	)
	(segment
		(start 339.681312 -143.891)
		(end 340.179406 -144.389094)
		(width 0.13208)
		(layer "F.Cu")
		(net "PRSNT_SSD15_FPGA_PCA9555_N")
	)
	(segment
		(start 340.179406 -144.389094)
		(end 340.992206 -145.201894)
		(width 0.13208)
		(layer "F.Cu")
		(net "PRSNT_SSD15_FPGA_PCA9555_N")
	)
	(via
		(at 340.179406 -144.389094)
		(size 0.508)
		(drill 0.254)
		(layers "F.Cu" "B.Cu")
		(net "PRSNT_SSD15_FPGA_PCA9555_N")
	)
	(segment
		(start 214.034878 -213.180168)
		(end 214.066628 -213.180168)
		(width 0.13208)
		(layer "F.Cu")
		(net "P0V8_PEX0_SMBALERT")
	)
	(segment
		(start 123.175776 -256.594864)
		(end 123.418092 -256.594864)
		(width 0.13208)
		(layer "F.Cu")
		(net "P0V8_PEX0_SMBALERT")
	)
	(segment
		(start 212.901276 -212.588348)
		(end 213.443058 -212.588348)
		(width 0.13208)
		(layer "F.Cu")
		(net "P0V8_PEX0_SMBALERT")
	)
	(segment
		(start 213.443058 -212.588348)
		(end 214.034878 -213.180168)
		(width 0.13208)
		(layer "F.Cu")
		(net "P0V8_PEX0_SMBALERT")
	)
	(segment
		(start 126.834392 -253.178564)
		(end 127.258064 -253.178564)
		(width 0.13208)
		(layer "F.Cu")
		(net "P0V8_PEX0_SMBALERT")
	)
	(segment
		(start 123.418092 -256.594864)
		(end 126.625096 -253.38786)
		(width 0.13208)
		(layer "F.Cu")
		(net "P0V8_PEX0_SMBALERT")
	)
	(segment
		(start 126.625096 -253.38786)
		(end 126.834392 -253.178564)
		(width 0.13208)
		(layer "F.Cu")
		(net "P0V8_PEX0_SMBALERT")
	)
	(via
		(at 124.639324 -218.272106)
		(size 0.508)
		(drill 0.254)
		(layers "F.Cu" "B.Cu")
		(net "P0V8_PEX0_SMBALERT")
	)
	(via
		(at 212.901276 -212.588348)
		(size 0.508)
		(drill 0.254)
		(layers "F.Cu" "B.Cu")
		(net "P0V8_PEX0_SMBALERT")
	)
	(via
		(at 206.35976 -219.025724)
		(size 0.508)
		(drill 0.254)
		(layers "F.Cu" "B.Cu")
		(net "P0V8_PEX0_SMBALERT")
	)
	(via
		(at 126.625096 -253.38786)
		(size 0.508)
		(drill 0.254)
		(layers "F.Cu" "B.Cu")
		(net "P0V8_PEX0_SMBALERT")
	)
	(segment
		(start 207.020668 -216.373964)
		(end 208.823814 -214.570818)
		(width 0.13208)
		(layer "B.Cu")
		(net "P0V8_PEX0_SMBALERT")
	)
	(segment
		(start 208.823814 -214.570818)
		(end 208.823814 -212.75421)
		(width 0.13208)
		(layer "B.Cu")
		(net "P0V8_PEX0_SMBALERT")
	)
	(segment
		(start 212.430614 -212.588348)
		(end 212.901276 -212.588348)
		(width 0.13208)
		(layer "B.Cu")
		(net "P0V8_PEX0_SMBALERT")
	)
	(segment
		(start 210.7438 -212.592666)
		(end 212.426296 -212.592666)
		(width 0.13208)
		(layer "B.Cu")
		(net "P0V8_PEX0_SMBALERT")
	)
	(segment
		(start 206.35976 -219.025724)
		(end 207.020668 -218.364816)
		(width 0.13208)
		(layer "B.Cu")
		(net "P0V8_PEX0_SMBALERT")
	)
	(segment
		(start 212.426296 -212.592666)
		(end 212.430614 -212.588348)
		(width 0.13208)
		(layer "B.Cu")
		(net "P0V8_PEX0_SMBALERT")
	)
	(segment
		(start 209.5373 -212.040724)
		(end 210.191858 -212.040724)
		(width 0.13208)
		(layer "B.Cu")
		(net "P0V8_PEX0_SMBALERT")
	)
	(segment
		(start 208.823814 -212.75421)
		(end 209.5373 -212.040724)
		(width 0.13208)
		(layer "B.Cu")
		(net "P0V8_PEX0_SMBALERT")
	)
	(segment
		(start 207.020668 -218.364816)
		(end 207.020668 -216.373964)
		(width 0.13208)
		(layer "B.Cu")
		(net "P0V8_PEX0_SMBALERT")
	)
	(segment
		(start 210.191858 -212.040724)
		(end 210.7438 -212.592666)
		(width 0.13208)
		(layer "B.Cu")
		(net "P0V8_PEX0_SMBALERT")
	)
	(segment
		(start 126.625096 -251.342652)
		(end 123.597416 -248.314972)
		(width 0.15494)
		(layer "In5.Cu")
		(net "P0V8_PEX0_SMBALERT")
	)
	(segment
		(start 126.625096 -253.38786)
		(end 126.625096 -251.342652)
		(width 0.15494)
		(layer "In5.Cu")
		(net "P0V8_PEX0_SMBALERT")
	)
	(segment
		(start 123.597416 -248.314972)
		(end 123.597416 -238.821214)
		(width 0.15494)
		(layer "In5.Cu")
		(net "P0V8_PEX0_SMBALERT")
	)
	(segment
		(start 123.206256 -238.430054)
		(end 123.206256 -219.705174)
		(width 0.15494)
		(layer "In5.Cu")
		(net "P0V8_PEX0_SMBALERT")
	)
	(segment
		(start 123.597416 -238.821214)
		(end 123.206256 -238.430054)
		(width 0.15494)
		(layer "In5.Cu")
		(net "P0V8_PEX0_SMBALERT")
	)
	(segment
		(start 123.206256 -219.705174)
		(end 124.639324 -218.272106)
		(width 0.15494)
		(layer "In5.Cu")
		(net "P0V8_PEX0_SMBALERT")
	)
	(segment
		(start 151.675846 -216.319354)
		(end 149.203664 -218.791536)
		(width 0.15494)
		(layer "In13.Cu")
		(net "P0V8_PEX0_SMBALERT")
	)
	(segment
		(start 127.41402 -219.69222)
		(end 127.047498 -219.325698)
		(width 0.15494)
		(layer "In13.Cu")
		(net "P0V8_PEX0_SMBALERT")
	)
	(segment
		(start 206.35976 -219.025724)
		(end 206.200248 -219.025724)
		(width 0.15494)
		(layer "In13.Cu")
		(net "P0V8_PEX0_SMBALERT")
	)
	(segment
		(start 125.692916 -219.325698)
		(end 124.639324 -218.272106)
		(width 0.15494)
		(layer "In13.Cu")
		(net "P0V8_PEX0_SMBALERT")
	)
	(segment
		(start 203.493878 -216.319354)
		(end 151.675846 -216.319354)
		(width 0.15494)
		(layer "In13.Cu")
		(net "P0V8_PEX0_SMBALERT")
	)
	(segment
		(start 127.047498 -219.325698)
		(end 125.692916 -219.325698)
		(width 0.15494)
		(layer "In13.Cu")
		(net "P0V8_PEX0_SMBALERT")
	)
	(segment
		(start 132.221224 -219.69222)
		(end 127.41402 -219.69222)
		(width 0.15494)
		(layer "In13.Cu")
		(net "P0V8_PEX0_SMBALERT")
	)
	(segment
		(start 149.203664 -218.791536)
		(end 133.121908 -218.791536)
		(width 0.15494)
		(layer "In13.Cu")
		(net "P0V8_PEX0_SMBALERT")
	)
	(segment
		(start 133.121908 -218.791536)
		(end 132.221224 -219.69222)
		(width 0.15494)
		(layer "In13.Cu")
		(net "P0V8_PEX0_SMBALERT")
	)
	(segment
		(start 206.200248 -219.025724)
		(end 203.493878 -216.319354)
		(width 0.15494)
		(layer "In13.Cu")
		(net "P0V8_PEX0_SMBALERT")
	)
	(segment
		(start 340.512908 -147.802092)
		(end 342.019382 -147.802092)
		(width 0.13208)
		(layer "F.Cu")
		(net "PRSNT_SSD14_FPGA_PCA9555_N")
	)
	(segment
		(start 338.47405 -147.955)
		(end 340.36 -147.955)
		(width 0.13208)
		(layer "F.Cu")
		(net "PRSNT_SSD14_FPGA_PCA9555_N")
	)
	(segment
		(start 340.36 -147.955)
		(end 340.512908 -147.802092)
		(width 0.13208)
		(layer "F.Cu")
		(net "PRSNT_SSD14_FPGA_PCA9555_N")
	)
	(segment
		(start 342.019382 -147.802092)
		(end 343.149936 -147.802092)
		(width 0.13208)
		(layer "F.Cu")
		(net "PRSNT_SSD14_FPGA_PCA9555_N")
	)
	(via
		(at 342.019382 -147.802092)
		(size 0.508)
		(drill 0.254)
		(layers "F.Cu" "B.Cu")
		(net "PRSNT_SSD14_FPGA_PCA9555_N")
	)
	(segment
		(start 334.09382 -215.187022)
		(end 333.257398 -215.187022)
		(width 0.0889)
		(layer "F.Cu")
		(net "SSD8_PEX_PWR_EN_R")
	)
	(segment
		(start 336.44205 -183.007)
		(end 336.44205 -181.991)
		(width 0.13208)
		(layer "F.Cu")
		(net "SSD8_PEX_PWR_EN_R")
	)
	(segment
		(start 333.257398 -215.187022)
		(end 332.88097 -215.56345)
		(width 0.13208)
		(layer "F.Cu")
		(net "SSD8_PEX_PWR_EN_R")
	)
	(segment
		(start 337.058 -181.991)
		(end 336.44205 -181.991)
		(width 0.13208)
		(layer "F.Cu")
		(net "SSD8_PEX_PWR_EN_R")
	)
	(segment
		(start 337.67395 -181.991)
		(end 337.058 -181.991)
		(width 0.13208)
		(layer "F.Cu")
		(net "SSD8_PEX_PWR_EN_R")
	)
	(via
		(at 337.058 -181.991)
		(size 0.508)
		(drill 0.254)
		(layers "F.Cu" "B.Cu")
		(net "SSD8_PEX_PWR_EN_R")
	)
	(via
		(at 332.88097 -215.56345)
		(size 0.4572)
		(drill 0.254)
		(layers "F.Cu" "B.Cu")
		(net "SSD8_PEX_PWR_EN_R")
	)
	(segment
		(start 326.93864 -202.796648)
		(end 336.5246 -193.210688)
		(width 0.15494)
		(layer "In11.Cu")
		(net "SSD8_PEX_PWR_EN_R")
	)
	(segment
		(start 330.920598 -213.603078)
		(end 330.920598 -211.007198)
		(width 0.15494)
		(layer "In11.Cu")
		(net "SSD8_PEX_PWR_EN_R")
	)
	(segment
		(start 332.88097 -215.56345)
		(end 330.920598 -213.603078)
		(width 0.15494)
		(layer "In11.Cu")
		(net "SSD8_PEX_PWR_EN_R")
	)
	(segment
		(start 328.249026 -208.335626)
		(end 328.249026 -207.481678)
		(width 0.15494)
		(layer "In11.Cu")
		(net "SSD8_PEX_PWR_EN_R")
	)
	(segment
		(start 336.5246 -182.5244)
		(end 337.058 -181.991)
		(width 0.15494)
		(layer "In11.Cu")
		(net "SSD8_PEX_PWR_EN_R")
	)
	(segment
		(start 328.249026 -207.481678)
		(end 326.93864 -206.171292)
		(width 0.15494)
		(layer "In11.Cu")
		(net "SSD8_PEX_PWR_EN_R")
	)
	(segment
		(start 336.5246 -193.210688)
		(end 336.5246 -182.5244)
		(width 0.15494)
		(layer "In11.Cu")
		(net "SSD8_PEX_PWR_EN_R")
	)
	(segment
		(start 326.93864 -206.171292)
		(end 326.93864 -202.796648)
		(width 0.15494)
		(layer "In11.Cu")
		(net "SSD8_PEX_PWR_EN_R")
	)
	(segment
		(start 330.920598 -211.007198)
		(end 328.249026 -208.335626)
		(width 0.15494)
		(layer "In11.Cu")
		(net "SSD8_PEX_PWR_EN_R")
	)
	(segment
		(start 93.066108 -305.674522)
		(end 93.066108 -305.046126)
		(width 0.13208)
		(layer "F.Cu")
		(net "PEX0_EXT_GPIO_LATCH_N")
	)
	(segment
		(start 71.524876 -308.724808)
		(end 71.049896 -309.199788)
		(width 0.13208)
		(layer "F.Cu")
		(net "PEX0_EXT_GPIO_LATCH_N")
	)
	(segment
		(start 93.066108 -304.437034)
		(end 93.0656 -304.436526)
		(width 0.13208)
		(layer "F.Cu")
		(net "PEX0_EXT_GPIO_LATCH_N")
	)
	(segment
		(start 93.066108 -305.046126)
		(end 93.066108 -304.437034)
		(width 0.13208)
		(layer "F.Cu")
		(net "PEX0_EXT_GPIO_LATCH_N")
	)
	(via
		(at 93.066108 -305.046126)
		(size 0.508)
		(drill 0.254)
		(layers "F.Cu" "B.Cu")
		(net "PEX0_EXT_GPIO_LATCH_N")
	)
	(via
		(at 91.236038 -304.197004)
		(size 0.6604)
		(drill 0.3302)
		(layers "F.Cu" "B.Cu")
		(net "PEX0_EXT_GPIO_LATCH_N")
	)
	(via
		(at 71.524876 -308.724808)
		(size 0.4064)
		(drill 0.2032)
		(layers "F.Cu" "B.Cu")
		(net "PEX0_EXT_GPIO_LATCH_N")
	)
	(segment
		(start 72.400668 -309.6006)
		(end 71.524876 -308.724808)
		(width 0.13208)
		(layer "B.Cu")
		(net "PEX0_EXT_GPIO_LATCH_N")
	)
	(segment
		(start 89.967562 -304.197004)
		(end 89.4842 -304.680366)
		(width 0.13208)
		(layer "B.Cu")
		(net "PEX0_EXT_GPIO_LATCH_N")
	)
	(segment
		(start 74.193654 -309.6006)
		(end 72.400668 -309.6006)
		(width 0.13208)
		(layer "B.Cu")
		(net "PEX0_EXT_GPIO_LATCH_N")
	)
	(segment
		(start 74.727054 -308.7116)
		(end 74.3458 -309.092854)
		(width 0.13208)
		(layer "B.Cu")
		(net "PEX0_EXT_GPIO_LATCH_N")
	)
	(segment
		(start 91.236038 -304.197004)
		(end 89.967562 -304.197004)
		(width 0.13208)
		(layer "B.Cu")
		(net "PEX0_EXT_GPIO_LATCH_N")
	)
	(segment
		(start 89.4842 -305.331622)
		(end 86.104222 -308.7116)
		(width 0.13208)
		(layer "B.Cu")
		(net "PEX0_EXT_GPIO_LATCH_N")
	)
	(segment
		(start 74.3458 -309.448454)
		(end 74.193654 -309.6006)
		(width 0.13208)
		(layer "B.Cu")
		(net "PEX0_EXT_GPIO_LATCH_N")
	)
	(segment
		(start 74.3458 -309.092854)
		(end 74.3458 -309.448454)
		(width 0.13208)
		(layer "B.Cu")
		(net "PEX0_EXT_GPIO_LATCH_N")
	)
	(segment
		(start 93.066108 -305.046126)
		(end 93.066108 -304.696368)
		(width 0.13208)
		(layer "B.Cu")
		(net "PEX0_EXT_GPIO_LATCH_N")
	)
	(segment
		(start 86.104222 -308.7116)
		(end 74.727054 -308.7116)
		(width 0.13208)
		(layer "B.Cu")
		(net "PEX0_EXT_GPIO_LATCH_N")
	)
	(segment
		(start 92.566744 -304.197004)
		(end 91.236038 -304.197004)
		(width 0.13208)
		(layer "B.Cu")
		(net "PEX0_EXT_GPIO_LATCH_N")
	)
	(segment
		(start 89.4842 -304.680366)
		(end 89.4842 -305.331622)
		(width 0.13208)
		(layer "B.Cu")
		(net "PEX0_EXT_GPIO_LATCH_N")
	)
	(segment
		(start 93.066108 -304.696368)
		(end 92.566744 -304.197004)
		(width 0.13208)
		(layer "B.Cu")
		(net "PEX0_EXT_GPIO_LATCH_N")
	)
	(segment
		(start 333.187548 -219.987114)
		(end 332.992476 -220.182186)
		(width 0.13208)
		(layer "F.Cu")
		(net "SSD15_PWRDIS_BIC_R")
	)
	(segment
		(start 334.09382 -219.987114)
		(end 333.187548 -219.987114)
		(width 0.13208)
		(layer "F.Cu")
		(net "SSD15_PWRDIS_BIC_R")
	)
	(via
		(at 254.301498 -215.921336)
		(size 0.508)
		(drill 0.254)
		(layers "F.Cu" "B.Cu")
		(net "SSD15_PWRDIS_BIC_R")
	)
	(via
		(at 332.992476 -220.182186)
		(size 0.508)
		(drill 0.254)
		(layers "F.Cu" "B.Cu")
		(net "SSD15_PWRDIS_BIC_R")
	)
	(via
		(at 236.887512 -233.182668)
		(size 0.508)
		(drill 0.254)
		(layers "F.Cu" "B.Cu")
		(net "SSD15_PWRDIS_BIC_R")
	)
	(segment
		(start 236.413548 -232.708704)
		(end 236.413548 -231.758744)
		(width 0.13208)
		(layer "B.Cu")
		(net "SSD15_PWRDIS_BIC_R")
	)
	(segment
		(start 236.887512 -233.182668)
		(end 236.413548 -232.708704)
		(width 0.13208)
		(layer "B.Cu")
		(net "SSD15_PWRDIS_BIC_R")
	)
	(segment
		(start 236.887512 -234.327954)
		(end 236.887512 -233.182668)
		(width 0.13208)
		(layer "B.Cu")
		(net "SSD15_PWRDIS_BIC_R")
	)
	(segment
		(start 236.413548 -231.758744)
		(end 236.546644 -231.625648)
		(width 0.13208)
		(layer "B.Cu")
		(net "SSD15_PWRDIS_BIC_R")
	)
	(segment
		(start 249.231658 -227.866448)
		(end 249.476768 -227.866448)
		(width 0.15494)
		(layer "In7.Cu")
		(net "SSD15_PWRDIS_BIC_R")
	)
	(segment
		(start 251.678186 -225.435414)
		(end 254.0254 -223.0882)
		(width 0.15494)
		(layer "In7.Cu")
		(net "SSD15_PWRDIS_BIC_R")
	)
	(segment
		(start 251.668026 -226.080574)
		(end 251.668026 -225.92919)
		(width 0.15494)
		(layer "In7.Cu")
		(net "SSD15_PWRDIS_BIC_R")
	)
	(segment
		(start 254.3556 -220.343984)
		(end 254.35814 -220.341444)
		(width 0.15494)
		(layer "In7.Cu")
		(net "SSD15_PWRDIS_BIC_R")
	)
	(segment
		(start 248.262394 -228.44887)
		(end 248.663714 -228.44887)
		(width 0.15494)
		(layer "In7.Cu")
		(net "SSD15_PWRDIS_BIC_R")
	)
	(segment
		(start 250.862592 -226.480624)
		(end 251.267976 -226.480624)
		(width 0.15494)
		(layer "In7.Cu")
		(net "SSD15_PWRDIS_BIC_R")
	)
	(segment
		(start 251.668026 -225.92919)
		(end 251.678186 -225.91903)
		(width 0.15494)
		(layer "In7.Cu")
		(net "SSD15_PWRDIS_BIC_R")
	)
	(segment
		(start 248.946924 -228.151182)
		(end 249.231658 -227.866448)
		(width 0.15494)
		(layer "In7.Cu")
		(net "SSD15_PWRDIS_BIC_R")
	)
	(segment
		(start 254.0254 -223.0882)
		(end 254.0254 -220.6752)
		(width 0.15494)
		(layer "In7.Cu")
		(net "SSD15_PWRDIS_BIC_R")
	)
	(segment
		(start 237.371382 -233.666538)
		(end 242.075462 -233.666538)
		(width 0.15494)
		(layer "In7.Cu")
		(net "SSD15_PWRDIS_BIC_R")
	)
	(segment
		(start 254.35814 -220.341444)
		(end 254.35814 -215.977724)
		(width 0.15494)
		(layer "In7.Cu")
		(net "SSD15_PWRDIS_BIC_R")
	)
	(segment
		(start 242.075462 -233.666538)
		(end 243.6622 -232.0798)
		(width 0.15494)
		(layer "In7.Cu")
		(net "SSD15_PWRDIS_BIC_R")
	)
	(segment
		(start 248.261124 -228.4476)
		(end 248.262394 -228.44887)
		(width 0.15494)
		(layer "In7.Cu")
		(net "SSD15_PWRDIS_BIC_R")
	)
	(segment
		(start 251.267976 -226.480624)
		(end 251.668026 -226.080574)
		(width 0.15494)
		(layer "In7.Cu")
		(net "SSD15_PWRDIS_BIC_R")
	)
	(segment
		(start 247.887744 -228.4476)
		(end 248.261124 -228.4476)
		(width 0.15494)
		(layer "In7.Cu")
		(net "SSD15_PWRDIS_BIC_R")
	)
	(segment
		(start 254.35814 -215.977724)
		(end 254.301498 -215.921336)
		(width 0.15494)
		(layer "In7.Cu")
		(net "SSD15_PWRDIS_BIC_R")
	)
	(segment
		(start 251.678186 -225.91903)
		(end 251.678186 -225.435414)
		(width 0.15494)
		(layer "In7.Cu")
		(net "SSD15_PWRDIS_BIC_R")
	)
	(segment
		(start 243.6622 -232.0798)
		(end 244.255544 -232.0798)
		(width 0.15494)
		(layer "In7.Cu")
		(net "SSD15_PWRDIS_BIC_R")
	)
	(segment
		(start 248.946924 -228.16566)
		(end 248.946924 -228.151182)
		(width 0.15494)
		(layer "In7.Cu")
		(net "SSD15_PWRDIS_BIC_R")
	)
	(segment
		(start 244.255544 -232.0798)
		(end 247.887744 -228.4476)
		(width 0.15494)
		(layer "In7.Cu")
		(net "SSD15_PWRDIS_BIC_R")
	)
	(segment
		(start 236.887512 -233.182668)
		(end 237.371382 -233.666538)
		(width 0.15494)
		(layer "In7.Cu")
		(net "SSD15_PWRDIS_BIC_R")
	)
	(segment
		(start 249.476768 -227.866448)
		(end 250.862592 -226.480624)
		(width 0.15494)
		(layer "In7.Cu")
		(net "SSD15_PWRDIS_BIC_R")
	)
	(segment
		(start 248.663714 -228.44887)
		(end 248.946924 -228.16566)
		(width 0.15494)
		(layer "In7.Cu")
		(net "SSD15_PWRDIS_BIC_R")
	)
	(segment
		(start 254.0254 -220.6752)
		(end 254.3556 -220.345)
		(width 0.15494)
		(layer "In7.Cu")
		(net "SSD15_PWRDIS_BIC_R")
	)
	(segment
		(start 254.3556 -220.345)
		(end 254.3556 -220.343984)
		(width 0.15494)
		(layer "In7.Cu")
		(net "SSD15_PWRDIS_BIC_R")
	)
	(segment
		(start 261.125208 -218.243912)
		(end 260.068314 -217.187018)
		(width 0.15494)
		(layer "In15.Cu")
		(net "SSD15_PWRDIS_BIC_R")
	)
	(segment
		(start 329.093068 -218.313)
		(end 327.279 -218.313)
		(width 0.15494)
		(layer "In15.Cu")
		(net "SSD15_PWRDIS_BIC_R")
	)
	(segment
		(start 326.771 -217.805)
		(end 326.34047 -217.805)
		(width 0.15494)
		(layer "In15.Cu")
		(net "SSD15_PWRDIS_BIC_R")
	)
	(segment
		(start 263.143238 -218.123516)
		(end 263.022842 -218.243912)
		(width 0.15494)
		(layer "In15.Cu")
		(net "SSD15_PWRDIS_BIC_R")
	)
	(segment
		(start 291.988748 -213.705948)
		(end 286.892746 -218.80195)
		(width 0.15494)
		(layer "In15.Cu")
		(net "SSD15_PWRDIS_BIC_R")
	)
	(segment
		(start 330.124816 -219.344748)
		(end 329.093068 -218.313)
		(width 0.15494)
		(layer "In15.Cu")
		(net "SSD15_PWRDIS_BIC_R")
	)
	(segment
		(start 332.155038 -219.344748)
		(end 330.124816 -219.344748)
		(width 0.15494)
		(layer "In15.Cu")
		(net "SSD15_PWRDIS_BIC_R")
	)
	(segment
		(start 324.910196 -216.282524)
		(end 321.573398 -216.282524)
		(width 0.15494)
		(layer "In15.Cu")
		(net "SSD15_PWRDIS_BIC_R")
	)
	(segment
		(start 327.279 -218.313)
		(end 326.771 -217.805)
		(width 0.15494)
		(layer "In15.Cu")
		(net "SSD15_PWRDIS_BIC_R")
	)
	(segment
		(start 325.7296 -217.19413)
		(end 325.7296 -217.101928)
		(width 0.15494)
		(layer "In15.Cu")
		(net "SSD15_PWRDIS_BIC_R")
	)
	(segment
		(start 260.068314 -217.187018)
		(end 257.141472 -217.187018)
		(width 0.15494)
		(layer "In15.Cu")
		(net "SSD15_PWRDIS_BIC_R")
	)
	(segment
		(start 325.7296 -217.101928)
		(end 324.910196 -216.282524)
		(width 0.15494)
		(layer "In15.Cu")
		(net "SSD15_PWRDIS_BIC_R")
	)
	(segment
		(start 286.892746 -218.80195)
		(end 266.139676 -218.80195)
		(width 0.15494)
		(layer "In15.Cu")
		(net "SSD15_PWRDIS_BIC_R")
	)
	(segment
		(start 266.139676 -218.80195)
		(end 265.461242 -218.123516)
		(width 0.15494)
		(layer "In15.Cu")
		(net "SSD15_PWRDIS_BIC_R")
	)
	(segment
		(start 321.573398 -216.282524)
		(end 318.996822 -213.705948)
		(width 0.15494)
		(layer "In15.Cu")
		(net "SSD15_PWRDIS_BIC_R")
	)
	(segment
		(start 255.87579 -215.921336)
		(end 254.301498 -215.921336)
		(width 0.15494)
		(layer "In15.Cu")
		(net "SSD15_PWRDIS_BIC_R")
	)
	(segment
		(start 257.141472 -217.187018)
		(end 255.87579 -215.921336)
		(width 0.15494)
		(layer "In15.Cu")
		(net "SSD15_PWRDIS_BIC_R")
	)
	(segment
		(start 326.34047 -217.805)
		(end 325.7296 -217.19413)
		(width 0.15494)
		(layer "In15.Cu")
		(net "SSD15_PWRDIS_BIC_R")
	)
	(segment
		(start 265.461242 -218.123516)
		(end 263.143238 -218.123516)
		(width 0.15494)
		(layer "In15.Cu")
		(net "SSD15_PWRDIS_BIC_R")
	)
	(segment
		(start 318.996822 -213.705948)
		(end 291.988748 -213.705948)
		(width 0.15494)
		(layer "In15.Cu")
		(net "SSD15_PWRDIS_BIC_R")
	)
	(segment
		(start 263.022842 -218.243912)
		(end 261.125208 -218.243912)
		(width 0.15494)
		(layer "In15.Cu")
		(net "SSD15_PWRDIS_BIC_R")
	)
	(segment
		(start 332.992476 -220.182186)
		(end 332.155038 -219.344748)
		(width 0.15494)
		(layer "In15.Cu")
		(net "SSD15_PWRDIS_BIC_R")
	)
	(via
		(at 380.03099 -292.732714)
		(size 0.508)
		(drill 0.254)
		(layers "F.Cu" "B.Cu")
		(net "PCEPLL2_VDDA18_PEX3_R")
	)
	(via
		(at 382.989074 -256.375916)
		(size 0.508)
		(drill 0.254)
		(layers "F.Cu" "B.Cu")
		(net "PCEPLL5_VDDA18_PEX3_R")
	)
	(via
		(at 380.03099 -286.331914)
		(size 0.508)
		(drill 0.254)
		(layers "F.Cu" "B.Cu")
		(net "PCEPLL6_VDDA18_PEX3_R")
	)
	(segment
		(start 132.017262 -197.391782)
		(end 132.017262 -199.68083)
		(width 0.13208)
		(layer "F.Cu")
		(net "NIC6_CLK_EN_R_N")
	)
	(segment
		(start 358.41305 -218.44)
		(end 359.029 -218.44)
		(width 0.13208)
		(layer "F.Cu")
		(net "NIC6_CLK_EN_R_N")
	)
	(segment
		(start 132.017262 -196.715126)
		(end 132.291582 -196.440806)
		(width 0.13208)
		(layer "F.Cu")
		(net "NIC6_CLK_EN_R_N")
	)
	(segment
		(start 132.017262 -199.68083)
		(end 132.019802 -199.68337)
		(width 0.13208)
		(layer "F.Cu")
		(net "NIC6_CLK_EN_R_N")
	)
	(segment
		(start 132.017262 -197.391782)
		(end 132.017262 -196.715126)
		(width 0.13208)
		(layer "F.Cu")
		(net "NIC6_CLK_EN_R_N")
	)
	(via
		(at 128.145032 -199.089518)
		(size 0.508)
		(drill 0.254)
		(layers "F.Cu" "B.Cu")
		(net "NIC6_CLK_EN_R_N")
	)
	(via
		(at 132.291582 -196.440806)
		(size 0.508)
		(drill 0.254)
		(layers "F.Cu" "B.Cu")
		(net "NIC6_CLK_EN_R_N")
	)
	(via
		(at 359.029 -218.44)
		(size 0.508)
		(drill 0.254)
		(layers "F.Cu" "B.Cu")
		(net "NIC6_CLK_EN_R_N")
	)
	(segment
		(start 128.145032 -199.089518)
		(end 129.380488 -197.854062)
		(width 0.15494)
		(layer "In5.Cu")
		(net "NIC6_CLK_EN_R_N")
	)
	(segment
		(start 129.380488 -197.854062)
		(end 130.878326 -197.854062)
		(width 0.15494)
		(layer "In5.Cu")
		(net "NIC6_CLK_EN_R_N")
	)
	(segment
		(start 130.878326 -197.854062)
		(end 132.291582 -196.440806)
		(width 0.15494)
		(layer "In5.Cu")
		(net "NIC6_CLK_EN_R_N")
	)
	(segment
		(start 129.5019 -199.428354)
		(end 130.765042 -200.691496)
		(width 0.15494)
		(layer "In15.Cu")
		(net "NIC6_CLK_EN_R_N")
	)
	(segment
		(start 236.632242 -184.47893)
		(end 237.180882 -183.93029)
		(width 0.15494)
		(layer "In15.Cu")
		(net "NIC6_CLK_EN_R_N")
	)
	(segment
		(start 237.180882 -183.93029)
		(end 238.549434 -183.93029)
		(width 0.15494)
		(layer "In15.Cu")
		(net "NIC6_CLK_EN_R_N")
	)
	(segment
		(start 358.54513 -213.56066)
		(end 358.82834 -213.84387)
		(width 0.15494)
		(layer "In15.Cu")
		(net "NIC6_CLK_EN_R_N")
	)
	(segment
		(start 152.613868 -192.751964)
		(end 170.984164 -192.751964)
		(width 0.15494)
		(layer "In15.Cu")
		(net "NIC6_CLK_EN_R_N")
	)
	(segment
		(start 170.984164 -192.751964)
		(end 180.645562 -183.090566)
		(width 0.15494)
		(layer "In15.Cu")
		(net "NIC6_CLK_EN_R_N")
	)
	(segment
		(start 148.109686 -197.256146)
		(end 152.613868 -192.751964)
		(width 0.15494)
		(layer "In15.Cu")
		(net "NIC6_CLK_EN_R_N")
	)
	(segment
		(start 238.549434 -183.93029)
		(end 240.616486 -185.997342)
		(width 0.15494)
		(layer "In15.Cu")
		(net "NIC6_CLK_EN_R_N")
	)
	(segment
		(start 300.802294 -186.870594)
		(end 331.161644 -186.870594)
		(width 0.15494)
		(layer "In15.Cu")
		(net "NIC6_CLK_EN_R_N")
	)
	(segment
		(start 331.161644 -186.870594)
		(end 333.16037 -188.86932)
		(width 0.15494)
		(layer "In15.Cu")
		(net "NIC6_CLK_EN_R_N")
	)
	(segment
		(start 245.76024 -186.456574)
		(end 252.25629 -186.456574)
		(width 0.15494)
		(layer "In15.Cu")
		(net "NIC6_CLK_EN_R_N")
	)
	(segment
		(start 252.25629 -186.456574)
		(end 253.080012 -185.632852)
		(width 0.15494)
		(layer "In15.Cu")
		(net "NIC6_CLK_EN_R_N")
	)
	(segment
		(start 245.301008 -185.997342)
		(end 245.76024 -186.456574)
		(width 0.15494)
		(layer "In15.Cu")
		(net "NIC6_CLK_EN_R_N")
	)
	(segment
		(start 343.204292 -188.666628)
		(end 352.25863 -188.666628)
		(width 0.15494)
		(layer "In15.Cu")
		(net "NIC6_CLK_EN_R_N")
	)
	(segment
		(start 260.060694 -185.632852)
		(end 261.041896 -184.65165)
		(width 0.15494)
		(layer "In15.Cu")
		(net "NIC6_CLK_EN_R_N")
	)
	(segment
		(start 359.51287 -214.17534)
		(end 359.51287 -214.57666)
		(width 0.15494)
		(layer "In15.Cu")
		(net "NIC6_CLK_EN_R_N")
	)
	(segment
		(start 180.645562 -183.090566)
		(end 212.145118 -183.090566)
		(width 0.15494)
		(layer "In15.Cu")
		(net "NIC6_CLK_EN_R_N")
	)
	(segment
		(start 283.370274 -184.65165)
		(end 285.960312 -187.241688)
		(width 0.15494)
		(layer "In15.Cu")
		(net "NIC6_CLK_EN_R_N")
	)
	(segment
		(start 144.655032 -201.0918)
		(end 147.8407 -197.906132)
		(width 0.15494)
		(layer "In15.Cu")
		(net "NIC6_CLK_EN_R_N")
	)
	(segment
		(start 358.82834 -209.82813)
		(end 358.54513 -210.11134)
		(width 0.15494)
		(layer "In15.Cu")
		(net "NIC6_CLK_EN_R_N")
	)
	(segment
		(start 226.466908 -184.47893)
		(end 236.632242 -184.47893)
		(width 0.15494)
		(layer "In15.Cu")
		(net "NIC6_CLK_EN_R_N")
	)
	(segment
		(start 212.145118 -183.090566)
		(end 213.096602 -184.04205)
		(width 0.15494)
		(layer "In15.Cu")
		(net "NIC6_CLK_EN_R_N")
	)
	(segment
		(start 359.499916 -202.812904)
		(end 359.499916 -209.479896)
		(width 0.15494)
		(layer "In15.Cu")
		(net "NIC6_CLK_EN_R_N")
	)
	(segment
		(start 130.765042 -200.691496)
		(end 142.241016 -200.691496)
		(width 0.15494)
		(layer "In15.Cu")
		(net "NIC6_CLK_EN_R_N")
	)
	(segment
		(start 128.483868 -199.428354)
		(end 129.5019 -199.428354)
		(width 0.15494)
		(layer "In15.Cu")
		(net "NIC6_CLK_EN_R_N")
	)
	(segment
		(start 128.145032 -199.089518)
		(end 128.483868 -199.428354)
		(width 0.15494)
		(layer "In15.Cu")
		(net "NIC6_CLK_EN_R_N")
	)
	(segment
		(start 142.241016 -200.691496)
		(end 142.64132 -201.0918)
		(width 0.15494)
		(layer "In15.Cu")
		(net "NIC6_CLK_EN_R_N")
	)
	(segment
		(start 352.25863 -188.666628)
		(end 355.60381 -192.011808)
		(width 0.15494)
		(layer "In15.Cu")
		(net "NIC6_CLK_EN_R_N")
	)
	(segment
		(start 359.51287 -214.57666)
		(end 359.1814 -214.90813)
		(width 0.15494)
		(layer "In15.Cu")
		(net "NIC6_CLK_EN_R_N")
	)
	(segment
		(start 300.4312 -187.241688)
		(end 300.802294 -186.870594)
		(width 0.15494)
		(layer "In15.Cu")
		(net "NIC6_CLK_EN_R_N")
	)
	(segment
		(start 343.0016 -188.86932)
		(end 343.204292 -188.666628)
		(width 0.15494)
		(layer "In15.Cu")
		(net "NIC6_CLK_EN_R_N")
	)
	(segment
		(start 358.82834 -214.90813)
		(end 358.54513 -215.19134)
		(width 0.15494)
		(layer "In15.Cu")
		(net "NIC6_CLK_EN_R_N")
	)
	(segment
		(start 359.499916 -209.479896)
		(end 359.151682 -209.82813)
		(width 0.15494)
		(layer "In15.Cu")
		(net "NIC6_CLK_EN_R_N")
	)
	(segment
		(start 240.616486 -185.997342)
		(end 245.301008 -185.997342)
		(width 0.15494)
		(layer "In15.Cu")
		(net "NIC6_CLK_EN_R_N")
	)
	(segment
		(start 358.54513 -217.95613)
		(end 359.029 -218.44)
		(width 0.15494)
		(layer "In15.Cu")
		(net "NIC6_CLK_EN_R_N")
	)
	(segment
		(start 253.080012 -185.632852)
		(end 260.060694 -185.632852)
		(width 0.15494)
		(layer "In15.Cu")
		(net "NIC6_CLK_EN_R_N")
	)
	(segment
		(start 147.8407 -197.906132)
		(end 148.109686 -197.256146)
		(width 0.15494)
		(layer "In15.Cu")
		(net "NIC6_CLK_EN_R_N")
	)
	(segment
		(start 359.1814 -214.90813)
		(end 358.82834 -214.90813)
		(width 0.15494)
		(layer "In15.Cu")
		(net "NIC6_CLK_EN_R_N")
	)
	(segment
		(start 261.041896 -184.65165)
		(end 283.370274 -184.65165)
		(width 0.15494)
		(layer "In15.Cu")
		(net "NIC6_CLK_EN_R_N")
	)
	(segment
		(start 333.16037 -188.86932)
		(end 343.0016 -188.86932)
		(width 0.15494)
		(layer "In15.Cu")
		(net "NIC6_CLK_EN_R_N")
	)
	(segment
		(start 355.60381 -198.916798)
		(end 359.499916 -202.812904)
		(width 0.15494)
		(layer "In15.Cu")
		(net "NIC6_CLK_EN_R_N")
	)
	(segment
		(start 142.64132 -201.0918)
		(end 144.655032 -201.0918)
		(width 0.15494)
		(layer "In15.Cu")
		(net "NIC6_CLK_EN_R_N")
	)
	(segment
		(start 285.960312 -187.241688)
		(end 300.4312 -187.241688)
		(width 0.15494)
		(layer "In15.Cu")
		(net "NIC6_CLK_EN_R_N")
	)
	(segment
		(start 358.54513 -215.19134)
		(end 358.54513 -217.95613)
		(width 0.15494)
		(layer "In15.Cu")
		(net "NIC6_CLK_EN_R_N")
	)
	(segment
		(start 359.1814 -213.84387)
		(end 359.51287 -214.17534)
		(width 0.15494)
		(layer "In15.Cu")
		(net "NIC6_CLK_EN_R_N")
	)
	(segment
		(start 358.54513 -210.11134)
		(end 358.54513 -213.56066)
		(width 0.15494)
		(layer "In15.Cu")
		(net "NIC6_CLK_EN_R_N")
	)
	(segment
		(start 226.030028 -184.04205)
		(end 226.466908 -184.47893)
		(width 0.15494)
		(layer "In15.Cu")
		(net "NIC6_CLK_EN_R_N")
	)
	(segment
		(start 213.096602 -184.04205)
		(end 226.030028 -184.04205)
		(width 0.15494)
		(layer "In15.Cu")
		(net "NIC6_CLK_EN_R_N")
	)
	(segment
		(start 358.82834 -213.84387)
		(end 359.1814 -213.84387)
		(width 0.15494)
		(layer "In15.Cu")
		(net "NIC6_CLK_EN_R_N")
	)
	(segment
		(start 355.60381 -192.011808)
		(end 355.60381 -198.916798)
		(width 0.15494)
		(layer "In15.Cu")
		(net "NIC6_CLK_EN_R_N")
	)
	(segment
		(start 359.151682 -209.82813)
		(end 358.82834 -209.82813)
		(width 0.15494)
		(layer "In15.Cu")
		(net "NIC6_CLK_EN_R_N")
	)
	(via
		(at 380.03099 -289.532314)
		(size 0.508)
		(drill 0.254)
		(layers "F.Cu" "B.Cu")
		(net "PCEPLL4_VDDA18_PEX3_R")
	)
	(segment
		(start 210.75015 -184.31256)
		(end 210.130136 -183.692546)
		(width 0.13208)
		(layer "F.Cu")
		(net "SEL_FLASH_PEX3_BUF")
	)
	(segment
		(start 210.75015 -184.702958)
		(end 210.75015 -184.31256)
		(width 0.13208)
		(layer "F.Cu")
		(net "SEL_FLASH_PEX3_BUF")
	)
	(segment
		(start 210.130136 -183.692546)
		(end 210.130136 -183.200548)
		(width 0.13208)
		(layer "F.Cu")
		(net "SEL_FLASH_PEX3_BUF")
	)
	(segment
		(start 210.130136 -183.200548)
		(end 210.130136 -182.013606)
		(width 0.13208)
		(layer "F.Cu")
		(net "SEL_FLASH_PEX3_BUF")
	)
	(via
		(at 210.130136 -183.200548)
		(size 0.762)
		(drill 0.381)
		(layers "F.Cu" "B.Cu")
		(net "SEL_FLASH_PEX3_BUF")
	)
	(segment
		(start 237.808262 -226.368864)
		(end 237.550198 -226.1108)
		(width 0.4572)
		(layer "F.Cu")
		(net "P1V8_PLL0_PEX3")
	)
	(segment
		(start 237.550198 -226.1108)
		(end 236.8042 -226.1108)
		(width 0.4572)
		(layer "F.Cu")
		(net "P1V8_PLL0_PEX3")
	)
	(via
		(at 360.857546 -243.446808)
		(size 0.508)
		(drill 0.254)
		(layers "F.Cu" "B.Cu")
		(net "P1V8_PLL0_PEX3")
	)
	(via
		(at 374.665748 -254.623062)
		(size 0.508)
		(drill 0.254)
		(layers "F.Cu" "B.Cu")
		(net "P1V8_PLL0_PEX3")
	)
	(via
		(at 459.146402 -245.53164)
		(size 0.508)
		(drill 0.254)
		(layers "F.Cu" "B.Cu")
		(net "P1V8_PLL0_PEX3")
	)
	(via
		(at 375.978674 -291.430456)
		(size 0.508)
		(drill 0.254)
		(layers "F.Cu" "B.Cu")
		(net "P1V8_PLL0_PEX3")
	)
	(via
		(at 375.978674 -288.230056)
		(size 0.508)
		(drill 0.254)
		(layers "F.Cu" "B.Cu")
		(net "P1V8_PLL0_PEX3")
	)
	(via
		(at 375.978674 -301.031656)
		(size 0.508)
		(drill 0.254)
		(layers "F.Cu" "B.Cu")
		(net "P1V8_PLL0_PEX3")
	)
	(via
		(at 378.936758 -261.474458)
		(size 0.508)
		(drill 0.254)
		(layers "F.Cu" "B.Cu")
		(net "P1V8_PLL0_PEX3")
	)
	(via
		(at 374.493536 -294.630856)
		(size 0.508)
		(drill 0.254)
		(layers "F.Cu" "B.Cu")
		(net "P1V8_PLL0_PEX3")
	)
	(via
		(at 375.978674 -281.829256)
		(size 0.508)
		(drill 0.254)
		(layers "F.Cu" "B.Cu")
		(net "P1V8_PLL0_PEX3")
	)
	(via
		(at 386.817616 -259.399024)
		(size 0.508)
		(drill 0.254)
		(layers "F.Cu" "B.Cu")
		(net "P1V8_PLL0_PEX3")
	)
	(via
		(at 374.493536 -301.031656)
		(size 0.508)
		(drill 0.254)
		(layers "F.Cu" "B.Cu")
		(net "P1V8_PLL0_PEX3")
	)
	(via
		(at 374.493536 -288.230056)
		(size 0.508)
		(drill 0.254)
		(layers "F.Cu" "B.Cu")
		(net "P1V8_PLL0_PEX3")
	)
	(via
		(at 375.978674 -285.029656)
		(size 0.508)
		(drill 0.254)
		(layers "F.Cu" "B.Cu")
		(net "P1V8_PLL0_PEX3")
	)
	(via
		(at 374.493536 -291.430456)
		(size 0.508)
		(drill 0.254)
		(layers "F.Cu" "B.Cu")
		(net "P1V8_PLL0_PEX3")
	)
	(via
		(at 377.45162 -261.474458)
		(size 0.508)
		(drill 0.254)
		(layers "F.Cu" "B.Cu")
		(net "P1V8_PLL0_PEX3")
	)
	(via
		(at 248.792492 -230.505)
		(size 0.508)
		(drill 0.254)
		(layers "F.Cu" "B.Cu")
		(net "P1V8_PLL0_PEX3")
	)
	(via
		(at 375.978674 -294.630856)
		(size 0.508)
		(drill 0.254)
		(layers "F.Cu" "B.Cu")
		(net "P1V8_PLL0_PEX3")
	)
	(via
		(at 458.587602 -246.19204)
		(size 0.508)
		(drill 0.254)
		(layers "F.Cu" "B.Cu")
		(net "P1V8_PLL0_PEX3")
	)
	(via
		(at 378.936758 -258.274058)
		(size 0.508)
		(drill 0.254)
		(layers "F.Cu" "B.Cu")
		(net "P1V8_PLL0_PEX3")
	)
	(via
		(at 377.45162 -258.274058)
		(size 0.508)
		(drill 0.254)
		(layers "F.Cu" "B.Cu")
		(net "P1V8_PLL0_PEX3")
	)
	(via
		(at 457.698602 -246.16664)
		(size 0.508)
		(drill 0.254)
		(layers "F.Cu" "B.Cu")
		(net "P1V8_PLL0_PEX3")
	)
	(via
		(at 377.765564 -254.519684)
		(size 0.508)
		(drill 0.254)
		(layers "F.Cu" "B.Cu")
		(net "P1V8_PLL0_PEX3")
	)
	(via
		(at 375.978674 -297.831256)
		(size 0.508)
		(drill 0.254)
		(layers "F.Cu" "B.Cu")
		(net "P1V8_PLL0_PEX3")
	)
	(via
		(at 378.51969 -255.223264)
		(size 0.508)
		(drill 0.254)
		(layers "F.Cu" "B.Cu")
		(net "P1V8_PLL0_PEX3")
	)
	(via
		(at 236.8042 -226.1108)
		(size 0.508)
		(drill 0.254)
		(layers "F.Cu" "B.Cu")
		(net "P1V8_PLL0_PEX3")
	)
	(via
		(at 374.493536 -281.829256)
		(size 0.508)
		(drill 0.254)
		(layers "F.Cu" "B.Cu")
		(net "P1V8_PLL0_PEX3")
	)
	(via
		(at 374.493536 -297.831256)
		(size 0.508)
		(drill 0.254)
		(layers "F.Cu" "B.Cu")
		(net "P1V8_PLL0_PEX3")
	)
	(via
		(at 387.80974 -260.37286)
		(size 0.508)
		(drill 0.254)
		(layers "F.Cu" "B.Cu")
		(net "P1V8_PLL0_PEX3")
	)
	(via
		(at 374.493536 -285.029656)
		(size 0.508)
		(drill 0.254)
		(layers "F.Cu" "B.Cu")
		(net "P1V8_PLL0_PEX3")
	)
	(via
		(at 459.146402 -244.82044)
		(size 0.508)
		(drill 0.254)
		(layers "F.Cu" "B.Cu")
		(net "P1V8_PLL0_PEX3")
	)
	(via
		(at 374.665748 -256.1082)
		(size 0.508)
		(drill 0.254)
		(layers "F.Cu" "B.Cu")
		(net "P1V8_PLL0_PEX3")
	)
	(segment
		(start 313.06262 -235.721144)
		(end 313.06262 -225.934524)
		(width 0.508)
		(layer "B.Cu")
		(net "P1V8_PLL0_PEX3")
	)
	(segment
		(start 336.154776 -247.515126)
		(end 335.841086 -247.201436)
		(width 0.508)
		(layer "B.Cu")
		(net "P1V8_PLL0_PEX3")
	)
	(segment
		(start 295.94302 -222.109792)
		(end 285.878524 -232.174288)
		(width 0.508)
		(layer "B.Cu")
		(net "P1V8_PLL0_PEX3")
	)
	(segment
		(start 329.090782 -247.201436)
		(end 326.229472 -244.340126)
		(width 0.508)
		(layer "B.Cu")
		(net "P1V8_PLL0_PEX3")
	)
	(segment
		(start 360.857546 -243.446808)
		(end 358.172004 -246.13235)
		(width 0.508)
		(layer "B.Cu")
		(net "P1V8_PLL0_PEX3")
	)
	(segment
		(start 326.229472 -244.340126)
		(end 321.681602 -244.340126)
		(width 0.508)
		(layer "B.Cu")
		(net "P1V8_PLL0_PEX3")
	)
	(segment
		(start 375.978674 -301.031656)
		(end 374.493536 -301.031656)
		(width 0.508)
		(layer "B.Cu")
		(net "P1V8_PLL0_PEX3")
	)
	(segment
		(start 358.172004 -246.13235)
		(end 342.466422 -246.13235)
		(width 0.508)
		(layer "B.Cu")
		(net "P1V8_PLL0_PEX3")
	)
	(segment
		(start 335.841086 -247.201436)
		(end 329.090782 -247.201436)
		(width 0.508)
		(layer "B.Cu")
		(net "P1V8_PLL0_PEX3")
	)
	(segment
		(start 252.939296 -234.661456)
		(end 250.698762 -234.661456)
		(width 0.508)
		(layer "B.Cu")
		(net "P1V8_PLL0_PEX3")
	)
	(segment
		(start 296.972736 -219.211398)
		(end 295.94302 -220.241114)
		(width 0.508)
		(layer "B.Cu")
		(net "P1V8_PLL0_PEX3")
	)
	(segment
		(start 258.527042 -232.348024)
		(end 258.52374 -232.348024)
		(width 0.508)
		(layer "B.Cu")
		(net "P1V8_PLL0_PEX3")
	)
	(segment
		(start 295.94302 -220.241114)
		(end 295.94302 -222.109792)
		(width 0.508)
		(layer "B.Cu")
		(net "P1V8_PLL0_PEX3")
	)
	(segment
		(start 313.06262 -225.934524)
		(end 306.339494 -219.211398)
		(width 0.508)
		(layer "B.Cu")
		(net "P1V8_PLL0_PEX3")
	)
	(segment
		(start 258.52374 -232.348024)
		(end 252.939296 -234.661456)
		(width 0.508)
		(layer "B.Cu")
		(net "P1V8_PLL0_PEX3")
	)
	(segment
		(start 341.083646 -247.515126)
		(end 336.154776 -247.515126)
		(width 0.508)
		(layer "B.Cu")
		(net "P1V8_PLL0_PEX3")
	)
	(segment
		(start 250.698762 -234.661456)
		(end 248.792492 -232.755186)
		(width 0.508)
		(layer "B.Cu")
		(net "P1V8_PLL0_PEX3")
	)
	(segment
		(start 342.466422 -246.13235)
		(end 341.083646 -247.515126)
		(width 0.508)
		(layer "B.Cu")
		(net "P1V8_PLL0_PEX3")
	)
	(segment
		(start 285.878524 -232.174288)
		(end 259.400548 -232.174288)
		(width 0.508)
		(layer "B.Cu")
		(net "P1V8_PLL0_PEX3")
	)
	(segment
		(start 321.681602 -244.340126)
		(end 313.06262 -235.721144)
		(width 0.508)
		(layer "B.Cu")
		(net "P1V8_PLL0_PEX3")
	)
	(segment
		(start 306.339494 -219.211398)
		(end 296.972736 -219.211398)
		(width 0.508)
		(layer "B.Cu")
		(net "P1V8_PLL0_PEX3")
	)
	(segment
		(start 259.400548 -232.174288)
		(end 258.527042 -232.348024)
		(width 0.508)
		(layer "B.Cu")
		(net "P1V8_PLL0_PEX3")
	)
	(segment
		(start 248.792492 -232.755186)
		(end 248.792492 -230.505)
		(width 0.508)
		(layer "B.Cu")
		(net "P1V8_PLL0_PEX3")
	)
	(segment
		(start 365.037878 -249.898916)
		(end 365.037878 -248.99112)
		(width 0.508)
		(layer "In7.Cu")
		(net "P1V8_PLL0_PEX3")
	)
	(segment
		(start 371.258084 -259.336032)
		(end 370.618512 -258.69646)
		(width 0.508)
		(layer "In7.Cu")
		(net "P1V8_PLL0_PEX3")
	)
	(segment
		(start 369.165378 -257.056382)
		(end 369.165378 -254.026416)
		(width 0.508)
		(layer "In7.Cu")
		(net "P1V8_PLL0_PEX3")
	)
	(segment
		(start 373.079518 -259.704332)
		(end 372.711218 -259.336032)
		(width 0.508)
		(layer "In7.Cu")
		(net "P1V8_PLL0_PEX3")
	)
	(segment
		(start 370.618512 -258.69646)
		(end 370.618512 -258.509516)
		(width 0.508)
		(layer "In7.Cu")
		(net "P1V8_PLL0_PEX3")
	)
	(segment
		(start 365.037878 -248.99112)
		(end 360.857546 -244.810788)
		(width 0.508)
		(layer "In7.Cu")
		(net "P1V8_PLL0_PEX3")
	)
	(segment
		(start 369.165378 -254.026416)
		(end 365.037878 -249.898916)
		(width 0.508)
		(layer "In7.Cu")
		(net "P1V8_PLL0_PEX3")
	)
	(segment
		(start 377.45162 -258.274058)
		(end 376.021346 -259.704332)
		(width 0.508)
		(layer "In7.Cu")
		(net "P1V8_PLL0_PEX3")
	)
	(segment
		(start 370.618512 -258.509516)
		(end 369.165378 -257.056382)
		(width 0.508)
		(layer "In7.Cu")
		(net "P1V8_PLL0_PEX3")
	)
	(segment
		(start 376.021346 -259.704332)
		(end 373.079518 -259.704332)
		(width 0.508)
		(layer "In7.Cu")
		(net "P1V8_PLL0_PEX3")
	)
	(segment
		(start 372.711218 -259.336032)
		(end 371.258084 -259.336032)
		(width 0.508)
		(layer "In7.Cu")
		(net "P1V8_PLL0_PEX3")
	)
	(segment
		(start 360.857546 -244.810788)
		(end 360.857546 -243.446808)
		(width 0.508)
		(layer "In7.Cu")
		(net "P1V8_PLL0_PEX3")
	)
	(segment
		(start 248.792492 -230.233982)
		(end 245.794022 -227.235512)
		(width 0.508)
		(layer "In13.Cu")
		(net "P1V8_PLL0_PEX3")
	)
	(segment
		(start 245.794022 -227.235512)
		(end 237.598712 -227.235512)
		(width 0.508)
		(layer "In13.Cu")
		(net "P1V8_PLL0_PEX3")
	)
	(segment
		(start 248.792492 -230.505)
		(end 248.792492 -230.233982)
		(width 0.508)
		(layer "In13.Cu")
		(net "P1V8_PLL0_PEX3")
	)
	(segment
		(start 237.109 -226.7458)
		(end 237.109 -226.4156)
		(width 0.508)
		(layer "In13.Cu")
		(net "P1V8_PLL0_PEX3")
	)
	(segment
		(start 237.109 -226.4156)
		(end 236.8042 -226.1108)
		(width 0.508)
		(layer "In13.Cu")
		(net "P1V8_PLL0_PEX3")
	)
	(segment
		(start 237.598712 -227.235512)
		(end 237.109 -226.7458)
		(width 0.508)
		(layer "In13.Cu")
		(net "P1V8_PLL0_PEX3")
	)
	(segment
		(start 392.59002 -244.492272)
		(end 415.778442 -244.492272)
		(width 0.508)
		(layer "In15.Cu")
		(net "P1V8_PLL0_PEX3")
	)
	(segment
		(start 389.49376 -241.396012)
		(end 392.59002 -244.492272)
		(width 0.508)
		(layer "In15.Cu")
		(net "P1V8_PLL0_PEX3")
	)
	(segment
		(start 415.778442 -244.492272)
		(end 416.552634 -243.71808)
		(width 0.508)
		(layer "In15.Cu")
		(net "P1V8_PLL0_PEX3")
	)
	(segment
		(start 364.038642 -243.446808)
		(end 364.503716 -243.911882)
		(width 0.508)
		(layer "In15.Cu")
		(net "P1V8_PLL0_PEX3")
	)
	(segment
		(start 416.552634 -243.71808)
		(end 441.138056 -243.71808)
		(width 0.508)
		(layer "In15.Cu")
		(net "P1V8_PLL0_PEX3")
	)
	(segment
		(start 459.824582 -242.298728)
		(end 459.824582 -244.522752)
		(width 0.508)
		(layer "In15.Cu")
		(net "P1V8_PLL0_PEX3")
	)
	(segment
		(start 367.454688 -243.911882)
		(end 370.727986 -240.638584)
		(width 0.508)
		(layer "In15.Cu")
		(net "P1V8_PLL0_PEX3")
	)
	(segment
		(start 444.929006 -239.92713)
		(end 457.452984 -239.92713)
		(width 0.508)
		(layer "In15.Cu")
		(net "P1V8_PLL0_PEX3")
	)
	(segment
		(start 383.877566 -242.432586)
		(end 386.99694 -242.432586)
		(width 0.508)
		(layer "In15.Cu")
		(net "P1V8_PLL0_PEX3")
	)
	(segment
		(start 370.727986 -240.638584)
		(end 372.306342 -240.638584)
		(width 0.508)
		(layer "In15.Cu")
		(net "P1V8_PLL0_PEX3")
	)
	(segment
		(start 364.503716 -243.911882)
		(end 367.454688 -243.911882)
		(width 0.508)
		(layer "In15.Cu")
		(net "P1V8_PLL0_PEX3")
	)
	(segment
		(start 376.834654 -242.971574)
		(end 377.236228 -243.373148)
		(width 0.508)
		(layer "In15.Cu")
		(net "P1V8_PLL0_PEX3")
	)
	(segment
		(start 377.236228 -243.373148)
		(end 382.937004 -243.373148)
		(width 0.508)
		(layer "In15.Cu")
		(net "P1V8_PLL0_PEX3")
	)
	(segment
		(start 441.138056 -243.71808)
		(end 444.929006 -239.92713)
		(width 0.508)
		(layer "In15.Cu")
		(net "P1V8_PLL0_PEX3")
	)
	(segment
		(start 459.526894 -244.82044)
		(end 459.146402 -244.82044)
		(width 0.508)
		(layer "In15.Cu")
		(net "P1V8_PLL0_PEX3")
	)
	(segment
		(start 372.306342 -240.638584)
		(end 374.639332 -242.971574)
		(width 0.508)
		(layer "In15.Cu")
		(net "P1V8_PLL0_PEX3")
	)
	(segment
		(start 388.033514 -241.396012)
		(end 389.49376 -241.396012)
		(width 0.508)
		(layer "In15.Cu")
		(net "P1V8_PLL0_PEX3")
	)
	(segment
		(start 360.857546 -243.446808)
		(end 364.038642 -243.446808)
		(width 0.508)
		(layer "In15.Cu")
		(net "P1V8_PLL0_PEX3")
	)
	(segment
		(start 457.452984 -239.92713)
		(end 459.824582 -242.298728)
		(width 0.508)
		(layer "In15.Cu")
		(net "P1V8_PLL0_PEX3")
	)
	(segment
		(start 386.99694 -242.432586)
		(end 388.033514 -241.396012)
		(width 0.508)
		(layer "In15.Cu")
		(net "P1V8_PLL0_PEX3")
	)
	(segment
		(start 374.639332 -242.971574)
		(end 376.834654 -242.971574)
		(width 0.508)
		(layer "In15.Cu")
		(net "P1V8_PLL0_PEX3")
	)
	(segment
		(start 459.824582 -244.522752)
		(end 459.526894 -244.82044)
		(width 0.508)
		(layer "In15.Cu")
		(net "P1V8_PLL0_PEX3")
	)
	(segment
		(start 382.937004 -243.373148)
		(end 383.877566 -242.432586)
		(width 0.508)
		(layer "In15.Cu")
		(net "P1V8_PLL0_PEX3")
	)
	(segment
		(start 398.493488 -173.229524)
		(end 398.493488 -174.490634)
		(width 0.13208)
		(layer "F.Cu")
		(net "RST_NIC6_PERST_R_N")
	)
	(segment
		(start 358.41305 -219.456)
		(end 359.029 -219.456)
		(width 0.13208)
		(layer "F.Cu")
		(net "RST_NIC6_PERST_R_N")
	)
	(via
		(at 359.029 -219.456)
		(size 0.508)
		(drill 0.254)
		(layers "F.Cu" "B.Cu")
		(net "RST_NIC6_PERST_R_N")
	)
	(via
		(at 375.867676 -180.184552)
		(size 0.508)
		(drill 0.254)
		(layers "F.Cu" "B.Cu")
		(net "RST_NIC6_PERST_R_N")
	)
	(via
		(at 398.493488 -174.490634)
		(size 0.508)
		(drill 0.254)
		(layers "F.Cu" "B.Cu")
		(net "RST_NIC6_PERST_R_N")
	)
	(segment
		(start 378.301758 -209.050128)
		(end 378.301758 -208.001616)
		(width 0.15494)
		(layer "In7.Cu")
		(net "RST_NIC6_PERST_R_N")
	)
	(segment
		(start 359.029 -219.456)
		(end 360.60126 -217.88374)
		(width 0.15494)
		(layer "In7.Cu")
		(net "RST_NIC6_PERST_R_N")
	)
	(segment
		(start 378.33808 -203.786232)
		(end 378.170948 -203.6191)
		(width 0.15494)
		(layer "In7.Cu")
		(net "RST_NIC6_PERST_R_N")
	)
	(segment
		(start 377.572778 -200.407778)
		(end 377.572778 -189.68085)
		(width 0.15494)
		(layer "In7.Cu")
		(net "RST_NIC6_PERST_R_N")
	)
	(segment
		(start 377.014232 -189.122304)
		(end 377.014232 -189.093602)
		(width 0.15494)
		(layer "In7.Cu")
		(net "RST_NIC6_PERST_R_N")
	)
	(segment
		(start 360.60126 -217.88374)
		(end 369.052602 -217.88374)
		(width 0.15494)
		(layer "In7.Cu")
		(net "RST_NIC6_PERST_R_N")
	)
	(segment
		(start 375.867676 -181.59857)
		(end 375.867676 -180.184552)
		(width 0.15494)
		(layer "In7.Cu")
		(net "RST_NIC6_PERST_R_N")
	)
	(segment
		(start 378.53874 -210.171792)
		(end 378.53874 -209.28711)
		(width 0.15494)
		(layer "In7.Cu")
		(net "RST_NIC6_PERST_R_N")
	)
	(segment
		(start 376.88266 -182.613554)
		(end 375.867676 -181.59857)
		(width 0.15494)
		(layer "In7.Cu")
		(net "RST_NIC6_PERST_R_N")
	)
	(segment
		(start 377.014232 -189.093602)
		(end 376.88266 -188.96203)
		(width 0.15494)
		(layer "In7.Cu")
		(net "RST_NIC6_PERST_R_N")
	)
	(segment
		(start 378.301758 -208.001616)
		(end 378.3076 -207.995774)
		(width 0.15494)
		(layer "In7.Cu")
		(net "RST_NIC6_PERST_R_N")
	)
	(segment
		(start 378.3076 -207.446118)
		(end 378.7902 -206.963518)
		(width 0.15494)
		(layer "In7.Cu")
		(net "RST_NIC6_PERST_R_N")
	)
	(segment
		(start 376.88266 -188.96203)
		(end 376.88266 -182.613554)
		(width 0.15494)
		(layer "In7.Cu")
		(net "RST_NIC6_PERST_R_N")
	)
	(segment
		(start 376.9868 -210.99272)
		(end 377.717812 -210.99272)
		(width 0.15494)
		(layer "In7.Cu")
		(net "RST_NIC6_PERST_R_N")
	)
	(segment
		(start 378.635768 -204.08392)
		(end 378.62129 -204.08392)
		(width 0.15494)
		(layer "In7.Cu")
		(net "RST_NIC6_PERST_R_N")
	)
	(segment
		(start 378.53874 -209.28711)
		(end 378.301758 -209.050128)
		(width 0.15494)
		(layer "In7.Cu")
		(net "RST_NIC6_PERST_R_N")
	)
	(segment
		(start 377.717812 -210.99272)
		(end 378.53874 -210.171792)
		(width 0.15494)
		(layer "In7.Cu")
		(net "RST_NIC6_PERST_R_N")
	)
	(segment
		(start 378.33808 -203.80071)
		(end 378.33808 -203.786232)
		(width 0.15494)
		(layer "In7.Cu")
		(net "RST_NIC6_PERST_R_N")
	)
	(segment
		(start 378.170948 -203.6191)
		(end 378.170948 -201.005948)
		(width 0.15494)
		(layer "In7.Cu")
		(net "RST_NIC6_PERST_R_N")
	)
	(segment
		(start 377.572778 -189.68085)
		(end 377.014232 -189.122304)
		(width 0.15494)
		(layer "In7.Cu")
		(net "RST_NIC6_PERST_R_N")
	)
	(segment
		(start 376.01652 -211.963)
		(end 376.9868 -210.99272)
		(width 0.15494)
		(layer "In7.Cu")
		(net "RST_NIC6_PERST_R_N")
	)
	(segment
		(start 378.3076 -207.995774)
		(end 378.3076 -207.446118)
		(width 0.15494)
		(layer "In7.Cu")
		(net "RST_NIC6_PERST_R_N")
	)
	(segment
		(start 378.62129 -204.08392)
		(end 378.33808 -203.80071)
		(width 0.15494)
		(layer "In7.Cu")
		(net "RST_NIC6_PERST_R_N")
	)
	(segment
		(start 378.7902 -204.238352)
		(end 378.635768 -204.08392)
		(width 0.15494)
		(layer "In7.Cu")
		(net "RST_NIC6_PERST_R_N")
	)
	(segment
		(start 378.7902 -206.963518)
		(end 378.7902 -204.238352)
		(width 0.15494)
		(layer "In7.Cu")
		(net "RST_NIC6_PERST_R_N")
	)
	(segment
		(start 369.093242 -217.8431)
		(end 369.121944 -217.8431)
		(width 0.15494)
		(layer "In7.Cu")
		(net "RST_NIC6_PERST_R_N")
	)
	(segment
		(start 378.170948 -201.005948)
		(end 377.572778 -200.407778)
		(width 0.15494)
		(layer "In7.Cu")
		(net "RST_NIC6_PERST_R_N")
	)
	(segment
		(start 375.002044 -211.963)
		(end 376.01652 -211.963)
		(width 0.15494)
		(layer "In7.Cu")
		(net "RST_NIC6_PERST_R_N")
	)
	(segment
		(start 369.052602 -217.88374)
		(end 369.093242 -217.8431)
		(width 0.15494)
		(layer "In7.Cu")
		(net "RST_NIC6_PERST_R_N")
	)
	(segment
		(start 369.121944 -217.8431)
		(end 375.002044 -211.963)
		(width 0.15494)
		(layer "In7.Cu")
		(net "RST_NIC6_PERST_R_N")
	)
	(segment
		(start 379.808232 -174.490634)
		(end 376.57659 -177.722276)
		(width 0.15494)
		(layer "In15.Cu")
		(net "RST_NIC6_PERST_R_N")
	)
	(segment
		(start 376.57659 -179.475638)
		(end 375.867676 -180.184552)
		(width 0.15494)
		(layer "In15.Cu")
		(net "RST_NIC6_PERST_R_N")
	)
	(segment
		(start 398.493488 -174.490634)
		(end 379.808232 -174.490634)
		(width 0.15494)
		(layer "In15.Cu")
		(net "RST_NIC6_PERST_R_N")
	)
	(segment
		(start 376.57659 -177.722276)
		(end 376.57659 -179.475638)
		(width 0.15494)
		(layer "In15.Cu")
		(net "RST_NIC6_PERST_R_N")
	)
	(segment
		(start 414.637474 -158.35503)
		(end 416.95751 -158.35503)
		(width 0.13208)
		(layer "F.Cu")
		(net "NIC7_PWRBRK_R_N")
	)
	(segment
		(start 412.124652 -157.680152)
		(end 413.35452 -157.680152)
		(width 0.13208)
		(layer "F.Cu")
		(net "NIC7_PWRBRK_R_N")
	)
	(segment
		(start 413.35452 -157.680152)
		(end 413.962596 -157.680152)
		(width 0.13208)
		(layer "F.Cu")
		(net "NIC7_PWRBRK_R_N")
	)
	(segment
		(start 413.962596 -157.680152)
		(end 414.637474 -158.35503)
		(width 0.13208)
		(layer "F.Cu")
		(net "NIC7_PWRBRK_R_N")
	)
	(via
		(at 413.35452 -157.680152)
		(size 0.762)
		(drill 0.381)
		(layers "F.Cu" "B.Cu")
		(net "NIC7_PWRBRK_R_N")
	)
	(segment
		(start 212.050122 -184.702958)
		(end 212.050122 -184.055258)
		(width 0.13208)
		(layer "F.Cu")
		(net "SEL_FLASH_PEX2_BUF")
	)
	(segment
		(start 212.416136 -183.203342)
		(end 212.416136 -182.380128)
		(width 0.13208)
		(layer "F.Cu")
		(net "SEL_FLASH_PEX2_BUF")
	)
	(segment
		(start 212.787738 -182.008526)
		(end 213.17966 -182.008526)
		(width 0.13208)
		(layer "F.Cu")
		(net "SEL_FLASH_PEX2_BUF")
	)
	(segment
		(start 212.416136 -183.689244)
		(end 212.416136 -183.203342)
		(width 0.13208)
		(layer "F.Cu")
		(net "SEL_FLASH_PEX2_BUF")
	)
	(segment
		(start 212.416136 -182.380128)
		(end 212.787738 -182.008526)
		(width 0.13208)
		(layer "F.Cu")
		(net "SEL_FLASH_PEX2_BUF")
	)
	(segment
		(start 212.050122 -184.055258)
		(end 212.416136 -183.689244)
		(width 0.13208)
		(layer "F.Cu")
		(net "SEL_FLASH_PEX2_BUF")
	)
	(via
		(at 212.416136 -183.203342)
		(size 0.762)
		(drill 0.381)
		(layers "F.Cu" "B.Cu")
		(net "SEL_FLASH_PEX2_BUF")
	)
	(via
		(at 380.03099 -279.931114)
		(size 0.508)
		(drill 0.254)
		(layers "F.Cu" "B.Cu")
		(net "SYSPLL_VDDA18_PEX3_R")
	)
	(segment
		(start 369.503452 -196.212968)
		(end 370.024406 -196.733922)
		(width 0.13208)
		(layer "F.Cu")
		(net "RST_PEX_SSD5_PERST_N")
	)
	(segment
		(start 365.90605 -194.691)
		(end 367.284 -194.691)
		(width 0.13208)
		(layer "F.Cu")
		(net "RST_PEX_SSD5_PERST_N")
	)
	(segment
		(start 368.805968 -196.212968)
		(end 369.503452 -196.212968)
		(width 0.13208)
		(layer "F.Cu")
		(net "RST_PEX_SSD5_PERST_N")
	)
	(segment
		(start 367.284 -194.691)
		(end 368.805968 -196.212968)
		(width 0.13208)
		(layer "F.Cu")
		(net "RST_PEX_SSD5_PERST_N")
	)
	(segment
		(start 370.024406 -196.733922)
		(end 370.581936 -196.733922)
		(width 0.13208)
		(layer "F.Cu")
		(net "RST_PEX_SSD5_PERST_N")
	)
	(via
		(at 369.503452 -196.212968)
		(size 0.508)
		(drill 0.254)
		(layers "F.Cu" "B.Cu")
		(net "RST_PEX_SSD5_PERST_N")
	)
	(segment
		(start 214.81415 -184.702958)
		(end 214.81415 -184.31256)
		(width 0.13208)
		(layer "F.Cu")
		(net "SEL_FLASH_PEX1_BUF")
	)
	(segment
		(start 214.194136 -183.692546)
		(end 214.194136 -183.200548)
		(width 0.13208)
		(layer "F.Cu")
		(net "SEL_FLASH_PEX1_BUF")
	)
	(segment
		(start 214.194136 -183.200548)
		(end 214.194136 -182.013606)
		(width 0.13208)
		(layer "F.Cu")
		(net "SEL_FLASH_PEX1_BUF")
	)
	(segment
		(start 214.81415 -184.31256)
		(end 214.194136 -183.692546)
		(width 0.13208)
		(layer "F.Cu")
		(net "SEL_FLASH_PEX1_BUF")
	)
	(via
		(at 214.194136 -183.200548)
		(size 0.762)
		(drill 0.381)
		(layers "F.Cu" "B.Cu")
		(net "SEL_FLASH_PEX1_BUF")
	)
	(via
		(at 380.03099 -299.133514)
		(size 0.508)
		(drill 0.254)
		(layers "F.Cu" "B.Cu")
		(net "PCEPLL1_VDDA18_PEX3_R")
	)
	(segment
		(start 329.87488 -203.901548)
		(end 329.87488 -202.93965)
		(width 0.13208)
		(layer "F.Cu")
		(net "PU_CLK_25M_FPGA_EN")
	)
	(segment
		(start 329.87488 -202.93965)
		(end 329.854814 -202.919584)
		(width 0.13208)
		(layer "F.Cu")
		(net "PU_CLK_25M_FPGA_EN")
	)
	(segment
		(start 329.854814 -202.919584)
		(end 329.854814 -202.265534)
		(width 0.13208)
		(layer "F.Cu")
		(net "PU_CLK_25M_FPGA_EN")
	)
	(via
		(at 329.87488 -202.93965)
		(size 0.508)
		(drill 0.254)
		(layers "F.Cu" "B.Cu")
		(net "PU_CLK_25M_FPGA_EN")
	)
	(segment
		(start 216.480136 -183.689244)
		(end 216.480136 -183.203342)
		(width 0.13208)
		(layer "F.Cu")
		(net "SEL_FLASH_PEX0_BUF")
	)
	(segment
		(start 216.114122 -184.702958)
		(end 216.114122 -184.055258)
		(width 0.13208)
		(layer "F.Cu")
		(net "SEL_FLASH_PEX0_BUF")
	)
	(segment
		(start 216.480136 -183.203342)
		(end 216.480136 -182.013606)
		(width 0.13208)
		(layer "F.Cu")
		(net "SEL_FLASH_PEX0_BUF")
	)
	(segment
		(start 216.114122 -184.055258)
		(end 216.480136 -183.689244)
		(width 0.13208)
		(layer "F.Cu")
		(net "SEL_FLASH_PEX0_BUF")
	)
	(via
		(at 216.480136 -183.203342)
		(size 0.762)
		(drill 0.381)
		(layers "F.Cu" "B.Cu")
		(net "SEL_FLASH_PEX0_BUF")
	)
	(via
		(at 376.56389 -260.160516)
		(size 0.508)
		(drill 0.254)
		(layers "F.Cu" "B.Cu")
		(net "P1V8_VDDA_PEX3_R")
	)
	(segment
		(start 369.509548 -196.861684)
		(end 370.031772 -197.383908)
		(width 0.13208)
		(layer "F.Cu")
		(net "SSD5_PEX_PWR_EN")
	)
	(segment
		(start 367.284 -195.707)
		(end 367.9825 -196.4055)
		(width 0.13208)
		(layer "F.Cu")
		(net "SSD5_PEX_PWR_EN")
	)
	(segment
		(start 368.1095 -196.4055)
		(end 368.565684 -196.861684)
		(width 0.13208)
		(layer "F.Cu")
		(net "SSD5_PEX_PWR_EN")
	)
	(segment
		(start 367.9825 -196.4055)
		(end 368.1095 -196.4055)
		(width 0.13208)
		(layer "F.Cu")
		(net "SSD5_PEX_PWR_EN")
	)
	(segment
		(start 365.90605 -195.707)
		(end 367.284 -195.707)
		(width 0.13208)
		(layer "F.Cu")
		(net "SSD5_PEX_PWR_EN")
	)
	(segment
		(start 368.565684 -196.861684)
		(end 369.509548 -196.861684)
		(width 0.13208)
		(layer "F.Cu")
		(net "SSD5_PEX_PWR_EN")
	)
	(segment
		(start 370.031772 -197.383908)
		(end 370.581936 -197.383908)
		(width 0.13208)
		(layer "F.Cu")
		(net "SSD5_PEX_PWR_EN")
	)
	(via
		(at 367.284 -195.707)
		(size 0.508)
		(drill 0.254)
		(layers "F.Cu" "B.Cu")
		(net "SSD5_PEX_PWR_EN")
	)
	(via
		(at 380.03099 -295.933114)
		(size 0.508)
		(drill 0.254)
		(layers "F.Cu" "B.Cu")
		(net "PCEPLL0_VDDA18_PEX3_R")
	)
	(via
		(at 380.03099 -283.131514)
		(size 0.508)
		(drill 0.254)
		(layers "F.Cu" "B.Cu")
		(net "PCEPLL7_VDDA18_PEX3_R")
	)
	(segment
		(start 209.165698 -304.436526)
		(end 209.166206 -304.437034)
		(width 0.13208)
		(layer "F.Cu")
		(net "PEX1_EXT_GPIO_LATCH_N")
	)
	(segment
		(start 209.166206 -304.437034)
		(end 209.166206 -305.046126)
		(width 0.13208)
		(layer "F.Cu")
		(net "PEX1_EXT_GPIO_LATCH_N")
	)
	(segment
		(start 187.624974 -308.724808)
		(end 187.149994 -309.199788)
		(width 0.13208)
		(layer "F.Cu")
		(net "PEX1_EXT_GPIO_LATCH_N")
	)
	(segment
		(start 209.166206 -305.046126)
		(end 209.166206 -305.674522)
		(width 0.13208)
		(layer "F.Cu")
		(net "PEX1_EXT_GPIO_LATCH_N")
	)
	(via
		(at 187.624974 -308.724808)
		(size 0.4064)
		(drill 0.2032)
		(layers "F.Cu" "B.Cu")
		(net "PEX1_EXT_GPIO_LATCH_N")
	)
	(via
		(at 209.166206 -305.046126)
		(size 0.508)
		(drill 0.254)
		(layers "F.Cu" "B.Cu")
		(net "PEX1_EXT_GPIO_LATCH_N")
	)
	(via
		(at 207.336136 -304.197004)
		(size 0.6604)
		(drill 0.3302)
		(layers "F.Cu" "B.Cu")
		(net "PEX1_EXT_GPIO_LATCH_N")
	)
	(segment
		(start 189.5856 -308.7116)
		(end 202.20432 -308.7116)
		(width 0.13208)
		(layer "B.Cu")
		(net "PEX1_EXT_GPIO_LATCH_N")
	)
	(segment
		(start 209.166206 -304.696368)
		(end 209.166206 -305.046126)
		(width 0.13208)
		(layer "B.Cu")
		(net "PEX1_EXT_GPIO_LATCH_N")
	)
	(segment
		(start 188.099954 -309.199788)
		(end 189.097412 -309.199788)
		(width 0.13208)
		(layer "B.Cu")
		(net "PEX1_EXT_GPIO_LATCH_N")
	)
	(segment
		(start 205.6384 -305.27752)
		(end 205.6384 -304.626264)
		(width 0.13208)
		(layer "B.Cu")
		(net "PEX1_EXT_GPIO_LATCH_N")
	)
	(segment
		(start 187.624974 -308.724808)
		(end 188.099954 -309.199788)
		(width 0.13208)
		(layer "B.Cu")
		(net "PEX1_EXT_GPIO_LATCH_N")
	)
	(segment
		(start 189.097412 -309.199788)
		(end 189.5856 -308.7116)
		(width 0.13208)
		(layer "B.Cu")
		(net "PEX1_EXT_GPIO_LATCH_N")
	)
	(segment
		(start 206.06766 -304.197004)
		(end 207.336136 -304.197004)
		(width 0.13208)
		(layer "B.Cu")
		(net "PEX1_EXT_GPIO_LATCH_N")
	)
	(segment
		(start 205.6384 -304.626264)
		(end 206.06766 -304.197004)
		(width 0.13208)
		(layer "B.Cu")
		(net "PEX1_EXT_GPIO_LATCH_N")
	)
	(segment
		(start 202.20432 -308.7116)
		(end 205.6384 -305.27752)
		(width 0.13208)
		(layer "B.Cu")
		(net "PEX1_EXT_GPIO_LATCH_N")
	)
	(segment
		(start 207.336136 -304.197004)
		(end 208.666842 -304.197004)
		(width 0.13208)
		(layer "B.Cu")
		(net "PEX1_EXT_GPIO_LATCH_N")
	)
	(segment
		(start 208.666842 -304.197004)
		(end 209.166206 -304.696368)
		(width 0.13208)
		(layer "B.Cu")
		(net "PEX1_EXT_GPIO_LATCH_N")
	)
	(via
		(at 382.989074 -259.576316)
		(size 0.508)
		(drill 0.254)
		(layers "F.Cu" "B.Cu")
		(net "PCEPLL3_VDDA18_PEX3_R")
	)
	(segment
		(start 50.64252 -97.045018)
		(end 51.976782 -97.045018)
		(width 0.13208)
		(layer "F.Cu")
		(net "NIC0_PWRBRK_R_N")
	)
	(segment
		(start 51.976782 -97.045018)
		(end 51.98745 -97.055686)
		(width 0.13208)
		(layer "F.Cu")
		(net "NIC0_PWRBRK_R_N")
	)
	(segment
		(start 62.509908 -166.070534)
		(end 62.509908 -166.705534)
		(width 0.13208)
		(layer "F.Cu")
		(net "NIC0_PWRBRK_R_N")
	)
	(via
		(at 51.98745 -97.055686)
		(size 0.508)
		(drill 0.254)
		(layers "F.Cu" "B.Cu")
		(net "NIC0_PWRBRK_R_N")
	)
	(via
		(at 62.509908 -166.705534)
		(size 0.508)
		(drill 0.254)
		(layers "F.Cu" "B.Cu")
		(net "NIC0_PWRBRK_R_N")
	)
	(segment
		(start 57.3024 -132.2578)
		(end 57.3024 -117.390672)
		(width 0.15494)
		(layer "In9.Cu")
		(net "NIC0_PWRBRK_R_N")
	)
	(segment
		(start 51.10226 -113.509806)
		(end 51.10226 -98.502978)
		(width 0.15494)
		(layer "In9.Cu")
		(net "NIC0_PWRBRK_R_N")
	)
	(segment
		(start 56.1086 -133.4516)
		(end 57.3024 -132.2578)
		(width 0.15494)
		(layer "In9.Cu")
		(net "NIC0_PWRBRK_R_N")
	)
	(segment
		(start 51.638454 -114.046)
		(end 51.10226 -113.509806)
		(width 0.15494)
		(layer "In9.Cu")
		(net "NIC0_PWRBRK_R_N")
	)
	(segment
		(start 57.3024 -117.390672)
		(end 53.957728 -114.046)
		(width 0.15494)
		(layer "In9.Cu")
		(net "NIC0_PWRBRK_R_N")
	)
	(segment
		(start 51.10226 -98.502978)
		(end 51.98745 -97.617788)
		(width 0.15494)
		(layer "In9.Cu")
		(net "NIC0_PWRBRK_R_N")
	)
	(segment
		(start 57.31256 -145.882106)
		(end 56.1086 -144.678146)
		(width 0.15494)
		(layer "In9.Cu")
		(net "NIC0_PWRBRK_R_N")
	)
	(segment
		(start 62.509908 -166.705534)
		(end 57.31256 -161.508186)
		(width 0.15494)
		(layer "In9.Cu")
		(net "NIC0_PWRBRK_R_N")
	)
	(segment
		(start 53.957728 -114.046)
		(end 51.638454 -114.046)
		(width 0.15494)
		(layer "In9.Cu")
		(net "NIC0_PWRBRK_R_N")
	)
	(segment
		(start 56.1086 -144.678146)
		(end 56.1086 -133.4516)
		(width 0.15494)
		(layer "In9.Cu")
		(net "NIC0_PWRBRK_R_N")
	)
	(segment
		(start 51.98745 -97.617788)
		(end 51.98745 -97.055686)
		(width 0.15494)
		(layer "In9.Cu")
		(net "NIC0_PWRBRK_R_N")
	)
	(segment
		(start 57.31256 -161.508186)
		(end 57.31256 -145.882106)
		(width 0.15494)
		(layer "In9.Cu")
		(net "NIC0_PWRBRK_R_N")
	)
	(segment
		(start 338.093812 -215.987122)
		(end 337.694016 -215.587326)
		(width 0.13208)
		(layer "F.Cu")
		(net "PRSNT_SSD7_FPGA_N")
	)
	(segment
		(start 327.93305 -213.233)
		(end 329.358498 -213.233)
		(width 0.13208)
		(layer "F.Cu")
		(net "PRSNT_SSD7_FPGA_N")
	)
	(via
		(at 329.358498 -213.233)
		(size 0.508)
		(drill 0.254)
		(layers "F.Cu" "B.Cu")
		(net "PRSNT_SSD7_FPGA_N")
	)
	(via
		(at 337.694016 -215.587326)
		(size 0.4572)
		(drill 0.254)
		(layers "F.Cu" "B.Cu")
		(net "PRSNT_SSD7_FPGA_N")
	)
	(segment
		(start 337.062826 -215.176608)
		(end 335.056226 -215.176608)
		(width 0.0889)
		(layer "In5.Cu")
		(net "PRSNT_SSD7_FPGA_N")
	)
	(segment
		(start 333.940658 -214.979758)
		(end 332.043024 -214.979758)
		(width 0.15494)
		(layer "In5.Cu")
		(net "PRSNT_SSD7_FPGA_N")
	)
	(segment
		(start 330.201016 -214.075518)
		(end 329.358498 -213.233)
		(width 0.15494)
		(layer "In5.Cu")
		(net "PRSNT_SSD7_FPGA_N")
	)
	(segment
		(start 335.056226 -215.176608)
		(end 334.137508 -215.176608)
		(width 0.15494)
		(layer "In5.Cu")
		(net "PRSNT_SSD7_FPGA_N")
	)
	(segment
		(start 337.694016 -215.587326)
		(end 337.317334 -215.431116)
		(width 0.0889)
		(layer "In5.Cu")
		(net "PRSNT_SSD7_FPGA_N")
	)
	(segment
		(start 331.138784 -214.075518)
		(end 330.201016 -214.075518)
		(width 0.15494)
		(layer "In5.Cu")
		(net "PRSNT_SSD7_FPGA_N")
	)
	(segment
		(start 332.043024 -214.979758)
		(end 331.138784 -214.075518)
		(width 0.15494)
		(layer "In5.Cu")
		(net "PRSNT_SSD7_FPGA_N")
	)
	(segment
		(start 334.137508 -215.176608)
		(end 333.940658 -214.979758)
		(width 0.15494)
		(layer "In5.Cu")
		(net "PRSNT_SSD7_FPGA_N")
	)
	(segment
		(start 337.317334 -215.431116)
		(end 337.062826 -215.176608)
		(width 0.0889)
		(layer "In5.Cu")
		(net "PRSNT_SSD7_FPGA_N")
	)
	(segment
		(start 396.54988 -292.099746)
		(end 396.0749 -291.624766)
		(width 0.249936)
		(layer "F.Cu")
		(net "PCEPLL7_VDDA18_PEX3")
	)
	(via
		(at 381.41656 -283.893514)
		(size 0.508)
		(drill 0.254)
		(layers "F.Cu" "B.Cu")
		(net "PCEPLL7_VDDA18_PEX3")
	)
	(via
		(at 396.0749 -291.624766)
		(size 0.4064)
		(drill 0.2032)
		(layers "F.Cu" "B.Cu")
		(net "PCEPLL7_VDDA18_PEX3")
	)
	(via
		(at 380.01956 -283.893514)
		(size 0.508)
		(drill 0.254)
		(layers "F.Cu" "B.Cu")
		(net "PCEPLL7_VDDA18_PEX3")
	)
	(segment
		(start 396.0749 -291.208206)
		(end 396.0749 -291.624766)
		(width 0.3048)
		(layer "B.Cu")
		(net "PCEPLL7_VDDA18_PEX3")
	)
	(segment
		(start 395.30274 -291.624766)
		(end 396.0749 -291.624766)
		(width 0.3048)
		(layer "B.Cu")
		(net "PCEPLL7_VDDA18_PEX3")
	)
	(segment
		(start 395.59992 -294.94988)
		(end 395.12494 -294.4749)
		(width 0.249936)
		(layer "F.Cu")
		(net "PCEPLL4_VDDA18_PEX3")
	)
	(via
		(at 395.12494 -294.4749)
		(size 0.4064)
		(drill 0.2032)
		(layers "F.Cu" "B.Cu")
		(net "PCEPLL4_VDDA18_PEX3")
	)
	(via
		(at 380.01956 -290.294314)
		(size 0.508)
		(drill 0.254)
		(layers "F.Cu" "B.Cu")
		(net "PCEPLL4_VDDA18_PEX3")
	)
	(via
		(at 381.41656 -290.294314)
		(size 0.508)
		(drill 0.254)
		(layers "F.Cu" "B.Cu")
		(net "PCEPLL4_VDDA18_PEX3")
	)
	(segment
		(start 394.92174 -295.2623)
		(end 394.92174 -294.4749)
		(width 0.3048)
		(layer "B.Cu")
		(net "PCEPLL4_VDDA18_PEX3")
	)
	(segment
		(start 395.12494 -294.4749)
		(end 394.92174 -294.4749)
		(width 0.3048)
		(layer "B.Cu")
		(net "PCEPLL4_VDDA18_PEX3")
	)
	(segment
		(start 396.0749 -296.37482)
		(end 396.54988 -295.89984)
		(width 0.249936)
		(layer "F.Cu")
		(net "PCEPLL3_VDDA18_PEX3")
	)
	(via
		(at 382.977644 -260.338316)
		(size 0.508)
		(drill 0.254)
		(layers "F.Cu" "B.Cu")
		(net "PCEPLL3_VDDA18_PEX3")
	)
	(via
		(at 396.0749 -296.37482)
		(size 0.4064)
		(drill 0.2032)
		(layers "F.Cu" "B.Cu")
		(net "PCEPLL3_VDDA18_PEX3")
	)
	(via
		(at 384.374644 -260.338316)
		(size 0.508)
		(drill 0.254)
		(layers "F.Cu" "B.Cu")
		(net "PCEPLL3_VDDA18_PEX3")
	)
	(segment
		(start 396.0749 -295.6433)
		(end 396.0749 -296.37482)
		(width 0.3048)
		(layer "B.Cu")
		(net "PCEPLL3_VDDA18_PEX3")
	)
	(segment
		(start 395.59992 -298.74972)
		(end 395.12494 -299.224954)
		(width 0.249936)
		(layer "F.Cu")
		(net "PCEPLL1_VDDA18_PEX3")
	)
	(via
		(at 395.12494 -299.224954)
		(size 0.4064)
		(drill 0.2032)
		(layers "F.Cu" "B.Cu")
		(net "PCEPLL1_VDDA18_PEX3")
	)
	(via
		(at 380.01956 -299.895514)
		(size 0.508)
		(drill 0.254)
		(layers "F.Cu" "B.Cu")
		(net "PCEPLL1_VDDA18_PEX3")
	)
	(via
		(at 381.41656 -299.895514)
		(size 0.508)
		(drill 0.254)
		(layers "F.Cu" "B.Cu")
		(net "PCEPLL1_VDDA18_PEX3")
	)
	(segment
		(start 394.92174 -300.1772)
		(end 394.92174 -299.212)
		(width 0.3048)
		(layer "B.Cu")
		(net "PCEPLL1_VDDA18_PEX3")
	)
	(segment
		(start 395.12494 -299.224954)
		(end 394.934694 -299.224954)
		(width 0.3048)
		(layer "B.Cu")
		(net "PCEPLL1_VDDA18_PEX3")
	)
	(segment
		(start 394.934694 -299.224954)
		(end 394.92174 -299.212)
		(width 0.3048)
		(layer "B.Cu")
		(net "PCEPLL1_VDDA18_PEX3")
	)
	(segment
		(start 234.394248 -211.985352)
		(end 235.026708 -211.352892)
		(width 0.13208)
		(layer "F.Cu")
		(net "RST_BIC_EXTRST_N")
	)
	(segment
		(start 235.026708 -208.185766)
		(end 235.690664 -207.52181)
		(width 0.13208)
		(layer "F.Cu")
		(net "RST_BIC_EXTRST_N")
	)
	(segment
		(start 234.267756 -212.29066)
		(end 234.394248 -211.985352)
		(width 0.13208)
		(layer "F.Cu")
		(net "RST_BIC_EXTRST_N")
	)
	(segment
		(start 235.690664 -207.52181)
		(end 235.690664 -206.91221)
		(width 0.13208)
		(layer "F.Cu")
		(net "RST_BIC_EXTRST_N")
	)
	(segment
		(start 235.026708 -209.717132)
		(end 235.026708 -208.185766)
		(width 0.13208)
		(layer "F.Cu")
		(net "RST_BIC_EXTRST_N")
	)
	(segment
		(start 235.448094 -183.02478)
		(end 235.448094 -183.844438)
		(width 0.13208)
		(layer "F.Cu")
		(net "RST_BIC_EXTRST_N")
	)
	(segment
		(start 234.267756 -213.104222)
		(end 234.267756 -212.29066)
		(width 0.13208)
		(layer "F.Cu")
		(net "RST_BIC_EXTRST_N")
	)
	(segment
		(start 234.965494 -181.08168)
		(end 234.965494 -182.54218)
		(width 0.13208)
		(layer "F.Cu")
		(net "RST_BIC_EXTRST_N")
	)
	(segment
		(start 233.867706 -213.504272)
		(end 234.267756 -213.104222)
		(width 0.13208)
		(layer "F.Cu")
		(net "RST_BIC_EXTRST_N")
	)
	(segment
		(start 235.026708 -211.352892)
		(end 235.026708 -209.717132)
		(width 0.13208)
		(layer "F.Cu")
		(net "RST_BIC_EXTRST_N")
	)
	(segment
		(start 234.965494 -182.54218)
		(end 235.448094 -183.02478)
		(width 0.13208)
		(layer "F.Cu")
		(net "RST_BIC_EXTRST_N")
	)
	(via
		(at 235.026708 -209.717132)
		(size 0.762)
		(drill 0.381)
		(layers "F.Cu" "B.Cu")
		(net "RST_BIC_EXTRST_N")
	)
	(via
		(at 235.448094 -183.844438)
		(size 0.508)
		(drill 0.254)
		(layers "F.Cu" "B.Cu")
		(net "RST_BIC_EXTRST_N")
	)
	(via
		(at 235.690664 -207.52181)
		(size 0.508)
		(drill 0.254)
		(layers "F.Cu" "B.Cu")
		(net "RST_BIC_EXTRST_N")
	)
	(segment
		(start 242.107212 -198.938388)
		(end 242.107212 -197.203822)
		(width 0.15494)
		(layer "In7.Cu")
		(net "RST_BIC_EXTRST_N")
	)
	(segment
		(start 240.792 -201.422)
		(end 240.792 -200.2536)
		(width 0.15494)
		(layer "In7.Cu")
		(net "RST_BIC_EXTRST_N")
	)
	(segment
		(start 235.690664 -207.0735)
		(end 236.582458 -206.181706)
		(width 0.15494)
		(layer "In7.Cu")
		(net "RST_BIC_EXTRST_N")
	)
	(segment
		(start 241.307366 -186.606434)
		(end 242.1128 -185.801)
		(width 0.15494)
		(layer "In7.Cu")
		(net "RST_BIC_EXTRST_N")
	)
	(segment
		(start 243.7638 -184.8358)
		(end 243.7638 -183.8198)
		(width 0.15494)
		(layer "In7.Cu")
		(net "RST_BIC_EXTRST_N")
	)
	(segment
		(start 242.7986 -185.801)
		(end 243.7638 -184.8358)
		(width 0.15494)
		(layer "In7.Cu")
		(net "RST_BIC_EXTRST_N")
	)
	(segment
		(start 240.792 -200.2536)
		(end 242.107212 -198.938388)
		(width 0.15494)
		(layer "In7.Cu")
		(net "RST_BIC_EXTRST_N")
	)
	(segment
		(start 242.107212 -197.203822)
		(end 241.307366 -196.403976)
		(width 0.15494)
		(layer "In7.Cu")
		(net "RST_BIC_EXTRST_N")
	)
	(segment
		(start 235.690664 -207.52181)
		(end 235.690664 -207.0735)
		(width 0.15494)
		(layer "In7.Cu")
		(net "RST_BIC_EXTRST_N")
	)
	(segment
		(start 240.328196 -206.181706)
		(end 240.665 -205.844902)
		(width 0.15494)
		(layer "In7.Cu")
		(net "RST_BIC_EXTRST_N")
	)
	(segment
		(start 235.802932 -183.4896)
		(end 235.448094 -183.844438)
		(width 0.15494)
		(layer "In7.Cu")
		(net "RST_BIC_EXTRST_N")
	)
	(segment
		(start 242.1128 -185.801)
		(end 242.7986 -185.801)
		(width 0.15494)
		(layer "In7.Cu")
		(net "RST_BIC_EXTRST_N")
	)
	(segment
		(start 243.4336 -183.4896)
		(end 235.802932 -183.4896)
		(width 0.15494)
		(layer "In7.Cu")
		(net "RST_BIC_EXTRST_N")
	)
	(segment
		(start 243.7638 -183.8198)
		(end 243.4336 -183.4896)
		(width 0.15494)
		(layer "In7.Cu")
		(net "RST_BIC_EXTRST_N")
	)
	(segment
		(start 236.582458 -206.181706)
		(end 240.328196 -206.181706)
		(width 0.15494)
		(layer "In7.Cu")
		(net "RST_BIC_EXTRST_N")
	)
	(segment
		(start 240.665 -205.844902)
		(end 240.665 -201.549)
		(width 0.15494)
		(layer "In7.Cu")
		(net "RST_BIC_EXTRST_N")
	)
	(segment
		(start 240.665 -201.549)
		(end 240.792 -201.422)
		(width 0.15494)
		(layer "In7.Cu")
		(net "RST_BIC_EXTRST_N")
	)
	(segment
		(start 241.307366 -196.403976)
		(end 241.307366 -186.606434)
		(width 0.15494)
		(layer "In7.Cu")
		(net "RST_BIC_EXTRST_N")
	)
	(segment
		(start 252.60046 -202.939396)
		(end 252.287532 -203.252324)
		(width 0.13208)
		(layer "F.Cu")
		(net "JTAG_BIC_EN_R")
	)
	(segment
		(start 252.287532 -203.252324)
		(end 252.038612 -203.003404)
		(width 0.13208)
		(layer "F.Cu")
		(net "JTAG_BIC_EN_R")
	)
	(segment
		(start 254.23749 -204.79893)
		(end 254.23749 -203.298806)
		(width 0.13208)
		(layer "F.Cu")
		(net "JTAG_BIC_EN_R")
	)
	(segment
		(start 251.637546 -199.872854)
		(end 251.637546 -198.95693)
		(width 0.13208)
		(layer "F.Cu")
		(net "JTAG_BIC_EN_R")
	)
	(segment
		(start 252.336554 -200.571862)
		(end 251.637546 -199.872854)
		(width 0.13208)
		(layer "F.Cu")
		(net "JTAG_BIC_EN_R")
	)
	(segment
		(start 254.23749 -203.298806)
		(end 253.87808 -202.939396)
		(width 0.13208)
		(layer "F.Cu")
		(net "JTAG_BIC_EN_R")
	)
	(segment
		(start 253.587504 -198.95693)
		(end 253.587504 -199.788272)
		(width 0.13208)
		(layer "F.Cu")
		(net "JTAG_BIC_EN_R")
	)
	(segment
		(start 252.287532 -204.79893)
		(end 252.287532 -203.252324)
		(width 0.13208)
		(layer "F.Cu")
		(net "JTAG_BIC_EN_R")
	)
	(segment
		(start 252.803914 -200.571862)
		(end 252.336554 -200.571862)
		(width 0.13208)
		(layer "F.Cu")
		(net "JTAG_BIC_EN_R")
	)
	(segment
		(start 253.87808 -202.939396)
		(end 252.60046 -202.939396)
		(width 0.13208)
		(layer "F.Cu")
		(net "JTAG_BIC_EN_R")
	)
	(segment
		(start 251.637546 -197.77202)
		(end 251.637546 -198.95693)
		(width 0.13208)
		(layer "F.Cu")
		(net "JTAG_BIC_EN_R")
	)
	(segment
		(start 252.038612 -200.869804)
		(end 252.336554 -200.571862)
		(width 0.13208)
		(layer "F.Cu")
		(net "JTAG_BIC_EN_R")
	)
	(segment
		(start 253.587504 -199.788272)
		(end 252.803914 -200.571862)
		(width 0.13208)
		(layer "F.Cu")
		(net "JTAG_BIC_EN_R")
	)
	(segment
		(start 252.038612 -203.003404)
		(end 252.038612 -200.869804)
		(width 0.13208)
		(layer "F.Cu")
		(net "JTAG_BIC_EN_R")
	)
	(via
		(at 251.637546 -197.77202)
		(size 0.508)
		(drill 0.254)
		(layers "F.Cu" "B.Cu")
		(net "JTAG_BIC_EN_R")
	)
	(via
		(at 224.536508 -202.594464)
		(size 0.508)
		(drill 0.254)
		(layers "F.Cu" "B.Cu")
		(net "JTAG_BIC_EN_R")
	)
	(segment
		(start 251.637546 -197.77202)
		(end 251.968 -198.102474)
		(width 0.13208)
		(layer "B.Cu")
		(net "JTAG_BIC_EN_R")
	)
	(segment
		(start 223.021652 -204.467206)
		(end 223.498664 -203.990194)
		(width 0.13208)
		(layer "B.Cu")
		(net "JTAG_BIC_EN_R")
	)
	(segment
		(start 223.498664 -203.632308)
		(end 224.536508 -202.594464)
		(width 0.13208)
		(layer "B.Cu")
		(net "JTAG_BIC_EN_R")
	)
	(segment
		(start 223.498664 -203.990194)
		(end 223.498664 -203.632308)
		(width 0.13208)
		(layer "B.Cu")
		(net "JTAG_BIC_EN_R")
	)
	(segment
		(start 251.968 -198.102474)
		(end 251.968 -198.98995)
		(width 0.13208)
		(layer "B.Cu")
		(net "JTAG_BIC_EN_R")
	)
	(segment
		(start 224.501964 -208.38541)
		(end 224.501964 -207.16748)
		(width 0.13208)
		(layer "B.Cu")
		(net "JTAG_BIC_EN_R")
	)
	(segment
		(start 224.501964 -207.16748)
		(end 223.021652 -205.687168)
		(width 0.13208)
		(layer "B.Cu")
		(net "JTAG_BIC_EN_R")
	)
	(segment
		(start 223.021652 -205.687168)
		(end 223.021652 -204.467206)
		(width 0.13208)
		(layer "B.Cu")
		(net "JTAG_BIC_EN_R")
	)
	(segment
		(start 225.023934 -202.107038)
		(end 224.536508 -202.594464)
		(width 0.15494)
		(layer "In15.Cu")
		(net "JTAG_BIC_EN_R")
	)
	(segment
		(start 227.690172 -194.875658)
		(end 227.690172 -200.638664)
		(width 0.15494)
		(layer "In15.Cu")
		(net "JTAG_BIC_EN_R")
	)
	(segment
		(start 242.103148 -194.71259)
		(end 237.213394 -189.822836)
		(width 0.15494)
		(layer "In15.Cu")
		(net "JTAG_BIC_EN_R")
	)
	(segment
		(start 226.221798 -202.107038)
		(end 225.023934 -202.107038)
		(width 0.15494)
		(layer "In15.Cu")
		(net "JTAG_BIC_EN_R")
	)
	(segment
		(start 227.690172 -200.638664)
		(end 226.221798 -202.107038)
		(width 0.15494)
		(layer "In15.Cu")
		(net "JTAG_BIC_EN_R")
	)
	(segment
		(start 237.213394 -189.822836)
		(end 235.286042 -189.024514)
		(width 0.15494)
		(layer "In15.Cu")
		(net "JTAG_BIC_EN_R")
	)
	(segment
		(start 231.590088 -189.024514)
		(end 229.0699 -191.544702)
		(width 0.15494)
		(layer "In15.Cu")
		(net "JTAG_BIC_EN_R")
	)
	(segment
		(start 229.0699 -191.544702)
		(end 227.690172 -194.875658)
		(width 0.15494)
		(layer "In15.Cu")
		(net "JTAG_BIC_EN_R")
	)
	(segment
		(start 248.2088 -194.71259)
		(end 242.103148 -194.71259)
		(width 0.15494)
		(layer "In15.Cu")
		(net "JTAG_BIC_EN_R")
	)
	(segment
		(start 235.286042 -189.024514)
		(end 231.590088 -189.024514)
		(width 0.15494)
		(layer "In15.Cu")
		(net "JTAG_BIC_EN_R")
	)
	(segment
		(start 251.006864 -197.510654)
		(end 248.2088 -194.71259)
		(width 0.15494)
		(layer "In15.Cu")
		(net "JTAG_BIC_EN_R")
	)
	(segment
		(start 251.637546 -197.77202)
		(end 251.006864 -197.510654)
		(width 0.15494)
		(layer "In15.Cu")
		(net "JTAG_BIC_EN_R")
	)
	(segment
		(start 396.54988 -299.699934)
		(end 396.0749 -300.174914)
		(width 0.249936)
		(layer "F.Cu")
		(net "PCEPLL0_VDDA18_PEX3")
	)
	(via
		(at 380.01956 -296.695114)
		(size 0.508)
		(drill 0.254)
		(layers "F.Cu" "B.Cu")
		(net "PCEPLL0_VDDA18_PEX3")
	)
	(via
		(at 381.41656 -296.695114)
		(size 0.508)
		(drill 0.254)
		(layers "F.Cu" "B.Cu")
		(net "PCEPLL0_VDDA18_PEX3")
	)
	(via
		(at 396.0749 -300.174914)
		(size 0.4064)
		(drill 0.2032)
		(layers "F.Cu" "B.Cu")
		(net "PCEPLL0_VDDA18_PEX3")
	)
	(segment
		(start 396.07744 -300.5328)
		(end 396.07744 -300.177454)
		(width 0.3048)
		(layer "B.Cu")
		(net "PCEPLL0_VDDA18_PEX3")
	)
	(segment
		(start 396.07744 -300.177454)
		(end 396.0749 -300.174914)
		(width 0.3048)
		(layer "B.Cu")
		(net "PCEPLL0_VDDA18_PEX3")
	)
	(segment
		(start 396.07744 -300.172374)
		(end 396.0749 -300.174914)
		(width 0.3048)
		(layer "B.Cu")
		(net "PCEPLL0_VDDA18_PEX3")
	)
	(segment
		(start 396.07744 -299.8089)
		(end 396.07744 -300.172374)
		(width 0.3048)
		(layer "B.Cu")
		(net "PCEPLL0_VDDA18_PEX3")
	)
	(segment
		(start 231.149144 -173.67758)
		(end 231.765348 -173.67758)
		(width 0.13208)
		(layer "F.Cu")
		(net "PWRGD_P1V2_AUX_DLY")
	)
	(segment
		(start 244.8433 -185.829702)
		(end 244.8433 -186.481212)
		(width 0.13208)
		(layer "F.Cu")
		(net "PWRGD_P1V2_AUX_DLY")
	)
	(via
		(at 231.765348 -173.67758)
		(size 0.508)
		(drill 0.254)
		(layers "F.Cu" "B.Cu")
		(net "PWRGD_P1V2_AUX_DLY")
	)
	(via
		(at 244.8433 -186.481212)
		(size 0.508)
		(drill 0.254)
		(layers "F.Cu" "B.Cu")
		(net "PWRGD_P1V2_AUX_DLY")
	)
	(segment
		(start 244.8433 -186.481212)
		(end 243.87556 -187.448952)
		(width 0.15494)
		(layer "In5.Cu")
		(net "PWRGD_P1V2_AUX_DLY")
	)
	(segment
		(start 233.31805 -175.230282)
		(end 231.765348 -173.67758)
		(width 0.15494)
		(layer "In5.Cu")
		(net "PWRGD_P1V2_AUX_DLY")
	)
	(segment
		(start 233.31805 -182.79745)
		(end 233.31805 -175.230282)
		(width 0.15494)
		(layer "In5.Cu")
		(net "PWRGD_P1V2_AUX_DLY")
	)
	(segment
		(start 237.969552 -187.448952)
		(end 233.31805 -182.79745)
		(width 0.15494)
		(layer "In5.Cu")
		(net "PWRGD_P1V2_AUX_DLY")
	)
	(segment
		(start 243.87556 -187.448952)
		(end 237.969552 -187.448952)
		(width 0.15494)
		(layer "In5.Cu")
		(net "PWRGD_P1V2_AUX_DLY")
	)
	(segment
		(start 131.39674 -118.779036)
		(end 131.39674 -119.39143)
		(width 0.13208)
		(layer "F.Cu")
		(net "HP_NIC2_EN")
	)
	(segment
		(start 153.930604 -115.803934)
		(end 153.424128 -115.803934)
		(width 0.13208)
		(layer "F.Cu")
		(net "HP_NIC2_EN")
	)
	(segment
		(start 127.7366 -122.787664)
		(end 127.418846 -122.46991)
		(width 0.13208)
		(layer "F.Cu")
		(net "HP_NIC2_EN")
	)
	(segment
		(start 151.653494 -116.690648)
		(end 150.855934 -116.690648)
		(width 0.13208)
		(layer "F.Cu")
		(net "HP_NIC2_EN")
	)
	(segment
		(start 128.33096 -124.394722)
		(end 128.106424 -124.394722)
		(width 0.13208)
		(layer "F.Cu")
		(net "HP_NIC2_EN")
	)
	(segment
		(start 127.7366 -124.024898)
		(end 127.7366 -122.787664)
		(width 0.13208)
		(layer "F.Cu")
		(net "HP_NIC2_EN")
	)
	(segment
		(start 132.531612 -162.404044)
		(end 132.531612 -163.114736)
		(width 0.13208)
		(layer "F.Cu")
		(net "HP_NIC2_EN")
	)
	(segment
		(start 152.678892 -115.66525)
		(end 151.653494 -116.690648)
		(width 0.13208)
		(layer "F.Cu")
		(net "HP_NIC2_EN")
	)
	(segment
		(start 153.424128 -115.803934)
		(end 153.285444 -115.66525)
		(width 0.13208)
		(layer "F.Cu")
		(net "HP_NIC2_EN")
	)
	(segment
		(start 128.106424 -124.394722)
		(end 127.7366 -124.024898)
		(width 0.13208)
		(layer "F.Cu")
		(net "HP_NIC2_EN")
	)
	(segment
		(start 153.285444 -115.66525)
		(end 152.678892 -115.66525)
		(width 0.13208)
		(layer "F.Cu")
		(net "HP_NIC2_EN")
	)
	(segment
		(start 123.31319 -134.042404)
		(end 122.65787 -134.042404)
		(width 0.13208)
		(layer "F.Cu")
		(net "HP_NIC2_EN")
	)
	(segment
		(start 126.610364 -121.661428)
		(end 127.418846 -122.46991)
		(width 0.13208)
		(layer "F.Cu")
		(net "HP_NIC2_EN")
	)
	(via
		(at 153.930604 -115.803934)
		(size 0.508)
		(drill 0.254)
		(layers "F.Cu" "B.Cu")
		(net "HP_NIC2_EN")
	)
	(via
		(at 131.39674 -119.39143)
		(size 0.508)
		(drill 0.254)
		(layers "F.Cu" "B.Cu")
		(net "HP_NIC2_EN")
	)
	(via
		(at 122.65787 -134.042404)
		(size 0.508)
		(drill 0.254)
		(layers "F.Cu" "B.Cu")
		(net "HP_NIC2_EN")
	)
	(via
		(at 132.531612 -163.114736)
		(size 0.508)
		(drill 0.254)
		(layers "F.Cu" "B.Cu")
		(net "HP_NIC2_EN")
	)
	(via
		(at 127.418846 -122.46991)
		(size 0.508)
		(drill 0.254)
		(layers "F.Cu" "B.Cu")
		(net "HP_NIC2_EN")
	)
	(segment
		(start 127.21844 -122.269504)
		(end 127.418846 -122.46991)
		(width 0.15494)
		(layer "In5.Cu")
		(net "HP_NIC2_EN")
	)
	(segment
		(start 127.21844 -120.825006)
		(end 127.21844 -122.269504)
		(width 0.15494)
		(layer "In5.Cu")
		(net "HP_NIC2_EN")
	)
	(segment
		(start 122.65787 -130.474466)
		(end 122.65787 -134.042404)
		(width 0.15494)
		(layer "In5.Cu")
		(net "HP_NIC2_EN")
	)
	(segment
		(start 126.288292 -123.600464)
		(end 126.288292 -126.844044)
		(width 0.15494)
		(layer "In5.Cu")
		(net "HP_NIC2_EN")
	)
	(segment
		(start 131.040124 -118.59895)
		(end 128.189482 -118.59895)
		(width 0.15494)
		(layer "In5.Cu")
		(net "HP_NIC2_EN")
	)
	(segment
		(start 128.189482 -118.59895)
		(end 127.68707 -119.101362)
		(width 0.15494)
		(layer "In5.Cu")
		(net "HP_NIC2_EN")
	)
	(segment
		(start 127.68707 -119.101362)
		(end 127.68707 -120.356376)
		(width 0.15494)
		(layer "In5.Cu")
		(net "HP_NIC2_EN")
	)
	(segment
		(start 126.288292 -126.844044)
		(end 122.65787 -130.474466)
		(width 0.15494)
		(layer "In5.Cu")
		(net "HP_NIC2_EN")
	)
	(segment
		(start 131.39674 -118.955566)
		(end 131.040124 -118.59895)
		(width 0.15494)
		(layer "In5.Cu")
		(net "HP_NIC2_EN")
	)
	(segment
		(start 127.418846 -122.46991)
		(end 126.288292 -123.600464)
		(width 0.15494)
		(layer "In5.Cu")
		(net "HP_NIC2_EN")
	)
	(segment
		(start 127.68707 -120.356376)
		(end 127.21844 -120.825006)
		(width 0.15494)
		(layer "In5.Cu")
		(net "HP_NIC2_EN")
	)
	(segment
		(start 131.39674 -119.39143)
		(end 131.39674 -118.955566)
		(width 0.15494)
		(layer "In5.Cu")
		(net "HP_NIC2_EN")
	)
	(segment
		(start 122.020838 -145.745962)
		(end 121.63298 -146.13382)
		(width 0.15494)
		(layer "In7.Cu")
		(net "HP_NIC2_EN")
	)
	(segment
		(start 125.085094 -163.6776)
		(end 131.968748 -163.6776)
		(width 0.15494)
		(layer "In7.Cu")
		(net "HP_NIC2_EN")
	)
	(segment
		(start 122.020838 -134.925308)
		(end 122.020838 -145.745962)
		(width 0.15494)
		(layer "In7.Cu")
		(net "HP_NIC2_EN")
	)
	(segment
		(start 122.65787 -134.288276)
		(end 122.020838 -134.925308)
		(width 0.15494)
		(layer "In7.Cu")
		(net "HP_NIC2_EN")
	)
	(segment
		(start 122.65787 -134.042404)
		(end 122.65787 -134.288276)
		(width 0.15494)
		(layer "In7.Cu")
		(net "HP_NIC2_EN")
	)
	(segment
		(start 131.968748 -163.6776)
		(end 132.531612 -163.114736)
		(width 0.15494)
		(layer "In7.Cu")
		(net "HP_NIC2_EN")
	)
	(segment
		(start 121.63298 -160.225486)
		(end 125.085094 -163.6776)
		(width 0.15494)
		(layer "In7.Cu")
		(net "HP_NIC2_EN")
	)
	(segment
		(start 121.63298 -146.13382)
		(end 121.63298 -160.225486)
		(width 0.15494)
		(layer "In7.Cu")
		(net "HP_NIC2_EN")
	)
	(segment
		(start 132.14858 -118.63959)
		(end 131.39674 -119.39143)
		(width 0.15494)
		(layer "In15.Cu")
		(net "HP_NIC2_EN")
	)
	(segment
		(start 135.530082 -118.63959)
		(end 132.14858 -118.63959)
		(width 0.15494)
		(layer "In15.Cu")
		(net "HP_NIC2_EN")
	)
	(segment
		(start 138.365738 -115.803934)
		(end 135.530082 -118.63959)
		(width 0.15494)
		(layer "In15.Cu")
		(net "HP_NIC2_EN")
	)
	(segment
		(start 153.930604 -115.803934)
		(end 138.365738 -115.803934)
		(width 0.15494)
		(layer "In15.Cu")
		(net "HP_NIC2_EN")
	)
	(segment
		(start 71.524876 -304.924714)
		(end 71.999856 -304.449734)
		(width 0.13208)
		(layer "F.Cu")
		(net "RST_PEX0_S0_PERST_R_N")
	)
	(segment
		(start 85.057234 -288.830766)
		(end 85.53577 -288.830766)
		(width 0.13208)
		(layer "F.Cu")
		(net "RST_PEX0_S0_PERST_R_N")
	)
	(segment
		(start 85.13826 -297.95851)
		(end 84.8106 -297.63085)
		(width 0.13208)
		(layer "F.Cu")
		(net "RST_PEX0_S0_PERST_R_N")
	)
	(segment
		(start 84.8106 -297.63085)
		(end 84.8106 -289.0774)
		(width 0.13208)
		(layer "F.Cu")
		(net "RST_PEX0_S0_PERST_R_N")
	)
	(segment
		(start 84.8106 -289.0774)
		(end 85.057234 -288.830766)
		(width 0.13208)
		(layer "F.Cu")
		(net "RST_PEX0_S0_PERST_R_N")
	)
	(via
		(at 85.13826 -297.95851)
		(size 0.508)
		(drill 0.254)
		(layers "F.Cu" "B.Cu")
		(net "RST_PEX0_S0_PERST_R_N")
	)
	(via
		(at 71.524876 -304.924714)
		(size 0.4064)
		(drill 0.2032)
		(layers "F.Cu" "B.Cu")
		(net "RST_PEX0_S0_PERST_R_N")
	)
	(segment
		(start 71.7296 -301.5742)
		(end 72.0852 -301.2186)
		(width 0.15494)
		(layer "In5.Cu")
		(net "RST_PEX0_S0_PERST_R_N")
	)
	(segment
		(start 74.295 -297.79976)
		(end 84.389214 -297.79976)
		(width 0.15494)
		(layer "In5.Cu")
		(net "RST_PEX0_S0_PERST_R_N")
	)
	(segment
		(start 72.9234 -300.4566)
		(end 72.9234 -299.795946)
		(width 0.15494)
		(layer "In5.Cu")
		(net "RST_PEX0_S0_PERST_R_N")
	)
	(segment
		(start 71.2216 -301.5742)
		(end 71.7296 -301.5742)
		(width 0.15494)
		(layer "In5.Cu")
		(net "RST_PEX0_S0_PERST_R_N")
	)
	(segment
		(start 71.0946 -304.494438)
		(end 71.0946 -301.7012)
		(width 0.15494)
		(layer "In5.Cu")
		(net "RST_PEX0_S0_PERST_R_N")
	)
	(segment
		(start 73.0504 -299.668946)
		(end 73.5838 -299.668946)
		(width 0.15494)
		(layer "In5.Cu")
		(net "RST_PEX0_S0_PERST_R_N")
	)
	(segment
		(start 72.9234 -299.795946)
		(end 73.0504 -299.668946)
		(width 0.15494)
		(layer "In5.Cu")
		(net "RST_PEX0_S0_PERST_R_N")
	)
	(segment
		(start 71.524876 -304.924714)
		(end 71.0946 -304.494438)
		(width 0.15494)
		(layer "In5.Cu")
		(net "RST_PEX0_S0_PERST_R_N")
	)
	(segment
		(start 84.547964 -297.95851)
		(end 85.13826 -297.95851)
		(width 0.15494)
		(layer "In5.Cu")
		(net "RST_PEX0_S0_PERST_R_N")
	)
	(segment
		(start 72.263 -300.6598)
		(end 72.7202 -300.6598)
		(width 0.15494)
		(layer "In5.Cu")
		(net "RST_PEX0_S0_PERST_R_N")
	)
	(segment
		(start 73.5838 -299.668946)
		(end 73.9394 -299.313346)
		(width 0.15494)
		(layer "In5.Cu")
		(net "RST_PEX0_S0_PERST_R_N")
	)
	(segment
		(start 73.9394 -298.15536)
		(end 74.295 -297.79976)
		(width 0.15494)
		(layer "In5.Cu")
		(net "RST_PEX0_S0_PERST_R_N")
	)
	(segment
		(start 72.0852 -300.8376)
		(end 72.263 -300.6598)
		(width 0.15494)
		(layer "In5.Cu")
		(net "RST_PEX0_S0_PERST_R_N")
	)
	(segment
		(start 84.389214 -297.79976)
		(end 84.547964 -297.95851)
		(width 0.15494)
		(layer "In5.Cu")
		(net "RST_PEX0_S0_PERST_R_N")
	)
	(segment
		(start 72.0852 -301.2186)
		(end 72.0852 -300.8376)
		(width 0.15494)
		(layer "In5.Cu")
		(net "RST_PEX0_S0_PERST_R_N")
	)
	(segment
		(start 71.0946 -301.7012)
		(end 71.2216 -301.5742)
		(width 0.15494)
		(layer "In5.Cu")
		(net "RST_PEX0_S0_PERST_R_N")
	)
	(segment
		(start 73.9394 -299.313346)
		(end 73.9394 -298.15536)
		(width 0.15494)
		(layer "In5.Cu")
		(net "RST_PEX0_S0_PERST_R_N")
	)
	(segment
		(start 72.7202 -300.6598)
		(end 72.9234 -300.4566)
		(width 0.15494)
		(layer "In5.Cu")
		(net "RST_PEX0_S0_PERST_R_N")
	)
	(segment
		(start 225.867722 -218.30411)
		(end 225.467926 -217.904314)
		(width 0.13208)
		(layer "F.Cu")
		(net "PECI_VDD")
	)
	(via
		(at 223.074484 -218.43873)
		(size 0.6604)
		(drill 0.3302)
		(layers "F.Cu" "B.Cu")
		(net "PECI_VDD")
	)
	(via
		(at 225.467926 -217.904314)
		(size 0.4572)
		(drill 0.254)
		(layers "F.Cu" "B.Cu")
		(net "PECI_VDD")
	)
	(segment
		(start 215.543892 -216.798398)
		(end 214.497666 -216.798398)
		(width 0.13208)
		(layer "B.Cu")
		(net "PECI_VDD")
	)
	(segment
		(start 220.650816 -218.43873)
		(end 219.498672 -217.286586)
		(width 0.13208)
		(layer "B.Cu")
		(net "PECI_VDD")
	)
	(segment
		(start 224.93351 -218.43873)
		(end 223.074484 -218.43873)
		(width 0.13208)
		(layer "B.Cu")
		(net "PECI_VDD")
	)
	(segment
		(start 215.705944 -216.96045)
		(end 215.543892 -216.798398)
		(width 0.13208)
		(layer "B.Cu")
		(net "PECI_VDD")
	)
	(segment
		(start 215.705944 -217.469212)
		(end 215.705944 -216.96045)
		(width 0.13208)
		(layer "B.Cu")
		(net "PECI_VDD")
	)
	(segment
		(start 214.497666 -216.798398)
		(end 214.232744 -217.06332)
		(width 0.13208)
		(layer "B.Cu")
		(net "PECI_VDD")
	)
	(segment
		(start 217.635836 -217.286586)
		(end 217.635836 -217.66911)
		(width 0.13208)
		(layer "B.Cu")
		(net "PECI_VDD")
	)
	(segment
		(start 216.032842 -217.79611)
		(end 215.705944 -217.469212)
		(width 0.13208)
		(layer "B.Cu")
		(net "PECI_VDD")
	)
	(segment
		(start 217.635836 -217.66911)
		(end 217.508836 -217.79611)
		(width 0.13208)
		(layer "B.Cu")
		(net "PECI_VDD")
	)
	(segment
		(start 223.074484 -218.43873)
		(end 220.650816 -218.43873)
		(width 0.13208)
		(layer "B.Cu")
		(net "PECI_VDD")
	)
	(segment
		(start 219.498672 -217.286586)
		(end 217.635836 -217.286586)
		(width 0.13208)
		(layer "B.Cu")
		(net "PECI_VDD")
	)
	(segment
		(start 225.467926 -217.904314)
		(end 224.93351 -218.43873)
		(width 0.13208)
		(layer "B.Cu")
		(net "PECI_VDD")
	)
	(segment
		(start 214.232744 -217.06332)
		(end 214.232744 -217.270838)
		(width 0.13208)
		(layer "B.Cu")
		(net "PECI_VDD")
	)
	(segment
		(start 217.508836 -217.79611)
		(end 216.032842 -217.79611)
		(width 0.13208)
		(layer "B.Cu")
		(net "PECI_VDD")
	)
	(segment
		(start 395.59992 -293.04996)
		(end 395.12494 -292.57498)
		(width 0.249936)
		(layer "F.Cu")
		(net "PCEPLL6_VDDA18_PEX3")
	)
	(via
		(at 381.41656 -287.093914)
		(size 0.508)
		(drill 0.254)
		(layers "F.Cu" "B.Cu")
		(net "PCEPLL6_VDDA18_PEX3")
	)
	(via
		(at 380.01956 -287.093914)
		(size 0.508)
		(drill 0.254)
		(layers "F.Cu" "B.Cu")
		(net "PCEPLL6_VDDA18_PEX3")
	)
	(via
		(at 395.12494 -292.57498)
		(size 0.4064)
		(drill 0.2032)
		(layers "F.Cu" "B.Cu")
		(net "PCEPLL6_VDDA18_PEX3")
	)
	(segment
		(start 394.92174 -292.57498)
		(end 395.12494 -292.57498)
		(width 0.3048)
		(layer "B.Cu")
		(net "PCEPLL6_VDDA18_PEX3")
	)
	(segment
		(start 394.92174 -293.52494)
		(end 394.92174 -292.57498)
		(width 0.3048)
		(layer "B.Cu")
		(net "PCEPLL6_VDDA18_PEX3")
	)
	(segment
		(start 87.2744 -298.994322)
		(end 87.2744 -300.8884)
		(width 0.13208)
		(layer "F.Cu")
		(net "RST_PEX0_S1_PERST_R_N")
	)
	(segment
		(start 72.474836 -305.874928)
		(end 72.949816 -306.349908)
		(width 0.13208)
		(layer "F.Cu")
		(net "RST_PEX0_S1_PERST_R_N")
	)
	(segment
		(start 86.870286 -298.7294)
		(end 87.009478 -298.7294)
		(width 0.13208)
		(layer "F.Cu")
		(net "RST_PEX0_S1_PERST_R_N")
	)
	(segment
		(start 87.009478 -298.7294)
		(end 87.2744 -298.994322)
		(width 0.13208)
		(layer "F.Cu")
		(net "RST_PEX0_S1_PERST_R_N")
	)
	(segment
		(start 87.2744 -300.8884)
		(end 87.3887 -301.0027)
		(width 0.13208)
		(layer "F.Cu")
		(net "RST_PEX0_S1_PERST_R_N")
	)
	(segment
		(start 87.3887 -301.0027)
		(end 87.749634 -301.0027)
		(width 0.13208)
		(layer "F.Cu")
		(net "RST_PEX0_S1_PERST_R_N")
	)
	(via
		(at 72.474836 -305.874928)
		(size 0.4064)
		(drill 0.2032)
		(layers "F.Cu" "B.Cu")
		(net "RST_PEX0_S1_PERST_R_N")
	)
	(via
		(at 86.870286 -298.7294)
		(size 0.508)
		(drill 0.254)
		(layers "F.Cu" "B.Cu")
		(net "RST_PEX0_S1_PERST_R_N")
	)
	(segment
		(start 73.88098 -300.51502)
		(end 73.7362 -300.6598)
		(width 0.15494)
		(layer "In5.Cu")
		(net "RST_PEX0_S1_PERST_R_N")
	)
	(segment
		(start 72.771 -301.5742)
		(end 72.39 -301.5742)
		(width 0.15494)
		(layer "In5.Cu")
		(net "RST_PEX0_S1_PERST_R_N")
	)
	(segment
		(start 73.3044 -300.6598)
		(end 72.9488 -301.0154)
		(width 0.15494)
		(layer "In5.Cu")
		(net "RST_PEX0_S1_PERST_R_N")
	)
	(segment
		(start 72.474836 -305.494436)
		(end 72.474836 -305.874928)
		(width 0.15494)
		(layer "In5.Cu")
		(net "RST_PEX0_S1_PERST_R_N")
	)
	(segment
		(start 73.88098 -299.93082)
		(end 73.88098 -300.51502)
		(width 0.15494)
		(layer "In5.Cu")
		(net "RST_PEX0_S1_PERST_R_N")
	)
	(segment
		(start 72.39 -301.5742)
		(end 72.0344 -301.9298)
		(width 0.15494)
		(layer "In5.Cu")
		(net "RST_PEX0_S1_PERST_R_N")
	)
	(segment
		(start 75.05573 -298.75607)
		(end 73.88098 -299.93082)
		(width 0.15494)
		(layer "In5.Cu")
		(net "RST_PEX0_S1_PERST_R_N")
	)
	(segment
		(start 73.7362 -300.6598)
		(end 73.3044 -300.6598)
		(width 0.15494)
		(layer "In5.Cu")
		(net "RST_PEX0_S1_PERST_R_N")
	)
	(segment
		(start 86.706964 -298.566078)
		(end 85.708236 -298.566078)
		(width 0.15494)
		(layer "In5.Cu")
		(net "RST_PEX0_S1_PERST_R_N")
	)
	(segment
		(start 72.0344 -305.054)
		(end 72.474836 -305.494436)
		(width 0.15494)
		(layer "In5.Cu")
		(net "RST_PEX0_S1_PERST_R_N")
	)
	(segment
		(start 85.708236 -298.566078)
		(end 85.518244 -298.75607)
		(width 0.15494)
		(layer "In5.Cu")
		(net "RST_PEX0_S1_PERST_R_N")
	)
	(segment
		(start 72.9488 -301.3964)
		(end 72.771 -301.5742)
		(width 0.15494)
		(layer "In5.Cu")
		(net "RST_PEX0_S1_PERST_R_N")
	)
	(segment
		(start 85.518244 -298.75607)
		(end 75.05573 -298.75607)
		(width 0.15494)
		(layer "In5.Cu")
		(net "RST_PEX0_S1_PERST_R_N")
	)
	(segment
		(start 72.0344 -301.9298)
		(end 72.0344 -305.054)
		(width 0.15494)
		(layer "In5.Cu")
		(net "RST_PEX0_S1_PERST_R_N")
	)
	(segment
		(start 86.870286 -298.7294)
		(end 86.706964 -298.566078)
		(width 0.15494)
		(layer "In5.Cu")
		(net "RST_PEX0_S1_PERST_R_N")
	)
	(segment
		(start 72.9488 -301.0154)
		(end 72.9488 -301.3964)
		(width 0.15494)
		(layer "In5.Cu")
		(net "RST_PEX0_S1_PERST_R_N")
	)
	(segment
		(start 396.54988 -293.99992)
		(end 396.0749 -293.52494)
		(width 0.254)
		(layer "F.Cu")
		(net "PCEPLL5_VDDA18_PEX3")
	)
	(via
		(at 396.0749 -293.52494)
		(size 0.4064)
		(drill 0.2032)
		(layers "F.Cu" "B.Cu")
		(net "PCEPLL5_VDDA18_PEX3")
	)
	(via
		(at 382.977644 -257.137916)
		(size 0.508)
		(drill 0.254)
		(layers "F.Cu" "B.Cu")
		(net "PCEPLL5_VDDA18_PEX3")
	)
	(via
		(at 384.374644 -257.137916)
		(size 0.508)
		(drill 0.254)
		(layers "F.Cu" "B.Cu")
		(net "PCEPLL5_VDDA18_PEX3")
	)
	(segment
		(start 396.0749 -293.8653)
		(end 396.0749 -293.52494)
		(width 0.3048)
		(layer "B.Cu")
		(net "PCEPLL5_VDDA18_PEX3")
	)
	(segment
		(start 396.0749 -293.10838)
		(end 396.0749 -293.52494)
		(width 0.3048)
		(layer "B.Cu")
		(net "PCEPLL5_VDDA18_PEX3")
	)
	(segment
		(start 396.54988 -297.79976)
		(end 396.0749 -298.27474)
		(width 0.249936)
		(layer "F.Cu")
		(net "SYSPLL_VDDA18_PEX3")
	)
	(via
		(at 396.0749 -298.27474)
		(size 0.4064)
		(drill 0.2032)
		(layers "F.Cu" "B.Cu")
		(net "SYSPLL_VDDA18_PEX3")
	)
	(via
		(at 380.01956 -280.693114)
		(size 0.508)
		(drill 0.254)
		(layers "F.Cu" "B.Cu")
		(net "SYSPLL_VDDA18_PEX3")
	)
	(via
		(at 381.41656 -280.693114)
		(size 0.508)
		(drill 0.254)
		(layers "F.Cu" "B.Cu")
		(net "SYSPLL_VDDA18_PEX3")
	)
	(segment
		(start 395.30274 -298.27474)
		(end 396.0749 -298.27474)
		(width 0.3048)
		(layer "B.Cu")
		(net "SYSPLL_VDDA18_PEX3")
	)
	(segment
		(start 395.12494 -297.32478)
		(end 395.59992 -296.8498)
		(width 0.249936)
		(layer "F.Cu")
		(net "PCEPLL2_VDDA18_PEX3")
	)
	(via
		(at 380.01956 -293.494714)
		(size 0.508)
		(drill 0.254)
		(layers "F.Cu" "B.Cu")
		(net "PCEPLL2_VDDA18_PEX3")
	)
	(via
		(at 381.41656 -293.494714)
		(size 0.508)
		(drill 0.254)
		(layers "F.Cu" "B.Cu")
		(net "PCEPLL2_VDDA18_PEX3")
	)
	(via
		(at 395.12494 -297.32478)
		(size 0.4064)
		(drill 0.2032)
		(layers "F.Cu" "B.Cu")
		(net "PCEPLL2_VDDA18_PEX3")
	)
	(segment
		(start 394.92174 -296.37482)
		(end 394.92174 -297.32478)
		(width 0.3048)
		(layer "B.Cu")
		(net "PCEPLL2_VDDA18_PEX3")
	)
	(segment
		(start 394.92174 -297.32478)
		(end 395.12494 -297.32478)
		(width 0.3048)
		(layer "B.Cu")
		(net "PCEPLL2_VDDA18_PEX3")
	)
	(segment
		(start 225.304096 -175.65624)
		(end 225.882962 -175.65624)
		(width 0.13208)
		(layer "F.Cu")
		(net "ADM1085_IN")
	)
	(segment
		(start 224.136204 -175.65624)
		(end 223.986344 -175.50638)
		(width 0.13208)
		(layer "F.Cu")
		(net "ADM1085_IN")
	)
	(segment
		(start 223.986344 -174.49038)
		(end 223.986344 -175.50638)
		(width 0.13208)
		(layer "F.Cu")
		(net "ADM1085_IN")
	)
	(segment
		(start 224.44202 -175.65624)
		(end 224.136204 -175.65624)
		(width 0.13208)
		(layer "F.Cu")
		(net "ADM1085_IN")
	)
	(segment
		(start 223.986344 -173.283626)
		(end 223.986344 -174.49038)
		(width 0.13208)
		(layer "F.Cu")
		(net "ADM1085_IN")
	)
	(segment
		(start 224.767394 -175.330866)
		(end 224.978722 -175.330866)
		(width 0.13208)
		(layer "F.Cu")
		(net "ADM1085_IN")
	)
	(segment
		(start 224.978722 -175.330866)
		(end 225.304096 -175.65624)
		(width 0.13208)
		(layer "F.Cu")
		(net "ADM1085_IN")
	)
	(segment
		(start 224.767394 -175.330866)
		(end 224.44202 -175.65624)
		(width 0.13208)
		(layer "F.Cu")
		(net "ADM1085_IN")
	)
	(via
		(at 224.767394 -175.330866)
		(size 0.508)
		(drill 0.254)
		(layers "F.Cu" "B.Cu")
		(net "ADM1085_IN")
	)
	(via
		(at 223.986344 -173.283626)
		(size 0.762)
		(drill 0.381)
		(layers "F.Cu" "B.Cu")
		(net "ADM1085_IN")
	)
	(segment
		(start 223.941132 -175.825404)
		(end 224.43567 -175.330866)
		(width 0.13208)
		(layer "B.Cu")
		(net "ADM1085_IN")
	)
	(segment
		(start 224.376742 -177.454814)
		(end 223.941132 -177.019204)
		(width 0.13208)
		(layer "B.Cu")
		(net "ADM1085_IN")
	)
	(segment
		(start 223.941132 -177.019204)
		(end 223.941132 -175.825404)
		(width 0.13208)
		(layer "B.Cu")
		(net "ADM1085_IN")
	)
	(segment
		(start 225.998532 -177.454814)
		(end 224.376742 -177.454814)
		(width 0.13208)
		(layer "B.Cu")
		(net "ADM1085_IN")
	)
	(segment
		(start 226.321874 -177.131472)
		(end 225.998532 -177.454814)
		(width 0.13208)
		(layer "B.Cu")
		(net "ADM1085_IN")
	)
	(segment
		(start 226.321874 -176.80305)
		(end 226.321874 -177.131472)
		(width 0.13208)
		(layer "B.Cu")
		(net "ADM1085_IN")
	)
	(segment
		(start 224.43567 -175.330866)
		(end 224.767394 -175.330866)
		(width 0.13208)
		(layer "B.Cu")
		(net "ADM1085_IN")
	)
	(via
		(at 263.930892 -295.933114)
		(size 0.508)
		(drill 0.254)
		(layers "F.Cu" "B.Cu")
		(net "PCEPLL0_VDDA18_PEX2_R")
	)
	(segment
		(start 91.963748 -298.448476)
		(end 91.268804 -298.448476)
		(width 0.13208)
		(layer "F.Cu")
		(net "I2C_PEX0_HOST_R_SCL")
	)
	(segment
		(start 92.019628 -298.392596)
		(end 91.963748 -298.448476)
		(width 0.13208)
		(layer "F.Cu")
		(net "I2C_PEX0_HOST_R_SCL")
	)
	(segment
		(start 90.887042 -296.64533)
		(end 90.887042 -297.27398)
		(width 0.13208)
		(layer "F.Cu")
		(net "I2C_PEX0_HOST_R_SCL")
	)
	(segment
		(start 91.268804 -298.448476)
		(end 91.044522 -298.224194)
		(width 0.13208)
		(layer "F.Cu")
		(net "I2C_PEX0_HOST_R_SCL")
	)
	(segment
		(start 90.964512 -295.647872)
		(end 90.964512 -296.56786)
		(width 0.13208)
		(layer "F.Cu")
		(net "I2C_PEX0_HOST_R_SCL")
	)
	(segment
		(start 90.9193 -296.613072)
		(end 90.887042 -296.64533)
		(width 0.13208)
		(layer "F.Cu")
		(net "I2C_PEX0_HOST_R_SCL")
	)
	(segment
		(start 90.887042 -298.065698)
		(end 91.044522 -298.223178)
		(width 0.13208)
		(layer "F.Cu")
		(net "I2C_PEX0_HOST_R_SCL")
	)
	(segment
		(start 90.887042 -297.27398)
		(end 90.887042 -298.065698)
		(width 0.13208)
		(layer "F.Cu")
		(net "I2C_PEX0_HOST_R_SCL")
	)
	(segment
		(start 90.964512 -296.56786)
		(end 90.9193 -296.613072)
		(width 0.13208)
		(layer "F.Cu")
		(net "I2C_PEX0_HOST_R_SCL")
	)
	(segment
		(start 91.044522 -298.223178)
		(end 91.044522 -298.224194)
		(width 0.13208)
		(layer "F.Cu")
		(net "I2C_PEX0_HOST_R_SCL")
	)
	(via
		(at 90.9193 -296.613072)
		(size 0.508)
		(drill 0.254)
		(layers "F.Cu" "B.Cu")
		(net "I2C_PEX0_HOST_R_SCL")
	)
	(segment
		(start 335.693766 -222.38716)
		(end 335.29397 -222.786956)
		(width 0.13208)
		(layer "F.Cu")
		(net "RST_PEX3_PERST_N")
	)
	(via
		(at 335.29397 -222.786956)
		(size 0.4572)
		(drill 0.254)
		(layers "F.Cu" "B.Cu")
		(net "RST_PEX3_PERST_N")
	)
	(via
		(at 331.2287 -222.2246)
		(size 0.6604)
		(drill 0.3302)
		(layers "F.Cu" "B.Cu")
		(net "RST_PEX3_PERST_N")
	)
	(segment
		(start 330.676758 -222.4532)
		(end 331.2287 -222.2246)
		(width 0.13208)
		(layer "B.Cu")
		(net "RST_PEX3_PERST_N")
	)
	(segment
		(start 331.586586 -222.2246)
		(end 331.2287 -222.2246)
		(width 0.13208)
		(layer "B.Cu")
		(net "RST_PEX3_PERST_N")
	)
	(segment
		(start 333.052166 -222.435166)
		(end 332.09484 -222.435166)
		(width 0.13208)
		(layer "B.Cu")
		(net "RST_PEX3_PERST_N")
	)
	(segment
		(start 330.09205 -222.4532)
		(end 330.676758 -222.4532)
		(width 0.13208)
		(layer "B.Cu")
		(net "RST_PEX3_PERST_N")
	)
	(segment
		(start 332.09484 -222.435166)
		(end 331.586586 -222.2246)
		(width 0.13208)
		(layer "B.Cu")
		(net "RST_PEX3_PERST_N")
	)
	(segment
		(start 335.29397 -222.786956)
		(end 333.403956 -222.786956)
		(width 0.13208)
		(layer "B.Cu")
		(net "RST_PEX3_PERST_N")
	)
	(segment
		(start 333.403956 -222.786956)
		(end 333.052166 -222.435166)
		(width 0.13208)
		(layer "B.Cu")
		(net "RST_PEX3_PERST_N")
	)
	(via
		(at 263.930892 -279.931114)
		(size 0.508)
		(drill 0.254)
		(layers "F.Cu" "B.Cu")
		(net "SYSPLL_VDDA18_PEX2_R")
	)
	(segment
		(start 361.58805 -177.038)
		(end 361.90809 -177.35804)
		(width 0.13208)
		(layer "F.Cu")
		(net "RST_PEX_SSD6_PERST_N")
	)
	(segment
		(start 361.90809 -177.35804)
		(end 363.412786 -177.35804)
		(width 0.13208)
		(layer "F.Cu")
		(net "RST_PEX_SSD6_PERST_N")
	)
	(segment
		(start 363.671866 -177.61712)
		(end 365.133382 -177.61712)
		(width 0.13208)
		(layer "F.Cu")
		(net "RST_PEX_SSD6_PERST_N")
	)
	(segment
		(start 365.133382 -177.61712)
		(end 366.263936 -177.61712)
		(width 0.13208)
		(layer "F.Cu")
		(net "RST_PEX_SSD6_PERST_N")
	)
	(segment
		(start 363.412786 -177.35804)
		(end 363.671866 -177.61712)
		(width 0.13208)
		(layer "F.Cu")
		(net "RST_PEX_SSD6_PERST_N")
	)
	(via
		(at 365.133382 -177.61712)
		(size 0.508)
		(drill 0.254)
		(layers "F.Cu" "B.Cu")
		(net "RST_PEX_SSD6_PERST_N")
	)
	(via
		(at 263.930892 -299.133514)
		(size 0.508)
		(drill 0.254)
		(layers "F.Cu" "B.Cu")
		(net "PCEPLL1_VDDA18_PEX2_R")
	)
	(segment
		(start 90.314272 -295.647872)
		(end 90.314272 -296.476674)
		(width 0.13208)
		(layer "F.Cu")
		(net "I2C_PEX0_HOST_R_SDA")
	)
	(segment
		(start 90.177874 -296.613072)
		(end 89.644474 -296.613072)
		(width 0.13208)
		(layer "F.Cu")
		(net "I2C_PEX0_HOST_R_SDA")
	)
	(segment
		(start 89.898474 -298.06773)
		(end 90.021156 -298.190412)
		(width 0.13208)
		(layer "F.Cu")
		(net "I2C_PEX0_HOST_R_SDA")
	)
	(segment
		(start 90.021156 -298.47286)
		(end 89.005156 -298.47286)
		(width 0.13208)
		(layer "F.Cu")
		(net "I2C_PEX0_HOST_R_SDA")
	)
	(segment
		(start 89.898474 -297.46448)
		(end 89.898474 -298.06773)
		(width 0.13208)
		(layer "F.Cu")
		(net "I2C_PEX0_HOST_R_SDA")
	)
	(segment
		(start 90.021156 -298.190412)
		(end 90.021156 -298.47286)
		(width 0.13208)
		(layer "F.Cu")
		(net "I2C_PEX0_HOST_R_SDA")
	)
	(segment
		(start 89.898474 -297.46448)
		(end 89.898474 -296.867072)
		(width 0.13208)
		(layer "F.Cu")
		(net "I2C_PEX0_HOST_R_SDA")
	)
	(segment
		(start 89.898474 -296.867072)
		(end 89.644474 -296.613072)
		(width 0.13208)
		(layer "F.Cu")
		(net "I2C_PEX0_HOST_R_SDA")
	)
	(segment
		(start 90.314272 -296.476674)
		(end 90.177874 -296.613072)
		(width 0.13208)
		(layer "F.Cu")
		(net "I2C_PEX0_HOST_R_SDA")
	)
	(via
		(at 89.644474 -296.613072)
		(size 0.508)
		(drill 0.254)
		(layers "F.Cu" "B.Cu")
		(net "I2C_PEX0_HOST_R_SDA")
	)
	(segment
		(start 331.965554 -223.972882)
		(end 332.037436 -223.901)
		(width 0.13208)
		(layer "F.Cu")
		(net "RST_PEX0_PERST_N")
	)
	(segment
		(start 330.576428 -223.972882)
		(end 331.965554 -223.972882)
		(width 0.13208)
		(layer "F.Cu")
		(net "RST_PEX0_PERST_N")
	)
	(segment
		(start 333.381096 -223.901)
		(end 333.69885 -223.583246)
		(width 0.13208)
		(layer "F.Cu")
		(net "RST_PEX0_PERST_N")
	)
	(segment
		(start 333.69885 -223.583246)
		(end 334.49768 -223.583246)
		(width 0.13208)
		(layer "F.Cu")
		(net "RST_PEX0_PERST_N")
	)
	(segment
		(start 334.49768 -223.583246)
		(end 334.89392 -223.187006)
		(width 0.13208)
		(layer "F.Cu")
		(net "RST_PEX0_PERST_N")
	)
	(segment
		(start 332.037436 -223.901)
		(end 333.381096 -223.901)
		(width 0.13208)
		(layer "F.Cu")
		(net "RST_PEX0_PERST_N")
	)
	(segment
		(start 330.576428 -223.972882)
		(end 327.93178 -223.972882)
		(width 0.13208)
		(layer "F.Cu")
		(net "RST_PEX0_PERST_N")
	)
	(via
		(at 330.576428 -223.972882)
		(size 0.762)
		(drill 0.381)
		(layers "F.Cu" "B.Cu")
		(net "RST_PEX0_PERST_N")
	)
	(segment
		(start 229.167944 -176.360328)
		(end 229.533196 -176.72558)
		(width 0.13208)
		(layer "F.Cu")
		(net "THRESHOLD")
	)
	(segment
		(start 229.533196 -176.72558)
		(end 230.349044 -176.72558)
		(width 0.13208)
		(layer "F.Cu")
		(net "THRESHOLD")
	)
	(segment
		(start 229.113842 -176.306226)
		(end 229.167944 -176.360328)
		(width 0.13208)
		(layer "F.Cu")
		(net "THRESHOLD")
	)
	(segment
		(start 227.520754 -176.306226)
		(end 229.113842 -176.306226)
		(width 0.13208)
		(layer "F.Cu")
		(net "THRESHOLD")
	)
	(via
		(at 229.167944 -176.360328)
		(size 0.762)
		(drill 0.254)
		(layers "F.Cu" "B.Cu")
		(net "THRESHOLD")
	)
	(segment
		(start 229.110794 -176.303178)
		(end 229.167944 -176.360328)
		(width 0.13208)
		(layer "B.Cu")
		(net "THRESHOLD")
	)
	(segment
		(start 227.071936 -176.303178)
		(end 229.110794 -176.303178)
		(width 0.13208)
		(layer "B.Cu")
		(net "THRESHOLD")
	)
	(via
		(at 266.888976 -259.576316)
		(size 0.508)
		(drill 0.254)
		(layers "F.Cu" "B.Cu")
		(net "PCEPLL3_VDDA18_PEX2_R")
	)
	(segment
		(start 363.686852 -178.267106)
		(end 363.995462 -178.267106)
		(width 0.13208)
		(layer "F.Cu")
		(net "SSD6_PEX_PWR_EN")
	)
	(segment
		(start 361.58805 -178.054)
		(end 363.473746 -178.054)
		(width 0.13208)
		(layer "F.Cu")
		(net "SSD6_PEX_PWR_EN")
	)
	(segment
		(start 363.473746 -178.054)
		(end 363.686852 -178.267106)
		(width 0.13208)
		(layer "F.Cu")
		(net "SSD6_PEX_PWR_EN")
	)
	(segment
		(start 363.995462 -178.267106)
		(end 366.263936 -178.267106)
		(width 0.13208)
		(layer "F.Cu")
		(net "SSD6_PEX_PWR_EN")
	)
	(via
		(at 363.995462 -178.267106)
		(size 0.508)
		(drill 0.254)
		(layers "F.Cu" "B.Cu")
		(net "SSD6_PEX_PWR_EN")
	)
	(segment
		(start 225.067622 -215.104218)
		(end 224.667826 -214.704422)
		(width 0.13208)
		(layer "F.Cu")
		(net "RST_BIC_USB_HUB_N")
	)
	(via
		(at 224.667826 -214.704422)
		(size 0.4572)
		(drill 0.254)
		(layers "F.Cu" "B.Cu")
		(net "RST_BIC_USB_HUB_N")
	)
	(via
		(at 222.45828 -214.339424)
		(size 0.6604)
		(drill 0.3302)
		(layers "F.Cu" "B.Cu")
		(net "RST_BIC_USB_HUB_N")
	)
	(segment
		(start 220.336364 -214.525098)
		(end 222.272606 -214.525098)
		(width 0.13208)
		(layer "B.Cu")
		(net "RST_BIC_USB_HUB_N")
	)
	(segment
		(start 217.635836 -213.222586)
		(end 219.033852 -213.222586)
		(width 0.13208)
		(layer "B.Cu")
		(net "RST_BIC_USB_HUB_N")
	)
	(segment
		(start 224.27565 -214.541862)
		(end 224.04197 -214.308182)
		(width 0.0889)
		(layer "B.Cu")
		(net "RST_BIC_USB_HUB_N")
	)
	(segment
		(start 222.489522 -214.308182)
		(end 222.45828 -214.339424)
		(width 0.13208)
		(layer "B.Cu")
		(net "RST_BIC_USB_HUB_N")
	)
	(segment
		(start 222.272606 -214.525098)
		(end 222.45828 -214.339424)
		(width 0.13208)
		(layer "B.Cu")
		(net "RST_BIC_USB_HUB_N")
	)
	(segment
		(start 224.04197 -214.308182)
		(end 222.489522 -214.308182)
		(width 0.0889)
		(layer "B.Cu")
		(net "RST_BIC_USB_HUB_N")
	)
	(segment
		(start 224.667826 -214.704422)
		(end 224.27565 -214.541862)
		(width 0.0889)
		(layer "B.Cu")
		(net "RST_BIC_USB_HUB_N")
	)
	(segment
		(start 219.033852 -213.222586)
		(end 220.336364 -214.525098)
		(width 0.13208)
		(layer "B.Cu")
		(net "RST_BIC_USB_HUB_N")
	)
	(via
		(at 260.24078 -260.096762)
		(size 0.508)
		(drill 0.254)
		(layers "F.Cu" "B.Cu")
		(net "P1V8_VDDA_PEX2_R")
	)
	(segment
		(start 92.377768 -300.240954)
		(end 92.387166 -300.250352)
		(width 0.13208)
		(layer "F.Cu")
		(net "I2C_PEX0_HOST_SCL")
	)
	(segment
		(start 93.020388 -300.123352)
		(end 93.020388 -299.77969)
		(width 0.13208)
		(layer "F.Cu")
		(net "I2C_PEX0_HOST_SCL")
	)
	(segment
		(start 92.351606 -299.77969)
		(end 93.020388 -299.77969)
		(width 0.13208)
		(layer "F.Cu")
		(net "I2C_PEX0_HOST_SCL")
	)
	(segment
		(start 92.019628 -299.447712)
		(end 92.351606 -299.77969)
		(width 0.13208)
		(layer "F.Cu")
		(net "I2C_PEX0_HOST_SCL")
	)
	(segment
		(start 92.387166 -300.250352)
		(end 92.893388 -300.250352)
		(width 0.13208)
		(layer "F.Cu")
		(net "I2C_PEX0_HOST_SCL")
	)
	(segment
		(start 92.019628 -299.192696)
		(end 92.019628 -299.447712)
		(width 0.13208)
		(layer "F.Cu")
		(net "I2C_PEX0_HOST_SCL")
	)
	(segment
		(start 91.379294 -300.240954)
		(end 92.377768 -300.240954)
		(width 0.13208)
		(layer "F.Cu")
		(net "I2C_PEX0_HOST_SCL")
	)
	(segment
		(start 92.893388 -300.250352)
		(end 93.020388 -300.123352)
		(width 0.13208)
		(layer "F.Cu")
		(net "I2C_PEX0_HOST_SCL")
	)
	(via
		(at 93.020388 -299.77969)
		(size 0.508)
		(drill 0.254)
		(layers "F.Cu" "B.Cu")
		(net "I2C_PEX0_HOST_SCL")
	)
	(segment
		(start 230.4542 -231.81945)
		(end 230.4542 -232.134156)
		(width 0.13208)
		(layer "F.Cu")
		(net "NIC1_MAIN_PWR_BIC_EN_R")
	)
	(segment
		(start 230.4542 -232.134156)
		(end 230.791512 -232.471468)
		(width 0.13208)
		(layer "F.Cu")
		(net "NIC1_MAIN_PWR_BIC_EN_R")
	)
	(segment
		(start 350.893888 -214.387176)
		(end 351.293684 -213.98738)
		(width 0.13208)
		(layer "F.Cu")
		(net "NIC1_MAIN_PWR_BIC_EN_R")
	)
	(via
		(at 351.293684 -213.98738)
		(size 0.4572)
		(drill 0.254)
		(layers "F.Cu" "B.Cu")
		(net "NIC1_MAIN_PWR_BIC_EN_R")
	)
	(via
		(at 257.340354 -192.208404)
		(size 0.508)
		(drill 0.254)
		(layers "F.Cu" "B.Cu")
		(net "NIC1_MAIN_PWR_BIC_EN_R")
	)
	(via
		(at 230.791512 -232.471468)
		(size 0.508)
		(drill 0.254)
		(layers "F.Cu" "B.Cu")
		(net "NIC1_MAIN_PWR_BIC_EN_R")
	)
	(segment
		(start 237.480602 -227.313998)
		(end 236.7788 -228.0158)
		(width 0.15494)
		(layer "In7.Cu")
		(net "NIC1_MAIN_PWR_BIC_EN_R")
	)
	(segment
		(start 247.510046 -214.2998)
		(end 247.507506 -214.30234)
		(width 0.15494)
		(layer "In7.Cu")
		(net "NIC1_MAIN_PWR_BIC_EN_R")
	)
	(segment
		(start 257.340354 -195.700142)
		(end 249.936 -203.104496)
		(width 0.15494)
		(layer "In7.Cu")
		(net "NIC1_MAIN_PWR_BIC_EN_R")
	)
	(segment
		(start 247.84304 -208.81467)
		(end 248.515886 -209.487516)
		(width 0.15494)
		(layer "In7.Cu")
		(net "NIC1_MAIN_PWR_BIC_EN_R")
	)
	(segment
		(start 249.936 -203.104496)
		(end 249.936 -204.795628)
		(width 0.15494)
		(layer "In7.Cu")
		(net "NIC1_MAIN_PWR_BIC_EN_R")
	)
	(segment
		(start 245.214902 -223.174306)
		(end 241.07521 -227.313998)
		(width 0.15494)
		(layer "In7.Cu")
		(net "NIC1_MAIN_PWR_BIC_EN_R")
	)
	(segment
		(start 247.507506 -214.30234)
		(end 247.393714 -214.30234)
		(width 0.15494)
		(layer "In7.Cu")
		(net "NIC1_MAIN_PWR_BIC_EN_R")
	)
	(segment
		(start 248.1834 -206.548228)
		(end 248.1834 -207.467454)
		(width 0.15494)
		(layer "In7.Cu")
		(net "NIC1_MAIN_PWR_BIC_EN_R")
	)
	(segment
		(start 249.73026 -210.189572)
		(end 249.73026 -213.15934)
		(width 0.15494)
		(layer "In7.Cu")
		(net "NIC1_MAIN_PWR_BIC_EN_R")
	)
	(segment
		(start 249.936 -204.795628)
		(end 248.1834 -206.548228)
		(width 0.15494)
		(layer "In7.Cu")
		(net "NIC1_MAIN_PWR_BIC_EN_R")
	)
	(segment
		(start 249.73026 -213.15934)
		(end 248.5898 -214.2998)
		(width 0.15494)
		(layer "In7.Cu")
		(net "NIC1_MAIN_PWR_BIC_EN_R")
	)
	(segment
		(start 248.1834 -207.467454)
		(end 248.176542 -207.474312)
		(width 0.15494)
		(layer "In7.Cu")
		(net "NIC1_MAIN_PWR_BIC_EN_R")
	)
	(segment
		(start 234.188254 -228.0158)
		(end 230.791512 -231.412542)
		(width 0.15494)
		(layer "In7.Cu")
		(net "NIC1_MAIN_PWR_BIC_EN_R")
	)
	(segment
		(start 241.07521 -227.313998)
		(end 237.480602 -227.313998)
		(width 0.15494)
		(layer "In7.Cu")
		(net "NIC1_MAIN_PWR_BIC_EN_R")
	)
	(segment
		(start 249.6058 -210.058)
		(end 249.6058 -210.065112)
		(width 0.15494)
		(layer "In7.Cu")
		(net "NIC1_MAIN_PWR_BIC_EN_R")
	)
	(segment
		(start 247.393714 -214.30234)
		(end 245.214902 -216.481152)
		(width 0.15494)
		(layer "In7.Cu")
		(net "NIC1_MAIN_PWR_BIC_EN_R")
	)
	(segment
		(start 245.214902 -216.481152)
		(end 245.214902 -223.174306)
		(width 0.15494)
		(layer "In7.Cu")
		(net "NIC1_MAIN_PWR_BIC_EN_R")
	)
	(segment
		(start 249.035316 -209.487516)
		(end 249.6058 -210.058)
		(width 0.15494)
		(layer "In7.Cu")
		(net "NIC1_MAIN_PWR_BIC_EN_R")
	)
	(segment
		(start 248.5898 -214.2998)
		(end 247.510046 -214.2998)
		(width 0.15494)
		(layer "In7.Cu")
		(net "NIC1_MAIN_PWR_BIC_EN_R")
	)
	(segment
		(start 230.791512 -231.412542)
		(end 230.791512 -232.471468)
		(width 0.15494)
		(layer "In7.Cu")
		(net "NIC1_MAIN_PWR_BIC_EN_R")
	)
	(segment
		(start 247.84304 -208.41716)
		(end 247.84304 -208.81467)
		(width 0.15494)
		(layer "In7.Cu")
		(net "NIC1_MAIN_PWR_BIC_EN_R")
	)
	(segment
		(start 249.6058 -210.065112)
		(end 249.73026 -210.189572)
		(width 0.15494)
		(layer "In7.Cu")
		(net "NIC1_MAIN_PWR_BIC_EN_R")
	)
	(segment
		(start 248.176542 -207.474312)
		(end 248.176542 -208.083658)
		(width 0.15494)
		(layer "In7.Cu")
		(net "NIC1_MAIN_PWR_BIC_EN_R")
	)
	(segment
		(start 248.176542 -208.083658)
		(end 247.84304 -208.41716)
		(width 0.15494)
		(layer "In7.Cu")
		(net "NIC1_MAIN_PWR_BIC_EN_R")
	)
	(segment
		(start 236.7788 -228.0158)
		(end 234.188254 -228.0158)
		(width 0.15494)
		(layer "In7.Cu")
		(net "NIC1_MAIN_PWR_BIC_EN_R")
	)
	(segment
		(start 248.515886 -209.487516)
		(end 249.035316 -209.487516)
		(width 0.15494)
		(layer "In7.Cu")
		(net "NIC1_MAIN_PWR_BIC_EN_R")
	)
	(segment
		(start 257.340354 -192.208404)
		(end 257.340354 -195.700142)
		(width 0.15494)
		(layer "In7.Cu")
		(net "NIC1_MAIN_PWR_BIC_EN_R")
	)
	(segment
		(start 278.124412 -198.70674)
		(end 272.358358 -192.940686)
		(width 0.15494)
		(layer "In15.Cu")
		(net "NIC1_MAIN_PWR_BIC_EN_R")
	)
	(segment
		(start 337.03387 -199.95134)
		(end 336.03438 -198.95185)
		(width 0.15494)
		(layer "In15.Cu")
		(net "NIC1_MAIN_PWR_BIC_EN_R")
	)
	(segment
		(start 345.9734 -203.6826)
		(end 343.64295 -201.35215)
		(width 0.15494)
		(layer "In15.Cu")
		(net "NIC1_MAIN_PWR_BIC_EN_R")
	)
	(segment
		(start 343.64295 -201.35215)
		(end 338.519516 -201.35215)
		(width 0.15494)
		(layer "In15.Cu")
		(net "NIC1_MAIN_PWR_BIC_EN_R")
	)
	(segment
		(start 349.782892 -206.167736)
		(end 349.782892 -205.941422)
		(width 0.15494)
		(layer "In15.Cu")
		(net "NIC1_MAIN_PWR_BIC_EN_R")
	)
	(segment
		(start 337.803236 -200.63587)
		(end 337.36534 -200.63587)
		(width 0.15494)
		(layer "In15.Cu")
		(net "NIC1_MAIN_PWR_BIC_EN_R")
	)
	(segment
		(start 259.103622 -192.208404)
		(end 257.340354 -192.208404)
		(width 0.15494)
		(layer "In15.Cu")
		(net "NIC1_MAIN_PWR_BIC_EN_R")
	)
	(segment
		(start 351.293684 -213.98738)
		(end 351.701354 -213.57971)
		(width 0.15494)
		(layer "In15.Cu")
		(net "NIC1_MAIN_PWR_BIC_EN_R")
	)
	(segment
		(start 326.415654 -199.0344)
		(end 325.68388 -199.766174)
		(width 0.15494)
		(layer "In15.Cu")
		(net "NIC1_MAIN_PWR_BIC_EN_R")
	)
	(segment
		(start 272.358358 -192.940686)
		(end 259.835904 -192.940686)
		(width 0.15494)
		(layer "In15.Cu")
		(net "NIC1_MAIN_PWR_BIC_EN_R")
	)
	(segment
		(start 347.87713 -203.6826)
		(end 345.9734 -203.6826)
		(width 0.15494)
		(layer "In15.Cu")
		(net "NIC1_MAIN_PWR_BIC_EN_R")
	)
	(segment
		(start 337.36534 -200.63587)
		(end 337.03387 -200.3044)
		(width 0.15494)
		(layer "In15.Cu")
		(net "NIC1_MAIN_PWR_BIC_EN_R")
	)
	(segment
		(start 323.93763 -199.766174)
		(end 322.878196 -198.70674)
		(width 0.15494)
		(layer "In15.Cu")
		(net "NIC1_MAIN_PWR_BIC_EN_R")
	)
	(segment
		(start 348.20987 -204.01534)
		(end 347.87713 -203.6826)
		(width 0.15494)
		(layer "In15.Cu")
		(net "NIC1_MAIN_PWR_BIC_EN_R")
	)
	(segment
		(start 351.701354 -213.57971)
		(end 351.701354 -208.086198)
		(width 0.15494)
		(layer "In15.Cu")
		(net "NIC1_MAIN_PWR_BIC_EN_R")
	)
	(segment
		(start 349.782892 -205.941422)
		(end 348.20987 -204.3684)
		(width 0.15494)
		(layer "In15.Cu")
		(net "NIC1_MAIN_PWR_BIC_EN_R")
	)
	(segment
		(start 328.5236 -199.0344)
		(end 326.415654 -199.0344)
		(width 0.15494)
		(layer "In15.Cu")
		(net "NIC1_MAIN_PWR_BIC_EN_R")
	)
	(segment
		(start 322.878196 -198.70674)
		(end 278.124412 -198.70674)
		(width 0.15494)
		(layer "In15.Cu")
		(net "NIC1_MAIN_PWR_BIC_EN_R")
	)
	(segment
		(start 328.60615 -198.95185)
		(end 328.5236 -199.0344)
		(width 0.15494)
		(layer "In15.Cu")
		(net "NIC1_MAIN_PWR_BIC_EN_R")
	)
	(segment
		(start 351.701354 -208.086198)
		(end 349.782892 -206.167736)
		(width 0.15494)
		(layer "In15.Cu")
		(net "NIC1_MAIN_PWR_BIC_EN_R")
	)
	(segment
		(start 338.519516 -201.35215)
		(end 337.803236 -200.63587)
		(width 0.15494)
		(layer "In15.Cu")
		(net "NIC1_MAIN_PWR_BIC_EN_R")
	)
	(segment
		(start 336.03438 -198.95185)
		(end 328.60615 -198.95185)
		(width 0.15494)
		(layer "In15.Cu")
		(net "NIC1_MAIN_PWR_BIC_EN_R")
	)
	(segment
		(start 348.20987 -204.3684)
		(end 348.20987 -204.01534)
		(width 0.15494)
		(layer "In15.Cu")
		(net "NIC1_MAIN_PWR_BIC_EN_R")
	)
	(segment
		(start 325.68388 -199.766174)
		(end 323.93763 -199.766174)
		(width 0.15494)
		(layer "In15.Cu")
		(net "NIC1_MAIN_PWR_BIC_EN_R")
	)
	(segment
		(start 259.835904 -192.940686)
		(end 259.103622 -192.208404)
		(width 0.15494)
		(layer "In15.Cu")
		(net "NIC1_MAIN_PWR_BIC_EN_R")
	)
	(segment
		(start 337.03387 -200.3044)
		(end 337.03387 -199.95134)
		(width 0.15494)
		(layer "In15.Cu")
		(net "NIC1_MAIN_PWR_BIC_EN_R")
	)
	(segment
		(start 396.54988 -308.249828)
		(end 396.0749 -308.724808)
		(width 0.13208)
		(layer "F.Cu")
		(net "IRQ_PEX3_CLKREQ_INT_N")
	)
	(segment
		(start 375.161556 -308.89448)
		(end 375.682002 -309.414926)
		(width 0.13208)
		(layer "F.Cu")
		(net "IRQ_PEX3_CLKREQ_INT_N")
	)
	(via
		(at 375.682002 -309.414926)
		(size 0.508)
		(drill 0.254)
		(layers "F.Cu" "B.Cu")
		(net "IRQ_PEX3_CLKREQ_INT_N")
	)
	(via
		(at 396.0749 -308.724808)
		(size 0.4064)
		(drill 0.2032)
		(layers "F.Cu" "B.Cu")
		(net "IRQ_PEX3_CLKREQ_INT_N")
	)
	(segment
		(start 394.39088 -308.25948)
		(end 393.9032 -307.7718)
		(width 0.13208)
		(layer "B.Cu")
		(net "IRQ_PEX3_CLKREQ_INT_N")
	)
	(segment
		(start 395.640306 -308.25948)
		(end 394.39088 -308.25948)
		(width 0.13208)
		(layer "B.Cu")
		(net "IRQ_PEX3_CLKREQ_INT_N")
	)
	(segment
		(start 396.0749 -308.694074)
		(end 395.640306 -308.25948)
		(width 0.13208)
		(layer "B.Cu")
		(net "IRQ_PEX3_CLKREQ_INT_N")
	)
	(segment
		(start 396.0749 -308.724808)
		(end 396.0749 -308.694074)
		(width 0.13208)
		(layer "B.Cu")
		(net "IRQ_PEX3_CLKREQ_INT_N")
	)
	(segment
		(start 393.55522 -307.7718)
		(end 393.2936 -307.51018)
		(width 0.13208)
		(layer "B.Cu")
		(net "IRQ_PEX3_CLKREQ_INT_N")
	)
	(segment
		(start 382.037082 -306.787296)
		(end 379.409452 -309.414926)
		(width 0.13208)
		(layer "B.Cu")
		(net "IRQ_PEX3_CLKREQ_INT_N")
	)
	(segment
		(start 393.9032 -307.7718)
		(end 393.55522 -307.7718)
		(width 0.13208)
		(layer "B.Cu")
		(net "IRQ_PEX3_CLKREQ_INT_N")
	)
	(segment
		(start 393.2936 -307.2384)
		(end 392.842496 -306.787296)
		(width 0.13208)
		(layer "B.Cu")
		(net "IRQ_PEX3_CLKREQ_INT_N")
	)
	(segment
		(start 379.409452 -309.414926)
		(end 375.682002 -309.414926)
		(width 0.13208)
		(layer "B.Cu")
		(net "IRQ_PEX3_CLKREQ_INT_N")
	)
	(segment
		(start 393.2936 -307.51018)
		(end 393.2936 -307.2384)
		(width 0.13208)
		(layer "B.Cu")
		(net "IRQ_PEX3_CLKREQ_INT_N")
	)
	(segment
		(start 392.842496 -306.787296)
		(end 382.037082 -306.787296)
		(width 0.13208)
		(layer "B.Cu")
		(net "IRQ_PEX3_CLKREQ_INT_N")
	)
	(segment
		(start 227.467668 -215.904064)
		(end 227.067872 -215.504268)
		(width 0.13208)
		(layer "F.Cu")
		(net "RST_PEX_USB_HUB_N")
	)
	(via
		(at 227.067872 -215.504268)
		(size 0.4572)
		(drill 0.254)
		(layers "F.Cu" "B.Cu")
		(net "RST_PEX_USB_HUB_N")
	)
	(via
		(at 223.622616 -213.294468)
		(size 0.6604)
		(drill 0.3302)
		(layers "F.Cu" "B.Cu")
		(net "RST_PEX_USB_HUB_N")
	)
	(segment
		(start 223.622616 -213.294468)
		(end 224.61855 -213.294468)
		(width 0.13208)
		(layer "B.Cu")
		(net "RST_PEX_USB_HUB_N")
	)
	(segment
		(start 225.632264 -214.308182)
		(end 225.864166 -214.540084)
		(width 0.0889)
		(layer "B.Cu")
		(net "RST_PEX_USB_HUB_N")
	)
	(segment
		(start 220.244416 -213.1695)
		(end 223.497648 -213.1695)
		(width 0.13208)
		(layer "B.Cu")
		(net "RST_PEX_USB_HUB_N")
	)
	(segment
		(start 226.103434 -215.100662)
		(end 226.664266 -215.100662)
		(width 0.0889)
		(layer "B.Cu")
		(net "RST_PEX_USB_HUB_N")
	)
	(segment
		(start 225.311208 -214.308182)
		(end 225.632264 -214.308182)
		(width 0.0889)
		(layer "B.Cu")
		(net "RST_PEX_USB_HUB_N")
	)
	(segment
		(start 225.064066 -214.06104)
		(end 225.311208 -214.308182)
		(width 0.0889)
		(layer "B.Cu")
		(net "RST_PEX_USB_HUB_N")
	)
	(segment
		(start 225.864166 -214.540084)
		(end 225.864166 -214.861394)
		(width 0.0889)
		(layer "B.Cu")
		(net "RST_PEX_USB_HUB_N")
	)
	(segment
		(start 226.664266 -215.100662)
		(end 227.067872 -215.504268)
		(width 0.0889)
		(layer "B.Cu")
		(net "RST_PEX_USB_HUB_N")
	)
	(segment
		(start 223.497648 -213.1695)
		(end 223.622616 -213.294468)
		(width 0.13208)
		(layer "B.Cu")
		(net "RST_PEX_USB_HUB_N")
	)
	(segment
		(start 217.635836 -212.206586)
		(end 219.281502 -212.206586)
		(width 0.13208)
		(layer "B.Cu")
		(net "RST_PEX_USB_HUB_N")
	)
	(segment
		(start 225.864166 -214.861394)
		(end 226.103434 -215.100662)
		(width 0.0889)
		(layer "B.Cu")
		(net "RST_PEX_USB_HUB_N")
	)
	(segment
		(start 224.61855 -213.294468)
		(end 225.064066 -213.739984)
		(width 0.0889)
		(layer "B.Cu")
		(net "RST_PEX_USB_HUB_N")
	)
	(segment
		(start 219.281502 -212.206586)
		(end 220.244416 -213.1695)
		(width 0.13208)
		(layer "B.Cu")
		(net "RST_PEX_USB_HUB_N")
	)
	(segment
		(start 225.064066 -213.739984)
		(end 225.064066 -214.06104)
		(width 0.0889)
		(layer "B.Cu")
		(net "RST_PEX_USB_HUB_N")
	)
	(segment
		(start 239.164368 -228.411024)
		(end 239.164368 -228.830632)
		(width 0.4572)
		(layer "F.Cu")
		(net "P1V8_PLL0_PEX2")
	)
	(segment
		(start 238.891064 -228.13772)
		(end 239.164368 -228.411024)
		(width 0.4572)
		(layer "F.Cu")
		(net "P1V8_PLL0_PEX2")
	)
	(via
		(at 258.393438 -297.831256)
		(size 0.508)
		(drill 0.254)
		(layers "F.Cu" "B.Cu")
		(net "P1V8_PLL0_PEX2")
	)
	(via
		(at 262.83666 -258.274058)
		(size 0.508)
		(drill 0.254)
		(layers "F.Cu" "B.Cu")
		(net "P1V8_PLL0_PEX2")
	)
	(via
		(at 258.393438 -301.031656)
		(size 0.508)
		(drill 0.254)
		(layers "F.Cu" "B.Cu")
		(net "P1V8_PLL0_PEX2")
	)
	(via
		(at 258.393438 -291.430456)
		(size 0.508)
		(drill 0.254)
		(layers "F.Cu" "B.Cu")
		(net "P1V8_PLL0_PEX2")
	)
	(via
		(at 259.877306 -300.953424)
		(size 0.508)
		(drill 0.254)
		(layers "F.Cu" "B.Cu")
		(net "P1V8_PLL0_PEX2")
	)
	(via
		(at 262.386826 -237.698788)
		(size 0.508)
		(drill 0.254)
		(layers "F.Cu" "B.Cu")
		(net "P1V8_PLL0_PEX2")
	)
	(via
		(at 258.393438 -288.230056)
		(size 0.508)
		(drill 0.254)
		(layers "F.Cu" "B.Cu")
		(net "P1V8_PLL0_PEX2")
	)
	(via
		(at 260.939026 -238.333788)
		(size 0.508)
		(drill 0.254)
		(layers "F.Cu" "B.Cu")
		(net "P1V8_PLL0_PEX2")
	)
	(via
		(at 259.878576 -291.430456)
		(size 0.508)
		(drill 0.254)
		(layers "F.Cu" "B.Cu")
		(net "P1V8_PLL0_PEX2")
	)
	(via
		(at 260.386322 -261.790688)
		(size 0.508)
		(drill 0.254)
		(layers "F.Cu" "B.Cu")
		(net "P1V8_PLL0_PEX2")
	)
	(via
		(at 258.571492 -256.45237)
		(size 0.508)
		(drill 0.254)
		(layers "F.Cu" "B.Cu")
		(net "P1V8_PLL0_PEX2")
	)
	(via
		(at 262.386826 -236.987588)
		(size 0.508)
		(drill 0.254)
		(layers "F.Cu" "B.Cu")
		(net "P1V8_PLL0_PEX2")
	)
	(via
		(at 261.828026 -238.359188)
		(size 0.508)
		(drill 0.254)
		(layers "F.Cu" "B.Cu")
		(net "P1V8_PLL0_PEX2")
	)
	(via
		(at 259.883148 -298.30903)
		(size 0.508)
		(drill 0.254)
		(layers "F.Cu" "B.Cu")
		(net "P1V8_PLL0_PEX2")
	)
	(via
		(at 259.878576 -288.230056)
		(size 0.508)
		(drill 0.254)
		(layers "F.Cu" "B.Cu")
		(net "P1V8_PLL0_PEX2")
	)
	(via
		(at 261.351522 -261.474458)
		(size 0.508)
		(drill 0.254)
		(layers "F.Cu" "B.Cu")
		(net "P1V8_PLL0_PEX2")
	)
	(via
		(at 262.83666 -261.474458)
		(size 0.508)
		(drill 0.254)
		(layers "F.Cu" "B.Cu")
		(net "P1V8_PLL0_PEX2")
	)
	(via
		(at 258.393438 -294.630856)
		(size 0.508)
		(drill 0.254)
		(layers "F.Cu" "B.Cu")
		(net "P1V8_PLL0_PEX2")
	)
	(via
		(at 258.393438 -281.829256)
		(size 0.508)
		(drill 0.254)
		(layers "F.Cu" "B.Cu")
		(net "P1V8_PLL0_PEX2")
	)
	(via
		(at 259.878576 -281.829256)
		(size 0.508)
		(drill 0.254)
		(layers "F.Cu" "B.Cu")
		(net "P1V8_PLL0_PEX2")
	)
	(via
		(at 257.860292 -256.45237)
		(size 0.508)
		(drill 0.254)
		(layers "F.Cu" "B.Cu")
		(net "P1V8_PLL0_PEX2")
	)
	(via
		(at 259.878576 -294.630856)
		(size 0.508)
		(drill 0.254)
		(layers "F.Cu" "B.Cu")
		(net "P1V8_PLL0_PEX2")
	)
	(via
		(at 259.878576 -285.029656)
		(size 0.508)
		(drill 0.254)
		(layers "F.Cu" "B.Cu")
		(net "P1V8_PLL0_PEX2")
	)
	(via
		(at 261.351522 -258.274058)
		(size 0.508)
		(drill 0.254)
		(layers "F.Cu" "B.Cu")
		(net "P1V8_PLL0_PEX2")
	)
	(via
		(at 239.164368 -228.830632)
		(size 0.508)
		(drill 0.254)
		(layers "F.Cu" "B.Cu")
		(net "P1V8_PLL0_PEX2")
	)
	(via
		(at 258.393438 -285.029656)
		(size 0.508)
		(drill 0.254)
		(layers "F.Cu" "B.Cu")
		(net "P1V8_PLL0_PEX2")
	)
	(via
		(at 246.746522 -238.462312)
		(size 0.508)
		(drill 0.254)
		(layers "F.Cu" "B.Cu")
		(net "P1V8_PLL0_PEX2")
	)
	(segment
		(start 240.68151 -235.142024)
		(end 239.933988 -234.394502)
		(width 0.381)
		(layer "B.Cu")
		(net "P1V8_PLL0_PEX2")
	)
	(segment
		(start 245.606062 -239.602772)
		(end 242.500912 -239.602772)
		(width 0.381)
		(layer "B.Cu")
		(net "P1V8_PLL0_PEX2")
	)
	(segment
		(start 239.164368 -229.658672)
		(end 239.164368 -228.830632)
		(width 0.381)
		(layer "B.Cu")
		(net "P1V8_PLL0_PEX2")
	)
	(segment
		(start 239.933988 -234.394502)
		(end 239.933988 -230.428292)
		(width 0.381)
		(layer "B.Cu")
		(net "P1V8_PLL0_PEX2")
	)
	(segment
		(start 239.933988 -230.428292)
		(end 239.164368 -229.658672)
		(width 0.381)
		(layer "B.Cu")
		(net "P1V8_PLL0_PEX2")
	)
	(segment
		(start 240.68151 -237.78337)
		(end 240.68151 -235.142024)
		(width 0.381)
		(layer "B.Cu")
		(net "P1V8_PLL0_PEX2")
	)
	(segment
		(start 246.746522 -238.462312)
		(end 245.606062 -239.602772)
		(width 0.381)
		(layer "B.Cu")
		(net "P1V8_PLL0_PEX2")
	)
	(segment
		(start 242.500912 -239.602772)
		(end 240.68151 -237.78337)
		(width 0.381)
		(layer "B.Cu")
		(net "P1V8_PLL0_PEX2")
	)
	(segment
		(start 260.237986 -239.034828)
		(end 260.939026 -238.333788)
		(width 0.254)
		(layer "In13.Cu")
		(net "P1V8_PLL0_PEX2")
	)
	(segment
		(start 247.319038 -239.034828)
		(end 260.237986 -239.034828)
		(width 0.254)
		(layer "In13.Cu")
		(net "P1V8_PLL0_PEX2")
	)
	(segment
		(start 246.746522 -238.462312)
		(end 247.319038 -239.034828)
		(width 0.254)
		(layer "In13.Cu")
		(net "P1V8_PLL0_PEX2")
	)
	(segment
		(start 88.62695 -300.24197)
		(end 89.012268 -300.24197)
		(width 0.13208)
		(layer "F.Cu")
		(net "I2C_PEX0_HOST_SDA")
	)
	(segment
		(start 88.42375 -300.03877)
		(end 88.62695 -300.24197)
		(width 0.13208)
		(layer "F.Cu")
		(net "I2C_PEX0_HOST_SDA")
	)
	(segment
		(start 88.42375 -299.400214)
		(end 88.42375 -299.76445)
		(width 0.13208)
		(layer "F.Cu")
		(net "I2C_PEX0_HOST_SDA")
	)
	(segment
		(start 90.028268 -300.24197)
		(end 89.012268 -300.24197)
		(width 0.13208)
		(layer "F.Cu")
		(net "I2C_PEX0_HOST_SDA")
	)
	(segment
		(start 88.42375 -299.76445)
		(end 88.42375 -300.03877)
		(width 0.13208)
		(layer "F.Cu")
		(net "I2C_PEX0_HOST_SDA")
	)
	(segment
		(start 89.005156 -299.27296)
		(end 88.551004 -299.27296)
		(width 0.13208)
		(layer "F.Cu")
		(net "I2C_PEX0_HOST_SDA")
	)
	(segment
		(start 88.551004 -299.27296)
		(end 88.42375 -299.400214)
		(width 0.13208)
		(layer "F.Cu")
		(net "I2C_PEX0_HOST_SDA")
	)
	(via
		(at 88.42375 -299.76445)
		(size 0.508)
		(drill 0.254)
		(layers "F.Cu" "B.Cu")
		(net "I2C_PEX0_HOST_SDA")
	)
	(segment
		(start 370.581936 -199.33412)
		(end 369.451382 -199.33412)
		(width 0.13208)
		(layer "F.Cu")
		(net "RST_PEX_SSD4_PERST_N")
	)
	(segment
		(start 367.989866 -199.33412)
		(end 367.410746 -198.755)
		(width 0.13208)
		(layer "F.Cu")
		(net "RST_PEX_SSD4_PERST_N")
	)
	(segment
		(start 367.410746 -198.755)
		(end 365.90605 -198.755)
		(width 0.13208)
		(layer "F.Cu")
		(net "RST_PEX_SSD4_PERST_N")
	)
	(segment
		(start 369.451382 -199.33412)
		(end 367.989866 -199.33412)
		(width 0.13208)
		(layer "F.Cu")
		(net "RST_PEX_SSD4_PERST_N")
	)
	(via
		(at 369.451382 -199.33412)
		(size 0.508)
		(drill 0.254)
		(layers "F.Cu" "B.Cu")
		(net "RST_PEX_SSD4_PERST_N")
	)
	(segment
		(start 233.949494 -180.28158)
		(end 234.965494 -180.28158)
		(width 0.13208)
		(layer "F.Cu")
		(net "RST_BIC_EXTRST_R_N")
	)
	(segment
		(start 232.460292 -180.28158)
		(end 233.949494 -180.28158)
		(width 0.13208)
		(layer "F.Cu")
		(net "RST_BIC_EXTRST_R_N")
	)
	(segment
		(start 234.965494 -180.28158)
		(end 236.174788 -180.28158)
		(width 0.13208)
		(layer "F.Cu")
		(net "RST_BIC_EXTRST_R_N")
	)
	(via
		(at 236.174788 -180.28158)
		(size 0.762)
		(drill 0.381)
		(layers "F.Cu" "B.Cu")
		(net "RST_BIC_EXTRST_R_N")
	)
	(via
		(at 263.930892 -286.331914)
		(size 0.508)
		(drill 0.254)
		(layers "F.Cu" "B.Cu")
		(net "PCEPLL6_VDDA18_PEX2_R")
	)
	(segment
		(start 347.693742 -217.587068)
		(end 348.093538 -217.187272)
		(width 0.13208)
		(layer "F.Cu")
		(net "NIC0_MAIN_PWR_BIC_EN_R")
	)
	(segment
		(start 229.828852 -233.182668)
		(end 229.2858 -232.639616)
		(width 0.13208)
		(layer "F.Cu")
		(net "NIC0_MAIN_PWR_BIC_EN_R")
	)
	(segment
		(start 229.2858 -232.639616)
		(end 229.2858 -232.07345)
		(width 0.13208)
		(layer "F.Cu")
		(net "NIC0_MAIN_PWR_BIC_EN_R")
	)
	(segment
		(start 229.2858 -232.07345)
		(end 229.5398 -231.81945)
		(width 0.13208)
		(layer "F.Cu")
		(net "NIC0_MAIN_PWR_BIC_EN_R")
	)
	(via
		(at 260.269736 -192.14719)
		(size 0.508)
		(drill 0.254)
		(layers "F.Cu" "B.Cu")
		(net "NIC0_MAIN_PWR_BIC_EN_R")
	)
	(via
		(at 229.828852 -233.182668)
		(size 0.508)
		(drill 0.254)
		(layers "F.Cu" "B.Cu")
		(net "NIC0_MAIN_PWR_BIC_EN_R")
	)
	(via
		(at 348.093538 -217.187272)
		(size 0.4572)
		(drill 0.254)
		(layers "F.Cu" "B.Cu")
		(net "NIC0_MAIN_PWR_BIC_EN_R")
	)
	(via
		(at 265.27506 -218.74734)
		(size 0.508)
		(drill 0.254)
		(layers "F.Cu" "B.Cu")
		(net "NIC0_MAIN_PWR_BIC_EN_R")
	)
	(segment
		(start 258.880356 -196.955156)
		(end 258.880356 -195.845684)
		(width 0.15494)
		(layer "In5.Cu")
		(net "NIC0_MAIN_PWR_BIC_EN_R")
	)
	(segment
		(start 262.729726 -217.978482)
		(end 261.4676 -216.716356)
		(width 0.15494)
		(layer "In5.Cu")
		(net "NIC0_MAIN_PWR_BIC_EN_R")
	)
	(segment
		(start 260.03504 -198.10984)
		(end 258.880356 -196.955156)
		(width 0.15494)
		(layer "In5.Cu")
		(net "NIC0_MAIN_PWR_BIC_EN_R")
	)
	(segment
		(start 261.4676 -210.8962)
		(end 260.5786 -210.0072)
		(width 0.15494)
		(layer "In5.Cu")
		(net "NIC0_MAIN_PWR_BIC_EN_R")
	)
	(segment
		(start 260.03504 -192.381886)
		(end 260.269736 -192.14719)
		(width 0.15494)
		(layer "In5.Cu")
		(net "NIC0_MAIN_PWR_BIC_EN_R")
	)
	(segment
		(start 260.03504 -205.030578)
		(end 260.03504 -198.10984)
		(width 0.15494)
		(layer "In5.Cu")
		(net "NIC0_MAIN_PWR_BIC_EN_R")
	)
	(segment
		(start 265.27506 -218.74734)
		(end 264.506202 -217.978482)
		(width 0.15494)
		(layer "In5.Cu")
		(net "NIC0_MAIN_PWR_BIC_EN_R")
	)
	(segment
		(start 264.506202 -217.978482)
		(end 262.729726 -217.978482)
		(width 0.15494)
		(layer "In5.Cu")
		(net "NIC0_MAIN_PWR_BIC_EN_R")
	)
	(segment
		(start 260.5786 -205.574138)
		(end 260.03504 -205.030578)
		(width 0.15494)
		(layer "In5.Cu")
		(net "NIC0_MAIN_PWR_BIC_EN_R")
	)
	(segment
		(start 261.4676 -216.716356)
		(end 261.4676 -210.8962)
		(width 0.15494)
		(layer "In5.Cu")
		(net "NIC0_MAIN_PWR_BIC_EN_R")
	)
	(segment
		(start 260.5786 -210.0072)
		(end 260.5786 -205.574138)
		(width 0.15494)
		(layer "In5.Cu")
		(net "NIC0_MAIN_PWR_BIC_EN_R")
	)
	(segment
		(start 260.03504 -194.691)
		(end 260.03504 -192.381886)
		(width 0.15494)
		(layer "In5.Cu")
		(net "NIC0_MAIN_PWR_BIC_EN_R")
	)
	(segment
		(start 258.880356 -195.845684)
		(end 260.03504 -194.691)
		(width 0.15494)
		(layer "In5.Cu")
		(net "NIC0_MAIN_PWR_BIC_EN_R")
	)
	(segment
		(start 265.27506 -218.74734)
		(end 264.939526 -218.411806)
		(width 0.15494)
		(layer "In7.Cu")
		(net "NIC0_MAIN_PWR_BIC_EN_R")
	)
	(segment
		(start 257.99034 -224.04959)
		(end 256.447544 -225.592386)
		(width 0.15494)
		(layer "In7.Cu")
		(net "NIC0_MAIN_PWR_BIC_EN_R")
	)
	(segment
		(start 264.939526 -218.411806)
		(end 262.893048 -218.411806)
		(width 0.15494)
		(layer "In7.Cu")
		(net "NIC0_MAIN_PWR_BIC_EN_R")
	)
	(segment
		(start 232.313988 -237.109)
		(end 229.828852 -234.623864)
		(width 0.15494)
		(layer "In7.Cu")
		(net "NIC0_MAIN_PWR_BIC_EN_R")
	)
	(segment
		(start 246.35206 -236.01934)
		(end 245.411244 -236.960156)
		(width 0.15494)
		(layer "In7.Cu")
		(net "NIC0_MAIN_PWR_BIC_EN_R")
	)
	(segment
		(start 246.475504 -236.01934)
		(end 246.35206 -236.01934)
		(width 0.15494)
		(layer "In7.Cu")
		(net "NIC0_MAIN_PWR_BIC_EN_R")
	)
	(segment
		(start 250.429014 -232.560622)
		(end 250.053094 -232.716324)
		(width 0.15494)
		(layer "In7.Cu")
		(net "NIC0_MAIN_PWR_BIC_EN_R")
	)
	(segment
		(start 250.053094 -232.716324)
		(end 249.77852 -232.716324)
		(width 0.15494)
		(layer "In7.Cu")
		(net "NIC0_MAIN_PWR_BIC_EN_R")
	)
	(segment
		(start 250.64593 -232.343706)
		(end 250.429014 -232.560622)
		(width 0.15494)
		(layer "In7.Cu")
		(net "NIC0_MAIN_PWR_BIC_EN_R")
	)
	(segment
		(start 245.411244 -236.960156)
		(end 244.082316 -236.960156)
		(width 0.15494)
		(layer "In7.Cu")
		(net "NIC0_MAIN_PWR_BIC_EN_R")
	)
	(segment
		(start 262.893048 -218.411806)
		(end 258.795012 -222.509842)
		(width 0.15494)
		(layer "In7.Cu")
		(net "NIC0_MAIN_PWR_BIC_EN_R")
	)
	(segment
		(start 249.77852 -232.716324)
		(end 246.475504 -236.01934)
		(width 0.15494)
		(layer "In7.Cu")
		(net "NIC0_MAIN_PWR_BIC_EN_R")
	)
	(segment
		(start 243.933472 -237.109)
		(end 232.313988 -237.109)
		(width 0.15494)
		(layer "In7.Cu")
		(net "NIC0_MAIN_PWR_BIC_EN_R")
	)
	(segment
		(start 257.99161 -224.04959)
		(end 257.99034 -224.04959)
		(width 0.15494)
		(layer "In7.Cu")
		(net "NIC0_MAIN_PWR_BIC_EN_R")
	)
	(segment
		(start 229.828852 -234.623864)
		(end 229.828852 -233.182668)
		(width 0.15494)
		(layer "In7.Cu")
		(net "NIC0_MAIN_PWR_BIC_EN_R")
	)
	(segment
		(start 258.795012 -223.246188)
		(end 257.99161 -224.04959)
		(width 0.15494)
		(layer "In7.Cu")
		(net "NIC0_MAIN_PWR_BIC_EN_R")
	)
	(segment
		(start 256.447544 -225.592386)
		(end 256.447544 -226.85121)
		(width 0.15494)
		(layer "In7.Cu")
		(net "NIC0_MAIN_PWR_BIC_EN_R")
	)
	(segment
		(start 256.447544 -226.85121)
		(end 250.955048 -232.343706)
		(width 0.15494)
		(layer "In7.Cu")
		(net "NIC0_MAIN_PWR_BIC_EN_R")
	)
	(segment
		(start 258.795012 -222.509842)
		(end 258.795012 -223.246188)
		(width 0.15494)
		(layer "In7.Cu")
		(net "NIC0_MAIN_PWR_BIC_EN_R")
	)
	(segment
		(start 250.955048 -232.343706)
		(end 250.64593 -232.343706)
		(width 0.15494)
		(layer "In7.Cu")
		(net "NIC0_MAIN_PWR_BIC_EN_R")
	)
	(segment
		(start 244.082316 -236.960156)
		(end 243.933472 -237.109)
		(width 0.15494)
		(layer "In7.Cu")
		(net "NIC0_MAIN_PWR_BIC_EN_R")
	)
	(segment
		(start 353.032314 -206.647542)
		(end 353.032314 -215.742012)
		(width 0.15494)
		(layer "In15.Cu")
		(net "NIC0_MAIN_PWR_BIC_EN_R")
	)
	(segment
		(start 277.66137 -196.723508)
		(end 325.612506 -196.723508)
		(width 0.15494)
		(layer "In15.Cu")
		(net "NIC0_MAIN_PWR_BIC_EN_R")
	)
	(segment
		(start 349.712534 -202.470004)
		(end 352.84029 -205.59776)
		(width 0.15494)
		(layer "In15.Cu")
		(net "NIC0_MAIN_PWR_BIC_EN_R")
	)
	(segment
		(start 271.613376 -190.675514)
		(end 277.66137 -196.723508)
		(width 0.15494)
		(layer "In15.Cu")
		(net "NIC0_MAIN_PWR_BIC_EN_R")
	)
	(segment
		(start 346.640658 -202.470004)
		(end 349.712534 -202.470004)
		(width 0.15494)
		(layer "In15.Cu")
		(net "NIC0_MAIN_PWR_BIC_EN_R")
	)
	(segment
		(start 328.628502 -195.33108)
		(end 330.040488 -196.743066)
		(width 0.15494)
		(layer "In15.Cu")
		(net "NIC0_MAIN_PWR_BIC_EN_R")
	)
	(segment
		(start 339.966554 -199.66305)
		(end 343.833704 -199.66305)
		(width 0.15494)
		(layer "In15.Cu")
		(net "NIC0_MAIN_PWR_BIC_EN_R")
	)
	(segment
		(start 260.269736 -192.14719)
		(end 260.269736 -191.68872)
		(width 0.15494)
		(layer "In15.Cu")
		(net "NIC0_MAIN_PWR_BIC_EN_R")
	)
	(segment
		(start 327.004934 -195.33108)
		(end 328.628502 -195.33108)
		(width 0.15494)
		(layer "In15.Cu")
		(net "NIC0_MAIN_PWR_BIC_EN_R")
	)
	(segment
		(start 261.282942 -190.675514)
		(end 271.613376 -190.675514)
		(width 0.15494)
		(layer "In15.Cu")
		(net "NIC0_MAIN_PWR_BIC_EN_R")
	)
	(segment
		(start 325.612506 -196.723508)
		(end 327.004934 -195.33108)
		(width 0.15494)
		(layer "In15.Cu")
		(net "NIC0_MAIN_PWR_BIC_EN_R")
	)
	(segment
		(start 352.84029 -206.455518)
		(end 353.032314 -206.647542)
		(width 0.15494)
		(layer "In15.Cu")
		(net "NIC0_MAIN_PWR_BIC_EN_R")
	)
	(segment
		(start 343.833704 -199.66305)
		(end 346.640658 -202.470004)
		(width 0.15494)
		(layer "In15.Cu")
		(net "NIC0_MAIN_PWR_BIC_EN_R")
	)
	(segment
		(start 260.269736 -191.68872)
		(end 261.282942 -190.675514)
		(width 0.15494)
		(layer "In15.Cu")
		(net "NIC0_MAIN_PWR_BIC_EN_R")
	)
	(segment
		(start 338.8106 -197.400418)
		(end 338.8106 -198.507096)
		(width 0.15494)
		(layer "In15.Cu")
		(net "NIC0_MAIN_PWR_BIC_EN_R")
	)
	(segment
		(start 351.212404 -217.561922)
		(end 348.468188 -217.561922)
		(width 0.0889)
		(layer "In15.Cu")
		(net "NIC0_MAIN_PWR_BIC_EN_R")
	)
	(segment
		(start 352.84029 -205.59776)
		(end 352.84029 -206.455518)
		(width 0.15494)
		(layer "In15.Cu")
		(net "NIC0_MAIN_PWR_BIC_EN_R")
	)
	(segment
		(start 330.040488 -196.743066)
		(end 338.153248 -196.743066)
		(width 0.15494)
		(layer "In15.Cu")
		(net "NIC0_MAIN_PWR_BIC_EN_R")
	)
	(segment
		(start 352.624136 -216.15019)
		(end 351.212404 -217.561922)
		(width 0.0889)
		(layer "In15.Cu")
		(net "NIC0_MAIN_PWR_BIC_EN_R")
	)
	(segment
		(start 338.8106 -198.507096)
		(end 339.966554 -199.66305)
		(width 0.15494)
		(layer "In15.Cu")
		(net "NIC0_MAIN_PWR_BIC_EN_R")
	)
	(segment
		(start 348.468188 -217.561922)
		(end 348.093538 -217.187272)
		(width 0.0889)
		(layer "In15.Cu")
		(net "NIC0_MAIN_PWR_BIC_EN_R")
	)
	(segment
		(start 338.153248 -196.743066)
		(end 338.8106 -197.400418)
		(width 0.15494)
		(layer "In15.Cu")
		(net "NIC0_MAIN_PWR_BIC_EN_R")
	)
	(segment
		(start 353.032314 -215.742012)
		(end 352.624136 -216.15019)
		(width 0.15494)
		(layer "In15.Cu")
		(net "NIC0_MAIN_PWR_BIC_EN_R")
	)
	(via
		(at 263.930892 -283.131514)
		(size 0.508)
		(drill 0.254)
		(layers "F.Cu" "B.Cu")
		(net "PCEPLL7_VDDA18_PEX2_R")
	)
	(segment
		(start 365.90605 -209.931)
		(end 369.087908 -209.931)
		(width 0.13208)
		(layer "F.Cu")
		(net "RST_PEX_SSD0_PERST_N")
	)
	(segment
		(start 369.667028 -210.51012)
		(end 370.581936 -210.51012)
		(width 0.13208)
		(layer "F.Cu")
		(net "RST_PEX_SSD0_PERST_N")
	)
	(segment
		(start 369.087908 -209.931)
		(end 369.667028 -210.51012)
		(width 0.13208)
		(layer "F.Cu")
		(net "RST_PEX_SSD0_PERST_N")
	)
	(via
		(at 369.087908 -209.931)
		(size 0.508)
		(drill 0.254)
		(layers "F.Cu" "B.Cu")
		(net "RST_PEX_SSD0_PERST_N")
	)
	(segment
		(start 236.492288 -95.998284)
		(end 236.492288 -96.858328)
		(width 0.13208)
		(layer "F.Cu")
		(net "RST_PEX_USB_HUB_R_N")
	)
	(segment
		(start 234.460288 -96.858328)
		(end 234.460288 -96.24949)
		(width 0.13208)
		(layer "F.Cu")
		(net "RST_PEX_USB_HUB_R_N")
	)
	(segment
		(start 234.520994 -96.188784)
		(end 234.520994 -94.679008)
		(width 0.13208)
		(layer "F.Cu")
		(net "RST_PEX_USB_HUB_R_N")
	)
	(segment
		(start 235.476288 -96.858328)
		(end 234.460288 -96.858328)
		(width 0.13208)
		(layer "F.Cu")
		(net "RST_PEX_USB_HUB_R_N")
	)
	(segment
		(start 236.206538 -95.712534)
		(end 236.492288 -95.998284)
		(width 0.13208)
		(layer "F.Cu")
		(net "RST_PEX_USB_HUB_R_N")
	)
	(segment
		(start 236.492288 -96.858328)
		(end 235.476288 -96.858328)
		(width 0.13208)
		(layer "F.Cu")
		(net "RST_PEX_USB_HUB_R_N")
	)
	(segment
		(start 234.460288 -96.24949)
		(end 234.520994 -96.188784)
		(width 0.13208)
		(layer "F.Cu")
		(net "RST_PEX_USB_HUB_R_N")
	)
	(via
		(at 236.206538 -95.712534)
		(size 0.508)
		(drill 0.254)
		(layers "F.Cu" "B.Cu")
		(net "RST_PEX_USB_HUB_R_N")
	)
	(via
		(at 215.489536 -212.206586)
		(size 0.508)
		(drill 0.254)
		(layers "F.Cu" "B.Cu")
		(net "RST_PEX_USB_HUB_R_N")
	)
	(via
		(at 221.528132 -91.430348)
		(size 0.508)
		(drill 0.254)
		(layers "F.Cu" "B.Cu")
		(net "RST_PEX_USB_HUB_R_N")
	)
	(segment
		(start 215.975184 -211.720938)
		(end 215.489536 -212.206586)
		(width 0.13208)
		(layer "B.Cu")
		(net "RST_PEX_USB_HUB_R_N")
	)
	(segment
		(start 216.835736 -212.161882)
		(end 216.394792 -211.720938)
		(width 0.13208)
		(layer "B.Cu")
		(net "RST_PEX_USB_HUB_R_N")
	)
	(segment
		(start 216.394792 -211.720938)
		(end 215.975184 -211.720938)
		(width 0.13208)
		(layer "B.Cu")
		(net "RST_PEX_USB_HUB_R_N")
	)
	(segment
		(start 216.835736 -212.206586)
		(end 216.835736 -212.161882)
		(width 0.13208)
		(layer "B.Cu")
		(net "RST_PEX_USB_HUB_R_N")
	)
	(segment
		(start 213.024212 -188.37275)
		(end 213.024212 -186.984386)
		(width 0.15494)
		(layer "In7.Cu")
		(net "RST_PEX_USB_HUB_R_N")
	)
	(segment
		(start 215.489536 -212.206586)
		(end 215.439752 -212.156802)
		(width 0.15494)
		(layer "In7.Cu")
		(net "RST_PEX_USB_HUB_R_N")
	)
	(segment
		(start 214.797894 -197.36689)
		(end 213.059772 -195.628768)
		(width 0.15494)
		(layer "In7.Cu")
		(net "RST_PEX_USB_HUB_R_N")
	)
	(segment
		(start 215.439752 -212.156802)
		(end 215.439752 -210.337908)
		(width 0.15494)
		(layer "In7.Cu")
		(net "RST_PEX_USB_HUB_R_N")
	)
	(segment
		(start 211.7598 -103.443786)
		(end 214.26678 -100.936806)
		(width 0.15494)
		(layer "In7.Cu")
		(net "RST_PEX_USB_HUB_R_N")
	)
	(segment
		(start 212.4456 -191.175894)
		(end 212.4456 -188.951362)
		(width 0.15494)
		(layer "In7.Cu")
		(net "RST_PEX_USB_HUB_R_N")
	)
	(segment
		(start 214.25662 -90.267028)
		(end 214.607394 -89.916254)
		(width 0.15494)
		(layer "In7.Cu")
		(net "RST_PEX_USB_HUB_R_N")
	)
	(segment
		(start 209.931 -124.2314)
		(end 209.4992 -123.7996)
		(width 0.15494)
		(layer "In7.Cu")
		(net "RST_PEX_USB_HUB_R_N")
	)
	(segment
		(start 210.696302 -112.671098)
		(end 211.7598 -111.6076)
		(width 0.15494)
		(layer "In7.Cu")
		(net "RST_PEX_USB_HUB_R_N")
	)
	(segment
		(start 212.4456 -188.951362)
		(end 213.024212 -188.37275)
		(width 0.15494)
		(layer "In7.Cu")
		(net "RST_PEX_USB_HUB_R_N")
	)
	(segment
		(start 211.844382 -182.974742)
		(end 211.844382 -170.492928)
		(width 0.15494)
		(layer "In7.Cu")
		(net "RST_PEX_USB_HUB_R_N")
	)
	(segment
		(start 211.4804 -169.091102)
		(end 218.316556 -162.254946)
		(width 0.15494)
		(layer "In7.Cu")
		(net "RST_PEX_USB_HUB_R_N")
	)
	(segment
		(start 213.059772 -195.628768)
		(end 213.059772 -191.790066)
		(width 0.15494)
		(layer "In7.Cu")
		(net "RST_PEX_USB_HUB_R_N")
	)
	(segment
		(start 214.323168 -132.860034)
		(end 209.931 -128.467866)
		(width 0.15494)
		(layer "In7.Cu")
		(net "RST_PEX_USB_HUB_R_N")
	)
	(segment
		(start 212.853524 -183.983884)
		(end 211.844382 -182.974742)
		(width 0.15494)
		(layer "In7.Cu")
		(net "RST_PEX_USB_HUB_R_N")
	)
	(segment
		(start 211.0486 -116.153946)
		(end 210.696302 -115.801648)
		(width 0.15494)
		(layer "In7.Cu")
		(net "RST_PEX_USB_HUB_R_N")
	)
	(segment
		(start 218.316556 -157.302708)
		(end 214.323168 -153.30932)
		(width 0.15494)
		(layer "In7.Cu")
		(net "RST_PEX_USB_HUB_R_N")
	)
	(segment
		(start 213.059772 -191.790066)
		(end 212.4456 -191.175894)
		(width 0.15494)
		(layer "In7.Cu")
		(net "RST_PEX_USB_HUB_R_N")
	)
	(segment
		(start 210.696302 -115.801648)
		(end 210.696302 -112.671098)
		(width 0.15494)
		(layer "In7.Cu")
		(net "RST_PEX_USB_HUB_R_N")
	)
	(segment
		(start 214.25662 -90.668348)
		(end 214.25662 -90.267028)
		(width 0.15494)
		(layer "In7.Cu")
		(net "RST_PEX_USB_HUB_R_N")
	)
	(segment
		(start 212.853524 -186.813698)
		(end 212.853524 -183.983884)
		(width 0.15494)
		(layer "In7.Cu")
		(net "RST_PEX_USB_HUB_R_N")
	)
	(segment
		(start 214.26678 -100.936806)
		(end 214.26678 -90.678508)
		(width 0.15494)
		(layer "In7.Cu")
		(net "RST_PEX_USB_HUB_R_N")
	)
	(segment
		(start 215.439752 -210.337908)
		(end 214.797894 -209.69605)
		(width 0.15494)
		(layer "In7.Cu")
		(net "RST_PEX_USB_HUB_R_N")
	)
	(segment
		(start 209.4992 -123.7996)
		(end 209.4992 -121.7422)
		(width 0.15494)
		(layer "In7.Cu")
		(net "RST_PEX_USB_HUB_R_N")
	)
	(segment
		(start 214.26678 -90.678508)
		(end 214.25662 -90.668348)
		(width 0.15494)
		(layer "In7.Cu")
		(net "RST_PEX_USB_HUB_R_N")
	)
	(segment
		(start 213.024212 -186.984386)
		(end 212.853524 -186.813698)
		(width 0.15494)
		(layer "In7.Cu")
		(net "RST_PEX_USB_HUB_R_N")
	)
	(segment
		(start 211.844382 -170.492928)
		(end 211.4804 -170.128946)
		(width 0.15494)
		(layer "In7.Cu")
		(net "RST_PEX_USB_HUB_R_N")
	)
	(segment
		(start 220.014038 -89.916254)
		(end 221.528132 -91.430348)
		(width 0.15494)
		(layer "In7.Cu")
		(net "RST_PEX_USB_HUB_R_N")
	)
	(segment
		(start 211.0486 -120.1928)
		(end 211.0486 -116.153946)
		(width 0.15494)
		(layer "In7.Cu")
		(net "RST_PEX_USB_HUB_R_N")
	)
	(segment
		(start 209.931 -128.467866)
		(end 209.931 -124.2314)
		(width 0.15494)
		(layer "In7.Cu")
		(net "RST_PEX_USB_HUB_R_N")
	)
	(segment
		(start 214.607394 -89.916254)
		(end 220.014038 -89.916254)
		(width 0.15494)
		(layer "In7.Cu")
		(net "RST_PEX_USB_HUB_R_N")
	)
	(segment
		(start 214.797894 -209.69605)
		(end 214.797894 -197.36689)
		(width 0.15494)
		(layer "In7.Cu")
		(net "RST_PEX_USB_HUB_R_N")
	)
	(segment
		(start 218.316556 -162.254946)
		(end 218.316556 -157.302708)
		(width 0.15494)
		(layer "In7.Cu")
		(net "RST_PEX_USB_HUB_R_N")
	)
	(segment
		(start 209.4992 -121.7422)
		(end 211.0486 -120.1928)
		(width 0.15494)
		(layer "In7.Cu")
		(net "RST_PEX_USB_HUB_R_N")
	)
	(segment
		(start 211.4804 -170.128946)
		(end 211.4804 -169.091102)
		(width 0.15494)
		(layer "In7.Cu")
		(net "RST_PEX_USB_HUB_R_N")
	)
	(segment
		(start 214.323168 -153.30932)
		(end 214.323168 -132.860034)
		(width 0.15494)
		(layer "In7.Cu")
		(net "RST_PEX_USB_HUB_R_N")
	)
	(segment
		(start 211.7598 -111.6076)
		(end 211.7598 -103.443786)
		(width 0.15494)
		(layer "In7.Cu")
		(net "RST_PEX_USB_HUB_R_N")
	)
	(segment
		(start 222.613474 -93.063822)
		(end 226.326954 -96.777302)
		(width 0.15494)
		(layer "In15.Cu")
		(net "RST_PEX_USB_HUB_R_N")
	)
	(segment
		(start 222.613474 -92.51569)
		(end 222.613474 -93.063822)
		(width 0.15494)
		(layer "In15.Cu")
		(net "RST_PEX_USB_HUB_R_N")
	)
	(segment
		(start 234.715558 -97.203514)
		(end 236.206538 -95.712534)
		(width 0.15494)
		(layer "In15.Cu")
		(net "RST_PEX_USB_HUB_R_N")
	)
	(segment
		(start 228.21519 -96.777302)
		(end 228.641402 -97.203514)
		(width 0.15494)
		(layer "In15.Cu")
		(net "RST_PEX_USB_HUB_R_N")
	)
	(segment
		(start 221.528132 -91.430348)
		(end 222.613474 -92.51569)
		(width 0.15494)
		(layer "In15.Cu")
		(net "RST_PEX_USB_HUB_R_N")
	)
	(segment
		(start 226.326954 -96.777302)
		(end 228.21519 -96.777302)
		(width 0.15494)
		(layer "In15.Cu")
		(net "RST_PEX_USB_HUB_R_N")
	)
	(segment
		(start 228.641402 -97.203514)
		(end 234.715558 -97.203514)
		(width 0.15494)
		(layer "In15.Cu")
		(net "RST_PEX_USB_HUB_R_N")
	)
	(via
		(at 263.930892 -292.732714)
		(size 0.508)
		(drill 0.254)
		(layers "F.Cu" "B.Cu")
		(net "PCEPLL2_VDDA18_PEX2_R")
	)
	(segment
		(start 336.493866 -222.38716)
		(end 336.09407 -222.786956)
		(width 0.13208)
		(layer "F.Cu")
		(net "RST_PEX2_PERST_N")
	)
	(via
		(at 333.918814 -222.158814)
		(size 0.6604)
		(drill 0.3302)
		(layers "F.Cu" "B.Cu")
		(net "RST_PEX2_PERST_N")
	)
	(via
		(at 336.09407 -222.786956)
		(size 0.4572)
		(drill 0.254)
		(layers "F.Cu" "B.Cu")
		(net "RST_PEX2_PERST_N")
	)
	(segment
		(start 333.410814 -222.158814)
		(end 333.280766 -222.028766)
		(width 0.13208)
		(layer "B.Cu")
		(net "RST_PEX2_PERST_N")
	)
	(segment
		(start 333.918814 -222.158814)
		(end 333.410814 -222.158814)
		(width 0.13208)
		(layer "B.Cu")
		(net "RST_PEX2_PERST_N")
	)
	(segment
		(start 332.219046 -222.028766)
		(end 331.838046 -221.647766)
		(width 0.13208)
		(layer "B.Cu")
		(net "RST_PEX2_PERST_N")
	)
	(segment
		(start 334.289654 -222.158814)
		(end 334.518 -222.38716)
		(width 0.13208)
		(layer "B.Cu")
		(net "RST_PEX2_PERST_N")
	)
	(segment
		(start 333.918814 -222.158814)
		(end 334.289654 -222.158814)
		(width 0.13208)
		(layer "B.Cu")
		(net "RST_PEX2_PERST_N")
	)
	(segment
		(start 330.302616 -221.647766)
		(end 330.09205 -221.4372)
		(width 0.13208)
		(layer "B.Cu")
		(net "RST_PEX2_PERST_N")
	)
	(segment
		(start 331.838046 -221.647766)
		(end 330.302616 -221.647766)
		(width 0.13208)
		(layer "B.Cu")
		(net "RST_PEX2_PERST_N")
	)
	(segment
		(start 333.280766 -222.028766)
		(end 332.219046 -222.028766)
		(width 0.13208)
		(layer "B.Cu")
		(net "RST_PEX2_PERST_N")
	)
	(segment
		(start 335.694274 -222.38716)
		(end 336.09407 -222.786956)
		(width 0.0889)
		(layer "B.Cu")
		(net "RST_PEX2_PERST_N")
	)
	(segment
		(start 334.518 -222.38716)
		(end 335.694274 -222.38716)
		(width 0.0889)
		(layer "B.Cu")
		(net "RST_PEX2_PERST_N")
	)
	(segment
		(start 226.667568 -215.104218)
		(end 226.267772 -214.704422)
		(width 0.13208)
		(layer "F.Cu")
		(net "SGPIO_BIC_DOUT")
	)
	(via
		(at 223.965262 -211.604098)
		(size 0.6604)
		(drill 0.3302)
		(layers "F.Cu" "B.Cu")
		(net "SGPIO_BIC_DOUT")
	)
	(via
		(at 226.267772 -214.704422)
		(size 0.4572)
		(drill 0.254)
		(layers "F.Cu" "B.Cu")
		(net "SGPIO_BIC_DOUT")
	)
	(segment
		(start 225.867722 -213.714838)
		(end 225.867722 -214.13978)
		(width 0.0889)
		(layer "B.Cu")
		(net "SGPIO_BIC_DOUT")
	)
	(segment
		(start 222.482664 -207.42021)
		(end 222.482664 -207.360266)
		(width 0.13208)
		(layer "B.Cu")
		(net "SGPIO_BIC_DOUT")
	)
	(segment
		(start 223.973898 -209.301588)
		(end 223.965262 -209.257138)
		(width 0.13208)
		(layer "B.Cu")
		(net "SGPIO_BIC_DOUT")
	)
	(segment
		(start 223.965262 -209.257138)
		(end 223.965262 -208.902808)
		(width 0.13208)
		(layer "B.Cu")
		(net "SGPIO_BIC_DOUT")
	)
	(segment
		(start 223.974152 -211.55914)
		(end 223.974152 -209.3087)
		(width 0.13208)
		(layer "B.Cu")
		(net "SGPIO_BIC_DOUT")
	)
	(segment
		(start 222.005144 -205.276958)
		(end 222.439992 -204.84211)
		(width 0.13208)
		(layer "B.Cu")
		(net "SGPIO_BIC_DOUT")
	)
	(segment
		(start 223.965262 -211.604098)
		(end 223.965262 -211.812378)
		(width 0.13208)
		(layer "B.Cu")
		(net "SGPIO_BIC_DOUT")
	)
	(segment
		(start 223.965262 -211.604098)
		(end 223.974152 -211.55914)
		(width 0.13208)
		(layer "B.Cu")
		(net "SGPIO_BIC_DOUT")
	)
	(segment
		(start 222.005144 -206.882746)
		(end 222.005144 -205.276958)
		(width 0.13208)
		(layer "B.Cu")
		(net "SGPIO_BIC_DOUT")
	)
	(segment
		(start 223.965262 -208.902808)
		(end 222.482664 -207.42021)
		(width 0.13208)
		(layer "B.Cu")
		(net "SGPIO_BIC_DOUT")
	)
	(segment
		(start 223.965262 -211.812378)
		(end 225.867722 -213.714838)
		(width 0.13208)
		(layer "B.Cu")
		(net "SGPIO_BIC_DOUT")
	)
	(segment
		(start 222.482664 -207.360266)
		(end 222.005144 -206.882746)
		(width 0.13208)
		(layer "B.Cu")
		(net "SGPIO_BIC_DOUT")
	)
	(segment
		(start 223.974152 -209.3087)
		(end 223.973898 -209.301588)
		(width 0.13208)
		(layer "B.Cu")
		(net "SGPIO_BIC_DOUT")
	)
	(segment
		(start 226.151186 -214.423244)
		(end 226.267772 -214.704422)
		(width 0.0889)
		(layer "B.Cu")
		(net "SGPIO_BIC_DOUT")
	)
	(segment
		(start 225.867722 -214.13978)
		(end 226.151186 -214.423244)
		(width 0.0889)
		(layer "B.Cu")
		(net "SGPIO_BIC_DOUT")
	)
	(segment
		(start 222.439992 -204.84211)
		(end 222.482664 -204.84211)
		(width 0.13208)
		(layer "B.Cu")
		(net "SGPIO_BIC_DOUT")
	)
	(via
		(at 266.888976 -256.375916)
		(size 0.508)
		(drill 0.254)
		(layers "F.Cu" "B.Cu")
		(net "PCEPLL5_VDDA18_PEX2_R")
	)
	(segment
		(start 367.497614 -210.947)
		(end 367.71072 -211.160106)
		(width 0.13208)
		(layer "F.Cu")
		(net "SSD0_PEX_PWR_EN")
	)
	(segment
		(start 369.453414 -211.160106)
		(end 370.581936 -211.160106)
		(width 0.13208)
		(layer "F.Cu")
		(net "SSD0_PEX_PWR_EN")
	)
	(segment
		(start 365.90605 -210.947)
		(end 367.497614 -210.947)
		(width 0.13208)
		(layer "F.Cu")
		(net "SSD0_PEX_PWR_EN")
	)
	(segment
		(start 367.71072 -211.160106)
		(end 369.453414 -211.160106)
		(width 0.13208)
		(layer "F.Cu")
		(net "SSD0_PEX_PWR_EN")
	)
	(via
		(at 369.453414 -211.160106)
		(size 0.508)
		(drill 0.254)
		(layers "F.Cu" "B.Cu")
		(net "SSD0_PEX_PWR_EN")
	)
	(segment
		(start 370.581936 -199.984106)
		(end 368.364262 -199.984106)
		(width 0.13208)
		(layer "F.Cu")
		(net "SSD4_PEX_PWR_EN")
	)
	(segment
		(start 368.364262 -199.984106)
		(end 368.004852 -199.984106)
		(width 0.13208)
		(layer "F.Cu")
		(net "SSD4_PEX_PWR_EN")
	)
	(segment
		(start 368.004852 -199.984106)
		(end 367.791746 -199.771)
		(width 0.13208)
		(layer "F.Cu")
		(net "SSD4_PEX_PWR_EN")
	)
	(segment
		(start 367.791746 -199.771)
		(end 365.90605 -199.771)
		(width 0.13208)
		(layer "F.Cu")
		(net "SSD4_PEX_PWR_EN")
	)
	(via
		(at 368.364262 -199.984106)
		(size 0.508)
		(drill 0.254)
		(layers "F.Cu" "B.Cu")
		(net "SSD4_PEX_PWR_EN")
	)
	(segment
		(start 166.742364 -97.045018)
		(end 168.076626 -97.045018)
		(width 0.13208)
		(layer "F.Cu")
		(net "NIC2_PWRBRK_R_N")
	)
	(segment
		(start 179.109624 -166.570406)
		(end 179.16906 -166.570406)
		(width 0.13208)
		(layer "F.Cu")
		(net "NIC2_PWRBRK_R_N")
	)
	(segment
		(start 168.076626 -97.045018)
		(end 168.087294 -97.055686)
		(width 0.13208)
		(layer "F.Cu")
		(net "NIC2_PWRBRK_R_N")
	)
	(segment
		(start 178.609752 -166.070534)
		(end 179.109624 -166.570406)
		(width 0.13208)
		(layer "F.Cu")
		(net "NIC2_PWRBRK_R_N")
	)
	(via
		(at 168.087294 -97.055686)
		(size 0.508)
		(drill 0.254)
		(layers "F.Cu" "B.Cu")
		(net "NIC2_PWRBRK_R_N")
	)
	(via
		(at 179.16906 -166.570406)
		(size 0.508)
		(drill 0.254)
		(layers "F.Cu" "B.Cu")
		(net "NIC2_PWRBRK_R_N")
	)
	(segment
		(start 172.0342 -117.9068)
		(end 171.186348 -117.058948)
		(width 0.15494)
		(layer "In9.Cu")
		(net "NIC2_PWRBRK_R_N")
	)
	(segment
		(start 172.0342 -143.945864)
		(end 172.0342 -117.9068)
		(width 0.15494)
		(layer "In9.Cu")
		(net "NIC2_PWRBRK_R_N")
	)
	(segment
		(start 171.5008 -144.479264)
		(end 172.0342 -143.945864)
		(width 0.15494)
		(layer "In9.Cu")
		(net "NIC2_PWRBRK_R_N")
	)
	(segment
		(start 171.5008 -159.596582)
		(end 171.5008 -144.479264)
		(width 0.15494)
		(layer "In9.Cu")
		(net "NIC2_PWRBRK_R_N")
	)
	(segment
		(start 171.186348 -117.058948)
		(end 170.831002 -117.058948)
		(width 0.15494)
		(layer "In9.Cu")
		(net "NIC2_PWRBRK_R_N")
	)
	(segment
		(start 170.831002 -117.058948)
		(end 167.2082 -113.436146)
		(width 0.15494)
		(layer "In9.Cu")
		(net "NIC2_PWRBRK_R_N")
	)
	(segment
		(start 167.2082 -97.93478)
		(end 168.087294 -97.055686)
		(width 0.15494)
		(layer "In9.Cu")
		(net "NIC2_PWRBRK_R_N")
	)
	(segment
		(start 167.2082 -113.436146)
		(end 167.2082 -97.93478)
		(width 0.15494)
		(layer "In9.Cu")
		(net "NIC2_PWRBRK_R_N")
	)
	(segment
		(start 179.16906 -166.570406)
		(end 178.474624 -166.570406)
		(width 0.15494)
		(layer "In9.Cu")
		(net "NIC2_PWRBRK_R_N")
	)
	(segment
		(start 178.474624 -166.570406)
		(end 171.5008 -159.596582)
		(width 0.15494)
		(layer "In9.Cu")
		(net "NIC2_PWRBRK_R_N")
	)
	(segment
		(start 280.449782 -308.249828)
		(end 279.974802 -308.724808)
		(width 0.13208)
		(layer "F.Cu")
		(net "IRQ_PEX2_CLKREQ_INT_N")
	)
	(segment
		(start 259.061458 -308.89448)
		(end 259.581904 -309.414926)
		(width 0.13208)
		(layer "F.Cu")
		(net "IRQ_PEX2_CLKREQ_INT_N")
	)
	(via
		(at 259.581904 -309.414926)
		(size 0.508)
		(drill 0.254)
		(layers "F.Cu" "B.Cu")
		(net "IRQ_PEX2_CLKREQ_INT_N")
	)
	(via
		(at 279.974802 -308.724808)
		(size 0.4064)
		(drill 0.2032)
		(layers "F.Cu" "B.Cu")
		(net "IRQ_PEX2_CLKREQ_INT_N")
	)
	(segment
		(start 264.421874 -309.414926)
		(end 266.0904 -307.7464)
		(width 0.13208)
		(layer "B.Cu")
		(net "IRQ_PEX2_CLKREQ_INT_N")
	)
	(segment
		(start 278.82088 -308.25948)
		(end 279.509474 -308.25948)
		(width 0.13208)
		(layer "B.Cu")
		(net "IRQ_PEX2_CLKREQ_INT_N")
	)
	(segment
		(start 279.509474 -308.25948)
		(end 279.974802 -308.724808)
		(width 0.13208)
		(layer "B.Cu")
		(net "IRQ_PEX2_CLKREQ_INT_N")
	)
	(segment
		(start 278.3078 -307.7464)
		(end 278.82088 -308.25948)
		(width 0.13208)
		(layer "B.Cu")
		(net "IRQ_PEX2_CLKREQ_INT_N")
	)
	(segment
		(start 259.581904 -309.414926)
		(end 264.421874 -309.414926)
		(width 0.13208)
		(layer "B.Cu")
		(net "IRQ_PEX2_CLKREQ_INT_N")
	)
	(segment
		(start 266.0904 -307.7464)
		(end 278.3078 -307.7464)
		(width 0.13208)
		(layer "B.Cu")
		(net "IRQ_PEX2_CLKREQ_INT_N")
	)
	(via
		(at 263.930892 -289.532314)
		(size 0.508)
		(drill 0.254)
		(layers "F.Cu" "B.Cu")
		(net "PCEPLL4_VDDA18_PEX2_R")
	)
	(segment
		(start 39.582344 -252.756924)
		(end 39.582344 -253.45644)
		(width 0.13208)
		(layer "F.Cu")
		(net "PEX0_PCA9555_INT_R_N")
	)
	(segment
		(start 63.449962 -283.549852)
		(end 63.924942 -284.024832)
		(width 0.1651)
		(layer "F.Cu")
		(net "PEX0_PCA9555_INT_R_N")
	)
	(segment
		(start 359.561892 -194.397122)
		(end 360.177842 -194.397122)
		(width 0.13208)
		(layer "F.Cu")
		(net "PEX0_PCA9555_INT_R_N")
	)
	(via
		(at 39.582344 -253.45644)
		(size 0.508)
		(drill 0.254)
		(layers "F.Cu" "B.Cu")
		(net "PEX0_PCA9555_INT_R_N")
	)
	(via
		(at 63.924942 -284.024832)
		(size 0.4064)
		(drill 0.2032)
		(layers "F.Cu" "B.Cu")
		(net "PEX0_PCA9555_INT_R_N")
	)
	(via
		(at 360.177842 -194.397122)
		(size 0.508)
		(drill 0.254)
		(layers "F.Cu" "B.Cu")
		(net "PEX0_PCA9555_INT_R_N")
	)
	(via
		(at 30.251146 -191.783208)
		(size 0.508)
		(drill 0.254)
		(layers "F.Cu" "B.Cu")
		(net "PEX0_PCA9555_INT_R_N")
	)
	(segment
		(start 69.783198 -284.48127)
		(end 70.124828 -284.13964)
		(width 0.13208)
		(layer "B.Cu")
		(net "PEX0_PCA9555_INT_R_N")
	)
	(segment
		(start 70.771766 -282.56738)
		(end 71.51243 -281.826716)
		(width 0.13208)
		(layer "B.Cu")
		(net "PEX0_PCA9555_INT_R_N")
	)
	(segment
		(start 64.38138 -284.48127)
		(end 69.783198 -284.48127)
		(width 0.13208)
		(layer "B.Cu")
		(net "PEX0_PCA9555_INT_R_N")
	)
	(segment
		(start 63.924942 -284.024832)
		(end 64.38138 -284.48127)
		(width 0.13208)
		(layer "B.Cu")
		(net "PEX0_PCA9555_INT_R_N")
	)
	(segment
		(start 71.51243 -271.720564)
		(end 52.770786 -252.97892)
		(width 0.13208)
		(layer "B.Cu")
		(net "PEX0_PCA9555_INT_R_N")
	)
	(segment
		(start 70.124828 -284.13964)
		(end 70.124828 -282.86202)
		(width 0.13208)
		(layer "B.Cu")
		(net "PEX0_PCA9555_INT_R_N")
	)
	(segment
		(start 71.51243 -281.826716)
		(end 71.51243 -271.720564)
		(width 0.13208)
		(layer "B.Cu")
		(net "PEX0_PCA9555_INT_R_N")
	)
	(segment
		(start 70.419468 -282.56738)
		(end 70.771766 -282.56738)
		(width 0.13208)
		(layer "B.Cu")
		(net "PEX0_PCA9555_INT_R_N")
	)
	(segment
		(start 40.059864 -252.97892)
		(end 39.582344 -253.45644)
		(width 0.13208)
		(layer "B.Cu")
		(net "PEX0_PCA9555_INT_R_N")
	)
	(segment
		(start 52.770786 -252.97892)
		(end 40.059864 -252.97892)
		(width 0.13208)
		(layer "B.Cu")
		(net "PEX0_PCA9555_INT_R_N")
	)
	(segment
		(start 70.124828 -282.86202)
		(end 70.419468 -282.56738)
		(width 0.13208)
		(layer "B.Cu")
		(net "PEX0_PCA9555_INT_R_N")
	)
	(segment
		(start 30.251146 -191.783208)
		(end 30.265878 -191.783208)
		(width 0.15494)
		(layer "In5.Cu")
		(net "PEX0_PCA9555_INT_R_N")
	)
	(segment
		(start 30.265878 -191.783208)
		(end 32.568388 -194.085718)
		(width 0.15494)
		(layer "In5.Cu")
		(net "PEX0_PCA9555_INT_R_N")
	)
	(segment
		(start 32.568388 -202.976226)
		(end 33.39592 -203.803758)
		(width 0.15494)
		(layer "In5.Cu")
		(net "PEX0_PCA9555_INT_R_N")
	)
	(segment
		(start 32.568388 -194.085718)
		(end 32.568388 -202.976226)
		(width 0.15494)
		(layer "In5.Cu")
		(net "PEX0_PCA9555_INT_R_N")
	)
	(segment
		(start 35.941 -240.729262)
		(end 40.056054 -250.663964)
		(width 0.15494)
		(layer "In5.Cu")
		(net "PEX0_PCA9555_INT_R_N")
	)
	(segment
		(start 40.056054 -250.663964)
		(end 40.056054 -252.98273)
		(width 0.15494)
		(layer "In5.Cu")
		(net "PEX0_PCA9555_INT_R_N")
	)
	(segment
		(start 35.941 -217.372946)
		(end 35.941 -240.729262)
		(width 0.15494)
		(layer "In5.Cu")
		(net "PEX0_PCA9555_INT_R_N")
	)
	(segment
		(start 40.056054 -252.98273)
		(end 39.582344 -253.45644)
		(width 0.15494)
		(layer "In5.Cu")
		(net "PEX0_PCA9555_INT_R_N")
	)
	(segment
		(start 33.39592 -203.803758)
		(end 33.39592 -214.827866)
		(width 0.15494)
		(layer "In5.Cu")
		(net "PEX0_PCA9555_INT_R_N")
	)
	(segment
		(start 33.39592 -214.827866)
		(end 35.941 -217.372946)
		(width 0.15494)
		(layer "In5.Cu")
		(net "PEX0_PCA9555_INT_R_N")
	)
	(segment
		(start 201.962766 -178.02098)
		(end 192.973706 -187.01004)
		(width 0.15494)
		(layer "In13.Cu")
		(net "PEX0_PCA9555_INT_R_N")
	)
	(segment
		(start 243.017294 -177.839624)
		(end 242.059714 -176.882044)
		(width 0.15494)
		(layer "In13.Cu")
		(net "PEX0_PCA9555_INT_R_N")
	)
	(segment
		(start 358.100122 -194.397122)
		(end 352.617532 -188.914532)
		(width 0.15494)
		(layer "In13.Cu")
		(net "PEX0_PCA9555_INT_R_N")
	)
	(segment
		(start 109.499654 -184.7596)
		(end 108.559854 -185.6994)
		(width 0.15494)
		(layer "In13.Cu")
		(net "PEX0_PCA9555_INT_R_N")
	)
	(segment
		(start 258.65836 -179.477924)
		(end 254.492506 -179.477924)
		(width 0.15494)
		(layer "In13.Cu")
		(net "PEX0_PCA9555_INT_R_N")
	)
	(segment
		(start 139.629896 -186.848496)
		(end 137.541 -184.7596)
		(width 0.15494)
		(layer "In13.Cu")
		(net "PEX0_PCA9555_INT_R_N")
	)
	(segment
		(start 252.854206 -177.839624)
		(end 243.017294 -177.839624)
		(width 0.15494)
		(layer "In13.Cu")
		(net "PEX0_PCA9555_INT_R_N")
	)
	(segment
		(start 217.231976 -182.445406)
		(end 215.594946 -180.808376)
		(width 0.15494)
		(layer "In13.Cu")
		(net "PEX0_PCA9555_INT_R_N")
	)
	(segment
		(start 105.17378 -184.83199)
		(end 37.202364 -184.83199)
		(width 0.15494)
		(layer "In13.Cu")
		(net "PEX0_PCA9555_INT_R_N")
	)
	(segment
		(start 192.973706 -187.01004)
		(end 180.41366 -187.01004)
		(width 0.15494)
		(layer "In13.Cu")
		(net "PEX0_PCA9555_INT_R_N")
	)
	(segment
		(start 179.508658 -187.915042)
		(end 147.139914 -187.915042)
		(width 0.15494)
		(layer "In13.Cu")
		(net "PEX0_PCA9555_INT_R_N")
	)
	(segment
		(start 137.541 -184.7596)
		(end 109.499654 -184.7596)
		(width 0.15494)
		(layer "In13.Cu")
		(net "PEX0_PCA9555_INT_R_N")
	)
	(segment
		(start 37.202364 -184.83199)
		(end 30.251146 -191.783208)
		(width 0.15494)
		(layer "In13.Cu")
		(net "PEX0_PCA9555_INT_R_N")
	)
	(segment
		(start 215.594946 -179.11826)
		(end 215.160606 -178.68392)
		(width 0.15494)
		(layer "In13.Cu")
		(net "PEX0_PCA9555_INT_R_N")
	)
	(segment
		(start 211.222844 -178.68392)
		(end 210.559904 -178.02098)
		(width 0.15494)
		(layer "In13.Cu")
		(net "PEX0_PCA9555_INT_R_N")
	)
	(segment
		(start 232.320338 -176.883568)
		(end 231.665526 -177.53838)
		(width 0.15494)
		(layer "In13.Cu")
		(net "PEX0_PCA9555_INT_R_N")
	)
	(segment
		(start 180.41366 -187.01004)
		(end 179.508658 -187.915042)
		(width 0.15494)
		(layer "In13.Cu")
		(net "PEX0_PCA9555_INT_R_N")
	)
	(segment
		(start 225.1456 -179.959)
		(end 222.89897 -179.959)
		(width 0.15494)
		(layer "In13.Cu")
		(net "PEX0_PCA9555_INT_R_N")
	)
	(segment
		(start 360.177842 -194.397122)
		(end 358.100122 -194.397122)
		(width 0.15494)
		(layer "In13.Cu")
		(net "PEX0_PCA9555_INT_R_N")
	)
	(segment
		(start 352.617532 -188.914532)
		(end 276.170644 -188.914532)
		(width 0.15494)
		(layer "In13.Cu")
		(net "PEX0_PCA9555_INT_R_N")
	)
	(segment
		(start 229.999794 -177.53838)
		(end 229.814374 -177.7238)
		(width 0.15494)
		(layer "In13.Cu")
		(net "PEX0_PCA9555_INT_R_N")
	)
	(segment
		(start 147.139914 -187.915042)
		(end 146.073368 -186.848496)
		(width 0.15494)
		(layer "In13.Cu")
		(net "PEX0_PCA9555_INT_R_N")
	)
	(segment
		(start 254.492506 -179.477924)
		(end 252.854206 -177.839624)
		(width 0.15494)
		(layer "In13.Cu")
		(net "PEX0_PCA9555_INT_R_N")
	)
	(segment
		(start 215.160606 -178.68392)
		(end 211.222844 -178.68392)
		(width 0.15494)
		(layer "In13.Cu")
		(net "PEX0_PCA9555_INT_R_N")
	)
	(segment
		(start 237.032292 -176.882044)
		(end 237.030514 -176.883568)
		(width 0.15494)
		(layer "In13.Cu")
		(net "PEX0_PCA9555_INT_R_N")
	)
	(segment
		(start 242.059714 -176.882044)
		(end 237.032292 -176.882044)
		(width 0.15494)
		(layer "In13.Cu")
		(net "PEX0_PCA9555_INT_R_N")
	)
	(segment
		(start 108.559854 -185.6994)
		(end 106.04119 -185.6994)
		(width 0.15494)
		(layer "In13.Cu")
		(net "PEX0_PCA9555_INT_R_N")
	)
	(segment
		(start 237.030514 -176.883568)
		(end 232.320338 -176.883568)
		(width 0.15494)
		(layer "In13.Cu")
		(net "PEX0_PCA9555_INT_R_N")
	)
	(segment
		(start 231.665526 -177.53838)
		(end 229.999794 -177.53838)
		(width 0.15494)
		(layer "In13.Cu")
		(net "PEX0_PCA9555_INT_R_N")
	)
	(segment
		(start 276.170644 -188.914532)
		(end 269.35684 -182.100728)
		(width 0.15494)
		(layer "In13.Cu")
		(net "PEX0_PCA9555_INT_R_N")
	)
	(segment
		(start 269.35684 -182.100728)
		(end 261.281164 -182.100728)
		(width 0.15494)
		(layer "In13.Cu")
		(net "PEX0_PCA9555_INT_R_N")
	)
	(segment
		(start 227.3808 -177.7238)
		(end 225.1456 -179.959)
		(width 0.15494)
		(layer "In13.Cu")
		(net "PEX0_PCA9555_INT_R_N")
	)
	(segment
		(start 229.814374 -177.7238)
		(end 227.3808 -177.7238)
		(width 0.15494)
		(layer "In13.Cu")
		(net "PEX0_PCA9555_INT_R_N")
	)
	(segment
		(start 220.412564 -182.445406)
		(end 217.231976 -182.445406)
		(width 0.15494)
		(layer "In13.Cu")
		(net "PEX0_PCA9555_INT_R_N")
	)
	(segment
		(start 106.04119 -185.6994)
		(end 105.17378 -184.83199)
		(width 0.15494)
		(layer "In13.Cu")
		(net "PEX0_PCA9555_INT_R_N")
	)
	(segment
		(start 210.559904 -178.02098)
		(end 201.962766 -178.02098)
		(width 0.15494)
		(layer "In13.Cu")
		(net "PEX0_PCA9555_INT_R_N")
	)
	(segment
		(start 261.281164 -182.100728)
		(end 258.65836 -179.477924)
		(width 0.15494)
		(layer "In13.Cu")
		(net "PEX0_PCA9555_INT_R_N")
	)
	(segment
		(start 146.073368 -186.848496)
		(end 139.629896 -186.848496)
		(width 0.15494)
		(layer "In13.Cu")
		(net "PEX0_PCA9555_INT_R_N")
	)
	(segment
		(start 222.89897 -179.959)
		(end 220.412564 -182.445406)
		(width 0.15494)
		(layer "In13.Cu")
		(net "PEX0_PCA9555_INT_R_N")
	)
	(segment
		(start 215.594946 -180.808376)
		(end 215.594946 -179.11826)
		(width 0.15494)
		(layer "In13.Cu")
		(net "PEX0_PCA9555_INT_R_N")
	)
	(segment
		(start 222.482664 -204.84211)
		(end 222.401384 -204.84211)
		(width 0.13208)
		(layer "F.Cu")
		(net "SGPIO_BIC_CLK")
	)
	(segment
		(start 223.31426 -208.626456)
		(end 222.962216 -208.274412)
		(width 0.13208)
		(layer "F.Cu")
		(net "SGPIO_BIC_CLK")
	)
	(segment
		(start 222.007938 -206.145384)
		(end 222.482664 -206.62011)
		(width 0.13208)
		(layer "F.Cu")
		(net "SGPIO_BIC_CLK")
	)
	(segment
		(start 223.489012 -208.801208)
		(end 223.31426 -208.626456)
		(width 0.13208)
		(layer "F.Cu")
		(net "SGPIO_BIC_CLK")
	)
	(segment
		(start 223.489012 -211.115656)
		(end 223.489012 -208.801208)
		(width 0.13208)
		(layer "F.Cu")
		(net "SGPIO_BIC_CLK")
	)
	(segment
		(start 222.401384 -204.84211)
		(end 222.007938 -205.235556)
		(width 0.13208)
		(layer "F.Cu")
		(net "SGPIO_BIC_CLK")
	)
	(segment
		(start 224.667572 -212.294216)
		(end 223.489012 -211.115656)
		(width 0.13208)
		(layer "F.Cu")
		(net "SGPIO_BIC_CLK")
	)
	(segment
		(start 224.667572 -213.104222)
		(end 224.667572 -212.294216)
		(width 0.0889)
		(layer "F.Cu")
		(net "SGPIO_BIC_CLK")
	)
	(segment
		(start 222.007938 -205.235556)
		(end 222.007938 -206.145384)
		(width 0.13208)
		(layer "F.Cu")
		(net "SGPIO_BIC_CLK")
	)
	(segment
		(start 225.067622 -213.504272)
		(end 224.667572 -213.104222)
		(width 0.0889)
		(layer "F.Cu")
		(net "SGPIO_BIC_CLK")
	)
	(segment
		(start 222.835216 -206.62011)
		(end 222.482664 -206.62011)
		(width 0.13208)
		(layer "F.Cu")
		(net "SGPIO_BIC_CLK")
	)
	(segment
		(start 222.962216 -206.74711)
		(end 222.835216 -206.62011)
		(width 0.13208)
		(layer "F.Cu")
		(net "SGPIO_BIC_CLK")
	)
	(segment
		(start 222.962216 -208.274412)
		(end 222.962216 -206.74711)
		(width 0.13208)
		(layer "F.Cu")
		(net "SGPIO_BIC_CLK")
	)
	(via
		(at 223.31426 -208.626456)
		(size 0.762)
		(drill 0.381)
		(layers "F.Cu" "B.Cu")
		(net "SGPIO_BIC_CLK")
	)
	(segment
		(start 280.449782 -293.99992)
		(end 279.974802 -293.52494)
		(width 0.254)
		(layer "F.Cu")
		(net "PCEPLL5_VDDA18_PEX2")
	)
	(via
		(at 266.877546 -257.137916)
		(size 0.508)
		(drill 0.254)
		(layers "F.Cu" "B.Cu")
		(net "PCEPLL5_VDDA18_PEX2")
	)
	(via
		(at 279.974802 -293.52494)
		(size 0.4064)
		(drill 0.2032)
		(layers "F.Cu" "B.Cu")
		(net "PCEPLL5_VDDA18_PEX2")
	)
	(via
		(at 268.274546 -257.137916)
		(size 0.508)
		(drill 0.254)
		(layers "F.Cu" "B.Cu")
		(net "PCEPLL5_VDDA18_PEX2")
	)
	(segment
		(start 279.974802 -293.10838)
		(end 279.974802 -293.52494)
		(width 0.3048)
		(layer "B.Cu")
		(net "PCEPLL5_VDDA18_PEX2")
	)
	(segment
		(start 279.974802 -293.8653)
		(end 279.974802 -293.52494)
		(width 0.3048)
		(layer "B.Cu")
		(net "PCEPLL5_VDDA18_PEX2")
	)
	(segment
		(start 333.204058 -223.461834)
		(end 333.478886 -223.187006)
		(width 0.13208)
		(layer "F.Cu")
		(net "RST_PEX1_PERST_N")
	)
	(segment
		(start 333.478886 -223.187006)
		(end 334.09382 -223.187006)
		(width 0.13208)
		(layer "F.Cu")
		(net "RST_PEX1_PERST_N")
	)
	(segment
		(start 329.122532 -222.956882)
		(end 329.506072 -223.340422)
		(width 0.13208)
		(layer "F.Cu")
		(net "RST_PEX1_PERST_N")
	)
	(segment
		(start 331.143356 -223.461834)
		(end 333.204058 -223.461834)
		(width 0.13208)
		(layer "F.Cu")
		(net "RST_PEX1_PERST_N")
	)
	(segment
		(start 331.021944 -223.340422)
		(end 331.143356 -223.461834)
		(width 0.13208)
		(layer "F.Cu")
		(net "RST_PEX1_PERST_N")
	)
	(segment
		(start 329.122532 -222.956882)
		(end 327.93178 -222.956882)
		(width 0.13208)
		(layer "F.Cu")
		(net "RST_PEX1_PERST_N")
	)
	(segment
		(start 329.506072 -223.340422)
		(end 331.021944 -223.340422)
		(width 0.13208)
		(layer "F.Cu")
		(net "RST_PEX1_PERST_N")
	)
	(via
		(at 329.122532 -222.956882)
		(size 0.762)
		(drill 0.381)
		(layers "F.Cu" "B.Cu")
		(net "RST_PEX1_PERST_N")
	)
	(segment
		(start 279.024842 -297.32478)
		(end 279.499822 -296.8498)
		(width 0.249936)
		(layer "F.Cu")
		(net "PCEPLL2_VDDA18_PEX2")
	)
	(via
		(at 263.919462 -293.494714)
		(size 0.508)
		(drill 0.254)
		(layers "F.Cu" "B.Cu")
		(net "PCEPLL2_VDDA18_PEX2")
	)
	(via
		(at 279.024842 -297.32478)
		(size 0.4064)
		(drill 0.2032)
		(layers "F.Cu" "B.Cu")
		(net "PCEPLL2_VDDA18_PEX2")
	)
	(via
		(at 265.316462 -293.494714)
		(size 0.508)
		(drill 0.254)
		(layers "F.Cu" "B.Cu")
		(net "PCEPLL2_VDDA18_PEX2")
	)
	(segment
		(start 279.024842 -297.32478)
		(end 278.821642 -297.32478)
		(width 0.3048)
		(layer "B.Cu")
		(net "PCEPLL2_VDDA18_PEX2")
	)
	(segment
		(start 278.821642 -296.37482)
		(end 278.821642 -297.32478)
		(width 0.3048)
		(layer "B.Cu")
		(net "PCEPLL2_VDDA18_PEX2")
	)
	(segment
		(start 63.924942 -307.774594)
		(end 63.449962 -308.249828)
		(width 0.13208)
		(layer "F.Cu")
		(net "I2C0_PEX0_SHPC_SCL")
	)
	(segment
		(start 92.387166 -301.050452)
		(end 93.072966 -301.050452)
		(width 0.13208)
		(layer "F.Cu")
		(net "I2C0_PEX0_SHPC_SCL")
	)
	(via
		(at 93.072966 -301.050452)
		(size 0.508)
		(drill 0.254)
		(layers "F.Cu" "B.Cu")
		(net "I2C0_PEX0_SHPC_SCL")
	)
	(via
		(at 63.924942 -307.774594)
		(size 0.4064)
		(drill 0.2032)
		(layers "F.Cu" "B.Cu")
		(net "I2C0_PEX0_SHPC_SCL")
	)
	(segment
		(start 73.276206 -301.576994)
		(end 72.9488 -301.9044)
		(width 0.15494)
		(layer "In5.Cu")
		(net "I2C0_PEX0_SHPC_SCL")
	)
	(segment
		(start 76.03109 -299.716698)
		(end 74.170794 -301.576994)
		(width 0.15494)
		(layer "In5.Cu")
		(net "I2C0_PEX0_SHPC_SCL")
	)
	(segment
		(start 83.442302 -299.716698)
		(end 76.03109 -299.716698)
		(width 0.15494)
		(layer "In5.Cu")
		(net "I2C0_PEX0_SHPC_SCL")
	)
	(segment
		(start 72.042528 -306.158646)
		(end 72.042528 -305.569366)
		(width 0.15494)
		(layer "In5.Cu")
		(net "I2C0_PEX0_SHPC_SCL")
	)
	(segment
		(start 72.8218 -306.324)
		(end 72.207882 -306.324)
		(width 0.15494)
		(layer "In5.Cu")
		(net "I2C0_PEX0_SHPC_SCL")
	)
	(segment
		(start 91.49588 -300.087538)
		(end 89.537286 -300.087538)
		(width 0.15494)
		(layer "In5.Cu")
		(net "I2C0_PEX0_SHPC_SCL")
	)
	(segment
		(start 69.854572 -307.299868)
		(end 64.363092 -307.299868)
		(width 0.15494)
		(layer "In5.Cu")
		(net "I2C0_PEX0_SHPC_SCL")
	)
	(segment
		(start 88.578436 -299.128688)
		(end 88.257634 -299.128688)
		(width 0.15494)
		(layer "In5.Cu")
		(net "I2C0_PEX0_SHPC_SCL")
	)
	(segment
		(start 72.042528 -305.569366)
		(end 71.882762 -305.4096)
		(width 0.15494)
		(layer "In5.Cu")
		(net "I2C0_PEX0_SHPC_SCL")
	)
	(segment
		(start 74.170794 -301.576994)
		(end 73.276206 -301.576994)
		(width 0.15494)
		(layer "In5.Cu")
		(net "I2C0_PEX0_SHPC_SCL")
	)
	(segment
		(start 72.207882 -306.324)
		(end 72.042528 -306.158646)
		(width 0.15494)
		(layer "In5.Cu")
		(net "I2C0_PEX0_SHPC_SCL")
	)
	(segment
		(start 88.257634 -299.128688)
		(end 88.16848 -299.217842)
		(width 0.15494)
		(layer "In5.Cu")
		(net "I2C0_PEX0_SHPC_SCL")
	)
	(segment
		(start 72.9488 -306.197)
		(end 72.8218 -306.324)
		(width 0.15494)
		(layer "In5.Cu")
		(net "I2C0_PEX0_SHPC_SCL")
	)
	(segment
		(start 71.882762 -305.4096)
		(end 70.273672 -305.4096)
		(width 0.15494)
		(layer "In5.Cu")
		(net "I2C0_PEX0_SHPC_SCL")
	)
	(segment
		(start 70.106286 -305.576986)
		(end 70.106286 -307.048154)
		(width 0.15494)
		(layer "In5.Cu")
		(net "I2C0_PEX0_SHPC_SCL")
	)
	(segment
		(start 72.9488 -301.9044)
		(end 72.9488 -306.197)
		(width 0.15494)
		(layer "In5.Cu")
		(net "I2C0_PEX0_SHPC_SCL")
	)
	(segment
		(start 83.941158 -299.217842)
		(end 83.442302 -299.716698)
		(width 0.15494)
		(layer "In5.Cu")
		(net "I2C0_PEX0_SHPC_SCL")
	)
	(segment
		(start 70.106286 -307.048154)
		(end 69.854572 -307.299868)
		(width 0.15494)
		(layer "In5.Cu")
		(net "I2C0_PEX0_SHPC_SCL")
	)
	(segment
		(start 88.16848 -299.217842)
		(end 83.941158 -299.217842)
		(width 0.15494)
		(layer "In5.Cu")
		(net "I2C0_PEX0_SHPC_SCL")
	)
	(segment
		(start 70.273672 -305.4096)
		(end 70.106286 -305.576986)
		(width 0.15494)
		(layer "In5.Cu")
		(net "I2C0_PEX0_SHPC_SCL")
	)
	(segment
		(start 63.924942 -307.738018)
		(end 63.924942 -307.774594)
		(width 0.15494)
		(layer "In5.Cu")
		(net "I2C0_PEX0_SHPC_SCL")
	)
	(segment
		(start 92.458794 -301.050452)
		(end 91.49588 -300.087538)
		(width 0.15494)
		(layer "In5.Cu")
		(net "I2C0_PEX0_SHPC_SCL")
	)
	(segment
		(start 89.537286 -300.087538)
		(end 88.578436 -299.128688)
		(width 0.15494)
		(layer "In5.Cu")
		(net "I2C0_PEX0_SHPC_SCL")
	)
	(segment
		(start 64.363092 -307.299868)
		(end 63.924942 -307.738018)
		(width 0.15494)
		(layer "In5.Cu")
		(net "I2C0_PEX0_SHPC_SCL")
	)
	(segment
		(start 93.072966 -301.050452)
		(end 92.458794 -301.050452)
		(width 0.15494)
		(layer "In5.Cu")
		(net "I2C0_PEX0_SHPC_SCL")
	)
	(segment
		(start 280.449782 -292.099746)
		(end 279.974802 -291.624766)
		(width 0.249936)
		(layer "F.Cu")
		(net "PCEPLL7_VDDA18_PEX2")
	)
	(via
		(at 263.919462 -283.893514)
		(size 0.508)
		(drill 0.254)
		(layers "F.Cu" "B.Cu")
		(net "PCEPLL7_VDDA18_PEX2")
	)
	(via
		(at 279.974802 -291.624766)
		(size 0.4064)
		(drill 0.2032)
		(layers "F.Cu" "B.Cu")
		(net "PCEPLL7_VDDA18_PEX2")
	)
	(via
		(at 265.316462 -283.893514)
		(size 0.508)
		(drill 0.254)
		(layers "F.Cu" "B.Cu")
		(net "PCEPLL7_VDDA18_PEX2")
	)
	(segment
		(start 279.974802 -291.208206)
		(end 279.974802 -291.624766)
		(width 0.3048)
		(layer "B.Cu")
		(net "PCEPLL7_VDDA18_PEX2")
	)
	(segment
		(start 279.202642 -291.624766)
		(end 279.974802 -291.624766)
		(width 0.3048)
		(layer "B.Cu")
		(net "PCEPLL7_VDDA18_PEX2")
	)
	(segment
		(start 88.501728 -301.55261)
		(end 89.012268 -301.04207)
		(width 0.13208)
		(layer "F.Cu")
		(net "I2C0_PEX0_SHPC_SDA")
	)
	(segment
		(start 62.974728 -307.774594)
		(end 62.499748 -308.249828)
		(width 0.13208)
		(layer "F.Cu")
		(net "I2C0_PEX0_SHPC_SDA")
	)
	(via
		(at 62.974728 -307.774594)
		(size 0.4064)
		(drill 0.2032)
		(layers "F.Cu" "B.Cu")
		(net "I2C0_PEX0_SHPC_SDA")
	)
	(via
		(at 88.501728 -301.55261)
		(size 0.508)
		(drill 0.254)
		(layers "F.Cu" "B.Cu")
		(net "I2C0_PEX0_SHPC_SDA")
	)
	(segment
		(start 72.940164 -308.647084)
		(end 72.542908 -308.249828)
		(width 0.15494)
		(layer "In5.Cu")
		(net "I2C0_PEX0_SHPC_SDA")
	)
	(segment
		(start 78.2066 -304.2158)
		(end 78.2066 -309.4228)
		(width 0.15494)
		(layer "In5.Cu")
		(net "I2C0_PEX0_SHPC_SDA")
	)
	(segment
		(start 77.9526 -309.6768)
		(end 73.4568 -309.6768)
		(width 0.15494)
		(layer "In5.Cu")
		(net "I2C0_PEX0_SHPC_SDA")
	)
	(segment
		(start 77.6605 -303.6697)
		(end 78.2066 -304.2158)
		(width 0.15494)
		(layer "In5.Cu")
		(net "I2C0_PEX0_SHPC_SDA")
	)
	(segment
		(start 72.940164 -309.160164)
		(end 72.940164 -308.647084)
		(width 0.15494)
		(layer "In5.Cu")
		(net "I2C0_PEX0_SHPC_SDA")
	)
	(segment
		(start 86.94801 -300.73727)
		(end 85.012784 -300.73727)
		(width 0.15494)
		(layer "In5.Cu")
		(net "I2C0_PEX0_SHPC_SDA")
	)
	(segment
		(start 85.012784 -300.73727)
		(end 83.182206 -302.567848)
		(width 0.15494)
		(layer "In5.Cu")
		(net "I2C0_PEX0_SHPC_SDA")
	)
	(segment
		(start 71.058532 -307.552852)
		(end 71.058532 -307.966618)
		(width 0.15494)
		(layer "In5.Cu")
		(net "I2C0_PEX0_SHPC_SDA")
	)
	(segment
		(start 88.501728 -301.55261)
		(end 87.76335 -301.55261)
		(width 0.15494)
		(layer "In5.Cu")
		(net "I2C0_PEX0_SHPC_SDA")
	)
	(segment
		(start 71.712074 -307.316886)
		(end 71.294498 -307.316886)
		(width 0.15494)
		(layer "In5.Cu")
		(net "I2C0_PEX0_SHPC_SDA")
	)
	(segment
		(start 72.542908 -308.249828)
		(end 72.129142 -308.249828)
		(width 0.15494)
		(layer "In5.Cu")
		(net "I2C0_PEX0_SHPC_SDA")
	)
	(segment
		(start 71.058532 -307.966618)
		(end 70.775322 -308.249828)
		(width 0.15494)
		(layer "In5.Cu")
		(net "I2C0_PEX0_SHPC_SDA")
	)
	(segment
		(start 77.924152 -302.567848)
		(end 77.6605 -302.8315)
		(width 0.15494)
		(layer "In5.Cu")
		(net "I2C0_PEX0_SHPC_SDA")
	)
	(segment
		(start 63.449962 -308.249828)
		(end 62.974728 -307.774594)
		(width 0.15494)
		(layer "In5.Cu")
		(net "I2C0_PEX0_SHPC_SDA")
	)
	(segment
		(start 72.129142 -308.249828)
		(end 72.003158 -308.123844)
		(width 0.15494)
		(layer "In5.Cu")
		(net "I2C0_PEX0_SHPC_SDA")
	)
	(segment
		(start 87.76335 -301.55261)
		(end 86.94801 -300.73727)
		(width 0.15494)
		(layer "In5.Cu")
		(net "I2C0_PEX0_SHPC_SDA")
	)
	(segment
		(start 72.003158 -307.60797)
		(end 71.712074 -307.316886)
		(width 0.15494)
		(layer "In5.Cu")
		(net "I2C0_PEX0_SHPC_SDA")
	)
	(segment
		(start 77.6605 -302.8315)
		(end 77.6605 -303.6697)
		(width 0.15494)
		(layer "In5.Cu")
		(net "I2C0_PEX0_SHPC_SDA")
	)
	(segment
		(start 83.182206 -302.567848)
		(end 77.924152 -302.567848)
		(width 0.15494)
		(layer "In5.Cu")
		(net "I2C0_PEX0_SHPC_SDA")
	)
	(segment
		(start 73.4568 -309.6768)
		(end 72.940164 -309.160164)
		(width 0.15494)
		(layer "In5.Cu")
		(net "I2C0_PEX0_SHPC_SDA")
	)
	(segment
		(start 71.294498 -307.316886)
		(end 71.058532 -307.552852)
		(width 0.15494)
		(layer "In5.Cu")
		(net "I2C0_PEX0_SHPC_SDA")
	)
	(segment
		(start 70.775322 -308.249828)
		(end 63.449962 -308.249828)
		(width 0.15494)
		(layer "In5.Cu")
		(net "I2C0_PEX0_SHPC_SDA")
	)
	(segment
		(start 72.003158 -308.123844)
		(end 72.003158 -307.60797)
		(width 0.15494)
		(layer "In5.Cu")
		(net "I2C0_PEX0_SHPC_SDA")
	)
	(segment
		(start 78.2066 -309.4228)
		(end 77.9526 -309.6768)
		(width 0.15494)
		(layer "In5.Cu")
		(net "I2C0_PEX0_SHPC_SDA")
	)
	(segment
		(start 359.619042 -122.46991)
		(end 358.81056 -121.661428)
		(width 0.13208)
		(layer "F.Cu")
		(net "HP_NIC6_EN")
	)
	(segment
		(start 359.73131 -123.829064)
		(end 359.73131 -123.183396)
		(width 0.13208)
		(layer "F.Cu")
		(net "HP_NIC6_EN")
	)
	(segment
		(start 363.596936 -118.779036)
		(end 363.596936 -119.39143)
		(width 0.13208)
		(layer "F.Cu")
		(net "HP_NIC6_EN")
	)
	(segment
		(start 385.48564 -115.66525)
		(end 384.879088 -115.66525)
		(width 0.13208)
		(layer "F.Cu")
		(net "HP_NIC6_EN")
	)
	(segment
		(start 364.731808 -162.404044)
		(end 364.731808 -163.114736)
		(width 0.13208)
		(layer "F.Cu")
		(net "HP_NIC6_EN")
	)
	(segment
		(start 355.513386 -134.042404)
		(end 354.858066 -134.042404)
		(width 0.13208)
		(layer "F.Cu")
		(net "HP_NIC6_EN")
	)
	(segment
		(start 386.1308 -115.803934)
		(end 385.624324 -115.803934)
		(width 0.13208)
		(layer "F.Cu")
		(net "HP_NIC6_EN")
	)
	(segment
		(start 359.619042 -123.071128)
		(end 359.619042 -122.46991)
		(width 0.13208)
		(layer "F.Cu")
		(net "HP_NIC6_EN")
	)
	(segment
		(start 384.879088 -115.66525)
		(end 383.85369 -116.690648)
		(width 0.13208)
		(layer "F.Cu")
		(net "HP_NIC6_EN")
	)
	(segment
		(start 360.531156 -124.394722)
		(end 360.296968 -124.394722)
		(width 0.13208)
		(layer "F.Cu")
		(net "HP_NIC6_EN")
	)
	(segment
		(start 383.85369 -116.690648)
		(end 383.05613 -116.690648)
		(width 0.13208)
		(layer "F.Cu")
		(net "HP_NIC6_EN")
	)
	(segment
		(start 359.73131 -123.183396)
		(end 359.619042 -123.071128)
		(width 0.13208)
		(layer "F.Cu")
		(net "HP_NIC6_EN")
	)
	(segment
		(start 360.296968 -124.394722)
		(end 359.73131 -123.829064)
		(width 0.13208)
		(layer "F.Cu")
		(net "HP_NIC6_EN")
	)
	(segment
		(start 385.624324 -115.803934)
		(end 385.48564 -115.66525)
		(width 0.13208)
		(layer "F.Cu")
		(net "HP_NIC6_EN")
	)
	(via
		(at 386.1308 -115.803934)
		(size 0.508)
		(drill 0.254)
		(layers "F.Cu" "B.Cu")
		(net "HP_NIC6_EN")
	)
	(via
		(at 364.731808 -163.114736)
		(size 0.508)
		(drill 0.254)
		(layers "F.Cu" "B.Cu")
		(net "HP_NIC6_EN")
	)
	(via
		(at 363.596936 -119.39143)
		(size 0.508)
		(drill 0.254)
		(layers "F.Cu" "B.Cu")
		(net "HP_NIC6_EN")
	)
	(via
		(at 354.858066 -134.042404)
		(size 0.508)
		(drill 0.254)
		(layers "F.Cu" "B.Cu")
		(net "HP_NIC6_EN")
	)
	(via
		(at 359.619042 -122.46991)
		(size 0.508)
		(drill 0.254)
		(layers "F.Cu" "B.Cu")
		(net "HP_NIC6_EN")
	)
	(segment
		(start 355.005386 -145.266664)
		(end 355.869748 -144.402302)
		(width 0.15494)
		(layer "In7.Cu")
		(net "HP_NIC6_EN")
	)
	(segment
		(start 357.369364 -161.684716)
		(end 356.479856 -160.795208)
		(width 0.15494)
		(layer "In7.Cu")
		(net "HP_NIC6_EN")
	)
	(segment
		(start 358.443022 -123.64593)
		(end 359.619042 -122.46991)
		(width 0.15494)
		(layer "In7.Cu")
		(net "HP_NIC6_EN")
	)
	(segment
		(start 354.858066 -134.042404)
		(end 354.858066 -132.872226)
		(width 0.15494)
		(layer "In7.Cu")
		(net "HP_NIC6_EN")
	)
	(segment
		(start 356.479856 -160.795208)
		(end 356.479856 -158.17596)
		(width 0.15494)
		(layer "In7.Cu")
		(net "HP_NIC6_EN")
	)
	(segment
		(start 360.28376 -118.691406)
		(end 362.896912 -118.691406)
		(width 0.15494)
		(layer "In7.Cu")
		(net "HP_NIC6_EN")
	)
	(segment
		(start 355.4476 -136.463278)
		(end 355.4476 -134.692644)
		(width 0.15494)
		(layer "In7.Cu")
		(net "HP_NIC6_EN")
	)
	(segment
		(start 355.4476 -134.692644)
		(end 354.858066 -134.10311)
		(width 0.15494)
		(layer "In7.Cu")
		(net "HP_NIC6_EN")
	)
	(segment
		(start 359.619042 -122.46991)
		(end 359.88625 -122.202702)
		(width 0.15494)
		(layer "In7.Cu")
		(net "HP_NIC6_EN")
	)
	(segment
		(start 357.452422 -130.27787)
		(end 357.452422 -128.043178)
		(width 0.15494)
		(layer "In7.Cu")
		(net "HP_NIC6_EN")
	)
	(segment
		(start 357.452422 -128.043178)
		(end 358.443022 -127.052578)
		(width 0.15494)
		(layer "In7.Cu")
		(net "HP_NIC6_EN")
	)
	(segment
		(start 364.731808 -163.114736)
		(end 360.223562 -163.114736)
		(width 0.15494)
		(layer "In7.Cu")
		(net "HP_NIC6_EN")
	)
	(segment
		(start 358.793542 -161.684716)
		(end 357.369364 -161.684716)
		(width 0.15494)
		(layer "In7.Cu")
		(net "HP_NIC6_EN")
	)
	(segment
		(start 359.88625 -119.088916)
		(end 360.28376 -118.691406)
		(width 0.15494)
		(layer "In7.Cu")
		(net "HP_NIC6_EN")
	)
	(segment
		(start 360.223562 -163.114736)
		(end 358.793542 -161.684716)
		(width 0.15494)
		(layer "In7.Cu")
		(net "HP_NIC6_EN")
	)
	(segment
		(start 355.869748 -136.885426)
		(end 355.4476 -136.463278)
		(width 0.15494)
		(layer "In7.Cu")
		(net "HP_NIC6_EN")
	)
	(segment
		(start 354.858066 -134.10311)
		(end 354.858066 -134.042404)
		(width 0.15494)
		(layer "In7.Cu")
		(net "HP_NIC6_EN")
	)
	(segment
		(start 362.896912 -118.691406)
		(end 363.596936 -119.39143)
		(width 0.15494)
		(layer "In7.Cu")
		(net "HP_NIC6_EN")
	)
	(segment
		(start 354.858066 -132.872226)
		(end 357.452422 -130.27787)
		(width 0.15494)
		(layer "In7.Cu")
		(net "HP_NIC6_EN")
	)
	(segment
		(start 359.88625 -122.202702)
		(end 359.88625 -119.088916)
		(width 0.15494)
		(layer "In7.Cu")
		(net "HP_NIC6_EN")
	)
	(segment
		(start 356.479856 -158.17596)
		(end 355.005386 -156.70149)
		(width 0.15494)
		(layer "In7.Cu")
		(net "HP_NIC6_EN")
	)
	(segment
		(start 358.443022 -127.052578)
		(end 358.443022 -123.64593)
		(width 0.15494)
		(layer "In7.Cu")
		(net "HP_NIC6_EN")
	)
	(segment
		(start 355.869748 -144.402302)
		(end 355.869748 -136.885426)
		(width 0.15494)
		(layer "In7.Cu")
		(net "HP_NIC6_EN")
	)
	(segment
		(start 355.005386 -156.70149)
		(end 355.005386 -145.266664)
		(width 0.15494)
		(layer "In7.Cu")
		(net "HP_NIC6_EN")
	)
	(segment
		(start 370.110004 -116.259864)
		(end 384.353054 -116.259864)
		(width 0.15494)
		(layer "In13.Cu")
		(net "HP_NIC6_EN")
	)
	(segment
		(start 364.784894 -118.203472)
		(end 368.166396 -118.203472)
		(width 0.15494)
		(layer "In13.Cu")
		(net "HP_NIC6_EN")
	)
	(segment
		(start 384.808984 -115.803934)
		(end 386.1308 -115.803934)
		(width 0.15494)
		(layer "In13.Cu")
		(net "HP_NIC6_EN")
	)
	(segment
		(start 363.596936 -119.39143)
		(end 364.784894 -118.203472)
		(width 0.15494)
		(layer "In13.Cu")
		(net "HP_NIC6_EN")
	)
	(segment
		(start 368.166396 -118.203472)
		(end 370.110004 -116.259864)
		(width 0.15494)
		(layer "In13.Cu")
		(net "HP_NIC6_EN")
	)
	(segment
		(start 384.353054 -116.259864)
		(end 384.808984 -115.803934)
		(width 0.15494)
		(layer "In13.Cu")
		(net "HP_NIC6_EN")
	)
	(segment
		(start 280.449782 -299.699934)
		(end 279.974802 -300.174914)
		(width 0.249936)
		(layer "F.Cu")
		(net "PCEPLL0_VDDA18_PEX2")
	)
	(via
		(at 279.974802 -300.174914)
		(size 0.4064)
		(drill 0.2032)
		(layers "F.Cu" "B.Cu")
		(net "PCEPLL0_VDDA18_PEX2")
	)
	(via
		(at 265.316462 -296.695114)
		(size 0.508)
		(drill 0.254)
		(layers "F.Cu" "B.Cu")
		(net "PCEPLL0_VDDA18_PEX2")
	)
	(via
		(at 263.919462 -296.695114)
		(size 0.508)
		(drill 0.254)
		(layers "F.Cu" "B.Cu")
		(net "PCEPLL0_VDDA18_PEX2")
	)
	(segment
		(start 279.977342 -300.177454)
		(end 279.974802 -300.174914)
		(width 0.3048)
		(layer "B.Cu")
		(net "PCEPLL0_VDDA18_PEX2")
	)
	(segment
		(start 279.977342 -300.172374)
		(end 279.974802 -300.174914)
		(width 0.3048)
		(layer "B.Cu")
		(net "PCEPLL0_VDDA18_PEX2")
	)
	(segment
		(start 279.977342 -300.5328)
		(end 279.977342 -300.177454)
		(width 0.3048)
		(layer "B.Cu")
		(net "PCEPLL0_VDDA18_PEX2")
	)
	(segment
		(start 279.977342 -299.8089)
		(end 279.977342 -300.172374)
		(width 0.3048)
		(layer "B.Cu")
		(net "PCEPLL0_VDDA18_PEX2")
	)
	(segment
		(start 91.895168 -301.556928)
		(end 91.895168 -301.57674)
		(width 0.13208)
		(layer "F.Cu")
		(net "I2C0_PEX0_SCL")
	)
	(segment
		(start 69.624956 -307.774848)
		(end 69.149976 -308.249828)
		(width 0.13208)
		(layer "F.Cu")
		(net "I2C0_PEX0_SCL")
	)
	(segment
		(start 91.379294 -301.041054)
		(end 91.895168 -301.556928)
		(width 0.13208)
		(layer "F.Cu")
		(net "I2C0_PEX0_SCL")
	)
	(via
		(at 91.895168 -301.57674)
		(size 0.508)
		(drill 0.254)
		(layers "F.Cu" "B.Cu")
		(net "I2C0_PEX0_SCL")
	)
	(via
		(at 69.624956 -307.774848)
		(size 0.4064)
		(drill 0.2032)
		(layers "F.Cu" "B.Cu")
		(net "I2C0_PEX0_SCL")
	)
	(segment
		(start 71.703946 -306.309268)
		(end 71.27113 -306.309268)
		(width 0.15494)
		(layer "In5.Cu")
		(net "I2C0_PEX0_SCL")
	)
	(segment
		(start 75.0824 -302.0568)
		(end 74.3966 -302.7426)
		(width 0.15494)
		(layer "In5.Cu")
		(net "I2C0_PEX0_SCL")
	)
	(segment
		(start 70.023228 -307.774848)
		(end 69.624956 -307.774848)
		(width 0.15494)
		(layer "In5.Cu")
		(net "I2C0_PEX0_SCL")
	)
	(segment
		(start 72.121268 -307.34)
		(end 71.971662 -307.190394)
		(width 0.15494)
		(layer "In5.Cu")
		(net "I2C0_PEX0_SCL")
	)
	(segment
		(start 71.971662 -306.576984)
		(end 71.703946 -306.309268)
		(width 0.15494)
		(layer "In5.Cu")
		(net "I2C0_PEX0_SCL")
	)
	(segment
		(start 73.3044 -306.8066)
		(end 72.771 -307.34)
		(width 0.15494)
		(layer "In5.Cu")
		(net "I2C0_PEX0_SCL")
	)
	(segment
		(start 74.3966 -302.7426)
		(end 74.3966 -306.6796)
		(width 0.15494)
		(layer "In5.Cu")
		(net "I2C0_PEX0_SCL")
	)
	(segment
		(start 87.488522 -299.701458)
		(end 84.264246 -299.701458)
		(width 0.15494)
		(layer "In5.Cu")
		(net "I2C0_PEX0_SCL")
	)
	(segment
		(start 72.771 -307.34)
		(end 72.121268 -307.34)
		(width 0.15494)
		(layer "In5.Cu")
		(net "I2C0_PEX0_SCL")
	)
	(segment
		(start 71.27113 -306.309268)
		(end 71.050658 -306.52974)
		(width 0.15494)
		(layer "In5.Cu")
		(net "I2C0_PEX0_SCL")
	)
	(segment
		(start 71.050658 -306.52974)
		(end 71.050658 -307.088286)
		(width 0.15494)
		(layer "In5.Cu")
		(net "I2C0_PEX0_SCL")
	)
	(segment
		(start 70.458076 -307.34)
		(end 70.023228 -307.774848)
		(width 0.15494)
		(layer "In5.Cu")
		(net "I2C0_PEX0_SCL")
	)
	(segment
		(start 71.971662 -307.190394)
		(end 71.971662 -306.576984)
		(width 0.15494)
		(layer "In5.Cu")
		(net "I2C0_PEX0_SCL")
	)
	(segment
		(start 75.92949 -300.65091)
		(end 75.0824 -301.498)
		(width 0.15494)
		(layer "In5.Cu")
		(net "I2C0_PEX0_SCL")
	)
	(segment
		(start 88.345264 -300.5582)
		(end 87.488522 -299.701458)
		(width 0.15494)
		(layer "In5.Cu")
		(net "I2C0_PEX0_SCL")
	)
	(segment
		(start 71.050658 -307.088286)
		(end 70.798944 -307.34)
		(width 0.15494)
		(layer "In5.Cu")
		(net "I2C0_PEX0_SCL")
	)
	(segment
		(start 74.3966 -306.6796)
		(end 74.2696 -306.8066)
		(width 0.15494)
		(layer "In5.Cu")
		(net "I2C0_PEX0_SCL")
	)
	(segment
		(start 91.308428 -300.5582)
		(end 88.345264 -300.5582)
		(width 0.15494)
		(layer "In5.Cu")
		(net "I2C0_PEX0_SCL")
	)
	(segment
		(start 91.895168 -301.14494)
		(end 91.308428 -300.5582)
		(width 0.15494)
		(layer "In5.Cu")
		(net "I2C0_PEX0_SCL")
	)
	(segment
		(start 70.798944 -307.34)
		(end 70.458076 -307.34)
		(width 0.15494)
		(layer "In5.Cu")
		(net "I2C0_PEX0_SCL")
	)
	(segment
		(start 74.2696 -306.8066)
		(end 73.3044 -306.8066)
		(width 0.15494)
		(layer "In5.Cu")
		(net "I2C0_PEX0_SCL")
	)
	(segment
		(start 91.895168 -301.57674)
		(end 91.895168 -301.14494)
		(width 0.15494)
		(layer "In5.Cu")
		(net "I2C0_PEX0_SCL")
	)
	(segment
		(start 83.314794 -300.65091)
		(end 75.92949 -300.65091)
		(width 0.15494)
		(layer "In5.Cu")
		(net "I2C0_PEX0_SCL")
	)
	(segment
		(start 84.264246 -299.701458)
		(end 83.314794 -300.65091)
		(width 0.15494)
		(layer "In5.Cu")
		(net "I2C0_PEX0_SCL")
	)
	(segment
		(start 75.0824 -301.498)
		(end 75.0824 -302.0568)
		(width 0.15494)
		(layer "In5.Cu")
		(net "I2C0_PEX0_SCL")
	)
	(segment
		(start 219.432378 -84.765388)
		(end 218.427554 -83.760564)
		(width 0.13208)
		(layer "F.Cu")
		(net "SSD_LED_IOEXP_A0")
	)
	(segment
		(start 223.622108 -85.684868)
		(end 222.417386 -85.684868)
		(width 0.13208)
		(layer "F.Cu")
		(net "SSD_LED_IOEXP_A0")
	)
	(segment
		(start 220.960696 -84.765388)
		(end 219.432378 -84.765388)
		(width 0.13208)
		(layer "F.Cu")
		(net "SSD_LED_IOEXP_A0")
	)
	(segment
		(start 222.417386 -85.684868)
		(end 222.417386 -85.382608)
		(width 0.13208)
		(layer "F.Cu")
		(net "SSD_LED_IOEXP_A0")
	)
	(segment
		(start 218.427554 -83.760564)
		(end 217.422222 -83.760564)
		(width 0.13208)
		(layer "F.Cu")
		(net "SSD_LED_IOEXP_A0")
	)
	(segment
		(start 222.417386 -85.382608)
		(end 222.197676 -85.162898)
		(width 0.13208)
		(layer "F.Cu")
		(net "SSD_LED_IOEXP_A0")
	)
	(segment
		(start 222.197676 -85.162898)
		(end 221.358206 -85.162898)
		(width 0.13208)
		(layer "F.Cu")
		(net "SSD_LED_IOEXP_A0")
	)
	(segment
		(start 221.358206 -85.162898)
		(end 220.960696 -84.765388)
		(width 0.13208)
		(layer "F.Cu")
		(net "SSD_LED_IOEXP_A0")
	)
	(via
		(at 220.960696 -84.765388)
		(size 0.508)
		(drill 0.254)
		(layers "F.Cu" "B.Cu")
		(net "SSD_LED_IOEXP_A0")
	)
	(segment
		(start 142.961614 -308.89448)
		(end 143.48206 -309.414926)
		(width 0.13208)
		(layer "F.Cu")
		(net "IRQ_PEX1_CLKREQ_INT_N")
	)
	(segment
		(start 164.349938 -308.249828)
		(end 163.874958 -308.724808)
		(width 0.13208)
		(layer "F.Cu")
		(net "IRQ_PEX1_CLKREQ_INT_N")
	)
	(via
		(at 163.874958 -308.724808)
		(size 0.4064)
		(drill 0.2032)
		(layers "F.Cu" "B.Cu")
		(net "IRQ_PEX1_CLKREQ_INT_N")
	)
	(via
		(at 143.48206 -309.414926)
		(size 0.508)
		(drill 0.254)
		(layers "F.Cu" "B.Cu")
		(net "IRQ_PEX1_CLKREQ_INT_N")
	)
	(segment
		(start 162.429698 -307.8226)
		(end 148.801836 -307.8226)
		(width 0.13208)
		(layer "B.Cu")
		(net "IRQ_PEX1_CLKREQ_INT_N")
	)
	(segment
		(start 163.874958 -308.724808)
		(end 163.874958 -308.694074)
		(width 0.13208)
		(layer "B.Cu")
		(net "IRQ_PEX1_CLKREQ_INT_N")
	)
	(segment
		(start 163.440364 -308.25948)
		(end 162.866578 -308.25948)
		(width 0.13208)
		(layer "B.Cu")
		(net "IRQ_PEX1_CLKREQ_INT_N")
	)
	(segment
		(start 148.801836 -307.8226)
		(end 147.20951 -309.414926)
		(width 0.13208)
		(layer "B.Cu")
		(net "IRQ_PEX1_CLKREQ_INT_N")
	)
	(segment
		(start 162.866578 -308.25948)
		(end 162.429698 -307.8226)
		(width 0.13208)
		(layer "B.Cu")
		(net "IRQ_PEX1_CLKREQ_INT_N")
	)
	(segment
		(start 163.874958 -308.694074)
		(end 163.440364 -308.25948)
		(width 0.13208)
		(layer "B.Cu")
		(net "IRQ_PEX1_CLKREQ_INT_N")
	)
	(segment
		(start 147.20951 -309.414926)
		(end 143.48206 -309.414926)
		(width 0.13208)
		(layer "B.Cu")
		(net "IRQ_PEX1_CLKREQ_INT_N")
	)
	(segment
		(start 104.496362 -389.076438)
		(end 104.496362 -389.344662)
		(width 0.13462)
		(layer "F.Cu")
		(net "USB2_GPU_HMC_R_DN")
	)
	(segment
		(start 105.38968 -386.626608)
		(end 105.38968 -385.585462)
		(width 0.13462)
		(layer "F.Cu")
		(net "USB2_GPU_HMC_R_DN")
	)
	(segment
		(start 104.376982 -389.464042)
		(end 104.376982 -389.741918)
		(width 0.13462)
		(layer "F.Cu")
		(net "USB2_GPU_HMC_R_DN")
	)
	(segment
		(start 105.379266 -388.51459)
		(end 105.235502 -388.658354)
		(width 0.13462)
		(layer "F.Cu")
		(net "USB2_GPU_HMC_R_DN")
	)
	(segment
		(start 105.379266 -387.197346)
		(end 105.379266 -388.51459)
		(width 0.13462)
		(layer "F.Cu")
		(net "USB2_GPU_HMC_R_DN")
	)
	(segment
		(start 105.099104 -386.917184)
		(end 105.379266 -387.197346)
		(width 0.13462)
		(layer "F.Cu")
		(net "USB2_GPU_HMC_R_DN")
	)
	(segment
		(start 105.38968 -385.585462)
		(end 105.093262 -385.289044)
		(width 0.13462)
		(layer "F.Cu")
		(net "USB2_GPU_HMC_R_DN")
	)
	(segment
		(start 105.099104 -386.917184)
		(end 105.38968 -386.626608)
		(width 0.13462)
		(layer "F.Cu")
		(net "USB2_GPU_HMC_R_DN")
	)
	(segment
		(start 104.914446 -388.658354)
		(end 104.496362 -389.076438)
		(width 0.13462)
		(layer "F.Cu")
		(net "USB2_GPU_HMC_R_DN")
	)
	(segment
		(start 105.235502 -388.658354)
		(end 104.914446 -388.658354)
		(width 0.13462)
		(layer "F.Cu")
		(net "USB2_GPU_HMC_R_DN")
	)
	(segment
		(start 54.404514 -364.086648)
		(end 54.404514 -363.780832)
		(width 0.13462)
		(layer "F.Cu")
		(net "USB2_GPU_HMC_R_DN")
	)
	(segment
		(start 104.496362 -389.344662)
		(end 104.376982 -389.464042)
		(width 0.13462)
		(layer "F.Cu")
		(net "USB2_GPU_HMC_R_DN")
	)
	(segment
		(start 54.89575 -365.767112)
		(end 55.1942 -365.468662)
		(width 0.13462)
		(layer "F.Cu")
		(net "USB2_GPU_HMC_R_DN")
	)
	(segment
		(start 55.1942 -365.468662)
		(end 55.1942 -364.876334)
		(width 0.13462)
		(layer "F.Cu")
		(net "USB2_GPU_HMC_R_DN")
	)
	(segment
		(start 55.1942 -364.876334)
		(end 54.404514 -364.086648)
		(width 0.13462)
		(layer "F.Cu")
		(net "USB2_GPU_HMC_R_DN")
	)
	(via
		(at 105.093262 -385.289044)
		(size 0.508)
		(drill 0.254)
		(layers "F.Cu" "B.Cu")
		(net "USB2_GPU_HMC_R_DN")
	)
	(via
		(at 54.89575 -365.767112)
		(size 0.508)
		(drill 0.254)
		(layers "F.Cu" "B.Cu")
		(net "USB2_GPU_HMC_R_DN")
	)
	(via
		(at 60.29706 -365.057944)
		(size 0.4064)
		(drill 0.2032)
		(layers "F.Cu" "B.Cu")
		(net "USB2_GPU_HMC_R_DN")
	)
	(segment
		(start 55.568342 -366.720374)
		(end 55.251096 -366.403128)
		(width 0.13462)
		(layer "B.Cu")
		(net "USB2_GPU_HMC_R_DN")
	)
	(segment
		(start 56.49468 -366.720374)
		(end 55.568342 -366.720374)
		(width 0.13462)
		(layer "B.Cu")
		(net "USB2_GPU_HMC_R_DN")
	)
	(segment
		(start 105.381552 -384.170682)
		(end 105.381552 -385.000754)
		(width 0.13462)
		(layer "B.Cu")
		(net "USB2_GPU_HMC_R_DN")
	)
	(segment
		(start 55.251096 -366.403128)
		(end 55.251096 -366.122458)
		(width 0.13462)
		(layer "B.Cu")
		(net "USB2_GPU_HMC_R_DN")
	)
	(segment
		(start 55.251096 -366.122458)
		(end 54.89575 -365.767112)
		(width 0.13462)
		(layer "B.Cu")
		(net "USB2_GPU_HMC_R_DN")
	)
	(segment
		(start 108.289344 -374.793002)
		(end 108.289344 -381.26289)
		(width 0.13462)
		(layer "B.Cu")
		(net "USB2_GPU_HMC_R_DN")
	)
	(segment
		(start 58.15711 -365.057944)
		(end 56.49468 -366.720374)
		(width 0.13462)
		(layer "B.Cu")
		(net "USB2_GPU_HMC_R_DN")
	)
	(segment
		(start 108.289344 -381.26289)
		(end 105.381552 -384.170682)
		(width 0.13462)
		(layer "B.Cu")
		(net "USB2_GPU_HMC_R_DN")
	)
	(segment
		(start 102.79634 -373.033798)
		(end 106.53014 -373.033798)
		(width 0.13462)
		(layer "B.Cu")
		(net "USB2_GPU_HMC_R_DN")
	)
	(segment
		(start 105.381552 -385.000754)
		(end 105.093262 -385.289044)
		(width 0.13462)
		(layer "B.Cu")
		(net "USB2_GPU_HMC_R_DN")
	)
	(segment
		(start 106.53014 -373.033798)
		(end 108.289344 -374.793002)
		(width 0.13462)
		(layer "B.Cu")
		(net "USB2_GPU_HMC_R_DN")
	)
	(segment
		(start 94.820486 -365.057944)
		(end 102.79634 -373.033798)
		(width 0.13462)
		(layer "B.Cu")
		(net "USB2_GPU_HMC_R_DN")
	)
	(segment
		(start 60.29706 -365.057944)
		(end 58.15711 -365.057944)
		(width 0.13462)
		(layer "B.Cu")
		(net "USB2_GPU_HMC_R_DN")
	)
	(segment
		(start 60.29706 -365.057944)
		(end 94.820486 -365.057944)
		(width 0.13462)
		(layer "B.Cu")
		(net "USB2_GPU_HMC_R_DN")
	)
	(segment
		(start 225.867722 -215.104218)
		(end 225.467926 -214.704422)
		(width 0.13208)
		(layer "F.Cu")
		(net "UART_BIC_DEBUG_TX")
	)
	(segment
		(start 211.610448 -210.766152)
		(end 211.610448 -211.71281)
		(width 0.13208)
		(layer "F.Cu")
		(net "UART_BIC_DEBUG_TX")
	)
	(segment
		(start 211.610448 -210.766152)
		(end 210.806284 -210.766152)
		(width 0.13208)
		(layer "F.Cu")
		(net "UART_BIC_DEBUG_TX")
	)
	(via
		(at 210.806284 -210.766152)
		(size 0.508)
		(drill 0.254)
		(layers "F.Cu" "B.Cu")
		(net "UART_BIC_DEBUG_TX")
	)
	(via
		(at 220.880686 -213.722966)
		(size 0.6604)
		(drill 0.3302)
		(layers "F.Cu" "B.Cu")
		(net "UART_BIC_DEBUG_TX")
	)
	(via
		(at 225.467926 -214.704422)
		(size 0.4572)
		(drill 0.254)
		(layers "F.Cu" "B.Cu")
		(net "UART_BIC_DEBUG_TX")
	)
	(segment
		(start 219.169742 -212.722714)
		(end 220.169994 -213.722966)
		(width 0.13208)
		(layer "B.Cu")
		(net "UART_BIC_DEBUG_TX")
	)
	(segment
		(start 213.660482 -210.539076)
		(end 214.854536 -211.73313)
		(width 0.13208)
		(layer "B.Cu")
		(net "UART_BIC_DEBUG_TX")
	)
	(segment
		(start 225.237548 -214.704422)
		(end 225.467926 -214.704422)
		(width 0.0889)
		(layer "B.Cu")
		(net "UART_BIC_DEBUG_TX")
	)
	(segment
		(start 211.229448 -210.766152)
		(end 211.456524 -210.539076)
		(width 0.13208)
		(layer "B.Cu")
		(net "UART_BIC_DEBUG_TX")
	)
	(segment
		(start 214.981028 -212.398102)
		(end 215.30564 -212.722714)
		(width 0.13208)
		(layer "B.Cu")
		(net "UART_BIC_DEBUG_TX")
	)
	(segment
		(start 223.002856 -213.869524)
		(end 224.07245 -213.869524)
		(width 0.13208)
		(layer "B.Cu")
		(net "UART_BIC_DEBUG_TX")
	)
	(segment
		(start 224.07245 -213.869524)
		(end 224.503488 -214.300562)
		(width 0.0889)
		(layer "B.Cu")
		(net "UART_BIC_DEBUG_TX")
	)
	(segment
		(start 210.806284 -210.766152)
		(end 211.229448 -210.766152)
		(width 0.13208)
		(layer "B.Cu")
		(net "UART_BIC_DEBUG_TX")
	)
	(segment
		(start 214.981028 -212.333078)
		(end 214.981028 -212.398102)
		(width 0.13208)
		(layer "B.Cu")
		(net "UART_BIC_DEBUG_TX")
	)
	(segment
		(start 211.456524 -210.539076)
		(end 213.660482 -210.539076)
		(width 0.13208)
		(layer "B.Cu")
		(net "UART_BIC_DEBUG_TX")
	)
	(segment
		(start 220.880686 -213.722966)
		(end 222.856298 -213.722966)
		(width 0.13208)
		(layer "B.Cu")
		(net "UART_BIC_DEBUG_TX")
	)
	(segment
		(start 224.503488 -214.300562)
		(end 224.833688 -214.300562)
		(width 0.0889)
		(layer "B.Cu")
		(net "UART_BIC_DEBUG_TX")
	)
	(segment
		(start 214.854536 -212.206586)
		(end 214.981028 -212.333078)
		(width 0.13208)
		(layer "B.Cu")
		(net "UART_BIC_DEBUG_TX")
	)
	(segment
		(start 224.833688 -214.300562)
		(end 225.237548 -214.704422)
		(width 0.0889)
		(layer "B.Cu")
		(net "UART_BIC_DEBUG_TX")
	)
	(segment
		(start 220.169994 -213.722966)
		(end 220.880686 -213.722966)
		(width 0.13208)
		(layer "B.Cu")
		(net "UART_BIC_DEBUG_TX")
	)
	(segment
		(start 222.856298 -213.722966)
		(end 223.002856 -213.869524)
		(width 0.13208)
		(layer "B.Cu")
		(net "UART_BIC_DEBUG_TX")
	)
	(segment
		(start 214.854536 -211.73313)
		(end 214.854536 -212.206586)
		(width 0.13208)
		(layer "B.Cu")
		(net "UART_BIC_DEBUG_TX")
	)
	(segment
		(start 215.30564 -212.722714)
		(end 219.169742 -212.722714)
		(width 0.13208)
		(layer "B.Cu")
		(net "UART_BIC_DEBUG_TX")
	)
	(segment
		(start 90.699082 -301.04207)
		(end 90.028268 -301.04207)
		(width 0.13208)
		(layer "F.Cu")
		(net "I2C0_PEX0_SDA")
	)
	(segment
		(start 72.474836 -307.774848)
		(end 72.949816 -308.249828)
		(width 0.13208)
		(layer "F.Cu")
		(net "I2C0_PEX0_SDA")
	)
	(via
		(at 90.699082 -301.04207)
		(size 0.508)
		(drill 0.254)
		(layers "F.Cu" "B.Cu")
		(net "I2C0_PEX0_SDA")
	)
	(via
		(at 72.474836 -307.774848)
		(size 0.4064)
		(drill 0.2032)
		(layers "F.Cu" "B.Cu")
		(net "I2C0_PEX0_SDA")
	)
	(segment
		(start 76.2762 -304.25771)
		(end 76.74991 -303.784)
		(width 0.15494)
		(layer "In5.Cu")
		(net "I2C0_PEX0_SDA")
	)
	(segment
		(start 72.474836 -307.774848)
		(end 72.875648 -307.774848)
		(width 0.15494)
		(layer "In5.Cu")
		(net "I2C0_PEX0_SDA")
	)
	(segment
		(start 87.164164 -300.230794)
		(end 87.97544 -301.04207)
		(width 0.15494)
		(layer "In5.Cu")
		(net "I2C0_PEX0_SDA")
	)
	(segment
		(start 73.8886 -308.7878)
		(end 75.946 -308.7878)
		(width 0.15494)
		(layer "In5.Cu")
		(net "I2C0_PEX0_SDA")
	)
	(segment
		(start 87.97544 -301.04207)
		(end 90.699082 -301.04207)
		(width 0.15494)
		(layer "In5.Cu")
		(net "I2C0_PEX0_SDA")
	)
	(segment
		(start 77.100938 -301.613062)
		(end 83.203034 -301.613062)
		(width 0.15494)
		(layer "In5.Cu")
		(net "I2C0_PEX0_SDA")
	)
	(segment
		(start 72.875648 -307.774848)
		(end 73.8886 -308.7878)
		(width 0.15494)
		(layer "In5.Cu")
		(net "I2C0_PEX0_SDA")
	)
	(segment
		(start 83.203034 -301.613062)
		(end 84.585302 -300.230794)
		(width 0.15494)
		(layer "In5.Cu")
		(net "I2C0_PEX0_SDA")
	)
	(segment
		(start 76.2762 -308.4576)
		(end 76.2762 -304.25771)
		(width 0.15494)
		(layer "In5.Cu")
		(net "I2C0_PEX0_SDA")
	)
	(segment
		(start 75.946 -308.7878)
		(end 76.2762 -308.4576)
		(width 0.15494)
		(layer "In5.Cu")
		(net "I2C0_PEX0_SDA")
	)
	(segment
		(start 84.585302 -300.230794)
		(end 87.164164 -300.230794)
		(width 0.15494)
		(layer "In5.Cu")
		(net "I2C0_PEX0_SDA")
	)
	(segment
		(start 76.74991 -303.784)
		(end 76.74991 -301.96409)
		(width 0.15494)
		(layer "In5.Cu")
		(net "I2C0_PEX0_SDA")
	)
	(segment
		(start 76.74991 -301.96409)
		(end 77.100938 -301.613062)
		(width 0.15494)
		(layer "In5.Cu")
		(net "I2C0_PEX0_SDA")
	)
	(segment
		(start 218.421204 -84.41055)
		(end 219.329254 -85.3186)
		(width 0.13208)
		(layer "F.Cu")
		(net "SMB_SSD_LED_IOEXP_SCL")
	)
	(segment
		(start 223.622108 -86.700868)
		(end 223.254062 -87.068914)
		(width 0.13208)
		(layer "F.Cu")
		(net "SMB_SSD_LED_IOEXP_SCL")
	)
	(segment
		(start 217.422222 -84.41055)
		(end 218.421204 -84.41055)
		(width 0.13208)
		(layer "F.Cu")
		(net "SMB_SSD_LED_IOEXP_SCL")
	)
	(segment
		(start 223.254062 -87.068914)
		(end 221.084902 -87.068914)
		(width 0.13208)
		(layer "F.Cu")
		(net "SMB_SSD_LED_IOEXP_SCL")
	)
	(segment
		(start 220.98 -86.0806)
		(end 220.98 -86.964012)
		(width 0.13208)
		(layer "F.Cu")
		(net "SMB_SSD_LED_IOEXP_SCL")
	)
	(segment
		(start 220.98 -86.964012)
		(end 221.084902 -87.068914)
		(width 0.13208)
		(layer "F.Cu")
		(net "SMB_SSD_LED_IOEXP_SCL")
	)
	(segment
		(start 220.218 -85.3186)
		(end 220.98 -86.0806)
		(width 0.13208)
		(layer "F.Cu")
		(net "SMB_SSD_LED_IOEXP_SCL")
	)
	(segment
		(start 219.329254 -85.3186)
		(end 220.218 -85.3186)
		(width 0.13208)
		(layer "F.Cu")
		(net "SMB_SSD_LED_IOEXP_SCL")
	)
	(via
		(at 221.084902 -87.068914)
		(size 0.508)
		(drill 0.254)
		(layers "F.Cu" "B.Cu")
		(net "SMB_SSD_LED_IOEXP_SCL")
	)
	(segment
		(start 225.067622 -218.30411)
		(end 224.667826 -217.904314)
		(width 0.13208)
		(layer "F.Cu")
		(net "BIC_PECI")
	)
	(via
		(at 224.667826 -217.904314)
		(size 0.4572)
		(drill 0.254)
		(layers "F.Cu" "B.Cu")
		(net "BIC_PECI")
	)
	(via
		(at 219.765372 -216.740994)
		(size 0.6604)
		(drill 0.3302)
		(layers "F.Cu" "B.Cu")
		(net "BIC_PECI")
	)
	(segment
		(start 220.928692 -217.904314)
		(end 224.667826 -217.904314)
		(width 0.13208)
		(layer "B.Cu")
		(net "BIC_PECI")
	)
	(segment
		(start 217.647774 -216.388696)
		(end 217.753946 -216.388696)
		(width 0.13208)
		(layer "B.Cu")
		(net "BIC_PECI")
	)
	(segment
		(start 217.753946 -216.388696)
		(end 218.106244 -216.740994)
		(width 0.13208)
		(layer "B.Cu")
		(net "BIC_PECI")
	)
	(segment
		(start 219.765372 -216.740994)
		(end 220.928692 -217.904314)
		(width 0.13208)
		(layer "B.Cu")
		(net "BIC_PECI")
	)
	(segment
		(start 218.106244 -216.740994)
		(end 219.765372 -216.740994)
		(width 0.13208)
		(layer "B.Cu")
		(net "BIC_PECI")
	)
	(segment
		(start 55.75935 -365.767112)
		(end 55.46852 -365.476282)
		(width 0.13462)
		(layer "F.Cu")
		(net "USB2_GPU_HMC_R_DP")
	)
	(segment
		(start 104.770682 -389.19023)
		(end 104.770682 -389.33755)
		(width 0.13462)
		(layer "F.Cu")
		(net "USB2_GPU_HMC_R_DP")
	)
	(segment
		(start 55.46852 -365.476282)
		(end 55.46852 -364.868714)
		(width 0.13462)
		(layer "F.Cu")
		(net "USB2_GPU_HMC_R_DP")
	)
	(segment
		(start 105.653586 -387.214364)
		(end 105.653586 -388.628382)
		(width 0.13462)
		(layer "F.Cu")
		(net "USB2_GPU_HMC_R_DP")
	)
	(segment
		(start 105.664 -386.630418)
		(end 105.664 -385.581906)
		(width 0.13462)
		(layer "F.Cu")
		(net "USB2_GPU_HMC_R_DP")
	)
	(segment
		(start 104.877108 -389.443976)
		(end 104.877108 -389.741918)
		(width 0.13462)
		(layer "F.Cu")
		(net "USB2_GPU_HMC_R_DP")
	)
	(segment
		(start 105.950766 -386.917184)
		(end 105.664 -386.630418)
		(width 0.13462)
		(layer "F.Cu")
		(net "USB2_GPU_HMC_R_DP")
	)
	(segment
		(start 105.950766 -386.917184)
		(end 105.653586 -387.214364)
		(width 0.13462)
		(layer "F.Cu")
		(net "USB2_GPU_HMC_R_DP")
	)
	(segment
		(start 105.028238 -388.932674)
		(end 104.770682 -389.19023)
		(width 0.13462)
		(layer "F.Cu")
		(net "USB2_GPU_HMC_R_DP")
	)
	(segment
		(start 104.770682 -389.33755)
		(end 104.877108 -389.443976)
		(width 0.13462)
		(layer "F.Cu")
		(net "USB2_GPU_HMC_R_DP")
	)
	(segment
		(start 55.46852 -364.868714)
		(end 56.271922 -364.065312)
		(width 0.13462)
		(layer "F.Cu")
		(net "USB2_GPU_HMC_R_DP")
	)
	(segment
		(start 105.653586 -388.628382)
		(end 105.349294 -388.932674)
		(width 0.13462)
		(layer "F.Cu")
		(net "USB2_GPU_HMC_R_DP")
	)
	(segment
		(start 105.664 -385.581906)
		(end 105.956862 -385.289044)
		(width 0.13462)
		(layer "F.Cu")
		(net "USB2_GPU_HMC_R_DP")
	)
	(segment
		(start 56.271922 -364.065312)
		(end 56.271922 -363.756194)
		(width 0.13462)
		(layer "F.Cu")
		(net "USB2_GPU_HMC_R_DP")
	)
	(segment
		(start 105.349294 -388.932674)
		(end 105.028238 -388.932674)
		(width 0.13462)
		(layer "F.Cu")
		(net "USB2_GPU_HMC_R_DP")
	)
	(via
		(at 63.930276 -364.783624)
		(size 0.4064)
		(drill 0.2032)
		(layers "F.Cu" "B.Cu")
		(net "USB2_GPU_HMC_R_DP")
	)
	(via
		(at 105.956862 -385.289044)
		(size 0.508)
		(drill 0.254)
		(layers "F.Cu" "B.Cu")
		(net "USB2_GPU_HMC_R_DP")
	)
	(via
		(at 55.75935 -365.767112)
		(size 0.508)
		(drill 0.254)
		(layers "F.Cu" "B.Cu")
		(net "USB2_GPU_HMC_R_DP")
	)
	(segment
		(start 58.043318 -364.783624)
		(end 56.380888 -366.446054)
		(width 0.13462)
		(layer "B.Cu")
		(net "USB2_GPU_HMC_R_DP")
	)
	(segment
		(start 105.655872 -384.284474)
		(end 105.655872 -384.988054)
		(width 0.13462)
		(layer "B.Cu")
		(net "USB2_GPU_HMC_R_DP")
	)
	(segment
		(start 105.655872 -384.988054)
		(end 105.956862 -385.289044)
		(width 0.13462)
		(layer "B.Cu")
		(net "USB2_GPU_HMC_R_DP")
	)
	(segment
		(start 55.512716 -366.014)
		(end 55.75935 -365.767112)
		(width 0.13462)
		(layer "B.Cu")
		(net "USB2_GPU_HMC_R_DP")
	)
	(segment
		(start 55.525416 -366.122458)
		(end 55.512716 -366.109758)
		(width 0.13462)
		(layer "B.Cu")
		(net "USB2_GPU_HMC_R_DP")
	)
	(segment
		(start 106.643932 -372.759478)
		(end 108.563664 -374.67921)
		(width 0.13462)
		(layer "B.Cu")
		(net "USB2_GPU_HMC_R_DP")
	)
	(segment
		(start 102.910132 -372.759478)
		(end 106.643932 -372.759478)
		(width 0.13462)
		(layer "B.Cu")
		(net "USB2_GPU_HMC_R_DP")
	)
	(segment
		(start 63.930276 -364.783624)
		(end 58.043318 -364.783624)
		(width 0.13462)
		(layer "B.Cu")
		(net "USB2_GPU_HMC_R_DP")
	)
	(segment
		(start 56.380888 -366.446054)
		(end 55.682134 -366.446054)
		(width 0.13462)
		(layer "B.Cu")
		(net "USB2_GPU_HMC_R_DP")
	)
	(segment
		(start 94.934278 -364.783624)
		(end 102.910132 -372.759478)
		(width 0.13462)
		(layer "B.Cu")
		(net "USB2_GPU_HMC_R_DP")
	)
	(segment
		(start 55.512716 -366.109758)
		(end 55.512716 -366.014)
		(width 0.13462)
		(layer "B.Cu")
		(net "USB2_GPU_HMC_R_DP")
	)
	(segment
		(start 55.525416 -366.289336)
		(end 55.525416 -366.122458)
		(width 0.13462)
		(layer "B.Cu")
		(net "USB2_GPU_HMC_R_DP")
	)
	(segment
		(start 108.563664 -381.376682)
		(end 105.655872 -384.284474)
		(width 0.13462)
		(layer "B.Cu")
		(net "USB2_GPU_HMC_R_DP")
	)
	(segment
		(start 108.563664 -374.67921)
		(end 108.563664 -381.376682)
		(width 0.13462)
		(layer "B.Cu")
		(net "USB2_GPU_HMC_R_DP")
	)
	(segment
		(start 55.682134 -366.446054)
		(end 55.525416 -366.289336)
		(width 0.13462)
		(layer "B.Cu")
		(net "USB2_GPU_HMC_R_DP")
	)
	(segment
		(start 63.930276 -364.783624)
		(end 94.934278 -364.783624)
		(width 0.13462)
		(layer "B.Cu")
		(net "USB2_GPU_HMC_R_DP")
	)
	(segment
		(start 279.499822 -294.94988)
		(end 279.024842 -294.4749)
		(width 0.249936)
		(layer "F.Cu")
		(net "PCEPLL4_VDDA18_PEX2")
	)
	(via
		(at 263.919462 -290.294314)
		(size 0.508)
		(drill 0.254)
		(layers "F.Cu" "B.Cu")
		(net "PCEPLL4_VDDA18_PEX2")
	)
	(via
		(at 265.316462 -290.294314)
		(size 0.508)
		(drill 0.254)
		(layers "F.Cu" "B.Cu")
		(net "PCEPLL4_VDDA18_PEX2")
	)
	(via
		(at 279.024842 -294.4749)
		(size 0.4064)
		(drill 0.2032)
		(layers "F.Cu" "B.Cu")
		(net "PCEPLL4_VDDA18_PEX2")
	)
	(segment
		(start 279.024842 -294.4749)
		(end 278.821642 -294.4749)
		(width 0.3048)
		(layer "B.Cu")
		(net "PCEPLL4_VDDA18_PEX2")
	)
	(segment
		(start 278.821642 -295.2623)
		(end 278.821642 -294.4749)
		(width 0.3048)
		(layer "B.Cu")
		(net "PCEPLL4_VDDA18_PEX2")
	)
	(segment
		(start 140.310108 -187.593732)
		(end 140.361924 -187.593732)
		(width 0.13208)
		(layer "F.Cu")
		(net "NIC5_CLK_EN_R_N")
	)
	(segment
		(start 140.354812 -189.128146)
		(end 139.803632 -188.576966)
		(width 0.13208)
		(layer "F.Cu")
		(net "NIC5_CLK_EN_R_N")
	)
	(segment
		(start 358.41305 -220.472)
		(end 359.029 -220.472)
		(width 0.13208)
		(layer "F.Cu")
		(net "NIC5_CLK_EN_R_N")
	)
	(segment
		(start 139.803632 -188.576966)
		(end 139.803632 -188.100208)
		(width 0.13208)
		(layer "F.Cu")
		(net "NIC5_CLK_EN_R_N")
	)
	(segment
		(start 139.803632 -188.100208)
		(end 140.310108 -187.593732)
		(width 0.13208)
		(layer "F.Cu")
		(net "NIC5_CLK_EN_R_N")
	)
	(segment
		(start 140.705332 -189.128146)
		(end 140.354812 -189.128146)
		(width 0.13208)
		(layer "F.Cu")
		(net "NIC5_CLK_EN_R_N")
	)
	(segment
		(start 140.705332 -189.128146)
		(end 141.693138 -189.128146)
		(width 0.13208)
		(layer "F.Cu")
		(net "NIC5_CLK_EN_R_N")
	)
	(via
		(at 141.693138 -189.128146)
		(size 0.508)
		(drill 0.254)
		(layers "F.Cu" "B.Cu")
		(net "NIC5_CLK_EN_R_N")
	)
	(via
		(at 130.372612 -198.954644)
		(size 0.508)
		(drill 0.254)
		(layers "F.Cu" "B.Cu")
		(net "NIC5_CLK_EN_R_N")
	)
	(via
		(at 359.029 -220.472)
		(size 0.508)
		(drill 0.254)
		(layers "F.Cu" "B.Cu")
		(net "NIC5_CLK_EN_R_N")
	)
	(segment
		(start 132.839714 -198.954644)
		(end 130.372612 -198.954644)
		(width 0.15494)
		(layer "In11.Cu")
		(net "NIC5_CLK_EN_R_N")
	)
	(segment
		(start 137.282428 -189.128146)
		(end 133.980174 -192.4304)
		(width 0.15494)
		(layer "In11.Cu")
		(net "NIC5_CLK_EN_R_N")
	)
	(segment
		(start 133.980174 -192.4304)
		(end 133.980174 -197.814184)
		(width 0.15494)
		(layer "In11.Cu")
		(net "NIC5_CLK_EN_R_N")
	)
	(segment
		(start 141.693138 -189.128146)
		(end 137.282428 -189.128146)
		(width 0.15494)
		(layer "In11.Cu")
		(net "NIC5_CLK_EN_R_N")
	)
	(segment
		(start 133.980174 -197.814184)
		(end 132.839714 -198.954644)
		(width 0.15494)
		(layer "In11.Cu")
		(net "NIC5_CLK_EN_R_N")
	)
	(segment
		(start 251.858018 -186.098434)
		(end 252.68174 -185.274712)
		(width 0.15494)
		(layer "In15.Cu")
		(net "NIC5_CLK_EN_R_N")
	)
	(segment
		(start 286.108902 -186.883548)
		(end 300.28261 -186.883548)
		(width 0.15494)
		(layer "In15.Cu")
		(net "NIC5_CLK_EN_R_N")
	)
	(segment
		(start 143.014954 -200.73366)
		(end 144.506442 -200.73366)
		(width 0.15494)
		(layer "In15.Cu")
		(net "NIC5_CLK_EN_R_N")
	)
	(segment
		(start 243.755672 -184.034684)
		(end 243.755672 -184.288684)
		(width 0.15494)
		(layer "In15.Cu")
		(net "NIC5_CLK_EN_R_N")
	)
	(segment
		(start 355.96195 -191.863218)
		(end 355.96195 -198.64705)
		(width 0.15494)
		(layer "In15.Cu")
		(net "NIC5_CLK_EN_R_N")
	)
	(segment
		(start 235.779056 -183.49087)
		(end 243.211858 -183.49087)
		(width 0.15494)
		(layer "In15.Cu")
		(net "NIC5_CLK_EN_R_N")
	)
	(segment
		(start 331.450696 -186.512454)
		(end 333.149702 -188.21146)
		(width 0.15494)
		(layer "In15.Cu")
		(net "NIC5_CLK_EN_R_N")
	)
	(segment
		(start 243.211858 -183.49087)
		(end 243.755672 -184.034684)
		(width 0.15494)
		(layer "In15.Cu")
		(net "NIC5_CLK_EN_R_N")
	)
	(segment
		(start 333.149702 -188.21146)
		(end 341.060532 -188.21146)
		(width 0.15494)
		(layer "In15.Cu")
		(net "NIC5_CLK_EN_R_N")
	)
	(segment
		(start 252.68174 -185.274712)
		(end 259.912104 -185.274712)
		(width 0.15494)
		(layer "In15.Cu")
		(net "NIC5_CLK_EN_R_N")
	)
	(segment
		(start 342.17864 -188.308488)
		(end 352.40722 -188.308488)
		(width 0.15494)
		(layer "In15.Cu")
		(net "NIC5_CLK_EN_R_N")
	)
	(segment
		(start 212.350096 -182.732426)
		(end 212.53704 -182.91937)
		(width 0.15494)
		(layer "In15.Cu")
		(net "NIC5_CLK_EN_R_N")
	)
	(segment
		(start 152.324816 -192.393824)
		(end 170.716448 -192.393824)
		(width 0.15494)
		(layer "In15.Cu")
		(net "NIC5_CLK_EN_R_N")
	)
	(segment
		(start 144.506442 -200.73366)
		(end 147.532344 -197.707758)
		(width 0.15494)
		(layer "In15.Cu")
		(net "NIC5_CLK_EN_R_N")
	)
	(segment
		(start 147.900898 -196.817742)
		(end 152.324816 -192.393824)
		(width 0.15494)
		(layer "In15.Cu")
		(net "NIC5_CLK_EN_R_N")
	)
	(segment
		(start 131.751324 -200.333356)
		(end 142.61465 -200.333356)
		(width 0.15494)
		(layer "In15.Cu")
		(net "NIC5_CLK_EN_R_N")
	)
	(segment
		(start 359.3211 -220.1799)
		(end 359.029 -220.472)
		(width 0.15494)
		(layer "In15.Cu")
		(net "NIC5_CLK_EN_R_N")
	)
	(segment
		(start 355.96195 -198.64705)
		(end 359.87101 -202.55611)
		(width 0.15494)
		(layer "In15.Cu")
		(net "NIC5_CLK_EN_R_N")
	)
	(segment
		(start 234.487212 -184.12079)
		(end 235.247434 -183.360568)
		(width 0.15494)
		(layer "In15.Cu")
		(net "NIC5_CLK_EN_R_N")
	)
	(segment
		(start 180.377846 -182.732426)
		(end 212.350096 -182.732426)
		(width 0.15494)
		(layer "In15.Cu")
		(net "NIC5_CLK_EN_R_N")
	)
	(segment
		(start 243.755672 -184.288684)
		(end 244.921278 -185.45429)
		(width 0.15494)
		(layer "In15.Cu")
		(net "NIC5_CLK_EN_R_N")
	)
	(segment
		(start 142.61465 -200.333356)
		(end 143.014954 -200.73366)
		(width 0.15494)
		(layer "In15.Cu")
		(net "NIC5_CLK_EN_R_N")
	)
	(segment
		(start 352.40722 -188.308488)
		(end 355.96195 -191.863218)
		(width 0.15494)
		(layer "In15.Cu")
		(net "NIC5_CLK_EN_R_N")
	)
	(segment
		(start 235.247434 -183.360568)
		(end 235.648754 -183.360568)
		(width 0.15494)
		(layer "In15.Cu")
		(net "NIC5_CLK_EN_R_N")
	)
	(segment
		(start 130.372612 -198.954644)
		(end 131.751324 -200.333356)
		(width 0.15494)
		(layer "In15.Cu")
		(net "NIC5_CLK_EN_R_N")
	)
	(segment
		(start 359.868978 -218.856814)
		(end 359.3211 -220.1799)
		(width 0.15494)
		(layer "In15.Cu")
		(net "NIC5_CLK_EN_R_N")
	)
	(segment
		(start 359.87101 -214.72525)
		(end 359.868978 -214.727282)
		(width 0.15494)
		(layer "In15.Cu")
		(net "NIC5_CLK_EN_R_N")
	)
	(segment
		(start 359.87101 -202.55611)
		(end 359.87101 -214.72525)
		(width 0.15494)
		(layer "In15.Cu")
		(net "NIC5_CLK_EN_R_N")
	)
	(segment
		(start 226.662488 -182.91937)
		(end 227.863908 -184.12079)
		(width 0.15494)
		(layer "In15.Cu")
		(net "NIC5_CLK_EN_R_N")
	)
	(segment
		(start 212.53704 -182.91937)
		(end 226.662488 -182.91937)
		(width 0.15494)
		(layer "In15.Cu")
		(net "NIC5_CLK_EN_R_N")
	)
	(segment
		(start 227.863908 -184.12079)
		(end 234.487212 -184.12079)
		(width 0.15494)
		(layer "In15.Cu")
		(net "NIC5_CLK_EN_R_N")
	)
	(segment
		(start 300.28261 -186.883548)
		(end 300.653704 -186.512454)
		(width 0.15494)
		(layer "In15.Cu")
		(net "NIC5_CLK_EN_R_N")
	)
	(segment
		(start 260.893306 -184.29351)
		(end 283.518864 -184.29351)
		(width 0.15494)
		(layer "In15.Cu")
		(net "NIC5_CLK_EN_R_N")
	)
	(segment
		(start 235.648754 -183.360568)
		(end 235.779056 -183.49087)
		(width 0.15494)
		(layer "In15.Cu")
		(net "NIC5_CLK_EN_R_N")
	)
	(segment
		(start 341.060532 -188.21146)
		(end 341.370412 -187.90158)
		(width 0.15494)
		(layer "In15.Cu")
		(net "NIC5_CLK_EN_R_N")
	)
	(segment
		(start 259.912104 -185.274712)
		(end 260.893306 -184.29351)
		(width 0.15494)
		(layer "In15.Cu")
		(net "NIC5_CLK_EN_R_N")
	)
	(segment
		(start 341.370412 -187.90158)
		(end 341.771732 -187.90158)
		(width 0.15494)
		(layer "In15.Cu")
		(net "NIC5_CLK_EN_R_N")
	)
	(segment
		(start 359.868978 -214.727282)
		(end 359.868978 -218.856814)
		(width 0.15494)
		(layer "In15.Cu")
		(net "NIC5_CLK_EN_R_N")
	)
	(segment
		(start 300.653704 -186.512454)
		(end 331.450696 -186.512454)
		(width 0.15494)
		(layer "In15.Cu")
		(net "NIC5_CLK_EN_R_N")
	)
	(segment
		(start 283.518864 -184.29351)
		(end 286.108902 -186.883548)
		(width 0.15494)
		(layer "In15.Cu")
		(net "NIC5_CLK_EN_R_N")
	)
	(segment
		(start 341.771732 -187.90158)
		(end 342.17864 -188.308488)
		(width 0.15494)
		(layer "In15.Cu")
		(net "NIC5_CLK_EN_R_N")
	)
	(segment
		(start 170.716448 -192.393824)
		(end 180.377846 -182.732426)
		(width 0.15494)
		(layer "In15.Cu")
		(net "NIC5_CLK_EN_R_N")
	)
	(segment
		(start 246.141494 -186.098434)
		(end 251.858018 -186.098434)
		(width 0.15494)
		(layer "In15.Cu")
		(net "NIC5_CLK_EN_R_N")
	)
	(segment
		(start 147.532344 -197.707758)
		(end 147.900898 -196.817742)
		(width 0.15494)
		(layer "In15.Cu")
		(net "NIC5_CLK_EN_R_N")
	)
	(segment
		(start 244.921278 -185.45429)
		(end 245.49735 -185.45429)
		(width 0.15494)
		(layer "In15.Cu")
		(net "NIC5_CLK_EN_R_N")
	)
	(segment
		(start 245.49735 -185.45429)
		(end 246.141494 -186.098434)
		(width 0.15494)
		(layer "In15.Cu")
		(net "NIC5_CLK_EN_R_N")
	)
	(segment
		(start 221.99727 -87.608918)
		(end 222.286576 -87.898224)
		(width 0.13208)
		(layer "F.Cu")
		(net "SMB_SSD_LED_IOEXP_SDA")
	)
	(segment
		(start 217.422222 -85.060536)
		(end 218.435682 -85.060536)
		(width 0.13208)
		(layer "F.Cu")
		(net "SMB_SSD_LED_IOEXP_SDA")
	)
	(segment
		(start 218.435682 -85.060536)
		(end 219.21216 -85.837014)
		(width 0.13208)
		(layer "F.Cu")
		(net "SMB_SSD_LED_IOEXP_SDA")
	)
	(segment
		(start 220.533468 -87.5919)
		(end 220.839792 -87.898224)
		(width 0.13208)
		(layer "F.Cu")
		(net "SMB_SSD_LED_IOEXP_SDA")
	)
	(segment
		(start 222.286576 -87.898224)
		(end 223.440752 -87.898224)
		(width 0.13208)
		(layer "F.Cu")
		(net "SMB_SSD_LED_IOEXP_SDA")
	)
	(segment
		(start 223.440752 -87.898224)
		(end 223.622108 -87.716868)
		(width 0.13208)
		(layer "F.Cu")
		(net "SMB_SSD_LED_IOEXP_SDA")
	)
	(segment
		(start 220.839792 -87.898224)
		(end 221.707964 -87.898224)
		(width 0.13208)
		(layer "F.Cu")
		(net "SMB_SSD_LED_IOEXP_SDA")
	)
	(segment
		(start 221.707964 -87.898224)
		(end 221.99727 -87.608918)
		(width 0.13208)
		(layer "F.Cu")
		(net "SMB_SSD_LED_IOEXP_SDA")
	)
	(segment
		(start 219.21216 -85.837014)
		(end 220.048074 -85.837014)
		(width 0.13208)
		(layer "F.Cu")
		(net "SMB_SSD_LED_IOEXP_SDA")
	)
	(segment
		(start 220.048074 -85.837014)
		(end 220.533468 -86.322408)
		(width 0.13208)
		(layer "F.Cu")
		(net "SMB_SSD_LED_IOEXP_SDA")
	)
	(segment
		(start 220.533468 -86.322408)
		(end 220.533468 -87.5919)
		(width 0.13208)
		(layer "F.Cu")
		(net "SMB_SSD_LED_IOEXP_SDA")
	)
	(via
		(at 221.99727 -87.608918)
		(size 0.508)
		(drill 0.254)
		(layers "F.Cu" "B.Cu")
		(net "SMB_SSD_LED_IOEXP_SDA")
	)
	(segment
		(start 279.499822 -293.04996)
		(end 279.024842 -292.57498)
		(width 0.249936)
		(layer "F.Cu")
		(net "PCEPLL6_VDDA18_PEX2")
	)
	(via
		(at 263.919462 -287.093914)
		(size 0.508)
		(drill 0.254)
		(layers "F.Cu" "B.Cu")
		(net "PCEPLL6_VDDA18_PEX2")
	)
	(via
		(at 279.024842 -292.57498)
		(size 0.4064)
		(drill 0.2032)
		(layers "F.Cu" "B.Cu")
		(net "PCEPLL6_VDDA18_PEX2")
	)
	(via
		(at 265.316462 -287.093914)
		(size 0.508)
		(drill 0.254)
		(layers "F.Cu" "B.Cu")
		(net "PCEPLL6_VDDA18_PEX2")
	)
	(segment
		(start 278.821642 -293.52494)
		(end 278.821642 -292.57498)
		(width 0.3048)
		(layer "B.Cu")
		(net "PCEPLL6_VDDA18_PEX2")
	)
	(segment
		(start 279.024842 -292.57498)
		(end 278.821642 -292.57498)
		(width 0.3048)
		(layer "B.Cu")
		(net "PCEPLL6_VDDA18_PEX2")
	)
	(segment
		(start 105.320592 -382.827022)
		(end 105.320592 -382.479804)
		(width 0.13462)
		(layer "F.Cu")
		(net "USB2_BIC_R_DN")
	)
	(segment
		(start 104.517698 -381.67691)
		(end 104.517698 -381.323596)
		(width 0.13462)
		(layer "F.Cu")
		(net "USB2_BIC_R_DN")
	)
	(segment
		(start 103.555038 -385.500118)
		(end 103.555038 -384.592576)
		(width 0.13462)
		(layer "F.Cu")
		(net "USB2_BIC_R_DN")
	)
	(segment
		(start 105.320592 -382.479804)
		(end 104.517698 -381.67691)
		(width 0.13462)
		(layer "F.Cu")
		(net "USB2_BIC_R_DN")
	)
	(segment
		(start 102.877112 -389.464042)
		(end 102.877112 -389.741918)
		(width 0.13462)
		(layer "F.Cu")
		(net "USB2_BIC_R_DN")
	)
	(segment
		(start 102.996492 -389.344662)
		(end 102.877112 -389.464042)
		(width 0.13462)
		(layer "F.Cu")
		(net "USB2_BIC_R_DN")
	)
	(segment
		(start 102.996492 -387.180836)
		(end 102.996492 -386.849366)
		(width 0.13462)
		(layer "F.Cu")
		(net "USB2_BIC_R_DN")
	)
	(segment
		(start 103.555038 -384.592576)
		(end 105.320592 -382.827022)
		(width 0.13462)
		(layer "F.Cu")
		(net "USB2_BIC_R_DN")
	)
	(segment
		(start 102.996492 -387.180836)
		(end 102.996492 -389.344662)
		(width 0.13462)
		(layer "F.Cu")
		(net "USB2_BIC_R_DN")
	)
	(segment
		(start 102.996492 -386.849366)
		(end 103.555038 -385.500118)
		(width 0.13462)
		(layer "F.Cu")
		(net "USB2_BIC_R_DN")
	)
	(via
		(at 102.996492 -387.180836)
		(size 0.4064)
		(drill 0.2032)
		(layers "F.Cu" "B.Cu")
		(net "USB2_BIC_R_DN")
	)
	(segment
		(start 279.499822 -298.74972)
		(end 279.024842 -299.224954)
		(width 0.249936)
		(layer "F.Cu")
		(net "PCEPLL1_VDDA18_PEX2")
	)
	(via
		(at 263.919462 -299.895514)
		(size 0.508)
		(drill 0.254)
		(layers "F.Cu" "B.Cu")
		(net "PCEPLL1_VDDA18_PEX2")
	)
	(via
		(at 265.316462 -299.895514)
		(size 0.508)
		(drill 0.254)
		(layers "F.Cu" "B.Cu")
		(net "PCEPLL1_VDDA18_PEX2")
	)
	(via
		(at 279.024842 -299.224954)
		(size 0.4064)
		(drill 0.2032)
		(layers "F.Cu" "B.Cu")
		(net "PCEPLL1_VDDA18_PEX2")
	)
	(segment
		(start 278.834596 -299.224954)
		(end 278.821642 -299.212)
		(width 0.3048)
		(layer "B.Cu")
		(net "PCEPLL1_VDDA18_PEX2")
	)
	(segment
		(start 279.024842 -299.224954)
		(end 278.834596 -299.224954)
		(width 0.3048)
		(layer "B.Cu")
		(net "PCEPLL1_VDDA18_PEX2")
	)
	(segment
		(start 278.821642 -300.1772)
		(end 278.821642 -299.212)
		(width 0.3048)
		(layer "B.Cu")
		(net "PCEPLL1_VDDA18_PEX2")
	)
	(segment
		(start 329.132946 -224.988882)
		(end 327.93178 -224.988882)
		(width 0.13208)
		(layer "F.Cu")
		(net "FM_CLK_EN")
	)
	(segment
		(start 331.089 -224.79)
		(end 330.890118 -224.988882)
		(width 0.13208)
		(layer "F.Cu")
		(net "FM_CLK_EN")
	)
	(segment
		(start 332.167484 -224.79)
		(end 331.089 -224.79)
		(width 0.13208)
		(layer "F.Cu")
		(net "FM_CLK_EN")
	)
	(segment
		(start 332.613 -224.344484)
		(end 332.167484 -224.79)
		(width 0.13208)
		(layer "F.Cu")
		(net "FM_CLK_EN")
	)
	(segment
		(start 333.736442 -224.344484)
		(end 332.613 -224.344484)
		(width 0.13208)
		(layer "F.Cu")
		(net "FM_CLK_EN")
	)
	(segment
		(start 330.890118 -224.988882)
		(end 329.132946 -224.988882)
		(width 0.13208)
		(layer "F.Cu")
		(net "FM_CLK_EN")
	)
	(segment
		(start 334.09382 -223.987106)
		(end 333.736442 -224.344484)
		(width 0.13208)
		(layer "F.Cu")
		(net "FM_CLK_EN")
	)
	(via
		(at 329.132946 -224.988882)
		(size 0.762)
		(drill 0.381)
		(layers "F.Cu" "B.Cu")
		(net "FM_CLK_EN")
	)
	(segment
		(start 313.549538 -84.476336)
		(end 312.277252 -84.476336)
		(width 0.13208)
		(layer "F.Cu")
		(net "RST_NIC5_PERST_R_N")
	)
	(segment
		(start 358.41305 -221.488)
		(end 359.029 -221.488)
		(width 0.13208)
		(layer "F.Cu")
		(net "RST_NIC5_PERST_R_N")
	)
	(via
		(at 312.277252 -84.476336)
		(size 0.508)
		(drill 0.254)
		(layers "F.Cu" "B.Cu")
		(net "RST_NIC5_PERST_R_N")
	)
	(via
		(at 357.696516 -101.102414)
		(size 0.508)
		(drill 0.254)
		(layers "F.Cu" "B.Cu")
		(net "RST_NIC5_PERST_R_N")
	)
	(via
		(at 359.029 -221.488)
		(size 0.508)
		(drill 0.254)
		(layers "F.Cu" "B.Cu")
		(net "RST_NIC5_PERST_R_N")
	)
	(segment
		(start 354.391468 -99.680522)
		(end 356.274624 -99.680522)
		(width 0.13208)
		(layer "B.Cu")
		(net "RST_NIC5_PERST_R_N")
	)
	(segment
		(start 356.274624 -99.680522)
		(end 357.696516 -101.102414)
		(width 0.13208)
		(layer "B.Cu")
		(net "RST_NIC5_PERST_R_N")
	)
	(segment
		(start 316.9666 -89.165684)
		(end 326.155812 -89.165684)
		(width 0.13208)
		(layer "B.Cu")
		(net "RST_NIC5_PERST_R_N")
	)
	(segment
		(start 328.355452 -91.365324)
		(end 332.04912 -91.365324)
		(width 0.13208)
		(layer "B.Cu")
		(net "RST_NIC5_PERST_R_N")
	)
	(segment
		(start 347.878146 -93.1672)
		(end 354.391468 -99.680522)
		(width 0.13208)
		(layer "B.Cu")
		(net "RST_NIC5_PERST_R_N")
	)
	(segment
		(start 312.277252 -84.476336)
		(end 316.9666 -89.165684)
		(width 0.13208)
		(layer "B.Cu")
		(net "RST_NIC5_PERST_R_N")
	)
	(segment
		(start 326.155812 -89.165684)
		(end 328.355452 -91.365324)
		(width 0.13208)
		(layer "B.Cu")
		(net "RST_NIC5_PERST_R_N")
	)
	(segment
		(start 333.850996 -93.1672)
		(end 347.878146 -93.1672)
		(width 0.13208)
		(layer "B.Cu")
		(net "RST_NIC5_PERST_R_N")
	)
	(segment
		(start 332.04912 -91.365324)
		(end 333.850996 -93.1672)
		(width 0.13208)
		(layer "B.Cu")
		(net "RST_NIC5_PERST_R_N")
	)
	(segment
		(start 353.240848 -132.096002)
		(end 356.0826 -129.25425)
		(width 0.15494)
		(layer "In7.Cu")
		(net "RST_NIC5_PERST_R_N")
	)
	(segment
		(start 358.081072 -164.25545)
		(end 357.808022 -163.9824)
		(width 0.15494)
		(layer "In7.Cu")
		(net "RST_NIC5_PERST_R_N")
	)
	(segment
		(start 378.99848 -210.362292)
		(end 378.99848 -209.09661)
		(width 0.15494)
		(layer "In7.Cu")
		(net "RST_NIC5_PERST_R_N")
	)
	(segment
		(start 358.267 -104.681528)
		(end 358.267 -101.672898)
		(width 0.15494)
		(layer "In7.Cu")
		(net "RST_NIC5_PERST_R_N")
	)
	(segment
		(start 378.9934 -209.09153)
		(end 378.9934 -209.041746)
		(width 0.15494)
		(layer "In7.Cu")
		(net "RST_NIC5_PERST_R_N")
	)
	(segment
		(start 356.2858 -163.9824)
		(end 353.106228 -160.802828)
		(width 0.15494)
		(layer "In7.Cu")
		(net "RST_NIC5_PERST_R_N")
	)
	(segment
		(start 373.083074 -169.8752)
		(end 369.937792 -169.8752)
		(width 0.15494)
		(layer "In7.Cu")
		(net "RST_NIC5_PERST_R_N")
	)
	(segment
		(start 357.808022 -163.9824)
		(end 356.2858 -163.9824)
		(width 0.15494)
		(layer "In7.Cu")
		(net "RST_NIC5_PERST_R_N")
	)
	(segment
		(start 379.29566 -202.56119)
		(end 379.28931 -202.55484)
		(width 0.15494)
		(layer "In7.Cu")
		(net "RST_NIC5_PERST_R_N")
	)
	(segment
		(start 379.29566 -203.38923)
		(end 379.29566 -203.01077)
		(width 0.15494)
		(layer "In7.Cu")
		(net "RST_NIC5_PERST_R_N")
	)
	(segment
		(start 374.0658 -176.248314)
		(end 374.0658 -170.857926)
		(width 0.15494)
		(layer "In7.Cu")
		(net "RST_NIC5_PERST_R_N")
	)
	(segment
		(start 362.0516 -218.4654)
		(end 370.205 -218.4654)
		(width 0.15494)
		(layer "In7.Cu")
		(net "RST_NIC5_PERST_R_N")
	)
	(segment
		(start 379.29566 -202.58913)
		(end 379.29566 -202.56119)
		(width 0.15494)
		(layer "In7.Cu")
		(net "RST_NIC5_PERST_R_N")
	)
	(segment
		(start 377.1773 -211.45246)
		(end 377.908312 -211.45246)
		(width 0.15494)
		(layer "In7.Cu")
		(net "RST_NIC5_PERST_R_N")
	)
	(segment
		(start 371.757956 -216.871804)
		(end 377.1773 -211.45246)
		(width 0.15494)
		(layer "In7.Cu")
		(net "RST_NIC5_PERST_R_N")
	)
	(segment
		(start 371.757956 -216.912444)
		(end 371.757956 -216.871804)
		(width 0.15494)
		(layer "In7.Cu")
		(net "RST_NIC5_PERST_R_N")
	)
	(segment
		(start 379.30582 -202.59929)
		(end 379.29566 -202.58913)
		(width 0.15494)
		(layer "In7.Cu")
		(net "RST_NIC5_PERST_R_N")
	)
	(segment
		(start 377.3424 -188.77153)
		(end 377.3424 -182.423054)
		(width 0.15494)
		(layer "In7.Cu")
		(net "RST_NIC5_PERST_R_N")
	)
	(segment
		(start 353.062032 -142.01013)
		(end 353.240848 -141.831314)
		(width 0.15494)
		(layer "In7.Cu")
		(net "RST_NIC5_PERST_R_N")
	)
	(segment
		(start 353.240848 -141.831314)
		(end 353.240848 -132.096002)
		(width 0.15494)
		(layer "In7.Cu")
		(net "RST_NIC5_PERST_R_N")
	)
	(segment
		(start 370.205 -218.4654)
		(end 371.757956 -216.912444)
		(width 0.15494)
		(layer "In7.Cu")
		(net "RST_NIC5_PERST_R_N")
	)
	(segment
		(start 378.76734 -207.795114)
		(end 379.29566 -207.266794)
		(width 0.15494)
		(layer "In7.Cu")
		(net "RST_NIC5_PERST_R_N")
	)
	(segment
		(start 379.29566 -203.81087)
		(end 379.30582 -203.80071)
		(width 0.15494)
		(layer "In7.Cu")
		(net "RST_NIC5_PERST_R_N")
	)
	(segment
		(start 352.45294 -159.196532)
		(end 352.45294 -142.82674)
		(width 0.15494)
		(layer "In7.Cu")
		(net "RST_NIC5_PERST_R_N")
	)
	(segment
		(start 379.28931 -202.55484)
		(end 379.28931 -202.15352)
		(width 0.15494)
		(layer "In7.Cu")
		(net "RST_NIC5_PERST_R_N")
	)
	(segment
		(start 352.764344 -142.307818)
		(end 352.764344 -142.29334)
		(width 0.15494)
		(layer "In7.Cu")
		(net "RST_NIC5_PERST_R_N")
	)
	(segment
		(start 379.30582 -203.00061)
		(end 379.30582 -202.59929)
		(width 0.15494)
		(layer "In7.Cu")
		(net "RST_NIC5_PERST_R_N")
	)
	(segment
		(start 379.29566 -207.266794)
		(end 379.29566 -203.81087)
		(width 0.15494)
		(layer "In7.Cu")
		(net "RST_NIC5_PERST_R_N")
	)
	(segment
		(start 376.36069 -181.441344)
		(end 376.36069 -181.342792)
		(width 0.15494)
		(layer "In7.Cu")
		(net "RST_NIC5_PERST_R_N")
	)
	(segment
		(start 378.761498 -208.809844)
		(end 378.761498 -208.192116)
		(width 0.15494)
		(layer "In7.Cu")
		(net "RST_NIC5_PERST_R_N")
	)
	(segment
		(start 352.543618 -142.528544)
		(end 352.764344 -142.307818)
		(width 0.15494)
		(layer "In7.Cu")
		(net "RST_NIC5_PERST_R_N")
	)
	(segment
		(start 378.032518 -199.978518)
		(end 378.032518 -189.49035)
		(width 0.15494)
		(layer "In7.Cu")
		(net "RST_NIC5_PERST_R_N")
	)
	(segment
		(start 377.473972 -188.903102)
		(end 377.3424 -188.77153)
		(width 0.15494)
		(layer "In7.Cu")
		(net "RST_NIC5_PERST_R_N")
	)
	(segment
		(start 379.29566 -203.01077)
		(end 379.30582 -203.00061)
		(width 0.15494)
		(layer "In7.Cu")
		(net "RST_NIC5_PERST_R_N")
	)
	(segment
		(start 376.36069 -181.342792)
		(end 376.35307 -181.335172)
		(width 0.15494)
		(layer "In7.Cu")
		(net "RST_NIC5_PERST_R_N")
	)
	(segment
		(start 379.29566 -201.24166)
		(end 378.032518 -199.978518)
		(width 0.15494)
		(layer "In7.Cu")
		(net "RST_NIC5_PERST_R_N")
	)
	(segment
		(start 378.032518 -189.49035)
		(end 377.473972 -188.931804)
		(width 0.15494)
		(layer "In7.Cu")
		(net "RST_NIC5_PERST_R_N")
	)
	(segment
		(start 352.45294 -142.82674)
		(end 352.543618 -142.736062)
		(width 0.15494)
		(layer "In7.Cu")
		(net "RST_NIC5_PERST_R_N")
	)
	(segment
		(start 377.473972 -188.931804)
		(end 377.473972 -188.903102)
		(width 0.15494)
		(layer "In7.Cu")
		(net "RST_NIC5_PERST_R_N")
	)
	(segment
		(start 377.3424 -182.423054)
		(end 376.36069 -181.441344)
		(width 0.15494)
		(layer "In7.Cu")
		(net "RST_NIC5_PERST_R_N")
	)
	(segment
		(start 378.9934 -209.041746)
		(end 378.761498 -208.809844)
		(width 0.15494)
		(layer "In7.Cu")
		(net "RST_NIC5_PERST_R_N")
	)
	(segment
		(start 378.99848 -209.09661)
		(end 378.9934 -209.09153)
		(width 0.15494)
		(layer "In7.Cu")
		(net "RST_NIC5_PERST_R_N")
	)
	(segment
		(start 358.267 -101.672898)
		(end 357.696516 -101.102414)
		(width 0.15494)
		(layer "In7.Cu")
		(net "RST_NIC5_PERST_R_N")
	)
	(segment
		(start 379.30582 -203.80071)
		(end 379.30582 -203.39939)
		(width 0.15494)
		(layer "In7.Cu")
		(net "RST_NIC5_PERST_R_N")
	)
	(segment
		(start 359.029 -221.488)
		(end 362.0516 -218.4654)
		(width 0.15494)
		(layer "In7.Cu")
		(net "RST_NIC5_PERST_R_N")
	)
	(segment
		(start 353.106228 -160.802828)
		(end 353.106228 -159.84982)
		(width 0.15494)
		(layer "In7.Cu")
		(net "RST_NIC5_PERST_R_N")
	)
	(segment
		(start 379.29566 -202.14717)
		(end 379.29566 -201.24166)
		(width 0.15494)
		(layer "In7.Cu")
		(net "RST_NIC5_PERST_R_N")
	)
	(segment
		(start 353.106228 -159.84982)
		(end 352.45294 -159.196532)
		(width 0.15494)
		(layer "In7.Cu")
		(net "RST_NIC5_PERST_R_N")
	)
	(segment
		(start 374.0658 -170.857926)
		(end 373.938038 -170.730164)
		(width 0.15494)
		(layer "In7.Cu")
		(net "RST_NIC5_PERST_R_N")
	)
	(segment
		(start 352.543618 -142.736062)
		(end 352.543618 -142.528544)
		(width 0.15494)
		(layer "In7.Cu")
		(net "RST_NIC5_PERST_R_N")
	)
	(segment
		(start 369.937792 -169.8752)
		(end 364.318042 -164.25545)
		(width 0.15494)
		(layer "In7.Cu")
		(net "RST_NIC5_PERST_R_N")
	)
	(segment
		(start 356.0826 -129.25425)
		(end 356.0826 -121.3866)
		(width 0.15494)
		(layer "In7.Cu")
		(net "RST_NIC5_PERST_R_N")
	)
	(segment
		(start 353.047554 -142.01013)
		(end 353.062032 -142.01013)
		(width 0.15494)
		(layer "In7.Cu")
		(net "RST_NIC5_PERST_R_N")
	)
	(segment
		(start 352.764344 -142.29334)
		(end 353.047554 -142.01013)
		(width 0.15494)
		(layer "In7.Cu")
		(net "RST_NIC5_PERST_R_N")
	)
	(segment
		(start 378.76734 -208.186274)
		(end 378.76734 -207.795114)
		(width 0.15494)
		(layer "In7.Cu")
		(net "RST_NIC5_PERST_R_N")
	)
	(segment
		(start 373.264938 -169.99966)
		(end 373.207534 -169.99966)
		(width 0.15494)
		(layer "In7.Cu")
		(net "RST_NIC5_PERST_R_N")
	)
	(segment
		(start 376.35307 -181.335172)
		(end 376.35307 -178.535584)
		(width 0.15494)
		(layer "In7.Cu")
		(net "RST_NIC5_PERST_R_N")
	)
	(segment
		(start 356.0826 -121.3866)
		(end 357.3526 -120.1166)
		(width 0.15494)
		(layer "In7.Cu")
		(net "RST_NIC5_PERST_R_N")
	)
	(segment
		(start 373.938038 -170.730164)
		(end 373.938038 -170.67276)
		(width 0.15494)
		(layer "In7.Cu")
		(net "RST_NIC5_PERST_R_N")
	)
	(segment
		(start 357.3526 -120.1166)
		(end 357.3526 -105.595928)
		(width 0.15494)
		(layer "In7.Cu")
		(net "RST_NIC5_PERST_R_N")
	)
	(segment
		(start 379.28931 -202.15352)
		(end 379.29566 -202.14717)
		(width 0.15494)
		(layer "In7.Cu")
		(net "RST_NIC5_PERST_R_N")
	)
	(segment
		(start 377.908312 -211.45246)
		(end 378.99848 -210.362292)
		(width 0.15494)
		(layer "In7.Cu")
		(net "RST_NIC5_PERST_R_N")
	)
	(segment
		(start 376.35307 -178.535584)
		(end 374.0658 -176.248314)
		(width 0.15494)
		(layer "In7.Cu")
		(net "RST_NIC5_PERST_R_N")
	)
	(segment
		(start 357.3526 -105.595928)
		(end 358.267 -104.681528)
		(width 0.15494)
		(layer "In7.Cu")
		(net "RST_NIC5_PERST_R_N")
	)
	(segment
		(start 379.30582 -203.39939)
		(end 379.29566 -203.38923)
		(width 0.15494)
		(layer "In7.Cu")
		(net "RST_NIC5_PERST_R_N")
	)
	(segment
		(start 373.207534 -169.99966)
		(end 373.083074 -169.8752)
		(width 0.15494)
		(layer "In7.Cu")
		(net "RST_NIC5_PERST_R_N")
	)
	(segment
		(start 378.761498 -208.192116)
		(end 378.76734 -208.186274)
		(width 0.15494)
		(layer "In7.Cu")
		(net "RST_NIC5_PERST_R_N")
	)
	(segment
		(start 373.938038 -170.67276)
		(end 373.264938 -169.99966)
		(width 0.15494)
		(layer "In7.Cu")
		(net "RST_NIC5_PERST_R_N")
	)
	(segment
		(start 364.318042 -164.25545)
		(end 358.081072 -164.25545)
		(width 0.15494)
		(layer "In7.Cu")
		(net "RST_NIC5_PERST_R_N")
	)
	(segment
		(start 227.467668 -212.704172)
		(end 227.46716 -212.704172)
		(width 0.13208)
		(layer "F.Cu")
		(net "JTAG_BIC_TDO_R1")
	)
	(segment
		(start 242.750848 -211.832952)
		(end 243.374418 -211.832952)
		(width 0.13208)
		(layer "F.Cu")
		(net "JTAG_BIC_TDO_R1")
	)
	(segment
		(start 243.374418 -211.832952)
		(end 243.505228 -211.963762)
		(width 0.13208)
		(layer "F.Cu")
		(net "JTAG_BIC_TDO_R1")
	)
	(segment
		(start 227.46716 -212.704172)
		(end 227.067872 -212.304884)
		(width 0.13208)
		(layer "F.Cu")
		(net "JTAG_BIC_TDO_R1")
	)
	(via
		(at 242.750848 -211.832952)
		(size 0.508)
		(drill 0.254)
		(layers "F.Cu" "B.Cu")
		(net "JTAG_BIC_TDO_R1")
	)
	(via
		(at 227.067872 -212.304884)
		(size 0.4572)
		(drill 0.254)
		(layers "F.Cu" "B.Cu")
		(net "JTAG_BIC_TDO_R1")
	)
	(segment
		(start 241.504724 -212.0646)
		(end 241.098324 -211.6582)
		(width 0.15494)
		(layer "In15.Cu")
		(net "JTAG_BIC_TDO_R1")
	)
	(segment
		(start 242.4176 -212.0646)
		(end 241.504724 -212.0646)
		(width 0.15494)
		(layer "In15.Cu")
		(net "JTAG_BIC_TDO_R1")
	)
	(segment
		(start 242.712748 -211.794852)
		(end 242.687348 -211.794852)
		(width 0.15494)
		(layer "In15.Cu")
		(net "JTAG_BIC_TDO_R1")
	)
	(segment
		(start 242.750848 -211.832952)
		(end 242.712748 -211.794852)
		(width 0.15494)
		(layer "In15.Cu")
		(net "JTAG_BIC_TDO_R1")
	)
	(segment
		(start 241.098324 -211.6582)
		(end 227.714556 -211.6582)
		(width 0.15494)
		(layer "In15.Cu")
		(net "JTAG_BIC_TDO_R1")
	)
	(segment
		(start 242.687348 -211.794852)
		(end 242.4176 -212.0646)
		(width 0.15494)
		(layer "In15.Cu")
		(net "JTAG_BIC_TDO_R1")
	)
	(segment
		(start 227.714556 -211.6582)
		(end 227.067872 -212.304884)
		(width 0.15494)
		(layer "In15.Cu")
		(net "JTAG_BIC_TDO_R1")
	)
	(segment
		(start 105.16235 -383.373376)
		(end 105.594912 -382.940814)
		(width 0.13462)
		(layer "F.Cu")
		(net "USB2_BIC_R_DP")
	)
	(segment
		(start 103.376984 -389.464804)
		(end 103.376984 -389.741918)
		(width 0.13462)
		(layer "F.Cu")
		(net "USB2_BIC_R_DP")
	)
	(segment
		(start 103.270812 -389.358632)
		(end 103.376984 -389.464804)
		(width 0.13462)
		(layer "F.Cu")
		(net "USB2_BIC_R_DP")
	)
	(segment
		(start 106.385106 -381.701548)
		(end 106.385106 -381.298958)
		(width 0.13462)
		(layer "F.Cu")
		(net "USB2_BIC_R_DP")
	)
	(segment
		(start 105.594912 -382.491742)
		(end 106.385106 -381.701548)
		(width 0.13462)
		(layer "F.Cu")
		(net "USB2_BIC_R_DP")
	)
	(segment
		(start 103.829358 -384.706368)
		(end 103.829358 -385.554728)
		(width 0.13462)
		(layer "F.Cu")
		(net "USB2_BIC_R_DP")
	)
	(segment
		(start 103.829358 -385.554728)
		(end 103.270812 -386.903976)
		(width 0.13462)
		(layer "F.Cu")
		(net "USB2_BIC_R_DP")
	)
	(segment
		(start 105.16235 -383.373376)
		(end 103.829358 -384.706368)
		(width 0.13462)
		(layer "F.Cu")
		(net "USB2_BIC_R_DP")
	)
	(segment
		(start 103.270812 -386.903976)
		(end 103.270812 -389.358632)
		(width 0.13462)
		(layer "F.Cu")
		(net "USB2_BIC_R_DP")
	)
	(segment
		(start 105.594912 -382.940814)
		(end 105.594912 -382.491742)
		(width 0.13462)
		(layer "F.Cu")
		(net "USB2_BIC_R_DP")
	)
	(via
		(at 105.16235 -383.373376)
		(size 0.4064)
		(drill 0.2032)
		(layers "F.Cu" "B.Cu")
		(net "USB2_BIC_R_DP")
	)
	(segment
		(start 360.78795 -193.675)
		(end 360.91495 -193.802)
		(width 0.13208)
		(layer "F.Cu")
		(net "PEX0_PCA9555_1_INT_N")
	)
	(segment
		(start 359.55605 -193.294)
		(end 360.172 -193.294)
		(width 0.13208)
		(layer "F.Cu")
		(net "PEX0_PCA9555_1_INT_N")
	)
	(segment
		(start 365.077756 -192.3034)
		(end 365.238284 -192.142872)
		(width 0.13208)
		(layer "F.Cu")
		(net "PEX0_PCA9555_1_INT_N")
	)
	(segment
		(start 360.91495 -193.802)
		(end 362.458 -193.802)
		(width 0.13208)
		(layer "F.Cu")
		(net "PEX0_PCA9555_1_INT_N")
	)
	(segment
		(start 360.78795 -193.294)
		(end 360.78795 -193.675)
		(width 0.13208)
		(layer "F.Cu")
		(net "PEX0_PCA9555_1_INT_N")
	)
	(segment
		(start 365.077756 -193.285872)
		(end 365.077756 -192.3034)
		(width 0.13208)
		(layer "F.Cu")
		(net "PEX0_PCA9555_1_INT_N")
	)
	(segment
		(start 362.712 -193.548)
		(end 364.815628 -193.548)
		(width 0.13208)
		(layer "F.Cu")
		(net "PEX0_PCA9555_1_INT_N")
	)
	(segment
		(start 365.238284 -192.142872)
		(end 366.263936 -192.142872)
		(width 0.13208)
		(layer "F.Cu")
		(net "PEX0_PCA9555_1_INT_N")
	)
	(segment
		(start 360.172 -193.294)
		(end 360.78795 -193.294)
		(width 0.13208)
		(layer "F.Cu")
		(net "PEX0_PCA9555_1_INT_N")
	)
	(segment
		(start 362.458 -193.802)
		(end 362.712 -193.548)
		(width 0.13208)
		(layer "F.Cu")
		(net "PEX0_PCA9555_1_INT_N")
	)
	(segment
		(start 364.815628 -193.548)
		(end 365.077756 -193.285872)
		(width 0.13208)
		(layer "F.Cu")
		(net "PEX0_PCA9555_1_INT_N")
	)
	(via
		(at 360.172 -193.294)
		(size 0.508)
		(drill 0.254)
		(layers "F.Cu" "B.Cu")
		(net "PEX0_PCA9555_1_INT_N")
	)
	(segment
		(start 360.172 -172.974)
		(end 360.78795 -172.974)
		(width 0.13208)
		(layer "F.Cu")
		(net "RST_PEX_SSD7_PERST_R_N")
	)
	(segment
		(start 336.493866 -215.987122)
		(end 336.09407 -215.587326)
		(width 0.13208)
		(layer "F.Cu")
		(net "RST_PEX_SSD7_PERST_R_N")
	)
	(segment
		(start 359.55605 -172.974)
		(end 360.172 -172.974)
		(width 0.13208)
		(layer "F.Cu")
		(net "RST_PEX_SSD7_PERST_R_N")
	)
	(via
		(at 336.09407 -215.587326)
		(size 0.4572)
		(drill 0.254)
		(layers "F.Cu" "B.Cu")
		(net "RST_PEX_SSD7_PERST_R_N")
	)
	(via
		(at 340.435946 -174.305722)
		(size 0.508)
		(drill 0.254)
		(layers "F.Cu" "B.Cu")
		(net "RST_PEX_SSD7_PERST_R_N")
	)
	(via
		(at 360.172 -172.974)
		(size 0.508)
		(drill 0.254)
		(layers "F.Cu" "B.Cu")
		(net "RST_PEX_SSD7_PERST_R_N")
	)
	(segment
		(start 337.54187 -177.95113)
		(end 340.435946 -175.057054)
		(width 0.15494)
		(layer "In7.Cu")
		(net "RST_PEX_SSD7_PERST_R_N")
	)
	(segment
		(start 333.756 -179.9844)
		(end 335.68513 -179.9844)
		(width 0.15494)
		(layer "In7.Cu")
		(net "RST_PEX_SSD7_PERST_R_N")
	)
	(segment
		(start 328.437494 -206.173578)
		(end 328.437494 -202.75296)
		(width 0.15494)
		(layer "In7.Cu")
		(net "RST_PEX_SSD7_PERST_R_N")
	)
	(segment
		(start 334.697324 -215.0872)
		(end 333.19847 -215.0872)
		(width 0.15494)
		(layer "In7.Cu")
		(net "RST_PEX_SSD7_PERST_R_N")
	)
	(segment
		(start 328.976482 -206.712566)
		(end 328.437494 -206.173578)
		(width 0.15494)
		(layer "In7.Cu")
		(net "RST_PEX_SSD7_PERST_R_N")
	)
	(segment
		(start 335.0006 -215.187276)
		(end 334.900524 -215.0872)
		(width 0.0889)
		(layer "In7.Cu")
		(net "RST_PEX_SSD7_PERST_R_N")
	)
	(segment
		(start 331.9399 -213.82863)
		(end 331.9399 -209.2071)
		(width 0.15494)
		(layer "In7.Cu")
		(net "RST_PEX_SSD7_PERST_R_N")
	)
	(segment
		(start 337.54187 -178.12766)
		(end 337.54187 -177.95113)
		(width 0.15494)
		(layer "In7.Cu")
		(net "RST_PEX_SSD7_PERST_R_N")
	)
	(segment
		(start 335.69402 -215.187276)
		(end 335.0006 -215.187276)
		(width 0.0889)
		(layer "In7.Cu")
		(net "RST_PEX_SSD7_PERST_R_N")
	)
	(segment
		(start 340.435946 -175.057054)
		(end 340.435946 -174.305722)
		(width 0.15494)
		(layer "In7.Cu")
		(net "RST_PEX_SSD7_PERST_R_N")
	)
	(segment
		(start 328.437494 -202.75296)
		(end 332.54315 -198.647304)
		(width 0.15494)
		(layer "In7.Cu")
		(net "RST_PEX_SSD7_PERST_R_N")
	)
	(segment
		(start 335.68513 -179.9844)
		(end 337.54187 -178.12766)
		(width 0.15494)
		(layer "In7.Cu")
		(net "RST_PEX_SSD7_PERST_R_N")
	)
	(segment
		(start 331.9399 -209.2071)
		(end 329.445366 -206.712566)
		(width 0.15494)
		(layer "In7.Cu")
		(net "RST_PEX_SSD7_PERST_R_N")
	)
	(segment
		(start 336.09407 -215.587326)
		(end 335.69402 -215.187276)
		(width 0.0889)
		(layer "In7.Cu")
		(net "RST_PEX_SSD7_PERST_R_N")
	)
	(segment
		(start 332.54315 -198.647304)
		(end 332.54315 -181.19725)
		(width 0.15494)
		(layer "In7.Cu")
		(net "RST_PEX_SSD7_PERST_R_N")
	)
	(segment
		(start 332.54315 -181.19725)
		(end 333.756 -179.9844)
		(width 0.15494)
		(layer "In7.Cu")
		(net "RST_PEX_SSD7_PERST_R_N")
	)
	(segment
		(start 329.445366 -206.712566)
		(end 328.976482 -206.712566)
		(width 0.15494)
		(layer "In7.Cu")
		(net "RST_PEX_SSD7_PERST_R_N")
	)
	(segment
		(start 334.900524 -215.0872)
		(end 334.697324 -215.0872)
		(width 0.0889)
		(layer "In7.Cu")
		(net "RST_PEX_SSD7_PERST_R_N")
	)
	(segment
		(start 333.19847 -215.0872)
		(end 331.9399 -213.82863)
		(width 0.15494)
		(layer "In7.Cu")
		(net "RST_PEX_SSD7_PERST_R_N")
	)
	(segment
		(start 340.435946 -174.305722)
		(end 342.13419 -174.305722)
		(width 0.15494)
		(layer "In13.Cu")
		(net "RST_PEX_SSD7_PERST_R_N")
	)
	(segment
		(start 349.948754 -173.655482)
		(end 351.484438 -172.119798)
		(width 0.15494)
		(layer "In13.Cu")
		(net "RST_PEX_SSD7_PERST_R_N")
	)
	(segment
		(start 351.484438 -172.119798)
		(end 359.317798 -172.119798)
		(width 0.15494)
		(layer "In13.Cu")
		(net "RST_PEX_SSD7_PERST_R_N")
	)
	(segment
		(start 359.317798 -172.119798)
		(end 360.172 -172.974)
		(width 0.15494)
		(layer "In13.Cu")
		(net "RST_PEX_SSD7_PERST_R_N")
	)
	(segment
		(start 342.78443 -173.655482)
		(end 349.948754 -173.655482)
		(width 0.15494)
		(layer "In13.Cu")
		(net "RST_PEX_SSD7_PERST_R_N")
	)
	(segment
		(start 342.13419 -174.305722)
		(end 342.78443 -173.655482)
		(width 0.15494)
		(layer "In13.Cu")
		(net "RST_PEX_SSD7_PERST_R_N")
	)
	(segment
		(start 26.861516 -308.89448)
		(end 27.381962 -309.414926)
		(width 0.13208)
		(layer "F.Cu")
		(net "IRQ_PEX0_CLKREQ_INT_N")
	)
	(via
		(at 27.381962 -309.414926)
		(size 0.508)
		(drill 0.254)
		(layers "F.Cu" "B.Cu")
		(net "IRQ_PEX0_CLKREQ_INT_N")
	)
	(via
		(at 48.24984 -308.249828)
		(size 0.4064)
		(drill 0.2032)
		(layers "F.Cu" "B.Cu")
		(net "IRQ_PEX0_CLKREQ_INT_N")
	)
	(segment
		(start 48.240188 -308.25948)
		(end 47.96028 -308.25948)
		(width 0.13208)
		(layer "B.Cu")
		(net "IRQ_PEX0_CLKREQ_INT_N")
	)
	(segment
		(start 48.24984 -308.249828)
		(end 48.240188 -308.25948)
		(width 0.13208)
		(layer "B.Cu")
		(net "IRQ_PEX0_CLKREQ_INT_N")
	)
	(segment
		(start 28.8798 -307.6702)
		(end 27.9146 -307.6702)
		(width 0.13208)
		(layer "B.Cu")
		(net "IRQ_PEX0_CLKREQ_INT_N")
	)
	(segment
		(start 47.96028 -308.25948)
		(end 47.5234 -307.8226)
		(width 0.13208)
		(layer "B.Cu")
		(net "IRQ_PEX0_CLKREQ_INT_N")
	)
	(segment
		(start 27.9146 -307.6702)
		(end 27.686 -307.8988)
		(width 0.13208)
		(layer "B.Cu")
		(net "IRQ_PEX0_CLKREQ_INT_N")
	)
	(segment
		(start 29.0322 -307.8226)
		(end 28.8798 -307.6702)
		(width 0.13208)
		(layer "B.Cu")
		(net "IRQ_PEX0_CLKREQ_INT_N")
	)
	(segment
		(start 27.686 -307.8988)
		(end 27.686 -309.110888)
		(width 0.13208)
		(layer "B.Cu")
		(net "IRQ_PEX0_CLKREQ_INT_N")
	)
	(segment
		(start 27.686 -309.110888)
		(end 27.381962 -309.414926)
		(width 0.13208)
		(layer "B.Cu")
		(net "IRQ_PEX0_CLKREQ_INT_N")
	)
	(segment
		(start 47.5234 -307.8226)
		(end 29.0322 -307.8226)
		(width 0.13208)
		(layer "B.Cu")
		(net "IRQ_PEX0_CLKREQ_INT_N")
	)
	(segment
		(start 329.37958 -210.50885)
		(end 329.099164 -209.832194)
		(width 0.13208)
		(layer "F.Cu")
		(net "HSC_TIMER_R_N")
	)
	(segment
		(start 327.93305 -208.153)
		(end 327.93305 -209.169)
		(width 0.13208)
		(layer "F.Cu")
		(net "HSC_TIMER_R_N")
	)
	(segment
		(start 328.43597 -209.169)
		(end 327.93305 -209.169)
		(width 0.13208)
		(layer "F.Cu")
		(net "HSC_TIMER_R_N")
	)
	(segment
		(start 335.693766 -217.587068)
		(end 335.29397 -217.187272)
		(width 0.13208)
		(layer "F.Cu")
		(net "HSC_TIMER_R_N")
	)
	(segment
		(start 329.099164 -209.832194)
		(end 328.43597 -209.169)
		(width 0.13208)
		(layer "F.Cu")
		(net "HSC_TIMER_R_N")
	)
	(via
		(at 329.37958 -210.50885)
		(size 0.762)
		(drill 0.254)
		(layers "F.Cu" "B.Cu")
		(net "HSC_TIMER_R_N")
	)
	(via
		(at 335.29397 -217.187272)
		(size 0.4572)
		(drill 0.254)
		(layers "F.Cu" "B.Cu")
		(net "HSC_TIMER_R_N")
	)
	(segment
		(start 334.66532 -216.558622)
		(end 335.29397 -217.187272)
		(width 0.15494)
		(layer "In7.Cu")
		(net "HSC_TIMER_R_N")
	)
	(segment
		(start 330.39685 -210.50885)
		(end 331.29982 -211.41182)
		(width 0.15494)
		(layer "In7.Cu")
		(net "HSC_TIMER_R_N")
	)
	(segment
		(start 329.37958 -210.50885)
		(end 330.39685 -210.50885)
		(width 0.15494)
		(layer "In7.Cu")
		(net "HSC_TIMER_R_N")
	)
	(segment
		(start 331.29982 -211.41182)
		(end 331.29982 -214.733124)
		(width 0.15494)
		(layer "In7.Cu")
		(net "HSC_TIMER_R_N")
	)
	(segment
		(start 331.29982 -214.733124)
		(end 333.125318 -216.558622)
		(width 0.15494)
		(layer "In7.Cu")
		(net "HSC_TIMER_R_N")
	)
	(segment
		(start 333.125318 -216.558622)
		(end 334.66532 -216.558622)
		(width 0.15494)
		(layer "In7.Cu")
		(net "HSC_TIMER_R_N")
	)
	(segment
		(start 252.810518 -205.961234)
		(end 252.937518 -205.834234)
		(width 0.13208)
		(layer "F.Cu")
		(net "JTAG_BIC_TDO")
	)
	(segment
		(start 252.488954 -206.697072)
		(end 252.488954 -205.961234)
		(width 0.13208)
		(layer "F.Cu")
		(net "JTAG_BIC_TDO")
	)
	(segment
		(start 252.488954 -205.961234)
		(end 252.810518 -205.961234)
		(width 0.13208)
		(layer "F.Cu")
		(net "JTAG_BIC_TDO")
	)
	(segment
		(start 252.937518 -205.834234)
		(end 252.937518 -204.79893)
		(width 0.13208)
		(layer "F.Cu")
		(net "JTAG_BIC_TDO")
	)
	(via
		(at 252.488954 -205.961234)
		(size 0.508)
		(drill 0.254)
		(layers "F.Cu" "B.Cu")
		(net "JTAG_BIC_TDO")
	)
	(segment
		(start 101.779832 -388.85622)
		(end 101.00818 -388.536434)
		(width 0.13462)
		(layer "F.Cu")
		(net "USB2_MB_BMC_R_DN")
	)
	(segment
		(start 101.00818 -388.536434)
		(end 100.78847 -388.316724)
		(width 0.13462)
		(layer "F.Cu")
		(net "USB2_MB_BMC_R_DN")
	)
	(segment
		(start 100.78847 -388.316724)
		(end 100.78847 -387.203442)
		(width 0.13462)
		(layer "F.Cu")
		(net "USB2_MB_BMC_R_DN")
	)
	(segment
		(start 101.98354 -389.357362)
		(end 101.98354 -389.059928)
		(width 0.13462)
		(layer "F.Cu")
		(net "USB2_MB_BMC_R_DN")
	)
	(segment
		(start 101.87686 -389.741918)
		(end 101.87686 -389.464042)
		(width 0.13462)
		(layer "F.Cu")
		(net "USB2_MB_BMC_R_DN")
	)
	(segment
		(start 101.87686 -389.464042)
		(end 101.98354 -389.357362)
		(width 0.13462)
		(layer "F.Cu")
		(net "USB2_MB_BMC_R_DN")
	)
	(segment
		(start 99.97948 -386.394452)
		(end 99.97948 -385.977892)
		(width 0.13462)
		(layer "F.Cu")
		(net "USB2_MB_BMC_R_DN")
	)
	(segment
		(start 101.98354 -389.059928)
		(end 101.779832 -388.85622)
		(width 0.13462)
		(layer "F.Cu")
		(net "USB2_MB_BMC_R_DN")
	)
	(segment
		(start 100.78847 -387.203442)
		(end 99.97948 -386.394452)
		(width 0.13462)
		(layer "F.Cu")
		(net "USB2_MB_BMC_R_DN")
	)
	(segment
		(start 358.761792 -193.299842)
		(end 358.75595 -193.294)
		(width 0.13208)
		(layer "F.Cu")
		(net "PEX0_PCA9555_INT_N")
	)
	(segment
		(start 358.761792 -194.397122)
		(end 358.761792 -193.299842)
		(width 0.13208)
		(layer "F.Cu")
		(net "PEX0_PCA9555_INT_N")
	)
	(segment
		(start 358.75595 -193.294)
		(end 358.14 -193.294)
		(width 0.13208)
		(layer "F.Cu")
		(net "PEX0_PCA9555_INT_N")
	)
	(segment
		(start 363.07395 -215.011)
		(end 362.458 -215.011)
		(width 0.13208)
		(layer "F.Cu")
		(net "PEX0_PCA9555_INT_N")
	)
	(via
		(at 358.14 -193.294)
		(size 0.508)
		(drill 0.254)
		(layers "F.Cu" "B.Cu")
		(net "PEX0_PCA9555_INT_N")
	)
	(via
		(at 362.458 -215.011)
		(size 0.508)
		(drill 0.254)
		(layers "F.Cu" "B.Cu")
		(net "PEX0_PCA9555_INT_N")
	)
	(segment
		(start 358.14 -194.332352)
		(end 358.14 -193.294)
		(width 0.13208)
		(layer "B.Cu")
		(net "PEX0_PCA9555_INT_N")
	)
	(segment
		(start 361.28198 -205.632812)
		(end 359.946194 -204.297026)
		(width 0.13208)
		(layer "B.Cu")
		(net "PEX0_PCA9555_INT_N")
	)
	(segment
		(start 359.946194 -204.297026)
		(end 359.946194 -196.138546)
		(width 0.13208)
		(layer "B.Cu")
		(net "PEX0_PCA9555_INT_N")
	)
	(segment
		(start 359.946194 -196.138546)
		(end 358.14 -194.332352)
		(width 0.13208)
		(layer "B.Cu")
		(net "PEX0_PCA9555_INT_N")
	)
	(segment
		(start 362.458 -215.011)
		(end 362.38561 -215.011)
		(width 0.13208)
		(layer "B.Cu")
		(net "PEX0_PCA9555_INT_N")
	)
	(segment
		(start 362.38561 -215.011)
		(end 361.28198 -213.90737)
		(width 0.13208)
		(layer "B.Cu")
		(net "PEX0_PCA9555_INT_N")
	)
	(segment
		(start 361.28198 -213.90737)
		(end 361.28198 -205.632812)
		(width 0.13208)
		(layer "B.Cu")
		(net "PEX0_PCA9555_INT_N")
	)
	(segment
		(start 336.493866 -223.187006)
		(end 336.09407 -223.586802)
		(width 0.13208)
		(layer "F.Cu")
		(net "FM_SYS_THROTTLE")
	)
	(via
		(at 336.09407 -223.586802)
		(size 0.4572)
		(drill 0.254)
		(layers "F.Cu" "B.Cu")
		(net "FM_SYS_THROTTLE")
	)
	(via
		(at 332.105 -223.52)
		(size 0.6604)
		(drill 0.3302)
		(layers "F.Cu" "B.Cu")
		(net "FM_SYS_THROTTLE")
	)
	(segment
		(start 333.58074 -223.18726)
		(end 335.694528 -223.18726)
		(width 0.0889)
		(layer "B.Cu")
		(net "FM_SYS_THROTTLE")
	)
	(segment
		(start 332.105 -223.52)
		(end 333.248 -223.52)
		(width 0.13208)
		(layer "B.Cu")
		(net "FM_SYS_THROTTLE")
	)
	(segment
		(start 330.09205 -223.4692)
		(end 332.0542 -223.4692)
		(width 0.13208)
		(layer "B.Cu")
		(net "FM_SYS_THROTTLE")
	)
	(segment
		(start 329.583542 -223.977708)
		(end 330.09205 -223.4692)
		(width 0.13208)
		(layer "B.Cu")
		(net "FM_SYS_THROTTLE")
	)
	(segment
		(start 332.0542 -223.4692)
		(end 332.105 -223.52)
		(width 0.13208)
		(layer "B.Cu")
		(net "FM_SYS_THROTTLE")
	)
	(segment
		(start 335.694528 -223.18726)
		(end 336.09407 -223.586802)
		(width 0.0889)
		(layer "B.Cu")
		(net "FM_SYS_THROTTLE")
	)
	(segment
		(start 333.248 -223.52)
		(end 333.58074 -223.18726)
		(width 0.13208)
		(layer "B.Cu")
		(net "FM_SYS_THROTTLE")
	)
	(segment
		(start 327.923906 -223.977708)
		(end 329.583542 -223.977708)
		(width 0.13208)
		(layer "B.Cu")
		(net "FM_SYS_THROTTLE")
	)
	(segment
		(start 224.671382 -225.120708)
		(end 224.671382 -224.300288)
		(width 0.13208)
		(layer "F.Cu")
		(net "HSC_UV_R_N")
	)
	(segment
		(start 185.972704 -415.15919)
		(end 185.972704 -414.031684)
		(width 0.13208)
		(layer "F.Cu")
		(net "HSC_UV_R_N")
	)
	(segment
		(start 185.976768 -412.797498)
		(end 185.97118 -412.79191)
		(width 0.13208)
		(layer "F.Cu")
		(net "HSC_UV_R_N")
	)
	(segment
		(start 185.97118 -412.79191)
		(end 185.3184 -412.79191)
		(width 0.13208)
		(layer "F.Cu")
		(net "HSC_UV_R_N")
	)
	(segment
		(start 185.976768 -414.02762)
		(end 185.976768 -412.797498)
		(width 0.13208)
		(layer "F.Cu")
		(net "HSC_UV_R_N")
	)
	(segment
		(start 185.972704 -414.031684)
		(end 185.976768 -414.02762)
		(width 0.13208)
		(layer "F.Cu")
		(net "HSC_UV_R_N")
	)
	(segment
		(start 224.68459 -225.133916)
		(end 224.671382 -225.120708)
		(width 0.13208)
		(layer "F.Cu")
		(net "HSC_UV_R_N")
	)
	(segment
		(start 335.693766 -219.987114)
		(end 335.29397 -220.38691)
		(width 0.13208)
		(layer "F.Cu")
		(net "HSC_UV_R_N")
	)
	(segment
		(start 224.671382 -224.300288)
		(end 225.067622 -223.904048)
		(width 0.13208)
		(layer "F.Cu")
		(net "HSC_UV_R_N")
	)
	(via
		(at 335.29397 -220.38691)
		(size 0.4572)
		(drill 0.254)
		(layers "F.Cu" "B.Cu")
		(net "HSC_UV_R_N")
	)
	(via
		(at 224.68459 -225.133916)
		(size 0.4572)
		(drill 0.254)
		(layers "F.Cu" "B.Cu")
		(net "HSC_UV_R_N")
	)
	(via
		(at 230.928164 -252.523752)
		(size 0.508)
		(drill 0.254)
		(layers "F.Cu" "B.Cu")
		(net "HSC_UV_R_N")
	)
	(via
		(at 185.3184 -412.79191)
		(size 0.508)
		(drill 0.254)
		(layers "F.Cu" "B.Cu")
		(net "HSC_UV_R_N")
	)
	(via
		(at 228.523546 -326.103488)
		(size 0.508)
		(drill 0.254)
		(layers "F.Cu" "B.Cu")
		(net "HSC_UV_R_N")
	)
	(segment
		(start 186.703716 -412.79191)
		(end 185.3184 -412.79191)
		(width 0.15494)
		(layer "In5.Cu")
		(net "HSC_UV_R_N")
	)
	(segment
		(start 189.221872 -368.450622)
		(end 189.221872 -372.482618)
		(width 0.15494)
		(layer "In5.Cu")
		(net "HSC_UV_R_N")
	)
	(segment
		(start 229.081076 -247.310148)
		(end 228.210872 -246.439944)
		(width 0.15494)
		(layer "In5.Cu")
		(net "HSC_UV_R_N")
	)
	(segment
		(start 186.097672 -375.606818)
		(end 186.097672 -403.039072)
		(width 0.15494)
		(layer "In5.Cu")
		(net "HSC_UV_R_N")
	)
	(segment
		(start 189.221872 -372.482618)
		(end 186.097672 -375.606818)
		(width 0.15494)
		(layer "In5.Cu")
		(net "HSC_UV_R_N")
	)
	(segment
		(start 202.7174 -353.695)
		(end 202.7174 -354.823268)
		(width 0.15494)
		(layer "In5.Cu")
		(net "HSC_UV_R_N")
	)
	(segment
		(start 199.542146 -357.998522)
		(end 199.542146 -358.642666)
		(width 0.15494)
		(layer "In5.Cu")
		(net "HSC_UV_R_N")
	)
	(segment
		(start 228.523546 -326.103488)
		(end 228.523546 -329.8444)
		(width 0.15494)
		(layer "In5.Cu")
		(net "HSC_UV_R_N")
	)
	(segment
		(start 191.502284 -366.17021)
		(end 189.221872 -368.450622)
		(width 0.15494)
		(layer "In5.Cu")
		(net "HSC_UV_R_N")
	)
	(segment
		(start 225.0821 -225.133916)
		(end 224.68459 -225.133916)
		(width 0.15494)
		(layer "In5.Cu")
		(net "HSC_UV_R_N")
	)
	(segment
		(start 197.586092 -360.198162)
		(end 191.839088 -365.945166)
		(width 0.15494)
		(layer "In5.Cu")
		(net "HSC_UV_R_N")
	)
	(segment
		(start 228.523546 -329.8444)
		(end 224.900998 -333.466948)
		(width 0.15494)
		(layer "In5.Cu")
		(net "HSC_UV_R_N")
	)
	(segment
		(start 203.1746 -353.2378)
		(end 202.7174 -353.695)
		(width 0.15494)
		(layer "In5.Cu")
		(net "HSC_UV_R_N")
	)
	(segment
		(start 191.839088 -365.945166)
		(end 191.502284 -366.17021)
		(width 0.15494)
		(layer "In5.Cu")
		(net "HSC_UV_R_N")
	)
	(segment
		(start 224.900998 -346.782898)
		(end 218.446096 -353.2378)
		(width 0.15494)
		(layer "In5.Cu")
		(net "HSC_UV_R_N")
	)
	(segment
		(start 186.097672 -403.039072)
		(end 188.408818 -405.350218)
		(width 0.15494)
		(layer "In5.Cu")
		(net "HSC_UV_R_N")
	)
	(segment
		(start 218.446096 -353.2378)
		(end 203.1746 -353.2378)
		(width 0.15494)
		(layer "In5.Cu")
		(net "HSC_UV_R_N")
	)
	(segment
		(start 230.928164 -252.523752)
		(end 229.081076 -250.676664)
		(width 0.15494)
		(layer "In5.Cu")
		(net "HSC_UV_R_N")
	)
	(segment
		(start 229.081076 -250.676664)
		(end 229.081076 -247.310148)
		(width 0.15494)
		(layer "In5.Cu")
		(net "HSC_UV_R_N")
	)
	(segment
		(start 188.408818 -405.350218)
		(end 188.408818 -411.086808)
		(width 0.15494)
		(layer "In5.Cu")
		(net "HSC_UV_R_N")
	)
	(segment
		(start 199.542146 -358.642666)
		(end 197.98665 -360.198162)
		(width 0.15494)
		(layer "In5.Cu")
		(net "HSC_UV_R_N")
	)
	(segment
		(start 188.408818 -411.086808)
		(end 186.703716 -412.79191)
		(width 0.15494)
		(layer "In5.Cu")
		(net "HSC_UV_R_N")
	)
	(segment
		(start 202.7174 -354.823268)
		(end 199.542146 -357.998522)
		(width 0.15494)
		(layer "In5.Cu")
		(net "HSC_UV_R_N")
	)
	(segment
		(start 197.98665 -360.198162)
		(end 197.586092 -360.198162)
		(width 0.15494)
		(layer "In5.Cu")
		(net "HSC_UV_R_N")
	)
	(segment
		(start 228.210872 -246.439944)
		(end 228.210872 -228.262688)
		(width 0.15494)
		(layer "In5.Cu")
		(net "HSC_UV_R_N")
	)
	(segment
		(start 224.900998 -333.466948)
		(end 224.900998 -346.782898)
		(width 0.15494)
		(layer "In5.Cu")
		(net "HSC_UV_R_N")
	)
	(segment
		(start 228.210872 -228.262688)
		(end 225.0821 -225.133916)
		(width 0.15494)
		(layer "In5.Cu")
		(net "HSC_UV_R_N")
	)
	(segment
		(start 233.786172 -323.348858)
		(end 233.786172 -282.667964)
		(width 0.15494)
		(layer "In11.Cu")
		(net "HSC_UV_R_N")
	)
	(segment
		(start 233.786172 -282.667964)
		(end 232.212134 -281.093926)
		(width 0.15494)
		(layer "In11.Cu")
		(net "HSC_UV_R_N")
	)
	(segment
		(start 228.523546 -326.103488)
		(end 231.031542 -326.103488)
		(width 0.15494)
		(layer "In11.Cu")
		(net "HSC_UV_R_N")
	)
	(segment
		(start 230.928164 -255.51384)
		(end 230.928164 -252.523752)
		(width 0.15494)
		(layer "In11.Cu")
		(net "HSC_UV_R_N")
	)
	(segment
		(start 232.212134 -256.79781)
		(end 230.928164 -255.51384)
		(width 0.15494)
		(layer "In11.Cu")
		(net "HSC_UV_R_N")
	)
	(segment
		(start 231.031542 -326.103488)
		(end 233.786172 -323.348858)
		(width 0.15494)
		(layer "In11.Cu")
		(net "HSC_UV_R_N")
	)
	(segment
		(start 232.212134 -281.093926)
		(end 232.212134 -256.79781)
		(width 0.15494)
		(layer "In11.Cu")
		(net "HSC_UV_R_N")
	)
	(segment
		(start 246.619776 -218.0336)
		(end 244.956076 -219.6973)
		(width 0.15494)
		(layer "In15.Cu")
		(net "HSC_UV_R_N")
	)
	(segment
		(start 286.744156 -218.44381)
		(end 266.288266 -218.44381)
		(width 0.15494)
		(layer "In15.Cu")
		(net "HSC_UV_R_N")
	)
	(segment
		(start 236.564932 -225.553524)
		(end 236.033056 -226.0854)
		(width 0.15494)
		(layer "In15.Cu")
		(net "HSC_UV_R_N")
	)
	(segment
		(start 236.033056 -226.0854)
		(end 226.449382 -226.0854)
		(width 0.15494)
		(layer "In15.Cu")
		(net "HSC_UV_R_N")
	)
	(segment
		(start 291.840158 -213.347808)
		(end 286.744156 -218.44381)
		(width 0.15494)
		(layer "In15.Cu")
		(net "HSC_UV_R_N")
	)
	(segment
		(start 237.893352 -224.4471)
		(end 237.325154 -224.4471)
		(width 0.15494)
		(layer "In15.Cu")
		(net "HSC_UV_R_N")
	)
	(segment
		(start 260.202426 -216.8144)
		(end 257.4036 -216.8144)
		(width 0.15494)
		(layer "In15.Cu")
		(net "HSC_UV_R_N")
	)
	(segment
		(start 253.858268 -215.3158)
		(end 252.271276 -216.902792)
		(width 0.15494)
		(layer "In15.Cu")
		(net "HSC_UV_R_N")
	)
	(segment
		(start 327.999344 -217.8558)
		(end 326.9488 -216.805256)
		(width 0.15494)
		(layer "In15.Cu")
		(net "HSC_UV_R_N")
	)
	(segment
		(start 237.325154 -224.4471)
		(end 236.810296 -224.961958)
		(width 0.15494)
		(layer "In15.Cu")
		(net "HSC_UV_R_N")
	)
	(segment
		(start 330.190348 -218.850972)
		(end 329.195176 -217.8558)
		(width 0.15494)
		(layer "In15.Cu")
		(net "HSC_UV_R_N")
	)
	(segment
		(start 266.288266 -218.44381)
		(end 265.609832 -217.765376)
		(width 0.15494)
		(layer "In15.Cu")
		(net "HSC_UV_R_N")
	)
	(segment
		(start 333.54137 -219.89796)
		(end 332.494382 -218.850972)
		(width 0.15494)
		(layer "In15.Cu")
		(net "HSC_UV_R_N")
	)
	(segment
		(start 319.506092 -213.347808)
		(end 291.840158 -213.347808)
		(width 0.15494)
		(layer "In15.Cu")
		(net "HSC_UV_R_N")
	)
	(segment
		(start 257.4036 -216.8144)
		(end 255.905 -215.3158)
		(width 0.15494)
		(layer "In15.Cu")
		(net "HSC_UV_R_N")
	)
	(segment
		(start 322.082668 -215.924384)
		(end 319.506092 -213.347808)
		(width 0.15494)
		(layer "In15.Cu")
		(net "HSC_UV_R_N")
	)
	(segment
		(start 244.956076 -219.6973)
		(end 244.956076 -220.567504)
		(width 0.15494)
		(layer "In15.Cu")
		(net "HSC_UV_R_N")
	)
	(segment
		(start 326.15251 -216.805256)
		(end 325.271638 -215.924384)
		(width 0.15494)
		(layer "In15.Cu")
		(net "HSC_UV_R_N")
	)
	(segment
		(start 329.195176 -217.8558)
		(end 327.999344 -217.8558)
		(width 0.15494)
		(layer "In15.Cu")
		(net "HSC_UV_R_N")
	)
	(segment
		(start 261.273798 -217.885772)
		(end 260.202426 -216.8144)
		(width 0.15494)
		(layer "In15.Cu")
		(net "HSC_UV_R_N")
	)
	(segment
		(start 244.956076 -220.567504)
		(end 241.975132 -223.548448)
		(width 0.15494)
		(layer "In15.Cu")
		(net "HSC_UV_R_N")
	)
	(segment
		(start 262.994648 -217.765376)
		(end 262.874252 -217.885772)
		(width 0.15494)
		(layer "In15.Cu")
		(net "HSC_UV_R_N")
	)
	(segment
		(start 249.503946 -218.0336)
		(end 246.619776 -218.0336)
		(width 0.15494)
		(layer "In15.Cu")
		(net "HSC_UV_R_N")
	)
	(segment
		(start 238.792004 -223.548448)
		(end 237.893352 -224.4471)
		(width 0.15494)
		(layer "In15.Cu")
		(net "HSC_UV_R_N")
	)
	(segment
		(start 262.874252 -217.885772)
		(end 261.273798 -217.885772)
		(width 0.15494)
		(layer "In15.Cu")
		(net "HSC_UV_R_N")
	)
	(segment
		(start 226.449382 -226.0854)
		(end 225.497898 -225.133916)
		(width 0.15494)
		(layer "In15.Cu")
		(net "HSC_UV_R_N")
	)
	(segment
		(start 326.9488 -216.805256)
		(end 326.15251 -216.805256)
		(width 0.15494)
		(layer "In15.Cu")
		(net "HSC_UV_R_N")
	)
	(segment
		(start 325.271638 -215.924384)
		(end 322.082668 -215.924384)
		(width 0.15494)
		(layer "In15.Cu")
		(net "HSC_UV_R_N")
	)
	(segment
		(start 265.609832 -217.765376)
		(end 262.994648 -217.765376)
		(width 0.15494)
		(layer "In15.Cu")
		(net "HSC_UV_R_N")
	)
	(segment
		(start 250.634754 -216.902792)
		(end 249.503946 -218.0336)
		(width 0.15494)
		(layer "In15.Cu")
		(net "HSC_UV_R_N")
	)
	(segment
		(start 255.905 -215.3158)
		(end 253.858268 -215.3158)
		(width 0.15494)
		(layer "In15.Cu")
		(net "HSC_UV_R_N")
	)
	(segment
		(start 225.497898 -225.133916)
		(end 224.68459 -225.133916)
		(width 0.15494)
		(layer "In15.Cu")
		(net "HSC_UV_R_N")
	)
	(segment
		(start 241.975132 -223.548448)
		(end 238.792004 -223.548448)
		(width 0.15494)
		(layer "In15.Cu")
		(net "HSC_UV_R_N")
	)
	(segment
		(start 332.494382 -218.850972)
		(end 330.190348 -218.850972)
		(width 0.15494)
		(layer "In15.Cu")
		(net "HSC_UV_R_N")
	)
	(segment
		(start 252.271276 -216.902792)
		(end 250.634754 -216.902792)
		(width 0.15494)
		(layer "In15.Cu")
		(net "HSC_UV_R_N")
	)
	(segment
		(start 236.810296 -224.961958)
		(end 236.564932 -225.553524)
		(width 0.15494)
		(layer "In15.Cu")
		(net "HSC_UV_R_N")
	)
	(segment
		(start 334.80502 -219.89796)
		(end 333.54137 -219.89796)
		(width 0.15494)
		(layer "In15.Cu")
		(net "HSC_UV_R_N")
	)
	(segment
		(start 335.29397 -220.38691)
		(end 334.80502 -219.89796)
		(width 0.15494)
		(layer "In15.Cu")
		(net "HSC_UV_R_N")
	)
	(segment
		(start 101.06279 -388.202932)
		(end 101.06279 -387.203696)
		(width 0.13462)
		(layer "F.Cu")
		(net "USB2_MB_BMC_R_DP")
	)
	(segment
		(start 101.163628 -388.30377)
		(end 101.06279 -388.202932)
		(width 0.13462)
		(layer "F.Cu")
		(net "USB2_MB_BMC_R_DP")
	)
	(segment
		(start 102.25786 -389.32485)
		(end 102.25786 -388.946136)
		(width 0.13462)
		(layer "F.Cu")
		(net "USB2_MB_BMC_R_DP")
	)
	(segment
		(start 101.062536 -387.203442)
		(end 101.062536 -387.200394)
		(width 0.13462)
		(layer "F.Cu")
		(net "USB2_MB_BMC_R_DP")
	)
	(segment
		(start 102.376986 -389.443976)
		(end 102.25786 -389.32485)
		(width 0.13462)
		(layer "F.Cu")
		(net "USB2_MB_BMC_R_DP")
	)
	(segment
		(start 101.06279 -387.203696)
		(end 101.062536 -387.203442)
		(width 0.13462)
		(layer "F.Cu")
		(net "USB2_MB_BMC_R_DP")
	)
	(segment
		(start 101.829362 -386.433568)
		(end 101.829362 -386.005324)
		(width 0.13462)
		(layer "F.Cu")
		(net "USB2_MB_BMC_R_DP")
	)
	(segment
		(start 102.25786 -388.946136)
		(end 101.93528 -388.623556)
		(width 0.13462)
		(layer "F.Cu")
		(net "USB2_MB_BMC_R_DP")
	)
	(segment
		(start 101.93528 -388.623556)
		(end 101.163628 -388.30377)
		(width 0.13462)
		(layer "F.Cu")
		(net "USB2_MB_BMC_R_DP")
	)
	(segment
		(start 101.062536 -387.200394)
		(end 101.829362 -386.433568)
		(width 0.13462)
		(layer "F.Cu")
		(net "USB2_MB_BMC_R_DP")
	)
	(segment
		(start 102.376986 -389.741918)
		(end 102.376986 -389.443976)
		(width 0.13462)
		(layer "F.Cu")
		(net "USB2_MB_BMC_R_DP")
	)
	(segment
		(start 280.449782 -297.79976)
		(end 279.974802 -298.27474)
		(width 0.249936)
		(layer "F.Cu")
		(net "SYSPLL_VDDA18_PEX2")
	)
	(via
		(at 265.316462 -280.693114)
		(size 0.508)
		(drill 0.254)
		(layers "F.Cu" "B.Cu")
		(net "SYSPLL_VDDA18_PEX2")
	)
	(via
		(at 263.919462 -280.693114)
		(size 0.508)
		(drill 0.254)
		(layers "F.Cu" "B.Cu")
		(net "SYSPLL_VDDA18_PEX2")
	)
	(via
		(at 279.974802 -298.27474)
		(size 0.4064)
		(drill 0.2032)
		(layers "F.Cu" "B.Cu")
		(net "SYSPLL_VDDA18_PEX2")
	)
	(segment
		(start 279.202642 -298.27474)
		(end 279.974802 -298.27474)
		(width 0.3048)
		(layer "B.Cu")
		(net "SYSPLL_VDDA18_PEX2")
	)
	(segment
		(start 364.487968 -185.671968)
		(end 365.185452 -185.671968)
		(width 0.13208)
		(layer "F.Cu")
		(net "RST_PEX_SSD3_PERST_N")
	)
	(segment
		(start 361.58805 -184.15)
		(end 362.966 -184.15)
		(width 0.13208)
		(layer "F.Cu")
		(net "RST_PEX_SSD3_PERST_N")
	)
	(segment
		(start 362.966 -184.15)
		(end 364.487968 -185.671968)
		(width 0.13208)
		(layer "F.Cu")
		(net "RST_PEX_SSD3_PERST_N")
	)
	(segment
		(start 365.185452 -185.671968)
		(end 365.706406 -186.192922)
		(width 0.13208)
		(layer "F.Cu")
		(net "RST_PEX_SSD3_PERST_N")
	)
	(segment
		(start 365.706406 -186.192922)
		(end 366.263936 -186.192922)
		(width 0.13208)
		(layer "F.Cu")
		(net "RST_PEX_SSD3_PERST_N")
	)
	(via
		(at 365.185452 -185.671968)
		(size 0.508)
		(drill 0.254)
		(layers "F.Cu" "B.Cu")
		(net "RST_PEX_SSD3_PERST_N")
	)
	(segment
		(start 218.17203 -78.4606)
		(end 219.069158 -77.563472)
		(width 0.13208)
		(layer "F.Cu")
		(net "SSD8_LED")
	)
	(segment
		(start 220.960696 -77.563472)
		(end 221.590108 -77.563472)
		(width 0.13208)
		(layer "F.Cu")
		(net "SSD8_LED")
	)
	(segment
		(start 217.422222 -78.4606)
		(end 218.17203 -78.4606)
		(width 0.13208)
		(layer "F.Cu")
		(net "SSD8_LED")
	)
	(segment
		(start 219.069158 -77.563472)
		(end 220.960696 -77.563472)
		(width 0.13208)
		(layer "F.Cu")
		(net "SSD8_LED")
	)
	(via
		(at 220.960696 -77.563472)
		(size 0.508)
		(drill 0.254)
		(layers "F.Cu" "B.Cu")
		(net "SSD8_LED")
	)
	(segment
		(start 227.467668 -223.104202)
		(end 227.067872 -223.503998)
		(width 0.13208)
		(layer "F.Cu")
		(net "BOARD_ID1")
	)
	(via
		(at 227.067872 -223.503998)
		(size 0.4572)
		(drill 0.254)
		(layers "F.Cu" "B.Cu")
		(net "BOARD_ID1")
	)
	(via
		(at 227.996242 -229.211886)
		(size 0.6604)
		(drill 0.3302)
		(layers "F.Cu" "B.Cu")
		(net "BOARD_ID1")
	)
	(segment
		(start 229.434644 -229.452932)
		(end 229.434644 -230.825548)
		(width 0.13208)
		(layer "B.Cu")
		(net "BOARD_ID1")
	)
	(segment
		(start 227.996242 -229.211886)
		(end 229.193598 -229.211886)
		(width 0.13208)
		(layer "B.Cu")
		(net "BOARD_ID1")
	)
	(segment
		(start 229.193598 -229.211886)
		(end 229.434644 -229.452932)
		(width 0.13208)
		(layer "B.Cu")
		(net "BOARD_ID1")
	)
	(segment
		(start 228.418644 -230.825548)
		(end 229.434644 -230.825548)
		(width 0.13208)
		(layer "B.Cu")
		(net "BOARD_ID1")
	)
	(segment
		(start 227.067872 -228.283516)
		(end 227.067872 -223.503998)
		(width 0.13208)
		(layer "B.Cu")
		(net "BOARD_ID1")
	)
	(segment
		(start 227.996242 -229.211886)
		(end 227.067872 -228.283516)
		(width 0.13208)
		(layer "B.Cu")
		(net "BOARD_ID1")
	)
	(segment
		(start 229.810818 -93.675454)
		(end 229.19309 -93.057726)
		(width 0.13208)
		(layer "F.Cu")
		(net "PEX_USB_HUB_PSELF")
	)
	(segment
		(start 229.19309 -95.089726)
		(end 229.19309 -94.073726)
		(width 0.13208)
		(layer "F.Cu")
		(net "PEX_USB_HUB_PSELF")
	)
	(segment
		(start 231.065832 -93.76664)
		(end 230.211376 -94.621096)
		(width 0.13208)
		(layer "F.Cu")
		(net "PEX_USB_HUB_PSELF")
	)
	(segment
		(start 229.810818 -94.220538)
		(end 229.810818 -93.675454)
		(width 0.13208)
		(layer "F.Cu")
		(net "PEX_USB_HUB_PSELF")
	)
	(segment
		(start 229.19309 -94.073726)
		(end 229.19309 -93.057726)
		(width 0.13208)
		(layer "F.Cu")
		(net "PEX_USB_HUB_PSELF")
	)
	(segment
		(start 231.60863 -93.76664)
		(end 231.065832 -93.76664)
		(width 0.13208)
		(layer "F.Cu")
		(net "PEX_USB_HUB_PSELF")
	)
	(segment
		(start 230.211376 -94.621096)
		(end 229.810818 -94.220538)
		(width 0.13208)
		(layer "F.Cu")
		(net "PEX_USB_HUB_PSELF")
	)
	(via
		(at 230.211376 -94.621096)
		(size 0.508)
		(drill 0.254)
		(layers "F.Cu" "B.Cu")
		(net "PEX_USB_HUB_PSELF")
	)
	(segment
		(start 279.974802 -296.37482)
		(end 280.449782 -295.89984)
		(width 0.249936)
		(layer "F.Cu")
		(net "PCEPLL3_VDDA18_PEX2")
	)
	(via
		(at 279.974802 -296.37482)
		(size 0.4064)
		(drill 0.2032)
		(layers "F.Cu" "B.Cu")
		(net "PCEPLL3_VDDA18_PEX2")
	)
	(via
		(at 268.274546 -260.338316)
		(size 0.508)
		(drill 0.254)
		(layers "F.Cu" "B.Cu")
		(net "PCEPLL3_VDDA18_PEX2")
	)
	(via
		(at 266.877546 -260.338316)
		(size 0.508)
		(drill 0.254)
		(layers "F.Cu" "B.Cu")
		(net "PCEPLL3_VDDA18_PEX2")
	)
	(segment
		(start 279.974802 -295.6433)
		(end 279.974802 -296.37482)
		(width 0.3048)
		(layer "B.Cu")
		(net "PCEPLL3_VDDA18_PEX2")
	)
	(segment
		(start 365.713772 -186.842908)
		(end 365.191548 -186.320684)
		(width 0.13208)
		(layer "F.Cu")
		(net "SSD3_PEX_PWR_EN")
	)
	(segment
		(start 363.7915 -185.8645)
		(end 363.6645 -185.8645)
		(width 0.13208)
		(layer "F.Cu")
		(net "SSD3_PEX_PWR_EN")
	)
	(segment
		(start 362.966 -185.166)
		(end 361.58805 -185.166)
		(width 0.13208)
		(layer "F.Cu")
		(net "SSD3_PEX_PWR_EN")
	)
	(segment
		(start 366.263936 -186.842908)
		(end 365.713772 -186.842908)
		(width 0.13208)
		(layer "F.Cu")
		(net "SSD3_PEX_PWR_EN")
	)
	(segment
		(start 365.191548 -186.320684)
		(end 364.247684 -186.320684)
		(width 0.13208)
		(layer "F.Cu")
		(net "SSD3_PEX_PWR_EN")
	)
	(segment
		(start 363.6645 -185.8645)
		(end 362.966 -185.166)
		(width 0.13208)
		(layer "F.Cu")
		(net "SSD3_PEX_PWR_EN")
	)
	(segment
		(start 364.247684 -186.320684)
		(end 363.7915 -185.8645)
		(width 0.13208)
		(layer "F.Cu")
		(net "SSD3_PEX_PWR_EN")
	)
	(via
		(at 362.966 -185.166)
		(size 0.508)
		(drill 0.254)
		(layers "F.Cu" "B.Cu")
		(net "SSD3_PEX_PWR_EN")
	)
	(segment
		(start 338.47405 -142.875)
		(end 339.852 -142.875)
		(width 0.13208)
		(layer "F.Cu")
		(net "SSD15_PEX_PWR_EN")
	)
	(segment
		(start 342.599772 -144.551908)
		(end 343.149936 -144.551908)
		(width 0.13208)
		(layer "F.Cu")
		(net "SSD15_PEX_PWR_EN")
	)
	(segment
		(start 339.852 -142.875)
		(end 340.5505 -143.5735)
		(width 0.13208)
		(layer "F.Cu")
		(net "SSD15_PEX_PWR_EN")
	)
	(segment
		(start 340.6775 -143.5735)
		(end 341.133684 -144.029684)
		(width 0.13208)
		(layer "F.Cu")
		(net "SSD15_PEX_PWR_EN")
	)
	(segment
		(start 341.133684 -144.029684)
		(end 342.077548 -144.029684)
		(width 0.13208)
		(layer "F.Cu")
		(net "SSD15_PEX_PWR_EN")
	)
	(segment
		(start 340.5505 -143.5735)
		(end 340.6775 -143.5735)
		(width 0.13208)
		(layer "F.Cu")
		(net "SSD15_PEX_PWR_EN")
	)
	(segment
		(start 342.077548 -144.029684)
		(end 342.599772 -144.551908)
		(width 0.13208)
		(layer "F.Cu")
		(net "SSD15_PEX_PWR_EN")
	)
	(via
		(at 339.852 -142.875)
		(size 0.508)
		(drill 0.254)
		(layers "F.Cu" "B.Cu")
		(net "SSD15_PEX_PWR_EN")
	)
	(segment
		(start 335.693766 -223.187006)
		(end 335.29397 -223.586802)
		(width 0.13208)
		(layer "F.Cu")
		(net "RST_PEX_SYS_N")
	)
	(segment
		(start 327.946766 -227.089716)
		(end 327.946766 -226.635818)
		(width 0.13208)
		(layer "F.Cu")
		(net "RST_PEX_SYS_N")
	)
	(segment
		(start 328.168 -227.31095)
		(end 327.946766 -227.089716)
		(width 0.13208)
		(layer "F.Cu")
		(net "RST_PEX_SYS_N")
	)
	(via
		(at 335.29397 -223.586802)
		(size 0.4572)
		(drill 0.254)
		(layers "F.Cu" "B.Cu")
		(net "RST_PEX_SYS_N")
	)
	(via
		(at 327.946766 -226.635818)
		(size 0.508)
		(drill 0.254)
		(layers "F.Cu" "B.Cu")
		(net "RST_PEX_SYS_N")
	)
	(segment
		(start 328.576178 -226.280726)
		(end 331.270102 -223.586802)
		(width 0.15494)
		(layer "In5.Cu")
		(net "RST_PEX_SYS_N")
	)
	(segment
		(start 328.301858 -226.280726)
		(end 328.576178 -226.280726)
		(width 0.15494)
		(layer "In5.Cu")
		(net "RST_PEX_SYS_N")
	)
	(segment
		(start 331.270102 -223.586802)
		(end 335.29397 -223.586802)
		(width 0.15494)
		(layer "In5.Cu")
		(net "RST_PEX_SYS_N")
	)
	(segment
		(start 327.946766 -226.635818)
		(end 328.301858 -226.280726)
		(width 0.15494)
		(layer "In5.Cu")
		(net "RST_PEX_SYS_N")
	)
	(segment
		(start 48.24984 -292.099746)
		(end 47.77486 -291.624766)
		(width 0.249936)
		(layer "F.Cu")
		(net "PCEPLL7_VDDA18_PEX0")
	)
	(via
		(at 31.71952 -283.893514)
		(size 0.508)
		(drill 0.254)
		(layers "F.Cu" "B.Cu")
		(net "PCEPLL7_VDDA18_PEX0")
	)
	(via
		(at 33.11652 -283.893514)
		(size 0.508)
		(drill 0.254)
		(layers "F.Cu" "B.Cu")
		(net "PCEPLL7_VDDA18_PEX0")
	)
	(via
		(at 47.77486 -291.624766)
		(size 0.4064)
		(drill 0.2032)
		(layers "F.Cu" "B.Cu")
		(net "PCEPLL7_VDDA18_PEX0")
	)
	(segment
		(start 47.0027 -291.624766)
		(end 47.77486 -291.624766)
		(width 0.3048)
		(layer "B.Cu")
		(net "PCEPLL7_VDDA18_PEX0")
	)
	(segment
		(start 47.77486 -291.208206)
		(end 47.77486 -291.624766)
		(width 0.3048)
		(layer "B.Cu")
		(net "PCEPLL7_VDDA18_PEX0")
	)
	(segment
		(start 342.592406 -143.901922)
		(end 343.149936 -143.901922)
		(width 0.13208)
		(layer "F.Cu")
		(net "RST_PEX_SSD15_PERST_N")
	)
	(segment
		(start 341.373968 -143.380968)
		(end 342.071452 -143.380968)
		(width 0.13208)
		(layer "F.Cu")
		(net "RST_PEX_SSD15_PERST_N")
	)
	(segment
		(start 338.47405 -141.859)
		(end 339.852 -141.859)
		(width 0.13208)
		(layer "F.Cu")
		(net "RST_PEX_SSD15_PERST_N")
	)
	(segment
		(start 342.071452 -143.380968)
		(end 342.592406 -143.901922)
		(width 0.13208)
		(layer "F.Cu")
		(net "RST_PEX_SSD15_PERST_N")
	)
	(segment
		(start 339.852 -141.859)
		(end 341.373968 -143.380968)
		(width 0.13208)
		(layer "F.Cu")
		(net "RST_PEX_SSD15_PERST_N")
	)
	(via
		(at 342.071452 -143.380968)
		(size 0.508)
		(drill 0.254)
		(layers "F.Cu" "B.Cu")
		(net "RST_PEX_SSD15_PERST_N")
	)
	(segment
		(start 224.818702 -226.63023)
		(end 225.467672 -225.98126)
		(width 0.13208)
		(layer "F.Cu")
		(net "BOARD_ID2")
	)
	(segment
		(start 218.75242 -229.602284)
		(end 217.56624 -229.602284)
		(width 0.13208)
		(layer "F.Cu")
		(net "BOARD_ID2")
	)
	(segment
		(start 217.56624 -229.602284)
		(end 216.567512 -230.601012)
		(width 0.13208)
		(layer "F.Cu")
		(net "BOARD_ID2")
	)
	(segment
		(start 223.303338 -227.71862)
		(end 222.903034 -227.71862)
		(width 0.13208)
		(layer "F.Cu")
		(net "BOARD_ID2")
	)
	(segment
		(start 221.843854 -228.7778)
		(end 219.576904 -228.7778)
		(width 0.13208)
		(layer "F.Cu")
		(net "BOARD_ID2")
	)
	(segment
		(start 223.303338 -227.71862)
		(end 223.303338 -227.247704)
		(width 0.13208)
		(layer "F.Cu")
		(net "BOARD_ID2")
	)
	(segment
		(start 219.576904 -228.7778)
		(end 218.75242 -229.602284)
		(width 0.13208)
		(layer "F.Cu")
		(net "BOARD_ID2")
	)
	(segment
		(start 222.903034 -227.71862)
		(end 221.843854 -228.7778)
		(width 0.13208)
		(layer "F.Cu")
		(net "BOARD_ID2")
	)
	(segment
		(start 223.920812 -226.63023)
		(end 224.818702 -226.63023)
		(width 0.13208)
		(layer "F.Cu")
		(net "BOARD_ID2")
	)
	(segment
		(start 215.551512 -231.016556)
		(end 216.567512 -231.016556)
		(width 0.13208)
		(layer "F.Cu")
		(net "BOARD_ID2")
	)
	(segment
		(start 216.567512 -230.601012)
		(end 216.567512 -231.016556)
		(width 0.13208)
		(layer "F.Cu")
		(net "BOARD_ID2")
	)
	(segment
		(start 223.303338 -227.247704)
		(end 223.920812 -226.63023)
		(width 0.13208)
		(layer "F.Cu")
		(net "BOARD_ID2")
	)
	(segment
		(start 225.467672 -225.98126)
		(end 225.467672 -224.304098)
		(width 0.13208)
		(layer "F.Cu")
		(net "BOARD_ID2")
	)
	(segment
		(start 225.467672 -224.304098)
		(end 225.867722 -223.904048)
		(width 0.13208)
		(layer "F.Cu")
		(net "BOARD_ID2")
	)
	(via
		(at 223.303338 -227.71862)
		(size 0.762)
		(drill 0.381)
		(layers "F.Cu" "B.Cu")
		(net "BOARD_ID2")
	)
	(segment
		(start 238.342678 -204.441044)
		(end 238.342678 -205.449424)
		(width 0.13208)
		(layer "F.Cu")
		(net "CLK_25M_BIC")
	)
	(via
		(at 238.342678 -205.449424)
		(size 0.508)
		(drill 0.254)
		(layers "F.Cu" "B.Cu")
		(net "CLK_25M_BIC")
	)
	(segment
		(start 234.13466 -206.62011)
		(end 235.305346 -205.449424)
		(width 0.13208)
		(layer "B.Cu")
		(net "CLK_25M_BIC")
	)
	(segment
		(start 235.305346 -205.449424)
		(end 238.342678 -205.449424)
		(width 0.13208)
		(layer "B.Cu")
		(net "CLK_25M_BIC")
	)
	(segment
		(start 99.50196 -395.180566)
		(end 100.286312 -394.396214)
		(width 0.13208)
		(layer "F.Cu")
		(net "BIC_USB_HUB_PSELF")
	)
	(segment
		(start 100.286312 -393.796774)
		(end 100.428552 -393.654534)
		(width 0.13208)
		(layer "F.Cu")
		(net "BIC_USB_HUB_PSELF")
	)
	(segment
		(start 100.286312 -394.396214)
		(end 100.286312 -393.796774)
		(width 0.13208)
		(layer "F.Cu")
		(net "BIC_USB_HUB_PSELF")
	)
	(segment
		(start 100.428552 -393.654534)
		(end 100.964492 -393.654534)
		(width 0.13208)
		(layer "F.Cu")
		(net "BIC_USB_HUB_PSELF")
	)
	(segment
		(start 98.448368 -395.1478)
		(end 98.448368 -394.1318)
		(width 0.13208)
		(layer "F.Cu")
		(net "BIC_USB_HUB_PSELF")
	)
	(segment
		(start 98.448368 -395.1478)
		(end 98.448368 -396.1638)
		(width 0.13208)
		(layer "F.Cu")
		(net "BIC_USB_HUB_PSELF")
	)
	(segment
		(start 98.448368 -394.1318)
		(end 98.453194 -394.1318)
		(width 0.13208)
		(layer "F.Cu")
		(net "BIC_USB_HUB_PSELF")
	)
	(segment
		(start 98.453194 -394.1318)
		(end 99.50196 -395.180566)
		(width 0.13208)
		(layer "F.Cu")
		(net "BIC_USB_HUB_PSELF")
	)
	(via
		(at 99.50196 -395.180566)
		(size 0.508)
		(drill 0.254)
		(layers "F.Cu" "B.Cu")
		(net "BIC_USB_HUB_PSELF")
	)
	(segment
		(start 47.29988 -298.74972)
		(end 46.8249 -299.224954)
		(width 0.249936)
		(layer "F.Cu")
		(net "PCEPLL1_VDDA18_PEX0")
	)
	(via
		(at 31.69031 -299.895514)
		(size 0.508)
		(drill 0.254)
		(layers "F.Cu" "B.Cu")
		(net "PCEPLL1_VDDA18_PEX0")
	)
	(via
		(at 46.8249 -299.224954)
		(size 0.4064)
		(drill 0.2032)
		(layers "F.Cu" "B.Cu")
		(net "PCEPLL1_VDDA18_PEX0")
	)
	(via
		(at 33.274 -299.787564)
		(size 0.508)
		(drill 0.254)
		(layers "F.Cu" "B.Cu")
		(net "PCEPLL1_VDDA18_PEX0")
	)
	(segment
		(start 46.811946 -299.212)
		(end 46.8249 -299.224954)
		(width 0.3048)
		(layer "B.Cu")
		(net "PCEPLL1_VDDA18_PEX0")
	)
	(segment
		(start 46.6217 -300.1772)
		(end 46.6217 -299.212)
		(width 0.3048)
		(layer "B.Cu")
		(net "PCEPLL1_VDDA18_PEX0")
	)
	(segment
		(start 46.6217 -299.212)
		(end 46.811946 -299.212)
		(width 0.3048)
		(layer "B.Cu")
		(net "PCEPLL1_VDDA18_PEX0")
	)
	(segment
		(start 358.41305 -228.6)
		(end 359.029 -228.6)
		(width 0.13208)
		(layer "F.Cu")
		(net "NIC4_CLK_EN_R_N")
	)
	(segment
		(start 139.599924 -190.428118)
		(end 139.459716 -190.28791)
		(width 0.13208)
		(layer "F.Cu")
		(net "NIC4_CLK_EN_R_N")
	)
	(segment
		(start 139.459716 -190.28791)
		(end 138.5697 -190.28791)
		(width 0.13208)
		(layer "F.Cu")
		(net "NIC4_CLK_EN_R_N")
	)
	(segment
		(start 141.380718 -190.428118)
		(end 140.705332 -190.428118)
		(width 0.13208)
		(layer "F.Cu")
		(net "NIC4_CLK_EN_R_N")
	)
	(segment
		(start 138.335258 -190.053468)
		(end 138.335258 -189.614556)
		(width 0.13208)
		(layer "F.Cu")
		(net "NIC4_CLK_EN_R_N")
	)
	(segment
		(start 140.705332 -190.428118)
		(end 139.599924 -190.428118)
		(width 0.13208)
		(layer "F.Cu")
		(net "NIC4_CLK_EN_R_N")
	)
	(segment
		(start 141.668754 -190.716154)
		(end 141.380718 -190.428118)
		(width 0.13208)
		(layer "F.Cu")
		(net "NIC4_CLK_EN_R_N")
	)
	(segment
		(start 138.5697 -190.28791)
		(end 138.335258 -190.053468)
		(width 0.13208)
		(layer "F.Cu")
		(net "NIC4_CLK_EN_R_N")
	)
	(via
		(at 141.668754 -190.716154)
		(size 0.508)
		(drill 0.254)
		(layers "F.Cu" "B.Cu")
		(net "NIC4_CLK_EN_R_N")
	)
	(via
		(at 259.825998 -175.620934)
		(size 0.508)
		(drill 0.254)
		(layers "F.Cu" "B.Cu")
		(net "NIC4_CLK_EN_R_N")
	)
	(via
		(at 359.029 -228.6)
		(size 0.508)
		(drill 0.254)
		(layers "F.Cu" "B.Cu")
		(net "NIC4_CLK_EN_R_N")
	)
	(via
		(at 142.842996 -183.284622)
		(size 0.508)
		(drill 0.254)
		(layers "F.Cu" "B.Cu")
		(net "NIC4_CLK_EN_R_N")
	)
	(segment
		(start 144.039336 -188.345572)
		(end 144.039336 -184.480962)
		(width 0.15494)
		(layer "In11.Cu")
		(net "NIC4_CLK_EN_R_N")
	)
	(segment
		(start 141.668754 -190.716154)
		(end 144.039336 -188.345572)
		(width 0.15494)
		(layer "In11.Cu")
		(net "NIC4_CLK_EN_R_N")
	)
	(segment
		(start 144.039336 -184.480962)
		(end 142.842996 -183.284622)
		(width 0.15494)
		(layer "In11.Cu")
		(net "NIC4_CLK_EN_R_N")
	)
	(segment
		(start 219.531184 -173.1772)
		(end 229.200964 -173.1772)
		(width 0.15494)
		(layer "In13.Cu")
		(net "NIC4_CLK_EN_R_N")
	)
	(segment
		(start 229.200964 -173.1772)
		(end 230.928164 -171.45)
		(width 0.15494)
		(layer "In13.Cu")
		(net "NIC4_CLK_EN_R_N")
	)
	(segment
		(start 248.081546 -171.45)
		(end 249.199146 -170.3324)
		(width 0.15494)
		(layer "In13.Cu")
		(net "NIC4_CLK_EN_R_N")
	)
	(segment
		(start 210.210146 -176.403)
		(end 211.657946 -174.9552)
		(width 0.15494)
		(layer "In13.Cu")
		(net "NIC4_CLK_EN_R_N")
	)
	(segment
		(start 249.199146 -170.3324)
		(end 258.947666 -170.3324)
		(width 0.15494)
		(layer "In13.Cu")
		(net "NIC4_CLK_EN_R_N")
	)
	(segment
		(start 258.947666 -170.3324)
		(end 259.825998 -171.210732)
		(width 0.15494)
		(layer "In13.Cu")
		(net "NIC4_CLK_EN_R_N")
	)
	(segment
		(start 142.842996 -183.284622)
		(end 143.731996 -184.173622)
		(width 0.15494)
		(layer "In13.Cu")
		(net "NIC4_CLK_EN_R_N")
	)
	(segment
		(start 192.101978 -184.173622)
		(end 199.8726 -176.403)
		(width 0.15494)
		(layer "In13.Cu")
		(net "NIC4_CLK_EN_R_N")
	)
	(segment
		(start 230.928164 -171.45)
		(end 248.081546 -171.45)
		(width 0.15494)
		(layer "In13.Cu")
		(net "NIC4_CLK_EN_R_N")
	)
	(segment
		(start 199.8726 -176.403)
		(end 210.210146 -176.403)
		(width 0.15494)
		(layer "In13.Cu")
		(net "NIC4_CLK_EN_R_N")
	)
	(segment
		(start 143.731996 -184.173622)
		(end 192.101978 -184.173622)
		(width 0.15494)
		(layer "In13.Cu")
		(net "NIC4_CLK_EN_R_N")
	)
	(segment
		(start 211.657946 -174.9552)
		(end 217.753184 -174.9552)
		(width 0.15494)
		(layer "In13.Cu")
		(net "NIC4_CLK_EN_R_N")
	)
	(segment
		(start 259.825998 -171.210732)
		(end 259.825998 -175.620934)
		(width 0.15494)
		(layer "In13.Cu")
		(net "NIC4_CLK_EN_R_N")
	)
	(segment
		(start 217.753184 -174.9552)
		(end 219.531184 -173.1772)
		(width 0.15494)
		(layer "In13.Cu")
		(net "NIC4_CLK_EN_R_N")
	)
	(segment
		(start 358.09428 -176.30775)
		(end 357.60025 -176.30775)
		(width 0.15494)
		(layer "In15.Cu")
		(net "NIC4_CLK_EN_R_N")
	)
	(segment
		(start 366.36198 -183.608218)
		(end 366.36198 -182.063644)
		(width 0.15494)
		(layer "In15.Cu")
		(net "NIC4_CLK_EN_R_N")
	)
	(segment
		(start 359.683812 -178.250342)
		(end 359.683812 -177.897282)
		(width 0.15494)
		(layer "In15.Cu")
		(net "NIC4_CLK_EN_R_N")
	)
	(segment
		(start 368.850418 -186.096656)
		(end 366.36198 -183.608218)
		(width 0.15494)
		(layer "In15.Cu")
		(net "NIC4_CLK_EN_R_N")
	)
	(segment
		(start 360.010202 -178.576732)
		(end 359.683812 -178.250342)
		(width 0.15494)
		(layer "In15.Cu")
		(net "NIC4_CLK_EN_R_N")
	)
	(segment
		(start 357.60025 -176.30775)
		(end 357.561134 -176.268634)
		(width 0.15494)
		(layer "In15.Cu")
		(net "NIC4_CLK_EN_R_N")
	)
	(segment
		(start 342.611202 -174.858172)
		(end 285.413958 -174.858172)
		(width 0.15494)
		(layer "In15.Cu")
		(net "NIC4_CLK_EN_R_N")
	)
	(segment
		(start 365.261398 -225.656902)
		(end 369.26393 -221.65437)
		(width 0.15494)
		(layer "In15.Cu")
		(net "NIC4_CLK_EN_R_N")
	)
	(segment
		(start 361.41406 -179.337208)
		(end 360.653584 -178.576732)
		(width 0.15494)
		(layer "In15.Cu")
		(net "NIC4_CLK_EN_R_N")
	)
	(segment
		(start 368.850418 -194.145408)
		(end 368.850418 -186.096656)
		(width 0.15494)
		(layer "In15.Cu")
		(net "NIC4_CLK_EN_R_N")
	)
	(segment
		(start 366.36198 -182.063644)
		(end 363.635544 -179.337208)
		(width 0.15494)
		(layer "In15.Cu")
		(net "NIC4_CLK_EN_R_N")
	)
	(segment
		(start 363.95533 -225.656902)
		(end 365.261398 -225.656902)
		(width 0.15494)
		(layer "In15.Cu")
		(net "NIC4_CLK_EN_R_N")
	)
	(segment
		(start 344.021664 -176.268634)
		(end 342.611202 -174.858172)
		(width 0.15494)
		(layer "In15.Cu")
		(net "NIC4_CLK_EN_R_N")
	)
	(segment
		(start 369.26393 -221.65437)
		(end 369.26393 -213.316058)
		(width 0.15494)
		(layer "In15.Cu")
		(net "NIC4_CLK_EN_R_N")
	)
	(segment
		(start 357.561134 -176.268634)
		(end 344.021664 -176.268634)
		(width 0.15494)
		(layer "In15.Cu")
		(net "NIC4_CLK_EN_R_N")
	)
	(segment
		(start 363.635544 -179.337208)
		(end 361.41406 -179.337208)
		(width 0.15494)
		(layer "In15.Cu")
		(net "NIC4_CLK_EN_R_N")
	)
	(segment
		(start 359.029 -228.6)
		(end 361.012232 -228.6)
		(width 0.15494)
		(layer "In15.Cu")
		(net "NIC4_CLK_EN_R_N")
	)
	(segment
		(start 361.012232 -228.6)
		(end 363.95533 -225.656902)
		(width 0.15494)
		(layer "In15.Cu")
		(net "NIC4_CLK_EN_R_N")
	)
	(segment
		(start 369.987322 -195.282312)
		(end 368.850418 -194.145408)
		(width 0.15494)
		(layer "In15.Cu")
		(net "NIC4_CLK_EN_R_N")
	)
	(segment
		(start 360.653584 -178.576732)
		(end 360.010202 -178.576732)
		(width 0.15494)
		(layer "In15.Cu")
		(net "NIC4_CLK_EN_R_N")
	)
	(segment
		(start 369.26393 -213.316058)
		(end 369.987322 -212.592666)
		(width 0.15494)
		(layer "In15.Cu")
		(net "NIC4_CLK_EN_R_N")
	)
	(segment
		(start 369.987322 -212.592666)
		(end 369.987322 -195.282312)
		(width 0.15494)
		(layer "In15.Cu")
		(net "NIC4_CLK_EN_R_N")
	)
	(segment
		(start 261.440168 -174.006764)
		(end 259.825998 -175.620934)
		(width 0.15494)
		(layer "In15.Cu")
		(net "NIC4_CLK_EN_R_N")
	)
	(segment
		(start 359.683812 -177.897282)
		(end 358.09428 -176.30775)
		(width 0.15494)
		(layer "In15.Cu")
		(net "NIC4_CLK_EN_R_N")
	)
	(segment
		(start 285.413958 -174.858172)
		(end 284.56255 -174.006764)
		(width 0.15494)
		(layer "In15.Cu")
		(net "NIC4_CLK_EN_R_N")
	)
	(segment
		(start 284.56255 -174.006764)
		(end 261.440168 -174.006764)
		(width 0.15494)
		(layer "In15.Cu")
		(net "NIC4_CLK_EN_R_N")
	)
	(segment
		(start 217.583512 -230.601012)
		(end 217.583512 -231.016556)
		(width 0.13208)
		(layer "F.Cu")
		(net "BOARD_ID0")
	)
	(segment
		(start 222.4532 -229.1588)
		(end 219.963238 -229.1588)
		(width 0.13208)
		(layer "F.Cu")
		(net "BOARD_ID0")
	)
	(segment
		(start 218.599512 -231.016556)
		(end 217.583512 -231.016556)
		(width 0.13208)
		(layer "F.Cu")
		(net "BOARD_ID0")
	)
	(segment
		(start 224.840292 -227.010976)
		(end 225.867722 -225.983546)
		(width 0.13208)
		(layer "F.Cu")
		(net "BOARD_ID0")
	)
	(segment
		(start 223.434656 -228.998272)
		(end 223.935798 -228.49713)
		(width 0.13208)
		(layer "F.Cu")
		(net "BOARD_ID0")
	)
	(segment
		(start 219.963238 -229.1588)
		(end 218.95816 -230.163878)
		(width 0.13208)
		(layer "F.Cu")
		(net "BOARD_ID0")
	)
	(segment
		(start 223.935798 -228.49713)
		(end 223.935798 -227.470716)
		(width 0.13208)
		(layer "F.Cu")
		(net "BOARD_ID0")
	)
	(segment
		(start 218.95816 -230.163878)
		(end 218.020646 -230.163878)
		(width 0.13208)
		(layer "F.Cu")
		(net "BOARD_ID0")
	)
	(segment
		(start 218.020646 -230.163878)
		(end 217.583512 -230.601012)
		(width 0.13208)
		(layer "F.Cu")
		(net "BOARD_ID0")
	)
	(segment
		(start 223.434656 -228.998272)
		(end 222.613728 -228.998272)
		(width 0.13208)
		(layer "F.Cu")
		(net "BOARD_ID0")
	)
	(segment
		(start 223.935798 -227.470716)
		(end 224.395538 -227.010976)
		(width 0.13208)
		(layer "F.Cu")
		(net "BOARD_ID0")
	)
	(segment
		(start 225.867722 -225.983546)
		(end 225.867722 -224.704148)
		(width 0.13208)
		(layer "F.Cu")
		(net "BOARD_ID0")
	)
	(segment
		(start 224.395538 -227.010976)
		(end 224.840292 -227.010976)
		(width 0.13208)
		(layer "F.Cu")
		(net "BOARD_ID0")
	)
	(segment
		(start 222.613728 -228.998272)
		(end 222.4532 -229.1588)
		(width 0.13208)
		(layer "F.Cu")
		(net "BOARD_ID0")
	)
	(via
		(at 223.434656 -228.998272)
		(size 0.762)
		(drill 0.381)
		(layers "F.Cu" "B.Cu")
		(net "BOARD_ID0")
	)
	(segment
		(start 241.200686 -202.196954)
		(end 241.200686 -201.29627)
		(width 0.13208)
		(layer "F.Cu")
		(net "PU_CLK_25M_BIC_EN")
	)
	(segment
		(start 240.656364 -202.741276)
		(end 241.200686 -202.196954)
		(width 0.13208)
		(layer "F.Cu")
		(net "PU_CLK_25M_BIC_EN")
	)
	(segment
		(start 239.64265 -202.741276)
		(end 240.656364 -202.741276)
		(width 0.13208)
		(layer "F.Cu")
		(net "PU_CLK_25M_BIC_EN")
	)
	(via
		(at 241.200686 -202.196954)
		(size 0.508)
		(drill 0.254)
		(layers "F.Cu" "B.Cu")
		(net "PU_CLK_25M_BIC_EN")
	)
	(segment
		(start 47.29988 -293.04996)
		(end 46.8249 -292.57498)
		(width 0.249936)
		(layer "F.Cu")
		(net "PCEPLL6_VDDA18_PEX0")
	)
	(via
		(at 33.11652 -287.093914)
		(size 0.508)
		(drill 0.254)
		(layers "F.Cu" "B.Cu")
		(net "PCEPLL6_VDDA18_PEX0")
	)
	(via
		(at 46.8249 -292.57498)
		(size 0.4064)
		(drill 0.2032)
		(layers "F.Cu" "B.Cu")
		(net "PCEPLL6_VDDA18_PEX0")
	)
	(via
		(at 31.71952 -287.093914)
		(size 0.508)
		(drill 0.254)
		(layers "F.Cu" "B.Cu")
		(net "PCEPLL6_VDDA18_PEX0")
	)
	(segment
		(start 46.8249 -292.57498)
		(end 46.6217 -292.57498)
		(width 0.3048)
		(layer "B.Cu")
		(net "PCEPLL6_VDDA18_PEX0")
	)
	(segment
		(start 46.8249 -293.32174)
		(end 46.8249 -292.57498)
		(width 0.3048)
		(layer "B.Cu")
		(net "PCEPLL6_VDDA18_PEX0")
	)
	(segment
		(start 46.6217 -293.52494)
		(end 46.8249 -293.32174)
		(width 0.3048)
		(layer "B.Cu")
		(net "PCEPLL6_VDDA18_PEX0")
	)
	(segment
		(start 336.493866 -223.987106)
		(end 336.09407 -224.386902)
		(width 0.13208)
		(layer "F.Cu")
		(net "PWR_EN_P3V3")
	)
	(via
		(at 336.09407 -224.386902)
		(size 0.4572)
		(drill 0.254)
		(layers "F.Cu" "B.Cu")
		(net "PWR_EN_P3V3")
	)
	(via
		(at 331.216 -224.536)
		(size 0.6604)
		(drill 0.3302)
		(layers "F.Cu" "B.Cu")
		(net "PWR_EN_P3V3")
	)
	(segment
		(start 330.09205 -224.4852)
		(end 331.1652 -224.4852)
		(width 0.13208)
		(layer "B.Cu")
		(net "PWR_EN_P3V3")
	)
	(segment
		(start 332.953106 -224.536)
		(end 333.502 -223.987106)
		(width 0.13208)
		(layer "B.Cu")
		(net "PWR_EN_P3V3")
	)
	(segment
		(start 335.694274 -223.987106)
		(end 336.09407 -224.386902)
		(width 0.0889)
		(layer "B.Cu")
		(net "PWR_EN_P3V3")
	)
	(segment
		(start 331.216 -224.536)
		(end 332.953106 -224.536)
		(width 0.13208)
		(layer "B.Cu")
		(net "PWR_EN_P3V3")
	)
	(segment
		(start 333.502 -223.987106)
		(end 335.694274 -223.987106)
		(width 0.0889)
		(layer "B.Cu")
		(net "PWR_EN_P3V3")
	)
	(segment
		(start 331.1652 -224.4852)
		(end 331.216 -224.536)
		(width 0.13208)
		(layer "B.Cu")
		(net "PWR_EN_P3V3")
	)
	(segment
		(start 255.537716 -205.986126)
		(end 255.537462 -205.985872)
		(width 0.13208)
		(layer "F.Cu")
		(net "JTAG_PLD_TDI")
	)
	(segment
		(start 255.537462 -205.985872)
		(end 255.537462 -204.79893)
		(width 0.13208)
		(layer "F.Cu")
		(net "JTAG_PLD_TDI")
	)
	(via
		(at 255.537716 -205.986126)
		(size 0.508)
		(drill 0.254)
		(layers "F.Cu" "B.Cu")
		(net "JTAG_PLD_TDI")
	)
	(segment
		(start 255.537716 -206.910178)
		(end 255.63322 -207.005682)
		(width 0.13208)
		(layer "B.Cu")
		(net "JTAG_PLD_TDI")
	)
	(segment
		(start 255.537716 -205.986126)
		(end 255.537716 -206.910178)
		(width 0.13208)
		(layer "B.Cu")
		(net "JTAG_PLD_TDI")
	)
	(segment
		(start 255.63322 -207.005682)
		(end 255.63322 -207.507078)
		(width 0.13208)
		(layer "B.Cu")
		(net "JTAG_PLD_TDI")
	)
	(segment
		(start 99.50196 -391.294366)
		(end 99.291394 -391.0838)
		(width 0.13208)
		(layer "F.Cu")
		(net "BIC_USB_HUB_OVCUR1")
	)
	(segment
		(start 100.362004 -392.15441)
		(end 99.50196 -391.294366)
		(width 0.13208)
		(layer "F.Cu")
		(net "BIC_USB_HUB_OVCUR1")
	)
	(segment
		(start 100.964492 -392.15441)
		(end 100.362004 -392.15441)
		(width 0.13208)
		(layer "F.Cu")
		(net "BIC_USB_HUB_OVCUR1")
	)
	(segment
		(start 99.291394 -391.0838)
		(end 98.448368 -391.0838)
		(width 0.13208)
		(layer "F.Cu")
		(net "BIC_USB_HUB_OVCUR1")
	)
	(via
		(at 99.50196 -391.294366)
		(size 0.508)
		(drill 0.254)
		(layers "F.Cu" "B.Cu")
		(net "BIC_USB_HUB_OVCUR1")
	)
	(via
		(at 34.689034 -256.375916)
		(size 0.508)
		(drill 0.254)
		(layers "F.Cu" "B.Cu")
		(net "PCEPLL5_VDDA18_PEX0_R")
	)
	(segment
		(start 109.411516 -395.554454)
		(end 110.25378 -396.396718)
		(width 0.13208)
		(layer "F.Cu")
		(net "BIC_USB_HUB_XIN")
	)
	(segment
		(start 109.662214 -393.716764)
		(end 109.638846 -393.740132)
		(width 0.13208)
		(layer "F.Cu")
		(net "BIC_USB_HUB_XIN")
	)
	(segment
		(start 109.231176 -392.189462)
		(end 109.662214 -393.2301)
		(width 0.13208)
		(layer "F.Cu")
		(net "BIC_USB_HUB_XIN")
	)
	(segment
		(start 109.638846 -394.217906)
		(end 109.411516 -394.445236)
		(width 0.13208)
		(layer "F.Cu")
		(net "BIC_USB_HUB_XIN")
	)
	(segment
		(start 108.696252 -391.654538)
		(end 109.231176 -392.189462)
		(width 0.13208)
		(layer "F.Cu")
		(net "BIC_USB_HUB_XIN")
	)
	(segment
		(start 108.382054 -391.654538)
		(end 108.696252 -391.654538)
		(width 0.13208)
		(layer "F.Cu")
		(net "BIC_USB_HUB_XIN")
	)
	(segment
		(start 105.789476 -391.654538)
		(end 108.382054 -391.654538)
		(width 0.13208)
		(layer "F.Cu")
		(net "BIC_USB_HUB_XIN")
	)
	(segment
		(start 109.411516 -394.445236)
		(end 109.411516 -395.554454)
		(width 0.13208)
		(layer "F.Cu")
		(net "BIC_USB_HUB_XIN")
	)
	(segment
		(start 109.662214 -393.2301)
		(end 109.662214 -393.716764)
		(width 0.13208)
		(layer "F.Cu")
		(net "BIC_USB_HUB_XIN")
	)
	(segment
		(start 109.638846 -393.740132)
		(end 109.638846 -394.217906)
		(width 0.13208)
		(layer "F.Cu")
		(net "BIC_USB_HUB_XIN")
	)
	(via
		(at 108.382054 -391.654538)
		(size 0.508)
		(drill 0.254)
		(layers "F.Cu" "B.Cu")
		(net "BIC_USB_HUB_XIN")
	)
	(segment
		(start 450.195188 -414.689544)
		(end 450.55028 -414.334452)
		(width 0.13208)
		(layer "F.Cu")
		(net "LM75_1_A2")
	)
	(segment
		(start 450.195188 -415.221166)
		(end 450.195188 -414.689544)
		(width 0.13208)
		(layer "F.Cu")
		(net "LM75_1_A2")
	)
	(segment
		(start 450.55028 -412.806642)
		(end 450.55028 -414.334452)
		(width 0.13208)
		(layer "F.Cu")
		(net "LM75_1_A2")
	)
	(segment
		(start 451.211188 -415.221166)
		(end 450.195188 -415.221166)
		(width 0.13208)
		(layer "F.Cu")
		(net "LM75_1_A2")
	)
	(via
		(at 450.55028 -414.334452)
		(size 0.508)
		(drill 0.254)
		(layers "F.Cu" "B.Cu")
		(net "LM75_1_A2")
	)
	(via
		(at 31.73095 -292.732714)
		(size 0.508)
		(drill 0.254)
		(layers "F.Cu" "B.Cu")
		(net "PCEPLL2_VDDA18_PEX0_R")
	)
	(segment
		(start 205.95209 -288.39541)
		(end 206.248 -288.0995)
		(width 0.13208)
		(layer "F.Cu")
		(net "SMB_PEX1_PCA9555_SDA")
	)
	(segment
		(start 205.95209 -288.830766)
		(end 205.95209 -288.39541)
		(width 0.13208)
		(layer "F.Cu")
		(net "SMB_PEX1_PCA9555_SDA")
	)
	(segment
		(start 373.3927 -180.217064)
		(end 374.031764 -179.578)
		(width 0.13208)
		(layer "F.Cu")
		(net "SMB_PEX1_PCA9555_SDA")
	)
	(segment
		(start 206.248 -288.0995)
		(end 206.248 -287.300162)
		(width 0.13208)
		(layer "F.Cu")
		(net "SMB_PEX1_PCA9555_SDA")
	)
	(segment
		(start 206.248 -287.300162)
		(end 207.001364 -286.546798)
		(width 0.13208)
		(layer "F.Cu")
		(net "SMB_PEX1_PCA9555_SDA")
	)
	(segment
		(start 207.001364 -286.546798)
		(end 208.032604 -286.546798)
		(width 0.13208)
		(layer "F.Cu")
		(net "SMB_PEX1_PCA9555_SDA")
	)
	(segment
		(start 379.353064 -201.934064)
		(end 376.432064 -201.934064)
		(width 0.13208)
		(layer "F.Cu")
		(net "SMB_PEX1_PCA9555_SDA")
	)
	(segment
		(start 379.77318 -202.35418)
		(end 379.353064 -201.934064)
		(width 0.13208)
		(layer "F.Cu")
		(net "SMB_PEX1_PCA9555_SDA")
	)
	(segment
		(start 374.031764 -179.578)
		(end 374.396 -179.578)
		(width 0.13208)
		(layer "F.Cu")
		(net "SMB_PEX1_PCA9555_SDA")
	)
	(segment
		(start 372.114064 -180.217064)
		(end 373.3927 -180.217064)
		(width 0.13208)
		(layer "F.Cu")
		(net "SMB_PEX1_PCA9555_SDA")
	)
	(via
		(at 208.032604 -286.546798)
		(size 0.508)
		(drill 0.254)
		(layers "F.Cu" "B.Cu")
		(net "SMB_PEX1_PCA9555_SDA")
	)
	(via
		(at 374.396 -179.578)
		(size 0.508)
		(drill 0.254)
		(layers "F.Cu" "B.Cu")
		(net "SMB_PEX1_PCA9555_SDA")
	)
	(via
		(at 379.77318 -202.35418)
		(size 0.508)
		(drill 0.254)
		(layers "F.Cu" "B.Cu")
		(net "SMB_PEX1_PCA9555_SDA")
	)
	(via
		(at 212.199474 -248.35485)
		(size 0.508)
		(drill 0.254)
		(layers "F.Cu" "B.Cu")
		(net "SMB_PEX1_PCA9555_SDA")
	)
	(segment
		(start 212.199474 -248.35485)
		(end 212.499448 -248.654824)
		(width 0.13208)
		(layer "B.Cu")
		(net "SMB_PEX1_PCA9555_SDA")
	)
	(segment
		(start 212.499448 -280.310082)
		(end 208.032604 -284.776926)
		(width 0.13208)
		(layer "B.Cu")
		(net "SMB_PEX1_PCA9555_SDA")
	)
	(segment
		(start 208.032604 -284.776926)
		(end 208.032604 -286.546798)
		(width 0.13208)
		(layer "B.Cu")
		(net "SMB_PEX1_PCA9555_SDA")
	)
	(segment
		(start 212.499448 -248.654824)
		(end 212.499448 -280.310082)
		(width 0.13208)
		(layer "B.Cu")
		(net "SMB_PEX1_PCA9555_SDA")
	)
	(segment
		(start 378.217176 -189.427358)
		(end 377.196604 -188.406786)
		(width 0.15494)
		(layer "In9.Cu")
		(net "SMB_PEX1_PCA9555_SDA")
	)
	(segment
		(start 377.196604 -188.406786)
		(end 377.196604 -183.55056)
		(width 0.15494)
		(layer "In9.Cu")
		(net "SMB_PEX1_PCA9555_SDA")
	)
	(segment
		(start 379.77318 -201.71918)
		(end 378.217176 -200.163176)
		(width 0.15494)
		(layer "In9.Cu")
		(net "SMB_PEX1_PCA9555_SDA")
	)
	(segment
		(start 375.031 -181.384956)
		(end 375.031 -180.213)
		(width 0.15494)
		(layer "In9.Cu")
		(net "SMB_PEX1_PCA9555_SDA")
	)
	(segment
		(start 375.031 -180.213)
		(end 374.396 -179.578)
		(width 0.15494)
		(layer "In9.Cu")
		(net "SMB_PEX1_PCA9555_SDA")
	)
	(segment
		(start 379.77318 -202.35418)
		(end 379.77318 -201.71918)
		(width 0.15494)
		(layer "In9.Cu")
		(net "SMB_PEX1_PCA9555_SDA")
	)
	(segment
		(start 377.196604 -183.55056)
		(end 375.031 -181.384956)
		(width 0.15494)
		(layer "In9.Cu")
		(net "SMB_PEX1_PCA9555_SDA")
	)
	(segment
		(start 378.217176 -200.163176)
		(end 378.217176 -189.427358)
		(width 0.15494)
		(layer "In9.Cu")
		(net "SMB_PEX1_PCA9555_SDA")
	)
	(segment
		(start 381.14224 -213.904576)
		(end 381.14224 -203.72324)
		(width 0.15494)
		(layer "In13.Cu")
		(net "SMB_PEX1_PCA9555_SDA")
	)
	(segment
		(start 373.407178 -226.09556)
		(end 375.0056 -224.497138)
		(width 0.15494)
		(layer "In13.Cu")
		(net "SMB_PEX1_PCA9555_SDA")
	)
	(segment
		(start 340.2584 -250.70054)
		(end 346.36202 -244.59692)
		(width 0.15494)
		(layer "In13.Cu")
		(net "SMB_PEX1_PCA9555_SDA")
	)
	(segment
		(start 213.658196 -248.35485)
		(end 215.022684 -246.990362)
		(width 0.15494)
		(layer "In13.Cu")
		(net "SMB_PEX1_PCA9555_SDA")
	)
	(segment
		(start 340.2584 -251.172726)
		(end 340.2584 -250.70054)
		(width 0.15494)
		(layer "In13.Cu")
		(net "SMB_PEX1_PCA9555_SDA")
	)
	(segment
		(start 375.3358 -221.1832)
		(end 375.3358 -219.711016)
		(width 0.15494)
		(layer "In13.Cu")
		(net "SMB_PEX1_PCA9555_SDA")
	)
	(segment
		(start 346.36202 -244.59692)
		(end 349.692976 -244.59692)
		(width 0.15494)
		(layer "In13.Cu")
		(net "SMB_PEX1_PCA9555_SDA")
	)
	(segment
		(start 338.23402 -253.197106)
		(end 340.2584 -251.172726)
		(width 0.15494)
		(layer "In13.Cu")
		(net "SMB_PEX1_PCA9555_SDA")
	)
	(segment
		(start 369.550442 -233.5276)
		(end 373.407178 -229.670864)
		(width 0.15494)
		(layer "In13.Cu")
		(net "SMB_PEX1_PCA9555_SDA")
	)
	(segment
		(start 272.288 -250.9012)
		(end 272.288 -251.6378)
		(width 0.15494)
		(layer "In13.Cu")
		(net "SMB_PEX1_PCA9555_SDA")
	)
	(segment
		(start 229.134416 -246.990362)
		(end 231.27335 -249.129296)
		(width 0.15494)
		(layer "In13.Cu")
		(net "SMB_PEX1_PCA9555_SDA")
	)
	(segment
		(start 212.199474 -248.35485)
		(end 213.658196 -248.35485)
		(width 0.15494)
		(layer "In13.Cu")
		(net "SMB_PEX1_PCA9555_SDA")
	)
	(segment
		(start 381.14224 -203.72324)
		(end 379.77318 -202.35418)
		(width 0.15494)
		(layer "In13.Cu")
		(net "SMB_PEX1_PCA9555_SDA")
	)
	(segment
		(start 375.3358 -219.711016)
		(end 381.14224 -213.904576)
		(width 0.15494)
		(layer "In13.Cu")
		(net "SMB_PEX1_PCA9555_SDA")
	)
	(segment
		(start 215.022684 -246.990362)
		(end 229.134416 -246.990362)
		(width 0.15494)
		(layer "In13.Cu")
		(net "SMB_PEX1_PCA9555_SDA")
	)
	(segment
		(start 301.42688 -255.7272)
		(end 306.2986 -255.7272)
		(width 0.15494)
		(layer "In13.Cu")
		(net "SMB_PEX1_PCA9555_SDA")
	)
	(segment
		(start 373.407178 -229.670864)
		(end 373.407178 -226.09556)
		(width 0.15494)
		(layer "In13.Cu")
		(net "SMB_PEX1_PCA9555_SDA")
	)
	(segment
		(start 375.0056 -224.497138)
		(end 375.0056 -221.5134)
		(width 0.15494)
		(layer "In13.Cu")
		(net "SMB_PEX1_PCA9555_SDA")
	)
	(segment
		(start 272.288 -251.6378)
		(end 272.68932 -252.03912)
		(width 0.15494)
		(layer "In13.Cu")
		(net "SMB_PEX1_PCA9555_SDA")
	)
	(segment
		(start 234.016296 -249.129296)
		(end 235.040932 -250.153932)
		(width 0.15494)
		(layer "In13.Cu")
		(net "SMB_PEX1_PCA9555_SDA")
	)
	(segment
		(start 253.750826 -250.49988)
		(end 271.88668 -250.49988)
		(width 0.15494)
		(layer "In13.Cu")
		(net "SMB_PEX1_PCA9555_SDA")
	)
	(segment
		(start 272.68932 -252.03912)
		(end 297.7388 -252.03912)
		(width 0.15494)
		(layer "In13.Cu")
		(net "SMB_PEX1_PCA9555_SDA")
	)
	(segment
		(start 306.2986 -255.7272)
		(end 308.828694 -253.197106)
		(width 0.15494)
		(layer "In13.Cu")
		(net "SMB_PEX1_PCA9555_SDA")
	)
	(segment
		(start 308.828694 -253.197106)
		(end 338.23402 -253.197106)
		(width 0.15494)
		(layer "In13.Cu")
		(net "SMB_PEX1_PCA9555_SDA")
	)
	(segment
		(start 360.762296 -233.5276)
		(end 369.550442 -233.5276)
		(width 0.15494)
		(layer "In13.Cu")
		(net "SMB_PEX1_PCA9555_SDA")
	)
	(segment
		(start 253.404878 -250.153932)
		(end 253.750826 -250.49988)
		(width 0.15494)
		(layer "In13.Cu")
		(net "SMB_PEX1_PCA9555_SDA")
	)
	(segment
		(start 297.7388 -252.03912)
		(end 301.42688 -255.7272)
		(width 0.15494)
		(layer "In13.Cu")
		(net "SMB_PEX1_PCA9555_SDA")
	)
	(segment
		(start 235.040932 -250.153932)
		(end 253.404878 -250.153932)
		(width 0.15494)
		(layer "In13.Cu")
		(net "SMB_PEX1_PCA9555_SDA")
	)
	(segment
		(start 349.692976 -244.59692)
		(end 360.762296 -233.5276)
		(width 0.15494)
		(layer "In13.Cu")
		(net "SMB_PEX1_PCA9555_SDA")
	)
	(segment
		(start 231.27335 -249.129296)
		(end 234.016296 -249.129296)
		(width 0.15494)
		(layer "In13.Cu")
		(net "SMB_PEX1_PCA9555_SDA")
	)
	(segment
		(start 375.0056 -221.5134)
		(end 375.3358 -221.1832)
		(width 0.15494)
		(layer "In13.Cu")
		(net "SMB_PEX1_PCA9555_SDA")
	)
	(segment
		(start 271.88668 -250.49988)
		(end 272.288 -250.9012)
		(width 0.15494)
		(layer "In13.Cu")
		(net "SMB_PEX1_PCA9555_SDA")
	)
	(segment
		(start 400.28749 -97.055686)
		(end 400.276822 -97.045018)
		(width 0.13208)
		(layer "F.Cu")
		(net "NIC6_PWRBRK_R_N")
	)
	(segment
		(start 400.276822 -97.045018)
		(end 398.94256 -97.045018)
		(width 0.13208)
		(layer "F.Cu")
		(net "NIC6_PWRBRK_R_N")
	)
	(segment
		(start 410.809948 -166.070534)
		(end 410.809948 -166.705534)
		(width 0.13208)
		(layer "F.Cu")
		(net "NIC6_PWRBRK_R_N")
	)
	(via
		(at 410.809948 -166.705534)
		(size 0.508)
		(drill 0.254)
		(layers "F.Cu" "B.Cu")
		(net "NIC6_PWRBRK_R_N")
	)
	(via
		(at 400.28749 -97.055686)
		(size 0.508)
		(drill 0.254)
		(layers "F.Cu" "B.Cu")
		(net "NIC6_PWRBRK_R_N")
	)
	(segment
		(start 410.809948 -166.705534)
		(end 403.79904 -159.694626)
		(width 0.15494)
		(layer "In9.Cu")
		(net "NIC6_PWRBRK_R_N")
	)
	(segment
		(start 403.79904 -132.366512)
		(end 404.593552 -131.572)
		(width 0.15494)
		(layer "In9.Cu")
		(net "NIC6_PWRBRK_R_N")
	)
	(segment
		(start 404.593552 -131.572)
		(end 404.593552 -119.462042)
		(width 0.15494)
		(layer "In9.Cu")
		(net "NIC6_PWRBRK_R_N")
	)
	(segment
		(start 399.4023 -113.56975)
		(end 399.4023 -98.502978)
		(width 0.15494)
		(layer "In9.Cu")
		(net "NIC6_PWRBRK_R_N")
	)
	(segment
		(start 400.28749 -97.617788)
		(end 400.28749 -97.055686)
		(width 0.15494)
		(layer "In9.Cu")
		(net "NIC6_PWRBRK_R_N")
	)
	(segment
		(start 403.272244 -117.439694)
		(end 399.4023 -113.56975)
		(width 0.15494)
		(layer "In9.Cu")
		(net "NIC6_PWRBRK_R_N")
	)
	(segment
		(start 399.4023 -98.502978)
		(end 400.28749 -97.617788)
		(width 0.15494)
		(layer "In9.Cu")
		(net "NIC6_PWRBRK_R_N")
	)
	(segment
		(start 404.593552 -119.462042)
		(end 403.272244 -118.140734)
		(width 0.15494)
		(layer "In9.Cu")
		(net "NIC6_PWRBRK_R_N")
	)
	(segment
		(start 403.272244 -118.140734)
		(end 403.272244 -117.439694)
		(width 0.15494)
		(layer "In9.Cu")
		(net "NIC6_PWRBRK_R_N")
	)
	(segment
		(start 403.79904 -159.694626)
		(end 403.79904 -132.366512)
		(width 0.15494)
		(layer "In9.Cu")
		(net "NIC6_PWRBRK_R_N")
	)
	(segment
		(start 252.937518 -197.510146)
		(end 253.250954 -197.823582)
		(width 0.13208)
		(layer "F.Cu")
		(net "JTAG_PLD_TCK")
	)
	(segment
		(start 252.98146 -195.973446)
		(end 252.937518 -196.017388)
		(width 0.13208)
		(layer "F.Cu")
		(net "JTAG_PLD_TCK")
	)
	(segment
		(start 252.937518 -198.137018)
		(end 252.937518 -198.95693)
		(width 0.13208)
		(layer "F.Cu")
		(net "JTAG_PLD_TCK")
	)
	(segment
		(start 253.250954 -197.823582)
		(end 252.937518 -198.137018)
		(width 0.13208)
		(layer "F.Cu")
		(net "JTAG_PLD_TCK")
	)
	(segment
		(start 252.937518 -196.017388)
		(end 252.937518 -197.510146)
		(width 0.13208)
		(layer "F.Cu")
		(net "JTAG_PLD_TCK")
	)
	(via
		(at 253.250954 -197.823582)
		(size 0.508)
		(drill 0.254)
		(layers "F.Cu" "B.Cu")
		(net "JTAG_PLD_TCK")
	)
	(segment
		(start 255.80594 -208.742788)
		(end 256.717546 -207.831182)
		(width 0.13208)
		(layer "F.Cu")
		(net "JTAG_BIC_TDI_R")
	)
	(segment
		(start 249.555254 -207.674972)
		(end 250.62307 -208.742788)
		(width 0.13208)
		(layer "F.Cu")
		(net "JTAG_BIC_TDI_R")
	)
	(segment
		(start 255.816608 -206.826612)
		(end 255.701546 -206.71155)
		(width 0.13208)
		(layer "F.Cu")
		(net "JTAG_BIC_TDI_R")
	)
	(segment
		(start 256.717546 -207.454754)
		(end 256.089404 -206.826612)
		(width 0.13208)
		(layer "F.Cu")
		(net "JTAG_BIC_TDI_R")
	)
	(segment
		(start 248.660412 -207.674972)
		(end 249.555254 -207.674972)
		(width 0.13208)
		(layer "F.Cu")
		(net "JTAG_BIC_TDI_R")
	)
	(segment
		(start 250.62307 -208.742788)
		(end 255.80594 -208.742788)
		(width 0.13208)
		(layer "F.Cu")
		(net "JTAG_BIC_TDI_R")
	)
	(segment
		(start 226.546664 -204.04201)
		(end 226.546664 -203.09967)
		(width 0.13208)
		(layer "F.Cu")
		(net "JTAG_BIC_TDI_R")
	)
	(segment
		(start 256.089404 -206.826612)
		(end 255.816608 -206.826612)
		(width 0.13208)
		(layer "F.Cu")
		(net "JTAG_BIC_TDI_R")
	)
	(segment
		(start 256.717546 -207.51165)
		(end 256.717546 -207.454754)
		(width 0.13208)
		(layer "F.Cu")
		(net "JTAG_BIC_TDI_R")
	)
	(segment
		(start 256.717546 -207.831182)
		(end 256.717546 -207.51165)
		(width 0.13208)
		(layer "F.Cu")
		(net "JTAG_BIC_TDI_R")
	)
	(via
		(at 226.546664 -203.09967)
		(size 0.508)
		(drill 0.254)
		(layers "F.Cu" "B.Cu")
		(net "JTAG_BIC_TDI_R")
	)
	(via
		(at 248.660412 -207.674972)
		(size 0.508)
		(drill 0.254)
		(layers "F.Cu" "B.Cu")
		(net "JTAG_BIC_TDI_R")
	)
	(segment
		(start 247.396 -209.601054)
		(end 245.519702 -211.477352)
		(width 0.15494)
		(layer "In5.Cu")
		(net "JTAG_BIC_TDI_R")
	)
	(segment
		(start 241.8842 -212.2678)
		(end 240.03 -210.4136)
		(width 0.15494)
		(layer "In5.Cu")
		(net "JTAG_BIC_TDI_R")
	)
	(segment
		(start 243.586254 -212.5218)
		(end 243.14531 -212.5218)
		(width 0.15494)
		(layer "In5.Cu")
		(net "JTAG_BIC_TDI_R")
	)
	(segment
		(start 248.076974 -207.674972)
		(end 247.396 -208.355946)
		(width 0.15494)
		(layer "In5.Cu")
		(net "JTAG_BIC_TDI_R")
	)
	(segment
		(start 242.532154 -212.2678)
		(end 241.8842 -212.2678)
		(width 0.15494)
		(layer "In5.Cu")
		(net "JTAG_BIC_TDI_R")
	)
	(segment
		(start 228.059234 -206.060548)
		(end 228.059234 -204.909928)
		(width 0.15494)
		(layer "In5.Cu")
		(net "JTAG_BIC_TDI_R")
	)
	(segment
		(start 233.242866 -206.9592)
		(end 232.963466 -207.2386)
		(width 0.15494)
		(layer "In5.Cu")
		(net "JTAG_BIC_TDI_R")
	)
	(segment
		(start 243.14531 -212.5218)
		(end 242.532154 -212.2678)
		(width 0.15494)
		(layer "In5.Cu")
		(net "JTAG_BIC_TDI_R")
	)
	(segment
		(start 240.03 -209.505296)
		(end 237.483904 -206.9592)
		(width 0.15494)
		(layer "In5.Cu")
		(net "JTAG_BIC_TDI_R")
	)
	(segment
		(start 232.963466 -207.2386)
		(end 229.237286 -207.2386)
		(width 0.15494)
		(layer "In5.Cu")
		(net "JTAG_BIC_TDI_R")
	)
	(segment
		(start 240.03 -210.4136)
		(end 240.03 -209.505296)
		(width 0.15494)
		(layer "In5.Cu")
		(net "JTAG_BIC_TDI_R")
	)
	(segment
		(start 228.059234 -204.909928)
		(end 226.546664 -203.397358)
		(width 0.15494)
		(layer "In5.Cu")
		(net "JTAG_BIC_TDI_R")
	)
	(segment
		(start 245.519702 -211.477352)
		(end 244.630702 -211.477352)
		(width 0.15494)
		(layer "In5.Cu")
		(net "JTAG_BIC_TDI_R")
	)
	(segment
		(start 226.546664 -203.397358)
		(end 226.546664 -203.09967)
		(width 0.15494)
		(layer "In5.Cu")
		(net "JTAG_BIC_TDI_R")
	)
	(segment
		(start 247.396 -208.355946)
		(end 247.396 -209.601054)
		(width 0.15494)
		(layer "In5.Cu")
		(net "JTAG_BIC_TDI_R")
	)
	(segment
		(start 237.483904 -206.9592)
		(end 233.242866 -206.9592)
		(width 0.15494)
		(layer "In5.Cu")
		(net "JTAG_BIC_TDI_R")
	)
	(segment
		(start 248.660412 -207.674972)
		(end 248.076974 -207.674972)
		(width 0.15494)
		(layer "In5.Cu")
		(net "JTAG_BIC_TDI_R")
	)
	(segment
		(start 229.237286 -207.2386)
		(end 228.059234 -206.060548)
		(width 0.15494)
		(layer "In5.Cu")
		(net "JTAG_BIC_TDI_R")
	)
	(segment
		(start 244.630702 -211.477352)
		(end 243.586254 -212.5218)
		(width 0.15494)
		(layer "In5.Cu")
		(net "JTAG_BIC_TDI_R")
	)
	(segment
		(start 99.50196 -393.885166)
		(end 100.232718 -393.154408)
		(width 0.13208)
		(layer "F.Cu")
		(net "BIC_USB_HUB_PGANG")
	)
	(segment
		(start 98.448368 -393.1158)
		(end 98.732594 -393.1158)
		(width 0.13208)
		(layer "F.Cu")
		(net "BIC_USB_HUB_PGANG")
	)
	(segment
		(start 100.232718 -393.154408)
		(end 100.964492 -393.154408)
		(width 0.13208)
		(layer "F.Cu")
		(net "BIC_USB_HUB_PGANG")
	)
	(segment
		(start 98.732594 -393.1158)
		(end 99.50196 -393.885166)
		(width 0.13208)
		(layer "F.Cu")
		(net "BIC_USB_HUB_PGANG")
	)
	(via
		(at 99.50196 -393.885166)
		(size 0.508)
		(drill 0.254)
		(layers "F.Cu" "B.Cu")
		(net "BIC_USB_HUB_PGANG")
	)
	(segment
		(start 449.179188 -415.221166)
		(end 449.179188 -414.59023)
		(width 0.13208)
		(layer "F.Cu")
		(net "LM75_1_A1")
	)
	(segment
		(start 449.28028 -413.96793)
		(end 449.28028 -412.806642)
		(width 0.13208)
		(layer "F.Cu")
		(net "LM75_1_A1")
	)
	(segment
		(start 449.179188 -414.59023)
		(end 449.179188 -414.069022)
		(width 0.13208)
		(layer "F.Cu")
		(net "LM75_1_A1")
	)
	(segment
		(start 448.163188 -415.221166)
		(end 449.179188 -415.221166)
		(width 0.13208)
		(layer "F.Cu")
		(net "LM75_1_A1")
	)
	(segment
		(start 449.179188 -414.069022)
		(end 449.28028 -413.96793)
		(width 0.13208)
		(layer "F.Cu")
		(net "LM75_1_A1")
	)
	(via
		(at 449.179188 -414.59023)
		(size 0.508)
		(drill 0.254)
		(layers "F.Cu" "B.Cu")
		(net "LM75_1_A1")
	)
	(segment
		(start 48.24984 -297.79976)
		(end 47.77486 -298.27474)
		(width 0.249936)
		(layer "F.Cu")
		(net "SYSPLL_VDDA18_PEX0")
	)
	(via
		(at 47.77486 -298.27474)
		(size 0.4064)
		(drill 0.2032)
		(layers "F.Cu" "B.Cu")
		(net "SYSPLL_VDDA18_PEX0")
	)
	(via
		(at 33.11652 -280.693114)
		(size 0.508)
		(drill 0.254)
		(layers "F.Cu" "B.Cu")
		(net "SYSPLL_VDDA18_PEX0")
	)
	(via
		(at 31.71952 -280.693114)
		(size 0.508)
		(drill 0.254)
		(layers "F.Cu" "B.Cu")
		(net "SYSPLL_VDDA18_PEX0")
	)
	(segment
		(start 47.0027 -298.27474)
		(end 47.77486 -298.27474)
		(width 0.3048)
		(layer "B.Cu")
		(net "SYSPLL_VDDA18_PEX0")
	)
	(segment
		(start 102.877112 -395.323568)
		(end 102.877112 -394.566902)
		(width 0.13208)
		(layer "F.Cu")
		(net "BIC_USB_HUB_OVCUR4")
	)
	(segment
		(start 101.971094 -397.112236)
		(end 101.971094 -396.770606)
		(width 0.13208)
		(layer "F.Cu")
		(net "BIC_USB_HUB_OVCUR4")
	)
	(segment
		(start 101.971094 -396.770606)
		(end 101.700584 -396.500096)
		(width 0.13208)
		(layer "F.Cu")
		(net "BIC_USB_HUB_OVCUR4")
	)
	(segment
		(start 101.700584 -396.500096)
		(end 102.877112 -395.323568)
		(width 0.13208)
		(layer "F.Cu")
		(net "BIC_USB_HUB_OVCUR4")
	)
	(via
		(at 101.700584 -396.500096)
		(size 0.508)
		(drill 0.254)
		(layers "F.Cu" "B.Cu")
		(net "BIC_USB_HUB_OVCUR4")
	)
	(segment
		(start 326.412606 -196.234304)
		(end 327.132696 -196.234304)
		(width 0.13208)
		(layer "F.Cu")
		(net "IOEXP_DBV2_A2")
	)
	(segment
		(start 328.067416 -195.94449)
		(end 329.754484 -195.94449)
		(width 0.13208)
		(layer "F.Cu")
		(net "IOEXP_DBV2_A2")
	)
	(segment
		(start 326.412606 -195.218304)
		(end 326.412606 -196.234304)
		(width 0.13208)
		(layer "F.Cu")
		(net "IOEXP_DBV2_A2")
	)
	(segment
		(start 327.42251 -195.94449)
		(end 328.067416 -195.94449)
		(width 0.13208)
		(layer "F.Cu")
		(net "IOEXP_DBV2_A2")
	)
	(segment
		(start 327.132696 -196.234304)
		(end 327.42251 -195.94449)
		(width 0.13208)
		(layer "F.Cu")
		(net "IOEXP_DBV2_A2")
	)
	(via
		(at 328.067416 -195.94449)
		(size 0.508)
		(drill 0.254)
		(layers "F.Cu" "B.Cu")
		(net "IOEXP_DBV2_A2")
	)
	(segment
		(start 448.01028 -413.951928)
		(end 448.01028 -412.806642)
		(width 0.13208)
		(layer "F.Cu")
		(net "LM75_1_A0")
	)
	(segment
		(start 447.147188 -415.221166)
		(end 447.147188 -414.81502)
		(width 0.13208)
		(layer "F.Cu")
		(net "LM75_1_A0")
	)
	(segment
		(start 447.558414 -414.403794)
		(end 448.01028 -413.951928)
		(width 0.13208)
		(layer "F.Cu")
		(net "LM75_1_A0")
	)
	(segment
		(start 447.147188 -414.81502)
		(end 447.558414 -414.403794)
		(width 0.13208)
		(layer "F.Cu")
		(net "LM75_1_A0")
	)
	(segment
		(start 446.131188 -415.221166)
		(end 447.147188 -415.221166)
		(width 0.13208)
		(layer "F.Cu")
		(net "LM75_1_A0")
	)
	(via
		(at 447.558414 -414.403794)
		(size 0.508)
		(drill 0.254)
		(layers "F.Cu" "B.Cu")
		(net "LM75_1_A0")
	)
	(via
		(at 31.73095 -286.331914)
		(size 0.508)
		(drill 0.254)
		(layers "F.Cu" "B.Cu")
		(net "PCEPLL6_VDDA18_PEX0_R")
	)
	(segment
		(start 207.98409 -288.830766)
		(end 208.140046 -288.67481)
		(width 0.13208)
		(layer "F.Cu")
		(net "SMB_PEX1_PCA9555_SCL")
	)
	(segment
		(start 208.140046 -288.67481)
		(end 208.140046 -288.171636)
		(width 0.13208)
		(layer "F.Cu")
		(net "SMB_PEX1_PCA9555_SCL")
	)
	(segment
		(start 376.432064 -201.284078)
		(end 377.687078 -201.284078)
		(width 0.13208)
		(layer "F.Cu")
		(net "SMB_PEX1_PCA9555_SCL")
	)
	(segment
		(start 372.114064 -179.567078)
		(end 373.369078 -179.567078)
		(width 0.13208)
		(layer "F.Cu")
		(net "SMB_PEX1_PCA9555_SCL")
	)
	(via
		(at 210.556856 -248.35612)
		(size 0.508)
		(drill 0.254)
		(layers "F.Cu" "B.Cu")
		(net "SMB_PEX1_PCA9555_SCL")
	)
	(via
		(at 377.687078 -201.284078)
		(size 0.508)
		(drill 0.254)
		(layers "F.Cu" "B.Cu")
		(net "SMB_PEX1_PCA9555_SCL")
	)
	(via
		(at 373.369078 -179.567078)
		(size 0.508)
		(drill 0.254)
		(layers "F.Cu" "B.Cu")
		(net "SMB_PEX1_PCA9555_SCL")
	)
	(via
		(at 208.140046 -288.171636)
		(size 0.508)
		(drill 0.254)
		(layers "F.Cu" "B.Cu")
		(net "SMB_PEX1_PCA9555_SCL")
	)
	(segment
		(start 211.731606 -259.35051)
		(end 211.731606 -253.174246)
		(width 0.13208)
		(layer "B.Cu")
		(net "SMB_PEX1_PCA9555_SCL")
	)
	(segment
		(start 211.731606 -251.666502)
		(end 211.731606 -249.61088)
		(width 0.13208)
		(layer "B.Cu")
		(net "SMB_PEX1_PCA9555_SCL")
	)
	(segment
		(start 211.731606 -280.459942)
		(end 211.731606 -260.072886)
		(width 0.13208)
		(layer "B.Cu")
		(net "SMB_PEX1_PCA9555_SCL")
	)
	(segment
		(start 208.140046 -287.499044)
		(end 207.519524 -286.878522)
		(width 0.13208)
		(layer "B.Cu")
		(net "SMB_PEX1_PCA9555_SCL")
	)
	(segment
		(start 210.556856 -248.43613)
		(end 210.556856 -248.35612)
		(width 0.13208)
		(layer "B.Cu")
		(net "SMB_PEX1_PCA9555_SCL")
	)
	(segment
		(start 211.731606 -260.072886)
		(end 211.844382 -259.96011)
		(width 0.13208)
		(layer "B.Cu")
		(net "SMB_PEX1_PCA9555_SCL")
	)
	(segment
		(start 212.02904 -251.963936)
		(end 211.731606 -251.666502)
		(width 0.13208)
		(layer "B.Cu")
		(net "SMB_PEX1_PCA9555_SCL")
	)
	(segment
		(start 212.02904 -252.876812)
		(end 212.02904 -251.963936)
		(width 0.13208)
		(layer "B.Cu")
		(net "SMB_PEX1_PCA9555_SCL")
	)
	(segment
		(start 211.844382 -259.96011)
		(end 211.844382 -259.463286)
		(width 0.13208)
		(layer "B.Cu")
		(net "SMB_PEX1_PCA9555_SCL")
	)
	(segment
		(start 208.140046 -288.171636)
		(end 208.140046 -287.499044)
		(width 0.13208)
		(layer "B.Cu")
		(net "SMB_PEX1_PCA9555_SCL")
	)
	(segment
		(start 207.519524 -284.672024)
		(end 211.731606 -280.459942)
		(width 0.13208)
		(layer "B.Cu")
		(net "SMB_PEX1_PCA9555_SCL")
	)
	(segment
		(start 207.519524 -286.878522)
		(end 207.519524 -284.672024)
		(width 0.13208)
		(layer "B.Cu")
		(net "SMB_PEX1_PCA9555_SCL")
	)
	(segment
		(start 211.731606 -253.174246)
		(end 212.02904 -252.876812)
		(width 0.13208)
		(layer "B.Cu")
		(net "SMB_PEX1_PCA9555_SCL")
	)
	(segment
		(start 211.731606 -249.61088)
		(end 210.556856 -248.43613)
		(width 0.13208)
		(layer "B.Cu")
		(net "SMB_PEX1_PCA9555_SCL")
	)
	(segment
		(start 211.844382 -259.463286)
		(end 211.731606 -259.35051)
		(width 0.13208)
		(layer "B.Cu")
		(net "SMB_PEX1_PCA9555_SCL")
	)
	(segment
		(start 373.724424 -179.922424)
		(end 373.369078 -179.567078)
		(width 0.15494)
		(layer "In9.Cu")
		(net "SMB_PEX1_PCA9555_SCL")
	)
	(segment
		(start 376.244104 -183.757316)
		(end 375.630694 -183.757316)
		(width 0.15494)
		(layer "In9.Cu")
		(net "SMB_PEX1_PCA9555_SCL")
	)
	(segment
		(start 377.687078 -189.898782)
		(end 376.658632 -188.870336)
		(width 0.15494)
		(layer "In9.Cu")
		(net "SMB_PEX1_PCA9555_SCL")
	)
	(segment
		(start 376.658632 -188.870336)
		(end 376.658632 -184.171844)
		(width 0.15494)
		(layer "In9.Cu")
		(net "SMB_PEX1_PCA9555_SCL")
	)
	(segment
		(start 377.687078 -201.284078)
		(end 377.687078 -189.898782)
		(width 0.15494)
		(layer "In9.Cu")
		(net "SMB_PEX1_PCA9555_SCL")
	)
	(segment
		(start 373.724424 -181.851046)
		(end 373.724424 -179.922424)
		(width 0.15494)
		(layer "In9.Cu")
		(net "SMB_PEX1_PCA9555_SCL")
	)
	(segment
		(start 376.658632 -184.171844)
		(end 376.244104 -183.757316)
		(width 0.15494)
		(layer "In9.Cu")
		(net "SMB_PEX1_PCA9555_SCL")
	)
	(segment
		(start 375.630694 -183.757316)
		(end 373.724424 -181.851046)
		(width 0.15494)
		(layer "In9.Cu")
		(net "SMB_PEX1_PCA9555_SCL")
	)
	(segment
		(start 349.502476 -244.13718)
		(end 360.696256 -232.9434)
		(width 0.15494)
		(layer "In13.Cu")
		(net "SMB_PEX1_PCA9555_SCL")
	)
	(segment
		(start 246.81053 -249.694192)
		(end 253.595378 -249.694192)
		(width 0.15494)
		(layer "In13.Cu")
		(net "SMB_PEX1_PCA9555_SCL")
	)
	(segment
		(start 253.941326 -250.04014)
		(end 272.630646 -250.04014)
		(width 0.15494)
		(layer "In13.Cu")
		(net "SMB_PEX1_PCA9555_SCL")
	)
	(segment
		(start 375.364248 -216.7636)
		(end 377.5964 -216.7636)
		(width 0.15494)
		(layer "In13.Cu")
		(net "SMB_PEX1_PCA9555_SCL")
	)
	(segment
		(start 372.947438 -225.556318)
		(end 373.599964 -224.903792)
		(width 0.15494)
		(layer "In13.Cu")
		(net "SMB_PEX1_PCA9555_SCL")
	)
	(segment
		(start 231.575356 -248.669556)
		(end 234.206796 -248.669556)
		(width 0.15494)
		(layer "In13.Cu")
		(net "SMB_PEX1_PCA9555_SCL")
	)
	(segment
		(start 369.484402 -232.9434)
		(end 372.947438 -229.480364)
		(width 0.15494)
		(layer "In13.Cu")
		(net "SMB_PEX1_PCA9555_SCL")
	)
	(segment
		(start 274.169886 -251.57938)
		(end 297.9293 -251.57938)
		(width 0.15494)
		(layer "In13.Cu")
		(net "SMB_PEX1_PCA9555_SCL")
	)
	(segment
		(start 380.6825 -203.9747)
		(end 378.756926 -202.049126)
		(width 0.15494)
		(layer "In13.Cu")
		(net "SMB_PEX1_PCA9555_SCL")
	)
	(segment
		(start 253.595378 -249.694192)
		(end 253.941326 -250.04014)
		(width 0.15494)
		(layer "In13.Cu")
		(net "SMB_PEX1_PCA9555_SCL")
	)
	(segment
		(start 333.756 -250.7234)
		(end 334.19034 -250.28906)
		(width 0.15494)
		(layer "In13.Cu")
		(net "SMB_PEX1_PCA9555_SCL")
	)
	(segment
		(start 214.89797 -246.4562)
		(end 229.362 -246.4562)
		(width 0.15494)
		(layer "In13.Cu")
		(net "SMB_PEX1_PCA9555_SCL")
	)
	(segment
		(start 241.652044 -249.301)
		(end 242.0874 -248.865644)
		(width 0.15494)
		(layer "In13.Cu")
		(net "SMB_PEX1_PCA9555_SCL")
	)
	(segment
		(start 333.756 -251.412248)
		(end 333.756 -250.7234)
		(width 0.15494)
		(layer "In13.Cu")
		(net "SMB_PEX1_PCA9555_SCL")
	)
	(segment
		(start 346.17152 -244.13718)
		(end 349.502476 -244.13718)
		(width 0.15494)
		(layer "In13.Cu")
		(net "SMB_PEX1_PCA9555_SCL")
	)
	(segment
		(start 242.59159 -248.865644)
		(end 243.153946 -249.428)
		(width 0.15494)
		(layer "In13.Cu")
		(net "SMB_PEX1_PCA9555_SCL")
	)
	(segment
		(start 305.892454 -255.016)
		(end 308.171088 -252.737366)
		(width 0.15494)
		(layer "In13.Cu")
		(net "SMB_PEX1_PCA9555_SCL")
	)
	(segment
		(start 340.01964 -250.28906)
		(end 346.17152 -244.13718)
		(width 0.15494)
		(layer "In13.Cu")
		(net "SMB_PEX1_PCA9555_SCL")
	)
	(segment
		(start 211.206334 -247.6246)
		(end 213.72957 -247.6246)
		(width 0.15494)
		(layer "In13.Cu")
		(net "SMB_PEX1_PCA9555_SCL")
	)
	(segment
		(start 213.72957 -247.6246)
		(end 214.89797 -246.4562)
		(width 0.15494)
		(layer "In13.Cu")
		(net "SMB_PEX1_PCA9555_SCL")
	)
	(segment
		(start 239.903 -248.9454)
		(end 240.8682 -248.9454)
		(width 0.15494)
		(layer "In13.Cu")
		(net "SMB_PEX1_PCA9555_SCL")
	)
	(segment
		(start 332.430882 -252.737366)
		(end 333.756 -251.412248)
		(width 0.15494)
		(layer "In13.Cu")
		(net "SMB_PEX1_PCA9555_SCL")
	)
	(segment
		(start 244.644418 -249.428)
		(end 245.079774 -248.992644)
		(width 0.15494)
		(layer "In13.Cu")
		(net "SMB_PEX1_PCA9555_SCL")
	)
	(segment
		(start 210.556856 -248.274078)
		(end 211.206334 -247.6246)
		(width 0.15494)
		(layer "In13.Cu")
		(net "SMB_PEX1_PCA9555_SCL")
	)
	(segment
		(start 235.231432 -249.694192)
		(end 239.154208 -249.694192)
		(width 0.15494)
		(layer "In13.Cu")
		(net "SMB_PEX1_PCA9555_SCL")
	)
	(segment
		(start 372.947438 -229.480364)
		(end 372.947438 -225.556318)
		(width 0.15494)
		(layer "In13.Cu")
		(net "SMB_PEX1_PCA9555_SCL")
	)
	(segment
		(start 234.206796 -248.669556)
		(end 235.231432 -249.694192)
		(width 0.15494)
		(layer "In13.Cu")
		(net "SMB_PEX1_PCA9555_SCL")
	)
	(segment
		(start 378.452126 -202.049126)
		(end 377.687078 -201.284078)
		(width 0.15494)
		(layer "In13.Cu")
		(net "SMB_PEX1_PCA9555_SCL")
	)
	(segment
		(start 380.6825 -213.6775)
		(end 380.6825 -203.9747)
		(width 0.15494)
		(layer "In13.Cu")
		(net "SMB_PEX1_PCA9555_SCL")
	)
	(segment
		(start 243.153946 -249.428)
		(end 244.644418 -249.428)
		(width 0.15494)
		(layer "In13.Cu")
		(net "SMB_PEX1_PCA9555_SCL")
	)
	(segment
		(start 301.36592 -255.016)
		(end 305.892454 -255.016)
		(width 0.15494)
		(layer "In13.Cu")
		(net "SMB_PEX1_PCA9555_SCL")
	)
	(segment
		(start 373.599964 -224.903792)
		(end 373.599964 -218.527884)
		(width 0.15494)
		(layer "In13.Cu")
		(net "SMB_PEX1_PCA9555_SCL")
	)
	(segment
		(start 308.171088 -252.737366)
		(end 332.430882 -252.737366)
		(width 0.15494)
		(layer "In13.Cu")
		(net "SMB_PEX1_PCA9555_SCL")
	)
	(segment
		(start 239.154208 -249.694192)
		(end 239.903 -248.9454)
		(width 0.15494)
		(layer "In13.Cu")
		(net "SMB_PEX1_PCA9555_SCL")
	)
	(segment
		(start 334.19034 -250.28906)
		(end 340.01964 -250.28906)
		(width 0.15494)
		(layer "In13.Cu")
		(net "SMB_PEX1_PCA9555_SCL")
	)
	(segment
		(start 246.108982 -248.992644)
		(end 246.81053 -249.694192)
		(width 0.15494)
		(layer "In13.Cu")
		(net "SMB_PEX1_PCA9555_SCL")
	)
	(segment
		(start 377.5964 -216.7636)
		(end 380.6825 -213.6775)
		(width 0.15494)
		(layer "In13.Cu")
		(net "SMB_PEX1_PCA9555_SCL")
	)
	(segment
		(start 241.2238 -249.301)
		(end 241.652044 -249.301)
		(width 0.15494)
		(layer "In13.Cu")
		(net "SMB_PEX1_PCA9555_SCL")
	)
	(segment
		(start 229.362 -246.4562)
		(end 231.575356 -248.669556)
		(width 0.15494)
		(layer "In13.Cu")
		(net "SMB_PEX1_PCA9555_SCL")
	)
	(segment
		(start 373.599964 -218.527884)
		(end 375.364248 -216.7636)
		(width 0.15494)
		(layer "In13.Cu")
		(net "SMB_PEX1_PCA9555_SCL")
	)
	(segment
		(start 378.756926 -202.049126)
		(end 378.452126 -202.049126)
		(width 0.15494)
		(layer "In13.Cu")
		(net "SMB_PEX1_PCA9555_SCL")
	)
	(segment
		(start 297.9293 -251.57938)
		(end 301.36592 -255.016)
		(width 0.15494)
		(layer "In13.Cu")
		(net "SMB_PEX1_PCA9555_SCL")
	)
	(segment
		(start 242.0874 -248.865644)
		(end 242.59159 -248.865644)
		(width 0.15494)
		(layer "In13.Cu")
		(net "SMB_PEX1_PCA9555_SCL")
	)
	(segment
		(start 210.556856 -248.35612)
		(end 210.556856 -248.274078)
		(width 0.15494)
		(layer "In13.Cu")
		(net "SMB_PEX1_PCA9555_SCL")
	)
	(segment
		(start 245.079774 -248.992644)
		(end 246.108982 -248.992644)
		(width 0.15494)
		(layer "In13.Cu")
		(net "SMB_PEX1_PCA9555_SCL")
	)
	(segment
		(start 272.630646 -250.04014)
		(end 274.169886 -251.57938)
		(width 0.15494)
		(layer "In13.Cu")
		(net "SMB_PEX1_PCA9555_SCL")
	)
	(segment
		(start 360.696256 -232.9434)
		(end 369.484402 -232.9434)
		(width 0.15494)
		(layer "In13.Cu")
		(net "SMB_PEX1_PCA9555_SCL")
	)
	(segment
		(start 240.8682 -248.9454)
		(end 241.2238 -249.301)
		(width 0.15494)
		(layer "In13.Cu")
		(net "SMB_PEX1_PCA9555_SCL")
	)
	(segment
		(start 105.789476 -390.654286)
		(end 105.789476 -389.868918)
		(width 0.13208)
		(layer "F.Cu")
		(net "BIC_USB_HUB_RREF")
	)
	(segment
		(start 105.789476 -389.868918)
		(end 105.9307 -389.727694)
		(width 0.13208)
		(layer "F.Cu")
		(net "BIC_USB_HUB_RREF")
	)
	(segment
		(start 107.706414 -390.109202)
		(end 107.706414 -390.420352)
		(width 0.13208)
		(layer "F.Cu")
		(net "BIC_USB_HUB_RREF")
	)
	(segment
		(start 107.324906 -389.727694)
		(end 107.706414 -390.109202)
		(width 0.13208)
		(layer "F.Cu")
		(net "BIC_USB_HUB_RREF")
	)
	(segment
		(start 105.9307 -389.727694)
		(end 107.324906 -389.727694)
		(width 0.13208)
		(layer "F.Cu")
		(net "BIC_USB_HUB_RREF")
	)
	(via
		(at 107.324906 -389.727694)
		(size 0.508)
		(drill 0.254)
		(layers "F.Cu" "B.Cu")
		(net "BIC_USB_HUB_RREF")
	)
	(segment
		(start 328.723244 -196.594476)
		(end 329.754484 -196.594476)
		(width 0.13208)
		(layer "F.Cu")
		(net "IOEXP_DBV2_A1")
	)
	(segment
		(start 326.412606 -197.250304)
		(end 328.067416 -197.250304)
		(width 0.13208)
		(layer "F.Cu")
		(net "IOEXP_DBV2_A1")
	)
	(segment
		(start 326.412606 -198.266304)
		(end 326.412606 -197.250304)
		(width 0.13208)
		(layer "F.Cu")
		(net "IOEXP_DBV2_A1")
	)
	(segment
		(start 328.067416 -197.250304)
		(end 328.723244 -196.594476)
		(width 0.13208)
		(layer "F.Cu")
		(net "IOEXP_DBV2_A1")
	)
	(via
		(at 328.067416 -197.250304)
		(size 0.508)
		(drill 0.254)
		(layers "F.Cu" "B.Cu")
		(net "IOEXP_DBV2_A1")
	)
	(segment
		(start 47.77486 -296.37482)
		(end 48.24984 -295.89984)
		(width 0.249936)
		(layer "F.Cu")
		(net "PCEPLL3_VDDA18_PEX0")
	)
	(via
		(at 47.77486 -296.37482)
		(size 0.4064)
		(drill 0.2032)
		(layers "F.Cu" "B.Cu")
		(net "PCEPLL3_VDDA18_PEX0")
	)
	(via
		(at 34.677604 -260.338316)
		(size 0.508)
		(drill 0.254)
		(layers "F.Cu" "B.Cu")
		(net "PCEPLL3_VDDA18_PEX0")
	)
	(via
		(at 36.074604 -260.338316)
		(size 0.508)
		(drill 0.254)
		(layers "F.Cu" "B.Cu")
		(net "PCEPLL3_VDDA18_PEX0")
	)
	(segment
		(start 47.77486 -295.6433)
		(end 47.77486 -296.37482)
		(width 0.3048)
		(layer "B.Cu")
		(net "PCEPLL3_VDDA18_PEX0")
	)
	(segment
		(start 99.50196 -392.589766)
		(end 100.192078 -392.589766)
		(width 0.13208)
		(layer "F.Cu")
		(net "BIC_USB_HUB_OVCUR2")
	)
	(segment
		(start 98.448368 -392.0998)
		(end 99.011994 -392.0998)
		(width 0.13208)
		(layer "F.Cu")
		(net "BIC_USB_HUB_OVCUR2")
	)
	(segment
		(start 99.011994 -392.0998)
		(end 99.50196 -392.589766)
		(width 0.13208)
		(layer "F.Cu")
		(net "BIC_USB_HUB_OVCUR2")
	)
	(segment
		(start 100.192078 -392.589766)
		(end 100.256594 -392.654282)
		(width 0.13208)
		(layer "F.Cu")
		(net "BIC_USB_HUB_OVCUR2")
	)
	(segment
		(start 100.256594 -392.654282)
		(end 100.964492 -392.654282)
		(width 0.13208)
		(layer "F.Cu")
		(net "BIC_USB_HUB_OVCUR2")
	)
	(via
		(at 99.50196 -392.589766)
		(size 0.508)
		(drill 0.254)
		(layers "F.Cu" "B.Cu")
		(net "BIC_USB_HUB_OVCUR2")
	)
	(segment
		(start 338.92236 -195.294504)
		(end 335.604612 -195.294504)
		(width 0.13208)
		(layer "F.Cu")
		(net "IOEXP_DBV2_A0")
	)
	(segment
		(start 340.161372 -195.49745)
		(end 339.703664 -195.49745)
		(width 0.13208)
		(layer "F.Cu")
		(net "IOEXP_DBV2_A0")
	)
	(segment
		(start 339.500718 -195.294504)
		(end 338.92236 -195.294504)
		(width 0.13208)
		(layer "F.Cu")
		(net "IOEXP_DBV2_A0")
	)
	(segment
		(start 339.703664 -195.49745)
		(end 339.500718 -195.294504)
		(width 0.13208)
		(layer "F.Cu")
		(net "IOEXP_DBV2_A0")
	)
	(segment
		(start 340.161372 -196.51345)
		(end 340.161372 -195.49745)
		(width 0.13208)
		(layer "F.Cu")
		(net "IOEXP_DBV2_A0")
	)
	(via
		(at 338.92236 -195.294504)
		(size 0.762)
		(drill 0.381)
		(layers "F.Cu" "B.Cu")
		(net "IOEXP_DBV2_A0")
	)
	(segment
		(start 448.328288 -405.470868)
		(end 448.328288 -406.267666)
		(width 0.13208)
		(layer "F.Cu")
		(net "SMB_LM75_1_SCL")
	)
	(segment
		(start 448.01028 -407.506678)
		(end 448.01028 -406.585674)
		(width 0.13208)
		(layer "F.Cu")
		(net "SMB_LM75_1_SCL")
	)
	(segment
		(start 448.01028 -406.585674)
		(end 448.32016 -406.275794)
		(width 0.13208)
		(layer "F.Cu")
		(net "SMB_LM75_1_SCL")
	)
	(segment
		(start 448.328288 -406.267666)
		(end 448.32016 -406.275794)
		(width 0.13208)
		(layer "F.Cu")
		(net "SMB_LM75_1_SCL")
	)
	(via
		(at 448.32016 -406.275794)
		(size 0.508)
		(drill 0.254)
		(layers "F.Cu" "B.Cu")
		(net "SMB_LM75_1_SCL")
	)
	(via
		(at 31.73095 -279.931114)
		(size 0.508)
		(drill 0.254)
		(layers "F.Cu" "B.Cu")
		(net "SYSPLL_VDDA18_PEX0_R")
	)
	(segment
		(start 206.41437 -290.093146)
		(end 206.41437 -291.297868)
		(width 0.13208)
		(layer "F.Cu")
		(net "SMB_PEX1_HOST_LS_SDA")
	)
	(segment
		(start 205.051152 -294.460422)
		(end 205.051152 -297.31716)
		(width 0.13208)
		(layer "F.Cu")
		(net "SMB_PEX1_HOST_LS_SDA")
	)
	(segment
		(start 206.122778 -294.016176)
		(end 205.495398 -294.016176)
		(width 0.13208)
		(layer "F.Cu")
		(net "SMB_PEX1_HOST_LS_SDA")
	)
	(segment
		(start 204.93609 -289.630866)
		(end 205.95209 -289.630866)
		(width 0.13208)
		(layer "F.Cu")
		(net "SMB_PEX1_HOST_LS_SDA")
	)
	(segment
		(start 205.051152 -297.31716)
		(end 205.198472 -297.46448)
		(width 0.13208)
		(layer "F.Cu")
		(net "SMB_PEX1_HOST_LS_SDA")
	)
	(segment
		(start 206.41437 -291.297868)
		(end 206.41437 -293.724584)
		(width 0.13208)
		(layer "F.Cu")
		(net "SMB_PEX1_HOST_LS_SDA")
	)
	(segment
		(start 205.95209 -289.630866)
		(end 206.41437 -290.093146)
		(width 0.13208)
		(layer "F.Cu")
		(net "SMB_PEX1_HOST_LS_SDA")
	)
	(segment
		(start 206.41437 -293.724584)
		(end 206.122778 -294.016176)
		(width 0.13208)
		(layer "F.Cu")
		(net "SMB_PEX1_HOST_LS_SDA")
	)
	(segment
		(start 203.92009 -289.630866)
		(end 204.93609 -289.630866)
		(width 0.13208)
		(layer "F.Cu")
		(net "SMB_PEX1_HOST_LS_SDA")
	)
	(segment
		(start 205.495398 -294.016176)
		(end 205.051152 -294.460422)
		(width 0.13208)
		(layer "F.Cu")
		(net "SMB_PEX1_HOST_LS_SDA")
	)
	(via
		(at 206.122778 -294.016176)
		(size 0.508)
		(drill 0.254)
		(layers "F.Cu" "B.Cu")
		(net "SMB_PEX1_HOST_LS_SDA")
	)
	(segment
		(start 359.55605 -175.006)
		(end 359.55605 -173.99)
		(width 0.13208)
		(layer "F.Cu")
		(net "SSD7_PEX_PWR_EN_R")
	)
	(segment
		(start 359.55605 -173.99)
		(end 360.172 -173.99)
		(width 0.13208)
		(layer "F.Cu")
		(net "SSD7_PEX_PWR_EN_R")
	)
	(segment
		(start 360.172 -173.99)
		(end 360.78795 -173.99)
		(width 0.13208)
		(layer "F.Cu")
		(net "SSD7_PEX_PWR_EN_R")
	)
	(segment
		(start 337.293966 -215.987122)
		(end 336.89417 -215.587326)
		(width 0.13208)
		(layer "F.Cu")
		(net "SSD7_PEX_PWR_EN_R")
	)
	(via
		(at 360.172 -173.99)
		(size 0.508)
		(drill 0.254)
		(layers "F.Cu" "B.Cu")
		(net "SSD7_PEX_PWR_EN_R")
	)
	(via
		(at 343.135966 -174.508922)
		(size 0.508)
		(drill 0.254)
		(layers "F.Cu" "B.Cu")
		(net "SSD7_PEX_PWR_EN_R")
	)
	(via
		(at 336.89417 -215.587326)
		(size 0.4572)
		(drill 0.254)
		(layers "F.Cu" "B.Cu")
		(net "SSD7_PEX_PWR_EN_R")
	)
	(segment
		(start 337.7184 -179.25161)
		(end 338.46135 -178.50866)
		(width 0.15494)
		(layer "In7.Cu")
		(net "SSD7_PEX_PWR_EN_R")
	)
	(segment
		(start 335.22666 -184.50687)
		(end 335.50987 -184.22366)
		(width 0.15494)
		(layer "In7.Cu")
		(net "SSD7_PEX_PWR_EN_R")
	)
	(segment
		(start 337.54187 -182.177182)
		(end 337.7184 -182.000652)
		(width 0.15494)
		(layer "In7.Cu")
		(net "SSD7_PEX_PWR_EN_R")
	)
	(segment
		(start 338.46135 -178.33213)
		(end 342.284558 -174.508922)
		(width 0.15494)
		(layer "In7.Cu")
		(net "SSD7_PEX_PWR_EN_R")
	)
	(segment
		(start 334.50784 -206.797402)
		(end 334.50784 -205.291944)
		(width 0.15494)
		(layer "In7.Cu")
		(net "SSD7_PEX_PWR_EN_R")
	)
	(segment
		(start 334.50784 -205.291944)
		(end 334.01 -204.794104)
		(width 0.15494)
		(layer "In7.Cu")
		(net "SSD7_PEX_PWR_EN_R")
	)
	(segment
		(start 335.50987 -184.209182)
		(end 337.244182 -182.47487)
		(width 0.15494)
		(layer "In7.Cu")
		(net "SSD7_PEX_PWR_EN_R")
	)
	(segment
		(start 337.244182 -182.47487)
		(end 337.25866 -182.47487)
		(width 0.15494)
		(layer "In7.Cu")
		(net "SSD7_PEX_PWR_EN_R")
	)
	(segment
		(start 334.01 -204.794104)
		(end 334.01 -185.2676)
		(width 0.15494)
		(layer "In7.Cu")
		(net "SSD7_PEX_PWR_EN_R")
	)
	(segment
		(start 334.77073 -184.50687)
		(end 335.22666 -184.50687)
		(width 0.15494)
		(layer "In7.Cu")
		(net "SSD7_PEX_PWR_EN_R")
	)
	(segment
		(start 336.89417 -215.587326)
		(end 336.49412 -215.187276)
		(width 0.0889)
		(layer "In7.Cu")
		(net "SSD7_PEX_PWR_EN_R")
	)
	(segment
		(start 336.49412 -215.187276)
		(end 336.49412 -211.84108)
		(width 0.0889)
		(layer "In7.Cu")
		(net "SSD7_PEX_PWR_EN_R")
	)
	(segment
		(start 338.46135 -178.50866)
		(end 338.46135 -178.33213)
		(width 0.15494)
		(layer "In7.Cu")
		(net "SSD7_PEX_PWR_EN_R")
	)
	(segment
		(start 337.25866 -182.47487)
		(end 337.54187 -182.19166)
		(width 0.15494)
		(layer "In7.Cu")
		(net "SSD7_PEX_PWR_EN_R")
	)
	(segment
		(start 337.54187 -182.19166)
		(end 337.54187 -182.177182)
		(width 0.15494)
		(layer "In7.Cu")
		(net "SSD7_PEX_PWR_EN_R")
	)
	(segment
		(start 335.50987 -184.22366)
		(end 335.50987 -184.209182)
		(width 0.15494)
		(layer "In7.Cu")
		(net "SSD7_PEX_PWR_EN_R")
	)
	(segment
		(start 337.7184 -182.000652)
		(end 337.7184 -179.25161)
		(width 0.15494)
		(layer "In7.Cu")
		(net "SSD7_PEX_PWR_EN_R")
	)
	(segment
		(start 334.01 -185.2676)
		(end 334.77073 -184.50687)
		(width 0.15494)
		(layer "In7.Cu")
		(net "SSD7_PEX_PWR_EN_R")
	)
	(segment
		(start 342.284558 -174.508922)
		(end 343.135966 -174.508922)
		(width 0.15494)
		(layer "In7.Cu")
		(net "SSD7_PEX_PWR_EN_R")
	)
	(segment
		(start 336.5246 -208.814162)
		(end 334.50784 -206.797402)
		(width 0.15494)
		(layer "In7.Cu")
		(net "SSD7_PEX_PWR_EN_R")
	)
	(segment
		(start 336.49412 -211.84108)
		(end 336.5246 -211.8106)
		(width 0.0889)
		(layer "In7.Cu")
		(net "SSD7_PEX_PWR_EN_R")
	)
	(segment
		(start 336.5246 -211.8106)
		(end 336.5246 -208.814162)
		(width 0.15494)
		(layer "In7.Cu")
		(net "SSD7_PEX_PWR_EN_R")
	)
	(segment
		(start 356.173024 -173.482)
		(end 355.146102 -174.508922)
		(width 0.15494)
		(layer "In13.Cu")
		(net "SSD7_PEX_PWR_EN_R")
	)
	(segment
		(start 355.146102 -174.508922)
		(end 343.135966 -174.508922)
		(width 0.15494)
		(layer "In13.Cu")
		(net "SSD7_PEX_PWR_EN_R")
	)
	(segment
		(start 359.664 -173.482)
		(end 356.173024 -173.482)
		(width 0.15494)
		(layer "In13.Cu")
		(net "SSD7_PEX_PWR_EN_R")
	)
	(segment
		(start 360.172 -173.99)
		(end 359.664 -173.482)
		(width 0.15494)
		(layer "In13.Cu")
		(net "SSD7_PEX_PWR_EN_R")
	)
	(segment
		(start 334.09382 -224.786952)
		(end 332.74 -224.786952)
		(width 0.13208)
		(layer "F.Cu")
		(net "PWR_EN_PEX")
	)
	(segment
		(start 327.93178 -226.004882)
		(end 327.93178 -226.000818)
		(width 0.13208)
		(layer "F.Cu")
		(net "PWR_EN_PEX")
	)
	(segment
		(start 327.80478 -225.53295)
		(end 327.93178 -225.65995)
		(width 0.13208)
		(layer "F.Cu")
		(net "PWR_EN_PEX")
	)
	(segment
		(start 325.674736 -228.308916)
		(end 325.324724 -227.958904)
		(width 0.13208)
		(layer "F.Cu")
		(net "PWR_EN_PEX")
	)
	(segment
		(start 364.659926 -255.362964)
		(end 364.659926 -254.385826)
		(width 0.13208)
		(layer "F.Cu")
		(net "PWR_EN_PEX")
	)
	(segment
		(start 325.324724 -226.502468)
		(end 326.294242 -225.53295)
		(width 0.13208)
		(layer "F.Cu")
		(net "PWR_EN_PEX")
	)
	(segment
		(start 330.550266 -226.004882)
		(end 327.93178 -226.004882)
		(width 0.13208)
		(layer "F.Cu")
		(net "PWR_EN_PEX")
	)
	(segment
		(start 364.66018 -254.385572)
		(end 365.769398 -254.385572)
		(width 0.13208)
		(layer "F.Cu")
		(net "PWR_EN_PEX")
	)
	(segment
		(start 326.294242 -225.53295)
		(end 327.80478 -225.53295)
		(width 0.13208)
		(layer "F.Cu")
		(net "PWR_EN_PEX")
	)
	(segment
		(start 332.335378 -225.191574)
		(end 331.363574 -225.191574)
		(width 0.13208)
		(layer "F.Cu")
		(net "PWR_EN_PEX")
	)
	(segment
		(start 325.324724 -227.958904)
		(end 325.324724 -226.502468)
		(width 0.13208)
		(layer "F.Cu")
		(net "PWR_EN_PEX")
	)
	(segment
		(start 364.659926 -254.385826)
		(end 364.66018 -254.385572)
		(width 0.13208)
		(layer "F.Cu")
		(net "PWR_EN_PEX")
	)
	(segment
		(start 332.74 -224.786952)
		(end 332.335378 -225.191574)
		(width 0.13208)
		(layer "F.Cu")
		(net "PWR_EN_PEX")
	)
	(segment
		(start 327.93178 -225.65995)
		(end 327.93178 -226.000818)
		(width 0.13208)
		(layer "F.Cu")
		(net "PWR_EN_PEX")
	)
	(segment
		(start 331.363574 -225.191574)
		(end 330.550266 -226.004882)
		(width 0.13208)
		(layer "F.Cu")
		(net "PWR_EN_PEX")
	)
	(via
		(at 364.659926 -255.362964)
		(size 0.508)
		(drill 0.254)
		(layers "F.Cu" "B.Cu")
		(net "PWR_EN_PEX")
	)
	(via
		(at 328.380344 -247.711976)
		(size 0.508)
		(drill 0.254)
		(layers "F.Cu" "B.Cu")
		(net "PWR_EN_PEX")
	)
	(via
		(at 325.674736 -228.308916)
		(size 0.508)
		(drill 0.254)
		(layers "F.Cu" "B.Cu")
		(net "PWR_EN_PEX")
	)
	(via
		(at 330.550266 -226.004882)
		(size 0.762)
		(drill 0.381)
		(layers "F.Cu" "B.Cu")
		(net "PWR_EN_PEX")
	)
	(segment
		(start 328.380344 -247.711976)
		(end 334.692752 -247.711976)
		(width 0.13208)
		(layer "B.Cu")
		(net "PWR_EN_PEX")
	)
	(segment
		(start 360.25963 -246.822468)
		(end 360.634534 -247.197626)
		(width 0.13208)
		(layer "B.Cu")
		(net "PWR_EN_PEX")
	)
	(segment
		(start 334.692752 -247.711976)
		(end 335.639918 -248.659142)
		(width 0.13208)
		(layer "B.Cu")
		(net "PWR_EN_PEX")
	)
	(segment
		(start 360.634534 -247.197626)
		(end 364.659926 -251.222764)
		(width 0.13208)
		(layer "B.Cu")
		(net "PWR_EN_PEX")
	)
	(segment
		(start 364.659926 -251.222764)
		(end 364.659926 -255.362964)
		(width 0.13208)
		(layer "B.Cu")
		(net "PWR_EN_PEX")
	)
	(segment
		(start 342.097868 -248.659142)
		(end 343.934542 -246.822468)
		(width 0.13208)
		(layer "B.Cu")
		(net "PWR_EN_PEX")
	)
	(segment
		(start 335.639918 -248.659142)
		(end 342.097868 -248.659142)
		(width 0.13208)
		(layer "B.Cu")
		(net "PWR_EN_PEX")
	)
	(segment
		(start 343.934542 -246.822468)
		(end 360.25963 -246.822468)
		(width 0.13208)
		(layer "B.Cu")
		(net "PWR_EN_PEX")
	)
	(segment
		(start 324.6374 -238.305848)
		(end 325.501 -237.442248)
		(width 0.15494)
		(layer "In7.Cu")
		(net "PWR_EN_PEX")
	)
	(segment
		(start 324.6374 -239.126268)
		(end 324.6374 -238.305848)
		(width 0.15494)
		(layer "In7.Cu")
		(net "PWR_EN_PEX")
	)
	(segment
		(start 325.501 -237.442248)
		(end 325.501 -235.1786)
		(width 0.15494)
		(layer "In7.Cu")
		(net "PWR_EN_PEX")
	)
	(segment
		(start 326.138286 -245.469918)
		(end 326.138286 -240.627154)
		(width 0.15494)
		(layer "In7.Cu")
		(net "PWR_EN_PEX")
	)
	(segment
		(start 324.866 -229.117652)
		(end 325.674736 -228.308916)
		(width 0.15494)
		(layer "In7.Cu")
		(net "PWR_EN_PEX")
	)
	(segment
		(start 325.628 -232.715054)
		(end 324.866 -231.953054)
		(width 0.15494)
		(layer "In7.Cu")
		(net "PWR_EN_PEX")
	)
	(segment
		(start 325.628 -235.0516)
		(end 325.628 -232.715054)
		(width 0.15494)
		(layer "In7.Cu")
		(net "PWR_EN_PEX")
	)
	(segment
		(start 324.866 -231.953054)
		(end 324.866 -229.117652)
		(width 0.15494)
		(layer "In7.Cu")
		(net "PWR_EN_PEX")
	)
	(segment
		(start 326.138286 -240.627154)
		(end 324.6374 -239.126268)
		(width 0.15494)
		(layer "In7.Cu")
		(net "PWR_EN_PEX")
	)
	(segment
		(start 328.380344 -247.711976)
		(end 326.138286 -245.469918)
		(width 0.15494)
		(layer "In7.Cu")
		(net "PWR_EN_PEX")
	)
	(segment
		(start 325.501 -235.1786)
		(end 325.628 -235.0516)
		(width 0.15494)
		(layer "In7.Cu")
		(net "PWR_EN_PEX")
	)
	(segment
		(start 255.01346 -195.973446)
		(end 254.21336 -195.173346)
		(width 0.13208)
		(layer "F.Cu")
		(net "JTAG_BIC_TMS_R")
	)
	(segment
		(start 253.99746 -195.173346)
		(end 253.99746 -194.199764)
		(width 0.13208)
		(layer "F.Cu")
		(net "JTAG_BIC_TMS_R")
	)
	(segment
		(start 254.21336 -195.173346)
		(end 253.99746 -195.173346)
		(width 0.13208)
		(layer "F.Cu")
		(net "JTAG_BIC_TMS_R")
	)
	(via
		(at 231.401112 -202.335892)
		(size 0.508)
		(drill 0.254)
		(layers "F.Cu" "B.Cu")
		(net "JTAG_BIC_TMS_R")
	)
	(via
		(at 253.99746 -194.199764)
		(size 0.508)
		(drill 0.254)
		(layers "F.Cu" "B.Cu")
		(net "JTAG_BIC_TMS_R")
	)
	(segment
		(start 227.02012 -202.84059)
		(end 227.02012 -204.305662)
		(width 0.13208)
		(layer "B.Cu")
		(net "JTAG_BIC_TMS_R")
	)
	(segment
		(start 226.546664 -208.38541)
		(end 226.546664 -207.42021)
		(width 0.13208)
		(layer "B.Cu")
		(net "JTAG_BIC_TMS_R")
	)
	(segment
		(start 227.02012 -204.305662)
		(end 227.082096 -204.367638)
		(width 0.13208)
		(layer "B.Cu")
		(net "JTAG_BIC_TMS_R")
	)
	(segment
		(start 229.678484 -201.585068)
		(end 229.04196 -202.221592)
		(width 0.13208)
		(layer "B.Cu")
		(net "JTAG_BIC_TMS_R")
	)
	(segment
		(start 227.082096 -204.367638)
		(end 227.082096 -206.884778)
		(width 0.13208)
		(layer "B.Cu")
		(net "JTAG_BIC_TMS_R")
	)
	(segment
		(start 231.01681 -201.585068)
		(end 229.678484 -201.585068)
		(width 0.13208)
		(layer "B.Cu")
		(net "JTAG_BIC_TMS_R")
	)
	(segment
		(start 229.04196 -202.221592)
		(end 227.639118 -202.221592)
		(width 0.13208)
		(layer "B.Cu")
		(net "JTAG_BIC_TMS_R")
	)
	(segment
		(start 227.082096 -206.884778)
		(end 226.546664 -207.42021)
		(width 0.13208)
		(layer "B.Cu")
		(net "JTAG_BIC_TMS_R")
	)
	(segment
		(start 231.401112 -202.335892)
		(end 231.401112 -201.96937)
		(width 0.13208)
		(layer "B.Cu")
		(net "JTAG_BIC_TMS_R")
	)
	(segment
		(start 227.639118 -202.221592)
		(end 227.02012 -202.84059)
		(width 0.13208)
		(layer "B.Cu")
		(net "JTAG_BIC_TMS_R")
	)
	(segment
		(start 231.401112 -201.96937)
		(end 231.01681 -201.585068)
		(width 0.13208)
		(layer "B.Cu")
		(net "JTAG_BIC_TMS_R")
	)
	(segment
		(start 252.534166 -198.07047)
		(end 251.168154 -198.9836)
		(width 0.15494)
		(layer "In15.Cu")
		(net "JTAG_BIC_TMS_R")
	)
	(segment
		(start 253.99746 -194.5386)
		(end 252.534166 -198.07047)
		(width 0.15494)
		(layer "In15.Cu")
		(net "JTAG_BIC_TMS_R")
	)
	(segment
		(start 251.168154 -198.9836)
		(end 249.936 -198.9836)
		(width 0.15494)
		(layer "In15.Cu")
		(net "JTAG_BIC_TMS_R")
	)
	(segment
		(start 239.670082 -196.717158)
		(end 237.595664 -198.791576)
		(width 0.15494)
		(layer "In15.Cu")
		(net "JTAG_BIC_TMS_R")
	)
	(segment
		(start 249.936 -198.9836)
		(end 247.669558 -196.717158)
		(width 0.15494)
		(layer "In15.Cu")
		(net "JTAG_BIC_TMS_R")
	)
	(segment
		(start 236.684058 -199.413114)
		(end 235.182664 -200.914508)
		(width 0.15494)
		(layer "In15.Cu")
		(net "JTAG_BIC_TMS_R")
	)
	(segment
		(start 237.595664 -198.791576)
		(end 236.684058 -199.413114)
		(width 0.15494)
		(layer "In15.Cu")
		(net "JTAG_BIC_TMS_R")
	)
	(segment
		(start 235.182664 -200.914508)
		(end 232.822496 -200.914508)
		(width 0.15494)
		(layer "In15.Cu")
		(net "JTAG_BIC_TMS_R")
	)
	(segment
		(start 253.99746 -194.199764)
		(end 253.99746 -194.5386)
		(width 0.15494)
		(layer "In15.Cu")
		(net "JTAG_BIC_TMS_R")
	)
	(segment
		(start 247.669558 -196.717158)
		(end 239.670082 -196.717158)
		(width 0.15494)
		(layer "In15.Cu")
		(net "JTAG_BIC_TMS_R")
	)
	(segment
		(start 232.822496 -200.914508)
		(end 231.401112 -202.335892)
		(width 0.15494)
		(layer "In15.Cu")
		(net "JTAG_BIC_TMS_R")
	)
	(segment
		(start 328.067416 -198.17461)
		(end 328.897742 -197.344284)
		(width 0.13208)
		(layer "F.Cu")
		(net "IRQ_IOEXP_DBV2_N")
	)
	(segment
		(start 328.067416 -198.520304)
		(end 328.067416 -198.17461)
		(width 0.13208)
		(layer "F.Cu")
		(net "IRQ_IOEXP_DBV2_N")
	)
	(segment
		(start 327.305416 -199.282304)
		(end 328.067416 -198.520304)
		(width 0.13208)
		(layer "F.Cu")
		(net "IRQ_IOEXP_DBV2_N")
	)
	(segment
		(start 326.412606 -199.282304)
		(end 327.305416 -199.282304)
		(width 0.13208)
		(layer "F.Cu")
		(net "IRQ_IOEXP_DBV2_N")
	)
	(segment
		(start 328.897742 -197.344284)
		(end 329.754484 -197.344284)
		(width 0.13208)
		(layer "F.Cu")
		(net "IRQ_IOEXP_DBV2_N")
	)
	(via
		(at 328.067416 -198.520304)
		(size 0.508)
		(drill 0.254)
		(layers "F.Cu" "B.Cu")
		(net "IRQ_IOEXP_DBV2_N")
	)
	(segment
		(start 447.312288 -405.867616)
		(end 447.026538 -406.153366)
		(width 0.13208)
		(layer "F.Cu")
		(net "SMB_LM75_1_SDA")
	)
	(segment
		(start 446.74028 -407.506678)
		(end 446.74028 -406.439624)
		(width 0.13208)
		(layer "F.Cu")
		(net "SMB_LM75_1_SDA")
	)
	(segment
		(start 446.74028 -406.439624)
		(end 447.026538 -406.153366)
		(width 0.13208)
		(layer "F.Cu")
		(net "SMB_LM75_1_SDA")
	)
	(segment
		(start 447.312288 -405.470868)
		(end 447.312288 -405.867616)
		(width 0.13208)
		(layer "F.Cu")
		(net "SMB_LM75_1_SDA")
	)
	(via
		(at 447.026538 -406.153366)
		(size 0.508)
		(drill 0.254)
		(layers "F.Cu" "B.Cu")
		(net "SMB_LM75_1_SDA")
	)
	(via
		(at 31.73095 -289.532314)
		(size 0.508)
		(drill 0.254)
		(layers "F.Cu" "B.Cu")
		(net "PCEPLL4_VDDA18_PEX0_R")
	)
	(segment
		(start 209.00009 -289.630866)
		(end 207.98409 -289.630866)
		(width 0.13208)
		(layer "F.Cu")
		(net "SMB_PEX1_HOST_LS_SCL")
	)
	(segment
		(start 206.96809 -289.630866)
		(end 207.06461 -289.727386)
		(width 0.13208)
		(layer "F.Cu")
		(net "SMB_PEX1_HOST_LS_SCL")
	)
	(segment
		(start 208.484216 -293.980616)
		(end 209.7024 -295.1988)
		(width 0.13208)
		(layer "F.Cu")
		(net "SMB_PEX1_HOST_LS_SCL")
	)
	(segment
		(start 207.06461 -291.297868)
		(end 207.06461 -293.28237)
		(width 0.13208)
		(layer "F.Cu")
		(net "SMB_PEX1_HOST_LS_SCL")
	)
	(segment
		(start 207.06461 -289.727386)
		(end 207.06461 -291.297868)
		(width 0.13208)
		(layer "F.Cu")
		(net "SMB_PEX1_HOST_LS_SCL")
	)
	(segment
		(start 209.575146 -297.9166)
		(end 208.228438 -297.9166)
		(width 0.13208)
		(layer "F.Cu")
		(net "SMB_PEX1_HOST_LS_SCL")
	)
	(segment
		(start 209.7024 -297.789346)
		(end 209.575146 -297.9166)
		(width 0.13208)
		(layer "F.Cu")
		(net "SMB_PEX1_HOST_LS_SCL")
	)
	(segment
		(start 207.06461 -293.28237)
		(end 207.762856 -293.980616)
		(width 0.13208)
		(layer "F.Cu")
		(net "SMB_PEX1_HOST_LS_SCL")
	)
	(segment
		(start 208.228438 -297.9166)
		(end 207.776318 -297.46448)
		(width 0.13208)
		(layer "F.Cu")
		(net "SMB_PEX1_HOST_LS_SCL")
	)
	(segment
		(start 209.7024 -295.1988)
		(end 209.7024 -297.789346)
		(width 0.13208)
		(layer "F.Cu")
		(net "SMB_PEX1_HOST_LS_SCL")
	)
	(segment
		(start 207.98409 -289.630866)
		(end 206.96809 -289.630866)
		(width 0.13208)
		(layer "F.Cu")
		(net "SMB_PEX1_HOST_LS_SCL")
	)
	(segment
		(start 207.762856 -293.980616)
		(end 208.484216 -293.980616)
		(width 0.13208)
		(layer "F.Cu")
		(net "SMB_PEX1_HOST_LS_SCL")
	)
	(via
		(at 207.762856 -293.980616)
		(size 0.508)
		(drill 0.254)
		(layers "F.Cu" "B.Cu")
		(net "SMB_PEX1_HOST_LS_SCL")
	)
	(segment
		(start 360.120438 -223.393254)
		(end 358.539796 -223.393254)
		(width 0.13208)
		(layer "F.Cu")
		(net "NIC3_CLK_EN_R_N")
	)
	(segment
		(start 176.068736 -177.061876)
		(end 176.063402 -177.056542)
		(width 0.13208)
		(layer "F.Cu")
		(net "NIC3_CLK_EN_R_N")
	)
	(segment
		(start 358.539796 -223.393254)
		(end 358.41305 -223.52)
		(width 0.13208)
		(layer "F.Cu")
		(net "NIC3_CLK_EN_R_N")
	)
	(segment
		(start 177.746406 -177.061876)
		(end 176.068736 -177.061876)
		(width 0.13208)
		(layer "F.Cu")
		(net "NIC3_CLK_EN_R_N")
	)
	(segment
		(start 177.746406 -177.061876)
		(end 178.73472 -177.061876)
		(width 0.13208)
		(layer "F.Cu")
		(net "NIC3_CLK_EN_R_N")
	)
	(via
		(at 178.73472 -177.061876)
		(size 0.508)
		(drill 0.254)
		(layers "F.Cu" "B.Cu")
		(net "NIC3_CLK_EN_R_N")
	)
	(via
		(at 296.19321 -182.491126)
		(size 0.508)
		(drill 0.254)
		(layers "F.Cu" "B.Cu")
		(net "NIC3_CLK_EN_R_N")
	)
	(via
		(at 360.120438 -223.393254)
		(size 0.508)
		(drill 0.254)
		(layers "F.Cu" "B.Cu")
		(net "NIC3_CLK_EN_R_N")
	)
	(segment
		(start 228.954838 -172.720762)
		(end 230.6066 -171.069)
		(width 0.15494)
		(layer "In13.Cu")
		(net "NIC3_CLK_EN_R_N")
	)
	(segment
		(start 291.984684 -178.2826)
		(end 296.19321 -182.491126)
		(width 0.15494)
		(layer "In13.Cu")
		(net "NIC3_CLK_EN_R_N")
	)
	(segment
		(start 263.508998 -169.926)
		(end 271.865598 -178.2826)
		(width 0.15494)
		(layer "In13.Cu")
		(net "NIC3_CLK_EN_R_N")
	)
	(segment
		(start 271.865598 -178.2826)
		(end 291.984684 -178.2826)
		(width 0.15494)
		(layer "In13.Cu")
		(net "NIC3_CLK_EN_R_N")
	)
	(segment
		(start 248.970546 -169.926)
		(end 263.508998 -169.926)
		(width 0.15494)
		(layer "In13.Cu")
		(net "NIC3_CLK_EN_R_N")
	)
	(segment
		(start 230.6066 -171.069)
		(end 247.827546 -171.069)
		(width 0.15494)
		(layer "In13.Cu")
		(net "NIC3_CLK_EN_R_N")
	)
	(segment
		(start 180.079396 -175.7172)
		(end 209.601054 -175.7172)
		(width 0.15494)
		(layer "In13.Cu")
		(net "NIC3_CLK_EN_R_N")
	)
	(segment
		(start 178.73472 -177.061876)
		(end 180.079396 -175.7172)
		(width 0.15494)
		(layer "In13.Cu")
		(net "NIC3_CLK_EN_R_N")
	)
	(segment
		(start 212.597492 -172.720762)
		(end 228.954838 -172.720762)
		(width 0.15494)
		(layer "In13.Cu")
		(net "NIC3_CLK_EN_R_N")
	)
	(segment
		(start 247.827546 -171.069)
		(end 248.970546 -169.926)
		(width 0.15494)
		(layer "In13.Cu")
		(net "NIC3_CLK_EN_R_N")
	)
	(segment
		(start 209.601054 -175.7172)
		(end 212.597492 -172.720762)
		(width 0.15494)
		(layer "In13.Cu")
		(net "NIC3_CLK_EN_R_N")
	)
	(segment
		(start 359.612692 -197.743318)
		(end 361.86491 -199.995536)
		(width 0.15494)
		(layer "In15.Cu")
		(net "NIC3_CLK_EN_R_N")
	)
	(segment
		(start 297.635168 -183.933084)
		(end 334.431386 -183.933084)
		(width 0.15494)
		(layer "In15.Cu")
		(net "NIC3_CLK_EN_R_N")
	)
	(segment
		(start 361.86491 -219.357448)
		(end 360.530902 -222.578676)
		(width 0.15494)
		(layer "In15.Cu")
		(net "NIC3_CLK_EN_R_N")
	)
	(segment
		(start 340.73084 -183.445912)
		(end 341.821008 -184.53608)
		(width 0.15494)
		(layer "In15.Cu")
		(net "NIC3_CLK_EN_R_N")
	)
	(segment
		(start 360.501184 -222.650304)
		(end 360.120438 -223.03105)
		(width 0.15494)
		(layer "In15.Cu")
		(net "NIC3_CLK_EN_R_N")
	)
	(segment
		(start 334.82534 -183.53913)
		(end 335.641696 -183.53913)
		(width 0.15494)
		(layer "In15.Cu")
		(net "NIC3_CLK_EN_R_N")
	)
	(segment
		(start 353.526852 -184.53608)
		(end 357.736902 -188.74613)
		(width 0.15494)
		(layer "In15.Cu")
		(net "NIC3_CLK_EN_R_N")
	)
	(segment
		(start 361.86491 -199.995536)
		(end 361.86491 -219.357448)
		(width 0.15494)
		(layer "In15.Cu")
		(net "NIC3_CLK_EN_R_N")
	)
	(segment
		(start 341.821008 -184.53608)
		(end 353.526852 -184.53608)
		(width 0.15494)
		(layer "In15.Cu")
		(net "NIC3_CLK_EN_R_N")
	)
	(segment
		(start 296.19321 -182.491126)
		(end 297.635168 -183.933084)
		(width 0.15494)
		(layer "In15.Cu")
		(net "NIC3_CLK_EN_R_N")
	)
	(segment
		(start 335.641696 -183.53913)
		(end 335.734914 -183.445912)
		(width 0.15494)
		(layer "In15.Cu")
		(net "NIC3_CLK_EN_R_N")
	)
	(segment
		(start 360.120438 -223.03105)
		(end 360.120438 -223.393254)
		(width 0.15494)
		(layer "In15.Cu")
		(net "NIC3_CLK_EN_R_N")
	)
	(segment
		(start 358.34066 -188.74613)
		(end 359.612692 -190.018162)
		(width 0.15494)
		(layer "In15.Cu")
		(net "NIC3_CLK_EN_R_N")
	)
	(segment
		(start 357.736902 -188.74613)
		(end 358.34066 -188.74613)
		(width 0.15494)
		(layer "In15.Cu")
		(net "NIC3_CLK_EN_R_N")
	)
	(segment
		(start 335.734914 -183.445912)
		(end 340.73084 -183.445912)
		(width 0.15494)
		(layer "In15.Cu")
		(net "NIC3_CLK_EN_R_N")
	)
	(segment
		(start 359.612692 -190.018162)
		(end 359.612692 -197.743318)
		(width 0.15494)
		(layer "In15.Cu")
		(net "NIC3_CLK_EN_R_N")
	)
	(segment
		(start 360.530902 -222.578676)
		(end 360.501184 -222.650304)
		(width 0.15494)
		(layer "In15.Cu")
		(net "NIC3_CLK_EN_R_N")
	)
	(segment
		(start 334.431386 -183.933084)
		(end 334.82534 -183.53913)
		(width 0.15494)
		(layer "In15.Cu")
		(net "NIC3_CLK_EN_R_N")
	)
	(segment
		(start 250.587256 -195.173346)
		(end 250.94946 -195.173346)
		(width 0.13208)
		(layer "F.Cu")
		(net "JTAG_BIC_TCK_R")
	)
	(segment
		(start 250.026678 -195.733924)
		(end 250.587256 -195.173346)
		(width 0.13208)
		(layer "F.Cu")
		(net "JTAG_BIC_TCK_R")
	)
	(segment
		(start 250.026678 -197.49897)
		(end 250.026678 -195.733924)
		(width 0.13208)
		(layer "F.Cu")
		(net "JTAG_BIC_TCK_R")
	)
	(via
		(at 250.026678 -197.49897)
		(size 0.508)
		(drill 0.254)
		(layers "F.Cu" "B.Cu")
		(net "JTAG_BIC_TCK_R")
	)
	(via
		(at 230.597964 -202.075288)
		(size 0.508)
		(drill 0.254)
		(layers "F.Cu" "B.Cu")
		(net "JTAG_BIC_TCK_R")
	)
	(segment
		(start 228.055424 -204.260958)
		(end 228.055424 -203.261976)
		(width 0.13208)
		(layer "B.Cu")
		(net "JTAG_BIC_TCK_R")
	)
	(segment
		(start 227.549964 -206.191358)
		(end 227.549964 -208.38541)
		(width 0.13208)
		(layer "B.Cu")
		(net "JTAG_BIC_TCK_R")
	)
	(segment
		(start 228.534976 -202.782424)
		(end 229.890828 -202.782424)
		(width 0.13208)
		(layer "B.Cu")
		(net "JTAG_BIC_TCK_R")
	)
	(segment
		(start 250.089162 -195.938394)
		(end 250.758706 -195.26885)
		(width 0.13208)
		(layer "B.Cu")
		(net "JTAG_BIC_TCK_R")
	)
	(segment
		(start 228.068378 -205.672944)
		(end 227.549964 -206.191358)
		(width 0.13208)
		(layer "B.Cu")
		(net "JTAG_BIC_TCK_R")
	)
	(segment
		(start 228.055424 -203.261976)
		(end 228.534976 -202.782424)
		(width 0.13208)
		(layer "B.Cu")
		(net "JTAG_BIC_TCK_R")
	)
	(segment
		(start 229.890828 -202.782424)
		(end 230.597964 -202.075288)
		(width 0.13208)
		(layer "B.Cu")
		(net "JTAG_BIC_TCK_R")
	)
	(segment
		(start 228.436424 -204.951076)
		(end 228.068378 -205.319122)
		(width 0.13208)
		(layer "B.Cu")
		(net "JTAG_BIC_TCK_R")
	)
	(segment
		(start 228.578664 -204.84211)
		(end 228.578664 -204.784198)
		(width 0.13208)
		(layer "B.Cu")
		(net "JTAG_BIC_TCK_R")
	)
	(segment
		(start 250.026678 -197.49897)
		(end 250.089162 -197.436486)
		(width 0.13208)
		(layer "B.Cu")
		(net "JTAG_BIC_TCK_R")
	)
	(segment
		(start 228.469698 -204.951076)
		(end 228.436424 -204.951076)
		(width 0.13208)
		(layer "B.Cu")
		(net "JTAG_BIC_TCK_R")
	)
	(segment
		(start 250.089162 -197.436486)
		(end 250.089162 -195.938394)
		(width 0.13208)
		(layer "B.Cu")
		(net "JTAG_BIC_TCK_R")
	)
	(segment
		(start 228.578664 -204.784198)
		(end 228.055424 -204.260958)
		(width 0.13208)
		(layer "B.Cu")
		(net "JTAG_BIC_TCK_R")
	)
	(segment
		(start 250.758706 -195.26885)
		(end 251.430536 -195.26885)
		(width 0.13208)
		(layer "B.Cu")
		(net "JTAG_BIC_TCK_R")
	)
	(segment
		(start 228.068378 -205.319122)
		(end 228.068378 -205.672944)
		(width 0.13208)
		(layer "B.Cu")
		(net "JTAG_BIC_TCK_R")
	)
	(segment
		(start 228.578664 -204.84211)
		(end 228.469698 -204.951076)
		(width 0.13208)
		(layer "B.Cu")
		(net "JTAG_BIC_TCK_R")
	)
	(segment
		(start 247.700038 -195.17233)
		(end 240.53292 -195.17233)
		(width 0.15494)
		(layer "In15.Cu")
		(net "JTAG_BIC_TCK_R")
	)
	(segment
		(start 235.109512 -200.33742)
		(end 232.335832 -200.33742)
		(width 0.15494)
		(layer "In15.Cu")
		(net "JTAG_BIC_TCK_R")
	)
	(segment
		(start 232.335832 -200.33742)
		(end 230.597964 -202.075288)
		(width 0.15494)
		(layer "In15.Cu")
		(net "JTAG_BIC_TCK_R")
	)
	(segment
		(start 237.201202 -198.504048)
		(end 237.195614 -198.507858)
		(width 0.15494)
		(layer "In15.Cu")
		(net "JTAG_BIC_TCK_R")
	)
	(segment
		(start 240.53292 -195.17233)
		(end 237.201202 -198.504048)
		(width 0.15494)
		(layer "In15.Cu")
		(net "JTAG_BIC_TCK_R")
	)
	(segment
		(start 237.195614 -198.507858)
		(end 236.389418 -199.057514)
		(width 0.15494)
		(layer "In15.Cu")
		(net "JTAG_BIC_TCK_R")
	)
	(segment
		(start 250.026678 -197.49897)
		(end 247.700038 -195.17233)
		(width 0.15494)
		(layer "In15.Cu")
		(net "JTAG_BIC_TCK_R")
	)
	(segment
		(start 236.389418 -199.057514)
		(end 235.109512 -200.33742)
		(width 0.15494)
		(layer "In15.Cu")
		(net "JTAG_BIC_TCK_R")
	)
	(segment
		(start 101.741732 -395.791436)
		(end 101.113844 -395.791436)
		(width 0.13208)
		(layer "F.Cu")
		(net "BIC_USB_HUB_OVCUR3")
	)
	(segment
		(start 102.376986 -395.156182)
		(end 101.741732 -395.791436)
		(width 0.13208)
		(layer "F.Cu")
		(net "BIC_USB_HUB_OVCUR3")
	)
	(segment
		(start 100.531676 -397.112236)
		(end 100.955094 -397.112236)
		(width 0.13208)
		(layer "F.Cu")
		(net "BIC_USB_HUB_OVCUR3")
	)
	(segment
		(start 101.113844 -395.791436)
		(end 100.405184 -396.500096)
		(width 0.13208)
		(layer "F.Cu")
		(net "BIC_USB_HUB_OVCUR3")
	)
	(segment
		(start 100.405184 -396.500096)
		(end 100.405184 -396.985744)
		(width 0.13208)
		(layer "F.Cu")
		(net "BIC_USB_HUB_OVCUR3")
	)
	(segment
		(start 102.376986 -394.566902)
		(end 102.376986 -395.156182)
		(width 0.13208)
		(layer "F.Cu")
		(net "BIC_USB_HUB_OVCUR3")
	)
	(segment
		(start 100.405184 -396.985744)
		(end 100.531676 -397.112236)
		(width 0.13208)
		(layer "F.Cu")
		(net "BIC_USB_HUB_OVCUR3")
	)
	(via
		(at 100.405184 -396.500096)
		(size 0.508)
		(drill 0.254)
		(layers "F.Cu" "B.Cu")
		(net "BIC_USB_HUB_OVCUR3")
	)
	(via
		(at 31.73095 -283.131514)
		(size 0.508)
		(drill 0.254)
		(layers "F.Cu" "B.Cu")
		(net "PCEPLL7_VDDA18_PEX0_R")
	)
	(segment
		(start 180.02504 -307.774594)
		(end 179.55006 -308.249828)
		(width 0.13208)
		(layer "F.Cu")
		(net "I2C0_PEX1_SHPC_SCL")
	)
	(segment
		(start 208.487264 -301.050452)
		(end 209.173064 -301.050452)
		(width 0.13208)
		(layer "F.Cu")
		(net "I2C0_PEX1_SHPC_SCL")
	)
	(via
		(at 209.173064 -301.050452)
		(size 0.508)
		(drill 0.254)
		(layers "F.Cu" "B.Cu")
		(net "I2C0_PEX1_SHPC_SCL")
	)
	(via
		(at 180.02504 -307.774594)
		(size 0.4064)
		(drill 0.2032)
		(layers "F.Cu" "B.Cu")
		(net "I2C0_PEX1_SHPC_SCL")
	)
	(segment
		(start 207.499712 -299.991272)
		(end 208.558892 -301.050452)
		(width 0.15494)
		(layer "In5.Cu")
		(net "I2C0_PEX1_SHPC_SCL")
	)
	(segment
		(start 180.46319 -307.299868)
		(end 184.159398 -307.299868)
		(width 0.15494)
		(layer "In5.Cu")
		(net "I2C0_PEX1_SHPC_SCL")
	)
	(segment
		(start 184.277508 -307.181758)
		(end 184.277508 -306.534566)
		(width 0.15494)
		(layer "In5.Cu")
		(net "I2C0_PEX1_SHPC_SCL")
	)
	(segment
		(start 189.12967 -299.81398)
		(end 189.29985 -299.6438)
		(width 0.15494)
		(layer "In5.Cu")
		(net "I2C0_PEX1_SHPC_SCL")
	)
	(segment
		(start 189.764924 -299.6438)
		(end 190.248794 -299.15993)
		(width 0.15494)
		(layer "In5.Cu")
		(net "I2C0_PEX1_SHPC_SCL")
	)
	(segment
		(start 180.02504 -307.774594)
		(end 180.02504 -307.738018)
		(width 0.15494)
		(layer "In5.Cu")
		(net "I2C0_PEX1_SHPC_SCL")
	)
	(segment
		(start 204.357732 -299.128688)
		(end 204.678534 -299.128688)
		(width 0.15494)
		(layer "In5.Cu")
		(net "I2C0_PEX1_SHPC_SCL")
	)
	(segment
		(start 208.558892 -301.050452)
		(end 209.173064 -301.050452)
		(width 0.15494)
		(layer "In5.Cu")
		(net "I2C0_PEX1_SHPC_SCL")
	)
	(segment
		(start 199.750172 -299.2882)
		(end 204.19822 -299.2882)
		(width 0.15494)
		(layer "In5.Cu")
		(net "I2C0_PEX1_SHPC_SCL")
	)
	(segment
		(start 204.19822 -299.2882)
		(end 204.357732 -299.128688)
		(width 0.15494)
		(layer "In5.Cu")
		(net "I2C0_PEX1_SHPC_SCL")
	)
	(segment
		(start 184.159398 -307.299868)
		(end 184.277508 -307.181758)
		(width 0.15494)
		(layer "In5.Cu")
		(net "I2C0_PEX1_SHPC_SCL")
	)
	(segment
		(start 185.263028 -306.126896)
		(end 185.263028 -305.517296)
		(width 0.15494)
		(layer "In5.Cu")
		(net "I2C0_PEX1_SHPC_SCL")
	)
	(segment
		(start 185.065924 -306.324)
		(end 185.263028 -306.126896)
		(width 0.15494)
		(layer "In5.Cu")
		(net "I2C0_PEX1_SHPC_SCL")
	)
	(segment
		(start 188.116718 -305.710336)
		(end 188.116718 -306.198016)
		(width 0.15494)
		(layer "In5.Cu")
		(net "I2C0_PEX1_SHPC_SCL")
	)
	(segment
		(start 188.116718 -306.198016)
		(end 188.242702 -306.324)
		(width 0.15494)
		(layer "In5.Cu")
		(net "I2C0_PEX1_SHPC_SCL")
	)
	(segment
		(start 189.29985 -299.6438)
		(end 189.764924 -299.6438)
		(width 0.15494)
		(layer "In5.Cu")
		(net "I2C0_PEX1_SHPC_SCL")
	)
	(segment
		(start 204.678534 -299.128688)
		(end 205.541118 -299.991272)
		(width 0.15494)
		(layer "In5.Cu")
		(net "I2C0_PEX1_SHPC_SCL")
	)
	(segment
		(start 190.248794 -299.15993)
		(end 191.833246 -299.15993)
		(width 0.15494)
		(layer "In5.Cu")
		(net "I2C0_PEX1_SHPC_SCL")
	)
	(segment
		(start 188.242702 -306.324)
		(end 188.735462 -306.324)
		(width 0.15494)
		(layer "In5.Cu")
		(net "I2C0_PEX1_SHPC_SCL")
	)
	(segment
		(start 199.22363 -298.761658)
		(end 199.750172 -299.2882)
		(width 0.15494)
		(layer "In5.Cu")
		(net "I2C0_PEX1_SHPC_SCL")
	)
	(segment
		(start 180.02504 -307.738018)
		(end 180.46319 -307.299868)
		(width 0.15494)
		(layer "In5.Cu")
		(net "I2C0_PEX1_SHPC_SCL")
	)
	(segment
		(start 188.735462 -306.324)
		(end 189.12967 -305.929792)
		(width 0.15494)
		(layer "In5.Cu")
		(net "I2C0_PEX1_SHPC_SCL")
	)
	(segment
		(start 187.750196 -305.343814)
		(end 188.116718 -305.710336)
		(width 0.15494)
		(layer "In5.Cu")
		(net "I2C0_PEX1_SHPC_SCL")
	)
	(segment
		(start 205.541118 -299.991272)
		(end 207.499712 -299.991272)
		(width 0.15494)
		(layer "In5.Cu")
		(net "I2C0_PEX1_SHPC_SCL")
	)
	(segment
		(start 189.12967 -305.929792)
		(end 189.12967 -299.81398)
		(width 0.15494)
		(layer "In5.Cu")
		(net "I2C0_PEX1_SHPC_SCL")
	)
	(segment
		(start 192.231518 -298.761658)
		(end 199.22363 -298.761658)
		(width 0.15494)
		(layer "In5.Cu")
		(net "I2C0_PEX1_SHPC_SCL")
	)
	(segment
		(start 185.43651 -305.343814)
		(end 187.750196 -305.343814)
		(width 0.15494)
		(layer "In5.Cu")
		(net "I2C0_PEX1_SHPC_SCL")
	)
	(segment
		(start 185.263028 -305.517296)
		(end 185.43651 -305.343814)
		(width 0.15494)
		(layer "In5.Cu")
		(net "I2C0_PEX1_SHPC_SCL")
	)
	(segment
		(start 184.488074 -306.324)
		(end 185.065924 -306.324)
		(width 0.15494)
		(layer "In5.Cu")
		(net "I2C0_PEX1_SHPC_SCL")
	)
	(segment
		(start 191.833246 -299.15993)
		(end 192.231518 -298.761658)
		(width 0.15494)
		(layer "In5.Cu")
		(net "I2C0_PEX1_SHPC_SCL")
	)
	(segment
		(start 184.277508 -306.534566)
		(end 184.488074 -306.324)
		(width 0.15494)
		(layer "In5.Cu")
		(net "I2C0_PEX1_SHPC_SCL")
	)
	(segment
		(start 208.274158 -82.460592)
		(end 211.572094 -82.460592)
		(width 0.13208)
		(layer "F.Cu")
		(net "SSD2_LED")
	)
	(segment
		(start 207.023208 -82.643472)
		(end 207.511904 -82.643472)
		(width 0.13208)
		(layer "F.Cu")
		(net "SSD2_LED")
	)
	(segment
		(start 207.511904 -82.643472)
		(end 207.694784 -82.460592)
		(width 0.13208)
		(layer "F.Cu")
		(net "SSD2_LED")
	)
	(segment
		(start 207.694784 -82.460592)
		(end 208.274158 -82.460592)
		(width 0.13208)
		(layer "F.Cu")
		(net "SSD2_LED")
	)
	(via
		(at 208.274158 -82.460592)
		(size 0.762)
		(drill 0.381)
		(layers "F.Cu" "B.Cu")
		(net "SSD2_LED")
	)
	(segment
		(start 107.860846 -392.509248)
		(end 107.686348 -392.33475)
		(width 0.13208)
		(layer "F.Cu")
		(net "BIC_USB_HUB_XOUT")
	)
	(segment
		(start 107.860846 -392.778488)
		(end 107.860846 -392.509248)
		(width 0.13208)
		(layer "F.Cu")
		(net "BIC_USB_HUB_XOUT")
	)
	(segment
		(start 106.678984 -392.33475)
		(end 106.498644 -392.15441)
		(width 0.13208)
		(layer "F.Cu")
		(net "BIC_USB_HUB_XOUT")
	)
	(segment
		(start 107.686348 -392.33475)
		(end 107.049316 -392.33475)
		(width 0.13208)
		(layer "F.Cu")
		(net "BIC_USB_HUB_XOUT")
	)
	(segment
		(start 106.498644 -392.15441)
		(end 105.789476 -392.15441)
		(width 0.13208)
		(layer "F.Cu")
		(net "BIC_USB_HUB_XOUT")
	)
	(segment
		(start 107.049316 -392.33475)
		(end 106.678984 -392.33475)
		(width 0.13208)
		(layer "F.Cu")
		(net "BIC_USB_HUB_XOUT")
	)
	(via
		(at 107.049316 -392.33475)
		(size 0.508)
		(drill 0.254)
		(layers "F.Cu" "B.Cu")
		(net "BIC_USB_HUB_XOUT")
	)
	(segment
		(start 21.257006 -412.682944)
		(end 20.901914 -413.038036)
		(width 0.13208)
		(layer "F.Cu")
		(net "LM75_0_A2")
	)
	(segment
		(start 21.917914 -413.569658)
		(end 20.901914 -413.569658)
		(width 0.13208)
		(layer "F.Cu")
		(net "LM75_0_A2")
	)
	(segment
		(start 20.901914 -413.038036)
		(end 20.901914 -413.569658)
		(width 0.13208)
		(layer "F.Cu")
		(net "LM75_0_A2")
	)
	(segment
		(start 21.257006 -411.155134)
		(end 21.257006 -412.682944)
		(width 0.13208)
		(layer "F.Cu")
		(net "LM75_0_A2")
	)
	(via
		(at 21.257006 -412.682944)
		(size 0.508)
		(drill 0.254)
		(layers "F.Cu" "B.Cu")
		(net "LM75_0_A2")
	)
	(via
		(at 31.73095 -299.133514)
		(size 0.508)
		(drill 0.254)
		(layers "F.Cu" "B.Cu")
		(net "PCEPLL1_VDDA18_PEX0_R")
	)
	(segment
		(start 179.074826 -307.774594)
		(end 178.599846 -308.249828)
		(width 0.13208)
		(layer "F.Cu")
		(net "I2C0_PEX1_SHPC_SDA")
	)
	(segment
		(start 204.601826 -301.55261)
		(end 205.112366 -301.04207)
		(width 0.13208)
		(layer "F.Cu")
		(net "I2C0_PEX1_SHPC_SDA")
	)
	(via
		(at 179.074826 -307.774594)
		(size 0.4064)
		(drill 0.2032)
		(layers "F.Cu" "B.Cu")
		(net "I2C0_PEX1_SHPC_SDA")
	)
	(via
		(at 204.601826 -301.55261)
		(size 0.508)
		(drill 0.254)
		(layers "F.Cu" "B.Cu")
		(net "I2C0_PEX1_SHPC_SDA")
	)
	(segment
		(start 179.55006 -308.249828)
		(end 185.955178 -308.249828)
		(width 0.15494)
		(layer "In5.Cu")
		(net "I2C0_PEX1_SHPC_SDA")
	)
	(segment
		(start 186.185302 -307.511704)
		(end 186.35091 -307.346096)
		(width 0.15494)
		(layer "In5.Cu")
		(net "I2C0_PEX1_SHPC_SDA")
	)
	(segment
		(start 192.830704 -301.631096)
		(end 200.755504 -301.631096)
		(width 0.15494)
		(layer "In5.Cu")
		(net "I2C0_PEX1_SHPC_SDA")
	)
	(segment
		(start 188.707776 -308.26837)
		(end 189.151006 -308.7116)
		(width 0.15494)
		(layer "In5.Cu")
		(net "I2C0_PEX1_SHPC_SDA")
	)
	(segment
		(start 188.084968 -307.448458)
		(end 188.084968 -308.095142)
		(width 0.15494)
		(layer "In5.Cu")
		(net "I2C0_PEX1_SHPC_SDA")
	)
	(segment
		(start 188.258196 -308.26837)
		(end 188.707776 -308.26837)
		(width 0.15494)
		(layer "In5.Cu")
		(net "I2C0_PEX1_SHPC_SDA")
	)
	(segment
		(start 179.074826 -307.774594)
		(end 179.55006 -308.249828)
		(width 0.15494)
		(layer "In5.Cu")
		(net "I2C0_PEX1_SHPC_SDA")
	)
	(segment
		(start 189.151006 -308.7116)
		(end 192.0748 -308.7116)
		(width 0.15494)
		(layer "In5.Cu")
		(net "I2C0_PEX1_SHPC_SDA")
	)
	(segment
		(start 192.405 -302.0568)
		(end 192.830704 -301.631096)
		(width 0.15494)
		(layer "In5.Cu")
		(net "I2C0_PEX1_SHPC_SDA")
	)
	(segment
		(start 203.863448 -301.55261)
		(end 204.601826 -301.55261)
		(width 0.15494)
		(layer "In5.Cu")
		(net "I2C0_PEX1_SHPC_SDA")
	)
	(segment
		(start 186.35091 -307.346096)
		(end 187.982606 -307.346096)
		(width 0.15494)
		(layer "In5.Cu")
		(net "I2C0_PEX1_SHPC_SDA")
	)
	(segment
		(start 192.0748 -308.7116)
		(end 192.405 -308.3814)
		(width 0.15494)
		(layer "In5.Cu")
		(net "I2C0_PEX1_SHPC_SDA")
	)
	(segment
		(start 186.185302 -308.019704)
		(end 186.185302 -307.511704)
		(width 0.15494)
		(layer "In5.Cu")
		(net "I2C0_PEX1_SHPC_SDA")
	)
	(segment
		(start 185.955178 -308.249828)
		(end 186.185302 -308.019704)
		(width 0.15494)
		(layer "In5.Cu")
		(net "I2C0_PEX1_SHPC_SDA")
	)
	(segment
		(start 201.64933 -300.73727)
		(end 203.048108 -300.73727)
		(width 0.15494)
		(layer "In5.Cu")
		(net "I2C0_PEX1_SHPC_SDA")
	)
	(segment
		(start 187.982606 -307.346096)
		(end 188.084968 -307.448458)
		(width 0.15494)
		(layer "In5.Cu")
		(net "I2C0_PEX1_SHPC_SDA")
	)
	(segment
		(start 200.755504 -301.631096)
		(end 201.64933 -300.73727)
		(width 0.15494)
		(layer "In5.Cu")
		(net "I2C0_PEX1_SHPC_SDA")
	)
	(segment
		(start 188.084968 -308.095142)
		(end 188.258196 -308.26837)
		(width 0.15494)
		(layer "In5.Cu")
		(net "I2C0_PEX1_SHPC_SDA")
	)
	(segment
		(start 192.405 -308.3814)
		(end 192.405 -302.0568)
		(width 0.15494)
		(layer "In5.Cu")
		(net "I2C0_PEX1_SHPC_SDA")
	)
	(segment
		(start 203.048108 -300.73727)
		(end 203.863448 -301.55261)
		(width 0.15494)
		(layer "In5.Cu")
		(net "I2C0_PEX1_SHPC_SDA")
	)
	(segment
		(start 253.587504 -205.98638)
		(end 253.587504 -204.79893)
		(width 0.13208)
		(layer "F.Cu")
		(net "JTAG_PLD_TDO")
	)
	(via
		(at 253.587504 -204.72019)
		(size 0.7112)
		(drill 0.3556)
		(layers "F.Cu" "B.Cu")
		(net "JTAG_PLD_TDO")
	)
	(via
		(at 253.587504 -205.98638)
		(size 0.508)
		(drill 0.254)
		(layers "F.Cu" "B.Cu")
		(net "JTAG_PLD_TDO")
	)
	(segment
		(start 254.125476 -203.57465)
		(end 253.587504 -204.112622)
		(width 0.13208)
		(layer "B.Cu")
		(net "JTAG_PLD_TDO")
	)
	(segment
		(start 253.587504 -204.112622)
		(end 253.587504 -204.72019)
		(width 0.13208)
		(layer "B.Cu")
		(net "JTAG_PLD_TDO")
	)
	(segment
		(start 254.616204 -203.57465)
		(end 254.125476 -203.57465)
		(width 0.13208)
		(layer "B.Cu")
		(net "JTAG_PLD_TDO")
	)
	(segment
		(start 253.587504 -204.72019)
		(end 253.587504 -205.98638)
		(width 0.13208)
		(layer "B.Cu")
		(net "JTAG_PLD_TDO")
	)
	(segment
		(start 208.400904 -79.595472)
		(end 209.315812 -80.51038)
		(width 0.13208)
		(layer "F.Cu")
		(net "SSD5_LED")
	)
	(segment
		(start 209.315812 -80.51038)
		(end 211.572094 -80.51038)
		(width 0.13208)
		(layer "F.Cu")
		(net "SSD5_LED")
	)
	(segment
		(start 207.023208 -79.595472)
		(end 207.633824 -79.595472)
		(width 0.13208)
		(layer "F.Cu")
		(net "SSD5_LED")
	)
	(segment
		(start 207.633824 -79.595472)
		(end 208.400904 -79.595472)
		(width 0.13208)
		(layer "F.Cu")
		(net "SSD5_LED")
	)
	(via
		(at 207.633824 -79.595472)
		(size 0.508)
		(drill 0.254)
		(layers "F.Cu" "B.Cu")
		(net "SSD5_LED")
	)
	(segment
		(start 102.995984 -396.500096)
		(end 103.376984 -396.119096)
		(width 0.13208)
		(layer "F.Cu")
		(net "BIC_USB_HUB_TEST")
	)
	(segment
		(start 103.376984 -396.119096)
		(end 103.376984 -394.566902)
		(width 0.13208)
		(layer "F.Cu")
		(net "BIC_USB_HUB_TEST")
	)
	(segment
		(start 102.987094 -396.508986)
		(end 102.995984 -396.500096)
		(width 0.13208)
		(layer "F.Cu")
		(net "BIC_USB_HUB_TEST")
	)
	(segment
		(start 102.987094 -397.112236)
		(end 102.987094 -396.508986)
		(width 0.13208)
		(layer "F.Cu")
		(net "BIC_USB_HUB_TEST")
	)
	(via
		(at 102.995984 -396.500096)
		(size 0.508)
		(drill 0.254)
		(layers "F.Cu" "B.Cu")
		(net "BIC_USB_HUB_TEST")
	)
	(segment
		(start 19.885914 -412.938722)
		(end 19.885914 -413.569658)
		(width 0.13208)
		(layer "F.Cu")
		(net "LM75_0_A1")
	)
	(segment
		(start 19.885914 -412.417514)
		(end 19.885914 -412.938722)
		(width 0.13208)
		(layer "F.Cu")
		(net "LM75_0_A1")
	)
	(segment
		(start 18.869914 -413.569658)
		(end 19.885914 -413.569658)
		(width 0.13208)
		(layer "F.Cu")
		(net "LM75_0_A1")
	)
	(segment
		(start 19.987006 -412.316422)
		(end 19.885914 -412.417514)
		(width 0.13208)
		(layer "F.Cu")
		(net "LM75_0_A1")
	)
	(segment
		(start 19.987006 -411.155134)
		(end 19.987006 -412.316422)
		(width 0.13208)
		(layer "F.Cu")
		(net "LM75_0_A1")
	)
	(via
		(at 19.885914 -412.938722)
		(size 0.508)
		(drill 0.254)
		(layers "F.Cu" "B.Cu")
		(net "LM75_0_A1")
	)
	(via
		(at 31.73095 -295.933114)
		(size 0.508)
		(drill 0.254)
		(layers "F.Cu" "B.Cu")
		(net "PCEPLL0_VDDA18_PEX0_R")
	)
	(segment
		(start 201.811382 -305.424332)
		(end 201.811382 -303.724564)
		(width 0.13208)
		(layer "F.Cu")
		(net "SMB_PEX1_SLAVE_SCL")
	)
	(segment
		(start 202.036172 -305.649122)
		(end 201.811382 -305.424332)
		(width 0.13208)
		(layer "F.Cu")
		(net "SMB_PEX1_SLAVE_SCL")
	)
	(segment
		(start 188.574934 -306.824888)
		(end 188.099954 -307.299868)
		(width 0.13208)
		(layer "F.Cu")
		(net "SMB_PEX1_SLAVE_SCL")
	)
	(via
		(at 200.809098 -305.3588)
		(size 0.6604)
		(drill 0.3302)
		(layers "F.Cu" "B.Cu")
		(net "SMB_PEX1_SLAVE_SCL")
	)
	(via
		(at 188.574934 -306.824888)
		(size 0.4064)
		(drill 0.2032)
		(layers "F.Cu" "B.Cu")
		(net "SMB_PEX1_SLAVE_SCL")
	)
	(via
		(at 201.811382 -303.724564)
		(size 0.508)
		(drill 0.254)
		(layers "F.Cu" "B.Cu")
		(net "SMB_PEX1_SLAVE_SCL")
	)
	(segment
		(start 189.507622 -305.8922)
		(end 200.275698 -305.8922)
		(width 0.13208)
		(layer "B.Cu")
		(net "SMB_PEX1_SLAVE_SCL")
	)
	(segment
		(start 201.811382 -304.356516)
		(end 200.809098 -305.3588)
		(width 0.13208)
		(layer "B.Cu")
		(net "SMB_PEX1_SLAVE_SCL")
	)
	(segment
		(start 200.275698 -305.8922)
		(end 200.809098 -305.3588)
		(width 0.13208)
		(layer "B.Cu")
		(net "SMB_PEX1_SLAVE_SCL")
	)
	(segment
		(start 188.574934 -306.824888)
		(end 189.507622 -305.8922)
		(width 0.13208)
		(layer "B.Cu")
		(net "SMB_PEX1_SLAVE_SCL")
	)
	(segment
		(start 201.811382 -303.724564)
		(end 201.811382 -304.356516)
		(width 0.13208)
		(layer "B.Cu")
		(net "SMB_PEX1_SLAVE_SCL")
	)
	(segment
		(start 254.887476 -198.30923)
		(end 255.388618 -197.808088)
		(width 0.13208)
		(layer "F.Cu")
		(net "JTAG_PLD_TMS")
	)
	(segment
		(start 255.388618 -197.808088)
		(end 256.705354 -197.808088)
		(width 0.13208)
		(layer "F.Cu")
		(net "JTAG_PLD_TMS")
	)
	(segment
		(start 256.705354 -197.808088)
		(end 257.22453 -197.288912)
		(width 0.13208)
		(layer "F.Cu")
		(net "JTAG_PLD_TMS")
	)
	(segment
		(start 256.02946 -196.093842)
		(end 256.02946 -195.973446)
		(width 0.13208)
		(layer "F.Cu")
		(net "JTAG_PLD_TMS")
	)
	(segment
		(start 257.22453 -197.288912)
		(end 256.02946 -196.093842)
		(width 0.13208)
		(layer "F.Cu")
		(net "JTAG_PLD_TMS")
	)
	(segment
		(start 254.887476 -198.95693)
		(end 254.887476 -198.30923)
		(width 0.13208)
		(layer "F.Cu")
		(net "JTAG_PLD_TMS")
	)
	(via
		(at 257.22453 -197.288912)
		(size 0.508)
		(drill 0.254)
		(layers "F.Cu" "B.Cu")
		(net "JTAG_PLD_TMS")
	)
	(segment
		(start 208.401158 -77.563472)
		(end 208.782158 -77.944472)
		(width 0.13208)
		(layer "F.Cu")
		(net "SSD7_LED")
	)
	(segment
		(start 210.429094 -79.210408)
		(end 211.572094 -79.210408)
		(width 0.13208)
		(layer "F.Cu")
		(net "SSD7_LED")
	)
	(segment
		(start 207.023208 -77.563472)
		(end 207.633824 -77.563472)
		(width 0.13208)
		(layer "F.Cu")
		(net "SSD7_LED")
	)
	(segment
		(start 209.163158 -77.944472)
		(end 210.429094 -79.210408)
		(width 0.13208)
		(layer "F.Cu")
		(net "SSD7_LED")
	)
	(segment
		(start 208.782158 -77.944472)
		(end 209.163158 -77.944472)
		(width 0.13208)
		(layer "F.Cu")
		(net "SSD7_LED")
	)
	(segment
		(start 207.633824 -77.563472)
		(end 208.401158 -77.563472)
		(width 0.13208)
		(layer "F.Cu")
		(net "SSD7_LED")
	)
	(via
		(at 207.633824 -77.563472)
		(size 0.508)
		(drill 0.254)
		(layers "F.Cu" "B.Cu")
		(net "SSD7_LED")
	)
	(segment
		(start 337.293966 -219.187014)
		(end 336.89417 -218.787218)
		(width 0.13208)
		(layer "F.Cu")
		(net "NIC6_MAIN_PWR_BIC_EN_R")
	)
	(segment
		(start 225.711512 -231.816656)
		(end 225.711512 -232.471468)
		(width 0.13208)
		(layer "F.Cu")
		(net "NIC6_MAIN_PWR_BIC_EN_R")
	)
	(via
		(at 267.692886 -217.289888)
		(size 0.508)
		(drill 0.254)
		(layers "F.Cu" "B.Cu")
		(net "NIC6_MAIN_PWR_BIC_EN_R")
	)
	(via
		(at 225.711512 -232.471468)
		(size 0.508)
		(drill 0.254)
		(layers "F.Cu" "B.Cu")
		(net "NIC6_MAIN_PWR_BIC_EN_R")
	)
	(via
		(at 336.89417 -218.787218)
		(size 0.4572)
		(drill 0.254)
		(layers "F.Cu" "B.Cu")
		(net "NIC6_MAIN_PWR_BIC_EN_R")
	)
	(segment
		(start 260.4516 -222.986346)
		(end 260.4516 -223.646746)
		(width 0.15494)
		(layer "In7.Cu")
		(net "NIC6_MAIN_PWR_BIC_EN_R")
	)
	(segment
		(start 267.692886 -217.289888)
		(end 267.692886 -218.69527)
		(width 0.15494)
		(layer "In7.Cu")
		(net "NIC6_MAIN_PWR_BIC_EN_R")
	)
	(segment
		(start 257.20294 -228.459284)
		(end 257.20294 -229.63124)
		(width 0.15494)
		(layer "In7.Cu")
		(net "NIC6_MAIN_PWR_BIC_EN_R")
	)
	(segment
		(start 226.195382 -233.485182)
		(end 226.195382 -232.982008)
		(width 0.15494)
		(layer "In7.Cu")
		(net "NIC6_MAIN_PWR_BIC_EN_R")
	)
	(segment
		(start 247.269 -239.5474)
		(end 232.2576 -239.5474)
		(width 0.15494)
		(layer "In7.Cu")
		(net "NIC6_MAIN_PWR_BIC_EN_R")
	)
	(segment
		(start 260.4516 -223.646746)
		(end 259.58419 -224.514156)
		(width 0.15494)
		(layer "In7.Cu")
		(net "NIC6_MAIN_PWR_BIC_EN_R")
	)
	(segment
		(start 226.195382 -232.982008)
		(end 225.711512 -232.498138)
		(width 0.15494)
		(layer "In7.Cu")
		(net "NIC6_MAIN_PWR_BIC_EN_R")
	)
	(segment
		(start 259.58419 -225.658934)
		(end 258.265168 -226.977956)
		(width 0.15494)
		(layer "In7.Cu")
		(net "NIC6_MAIN_PWR_BIC_EN_R")
	)
	(segment
		(start 258.265168 -226.977956)
		(end 258.265168 -227.397056)
		(width 0.15494)
		(layer "In7.Cu")
		(net "NIC6_MAIN_PWR_BIC_EN_R")
	)
	(segment
		(start 232.2576 -239.5474)
		(end 226.195382 -233.485182)
		(width 0.15494)
		(layer "In7.Cu")
		(net "NIC6_MAIN_PWR_BIC_EN_R")
	)
	(segment
		(start 247.30964 -239.52454)
		(end 247.29186 -239.52454)
		(width 0.15494)
		(layer "In7.Cu")
		(net "NIC6_MAIN_PWR_BIC_EN_R")
	)
	(segment
		(start 262.727186 -220.71076)
		(end 260.4516 -222.986346)
		(width 0.15494)
		(layer "In7.Cu")
		(net "NIC6_MAIN_PWR_BIC_EN_R")
	)
	(segment
		(start 259.58419 -224.514156)
		(end 259.58419 -225.658934)
		(width 0.15494)
		(layer "In7.Cu")
		(net "NIC6_MAIN_PWR_BIC_EN_R")
	)
	(segment
		(start 258.265168 -227.397056)
		(end 257.20294 -228.459284)
		(width 0.15494)
		(layer "In7.Cu")
		(net "NIC6_MAIN_PWR_BIC_EN_R")
	)
	(segment
		(start 257.20294 -229.63124)
		(end 247.30964 -239.52454)
		(width 0.15494)
		(layer "In7.Cu")
		(net "NIC6_MAIN_PWR_BIC_EN_R")
	)
	(segment
		(start 225.711512 -232.498138)
		(end 225.711512 -232.471468)
		(width 0.15494)
		(layer "In7.Cu")
		(net "NIC6_MAIN_PWR_BIC_EN_R")
	)
	(segment
		(start 267.692886 -218.69527)
		(end 265.677396 -220.71076)
		(width 0.15494)
		(layer "In7.Cu")
		(net "NIC6_MAIN_PWR_BIC_EN_R")
	)
	(segment
		(start 247.29186 -239.52454)
		(end 247.269 -239.5474)
		(width 0.15494)
		(layer "In7.Cu")
		(net "NIC6_MAIN_PWR_BIC_EN_R")
	)
	(segment
		(start 265.677396 -220.71076)
		(end 262.727186 -220.71076)
		(width 0.15494)
		(layer "In7.Cu")
		(net "NIC6_MAIN_PWR_BIC_EN_R")
	)
	(segment
		(start 267.87094 -217.111834)
		(end 286.912558 -217.111834)
		(width 0.15494)
		(layer "In15.Cu")
		(net "NIC6_MAIN_PWR_BIC_EN_R")
	)
	(segment
		(start 322.83019 -214.93607)
		(end 326.72147 -214.93607)
		(width 0.15494)
		(layer "In15.Cu")
		(net "NIC6_MAIN_PWR_BIC_EN_R")
	)
	(segment
		(start 329.8444 -215.6968)
		(end 330.539598 -215.6968)
		(width 0.15494)
		(layer "In15.Cu")
		(net "NIC6_MAIN_PWR_BIC_EN_R")
	)
	(segment
		(start 334.3656 -218.5416)
		(end 334.7212 -218.5416)
		(width 0.0889)
		(layer "In15.Cu")
		(net "NIC6_MAIN_PWR_BIC_EN_R")
	)
	(segment
		(start 336.496152 -218.3892)
		(end 336.89417 -218.787218)
		(width 0.0889)
		(layer "In15.Cu")
		(net "NIC6_MAIN_PWR_BIC_EN_R")
	)
	(segment
		(start 320.28892 -212.3948)
		(end 322.83019 -214.93607)
		(width 0.15494)
		(layer "In15.Cu")
		(net "NIC6_MAIN_PWR_BIC_EN_R")
	)
	(segment
		(start 286.912558 -217.111834)
		(end 291.629592 -212.3948)
		(width 0.15494)
		(layer "In15.Cu")
		(net "NIC6_MAIN_PWR_BIC_EN_R")
	)
	(segment
		(start 327.6854 -216.3064)
		(end 328.1934 -216.8144)
		(width 0.15494)
		(layer "In15.Cu")
		(net "NIC6_MAIN_PWR_BIC_EN_R")
	)
	(segment
		(start 328.9554 -216.8144)
		(end 329.311 -216.4588)
		(width 0.15494)
		(layer "In15.Cu")
		(net "NIC6_MAIN_PWR_BIC_EN_R")
	)
	(segment
		(start 291.629592 -212.3948)
		(end 320.28892 -212.3948)
		(width 0.15494)
		(layer "In15.Cu")
		(net "NIC6_MAIN_PWR_BIC_EN_R")
	)
	(segment
		(start 329.311 -216.4588)
		(end 329.311 -216.2302)
		(width 0.15494)
		(layer "In15.Cu")
		(net "NIC6_MAIN_PWR_BIC_EN_R")
	)
	(segment
		(start 327.6854 -215.9)
		(end 327.6854 -216.3064)
		(width 0.15494)
		(layer "In15.Cu")
		(net "NIC6_MAIN_PWR_BIC_EN_R")
	)
	(segment
		(start 267.692886 -217.289888)
		(end 267.87094 -217.111834)
		(width 0.15494)
		(layer "In15.Cu")
		(net "NIC6_MAIN_PWR_BIC_EN_R")
	)
	(segment
		(start 329.311 -216.2302)
		(end 329.8444 -215.6968)
		(width 0.15494)
		(layer "In15.Cu")
		(net "NIC6_MAIN_PWR_BIC_EN_R")
	)
	(segment
		(start 333.384398 -218.5416)
		(end 334.3656 -218.5416)
		(width 0.15494)
		(layer "In15.Cu")
		(net "NIC6_MAIN_PWR_BIC_EN_R")
	)
	(segment
		(start 334.8736 -218.3892)
		(end 336.496152 -218.3892)
		(width 0.0889)
		(layer "In15.Cu")
		(net "NIC6_MAIN_PWR_BIC_EN_R")
	)
	(segment
		(start 326.72147 -214.93607)
		(end 327.6854 -215.9)
		(width 0.15494)
		(layer "In15.Cu")
		(net "NIC6_MAIN_PWR_BIC_EN_R")
	)
	(segment
		(start 328.1934 -216.8144)
		(end 328.9554 -216.8144)
		(width 0.15494)
		(layer "In15.Cu")
		(net "NIC6_MAIN_PWR_BIC_EN_R")
	)
	(segment
		(start 330.539598 -215.6968)
		(end 333.384398 -218.5416)
		(width 0.15494)
		(layer "In15.Cu")
		(net "NIC6_MAIN_PWR_BIC_EN_R")
	)
	(segment
		(start 334.7212 -218.5416)
		(end 334.8736 -218.3892)
		(width 0.0889)
		(layer "In15.Cu")
		(net "NIC6_MAIN_PWR_BIC_EN_R")
	)
	(segment
		(start 242.321842 -180.633878)
		(end 242.456716 -180.499004)
		(width 0.13208)
		(layer "F.Cu")
		(net "BIC_RST_PWRGD_RSMRST_R")
	)
	(segment
		(start 242.851178 -179.554378)
		(end 243.217954 -179.187602)
		(width 0.13208)
		(layer "F.Cu")
		(net "BIC_RST_PWRGD_RSMRST_R")
	)
	(segment
		(start 242.201954 -178.919378)
		(end 243.217954 -178.919378)
		(width 0.13208)
		(layer "F.Cu")
		(net "BIC_RST_PWRGD_RSMRST_R")
	)
	(segment
		(start 243.217954 -179.187602)
		(end 243.217954 -178.919378)
		(width 0.13208)
		(layer "F.Cu")
		(net "BIC_RST_PWRGD_RSMRST_R")
	)
	(segment
		(start 242.456716 -179.927504)
		(end 242.829842 -179.554378)
		(width 0.13208)
		(layer "F.Cu")
		(net "BIC_RST_PWRGD_RSMRST_R")
	)
	(segment
		(start 242.456716 -180.499004)
		(end 242.456716 -179.927504)
		(width 0.13208)
		(layer "F.Cu")
		(net "BIC_RST_PWRGD_RSMRST_R")
	)
	(segment
		(start 242.829842 -179.554378)
		(end 242.851178 -179.554378)
		(width 0.13208)
		(layer "F.Cu")
		(net "BIC_RST_PWRGD_RSMRST_R")
	)
	(via
		(at 242.829842 -179.554378)
		(size 0.508)
		(drill 0.254)
		(layers "F.Cu" "B.Cu")
		(net "BIC_RST_PWRGD_RSMRST_R")
	)
	(segment
		(start 18.26514 -412.752286)
		(end 17.853914 -413.163512)
		(width 0.13208)
		(layer "F.Cu")
		(net "LM75_0_A0")
	)
	(segment
		(start 18.717006 -411.155134)
		(end 18.717006 -412.30042)
		(width 0.13208)
		(layer "F.Cu")
		(net "LM75_0_A0")
	)
	(segment
		(start 18.717006 -412.30042)
		(end 18.26514 -412.752286)
		(width 0.13208)
		(layer "F.Cu")
		(net "LM75_0_A0")
	)
	(segment
		(start 16.837914 -413.569658)
		(end 17.853914 -413.569658)
		(width 0.13208)
		(layer "F.Cu")
		(net "LM75_0_A0")
	)
	(segment
		(start 17.853914 -413.163512)
		(end 17.853914 -413.569658)
		(width 0.13208)
		(layer "F.Cu")
		(net "LM75_0_A0")
	)
	(via
		(at 18.26514 -412.752286)
		(size 0.508)
		(drill 0.254)
		(layers "F.Cu" "B.Cu")
		(net "LM75_0_A0")
	)
	(segment
		(start 46.8249 -297.32478)
		(end 47.29988 -296.8498)
		(width 0.249936)
		(layer "F.Cu")
		(net "PCEPLL2_VDDA18_PEX0")
	)
	(via
		(at 31.71952 -293.494714)
		(size 0.508)
		(drill 0.254)
		(layers "F.Cu" "B.Cu")
		(net "PCEPLL2_VDDA18_PEX0")
	)
	(via
		(at 33.11652 -293.494714)
		(size 0.508)
		(drill 0.254)
		(layers "F.Cu" "B.Cu")
		(net "PCEPLL2_VDDA18_PEX0")
	)
	(via
		(at 46.8249 -297.32478)
		(size 0.4064)
		(drill 0.2032)
		(layers "F.Cu" "B.Cu")
		(net "PCEPLL2_VDDA18_PEX0")
	)
	(segment
		(start 46.6217 -297.32478)
		(end 46.8249 -297.32478)
		(width 0.3048)
		(layer "B.Cu")
		(net "PCEPLL2_VDDA18_PEX0")
	)
	(segment
		(start 46.8249 -296.57802)
		(end 46.8249 -297.32478)
		(width 0.3048)
		(layer "B.Cu")
		(net "PCEPLL2_VDDA18_PEX0")
	)
	(segment
		(start 46.6217 -296.37482)
		(end 46.8249 -296.57802)
		(width 0.3048)
		(layer "B.Cu")
		(net "PCEPLL2_VDDA18_PEX0")
	)
	(segment
		(start 361.58805 -189.23)
		(end 363.473746 -189.23)
		(width 0.13208)
		(layer "F.Cu")
		(net "SSD2_PEX_PWR_EN")
	)
	(segment
		(start 363.473746 -189.23)
		(end 363.686852 -189.443106)
		(width 0.13208)
		(layer "F.Cu")
		(net "SSD2_PEX_PWR_EN")
	)
	(segment
		(start 363.686852 -189.443106)
		(end 364.020862 -189.443106)
		(width 0.13208)
		(layer "F.Cu")
		(net "SSD2_PEX_PWR_EN")
	)
	(segment
		(start 364.020862 -189.443106)
		(end 366.263936 -189.443106)
		(width 0.13208)
		(layer "F.Cu")
		(net "SSD2_PEX_PWR_EN")
	)
	(via
		(at 364.020862 -189.443106)
		(size 0.508)
		(drill 0.254)
		(layers "F.Cu" "B.Cu")
		(net "SSD2_PEX_PWR_EN")
	)
	(segment
		(start 204.115416 -304.968148)
		(end 204.330808 -304.752756)
		(width 0.13208)
		(layer "F.Cu")
		(net "SMB_PEX1_SLAVE_SDA")
	)
	(segment
		(start 204.115416 -305.6636)
		(end 204.115416 -304.968148)
		(width 0.13208)
		(layer "F.Cu")
		(net "SMB_PEX1_SLAVE_SDA")
	)
	(segment
		(start 188.574934 -308.724808)
		(end 189.049914 -309.199788)
		(width 0.13208)
		(layer "F.Cu")
		(net "SMB_PEX1_SLAVE_SDA")
	)
	(via
		(at 204.330808 -304.752756)
		(size 0.508)
		(drill 0.254)
		(layers "F.Cu" "B.Cu")
		(net "SMB_PEX1_SLAVE_SDA")
	)
	(via
		(at 202.381358 -306.399946)
		(size 0.6604)
		(drill 0.3302)
		(layers "F.Cu" "B.Cu")
		(net "SMB_PEX1_SLAVE_SDA")
	)
	(via
		(at 188.574934 -308.724808)
		(size 0.4064)
		(drill 0.2032)
		(layers "F.Cu" "B.Cu")
		(net "SMB_PEX1_SLAVE_SDA")
	)
	(segment
		(start 200.263252 -307.815234)
		(end 202.381358 -306.399946)
		(width 0.13208)
		(layer "B.Cu")
		(net "SMB_PEX1_SLAVE_SDA")
	)
	(segment
		(start 204.330808 -304.752756)
		(end 203.292202 -305.791362)
		(width 0.13208)
		(layer "B.Cu")
		(net "SMB_PEX1_SLAVE_SDA")
	)
	(segment
		(start 188.574934 -308.724808)
		(end 189.484508 -307.815234)
		(width 0.13208)
		(layer "B.Cu")
		(net "SMB_PEX1_SLAVE_SDA")
	)
	(segment
		(start 203.292202 -305.791362)
		(end 202.381358 -306.399946)
		(width 0.13208)
		(layer "B.Cu")
		(net "SMB_PEX1_SLAVE_SDA")
	)
	(segment
		(start 189.484508 -307.815234)
		(end 200.263252 -307.815234)
		(width 0.13208)
		(layer "B.Cu")
		(net "SMB_PEX1_SLAVE_SDA")
	)
	(segment
		(start 207.47228 -81.1784)
		(end 207.023208 -81.627472)
		(width 0.13208)
		(layer "F.Cu")
		(net "SSD3_LED")
	)
	(segment
		(start 208.175352 -81.810352)
		(end 207.5434 -81.1784)
		(width 0.13208)
		(layer "F.Cu")
		(net "SSD3_LED")
	)
	(segment
		(start 211.572094 -81.810352)
		(end 208.175352 -81.810352)
		(width 0.13208)
		(layer "F.Cu")
		(net "SSD3_LED")
	)
	(segment
		(start 207.5434 -81.1784)
		(end 207.47228 -81.1784)
		(width 0.13208)
		(layer "F.Cu")
		(net "SSD3_LED")
	)
	(via
		(at 207.5434 -81.1784)
		(size 0.508)
		(drill 0.254)
		(layers "F.Cu" "B.Cu")
		(net "SSD3_LED")
	)
	(segment
		(start 226.727512 -231.816656)
		(end 226.727512 -232.471468)
		(width 0.13208)
		(layer "F.Cu")
		(net "NIC4_MAIN_PWR_BIC_EN_R")
	)
	(segment
		(start 347.693742 -215.187022)
		(end 348.093538 -214.787226)
		(width 0.13208)
		(layer "F.Cu")
		(net "NIC4_MAIN_PWR_BIC_EN_R")
	)
	(via
		(at 348.093538 -214.787226)
		(size 0.4572)
		(drill 0.254)
		(layers "F.Cu" "B.Cu")
		(net "NIC4_MAIN_PWR_BIC_EN_R")
	)
	(via
		(at 267.335 -213.6648)
		(size 0.508)
		(drill 0.254)
		(layers "F.Cu" "B.Cu")
		(net "NIC4_MAIN_PWR_BIC_EN_R")
	)
	(via
		(at 226.727512 -232.471468)
		(size 0.508)
		(drill 0.254)
		(layers "F.Cu" "B.Cu")
		(net "NIC4_MAIN_PWR_BIC_EN_R")
	)
	(segment
		(start 257.76682 -225.82378)
		(end 260.0452 -223.5454)
		(width 0.15494)
		(layer "In7.Cu")
		(net "NIC4_MAIN_PWR_BIC_EN_R")
	)
	(segment
		(start 256.8448 -229.48265)
		(end 256.8448 -228.310694)
		(width 0.15494)
		(layer "In7.Cu")
		(net "NIC4_MAIN_PWR_BIC_EN_R")
	)
	(segment
		(start 232.588054 -239.1664)
		(end 247.16105 -239.1664)
		(width 0.15494)
		(layer "In7.Cu")
		(net "NIC4_MAIN_PWR_BIC_EN_R")
	)
	(segment
		(start 257.76682 -227.388674)
		(end 257.76682 -225.82378)
		(width 0.15494)
		(layer "In7.Cu")
		(net "NIC4_MAIN_PWR_BIC_EN_R")
	)
	(segment
		(start 265.515852 -220.35262)
		(end 266.985242 -218.88323)
		(width 0.15494)
		(layer "In7.Cu")
		(net "NIC4_MAIN_PWR_BIC_EN_R")
	)
	(segment
		(start 266.985242 -218.88323)
		(end 266.985242 -214.159084)
		(width 0.15494)
		(layer "In7.Cu")
		(net "NIC4_MAIN_PWR_BIC_EN_R")
	)
	(segment
		(start 266.985242 -214.159084)
		(end 267.335 -213.809326)
		(width 0.15494)
		(layer "In7.Cu")
		(net "NIC4_MAIN_PWR_BIC_EN_R")
	)
	(segment
		(start 262.578596 -220.35262)
		(end 265.515852 -220.35262)
		(width 0.15494)
		(layer "In7.Cu")
		(net "NIC4_MAIN_PWR_BIC_EN_R")
	)
	(segment
		(start 226.727512 -233.305858)
		(end 232.588054 -239.1664)
		(width 0.15494)
		(layer "In7.Cu")
		(net "NIC4_MAIN_PWR_BIC_EN_R")
	)
	(segment
		(start 226.727512 -232.471468)
		(end 226.727512 -233.305858)
		(width 0.15494)
		(layer "In7.Cu")
		(net "NIC4_MAIN_PWR_BIC_EN_R")
	)
	(segment
		(start 260.0452 -223.5454)
		(end 260.0452 -222.886016)
		(width 0.15494)
		(layer "In7.Cu")
		(net "NIC4_MAIN_PWR_BIC_EN_R")
	)
	(segment
		(start 260.0452 -222.886016)
		(end 262.578596 -220.35262)
		(width 0.15494)
		(layer "In7.Cu")
		(net "NIC4_MAIN_PWR_BIC_EN_R")
	)
	(segment
		(start 256.8448 -228.310694)
		(end 257.76682 -227.388674)
		(width 0.15494)
		(layer "In7.Cu")
		(net "NIC4_MAIN_PWR_BIC_EN_R")
	)
	(segment
		(start 267.335 -213.809326)
		(end 267.335 -213.6648)
		(width 0.15494)
		(layer "In7.Cu")
		(net "NIC4_MAIN_PWR_BIC_EN_R")
	)
	(segment
		(start 247.16105 -239.1664)
		(end 256.8448 -229.48265)
		(width 0.15494)
		(layer "In7.Cu")
		(net "NIC4_MAIN_PWR_BIC_EN_R")
	)
	(segment
		(start 262.331708 -210.797902)
		(end 262.331708 -212.965284)
		(width 0.15494)
		(layer "In15.Cu")
		(net "NIC4_MAIN_PWR_BIC_EN_R")
	)
	(segment
		(start 349.291402 -210.51393)
		(end 347.70822 -208.930748)
		(width 0.15494)
		(layer "In15.Cu")
		(net "NIC4_MAIN_PWR_BIC_EN_R")
	)
	(segment
		(start 335.00187 -200.3044)
		(end 335.00187 -199.95134)
		(width 0.15494)
		(layer "In15.Cu")
		(net "NIC4_MAIN_PWR_BIC_EN_R")
	)
	(segment
		(start 265.176 -213.504018)
		(end 265.49477 -213.185248)
		(width 0.15494)
		(layer "In15.Cu")
		(net "NIC4_MAIN_PWR_BIC_EN_R")
	)
	(segment
		(start 347.70822 -208.930748)
		(end 347.70822 -205.95717)
		(width 0.15494)
		(layer "In15.Cu")
		(net "NIC4_MAIN_PWR_BIC_EN_R")
	)
	(segment
		(start 344.14587 -204.3684)
		(end 344.14587 -204.01534)
		(width 0.15494)
		(layer "In15.Cu")
		(net "NIC4_MAIN_PWR_BIC_EN_R")
	)
	(segment
		(start 347.1164 -205.36535)
		(end 345.14282 -205.36535)
		(width 0.15494)
		(layer "In15.Cu")
		(net "NIC4_MAIN_PWR_BIC_EN_R")
	)
	(segment
		(start 266.66698 -213.6648)
		(end 267.335 -213.6648)
		(width 0.15494)
		(layer "In15.Cu")
		(net "NIC4_MAIN_PWR_BIC_EN_R")
	)
	(segment
		(start 344.14587 -204.01534)
		(end 343.673176 -203.542646)
		(width 0.15494)
		(layer "In15.Cu")
		(net "NIC4_MAIN_PWR_BIC_EN_R")
	)
	(segment
		(start 262.331708 -212.965284)
		(end 263.5504 -214.183976)
		(width 0.15494)
		(layer "In15.Cu")
		(net "NIC4_MAIN_PWR_BIC_EN_R")
	)
	(segment
		(start 325.98106 -200.482454)
		(end 323.640704 -200.482454)
		(width 0.15494)
		(layer "In15.Cu")
		(net "NIC4_MAIN_PWR_BIC_EN_R")
	)
	(segment
		(start 349.025972 -214.38489)
		(end 349.291402 -214.11946)
		(width 0.0889)
		(layer "In15.Cu")
		(net "NIC4_MAIN_PWR_BIC_EN_R")
	)
	(segment
		(start 328.90333 -199.66813)
		(end 328.82078 -199.75068)
		(width 0.15494)
		(layer "In15.Cu")
		(net "NIC4_MAIN_PWR_BIC_EN_R")
	)
	(segment
		(start 335.50987 -200.8124)
		(end 335.00187 -200.3044)
		(width 0.15494)
		(layer "In15.Cu")
		(net "NIC4_MAIN_PWR_BIC_EN_R")
	)
	(segment
		(start 335.00187 -199.95134)
		(end 334.71866 -199.66813)
		(width 0.15494)
		(layer "In15.Cu")
		(net "NIC4_MAIN_PWR_BIC_EN_R")
	)
	(segment
		(start 336.01914 -200.8124)
		(end 335.50987 -200.8124)
		(width 0.15494)
		(layer "In15.Cu")
		(net "NIC4_MAIN_PWR_BIC_EN_R")
	)
	(segment
		(start 336.882232 -201.675492)
		(end 336.01914 -200.8124)
		(width 0.15494)
		(layer "In15.Cu")
		(net "NIC4_MAIN_PWR_BIC_EN_R")
	)
	(segment
		(start 337.742022 -201.675492)
		(end 336.882232 -201.675492)
		(width 0.15494)
		(layer "In15.Cu")
		(net "NIC4_MAIN_PWR_BIC_EN_R")
	)
	(segment
		(start 266.187428 -213.185248)
		(end 266.66698 -213.6648)
		(width 0.15494)
		(layer "In15.Cu")
		(net "NIC4_MAIN_PWR_BIC_EN_R")
	)
	(segment
		(start 349.291402 -211.3026)
		(end 349.291402 -210.51393)
		(width 0.15494)
		(layer "In15.Cu")
		(net "NIC4_MAIN_PWR_BIC_EN_R")
	)
	(segment
		(start 345.14282 -205.36535)
		(end 344.14587 -204.3684)
		(width 0.15494)
		(layer "In15.Cu")
		(net "NIC4_MAIN_PWR_BIC_EN_R")
	)
	(segment
		(start 263.5504 -214.183976)
		(end 264.569448 -214.183976)
		(width 0.15494)
		(layer "In15.Cu")
		(net "NIC4_MAIN_PWR_BIC_EN_R")
	)
	(segment
		(start 338.074 -202.00747)
		(end 337.742022 -201.675492)
		(width 0.15494)
		(layer "In15.Cu")
		(net "NIC4_MAIN_PWR_BIC_EN_R")
	)
	(segment
		(start 343.673176 -203.542646)
		(end 338.494116 -203.542646)
		(width 0.15494)
		(layer "In15.Cu")
		(net "NIC4_MAIN_PWR_BIC_EN_R")
	)
	(segment
		(start 328.82078 -199.75068)
		(end 326.712834 -199.75068)
		(width 0.15494)
		(layer "In15.Cu")
		(net "NIC4_MAIN_PWR_BIC_EN_R")
	)
	(segment
		(start 265.176 -213.577424)
		(end 265.176 -213.504018)
		(width 0.15494)
		(layer "In15.Cu")
		(net "NIC4_MAIN_PWR_BIC_EN_R")
	)
	(segment
		(start 338.074 -203.12253)
		(end 338.074 -202.00747)
		(width 0.15494)
		(layer "In15.Cu")
		(net "NIC4_MAIN_PWR_BIC_EN_R")
	)
	(segment
		(start 349.291402 -214.11946)
		(end 349.291402 -211.3026)
		(width 0.0889)
		(layer "In15.Cu")
		(net "NIC4_MAIN_PWR_BIC_EN_R")
	)
	(segment
		(start 347.70822 -205.95717)
		(end 347.1164 -205.36535)
		(width 0.15494)
		(layer "In15.Cu")
		(net "NIC4_MAIN_PWR_BIC_EN_R")
	)
	(segment
		(start 338.494116 -203.542646)
		(end 338.074 -203.12253)
		(width 0.15494)
		(layer "In15.Cu")
		(net "NIC4_MAIN_PWR_BIC_EN_R")
	)
	(segment
		(start 334.71866 -199.66813)
		(end 328.90333 -199.66813)
		(width 0.15494)
		(layer "In15.Cu")
		(net "NIC4_MAIN_PWR_BIC_EN_R")
	)
	(segment
		(start 264.569448 -214.183976)
		(end 265.176 -213.577424)
		(width 0.15494)
		(layer "In15.Cu")
		(net "NIC4_MAIN_PWR_BIC_EN_R")
	)
	(segment
		(start 326.712834 -199.75068)
		(end 325.98106 -200.482454)
		(width 0.15494)
		(layer "In15.Cu")
		(net "NIC4_MAIN_PWR_BIC_EN_R")
	)
	(segment
		(start 323.489066 -200.33107)
		(end 272.79854 -200.33107)
		(width 0.15494)
		(layer "In15.Cu")
		(net "NIC4_MAIN_PWR_BIC_EN_R")
	)
	(segment
		(start 348.093538 -214.787226)
		(end 348.495874 -214.38489)
		(width 0.0889)
		(layer "In15.Cu")
		(net "NIC4_MAIN_PWR_BIC_EN_R")
	)
	(segment
		(start 265.49477 -213.185248)
		(end 266.187428 -213.185248)
		(width 0.15494)
		(layer "In15.Cu")
		(net "NIC4_MAIN_PWR_BIC_EN_R")
	)
	(segment
		(start 348.495874 -214.38489)
		(end 349.025972 -214.38489)
		(width 0.0889)
		(layer "In15.Cu")
		(net "NIC4_MAIN_PWR_BIC_EN_R")
	)
	(segment
		(start 272.79854 -200.33107)
		(end 262.331708 -210.797902)
		(width 0.15494)
		(layer "In15.Cu")
		(net "NIC4_MAIN_PWR_BIC_EN_R")
	)
	(segment
		(start 323.640704 -200.482454)
		(end 323.489066 -200.33107)
		(width 0.15494)
		(layer "In15.Cu")
		(net "NIC4_MAIN_PWR_BIC_EN_R")
	)
	(segment
		(start 243.271802 -184.235344)
		(end 242.8113 -184.695846)
		(width 0.13208)
		(layer "F.Cu")
		(net "BIC_RST_RSMRST_R_N")
	)
	(segment
		(start 243.271802 -183.083962)
		(end 243.271802 -184.235344)
		(width 0.13208)
		(layer "F.Cu")
		(net "BIC_RST_RSMRST_R_N")
	)
	(segment
		(start 242.8113 -184.695846)
		(end 242.8113 -185.029602)
		(width 0.13208)
		(layer "F.Cu")
		(net "BIC_RST_RSMRST_R_N")
	)
	(via
		(at 243.271802 -184.235344)
		(size 0.508)
		(drill 0.254)
		(layers "F.Cu" "B.Cu")
		(net "BIC_RST_RSMRST_R_N")
	)
	(segment
		(start 18.717006 -404.934166)
		(end 19.026886 -404.624286)
		(width 0.13208)
		(layer "F.Cu")
		(net "SMB_LM75_0_SCL")
	)
	(segment
		(start 23.1394 -401.08886)
		(end 23.1394 -364.311946)
		(width 0.13208)
		(layer "F.Cu")
		(net "SMB_LM75_0_SCL")
	)
	(segment
		(start 19.603974 -404.624286)
		(end 23.1394 -401.08886)
		(width 0.13208)
		(layer "F.Cu")
		(net "SMB_LM75_0_SCL")
	)
	(segment
		(start 24.128476 -363.32287)
		(end 52.562252 -363.32287)
		(width 0.13208)
		(layer "F.Cu")
		(net "SMB_LM75_0_SCL")
	)
	(segment
		(start 447.802 -401.80895)
		(end 447.802 -401.393152)
		(width 0.13208)
		(layer "F.Cu")
		(net "SMB_LM75_0_SCL")
	)
	(segment
		(start 447.802 -401.393152)
		(end 447.196718 -400.78787)
		(width 0.13208)
		(layer "F.Cu")
		(net "SMB_LM75_0_SCL")
	)
	(segment
		(start 99.192842 -368.305588)
		(end 100.555552 -368.305588)
		(width 0.13208)
		(layer "F.Cu")
		(net "SMB_LM75_0_SCL")
	)
	(segment
		(start 52.963318 -371.51691)
		(end 53.81244 -372.366032)
		(width 0.13208)
		(layer "F.Cu")
		(net "SMB_LM75_0_SCL")
	)
	(segment
		(start 23.1394 -364.311946)
		(end 24.128476 -363.32287)
		(width 0.13208)
		(layer "F.Cu")
		(net "SMB_LM75_0_SCL")
	)
	(segment
		(start 53.81244 -372.366032)
		(end 58.457084 -372.366032)
		(width 0.13208)
		(layer "F.Cu")
		(net "SMB_LM75_0_SCL")
	)
	(segment
		(start 61.31179 -362.88091)
		(end 93.768164 -362.88091)
		(width 0.13208)
		(layer "F.Cu")
		(net "SMB_LM75_0_SCL")
	)
	(segment
		(start 19.026886 -404.624286)
		(end 19.603974 -404.624286)
		(width 0.13208)
		(layer "F.Cu")
		(net "SMB_LM75_0_SCL")
	)
	(segment
		(start 93.768164 -362.88091)
		(end 99.192842 -368.305588)
		(width 0.13208)
		(layer "F.Cu")
		(net "SMB_LM75_0_SCL")
	)
	(segment
		(start 58.457084 -372.366032)
		(end 60.013596 -370.80952)
		(width 0.13208)
		(layer "F.Cu")
		(net "SMB_LM75_0_SCL")
	)
	(segment
		(start 52.963318 -363.723936)
		(end 52.963318 -371.51691)
		(width 0.13208)
		(layer "F.Cu")
		(net "SMB_LM75_0_SCL")
	)
	(segment
		(start 60.013596 -370.80952)
		(end 60.013596 -364.179104)
		(width 0.13208)
		(layer "F.Cu")
		(net "SMB_LM75_0_SCL")
	)
	(segment
		(start 60.013596 -364.179104)
		(end 61.31179 -362.88091)
		(width 0.13208)
		(layer "F.Cu")
		(net "SMB_LM75_0_SCL")
	)
	(segment
		(start 52.562252 -363.32287)
		(end 52.963318 -363.723936)
		(width 0.13208)
		(layer "F.Cu")
		(net "SMB_LM75_0_SCL")
	)
	(segment
		(start 18.717006 -405.85517)
		(end 18.717006 -404.934166)
		(width 0.13208)
		(layer "F.Cu")
		(net "SMB_LM75_0_SCL")
	)
	(segment
		(start 447.196718 -400.78787)
		(end 446.63106 -400.78787)
		(width 0.13208)
		(layer "F.Cu")
		(net "SMB_LM75_0_SCL")
	)
	(via
		(at 446.63106 -400.78787)
		(size 0.508)
		(drill 0.254)
		(layers "F.Cu" "B.Cu")
		(net "SMB_LM75_0_SCL")
	)
	(via
		(at 100.555552 -368.305588)
		(size 0.508)
		(drill 0.254)
		(layers "F.Cu" "B.Cu")
		(net "SMB_LM75_0_SCL")
	)
	(via
		(at 19.026886 -404.624286)
		(size 0.508)
		(drill 0.254)
		(layers "F.Cu" "B.Cu")
		(net "SMB_LM75_0_SCL")
	)
	(segment
		(start 222.309436 -341.273638)
		(end 223.89592 -342.860122)
		(width 0.13208)
		(layer "B.Cu")
		(net "SMB_LM75_0_SCL")
	)
	(segment
		(start 266.002008 -355.117654)
		(end 270.56588 -359.681526)
		(width 0.13208)
		(layer "B.Cu")
		(net "SMB_LM75_0_SCL")
	)
	(segment
		(start 401.36318 -390.29767)
		(end 404.692358 -393.626848)
		(width 0.13208)
		(layer "B.Cu")
		(net "SMB_LM75_0_SCL")
	)
	(segment
		(start 364.00867 -387.56844)
		(end 366.7379 -390.29767)
		(width 0.13208)
		(layer "B.Cu")
		(net "SMB_LM75_0_SCL")
	)
	(segment
		(start 109.515402 -364.883446)
		(end 113.765584 -360.633264)
		(width 0.13208)
		(layer "B.Cu")
		(net "SMB_LM75_0_SCL")
	)
	(segment
		(start 252.96368 -343.978484)
		(end 260.876796 -343.978484)
		(width 0.13208)
		(layer "B.Cu")
		(net "SMB_LM75_0_SCL")
	)
	(segment
		(start 208.46669 -341.273638)
		(end 222.309436 -341.273638)
		(width 0.13208)
		(layer "B.Cu")
		(net "SMB_LM75_0_SCL")
	)
	(segment
		(start 266.002008 -349.103696)
		(end 266.002008 -355.117654)
		(width 0.13208)
		(layer "B.Cu")
		(net "SMB_LM75_0_SCL")
	)
	(segment
		(start 100.555552 -368.305588)
		(end 103.977694 -364.883446)
		(width 0.13208)
		(layer "B.Cu")
		(net "SMB_LM75_0_SCL")
	)
	(segment
		(start 366.7379 -390.29767)
		(end 401.36318 -390.29767)
		(width 0.13208)
		(layer "B.Cu")
		(net "SMB_LM75_0_SCL")
	)
	(segment
		(start 446.351406 -400.508216)
		(end 446.63106 -400.78787)
		(width 0.13208)
		(layer "B.Cu")
		(net "SMB_LM75_0_SCL")
	)
	(segment
		(start 446.351406 -394.858748)
		(end 446.351406 -400.508216)
		(width 0.13208)
		(layer "B.Cu")
		(net "SMB_LM75_0_SCL")
	)
	(segment
		(start 359.9434 -382.973326)
		(end 364.00867 -387.038596)
		(width 0.13208)
		(layer "B.Cu")
		(net "SMB_LM75_0_SCL")
	)
	(segment
		(start 260.876796 -343.978484)
		(end 266.002008 -349.103696)
		(width 0.13208)
		(layer "B.Cu")
		(net "SMB_LM75_0_SCL")
	)
	(segment
		(start 358.695752 -359.681526)
		(end 359.9434 -360.929174)
		(width 0.13208)
		(layer "B.Cu")
		(net "SMB_LM75_0_SCL")
	)
	(segment
		(start 445.119506 -393.626848)
		(end 446.351406 -394.858748)
		(width 0.13208)
		(layer "B.Cu")
		(net "SMB_LM75_0_SCL")
	)
	(segment
		(start 359.9434 -360.929174)
		(end 359.9434 -382.973326)
		(width 0.13208)
		(layer "B.Cu")
		(net "SMB_LM75_0_SCL")
	)
	(segment
		(start 270.56588 -359.681526)
		(end 358.695752 -359.681526)
		(width 0.13208)
		(layer "B.Cu")
		(net "SMB_LM75_0_SCL")
	)
	(segment
		(start 251.845318 -342.860122)
		(end 252.96368 -343.978484)
		(width 0.13208)
		(layer "B.Cu")
		(net "SMB_LM75_0_SCL")
	)
	(segment
		(start 364.00867 -387.038596)
		(end 364.00867 -387.56844)
		(width 0.13208)
		(layer "B.Cu")
		(net "SMB_LM75_0_SCL")
	)
	(segment
		(start 103.977694 -364.883446)
		(end 109.515402 -364.883446)
		(width 0.13208)
		(layer "B.Cu")
		(net "SMB_LM75_0_SCL")
	)
	(segment
		(start 189.107064 -360.633264)
		(end 208.46669 -341.273638)
		(width 0.13208)
		(layer "B.Cu")
		(net "SMB_LM75_0_SCL")
	)
	(segment
		(start 223.89592 -342.860122)
		(end 251.845318 -342.860122)
		(width 0.13208)
		(layer "B.Cu")
		(net "SMB_LM75_0_SCL")
	)
	(segment
		(start 404.692358 -393.626848)
		(end 445.119506 -393.626848)
		(width 0.13208)
		(layer "B.Cu")
		(net "SMB_LM75_0_SCL")
	)
	(segment
		(start 113.765584 -360.633264)
		(end 189.107064 -360.633264)
		(width 0.13208)
		(layer "B.Cu")
		(net "SMB_LM75_0_SCL")
	)
	(segment
		(start 47.29988 -294.94988)
		(end 46.8249 -294.4749)
		(width 0.249936)
		(layer "F.Cu")
		(net "PCEPLL4_VDDA18_PEX0")
	)
	(via
		(at 31.616396 -290.321238)
		(size 0.508)
		(drill 0.254)
		(layers "F.Cu" "B.Cu")
		(net "PCEPLL4_VDDA18_PEX0")
	)
	(via
		(at 33.130236 -290.820856)
		(size 0.508)
		(drill 0.254)
		(layers "F.Cu" "B.Cu")
		(net "PCEPLL4_VDDA18_PEX0")
	)
	(via
		(at 46.8249 -294.4749)
		(size 0.4064)
		(drill 0.2032)
		(layers "F.Cu" "B.Cu")
		(net "PCEPLL4_VDDA18_PEX0")
	)
	(segment
		(start 46.6217 -294.4749)
		(end 46.8249 -294.4749)
		(width 0.3048)
		(layer "B.Cu")
		(net "PCEPLL4_VDDA18_PEX0")
	)
	(segment
		(start 46.6217 -295.2623)
		(end 46.8249 -295.0591)
		(width 0.3048)
		(layer "B.Cu")
		(net "PCEPLL4_VDDA18_PEX0")
	)
	(segment
		(start 46.8249 -295.0591)
		(end 46.8249 -294.4749)
		(width 0.3048)
		(layer "B.Cu")
		(net "PCEPLL4_VDDA18_PEX0")
	)
	(segment
		(start 207.06461 -296.56786)
		(end 207.06461 -295.647872)
		(width 0.13208)
		(layer "F.Cu")
		(net "I2C_PEX1_HOST_R_SCL")
	)
	(segment
		(start 208.489804 -298.485052)
		(end 207.473804 -298.485052)
		(width 0.13208)
		(layer "F.Cu")
		(net "I2C_PEX1_HOST_R_SCL")
	)
	(segment
		(start 207.473804 -298.485052)
		(end 207.103218 -298.485052)
		(width 0.13208)
		(layer "F.Cu")
		(net "I2C_PEX1_HOST_R_SCL")
	)
	(segment
		(start 207.103218 -298.485052)
		(end 206.976218 -298.358052)
		(width 0.13208)
		(layer "F.Cu")
		(net "I2C_PEX1_HOST_R_SCL")
	)
	(segment
		(start 207.019398 -296.613072)
		(end 207.06461 -296.56786)
		(width 0.13208)
		(layer "F.Cu")
		(net "I2C_PEX1_HOST_R_SCL")
	)
	(segment
		(start 207.019398 -297.4213)
		(end 207.019398 -296.613072)
		(width 0.13208)
		(layer "F.Cu")
		(net "I2C_PEX1_HOST_R_SCL")
	)
	(segment
		(start 206.976218 -298.358052)
		(end 206.976218 -297.46448)
		(width 0.13208)
		(layer "F.Cu")
		(net "I2C_PEX1_HOST_R_SCL")
	)
	(segment
		(start 206.976218 -297.46448)
		(end 207.019398 -297.4213)
		(width 0.13208)
		(layer "F.Cu")
		(net "I2C_PEX1_HOST_R_SCL")
	)
	(via
		(at 207.019398 -296.613072)
		(size 0.508)
		(drill 0.254)
		(layers "F.Cu" "B.Cu")
		(net "I2C_PEX1_HOST_R_SCL")
	)
	(segment
		(start 350.642936 -172.216064)
		(end 351.282 -171.577)
		(width 0.13208)
		(layer "F.Cu")
		(net "SMB_PEX2_PCA9555_SDA")
	)
	(segment
		(start 351.86366 -183.4896)
		(end 351.199196 -184.154064)
		(width 0.13208)
		(layer "F.Cu")
		(net "SMB_PEX2_PCA9555_SDA")
	)
	(segment
		(start 349.000064 -172.216064)
		(end 350.642936 -172.216064)
		(width 0.13208)
		(layer "F.Cu")
		(net "SMB_PEX2_PCA9555_SDA")
	)
	(segment
		(start 351.199196 -184.154064)
		(end 349.000064 -184.154064)
		(width 0.13208)
		(layer "F.Cu")
		(net "SMB_PEX2_PCA9555_SDA")
	)
	(segment
		(start 321.035934 -288.830766)
		(end 321.035934 -288.221166)
		(width 0.13208)
		(layer "F.Cu")
		(net "SMB_PEX2_PCA9555_SDA")
	)
	(via
		(at 351.86366 -183.4896)
		(size 0.508)
		(drill 0.254)
		(layers "F.Cu" "B.Cu")
		(net "SMB_PEX2_PCA9555_SDA")
	)
	(via
		(at 316.3316 -254.9398)
		(size 0.508)
		(drill 0.254)
		(layers "F.Cu" "B.Cu")
		(net "SMB_PEX2_PCA9555_SDA")
	)
	(via
		(at 321.035934 -288.221166)
		(size 0.508)
		(drill 0.254)
		(layers "F.Cu" "B.Cu")
		(net "SMB_PEX2_PCA9555_SDA")
	)
	(via
		(at 351.282 -171.577)
		(size 0.508)
		(drill 0.254)
		(layers "F.Cu" "B.Cu")
		(net "SMB_PEX2_PCA9555_SDA")
	)
	(segment
		(start 316.3316 -255.2446)
		(end 316.9666 -255.8796)
		(width 0.13208)
		(layer "B.Cu")
		(net "SMB_PEX2_PCA9555_SDA")
	)
	(segment
		(start 316.596522 -267.866622)
		(end 316.596522 -273.155156)
		(width 0.13208)
		(layer "B.Cu")
		(net "SMB_PEX2_PCA9555_SDA")
	)
	(segment
		(start 317.740284 -266.728956)
		(end 317.734188 -266.728956)
		(width 0.13208)
		(layer "B.Cu")
		(net "SMB_PEX2_PCA9555_SDA")
	)
	(segment
		(start 319.903602 -264.565638)
		(end 317.740284 -266.728956)
		(width 0.13208)
		(layer "B.Cu")
		(net "SMB_PEX2_PCA9555_SDA")
	)
	(segment
		(start 321.035934 -277.594568)
		(end 321.035934 -288.221166)
		(width 0.13208)
		(layer "B.Cu")
		(net "SMB_PEX2_PCA9555_SDA")
	)
	(segment
		(start 316.9666 -255.8796)
		(end 317.068454 -255.8796)
		(width 0.13208)
		(layer "B.Cu")
		(net "SMB_PEX2_PCA9555_SDA")
	)
	(segment
		(start 316.3316 -254.9398)
		(end 316.3316 -255.2446)
		(width 0.13208)
		(layer "B.Cu")
		(net "SMB_PEX2_PCA9555_SDA")
	)
	(segment
		(start 317.068454 -255.8796)
		(end 319.903602 -258.714748)
		(width 0.13208)
		(layer "B.Cu")
		(net "SMB_PEX2_PCA9555_SDA")
	)
	(segment
		(start 319.903602 -258.714748)
		(end 319.903602 -264.565638)
		(width 0.13208)
		(layer "B.Cu")
		(net "SMB_PEX2_PCA9555_SDA")
	)
	(segment
		(start 316.596522 -273.155156)
		(end 321.035934 -277.594568)
		(width 0.13208)
		(layer "B.Cu")
		(net "SMB_PEX2_PCA9555_SDA")
	)
	(segment
		(start 317.734188 -266.728956)
		(end 316.596522 -267.866622)
		(width 0.13208)
		(layer "B.Cu")
		(net "SMB_PEX2_PCA9555_SDA")
	)
	(segment
		(start 351.9424 -172.2374)
		(end 351.282 -171.577)
		(width 0.15494)
		(layer "In9.Cu")
		(net "SMB_PEX2_PCA9555_SDA")
	)
	(segment
		(start 351.86366 -183.4896)
		(end 351.9424 -183.41086)
		(width 0.15494)
		(layer "In9.Cu")
		(net "SMB_PEX2_PCA9555_SDA")
	)
	(segment
		(start 351.9424 -183.41086)
		(end 351.9424 -172.2374)
		(width 0.15494)
		(layer "In9.Cu")
		(net "SMB_PEX2_PCA9555_SDA")
	)
	(segment
		(start 362.656374 -184.2516)
		(end 377.2408 -184.2516)
		(width 0.15494)
		(layer "In13.Cu")
		(net "SMB_PEX2_PCA9555_SDA")
	)
	(segment
		(start 381.60198 -188.61278)
		(end 381.60198 -214.421466)
		(width 0.15494)
		(layer "In13.Cu")
		(net "SMB_PEX2_PCA9555_SDA")
	)
	(segment
		(start 340.71814 -250.89104)
		(end 340.71814 -251.363734)
		(width 0.15494)
		(layer "In13.Cu")
		(net "SMB_PEX2_PCA9555_SDA")
	)
	(segment
		(start 346.55252 -245.05666)
		(end 340.71814 -250.89104)
		(width 0.15494)
		(layer "In13.Cu")
		(net "SMB_PEX2_PCA9555_SDA")
	)
	(segment
		(start 360.853736 -234.0864)
		(end 349.883476 -245.05666)
		(width 0.15494)
		(layer "In13.Cu")
		(net "SMB_PEX2_PCA9555_SDA")
	)
	(segment
		(start 351.86366 -183.4896)
		(end 351.86366 -184.09666)
		(width 0.15494)
		(layer "In13.Cu")
		(net "SMB_PEX2_PCA9555_SDA")
	)
	(segment
		(start 369.641882 -234.0864)
		(end 360.853736 -234.0864)
		(width 0.15494)
		(layer "In13.Cu")
		(net "SMB_PEX2_PCA9555_SDA")
	)
	(segment
		(start 349.883476 -245.05666)
		(end 346.55252 -245.05666)
		(width 0.15494)
		(layer "In13.Cu")
		(net "SMB_PEX2_PCA9555_SDA")
	)
	(segment
		(start 361.233974 -185.674)
		(end 362.656374 -184.2516)
		(width 0.15494)
		(layer "In13.Cu")
		(net "SMB_PEX2_PCA9555_SDA")
	)
	(segment
		(start 353.441 -185.674)
		(end 361.233974 -185.674)
		(width 0.15494)
		(layer "In13.Cu")
		(net "SMB_PEX2_PCA9555_SDA")
	)
	(segment
		(start 375.4882 -222.4024)
		(end 375.4882 -228.240082)
		(width 0.15494)
		(layer "In13.Cu")
		(net "SMB_PEX2_PCA9555_SDA")
	)
	(segment
		(start 375.855992 -220.167454)
		(end 375.855992 -222.034608)
		(width 0.15494)
		(layer "In13.Cu")
		(net "SMB_PEX2_PCA9555_SDA")
	)
	(segment
		(start 340.71814 -251.363734)
		(end 338.425028 -253.656846)
		(width 0.15494)
		(layer "In13.Cu")
		(net "SMB_PEX2_PCA9555_SDA")
	)
	(segment
		(start 351.86366 -184.09666)
		(end 353.441 -185.674)
		(width 0.15494)
		(layer "In13.Cu")
		(net "SMB_PEX2_PCA9555_SDA")
	)
	(segment
		(start 338.425028 -253.656846)
		(end 316.637162 -253.656846)
		(width 0.15494)
		(layer "In13.Cu")
		(net "SMB_PEX2_PCA9555_SDA")
	)
	(segment
		(start 316.152784 -254.760984)
		(end 316.3316 -254.9398)
		(width 0.15494)
		(layer "In13.Cu")
		(net "SMB_PEX2_PCA9555_SDA")
	)
	(segment
		(start 377.2408 -184.2516)
		(end 381.60198 -188.61278)
		(width 0.15494)
		(layer "In13.Cu")
		(net "SMB_PEX2_PCA9555_SDA")
	)
	(segment
		(start 316.152784 -254.141224)
		(end 316.152784 -254.760984)
		(width 0.15494)
		(layer "In13.Cu")
		(net "SMB_PEX2_PCA9555_SDA")
	)
	(segment
		(start 316.637162 -253.656846)
		(end 316.152784 -254.141224)
		(width 0.15494)
		(layer "In13.Cu")
		(net "SMB_PEX2_PCA9555_SDA")
	)
	(segment
		(start 375.4882 -228.240082)
		(end 369.641882 -234.0864)
		(width 0.15494)
		(layer "In13.Cu")
		(net "SMB_PEX2_PCA9555_SDA")
	)
	(segment
		(start 375.855992 -222.034608)
		(end 375.4882 -222.4024)
		(width 0.15494)
		(layer "In13.Cu")
		(net "SMB_PEX2_PCA9555_SDA")
	)
	(segment
		(start 381.60198 -214.421466)
		(end 375.855992 -220.167454)
		(width 0.15494)
		(layer "In13.Cu")
		(net "SMB_PEX2_PCA9555_SDA")
	)
	(segment
		(start 208.909158 -78.579472)
		(end 210.19008 -79.860394)
		(width 0.13208)
		(layer "F.Cu")
		(net "SSD6_LED")
	)
	(segment
		(start 210.19008 -79.860394)
		(end 211.572094 -79.860394)
		(width 0.13208)
		(layer "F.Cu")
		(net "SSD6_LED")
	)
	(segment
		(start 207.023208 -78.579472)
		(end 208.909158 -78.579472)
		(width 0.13208)
		(layer "F.Cu")
		(net "SSD6_LED")
	)
	(via
		(at 208.909158 -78.579472)
		(size 0.508)
		(drill 0.254)
		(layers "F.Cu" "B.Cu")
		(net "SSD6_LED")
	)
	(segment
		(start 227.743512 -233.19232)
		(end 227.743512 -231.816656)
		(width 0.13208)
		(layer "F.Cu")
		(net "NIC3_MAIN_PWR_BIC_EN_R")
	)
	(segment
		(start 227.724462 -233.182668)
		(end 227.734114 -233.19232)
		(width 0.13208)
		(layer "F.Cu")
		(net "NIC3_MAIN_PWR_BIC_EN_R")
	)
	(segment
		(start 346.893896 -215.987122)
		(end 347.293692 -215.587326)
		(width 0.13208)
		(layer "F.Cu")
		(net "NIC3_MAIN_PWR_BIC_EN_R")
	)
	(segment
		(start 227.734114 -233.19232)
		(end 227.743512 -233.19232)
		(width 0.13208)
		(layer "F.Cu")
		(net "NIC3_MAIN_PWR_BIC_EN_R")
	)
	(via
		(at 266.468098 -217.432382)
		(size 0.508)
		(drill 0.254)
		(layers "F.Cu" "B.Cu")
		(net "NIC3_MAIN_PWR_BIC_EN_R")
	)
	(via
		(at 263.739376 -192.144904)
		(size 0.508)
		(drill 0.254)
		(layers "F.Cu" "B.Cu")
		(net "NIC3_MAIN_PWR_BIC_EN_R")
	)
	(via
		(at 347.293692 -215.587326)
		(size 0.4572)
		(drill 0.254)
		(layers "F.Cu" "B.Cu")
		(net "NIC3_MAIN_PWR_BIC_EN_R")
	)
	(via
		(at 227.724462 -233.182668)
		(size 0.508)
		(drill 0.254)
		(layers "F.Cu" "B.Cu")
		(net "NIC3_MAIN_PWR_BIC_EN_R")
	)
	(segment
		(start 266.468098 -217.432382)
		(end 263.486646 -217.432382)
		(width 0.15494)
		(layer "In5.Cu")
		(net "NIC3_MAIN_PWR_BIC_EN_R")
	)
	(segment
		(start 262.9408 -192.94348)
		(end 263.739376 -192.144904)
		(width 0.15494)
		(layer "In5.Cu")
		(net "NIC3_MAIN_PWR_BIC_EN_R")
	)
	(segment
		(start 262.9408 -216.886536)
		(end 262.9408 -192.94348)
		(width 0.15494)
		(layer "In5.Cu")
		(net "NIC3_MAIN_PWR_BIC_EN_R")
	)
	(segment
		(start 263.486646 -217.432382)
		(end 262.9408 -216.886536)
		(width 0.15494)
		(layer "In5.Cu")
		(net "NIC3_MAIN_PWR_BIC_EN_R")
	)
	(segment
		(start 250.258326 -233.47934)
		(end 250.06046 -233.47934)
		(width 0.15494)
		(layer "In7.Cu")
		(net "NIC3_MAIN_PWR_BIC_EN_R")
	)
	(segment
		(start 250.791218 -233.258614)
		(end 250.258326 -233.47934)
		(width 0.15494)
		(layer "In7.Cu")
		(net "NIC3_MAIN_PWR_BIC_EN_R")
	)
	(segment
		(start 266.468098 -218.803474)
		(end 265.277092 -219.99448)
		(width 0.15494)
		(layer "In7.Cu")
		(net "NIC3_MAIN_PWR_BIC_EN_R")
	)
	(segment
		(start 250.06046 -233.47934)
		(end 246.753126 -236.786674)
		(width 0.15494)
		(layer "In7.Cu")
		(net "NIC3_MAIN_PWR_BIC_EN_R")
	)
	(segment
		(start 266.468098 -217.432382)
		(end 266.468098 -218.803474)
		(width 0.15494)
		(layer "In7.Cu")
		(net "NIC3_MAIN_PWR_BIC_EN_R")
	)
	(segment
		(start 259.6134 -222.811086)
		(end 259.6134 -223.44126)
		(width 0.15494)
		(layer "In7.Cu")
		(net "NIC3_MAIN_PWR_BIC_EN_R")
	)
	(segment
		(start 250.989846 -233.059986)
		(end 250.791218 -233.258614)
		(width 0.15494)
		(layer "In7.Cu")
		(net "NIC3_MAIN_PWR_BIC_EN_R")
	)
	(segment
		(start 246.753126 -236.786674)
		(end 246.600726 -236.786674)
		(width 0.15494)
		(layer "In7.Cu")
		(net "NIC3_MAIN_PWR_BIC_EN_R")
	)
	(segment
		(start 257.2766 -225.77679)
		(end 257.2766 -227.035614)
		(width 0.15494)
		(layer "In7.Cu")
		(net "NIC3_MAIN_PWR_BIC_EN_R")
	)
	(segment
		(start 246.600726 -236.786674)
		(end 244.6528 -238.7346)
		(width 0.15494)
		(layer "In7.Cu")
		(net "NIC3_MAIN_PWR_BIC_EN_R")
	)
	(segment
		(start 262.430006 -219.99448)
		(end 259.6134 -222.811086)
		(width 0.15494)
		(layer "In7.Cu")
		(net "NIC3_MAIN_PWR_BIC_EN_R")
	)
	(segment
		(start 258.28752 -224.76587)
		(end 257.2766 -225.77679)
		(width 0.15494)
		(layer "In7.Cu")
		(net "NIC3_MAIN_PWR_BIC_EN_R")
	)
	(segment
		(start 244.6528 -238.7346)
		(end 232.791 -238.7346)
		(width 0.15494)
		(layer "In7.Cu")
		(net "NIC3_MAIN_PWR_BIC_EN_R")
	)
	(segment
		(start 265.277092 -219.99448)
		(end 262.430006 -219.99448)
		(width 0.15494)
		(layer "In7.Cu")
		(net "NIC3_MAIN_PWR_BIC_EN_R")
	)
	(segment
		(start 259.6134 -223.44126)
		(end 258.28879 -224.76587)
		(width 0.15494)
		(layer "In7.Cu")
		(net "NIC3_MAIN_PWR_BIC_EN_R")
	)
	(segment
		(start 227.724462 -233.668062)
		(end 227.724462 -233.182668)
		(width 0.15494)
		(layer "In7.Cu")
		(net "NIC3_MAIN_PWR_BIC_EN_R")
	)
	(segment
		(start 258.28879 -224.76587)
		(end 258.28752 -224.76587)
		(width 0.15494)
		(layer "In7.Cu")
		(net "NIC3_MAIN_PWR_BIC_EN_R")
	)
	(segment
		(start 232.791 -238.7346)
		(end 227.724462 -233.668062)
		(width 0.15494)
		(layer "In7.Cu")
		(net "NIC3_MAIN_PWR_BIC_EN_R")
	)
	(segment
		(start 251.252228 -233.059986)
		(end 250.989846 -233.059986)
		(width 0.15494)
		(layer "In7.Cu")
		(net "NIC3_MAIN_PWR_BIC_EN_R")
	)
	(segment
		(start 257.2766 -227.035614)
		(end 251.252228 -233.059986)
		(width 0.15494)
		(layer "In7.Cu")
		(net "NIC3_MAIN_PWR_BIC_EN_R")
	)
	(segment
		(start 348.432628 -203.186284)
		(end 346.01023 -203.186284)
		(width 0.15494)
		(layer "In15.Cu")
		(net "NIC3_MAIN_PWR_BIC_EN_R")
	)
	(segment
		(start 336.551778 -197.78726)
		(end 326.87514 -197.78726)
		(width 0.15494)
		(layer "In15.Cu")
		(net "NIC3_MAIN_PWR_BIC_EN_R")
	)
	(segment
		(start 352.059494 -215.198706)
		(end 352.059494 -207.784192)
		(width 0.15494)
		(layer "In15.Cu")
		(net "NIC3_MAIN_PWR_BIC_EN_R")
	)
	(segment
		(start 323.1642 -198.29907)
		(end 278.223472 -198.29907)
		(width 0.15494)
		(layer "In15.Cu")
		(net "NIC3_MAIN_PWR_BIC_EN_R")
	)
	(segment
		(start 325.912226 -198.750174)
		(end 323.615304 -198.750174)
		(width 0.15494)
		(layer "In15.Cu")
		(net "NIC3_MAIN_PWR_BIC_EN_R")
	)
	(segment
		(start 347.668342 -215.961976)
		(end 351.296224 -215.961976)
		(width 0.0889)
		(layer "In15.Cu")
		(net "NIC3_MAIN_PWR_BIC_EN_R")
	)
	(segment
		(start 343.817956 -200.99401)
		(end 338.73948 -200.99401)
		(width 0.15494)
		(layer "In15.Cu")
		(net "NIC3_MAIN_PWR_BIC_EN_R")
	)
	(segment
		(start 338.04987 -200.3044)
		(end 338.04987 -199.285352)
		(width 0.15494)
		(layer "In15.Cu")
		(net "NIC3_MAIN_PWR_BIC_EN_R")
	)
	(segment
		(start 346.01023 -203.186284)
		(end 343.817956 -200.99401)
		(width 0.15494)
		(layer "In15.Cu")
		(net "NIC3_MAIN_PWR_BIC_EN_R")
	)
	(segment
		(start 352.059494 -207.784192)
		(end 351.366582 -207.09128)
		(width 0.15494)
		(layer "In15.Cu")
		(net "NIC3_MAIN_PWR_BIC_EN_R")
	)
	(segment
		(start 351.366582 -206.120238)
		(end 348.432628 -203.186284)
		(width 0.15494)
		(layer "In15.Cu")
		(net "NIC3_MAIN_PWR_BIC_EN_R")
	)
	(segment
		(start 351.6884 -215.5698)
		(end 352.059494 -215.198706)
		(width 0.15494)
		(layer "In15.Cu")
		(net "NIC3_MAIN_PWR_BIC_EN_R")
	)
	(segment
		(start 351.296224 -215.961976)
		(end 351.6884 -215.5698)
		(width 0.0889)
		(layer "In15.Cu")
		(net "NIC3_MAIN_PWR_BIC_EN_R")
	)
	(segment
		(start 338.73948 -200.99401)
		(end 338.04987 -200.3044)
		(width 0.15494)
		(layer "In15.Cu")
		(net "NIC3_MAIN_PWR_BIC_EN_R")
	)
	(segment
		(start 326.87514 -197.78726)
		(end 325.912226 -198.750174)
		(width 0.15494)
		(layer "In15.Cu")
		(net "NIC3_MAIN_PWR_BIC_EN_R")
	)
	(segment
		(start 272.069306 -192.144904)
		(end 263.739376 -192.144904)
		(width 0.15494)
		(layer "In15.Cu")
		(net "NIC3_MAIN_PWR_BIC_EN_R")
	)
	(segment
		(start 338.04987 -199.285352)
		(end 336.551778 -197.78726)
		(width 0.15494)
		(layer "In15.Cu")
		(net "NIC3_MAIN_PWR_BIC_EN_R")
	)
	(segment
		(start 323.615304 -198.750174)
		(end 323.1642 -198.29907)
		(width 0.15494)
		(layer "In15.Cu")
		(net "NIC3_MAIN_PWR_BIC_EN_R")
	)
	(segment
		(start 351.366582 -207.09128)
		(end 351.366582 -206.120238)
		(width 0.15494)
		(layer "In15.Cu")
		(net "NIC3_MAIN_PWR_BIC_EN_R")
	)
	(segment
		(start 347.293692 -215.587326)
		(end 347.668342 -215.961976)
		(width 0.0889)
		(layer "In15.Cu")
		(net "NIC3_MAIN_PWR_BIC_EN_R")
	)
	(segment
		(start 278.223472 -198.29907)
		(end 272.069306 -192.144904)
		(width 0.15494)
		(layer "In15.Cu")
		(net "NIC3_MAIN_PWR_BIC_EN_R")
	)
	(segment
		(start 18.019014 -403.81936)
		(end 18.019014 -404.216108)
		(width 0.13208)
		(layer "F.Cu")
		(net "SMB_LM75_0_SDA")
	)
	(segment
		(start 17.447006 -405.85517)
		(end 17.447006 -404.788116)
		(width 0.13208)
		(layer "F.Cu")
		(net "SMB_LM75_0_SDA")
	)
	(segment
		(start 18.019014 -404.216108)
		(end 17.733264 -404.501858)
		(width 0.13208)
		(layer "F.Cu")
		(net "SMB_LM75_0_SDA")
	)
	(segment
		(start 17.447006 -404.788116)
		(end 17.733264 -404.501858)
		(width 0.13208)
		(layer "F.Cu")
		(net "SMB_LM75_0_SDA")
	)
	(via
		(at 17.733264 -404.501858)
		(size 0.508)
		(drill 0.254)
		(layers "F.Cu" "B.Cu")
		(net "SMB_LM75_0_SDA")
	)
	(via
		(at 34.689034 -259.576316)
		(size 0.508)
		(drill 0.254)
		(layers "F.Cu" "B.Cu")
		(net "PCEPLL3_VDDA18_PEX0_R")
	)
	(segment
		(start 350.905826 -255.269746)
		(end 351.175828 -255.539748)
		(width 0.13208)
		(layer "F.Cu")
		(net "P0V8_PEX3_PWM1")
	)
	(segment
		(start 350.905826 -253.05512)
		(end 350.905826 -255.269746)
		(width 0.13208)
		(layer "F.Cu")
		(net "P0V8_PEX3_PWM1")
	)
	(segment
		(start 351.175828 -255.539748)
		(end 351.175828 -255.994916)
		(width 0.13208)
		(layer "F.Cu")
		(net "P0V8_PEX3_PWM1")
	)
	(segment
		(start 354.570792 -281.438858)
		(end 354.649024 -281.249882)
		(width 0.2032)
		(layer "F.Cu")
		(net "P0V8_PEX3_PWM1")
	)
	(segment
		(start 354.570792 -281.999182)
		(end 354.570792 -281.438858)
		(width 0.2032)
		(layer "F.Cu")
		(net "P0V8_PEX3_PWM1")
	)
	(segment
		(start 354.649024 -280.897838)
		(end 354.774246 -280.617168)
		(width 0.2032)
		(layer "F.Cu")
		(net "P0V8_PEX3_PWM1")
	)
	(segment
		(start 354.649024 -281.249882)
		(end 354.649024 -280.897838)
		(width 0.2032)
		(layer "F.Cu")
		(net "P0V8_PEX3_PWM1")
	)
	(via
		(at 350.905826 -253.05512)
		(size 0.508)
		(drill 0.254)
		(layers "F.Cu" "B.Cu")
		(net "P0V8_PEX3_PWM1")
	)
	(via
		(at 354.774246 -280.617168)
		(size 0.508)
		(drill 0.254)
		(layers "F.Cu" "B.Cu")
		(net "P0V8_PEX3_PWM1")
	)
	(segment
		(start 355.603302 -253.82982)
		(end 355.603302 -260.86689)
		(width 0.2032)
		(layer "In5.Cu")
		(net "P0V8_PEX3_PWM1")
	)
	(segment
		(start 356.666546 -264.254488)
		(end 353.771708 -267.149326)
		(width 0.2032)
		(layer "In5.Cu")
		(net "P0V8_PEX3_PWM1")
	)
	(segment
		(start 353.771708 -267.149326)
		(end 352.848164 -267.149326)
		(width 0.2032)
		(layer "In5.Cu")
		(net "P0V8_PEX3_PWM1")
	)
	(segment
		(start 355.603302 -260.86689)
		(end 356.666546 -261.930134)
		(width 0.2032)
		(layer "In5.Cu")
		(net "P0V8_PEX3_PWM1")
	)
	(segment
		(start 350.905826 -253.05512)
		(end 354.828602 -253.05512)
		(width 0.2032)
		(layer "In5.Cu")
		(net "P0V8_PEX3_PWM1")
	)
	(segment
		(start 352.848164 -267.149326)
		(end 350.442276 -269.555214)
		(width 0.2032)
		(layer "In5.Cu")
		(net "P0V8_PEX3_PWM1")
	)
	(segment
		(start 351.915984 -279.860756)
		(end 354.017834 -279.860756)
		(width 0.2032)
		(layer "In5.Cu")
		(net "P0V8_PEX3_PWM1")
	)
	(segment
		(start 354.828602 -253.05512)
		(end 355.603302 -253.82982)
		(width 0.2032)
		(layer "In5.Cu")
		(net "P0V8_PEX3_PWM1")
	)
	(segment
		(start 350.442276 -269.555214)
		(end 350.442276 -278.387048)
		(width 0.2032)
		(layer "In5.Cu")
		(net "P0V8_PEX3_PWM1")
	)
	(segment
		(start 356.666546 -261.930134)
		(end 356.666546 -264.254488)
		(width 0.2032)
		(layer "In5.Cu")
		(net "P0V8_PEX3_PWM1")
	)
	(segment
		(start 350.442276 -278.387048)
		(end 351.915984 -279.860756)
		(width 0.2032)
		(layer "In5.Cu")
		(net "P0V8_PEX3_PWM1")
	)
	(segment
		(start 354.017834 -279.860756)
		(end 354.774246 -280.617168)
		(width 0.2032)
		(layer "In5.Cu")
		(net "P0V8_PEX3_PWM1")
	)
	(segment
		(start 207.023208 -80.611472)
		(end 208.274158 -80.611472)
		(width 0.13208)
		(layer "F.Cu")
		(net "SSD4_LED")
	)
	(segment
		(start 208.274158 -80.611472)
		(end 208.823052 -81.160366)
		(width 0.13208)
		(layer "F.Cu")
		(net "SSD4_LED")
	)
	(segment
		(start 208.823052 -81.160366)
		(end 211.572094 -81.160366)
		(width 0.13208)
		(layer "F.Cu")
		(net "SSD4_LED")
	)
	(via
		(at 208.274158 -80.611472)
		(size 0.762)
		(drill 0.381)
		(layers "F.Cu" "B.Cu")
		(net "SSD4_LED")
	)
	(segment
		(start 347.693742 -214.387176)
		(end 348.093538 -213.98738)
		(width 0.13208)
		(layer "F.Cu")
		(net "NIC5_MAIN_PWR_BIC_EN_R")
	)
	(via
		(at 264.368788 -213.700106)
		(size 0.508)
		(drill 0.254)
		(layers "F.Cu" "B.Cu")
		(net "NIC5_MAIN_PWR_BIC_EN_R")
	)
	(via
		(at 348.093538 -213.98738)
		(size 0.4572)
		(drill 0.254)
		(layers "F.Cu" "B.Cu")
		(net "NIC5_MAIN_PWR_BIC_EN_R")
	)
	(via
		(at 231.807512 -233.182668)
		(size 0.508)
		(drill 0.254)
		(layers "F.Cu" "B.Cu")
		(net "NIC5_MAIN_PWR_BIC_EN_R")
	)
	(segment
		(start 231.333548 -231.758744)
		(end 231.466644 -231.625648)
		(width 0.13208)
		(layer "B.Cu")
		(net "NIC5_MAIN_PWR_BIC_EN_R")
	)
	(segment
		(start 231.807512 -233.182668)
		(end 231.333548 -232.708704)
		(width 0.13208)
		(layer "B.Cu")
		(net "NIC5_MAIN_PWR_BIC_EN_R")
	)
	(segment
		(start 231.333548 -232.708704)
		(end 231.333548 -231.758744)
		(width 0.13208)
		(layer "B.Cu")
		(net "NIC5_MAIN_PWR_BIC_EN_R")
	)
	(segment
		(start 255.731264 -226.55403)
		(end 250.657868 -231.627426)
		(width 0.15494)
		(layer "In7.Cu")
		(net "NIC5_MAIN_PWR_BIC_EN_R")
	)
	(segment
		(start 234.654852 -236.221524)
		(end 234.371642 -235.938314)
		(width 0.15494)
		(layer "In7.Cu")
		(net "NIC5_MAIN_PWR_BIC_EN_R")
	)
	(segment
		(start 259.06476 -221.226634)
		(end 257.768344 -221.226634)
		(width 0.15494)
		(layer "In7.Cu")
		(net "NIC5_MAIN_PWR_BIC_EN_R")
	)
	(segment
		(start 245.1608 -236.1438)
		(end 243.713 -236.1438)
		(width 0.15494)
		(layer "In7.Cu")
		(net "NIC5_MAIN_PWR_BIC_EN_R")
	)
	(segment
		(start 250.657868 -231.627426)
		(end 250.34875 -231.627426)
		(width 0.15494)
		(layer "In7.Cu")
		(net "NIC5_MAIN_PWR_BIC_EN_R")
	)
	(segment
		(start 246.302784 -235.1786)
		(end 246.126 -235.1786)
		(width 0.15494)
		(layer "In7.Cu")
		(net "NIC5_MAIN_PWR_BIC_EN_R")
	)
	(segment
		(start 257.27406 -221.720918)
		(end 257.27406 -223.722184)
		(width 0.15494)
		(layer "In7.Cu")
		(net "NIC5_MAIN_PWR_BIC_EN_R")
	)
	(segment
		(start 262.595868 -217.695526)
		(end 259.06476 -221.226634)
		(width 0.15494)
		(layer "In7.Cu")
		(net "NIC5_MAIN_PWR_BIC_EN_R")
	)
	(segment
		(start 249.48134 -232.000044)
		(end 246.302784 -235.1786)
		(width 0.15494)
		(layer "In7.Cu")
		(net "NIC5_MAIN_PWR_BIC_EN_R")
	)
	(segment
		(start 257.27406 -223.722184)
		(end 255.731264 -225.26498)
		(width 0.15494)
		(layer "In7.Cu")
		(net "NIC5_MAIN_PWR_BIC_EN_R")
	)
	(segment
		(start 249.872754 -232.000044)
		(end 249.48134 -232.000044)
		(width 0.15494)
		(layer "In7.Cu")
		(net "NIC5_MAIN_PWR_BIC_EN_R")
	)
	(segment
		(start 246.126 -235.1786)
		(end 245.1608 -236.1438)
		(width 0.15494)
		(layer "In7.Cu")
		(net "NIC5_MAIN_PWR_BIC_EN_R")
	)
	(segment
		(start 257.768344 -221.226634)
		(end 257.27406 -221.720918)
		(width 0.15494)
		(layer "In7.Cu")
		(net "NIC5_MAIN_PWR_BIC_EN_R")
	)
	(segment
		(start 234.371642 -235.938314)
		(end 234.371642 -235.413296)
		(width 0.15494)
		(layer "In7.Cu")
		(net "NIC5_MAIN_PWR_BIC_EN_R")
	)
	(segment
		(start 264.368788 -213.700106)
		(end 264.368788 -216.097358)
		(width 0.15494)
		(layer "In7.Cu")
		(net "NIC5_MAIN_PWR_BIC_EN_R")
	)
	(segment
		(start 243.713 -236.1438)
		(end 243.635276 -236.221524)
		(width 0.15494)
		(layer "In7.Cu")
		(net "NIC5_MAIN_PWR_BIC_EN_R")
	)
	(segment
		(start 250.34875 -231.627426)
		(end 250.049284 -231.926892)
		(width 0.15494)
		(layer "In7.Cu")
		(net "NIC5_MAIN_PWR_BIC_EN_R")
	)
	(segment
		(start 250.049284 -231.926892)
		(end 249.872754 -232.000044)
		(width 0.15494)
		(layer "In7.Cu")
		(net "NIC5_MAIN_PWR_BIC_EN_R")
	)
	(segment
		(start 264.368788 -216.097358)
		(end 262.77062 -217.695526)
		(width 0.15494)
		(layer "In7.Cu")
		(net "NIC5_MAIN_PWR_BIC_EN_R")
	)
	(segment
		(start 243.635276 -236.221524)
		(end 234.654852 -236.221524)
		(width 0.15494)
		(layer "In7.Cu")
		(net "NIC5_MAIN_PWR_BIC_EN_R")
	)
	(segment
		(start 234.111546 -235.1532)
		(end 233.778044 -235.1532)
		(width 0.15494)
		(layer "In7.Cu")
		(net "NIC5_MAIN_PWR_BIC_EN_R")
	)
	(segment
		(start 255.731264 -225.26498)
		(end 255.731264 -226.55403)
		(width 0.15494)
		(layer "In7.Cu")
		(net "NIC5_MAIN_PWR_BIC_EN_R")
	)
	(segment
		(start 234.371642 -235.413296)
		(end 234.111546 -235.1532)
		(width 0.15494)
		(layer "In7.Cu")
		(net "NIC5_MAIN_PWR_BIC_EN_R")
	)
	(segment
		(start 262.77062 -217.695526)
		(end 262.595868 -217.695526)
		(width 0.15494)
		(layer "In7.Cu")
		(net "NIC5_MAIN_PWR_BIC_EN_R")
	)
	(segment
		(start 233.778044 -235.1532)
		(end 231.807512 -233.182668)
		(width 0.15494)
		(layer "In7.Cu")
		(net "NIC5_MAIN_PWR_BIC_EN_R")
	)
	(segment
		(start 344.65387 -206.770732)
		(end 344.65387 -205.95082)
		(width 0.15494)
		(layer "In15.Cu")
		(net "NIC5_MAIN_PWR_BIC_EN_R")
	)
	(segment
		(start 262.689848 -212.816694)
		(end 263.57326 -213.700106)
		(width 0.15494)
		(layer "In15.Cu")
		(net "NIC5_MAIN_PWR_BIC_EN_R")
	)
	(segment
		(start 336.37601 -201.83475)
		(end 335.73466 -201.1934)
		(width 0.15494)
		(layer "In15.Cu")
		(net "NIC5_MAIN_PWR_BIC_EN_R")
	)
	(segment
		(start 344.65387 -205.95082)
		(end 343.52865 -204.8256)
		(width 0.15494)
		(layer "In15.Cu")
		(net "NIC5_MAIN_PWR_BIC_EN_R")
	)
	(segment
		(start 338.50707 -204.8256)
		(end 338.04987 -204.3684)
		(width 0.15494)
		(layer "In15.Cu")
		(net "NIC5_MAIN_PWR_BIC_EN_R")
	)
	(segment
		(start 335.179416 -201.1934)
		(end 334.737456 -200.75144)
		(width 0.15494)
		(layer "In15.Cu")
		(net "NIC5_MAIN_PWR_BIC_EN_R")
	)
	(segment
		(start 326.458834 -200.75144)
		(end 324.692772 -202.517502)
		(width 0.15494)
		(layer "In15.Cu")
		(net "NIC5_MAIN_PWR_BIC_EN_R")
	)
	(segment
		(start 262.689848 -210.946492)
		(end 262.689848 -212.816694)
		(width 0.15494)
		(layer "In15.Cu")
		(net "NIC5_MAIN_PWR_BIC_EN_R")
	)
	(segment
		(start 335.73466 -201.1934)
		(end 335.179416 -201.1934)
		(width 0.15494)
		(layer "In15.Cu")
		(net "NIC5_MAIN_PWR_BIC_EN_R")
	)
	(segment
		(start 343.52865 -204.8256)
		(end 338.50707 -204.8256)
		(width 0.15494)
		(layer "In15.Cu")
		(net "NIC5_MAIN_PWR_BIC_EN_R")
	)
	(segment
		(start 348.491048 -210.60791)
		(end 344.65387 -206.770732)
		(width 0.15494)
		(layer "In15.Cu")
		(net "NIC5_MAIN_PWR_BIC_EN_R")
	)
	(segment
		(start 338.04987 -204.3684)
		(end 338.04987 -203.76134)
		(width 0.15494)
		(layer "In15.Cu")
		(net "NIC5_MAIN_PWR_BIC_EN_R")
	)
	(segment
		(start 334.737456 -200.75144)
		(end 326.458834 -200.75144)
		(width 0.15494)
		(layer "In15.Cu")
		(net "NIC5_MAIN_PWR_BIC_EN_R")
	)
	(segment
		(start 271.118838 -202.517502)
		(end 262.689848 -210.946492)
		(width 0.15494)
		(layer "In15.Cu")
		(net "NIC5_MAIN_PWR_BIC_EN_R")
	)
	(segment
		(start 263.57326 -213.700106)
		(end 264.368788 -213.700106)
		(width 0.15494)
		(layer "In15.Cu")
		(net "NIC5_MAIN_PWR_BIC_EN_R")
	)
	(segment
		(start 348.491048 -213.58987)
		(end 348.491048 -210.60791)
		(width 0.0889)
		(layer "In15.Cu")
		(net "NIC5_MAIN_PWR_BIC_EN_R")
	)
	(segment
		(start 324.692772 -202.517502)
		(end 271.118838 -202.517502)
		(width 0.15494)
		(layer "In15.Cu")
		(net "NIC5_MAIN_PWR_BIC_EN_R")
	)
	(segment
		(start 336.37601 -202.08748)
		(end 336.37601 -201.83475)
		(width 0.15494)
		(layer "In15.Cu")
		(net "NIC5_MAIN_PWR_BIC_EN_R")
	)
	(segment
		(start 348.093538 -213.98738)
		(end 348.491048 -213.58987)
		(width 0.0889)
		(layer "In15.Cu")
		(net "NIC5_MAIN_PWR_BIC_EN_R")
	)
	(segment
		(start 338.04987 -203.76134)
		(end 336.37601 -202.08748)
		(width 0.15494)
		(layer "In15.Cu")
		(net "NIC5_MAIN_PWR_BIC_EN_R")
	)
	(segment
		(start 48.24984 -293.99992)
		(end 47.77486 -293.52494)
		(width 0.254)
		(layer "F.Cu")
		(net "PCEPLL5_VDDA18_PEX0")
	)
	(via
		(at 34.677604 -257.137916)
		(size 0.508)
		(drill 0.254)
		(layers "F.Cu" "B.Cu")
		(net "PCEPLL5_VDDA18_PEX0")
	)
	(via
		(at 36.074604 -257.137916)
		(size 0.508)
		(drill 0.254)
		(layers "F.Cu" "B.Cu")
		(net "PCEPLL5_VDDA18_PEX0")
	)
	(via
		(at 47.77486 -293.52494)
		(size 0.4064)
		(drill 0.2032)
		(layers "F.Cu" "B.Cu")
		(net "PCEPLL5_VDDA18_PEX0")
	)
	(segment
		(start 47.77486 -293.8653)
		(end 47.77486 -293.52494)
		(width 0.3048)
		(layer "B.Cu")
		(net "PCEPLL5_VDDA18_PEX0")
	)
	(segment
		(start 47.77486 -293.10838)
		(end 47.77486 -293.52494)
		(width 0.3048)
		(layer "B.Cu")
		(net "PCEPLL5_VDDA18_PEX0")
	)
	(segment
		(start 206.41437 -295.647872)
		(end 206.41437 -296.40403)
		(width 0.13208)
		(layer "F.Cu")
		(net "I2C_PEX1_HOST_R_SDA")
	)
	(segment
		(start 206.121254 -298.47286)
		(end 206.121254 -298.190412)
		(width 0.13208)
		(layer "F.Cu")
		(net "I2C_PEX1_HOST_R_SDA")
	)
	(segment
		(start 205.998572 -298.06773)
		(end 205.998572 -297.46448)
		(width 0.13208)
		(layer "F.Cu")
		(net "I2C_PEX1_HOST_R_SDA")
	)
	(segment
		(start 206.41437 -296.40403)
		(end 206.205328 -296.613072)
		(width 0.13208)
		(layer "F.Cu")
		(net "I2C_PEX1_HOST_R_SDA")
	)
	(segment
		(start 205.998572 -296.867072)
		(end 205.744572 -296.613072)
		(width 0.13208)
		(layer "F.Cu")
		(net "I2C_PEX1_HOST_R_SDA")
	)
	(segment
		(start 205.998572 -297.46448)
		(end 205.998572 -296.867072)
		(width 0.13208)
		(layer "F.Cu")
		(net "I2C_PEX1_HOST_R_SDA")
	)
	(segment
		(start 206.121254 -298.190412)
		(end 205.998572 -298.06773)
		(width 0.13208)
		(layer "F.Cu")
		(net "I2C_PEX1_HOST_R_SDA")
	)
	(segment
		(start 205.105254 -298.47286)
		(end 206.121254 -298.47286)
		(width 0.13208)
		(layer "F.Cu")
		(net "I2C_PEX1_HOST_R_SDA")
	)
	(segment
		(start 206.205328 -296.613072)
		(end 205.744572 -296.613072)
		(width 0.13208)
		(layer "F.Cu")
		(net "I2C_PEX1_HOST_R_SDA")
	)
	(via
		(at 205.744572 -296.613072)
		(size 0.508)
		(drill 0.254)
		(layers "F.Cu" "B.Cu")
		(net "I2C_PEX1_HOST_R_SDA")
	)
	(segment
		(start 349.000064 -171.566078)
		(end 350.255078 -171.566078)
		(width 0.13208)
		(layer "F.Cu")
		(net "SMB_PEX2_PCA9555_SCL")
	)
	(segment
		(start 324.083934 -288.253424)
		(end 324.051676 -288.221166)
		(width 0.13208)
		(layer "F.Cu")
		(net "SMB_PEX2_PCA9555_SCL")
	)
	(segment
		(start 324.083934 -288.830766)
		(end 324.083934 -288.253424)
		(width 0.13208)
		(layer "F.Cu")
		(net "SMB_PEX2_PCA9555_SCL")
	)
	(segment
		(start 349.000064 -183.504078)
		(end 350.255078 -183.504078)
		(width 0.13208)
		(layer "F.Cu")
		(net "SMB_PEX2_PCA9555_SCL")
	)
	(via
		(at 350.255078 -183.504078)
		(size 0.508)
		(drill 0.254)
		(layers "F.Cu" "B.Cu")
		(net "SMB_PEX2_PCA9555_SCL")
	)
	(via
		(at 324.051676 -288.221166)
		(size 0.508)
		(drill 0.254)
		(layers "F.Cu" "B.Cu")
		(net "SMB_PEX2_PCA9555_SCL")
	)
	(via
		(at 317.018924 -255.1938)
		(size 0.508)
		(drill 0.254)
		(layers "F.Cu" "B.Cu")
		(net "SMB_PEX2_PCA9555_SCL")
	)
	(via
		(at 350.255078 -171.566078)
		(size 0.508)
		(drill 0.254)
		(layers "F.Cu" "B.Cu")
		(net "SMB_PEX2_PCA9555_SCL")
	)
	(segment
		(start 317.018924 -255.207262)
		(end 317.018924 -255.1938)
		(width 0.13208)
		(layer "B.Cu")
		(net "SMB_PEX2_PCA9555_SCL")
	)
	(segment
		(start 324.051676 -288.221166)
		(end 323.37502 -288.897822)
		(width 0.13208)
		(layer "B.Cu")
		(net "SMB_PEX2_PCA9555_SCL")
	)
	(segment
		(start 321.579494 -288.602674)
		(end 321.579494 -278.36749)
		(width 0.13208)
		(layer "B.Cu")
		(net "SMB_PEX2_PCA9555_SCL")
	)
	(segment
		(start 321.579494 -278.36749)
		(end 327.251314 -272.69567)
		(width 0.13208)
		(layer "B.Cu")
		(net "SMB_PEX2_PCA9555_SCL")
	)
	(segment
		(start 327.251314 -272.69567)
		(end 327.251314 -265.439652)
		(width 0.13208)
		(layer "B.Cu")
		(net "SMB_PEX2_PCA9555_SCL")
	)
	(segment
		(start 327.251314 -265.439652)
		(end 317.018924 -255.207262)
		(width 0.13208)
		(layer "B.Cu")
		(net "SMB_PEX2_PCA9555_SCL")
	)
	(segment
		(start 323.37502 -288.897822)
		(end 321.874642 -288.897822)
		(width 0.13208)
		(layer "B.Cu")
		(net "SMB_PEX2_PCA9555_SCL")
	)
	(segment
		(start 321.874642 -288.897822)
		(end 321.579494 -288.602674)
		(width 0.13208)
		(layer "B.Cu")
		(net "SMB_PEX2_PCA9555_SCL")
	)
	(segment
		(start 350.255078 -172.626528)
		(end 351.032572 -174.503588)
		(width 0.15494)
		(layer "In9.Cu")
		(net "SMB_PEX2_PCA9555_SCL")
	)
	(segment
		(start 350.255078 -171.566078)
		(end 350.255078 -172.626528)
		(width 0.15494)
		(layer "In9.Cu")
		(net "SMB_PEX2_PCA9555_SCL")
	)
	(segment
		(start 351.166684 -182.592472)
		(end 350.255078 -183.504078)
		(width 0.15494)
		(layer "In9.Cu")
		(net "SMB_PEX2_PCA9555_SCL")
	)
	(segment
		(start 351.166684 -174.827438)
		(end 351.166684 -182.592472)
		(width 0.15494)
		(layer "In9.Cu")
		(net "SMB_PEX2_PCA9555_SCL")
	)
	(segment
		(start 351.032572 -174.503588)
		(end 351.166684 -174.827438)
		(width 0.15494)
		(layer "In9.Cu")
		(net "SMB_PEX2_PCA9555_SCL")
	)
	(segment
		(start 350.267778 -245.5164)
		(end 346.74302 -245.5164)
		(width 0.15494)
		(layer "In13.Cu")
		(net "SMB_PEX2_PCA9555_SCL")
	)
	(segment
		(start 338.615528 -254.116586)
		(end 317.66256 -254.116586)
		(width 0.15494)
		(layer "In13.Cu")
		(net "SMB_PEX2_PCA9555_SCL")
	)
	(segment
		(start 377.344178 -183.668924)
		(end 382.7272 -189.051946)
		(width 0.15494)
		(layer "In13.Cu")
		(net "SMB_PEX2_PCA9555_SCL")
	)
	(segment
		(start 341.17788 -251.08154)
		(end 341.17788 -251.554234)
		(width 0.15494)
		(layer "In13.Cu")
		(net "SMB_PEX2_PCA9555_SCL")
	)
	(segment
		(start 361.138978 -234.6452)
		(end 350.267778 -245.5164)
		(width 0.15494)
		(layer "In13.Cu")
		(net "SMB_PEX2_PCA9555_SCL")
	)
	(segment
		(start 317.018924 -254.760222)
		(end 317.018924 -255.1938)
		(width 0.15494)
		(layer "In13.Cu")
		(net "SMB_PEX2_PCA9555_SCL")
	)
	(segment
		(start 377.0376 -222.2246)
		(end 375.9708 -223.2914)
		(width 0.15494)
		(layer "In13.Cu")
		(net "SMB_PEX2_PCA9555_SCL")
	)
	(segment
		(start 355.774244 -184.656984)
		(end 360.999278 -184.656984)
		(width 0.15494)
		(layer "In13.Cu")
		(net "SMB_PEX2_PCA9555_SCL")
	)
	(segment
		(start 375.9708 -223.2914)
		(end 375.9708 -228.904546)
		(width 0.15494)
		(layer "In13.Cu")
		(net "SMB_PEX2_PCA9555_SCL")
	)
	(segment
		(start 361.987338 -183.668924)
		(end 377.344178 -183.668924)
		(width 0.15494)
		(layer "In13.Cu")
		(net "SMB_PEX2_PCA9555_SCL")
	)
	(segment
		(start 375.9708 -228.904546)
		(end 370.230146 -234.6452)
		(width 0.15494)
		(layer "In13.Cu")
		(net "SMB_PEX2_PCA9555_SCL")
	)
	(segment
		(start 360.999278 -184.656984)
		(end 361.987338 -183.668924)
		(width 0.15494)
		(layer "In13.Cu")
		(net "SMB_PEX2_PCA9555_SCL")
	)
	(segment
		(start 341.17788 -251.554234)
		(end 338.615528 -254.116586)
		(width 0.15494)
		(layer "In13.Cu")
		(net "SMB_PEX2_PCA9555_SCL")
	)
	(segment
		(start 370.230146 -234.6452)
		(end 361.138978 -234.6452)
		(width 0.15494)
		(layer "In13.Cu")
		(net "SMB_PEX2_PCA9555_SCL")
	)
	(segment
		(start 346.74302 -245.5164)
		(end 341.17788 -251.08154)
		(width 0.15494)
		(layer "In13.Cu")
		(net "SMB_PEX2_PCA9555_SCL")
	)
	(segment
		(start 353.84486 -182.7276)
		(end 355.774244 -184.656984)
		(width 0.15494)
		(layer "In13.Cu")
		(net "SMB_PEX2_PCA9555_SCL")
	)
	(segment
		(start 382.7272 -214.319358)
		(end 377.0376 -220.008958)
		(width 0.15494)
		(layer "In13.Cu")
		(net "SMB_PEX2_PCA9555_SCL")
	)
	(segment
		(start 351.031556 -182.7276)
		(end 353.84486 -182.7276)
		(width 0.15494)
		(layer "In13.Cu")
		(net "SMB_PEX2_PCA9555_SCL")
	)
	(segment
		(start 350.255078 -183.504078)
		(end 351.031556 -182.7276)
		(width 0.15494)
		(layer "In13.Cu")
		(net "SMB_PEX2_PCA9555_SCL")
	)
	(segment
		(start 377.0376 -220.008958)
		(end 377.0376 -222.2246)
		(width 0.15494)
		(layer "In13.Cu")
		(net "SMB_PEX2_PCA9555_SCL")
	)
	(segment
		(start 382.7272 -189.051946)
		(end 382.7272 -214.319358)
		(width 0.15494)
		(layer "In13.Cu")
		(net "SMB_PEX2_PCA9555_SCL")
	)
	(segment
		(start 317.66256 -254.116586)
		(end 317.018924 -254.760222)
		(width 0.15494)
		(layer "In13.Cu")
		(net "SMB_PEX2_PCA9555_SCL")
	)
	(segment
		(start 282.334462 -28.469082)
		(end 282.334462 -28.550108)
		(width 0.13208)
		(layer "F.Cu")
		(net "SSD9_PWRDIS_R")
	)
	(segment
		(start 282.334462 -28.550108)
		(end 282.864306 -29.079952)
		(width 0.13208)
		(layer "F.Cu")
		(net "SSD9_PWRDIS_R")
	)
	(segment
		(start 336.55 -200.76795)
		(end 336.55 -200.152)
		(width 0.13208)
		(layer "F.Cu")
		(net "SSD9_PWRDIS_R")
	)
	(segment
		(start 273.464782 -25.390094)
		(end 272.391124 -25.390094)
		(width 0.13208)
		(layer "F.Cu")
		(net "SSD9_PWRDIS_R")
	)
	(via
		(at 336.55 -200.152)
		(size 0.508)
		(drill 0.254)
		(layers "F.Cu" "B.Cu")
		(net "SSD9_PWRDIS_R")
	)
	(via
		(at 282.334462 -28.469082)
		(size 0.508)
		(drill 0.254)
		(layers "F.Cu" "B.Cu")
		(net "SSD9_PWRDIS_R")
	)
	(via
		(at 314.526422 -80.593184)
		(size 0.508)
		(drill 0.254)
		(layers "F.Cu" "B.Cu")
		(net "SSD9_PWRDIS_R")
	)
	(via
		(at 272.391124 -25.390094)
		(size 0.508)
		(drill 0.254)
		(layers "F.Cu" "B.Cu")
		(net "SSD9_PWRDIS_R")
	)
	(via
		(at 299.22343 -79.297022)
		(size 0.508)
		(drill 0.254)
		(layers "F.Cu" "B.Cu")
		(net "SSD9_PWRDIS_R")
	)
	(segment
		(start 340.397846 -166.285926)
		(end 339.674962 -167.00881)
		(width 0.15494)
		(layer "In5.Cu")
		(net "SSD9_PWRDIS_R")
	)
	(segment
		(start 279.273254 -28.469082)
		(end 282.334462 -28.469082)
		(width 0.15494)
		(layer "In5.Cu")
		(net "SSD9_PWRDIS_R")
	)
	(segment
		(start 316.097412 -114.872516)
		(end 320.314066 -119.08917)
		(width 0.15494)
		(layer "In5.Cu")
		(net "SSD9_PWRDIS_R")
	)
	(segment
		(start 274.612608 -25.034748)
		(end 275.31314 -25.527508)
		(width 0.15494)
		(layer "In5.Cu")
		(net "SSD9_PWRDIS_R")
	)
	(segment
		(start 276.933914 -27.333448)
		(end 278.13762 -27.333448)
		(width 0.15494)
		(layer "In5.Cu")
		(net "SSD9_PWRDIS_R")
	)
	(segment
		(start 281.584908 -32.892492)
		(end 281.584908 -29.6926)
		(width 0.15494)
		(layer "In5.Cu")
		(net "SSD9_PWRDIS_R")
	)
	(segment
		(start 336.024982 -187.809886)
		(end 335.86166 -187.973208)
		(width 0.15494)
		(layer "In5.Cu")
		(net "SSD9_PWRDIS_R")
	)
	(segment
		(start 320.314066 -125.48235)
		(end 323.780658 -128.948942)
		(width 0.15494)
		(layer "In5.Cu")
		(net "SSD9_PWRDIS_R")
	)
	(segment
		(start 299.22343 -79.297022)
		(end 297.311826 -79.297022)
		(width 0.15494)
		(layer "In5.Cu")
		(net "SSD9_PWRDIS_R")
	)
	(segment
		(start 294.40886 -45.716444)
		(end 281.584908 -32.892492)
		(width 0.15494)
		(layer "In5.Cu")
		(net "SSD9_PWRDIS_R")
	)
	(segment
		(start 278.13762 -27.333448)
		(end 279.273254 -28.469082)
		(width 0.15494)
		(layer "In5.Cu")
		(net "SSD9_PWRDIS_R")
	)
	(segment
		(start 320.314066 -119.08917)
		(end 320.314066 -125.48235)
		(width 0.15494)
		(layer "In5.Cu")
		(net "SSD9_PWRDIS_R")
	)
	(segment
		(start 339.729572 -157.837632)
		(end 339.729572 -165.065456)
		(width 0.15494)
		(layer "In5.Cu")
		(net "SSD9_PWRDIS_R")
	)
	(segment
		(start 297.311826 -79.297022)
		(end 294.40886 -76.394056)
		(width 0.15494)
		(layer "In5.Cu")
		(net "SSD9_PWRDIS_R")
	)
	(segment
		(start 275.31314 -25.527508)
		(end 275.855684 -26.255218)
		(width 0.15494)
		(layer "In5.Cu")
		(net "SSD9_PWRDIS_R")
	)
	(segment
		(start 339.674962 -167.00881)
		(end 339.674962 -176.187608)
		(width 0.15494)
		(layer "In5.Cu")
		(net "SSD9_PWRDIS_R")
	)
	(segment
		(start 323.780658 -132.776468)
		(end 329.321414 -138.317224)
		(width 0.15494)
		(layer "In5.Cu")
		(net "SSD9_PWRDIS_R")
	)
	(segment
		(start 335.269586 -138.317224)
		(end 338.563204 -141.610842)
		(width 0.15494)
		(layer "In5.Cu")
		(net "SSD9_PWRDIS_R")
	)
	(segment
		(start 339.611208 -148.50872)
		(end 339.611208 -154.112468)
		(width 0.15494)
		(layer "In5.Cu")
		(net "SSD9_PWRDIS_R")
	)
	(segment
		(start 272.391124 -25.390094)
		(end 272.74647 -25.034748)
		(width 0.15494)
		(layer "In5.Cu")
		(net "SSD9_PWRDIS_R")
	)
	(segment
		(start 282.334462 -28.943046)
		(end 282.334462 -28.469082)
		(width 0.15494)
		(layer "In5.Cu")
		(net "SSD9_PWRDIS_R")
	)
	(segment
		(start 336.55 -199.199246)
		(end 336.55 -200.152)
		(width 0.15494)
		(layer "In5.Cu")
		(net "SSD9_PWRDIS_R")
	)
	(segment
		(start 272.74647 -25.034748)
		(end 274.612608 -25.034748)
		(width 0.15494)
		(layer "In5.Cu")
		(net "SSD9_PWRDIS_R")
	)
	(segment
		(start 336.024982 -179.837588)
		(end 336.024982 -187.809886)
		(width 0.15494)
		(layer "In5.Cu")
		(net "SSD9_PWRDIS_R")
	)
	(segment
		(start 339.674962 -176.187608)
		(end 336.024982 -179.837588)
		(width 0.15494)
		(layer "In5.Cu")
		(net "SSD9_PWRDIS_R")
	)
	(segment
		(start 339.364574 -157.472634)
		(end 339.729572 -157.837632)
		(width 0.15494)
		(layer "In5.Cu")
		(net "SSD9_PWRDIS_R")
	)
	(segment
		(start 275.855684 -26.255218)
		(end 276.933914 -27.333448)
		(width 0.15494)
		(layer "In5.Cu")
		(net "SSD9_PWRDIS_R")
	)
	(segment
		(start 323.780658 -128.948942)
		(end 323.780658 -132.776468)
		(width 0.15494)
		(layer "In5.Cu")
		(net "SSD9_PWRDIS_R")
	)
	(segment
		(start 339.364574 -154.359102)
		(end 339.364574 -157.472634)
		(width 0.15494)
		(layer "In5.Cu")
		(net "SSD9_PWRDIS_R")
	)
	(segment
		(start 294.40886 -76.394056)
		(end 294.40886 -45.716444)
		(width 0.15494)
		(layer "In5.Cu")
		(net "SSD9_PWRDIS_R")
	)
	(segment
		(start 314.526422 -80.593184)
		(end 316.097412 -82.164174)
		(width 0.15494)
		(layer "In5.Cu")
		(net "SSD9_PWRDIS_R")
	)
	(segment
		(start 338.563204 -141.610842)
		(end 338.563204 -147.460716)
		(width 0.15494)
		(layer "In5.Cu")
		(net "SSD9_PWRDIS_R")
	)
	(segment
		(start 335.86166 -187.973208)
		(end 335.86166 -198.510906)
		(width 0.15494)
		(layer "In5.Cu")
		(net "SSD9_PWRDIS_R")
	)
	(segment
		(start 339.611208 -154.112468)
		(end 339.364574 -154.359102)
		(width 0.15494)
		(layer "In5.Cu")
		(net "SSD9_PWRDIS_R")
	)
	(segment
		(start 316.097412 -82.164174)
		(end 316.097412 -114.872516)
		(width 0.15494)
		(layer "In5.Cu")
		(net "SSD9_PWRDIS_R")
	)
	(segment
		(start 339.729572 -165.065456)
		(end 340.397846 -165.73373)
		(width 0.15494)
		(layer "In5.Cu")
		(net "SSD9_PWRDIS_R")
	)
	(segment
		(start 281.584908 -29.6926)
		(end 282.334462 -28.943046)
		(width 0.15494)
		(layer "In5.Cu")
		(net "SSD9_PWRDIS_R")
	)
	(segment
		(start 338.563204 -147.460716)
		(end 339.611208 -148.50872)
		(width 0.15494)
		(layer "In5.Cu")
		(net "SSD9_PWRDIS_R")
	)
	(segment
		(start 340.397846 -165.73373)
		(end 340.397846 -166.285926)
		(width 0.15494)
		(layer "In5.Cu")
		(net "SSD9_PWRDIS_R")
	)
	(segment
		(start 329.321414 -138.317224)
		(end 335.269586 -138.317224)
		(width 0.15494)
		(layer "In5.Cu")
		(net "SSD9_PWRDIS_R")
	)
	(segment
		(start 335.86166 -198.510906)
		(end 336.55 -199.199246)
		(width 0.15494)
		(layer "In5.Cu")
		(net "SSD9_PWRDIS_R")
	)
	(segment
		(start 304.242724 -79.297022)
		(end 304.469546 -79.0702)
		(width 0.15494)
		(layer "In9.Cu")
		(net "SSD9_PWRDIS_R")
	)
	(segment
		(start 299.22343 -79.297022)
		(end 304.242724 -79.297022)
		(width 0.15494)
		(layer "In9.Cu")
		(net "SSD9_PWRDIS_R")
	)
	(segment
		(start 304.469546 -79.0702)
		(end 308.789324 -79.0702)
		(width 0.15494)
		(layer "In9.Cu")
		(net "SSD9_PWRDIS_R")
	)
	(segment
		(start 310.745124 -81.026)
		(end 314.093606 -81.026)
		(width 0.15494)
		(layer "In9.Cu")
		(net "SSD9_PWRDIS_R")
	)
	(segment
		(start 308.789324 -79.0702)
		(end 310.745124 -81.026)
		(width 0.15494)
		(layer "In9.Cu")
		(net "SSD9_PWRDIS_R")
	)
	(segment
		(start 314.093606 -81.026)
		(end 314.526422 -80.593184)
		(width 0.15494)
		(layer "In9.Cu")
		(net "SSD9_PWRDIS_R")
	)
	(segment
		(start 208.020158 -84.675472)
		(end 208.329784 -84.365846)
		(width 0.13208)
		(layer "F.Cu")
		(net "SSD0_LED")
	)
	(segment
		(start 208.329784 -84.365846)
		(end 208.935066 -83.760564)
		(width 0.13208)
		(layer "F.Cu")
		(net "SSD0_LED")
	)
	(segment
		(start 208.935066 -83.760564)
		(end 211.572094 -83.760564)
		(width 0.13208)
		(layer "F.Cu")
		(net "SSD0_LED")
	)
	(segment
		(start 207.023208 -84.675472)
		(end 208.020158 -84.675472)
		(width 0.13208)
		(layer "F.Cu")
		(net "SSD0_LED")
	)
	(via
		(at 208.329784 -84.365846)
		(size 0.762)
		(drill 0.381)
		(layers "F.Cu" "B.Cu")
		(net "SSD0_LED")
	)
	(segment
		(start 228.759512 -231.928162)
		(end 228.759512 -232.471468)
		(width 0.13208)
		(layer "F.Cu")
		(net "NIC2_MAIN_PWR_BIC_EN_R")
	)
	(segment
		(start 346.893896 -216.786968)
		(end 347.293692 -216.387172)
		(width 0.13208)
		(layer "F.Cu")
		(net "NIC2_MAIN_PWR_BIC_EN_R")
	)
	(segment
		(start 228.6508 -231.81945)
		(end 228.759512 -231.928162)
		(width 0.13208)
		(layer "F.Cu")
		(net "NIC2_MAIN_PWR_BIC_EN_R")
	)
	(via
		(at 263.047226 -191.975486)
		(size 0.508)
		(drill 0.254)
		(layers "F.Cu" "B.Cu")
		(net "NIC2_MAIN_PWR_BIC_EN_R")
	)
	(via
		(at 347.293692 -216.387172)
		(size 0.4572)
		(drill 0.254)
		(layers "F.Cu" "B.Cu")
		(net "NIC2_MAIN_PWR_BIC_EN_R")
	)
	(via
		(at 266.790932 -212.799422)
		(size 0.508)
		(drill 0.254)
		(layers "F.Cu" "B.Cu")
		(net "NIC2_MAIN_PWR_BIC_EN_R")
	)
	(via
		(at 228.759512 -232.471468)
		(size 0.508)
		(drill 0.254)
		(layers "F.Cu" "B.Cu")
		(net "NIC2_MAIN_PWR_BIC_EN_R")
	)
	(segment
		(start 263.7536 -198.766684)
		(end 263.7536 -205.307946)
		(width 0.15494)
		(layer "In5.Cu")
		(net "NIC2_MAIN_PWR_BIC_EN_R")
	)
	(segment
		(start 264.5156 -206.069946)
		(end 264.5156 -208.570576)
		(width 0.15494)
		(layer "In5.Cu")
		(net "NIC2_MAIN_PWR_BIC_EN_R")
	)
	(segment
		(start 263.7536 -205.307946)
		(end 264.5156 -206.069946)
		(width 0.15494)
		(layer "In5.Cu")
		(net "NIC2_MAIN_PWR_BIC_EN_R")
	)
	(segment
		(start 264.5156 -208.570576)
		(end 266.790932 -210.845908)
		(width 0.15494)
		(layer "In5.Cu")
		(net "NIC2_MAIN_PWR_BIC_EN_R")
	)
	(segment
		(start 263.481312 -191.5414)
		(end 264.0076 -191.5414)
		(width 0.15494)
		(layer "In5.Cu")
		(net "NIC2_MAIN_PWR_BIC_EN_R")
	)
	(segment
		(start 266.790932 -210.845908)
		(end 266.790932 -212.799422)
		(width 0.15494)
		(layer "In5.Cu")
		(net "NIC2_MAIN_PWR_BIC_EN_R")
	)
	(segment
		(start 264.0076 -191.5414)
		(end 264.3632 -191.897)
		(width 0.15494)
		(layer "In5.Cu")
		(net "NIC2_MAIN_PWR_BIC_EN_R")
	)
	(segment
		(start 263.047226 -191.975486)
		(end 263.481312 -191.5414)
		(width 0.15494)
		(layer "In5.Cu")
		(net "NIC2_MAIN_PWR_BIC_EN_R")
	)
	(segment
		(start 264.3632 -191.897)
		(end 264.3632 -197.294754)
		(width 0.15494)
		(layer "In5.Cu")
		(net "NIC2_MAIN_PWR_BIC_EN_R")
	)
	(segment
		(start 264.3632 -197.294754)
		(end 263.7536 -198.766684)
		(width 0.15494)
		(layer "In5.Cu")
		(net "NIC2_MAIN_PWR_BIC_EN_R")
	)
	(segment
		(start 250.79452 -232.701846)
		(end 251.103638 -232.701846)
		(width 0.15494)
		(layer "In7.Cu")
		(net "NIC2_MAIN_PWR_BIC_EN_R")
	)
	(segment
		(start 265.086592 -219.63634)
		(end 265.7856 -218.937332)
		(width 0.15494)
		(layer "In7.Cu")
		(net "NIC2_MAIN_PWR_BIC_EN_R")
	)
	(segment
		(start 266.551918 -213.038436)
		(end 266.790932 -212.799422)
		(width 0.15494)
		(layer "In7.Cu")
		(net "NIC2_MAIN_PWR_BIC_EN_R")
	)
	(segment
		(start 256.805684 -226.9998)
		(end 256.805684 -225.740976)
		(width 0.15494)
		(layer "In7.Cu")
		(net "NIC2_MAIN_PWR_BIC_EN_R")
	)
	(segment
		(start 251.103638 -232.701846)
		(end 256.805684 -226.9998)
		(width 0.15494)
		(layer "In7.Cu")
		(net "NIC2_MAIN_PWR_BIC_EN_R")
	)
	(segment
		(start 250.200414 -233.074464)
		(end 250.578366 -232.918)
		(width 0.15494)
		(layer "In7.Cu")
		(net "NIC2_MAIN_PWR_BIC_EN_R")
	)
	(segment
		(start 265.7856 -217.425524)
		(end 266.551918 -216.659206)
		(width 0.15494)
		(layer "In7.Cu")
		(net "NIC2_MAIN_PWR_BIC_EN_R")
	)
	(segment
		(start 266.551918 -216.659206)
		(end 266.551918 -213.038436)
		(width 0.15494)
		(layer "In7.Cu")
		(net "NIC2_MAIN_PWR_BIC_EN_R")
	)
	(segment
		(start 258.1402 -224.40773)
		(end 259.153152 -223.394778)
		(width 0.15494)
		(layer "In7.Cu")
		(net "NIC2_MAIN_PWR_BIC_EN_R")
	)
	(segment
		(start 261.572756 -220.345)
		(end 262.281416 -219.63634)
		(width 0.15494)
		(layer "In7.Cu")
		(net "NIC2_MAIN_PWR_BIC_EN_R")
	)
	(segment
		(start 258.13893 -224.40773)
		(end 258.1402 -224.40773)
		(width 0.15494)
		(layer "In7.Cu")
		(net "NIC2_MAIN_PWR_BIC_EN_R")
	)
	(segment
		(start 259.153152 -222.761302)
		(end 261.569454 -220.345)
		(width 0.15494)
		(layer "In7.Cu")
		(net "NIC2_MAIN_PWR_BIC_EN_R")
	)
	(segment
		(start 243.947696 -238.002826)
		(end 243.947696 -237.601506)
		(width 0.15494)
		(layer "In7.Cu")
		(net "NIC2_MAIN_PWR_BIC_EN_R")
	)
	(segment
		(start 229.300532 -234.602274)
		(end 233.074718 -238.37646)
		(width 0.15494)
		(layer "In7.Cu")
		(net "NIC2_MAIN_PWR_BIC_EN_R")
	)
	(segment
		(start 265.7856 -218.937332)
		(end 265.7856 -217.425524)
		(width 0.15494)
		(layer "In7.Cu")
		(net "NIC2_MAIN_PWR_BIC_EN_R")
	)
	(segment
		(start 245.561358 -237.318296)
		(end 246.502174 -236.37748)
		(width 0.15494)
		(layer "In7.Cu")
		(net "NIC2_MAIN_PWR_BIC_EN_R")
	)
	(segment
		(start 246.502174 -236.37748)
		(end 246.624094 -236.37748)
		(width 0.15494)
		(layer "In7.Cu")
		(net "NIC2_MAIN_PWR_BIC_EN_R")
	)
	(segment
		(start 250.578366 -232.918)
		(end 250.79452 -232.701846)
		(width 0.15494)
		(layer "In7.Cu")
		(net "NIC2_MAIN_PWR_BIC_EN_R")
	)
	(segment
		(start 262.281416 -219.63634)
		(end 265.086592 -219.63634)
		(width 0.15494)
		(layer "In7.Cu")
		(net "NIC2_MAIN_PWR_BIC_EN_R")
	)
	(segment
		(start 259.153152 -223.394778)
		(end 259.153152 -222.761302)
		(width 0.15494)
		(layer "In7.Cu")
		(net "NIC2_MAIN_PWR_BIC_EN_R")
	)
	(segment
		(start 228.759512 -232.471468)
		(end 229.300532 -233.012488)
		(width 0.15494)
		(layer "In7.Cu")
		(net "NIC2_MAIN_PWR_BIC_EN_R")
	)
	(segment
		(start 243.574062 -238.37646)
		(end 243.947696 -238.002826)
		(width 0.15494)
		(layer "In7.Cu")
		(net "NIC2_MAIN_PWR_BIC_EN_R")
	)
	(segment
		(start 243.947696 -237.601506)
		(end 244.230906 -237.318296)
		(width 0.15494)
		(layer "In7.Cu")
		(net "NIC2_MAIN_PWR_BIC_EN_R")
	)
	(segment
		(start 246.624094 -236.37748)
		(end 249.92711 -233.074464)
		(width 0.15494)
		(layer "In7.Cu")
		(net "NIC2_MAIN_PWR_BIC_EN_R")
	)
	(segment
		(start 244.230906 -237.318296)
		(end 245.561358 -237.318296)
		(width 0.15494)
		(layer "In7.Cu")
		(net "NIC2_MAIN_PWR_BIC_EN_R")
	)
	(segment
		(start 233.074718 -238.37646)
		(end 243.574062 -238.37646)
		(width 0.15494)
		(layer "In7.Cu")
		(net "NIC2_MAIN_PWR_BIC_EN_R")
	)
	(segment
		(start 229.300532 -233.012488)
		(end 229.300532 -234.602274)
		(width 0.15494)
		(layer "In7.Cu")
		(net "NIC2_MAIN_PWR_BIC_EN_R")
	)
	(segment
		(start 249.92711 -233.074464)
		(end 250.200414 -233.074464)
		(width 0.15494)
		(layer "In7.Cu")
		(net "NIC2_MAIN_PWR_BIC_EN_R")
	)
	(segment
		(start 256.805684 -225.740976)
		(end 258.13893 -224.40773)
		(width 0.15494)
		(layer "In7.Cu")
		(net "NIC2_MAIN_PWR_BIC_EN_R")
	)
	(segment
		(start 261.569454 -220.345)
		(end 261.572756 -220.345)
		(width 0.15494)
		(layer "In7.Cu")
		(net "NIC2_MAIN_PWR_BIC_EN_R")
	)
	(segment
		(start 339.06587 -199.794622)
		(end 336.372454 -197.101206)
		(width 0.15494)
		(layer "In15.Cu")
		(net "NIC2_MAIN_PWR_BIC_EN_R")
	)
	(segment
		(start 324.156578 -197.734174)
		(end 323.57568 -197.153276)
		(width 0.15494)
		(layer "In15.Cu")
		(net "NIC2_MAIN_PWR_BIC_EN_R")
	)
	(segment
		(start 263.361678 -191.661034)
		(end 263.047226 -191.975486)
		(width 0.15494)
		(layer "In15.Cu")
		(net "NIC2_MAIN_PWR_BIC_EN_R")
	)
	(segment
		(start 326.62622 -196.766434)
		(end 325.65848 -197.734174)
		(width 0.15494)
		(layer "In15.Cu")
		(net "NIC2_MAIN_PWR_BIC_EN_R")
	)
	(segment
		(start 323.57568 -197.153276)
		(end 277.584408 -197.153276)
		(width 0.15494)
		(layer "In15.Cu")
		(net "NIC2_MAIN_PWR_BIC_EN_R")
	)
	(segment
		(start 344.299794 -200.63587)
		(end 339.39734 -200.63587)
		(width 0.15494)
		(layer "In15.Cu")
		(net "NIC2_MAIN_PWR_BIC_EN_R")
	)
	(segment
		(start 325.65848 -197.734174)
		(end 324.156578 -197.734174)
		(width 0.15494)
		(layer "In15.Cu")
		(net "NIC2_MAIN_PWR_BIC_EN_R")
	)
	(segment
		(start 329.25258 -196.766434)
		(end 326.62622 -196.766434)
		(width 0.15494)
		(layer "In15.Cu")
		(net "NIC2_MAIN_PWR_BIC_EN_R")
	)
	(segment
		(start 351.917 -216.2937)
		(end 351.917 -215.9762)
		(width 0.0889)
		(layer "In15.Cu")
		(net "NIC2_MAIN_PWR_BIC_EN_R")
	)
	(segment
		(start 346.492068 -202.828144)
		(end 344.299794 -200.63587)
		(width 0.15494)
		(layer "In15.Cu")
		(net "NIC2_MAIN_PWR_BIC_EN_R")
	)
	(segment
		(start 347.293692 -216.387172)
		(end 347.668342 -216.761822)
		(width 0.0889)
		(layer "In15.Cu")
		(net "NIC2_MAIN_PWR_BIC_EN_R")
	)
	(segment
		(start 336.372454 -197.101206)
		(end 329.587352 -197.101206)
		(width 0.15494)
		(layer "In15.Cu")
		(net "NIC2_MAIN_PWR_BIC_EN_R")
	)
	(segment
		(start 351.08007 -205.2066)
		(end 348.701614 -202.828144)
		(width 0.15494)
		(layer "In15.Cu")
		(net "NIC2_MAIN_PWR_BIC_EN_R")
	)
	(segment
		(start 347.668342 -216.761822)
		(end 351.448878 -216.761822)
		(width 0.0889)
		(layer "In15.Cu")
		(net "NIC2_MAIN_PWR_BIC_EN_R")
	)
	(segment
		(start 272.092166 -191.661034)
		(end 263.361678 -191.661034)
		(width 0.15494)
		(layer "In15.Cu")
		(net "NIC2_MAIN_PWR_BIC_EN_R")
	)
	(segment
		(start 348.701614 -202.828144)
		(end 346.492068 -202.828144)
		(width 0.15494)
		(layer "In15.Cu")
		(net "NIC2_MAIN_PWR_BIC_EN_R")
	)
	(segment
		(start 329.587352 -197.101206)
		(end 329.25258 -196.766434)
		(width 0.15494)
		(layer "In15.Cu")
		(net "NIC2_MAIN_PWR_BIC_EN_R")
	)
	(segment
		(start 351.917 -215.9762)
		(end 352.417634 -215.475566)
		(width 0.15494)
		(layer "In15.Cu")
		(net "NIC2_MAIN_PWR_BIC_EN_R")
	)
	(segment
		(start 352.417634 -206.037942)
		(end 351.586292 -205.2066)
		(width 0.15494)
		(layer "In15.Cu")
		(net "NIC2_MAIN_PWR_BIC_EN_R")
	)
	(segment
		(start 339.39734 -200.63587)
		(end 339.06587 -200.3044)
		(width 0.15494)
		(layer "In15.Cu")
		(net "NIC2_MAIN_PWR_BIC_EN_R")
	)
	(segment
		(start 352.417634 -215.475566)
		(end 352.417634 -206.037942)
		(width 0.15494)
		(layer "In15.Cu")
		(net "NIC2_MAIN_PWR_BIC_EN_R")
	)
	(segment
		(start 351.586292 -205.2066)
		(end 351.08007 -205.2066)
		(width 0.15494)
		(layer "In15.Cu")
		(net "NIC2_MAIN_PWR_BIC_EN_R")
	)
	(segment
		(start 351.448878 -216.761822)
		(end 351.917 -216.2937)
		(width 0.0889)
		(layer "In15.Cu")
		(net "NIC2_MAIN_PWR_BIC_EN_R")
	)
	(segment
		(start 339.06587 -200.3044)
		(end 339.06587 -199.794622)
		(width 0.15494)
		(layer "In15.Cu")
		(net "NIC2_MAIN_PWR_BIC_EN_R")
	)
	(segment
		(start 277.584408 -197.153276)
		(end 272.092166 -191.661034)
		(width 0.15494)
		(layer "In15.Cu")
		(net "NIC2_MAIN_PWR_BIC_EN_R")
	)
	(segment
		(start 226.667568 -214.304118)
		(end 226.267772 -213.904322)
		(width 0.13208)
		(layer "F.Cu")
		(net "JTAG_BIC_EN")
	)
	(via
		(at 226.267772 -213.904322)
		(size 0.4572)
		(drill 0.254)
		(layers "F.Cu" "B.Cu")
		(net "JTAG_BIC_EN")
	)
	(via
		(at 225.07448 -211.40293)
		(size 0.7112)
		(drill 0.3556)
		(layers "F.Cu" "B.Cu")
		(net "JTAG_BIC_EN")
	)
	(segment
		(start 226.267772 -213.904322)
		(end 226.267772 -213.740238)
		(width 0.13208)
		(layer "B.Cu")
		(net "JTAG_BIC_EN")
	)
	(segment
		(start 225.521266 -211.849716)
		(end 225.07448 -211.40293)
		(width 0.13208)
		(layer "B.Cu")
		(net "JTAG_BIC_EN")
	)
	(segment
		(start 225.521266 -212.993732)
		(end 225.521266 -211.849716)
		(width 0.13208)
		(layer "B.Cu")
		(net "JTAG_BIC_EN")
	)
	(segment
		(start 224.501964 -210.830414)
		(end 224.501964 -209.18551)
		(width 0.13208)
		(layer "B.Cu")
		(net "JTAG_BIC_EN")
	)
	(segment
		(start 226.267772 -213.740238)
		(end 225.521266 -212.993732)
		(width 0.13208)
		(layer "B.Cu")
		(net "JTAG_BIC_EN")
	)
	(segment
		(start 225.07448 -211.40293)
		(end 224.501964 -210.830414)
		(width 0.13208)
		(layer "B.Cu")
		(net "JTAG_BIC_EN")
	)
	(segment
		(start 107.051094 -398.830546)
		(end 107.051094 -397.912336)
		(width 0.13208)
		(layer "F.Cu")
		(net "RST_BIC_USB_HUB_R_N")
	)
	(segment
		(start 24.562816 -363.777784)
		(end 52.247292 -363.777784)
		(width 0.13208)
		(layer "F.Cu")
		(net "RST_BIC_USB_HUB_R_N")
	)
	(segment
		(start 185.03773 -365.22787)
		(end 192.538858 -365.22787)
		(width 0.13208)
		(layer "F.Cu")
		(net "RST_BIC_USB_HUB_R_N")
	)
	(segment
		(start 107.338114 -397.912336)
		(end 107.782868 -398.35709)
		(width 0.13208)
		(layer "F.Cu")
		(net "RST_BIC_USB_HUB_R_N")
	)
	(segment
		(start 57.144666 -382.067308)
		(end 57.869074 -382.791716)
		(width 0.13208)
		(layer "F.Cu")
		(net "RST_BIC_USB_HUB_R_N")
	)
	(segment
		(start 52.247292 -363.777784)
		(end 52.489608 -364.0201)
		(width 0.13208)
		(layer "F.Cu")
		(net "RST_BIC_USB_HUB_R_N")
	)
	(segment
		(start 2.756408 -390.790938)
		(end 1.765554 -390.790938)
		(width 0.13208)
		(layer "F.Cu")
		(net "RST_BIC_USB_HUB_R_N")
	)
	(segment
		(start 57.869074 -382.791716)
		(end 59.32297 -382.791716)
		(width 0.13208)
		(layer "F.Cu")
		(net "RST_BIC_USB_HUB_R_N")
	)
	(segment
		(start 52.489608 -371.6655)
		(end 54.043326 -373.219218)
		(width 0.13208)
		(layer "F.Cu")
		(net "RST_BIC_USB_HUB_R_N")
	)
	(segment
		(start 52.489608 -364.0201)
		(end 52.489608 -371.6655)
		(width 0.13208)
		(layer "F.Cu")
		(net "RST_BIC_USB_HUB_R_N")
	)
	(segment
		(start 112.785144 -397.152622)
		(end 112.785144 -368.169698)
		(width 0.13208)
		(layer "F.Cu")
		(net "RST_BIC_USB_HUB_R_N")
	)
	(segment
		(start 107.782868 -398.35709)
		(end 111.580676 -398.35709)
		(width 0.13208)
		(layer "F.Cu")
		(net "RST_BIC_USB_HUB_R_N")
	)
	(segment
		(start 92.523056 -365.06531)
		(end 95.5802 -368.122454)
		(width 0.13208)
		(layer "F.Cu")
		(net "RST_BIC_USB_HUB_R_N")
	)
	(segment
		(start 54.043326 -373.219218)
		(end 54.043326 -380.405386)
		(width 0.13208)
		(layer "F.Cu")
		(net "RST_BIC_USB_HUB_R_N")
	)
	(segment
		(start 63.347346 -378.76734)
		(end 63.347346 -366.45088)
		(width 0.13208)
		(layer "F.Cu")
		(net "RST_BIC_USB_HUB_R_N")
	)
	(segment
		(start 106.691176 -399.190464)
		(end 107.051094 -398.830546)
		(width 0.13208)
		(layer "F.Cu")
		(net "RST_BIC_USB_HUB_R_N")
	)
	(segment
		(start 54.043326 -380.405386)
		(end 55.705248 -382.067308)
		(width 0.13208)
		(layer "F.Cu")
		(net "RST_BIC_USB_HUB_R_N")
	)
	(segment
		(start 95.5802 -368.122454)
		(end 95.5802 -396.815564)
		(width 0.13208)
		(layer "F.Cu")
		(net "RST_BIC_USB_HUB_R_N")
	)
	(segment
		(start 63.347346 -366.45088)
		(end 64.732916 -365.06531)
		(width 0.13208)
		(layer "F.Cu")
		(net "RST_BIC_USB_HUB_R_N")
	)
	(segment
		(start 111.580676 -398.35709)
		(end 112.785144 -397.152622)
		(width 0.13208)
		(layer "F.Cu")
		(net "RST_BIC_USB_HUB_R_N")
	)
	(segment
		(start 107.051094 -397.912336)
		(end 107.338114 -397.912336)
		(width 0.13208)
		(layer "F.Cu")
		(net "RST_BIC_USB_HUB_R_N")
	)
	(segment
		(start 112.785144 -368.169698)
		(end 114.229642 -366.7252)
		(width 0.13208)
		(layer "F.Cu")
		(net "RST_BIC_USB_HUB_R_N")
	)
	(segment
		(start 23.747984 -393.133072)
		(end 23.747984 -364.592616)
		(width 0.13208)
		(layer "F.Cu")
		(net "RST_BIC_USB_HUB_R_N")
	)
	(segment
		(start 59.32297 -382.791716)
		(end 63.347346 -378.76734)
		(width 0.13208)
		(layer "F.Cu")
		(net "RST_BIC_USB_HUB_R_N")
	)
	(segment
		(start 192.538858 -365.22787)
		(end 193.141092 -365.830104)
		(width 0.13208)
		(layer "F.Cu")
		(net "RST_BIC_USB_HUB_R_N")
	)
	(segment
		(start 97.9551 -399.190464)
		(end 106.691176 -399.190464)
		(width 0.13208)
		(layer "F.Cu")
		(net "RST_BIC_USB_HUB_R_N")
	)
	(segment
		(start 183.5404 -366.7252)
		(end 185.03773 -365.22787)
		(width 0.13208)
		(layer "F.Cu")
		(net "RST_BIC_USB_HUB_R_N")
	)
	(segment
		(start 114.229642 -366.7252)
		(end 183.5404 -366.7252)
		(width 0.13208)
		(layer "F.Cu")
		(net "RST_BIC_USB_HUB_R_N")
	)
	(segment
		(start 23.747984 -364.592616)
		(end 24.562816 -363.777784)
		(width 0.13208)
		(layer "F.Cu")
		(net "RST_BIC_USB_HUB_R_N")
	)
	(segment
		(start 64.732916 -365.06531)
		(end 92.523056 -365.06531)
		(width 0.13208)
		(layer "F.Cu")
		(net "RST_BIC_USB_HUB_R_N")
	)
	(segment
		(start 55.705248 -382.067308)
		(end 57.144666 -382.067308)
		(width 0.13208)
		(layer "F.Cu")
		(net "RST_BIC_USB_HUB_R_N")
	)
	(segment
		(start 95.5802 -396.815564)
		(end 97.9551 -399.190464)
		(width 0.13208)
		(layer "F.Cu")
		(net "RST_BIC_USB_HUB_R_N")
	)
	(via
		(at 230.8098 -334.3402)
		(size 0.508)
		(drill 0.254)
		(layers "F.Cu" "B.Cu")
		(net "RST_BIC_USB_HUB_R_N")
	)
	(via
		(at 23.747984 -393.133072)
		(size 0.508)
		(drill 0.254)
		(layers "F.Cu" "B.Cu")
		(net "RST_BIC_USB_HUB_R_N")
	)
	(via
		(at 215.489536 -213.222586)
		(size 0.508)
		(drill 0.254)
		(layers "F.Cu" "B.Cu")
		(net "RST_BIC_USB_HUB_R_N")
	)
	(via
		(at 1.765554 -390.790938)
		(size 0.508)
		(drill 0.254)
		(layers "F.Cu" "B.Cu")
		(net "RST_BIC_USB_HUB_R_N")
	)
	(via
		(at 219.286836 -256.385822)
		(size 0.508)
		(drill 0.254)
		(layers "F.Cu" "B.Cu")
		(net "RST_BIC_USB_HUB_R_N")
	)
	(via
		(at 193.141092 -365.830104)
		(size 0.508)
		(drill 0.254)
		(layers "F.Cu" "B.Cu")
		(net "RST_BIC_USB_HUB_R_N")
	)
	(segment
		(start 214.750904 -214.24646)
		(end 214.335106 -214.24646)
		(width 0.13208)
		(layer "B.Cu")
		(net "RST_BIC_USB_HUB_R_N")
	)
	(segment
		(start 214.854536 -214.142828)
		(end 214.750904 -214.24646)
		(width 0.13208)
		(layer "B.Cu")
		(net "RST_BIC_USB_HUB_R_N")
	)
	(segment
		(start 214.854536 -213.222586)
		(end 214.854536 -214.142828)
		(width 0.13208)
		(layer "B.Cu")
		(net "RST_BIC_USB_HUB_R_N")
	)
	(segment
		(start 4.43484 -395.273276)
		(end 4.158234 -394.99667)
		(width 0.13208)
		(layer "B.Cu")
		(net "RST_BIC_USB_HUB_R_N")
	)
	(segment
		(start 4.158234 -393.183618)
		(end 1.765554 -390.790938)
		(width 0.13208)
		(layer "B.Cu")
		(net "RST_BIC_USB_HUB_R_N")
	)
	(segment
		(start 214.854536 -213.222586)
		(end 215.489536 -213.222586)
		(width 0.13208)
		(layer "B.Cu")
		(net "RST_BIC_USB_HUB_R_N")
	)
	(segment
		(start 216.379552 -213.718394)
		(end 216.835736 -213.26221)
		(width 0.13208)
		(layer "B.Cu")
		(net "RST_BIC_USB_HUB_R_N")
	)
	(segment
		(start 215.489536 -213.222586)
		(end 215.985344 -213.718394)
		(width 0.13208)
		(layer "B.Cu")
		(net "RST_BIC_USB_HUB_R_N")
	)
	(segment
		(start 8.274304 -395.273276)
		(end 4.43484 -395.273276)
		(width 0.13208)
		(layer "B.Cu")
		(net "RST_BIC_USB_HUB_R_N")
	)
	(segment
		(start 19.801586 -397.07947)
		(end 10.080498 -397.07947)
		(width 0.13208)
		(layer "B.Cu")
		(net "RST_BIC_USB_HUB_R_N")
	)
	(segment
		(start 215.985344 -213.718394)
		(end 216.379552 -213.718394)
		(width 0.13208)
		(layer "B.Cu")
		(net "RST_BIC_USB_HUB_R_N")
	)
	(segment
		(start 4.158234 -394.99667)
		(end 4.158234 -393.183618)
		(width 0.13208)
		(layer "B.Cu")
		(net "RST_BIC_USB_HUB_R_N")
	)
	(segment
		(start 23.747984 -393.133072)
		(end 19.801586 -397.07947)
		(width 0.13208)
		(layer "B.Cu")
		(net "RST_BIC_USB_HUB_R_N")
	)
	(segment
		(start 216.835736 -213.26221)
		(end 216.835736 -213.222586)
		(width 0.13208)
		(layer "B.Cu")
		(net "RST_BIC_USB_HUB_R_N")
	)
	(segment
		(start 10.080498 -397.07947)
		(end 8.274304 -395.273276)
		(width 0.13208)
		(layer "B.Cu")
		(net "RST_BIC_USB_HUB_R_N")
	)
	(segment
		(start 221.5642 -245.6688)
		(end 221.5642 -240.881662)
		(width 0.15494)
		(layer "In5.Cu")
		(net "RST_BIC_USB_HUB_R_N")
	)
	(segment
		(start 219.920566 -217.916506)
		(end 218.71178 -216.70772)
		(width 0.15494)
		(layer "In5.Cu")
		(net "RST_BIC_USB_HUB_R_N")
	)
	(segment
		(start 219.298774 -234.17784)
		(end 219.004134 -233.8832)
		(width 0.15494)
		(layer "In5.Cu")
		(net "RST_BIC_USB_HUB_R_N")
	)
	(segment
		(start 219.920566 -219.100146)
		(end 219.920566 -217.916506)
		(width 0.15494)
		(layer "In5.Cu")
		(net "RST_BIC_USB_HUB_R_N")
	)
	(segment
		(start 230.8098 -346.726764)
		(end 230.8098 -334.3402)
		(width 0.15494)
		(layer "In5.Cu")
		(net "RST_BIC_USB_HUB_R_N")
	)
	(segment
		(start 219.286836 -256.385822)
		(end 219.286836 -247.946164)
		(width 0.15494)
		(layer "In5.Cu")
		(net "RST_BIC_USB_HUB_R_N")
	)
	(segment
		(start 207.177132 -358.125268)
		(end 219.411296 -358.125268)
		(width 0.15494)
		(layer "In5.Cu")
		(net "RST_BIC_USB_HUB_R_N")
	)
	(segment
		(start 218.71178 -216.70772)
		(end 218.71178 -214.889842)
		(width 0.15494)
		(layer "In5.Cu")
		(net "RST_BIC_USB_HUB_R_N")
	)
	(segment
		(start 216.021666 -213.754716)
		(end 215.489536 -213.222586)
		(width 0.15494)
		(layer "In5.Cu")
		(net "RST_BIC_USB_HUB_R_N")
	)
	(segment
		(start 219.586302 -231.252522)
		(end 219.586302 -226.695)
		(width 0.15494)
		(layer "In5.Cu")
		(net "RST_BIC_USB_HUB_R_N")
	)
	(segment
		(start 219.28582 -224.173034)
		(end 219.285566 -224.17278)
		(width 0.15494)
		(layer "In5.Cu")
		(net "RST_BIC_USB_HUB_R_N")
	)
	(segment
		(start 196.036184 -364.183168)
		(end 197.136004 -363.083348)
		(width 0.15494)
		(layer "In5.Cu")
		(net "RST_BIC_USB_HUB_R_N")
	)
	(segment
		(start 219.586302 -226.695)
		(end 219.28582 -226.394518)
		(width 0.15494)
		(layer "In5.Cu")
		(net "RST_BIC_USB_HUB_R_N")
	)
	(segment
		(start 197.136004 -363.083348)
		(end 200.778618 -363.083348)
		(width 0.15494)
		(layer "In5.Cu")
		(net "RST_BIC_USB_HUB_R_N")
	)
	(segment
		(start 201.785982 -362.52404)
		(end 203.4794 -361.823)
		(width 0.15494)
		(layer "In5.Cu")
		(net "RST_BIC_USB_HUB_R_N")
	)
	(segment
		(start 218.71178 -214.889842)
		(end 217.576654 -213.754716)
		(width 0.15494)
		(layer "In5.Cu")
		(net "RST_BIC_USB_HUB_R_N")
	)
	(segment
		(start 219.004134 -233.8832)
		(end 219.004134 -231.834944)
		(width 0.15494)
		(layer "In5.Cu")
		(net "RST_BIC_USB_HUB_R_N")
	)
	(segment
		(start 219.411296 -358.125268)
		(end 230.8098 -346.726764)
		(width 0.15494)
		(layer "In5.Cu")
		(net "RST_BIC_USB_HUB_R_N")
	)
	(segment
		(start 219.285566 -219.735146)
		(end 219.920566 -219.100146)
		(width 0.15494)
		(layer "In5.Cu")
		(net "RST_BIC_USB_HUB_R_N")
	)
	(segment
		(start 219.298774 -238.616236)
		(end 219.298774 -234.17784)
		(width 0.15494)
		(layer "In5.Cu")
		(net "RST_BIC_USB_HUB_R_N")
	)
	(segment
		(start 219.22994 -231.608884)
		(end 219.586302 -231.252522)
		(width 0.15494)
		(layer "In5.Cu")
		(net "RST_BIC_USB_HUB_R_N")
	)
	(segment
		(start 219.286836 -247.946164)
		(end 221.5642 -245.6688)
		(width 0.15494)
		(layer "In5.Cu")
		(net "RST_BIC_USB_HUB_R_N")
	)
	(segment
		(start 219.28582 -226.394518)
		(end 219.28582 -224.173034)
		(width 0.15494)
		(layer "In5.Cu")
		(net "RST_BIC_USB_HUB_R_N")
	)
	(segment
		(start 219.22994 -231.609138)
		(end 219.22994 -231.608884)
		(width 0.15494)
		(layer "In5.Cu")
		(net "RST_BIC_USB_HUB_R_N")
	)
	(segment
		(start 196.036184 -365.48568)
		(end 196.036184 -364.183168)
		(width 0.15494)
		(layer "In5.Cu")
		(net "RST_BIC_USB_HUB_R_N")
	)
	(segment
		(start 217.576654 -213.754716)
		(end 216.021666 -213.754716)
		(width 0.15494)
		(layer "In5.Cu")
		(net "RST_BIC_USB_HUB_R_N")
	)
	(segment
		(start 201.337926 -362.52404)
		(end 201.785982 -362.52404)
		(width 0.15494)
		(layer "In5.Cu")
		(net "RST_BIC_USB_HUB_R_N")
	)
	(segment
		(start 219.004134 -231.834944)
		(end 219.22994 -231.609138)
		(width 0.15494)
		(layer "In5.Cu")
		(net "RST_BIC_USB_HUB_R_N")
	)
	(segment
		(start 203.4794 -361.823)
		(end 207.177132 -358.125268)
		(width 0.15494)
		(layer "In5.Cu")
		(net "RST_BIC_USB_HUB_R_N")
	)
	(segment
		(start 195.69176 -365.830104)
		(end 196.036184 -365.48568)
		(width 0.15494)
		(layer "In5.Cu")
		(net "RST_BIC_USB_HUB_R_N")
	)
	(segment
		(start 221.5642 -240.881662)
		(end 219.298774 -238.616236)
		(width 0.15494)
		(layer "In5.Cu")
		(net "RST_BIC_USB_HUB_R_N")
	)
	(segment
		(start 219.285566 -224.17278)
		(end 219.285566 -219.735146)
		(width 0.15494)
		(layer "In5.Cu")
		(net "RST_BIC_USB_HUB_R_N")
	)
	(segment
		(start 200.778618 -363.083348)
		(end 201.337926 -362.52404)
		(width 0.15494)
		(layer "In5.Cu")
		(net "RST_BIC_USB_HUB_R_N")
	)
	(segment
		(start 193.141092 -365.830104)
		(end 195.69176 -365.830104)
		(width 0.15494)
		(layer "In5.Cu")
		(net "RST_BIC_USB_HUB_R_N")
	)
	(segment
		(start 219.6846 -277.927054)
		(end 219.6846 -266.168632)
		(width 0.15494)
		(layer "In9.Cu")
		(net "RST_BIC_USB_HUB_R_N")
	)
	(segment
		(start 217.6272 -322.834)
		(end 216.374218 -321.581018)
		(width 0.15494)
		(layer "In9.Cu")
		(net "RST_BIC_USB_HUB_R_N")
	)
	(segment
		(start 230.8098 -334.3402)
		(end 230.8098 -329.2856)
		(width 0.15494)
		(layer "In9.Cu")
		(net "RST_BIC_USB_HUB_R_N")
	)
	(segment
		(start 216.374218 -321.581018)
		(end 216.374218 -317.210694)
		(width 0.15494)
		(layer "In9.Cu")
		(net "RST_BIC_USB_HUB_R_N")
	)
	(segment
		(start 217.626438 -261.19963)
		(end 217.626438 -258.374134)
		(width 0.15494)
		(layer "In9.Cu")
		(net "RST_BIC_USB_HUB_R_N")
	)
	(segment
		(start 224.3582 -322.834)
		(end 217.6272 -322.834)
		(width 0.15494)
		(layer "In9.Cu")
		(net "RST_BIC_USB_HUB_R_N")
	)
	(segment
		(start 212.504782 -285.106872)
		(end 219.6846 -277.927054)
		(width 0.15494)
		(layer "In9.Cu")
		(net "RST_BIC_USB_HUB_R_N")
	)
	(segment
		(start 216.374218 -317.210694)
		(end 212.504782 -313.341258)
		(width 0.15494)
		(layer "In9.Cu")
		(net "RST_BIC_USB_HUB_R_N")
	)
	(segment
		(start 230.8098 -329.2856)
		(end 224.3582 -322.834)
		(width 0.15494)
		(layer "In9.Cu")
		(net "RST_BIC_USB_HUB_R_N")
	)
	(segment
		(start 219.286836 -256.713736)
		(end 219.286836 -256.385822)
		(width 0.15494)
		(layer "In9.Cu")
		(net "RST_BIC_USB_HUB_R_N")
	)
	(segment
		(start 217.626438 -258.374134)
		(end 219.286836 -256.713736)
		(width 0.15494)
		(layer "In9.Cu")
		(net "RST_BIC_USB_HUB_R_N")
	)
	(segment
		(start 212.504782 -313.341258)
		(end 212.504782 -285.106872)
		(width 0.15494)
		(layer "In9.Cu")
		(net "RST_BIC_USB_HUB_R_N")
	)
	(segment
		(start 219.6846 -266.168632)
		(end 217.626438 -261.19963)
		(width 0.15494)
		(layer "In9.Cu")
		(net "RST_BIC_USB_HUB_R_N")
	)
	(segment
		(start 48.24984 -299.699934)
		(end 47.77486 -300.174914)
		(width 0.249936)
		(layer "F.Cu")
		(net "PCEPLL0_VDDA18_PEX0")
	)
	(via
		(at 31.616396 -296.722038)
		(size 0.508)
		(drill 0.254)
		(layers "F.Cu" "B.Cu")
		(net "PCEPLL0_VDDA18_PEX0")
	)
	(via
		(at 47.77486 -300.174914)
		(size 0.4064)
		(drill 0.2032)
		(layers "F.Cu" "B.Cu")
		(net "PCEPLL0_VDDA18_PEX0")
	)
	(via
		(at 33.130236 -297.221656)
		(size 0.508)
		(drill 0.254)
		(layers "F.Cu" "B.Cu")
		(net "PCEPLL0_VDDA18_PEX0")
	)
	(segment
		(start 47.7774 -299.8089)
		(end 47.7774 -300.172374)
		(width 0.3048)
		(layer "B.Cu")
		(net "PCEPLL0_VDDA18_PEX0")
	)
	(segment
		(start 47.7774 -300.5328)
		(end 47.7774 -300.177454)
		(width 0.3048)
		(layer "B.Cu")
		(net "PCEPLL0_VDDA18_PEX0")
	)
	(segment
		(start 47.7774 -300.177454)
		(end 47.77486 -300.174914)
		(width 0.3048)
		(layer "B.Cu")
		(net "PCEPLL0_VDDA18_PEX0")
	)
	(segment
		(start 47.7774 -300.172374)
		(end 47.77486 -300.174914)
		(width 0.3048)
		(layer "B.Cu")
		(net "PCEPLL0_VDDA18_PEX0")
	)
	(segment
		(start 330.16317 -219.027248)
		(end 329.448922 -218.313)
		(width 0.13208)
		(layer "F.Cu")
		(net "PRSNT_NIC6_FPGA_N")
	)
	(segment
		(start 329.448922 -218.313)
		(end 327.93305 -218.313)
		(width 0.13208)
		(layer "F.Cu")
		(net "PRSNT_NIC6_FPGA_N")
	)
	(segment
		(start 330.322936 -219.187014)
		(end 330.16317 -219.027248)
		(width 0.13208)
		(layer "F.Cu")
		(net "PRSNT_NIC6_FPGA_N")
	)
	(segment
		(start 334.09382 -219.187014)
		(end 330.322936 -219.187014)
		(width 0.13208)
		(layer "F.Cu")
		(net "PRSNT_NIC6_FPGA_N")
	)
	(via
		(at 330.16317 -219.027248)
		(size 0.762)
		(drill 0.381)
		(layers "F.Cu" "B.Cu")
		(net "PRSNT_NIC6_FPGA_N")
	)
	(segment
		(start 335.534 -204.83195)
		(end 335.534 -204.216)
		(width 0.13208)
		(layer "F.Cu")
		(net "RST_SSD9_PERST_R_N")
	)
	(segment
		(start 272.403824 -24.189944)
		(end 273.464782 -24.189944)
		(width 0.13208)
		(layer "F.Cu")
		(net "RST_SSD9_PERST_R_N")
	)
	(via
		(at 272.403824 -24.189944)
		(size 0.508)
		(drill 0.254)
		(layers "F.Cu" "B.Cu")
		(net "RST_SSD9_PERST_R_N")
	)
	(via
		(at 335.534 -204.216)
		(size 0.508)
		(drill 0.254)
		(layers "F.Cu" "B.Cu")
		(net "RST_SSD9_PERST_R_N")
	)
	(via
		(at 312.978038 -80.508856)
		(size 0.508)
		(drill 0.254)
		(layers "F.Cu" "B.Cu")
		(net "RST_SSD9_PERST_R_N")
	)
	(via
		(at 300.153324 -78.773274)
		(size 0.508)
		(drill 0.254)
		(layers "F.Cu" "B.Cu")
		(net "RST_SSD9_PERST_R_N")
	)
	(segment
		(start 335.022698 -199.460866)
		(end 334.533494 -198.971662)
		(width 0.15494)
		(layer "In5.Cu")
		(net "RST_SSD9_PERST_R_N")
	)
	(segment
		(start 322.861178 -129.329942)
		(end 319.394586 -125.86335)
		(width 0.15494)
		(layer "In5.Cu")
		(net "RST_SSD9_PERST_R_N")
	)
	(segment
		(start 315.177932 -84.520786)
		(end 312.96991 -82.312764)
		(width 0.15494)
		(layer "In5.Cu")
		(net "RST_SSD9_PERST_R_N")
	)
	(segment
		(start 297.478196 -78.813152)
		(end 300.113446 -78.813152)
		(width 0.15494)
		(layer "In5.Cu")
		(net "RST_SSD9_PERST_R_N")
	)
	(segment
		(start 335.249774 -139.791948)
		(end 329.495658 -139.791948)
		(width 0.15494)
		(layer "In5.Cu")
		(net "RST_SSD9_PERST_R_N")
	)
	(segment
		(start 319.394586 -119.47017)
		(end 315.177932 -115.253516)
		(width 0.15494)
		(layer "In5.Cu")
		(net "RST_SSD9_PERST_R_N")
	)
	(segment
		(start 335.534 -203.162916)
		(end 335.022698 -202.651614)
		(width 0.15494)
		(layer "In5.Cu")
		(net "RST_SSD9_PERST_R_N")
	)
	(segment
		(start 282.044648 -29.8831)
		(end 282.044648 -32.701992)
		(width 0.15494)
		(layer "In5.Cu")
		(net "RST_SSD9_PERST_R_N")
	)
	(segment
		(start 334.533494 -198.971662)
		(end 334.533494 -176.1744)
		(width 0.15494)
		(layer "In5.Cu")
		(net "RST_SSD9_PERST_R_N")
	)
	(segment
		(start 282.044648 -32.701992)
		(end 294.8686 -45.525944)
		(width 0.15494)
		(layer "In5.Cu")
		(net "RST_SSD9_PERST_R_N")
	)
	(segment
		(start 336.081878 -140.624052)
		(end 335.249774 -139.791948)
		(width 0.15494)
		(layer "In5.Cu")
		(net "RST_SSD9_PERST_R_N")
	)
	(segment
		(start 315.177932 -115.253516)
		(end 315.177932 -84.520786)
		(width 0.15494)
		(layer "In5.Cu")
		(net "RST_SSD9_PERST_R_N")
	)
	(segment
		(start 277.124414 -26.873708)
		(end 278.32812 -26.873708)
		(width 0.15494)
		(layer "In5.Cu")
		(net "RST_SSD9_PERST_R_N")
	)
	(segment
		(start 334.533494 -176.1744)
		(end 336.081878 -174.626016)
		(width 0.15494)
		(layer "In5.Cu")
		(net "RST_SSD9_PERST_R_N")
	)
	(segment
		(start 312.96991 -81.502504)
		(end 312.978038 -81.494376)
		(width 0.15494)
		(layer "In5.Cu")
		(net "RST_SSD9_PERST_R_N")
	)
	(segment
		(start 275.636228 -25.192228)
		(end 276.242018 -25.991312)
		(width 0.15494)
		(layer "In5.Cu")
		(net "RST_SSD9_PERST_R_N")
	)
	(segment
		(start 335.534 -204.216)
		(end 335.534 -203.162916)
		(width 0.15494)
		(layer "In5.Cu")
		(net "RST_SSD9_PERST_R_N")
	)
	(segment
		(start 294.8686 -76.203556)
		(end 297.478196 -78.813152)
		(width 0.15494)
		(layer "In5.Cu")
		(net "RST_SSD9_PERST_R_N")
	)
	(segment
		(start 282.831032 -29.096716)
		(end 282.044648 -29.8831)
		(width 0.15494)
		(layer "In5.Cu")
		(net "RST_SSD9_PERST_R_N")
	)
	(segment
		(start 276.242018 -25.991312)
		(end 277.124414 -26.873708)
		(width 0.15494)
		(layer "In5.Cu")
		(net "RST_SSD9_PERST_R_N")
	)
	(segment
		(start 272.788888 -24.575008)
		(end 274.75815 -24.575008)
		(width 0.15494)
		(layer "In5.Cu")
		(net "RST_SSD9_PERST_R_N")
	)
	(segment
		(start 319.394586 -125.86335)
		(end 319.394586 -119.47017)
		(width 0.15494)
		(layer "In5.Cu")
		(net "RST_SSD9_PERST_R_N")
	)
	(segment
		(start 329.495658 -139.791948)
		(end 322.861178 -133.157468)
		(width 0.15494)
		(layer "In5.Cu")
		(net "RST_SSD9_PERST_R_N")
	)
	(segment
		(start 274.75815 -24.575008)
		(end 275.636228 -25.192228)
		(width 0.15494)
		(layer "In5.Cu")
		(net "RST_SSD9_PERST_R_N")
	)
	(segment
		(start 335.022698 -202.651614)
		(end 335.022698 -199.460866)
		(width 0.15494)
		(layer "In5.Cu")
		(net "RST_SSD9_PERST_R_N")
	)
	(segment
		(start 294.8686 -45.525944)
		(end 294.8686 -76.203556)
		(width 0.15494)
		(layer "In5.Cu")
		(net "RST_SSD9_PERST_R_N")
	)
	(segment
		(start 282.831032 -28.261056)
		(end 282.831032 -29.096716)
		(width 0.15494)
		(layer "In5.Cu")
		(net "RST_SSD9_PERST_R_N")
	)
	(segment
		(start 312.978038 -81.494376)
		(end 312.978038 -80.508856)
		(width 0.15494)
		(layer "In5.Cu")
		(net "RST_SSD9_PERST_R_N")
	)
	(segment
		(start 279.2222 -27.767788)
		(end 282.337764 -27.767788)
		(width 0.15494)
		(layer "In5.Cu")
		(net "RST_SSD9_PERST_R_N")
	)
	(segment
		(start 300.113446 -78.813152)
		(end 300.153324 -78.773274)
		(width 0.15494)
		(layer "In5.Cu")
		(net "RST_SSD9_PERST_R_N")
	)
	(segment
		(start 282.337764 -27.767788)
		(end 282.831032 -28.261056)
		(width 0.15494)
		(layer "In5.Cu")
		(net "RST_SSD9_PERST_R_N")
	)
	(segment
		(start 272.403824 -24.189944)
		(end 272.788888 -24.575008)
		(width 0.15494)
		(layer "In5.Cu")
		(net "RST_SSD9_PERST_R_N")
	)
	(segment
		(start 312.96991 -82.312764)
		(end 312.96991 -81.502504)
		(width 0.15494)
		(layer "In5.Cu")
		(net "RST_SSD9_PERST_R_N")
	)
	(segment
		(start 278.32812 -26.873708)
		(end 279.2222 -27.767788)
		(width 0.15494)
		(layer "In5.Cu")
		(net "RST_SSD9_PERST_R_N")
	)
	(segment
		(start 322.861178 -133.157468)
		(end 322.861178 -129.329942)
		(width 0.15494)
		(layer "In5.Cu")
		(net "RST_SSD9_PERST_R_N")
	)
	(segment
		(start 336.081878 -174.626016)
		(end 336.081878 -140.624052)
		(width 0.15494)
		(layer "In5.Cu")
		(net "RST_SSD9_PERST_R_N")
	)
	(segment
		(start 309.778654 -78.5876)
		(end 311.69991 -80.508856)
		(width 0.15494)
		(layer "In9.Cu")
		(net "RST_SSD9_PERST_R_N")
	)
	(segment
		(start 311.69991 -80.508856)
		(end 312.978038 -80.508856)
		(width 0.15494)
		(layer "In9.Cu")
		(net "RST_SSD9_PERST_R_N")
	)
	(segment
		(start 300.338998 -78.5876)
		(end 309.778654 -78.5876)
		(width 0.15494)
		(layer "In9.Cu")
		(net "RST_SSD9_PERST_R_N")
	)
	(segment
		(start 300.153324 -78.773274)
		(end 300.338998 -78.5876)
		(width 0.15494)
		(layer "In9.Cu")
		(net "RST_SSD9_PERST_R_N")
	)
	(segment
		(start 207.023208 -83.659472)
		(end 207.572102 -83.110578)
		(width 0.13208)
		(layer "F.Cu")
		(net "SSD1_LED")
	)
	(segment
		(start 207.572102 -83.110578)
		(end 209.798158 -83.110578)
		(width 0.13208)
		(layer "F.Cu")
		(net "SSD1_LED")
	)
	(segment
		(start 209.798158 -83.110578)
		(end 211.572094 -83.110578)
		(width 0.13208)
		(layer "F.Cu")
		(net "SSD1_LED")
	)
	(via
		(at 209.798158 -83.110578)
		(size 0.762)
		(drill 0.381)
		(layers "F.Cu" "B.Cu")
		(net "SSD1_LED")
	)
	(segment
		(start 334.494124 -217.187272)
		(end 334.89392 -217.587068)
		(width 0.13208)
		(layer "F.Cu")
		(net "NIC7_MAIN_PWR_BIC_EN_R")
	)
	(via
		(at 265.69543 -213.669118)
		(size 0.508)
		(drill 0.254)
		(layers "F.Cu" "B.Cu")
		(net "NIC7_MAIN_PWR_BIC_EN_R")
	)
	(via
		(at 334.494124 -217.187272)
		(size 0.4572)
		(drill 0.254)
		(layers "F.Cu" "B.Cu")
		(net "NIC7_MAIN_PWR_BIC_EN_R")
	)
	(via
		(at 230.791512 -233.182668)
		(size 0.508)
		(drill 0.254)
		(layers "F.Cu" "B.Cu")
		(net "NIC7_MAIN_PWR_BIC_EN_R")
	)
	(via
		(at 263.824212 -197.2945)
		(size 0.508)
		(drill 0.254)
		(layers "F.Cu" "B.Cu")
		(net "NIC7_MAIN_PWR_BIC_EN_R")
	)
	(segment
		(start 230.791512 -233.182668)
		(end 230.317548 -232.708704)
		(width 0.13208)
		(layer "B.Cu")
		(net "NIC7_MAIN_PWR_BIC_EN_R")
	)
	(segment
		(start 230.317548 -231.758744)
		(end 230.450644 -231.625648)
		(width 0.13208)
		(layer "B.Cu")
		(net "NIC7_MAIN_PWR_BIC_EN_R")
	)
	(segment
		(start 230.317548 -232.708704)
		(end 230.317548 -231.758744)
		(width 0.13208)
		(layer "B.Cu")
		(net "NIC7_MAIN_PWR_BIC_EN_R")
	)
	(segment
		(start 265.3411 -211.721446)
		(end 265.69543 -212.075776)
		(width 0.15494)
		(layer "In5.Cu")
		(net "NIC7_MAIN_PWR_BIC_EN_R")
	)
	(segment
		(start 263.3472 -197.771512)
		(end 263.3472 -210.083146)
		(width 0.15494)
		(layer "In5.Cu")
		(net "NIC7_MAIN_PWR_BIC_EN_R")
	)
	(segment
		(start 263.824212 -197.2945)
		(end 263.3472 -197.771512)
		(width 0.15494)
		(layer "In5.Cu")
		(net "NIC7_MAIN_PWR_BIC_EN_R")
	)
	(segment
		(start 265.69543 -212.075776)
		(end 265.69543 -213.669118)
		(width 0.15494)
		(layer "In5.Cu")
		(net "NIC7_MAIN_PWR_BIC_EN_R")
	)
	(segment
		(start 263.3472 -210.083146)
		(end 264.9855 -211.721446)
		(width 0.15494)
		(layer "In5.Cu")
		(net "NIC7_MAIN_PWR_BIC_EN_R")
	)
	(segment
		(start 264.9855 -211.721446)
		(end 265.3411 -211.721446)
		(width 0.15494)
		(layer "In5.Cu")
		(net "NIC7_MAIN_PWR_BIC_EN_R")
	)
	(segment
		(start 262.744458 -218.053666)
		(end 262.920734 -218.053666)
		(width 0.15494)
		(layer "In7.Cu")
		(net "NIC7_MAIN_PWR_BIC_EN_R")
	)
	(segment
		(start 243.784882 -236.75086)
		(end 243.933726 -236.602016)
		(width 0.15494)
		(layer "In7.Cu")
		(net "NIC7_MAIN_PWR_BIC_EN_R")
	)
	(segment
		(start 256.089404 -225.443796)
		(end 257.6322 -223.901)
		(width 0.15494)
		(layer "In7.Cu")
		(net "NIC7_MAIN_PWR_BIC_EN_R")
	)
	(segment
		(start 259.21335 -221.584774)
		(end 262.744458 -218.053666)
		(width 0.15494)
		(layer "In7.Cu")
		(net "NIC7_MAIN_PWR_BIC_EN_R")
	)
	(segment
		(start 262.920734 -218.053666)
		(end 265.69543 -215.27897)
		(width 0.15494)
		(layer "In7.Cu")
		(net "NIC7_MAIN_PWR_BIC_EN_R")
	)
	(segment
		(start 232.941114 -236.75086)
		(end 243.784882 -236.75086)
		(width 0.15494)
		(layer "In7.Cu")
		(net "NIC7_MAIN_PWR_BIC_EN_R")
	)
	(segment
		(start 250.806458 -231.985566)
		(end 256.089404 -226.70262)
		(width 0.15494)
		(layer "In7.Cu")
		(net "NIC7_MAIN_PWR_BIC_EN_R")
	)
	(segment
		(start 265.69543 -215.27897)
		(end 265.69543 -213.669118)
		(width 0.15494)
		(layer "In7.Cu")
		(net "NIC7_MAIN_PWR_BIC_EN_R")
	)
	(segment
		(start 257.6322 -223.901)
		(end 257.6322 -221.869508)
		(width 0.15494)
		(layer "In7.Cu")
		(net "NIC7_MAIN_PWR_BIC_EN_R")
	)
	(segment
		(start 250.49734 -231.985566)
		(end 250.806458 -231.985566)
		(width 0.15494)
		(layer "In7.Cu")
		(net "NIC7_MAIN_PWR_BIC_EN_R")
	)
	(segment
		(start 256.089404 -226.70262)
		(end 256.089404 -225.443796)
		(width 0.15494)
		(layer "In7.Cu")
		(net "NIC7_MAIN_PWR_BIC_EN_R")
	)
	(segment
		(start 243.933726 -236.602016)
		(end 245.261384 -236.602016)
		(width 0.15494)
		(layer "In7.Cu")
		(net "NIC7_MAIN_PWR_BIC_EN_R")
	)
	(segment
		(start 257.6322 -221.869508)
		(end 257.916934 -221.584774)
		(width 0.15494)
		(layer "In7.Cu")
		(net "NIC7_MAIN_PWR_BIC_EN_R")
	)
	(segment
		(start 249.968258 -232.358184)
		(end 250.235466 -232.24744)
		(width 0.15494)
		(layer "In7.Cu")
		(net "NIC7_MAIN_PWR_BIC_EN_R")
	)
	(segment
		(start 232.339642 -236.149388)
		(end 232.941114 -236.75086)
		(width 0.15494)
		(layer "In7.Cu")
		(net "NIC7_MAIN_PWR_BIC_EN_R")
	)
	(segment
		(start 246.2022 -235.6612)
		(end 246.326914 -235.6612)
		(width 0.15494)
		(layer "In7.Cu")
		(net "NIC7_MAIN_PWR_BIC_EN_R")
	)
	(segment
		(start 250.235466 -232.24744)
		(end 250.49734 -231.985566)
		(width 0.15494)
		(layer "In7.Cu")
		(net "NIC7_MAIN_PWR_BIC_EN_R")
	)
	(segment
		(start 230.791512 -233.182668)
		(end 232.339642 -234.730798)
		(width 0.15494)
		(layer "In7.Cu")
		(net "NIC7_MAIN_PWR_BIC_EN_R")
	)
	(segment
		(start 245.261384 -236.602016)
		(end 246.2022 -235.6612)
		(width 0.15494)
		(layer "In7.Cu")
		(net "NIC7_MAIN_PWR_BIC_EN_R")
	)
	(segment
		(start 232.339642 -234.730798)
		(end 232.339642 -236.149388)
		(width 0.15494)
		(layer "In7.Cu")
		(net "NIC7_MAIN_PWR_BIC_EN_R")
	)
	(segment
		(start 257.916934 -221.584774)
		(end 259.21335 -221.584774)
		(width 0.15494)
		(layer "In7.Cu")
		(net "NIC7_MAIN_PWR_BIC_EN_R")
	)
	(segment
		(start 249.62993 -232.358184)
		(end 249.968258 -232.358184)
		(width 0.15494)
		(layer "In7.Cu")
		(net "NIC7_MAIN_PWR_BIC_EN_R")
	)
	(segment
		(start 246.326914 -235.6612)
		(end 249.62993 -232.358184)
		(width 0.15494)
		(layer "In7.Cu")
		(net "NIC7_MAIN_PWR_BIC_EN_R")
	)
	(segment
		(start 334.494124 -217.187272)
		(end 333.96809 -216.661238)
		(width 0.15494)
		(layer "In13.Cu")
		(net "NIC7_MAIN_PWR_BIC_EN_R")
	)
	(segment
		(start 333.298038 -216.661238)
		(end 330.363576 -213.726776)
		(width 0.15494)
		(layer "In13.Cu")
		(net "NIC7_MAIN_PWR_BIC_EN_R")
	)
	(segment
		(start 322.456302 -211.67217)
		(end 321.270122 -210.48599)
		(width 0.15494)
		(layer "In13.Cu")
		(net "NIC7_MAIN_PWR_BIC_EN_R")
	)
	(segment
		(start 326.85609 -211.67217)
		(end 322.456302 -211.67217)
		(width 0.15494)
		(layer "In13.Cu")
		(net "NIC7_MAIN_PWR_BIC_EN_R")
	)
	(segment
		(start 333.96809 -216.661238)
		(end 333.298038 -216.661238)
		(width 0.15494)
		(layer "In13.Cu")
		(net "NIC7_MAIN_PWR_BIC_EN_R")
	)
	(segment
		(start 321.270122 -210.48599)
		(end 280.465276 -210.48599)
		(width 0.15494)
		(layer "In13.Cu")
		(net "NIC7_MAIN_PWR_BIC_EN_R")
	)
	(segment
		(start 330.363576 -213.726776)
		(end 328.910696 -213.726776)
		(width 0.15494)
		(layer "In13.Cu")
		(net "NIC7_MAIN_PWR_BIC_EN_R")
	)
	(segment
		(start 267.273786 -197.2945)
		(end 263.824212 -197.2945)
		(width 0.15494)
		(layer "In13.Cu")
		(net "NIC7_MAIN_PWR_BIC_EN_R")
	)
	(segment
		(start 328.910696 -213.726776)
		(end 326.85609 -211.67217)
		(width 0.15494)
		(layer "In13.Cu")
		(net "NIC7_MAIN_PWR_BIC_EN_R")
	)
	(segment
		(start 280.465276 -210.48599)
		(end 267.273786 -197.2945)
		(width 0.15494)
		(layer "In13.Cu")
		(net "NIC7_MAIN_PWR_BIC_EN_R")
	)
	(segment
		(start 236.832648 -177.008282)
		(end 236.832648 -176.646586)
		(width 0.13208)
		(layer "F.Cu")
		(net "BIC_RST_PWRGD_RSMRST")
	)
	(segment
		(start 241.123724 -175.816514)
		(end 242.237768 -176.930558)
		(width 0.13208)
		(layer "F.Cu")
		(net "BIC_RST_PWRGD_RSMRST")
	)
	(segment
		(start 242.237768 -178.083464)
		(end 242.201954 -178.119278)
		(width 0.13208)
		(layer "F.Cu")
		(net "BIC_RST_PWRGD_RSMRST")
	)
	(segment
		(start 237.66272 -175.816514)
		(end 241.123724 -175.816514)
		(width 0.13208)
		(layer "F.Cu")
		(net "BIC_RST_PWRGD_RSMRST")
	)
	(segment
		(start 236.832648 -176.646586)
		(end 237.66272 -175.816514)
		(width 0.13208)
		(layer "F.Cu")
		(net "BIC_RST_PWRGD_RSMRST")
	)
	(segment
		(start 242.237768 -176.930558)
		(end 242.237768 -178.083464)
		(width 0.13208)
		(layer "F.Cu")
		(net "BIC_RST_PWRGD_RSMRST")
	)
	(via
		(at 242.237768 -176.930558)
		(size 0.762)
		(drill 0.381)
		(layers "F.Cu" "B.Cu")
		(net "BIC_RST_PWRGD_RSMRST")
	)
	(via
		(at 150.789132 -259.576316)
		(size 0.508)
		(drill 0.254)
		(layers "F.Cu" "B.Cu")
		(net "PCEPLL3_VDDA18_PEX1_R")
	)
	(segment
		(start 363.671866 -188.79312)
		(end 365.133382 -188.79312)
		(width 0.13208)
		(layer "F.Cu")
		(net "RST_PEX_SSD2_PERST_N")
	)
	(segment
		(start 363.092746 -188.214)
		(end 363.671866 -188.79312)
		(width 0.13208)
		(layer "F.Cu")
		(net "RST_PEX_SSD2_PERST_N")
	)
	(segment
		(start 361.58805 -188.214)
		(end 363.092746 -188.214)
		(width 0.13208)
		(layer "F.Cu")
		(net "RST_PEX_SSD2_PERST_N")
	)
	(segment
		(start 365.133382 -188.79312)
		(end 366.263936 -188.79312)
		(width 0.13208)
		(layer "F.Cu")
		(net "RST_PEX_SSD2_PERST_N")
	)
	(via
		(at 365.133382 -188.79312)
		(size 0.508)
		(drill 0.254)
		(layers "F.Cu" "B.Cu")
		(net "RST_PEX_SSD2_PERST_N")
	)
	(segment
		(start 207.479392 -300.240954)
		(end 208.477866 -300.240954)
		(width 0.13208)
		(layer "F.Cu")
		(net "I2C_PEX1_HOST_SCL")
	)
	(segment
		(start 208.929986 -299.285152)
		(end 208.489804 -299.285152)
		(width 0.13208)
		(layer "F.Cu")
		(net "I2C_PEX1_HOST_SCL")
	)
	(segment
		(start 209.120486 -300.123352)
		(end 209.120486 -299.77969)
		(width 0.13208)
		(layer "F.Cu")
		(net "I2C_PEX1_HOST_SCL")
	)
	(segment
		(start 209.120486 -299.77969)
		(end 209.120486 -299.475652)
		(width 0.13208)
		(layer "F.Cu")
		(net "I2C_PEX1_HOST_SCL")
	)
	(segment
		(start 208.477866 -300.240954)
		(end 208.487264 -300.250352)
		(width 0.13208)
		(layer "F.Cu")
		(net "I2C_PEX1_HOST_SCL")
	)
	(segment
		(start 209.120486 -299.475652)
		(end 208.929986 -299.285152)
		(width 0.13208)
		(layer "F.Cu")
		(net "I2C_PEX1_HOST_SCL")
	)
	(segment
		(start 208.487264 -300.250352)
		(end 208.993486 -300.250352)
		(width 0.13208)
		(layer "F.Cu")
		(net "I2C_PEX1_HOST_SCL")
	)
	(segment
		(start 208.993486 -300.250352)
		(end 209.120486 -300.123352)
		(width 0.13208)
		(layer "F.Cu")
		(net "I2C_PEX1_HOST_SCL")
	)
	(via
		(at 209.120486 -299.77969)
		(size 0.508)
		(drill 0.254)
		(layers "F.Cu" "B.Cu")
		(net "I2C_PEX1_HOST_SCL")
	)
	(segment
		(start 321.789298 -290.28009)
		(end 321.746372 -290.237164)
		(width 0.13208)
		(layer "F.Cu")
		(net "PWRGD_P1V8_PEX2_R")
	)
	(segment
		(start 321.633596 -290.237164)
		(end 321.626484 -290.230052)
		(width 0.13208)
		(layer "F.Cu")
		(net "PWRGD_P1V8_PEX2_R")
	)
	(segment
		(start 319.340484 -290.230052)
		(end 319.003934 -289.893502)
		(width 0.13208)
		(layer "F.Cu")
		(net "PWRGD_P1V8_PEX2_R")
	)
	(segment
		(start 319.003934 -289.893502)
		(end 319.003934 -289.630866)
		(width 0.13208)
		(layer "F.Cu")
		(net "PWRGD_P1V8_PEX2_R")
	)
	(segment
		(start 321.746372 -290.237164)
		(end 321.633596 -290.237164)
		(width 0.13208)
		(layer "F.Cu")
		(net "PWRGD_P1V8_PEX2_R")
	)
	(segment
		(start 321.789298 -291.297868)
		(end 321.789298 -290.28009)
		(width 0.13208)
		(layer "F.Cu")
		(net "PWRGD_P1V8_PEX2_R")
	)
	(segment
		(start 321.626484 -290.230052)
		(end 319.340484 -290.230052)
		(width 0.13208)
		(layer "F.Cu")
		(net "PWRGD_P1V8_PEX2_R")
	)
	(via
		(at 321.746372 -290.237164)
		(size 0.508)
		(drill 0.254)
		(layers "F.Cu" "B.Cu")
		(net "PWRGD_P1V8_PEX2_R")
	)
	(segment
		(start 247.464834 -25.390094)
		(end 246.391176 -25.390094)
		(width 0.13208)
		(layer "F.Cu")
		(net "SSD8_PWRDIS_R")
	)
	(segment
		(start 256.334514 -28.550108)
		(end 256.864358 -29.079952)
		(width 0.13208)
		(layer "F.Cu")
		(net "SSD8_PWRDIS_R")
	)
	(segment
		(start 256.334514 -28.469082)
		(end 256.334514 -28.550108)
		(width 0.13208)
		(layer "F.Cu")
		(net "SSD8_PWRDIS_R")
	)
	(segment
		(start 333.502 -204.83195)
		(end 333.502 -204.216)
		(width 0.13208)
		(layer "F.Cu")
		(net "SSD8_PWRDIS_R")
	)
	(via
		(at 246.391176 -25.390094)
		(size 0.508)
		(drill 0.254)
		(layers "F.Cu" "B.Cu")
		(net "SSD8_PWRDIS_R")
	)
	(via
		(at 275.74621 -86.31301)
		(size 0.508)
		(drill 0.254)
		(layers "F.Cu" "B.Cu")
		(net "SSD8_PWRDIS_R")
	)
	(via
		(at 333.502 -204.216)
		(size 0.508)
		(drill 0.254)
		(layers "F.Cu" "B.Cu")
		(net "SSD8_PWRDIS_R")
	)
	(via
		(at 256.334514 -28.469082)
		(size 0.508)
		(drill 0.254)
		(layers "F.Cu" "B.Cu")
		(net "SSD8_PWRDIS_R")
	)
	(via
		(at 310.540654 -93.789754)
		(size 0.508)
		(drill 0.254)
		(layers "F.Cu" "B.Cu")
		(net "SSD8_PWRDIS_R")
	)
	(segment
		(start 268.469872 -66.247772)
		(end 264.303764 -70.41388)
		(width 0.15494)
		(layer "In5.Cu")
		(net "SSD8_PWRDIS_R")
	)
	(segment
		(start 321.123818 -130.050032)
		(end 317.657226 -126.58344)
		(width 0.15494)
		(layer "In5.Cu")
		(net "SSD8_PWRDIS_R")
	)
	(segment
		(start 331.153008 -142.078202)
		(end 329.324462 -142.078202)
		(width 0.15494)
		(layer "In5.Cu")
		(net "SSD8_PWRDIS_R")
	)
	(segment
		(start 249.855736 -26.255218)
		(end 249.313192 -25.527508)
		(width 0.15494)
		(layer "In5.Cu")
		(net "SSD8_PWRDIS_R")
	)
	(segment
		(start 315.06414 -117.597174)
		(end 313.709812 -117.597174)
		(width 0.15494)
		(layer "In5.Cu")
		(net "SSD8_PWRDIS_R")
	)
	(segment
		(start 268.469872 -45.777404)
		(end 268.469872 -66.247772)
		(width 0.15494)
		(layer "In5.Cu")
		(net "SSD8_PWRDIS_R")
	)
	(segment
		(start 255.58496 -29.625036)
		(end 255.58496 -32.892492)
		(width 0.15494)
		(layer "In5.Cu")
		(net "SSD8_PWRDIS_R")
	)
	(segment
		(start 321.123818 -133.877558)
		(end 321.123818 -130.050032)
		(width 0.15494)
		(layer "In5.Cu")
		(net "SSD8_PWRDIS_R")
	)
	(segment
		(start 250.933966 -27.333448)
		(end 249.855736 -26.255218)
		(width 0.15494)
		(layer "In5.Cu")
		(net "SSD8_PWRDIS_R")
	)
	(segment
		(start 311.235344 -115.122706)
		(end 311.235344 -94.484444)
		(width 0.15494)
		(layer "In5.Cu")
		(net "SSD8_PWRDIS_R")
	)
	(segment
		(start 311.235344 -94.484444)
		(end 310.540654 -93.789754)
		(width 0.15494)
		(layer "In5.Cu")
		(net "SSD8_PWRDIS_R")
	)
	(segment
		(start 273.362928 -85.917024)
		(end 275.350224 -85.917024)
		(width 0.15494)
		(layer "In5.Cu")
		(net "SSD8_PWRDIS_R")
	)
	(segment
		(start 253.27356 -28.469082)
		(end 252.137926 -27.333448)
		(width 0.15494)
		(layer "In5.Cu")
		(net "SSD8_PWRDIS_R")
	)
	(segment
		(start 329.324462 -142.078202)
		(end 321.123818 -133.877558)
		(width 0.15494)
		(layer "In5.Cu")
		(net "SSD8_PWRDIS_R")
	)
	(segment
		(start 332.796134 -143.721328)
		(end 331.153008 -142.078202)
		(width 0.15494)
		(layer "In5.Cu")
		(net "SSD8_PWRDIS_R")
	)
	(segment
		(start 275.350224 -85.917024)
		(end 275.74621 -86.31301)
		(width 0.15494)
		(layer "In5.Cu")
		(net "SSD8_PWRDIS_R")
	)
	(segment
		(start 256.334514 -28.875482)
		(end 255.58496 -29.625036)
		(width 0.15494)
		(layer "In5.Cu")
		(net "SSD8_PWRDIS_R")
	)
	(segment
		(start 317.657226 -126.58344)
		(end 317.657226 -120.19026)
		(width 0.15494)
		(layer "In5.Cu")
		(net "SSD8_PWRDIS_R")
	)
	(segment
		(start 313.709812 -117.597174)
		(end 311.235344 -115.122706)
		(width 0.15494)
		(layer "In5.Cu")
		(net "SSD8_PWRDIS_R")
	)
	(segment
		(start 256.334514 -28.469082)
		(end 256.334514 -28.875482)
		(width 0.15494)
		(layer "In5.Cu")
		(net "SSD8_PWRDIS_R")
	)
	(segment
		(start 317.657226 -120.19026)
		(end 315.06414 -117.597174)
		(width 0.15494)
		(layer "In5.Cu")
		(net "SSD8_PWRDIS_R")
	)
	(segment
		(start 249.313192 -25.527508)
		(end 248.61266 -25.034748)
		(width 0.15494)
		(layer "In5.Cu")
		(net "SSD8_PWRDIS_R")
	)
	(segment
		(start 270.323056 -77.511656)
		(end 270.323056 -82.877152)
		(width 0.15494)
		(layer "In5.Cu")
		(net "SSD8_PWRDIS_R")
	)
	(segment
		(start 248.61266 -25.034748)
		(end 246.746522 -25.034748)
		(width 0.15494)
		(layer "In5.Cu")
		(net "SSD8_PWRDIS_R")
	)
	(segment
		(start 252.137926 -27.333448)
		(end 250.933966 -27.333448)
		(width 0.15494)
		(layer "In5.Cu")
		(net "SSD8_PWRDIS_R")
	)
	(segment
		(start 333.502 -204.216)
		(end 333.112618 -203.826618)
		(width 0.15494)
		(layer "In5.Cu")
		(net "SSD8_PWRDIS_R")
	)
	(segment
		(start 270.323056 -82.877152)
		(end 273.362928 -85.917024)
		(width 0.15494)
		(layer "In5.Cu")
		(net "SSD8_PWRDIS_R")
	)
	(segment
		(start 333.112618 -202.740768)
		(end 332.796134 -202.424284)
		(width 0.15494)
		(layer "In5.Cu")
		(net "SSD8_PWRDIS_R")
	)
	(segment
		(start 333.112618 -203.826618)
		(end 333.112618 -202.740768)
		(width 0.15494)
		(layer "In5.Cu")
		(net "SSD8_PWRDIS_R")
	)
	(segment
		(start 264.303764 -71.492364)
		(end 270.323056 -77.511656)
		(width 0.15494)
		(layer "In5.Cu")
		(net "SSD8_PWRDIS_R")
	)
	(segment
		(start 332.796134 -202.424284)
		(end 332.796134 -143.721328)
		(width 0.15494)
		(layer "In5.Cu")
		(net "SSD8_PWRDIS_R")
	)
	(segment
		(start 256.334514 -28.469082)
		(end 253.27356 -28.469082)
		(width 0.15494)
		(layer "In5.Cu")
		(net "SSD8_PWRDIS_R")
	)
	(segment
		(start 264.303764 -70.41388)
		(end 264.303764 -71.492364)
		(width 0.15494)
		(layer "In5.Cu")
		(net "SSD8_PWRDIS_R")
	)
	(segment
		(start 246.746522 -25.034748)
		(end 246.391176 -25.390094)
		(width 0.15494)
		(layer "In5.Cu")
		(net "SSD8_PWRDIS_R")
	)
	(segment
		(start 255.58496 -32.892492)
		(end 268.469872 -45.777404)
		(width 0.15494)
		(layer "In5.Cu")
		(net "SSD8_PWRDIS_R")
	)
	(segment
		(start 276.60473 -86.31301)
		(end 275.74621 -86.31301)
		(width 0.15494)
		(layer "In9.Cu")
		(net "SSD8_PWRDIS_R")
	)
	(segment
		(start 309.829454 -93.789754)
		(end 303.693322 -87.653622)
		(width 0.15494)
		(layer "In9.Cu")
		(net "SSD8_PWRDIS_R")
	)
	(segment
		(start 277.945342 -87.653622)
		(end 276.60473 -86.31301)
		(width 0.15494)
		(layer "In9.Cu")
		(net "SSD8_PWRDIS_R")
	)
	(segment
		(start 310.540654 -93.789754)
		(end 309.829454 -93.789754)
		(width 0.15494)
		(layer "In9.Cu")
		(net "SSD8_PWRDIS_R")
	)
	(segment
		(start 303.693322 -87.653622)
		(end 277.945342 -87.653622)
		(width 0.15494)
		(layer "In9.Cu")
		(net "SSD8_PWRDIS_R")
	)
	(segment
		(start 206.223108 -87.977472)
		(end 206.223108 -88.367616)
		(width 0.13208)
		(layer "F.Cu")
		(net "SSD_LED_IOEXP_A1")
	)
	(segment
		(start 208.890616 -88.465152)
		(end 208.947004 -88.408764)
		(width 0.13208)
		(layer "F.Cu")
		(net "SSD_LED_IOEXP_A1")
	)
	(segment
		(start 204.991208 -87.977472)
		(end 206.223108 -87.977472)
		(width 0.13208)
		(layer "F.Cu")
		(net "SSD_LED_IOEXP_A1")
	)
	(segment
		(start 206.223108 -88.367616)
		(end 206.320644 -88.465152)
		(width 0.13208)
		(layer "F.Cu")
		(net "SSD_LED_IOEXP_A1")
	)
	(segment
		(start 210.65871 -85.060536)
		(end 211.572094 -85.060536)
		(width 0.13208)
		(layer "F.Cu")
		(net "SSD_LED_IOEXP_A1")
	)
	(segment
		(start 208.947004 -86.772242)
		(end 210.65871 -85.060536)
		(width 0.13208)
		(layer "F.Cu")
		(net "SSD_LED_IOEXP_A1")
	)
	(segment
		(start 206.320644 -88.465152)
		(end 208.890616 -88.465152)
		(width 0.13208)
		(layer "F.Cu")
		(net "SSD_LED_IOEXP_A1")
	)
	(segment
		(start 208.947004 -88.408764)
		(end 208.947004 -86.772242)
		(width 0.13208)
		(layer "F.Cu")
		(net "SSD_LED_IOEXP_A1")
	)
	(via
		(at 208.947004 -88.408764)
		(size 0.508)
		(drill 0.254)
		(layers "F.Cu" "B.Cu")
		(net "SSD_LED_IOEXP_A1")
	)
	(via
		(at 147.831048 -279.931114)
		(size 0.508)
		(drill 0.254)
		(layers "F.Cu" "B.Cu")
		(net "SYSPLL_VDDA18_PEX1_R")
	)
	(segment
		(start 321.035934 -289.630866)
		(end 322.051934 -289.630866)
		(width 0.13208)
		(layer "F.Cu")
		(net "SMB_PEX2_HOST_LS_SDA")
	)
	(segment
		(start 320.019934 -289.630866)
		(end 321.035934 -289.630866)
		(width 0.13208)
		(layer "F.Cu")
		(net "SMB_PEX2_HOST_LS_SDA")
	)
	(segment
		(start 322.514214 -290.093146)
		(end 322.514214 -291.297868)
		(width 0.13208)
		(layer "F.Cu")
		(net "SMB_PEX2_HOST_LS_SDA")
	)
	(segment
		(start 322.222622 -294.016176)
		(end 322.514214 -293.724584)
		(width 0.13208)
		(layer "F.Cu")
		(net "SMB_PEX2_HOST_LS_SDA")
	)
	(segment
		(start 321.647566 -294.016176)
		(end 321.150996 -294.512746)
		(width 0.13208)
		(layer "F.Cu")
		(net "SMB_PEX2_HOST_LS_SDA")
	)
	(segment
		(start 322.222622 -294.016176)
		(end 321.647566 -294.016176)
		(width 0.13208)
		(layer "F.Cu")
		(net "SMB_PEX2_HOST_LS_SDA")
	)
	(segment
		(start 321.150996 -294.512746)
		(end 321.150996 -297.31716)
		(width 0.13208)
		(layer "F.Cu")
		(net "SMB_PEX2_HOST_LS_SDA")
	)
	(segment
		(start 322.514214 -293.724584)
		(end 322.514214 -291.297868)
		(width 0.13208)
		(layer "F.Cu")
		(net "SMB_PEX2_HOST_LS_SDA")
	)
	(segment
		(start 321.150996 -297.31716)
		(end 321.298316 -297.46448)
		(width 0.13208)
		(layer "F.Cu")
		(net "SMB_PEX2_HOST_LS_SDA")
	)
	(segment
		(start 322.051934 -289.630866)
		(end 322.514214 -290.093146)
		(width 0.13208)
		(layer "F.Cu")
		(net "SMB_PEX2_HOST_LS_SDA")
	)
	(via
		(at 322.222622 -294.016176)
		(size 0.508)
		(drill 0.254)
		(layers "F.Cu" "B.Cu")
		(net "SMB_PEX2_HOST_LS_SDA")
	)
	(segment
		(start 329.169522 -217.297)
		(end 327.93305 -217.297)
		(width 0.13208)
		(layer "F.Cu")
		(net "PRSNT_NIC7_FPGA_N")
	)
	(segment
		(start 330.661264 -217.587068)
		(end 330.525628 -217.722704)
		(width 0.13208)
		(layer "F.Cu")
		(net "PRSNT_NIC7_FPGA_N")
	)
	(segment
		(start 329.664314 -217.297)
		(end 329.169522 -217.297)
		(width 0.13208)
		(layer "F.Cu")
		(net "PRSNT_NIC7_FPGA_N")
	)
	(segment
		(start 330.525628 -217.722704)
		(end 330.090018 -217.722704)
		(width 0.13208)
		(layer "F.Cu")
		(net "PRSNT_NIC7_FPGA_N")
	)
	(segment
		(start 330.090018 -217.722704)
		(end 329.664314 -217.297)
		(width 0.13208)
		(layer "F.Cu")
		(net "PRSNT_NIC7_FPGA_N")
	)
	(segment
		(start 333.248 -217.587068)
		(end 330.661264 -217.587068)
		(width 0.13208)
		(layer "F.Cu")
		(net "PRSNT_NIC7_FPGA_N")
	)
	(segment
		(start 334.09382 -217.587068)
		(end 333.248 -217.587068)
		(width 0.0889)
		(layer "F.Cu")
		(net "PRSNT_NIC7_FPGA_N")
	)
	(via
		(at 329.169522 -217.297)
		(size 0.762)
		(drill 0.381)
		(layers "F.Cu" "B.Cu")
		(net "PRSNT_NIC7_FPGA_N")
	)
	(segment
		(start 334.518 -204.83195)
		(end 334.518 -204.216)
		(width 0.13208)
		(layer "F.Cu")
		(net "RST_SSD8_PERST_R_N")
	)
	(segment
		(start 246.403876 -24.189944)
		(end 247.464834 -24.189944)
		(width 0.13208)
		(layer "F.Cu")
		(net "RST_SSD8_PERST_R_N")
	)
	(via
		(at 277.508716 -86.440772)
		(size 0.508)
		(drill 0.254)
		(layers "F.Cu" "B.Cu")
		(net "RST_SSD8_PERST_R_N")
	)
	(via
		(at 334.518 -204.216)
		(size 0.508)
		(drill 0.254)
		(layers "F.Cu" "B.Cu")
		(net "RST_SSD8_PERST_R_N")
	)
	(via
		(at 246.403876 -24.189944)
		(size 0.508)
		(drill 0.254)
		(layers "F.Cu" "B.Cu")
		(net "RST_SSD8_PERST_R_N")
	)
	(via
		(at 312.196988 -93.81617)
		(size 0.508)
		(drill 0.254)
		(layers "F.Cu" "B.Cu")
		(net "RST_SSD8_PERST_R_N")
	)
	(segment
		(start 334.518 -203.721716)
		(end 333.98587 -203.189586)
		(width 0.15494)
		(layer "In5.Cu")
		(net "RST_SSD8_PERST_R_N")
	)
	(segment
		(start 314.048902 -116.779294)
		(end 312.207148 -114.93754)
		(width 0.15494)
		(layer "In5.Cu")
		(net "RST_SSD8_PERST_R_N")
	)
	(segment
		(start 334.252062 -172.371004)
		(end 334.252062 -171.852844)
		(width 0.15494)
		(layer "In5.Cu")
		(net "RST_SSD8_PERST_R_N")
	)
	(segment
		(start 251.124466 -26.873708)
		(end 250.24207 -25.991312)
		(width 0.15494)
		(layer "In5.Cu")
		(net "RST_SSD8_PERST_R_N")
	)
	(segment
		(start 270.782796 -82.686652)
		(end 270.782796 -77.321156)
		(width 0.15494)
		(layer "In5.Cu")
		(net "RST_SSD8_PERST_R_N")
	)
	(segment
		(start 333.664814 -143.433038)
		(end 331.492098 -141.260322)
		(width 0.15494)
		(layer "In5.Cu")
		(net "RST_SSD8_PERST_R_N")
	)
	(segment
		(start 277.508716 -86.440772)
		(end 276.493732 -85.425788)
		(width 0.15494)
		(layer "In5.Cu")
		(net "RST_SSD8_PERST_R_N")
	)
	(segment
		(start 331.492098 -141.260322)
		(end 329.663552 -141.260322)
		(width 0.15494)
		(layer "In5.Cu")
		(net "RST_SSD8_PERST_R_N")
	)
	(segment
		(start 312.207148 -93.82633)
		(end 312.196988 -93.81617)
		(width 0.15494)
		(layer "In5.Cu")
		(net "RST_SSD8_PERST_R_N")
	)
	(segment
		(start 312.207148 -114.93754)
		(end 312.207148 -93.82633)
		(width 0.15494)
		(layer "In5.Cu")
		(net "RST_SSD8_PERST_R_N")
	)
	(segment
		(start 321.941698 -133.538468)
		(end 321.941698 -129.710942)
		(width 0.15494)
		(layer "In5.Cu")
		(net "RST_SSD8_PERST_R_N")
	)
	(segment
		(start 333.98587 -199.902572)
		(end 333.614014 -199.530716)
		(width 0.15494)
		(layer "In5.Cu")
		(net "RST_SSD8_PERST_R_N")
	)
	(segment
		(start 268.929612 -66.438272)
		(end 268.929612 -45.586904)
		(width 0.15494)
		(layer "In5.Cu")
		(net "RST_SSD8_PERST_R_N")
	)
	(segment
		(start 333.98587 -203.189586)
		(end 333.98587 -199.902572)
		(width 0.15494)
		(layer "In5.Cu")
		(net "RST_SSD8_PERST_R_N")
	)
	(segment
		(start 333.614014 -173.009052)
		(end 334.252062 -172.371004)
		(width 0.15494)
		(layer "In5.Cu")
		(net "RST_SSD8_PERST_R_N")
	)
	(segment
		(start 249.63628 -25.192228)
		(end 248.758202 -24.575008)
		(width 0.15494)
		(layer "In5.Cu")
		(net "RST_SSD8_PERST_R_N")
	)
	(segment
		(start 256.871978 -29.036264)
		(end 256.871978 -28.288742)
		(width 0.15494)
		(layer "In5.Cu")
		(net "RST_SSD8_PERST_R_N")
	)
	(segment
		(start 333.614014 -199.530716)
		(end 333.614014 -173.009052)
		(width 0.15494)
		(layer "In5.Cu")
		(net "RST_SSD8_PERST_R_N")
	)
	(segment
		(start 268.929612 -45.586904)
		(end 256.0447 -32.701992)
		(width 0.15494)
		(layer "In5.Cu")
		(net "RST_SSD8_PERST_R_N")
	)
	(segment
		(start 253.43993 -27.985212)
		(end 252.328426 -26.873708)
		(width 0.15494)
		(layer "In5.Cu")
		(net "RST_SSD8_PERST_R_N")
	)
	(segment
		(start 334.518 -204.216)
		(end 334.518 -203.721716)
		(width 0.15494)
		(layer "In5.Cu")
		(net "RST_SSD8_PERST_R_N")
	)
	(segment
		(start 329.663552 -141.260322)
		(end 321.941698 -133.538468)
		(width 0.15494)
		(layer "In5.Cu")
		(net "RST_SSD8_PERST_R_N")
	)
	(segment
		(start 318.475106 -119.85117)
		(end 315.40323 -116.779294)
		(width 0.15494)
		(layer "In5.Cu")
		(net "RST_SSD8_PERST_R_N")
	)
	(segment
		(start 334.252062 -171.852844)
		(end 333.664814 -171.265596)
		(width 0.15494)
		(layer "In5.Cu")
		(net "RST_SSD8_PERST_R_N")
	)
	(segment
		(start 273.521932 -85.425788)
		(end 270.782796 -82.686652)
		(width 0.15494)
		(layer "In5.Cu")
		(net "RST_SSD8_PERST_R_N")
	)
	(segment
		(start 276.493732 -85.425788)
		(end 273.521932 -85.425788)
		(width 0.15494)
		(layer "In5.Cu")
		(net "RST_SSD8_PERST_R_N")
	)
	(segment
		(start 315.40323 -116.779294)
		(end 314.048902 -116.779294)
		(width 0.15494)
		(layer "In5.Cu")
		(net "RST_SSD8_PERST_R_N")
	)
	(segment
		(start 318.475106 -126.24435)
		(end 318.475106 -119.85117)
		(width 0.15494)
		(layer "In5.Cu")
		(net "RST_SSD8_PERST_R_N")
	)
	(segment
		(start 264.763504 -70.60438)
		(end 268.929612 -66.438272)
		(width 0.15494)
		(layer "In5.Cu")
		(net "RST_SSD8_PERST_R_N")
	)
	(segment
		(start 256.0447 -29.863542)
		(end 256.871978 -29.036264)
		(width 0.15494)
		(layer "In5.Cu")
		(net "RST_SSD8_PERST_R_N")
	)
	(segment
		(start 256.871978 -28.288742)
		(end 256.568448 -27.985212)
		(width 0.15494)
		(layer "In5.Cu")
		(net "RST_SSD8_PERST_R_N")
	)
	(segment
		(start 270.782796 -77.321156)
		(end 264.763504 -71.301864)
		(width 0.15494)
		(layer "In5.Cu")
		(net "RST_SSD8_PERST_R_N")
	)
	(segment
		(start 252.328426 -26.873708)
		(end 251.124466 -26.873708)
		(width 0.15494)
		(layer "In5.Cu")
		(net "RST_SSD8_PERST_R_N")
	)
	(segment
		(start 264.763504 -71.301864)
		(end 264.763504 -70.60438)
		(width 0.15494)
		(layer "In5.Cu")
		(net "RST_SSD8_PERST_R_N")
	)
	(segment
		(start 246.78894 -24.575008)
		(end 246.403876 -24.189944)
		(width 0.15494)
		(layer "In5.Cu")
		(net "RST_SSD8_PERST_R_N")
	)
	(segment
		(start 256.568448 -27.985212)
		(end 253.43993 -27.985212)
		(width 0.15494)
		(layer "In5.Cu")
		(net "RST_SSD8_PERST_R_N")
	)
	(segment
		(start 256.0447 -32.701992)
		(end 256.0447 -29.863542)
		(width 0.15494)
		(layer "In5.Cu")
		(net "RST_SSD8_PERST_R_N")
	)
	(segment
		(start 248.758202 -24.575008)
		(end 246.78894 -24.575008)
		(width 0.15494)
		(layer "In5.Cu")
		(net "RST_SSD8_PERST_R_N")
	)
	(segment
		(start 321.941698 -129.710942)
		(end 318.475106 -126.24435)
		(width 0.15494)
		(layer "In5.Cu")
		(net "RST_SSD8_PERST_R_N")
	)
	(segment
		(start 250.24207 -25.991312)
		(end 249.63628 -25.192228)
		(width 0.15494)
		(layer "In5.Cu")
		(net "RST_SSD8_PERST_R_N")
	)
	(segment
		(start 333.664814 -171.265596)
		(end 333.664814 -143.433038)
		(width 0.15494)
		(layer "In5.Cu")
		(net "RST_SSD8_PERST_R_N")
	)
	(segment
		(start 310.071262 -93.269308)
		(end 303.992026 -87.190072)
		(width 0.15494)
		(layer "In9.Cu")
		(net "RST_SSD8_PERST_R_N")
	)
	(segment
		(start 303.992026 -87.190072)
		(end 278.258016 -87.190072)
		(width 0.15494)
		(layer "In9.Cu")
		(net "RST_SSD8_PERST_R_N")
	)
	(segment
		(start 311.650126 -93.269308)
		(end 310.071262 -93.269308)
		(width 0.15494)
		(layer "In9.Cu")
		(net "RST_SSD8_PERST_R_N")
	)
	(segment
		(start 312.196988 -93.81617)
		(end 311.650126 -93.269308)
		(width 0.15494)
		(layer "In9.Cu")
		(net "RST_SSD8_PERST_R_N")
	)
	(segment
		(start 278.258016 -87.190072)
		(end 277.508716 -86.440772)
		(width 0.15494)
		(layer "In9.Cu")
		(net "RST_SSD8_PERST_R_N")
	)
	(segment
		(start 242.8113 -185.829702)
		(end 242.8113 -186.481212)
		(width 0.13208)
		(layer "F.Cu")
		(net "BIC_RST_RSMRST_N")
	)
	(segment
		(start 242.8113 -186.481212)
		(end 242.527836 -186.481212)
		(width 0.13208)
		(layer "F.Cu")
		(net "BIC_RST_RSMRST_N")
	)
	(segment
		(start 240.930684 -185.899044)
		(end 240.930684 -181.920388)
		(width 0.13208)
		(layer "F.Cu")
		(net "BIC_RST_RSMRST_N")
	)
	(segment
		(start 242.527836 -186.481212)
		(end 242.107974 -186.06135)
		(width 0.13208)
		(layer "F.Cu")
		(net "BIC_RST_RSMRST_N")
	)
	(segment
		(start 240.679224 -179.59705)
		(end 240.305844 -179.97043)
		(width 0.13208)
		(layer "F.Cu")
		(net "BIC_RST_RSMRST_N")
	)
	(segment
		(start 242.107974 -186.06135)
		(end 241.09299 -186.06135)
		(width 0.13208)
		(layer "F.Cu")
		(net "BIC_RST_RSMRST_N")
	)
	(segment
		(start 240.305844 -179.97043)
		(end 240.305844 -180.885338)
		(width 0.13208)
		(layer "F.Cu")
		(net "BIC_RST_RSMRST_N")
	)
	(segment
		(start 241.09299 -186.06135)
		(end 240.930684 -185.899044)
		(width 0.13208)
		(layer "F.Cu")
		(net "BIC_RST_RSMRST_N")
	)
	(segment
		(start 240.930684 -181.920388)
		(end 240.305844 -181.295548)
		(width 0.13208)
		(layer "F.Cu")
		(net "BIC_RST_RSMRST_N")
	)
	(segment
		(start 240.305844 -181.295548)
		(end 240.305844 -180.885338)
		(width 0.13208)
		(layer "F.Cu")
		(net "BIC_RST_RSMRST_N")
	)
	(segment
		(start 240.679224 -179.1208)
		(end 240.679224 -179.59705)
		(width 0.13208)
		(layer "F.Cu")
		(net "BIC_RST_RSMRST_N")
	)
	(via
		(at 242.8113 -186.481212)
		(size 0.508)
		(drill 0.254)
		(layers "F.Cu" "B.Cu")
		(net "BIC_RST_RSMRST_N")
	)
	(via
		(at 147.831048 -292.732714)
		(size 0.508)
		(drill 0.254)
		(layers "F.Cu" "B.Cu")
		(net "PCEPLL2_VDDA18_PEX1_R")
	)
	(segment
		(start 325.099934 -289.630866)
		(end 324.083934 -289.630866)
		(width 0.13208)
		(layer "F.Cu")
		(net "SMB_PEX2_HOST_LS_SCL")
	)
	(segment
		(start 324.083934 -289.630866)
		(end 323.067934 -289.630866)
		(width 0.13208)
		(layer "F.Cu")
		(net "SMB_PEX2_HOST_LS_SCL")
	)
	(segment
		(start 324.353682 -297.942)
		(end 325.562722 -297.942)
		(width 0.13208)
		(layer "F.Cu")
		(net "SMB_PEX2_HOST_LS_SCL")
	)
	(segment
		(start 325.8312 -297.673522)
		(end 325.8312 -294.5638)
		(width 0.13208)
		(layer "F.Cu")
		(net "SMB_PEX2_HOST_LS_SCL")
	)
	(segment
		(start 325.8312 -294.5638)
		(end 325.248016 -293.980616)
		(width 0.13208)
		(layer "F.Cu")
		(net "SMB_PEX2_HOST_LS_SCL")
	)
	(segment
		(start 323.067934 -289.630866)
		(end 323.164454 -289.727386)
		(width 0.13208)
		(layer "F.Cu")
		(net "SMB_PEX2_HOST_LS_SCL")
	)
	(segment
		(start 323.164454 -293.28237)
		(end 323.8627 -293.980616)
		(width 0.13208)
		(layer "F.Cu")
		(net "SMB_PEX2_HOST_LS_SCL")
	)
	(segment
		(start 323.164454 -291.297868)
		(end 323.164454 -293.28237)
		(width 0.13208)
		(layer "F.Cu")
		(net "SMB_PEX2_HOST_LS_SCL")
	)
	(segment
		(start 323.876162 -297.46448)
		(end 324.353682 -297.942)
		(width 0.13208)
		(layer "F.Cu")
		(net "SMB_PEX2_HOST_LS_SCL")
	)
	(segment
		(start 325.562722 -297.942)
		(end 325.8312 -297.673522)
		(width 0.13208)
		(layer "F.Cu")
		(net "SMB_PEX2_HOST_LS_SCL")
	)
	(segment
		(start 323.164454 -289.727386)
		(end 323.164454 -291.297868)
		(width 0.13208)
		(layer "F.Cu")
		(net "SMB_PEX2_HOST_LS_SCL")
	)
	(segment
		(start 325.248016 -293.980616)
		(end 323.8627 -293.980616)
		(width 0.13208)
		(layer "F.Cu")
		(net "SMB_PEX2_HOST_LS_SCL")
	)
	(via
		(at 323.8627 -293.980616)
		(size 0.508)
		(drill 0.254)
		(layers "F.Cu" "B.Cu")
		(net "SMB_PEX2_HOST_LS_SCL")
	)
	(via
		(at 147.831048 -283.131514)
		(size 0.508)
		(drill 0.254)
		(layers "F.Cu" "B.Cu")
		(net "PCEPLL7_VDDA18_PEX1_R")
	)
	(segment
		(start 204.523848 -300.03877)
		(end 204.727048 -300.24197)
		(width 0.13208)
		(layer "F.Cu")
		(net "I2C_PEX1_HOST_SDA")
	)
	(segment
		(start 204.523848 -299.76445)
		(end 204.523848 -300.03877)
		(width 0.13208)
		(layer "F.Cu")
		(net "I2C_PEX1_HOST_SDA")
	)
	(segment
		(start 204.727048 -300.24197)
		(end 205.112366 -300.24197)
		(width 0.13208)
		(layer "F.Cu")
		(net "I2C_PEX1_HOST_SDA")
	)
	(segment
		(start 206.128366 -300.24197)
		(end 205.112366 -300.24197)
		(width 0.13208)
		(layer "F.Cu")
		(net "I2C_PEX1_HOST_SDA")
	)
	(segment
		(start 204.651102 -299.27296)
		(end 204.523848 -299.400214)
		(width 0.13208)
		(layer "F.Cu")
		(net "I2C_PEX1_HOST_SDA")
	)
	(segment
		(start 204.523848 -299.400214)
		(end 204.523848 -299.76445)
		(width 0.13208)
		(layer "F.Cu")
		(net "I2C_PEX1_HOST_SDA")
	)
	(segment
		(start 205.105254 -299.27296)
		(end 204.651102 -299.27296)
		(width 0.13208)
		(layer "F.Cu")
		(net "I2C_PEX1_HOST_SDA")
	)
	(via
		(at 204.523848 -299.76445)
		(size 0.508)
		(drill 0.254)
		(layers "F.Cu" "B.Cu")
		(net "I2C_PEX1_HOST_SDA")
	)
	(segment
		(start 323.076062 -298.358052)
		(end 323.076062 -297.46448)
		(width 0.13208)
		(layer "F.Cu")
		(net "I2C_PEX2_HOST_R_SCL")
	)
	(segment
		(start 323.164454 -295.647872)
		(end 323.164454 -296.56786)
		(width 0.13208)
		(layer "F.Cu")
		(net "I2C_PEX2_HOST_R_SCL")
	)
	(segment
		(start 323.119242 -296.613072)
		(end 323.119242 -297.4213)
		(width 0.13208)
		(layer "F.Cu")
		(net "I2C_PEX2_HOST_R_SCL")
	)
	(segment
		(start 323.164454 -296.56786)
		(end 323.119242 -296.613072)
		(width 0.13208)
		(layer "F.Cu")
		(net "I2C_PEX2_HOST_R_SCL")
	)
	(segment
		(start 323.573648 -298.485052)
		(end 323.203062 -298.485052)
		(width 0.13208)
		(layer "F.Cu")
		(net "I2C_PEX2_HOST_R_SCL")
	)
	(segment
		(start 323.203062 -298.485052)
		(end 323.076062 -298.358052)
		(width 0.13208)
		(layer "F.Cu")
		(net "I2C_PEX2_HOST_R_SCL")
	)
	(segment
		(start 324.589648 -298.485052)
		(end 323.573648 -298.485052)
		(width 0.13208)
		(layer "F.Cu")
		(net "I2C_PEX2_HOST_R_SCL")
	)
	(segment
		(start 323.119242 -297.4213)
		(end 323.076062 -297.46448)
		(width 0.13208)
		(layer "F.Cu")
		(net "I2C_PEX2_HOST_R_SCL")
	)
	(via
		(at 323.119242 -296.613072)
		(size 0.508)
		(drill 0.254)
		(layers "F.Cu" "B.Cu")
		(net "I2C_PEX2_HOST_R_SCL")
	)
	(segment
		(start 106.078528 -393.654534)
		(end 106.205528 -393.781534)
		(width 0.254)
		(layer "F.Cu")
		(net "P3V3_BIC_USB_HUB")
	)
	(segment
		(start 105.789476 -393.654534)
		(end 106.078528 -393.654534)
		(width 0.254)
		(layer "F.Cu")
		(net "P3V3_BIC_USB_HUB")
	)
	(segment
		(start 101.87686 -394.751052)
		(end 101.87686 -394.566902)
		(width 0.254)
		(layer "F.Cu")
		(net "P3V3_BIC_USB_HUB")
	)
	(segment
		(start 101.440742 -395.18717)
		(end 101.87686 -394.751052)
		(width 0.254)
		(layer "F.Cu")
		(net "P3V3_BIC_USB_HUB")
	)
	(segment
		(start 106.205528 -393.781534)
		(end 106.205528 -394.322554)
		(width 0.254)
		(layer "F.Cu")
		(net "P3V3_BIC_USB_HUB")
	)
	(segment
		(start 103.876856 -389.741918)
		(end 103.876856 -388.911846)
		(width 0.254)
		(layer "F.Cu")
		(net "P3V3_BIC_USB_HUB")
	)
	(segment
		(start 105.789476 -391.154412)
		(end 106.583226 -391.154412)
		(width 0.254)
		(layer "F.Cu")
		(net "P3V3_BIC_USB_HUB")
	)
	(segment
		(start 106.205528 -394.322554)
		(end 106.210354 -394.32738)
		(width 0.254)
		(layer "F.Cu")
		(net "P3V3_BIC_USB_HUB")
	)
	(via
		(at 100.175314 -389.962644)
		(size 0.508)
		(drill 0.254)
		(layers "F.Cu" "B.Cu")
		(net "P3V3_BIC_USB_HUB")
	)
	(via
		(at 100.175314 -390.597644)
		(size 0.508)
		(drill 0.254)
		(layers "F.Cu" "B.Cu")
		(net "P3V3_BIC_USB_HUB")
	)
	(via
		(at 106.210354 -394.32738)
		(size 0.508)
		(drill 0.254)
		(layers "F.Cu" "B.Cu")
		(net "P3V3_BIC_USB_HUB")
	)
	(via
		(at 103.876856 -388.911846)
		(size 0.508)
		(drill 0.254)
		(layers "F.Cu" "B.Cu")
		(net "P3V3_BIC_USB_HUB")
	)
	(via
		(at 106.583226 -391.154412)
		(size 0.508)
		(drill 0.254)
		(layers "F.Cu" "B.Cu")
		(net "P3V3_BIC_USB_HUB")
	)
	(via
		(at 105.516934 -389.198612)
		(size 0.6604)
		(drill 0.3302)
		(layers "F.Cu" "B.Cu")
		(net "P3V3_BIC_USB_HUB")
	)
	(via
		(at 101.440742 -395.18717)
		(size 0.508)
		(drill 0.254)
		(layers "F.Cu" "B.Cu")
		(net "P3V3_BIC_USB_HUB")
	)
	(via
		(at 104.148636 -395.075664)
		(size 0.6604)
		(drill 0.3302)
		(layers "F.Cu" "B.Cu")
		(net "P3V3_BIC_USB_HUB")
	)
	(via
		(at 147.831048 -295.933114)
		(size 0.508)
		(drill 0.254)
		(layers "F.Cu" "B.Cu")
		(net "PCEPLL0_VDDA18_PEX1_R")
	)
	(segment
		(start 207.995266 -301.556928)
		(end 207.479392 -301.041054)
		(width 0.13208)
		(layer "F.Cu")
		(net "I2C0_PEX1_SCL")
	)
	(segment
		(start 185.725054 -307.774848)
		(end 185.250074 -308.249828)
		(width 0.13208)
		(layer "F.Cu")
		(net "I2C0_PEX1_SCL")
	)
	(segment
		(start 207.995266 -301.57674)
		(end 207.995266 -301.556928)
		(width 0.13208)
		(layer "F.Cu")
		(net "I2C0_PEX1_SCL")
	)
	(via
		(at 207.995266 -301.57674)
		(size 0.508)
		(drill 0.254)
		(layers "F.Cu" "B.Cu")
		(net "I2C0_PEX1_SCL")
	)
	(via
		(at 185.725054 -307.774848)
		(size 0.4064)
		(drill 0.2032)
		(layers "F.Cu" "B.Cu")
		(net "I2C0_PEX1_SCL")
	)
	(segment
		(start 188.455554 -307.34)
		(end 189.0014 -307.34)
		(width 0.15494)
		(layer "In5.Cu")
		(net "I2C0_PEX1_SCL")
	)
	(segment
		(start 190.8937 -300.545246)
		(end 190.8937 -299.910246)
		(width 0.15494)
		(layer "In5.Cu")
		(net "I2C0_PEX1_SCL")
	)
	(segment
		(start 189.5348 -306.8066)
		(end 189.5348 -303.276)
		(width 0.15494)
		(layer "In5.Cu")
		(net "I2C0_PEX1_SCL")
	)
	(segment
		(start 188.116718 -307.001164)
		(end 188.455554 -307.34)
		(width 0.15494)
		(layer "In5.Cu")
		(net "I2C0_PEX1_SCL")
	)
	(segment
		(start 203.657962 -299.7708)
		(end 204.394562 -300.5074)
		(width 0.15494)
		(layer "In5.Cu")
		(net "I2C0_PEX1_SCL")
	)
	(segment
		(start 185.725054 -307.774848)
		(end 185.333894 -307.383688)
		(width 0.15494)
		(layer "In5.Cu")
		(net "I2C0_PEX1_SCL")
	)
	(segment
		(start 207.995266 -301.215044)
		(end 207.995266 -301.57674)
		(width 0.15494)
		(layer "In5.Cu")
		(net "I2C0_PEX1_SCL")
	)
	(segment
		(start 191.102488 -299.701458)
		(end 199.244712 -299.701458)
		(width 0.15494)
		(layer "In5.Cu")
		(net "I2C0_PEX1_SCL")
	)
	(segment
		(start 199.244712 -299.701458)
		(end 199.314054 -299.7708)
		(width 0.15494)
		(layer "In5.Cu")
		(net "I2C0_PEX1_SCL")
	)
	(segment
		(start 189.738 -303.0728)
		(end 190.0428 -303.0728)
		(width 0.15494)
		(layer "In5.Cu")
		(net "I2C0_PEX1_SCL")
	)
	(segment
		(start 190.0428 -303.0728)
		(end 190.5 -302.6156)
		(width 0.15494)
		(layer "In5.Cu")
		(net "I2C0_PEX1_SCL")
	)
	(segment
		(start 190.5 -300.938946)
		(end 190.8937 -300.545246)
		(width 0.15494)
		(layer "In5.Cu")
		(net "I2C0_PEX1_SCL")
	)
	(segment
		(start 188.116718 -306.605178)
		(end 188.116718 -307.001164)
		(width 0.15494)
		(layer "In5.Cu")
		(net "I2C0_PEX1_SCL")
	)
	(segment
		(start 199.314054 -299.7708)
		(end 203.657962 -299.7708)
		(width 0.15494)
		(layer "In5.Cu")
		(net "I2C0_PEX1_SCL")
	)
	(segment
		(start 204.394562 -300.5074)
		(end 207.287622 -300.5074)
		(width 0.15494)
		(layer "In5.Cu")
		(net "I2C0_PEX1_SCL")
	)
	(segment
		(start 185.507376 -306.384452)
		(end 187.895992 -306.384452)
		(width 0.15494)
		(layer "In5.Cu")
		(net "I2C0_PEX1_SCL")
	)
	(segment
		(start 207.287622 -300.5074)
		(end 207.995266 -301.215044)
		(width 0.15494)
		(layer "In5.Cu")
		(net "I2C0_PEX1_SCL")
	)
	(segment
		(start 185.333894 -306.557934)
		(end 185.507376 -306.384452)
		(width 0.15494)
		(layer "In5.Cu")
		(net "I2C0_PEX1_SCL")
	)
	(segment
		(start 190.8937 -299.910246)
		(end 191.102488 -299.701458)
		(width 0.15494)
		(layer "In5.Cu")
		(net "I2C0_PEX1_SCL")
	)
	(segment
		(start 187.895992 -306.384452)
		(end 188.116718 -306.605178)
		(width 0.15494)
		(layer "In5.Cu")
		(net "I2C0_PEX1_SCL")
	)
	(segment
		(start 189.5348 -303.276)
		(end 189.738 -303.0728)
		(width 0.15494)
		(layer "In5.Cu")
		(net "I2C0_PEX1_SCL")
	)
	(segment
		(start 190.5 -302.6156)
		(end 190.5 -300.938946)
		(width 0.15494)
		(layer "In5.Cu")
		(net "I2C0_PEX1_SCL")
	)
	(segment
		(start 185.333894 -307.383688)
		(end 185.333894 -306.557934)
		(width 0.15494)
		(layer "In5.Cu")
		(net "I2C0_PEX1_SCL")
	)
	(segment
		(start 189.0014 -307.34)
		(end 189.5348 -306.8066)
		(width 0.15494)
		(layer "In5.Cu")
		(net "I2C0_PEX1_SCL")
	)
	(segment
		(start 362.731304 -281.999182)
		(end 362.731304 -281.438858)
		(width 0.2032)
		(layer "F.Cu")
		(net "P0V8_PEX3_PWM2")
	)
	(segment
		(start 362.809536 -281.249882)
		(end 362.809536 -280.897838)
		(width 0.2032)
		(layer "F.Cu")
		(net "P0V8_PEX3_PWM2")
	)
	(segment
		(start 351.31629 -254.953008)
		(end 351.575878 -255.212596)
		(width 0.13208)
		(layer "F.Cu")
		(net "P0V8_PEX3_PWM2")
	)
	(segment
		(start 362.809536 -280.897838)
		(end 362.934758 -280.617168)
		(width 0.2032)
		(layer "F.Cu")
		(net "P0V8_PEX3_PWM2")
	)
	(segment
		(start 352.854768 -252.112272)
		(end 351.952306 -252.112272)
		(width 0.13208)
		(layer "F.Cu")
		(net "P0V8_PEX3_PWM2")
	)
	(segment
		(start 362.731304 -281.438858)
		(end 362.809536 -281.249882)
		(width 0.2032)
		(layer "F.Cu")
		(net "P0V8_PEX3_PWM2")
	)
	(segment
		(start 351.433638 -252.63094)
		(end 351.433638 -253.477014)
		(width 0.13208)
		(layer "F.Cu")
		(net "P0V8_PEX3_PWM2")
	)
	(segment
		(start 351.433638 -253.477014)
		(end 351.31629 -253.594362)
		(width 0.13208)
		(layer "F.Cu")
		(net "P0V8_PEX3_PWM2")
	)
	(segment
		(start 351.31629 -253.594362)
		(end 351.31629 -254.953008)
		(width 0.13208)
		(layer "F.Cu")
		(net "P0V8_PEX3_PWM2")
	)
	(segment
		(start 351.952306 -252.112272)
		(end 351.433638 -252.63094)
		(width 0.13208)
		(layer "F.Cu")
		(net "P0V8_PEX3_PWM2")
	)
	(segment
		(start 351.575878 -255.212596)
		(end 351.575878 -255.994916)
		(width 0.13208)
		(layer "F.Cu")
		(net "P0V8_PEX3_PWM2")
	)
	(via
		(at 362.934758 -280.617168)
		(size 0.508)
		(drill 0.254)
		(layers "F.Cu" "B.Cu")
		(net "P0V8_PEX3_PWM2")
	)
	(via
		(at 352.854768 -252.112272)
		(size 0.508)
		(drill 0.254)
		(layers "F.Cu" "B.Cu")
		(net "P0V8_PEX3_PWM2")
	)
	(segment
		(start 357.920544 -257.72618)
		(end 357.920544 -260.846062)
		(width 0.2032)
		(layer "In5.Cu")
		(net "P0V8_PEX3_PWM2")
	)
	(segment
		(start 357.920544 -260.846062)
		(end 363.905292 -266.83081)
		(width 0.2032)
		(layer "In5.Cu")
		(net "P0V8_PEX3_PWM2")
	)
	(segment
		(start 363.905292 -277.827232)
		(end 362.934758 -278.797766)
		(width 0.2032)
		(layer "In5.Cu")
		(net "P0V8_PEX3_PWM2")
	)
	(segment
		(start 356.90556 -253.595378)
		(end 356.90556 -256.711196)
		(width 0.2032)
		(layer "In5.Cu")
		(net "P0V8_PEX3_PWM2")
	)
	(segment
		(start 363.905292 -266.83081)
		(end 363.905292 -277.827232)
		(width 0.2032)
		(layer "In5.Cu")
		(net "P0V8_PEX3_PWM2")
	)
	(segment
		(start 356.90556 -256.711196)
		(end 357.920544 -257.72618)
		(width 0.2032)
		(layer "In5.Cu")
		(net "P0V8_PEX3_PWM2")
	)
	(segment
		(start 362.934758 -278.797766)
		(end 362.934758 -280.617168)
		(width 0.2032)
		(layer "In5.Cu")
		(net "P0V8_PEX3_PWM2")
	)
	(segment
		(start 355.422454 -252.112272)
		(end 356.90556 -253.595378)
		(width 0.2032)
		(layer "In5.Cu")
		(net "P0V8_PEX3_PWM2")
	)
	(segment
		(start 352.854768 -252.112272)
		(end 355.422454 -252.112272)
		(width 0.2032)
		(layer "In5.Cu")
		(net "P0V8_PEX3_PWM2")
	)
	(via
		(at 147.831048 -299.133514)
		(size 0.508)
		(drill 0.254)
		(layers "F.Cu" "B.Cu")
		(net "PCEPLL1_VDDA18_PEX1_R")
	)
	(segment
		(start 188.574934 -307.774848)
		(end 189.049914 -308.249828)
		(width 0.13208)
		(layer "F.Cu")
		(net "I2C0_PEX1_SDA")
	)
	(segment
		(start 206.79918 -301.04207)
		(end 206.128366 -301.04207)
		(width 0.13208)
		(layer "F.Cu")
		(net "I2C0_PEX1_SDA")
	)
	(via
		(at 206.79918 -301.04207)
		(size 0.508)
		(drill 0.254)
		(layers "F.Cu" "B.Cu")
		(net "I2C0_PEX1_SDA")
	)
	(via
		(at 188.574934 -307.774848)
		(size 0.4064)
		(drill 0.2032)
		(layers "F.Cu" "B.Cu")
		(net "I2C0_PEX1_SDA")
	)
	(segment
		(start 192.176654 -300.598332)
		(end 199.25538 -300.598332)
		(width 0.15494)
		(layer "In5.Cu")
		(net "I2C0_PEX1_SDA")
	)
	(segment
		(start 200.516236 -300.37278)
		(end 200.658222 -300.230794)
		(width 0.15494)
		(layer "In5.Cu")
		(net "I2C0_PEX1_SDA")
	)
	(segment
		(start 200.173082 -301.1678)
		(end 200.37425 -301.1678)
		(width 0.15494)
		(layer "In5.Cu")
		(net "I2C0_PEX1_SDA")
	)
	(segment
		(start 200.031096 -301.025814)
		(end 200.173082 -301.1678)
		(width 0.15494)
		(layer "In5.Cu")
		(net "I2C0_PEX1_SDA")
	)
	(segment
		(start 199.88911 -300.230794)
		(end 200.031096 -300.37278)
		(width 0.15494)
		(layer "In5.Cu")
		(net "I2C0_PEX1_SDA")
	)
	(segment
		(start 188.574934 -307.774848)
		(end 188.623702 -307.774848)
		(width 0.15494)
		(layer "In5.Cu")
		(net "I2C0_PEX1_SDA")
	)
	(segment
		(start 190.4238 -303.3268)
		(end 190.9572 -302.7934)
		(width 0.15494)
		(layer "In5.Cu")
		(net "I2C0_PEX1_SDA")
	)
	(segment
		(start 199.622918 -300.230794)
		(end 199.88911 -300.230794)
		(width 0.15494)
		(layer "In5.Cu")
		(net "I2C0_PEX1_SDA")
	)
	(segment
		(start 188.696854 -307.848)
		(end 190.2968 -307.848)
		(width 0.15494)
		(layer "In5.Cu")
		(net "I2C0_PEX1_SDA")
	)
	(segment
		(start 190.4238 -307.721)
		(end 190.4238 -303.3268)
		(width 0.15494)
		(layer "In5.Cu")
		(net "I2C0_PEX1_SDA")
	)
	(segment
		(start 204.075538 -301.04207)
		(end 206.79918 -301.04207)
		(width 0.15494)
		(layer "In5.Cu")
		(net "I2C0_PEX1_SDA")
	)
	(segment
		(start 190.2968 -307.848)
		(end 190.4238 -307.721)
		(width 0.15494)
		(layer "In5.Cu")
		(net "I2C0_PEX1_SDA")
	)
	(segment
		(start 200.37425 -301.1678)
		(end 200.516236 -301.025814)
		(width 0.15494)
		(layer "In5.Cu")
		(net "I2C0_PEX1_SDA")
	)
	(segment
		(start 200.516236 -301.025814)
		(end 200.516236 -300.37278)
		(width 0.15494)
		(layer "In5.Cu")
		(net "I2C0_PEX1_SDA")
	)
	(segment
		(start 200.031096 -300.37278)
		(end 200.031096 -301.025814)
		(width 0.15494)
		(layer "In5.Cu")
		(net "I2C0_PEX1_SDA")
	)
	(segment
		(start 190.9572 -301.817786)
		(end 192.176654 -300.598332)
		(width 0.15494)
		(layer "In5.Cu")
		(net "I2C0_PEX1_SDA")
	)
	(segment
		(start 188.623702 -307.774848)
		(end 188.696854 -307.848)
		(width 0.15494)
		(layer "In5.Cu")
		(net "I2C0_PEX1_SDA")
	)
	(segment
		(start 200.658222 -300.230794)
		(end 203.264262 -300.230794)
		(width 0.15494)
		(layer "In5.Cu")
		(net "I2C0_PEX1_SDA")
	)
	(segment
		(start 203.264262 -300.230794)
		(end 204.075538 -301.04207)
		(width 0.15494)
		(layer "In5.Cu")
		(net "I2C0_PEX1_SDA")
	)
	(segment
		(start 190.9572 -302.7934)
		(end 190.9572 -301.817786)
		(width 0.15494)
		(layer "In5.Cu")
		(net "I2C0_PEX1_SDA")
	)
	(segment
		(start 199.25538 -300.598332)
		(end 199.622918 -300.230794)
		(width 0.15494)
		(layer "In5.Cu")
		(net "I2C0_PEX1_SDA")
	)
	(segment
		(start 322.221098 -298.190412)
		(end 322.098416 -298.06773)
		(width 0.13208)
		(layer "F.Cu")
		(net "I2C_PEX2_HOST_R_SDA")
	)
	(segment
		(start 322.221098 -298.47286)
		(end 322.221098 -298.190412)
		(width 0.13208)
		(layer "F.Cu")
		(net "I2C_PEX2_HOST_R_SDA")
	)
	(segment
		(start 322.514214 -295.647872)
		(end 322.514214 -296.458386)
		(width 0.13208)
		(layer "F.Cu")
		(net "I2C_PEX2_HOST_R_SDA")
	)
	(segment
		(start 322.098416 -296.867072)
		(end 322.098416 -297.46448)
		(width 0.13208)
		(layer "F.Cu")
		(net "I2C_PEX2_HOST_R_SDA")
	)
	(segment
		(start 321.844416 -296.613072)
		(end 322.098416 -296.867072)
		(width 0.13208)
		(layer "F.Cu")
		(net "I2C_PEX2_HOST_R_SDA")
	)
	(segment
		(start 322.514214 -296.458386)
		(end 322.359528 -296.613072)
		(width 0.13208)
		(layer "F.Cu")
		(net "I2C_PEX2_HOST_R_SDA")
	)
	(segment
		(start 322.359528 -296.613072)
		(end 321.844416 -296.613072)
		(width 0.13208)
		(layer "F.Cu")
		(net "I2C_PEX2_HOST_R_SDA")
	)
	(segment
		(start 322.098416 -298.06773)
		(end 322.098416 -297.46448)
		(width 0.13208)
		(layer "F.Cu")
		(net "I2C_PEX2_HOST_R_SDA")
	)
	(segment
		(start 321.205098 -298.47286)
		(end 322.221098 -298.47286)
		(width 0.13208)
		(layer "F.Cu")
		(net "I2C_PEX2_HOST_R_SDA")
	)
	(via
		(at 321.844416 -296.613072)
		(size 0.508)
		(drill 0.254)
		(layers "F.Cu" "B.Cu")
		(net "I2C_PEX2_HOST_R_SDA")
	)
	(via
		(at 150.789132 -256.375916)
		(size 0.508)
		(drill 0.254)
		(layers "F.Cu" "B.Cu")
		(net "PCEPLL5_VDDA18_PEX1_R")
	)
	(segment
		(start 335.534 -200.76795)
		(end 335.534 -200.152)
		(width 0.13208)
		(layer "F.Cu")
		(net "RST_SSD10_PERST_R_N")
	)
	(segment
		(start 298.403772 -24.189944)
		(end 299.46473 -24.189944)
		(width 0.13208)
		(layer "F.Cu")
		(net "RST_SSD10_PERST_R_N")
	)
	(via
		(at 313.665616 -80.503268)
		(size 0.508)
		(drill 0.254)
		(layers "F.Cu" "B.Cu")
		(net "RST_SSD10_PERST_R_N")
	)
	(via
		(at 298.403772 -24.189944)
		(size 0.508)
		(drill 0.254)
		(layers "F.Cu" "B.Cu")
		(net "RST_SSD10_PERST_R_N")
	)
	(via
		(at 335.534 -200.152)
		(size 0.508)
		(drill 0.254)
		(layers "F.Cu" "B.Cu")
		(net "RST_SSD10_PERST_R_N")
	)
	(via
		(at 321.720464 -81.903824)
		(size 0.508)
		(drill 0.254)
		(layers "F.Cu" "B.Cu")
		(net "RST_SSD10_PERST_R_N")
	)
	(segment
		(start 321.163188 -77.54112)
		(end 320.256662 -77.54112)
		(width 0.15494)
		(layer "In5.Cu")
		(net "RST_SSD10_PERST_R_N")
	)
	(segment
		(start 320.888868 -45.468286)
		(end 308.044596 -32.624014)
		(width 0.15494)
		(layer "In5.Cu")
		(net "RST_SSD10_PERST_R_N")
	)
	(segment
		(start 320.057272 -72.66686)
		(end 320.888868 -71.835264)
		(width 0.15494)
		(layer "In5.Cu")
		(net "RST_SSD10_PERST_R_N")
	)
	(segment
		(start 308.861206 -28.259532)
		(end 308.420262 -27.818588)
		(width 0.15494)
		(layer "In5.Cu")
		(net "RST_SSD10_PERST_R_N")
	)
	(segment
		(start 300.758098 -24.575008)
		(end 298.788836 -24.575008)
		(width 0.15494)
		(layer "In5.Cu")
		(net "RST_SSD10_PERST_R_N")
	)
	(segment
		(start 335.565242 -187.300362)
		(end 335.565242 -175.866298)
		(width 0.15494)
		(layer "In5.Cu")
		(net "RST_SSD10_PERST_R_N")
	)
	(segment
		(start 321.720464 -81.903824)
		(end 321.966082 -81.658206)
		(width 0.15494)
		(layer "In5.Cu")
		(net "RST_SSD10_PERST_R_N")
	)
	(segment
		(start 335.565242 -175.866298)
		(end 336.551778 -174.879762)
		(width 0.15494)
		(layer "In5.Cu")
		(net "RST_SSD10_PERST_R_N")
	)
	(segment
		(start 321.964812 -78.342744)
		(end 321.163188 -77.54112)
		(width 0.15494)
		(layer "In5.Cu")
		(net "RST_SSD10_PERST_R_N")
	)
	(segment
		(start 308.044596 -29.903928)
		(end 308.861206 -29.087318)
		(width 0.15494)
		(layer "In5.Cu")
		(net "RST_SSD10_PERST_R_N")
	)
	(segment
		(start 321.964812 -81.656936)
		(end 321.964812 -78.342744)
		(width 0.15494)
		(layer "In5.Cu")
		(net "RST_SSD10_PERST_R_N")
	)
	(segment
		(start 319.854326 -125.67285)
		(end 319.854326 -119.27967)
		(width 0.15494)
		(layer "In5.Cu")
		(net "RST_SSD10_PERST_R_N")
	)
	(segment
		(start 315.637672 -115.063016)
		(end 315.637672 -82.475324)
		(width 0.15494)
		(layer "In5.Cu")
		(net "RST_SSD10_PERST_R_N")
	)
	(segment
		(start 323.320918 -132.966968)
		(end 323.320918 -129.139442)
		(width 0.15494)
		(layer "In5.Cu")
		(net "RST_SSD10_PERST_R_N")
	)
	(segment
		(start 308.044596 -32.624014)
		(end 308.044596 -29.903928)
		(width 0.15494)
		(layer "In5.Cu")
		(net "RST_SSD10_PERST_R_N")
	)
	(segment
		(start 320.057272 -77.34173)
		(end 320.057272 -72.66686)
		(width 0.15494)
		(layer "In5.Cu")
		(net "RST_SSD10_PERST_R_N")
	)
	(segment
		(start 302.241966 -25.991312)
		(end 301.636176 -25.192228)
		(width 0.15494)
		(layer "In5.Cu")
		(net "RST_SSD10_PERST_R_N")
	)
	(segment
		(start 321.966082 -81.658206)
		(end 321.964812 -81.656936)
		(width 0.15494)
		(layer "In5.Cu")
		(net "RST_SSD10_PERST_R_N")
	)
	(segment
		(start 335.079086 -138.776964)
		(end 329.130914 -138.776964)
		(width 0.15494)
		(layer "In5.Cu")
		(net "RST_SSD10_PERST_R_N")
	)
	(segment
		(start 335.534 -200.152)
		(end 335.534 -199.302624)
		(width 0.15494)
		(layer "In5.Cu")
		(net "RST_SSD10_PERST_R_N")
	)
	(segment
		(start 303.124362 -26.873708)
		(end 302.241966 -25.991312)
		(width 0.15494)
		(layer "In5.Cu")
		(net "RST_SSD10_PERST_R_N")
	)
	(segment
		(start 320.256662 -77.54112)
		(end 320.057272 -77.34173)
		(width 0.15494)
		(layer "In5.Cu")
		(net "RST_SSD10_PERST_R_N")
	)
	(segment
		(start 319.854326 -119.27967)
		(end 315.637672 -115.063016)
		(width 0.15494)
		(layer "In5.Cu")
		(net "RST_SSD10_PERST_R_N")
	)
	(segment
		(start 298.788836 -24.575008)
		(end 298.403772 -24.189944)
		(width 0.15494)
		(layer "In5.Cu")
		(net "RST_SSD10_PERST_R_N")
	)
	(segment
		(start 335.043018 -198.811642)
		(end 335.043018 -187.822586)
		(width 0.15494)
		(layer "In5.Cu")
		(net "RST_SSD10_PERST_R_N")
	)
	(segment
		(start 335.043018 -187.822586)
		(end 335.565242 -187.300362)
		(width 0.15494)
		(layer "In5.Cu")
		(net "RST_SSD10_PERST_R_N")
	)
	(segment
		(start 336.551778 -174.879762)
		(end 336.551778 -140.249656)
		(width 0.15494)
		(layer "In5.Cu")
		(net "RST_SSD10_PERST_R_N")
	)
	(segment
		(start 308.420262 -27.818588)
		(end 305.582828 -27.818588)
		(width 0.15494)
		(layer "In5.Cu")
		(net "RST_SSD10_PERST_R_N")
	)
	(segment
		(start 329.130914 -138.776964)
		(end 323.320918 -132.966968)
		(width 0.15494)
		(layer "In5.Cu")
		(net "RST_SSD10_PERST_R_N")
	)
	(segment
		(start 335.534 -199.302624)
		(end 335.043018 -198.811642)
		(width 0.15494)
		(layer "In5.Cu")
		(net "RST_SSD10_PERST_R_N")
	)
	(segment
		(start 336.551778 -140.249656)
		(end 335.079086 -138.776964)
		(width 0.15494)
		(layer "In5.Cu")
		(net "RST_SSD10_PERST_R_N")
	)
	(segment
		(start 304.637948 -26.873708)
		(end 303.124362 -26.873708)
		(width 0.15494)
		(layer "In5.Cu")
		(net "RST_SSD10_PERST_R_N")
	)
	(segment
		(start 308.861206 -29.087318)
		(end 308.861206 -28.259532)
		(width 0.15494)
		(layer "In5.Cu")
		(net "RST_SSD10_PERST_R_N")
	)
	(segment
		(start 323.320918 -129.139442)
		(end 319.854326 -125.67285)
		(width 0.15494)
		(layer "In5.Cu")
		(net "RST_SSD10_PERST_R_N")
	)
	(segment
		(start 301.636176 -25.192228)
		(end 300.758098 -24.575008)
		(width 0.15494)
		(layer "In5.Cu")
		(net "RST_SSD10_PERST_R_N")
	)
	(segment
		(start 315.637672 -82.475324)
		(end 313.665616 -80.503268)
		(width 0.15494)
		(layer "In5.Cu")
		(net "RST_SSD10_PERST_R_N")
	)
	(segment
		(start 320.888868 -71.835264)
		(end 320.888868 -45.468286)
		(width 0.15494)
		(layer "In5.Cu")
		(net "RST_SSD10_PERST_R_N")
	)
	(segment
		(start 305.582828 -27.818588)
		(end 304.637948 -26.873708)
		(width 0.15494)
		(layer "In5.Cu")
		(net "RST_SSD10_PERST_R_N")
	)
	(segment
		(start 313.665616 -80.503268)
		(end 315.966348 -82.804)
		(width 0.15494)
		(layer "In13.Cu")
		(net "RST_SSD10_PERST_R_N")
	)
	(segment
		(start 315.966348 -82.804)
		(end 320.820288 -82.804)
		(width 0.15494)
		(layer "In13.Cu")
		(net "RST_SSD10_PERST_R_N")
	)
	(segment
		(start 320.820288 -82.804)
		(end 321.720464 -81.903824)
		(width 0.15494)
		(layer "In13.Cu")
		(net "RST_SSD10_PERST_R_N")
	)
	(segment
		(start 227.467668 -226.354132)
		(end 227.467668 -224.704148)
		(width 0.13208)
		(layer "F.Cu")
		(net "NIC6_MAIN_PWR_BIC_EN")
	)
	(segment
		(start 225.711512 -231.016556)
		(end 226.480116 -230.247952)
		(width 0.13208)
		(layer "F.Cu")
		(net "NIC6_MAIN_PWR_BIC_EN")
	)
	(segment
		(start 226.480116 -227.341684)
		(end 227.467668 -226.354132)
		(width 0.13208)
		(layer "F.Cu")
		(net "NIC6_MAIN_PWR_BIC_EN")
	)
	(segment
		(start 226.480116 -228.796342)
		(end 226.480116 -227.341684)
		(width 0.13208)
		(layer "F.Cu")
		(net "NIC6_MAIN_PWR_BIC_EN")
	)
	(segment
		(start 226.480116 -230.247952)
		(end 226.480116 -228.796342)
		(width 0.13208)
		(layer "F.Cu")
		(net "NIC6_MAIN_PWR_BIC_EN")
	)
	(via
		(at 226.480116 -228.796342)
		(size 0.762)
		(drill 0.381)
		(layers "F.Cu" "B.Cu")
		(net "NIC6_MAIN_PWR_BIC_EN")
	)
	(segment
		(start 227.467668 -213.504272)
		(end 227.067872 -213.104476)
		(width 0.13208)
		(layer "F.Cu")
		(net "JTAG_BIC_TMS")
	)
	(via
		(at 227.036122 -211.441792)
		(size 0.7112)
		(drill 0.3556)
		(layers "F.Cu" "B.Cu")
		(net "JTAG_BIC_TMS")
	)
	(via
		(at 227.067872 -213.104476)
		(size 0.4572)
		(drill 0.254)
		(layers "F.Cu" "B.Cu")
		(net "JTAG_BIC_TMS")
	)
	(segment
		(start 227.507292 -212.338666)
		(end 227.507292 -211.912962)
		(width 0.13208)
		(layer "B.Cu")
		(net "JTAG_BIC_TMS")
	)
	(segment
		(start 226.716844 -209.35569)
		(end 226.546664 -209.18551)
		(width 0.13208)
		(layer "B.Cu")
		(net "JTAG_BIC_TMS")
	)
	(segment
		(start 226.716844 -211.122514)
		(end 226.716844 -209.35569)
		(width 0.13208)
		(layer "B.Cu")
		(net "JTAG_BIC_TMS")
	)
	(segment
		(start 227.067872 -213.104476)
		(end 227.276914 -212.895434)
		(width 0.13208)
		(layer "B.Cu")
		(net "JTAG_BIC_TMS")
	)
	(segment
		(start 227.276914 -212.895434)
		(end 227.507292 -212.338666)
		(width 0.13208)
		(layer "B.Cu")
		(net "JTAG_BIC_TMS")
	)
	(segment
		(start 227.036122 -211.441792)
		(end 226.716844 -211.122514)
		(width 0.13208)
		(layer "B.Cu")
		(net "JTAG_BIC_TMS")
	)
	(segment
		(start 227.507292 -211.912962)
		(end 227.036122 -211.441792)
		(width 0.13208)
		(layer "B.Cu")
		(net "JTAG_BIC_TMS")
	)
	(via
		(at 147.831048 -289.532314)
		(size 0.508)
		(drill 0.254)
		(layers "F.Cu" "B.Cu")
		(net "PCEPLL4_VDDA18_PEX1_R")
	)
	(segment
		(start 325.02983 -299.285152)
		(end 324.589648 -299.285152)
		(width 0.13208)
		(layer "F.Cu")
		(net "I2C_PEX2_HOST_SCL")
	)
	(segment
		(start 323.579236 -300.240954)
		(end 324.57771 -300.240954)
		(width 0.13208)
		(layer "F.Cu")
		(net "I2C_PEX2_HOST_SCL")
	)
	(segment
		(start 325.22033 -300.123098)
		(end 325.22033 -299.77969)
		(width 0.13208)
		(layer "F.Cu")
		(net "I2C_PEX2_HOST_SCL")
	)
	(segment
		(start 324.57771 -300.240954)
		(end 324.587108 -300.250352)
		(width 0.13208)
		(layer "F.Cu")
		(net "I2C_PEX2_HOST_SCL")
	)
	(segment
		(start 325.22033 -299.475652)
		(end 325.02983 -299.285152)
		(width 0.13208)
		(layer "F.Cu")
		(net "I2C_PEX2_HOST_SCL")
	)
	(segment
		(start 324.587108 -300.250352)
		(end 325.093076 -300.250352)
		(width 0.13208)
		(layer "F.Cu")
		(net "I2C_PEX2_HOST_SCL")
	)
	(segment
		(start 325.22033 -299.77969)
		(end 325.22033 -299.475652)
		(width 0.13208)
		(layer "F.Cu")
		(net "I2C_PEX2_HOST_SCL")
	)
	(segment
		(start 325.093076 -300.250352)
		(end 325.22033 -300.123098)
		(width 0.13208)
		(layer "F.Cu")
		(net "I2C_PEX2_HOST_SCL")
	)
	(via
		(at 325.22033 -299.77969)
		(size 0.508)
		(drill 0.254)
		(layers "F.Cu" "B.Cu")
		(net "I2C_PEX2_HOST_SCL")
	)
	(segment
		(start 308.33441 -28.469082)
		(end 308.33441 -28.550108)
		(width 0.13208)
		(layer "F.Cu")
		(net "SSD10_PWRDIS_R")
	)
	(segment
		(start 308.33441 -28.550108)
		(end 308.864254 -29.079952)
		(width 0.13208)
		(layer "F.Cu")
		(net "SSD10_PWRDIS_R")
	)
	(segment
		(start 299.46473 -25.390094)
		(end 298.391072 -25.390094)
		(width 0.13208)
		(layer "F.Cu")
		(net "SSD10_PWRDIS_R")
	)
	(via
		(at 308.33441 -28.469082)
		(size 0.508)
		(drill 0.254)
		(layers "F.Cu" "B.Cu")
		(net "SSD10_PWRDIS_R")
	)
	(via
		(at 298.391072 -25.390094)
		(size 0.508)
		(drill 0.254)
		(layers "F.Cu" "B.Cu")
		(net "SSD10_PWRDIS_R")
	)
	(via
		(at 320.885312 -78.486762)
		(size 0.508)
		(drill 0.254)
		(layers "F.Cu" "B.Cu")
		(net "SSD10_PWRDIS_R")
	)
	(via
		(at 335.026 -206.15148)
		(size 0.508)
		(drill 0.254)
		(layers "F.Cu" "B.Cu")
		(net "SSD10_PWRDIS_R")
	)
	(segment
		(start 335.153 -207.37195)
		(end 335.153 -206.756254)
		(width 0.13208)
		(layer "B.Cu")
		(net "SSD10_PWRDIS_R")
	)
	(segment
		(start 335.026 -206.629254)
		(end 335.026 -206.15148)
		(width 0.13208)
		(layer "B.Cu")
		(net "SSD10_PWRDIS_R")
	)
	(segment
		(start 335.153 -206.756254)
		(end 335.026 -206.629254)
		(width 0.13208)
		(layer "B.Cu")
		(net "SSD10_PWRDIS_R")
	)
	(segment
		(start 307.584856 -32.814514)
		(end 320.429128 -45.658786)
		(width 0.15494)
		(layer "In5.Cu")
		(net "SSD10_PWRDIS_R")
	)
	(segment
		(start 308.33441 -28.963874)
		(end 307.584856 -29.713428)
		(width 0.15494)
		(layer "In5.Cu")
		(net "SSD10_PWRDIS_R")
	)
	(segment
		(start 300.612556 -25.034748)
		(end 298.746418 -25.034748)
		(width 0.15494)
		(layer "In5.Cu")
		(net "SSD10_PWRDIS_R")
	)
	(segment
		(start 301.855632 -26.255218)
		(end 301.313088 -25.527508)
		(width 0.15494)
		(layer "In5.Cu")
		(net "SSD10_PWRDIS_R")
	)
	(segment
		(start 320.429128 -71.644764)
		(end 319.597532 -72.47636)
		(width 0.15494)
		(layer "In5.Cu")
		(net "SSD10_PWRDIS_R")
	)
	(segment
		(start 320.429128 -45.658786)
		(end 320.429128 -71.644764)
		(width 0.15494)
		(layer "In5.Cu")
		(net "SSD10_PWRDIS_R")
	)
	(segment
		(start 298.746418 -25.034748)
		(end 298.391072 -25.390094)
		(width 0.15494)
		(layer "In5.Cu")
		(net "SSD10_PWRDIS_R")
	)
	(segment
		(start 301.313088 -25.527508)
		(end 300.612556 -25.034748)
		(width 0.15494)
		(layer "In5.Cu")
		(net "SSD10_PWRDIS_R")
	)
	(segment
		(start 308.33441 -28.469082)
		(end 305.583082 -28.469082)
		(width 0.15494)
		(layer "In5.Cu")
		(net "SSD10_PWRDIS_R")
	)
	(segment
		(start 308.33441 -28.469082)
		(end 308.33441 -28.963874)
		(width 0.15494)
		(layer "In5.Cu")
		(net "SSD10_PWRDIS_R")
	)
	(segment
		(start 302.933862 -27.333448)
		(end 301.855632 -26.255218)
		(width 0.15494)
		(layer "In5.Cu")
		(net "SSD10_PWRDIS_R")
	)
	(segment
		(start 304.447448 -27.333448)
		(end 302.933862 -27.333448)
		(width 0.15494)
		(layer "In5.Cu")
		(net "SSD10_PWRDIS_R")
	)
	(segment
		(start 319.597532 -72.47636)
		(end 319.597532 -77.53223)
		(width 0.15494)
		(layer "In5.Cu")
		(net "SSD10_PWRDIS_R")
	)
	(segment
		(start 305.583082 -28.469082)
		(end 304.447448 -27.333448)
		(width 0.15494)
		(layer "In5.Cu")
		(net "SSD10_PWRDIS_R")
	)
	(segment
		(start 320.552064 -78.486762)
		(end 320.885312 -78.486762)
		(width 0.15494)
		(layer "In5.Cu")
		(net "SSD10_PWRDIS_R")
	)
	(segment
		(start 307.584856 -29.713428)
		(end 307.584856 -32.814514)
		(width 0.15494)
		(layer "In5.Cu")
		(net "SSD10_PWRDIS_R")
	)
	(segment
		(start 319.597532 -77.53223)
		(end 320.552064 -78.486762)
		(width 0.15494)
		(layer "In5.Cu")
		(net "SSD10_PWRDIS_R")
	)
	(segment
		(start 338.673948 -187.944506)
		(end 335.026 -191.592454)
		(width 0.15494)
		(layer "In9.Cu")
		(net "SSD10_PWRDIS_R")
	)
	(segment
		(start 334.691482 -82.726022)
		(end 335.1276 -83.16214)
		(width 0.15494)
		(layer "In9.Cu")
		(net "SSD10_PWRDIS_R")
	)
	(segment
		(start 335.026 -191.592454)
		(end 335.026 -206.15148)
		(width 0.15494)
		(layer "In9.Cu")
		(net "SSD10_PWRDIS_R")
	)
	(segment
		(start 342.9762 -92.8624)
		(end 347.6498 -97.536)
		(width 0.15494)
		(layer "In9.Cu")
		(net "SSD10_PWRDIS_R")
	)
	(segment
		(start 346.20708 -122.775726)
		(end 346.20708 -138.450066)
		(width 0.15494)
		(layer "In9.Cu")
		(net "SSD10_PWRDIS_R")
	)
	(segment
		(start 335.1276 -89.762076)
		(end 338.227924 -92.8624)
		(width 0.15494)
		(layer "In9.Cu")
		(net "SSD10_PWRDIS_R")
	)
	(segment
		(start 345.1352 -139.521946)
		(end 345.1352 -182.5752)
		(width 0.15494)
		(layer "In9.Cu")
		(net "SSD10_PWRDIS_R")
	)
	(segment
		(start 346.20708 -138.450066)
		(end 345.1352 -139.521946)
		(width 0.15494)
		(layer "In9.Cu")
		(net "SSD10_PWRDIS_R")
	)
	(segment
		(start 339.765894 -187.944506)
		(end 338.673948 -187.944506)
		(width 0.15494)
		(layer "In9.Cu")
		(net "SSD10_PWRDIS_R")
	)
	(segment
		(start 347.6498 -97.536)
		(end 347.6498 -121.333006)
		(width 0.15494)
		(layer "In9.Cu")
		(net "SSD10_PWRDIS_R")
	)
	(segment
		(start 327.772776 -78.486762)
		(end 332.012036 -82.726022)
		(width 0.15494)
		(layer "In9.Cu")
		(net "SSD10_PWRDIS_R")
	)
	(segment
		(start 335.1276 -83.16214)
		(end 335.1276 -89.762076)
		(width 0.15494)
		(layer "In9.Cu")
		(net "SSD10_PWRDIS_R")
	)
	(segment
		(start 332.012036 -82.726022)
		(end 334.691482 -82.726022)
		(width 0.15494)
		(layer "In9.Cu")
		(net "SSD10_PWRDIS_R")
	)
	(segment
		(start 338.227924 -92.8624)
		(end 342.9762 -92.8624)
		(width 0.15494)
		(layer "In9.Cu")
		(net "SSD10_PWRDIS_R")
	)
	(segment
		(start 345.1352 -182.5752)
		(end 339.765894 -187.944506)
		(width 0.15494)
		(layer "In9.Cu")
		(net "SSD10_PWRDIS_R")
	)
	(segment
		(start 320.885312 -78.486762)
		(end 327.772776 -78.486762)
		(width 0.15494)
		(layer "In9.Cu")
		(net "SSD10_PWRDIS_R")
	)
	(segment
		(start 347.6498 -121.333006)
		(end 346.20708 -122.775726)
		(width 0.15494)
		(layer "In9.Cu")
		(net "SSD10_PWRDIS_R")
	)
	(segment
		(start 227.467668 -222.304102)
		(end 227.067872 -222.703898)
		(width 0.13208)
		(layer "F.Cu")
		(net "NIC7_MAIN_PWR_BIC_EN")
	)
	(via
		(at 230.272844 -228.813614)
		(size 0.6604)
		(drill 0.3302)
		(layers "F.Cu" "B.Cu")
		(net "NIC7_MAIN_PWR_BIC_EN")
	)
	(via
		(at 227.067872 -222.703898)
		(size 0.4572)
		(drill 0.254)
		(layers "F.Cu" "B.Cu")
		(net "NIC7_MAIN_PWR_BIC_EN")
	)
	(segment
		(start 230.272844 -229.057454)
		(end 230.272844 -228.813614)
		(width 0.13208)
		(layer "B.Cu")
		(net "NIC7_MAIN_PWR_BIC_EN")
	)
	(segment
		(start 227.467922 -227.711762)
		(end 227.467922 -224.0788)
		(width 0.13208)
		(layer "B.Cu")
		(net "NIC7_MAIN_PWR_BIC_EN")
	)
	(segment
		(start 230.450644 -230.825548)
		(end 230.388668 -230.763572)
		(width 0.13208)
		(layer "B.Cu")
		(net "NIC7_MAIN_PWR_BIC_EN")
	)
	(segment
		(start 227.467922 -223.103948)
		(end 227.067872 -222.703898)
		(width 0.0889)
		(layer "B.Cu")
		(net "NIC7_MAIN_PWR_BIC_EN")
	)
	(segment
		(start 230.388668 -229.173278)
		(end 230.272844 -229.057454)
		(width 0.13208)
		(layer "B.Cu")
		(net "NIC7_MAIN_PWR_BIC_EN")
	)
	(segment
		(start 227.467922 -224.0788)
		(end 227.467922 -223.103948)
		(width 0.0889)
		(layer "B.Cu")
		(net "NIC7_MAIN_PWR_BIC_EN")
	)
	(segment
		(start 228.569774 -228.813614)
		(end 227.467922 -227.711762)
		(width 0.13208)
		(layer "B.Cu")
		(net "NIC7_MAIN_PWR_BIC_EN")
	)
	(segment
		(start 230.272844 -228.813614)
		(end 228.569774 -228.813614)
		(width 0.13208)
		(layer "B.Cu")
		(net "NIC7_MAIN_PWR_BIC_EN")
	)
	(segment
		(start 230.388668 -230.763572)
		(end 230.388668 -229.173278)
		(width 0.13208)
		(layer "B.Cu")
		(net "NIC7_MAIN_PWR_BIC_EN")
	)
	(segment
		(start 228.267768 -215.104218)
		(end 227.867972 -214.704422)
		(width 0.13208)
		(layer "F.Cu")
		(net "JTAG_BIC_TCK")
	)
	(via
		(at 228.30409 -211.305648)
		(size 0.7112)
		(drill 0.3556)
		(layers "F.Cu" "B.Cu")
		(net "JTAG_BIC_TCK")
	)
	(via
		(at 227.867972 -214.704422)
		(size 0.4572)
		(drill 0.254)
		(layers "F.Cu" "B.Cu")
		(net "JTAG_BIC_TCK")
	)
	(segment
		(start 227.867972 -214.704422)
		(end 227.471732 -214.308182)
		(width 0.0889)
		(layer "B.Cu")
		(net "JTAG_BIC_TCK")
	)
	(segment
		(start 228.153722 -209.789268)
		(end 227.549964 -209.18551)
		(width 0.13208)
		(layer "B.Cu")
		(net "JTAG_BIC_TCK")
	)
	(segment
		(start 227.471732 -214.308182)
		(end 227.471732 -213.347808)
		(width 0.0889)
		(layer "B.Cu")
		(net "JTAG_BIC_TCK")
	)
	(segment
		(start 228.153722 -211.15528)
		(end 228.153722 -209.789268)
		(width 0.13208)
		(layer "B.Cu")
		(net "JTAG_BIC_TCK")
	)
	(segment
		(start 227.867972 -212.391498)
		(end 227.867972 -211.741766)
		(width 0.13208)
		(layer "B.Cu")
		(net "JTAG_BIC_TCK")
	)
	(segment
		(start 227.471732 -213.347808)
		(end 227.867972 -212.391498)
		(width 0.13208)
		(layer "B.Cu")
		(net "JTAG_BIC_TCK")
	)
	(segment
		(start 228.30409 -211.305648)
		(end 228.153722 -211.15528)
		(width 0.13208)
		(layer "B.Cu")
		(net "JTAG_BIC_TCK")
	)
	(segment
		(start 227.867972 -211.741766)
		(end 228.30409 -211.305648)
		(width 0.13208)
		(layer "B.Cu")
		(net "JTAG_BIC_TCK")
	)
	(via
		(at 147.831048 -286.331914)
		(size 0.508)
		(drill 0.254)
		(layers "F.Cu" "B.Cu")
		(net "PCEPLL6_VDDA18_PEX1_R")
	)
	(segment
		(start 320.750946 -299.27296)
		(end 320.623692 -299.400214)
		(width 0.13208)
		(layer "F.Cu")
		(net "I2C_PEX2_HOST_SDA")
	)
	(segment
		(start 320.623692 -299.76445)
		(end 320.623692 -300.03877)
		(width 0.13208)
		(layer "F.Cu")
		(net "I2C_PEX2_HOST_SDA")
	)
	(segment
		(start 320.826892 -300.24197)
		(end 321.21221 -300.24197)
		(width 0.13208)
		(layer "F.Cu")
		(net "I2C_PEX2_HOST_SDA")
	)
	(segment
		(start 321.205098 -299.27296)
		(end 320.750946 -299.27296)
		(width 0.13208)
		(layer "F.Cu")
		(net "I2C_PEX2_HOST_SDA")
	)
	(segment
		(start 320.623692 -299.400214)
		(end 320.623692 -299.76445)
		(width 0.13208)
		(layer "F.Cu")
		(net "I2C_PEX2_HOST_SDA")
	)
	(segment
		(start 320.623692 -300.03877)
		(end 320.826892 -300.24197)
		(width 0.13208)
		(layer "F.Cu")
		(net "I2C_PEX2_HOST_SDA")
	)
	(segment
		(start 322.22821 -300.24197)
		(end 321.21221 -300.24197)
		(width 0.13208)
		(layer "F.Cu")
		(net "I2C_PEX2_HOST_SDA")
	)
	(via
		(at 320.623692 -299.76445)
		(size 0.508)
		(drill 0.254)
		(layers "F.Cu" "B.Cu")
		(net "I2C_PEX2_HOST_SDA")
	)
	(segment
		(start 324.40372 -24.189944)
		(end 325.464678 -24.189944)
		(width 0.13208)
		(layer "F.Cu")
		(net "RST_SSD11_PERST_R_N")
	)
	(via
		(at 324.40372 -24.189944)
		(size 0.508)
		(drill 0.254)
		(layers "F.Cu" "B.Cu")
		(net "RST_SSD11_PERST_R_N")
	)
	(via
		(at 339.09 -206.15148)
		(size 0.508)
		(drill 0.254)
		(layers "F.Cu" "B.Cu")
		(net "RST_SSD11_PERST_R_N")
	)
	(via
		(at 341.377778 -70.879716)
		(size 0.508)
		(drill 0.254)
		(layers "F.Cu" "B.Cu")
		(net "RST_SSD11_PERST_R_N")
	)
	(segment
		(start 339.725 -207.37195)
		(end 339.725 -206.78648)
		(width 0.13208)
		(layer "B.Cu")
		(net "RST_SSD11_PERST_R_N")
	)
	(segment
		(start 339.725 -206.78648)
		(end 339.09 -206.15148)
		(width 0.13208)
		(layer "B.Cu")
		(net "RST_SSD11_PERST_R_N")
	)
	(segment
		(start 334.017366 -35.944302)
		(end 339.51672 -41.443656)
		(width 0.15494)
		(layer "In5.Cu")
		(net "RST_SSD11_PERST_R_N")
	)
	(segment
		(start 326.758046 -24.575008)
		(end 327.636124 -25.192228)
		(width 0.15494)
		(layer "In5.Cu")
		(net "RST_SSD11_PERST_R_N")
	)
	(segment
		(start 341.087964 -70.589902)
		(end 341.377778 -70.879716)
		(width 0.15494)
		(layer "In5.Cu")
		(net "RST_SSD11_PERST_R_N")
	)
	(segment
		(start 334.017366 -29.964888)
		(end 334.017366 -35.944302)
		(width 0.15494)
		(layer "In5.Cu")
		(net "RST_SSD11_PERST_R_N")
	)
	(segment
		(start 334.825848 -28.27147)
		(end 334.825848 -29.156406)
		(width 0.15494)
		(layer "In5.Cu")
		(net "RST_SSD11_PERST_R_N")
	)
	(segment
		(start 327.636124 -25.192228)
		(end 328.241914 -25.991312)
		(width 0.15494)
		(layer "In5.Cu")
		(net "RST_SSD11_PERST_R_N")
	)
	(segment
		(start 329.12431 -26.873708)
		(end 330.536804 -26.873708)
		(width 0.15494)
		(layer "In5.Cu")
		(net "RST_SSD11_PERST_R_N")
	)
	(segment
		(start 339.51672 -41.443656)
		(end 339.51672 -68.188586)
		(width 0.15494)
		(layer "In5.Cu")
		(net "RST_SSD11_PERST_R_N")
	)
	(segment
		(start 334.53959 -27.985212)
		(end 334.825848 -28.27147)
		(width 0.15494)
		(layer "In5.Cu")
		(net "RST_SSD11_PERST_R_N")
	)
	(segment
		(start 330.536804 -26.873708)
		(end 331.648308 -27.985212)
		(width 0.15494)
		(layer "In5.Cu")
		(net "RST_SSD11_PERST_R_N")
	)
	(segment
		(start 339.51672 -68.188586)
		(end 341.087964 -69.75983)
		(width 0.15494)
		(layer "In5.Cu")
		(net "RST_SSD11_PERST_R_N")
	)
	(segment
		(start 324.40372 -24.189944)
		(end 324.788784 -24.575008)
		(width 0.15494)
		(layer "In5.Cu")
		(net "RST_SSD11_PERST_R_N")
	)
	(segment
		(start 324.788784 -24.575008)
		(end 326.758046 -24.575008)
		(width 0.15494)
		(layer "In5.Cu")
		(net "RST_SSD11_PERST_R_N")
	)
	(segment
		(start 331.648308 -27.985212)
		(end 334.53959 -27.985212)
		(width 0.15494)
		(layer "In5.Cu")
		(net "RST_SSD11_PERST_R_N")
	)
	(segment
		(start 328.241914 -25.991312)
		(end 329.12431 -26.873708)
		(width 0.15494)
		(layer "In5.Cu")
		(net "RST_SSD11_PERST_R_N")
	)
	(segment
		(start 341.087964 -69.75983)
		(end 341.087964 -70.589902)
		(width 0.15494)
		(layer "In5.Cu")
		(net "RST_SSD11_PERST_R_N")
	)
	(segment
		(start 334.825848 -29.156406)
		(end 334.017366 -29.964888)
		(width 0.15494)
		(layer "In5.Cu")
		(net "RST_SSD11_PERST_R_N")
	)
	(segment
		(start 344.767916 -92.22867)
		(end 350.8756 -98.336354)
		(width 0.15494)
		(layer "In9.Cu")
		(net "RST_SSD11_PERST_R_N")
	)
	(segment
		(start 342.6714 -191.770254)
		(end 342.6714 -199.1106)
		(width 0.15494)
		(layer "In9.Cu")
		(net "RST_SSD11_PERST_R_N")
	)
	(segment
		(start 350.3422 -121.910094)
		(end 348.51594 -123.736354)
		(width 0.15494)
		(layer "In9.Cu")
		(net "RST_SSD11_PERST_R_N")
	)
	(segment
		(start 348.51594 -123.736354)
		(end 348.51594 -139.40663)
		(width 0.15494)
		(layer "In9.Cu")
		(net "RST_SSD11_PERST_R_N")
	)
	(segment
		(start 342.138 -202.3618)
		(end 340.868 -203.6318)
		(width 0.15494)
		(layer "In9.Cu")
		(net "RST_SSD11_PERST_R_N")
	)
	(segment
		(start 340.3854 -203.6318)
		(end 340.10473 -203.91247)
		(width 0.15494)
		(layer "In9.Cu")
		(net "RST_SSD11_PERST_R_N")
	)
	(segment
		(start 348.51594 -139.40663)
		(end 347.48724 -140.43533)
		(width 0.15494)
		(layer "In9.Cu")
		(net "RST_SSD11_PERST_R_N")
	)
	(segment
		(start 340.10473 -203.91247)
		(end 340.10473 -205.13675)
		(width 0.15494)
		(layer "In9.Cu")
		(net "RST_SSD11_PERST_R_N")
	)
	(segment
		(start 342.6714 -199.1106)
		(end 342.138 -199.644)
		(width 0.15494)
		(layer "In9.Cu")
		(net "RST_SSD11_PERST_R_N")
	)
	(segment
		(start 341.377778 -70.879716)
		(end 341.377778 -80.178656)
		(width 0.15494)
		(layer "In9.Cu")
		(net "RST_SSD11_PERST_R_N")
	)
	(segment
		(start 350.8756 -101.8032)
		(end 350.3422 -102.3366)
		(width 0.15494)
		(layer "In9.Cu")
		(net "RST_SSD11_PERST_R_N")
	)
	(segment
		(start 350.8756 -98.336354)
		(end 350.8756 -101.8032)
		(width 0.15494)
		(layer "In9.Cu")
		(net "RST_SSD11_PERST_R_N")
	)
	(segment
		(start 340.868 -203.6318)
		(end 340.3854 -203.6318)
		(width 0.15494)
		(layer "In9.Cu")
		(net "RST_SSD11_PERST_R_N")
	)
	(segment
		(start 347.48724 -140.43533)
		(end 347.48724 -186.954414)
		(width 0.15494)
		(layer "In9.Cu")
		(net "RST_SSD11_PERST_R_N")
	)
	(segment
		(start 344.767916 -84.392516)
		(end 344.767916 -92.22867)
		(width 0.15494)
		(layer "In9.Cu")
		(net "RST_SSD11_PERST_R_N")
	)
	(segment
		(start 343.520522 -83.145122)
		(end 344.767916 -84.392516)
		(width 0.15494)
		(layer "In9.Cu")
		(net "RST_SSD11_PERST_R_N")
	)
	(segment
		(start 340.10473 -205.13675)
		(end 339.09 -206.15148)
		(width 0.15494)
		(layer "In9.Cu")
		(net "RST_SSD11_PERST_R_N")
	)
	(segment
		(start 341.377778 -80.178656)
		(end 343.520522 -82.3214)
		(width 0.15494)
		(layer "In9.Cu")
		(net "RST_SSD11_PERST_R_N")
	)
	(segment
		(start 347.48724 -186.954414)
		(end 342.6714 -191.770254)
		(width 0.15494)
		(layer "In9.Cu")
		(net "RST_SSD11_PERST_R_N")
	)
	(segment
		(start 350.3422 -102.3366)
		(end 350.3422 -121.910094)
		(width 0.15494)
		(layer "In9.Cu")
		(net "RST_SSD11_PERST_R_N")
	)
	(segment
		(start 343.520522 -82.3214)
		(end 343.520522 -83.145122)
		(width 0.15494)
		(layer "In9.Cu")
		(net "RST_SSD11_PERST_R_N")
	)
	(segment
		(start 342.138 -199.644)
		(end 342.138 -202.3618)
		(width 0.15494)
		(layer "In9.Cu")
		(net "RST_SSD11_PERST_R_N")
	)
	(segment
		(start 236.757718 -206.061056)
		(end 236.757718 -204.77734)
		(width 0.13208)
		(layer "F.Cu")
		(net "BIC_HEARTBEAT_N")
	)
	(segment
		(start 236.706664 -206.11211)
		(end 236.309916 -206.11211)
		(width 0.13208)
		(layer "F.Cu")
		(net "BIC_HEARTBEAT_N")
	)
	(segment
		(start 236.182916 -206.23911)
		(end 236.182916 -207.979518)
		(width 0.13208)
		(layer "F.Cu")
		(net "BIC_HEARTBEAT_N")
	)
	(segment
		(start 234.667552 -212.296248)
		(end 235.534708 -211.429092)
		(width 0.13208)
		(layer "F.Cu")
		(net "BIC_HEARTBEAT_N")
	)
	(segment
		(start 236.706664 -206.11211)
		(end 236.757718 -206.061056)
		(width 0.13208)
		(layer "F.Cu")
		(net "BIC_HEARTBEAT_N")
	)
	(segment
		(start 234.667552 -212.704172)
		(end 234.667552 -212.296248)
		(width 0.13208)
		(layer "F.Cu")
		(net "BIC_HEARTBEAT_N")
	)
	(segment
		(start 236.309916 -206.11211)
		(end 236.182916 -206.23911)
		(width 0.13208)
		(layer "F.Cu")
		(net "BIC_HEARTBEAT_N")
	)
	(segment
		(start 235.626148 -210.006692)
		(end 235.626148 -208.536286)
		(width 0.13208)
		(layer "F.Cu")
		(net "BIC_HEARTBEAT_N")
	)
	(segment
		(start 236.182916 -207.979518)
		(end 235.626148 -208.536286)
		(width 0.13208)
		(layer "F.Cu")
		(net "BIC_HEARTBEAT_N")
	)
	(segment
		(start 235.534708 -210.098132)
		(end 235.626148 -210.006692)
		(width 0.13208)
		(layer "F.Cu")
		(net "BIC_HEARTBEAT_N")
	)
	(segment
		(start 235.534708 -211.429092)
		(end 235.534708 -210.098132)
		(width 0.13208)
		(layer "F.Cu")
		(net "BIC_HEARTBEAT_N")
	)
	(via
		(at 235.626148 -208.536286)
		(size 0.762)
		(drill 0.381)
		(layers "F.Cu" "B.Cu")
		(net "BIC_HEARTBEAT_N")
	)
	(segment
		(start 296.124884 -307.774594)
		(end 295.649904 -308.249828)
		(width 0.13208)
		(layer "F.Cu")
		(net "I2C0_PEX2_SHPC_SCL")
	)
	(segment
		(start 324.587108 -301.050452)
		(end 325.272908 -301.050452)
		(width 0.13208)
		(layer "F.Cu")
		(net "I2C0_PEX2_SHPC_SCL")
	)
	(via
		(at 296.124884 -307.774594)
		(size 0.4064)
		(drill 0.2032)
		(layers "F.Cu" "B.Cu")
		(net "I2C0_PEX2_SHPC_SCL")
	)
	(via
		(at 325.272908 -301.050452)
		(size 0.508)
		(drill 0.254)
		(layers "F.Cu" "B.Cu")
		(net "I2C0_PEX2_SHPC_SCL")
	)
	(segment
		(start 306.578 -303.013618)
		(end 306.578 -305.816)
		(width 0.15494)
		(layer "In5.Cu")
		(net "I2C0_PEX2_SHPC_SCL")
	)
	(segment
		(start 306.451 -305.943)
		(end 305.816254 -305.943)
		(width 0.15494)
		(layer "In5.Cu")
		(net "I2C0_PEX2_SHPC_SCL")
	)
	(segment
		(start 315.642244 -299.716698)
		(end 307.368448 -299.716698)
		(width 0.15494)
		(layer "In5.Cu")
		(net "I2C0_PEX2_SHPC_SCL")
	)
	(segment
		(start 307.368448 -299.716698)
		(end 307.052218 -300.032928)
		(width 0.15494)
		(layer "In5.Cu")
		(net "I2C0_PEX2_SHPC_SCL")
	)
	(segment
		(start 304.412904 -306.343558)
		(end 304.194718 -306.561744)
		(width 0.15494)
		(layer "In5.Cu")
		(net "I2C0_PEX2_SHPC_SCL")
	)
	(segment
		(start 316.1411 -299.217842)
		(end 315.642244 -299.716698)
		(width 0.15494)
		(layer "In5.Cu")
		(net "I2C0_PEX2_SHPC_SCL")
	)
	(segment
		(start 320.778378 -299.128688)
		(end 320.457576 -299.128688)
		(width 0.15494)
		(layer "In5.Cu")
		(net "I2C0_PEX2_SHPC_SCL")
	)
	(segment
		(start 323.599556 -299.991272)
		(end 321.640962 -299.991272)
		(width 0.15494)
		(layer "In5.Cu")
		(net "I2C0_PEX2_SHPC_SCL")
	)
	(segment
		(start 325.272908 -301.050452)
		(end 324.658736 -301.050452)
		(width 0.15494)
		(layer "In5.Cu")
		(net "I2C0_PEX2_SHPC_SCL")
	)
	(segment
		(start 296.563034 -307.299868)
		(end 296.124884 -307.738018)
		(width 0.15494)
		(layer "In5.Cu")
		(net "I2C0_PEX2_SHPC_SCL")
	)
	(segment
		(start 307.052218 -300.032928)
		(end 307.052218 -302.5394)
		(width 0.15494)
		(layer "In5.Cu")
		(net "I2C0_PEX2_SHPC_SCL")
	)
	(segment
		(start 304.194718 -307.008022)
		(end 303.902872 -307.299868)
		(width 0.15494)
		(layer "In5.Cu")
		(net "I2C0_PEX2_SHPC_SCL")
	)
	(segment
		(start 304.194718 -306.561744)
		(end 304.194718 -307.008022)
		(width 0.15494)
		(layer "In5.Cu")
		(net "I2C0_PEX2_SHPC_SCL")
	)
	(segment
		(start 306.578 -305.816)
		(end 306.451 -305.943)
		(width 0.15494)
		(layer "In5.Cu")
		(net "I2C0_PEX2_SHPC_SCL")
	)
	(segment
		(start 303.902872 -307.299868)
		(end 296.563034 -307.299868)
		(width 0.15494)
		(layer "In5.Cu")
		(net "I2C0_PEX2_SHPC_SCL")
	)
	(segment
		(start 324.658736 -301.050452)
		(end 323.599556 -299.991272)
		(width 0.15494)
		(layer "In5.Cu")
		(net "I2C0_PEX2_SHPC_SCL")
	)
	(segment
		(start 305.415696 -306.343558)
		(end 304.412904 -306.343558)
		(width 0.15494)
		(layer "In5.Cu")
		(net "I2C0_PEX2_SHPC_SCL")
	)
	(segment
		(start 320.368422 -299.217842)
		(end 316.1411 -299.217842)
		(width 0.15494)
		(layer "In5.Cu")
		(net "I2C0_PEX2_SHPC_SCL")
	)
	(segment
		(start 321.640962 -299.991272)
		(end 320.778378 -299.128688)
		(width 0.15494)
		(layer "In5.Cu")
		(net "I2C0_PEX2_SHPC_SCL")
	)
	(segment
		(start 296.124884 -307.738018)
		(end 296.124884 -307.774594)
		(width 0.15494)
		(layer "In5.Cu")
		(net "I2C0_PEX2_SHPC_SCL")
	)
	(segment
		(start 305.816254 -305.943)
		(end 305.415696 -306.343558)
		(width 0.15494)
		(layer "In5.Cu")
		(net "I2C0_PEX2_SHPC_SCL")
	)
	(segment
		(start 307.052218 -302.5394)
		(end 306.578 -303.013618)
		(width 0.15494)
		(layer "In5.Cu")
		(net "I2C0_PEX2_SHPC_SCL")
	)
	(segment
		(start 320.457576 -299.128688)
		(end 320.368422 -299.217842)
		(width 0.15494)
		(layer "In5.Cu")
		(net "I2C0_PEX2_SHPC_SCL")
	)
	(segment
		(start 235.867448 -224.303844)
		(end 235.467652 -223.904048)
		(width 0.13208)
		(layer "F.Cu")
		(net "PRSNT_NIC6_R_N")
	)
	(segment
		(start 384.0988 -117.639338)
		(end 382.330452 -117.639338)
		(width 0.13208)
		(layer "F.Cu")
		(net "PRSNT_NIC6_R_N")
	)
	(segment
		(start 381.051816 -114.936524)
		(end 381.49784 -114.4905)
		(width 0.13208)
		(layer "F.Cu")
		(net "PRSNT_NIC6_R_N")
	)
	(segment
		(start 380.61773 -114.936524)
		(end 380.61773 -113.958624)
		(width 0.13208)
		(layer "F.Cu")
		(net "PRSNT_NIC6_R_N")
	)
	(segment
		(start 350.893888 -219.187014)
		(end 351.293684 -218.787218)
		(width 0.13208)
		(layer "F.Cu")
		(net "PRSNT_NIC6_R_N")
	)
	(segment
		(start 385.225544 -116.512594)
		(end 384.0988 -117.639338)
		(width 0.13208)
		(layer "F.Cu")
		(net "PRSNT_NIC6_R_N")
	)
	(segment
		(start 382.10617 -117.415056)
		(end 382.10617 -114.4905)
		(width 0.13208)
		(layer "F.Cu")
		(net "PRSNT_NIC6_R_N")
	)
	(segment
		(start 381.49784 -114.4905)
		(end 382.10617 -114.4905)
		(width 0.13208)
		(layer "F.Cu")
		(net "PRSNT_NIC6_R_N")
	)
	(segment
		(start 382.330452 -117.639338)
		(end 382.10617 -117.415056)
		(width 0.13208)
		(layer "F.Cu")
		(net "PRSNT_NIC6_R_N")
	)
	(segment
		(start 380.61773 -114.936524)
		(end 381.051816 -114.936524)
		(width 0.13208)
		(layer "F.Cu")
		(net "PRSNT_NIC6_R_N")
	)
	(via
		(at 368.662712 -171.006008)
		(size 0.508)
		(drill 0.254)
		(layers "F.Cu" "B.Cu")
		(net "PRSNT_NIC6_R_N")
	)
	(via
		(at 385.225544 -116.512594)
		(size 0.508)
		(drill 0.254)
		(layers "F.Cu" "B.Cu")
		(net "PRSNT_NIC6_R_N")
	)
	(via
		(at 351.293684 -218.787218)
		(size 0.4572)
		(drill 0.254)
		(layers "F.Cu" "B.Cu")
		(net "PRSNT_NIC6_R_N")
	)
	(via
		(at 249.881644 -194.474338)
		(size 0.508)
		(drill 0.254)
		(layers "F.Cu" "B.Cu")
		(net "PRSNT_NIC6_R_N")
	)
	(via
		(at 235.867448 -224.303844)
		(size 0.4572)
		(drill 0.254)
		(layers "F.Cu" "B.Cu")
		(net "PRSNT_NIC6_R_N")
	)
	(via
		(at 396.634208 -169.02557)
		(size 0.508)
		(drill 0.254)
		(layers "F.Cu" "B.Cu")
		(net "PRSNT_NIC6_R_N")
	)
	(segment
		(start 356.709472 -217.432128)
		(end 355.112828 -217.432128)
		(width 0.15494)
		(layer "In5.Cu")
		(net "PRSNT_NIC6_R_N")
	)
	(segment
		(start 369.730782 -174.858934)
		(end 369.730782 -179.820062)
		(width 0.15494)
		(layer "In5.Cu")
		(net "PRSNT_NIC6_R_N")
	)
	(segment
		(start 355.112828 -217.432128)
		(end 353.757738 -218.787218)
		(width 0.15494)
		(layer "In5.Cu")
		(net "PRSNT_NIC6_R_N")
	)
	(segment
		(start 364.672372 -213.482428)
		(end 361.23118 -216.92362)
		(width 0.15494)
		(layer "In5.Cu")
		(net "PRSNT_NIC6_R_N")
	)
	(segment
		(start 353.757738 -218.787218)
		(end 351.293684 -218.787218)
		(width 0.15494)
		(layer "In5.Cu")
		(net "PRSNT_NIC6_R_N")
	)
	(segment
		(start 361.23118 -216.92362)
		(end 357.21798 -216.92362)
		(width 0.15494)
		(layer "In5.Cu")
		(net "PRSNT_NIC6_R_N")
	)
	(segment
		(start 368.662712 -173.790864)
		(end 369.730782 -174.858934)
		(width 0.15494)
		(layer "In5.Cu")
		(net "PRSNT_NIC6_R_N")
	)
	(segment
		(start 357.21798 -216.92362)
		(end 356.709472 -217.432128)
		(width 0.15494)
		(layer "In5.Cu")
		(net "PRSNT_NIC6_R_N")
	)
	(segment
		(start 368.662712 -171.006008)
		(end 368.662712 -173.790864)
		(width 0.15494)
		(layer "In5.Cu")
		(net "PRSNT_NIC6_R_N")
	)
	(segment
		(start 372.136162 -206.196184)
		(end 364.849918 -213.482428)
		(width 0.15494)
		(layer "In5.Cu")
		(net "PRSNT_NIC6_R_N")
	)
	(segment
		(start 370.456968 -180.546248)
		(end 370.456968 -190.534544)
		(width 0.15494)
		(layer "In5.Cu")
		(net "PRSNT_NIC6_R_N")
	)
	(segment
		(start 372.136162 -192.213738)
		(end 372.136162 -206.196184)
		(width 0.15494)
		(layer "In5.Cu")
		(net "PRSNT_NIC6_R_N")
	)
	(segment
		(start 370.456968 -190.534544)
		(end 372.136162 -192.213738)
		(width 0.15494)
		(layer "In5.Cu")
		(net "PRSNT_NIC6_R_N")
	)
	(segment
		(start 369.730782 -179.820062)
		(end 370.456968 -180.546248)
		(width 0.15494)
		(layer "In5.Cu")
		(net "PRSNT_NIC6_R_N")
	)
	(segment
		(start 364.849918 -213.482428)
		(end 364.672372 -213.482428)
		(width 0.15494)
		(layer "In5.Cu")
		(net "PRSNT_NIC6_R_N")
	)
	(segment
		(start 247.07723 -207.503776)
		(end 246.76862 -207.812386)
		(width 0.15494)
		(layer "In7.Cu")
		(net "PRSNT_NIC6_R_N")
	)
	(segment
		(start 238.633 -224.4852)
		(end 236.048804 -224.4852)
		(width 0.15494)
		(layer "In7.Cu")
		(net "PRSNT_NIC6_R_N")
	)
	(segment
		(start 241.940842 -218.27998)
		(end 240.7666 -219.454222)
		(width 0.15494)
		(layer "In7.Cu")
		(net "PRSNT_NIC6_R_N")
	)
	(segment
		(start 246.795036 -209.503264)
		(end 246.795036 -210.934808)
		(width 0.15494)
		(layer "In7.Cu")
		(net "PRSNT_NIC6_R_N")
	)
	(segment
		(start 247.314974 -199.300592)
		(end 247.314974 -200.83272)
		(width 0.15494)
		(layer "In7.Cu")
		(net "PRSNT_NIC6_R_N")
	)
	(segment
		(start 247.07723 -206.134208)
		(end 247.07723 -207.503776)
		(width 0.15494)
		(layer "In7.Cu")
		(net "PRSNT_NIC6_R_N")
	)
	(segment
		(start 240.7666 -222.3516)
		(end 238.633 -224.4852)
		(width 0.15494)
		(layer "In7.Cu")
		(net "PRSNT_NIC6_R_N")
	)
	(segment
		(start 246.76862 -207.812386)
		(end 246.76862 -208.81594)
		(width 0.15494)
		(layer "In7.Cu")
		(net "PRSNT_NIC6_R_N")
	)
	(segment
		(start 249.881644 -194.474338)
		(end 249.881644 -196.733922)
		(width 0.15494)
		(layer "In7.Cu")
		(net "PRSNT_NIC6_R_N")
	)
	(segment
		(start 244.048534 -217.73134)
		(end 243.75491 -218.024964)
		(width 0.15494)
		(layer "In7.Cu")
		(net "PRSNT_NIC6_R_N")
	)
	(segment
		(start 236.048804 -224.4852)
		(end 235.867448 -224.303844)
		(width 0.15494)
		(layer "In7.Cu")
		(net "PRSNT_NIC6_R_N")
	)
	(segment
		(start 246.76354 -209.471768)
		(end 246.795036 -209.503264)
		(width 0.15494)
		(layer "In7.Cu")
		(net "PRSNT_NIC6_R_N")
	)
	(segment
		(start 244.048534 -215.818212)
		(end 244.048534 -217.73134)
		(width 0.15494)
		(layer "In7.Cu")
		(net "PRSNT_NIC6_R_N")
	)
	(segment
		(start 246.795036 -210.934808)
		(end 245.3386 -212.391244)
		(width 0.15494)
		(layer "In7.Cu")
		(net "PRSNT_NIC6_R_N")
	)
	(segment
		(start 247.314974 -200.83272)
		(end 248.7422 -202.259946)
		(width 0.15494)
		(layer "In7.Cu")
		(net "PRSNT_NIC6_R_N")
	)
	(segment
		(start 243.75491 -218.024964)
		(end 242.53698 -218.024964)
		(width 0.15494)
		(layer "In7.Cu")
		(net "PRSNT_NIC6_R_N")
	)
	(segment
		(start 242.281964 -218.27998)
		(end 241.940842 -218.27998)
		(width 0.15494)
		(layer "In7.Cu")
		(net "PRSNT_NIC6_R_N")
	)
	(segment
		(start 248.7422 -202.259946)
		(end 248.7422 -204.469238)
		(width 0.15494)
		(layer "In7.Cu")
		(net "PRSNT_NIC6_R_N")
	)
	(segment
		(start 246.76354 -208.82102)
		(end 246.76354 -209.471768)
		(width 0.15494)
		(layer "In7.Cu")
		(net "PRSNT_NIC6_R_N")
	)
	(segment
		(start 240.7666 -219.454222)
		(end 240.7666 -222.3516)
		(width 0.15494)
		(layer "In7.Cu")
		(net "PRSNT_NIC6_R_N")
	)
	(segment
		(start 245.3386 -212.391244)
		(end 245.3386 -214.528146)
		(width 0.15494)
		(layer "In7.Cu")
		(net "PRSNT_NIC6_R_N")
	)
	(segment
		(start 248.7422 -204.469238)
		(end 247.07723 -206.134208)
		(width 0.15494)
		(layer "In7.Cu")
		(net "PRSNT_NIC6_R_N")
	)
	(segment
		(start 245.3386 -214.528146)
		(end 244.048534 -215.818212)
		(width 0.15494)
		(layer "In7.Cu")
		(net "PRSNT_NIC6_R_N")
	)
	(segment
		(start 242.53698 -218.024964)
		(end 242.281964 -218.27998)
		(width 0.15494)
		(layer "In7.Cu")
		(net "PRSNT_NIC6_R_N")
	)
	(segment
		(start 249.881644 -196.733922)
		(end 247.314974 -199.300592)
		(width 0.15494)
		(layer "In7.Cu")
		(net "PRSNT_NIC6_R_N")
	)
	(segment
		(start 246.76862 -208.81594)
		(end 246.76354 -208.82102)
		(width 0.15494)
		(layer "In7.Cu")
		(net "PRSNT_NIC6_R_N")
	)
	(segment
		(start 390.51738 -123.751594)
		(end 390.51738 -145.94967)
		(width 0.15494)
		(layer "In9.Cu")
		(net "PRSNT_NIC6_R_N")
	)
	(segment
		(start 390.51738 -145.94967)
		(end 393.037314 -158.619444)
		(width 0.15494)
		(layer "In9.Cu")
		(net "PRSNT_NIC6_R_N")
	)
	(segment
		(start 385.225544 -116.512594)
		(end 385.225544 -118.459758)
		(width 0.15494)
		(layer "In9.Cu")
		(net "PRSNT_NIC6_R_N")
	)
	(segment
		(start 393.037314 -160.341818)
		(end 396.634208 -169.02557)
		(width 0.15494)
		(layer "In9.Cu")
		(net "PRSNT_NIC6_R_N")
	)
	(segment
		(start 385.225544 -118.459758)
		(end 390.51738 -123.751594)
		(width 0.15494)
		(layer "In9.Cu")
		(net "PRSNT_NIC6_R_N")
	)
	(segment
		(start 393.037314 -158.619444)
		(end 393.037314 -160.341818)
		(width 0.15494)
		(layer "In9.Cu")
		(net "PRSNT_NIC6_R_N")
	)
	(segment
		(start 326.41794 -194.6148)
		(end 328.925682 -194.6148)
		(width 0.15494)
		(layer "In15.Cu")
		(net "PRSNT_NIC6_R_N")
	)
	(segment
		(start 354.21189 -204.96149)
		(end 354.21189 -208.828386)
		(width 0.15494)
		(layer "In15.Cu")
		(net "PRSNT_NIC6_R_N")
	)
	(segment
		(start 354.21189 -208.828386)
		(end 354.0887 -208.951576)
		(width 0.15494)
		(layer "In15.Cu")
		(net "PRSNT_NIC6_R_N")
	)
	(segment
		(start 351.691194 -218.166442)
		(end 351.691194 -218.389708)
		(width 0.15494)
		(layer "In15.Cu")
		(net "PRSNT_NIC6_R_N")
	)
	(segment
		(start 346.861892 -201.651108)
		(end 351.39757 -201.651108)
		(width 0.15494)
		(layer "In15.Cu")
		(net "PRSNT_NIC6_R_N")
	)
	(segment
		(start 370.64315 -169.02557)
		(end 368.662712 -171.006008)
		(width 0.15494)
		(layer "In15.Cu")
		(net "PRSNT_NIC6_R_N")
	)
	(segment
		(start 325.965566 -195.067174)
		(end 326.41794 -194.6148)
		(width 0.15494)
		(layer "In15.Cu")
		(net "PRSNT_NIC6_R_N")
	)
	(segment
		(start 324.465188 -195.071492)
		(end 324.802246 -194.734434)
		(width 0.15494)
		(layer "In15.Cu")
		(net "PRSNT_NIC6_R_N")
	)
	(segment
		(start 353.680268 -204.429868)
		(end 354.21189 -204.96149)
		(width 0.15494)
		(layer "In15.Cu")
		(net "PRSNT_NIC6_R_N")
	)
	(segment
		(start 251.961142 -193.483484)
		(end 255.590294 -189.854332)
		(width 0.15494)
		(layer "In15.Cu")
		(net "PRSNT_NIC6_R_N")
	)
	(segment
		(start 249.881644 -194.474338)
		(end 250.872498 -193.483484)
		(width 0.15494)
		(layer "In15.Cu")
		(net "PRSNT_NIC6_R_N")
	)
	(segment
		(start 353.680268 -203.933806)
		(end 353.680268 -204.429868)
		(width 0.15494)
		(layer "In15.Cu")
		(net "PRSNT_NIC6_R_N")
	)
	(segment
		(start 354.0887 -215.768936)
		(end 351.691194 -218.166442)
		(width 0.15494)
		(layer "In15.Cu")
		(net "PRSNT_NIC6_R_N")
	)
	(segment
		(start 341.370412 -198.94677)
		(end 344.157554 -198.94677)
		(width 0.15494)
		(layer "In15.Cu")
		(net "PRSNT_NIC6_R_N")
	)
	(segment
		(start 277.022814 -195.071492)
		(end 324.465188 -195.071492)
		(width 0.15494)
		(layer "In15.Cu")
		(net "PRSNT_NIC6_R_N")
	)
	(segment
		(start 271.805654 -189.854332)
		(end 277.022814 -195.071492)
		(width 0.15494)
		(layer "In15.Cu")
		(net "PRSNT_NIC6_R_N")
	)
	(segment
		(start 325.564246 -195.067174)
		(end 325.965566 -195.067174)
		(width 0.15494)
		(layer "In15.Cu")
		(net "PRSNT_NIC6_R_N")
	)
	(segment
		(start 344.157554 -198.94677)
		(end 346.861892 -201.651108)
		(width 0.15494)
		(layer "In15.Cu")
		(net "PRSNT_NIC6_R_N")
	)
	(segment
		(start 338.450428 -196.026786)
		(end 341.370412 -198.94677)
		(width 0.15494)
		(layer "In15.Cu")
		(net "PRSNT_NIC6_R_N")
	)
	(segment
		(start 325.231506 -194.734434)
		(end 325.564246 -195.067174)
		(width 0.15494)
		(layer "In15.Cu")
		(net "PRSNT_NIC6_R_N")
	)
	(segment
		(start 250.872498 -193.483484)
		(end 251.961142 -193.483484)
		(width 0.15494)
		(layer "In15.Cu")
		(net "PRSNT_NIC6_R_N")
	)
	(segment
		(start 328.925682 -194.6148)
		(end 330.337668 -196.026786)
		(width 0.15494)
		(layer "In15.Cu")
		(net "PRSNT_NIC6_R_N")
	)
	(segment
		(start 255.590294 -189.854332)
		(end 271.805654 -189.854332)
		(width 0.15494)
		(layer "In15.Cu")
		(net "PRSNT_NIC6_R_N")
	)
	(segment
		(start 396.634208 -169.02557)
		(end 370.64315 -169.02557)
		(width 0.15494)
		(layer "In15.Cu")
		(net "PRSNT_NIC6_R_N")
	)
	(segment
		(start 351.691194 -218.389708)
		(end 351.293684 -218.787218)
		(width 0.15494)
		(layer "In15.Cu")
		(net "PRSNT_NIC6_R_N")
	)
	(segment
		(start 330.337668 -196.026786)
		(end 338.450428 -196.026786)
		(width 0.15494)
		(layer "In15.Cu")
		(net "PRSNT_NIC6_R_N")
	)
	(segment
		(start 324.802246 -194.734434)
		(end 325.231506 -194.734434)
		(width 0.15494)
		(layer "In15.Cu")
		(net "PRSNT_NIC6_R_N")
	)
	(segment
		(start 351.39757 -201.651108)
		(end 353.680268 -203.933806)
		(width 0.15494)
		(layer "In15.Cu")
		(net "PRSNT_NIC6_R_N")
	)
	(segment
		(start 354.0887 -208.951576)
		(end 354.0887 -215.768936)
		(width 0.15494)
		(layer "In15.Cu")
		(net "PRSNT_NIC6_R_N")
	)
	(segment
		(start 197.44944 -84.476336)
		(end 196.129148 -84.476336)
		(width 0.13208)
		(layer "F.Cu")
		(net "RST_NIC3_PERST_R_N")
	)
	(segment
		(start 358.41305 -225.552)
		(end 359.029 -225.552)
		(width 0.13208)
		(layer "F.Cu")
		(net "RST_NIC3_PERST_R_N")
	)
	(via
		(at 209.26806 -178.66741)
		(size 0.508)
		(drill 0.254)
		(layers "F.Cu" "B.Cu")
		(net "RST_NIC3_PERST_R_N")
	)
	(via
		(at 359.029 -225.552)
		(size 0.508)
		(drill 0.254)
		(layers "F.Cu" "B.Cu")
		(net "RST_NIC3_PERST_R_N")
	)
	(via
		(at 196.129148 -84.476336)
		(size 0.508)
		(drill 0.254)
		(layers "F.Cu" "B.Cu")
		(net "RST_NIC3_PERST_R_N")
	)
	(segment
		(start 198.896986 -86.470236)
		(end 196.903086 -84.476336)
		(width 0.15494)
		(layer "In5.Cu")
		(net "RST_NIC3_PERST_R_N")
	)
	(segment
		(start 196.903086 -84.476336)
		(end 196.129148 -84.476336)
		(width 0.15494)
		(layer "In5.Cu")
		(net "RST_NIC3_PERST_R_N")
	)
	(segment
		(start 198.896986 -103.367586)
		(end 198.896986 -86.470236)
		(width 0.15494)
		(layer "In5.Cu")
		(net "RST_NIC3_PERST_R_N")
	)
	(segment
		(start 202.34148 -127.106934)
		(end 202.34148 -106.81208)
		(width 0.15494)
		(layer "In5.Cu")
		(net "RST_NIC3_PERST_R_N")
	)
	(segment
		(start 209.26806 -178.66741)
		(end 209.26806 -136.268714)
		(width 0.15494)
		(layer "In5.Cu")
		(net "RST_NIC3_PERST_R_N")
	)
	(segment
		(start 205.1558 -129.921254)
		(end 202.34148 -127.106934)
		(width 0.15494)
		(layer "In5.Cu")
		(net "RST_NIC3_PERST_R_N")
	)
	(segment
		(start 202.34148 -106.81208)
		(end 198.896986 -103.367586)
		(width 0.15494)
		(layer "In5.Cu")
		(net "RST_NIC3_PERST_R_N")
	)
	(segment
		(start 205.1558 -132.156454)
		(end 205.1558 -129.921254)
		(width 0.15494)
		(layer "In5.Cu")
		(net "RST_NIC3_PERST_R_N")
	)
	(segment
		(start 209.26806 -136.268714)
		(end 205.1558 -132.156454)
		(width 0.15494)
		(layer "In5.Cu")
		(net "RST_NIC3_PERST_R_N")
	)
	(segment
		(start 358.62387 -184.96534)
		(end 358.34066 -184.68213)
		(width 0.15494)
		(layer "In15.Cu")
		(net "RST_NIC3_PERST_R_N")
	)
	(segment
		(start 227.574348 -178.498754)
		(end 225.849942 -178.498754)
		(width 0.15494)
		(layer "In15.Cu")
		(net "RST_NIC3_PERST_R_N")
	)
	(segment
		(start 362.586778 -190.03264)
		(end 362.586778 -189.040008)
		(width 0.15494)
		(layer "In15.Cu")
		(net "RST_NIC3_PERST_R_N")
	)
	(segment
		(start 229.748842 -179.667916)
		(end 229.742238 -179.67452)
		(width 0.15494)
		(layer "In15.Cu")
		(net "RST_NIC3_PERST_R_N")
	)
	(segment
		(start 353.855528 -181.425088)
		(end 348.280482 -181.425088)
		(width 0.15494)
		(layer "In15.Cu")
		(net "RST_NIC3_PERST_R_N")
	)
	(segment
		(start 360.21264 -186.66587)
		(end 359.97134 -186.66587)
		(width 0.15494)
		(layer "In15.Cu")
		(net "RST_NIC3_PERST_R_N")
	)
	(segment
		(start 358.34066 -184.68213)
		(end 357.11257 -184.68213)
		(width 0.15494)
		(layer "In15.Cu")
		(net "RST_NIC3_PERST_R_N")
	)
	(segment
		(start 214.189056 -177.892456)
		(end 213.743032 -178.33848)
		(width 0.15494)
		(layer "In15.Cu")
		(net "RST_NIC3_PERST_R_N")
	)
	(segment
		(start 363.534198 -196.76745)
		(end 363.534198 -190.98006)
		(width 0.15494)
		(layer "In15.Cu")
		(net "RST_NIC3_PERST_R_N")
	)
	(segment
		(start 225.767646 -178.58105)
		(end 216.100406 -178.58105)
		(width 0.15494)
		(layer "In15.Cu")
		(net "RST_NIC3_PERST_R_N")
	)
	(segment
		(start 363.362494 -219.933012)
		(end 365.027718 -218.267788)
		(width 0.15494)
		(layer "In15.Cu")
		(net "RST_NIC3_PERST_R_N")
	)
	(segment
		(start 358.62387 -185.3184)
		(end 358.62387 -184.96534)
		(width 0.15494)
		(layer "In15.Cu")
		(net "RST_NIC3_PERST_R_N")
	)
	(segment
		(start 359.97134 -186.66587)
		(end 358.62387 -185.3184)
		(width 0.15494)
		(layer "In15.Cu")
		(net "RST_NIC3_PERST_R_N")
	)
	(segment
		(start 283.285692 -180.212238)
		(end 282.559252 -179.485798)
		(width 0.15494)
		(layer "In15.Cu")
		(net "RST_NIC3_PERST_R_N")
	)
	(segment
		(start 365.027718 -218.267788)
		(end 365.027718 -198.26097)
		(width 0.15494)
		(layer "In15.Cu")
		(net "RST_NIC3_PERST_R_N")
	)
	(segment
		(start 341.260938 -178.957224)
		(end 338.977478 -178.957224)
		(width 0.15494)
		(layer "In15.Cu")
		(net "RST_NIC3_PERST_R_N")
	)
	(segment
		(start 215.411812 -177.892456)
		(end 214.189056 -177.892456)
		(width 0.15494)
		(layer "In15.Cu")
		(net "RST_NIC3_PERST_R_N")
	)
	(segment
		(start 332.500224 -180.212238)
		(end 283.285692 -180.212238)
		(width 0.15494)
		(layer "In15.Cu")
		(net "RST_NIC3_PERST_R_N")
	)
	(segment
		(start 360.309922 -225.552)
		(end 361.85348 -224.008442)
		(width 0.15494)
		(layer "In15.Cu")
		(net "RST_NIC3_PERST_R_N")
	)
	(segment
		(start 282.559252 -179.485798)
		(end 246.47779 -179.485798)
		(width 0.15494)
		(layer "In15.Cu")
		(net "RST_NIC3_PERST_R_N")
	)
	(segment
		(start 359.029 -225.552)
		(end 360.309922 -225.552)
		(width 0.15494)
		(layer "In15.Cu")
		(net "RST_NIC3_PERST_R_N")
	)
	(segment
		(start 341.680292 -179.376578)
		(end 341.260938 -178.957224)
		(width 0.15494)
		(layer "In15.Cu")
		(net "RST_NIC3_PERST_R_N")
	)
	(segment
		(start 348.280482 -181.425088)
		(end 346.231972 -179.376578)
		(width 0.15494)
		(layer "In15.Cu")
		(net "RST_NIC3_PERST_R_N")
	)
	(segment
		(start 362.586778 -189.040008)
		(end 360.21264 -186.66587)
		(width 0.15494)
		(layer "In15.Cu")
		(net "RST_NIC3_PERST_R_N")
	)
	(segment
		(start 212.602064 -178.250596)
		(end 209.684874 -178.250596)
		(width 0.15494)
		(layer "In15.Cu")
		(net "RST_NIC3_PERST_R_N")
	)
	(segment
		(start 225.849942 -178.498754)
		(end 225.767646 -178.58105)
		(width 0.15494)
		(layer "In15.Cu")
		(net "RST_NIC3_PERST_R_N")
	)
	(segment
		(start 361.85348 -224.008442)
		(end 361.85348 -223.575626)
		(width 0.15494)
		(layer "In15.Cu")
		(net "RST_NIC3_PERST_R_N")
	)
	(segment
		(start 357.11257 -184.68213)
		(end 353.855528 -181.425088)
		(width 0.15494)
		(layer "In15.Cu")
		(net "RST_NIC3_PERST_R_N")
	)
	(segment
		(start 338.429092 -179.50561)
		(end 333.206852 -179.50561)
		(width 0.15494)
		(layer "In15.Cu")
		(net "RST_NIC3_PERST_R_N")
	)
	(segment
		(start 209.684874 -178.250596)
		(end 209.26806 -178.66741)
		(width 0.15494)
		(layer "In15.Cu")
		(net "RST_NIC3_PERST_R_N")
	)
	(segment
		(start 235.193078 -179.667916)
		(end 229.748842 -179.667916)
		(width 0.15494)
		(layer "In15.Cu")
		(net "RST_NIC3_PERST_R_N")
	)
	(segment
		(start 228.750114 -179.67452)
		(end 227.574348 -178.498754)
		(width 0.15494)
		(layer "In15.Cu")
		(net "RST_NIC3_PERST_R_N")
	)
	(segment
		(start 245.68658 -180.277008)
		(end 235.80217 -180.277008)
		(width 0.15494)
		(layer "In15.Cu")
		(net "RST_NIC3_PERST_R_N")
	)
	(segment
		(start 361.85348 -223.575626)
		(end 363.362494 -219.933012)
		(width 0.15494)
		(layer "In15.Cu")
		(net "RST_NIC3_PERST_R_N")
	)
	(segment
		(start 346.231972 -179.376578)
		(end 341.680292 -179.376578)
		(width 0.15494)
		(layer "In15.Cu")
		(net "RST_NIC3_PERST_R_N")
	)
	(segment
		(start 216.100406 -178.58105)
		(end 215.411812 -177.892456)
		(width 0.15494)
		(layer "In15.Cu")
		(net "RST_NIC3_PERST_R_N")
	)
	(segment
		(start 235.80217 -180.277008)
		(end 235.193078 -179.667916)
		(width 0.15494)
		(layer "In15.Cu")
		(net "RST_NIC3_PERST_R_N")
	)
	(segment
		(start 212.689948 -178.33848)
		(end 212.602064 -178.250596)
		(width 0.15494)
		(layer "In15.Cu")
		(net "RST_NIC3_PERST_R_N")
	)
	(segment
		(start 229.742238 -179.67452)
		(end 228.750114 -179.67452)
		(width 0.15494)
		(layer "In15.Cu")
		(net "RST_NIC3_PERST_R_N")
	)
	(segment
		(start 363.534198 -190.98006)
		(end 362.586778 -190.03264)
		(width 0.15494)
		(layer "In15.Cu")
		(net "RST_NIC3_PERST_R_N")
	)
	(segment
		(start 213.743032 -178.33848)
		(end 212.689948 -178.33848)
		(width 0.15494)
		(layer "In15.Cu")
		(net "RST_NIC3_PERST_R_N")
	)
	(segment
		(start 246.47779 -179.485798)
		(end 245.68658 -180.277008)
		(width 0.15494)
		(layer "In15.Cu")
		(net "RST_NIC3_PERST_R_N")
	)
	(segment
		(start 338.977478 -178.957224)
		(end 338.429092 -179.50561)
		(width 0.15494)
		(layer "In15.Cu")
		(net "RST_NIC3_PERST_R_N")
	)
	(segment
		(start 333.206852 -179.50561)
		(end 332.500224 -180.212238)
		(width 0.15494)
		(layer "In15.Cu")
		(net "RST_NIC3_PERST_R_N")
	)
	(segment
		(start 365.027718 -198.26097)
		(end 363.534198 -196.76745)
		(width 0.15494)
		(layer "In15.Cu")
		(net "RST_NIC3_PERST_R_N")
	)
	(segment
		(start 337.566 -200.76795)
		(end 337.566 -200.152)
		(width 0.13208)
		(layer "F.Cu")
		(net "SSD11_PWRDIS_R")
	)
	(segment
		(start 334.334358 -28.550108)
		(end 334.864202 -29.079952)
		(width 0.13208)
		(layer "F.Cu")
		(net "SSD11_PWRDIS_R")
	)
	(segment
		(start 334.334358 -28.469082)
		(end 334.334358 -28.550108)
		(width 0.13208)
		(layer "F.Cu")
		(net "SSD11_PWRDIS_R")
	)
	(segment
		(start 325.464678 -25.390094)
		(end 324.39102 -25.390094)
		(width 0.13208)
		(layer "F.Cu")
		(net "SSD11_PWRDIS_R")
	)
	(via
		(at 324.39102 -25.390094)
		(size 0.508)
		(drill 0.254)
		(layers "F.Cu" "B.Cu")
		(net "SSD11_PWRDIS_R")
	)
	(via
		(at 334.334358 -28.469082)
		(size 0.508)
		(drill 0.254)
		(layers "F.Cu" "B.Cu")
		(net "SSD11_PWRDIS_R")
	)
	(via
		(at 322.979034 -71.42099)
		(size 0.508)
		(drill 0.254)
		(layers "F.Cu" "B.Cu")
		(net "SSD11_PWRDIS_R")
	)
	(via
		(at 337.566 -200.152)
		(size 0.508)
		(drill 0.254)
		(layers "F.Cu" "B.Cu")
		(net "SSD11_PWRDIS_R")
	)
	(via
		(at 340.386416 -70.895718)
		(size 0.508)
		(drill 0.254)
		(layers "F.Cu" "B.Cu")
		(net "SSD11_PWRDIS_R")
	)
	(segment
		(start 318.898016 -82.92973)
		(end 321.39509 -82.92973)
		(width 0.15494)
		(layer "In5.Cu")
		(net "SSD11_PWRDIS_R")
	)
	(segment
		(start 330.885292 -27.87269)
		(end 331.481684 -28.469082)
		(width 0.15494)
		(layer "In5.Cu")
		(net "SSD11_PWRDIS_R")
	)
	(segment
		(start 337.54187 -179.334668)
		(end 342.269826 -174.606712)
		(width 0.15494)
		(layer "In5.Cu")
		(net "SSD11_PWRDIS_R")
	)
	(segment
		(start 328.93381 -27.333448)
		(end 330.346304 -27.333448)
		(width 0.15494)
		(layer "In5.Cu")
		(net "SSD11_PWRDIS_R")
	)
	(segment
		(start 324.39102 -25.390094)
		(end 324.746366 -25.034748)
		(width 0.15494)
		(layer "In5.Cu")
		(net "SSD11_PWRDIS_R")
	)
	(segment
		(start 342.269826 -173.589188)
		(end 342.900762 -172.958252)
		(width 0.15494)
		(layer "In5.Cu")
		(net "SSD11_PWRDIS_R")
	)
	(segment
		(start 337.566 -200.152)
		(end 337.566 -198.941182)
		(width 0.15494)
		(layer "In5.Cu")
		(net "SSD11_PWRDIS_R")
	)
	(segment
		(start 327.313036 -25.527508)
		(end 327.85558 -26.255218)
		(width 0.15494)
		(layer "In5.Cu")
		(net "SSD11_PWRDIS_R")
	)
	(segment
		(start 322.979034 -81.345786)
		(end 322.979034 -71.42099)
		(width 0.15494)
		(layer "In5.Cu")
		(net "SSD11_PWRDIS_R")
	)
	(segment
		(start 321.39509 -82.92973)
		(end 322.979034 -81.345786)
		(width 0.15494)
		(layer "In5.Cu")
		(net "SSD11_PWRDIS_R")
	)
	(segment
		(start 334.334358 -28.997656)
		(end 333.557626 -29.774388)
		(width 0.15494)
		(layer "In5.Cu")
		(net "SSD11_PWRDIS_R")
	)
	(segment
		(start 342.269826 -174.606712)
		(end 342.269826 -173.589188)
		(width 0.15494)
		(layer "In5.Cu")
		(net "SSD11_PWRDIS_R")
	)
	(segment
		(start 336.83956 -188.66866)
		(end 337.54187 -187.96635)
		(width 0.15494)
		(layer "In5.Cu")
		(net "SSD11_PWRDIS_R")
	)
	(segment
		(start 334.334358 -28.469082)
		(end 334.334358 -28.997656)
		(width 0.15494)
		(layer "In5.Cu")
		(net "SSD11_PWRDIS_R")
	)
	(segment
		(start 333.557626 -36.134802)
		(end 339.05698 -41.634156)
		(width 0.15494)
		(layer "In5.Cu")
		(net "SSD11_PWRDIS_R")
	)
	(segment
		(start 340.580726 -70.701408)
		(end 340.386416 -70.895718)
		(width 0.15494)
		(layer "In5.Cu")
		(net "SSD11_PWRDIS_R")
	)
	(segment
		(start 337.54187 -187.96635)
		(end 337.54187 -179.334668)
		(width 0.15494)
		(layer "In5.Cu")
		(net "SSD11_PWRDIS_R")
	)
	(segment
		(start 340.580726 -69.902832)
		(end 340.580726 -70.701408)
		(width 0.15494)
		(layer "In5.Cu")
		(net "SSD11_PWRDIS_R")
	)
	(segment
		(start 339.05698 -68.379086)
		(end 340.580726 -69.902832)
		(width 0.15494)
		(layer "In5.Cu")
		(net "SSD11_PWRDIS_R")
	)
	(segment
		(start 331.481684 -28.469082)
		(end 334.334358 -28.469082)
		(width 0.15494)
		(layer "In5.Cu")
		(net "SSD11_PWRDIS_R")
	)
	(segment
		(start 339.05698 -41.634156)
		(end 339.05698 -68.379086)
		(width 0.15494)
		(layer "In5.Cu")
		(net "SSD11_PWRDIS_R")
	)
	(segment
		(start 337.39709 -198.772272)
		(end 337.39709 -197.028562)
		(width 0.15494)
		(layer "In5.Cu")
		(net "SSD11_PWRDIS_R")
	)
	(segment
		(start 330.346304 -27.333448)
		(end 330.885292 -27.872436)
		(width 0.15494)
		(layer "In5.Cu")
		(net "SSD11_PWRDIS_R")
	)
	(segment
		(start 336.83956 -196.471032)
		(end 336.83956 -188.66866)
		(width 0.15494)
		(layer "In5.Cu")
		(net "SSD11_PWRDIS_R")
	)
	(segment
		(start 342.900762 -143.260318)
		(end 336.826352 -137.185908)
		(width 0.15494)
		(layer "In5.Cu")
		(net "SSD11_PWRDIS_R")
	)
	(segment
		(start 330.885292 -27.872436)
		(end 330.885292 -27.87269)
		(width 0.15494)
		(layer "In5.Cu")
		(net "SSD11_PWRDIS_R")
	)
	(segment
		(start 327.85558 -26.255218)
		(end 328.93381 -27.333448)
		(width 0.15494)
		(layer "In5.Cu")
		(net "SSD11_PWRDIS_R")
	)
	(segment
		(start 326.612504 -25.034748)
		(end 327.313036 -25.527508)
		(width 0.15494)
		(layer "In5.Cu")
		(net "SSD11_PWRDIS_R")
	)
	(segment
		(start 324.746366 -25.034748)
		(end 326.612504 -25.034748)
		(width 0.15494)
		(layer "In5.Cu")
		(net "SSD11_PWRDIS_R")
	)
	(segment
		(start 333.557626 -29.774388)
		(end 333.557626 -36.134802)
		(width 0.15494)
		(layer "In5.Cu")
		(net "SSD11_PWRDIS_R")
	)
	(segment
		(start 337.39709 -197.028562)
		(end 336.83956 -196.471032)
		(width 0.15494)
		(layer "In5.Cu")
		(net "SSD11_PWRDIS_R")
	)
	(segment
		(start 316.813692 -114.575336)
		(end 316.813692 -85.014054)
		(width 0.15494)
		(layer "In5.Cu")
		(net "SSD11_PWRDIS_R")
	)
	(segment
		(start 321.030346 -125.18517)
		(end 321.030346 -118.79199)
		(width 0.15494)
		(layer "In5.Cu")
		(net "SSD11_PWRDIS_R")
	)
	(segment
		(start 336.826352 -137.185908)
		(end 329.246484 -137.185908)
		(width 0.15494)
		(layer "In5.Cu")
		(net "SSD11_PWRDIS_R")
	)
	(segment
		(start 316.813692 -85.014054)
		(end 318.898016 -82.92973)
		(width 0.15494)
		(layer "In5.Cu")
		(net "SSD11_PWRDIS_R")
	)
	(segment
		(start 321.030346 -118.79199)
		(end 316.813692 -114.575336)
		(width 0.15494)
		(layer "In5.Cu")
		(net "SSD11_PWRDIS_R")
	)
	(segment
		(start 329.246484 -137.185908)
		(end 324.496938 -132.436362)
		(width 0.15494)
		(layer "In5.Cu")
		(net "SSD11_PWRDIS_R")
	)
	(segment
		(start 324.496938 -132.436362)
		(end 324.496938 -128.651762)
		(width 0.15494)
		(layer "In5.Cu")
		(net "SSD11_PWRDIS_R")
	)
	(segment
		(start 324.496938 -128.651762)
		(end 321.030346 -125.18517)
		(width 0.15494)
		(layer "In5.Cu")
		(net "SSD11_PWRDIS_R")
	)
	(segment
		(start 342.900762 -172.958252)
		(end 342.900762 -143.260318)
		(width 0.15494)
		(layer "In5.Cu")
		(net "SSD11_PWRDIS_R")
	)
	(segment
		(start 337.566 -198.941182)
		(end 337.39709 -198.772272)
		(width 0.15494)
		(layer "In5.Cu")
		(net "SSD11_PWRDIS_R")
	)
	(segment
		(start 334.8736 -75.438)
		(end 339.415882 -70.895718)
		(width 0.15494)
		(layer "In15.Cu")
		(net "SSD11_PWRDIS_R")
	)
	(segment
		(start 339.415882 -70.895718)
		(end 340.386416 -70.895718)
		(width 0.15494)
		(layer "In15.Cu")
		(net "SSD11_PWRDIS_R")
	)
	(segment
		(start 322.979034 -74.440034)
		(end 323.977 -75.438)
		(width 0.15494)
		(layer "In15.Cu")
		(net "SSD11_PWRDIS_R")
	)
	(segment
		(start 323.977 -75.438)
		(end 334.8736 -75.438)
		(width 0.15494)
		(layer "In15.Cu")
		(net "SSD11_PWRDIS_R")
	)
	(segment
		(start 322.979034 -71.42099)
		(end 322.979034 -74.440034)
		(width 0.15494)
		(layer "In15.Cu")
		(net "SSD11_PWRDIS_R")
	)
	(segment
		(start 163.399978 -294.94988)
		(end 162.924998 -294.4749)
		(width 0.249936)
		(layer "F.Cu")
		(net "PCEPLL4_VDDA18_PEX1")
	)
	(via
		(at 162.924998 -294.4749)
		(size 0.4064)
		(drill 0.2032)
		(layers "F.Cu" "B.Cu")
		(net "PCEPLL4_VDDA18_PEX1")
	)
	(via
		(at 149.216618 -290.294314)
		(size 0.508)
		(drill 0.254)
		(layers "F.Cu" "B.Cu")
		(net "PCEPLL4_VDDA18_PEX1")
	)
	(via
		(at 147.819618 -290.294314)
		(size 0.508)
		(drill 0.254)
		(layers "F.Cu" "B.Cu")
		(net "PCEPLL4_VDDA18_PEX1")
	)
	(segment
		(start 162.7124 -295.275)
		(end 162.7124 -294.4749)
		(width 0.3048)
		(layer "B.Cu")
		(net "PCEPLL4_VDDA18_PEX1")
	)
	(segment
		(start 162.7124 -294.4749)
		(end 162.924998 -294.4749)
		(width 0.3048)
		(layer "B.Cu")
		(net "PCEPLL4_VDDA18_PEX1")
	)
	(segment
		(start 295.17467 -307.774594)
		(end 294.69969 -308.249828)
		(width 0.13208)
		(layer "F.Cu")
		(net "I2C0_PEX2_SHPC_SDA")
	)
	(segment
		(start 320.70167 -301.55261)
		(end 321.21221 -301.04207)
		(width 0.13208)
		(layer "F.Cu")
		(net "I2C0_PEX2_SHPC_SDA")
	)
	(via
		(at 320.70167 -301.55261)
		(size 0.508)
		(drill 0.254)
		(layers "F.Cu" "B.Cu")
		(net "I2C0_PEX2_SHPC_SDA")
	)
	(via
		(at 295.17467 -307.774594)
		(size 0.4064)
		(drill 0.2032)
		(layers "F.Cu" "B.Cu")
		(net "I2C0_PEX2_SHPC_SDA")
	)
	(segment
		(start 317.212726 -300.73727)
		(end 315.382148 -302.567848)
		(width 0.15494)
		(layer "In5.Cu")
		(net "I2C0_PEX2_SHPC_SDA")
	)
	(segment
		(start 311.3532 -308.420008)
		(end 311.036208 -308.737)
		(width 0.15494)
		(layer "In5.Cu")
		(net "I2C0_PEX2_SHPC_SDA")
	)
	(segment
		(start 295.649904 -308.249828)
		(end 295.17467 -307.774594)
		(width 0.15494)
		(layer "In5.Cu")
		(net "I2C0_PEX2_SHPC_SDA")
	)
	(segment
		(start 311.7596 -302.768)
		(end 311.7596 -303.53)
		(width 0.15494)
		(layer "In5.Cu")
		(net "I2C0_PEX2_SHPC_SDA")
	)
	(segment
		(start 311.7596 -303.53)
		(end 311.3532 -303.9364)
		(width 0.15494)
		(layer "In5.Cu")
		(net "I2C0_PEX2_SHPC_SDA")
	)
	(segment
		(start 311.036208 -308.737)
		(end 305.689 -308.737)
		(width 0.15494)
		(layer "In5.Cu")
		(net "I2C0_PEX2_SHPC_SDA")
	)
	(segment
		(start 311.3532 -303.9364)
		(end 311.3532 -308.420008)
		(width 0.15494)
		(layer "In5.Cu")
		(net "I2C0_PEX2_SHPC_SDA")
	)
	(segment
		(start 305.689 -308.737)
		(end 305.226212 -309.199788)
		(width 0.15494)
		(layer "In5.Cu")
		(net "I2C0_PEX2_SHPC_SDA")
	)
	(segment
		(start 302.267112 -308.997096)
		(end 302.267112 -308.461918)
		(width 0.15494)
		(layer "In5.Cu")
		(net "I2C0_PEX2_SHPC_SDA")
	)
	(segment
		(start 319.355724 -300.73727)
		(end 317.212726 -300.73727)
		(width 0.15494)
		(layer "In5.Cu")
		(net "I2C0_PEX2_SHPC_SDA")
	)
	(segment
		(start 305.226212 -309.199788)
		(end 302.469804 -309.199788)
		(width 0.15494)
		(layer "In5.Cu")
		(net "I2C0_PEX2_SHPC_SDA")
	)
	(segment
		(start 302.469804 -309.199788)
		(end 302.267112 -308.997096)
		(width 0.15494)
		(layer "In5.Cu")
		(net "I2C0_PEX2_SHPC_SDA")
	)
	(segment
		(start 315.382148 -302.567848)
		(end 311.959752 -302.567848)
		(width 0.15494)
		(layer "In5.Cu")
		(net "I2C0_PEX2_SHPC_SDA")
	)
	(segment
		(start 320.70167 -301.55261)
		(end 320.171064 -301.55261)
		(width 0.15494)
		(layer "In5.Cu")
		(net "I2C0_PEX2_SHPC_SDA")
	)
	(segment
		(start 302.267112 -308.461918)
		(end 302.055022 -308.249828)
		(width 0.15494)
		(layer "In5.Cu")
		(net "I2C0_PEX2_SHPC_SDA")
	)
	(segment
		(start 311.959752 -302.567848)
		(end 311.7596 -302.768)
		(width 0.15494)
		(layer "In5.Cu")
		(net "I2C0_PEX2_SHPC_SDA")
	)
	(segment
		(start 302.055022 -308.249828)
		(end 295.649904 -308.249828)
		(width 0.15494)
		(layer "In5.Cu")
		(net "I2C0_PEX2_SHPC_SDA")
	)
	(segment
		(start 320.171064 -301.55261)
		(end 319.355724 -300.73727)
		(width 0.15494)
		(layer "In5.Cu")
		(net "I2C0_PEX2_SHPC_SDA")
	)
	(segment
		(start 352.025966 -263.82091)
		(end 350.983804 -262.778748)
		(width 0.2032)
		(layer "F.Cu")
		(net "P0V8_PEX3_ISEN1")
	)
	(segment
		(start 350.983804 -262.778748)
		(end 350.983804 -261.205218)
		(width 0.2032)
		(layer "F.Cu")
		(net "P0V8_PEX3_ISEN1")
	)
	(segment
		(start 350.983804 -261.205218)
		(end 351.175828 -261.013194)
		(width 0.2032)
		(layer "F.Cu")
		(net "P0V8_PEX3_ISEN1")
	)
	(segment
		(start 351.175828 -261.013194)
		(end 351.175828 -260.795008)
		(width 0.2032)
		(layer "F.Cu")
		(net "P0V8_PEX3_ISEN1")
	)
	(segment
		(start 356.37089 -281.999182)
		(end 356.37089 -281.65425)
		(width 0.2286)
		(layer "F.Cu")
		(net "P0V8_PEX3_ISEN1")
	)
	(segment
		(start 356.37089 -281.65425)
		(end 356.808024 -281.217116)
		(width 0.2286)
		(layer "F.Cu")
		(net "P0V8_PEX3_ISEN1")
	)
	(segment
		(start 356.808024 -281.217116)
		(end 356.808024 -281.151838)
		(width 0.2286)
		(layer "F.Cu")
		(net "P0V8_PEX3_ISEN1")
	)
	(via
		(at 352.025966 -263.82091)
		(size 0.508)
		(drill 0.254)
		(layers "F.Cu" "B.Cu")
		(net "P0V8_PEX3_ISEN1")
	)
	(via
		(at 356.808024 -281.151838)
		(size 0.508)
		(drill 0.254)
		(layers "F.Cu" "B.Cu")
		(net "P0V8_PEX3_ISEN1")
	)
	(segment
		(start 355.63683 -276.492208)
		(end 355.63683 -266.764516)
		(width 0.254)
		(layer "In11.Cu")
		(net "P0V8_PEX3_ISEN1")
	)
	(segment
		(start 355.63683 -266.764516)
		(end 354.140516 -265.268202)
		(width 0.254)
		(layer "In11.Cu")
		(net "P0V8_PEX3_ISEN1")
	)
	(segment
		(start 357.859838 -280.663904)
		(end 358.384856 -280.138886)
		(width 0.254)
		(layer "In11.Cu")
		(net "P0V8_PEX3_ISEN1")
	)
	(segment
		(start 358.384856 -280.138886)
		(end 358.384856 -279.240234)
		(width 0.254)
		(layer "In11.Cu")
		(net "P0V8_PEX3_ISEN1")
	)
	(segment
		(start 354.140516 -265.268202)
		(end 354.140516 -264.471912)
		(width 0.254)
		(layer "In11.Cu")
		(net "P0V8_PEX3_ISEN1")
	)
	(segment
		(start 354.140516 -264.471912)
		(end 353.489514 -263.82091)
		(width 0.254)
		(layer "In11.Cu")
		(net "P0V8_PEX3_ISEN1")
	)
	(segment
		(start 353.489514 -263.82091)
		(end 352.025966 -263.82091)
		(width 0.254)
		(layer "In11.Cu")
		(net "P0V8_PEX3_ISEN1")
	)
	(segment
		(start 358.384856 -279.240234)
		(end 355.63683 -276.492208)
		(width 0.254)
		(layer "In11.Cu")
		(net "P0V8_PEX3_ISEN1")
	)
	(segment
		(start 356.808024 -281.151838)
		(end 357.295958 -280.663904)
		(width 0.254)
		(layer "In11.Cu")
		(net "P0V8_PEX3_ISEN1")
	)
	(segment
		(start 357.295958 -280.663904)
		(end 357.859838 -280.663904)
		(width 0.254)
		(layer "In11.Cu")
		(net "P0V8_PEX3_ISEN1")
	)
	(segment
		(start 163.874958 -296.37482)
		(end 164.349938 -295.89984)
		(width 0.249936)
		(layer "F.Cu")
		(net "PCEPLL3_VDDA18_PEX1")
	)
	(via
		(at 163.874958 -296.37482)
		(size 0.4064)
		(drill 0.2032)
		(layers "F.Cu" "B.Cu")
		(net "PCEPLL3_VDDA18_PEX1")
	)
	(via
		(at 150.777702 -260.338316)
		(size 0.508)
		(drill 0.254)
		(layers "F.Cu" "B.Cu")
		(net "PCEPLL3_VDDA18_PEX1")
	)
	(via
		(at 152.174702 -260.338316)
		(size 0.508)
		(drill 0.254)
		(layers "F.Cu" "B.Cu")
		(net "PCEPLL3_VDDA18_PEX1")
	)
	(segment
		(start 163.874958 -295.7195)
		(end 163.874958 -296.37482)
		(width 0.3048)
		(layer "B.Cu")
		(net "PCEPLL3_VDDA18_PEX1")
	)
	(segment
		(start 318.845184 -303.798224)
		(end 319.02781 -303.615598)
		(width 0.13208)
		(layer "F.Cu")
		(net "SMB_PEX2_SLAVE_SCL")
	)
	(segment
		(start 319.02781 -303.615598)
		(end 319.02781 -302.863504)
		(width 0.13208)
		(layer "F.Cu")
		(net "SMB_PEX2_SLAVE_SCL")
	)
	(segment
		(start 304.674778 -306.824888)
		(end 304.199798 -307.299868)
		(width 0.13208)
		(layer "F.Cu")
		(net "SMB_PEX2_SLAVE_SCL")
	)
	(via
		(at 318.845184 -303.798224)
		(size 0.508)
		(drill 0.254)
		(layers "F.Cu" "B.Cu")
		(net "SMB_PEX2_SLAVE_SCL")
	)
	(via
		(at 316.498224 -306.097178)
		(size 0.6604)
		(drill 0.3302)
		(layers "F.Cu" "B.Cu")
		(net "SMB_PEX2_SLAVE_SCL")
	)
	(via
		(at 304.674778 -306.824888)
		(size 0.4064)
		(drill 0.2032)
		(layers "F.Cu" "B.Cu")
		(net "SMB_PEX2_SLAVE_SCL")
	)
	(segment
		(start 317.167006 -304.616104)
		(end 316.978284 -304.427382)
		(width 0.13208)
		(layer "B.Cu")
		(net "SMB_PEX2_SLAVE_SCL")
	)
	(segment
		(start 317.635636 -304.916078)
		(end 318.0461 -304.505614)
		(width 0.13208)
		(layer "B.Cu")
		(net "SMB_PEX2_SLAVE_SCL")
	)
	(segment
		(start 317.914782 -304.20564)
		(end 317.746126 -304.20564)
		(width 0.13208)
		(layer "B.Cu")
		(net "SMB_PEX2_SLAVE_SCL")
	)
	(segment
		(start 317.833502 -305.2826)
		(end 317.635636 -305.084734)
		(width 0.13208)
		(layer "B.Cu")
		(net "SMB_PEX2_SLAVE_SCL")
	)
	(segment
		(start 317.746126 -304.20564)
		(end 317.335662 -304.616104)
		(width 0.13208)
		(layer "B.Cu")
		(net "SMB_PEX2_SLAVE_SCL")
	)
	(segment
		(start 318.845184 -303.798224)
		(end 318.845184 -304.042318)
		(width 0.13208)
		(layer "B.Cu")
		(net "SMB_PEX2_SLAVE_SCL")
	)
	(segment
		(start 317.23457 -305.901344)
		(end 316.761876 -306.097178)
		(width 0.13208)
		(layer "B.Cu")
		(net "SMB_PEX2_SLAVE_SCL")
	)
	(segment
		(start 316.170564 -306.097178)
		(end 315.965586 -305.8922)
		(width 0.13208)
		(layer "B.Cu")
		(net "SMB_PEX2_SLAVE_SCL")
	)
	(segment
		(start 316.67831 -304.727356)
		(end 317.459106 -305.508152)
		(width 0.13208)
		(layer "B.Cu")
		(net "SMB_PEX2_SLAVE_SCL")
	)
	(segment
		(start 318.0461 -304.505614)
		(end 318.0461 -304.336958)
		(width 0.13208)
		(layer "B.Cu")
		(net "SMB_PEX2_SLAVE_SCL")
	)
	(segment
		(start 318.845184 -304.042318)
		(end 318.443102 -304.4444)
		(width 0.13208)
		(layer "B.Cu")
		(net "SMB_PEX2_SLAVE_SCL")
	)
	(segment
		(start 316.67831 -304.5587)
		(end 316.67831 -304.727356)
		(width 0.13208)
		(layer "B.Cu")
		(net "SMB_PEX2_SLAVE_SCL")
	)
	(segment
		(start 316.761876 -306.097178)
		(end 316.498224 -306.097178)
		(width 0.13208)
		(layer "B.Cu")
		(net "SMB_PEX2_SLAVE_SCL")
	)
	(segment
		(start 318.0461 -304.336958)
		(end 317.914782 -304.20564)
		(width 0.13208)
		(layer "B.Cu")
		(net "SMB_PEX2_SLAVE_SCL")
	)
	(segment
		(start 318.443102 -304.81016)
		(end 317.970662 -305.2826)
		(width 0.13208)
		(layer "B.Cu")
		(net "SMB_PEX2_SLAVE_SCL")
	)
	(segment
		(start 317.635636 -305.084734)
		(end 317.635636 -304.916078)
		(width 0.13208)
		(layer "B.Cu")
		(net "SMB_PEX2_SLAVE_SCL")
	)
	(segment
		(start 315.965586 -305.8922)
		(end 305.607466 -305.8922)
		(width 0.13208)
		(layer "B.Cu")
		(net "SMB_PEX2_SLAVE_SCL")
	)
	(segment
		(start 318.443102 -304.4444)
		(end 318.443102 -304.81016)
		(width 0.13208)
		(layer "B.Cu")
		(net "SMB_PEX2_SLAVE_SCL")
	)
	(segment
		(start 317.459106 -305.676808)
		(end 317.23457 -305.901344)
		(width 0.13208)
		(layer "B.Cu")
		(net "SMB_PEX2_SLAVE_SCL")
	)
	(segment
		(start 317.459106 -305.508152)
		(end 317.459106 -305.676808)
		(width 0.13208)
		(layer "B.Cu")
		(net "SMB_PEX2_SLAVE_SCL")
	)
	(segment
		(start 317.335662 -304.616104)
		(end 317.167006 -304.616104)
		(width 0.13208)
		(layer "B.Cu")
		(net "SMB_PEX2_SLAVE_SCL")
	)
	(segment
		(start 305.607466 -305.8922)
		(end 304.674778 -306.824888)
		(width 0.13208)
		(layer "B.Cu")
		(net "SMB_PEX2_SLAVE_SCL")
	)
	(segment
		(start 317.970662 -305.2826)
		(end 317.833502 -305.2826)
		(width 0.13208)
		(layer "B.Cu")
		(net "SMB_PEX2_SLAVE_SCL")
	)
	(segment
		(start 316.809628 -304.427382)
		(end 316.67831 -304.5587)
		(width 0.13208)
		(layer "B.Cu")
		(net "SMB_PEX2_SLAVE_SCL")
	)
	(segment
		(start 316.498224 -306.097178)
		(end 316.170564 -306.097178)
		(width 0.13208)
		(layer "B.Cu")
		(net "SMB_PEX2_SLAVE_SCL")
	)
	(segment
		(start 316.978284 -304.427382)
		(end 316.809628 -304.427382)
		(width 0.13208)
		(layer "B.Cu")
		(net "SMB_PEX2_SLAVE_SCL")
	)
	(segment
		(start 351.919794 -147.654264)
		(end 351.920048 -147.654518)
		(width 0.13208)
		(layer "F.Cu")
		(net "PCA9555_1_PEX3_A0")
	)
	(segment
		(start 351.919794 -146.606768)
		(end 351.919794 -147.654264)
		(width 0.13208)
		(layer "F.Cu")
		(net "PCA9555_1_PEX3_A0")
	)
	(segment
		(start 351.237804 -147.697952)
		(end 351.281238 -147.654518)
		(width 0.13208)
		(layer "F.Cu")
		(net "PCA9555_1_PEX3_A0")
	)
	(segment
		(start 349.000064 -147.802092)
		(end 349.807276 -147.802092)
		(width 0.13208)
		(layer "F.Cu")
		(net "PCA9555_1_PEX3_A0")
	)
	(segment
		(start 351.281238 -147.654518)
		(end 351.920048 -147.654518)
		(width 0.13208)
		(layer "F.Cu")
		(net "PCA9555_1_PEX3_A0")
	)
	(segment
		(start 349.911416 -147.697952)
		(end 351.237804 -147.697952)
		(width 0.13208)
		(layer "F.Cu")
		(net "PCA9555_1_PEX3_A0")
	)
	(segment
		(start 349.807276 -147.802092)
		(end 349.911416 -147.697952)
		(width 0.13208)
		(layer "F.Cu")
		(net "PCA9555_1_PEX3_A0")
	)
	(via
		(at 351.281238 -147.654518)
		(size 0.508)
		(drill 0.254)
		(layers "F.Cu" "B.Cu")
		(net "PCA9555_1_PEX3_A0")
	)
	(segment
		(start 353.575874 -255.11125)
		(end 353.575874 -255.994916)
		(width 0.13208)
		(layer "F.Cu")
		(net "P0V8_PEX2_PWM2")
	)
	(segment
		(start 346.150438 -281.249882)
		(end 346.150438 -280.897838)
		(width 0.2032)
		(layer "F.Cu")
		(net "P0V8_PEX2_PWM2")
	)
	(segment
		(start 346.072206 -281.999182)
		(end 346.072206 -281.438858)
		(width 0.2032)
		(layer "F.Cu")
		(net "P0V8_PEX2_PWM2")
	)
	(segment
		(start 346.072206 -281.438858)
		(end 346.150438 -281.249882)
		(width 0.2032)
		(layer "F.Cu")
		(net "P0V8_PEX2_PWM2")
	)
	(segment
		(start 346.150438 -280.897838)
		(end 346.27566 -280.617168)
		(width 0.2032)
		(layer "F.Cu")
		(net "P0V8_PEX2_PWM2")
	)
	(via
		(at 353.575874 -255.11125)
		(size 0.508)
		(drill 0.254)
		(layers "F.Cu" "B.Cu")
		(net "P0V8_PEX2_PWM2")
	)
	(via
		(at 346.27566 -280.617168)
		(size 0.508)
		(drill 0.254)
		(layers "F.Cu" "B.Cu")
		(net "P0V8_PEX2_PWM2")
	)
	(segment
		(start 346.27566 -278.594566)
		(end 346.27566 -280.617168)
		(width 0.2032)
		(layer "In5.Cu")
		(net "P0V8_PEX2_PWM2")
	)
	(segment
		(start 351.023936 -264.622534)
		(end 345.19108 -270.45539)
		(width 0.2032)
		(layer "In5.Cu")
		(net "P0V8_PEX2_PWM2")
	)
	(segment
		(start 352.152458 -256.534666)
		(end 352.152458 -259.994908)
		(width 0.2032)
		(layer "In5.Cu")
		(net "P0V8_PEX2_PWM2")
	)
	(segment
		(start 352.152458 -259.994908)
		(end 350.564196 -261.58317)
		(width 0.2032)
		(layer "In5.Cu")
		(net "P0V8_PEX2_PWM2")
	)
	(segment
		(start 345.19108 -277.509986)
		(end 346.27566 -278.594566)
		(width 0.2032)
		(layer "In5.Cu")
		(net "P0V8_PEX2_PWM2")
	)
	(segment
		(start 345.19108 -270.45539)
		(end 345.19108 -277.509986)
		(width 0.2032)
		(layer "In5.Cu")
		(net "P0V8_PEX2_PWM2")
	)
	(segment
		(start 350.564196 -262.83793)
		(end 351.023936 -263.29767)
		(width 0.2032)
		(layer "In5.Cu")
		(net "P0V8_PEX2_PWM2")
	)
	(segment
		(start 350.564196 -261.58317)
		(end 350.564196 -262.83793)
		(width 0.2032)
		(layer "In5.Cu")
		(net "P0V8_PEX2_PWM2")
	)
	(segment
		(start 351.023936 -263.29767)
		(end 351.023936 -264.622534)
		(width 0.2032)
		(layer "In5.Cu")
		(net "P0V8_PEX2_PWM2")
	)
	(segment
		(start 353.575874 -255.11125)
		(end 352.152458 -256.534666)
		(width 0.2032)
		(layer "In5.Cu")
		(net "P0V8_PEX2_PWM2")
	)
	(segment
		(start 196.956172 -33.248092)
		(end 196.956172 -33.8328)
		(width 0.13208)
		(layer "F.Cu")
		(net "SSD7_AUX_P3V3_EN_R")
	)
	(segment
		(start 196.956172 -34.361628)
		(end 196.956172 -36.874958)
		(width 0.13208)
		(layer "F.Cu")
		(net "SSD7_AUX_P3V3_EN_R")
	)
	(segment
		(start 194.377818 -37.84092)
		(end 194.689984 -37.529516)
		(width 0.13208)
		(layer "F.Cu")
		(net "SSD7_AUX_P3V3_EN_R")
	)
	(segment
		(start 194.689984 -37.529516)
		(end 195.226178 -37.529516)
		(width 0.13208)
		(layer "F.Cu")
		(net "SSD7_AUX_P3V3_EN_R")
	)
	(segment
		(start 198.815198 -59.100974)
		(end 199.840088 -58.076084)
		(width 0.13208)
		(layer "F.Cu")
		(net "SSD7_AUX_P3V3_EN_R")
	)
	(segment
		(start 200.2409 -57.675272)
		(end 199.840088 -58.076084)
		(width 0.13208)
		(layer "F.Cu")
		(net "SSD7_AUX_P3V3_EN_R")
	)
	(segment
		(start 196.956172 -36.874958)
		(end 196.30263 -37.529516)
		(width 0.13208)
		(layer "F.Cu")
		(net "SSD7_AUX_P3V3_EN_R")
	)
	(segment
		(start 196.30263 -37.529516)
		(end 195.226178 -37.529516)
		(width 0.13208)
		(layer "F.Cu")
		(net "SSD7_AUX_P3V3_EN_R")
	)
	(segment
		(start 194.377818 -39.97198)
		(end 194.377818 -37.84092)
		(width 0.13208)
		(layer "F.Cu")
		(net "SSD7_AUX_P3V3_EN_R")
	)
	(segment
		(start 200.2409 -57.16397)
		(end 200.2409 -57.675272)
		(width 0.13208)
		(layer "F.Cu")
		(net "SSD7_AUX_P3V3_EN_R")
	)
	(segment
		(start 197.0278 -34.29)
		(end 196.956172 -34.361628)
		(width 0.13208)
		(layer "F.Cu")
		(net "SSD7_AUX_P3V3_EN_R")
	)
	(segment
		(start 198.815198 -59.146186)
		(end 198.815198 -59.100974)
		(width 0.13208)
		(layer "F.Cu")
		(net "SSD7_AUX_P3V3_EN_R")
	)
	(segment
		(start 197.0278 -33.904428)
		(end 197.0278 -34.29)
		(width 0.13208)
		(layer "F.Cu")
		(net "SSD7_AUX_P3V3_EN_R")
	)
	(segment
		(start 196.956172 -33.8328)
		(end 197.0278 -33.904428)
		(width 0.13208)
		(layer "F.Cu")
		(net "SSD7_AUX_P3V3_EN_R")
	)
	(via
		(at 199.840088 -58.076084)
		(size 0.508)
		(drill 0.254)
		(layers "F.Cu" "B.Cu")
		(net "SSD7_AUX_P3V3_EN_R")
	)
	(via
		(at 194.377818 -39.97198)
		(size 0.508)
		(drill 0.254)
		(layers "F.Cu" "B.Cu")
		(net "SSD7_AUX_P3V3_EN_R")
	)
	(segment
		(start 197.658736 -39.97198)
		(end 203.623164 -45.936408)
		(width 0.15494)
		(layer "In5.Cu")
		(net "SSD7_AUX_P3V3_EN_R")
	)
	(segment
		(start 203.623164 -54.293008)
		(end 199.840088 -58.076084)
		(width 0.15494)
		(layer "In5.Cu")
		(net "SSD7_AUX_P3V3_EN_R")
	)
	(segment
		(start 194.377818 -39.97198)
		(end 197.658736 -39.97198)
		(width 0.15494)
		(layer "In5.Cu")
		(net "SSD7_AUX_P3V3_EN_R")
	)
	(segment
		(start 203.623164 -45.936408)
		(end 203.623164 -54.293008)
		(width 0.15494)
		(layer "In5.Cu")
		(net "SSD7_AUX_P3V3_EN_R")
	)
	(segment
		(start 164.349938 -292.099746)
		(end 163.874958 -291.624766)
		(width 0.249936)
		(layer "F.Cu")
		(net "PCEPLL7_VDDA18_PEX1")
	)
	(via
		(at 147.819618 -283.893514)
		(size 0.508)
		(drill 0.254)
		(layers "F.Cu" "B.Cu")
		(net "PCEPLL7_VDDA18_PEX1")
	)
	(via
		(at 149.216618 -283.893514)
		(size 0.508)
		(drill 0.254)
		(layers "F.Cu" "B.Cu")
		(net "PCEPLL7_VDDA18_PEX1")
	)
	(via
		(at 163.874958 -291.624766)
		(size 0.4064)
		(drill 0.2032)
		(layers "F.Cu" "B.Cu")
		(net "PCEPLL7_VDDA18_PEX1")
	)
	(segment
		(start 163.874958 -291.416486)
		(end 163.874958 -291.624766)
		(width 0.3048)
		(layer "B.Cu")
		(net "PCEPLL7_VDDA18_PEX1")
	)
	(segment
		(start 163.102798 -291.624766)
		(end 163.874958 -291.624766)
		(width 0.3048)
		(layer "B.Cu")
		(net "PCEPLL7_VDDA18_PEX1")
	)
	(segment
		(start 320.17589 -305.675792)
		(end 320.17589 -305.007518)
		(width 0.13208)
		(layer "F.Cu")
		(net "SMB_PEX2_SLAVE_SDA")
	)
	(segment
		(start 304.674778 -308.724808)
		(end 305.149758 -309.199788)
		(width 0.13208)
		(layer "F.Cu")
		(net "SMB_PEX2_SLAVE_SDA")
	)
	(segment
		(start 320.17589 -305.007518)
		(end 320.430652 -304.752756)
		(width 0.13208)
		(layer "F.Cu")
		(net "SMB_PEX2_SLAVE_SDA")
	)
	(via
		(at 320.430652 -304.752756)
		(size 0.508)
		(drill 0.254)
		(layers "F.Cu" "B.Cu")
		(net "SMB_PEX2_SLAVE_SDA")
	)
	(via
		(at 304.674778 -308.724808)
		(size 0.4064)
		(drill 0.2032)
		(layers "F.Cu" "B.Cu")
		(net "SMB_PEX2_SLAVE_SDA")
	)
	(via
		(at 319.592198 -305.59121)
		(size 0.6604)
		(drill 0.3302)
		(layers "F.Cu" "B.Cu")
		(net "SMB_PEX2_SLAVE_SDA")
	)
	(segment
		(start 319.592198 -305.59121)
		(end 320.430652 -304.752756)
		(width 0.13208)
		(layer "B.Cu")
		(net "SMB_PEX2_SLAVE_SDA")
	)
	(segment
		(start 316.470538 -307.815234)
		(end 305.584352 -307.815234)
		(width 0.13208)
		(layer "B.Cu")
		(net "SMB_PEX2_SLAVE_SDA")
	)
	(segment
		(start 319.592198 -305.59121)
		(end 319.175638 -306.00777)
		(width 0.13208)
		(layer "B.Cu")
		(net "SMB_PEX2_SLAVE_SDA")
	)
	(segment
		(start 305.584352 -307.815234)
		(end 304.674778 -308.724808)
		(width 0.13208)
		(layer "B.Cu")
		(net "SMB_PEX2_SLAVE_SDA")
	)
	(segment
		(start 319.175638 -306.00777)
		(end 316.470538 -307.815234)
		(width 0.13208)
		(layer "B.Cu")
		(net "SMB_PEX2_SLAVE_SDA")
	)
	(segment
		(start 341.996268 -149.102064)
		(end 343.149936 -149.102064)
		(width 0.13208)
		(layer "F.Cu")
		(net "PCA9555_1_PEX3_A1")
	)
	(segment
		(start 336.44205 -149.987)
		(end 337.67395 -149.987)
		(width 0.13208)
		(layer "F.Cu")
		(net "PCA9555_1_PEX3_A1")
	)
	(segment
		(start 337.67395 -150.368)
		(end 337.80095 -150.495)
		(width 0.13208)
		(layer "F.Cu")
		(net "PCA9555_1_PEX3_A1")
	)
	(segment
		(start 341.122 -149.976332)
		(end 341.996268 -149.102064)
		(width 0.13208)
		(layer "F.Cu")
		(net "PCA9555_1_PEX3_A1")
	)
	(segment
		(start 341.122 -149.987)
		(end 341.122 -149.976332)
		(width 0.13208)
		(layer "F.Cu")
		(net "PCA9555_1_PEX3_A1")
	)
	(segment
		(start 337.67395 -149.987)
		(end 337.67395 -150.368)
		(width 0.13208)
		(layer "F.Cu")
		(net "PCA9555_1_PEX3_A1")
	)
	(segment
		(start 340.614 -150.495)
		(end 341.122 -149.987)
		(width 0.13208)
		(layer "F.Cu")
		(net "PCA9555_1_PEX3_A1")
	)
	(segment
		(start 337.80095 -150.495)
		(end 340.614 -150.495)
		(width 0.13208)
		(layer "F.Cu")
		(net "PCA9555_1_PEX3_A1")
	)
	(via
		(at 341.122 -149.976332)
		(size 0.508)
		(drill 0.254)
		(layers "F.Cu" "B.Cu")
		(net "PCA9555_1_PEX3_A1")
	)
	(segment
		(start 164.349938 -293.99992)
		(end 163.874958 -293.52494)
		(width 0.254)
		(layer "F.Cu")
		(net "PCEPLL5_VDDA18_PEX1")
	)
	(via
		(at 163.874958 -293.52494)
		(size 0.4064)
		(drill 0.2032)
		(layers "F.Cu" "B.Cu")
		(net "PCEPLL5_VDDA18_PEX1")
	)
	(via
		(at 150.777702 -257.137916)
		(size 0.508)
		(drill 0.254)
		(layers "F.Cu" "B.Cu")
		(net "PCEPLL5_VDDA18_PEX1")
	)
	(via
		(at 152.174702 -257.137916)
		(size 0.508)
		(drill 0.254)
		(layers "F.Cu" "B.Cu")
		(net "PCEPLL5_VDDA18_PEX1")
	)
	(segment
		(start 163.874958 -293.9415)
		(end 163.874958 -293.52494)
		(width 0.3048)
		(layer "B.Cu")
		(net "PCEPLL5_VDDA18_PEX1")
	)
	(segment
		(start 163.874958 -293.2303)
		(end 163.874958 -293.52494)
		(width 0.3048)
		(layer "B.Cu")
		(net "PCEPLL5_VDDA18_PEX1")
	)
	(segment
		(start 301.824898 -307.774848)
		(end 301.349918 -308.249828)
		(width 0.13208)
		(layer "F.Cu")
		(net "I2C0_PEX2_SCL")
	)
	(segment
		(start 324.09511 -301.556928)
		(end 323.579236 -301.041054)
		(width 0.13208)
		(layer "F.Cu")
		(net "I2C0_PEX2_SCL")
	)
	(via
		(at 324.09511 -301.556928)
		(size 0.508)
		(drill 0.254)
		(layers "F.Cu" "B.Cu")
		(net "I2C0_PEX2_SCL")
	)
	(via
		(at 301.824898 -307.774848)
		(size 0.4064)
		(drill 0.2032)
		(layers "F.Cu" "B.Cu")
		(net "I2C0_PEX2_SCL")
	)
	(segment
		(start 308.474872 -303.817528)
		(end 308.474872 -306.433728)
		(width 0.15494)
		(layer "In5.Cu")
		(net "I2C0_PEX2_SCL")
	)
	(segment
		(start 324.09511 -301.215044)
		(end 323.387466 -300.5074)
		(width 0.15494)
		(layer "In5.Cu")
		(net "I2C0_PEX2_SCL")
	)
	(segment
		(start 308.083712 -306.824888)
		(end 306.585112 -306.824888)
		(width 0.15494)
		(layer "In5.Cu")
		(net "I2C0_PEX2_SCL")
	)
	(segment
		(start 316.464188 -299.701458)
		(end 315.514736 -300.65091)
		(width 0.15494)
		(layer "In5.Cu")
		(net "I2C0_PEX2_SCL")
	)
	(segment
		(start 320.599054 -300.5074)
		(end 319.793112 -299.701458)
		(width 0.15494)
		(layer "In5.Cu")
		(net "I2C0_PEX2_SCL")
	)
	(segment
		(start 303.948592 -308.249828)
		(end 302.69815 -308.249828)
		(width 0.15494)
		(layer "In5.Cu")
		(net "I2C0_PEX2_SCL")
	)
	(segment
		(start 309.0164 -300.77791)
		(end 309.0164 -303.276)
		(width 0.15494)
		(layer "In5.Cu")
		(net "I2C0_PEX2_SCL")
	)
	(segment
		(start 323.387466 -300.5074)
		(end 320.599054 -300.5074)
		(width 0.15494)
		(layer "In5.Cu")
		(net "I2C0_PEX2_SCL")
	)
	(segment
		(start 305.155854 -307.34)
		(end 304.417222 -307.34)
		(width 0.15494)
		(layer "In5.Cu")
		(net "I2C0_PEX2_SCL")
	)
	(segment
		(start 319.793112 -299.701458)
		(end 316.464188 -299.701458)
		(width 0.15494)
		(layer "In5.Cu")
		(net "I2C0_PEX2_SCL")
	)
	(segment
		(start 306.5526 -306.8574)
		(end 305.638454 -306.8574)
		(width 0.15494)
		(layer "In5.Cu")
		(net "I2C0_PEX2_SCL")
	)
	(segment
		(start 324.09511 -301.556928)
		(end 324.09511 -301.215044)
		(width 0.15494)
		(layer "In5.Cu")
		(net "I2C0_PEX2_SCL")
	)
	(segment
		(start 315.514736 -300.65091)
		(end 309.1434 -300.65091)
		(width 0.15494)
		(layer "In5.Cu")
		(net "I2C0_PEX2_SCL")
	)
	(segment
		(start 309.0164 -303.276)
		(end 308.474872 -303.817528)
		(width 0.15494)
		(layer "In5.Cu")
		(net "I2C0_PEX2_SCL")
	)
	(segment
		(start 305.638454 -306.8574)
		(end 305.155854 -307.34)
		(width 0.15494)
		(layer "In5.Cu")
		(net "I2C0_PEX2_SCL")
	)
	(segment
		(start 304.184304 -307.572918)
		(end 304.184304 -308.014116)
		(width 0.15494)
		(layer "In5.Cu")
		(net "I2C0_PEX2_SCL")
	)
	(segment
		(start 308.474872 -306.433728)
		(end 308.083712 -306.824888)
		(width 0.15494)
		(layer "In5.Cu")
		(net "I2C0_PEX2_SCL")
	)
	(segment
		(start 302.22317 -307.774848)
		(end 301.824898 -307.774848)
		(width 0.15494)
		(layer "In5.Cu")
		(net "I2C0_PEX2_SCL")
	)
	(segment
		(start 304.184304 -308.014116)
		(end 303.948592 -308.249828)
		(width 0.15494)
		(layer "In5.Cu")
		(net "I2C0_PEX2_SCL")
	)
	(segment
		(start 304.417222 -307.34)
		(end 304.184304 -307.572918)
		(width 0.15494)
		(layer "In5.Cu")
		(net "I2C0_PEX2_SCL")
	)
	(segment
		(start 309.1434 -300.65091)
		(end 309.0164 -300.77791)
		(width 0.15494)
		(layer "In5.Cu")
		(net "I2C0_PEX2_SCL")
	)
	(segment
		(start 302.69815 -308.249828)
		(end 302.22317 -307.774848)
		(width 0.15494)
		(layer "In5.Cu")
		(net "I2C0_PEX2_SCL")
	)
	(segment
		(start 306.585112 -306.824888)
		(end 306.5526 -306.8574)
		(width 0.15494)
		(layer "In5.Cu")
		(net "I2C0_PEX2_SCL")
	)
	(segment
		(start 337.67395 -149.352)
		(end 337.80095 -149.479)
		(width 0.13208)
		(layer "F.Cu")
		(net "PCA9555_1_PEX3_A2")
	)
	(segment
		(start 339.89137 -149.479)
		(end 340.492588 -148.877782)
		(width 0.13208)
		(layer "F.Cu")
		(net "PCA9555_1_PEX3_A2")
	)
	(segment
		(start 337.80095 -149.479)
		(end 339.89137 -149.479)
		(width 0.13208)
		(layer "F.Cu")
		(net "PCA9555_1_PEX3_A2")
	)
	(segment
		(start 336.44205 -148.971)
		(end 337.67395 -148.971)
		(width 0.13208)
		(layer "F.Cu")
		(net "PCA9555_1_PEX3_A2")
	)
	(segment
		(start 340.492588 -148.877782)
		(end 340.918292 -148.452078)
		(width 0.13208)
		(layer "F.Cu")
		(net "PCA9555_1_PEX3_A2")
	)
	(segment
		(start 340.918292 -148.452078)
		(end 343.149936 -148.452078)
		(width 0.13208)
		(layer "F.Cu")
		(net "PCA9555_1_PEX3_A2")
	)
	(segment
		(start 337.67395 -148.971)
		(end 337.67395 -149.352)
		(width 0.13208)
		(layer "F.Cu")
		(net "PCA9555_1_PEX3_A2")
	)
	(via
		(at 340.492588 -148.877782)
		(size 0.508)
		(drill 0.254)
		(layers "F.Cu" "B.Cu")
		(net "PCA9555_1_PEX3_A2")
	)
	(segment
		(start 331.342746 -220.904562)
		(end 332.22819 -220.904562)
		(width 0.13208)
		(layer "F.Cu")
		(net "PRSNT_SSD15_FPGA_N")
	)
	(segment
		(start 327.93305 -220.218)
		(end 329.375516 -220.218)
		(width 0.13208)
		(layer "F.Cu")
		(net "PRSNT_SSD15_FPGA_N")
	)
	(segment
		(start 329.741276 -220.58376)
		(end 330.069952 -220.58376)
		(width 0.13208)
		(layer "F.Cu")
		(net "PRSNT_SSD15_FPGA_N")
	)
	(segment
		(start 330.783184 -220.345)
		(end 331.342746 -220.904562)
		(width 0.13208)
		(layer "F.Cu")
		(net "PRSNT_SSD15_FPGA_N")
	)
	(segment
		(start 332.22819 -220.904562)
		(end 332.492604 -220.640148)
		(width 0.13208)
		(layer "F.Cu")
		(net "PRSNT_SSD15_FPGA_N")
	)
	(segment
		(start 333.480664 -220.640148)
		(end 333.627476 -220.78696)
		(width 0.13208)
		(layer "F.Cu")
		(net "PRSNT_SSD15_FPGA_N")
	)
	(segment
		(start 330.069952 -220.58376)
		(end 330.308712 -220.345)
		(width 0.13208)
		(layer "F.Cu")
		(net "PRSNT_SSD15_FPGA_N")
	)
	(segment
		(start 329.375516 -220.218)
		(end 329.741276 -220.58376)
		(width 0.13208)
		(layer "F.Cu")
		(net "PRSNT_SSD15_FPGA_N")
	)
	(segment
		(start 332.492604 -220.640148)
		(end 333.480664 -220.640148)
		(width 0.13208)
		(layer "F.Cu")
		(net "PRSNT_SSD15_FPGA_N")
	)
	(segment
		(start 333.627476 -220.78696)
		(end 334.09382 -220.78696)
		(width 0.13208)
		(layer "F.Cu")
		(net "PRSNT_SSD15_FPGA_N")
	)
	(segment
		(start 330.308712 -220.345)
		(end 330.783184 -220.345)
		(width 0.13208)
		(layer "F.Cu")
		(net "PRSNT_SSD15_FPGA_N")
	)
	(via
		(at 330.069952 -220.58376)
		(size 0.762)
		(drill 0.381)
		(layers "F.Cu" "B.Cu")
		(net "PRSNT_SSD15_FPGA_N")
	)
	(segment
		(start 106.910886 -94.686882)
		(end 107.526074 -95.30207)
		(width 0.13208)
		(layer "F.Cu")
		(net "HP_NIC1_EN")
	)
	(segment
		(start 100.877624 -124.408946)
		(end 108.350558 -121.313448)
		(width 0.13208)
		(layer "F.Cu")
		(net "HP_NIC1_EN")
	)
	(segment
		(start 82.657188 -139.192)
		(end 83.9216 -139.192)
		(width 0.13208)
		(layer "F.Cu")
		(net "HP_NIC1_EN")
	)
	(segment
		(start 108.350558 -121.313448)
		(end 113.9698 -115.694206)
		(width 0.13208)
		(layer "F.Cu")
		(net "HP_NIC1_EN")
	)
	(segment
		(start 101.152198 -94.864174)
		(end 101.32949 -94.686882)
		(width 0.13208)
		(layer "F.Cu")
		(net "HP_NIC1_EN")
	)
	(segment
		(start 97.409762 -123.381516)
		(end 97.823274 -123.795028)
		(width 0.13208)
		(layer "F.Cu")
		(net "HP_NIC1_EN")
	)
	(segment
		(start 97.409762 -122.428762)
		(end 97.409762 -123.381516)
		(width 0.13208)
		(layer "F.Cu")
		(net "HP_NIC1_EN")
	)
	(segment
		(start 96.903794 -138.358372)
		(end 85.191346 -138.358372)
		(width 0.13208)
		(layer "F.Cu")
		(net "HP_NIC1_EN")
	)
	(segment
		(start 101.32949 -94.686882)
		(end 106.910886 -94.686882)
		(width 0.13208)
		(layer "F.Cu")
		(net "HP_NIC1_EN")
	)
	(segment
		(start 112.711992 -96.629728)
		(end 112.711992 -107.848654)
		(width 0.13208)
		(layer "F.Cu")
		(net "HP_NIC1_EN")
	)
	(segment
		(start 96.77146 -122.04192)
		(end 97.02292 -122.04192)
		(width 0.13208)
		(layer "F.Cu")
		(net "HP_NIC1_EN")
	)
	(segment
		(start 84.50199 -139.77239)
		(end 84.50199 -140.050774)
		(width 0.13208)
		(layer "F.Cu")
		(net "HP_NIC1_EN")
	)
	(segment
		(start 98.575622 -123.795028)
		(end 98.575622 -124.262896)
		(width 0.13208)
		(layer "F.Cu")
		(net "HP_NIC1_EN")
	)
	(segment
		(start 97.02292 -122.04192)
		(end 97.409762 -122.428762)
		(width 0.13208)
		(layer "F.Cu")
		(net "HP_NIC1_EN")
	)
	(segment
		(start 113.422684 -107.848654)
		(end 112.711992 -107.848654)
		(width 0.13208)
		(layer "F.Cu")
		(net "HP_NIC1_EN")
	)
	(segment
		(start 107.526074 -95.30207)
		(end 111.384334 -95.30207)
		(width 0.13208)
		(layer "F.Cu")
		(net "HP_NIC1_EN")
	)
	(segment
		(start 82.11439 -139.734798)
		(end 82.657188 -139.192)
		(width 0.13208)
		(layer "F.Cu")
		(net "HP_NIC1_EN")
	)
	(segment
		(start 97.823274 -137.438892)
		(end 96.903794 -138.358372)
		(width 0.13208)
		(layer "F.Cu")
		(net "HP_NIC1_EN")
	)
	(segment
		(start 88.2523 -115.400836)
		(end 87.6427 -115.400836)
		(width 0.13208)
		(layer "F.Cu")
		(net "HP_NIC1_EN")
	)
	(segment
		(start 113.9698 -108.39577)
		(end 113.422684 -107.848654)
		(width 0.13208)
		(layer "F.Cu")
		(net "HP_NIC1_EN")
	)
	(segment
		(start 98.575622 -124.262896)
		(end 98.721672 -124.408946)
		(width 0.13208)
		(layer "F.Cu")
		(net "HP_NIC1_EN")
	)
	(segment
		(start 83.9216 -139.192)
		(end 84.50199 -139.77239)
		(width 0.13208)
		(layer "F.Cu")
		(net "HP_NIC1_EN")
	)
	(segment
		(start 98.721672 -124.408946)
		(end 100.877624 -124.408946)
		(width 0.13208)
		(layer "F.Cu")
		(net "HP_NIC1_EN")
	)
	(segment
		(start 113.9698 -115.694206)
		(end 113.9698 -108.39577)
		(width 0.13208)
		(layer "F.Cu")
		(net "HP_NIC1_EN")
	)
	(segment
		(start 97.823274 -123.795028)
		(end 97.823274 -137.438892)
		(width 0.13208)
		(layer "F.Cu")
		(net "HP_NIC1_EN")
	)
	(segment
		(start 84.50199 -140.050774)
		(end 85.617812 -140.050774)
		(width 0.13208)
		(layer "F.Cu")
		(net "HP_NIC1_EN")
	)
	(segment
		(start 97.823274 -123.795028)
		(end 98.575622 -123.795028)
		(width 0.13208)
		(layer "F.Cu")
		(net "HP_NIC1_EN")
	)
	(segment
		(start 111.384334 -95.30207)
		(end 112.711992 -96.629728)
		(width 0.13208)
		(layer "F.Cu")
		(net "HP_NIC1_EN")
	)
	(via
		(at 85.617812 -140.050774)
		(size 0.508)
		(drill 0.254)
		(layers "F.Cu" "B.Cu")
		(net "HP_NIC1_EN")
	)
	(via
		(at 87.6427 -115.400836)
		(size 0.508)
		(drill 0.254)
		(layers "F.Cu" "B.Cu")
		(net "HP_NIC1_EN")
	)
	(via
		(at 85.191346 -138.358372)
		(size 0.508)
		(drill 0.254)
		(layers "F.Cu" "B.Cu")
		(net "HP_NIC1_EN")
	)
	(via
		(at 97.823274 -123.795028)
		(size 0.508)
		(drill 0.254)
		(layers "F.Cu" "B.Cu")
		(net "HP_NIC1_EN")
	)
	(segment
		(start 85.617812 -138.784838)
		(end 85.617812 -140.050774)
		(width 0.13208)
		(layer "B.Cu")
		(net "HP_NIC1_EN")
	)
	(segment
		(start 85.191346 -138.358372)
		(end 85.617812 -138.784838)
		(width 0.13208)
		(layer "B.Cu")
		(net "HP_NIC1_EN")
	)
	(segment
		(start 88.654636 -115.400836)
		(end 87.6427 -115.400836)
		(width 0.15494)
		(layer "In5.Cu")
		(net "HP_NIC1_EN")
	)
	(segment
		(start 88.940132 -115.686332)
		(end 88.654636 -115.400836)
		(width 0.15494)
		(layer "In5.Cu")
		(net "HP_NIC1_EN")
	)
	(segment
		(start 88.940132 -116.698268)
		(end 88.940132 -115.686332)
		(width 0.15494)
		(layer "In5.Cu")
		(net "HP_NIC1_EN")
	)
	(segment
		(start 94.702376 -120.67413)
		(end 92.915994 -120.67413)
		(width 0.15494)
		(layer "In5.Cu")
		(net "HP_NIC1_EN")
	)
	(segment
		(start 92.915994 -120.67413)
		(end 88.940132 -116.698268)
		(width 0.15494)
		(layer "In5.Cu")
		(net "HP_NIC1_EN")
	)
	(segment
		(start 97.823274 -123.795028)
		(end 94.702376 -120.67413)
		(width 0.15494)
		(layer "In5.Cu")
		(net "HP_NIC1_EN")
	)
	(segment
		(start 198.947786 -40.185086)
		(end 198.947786 -41.137332)
		(width 0.13208)
		(layer "F.Cu")
		(net "SSD7_AUX_P3V3_EN")
	)
	(segment
		(start 195.226178 -39.33571)
		(end 196.480176 -39.33571)
		(width 0.13208)
		(layer "F.Cu")
		(net "SSD7_AUX_P3V3_EN")
	)
	(segment
		(start 198.820786 -40.058086)
		(end 198.947786 -40.185086)
		(width 0.13208)
		(layer "F.Cu")
		(net "SSD7_AUX_P3V3_EN")
	)
	(segment
		(start 196.480176 -39.33571)
		(end 197.202552 -40.058086)
		(width 0.13208)
		(layer "F.Cu")
		(net "SSD7_AUX_P3V3_EN")
	)
	(segment
		(start 195.226178 -38.329616)
		(end 195.226178 -39.33571)
		(width 0.13208)
		(layer "F.Cu")
		(net "SSD7_AUX_P3V3_EN")
	)
	(segment
		(start 197.202552 -40.058086)
		(end 198.820786 -40.058086)
		(width 0.13208)
		(layer "F.Cu")
		(net "SSD7_AUX_P3V3_EN")
	)
	(via
		(at 196.480176 -39.33571)
		(size 0.762)
		(drill 0.381)
		(layers "F.Cu" "B.Cu")
		(net "SSD7_AUX_P3V3_EN")
	)
	(segment
		(start 163.399978 -293.04996)
		(end 162.924998 -292.57498)
		(width 0.249936)
		(layer "F.Cu")
		(net "PCEPLL6_VDDA18_PEX1")
	)
	(via
		(at 147.819618 -287.093914)
		(size 0.508)
		(drill 0.254)
		(layers "F.Cu" "B.Cu")
		(net "PCEPLL6_VDDA18_PEX1")
	)
	(via
		(at 162.924998 -292.57498)
		(size 0.4064)
		(drill 0.2032)
		(layers "F.Cu" "B.Cu")
		(net "PCEPLL6_VDDA18_PEX1")
	)
	(via
		(at 149.216618 -287.093914)
		(size 0.508)
		(drill 0.254)
		(layers "F.Cu" "B.Cu")
		(net "PCEPLL6_VDDA18_PEX1")
	)
	(segment
		(start 162.7124 -292.57498)
		(end 162.924998 -292.57498)
		(width 0.3048)
		(layer "B.Cu")
		(net "PCEPLL6_VDDA18_PEX1")
	)
	(segment
		(start 162.7124 -293.52494)
		(end 162.7124 -292.57498)
		(width 0.3048)
		(layer "B.Cu")
		(net "PCEPLL6_VDDA18_PEX1")
	)
	(segment
		(start 322.899024 -301.04207)
		(end 322.22821 -301.04207)
		(width 0.13208)
		(layer "F.Cu")
		(net "I2C0_PEX2_SDA")
	)
	(segment
		(start 304.674778 -307.774848)
		(end 305.149758 -308.249828)
		(width 0.13208)
		(layer "F.Cu")
		(net "I2C0_PEX2_SDA")
	)
	(via
		(at 322.899024 -301.04207)
		(size 0.508)
		(drill 0.254)
		(layers "F.Cu" "B.Cu")
		(net "I2C0_PEX2_SDA")
	)
	(via
		(at 304.674778 -307.774848)
		(size 0.4064)
		(drill 0.2032)
		(layers "F.Cu" "B.Cu")
		(net "I2C0_PEX2_SDA")
	)
	(segment
		(start 319.58153 -300.230794)
		(end 316.785244 -300.230794)
		(width 0.15494)
		(layer "In5.Cu")
		(net "I2C0_PEX2_SDA")
	)
	(segment
		(start 309.926228 -303.424082)
		(end 310.3118 -303.809654)
		(width 0.15494)
		(layer "In5.Cu")
		(net "I2C0_PEX2_SDA")
	)
	(segment
		(start 310.053228 -301.613062)
		(end 309.926228 -301.740062)
		(width 0.15494)
		(layer "In5.Cu")
		(net "I2C0_PEX2_SDA")
	)
	(segment
		(start 310.3118 -307.5432)
		(end 310.080152 -307.774848)
		(width 0.15494)
		(layer "In5.Cu")
		(net "I2C0_PEX2_SDA")
	)
	(segment
		(start 316.785244 -300.230794)
		(end 315.402976 -301.613062)
		(width 0.15494)
		(layer "In5.Cu")
		(net "I2C0_PEX2_SDA")
	)
	(segment
		(start 310.080152 -307.774848)
		(end 304.674778 -307.774848)
		(width 0.15494)
		(layer "In5.Cu")
		(net "I2C0_PEX2_SDA")
	)
	(segment
		(start 315.402976 -301.613062)
		(end 310.053228 -301.613062)
		(width 0.15494)
		(layer "In5.Cu")
		(net "I2C0_PEX2_SDA")
	)
	(segment
		(start 322.899024 -301.04207)
		(end 320.392806 -301.04207)
		(width 0.15494)
		(layer "In5.Cu")
		(net "I2C0_PEX2_SDA")
	)
	(segment
		(start 310.3118 -303.809654)
		(end 310.3118 -307.5432)
		(width 0.15494)
		(layer "In5.Cu")
		(net "I2C0_PEX2_SDA")
	)
	(segment
		(start 309.926228 -301.740062)
		(end 309.926228 -303.424082)
		(width 0.15494)
		(layer "In5.Cu")
		(net "I2C0_PEX2_SDA")
	)
	(segment
		(start 320.392806 -301.04207)
		(end 319.58153 -300.230794)
		(width 0.15494)
		(layer "In5.Cu")
		(net "I2C0_PEX2_SDA")
	)
	(segment
		(start 341.122 -161.787332)
		(end 341.996268 -160.913064)
		(width 0.13208)
		(layer "F.Cu")
		(net "PCA9555_0_PEX3_A1")
	)
	(segment
		(start 337.67395 -161.798)
		(end 337.67395 -162.179)
		(width 0.13208)
		(layer "F.Cu")
		(net "PCA9555_0_PEX3_A1")
	)
	(segment
		(start 341.996268 -160.913064)
		(end 343.149936 -160.913064)
		(width 0.13208)
		(layer "F.Cu")
		(net "PCA9555_0_PEX3_A1")
	)
	(segment
		(start 340.614 -162.306)
		(end 341.122 -161.798)
		(width 0.13208)
		(layer "F.Cu")
		(net "PCA9555_0_PEX3_A1")
	)
	(segment
		(start 337.67395 -162.179)
		(end 337.80095 -162.306)
		(width 0.13208)
		(layer "F.Cu")
		(net "PCA9555_0_PEX3_A1")
	)
	(segment
		(start 336.44205 -161.798)
		(end 337.67395 -161.798)
		(width 0.13208)
		(layer "F.Cu")
		(net "PCA9555_0_PEX3_A1")
	)
	(segment
		(start 341.122 -161.798)
		(end 341.122 -161.787332)
		(width 0.13208)
		(layer "F.Cu")
		(net "PCA9555_0_PEX3_A1")
	)
	(segment
		(start 337.80095 -162.306)
		(end 340.614 -162.306)
		(width 0.13208)
		(layer "F.Cu")
		(net "PCA9555_0_PEX3_A1")
	)
	(via
		(at 341.122 -161.787332)
		(size 0.508)
		(drill 0.254)
		(layers "F.Cu" "B.Cu")
		(net "PCA9555_0_PEX3_A1")
	)
	(segment
		(start 340.614 -204.83195)
		(end 340.614 -204.216)
		(width 0.13208)
		(layer "F.Cu")
		(net "RST_SSD12_PERST_R_N")
	)
	(segment
		(start 362.503974 -24.189944)
		(end 363.564932 -24.189944)
		(width 0.13208)
		(layer "F.Cu")
		(net "RST_SSD12_PERST_R_N")
	)
	(via
		(at 340.614 -204.216)
		(size 0.508)
		(drill 0.254)
		(layers "F.Cu" "B.Cu")
		(net "RST_SSD12_PERST_R_N")
	)
	(via
		(at 353.128834 -106.064812)
		(size 0.508)
		(drill 0.254)
		(layers "F.Cu" "B.Cu")
		(net "RST_SSD12_PERST_R_N")
	)
	(via
		(at 373.262652 -105.86593)
		(size 0.508)
		(drill 0.254)
		(layers "F.Cu" "B.Cu")
		(net "RST_SSD12_PERST_R_N")
	)
	(via
		(at 362.503974 -24.189944)
		(size 0.508)
		(drill 0.254)
		(layers "F.Cu" "B.Cu")
		(net "RST_SSD12_PERST_R_N")
	)
	(segment
		(start 364.928404 -24.575008)
		(end 362.889038 -24.575008)
		(width 0.15494)
		(layer "In5.Cu")
		(net "RST_SSD12_PERST_R_N")
	)
	(segment
		(start 373.526304 -99.8728)
		(end 382.519682 -90.879422)
		(width 0.15494)
		(layer "In5.Cu")
		(net "RST_SSD12_PERST_R_N")
	)
	(segment
		(start 372.48846 -27.802078)
		(end 369.543584 -27.802078)
		(width 0.15494)
		(layer "In5.Cu")
		(net "RST_SSD12_PERST_R_N")
	)
	(segment
		(start 372.13794 -29.959046)
		(end 372.921022 -29.175964)
		(width 0.15494)
		(layer "In5.Cu")
		(net "RST_SSD12_PERST_R_N")
	)
	(segment
		(start 382.519682 -90.879422)
		(end 382.519682 -78.859126)
		(width 0.15494)
		(layer "In5.Cu")
		(net "RST_SSD12_PERST_R_N")
	)
	(segment
		(start 373.262652 -105.86593)
		(end 373.526304 -105.602278)
		(width 0.15494)
		(layer "In5.Cu")
		(net "RST_SSD12_PERST_R_N")
	)
	(segment
		(start 372.921022 -29.175964)
		(end 372.921022 -28.23464)
		(width 0.15494)
		(layer "In5.Cu")
		(net "RST_SSD12_PERST_R_N")
	)
	(segment
		(start 362.889038 -24.575008)
		(end 362.503974 -24.189944)
		(width 0.15494)
		(layer "In5.Cu")
		(net "RST_SSD12_PERST_R_N")
	)
	(segment
		(start 372.921022 -28.23464)
		(end 372.48846 -27.802078)
		(width 0.15494)
		(layer "In5.Cu")
		(net "RST_SSD12_PERST_R_N")
	)
	(segment
		(start 369.543584 -27.802078)
		(end 368.615214 -26.873708)
		(width 0.15494)
		(layer "In5.Cu")
		(net "RST_SSD12_PERST_R_N")
	)
	(segment
		(start 379.626368 -75.965812)
		(end 379.626368 -68.817998)
		(width 0.15494)
		(layer "In5.Cu")
		(net "RST_SSD12_PERST_R_N")
	)
	(segment
		(start 382.519682 -78.859126)
		(end 379.626368 -75.965812)
		(width 0.15494)
		(layer "In5.Cu")
		(net "RST_SSD12_PERST_R_N")
	)
	(segment
		(start 385.00939 -63.434976)
		(end 385.00939 -45.566584)
		(width 0.15494)
		(layer "In5.Cu")
		(net "RST_SSD12_PERST_R_N")
	)
	(segment
		(start 368.615214 -26.873708)
		(end 367.227104 -26.873708)
		(width 0.15494)
		(layer "In5.Cu")
		(net "RST_SSD12_PERST_R_N")
	)
	(segment
		(start 373.526304 -105.602278)
		(end 373.526304 -99.8728)
		(width 0.15494)
		(layer "In5.Cu")
		(net "RST_SSD12_PERST_R_N")
	)
	(segment
		(start 379.626368 -68.817998)
		(end 385.00939 -63.434976)
		(width 0.15494)
		(layer "In5.Cu")
		(net "RST_SSD12_PERST_R_N")
	)
	(segment
		(start 385.00939 -45.566584)
		(end 372.13794 -32.695134)
		(width 0.15494)
		(layer "In5.Cu")
		(net "RST_SSD12_PERST_R_N")
	)
	(segment
		(start 367.227104 -26.873708)
		(end 364.928404 -24.575008)
		(width 0.15494)
		(layer "In5.Cu")
		(net "RST_SSD12_PERST_R_N")
	)
	(segment
		(start 372.13794 -32.695134)
		(end 372.13794 -29.959046)
		(width 0.15494)
		(layer "In5.Cu")
		(net "RST_SSD12_PERST_R_N")
	)
	(segment
		(start 342.417654 -202.7428)
		(end 340.944454 -204.216)
		(width 0.15494)
		(layer "In9.Cu")
		(net "RST_SSD12_PERST_R_N")
	)
	(segment
		(start 353.128834 -106.064812)
		(end 350.8248 -108.368846)
		(width 0.15494)
		(layer "In9.Cu")
		(net "RST_SSD12_PERST_R_N")
	)
	(segment
		(start 343.1286 -202.565)
		(end 342.9508 -202.7428)
		(width 0.15494)
		(layer "In9.Cu")
		(net "RST_SSD12_PERST_R_N")
	)
	(segment
		(start 343.1286 -199.8726)
		(end 343.1286 -202.565)
		(width 0.15494)
		(layer "In9.Cu")
		(net "RST_SSD12_PERST_R_N")
	)
	(segment
		(start 342.9508 -202.7428)
		(end 342.417654 -202.7428)
		(width 0.15494)
		(layer "In9.Cu")
		(net "RST_SSD12_PERST_R_N")
	)
	(segment
		(start 343.4842 -199.517)
		(end 343.1286 -199.8726)
		(width 0.15494)
		(layer "In9.Cu")
		(net "RST_SSD12_PERST_R_N")
	)
	(segment
		(start 350.8248 -108.368846)
		(end 350.8248 -122.1232)
		(width 0.15494)
		(layer "In9.Cu")
		(net "RST_SSD12_PERST_R_N")
	)
	(segment
		(start 343.4842 -191.6684)
		(end 343.4842 -199.517)
		(width 0.15494)
		(layer "In9.Cu")
		(net "RST_SSD12_PERST_R_N")
	)
	(segment
		(start 350.8248 -122.1232)
		(end 348.97568 -123.97232)
		(width 0.15494)
		(layer "In9.Cu")
		(net "RST_SSD12_PERST_R_N")
	)
	(segment
		(start 340.944454 -204.216)
		(end 340.614 -204.216)
		(width 0.15494)
		(layer "In9.Cu")
		(net "RST_SSD12_PERST_R_N")
	)
	(segment
		(start 348.97568 -139.59713)
		(end 347.94698 -140.62583)
		(width 0.15494)
		(layer "In9.Cu")
		(net "RST_SSD12_PERST_R_N")
	)
	(segment
		(start 347.94698 -187.20562)
		(end 343.4842 -191.6684)
		(width 0.15494)
		(layer "In9.Cu")
		(net "RST_SSD12_PERST_R_N")
	)
	(segment
		(start 347.94698 -140.62583)
		(end 347.94698 -187.20562)
		(width 0.15494)
		(layer "In9.Cu")
		(net "RST_SSD12_PERST_R_N")
	)
	(segment
		(start 348.97568 -123.97232)
		(end 348.97568 -139.59713)
		(width 0.15494)
		(layer "In9.Cu")
		(net "RST_SSD12_PERST_R_N")
	)
	(segment
		(start 373.262652 -105.86593)
		(end 361.670854 -105.86593)
		(width 0.15494)
		(layer "In13.Cu")
		(net "RST_SSD12_PERST_R_N")
	)
	(segment
		(start 361.670854 -105.86593)
		(end 359.713784 -107.823)
		(width 0.15494)
		(layer "In13.Cu")
		(net "RST_SSD12_PERST_R_N")
	)
	(segment
		(start 357.067612 -106.064812)
		(end 353.128834 -106.064812)
		(width 0.15494)
		(layer "In13.Cu")
		(net "RST_SSD12_PERST_R_N")
	)
	(segment
		(start 359.713784 -107.823)
		(end 358.8258 -107.823)
		(width 0.15494)
		(layer "In13.Cu")
		(net "RST_SSD12_PERST_R_N")
	)
	(segment
		(start 358.8258 -107.823)
		(end 357.067612 -106.064812)
		(width 0.15494)
		(layer "In13.Cu")
		(net "RST_SSD12_PERST_R_N")
	)
	(segment
		(start 342.893904 -215.187022)
		(end 343.2937 -214.787226)
		(width 0.13208)
		(layer "F.Cu")
		(net "FM_PFR_LED_BLUE")
	)
	(segment
		(start 353.196398 -205.550516)
		(end 353.32416 -205.678278)
		(width 0.13208)
		(layer "F.Cu")
		(net "FM_PFR_LED_BLUE")
	)
	(segment
		(start 353.32416 -205.678278)
		(end 353.32416 -206.254858)
		(width 0.13208)
		(layer "F.Cu")
		(net "FM_PFR_LED_BLUE")
	)
	(via
		(at 343.2937 -214.787226)
		(size 0.4572)
		(drill 0.254)
		(layers "F.Cu" "B.Cu")
		(net "FM_PFR_LED_BLUE")
	)
	(via
		(at 353.32416 -206.254858)
		(size 0.508)
		(drill 0.254)
		(layers "F.Cu" "B.Cu")
		(net "FM_PFR_LED_BLUE")
	)
	(segment
		(start 343.69121 -214.389716)
		(end 343.69121 -211.196936)
		(width 0.0889)
		(layer "In9.Cu")
		(net "FM_PFR_LED_BLUE")
	)
	(segment
		(start 347.340174 -207.547972)
		(end 352.031046 -207.547972)
		(width 0.15494)
		(layer "In9.Cu")
		(net "FM_PFR_LED_BLUE")
	)
	(segment
		(start 352.031046 -207.547972)
		(end 353.32416 -206.254858)
		(width 0.15494)
		(layer "In9.Cu")
		(net "FM_PFR_LED_BLUE")
	)
	(segment
		(start 343.2937 -214.787226)
		(end 343.69121 -214.389716)
		(width 0.0889)
		(layer "In9.Cu")
		(net "FM_PFR_LED_BLUE")
	)
	(segment
		(start 343.69121 -211.196936)
		(end 347.340174 -207.547972)
		(width 0.15494)
		(layer "In9.Cu")
		(net "FM_PFR_LED_BLUE")
	)
	(segment
		(start 198.391018 -37.774118)
		(end 199.946768 -37.774118)
		(width 0.13208)
		(layer "F.Cu")
		(net "PRSNT_SSD7_R1_N")
	)
	(segment
		(start 199.946768 -37.774118)
		(end 200.49363 -37.774118)
		(width 0.13208)
		(layer "F.Cu")
		(net "PRSNT_SSD7_R1_N")
	)
	(segment
		(start 200.49363 -37.774118)
		(end 200.675748 -37.592)
		(width 0.13208)
		(layer "F.Cu")
		(net "PRSNT_SSD7_R1_N")
	)
	(segment
		(start 197.997826 -38.937184)
		(end 197.997826 -38.16731)
		(width 0.13208)
		(layer "F.Cu")
		(net "PRSNT_SSD7_R1_N")
	)
	(segment
		(start 197.997826 -38.16731)
		(end 198.391018 -37.774118)
		(width 0.13208)
		(layer "F.Cu")
		(net "PRSNT_SSD7_R1_N")
	)
	(segment
		(start 200.675748 -37.592)
		(end 200.675748 -37.315648)
		(width 0.13208)
		(layer "F.Cu")
		(net "PRSNT_SSD7_R1_N")
	)
	(via
		(at 199.946768 -37.774118)
		(size 0.508)
		(drill 0.254)
		(layers "F.Cu" "B.Cu")
		(net "PRSNT_SSD7_R1_N")
	)
	(segment
		(start 164.349938 -297.79976)
		(end 163.874958 -298.27474)
		(width 0.249936)
		(layer "F.Cu")
		(net "SYSPLL_VDDA18_PEX1")
	)
	(via
		(at 147.819618 -280.693114)
		(size 0.508)
		(drill 0.254)
		(layers "F.Cu" "B.Cu")
		(net "SYSPLL_VDDA18_PEX1")
	)
	(via
		(at 163.874958 -298.27474)
		(size 0.4064)
		(drill 0.2032)
		(layers "F.Cu" "B.Cu")
		(net "SYSPLL_VDDA18_PEX1")
	)
	(via
		(at 149.216618 -280.693114)
		(size 0.508)
		(drill 0.254)
		(layers "F.Cu" "B.Cu")
		(net "SYSPLL_VDDA18_PEX1")
	)
	(segment
		(start 163.0553 -298.4246)
		(end 163.725098 -298.4246)
		(width 0.3048)
		(layer "B.Cu")
		(net "SYSPLL_VDDA18_PEX1")
	)
	(segment
		(start 163.725098 -298.4246)
		(end 163.874958 -298.27474)
		(width 0.3048)
		(layer "B.Cu")
		(net "SYSPLL_VDDA18_PEX1")
	)
	(segment
		(start 350.255078 -159.508952)
		(end 349.911416 -159.508952)
		(width 0.13208)
		(layer "F.Cu")
		(net "PCA9555_0_PEX3_A0")
	)
	(segment
		(start 351.876614 -159.508952)
		(end 350.255078 -159.508952)
		(width 0.13208)
		(layer "F.Cu")
		(net "PCA9555_0_PEX3_A0")
	)
	(segment
		(start 351.919794 -158.417768)
		(end 351.919794 -159.465264)
		(width 0.13208)
		(layer "F.Cu")
		(net "PCA9555_0_PEX3_A0")
	)
	(segment
		(start 351.920048 -159.465518)
		(end 351.876614 -159.508952)
		(width 0.13208)
		(layer "F.Cu")
		(net "PCA9555_0_PEX3_A0")
	)
	(segment
		(start 351.919794 -159.465264)
		(end 351.920048 -159.465518)
		(width 0.13208)
		(layer "F.Cu")
		(net "PCA9555_0_PEX3_A0")
	)
	(segment
		(start 349.911416 -159.508952)
		(end 349.807276 -159.613092)
		(width 0.13208)
		(layer "F.Cu")
		(net "PCA9555_0_PEX3_A0")
	)
	(segment
		(start 349.807276 -159.613092)
		(end 349.000064 -159.613092)
		(width 0.13208)
		(layer "F.Cu")
		(net "PCA9555_0_PEX3_A0")
	)
	(via
		(at 350.255078 -159.508952)
		(size 0.508)
		(drill 0.254)
		(layers "F.Cu" "B.Cu")
		(net "PCA9555_0_PEX3_A0")
	)
	(segment
		(start 176.945798 -178.361848)
		(end 177.746406 -178.361848)
		(width 0.13208)
		(layer "F.Cu")
		(net "NIC2_CLK_EN_R_N")
	)
	(segment
		(start 176.61636 -178.691286)
		(end 176.945798 -178.361848)
		(width 0.13208)
		(layer "F.Cu")
		(net "NIC2_CLK_EN_R_N")
	)
	(segment
		(start 358.41305 -224.536)
		(end 359.029 -224.536)
		(width 0.13208)
		(layer "F.Cu")
		(net "NIC2_CLK_EN_R_N")
	)
	(segment
		(start 174.936912 -178.691286)
		(end 176.61636 -178.691286)
		(width 0.13208)
		(layer "F.Cu")
		(net "NIC2_CLK_EN_R_N")
	)
	(segment
		(start 177.746406 -178.361848)
		(end 178.7144 -178.361848)
		(width 0.13208)
		(layer "F.Cu")
		(net "NIC2_CLK_EN_R_N")
	)
	(via
		(at 295.598596 -181.190138)
		(size 0.508)
		(drill 0.254)
		(layers "F.Cu" "B.Cu")
		(net "NIC2_CLK_EN_R_N")
	)
	(via
		(at 359.029 -224.536)
		(size 0.508)
		(drill 0.254)
		(layers "F.Cu" "B.Cu")
		(net "NIC2_CLK_EN_R_N")
	)
	(via
		(at 178.7144 -178.361848)
		(size 0.508)
		(drill 0.254)
		(layers "F.Cu" "B.Cu")
		(net "NIC2_CLK_EN_R_N")
	)
	(segment
		(start 178.042316 -178.09718)
		(end 178.042316 -176.184814)
		(width 0.15494)
		(layer "In13.Cu")
		(net "NIC2_CLK_EN_R_N")
	)
	(segment
		(start 263.65073 -169.4942)
		(end 271.98193 -177.8254)
		(width 0.15494)
		(layer "In13.Cu")
		(net "NIC2_CLK_EN_R_N")
	)
	(segment
		(start 271.98193 -177.8254)
		(end 292.233858 -177.8254)
		(width 0.15494)
		(layer "In13.Cu")
		(net "NIC2_CLK_EN_R_N")
	)
	(segment
		(start 247.7262 -170.6372)
		(end 248.8692 -169.4942)
		(width 0.15494)
		(layer "In13.Cu")
		(net "NIC2_CLK_EN_R_N")
	)
	(segment
		(start 178.910234 -175.316896)
		(end 209.34045 -175.316896)
		(width 0.15494)
		(layer "In13.Cu")
		(net "NIC2_CLK_EN_R_N")
	)
	(segment
		(start 178.042316 -176.184814)
		(end 178.910234 -175.316896)
		(width 0.15494)
		(layer "In13.Cu")
		(net "NIC2_CLK_EN_R_N")
	)
	(segment
		(start 213.082378 -171.574968)
		(end 229.516432 -171.574968)
		(width 0.15494)
		(layer "In13.Cu")
		(net "NIC2_CLK_EN_R_N")
	)
	(segment
		(start 292.233858 -177.8254)
		(end 295.598596 -181.190138)
		(width 0.15494)
		(layer "In13.Cu")
		(net "NIC2_CLK_EN_R_N")
	)
	(segment
		(start 248.8692 -169.4942)
		(end 263.65073 -169.4942)
		(width 0.15494)
		(layer "In13.Cu")
		(net "NIC2_CLK_EN_R_N")
	)
	(segment
		(start 230.4542 -170.6372)
		(end 247.7262 -170.6372)
		(width 0.15494)
		(layer "In13.Cu")
		(net "NIC2_CLK_EN_R_N")
	)
	(segment
		(start 178.7144 -178.361848)
		(end 178.306984 -178.361848)
		(width 0.15494)
		(layer "In13.Cu")
		(net "NIC2_CLK_EN_R_N")
	)
	(segment
		(start 229.516432 -171.574968)
		(end 230.4542 -170.6372)
		(width 0.15494)
		(layer "In13.Cu")
		(net "NIC2_CLK_EN_R_N")
	)
	(segment
		(start 178.306984 -178.361848)
		(end 178.042316 -178.09718)
		(width 0.15494)
		(layer "In13.Cu")
		(net "NIC2_CLK_EN_R_N")
	)
	(segment
		(start 209.34045 -175.316896)
		(end 213.082378 -171.574968)
		(width 0.15494)
		(layer "In13.Cu")
		(net "NIC2_CLK_EN_R_N")
	)
	(segment
		(start 359.029 -224.536)
		(end 360.168952 -224.536)
		(width 0.15494)
		(layer "In15.Cu")
		(net "NIC2_CLK_EN_R_N")
	)
	(segment
		(start 361.0356 -223.669352)
		(end 361.0356 -223.412558)
		(width 0.15494)
		(layer "In15.Cu")
		(net "NIC2_CLK_EN_R_N")
	)
	(segment
		(start 363.30001 -200.417176)
		(end 361.19308 -198.310246)
		(width 0.15494)
		(layer "In15.Cu")
		(net "NIC2_CLK_EN_R_N")
	)
	(segment
		(start 347.622114 -182.242968)
		(end 346.449396 -181.07025)
		(width 0.15494)
		(layer "In15.Cu")
		(net "NIC2_CLK_EN_R_N")
	)
	(segment
		(start 360.168952 -224.536)
		(end 361.0356 -223.669352)
		(width 0.15494)
		(layer "In15.Cu")
		(net "NIC2_CLK_EN_R_N")
	)
	(segment
		(start 362.66374 -219.481654)
		(end 362.66374 -217.344244)
		(width 0.15494)
		(layer "In15.Cu")
		(net "NIC2_CLK_EN_R_N")
	)
	(segment
		(start 333.555086 -181.190138)
		(end 295.598596 -181.190138)
		(width 0.15494)
		(layer "In15.Cu")
		(net "NIC2_CLK_EN_R_N")
	)
	(segment
		(start 333.823818 -181.45887)
		(end 333.555086 -181.190138)
		(width 0.15494)
		(layer "In15.Cu")
		(net "NIC2_CLK_EN_R_N")
	)
	(segment
		(start 363.30001 -216.707974)
		(end 363.30001 -200.417176)
		(width 0.15494)
		(layer "In15.Cu")
		(net "NIC2_CLK_EN_R_N")
	)
	(segment
		(start 361.19308 -198.310246)
		(end 361.19308 -189.56655)
		(width 0.15494)
		(layer "In15.Cu")
		(net "NIC2_CLK_EN_R_N")
	)
	(segment
		(start 337.69554 -181.07025)
		(end 337.30692 -181.45887)
		(width 0.15494)
		(layer "In15.Cu")
		(net "NIC2_CLK_EN_R_N")
	)
	(segment
		(start 362.66374 -217.344244)
		(end 363.30001 -216.707974)
		(width 0.15494)
		(layer "In15.Cu")
		(net "NIC2_CLK_EN_R_N")
	)
	(segment
		(start 359.91927 -188.70168)
		(end 353.460558 -182.242968)
		(width 0.15494)
		(layer "In15.Cu")
		(net "NIC2_CLK_EN_R_N")
	)
	(segment
		(start 337.30692 -181.45887)
		(end 333.823818 -181.45887)
		(width 0.15494)
		(layer "In15.Cu")
		(net "NIC2_CLK_EN_R_N")
	)
	(segment
		(start 361.19308 -189.56655)
		(end 360.32821 -188.70168)
		(width 0.15494)
		(layer "In15.Cu")
		(net "NIC2_CLK_EN_R_N")
	)
	(segment
		(start 360.32821 -188.70168)
		(end 359.91927 -188.70168)
		(width 0.15494)
		(layer "In15.Cu")
		(net "NIC2_CLK_EN_R_N")
	)
	(segment
		(start 361.0356 -223.412558)
		(end 362.66374 -219.481654)
		(width 0.15494)
		(layer "In15.Cu")
		(net "NIC2_CLK_EN_R_N")
	)
	(segment
		(start 346.449396 -181.07025)
		(end 337.69554 -181.07025)
		(width 0.15494)
		(layer "In15.Cu")
		(net "NIC2_CLK_EN_R_N")
	)
	(segment
		(start 353.460558 -182.242968)
		(end 347.622114 -182.242968)
		(width 0.15494)
		(layer "In15.Cu")
		(net "NIC2_CLK_EN_R_N")
	)
	(segment
		(start 341.63 -204.83195)
		(end 341.63 -204.216)
		(width 0.13208)
		(layer "F.Cu")
		(net "RST_SSD13_PERST_R_N")
	)
	(segment
		(start 388.503922 -24.189944)
		(end 389.56488 -24.189944)
		(width 0.13208)
		(layer "F.Cu")
		(net "RST_SSD13_PERST_R_N")
	)
	(via
		(at 404.994364 -89.149936)
		(size 0.508)
		(drill 0.254)
		(layers "F.Cu" "B.Cu")
		(net "RST_SSD13_PERST_R_N")
	)
	(via
		(at 341.63 -204.216)
		(size 0.508)
		(drill 0.254)
		(layers "F.Cu" "B.Cu")
		(net "RST_SSD13_PERST_R_N")
	)
	(via
		(at 388.503922 -24.189944)
		(size 0.508)
		(drill 0.254)
		(layers "F.Cu" "B.Cu")
		(net "RST_SSD13_PERST_R_N")
	)
	(via
		(at 356.353872 -99.104958)
		(size 0.508)
		(drill 0.254)
		(layers "F.Cu" "B.Cu")
		(net "RST_SSD13_PERST_R_N")
	)
	(segment
		(start 404.620476 -69.945758)
		(end 411.049978 -63.516256)
		(width 0.15494)
		(layer "In5.Cu")
		(net "RST_SSD13_PERST_R_N")
	)
	(segment
		(start 392.158728 -25.801828)
		(end 390.931908 -24.575008)
		(width 0.15494)
		(layer "In5.Cu")
		(net "RST_SSD13_PERST_R_N")
	)
	(segment
		(start 341.167212 -203.257404)
		(end 341.167212 -202.79614)
		(width 0.15494)
		(layer "In5.Cu")
		(net "RST_SSD13_PERST_R_N")
	)
	(segment
		(start 341.012018 -184.124346)
		(end 341.012018 -183.708294)
		(width 0.15494)
		(layer "In5.Cu")
		(net "RST_SSD13_PERST_R_N")
	)
	(segment
		(start 340.125304 -201.754232)
		(end 340.125304 -199.618854)
		(width 0.15494)
		(layer "In5.Cu")
		(net "RST_SSD13_PERST_R_N")
	)
	(segment
		(start 341.63 -203.720192)
		(end 341.167212 -203.257404)
		(width 0.15494)
		(layer "In5.Cu")
		(net "RST_SSD13_PERST_R_N")
	)
	(segment
		(start 340.329774 -183.02605)
		(end 340.329774 -181.615842)
		(width 0.15494)
		(layer "In5.Cu")
		(net "RST_SSD13_PERST_R_N")
	)
	(segment
		(start 398.137888 -29.920946)
		(end 398.96161 -29.097224)
		(width 0.15494)
		(layer "In5.Cu")
		(net "RST_SSD13_PERST_R_N")
	)
	(segment
		(start 398.96161 -29.097224)
		(end 398.96161 -28.28798)
		(width 0.15494)
		(layer "In5.Cu")
		(net "RST_SSD13_PERST_R_N")
	)
	(segment
		(start 341.167212 -202.79614)
		(end 340.125304 -201.754232)
		(width 0.15494)
		(layer "In5.Cu")
		(net "RST_SSD13_PERST_R_N")
	)
	(segment
		(start 392.71702 -26.637742)
		(end 392.158728 -25.801828)
		(width 0.15494)
		(layer "In5.Cu")
		(net "RST_SSD13_PERST_R_N")
	)
	(segment
		(start 350.207072 -115.43157)
		(end 356.6033 -109.035342)
		(width 0.15494)
		(layer "In5.Cu")
		(net "RST_SSD13_PERST_R_N")
	)
	(segment
		(start 346.242894 -127.18796)
		(end 350.207072 -123.223782)
		(width 0.15494)
		(layer "In5.Cu")
		(net "RST_SSD13_PERST_R_N")
	)
	(segment
		(start 404.994364 -89.149936)
		(end 405.877776 -88.266524)
		(width 0.15494)
		(layer "In5.Cu")
		(net "RST_SSD13_PERST_R_N")
	)
	(segment
		(start 356.6033 -99.354386)
		(end 356.353872 -99.104958)
		(width 0.15494)
		(layer "In5.Cu")
		(net "RST_SSD13_PERST_R_N")
	)
	(segment
		(start 390.931908 -24.575008)
		(end 388.888986 -24.575008)
		(width 0.15494)
		(layer "In5.Cu")
		(net "RST_SSD13_PERST_R_N")
	)
	(segment
		(start 405.877776 -85.375496)
		(end 404.620476 -84.118196)
		(width 0.15494)
		(layer "In5.Cu")
		(net "RST_SSD13_PERST_R_N")
	)
	(segment
		(start 340.617302 -199.126856)
		(end 340.617302 -184.519062)
		(width 0.15494)
		(layer "In5.Cu")
		(net "RST_SSD13_PERST_R_N")
	)
	(segment
		(start 340.329774 -181.615842)
		(end 346.242894 -175.702722)
		(width 0.15494)
		(layer "In5.Cu")
		(net "RST_SSD13_PERST_R_N")
	)
	(segment
		(start 340.617302 -184.519062)
		(end 341.012018 -184.124346)
		(width 0.15494)
		(layer "In5.Cu")
		(net "RST_SSD13_PERST_R_N")
	)
	(segment
		(start 411.049978 -45.480224)
		(end 398.137888 -32.568134)
		(width 0.15494)
		(layer "In5.Cu")
		(net "RST_SSD13_PERST_R_N")
	)
	(segment
		(start 405.877776 -88.266524)
		(end 405.877776 -85.375496)
		(width 0.15494)
		(layer "In5.Cu")
		(net "RST_SSD13_PERST_R_N")
	)
	(segment
		(start 398.255236 -27.581606)
		(end 395.136116 -27.581606)
		(width 0.15494)
		(layer "In5.Cu")
		(net "RST_SSD13_PERST_R_N")
	)
	(segment
		(start 346.242894 -175.702722)
		(end 346.242894 -127.18796)
		(width 0.15494)
		(layer "In5.Cu")
		(net "RST_SSD13_PERST_R_N")
	)
	(segment
		(start 393.156186 -26.873708)
		(end 392.71702 -26.637742)
		(width 0.15494)
		(layer "In5.Cu")
		(net "RST_SSD13_PERST_R_N")
	)
	(segment
		(start 411.049978 -63.516256)
		(end 411.049978 -45.480224)
		(width 0.15494)
		(layer "In5.Cu")
		(net "RST_SSD13_PERST_R_N")
	)
	(segment
		(start 398.137888 -32.568134)
		(end 398.137888 -29.920946)
		(width 0.15494)
		(layer "In5.Cu")
		(net "RST_SSD13_PERST_R_N")
	)
	(segment
		(start 398.96161 -28.28798)
		(end 398.255236 -27.581606)
		(width 0.15494)
		(layer "In5.Cu")
		(net "RST_SSD13_PERST_R_N")
	)
	(segment
		(start 341.012018 -183.708294)
		(end 340.329774 -183.02605)
		(width 0.15494)
		(layer "In5.Cu")
		(net "RST_SSD13_PERST_R_N")
	)
	(segment
		(start 395.136116 -27.581606)
		(end 394.428218 -26.873708)
		(width 0.15494)
		(layer "In5.Cu")
		(net "RST_SSD13_PERST_R_N")
	)
	(segment
		(start 356.6033 -109.035342)
		(end 356.6033 -99.354386)
		(width 0.15494)
		(layer "In5.Cu")
		(net "RST_SSD13_PERST_R_N")
	)
	(segment
		(start 394.428218 -26.873708)
		(end 393.156186 -26.873708)
		(width 0.15494)
		(layer "In5.Cu")
		(net "RST_SSD13_PERST_R_N")
	)
	(segment
		(start 340.125304 -199.618854)
		(end 340.617302 -199.126856)
		(width 0.15494)
		(layer "In5.Cu")
		(net "RST_SSD13_PERST_R_N")
	)
	(segment
		(start 341.63 -204.216)
		(end 341.63 -203.720192)
		(width 0.15494)
		(layer "In5.Cu")
		(net "RST_SSD13_PERST_R_N")
	)
	(segment
		(start 388.888986 -24.575008)
		(end 388.503922 -24.189944)
		(width 0.15494)
		(layer "In5.Cu")
		(net "RST_SSD13_PERST_R_N")
	)
	(segment
		(start 350.207072 -123.223782)
		(end 350.207072 -115.43157)
		(width 0.15494)
		(layer "In5.Cu")
		(net "RST_SSD13_PERST_R_N")
	)
	(segment
		(start 404.620476 -84.118196)
		(end 404.620476 -69.945758)
		(width 0.15494)
		(layer "In5.Cu")
		(net "RST_SSD13_PERST_R_N")
	)
	(segment
		(start 391.896346 -93.7768)
		(end 384.378454 -93.7768)
		(width 0.15494)
		(layer "In15.Cu")
		(net "RST_SSD13_PERST_R_N")
	)
	(segment
		(start 368.194082 -99.2886)
		(end 357.23703 -99.2886)
		(width 0.15494)
		(layer "In15.Cu")
		(net "RST_SSD13_PERST_R_N")
	)
	(segment
		(start 400.2024 -91.694)
		(end 393.979146 -91.694)
		(width 0.15494)
		(layer "In15.Cu")
		(net "RST_SSD13_PERST_R_N")
	)
	(segment
		(start 369.464082 -98.0186)
		(end 368.194082 -99.2886)
		(width 0.15494)
		(layer "In15.Cu")
		(net "RST_SSD13_PERST_R_N")
	)
	(segment
		(start 357.053388 -99.104958)
		(end 356.353872 -99.104958)
		(width 0.15494)
		(layer "In15.Cu")
		(net "RST_SSD13_PERST_R_N")
	)
	(segment
		(start 404.994364 -89.149936)
		(end 402.746464 -89.149936)
		(width 0.15494)
		(layer "In15.Cu")
		(net "RST_SSD13_PERST_R_N")
	)
	(segment
		(start 357.23703 -99.2886)
		(end 357.053388 -99.104958)
		(width 0.15494)
		(layer "In15.Cu")
		(net "RST_SSD13_PERST_R_N")
	)
	(segment
		(start 393.979146 -91.694)
		(end 391.896346 -93.7768)
		(width 0.15494)
		(layer "In15.Cu")
		(net "RST_SSD13_PERST_R_N")
	)
	(segment
		(start 380.136654 -98.0186)
		(end 369.464082 -98.0186)
		(width 0.15494)
		(layer "In15.Cu")
		(net "RST_SSD13_PERST_R_N")
	)
	(segment
		(start 384.378454 -93.7768)
		(end 380.136654 -98.0186)
		(width 0.15494)
		(layer "In15.Cu")
		(net "RST_SSD13_PERST_R_N")
	)
	(segment
		(start 402.746464 -89.149936)
		(end 400.2024 -91.694)
		(width 0.15494)
		(layer "In15.Cu")
		(net "RST_SSD13_PERST_R_N")
	)
	(segment
		(start 229.108 -205.105254)
		(end 228.844856 -204.84211)
		(width 0.13208)
		(layer "F.Cu")
		(net "BIC_SEL_FLASH_SW3")
	)
	(segment
		(start 229.108 -205.607158)
		(end 229.108 -205.105254)
		(width 0.13208)
		(layer "F.Cu")
		(net "BIC_SEL_FLASH_SW3")
	)
	(segment
		(start 228.844856 -204.84211)
		(end 228.578664 -204.84211)
		(width 0.13208)
		(layer "F.Cu")
		(net "BIC_SEL_FLASH_SW3")
	)
	(segment
		(start 229.02926 -209.727546)
		(end 229.02672 -209.725006)
		(width 0.13208)
		(layer "F.Cu")
		(net "BIC_SEL_FLASH_SW3")
	)
	(segment
		(start 229.02926 -211.579206)
		(end 229.02926 -209.727546)
		(width 0.13208)
		(layer "F.Cu")
		(net "BIC_SEL_FLASH_SW3")
	)
	(segment
		(start 229.02672 -205.688438)
		(end 229.108 -205.607158)
		(width 0.13208)
		(layer "F.Cu")
		(net "BIC_SEL_FLASH_SW3")
	)
	(segment
		(start 229.02672 -209.725006)
		(end 229.02672 -205.688438)
		(width 0.13208)
		(layer "F.Cu")
		(net "BIC_SEL_FLASH_SW3")
	)
	(segment
		(start 229.867714 -212.41766)
		(end 229.02926 -211.579206)
		(width 0.13208)
		(layer "F.Cu")
		(net "BIC_SEL_FLASH_SW3")
	)
	(segment
		(start 229.867714 -212.704172)
		(end 229.867714 -212.41766)
		(width 0.13208)
		(layer "F.Cu")
		(net "BIC_SEL_FLASH_SW3")
	)
	(via
		(at 229.02926 -209.727546)
		(size 0.762)
		(drill 0.381)
		(layers "F.Cu" "B.Cu")
		(net "BIC_SEL_FLASH_SW3")
	)
	(segment
		(start 170.9928 -34.431224)
		(end 170.9928 -33.945576)
		(width 0.13208)
		(layer "F.Cu")
		(net "SSD6_AUX_P3V3_EN_R")
	)
	(segment
		(start 170.956224 -33.909)
		(end 170.956224 -33.248092)
		(width 0.13208)
		(layer "F.Cu")
		(net "SSD6_AUX_P3V3_EN_R")
	)
	(segment
		(start 170.956224 -34.4678)
		(end 170.9928 -34.431224)
		(width 0.13208)
		(layer "F.Cu")
		(net "SSD6_AUX_P3V3_EN_R")
	)
	(segment
		(start 168.37787 -37.84092)
		(end 168.690036 -37.529516)
		(width 0.13208)
		(layer "F.Cu")
		(net "SSD6_AUX_P3V3_EN_R")
	)
	(segment
		(start 170.956224 -36.874958)
		(end 170.956224 -34.4678)
		(width 0.13208)
		(layer "F.Cu")
		(net "SSD6_AUX_P3V3_EN_R")
	)
	(segment
		(start 169.22623 -37.529516)
		(end 170.302682 -37.529516)
		(width 0.13208)
		(layer "F.Cu")
		(net "SSD6_AUX_P3V3_EN_R")
	)
	(segment
		(start 168.690036 -37.529516)
		(end 169.22623 -37.529516)
		(width 0.13208)
		(layer "F.Cu")
		(net "SSD6_AUX_P3V3_EN_R")
	)
	(segment
		(start 172.81525 -59.100974)
		(end 173.84014 -58.076084)
		(width 0.13208)
		(layer "F.Cu")
		(net "SSD6_AUX_P3V3_EN_R")
	)
	(segment
		(start 172.81525 -59.146186)
		(end 172.81525 -59.100974)
		(width 0.13208)
		(layer "F.Cu")
		(net "SSD6_AUX_P3V3_EN_R")
	)
	(segment
		(start 170.9928 -33.945576)
		(end 170.956224 -33.909)
		(width 0.13208)
		(layer "F.Cu")
		(net "SSD6_AUX_P3V3_EN_R")
	)
	(segment
		(start 174.240952 -57.675272)
		(end 173.84014 -58.076084)
		(width 0.13208)
		(layer "F.Cu")
		(net "SSD6_AUX_P3V3_EN_R")
	)
	(segment
		(start 174.240952 -57.16397)
		(end 174.240952 -57.675272)
		(width 0.13208)
		(layer "F.Cu")
		(net "SSD6_AUX_P3V3_EN_R")
	)
	(segment
		(start 170.302682 -37.529516)
		(end 170.956224 -36.874958)
		(width 0.13208)
		(layer "F.Cu")
		(net "SSD6_AUX_P3V3_EN_R")
	)
	(segment
		(start 168.37787 -39.97198)
		(end 168.37787 -37.84092)
		(width 0.13208)
		(layer "F.Cu")
		(net "SSD6_AUX_P3V3_EN_R")
	)
	(via
		(at 173.84014 -58.076084)
		(size 0.508)
		(drill 0.254)
		(layers "F.Cu" "B.Cu")
		(net "SSD6_AUX_P3V3_EN_R")
	)
	(via
		(at 168.37787 -39.97198)
		(size 0.508)
		(drill 0.254)
		(layers "F.Cu" "B.Cu")
		(net "SSD6_AUX_P3V3_EN_R")
	)
	(segment
		(start 171.752514 -39.97198)
		(end 168.37787 -39.97198)
		(width 0.15494)
		(layer "In5.Cu")
		(net "SSD6_AUX_P3V3_EN_R")
	)
	(segment
		(start 177.56886 -54.347364)
		(end 177.56886 -45.788326)
		(width 0.15494)
		(layer "In5.Cu")
		(net "SSD6_AUX_P3V3_EN_R")
	)
	(segment
		(start 177.56886 -45.788326)
		(end 171.752514 -39.97198)
		(width 0.15494)
		(layer "In5.Cu")
		(net "SSD6_AUX_P3V3_EN_R")
	)
	(segment
		(start 173.84014 -58.076084)
		(end 177.56886 -54.347364)
		(width 0.15494)
		(layer "In5.Cu")
		(net "SSD6_AUX_P3V3_EN_R")
	)
	(segment
		(start 162.924998 -297.32478)
		(end 163.399978 -296.8498)
		(width 0.249936)
		(layer "F.Cu")
		(net "PCEPLL2_VDDA18_PEX1")
	)
	(via
		(at 162.924998 -297.32478)
		(size 0.4064)
		(drill 0.2032)
		(layers "F.Cu" "B.Cu")
		(net "PCEPLL2_VDDA18_PEX1")
	)
	(via
		(at 147.819618 -293.494714)
		(size 0.508)
		(drill 0.254)
		(layers "F.Cu" "B.Cu")
		(net "PCEPLL2_VDDA18_PEX1")
	)
	(via
		(at 149.216618 -293.494714)
		(size 0.508)
		(drill 0.254)
		(layers "F.Cu" "B.Cu")
		(net "PCEPLL2_VDDA18_PEX1")
	)
	(segment
		(start 162.924998 -297.32478)
		(end 162.7124 -297.32478)
		(width 0.3048)
		(layer "B.Cu")
		(net "PCEPLL2_VDDA18_PEX1")
	)
	(segment
		(start 162.7124 -296.37482)
		(end 162.7124 -297.32478)
		(width 0.3048)
		(layer "B.Cu")
		(net "PCEPLL2_VDDA18_PEX1")
	)
	(segment
		(start 207.451452 -310.761888)
		(end 207.451452 -311.004458)
		(width 0.13208)
		(layer "F.Cu")
		(net "PU_PEX1_SIO_BLINK")
	)
	(segment
		(start 207.451452 -311.004458)
		(end 207.047846 -311.408064)
		(width 0.13208)
		(layer "F.Cu")
		(net "PU_PEX1_SIO_BLINK")
	)
	(via
		(at 207.047846 -311.408064)
		(size 0.508)
		(drill 0.254)
		(layers "F.Cu" "B.Cu")
		(net "PU_PEX1_SIO_BLINK")
	)
	(via
		(at 206.35087 -312.10504)
		(size 0.6604)
		(drill 0.3302)
		(layers "F.Cu" "B.Cu")
		(net "PU_PEX1_SIO_BLINK")
	)
	(via
		(at 176.699926 -309.199788)
		(size 0.4064)
		(drill 0.2032)
		(layers "F.Cu" "B.Cu")
		(net "PU_PEX1_SIO_BLINK")
	)
	(segment
		(start 177.19548 -319.794636)
		(end 177.19548 -309.695342)
		(width 0.13208)
		(layer "B.Cu")
		(net "PU_PEX1_SIO_BLINK")
	)
	(segment
		(start 206.35087 -312.10504)
		(end 207.047846 -311.408064)
		(width 0.13208)
		(layer "B.Cu")
		(net "PU_PEX1_SIO_BLINK")
	)
	(segment
		(start 177.745644 -320.3448)
		(end 177.19548 -319.794636)
		(width 0.13208)
		(layer "B.Cu")
		(net "PU_PEX1_SIO_BLINK")
	)
	(segment
		(start 206.35087 -312.10504)
		(end 198.11111 -320.3448)
		(width 0.13208)
		(layer "B.Cu")
		(net "PU_PEX1_SIO_BLINK")
	)
	(segment
		(start 177.19548 -309.695342)
		(end 176.699926 -309.199788)
		(width 0.13208)
		(layer "B.Cu")
		(net "PU_PEX1_SIO_BLINK")
	)
	(segment
		(start 198.11111 -320.3448)
		(end 177.745644 -320.3448)
		(width 0.13208)
		(layer "B.Cu")
		(net "PU_PEX1_SIO_BLINK")
	)
	(segment
		(start 339.89137 -161.29)
		(end 340.492588 -160.688782)
		(width 0.13208)
		(layer "F.Cu")
		(net "PCA9555_0_PEX3_A2")
	)
	(segment
		(start 336.44205 -160.782)
		(end 337.67395 -160.782)
		(width 0.13208)
		(layer "F.Cu")
		(net "PCA9555_0_PEX3_A2")
	)
	(segment
		(start 340.918292 -160.263078)
		(end 343.149936 -160.263078)
		(width 0.13208)
		(layer "F.Cu")
		(net "PCA9555_0_PEX3_A2")
	)
	(segment
		(start 340.492588 -160.688782)
		(end 340.918292 -160.263078)
		(width 0.13208)
		(layer "F.Cu")
		(net "PCA9555_0_PEX3_A2")
	)
	(segment
		(start 337.67395 -160.782)
		(end 337.67395 -161.163)
		(width 0.13208)
		(layer "F.Cu")
		(net "PCA9555_0_PEX3_A2")
	)
	(segment
		(start 337.80095 -161.29)
		(end 339.89137 -161.29)
		(width 0.13208)
		(layer "F.Cu")
		(net "PCA9555_0_PEX3_A2")
	)
	(segment
		(start 337.67395 -161.163)
		(end 337.80095 -161.29)
		(width 0.13208)
		(layer "F.Cu")
		(net "PCA9555_0_PEX3_A2")
	)
	(via
		(at 340.492588 -160.688782)
		(size 0.508)
		(drill 0.254)
		(layers "F.Cu" "B.Cu")
		(net "PCA9555_0_PEX3_A2")
	)
	(segment
		(start 327.93305 -219.329)
		(end 328.676 -219.329)
		(width 0.13208)
		(layer "F.Cu")
		(net "PRSNT_SSD14_FPGA_N")
	)
	(segment
		(start 338.893912 -219.987114)
		(end 338.494116 -220.38691)
		(width 0.13208)
		(layer "F.Cu")
		(net "PRSNT_SSD14_FPGA_N")
	)
	(via
		(at 328.676 -219.329)
		(size 0.508)
		(drill 0.254)
		(layers "F.Cu" "B.Cu")
		(net "PRSNT_SSD14_FPGA_N")
	)
	(via
		(at 338.494116 -220.38691)
		(size 0.4572)
		(drill 0.254)
		(layers "F.Cu" "B.Cu")
		(net "PRSNT_SSD14_FPGA_N")
	)
	(segment
		(start 333.193898 -219.732352)
		(end 333.40929 -219.947744)
		(width 0.15494)
		(layer "In5.Cu")
		(net "PRSNT_SSD14_FPGA_N")
	)
	(segment
		(start 333.40929 -219.947744)
		(end 338.05495 -219.947744)
		(width 0.15494)
		(layer "In5.Cu")
		(net "PRSNT_SSD14_FPGA_N")
	)
	(segment
		(start 329.079352 -219.732352)
		(end 333.193898 -219.732352)
		(width 0.15494)
		(layer "In5.Cu")
		(net "PRSNT_SSD14_FPGA_N")
	)
	(segment
		(start 338.05495 -219.947744)
		(end 338.494116 -220.38691)
		(width 0.15494)
		(layer "In5.Cu")
		(net "PRSNT_SSD14_FPGA_N")
	)
	(segment
		(start 328.676 -219.329)
		(end 329.079352 -219.732352)
		(width 0.15494)
		(layer "In5.Cu")
		(net "PRSNT_SSD14_FPGA_N")
	)
	(segment
		(start 363.564932 -25.390094)
		(end 362.491274 -25.390094)
		(width 0.13208)
		(layer "F.Cu")
		(net "SSD12_PWRDIS_R")
	)
	(segment
		(start 372.434612 -28.469082)
		(end 372.434612 -28.550108)
		(width 0.13208)
		(layer "F.Cu")
		(net "SSD12_PWRDIS_R")
	)
	(segment
		(start 339.598 -204.83195)
		(end 339.598 -204.216)
		(width 0.13208)
		(layer "F.Cu")
		(net "SSD12_PWRDIS_R")
	)
	(segment
		(start 372.434612 -28.550108)
		(end 372.964456 -29.079952)
		(width 0.13208)
		(layer "F.Cu")
		(net "SSD12_PWRDIS_R")
	)
	(via
		(at 372.950486 -103.850694)
		(size 0.508)
		(drill 0.254)
		(layers "F.Cu" "B.Cu")
		(net "SSD12_PWRDIS_R")
	)
	(via
		(at 339.598 -204.216)
		(size 0.508)
		(drill 0.254)
		(layers "F.Cu" "B.Cu")
		(net "SSD12_PWRDIS_R")
	)
	(via
		(at 353.472242 -104.1146)
		(size 0.508)
		(drill 0.254)
		(layers "F.Cu" "B.Cu")
		(net "SSD12_PWRDIS_R")
	)
	(via
		(at 362.491274 -25.390094)
		(size 0.508)
		(drill 0.254)
		(layers "F.Cu" "B.Cu")
		(net "SSD12_PWRDIS_R")
	)
	(via
		(at 372.434612 -28.469082)
		(size 0.508)
		(drill 0.254)
		(layers "F.Cu" "B.Cu")
		(net "SSD12_PWRDIS_R")
	)
	(segment
		(start 343.510616 -141.509242)
		(end 345.066874 -139.952984)
		(width 0.15494)
		(layer "In5.Cu")
		(net "SSD12_PWRDIS_R")
	)
	(segment
		(start 353.750118 -104.392476)
		(end 353.472242 -104.1146)
		(width 0.15494)
		(layer "In5.Cu")
		(net "SSD12_PWRDIS_R")
	)
	(segment
		(start 353.750118 -106.172508)
		(end 353.750118 -104.392476)
		(width 0.15494)
		(layer "In5.Cu")
		(net "SSD12_PWRDIS_R")
	)
	(segment
		(start 338.058506 -199.499982)
		(end 338.680044 -198.878444)
		(width 0.15494)
		(layer "In5.Cu")
		(net "SSD12_PWRDIS_R")
	)
	(segment
		(start 337.1977 -188.81725)
		(end 337.905598 -188.109352)
		(width 0.15494)
		(layer "In5.Cu")
		(net "SSD12_PWRDIS_R")
	)
	(segment
		(start 342.627966 -175.311562)
		(end 342.627966 -173.946566)
		(width 0.15494)
		(layer "In5.Cu")
		(net "SSD12_PWRDIS_R")
	)
	(segment
		(start 384.54965 -63.09614)
		(end 384.54965 -45.757084)
		(width 0.15494)
		(layer "In5.Cu")
		(net "SSD12_PWRDIS_R")
	)
	(segment
		(start 338.680044 -198.878444)
		(end 338.680044 -196.54266)
		(width 0.15494)
		(layer "In5.Cu")
		(net "SSD12_PWRDIS_R")
	)
	(segment
		(start 384.54965 -45.757084)
		(end 371.6782 -32.885634)
		(width 0.15494)
		(layer "In5.Cu")
		(net "SSD12_PWRDIS_R")
	)
	(segment
		(start 343.510616 -173.063916)
		(end 343.510616 -141.509242)
		(width 0.15494)
		(layer "In5.Cu")
		(net "SSD12_PWRDIS_R")
	)
	(segment
		(start 372.950486 -103.850694)
		(end 372.950486 -99.780852)
		(width 0.15494)
		(layer "In5.Cu")
		(net "SSD12_PWRDIS_R")
	)
	(segment
		(start 372.950486 -99.780852)
		(end 382.059942 -90.671396)
		(width 0.15494)
		(layer "In5.Cu")
		(net "SSD12_PWRDIS_R")
	)
	(segment
		(start 345.066874 -126.70028)
		(end 349.031052 -122.736102)
		(width 0.15494)
		(layer "In5.Cu")
		(net "SSD12_PWRDIS_R")
	)
	(segment
		(start 362.84662 -25.034748)
		(end 364.737904 -25.034748)
		(width 0.15494)
		(layer "In5.Cu")
		(net "SSD12_PWRDIS_R")
	)
	(segment
		(start 338.680044 -196.54266)
		(end 337.1977 -195.060316)
		(width 0.15494)
		(layer "In5.Cu")
		(net "SSD12_PWRDIS_R")
	)
	(segment
		(start 352.250756 -111.703612)
		(end 352.250756 -106.960416)
		(width 0.15494)
		(layer "In5.Cu")
		(net "SSD12_PWRDIS_R")
	)
	(segment
		(start 379.048264 -76.186284)
		(end 379.048264 -68.597526)
		(width 0.15494)
		(layer "In5.Cu")
		(net "SSD12_PWRDIS_R")
	)
	(segment
		(start 340.486746 -177.452782)
		(end 342.627966 -175.311562)
		(width 0.15494)
		(layer "In5.Cu")
		(net "SSD12_PWRDIS_R")
	)
	(segment
		(start 337.905598 -180.565806)
		(end 340.486746 -177.984658)
		(width 0.15494)
		(layer "In5.Cu")
		(net "SSD12_PWRDIS_R")
	)
	(segment
		(start 382.059942 -79.197962)
		(end 379.048264 -76.186284)
		(width 0.15494)
		(layer "In5.Cu")
		(net "SSD12_PWRDIS_R")
	)
	(segment
		(start 367.036604 -27.333448)
		(end 368.424714 -27.333448)
		(width 0.15494)
		(layer "In5.Cu")
		(net "SSD12_PWRDIS_R")
	)
	(segment
		(start 349.031052 -114.923316)
		(end 352.250756 -111.703612)
		(width 0.15494)
		(layer "In5.Cu")
		(net "SSD12_PWRDIS_R")
	)
	(segment
		(start 371.6782 -29.768546)
		(end 372.434612 -29.012134)
		(width 0.15494)
		(layer "In5.Cu")
		(net "SSD12_PWRDIS_R")
	)
	(segment
		(start 368.424714 -27.333448)
		(end 369.560348 -28.469082)
		(width 0.15494)
		(layer "In5.Cu")
		(net "SSD12_PWRDIS_R")
	)
	(segment
		(start 352.65614 -106.555032)
		(end 353.367594 -106.555032)
		(width 0.15494)
		(layer "In5.Cu")
		(net "SSD12_PWRDIS_R")
	)
	(segment
		(start 382.059942 -90.671396)
		(end 382.059942 -79.197962)
		(width 0.15494)
		(layer "In5.Cu")
		(net "SSD12_PWRDIS_R")
	)
	(segment
		(start 337.1977 -195.060316)
		(end 337.1977 -188.81725)
		(width 0.15494)
		(layer "In5.Cu")
		(net "SSD12_PWRDIS_R")
	)
	(segment
		(start 339.598 -203.197714)
		(end 338.058506 -201.65822)
		(width 0.15494)
		(layer "In5.Cu")
		(net "SSD12_PWRDIS_R")
	)
	(segment
		(start 339.598 -204.216)
		(end 339.598 -203.197714)
		(width 0.15494)
		(layer "In5.Cu")
		(net "SSD12_PWRDIS_R")
	)
	(segment
		(start 345.066874 -139.952984)
		(end 345.066874 -126.70028)
		(width 0.15494)
		(layer "In5.Cu")
		(net "SSD12_PWRDIS_R")
	)
	(segment
		(start 352.250756 -106.960416)
		(end 352.65614 -106.555032)
		(width 0.15494)
		(layer "In5.Cu")
		(net "SSD12_PWRDIS_R")
	)
	(segment
		(start 353.367594 -106.555032)
		(end 353.750118 -106.172508)
		(width 0.15494)
		(layer "In5.Cu")
		(net "SSD12_PWRDIS_R")
	)
	(segment
		(start 342.627966 -173.946566)
		(end 343.510616 -173.063916)
		(width 0.15494)
		(layer "In5.Cu")
		(net "SSD12_PWRDIS_R")
	)
	(segment
		(start 379.048264 -68.597526)
		(end 384.54965 -63.09614)
		(width 0.15494)
		(layer "In5.Cu")
		(net "SSD12_PWRDIS_R")
	)
	(segment
		(start 372.434612 -29.012134)
		(end 372.434612 -28.469082)
		(width 0.15494)
		(layer "In5.Cu")
		(net "SSD12_PWRDIS_R")
	)
	(segment
		(start 338.058506 -201.65822)
		(end 338.058506 -199.499982)
		(width 0.15494)
		(layer "In5.Cu")
		(net "SSD12_PWRDIS_R")
	)
	(segment
		(start 349.031052 -122.736102)
		(end 349.031052 -114.923316)
		(width 0.15494)
		(layer "In5.Cu")
		(net "SSD12_PWRDIS_R")
	)
	(segment
		(start 369.560348 -28.469082)
		(end 372.434612 -28.469082)
		(width 0.15494)
		(layer "In5.Cu")
		(net "SSD12_PWRDIS_R")
	)
	(segment
		(start 337.905598 -188.109352)
		(end 337.905598 -180.565806)
		(width 0.15494)
		(layer "In5.Cu")
		(net "SSD12_PWRDIS_R")
	)
	(segment
		(start 362.491274 -25.390094)
		(end 362.84662 -25.034748)
		(width 0.15494)
		(layer "In5.Cu")
		(net "SSD12_PWRDIS_R")
	)
	(segment
		(start 371.6782 -32.885634)
		(end 371.6782 -29.768546)
		(width 0.15494)
		(layer "In5.Cu")
		(net "SSD12_PWRDIS_R")
	)
	(segment
		(start 364.737904 -25.034748)
		(end 367.036604 -27.333448)
		(width 0.15494)
		(layer "In5.Cu")
		(net "SSD12_PWRDIS_R")
	)
	(segment
		(start 340.486746 -177.984658)
		(end 340.486746 -177.452782)
		(width 0.15494)
		(layer "In5.Cu")
		(net "SSD12_PWRDIS_R")
	)
	(segment
		(start 356.705916 -103.826818)
		(end 359.01122 -103.826818)
		(width 0.15494)
		(layer "In13.Cu")
		(net "SSD12_PWRDIS_R")
	)
	(segment
		(start 353.472242 -104.1146)
		(end 356.418134 -104.1146)
		(width 0.15494)
		(layer "In13.Cu")
		(net "SSD12_PWRDIS_R")
	)
	(segment
		(start 372.70309 -104.09809)
		(end 372.950486 -103.850694)
		(width 0.15494)
		(layer "In13.Cu")
		(net "SSD12_PWRDIS_R")
	)
	(segment
		(start 356.418134 -104.1146)
		(end 356.705916 -103.826818)
		(width 0.15494)
		(layer "In13.Cu")
		(net "SSD12_PWRDIS_R")
	)
	(segment
		(start 359.282492 -104.09809)
		(end 372.70309 -104.09809)
		(width 0.15494)
		(layer "In13.Cu")
		(net "SSD12_PWRDIS_R")
	)
	(segment
		(start 359.01122 -103.826818)
		(end 359.282492 -104.09809)
		(width 0.15494)
		(layer "In13.Cu")
		(net "SSD12_PWRDIS_R")
	)
	(segment
		(start 212.050122 -186.702954)
		(end 212.050122 -187.167774)
		(width 0.13208)
		(layer "F.Cu")
		(net "BIC_SEL_FLASH_SW2_R")
	)
	(segment
		(start 212.974936 -188.252354)
		(end 211.958936 -188.252354)
		(width 0.13208)
		(layer "F.Cu")
		(net "BIC_SEL_FLASH_SW2_R")
	)
	(segment
		(start 212.525102 -187.642754)
		(end 212.847682 -187.642754)
		(width 0.13208)
		(layer "F.Cu")
		(net "BIC_SEL_FLASH_SW2_R")
	)
	(segment
		(start 212.050122 -187.167774)
		(end 212.525102 -187.642754)
		(width 0.13208)
		(layer "F.Cu")
		(net "BIC_SEL_FLASH_SW2_R")
	)
	(segment
		(start 212.974936 -187.770008)
		(end 212.974936 -188.252354)
		(width 0.13208)
		(layer "F.Cu")
		(net "BIC_SEL_FLASH_SW2_R")
	)
	(segment
		(start 212.847682 -187.642754)
		(end 212.974936 -187.770008)
		(width 0.13208)
		(layer "F.Cu")
		(net "BIC_SEL_FLASH_SW2_R")
	)
	(via
		(at 229.270814 -203.389992)
		(size 0.508)
		(drill 0.254)
		(layers "F.Cu" "B.Cu")
		(net "BIC_SEL_FLASH_SW2_R")
	)
	(via
		(at 212.525102 -187.642754)
		(size 0.508)
		(drill 0.254)
		(layers "F.Cu" "B.Cu")
		(net "BIC_SEL_FLASH_SW2_R")
	)
	(segment
		(start 228.553264 -208.38541)
		(end 228.553264 -206.32039)
		(width 0.13208)
		(layer "B.Cu")
		(net "BIC_SEL_FLASH_SW2_R")
	)
	(segment
		(start 229.087172 -205.786482)
		(end 229.087172 -203.573634)
		(width 0.13208)
		(layer "B.Cu")
		(net "BIC_SEL_FLASH_SW2_R")
	)
	(segment
		(start 229.087172 -203.573634)
		(end 229.270814 -203.389992)
		(width 0.13208)
		(layer "B.Cu")
		(net "BIC_SEL_FLASH_SW2_R")
	)
	(segment
		(start 228.553264 -206.32039)
		(end 229.087172 -205.786482)
		(width 0.13208)
		(layer "B.Cu")
		(net "BIC_SEL_FLASH_SW2_R")
	)
	(segment
		(start 215.535764 -188.1632)
		(end 213.045548 -188.1632)
		(width 0.15494)
		(layer "In5.Cu")
		(net "BIC_SEL_FLASH_SW2_R")
	)
	(segment
		(start 220.2688 -191.897)
		(end 220.2688 -189.2046)
		(width 0.15494)
		(layer "In5.Cu")
		(net "BIC_SEL_FLASH_SW2_R")
	)
	(segment
		(start 221.1578 -194.716654)
		(end 220.09608 -193.654934)
		(width 0.15494)
		(layer "In5.Cu")
		(net "BIC_SEL_FLASH_SW2_R")
	)
	(segment
		(start 221.7166 -194.716654)
		(end 221.1578 -194.716654)
		(width 0.15494)
		(layer "In5.Cu")
		(net "BIC_SEL_FLASH_SW2_R")
	)
	(segment
		(start 213.045548 -188.1632)
		(end 212.525102 -187.642754)
		(width 0.15494)
		(layer "In5.Cu")
		(net "BIC_SEL_FLASH_SW2_R")
	)
	(segment
		(start 220.2688 -189.2046)
		(end 218.059 -186.9948)
		(width 0.15494)
		(layer "In5.Cu")
		(net "BIC_SEL_FLASH_SW2_R")
	)
	(segment
		(start 229.270814 -199.57796)
		(end 226.060254 -196.3674)
		(width 0.15494)
		(layer "In5.Cu")
		(net "BIC_SEL_FLASH_SW2_R")
	)
	(segment
		(start 220.09608 -193.654934)
		(end 220.09608 -192.06972)
		(width 0.15494)
		(layer "In5.Cu")
		(net "BIC_SEL_FLASH_SW2_R")
	)
	(segment
		(start 220.09608 -192.06972)
		(end 220.2688 -191.897)
		(width 0.15494)
		(layer "In5.Cu")
		(net "BIC_SEL_FLASH_SW2_R")
	)
	(segment
		(start 226.060254 -196.3674)
		(end 223.367346 -196.3674)
		(width 0.15494)
		(layer "In5.Cu")
		(net "BIC_SEL_FLASH_SW2_R")
	)
	(segment
		(start 216.704164 -186.9948)
		(end 215.535764 -188.1632)
		(width 0.15494)
		(layer "In5.Cu")
		(net "BIC_SEL_FLASH_SW2_R")
	)
	(segment
		(start 218.059 -186.9948)
		(end 216.704164 -186.9948)
		(width 0.15494)
		(layer "In5.Cu")
		(net "BIC_SEL_FLASH_SW2_R")
	)
	(segment
		(start 229.270814 -203.389992)
		(end 229.270814 -199.57796)
		(width 0.15494)
		(layer "In5.Cu")
		(net "BIC_SEL_FLASH_SW2_R")
	)
	(segment
		(start 223.367346 -196.3674)
		(end 221.7166 -194.716654)
		(width 0.15494)
		(layer "In5.Cu")
		(net "BIC_SEL_FLASH_SW2_R")
	)
	(segment
		(start 352.12909 -205.556866)
		(end 352.12909 -205.938628)
		(width 0.13208)
		(layer "F.Cu")
		(net "FM_PFR_LED_AMBER")
	)
	(segment
		(start 342.893904 -215.987122)
		(end 343.2937 -215.587326)
		(width 0.13208)
		(layer "F.Cu")
		(net "FM_PFR_LED_AMBER")
	)
	(segment
		(start 352.12909 -205.938628)
		(end 351.88144 -206.186278)
		(width 0.13208)
		(layer "F.Cu")
		(net "FM_PFR_LED_AMBER")
	)
	(via
		(at 351.88144 -206.186278)
		(size 0.508)
		(drill 0.254)
		(layers "F.Cu" "B.Cu")
		(net "FM_PFR_LED_AMBER")
	)
	(via
		(at 343.2937 -215.587326)
		(size 0.4572)
		(drill 0.254)
		(layers "F.Cu" "B.Cu")
		(net "FM_PFR_LED_AMBER")
	)
	(segment
		(start 343.738708 -210.489292)
		(end 342.726264 -211.501736)
		(width 0.15494)
		(layer "In9.Cu")
		(net "FM_PFR_LED_AMBER")
	)
	(segment
		(start 342.726264 -211.501736)
		(end 342.726264 -214.992458)
		(width 0.15494)
		(layer "In9.Cu")
		(net "FM_PFR_LED_AMBER")
	)
	(segment
		(start 351.88144 -206.186278)
		(end 350.985074 -207.082644)
		(width 0.15494)
		(layer "In9.Cu")
		(net "FM_PFR_LED_AMBER")
	)
	(segment
		(start 350.985074 -207.082644)
		(end 346.406978 -207.082644)
		(width 0.15494)
		(layer "In9.Cu")
		(net "FM_PFR_LED_AMBER")
	)
	(segment
		(start 342.726264 -214.992458)
		(end 343.2937 -215.559894)
		(width 0.15494)
		(layer "In9.Cu")
		(net "FM_PFR_LED_AMBER")
	)
	(segment
		(start 343.2937 -215.559894)
		(end 343.2937 -215.587326)
		(width 0.15494)
		(layer "In9.Cu")
		(net "FM_PFR_LED_AMBER")
	)
	(segment
		(start 346.406978 -207.082644)
		(end 343.738708 -209.750914)
		(width 0.15494)
		(layer "In9.Cu")
		(net "FM_PFR_LED_AMBER")
	)
	(segment
		(start 343.738708 -209.750914)
		(end 343.738708 -210.489292)
		(width 0.15494)
		(layer "In9.Cu")
		(net "FM_PFR_LED_AMBER")
	)
	(segment
		(start 164.349938 -299.699934)
		(end 163.874958 -300.174914)
		(width 0.249936)
		(layer "F.Cu")
		(net "PCEPLL0_VDDA18_PEX1")
	)
	(via
		(at 147.819618 -296.695114)
		(size 0.508)
		(drill 0.254)
		(layers "F.Cu" "B.Cu")
		(net "PCEPLL0_VDDA18_PEX1")
	)
	(via
		(at 163.874958 -300.174914)
		(size 0.4064)
		(drill 0.2032)
		(layers "F.Cu" "B.Cu")
		(net "PCEPLL0_VDDA18_PEX1")
	)
	(via
		(at 149.216618 -296.695114)
		(size 0.508)
		(drill 0.254)
		(layers "F.Cu" "B.Cu")
		(net "PCEPLL0_VDDA18_PEX1")
	)
	(segment
		(start 163.874958 -299.758354)
		(end 163.874958 -300.174914)
		(width 0.3048)
		(layer "B.Cu")
		(net "PCEPLL0_VDDA18_PEX1")
	)
	(segment
		(start 163.874958 -300.591474)
		(end 163.874958 -300.174914)
		(width 0.3048)
		(layer "B.Cu")
		(net "PCEPLL0_VDDA18_PEX1")
	)
	(segment
		(start 323.551296 -311.004458)
		(end 323.14769 -311.408064)
		(width 0.13208)
		(layer "F.Cu")
		(net "PU_PEX2_SIO_BLINK")
	)
	(segment
		(start 323.551296 -310.761888)
		(end 323.551296 -311.004458)
		(width 0.13208)
		(layer "F.Cu")
		(net "PU_PEX2_SIO_BLINK")
	)
	(via
		(at 292.79977 -309.199788)
		(size 0.4064)
		(drill 0.2032)
		(layers "F.Cu" "B.Cu")
		(net "PU_PEX2_SIO_BLINK")
	)
	(via
		(at 322.450714 -312.10504)
		(size 0.6604)
		(drill 0.3302)
		(layers "F.Cu" "B.Cu")
		(net "PU_PEX2_SIO_BLINK")
	)
	(via
		(at 323.14769 -311.408064)
		(size 0.508)
		(drill 0.254)
		(layers "F.Cu" "B.Cu")
		(net "PU_PEX2_SIO_BLINK")
	)
	(segment
		(start 314.210954 -320.3448)
		(end 293.845488 -320.3448)
		(width 0.13208)
		(layer "B.Cu")
		(net "PU_PEX2_SIO_BLINK")
	)
	(segment
		(start 322.450714 -312.10504)
		(end 314.210954 -320.3448)
		(width 0.13208)
		(layer "B.Cu")
		(net "PU_PEX2_SIO_BLINK")
	)
	(segment
		(start 322.450714 -312.10504)
		(end 323.14769 -311.408064)
		(width 0.13208)
		(layer "B.Cu")
		(net "PU_PEX2_SIO_BLINK")
	)
	(segment
		(start 293.295324 -309.695342)
		(end 292.79977 -309.199788)
		(width 0.13208)
		(layer "B.Cu")
		(net "PU_PEX2_SIO_BLINK")
	)
	(segment
		(start 293.845488 -320.3448)
		(end 293.295324 -319.794636)
		(width 0.13208)
		(layer "B.Cu")
		(net "PU_PEX2_SIO_BLINK")
	)
	(segment
		(start 293.295324 -319.794636)
		(end 293.295324 -309.695342)
		(width 0.13208)
		(layer "B.Cu")
		(net "PU_PEX2_SIO_BLINK")
	)
	(segment
		(start 337.67395 -185.039)
		(end 336.44205 -185.039)
		(width 0.13208)
		(layer "F.Cu")
		(net "PCA9555_0_PEX2_A1")
	)
	(segment
		(start 337.80095 -185.547)
		(end 340.614 -185.547)
		(width 0.13208)
		(layer "F.Cu")
		(net "PCA9555_0_PEX2_A1")
	)
	(segment
		(start 341.122 -185.028332)
		(end 341.996268 -184.154064)
		(width 0.13208)
		(layer "F.Cu")
		(net "PCA9555_0_PEX2_A1")
	)
	(segment
		(start 341.996268 -184.154064)
		(end 343.149936 -184.154064)
		(width 0.13208)
		(layer "F.Cu")
		(net "PCA9555_0_PEX2_A1")
	)
	(segment
		(start 341.122 -185.039)
		(end 341.122 -185.028332)
		(width 0.13208)
		(layer "F.Cu")
		(net "PCA9555_0_PEX2_A1")
	)
	(segment
		(start 337.67395 -185.42)
		(end 337.80095 -185.547)
		(width 0.13208)
		(layer "F.Cu")
		(net "PCA9555_0_PEX2_A1")
	)
	(segment
		(start 340.614 -185.547)
		(end 341.122 -185.039)
		(width 0.13208)
		(layer "F.Cu")
		(net "PCA9555_0_PEX2_A1")
	)
	(segment
		(start 337.67395 -185.039)
		(end 337.67395 -185.42)
		(width 0.13208)
		(layer "F.Cu")
		(net "PCA9555_0_PEX2_A1")
	)
	(via
		(at 341.122 -185.028332)
		(size 0.508)
		(drill 0.254)
		(layers "F.Cu" "B.Cu")
		(net "PCA9555_0_PEX2_A1")
	)
	(segment
		(start 181.813708 -179.437284)
		(end 182.274718 -179.898294)
		(width 0.13208)
		(layer "F.Cu")
		(net "RST_NIC2_PERST_R_N")
	)
	(segment
		(start 175.410622 -180.968396)
		(end 172.007276 -177.56505)
		(width 0.13208)
		(layer "F.Cu")
		(net "RST_NIC2_PERST_R_N")
	)
	(segment
		(start 166.293292 -174.490634)
		(end 166.293292 -173.229524)
		(width 0.13208)
		(layer "F.Cu")
		(net "RST_NIC2_PERST_R_N")
	)
	(segment
		(start 166.51478 -177.56505)
		(end 166.191438 -177.241708)
		(width 0.13208)
		(layer "F.Cu")
		(net "RST_NIC2_PERST_R_N")
	)
	(segment
		(start 358.41305 -226.568)
		(end 359.029 -226.568)
		(width 0.13208)
		(layer "F.Cu")
		(net "RST_NIC2_PERST_R_N")
	)
	(segment
		(start 182.274718 -179.898294)
		(end 182.274718 -180.554122)
		(width 0.13208)
		(layer "F.Cu")
		(net "RST_NIC2_PERST_R_N")
	)
	(segment
		(start 182.274718 -180.554122)
		(end 181.860444 -180.968396)
		(width 0.13208)
		(layer "F.Cu")
		(net "RST_NIC2_PERST_R_N")
	)
	(segment
		(start 166.191438 -177.241708)
		(end 166.191438 -174.592488)
		(width 0.13208)
		(layer "F.Cu")
		(net "RST_NIC2_PERST_R_N")
	)
	(segment
		(start 166.191438 -174.592488)
		(end 166.293292 -174.490634)
		(width 0.13208)
		(layer "F.Cu")
		(net "RST_NIC2_PERST_R_N")
	)
	(segment
		(start 172.007276 -177.56505)
		(end 166.51478 -177.56505)
		(width 0.13208)
		(layer "F.Cu")
		(net "RST_NIC2_PERST_R_N")
	)
	(segment
		(start 181.860444 -180.968396)
		(end 175.410622 -180.968396)
		(width 0.13208)
		(layer "F.Cu")
		(net "RST_NIC2_PERST_R_N")
	)
	(via
		(at 181.813708 -179.437284)
		(size 0.508)
		(drill 0.254)
		(layers "F.Cu" "B.Cu")
		(net "RST_NIC2_PERST_R_N")
	)
	(via
		(at 359.029 -226.568)
		(size 0.508)
		(drill 0.254)
		(layers "F.Cu" "B.Cu")
		(net "RST_NIC2_PERST_R_N")
	)
	(segment
		(start 355.596444 -180.258974)
		(end 349.097346 -180.258974)
		(width 0.15494)
		(layer "In15.Cu")
		(net "RST_NIC2_PERST_R_N")
	)
	(segment
		(start 283.561282 -177.186844)
		(end 282.492704 -178.255422)
		(width 0.15494)
		(layer "In15.Cu")
		(net "RST_NIC2_PERST_R_N")
	)
	(segment
		(start 334.82534 -177.44313)
		(end 334.799178 -177.469292)
		(width 0.15494)
		(layer "In15.Cu")
		(net "RST_NIC2_PERST_R_N")
	)
	(segment
		(start 339.563964 -177.070258)
		(end 339.191092 -177.44313)
		(width 0.15494)
		(layer "In15.Cu")
		(net "RST_NIC2_PERST_R_N")
	)
	(segment
		(start 282.492704 -178.255422)
		(end 241.94897 -178.255422)
		(width 0.15494)
		(layer "In15.Cu")
		(net "RST_NIC2_PERST_R_N")
	)
	(segment
		(start 365.248444 -222.432372)
		(end 365.248444 -221.414086)
		(width 0.15494)
		(layer "In15.Cu")
		(net "RST_NIC2_PERST_R_N")
	)
	(segment
		(start 334.799178 -177.469292)
		(end 295.823386 -177.469292)
		(width 0.15494)
		(layer "In15.Cu")
		(net "RST_NIC2_PERST_R_N")
	)
	(segment
		(start 241.653568 -178.550824)
		(end 232.185972 -178.550824)
		(width 0.15494)
		(layer "In15.Cu")
		(net "RST_NIC2_PERST_R_N")
	)
	(segment
		(start 215.198452 -176.911)
		(end 186.311032 -176.911)
		(width 0.15494)
		(layer "In15.Cu")
		(net "RST_NIC2_PERST_R_N")
	)
	(segment
		(start 342.47201 -177.070258)
		(end 339.563964 -177.070258)
		(width 0.15494)
		(layer "In15.Cu")
		(net "RST_NIC2_PERST_R_N")
	)
	(segment
		(start 364.385098 -222.884746)
		(end 364.79607 -222.884746)
		(width 0.15494)
		(layer "In15.Cu")
		(net "RST_NIC2_PERST_R_N")
	)
	(segment
		(start 231.204262 -177.569114)
		(end 223.855534 -177.569114)
		(width 0.15494)
		(layer "In15.Cu")
		(net "RST_NIC2_PERST_R_N")
	)
	(segment
		(start 241.94897 -178.255422)
		(end 241.653568 -178.550824)
		(width 0.15494)
		(layer "In15.Cu")
		(net "RST_NIC2_PERST_R_N")
	)
	(segment
		(start 223.29267 -177.00625)
		(end 222.375984 -177.00625)
		(width 0.15494)
		(layer "In15.Cu")
		(net "RST_NIC2_PERST_R_N")
	)
	(segment
		(start 222.33001 -176.960276)
		(end 215.247728 -176.960276)
		(width 0.15494)
		(layer "In15.Cu")
		(net "RST_NIC2_PERST_R_N")
	)
	(segment
		(start 360.701844 -226.568)
		(end 364.385098 -222.884746)
		(width 0.15494)
		(layer "In15.Cu")
		(net "RST_NIC2_PERST_R_N")
	)
	(segment
		(start 295.540938 -177.186844)
		(end 283.561282 -177.186844)
		(width 0.15494)
		(layer "In15.Cu")
		(net "RST_NIC2_PERST_R_N")
	)
	(segment
		(start 359.798112 -184.460642)
		(end 355.596444 -180.258974)
		(width 0.15494)
		(layer "In15.Cu")
		(net "RST_NIC2_PERST_R_N")
	)
	(segment
		(start 365.947198 -220.715332)
		(end 365.947198 -190.222378)
		(width 0.15494)
		(layer "In15.Cu")
		(net "RST_NIC2_PERST_R_N")
	)
	(segment
		(start 365.099346 -189.374526)
		(end 365.030258 -189.374526)
		(width 0.15494)
		(layer "In15.Cu")
		(net "RST_NIC2_PERST_R_N")
	)
	(segment
		(start 339.191092 -177.44313)
		(end 334.82534 -177.44313)
		(width 0.15494)
		(layer "In15.Cu")
		(net "RST_NIC2_PERST_R_N")
	)
	(segment
		(start 343.204546 -177.802794)
		(end 342.47201 -177.070258)
		(width 0.15494)
		(layer "In15.Cu")
		(net "RST_NIC2_PERST_R_N")
	)
	(segment
		(start 223.855534 -177.569114)
		(end 223.29267 -177.00625)
		(width 0.15494)
		(layer "In15.Cu")
		(net "RST_NIC2_PERST_R_N")
	)
	(segment
		(start 365.248444 -221.414086)
		(end 365.947198 -220.715332)
		(width 0.15494)
		(layer "In15.Cu")
		(net "RST_NIC2_PERST_R_N")
	)
	(segment
		(start 349.097346 -180.258974)
		(end 346.641166 -177.802794)
		(width 0.15494)
		(layer "In15.Cu")
		(net "RST_NIC2_PERST_R_N")
	)
	(segment
		(start 359.029 -226.568)
		(end 360.701844 -226.568)
		(width 0.15494)
		(layer "In15.Cu")
		(net "RST_NIC2_PERST_R_N")
	)
	(segment
		(start 364.297722 -188.64199)
		(end 364.297722 -188.607192)
		(width 0.15494)
		(layer "In15.Cu")
		(net "RST_NIC2_PERST_R_N")
	)
	(segment
		(start 186.311032 -176.911)
		(end 185.853324 -177.368708)
		(width 0.15494)
		(layer "In15.Cu")
		(net "RST_NIC2_PERST_R_N")
	)
	(segment
		(start 182.90667 -178.344322)
		(end 181.813708 -179.437284)
		(width 0.15494)
		(layer "In15.Cu")
		(net "RST_NIC2_PERST_R_N")
	)
	(segment
		(start 183.498236 -178.344322)
		(end 182.90667 -178.344322)
		(width 0.15494)
		(layer "In15.Cu")
		(net "RST_NIC2_PERST_R_N")
	)
	(segment
		(start 232.185972 -178.550824)
		(end 231.204262 -177.569114)
		(width 0.15494)
		(layer "In15.Cu")
		(net "RST_NIC2_PERST_R_N")
	)
	(segment
		(start 360.151172 -184.460642)
		(end 359.798112 -184.460642)
		(width 0.15494)
		(layer "In15.Cu")
		(net "RST_NIC2_PERST_R_N")
	)
	(segment
		(start 364.297722 -188.607192)
		(end 360.151172 -184.460642)
		(width 0.15494)
		(layer "In15.Cu")
		(net "RST_NIC2_PERST_R_N")
	)
	(segment
		(start 215.247728 -176.960276)
		(end 215.198452 -176.911)
		(width 0.15494)
		(layer "In15.Cu")
		(net "RST_NIC2_PERST_R_N")
	)
	(segment
		(start 295.823386 -177.469292)
		(end 295.540938 -177.186844)
		(width 0.15494)
		(layer "In15.Cu")
		(net "RST_NIC2_PERST_R_N")
	)
	(segment
		(start 185.853324 -177.368708)
		(end 183.498236 -178.344322)
		(width 0.15494)
		(layer "In15.Cu")
		(net "RST_NIC2_PERST_R_N")
	)
	(segment
		(start 222.375984 -177.00625)
		(end 222.33001 -176.960276)
		(width 0.15494)
		(layer "In15.Cu")
		(net "RST_NIC2_PERST_R_N")
	)
	(segment
		(start 365.947198 -190.222378)
		(end 365.099346 -189.374526)
		(width 0.15494)
		(layer "In15.Cu")
		(net "RST_NIC2_PERST_R_N")
	)
	(segment
		(start 365.030258 -189.374526)
		(end 364.297722 -188.64199)
		(width 0.15494)
		(layer "In15.Cu")
		(net "RST_NIC2_PERST_R_N")
	)
	(segment
		(start 346.641166 -177.802794)
		(end 343.204546 -177.802794)
		(width 0.15494)
		(layer "In15.Cu")
		(net "RST_NIC2_PERST_R_N")
	)
	(segment
		(start 364.79607 -222.884746)
		(end 365.248444 -222.432372)
		(width 0.15494)
		(layer "In15.Cu")
		(net "RST_NIC2_PERST_R_N")
	)
	(segment
		(start 398.43456 -28.550108)
		(end 398.964404 -29.079952)
		(width 0.13208)
		(layer "F.Cu")
		(net "SSD13_PWRDIS_R")
	)
	(segment
		(start 398.43456 -28.469082)
		(end 398.43456 -28.550108)
		(width 0.13208)
		(layer "F.Cu")
		(net "SSD13_PWRDIS_R")
	)
	(segment
		(start 389.56488 -25.390094)
		(end 388.491222 -25.390094)
		(width 0.13208)
		(layer "F.Cu")
		(net "SSD13_PWRDIS_R")
	)
	(via
		(at 405.448262 -95.410782)
		(size 0.508)
		(drill 0.254)
		(layers "F.Cu" "B.Cu")
		(net "SSD13_PWRDIS_R")
	)
	(via
		(at 388.491222 -25.390094)
		(size 0.508)
		(drill 0.254)
		(layers "F.Cu" "B.Cu")
		(net "SSD13_PWRDIS_R")
	)
	(via
		(at 398.43456 -28.469082)
		(size 0.508)
		(drill 0.254)
		(layers "F.Cu" "B.Cu")
		(net "SSD13_PWRDIS_R")
	)
	(via
		(at 341.122 -206.15148)
		(size 0.508)
		(drill 0.254)
		(layers "F.Cu" "B.Cu")
		(net "SSD13_PWRDIS_R")
	)
	(via
		(at 352.915474 -107.084622)
		(size 0.508)
		(drill 0.254)
		(layers "F.Cu" "B.Cu")
		(net "SSD13_PWRDIS_R")
	)
	(segment
		(start 340.868 -207.37195)
		(end 340.868 -206.40548)
		(width 0.13208)
		(layer "B.Cu")
		(net "SSD13_PWRDIS_R")
	)
	(segment
		(start 340.868 -206.40548)
		(end 341.122 -206.15148)
		(width 0.13208)
		(layer "B.Cu")
		(net "SSD13_PWRDIS_R")
	)
	(segment
		(start 404.160736 -94.123256)
		(end 405.448262 -95.410782)
		(width 0.15494)
		(layer "In5.Cu")
		(net "SSD13_PWRDIS_R")
	)
	(segment
		(start 397.678148 -32.770826)
		(end 410.590238 -45.682916)
		(width 0.15494)
		(layer "In5.Cu")
		(net "SSD13_PWRDIS_R")
	)
	(segment
		(start 398.43456 -28.469082)
		(end 398.43456 -28.974034)
		(width 0.15494)
		(layer "In5.Cu")
		(net "SSD13_PWRDIS_R")
	)
	(segment
		(start 394.237718 -27.333448)
		(end 395.373352 -28.469082)
		(width 0.15494)
		(layer "In5.Cu")
		(net "SSD13_PWRDIS_R")
	)
	(segment
		(start 392.38682 -26.98242)
		(end 393.040108 -27.333448)
		(width 0.15494)
		(layer "In5.Cu")
		(net "SSD13_PWRDIS_R")
	)
	(segment
		(start 390.741408 -25.034748)
		(end 391.77976 -26.0731)
		(width 0.15494)
		(layer "In5.Cu")
		(net "SSD13_PWRDIS_R")
	)
	(segment
		(start 404.160736 -69.755258)
		(end 404.160736 -94.123256)
		(width 0.15494)
		(layer "In5.Cu")
		(net "SSD13_PWRDIS_R")
	)
	(segment
		(start 395.373352 -28.469082)
		(end 398.43456 -28.469082)
		(width 0.15494)
		(layer "In5.Cu")
		(net "SSD13_PWRDIS_R")
	)
	(segment
		(start 410.590238 -45.682916)
		(end 410.590238 -63.325756)
		(width 0.15494)
		(layer "In5.Cu")
		(net "SSD13_PWRDIS_R")
	)
	(segment
		(start 391.77976 -26.0731)
		(end 392.38682 -26.98242)
		(width 0.15494)
		(layer "In5.Cu")
		(net "SSD13_PWRDIS_R")
	)
	(segment
		(start 393.040108 -27.333448)
		(end 394.237718 -27.333448)
		(width 0.15494)
		(layer "In5.Cu")
		(net "SSD13_PWRDIS_R")
	)
	(segment
		(start 388.491222 -25.390094)
		(end 388.846568 -25.034748)
		(width 0.15494)
		(layer "In5.Cu")
		(net "SSD13_PWRDIS_R")
	)
	(segment
		(start 410.590238 -63.325756)
		(end 404.160736 -69.755258)
		(width 0.15494)
		(layer "In5.Cu")
		(net "SSD13_PWRDIS_R")
	)
	(segment
		(start 398.43456 -28.974034)
		(end 397.678148 -29.730446)
		(width 0.15494)
		(layer "In5.Cu")
		(net "SSD13_PWRDIS_R")
	)
	(segment
		(start 397.678148 -29.730446)
		(end 397.678148 -32.770826)
		(width 0.15494)
		(layer "In5.Cu")
		(net "SSD13_PWRDIS_R")
	)
	(segment
		(start 388.846568 -25.034748)
		(end 390.741408 -25.034748)
		(width 0.15494)
		(layer "In5.Cu")
		(net "SSD13_PWRDIS_R")
	)
	(segment
		(start 344.1446 -202.4126)
		(end 343.3318 -203.2254)
		(width 0.15494)
		(layer "In9.Cu")
		(net "SSD13_PWRDIS_R")
	)
	(segment
		(start 342.116664 -203.957682)
		(end 342.116664 -205.156816)
		(width 0.15494)
		(layer "In9.Cu")
		(net "SSD13_PWRDIS_R")
	)
	(segment
		(start 343.3318 -203.2254)
		(end 342.848946 -203.2254)
		(width 0.15494)
		(layer "In9.Cu")
		(net "SSD13_PWRDIS_R")
	)
	(segment
		(start 351.3074 -122.300746)
		(end 349.4532 -124.154946)
		(width 0.15494)
		(layer "In9.Cu")
		(net "SSD13_PWRDIS_R")
	)
	(segment
		(start 349.4532 -124.154946)
		(end 349.4532 -139.76985)
		(width 0.15494)
		(layer "In9.Cu")
		(net "SSD13_PWRDIS_R")
	)
	(segment
		(start 348.40672 -140.81633)
		(end 348.40672 -187.406026)
		(width 0.15494)
		(layer "In9.Cu")
		(net "SSD13_PWRDIS_R")
	)
	(segment
		(start 351.3074 -108.692696)
		(end 351.3074 -122.300746)
		(width 0.15494)
		(layer "In9.Cu")
		(net "SSD13_PWRDIS_R")
	)
	(segment
		(start 342.848946 -203.2254)
		(end 342.116664 -203.957682)
		(width 0.15494)
		(layer "In9.Cu")
		(net "SSD13_PWRDIS_R")
	)
	(segment
		(start 344.1446 -198.9836)
		(end 344.1446 -202.4126)
		(width 0.15494)
		(layer "In9.Cu")
		(net "SSD13_PWRDIS_R")
	)
	(segment
		(start 348.40672 -187.406026)
		(end 343.9668 -191.845946)
		(width 0.15494)
		(layer "In9.Cu")
		(net "SSD13_PWRDIS_R")
	)
	(segment
		(start 349.4532 -139.76985)
		(end 348.40672 -140.81633)
		(width 0.15494)
		(layer "In9.Cu")
		(net "SSD13_PWRDIS_R")
	)
	(segment
		(start 352.915474 -107.084622)
		(end 351.3074 -108.692696)
		(width 0.15494)
		(layer "In9.Cu")
		(net "SSD13_PWRDIS_R")
	)
	(segment
		(start 342.116664 -205.156816)
		(end 341.122 -206.15148)
		(width 0.15494)
		(layer "In9.Cu")
		(net "SSD13_PWRDIS_R")
	)
	(segment
		(start 343.9668 -198.8058)
		(end 344.1446 -198.9836)
		(width 0.15494)
		(layer "In9.Cu")
		(net "SSD13_PWRDIS_R")
	)
	(segment
		(start 343.9668 -191.845946)
		(end 343.9668 -198.8058)
		(width 0.15494)
		(layer "In9.Cu")
		(net "SSD13_PWRDIS_R")
	)
	(segment
		(start 359.824528 -108.424218)
		(end 361.684062 -106.564684)
		(width 0.15494)
		(layer "In13.Cu")
		(net "SSD13_PWRDIS_R")
	)
	(segment
		(start 378.382276 -100.224082)
		(end 385.261358 -93.345)
		(width 0.15494)
		(layer "In13.Cu")
		(net "SSD13_PWRDIS_R")
	)
	(segment
		(start 377.223274 -106.564684)
		(end 378.382276 -105.405682)
		(width 0.15494)
		(layer "In13.Cu")
		(net "SSD13_PWRDIS_R")
	)
	(segment
		(start 394.204952 -97.177352)
		(end 397.81607 -97.177352)
		(width 0.15494)
		(layer "In13.Cu")
		(net "SSD13_PWRDIS_R")
	)
	(segment
		(start 390.3726 -93.345)
		(end 394.204952 -97.177352)
		(width 0.15494)
		(layer "In13.Cu")
		(net "SSD13_PWRDIS_R")
	)
	(segment
		(start 361.684062 -106.564684)
		(end 377.223274 -106.564684)
		(width 0.15494)
		(layer "In13.Cu")
		(net "SSD13_PWRDIS_R")
	)
	(segment
		(start 399.58264 -95.410782)
		(end 405.448262 -95.410782)
		(width 0.15494)
		(layer "In13.Cu")
		(net "SSD13_PWRDIS_R")
	)
	(segment
		(start 378.382276 -105.405682)
		(end 378.382276 -100.224082)
		(width 0.15494)
		(layer "In13.Cu")
		(net "SSD13_PWRDIS_R")
	)
	(segment
		(start 385.261358 -93.345)
		(end 390.3726 -93.345)
		(width 0.15494)
		(layer "In13.Cu")
		(net "SSD13_PWRDIS_R")
	)
	(segment
		(start 358.290876 -108.424218)
		(end 359.824528 -108.424218)
		(width 0.15494)
		(layer "In13.Cu")
		(net "SSD13_PWRDIS_R")
	)
	(segment
		(start 352.915474 -107.084622)
		(end 353.269296 -106.7308)
		(width 0.15494)
		(layer "In13.Cu")
		(net "SSD13_PWRDIS_R")
	)
	(segment
		(start 397.81607 -97.177352)
		(end 399.58264 -95.410782)
		(width 0.15494)
		(layer "In13.Cu")
		(net "SSD13_PWRDIS_R")
	)
	(segment
		(start 353.269296 -106.7308)
		(end 356.597458 -106.7308)
		(width 0.15494)
		(layer "In13.Cu")
		(net "SSD13_PWRDIS_R")
	)
	(segment
		(start 356.597458 -106.7308)
		(end 358.290876 -108.424218)
		(width 0.15494)
		(layer "In13.Cu")
		(net "SSD13_PWRDIS_R")
	)
	(segment
		(start 352.504502 -261.861808)
		(end 352.504502 -261.328916)
		(width 0.13208)
		(layer "F.Cu")
		(net "NC_P0V8_PEX2_ISEN4")
	)
	(segment
		(start 352.504502 -261.328916)
		(end 352.375978 -261.200392)
		(width 0.13208)
		(layer "F.Cu")
		(net "NC_P0V8_PEX2_ISEN4")
	)
	(segment
		(start 352.375978 -261.200392)
		(end 352.375978 -260.795008)
		(width 0.13208)
		(layer "F.Cu")
		(net "NC_P0V8_PEX2_ISEN4")
	)
	(via
		(at 354.052886 -262.267954)
		(size 0.6604)
		(drill 0.3302)
		(layers "F.Cu" "B.Cu")
		(net "NC_P0V8_PEX2_ISEN4")
	)
	(via
		(at 352.504502 -261.861808)
		(size 0.508)
		(drill 0.254)
		(layers "F.Cu" "B.Cu")
		(net "NC_P0V8_PEX2_ISEN4")
	)
	(segment
		(start 355.165406 -261.155434)
		(end 354.052886 -262.267954)
		(width 0.13208)
		(layer "B.Cu")
		(net "NC_P0V8_PEX2_ISEN4")
	)
	(segment
		(start 352.504502 -261.861808)
		(end 352.910648 -262.267954)
		(width 0.13208)
		(layer "B.Cu")
		(net "NC_P0V8_PEX2_ISEN4")
	)
	(segment
		(start 352.910648 -262.267954)
		(end 354.052886 -262.267954)
		(width 0.13208)
		(layer "B.Cu")
		(net "NC_P0V8_PEX2_ISEN4")
	)
	(segment
		(start 355.165406 -260.869176)
		(end 355.165406 -261.155434)
		(width 0.13208)
		(layer "B.Cu")
		(net "NC_P0V8_PEX2_ISEN4")
	)
	(segment
		(start 293.941754 -164.0586)
		(end 293.941754 -162.781488)
		(width 0.13208)
		(layer "F.Cu")
		(net "NIC4_PWRBRK_N")
	)
	(segment
		(start 293.941754 -164.56533)
		(end 293.69385 -164.813234)
		(width 0.13208)
		(layer "F.Cu")
		(net "NIC4_PWRBRK_N")
	)
	(segment
		(start 293.69385 -164.813234)
		(end 293.69385 -165.270434)
		(width 0.13208)
		(layer "F.Cu")
		(net "NIC4_PWRBRK_N")
	)
	(segment
		(start 294.70985 -165.270434)
		(end 293.69385 -165.270434)
		(width 0.13208)
		(layer "F.Cu")
		(net "NIC4_PWRBRK_N")
	)
	(segment
		(start 293.941754 -164.0586)
		(end 293.941754 -164.56533)
		(width 0.13208)
		(layer "F.Cu")
		(net "NIC4_PWRBRK_N")
	)
	(via
		(at 293.941754 -164.0586)
		(size 0.762)
		(drill 0.381)
		(layers "F.Cu" "B.Cu")
		(net "NIC4_PWRBRK_N")
	)
	(segment
		(start 172.820838 -40.058086)
		(end 172.947838 -40.185086)
		(width 0.13208)
		(layer "F.Cu")
		(net "SSD6_AUX_P3V3_EN")
	)
	(segment
		(start 169.22623 -38.329616)
		(end 169.22623 -39.33571)
		(width 0.13208)
		(layer "F.Cu")
		(net "SSD6_AUX_P3V3_EN")
	)
	(segment
		(start 171.202604 -40.058086)
		(end 172.820838 -40.058086)
		(width 0.13208)
		(layer "F.Cu")
		(net "SSD6_AUX_P3V3_EN")
	)
	(segment
		(start 170.480228 -39.33571)
		(end 171.202604 -40.058086)
		(width 0.13208)
		(layer "F.Cu")
		(net "SSD6_AUX_P3V3_EN")
	)
	(segment
		(start 172.947838 -40.185086)
		(end 172.947838 -41.137332)
		(width 0.13208)
		(layer "F.Cu")
		(net "SSD6_AUX_P3V3_EN")
	)
	(segment
		(start 169.22623 -39.33571)
		(end 170.480228 -39.33571)
		(width 0.13208)
		(layer "F.Cu")
		(net "SSD6_AUX_P3V3_EN")
	)
	(via
		(at 170.480228 -39.33571)
		(size 0.762)
		(drill 0.381)
		(layers "F.Cu" "B.Cu")
		(net "SSD6_AUX_P3V3_EN")
	)
	(segment
		(start 163.399978 -298.74972)
		(end 162.924998 -299.224954)
		(width 0.249936)
		(layer "F.Cu")
		(net "PCEPLL1_VDDA18_PEX1")
	)
	(via
		(at 162.924998 -299.224954)
		(size 0.4064)
		(drill 0.2032)
		(layers "F.Cu" "B.Cu")
		(net "PCEPLL1_VDDA18_PEX1")
	)
	(via
		(at 149.216618 -299.895514)
		(size 0.508)
		(drill 0.254)
		(layers "F.Cu" "B.Cu")
		(net "PCEPLL1_VDDA18_PEX1")
	)
	(via
		(at 147.819618 -299.895514)
		(size 0.508)
		(drill 0.254)
		(layers "F.Cu" "B.Cu")
		(net "PCEPLL1_VDDA18_PEX1")
	)
	(segment
		(start 162.721798 -300.1772)
		(end 162.721798 -299.212)
		(width 0.3048)
		(layer "B.Cu")
		(net "PCEPLL1_VDDA18_PEX1")
	)
	(segment
		(start 162.924998 -299.224954)
		(end 162.734752 -299.224954)
		(width 0.3048)
		(layer "B.Cu")
		(net "PCEPLL1_VDDA18_PEX1")
	)
	(segment
		(start 162.734752 -299.224954)
		(end 162.721798 -299.212)
		(width 0.3048)
		(layer "B.Cu")
		(net "PCEPLL1_VDDA18_PEX1")
	)
	(segment
		(start 337.67395 -184.023)
		(end 337.67395 -184.404)
		(width 0.13208)
		(layer "F.Cu")
		(net "PCA9555_0_PEX2_A2")
	)
	(segment
		(start 337.67395 -184.404)
		(end 337.80095 -184.531)
		(width 0.13208)
		(layer "F.Cu")
		(net "PCA9555_0_PEX2_A2")
	)
	(segment
		(start 337.80095 -184.531)
		(end 339.89137 -184.531)
		(width 0.13208)
		(layer "F.Cu")
		(net "PCA9555_0_PEX2_A2")
	)
	(segment
		(start 337.67395 -184.023)
		(end 336.44205 -184.023)
		(width 0.13208)
		(layer "F.Cu")
		(net "PCA9555_0_PEX2_A2")
	)
	(segment
		(start 339.89137 -184.531)
		(end 340.492588 -183.929782)
		(width 0.13208)
		(layer "F.Cu")
		(net "PCA9555_0_PEX2_A2")
	)
	(segment
		(start 340.918292 -183.504078)
		(end 343.149936 -183.504078)
		(width 0.13208)
		(layer "F.Cu")
		(net "PCA9555_0_PEX2_A2")
	)
	(segment
		(start 340.492588 -183.929782)
		(end 340.918292 -183.504078)
		(width 0.13208)
		(layer "F.Cu")
		(net "PCA9555_0_PEX2_A2")
	)
	(via
		(at 340.492588 -183.929782)
		(size 0.508)
		(drill 0.254)
		(layers "F.Cu" "B.Cu")
		(net "PCA9555_0_PEX2_A2")
	)
	(segment
		(start 210.942936 -187.6425)
		(end 210.942936 -188.252354)
		(width 0.13208)
		(layer "F.Cu")
		(net "BIC_SEL_FLASH_SW3_R")
	)
	(segment
		(start 210.75015 -186.702954)
		(end 210.75015 -187.449714)
		(width 0.13208)
		(layer "F.Cu")
		(net "BIC_SEL_FLASH_SW3_R")
	)
	(segment
		(start 210.75015 -187.449714)
		(end 210.942936 -187.6425)
		(width 0.13208)
		(layer "F.Cu")
		(net "BIC_SEL_FLASH_SW3_R")
	)
	(segment
		(start 228.578664 -204.04201)
		(end 228.214936 -204.04201)
		(width 0.13208)
		(layer "F.Cu")
		(net "BIC_SEL_FLASH_SW3_R")
	)
	(segment
		(start 209.926936 -188.252354)
		(end 210.942936 -188.252354)
		(width 0.13208)
		(layer "F.Cu")
		(net "BIC_SEL_FLASH_SW3_R")
	)
	(segment
		(start 228.214936 -204.04201)
		(end 227.540566 -203.36764)
		(width 0.13208)
		(layer "F.Cu")
		(net "BIC_SEL_FLASH_SW3_R")
	)
	(via
		(at 227.540566 -203.36764)
		(size 0.508)
		(drill 0.254)
		(layers "F.Cu" "B.Cu")
		(net "BIC_SEL_FLASH_SW3_R")
	)
	(via
		(at 210.942936 -187.6425)
		(size 0.508)
		(drill 0.254)
		(layers "F.Cu" "B.Cu")
		(net "BIC_SEL_FLASH_SW3_R")
	)
	(segment
		(start 221.615 -197.257162)
		(end 220.776292 -196.418454)
		(width 0.15494)
		(layer "In5.Cu")
		(net "BIC_SEL_FLASH_SW3_R")
	)
	(segment
		(start 218.484704 -188.512704)
		(end 216.7382 -188.512704)
		(width 0.15494)
		(layer "In5.Cu")
		(net "BIC_SEL_FLASH_SW3_R")
	)
	(segment
		(start 218.7956 -194.106546)
		(end 218.7956 -190.287656)
		(width 0.15494)
		(layer "In5.Cu")
		(net "BIC_SEL_FLASH_SW3_R")
	)
	(segment
		(start 227.457 -198.882254)
		(end 225.831908 -197.257162)
		(width 0.15494)
		(layer "In5.Cu")
		(net "BIC_SEL_FLASH_SW3_R")
	)
	(segment
		(start 226.9744 -202.801474)
		(end 226.9744 -200.279254)
		(width 0.15494)
		(layer "In5.Cu")
		(net "BIC_SEL_FLASH_SW3_R")
	)
	(segment
		(start 226.9744 -200.279254)
		(end 227.457 -199.796654)
		(width 0.15494)
		(layer "In5.Cu")
		(net "BIC_SEL_FLASH_SW3_R")
	)
	(segment
		(start 220.776292 -196.087238)
		(end 218.7956 -194.106546)
		(width 0.15494)
		(layer "In5.Cu")
		(net "BIC_SEL_FLASH_SW3_R")
	)
	(segment
		(start 218.7956 -190.287656)
		(end 219.1258 -189.957456)
		(width 0.15494)
		(layer "In5.Cu")
		(net "BIC_SEL_FLASH_SW3_R")
	)
	(segment
		(start 220.776292 -196.418454)
		(end 220.776292 -196.087238)
		(width 0.15494)
		(layer "In5.Cu")
		(net "BIC_SEL_FLASH_SW3_R")
	)
	(segment
		(start 216.605104 -188.6458)
		(end 212.445346 -188.6458)
		(width 0.15494)
		(layer "In5.Cu")
		(net "BIC_SEL_FLASH_SW3_R")
	)
	(segment
		(start 212.445346 -188.6458)
		(end 211.442046 -187.6425)
		(width 0.15494)
		(layer "In5.Cu")
		(net "BIC_SEL_FLASH_SW3_R")
	)
	(segment
		(start 227.457 -199.796654)
		(end 227.457 -198.882254)
		(width 0.15494)
		(layer "In5.Cu")
		(net "BIC_SEL_FLASH_SW3_R")
	)
	(segment
		(start 216.7382 -188.512704)
		(end 216.605104 -188.6458)
		(width 0.15494)
		(layer "In5.Cu")
		(net "BIC_SEL_FLASH_SW3_R")
	)
	(segment
		(start 219.1258 -189.957456)
		(end 219.1258 -189.1538)
		(width 0.15494)
		(layer "In5.Cu")
		(net "BIC_SEL_FLASH_SW3_R")
	)
	(segment
		(start 227.540566 -203.36764)
		(end 226.9744 -202.801474)
		(width 0.15494)
		(layer "In5.Cu")
		(net "BIC_SEL_FLASH_SW3_R")
	)
	(segment
		(start 211.442046 -187.6425)
		(end 210.942936 -187.6425)
		(width 0.15494)
		(layer "In5.Cu")
		(net "BIC_SEL_FLASH_SW3_R")
	)
	(segment
		(start 225.831908 -197.257162)
		(end 221.615 -197.257162)
		(width 0.15494)
		(layer "In5.Cu")
		(net "BIC_SEL_FLASH_SW3_R")
	)
	(segment
		(start 219.1258 -189.1538)
		(end 218.484704 -188.512704)
		(width 0.15494)
		(layer "In5.Cu")
		(net "BIC_SEL_FLASH_SW3_R")
	)
	(segment
		(start 61.741812 -164.56533)
		(end 61.493908 -164.813234)
		(width 0.13208)
		(layer "F.Cu")
		(net "NIC0_PWRBRK_N")
	)
	(segment
		(start 61.741812 -164.0586)
		(end 61.741812 -164.56533)
		(width 0.13208)
		(layer "F.Cu")
		(net "NIC0_PWRBRK_N")
	)
	(segment
		(start 61.741812 -162.781488)
		(end 61.741812 -164.0586)
		(width 0.13208)
		(layer "F.Cu")
		(net "NIC0_PWRBRK_N")
	)
	(segment
		(start 62.509908 -165.270434)
		(end 61.493908 -165.270434)
		(width 0.13208)
		(layer "F.Cu")
		(net "NIC0_PWRBRK_N")
	)
	(segment
		(start 61.493908 -164.813234)
		(end 61.493908 -165.270434)
		(width 0.13208)
		(layer "F.Cu")
		(net "NIC0_PWRBRK_N")
	)
	(via
		(at 61.741812 -164.0586)
		(size 0.762)
		(drill 0.381)
		(layers "F.Cu" "B.Cu")
		(net "NIC0_PWRBRK_N")
	)
	(segment
		(start 207.264 -217.932)
		(end 207.273398 -217.932)
		(width 0.13208)
		(layer "F.Cu")
		(net "UART_FIO_DEBUG_R_RX")
	)
	(segment
		(start 207.01 -217.678)
		(end 207.264 -217.932)
		(width 0.13208)
		(layer "F.Cu")
		(net "UART_FIO_DEBUG_R_RX")
	)
	(segment
		(start 227.674424 -67.369944)
		(end 227.36556 -67.369944)
		(width 0.13208)
		(layer "F.Cu")
		(net "UART_FIO_DEBUG_R_RX")
	)
	(segment
		(start 204.089 -216.408254)
		(end 205.358746 -217.678)
		(width 0.13208)
		(layer "F.Cu")
		(net "UART_FIO_DEBUG_R_RX")
	)
	(segment
		(start 229.437438 -67.200018)
		(end 227.84435 -67.200018)
		(width 0.13208)
		(layer "F.Cu")
		(net "UART_FIO_DEBUG_R_RX")
	)
	(segment
		(start 206.66329 -193.548)
		(end 206.66329 -195.672202)
		(width 0.13208)
		(layer "F.Cu")
		(net "UART_FIO_DEBUG_R_RX")
	)
	(segment
		(start 204.089 -201.887328)
		(end 204.089 -216.408254)
		(width 0.13208)
		(layer "F.Cu")
		(net "UART_FIO_DEBUG_R_RX")
	)
	(segment
		(start 207.273398 -217.932)
		(end 207.273652 -217.932254)
		(width 0.13208)
		(layer "F.Cu")
		(net "UART_FIO_DEBUG_R_RX")
	)
	(segment
		(start 205.358746 -217.678)
		(end 207.01 -217.678)
		(width 0.13208)
		(layer "F.Cu")
		(net "UART_FIO_DEBUG_R_RX")
	)
	(segment
		(start 206.66329 -195.672202)
		(end 204.089 -201.887328)
		(width 0.13208)
		(layer "F.Cu")
		(net "UART_FIO_DEBUG_R_RX")
	)
	(segment
		(start 227.84435 -67.200018)
		(end 227.674424 -67.369944)
		(width 0.13208)
		(layer "F.Cu")
		(net "UART_FIO_DEBUG_R_RX")
	)
	(segment
		(start 207.273652 -217.932254)
		(end 207.273652 -218.236546)
		(width 0.13208)
		(layer "F.Cu")
		(net "UART_FIO_DEBUG_R_RX")
	)
	(via
		(at 206.66329 -193.548)
		(size 0.762)
		(drill 0.254)
		(layers "F.Cu" "B.Cu")
		(net "UART_FIO_DEBUG_R_RX")
	)
	(via
		(at 223.18218 -188.681614)
		(size 0.508)
		(drill 0.254)
		(layers "F.Cu" "B.Cu")
		(net "UART_FIO_DEBUG_R_RX")
	)
	(via
		(at 227.36556 -67.369944)
		(size 0.508)
		(drill 0.254)
		(layers "F.Cu" "B.Cu")
		(net "UART_FIO_DEBUG_R_RX")
	)
	(segment
		(start 226.778058 -71.117968)
		(end 226.778058 -94.987364)
		(width 0.15494)
		(layer "In5.Cu")
		(net "UART_FIO_DEBUG_R_RX")
	)
	(segment
		(start 254.18796 -165.3032)
		(end 234.2134 -165.3032)
		(width 0.15494)
		(layer "In5.Cu")
		(net "UART_FIO_DEBUG_R_RX")
	)
	(segment
		(start 225.5774 -180.5686)
		(end 223.18218 -182.96382)
		(width 0.15494)
		(layer "In5.Cu")
		(net "UART_FIO_DEBUG_R_RX")
	)
	(segment
		(start 256.676906 -162.814254)
		(end 254.18796 -165.3032)
		(width 0.15494)
		(layer "In5.Cu")
		(net "UART_FIO_DEBUG_R_RX")
	)
	(segment
		(start 226.949254 -180.5686)
		(end 225.5774 -180.5686)
		(width 0.15494)
		(layer "In5.Cu")
		(net "UART_FIO_DEBUG_R_RX")
	)
	(segment
		(start 228.0666 -179.451254)
		(end 226.949254 -180.5686)
		(width 0.15494)
		(layer "In5.Cu")
		(net "UART_FIO_DEBUG_R_RX")
	)
	(segment
		(start 227.36556 -67.369944)
		(end 227.36556 -68.49364)
		(width 0.15494)
		(layer "In5.Cu")
		(net "UART_FIO_DEBUG_R_RX")
	)
	(segment
		(start 223.18218 -182.96382)
		(end 223.18218 -188.681614)
		(width 0.15494)
		(layer "In5.Cu")
		(net "UART_FIO_DEBUG_R_RX")
	)
	(segment
		(start 228.0666 -171.45)
		(end 228.0666 -179.451254)
		(width 0.15494)
		(layer "In5.Cu")
		(net "UART_FIO_DEBUG_R_RX")
	)
	(segment
		(start 227.466906 -95.676212)
		(end 230.053388 -95.676212)
		(width 0.15494)
		(layer "In5.Cu")
		(net "UART_FIO_DEBUG_R_RX")
	)
	(segment
		(start 227.36556 -68.49364)
		(end 226.593146 -69.266054)
		(width 0.15494)
		(layer "In5.Cu")
		(net "UART_FIO_DEBUG_R_RX")
	)
	(segment
		(start 226.593146 -69.266054)
		(end 226.593146 -70.933056)
		(width 0.15494)
		(layer "In5.Cu")
		(net "UART_FIO_DEBUG_R_RX")
	)
	(segment
		(start 234.2134 -165.3032)
		(end 228.0666 -171.45)
		(width 0.15494)
		(layer "In5.Cu")
		(net "UART_FIO_DEBUG_R_RX")
	)
	(segment
		(start 256.676906 -115.844066)
		(end 256.676906 -162.814254)
		(width 0.15494)
		(layer "In5.Cu")
		(net "UART_FIO_DEBUG_R_RX")
	)
	(segment
		(start 226.593146 -70.933056)
		(end 226.778058 -71.117968)
		(width 0.15494)
		(layer "In5.Cu")
		(net "UART_FIO_DEBUG_R_RX")
	)
	(segment
		(start 230.810054 -96.432878)
		(end 237.265718 -96.432878)
		(width 0.15494)
		(layer "In5.Cu")
		(net "UART_FIO_DEBUG_R_RX")
	)
	(segment
		(start 237.265718 -96.432878)
		(end 256.676906 -115.844066)
		(width 0.15494)
		(layer "In5.Cu")
		(net "UART_FIO_DEBUG_R_RX")
	)
	(segment
		(start 230.053388 -95.676212)
		(end 230.810054 -96.432878)
		(width 0.15494)
		(layer "In5.Cu")
		(net "UART_FIO_DEBUG_R_RX")
	)
	(segment
		(start 226.778058 -94.987364)
		(end 227.466906 -95.676212)
		(width 0.15494)
		(layer "In5.Cu")
		(net "UART_FIO_DEBUG_R_RX")
	)
	(segment
		(start 222.252286 -189.611508)
		(end 223.18218 -188.681614)
		(width 0.15494)
		(layer "In15.Cu")
		(net "UART_FIO_DEBUG_R_RX")
	)
	(segment
		(start 207.977232 -193.65087)
		(end 210.261454 -193.65087)
		(width 0.15494)
		(layer "In15.Cu")
		(net "UART_FIO_DEBUG_R_RX")
	)
	(segment
		(start 207.874362 -193.548)
		(end 207.977232 -193.65087)
		(width 0.15494)
		(layer "In15.Cu")
		(net "UART_FIO_DEBUG_R_RX")
	)
	(segment
		(start 220.311218 -190.382906)
		(end 221.082616 -189.611508)
		(width 0.15494)
		(layer "In15.Cu")
		(net "UART_FIO_DEBUG_R_RX")
	)
	(segment
		(start 213.529418 -190.382906)
		(end 220.311218 -190.382906)
		(width 0.15494)
		(layer "In15.Cu")
		(net "UART_FIO_DEBUG_R_RX")
	)
	(segment
		(start 206.66329 -193.548)
		(end 207.874362 -193.548)
		(width 0.15494)
		(layer "In15.Cu")
		(net "UART_FIO_DEBUG_R_RX")
	)
	(segment
		(start 221.082616 -189.611508)
		(end 222.252286 -189.611508)
		(width 0.15494)
		(layer "In15.Cu")
		(net "UART_FIO_DEBUG_R_RX")
	)
	(segment
		(start 210.261454 -193.65087)
		(end 213.529418 -190.382906)
		(width 0.15494)
		(layer "In15.Cu")
		(net "UART_FIO_DEBUG_R_RX")
	)
	(segment
		(start 174.493682 -37.774118)
		(end 173.94682 -37.774118)
		(width 0.13208)
		(layer "F.Cu")
		(net "PRSNT_SSD6_R1_N")
	)
	(segment
		(start 174.6758 -37.315648)
		(end 174.6758 -37.592)
		(width 0.13208)
		(layer "F.Cu")
		(net "PRSNT_SSD6_R1_N")
	)
	(segment
		(start 173.94682 -37.774118)
		(end 172.39107 -37.774118)
		(width 0.13208)
		(layer "F.Cu")
		(net "PRSNT_SSD6_R1_N")
	)
	(segment
		(start 172.39107 -37.774118)
		(end 171.997878 -38.16731)
		(width 0.13208)
		(layer "F.Cu")
		(net "PRSNT_SSD6_R1_N")
	)
	(segment
		(start 174.6758 -37.592)
		(end 174.493682 -37.774118)
		(width 0.13208)
		(layer "F.Cu")
		(net "PRSNT_SSD6_R1_N")
	)
	(segment
		(start 171.997878 -38.16731)
		(end 171.997878 -38.937184)
		(width 0.13208)
		(layer "F.Cu")
		(net "PRSNT_SSD6_R1_N")
	)
	(via
		(at 173.94682 -37.774118)
		(size 0.508)
		(drill 0.254)
		(layers "F.Cu" "B.Cu")
		(net "PRSNT_SSD6_R1_N")
	)
	(segment
		(start 354.09505 -182.980584)
		(end 354.09505 -183.388)
		(width 0.13208)
		(layer "F.Cu")
		(net "PCA9555_0_PEX2_A0")
	)
	(segment
		(start 353.864418 -182.749952)
		(end 354.09505 -182.980584)
		(width 0.13208)
		(layer "F.Cu")
		(net "PCA9555_0_PEX2_A0")
	)
	(segment
		(start 355.32695 -183.388)
		(end 354.09505 -183.388)
		(width 0.13208)
		(layer "F.Cu")
		(net "PCA9555_0_PEX2_A0")
	)
	(segment
		(start 349.911416 -182.749952)
		(end 350.255078 -182.749952)
		(width 0.13208)
		(layer "F.Cu")
		(net "PCA9555_0_PEX2_A0")
	)
	(segment
		(start 349.807276 -182.854092)
		(end 349.911416 -182.749952)
		(width 0.13208)
		(layer "F.Cu")
		(net "PCA9555_0_PEX2_A0")
	)
	(segment
		(start 350.255078 -182.749952)
		(end 353.864418 -182.749952)
		(width 0.13208)
		(layer "F.Cu")
		(net "PCA9555_0_PEX2_A0")
	)
	(segment
		(start 349.000064 -182.854092)
		(end 349.807276 -182.854092)
		(width 0.13208)
		(layer "F.Cu")
		(net "PCA9555_0_PEX2_A0")
	)
	(via
		(at 350.255078 -182.749952)
		(size 0.508)
		(drill 0.254)
		(layers "F.Cu" "B.Cu")
		(net "PCA9555_0_PEX2_A0")
	)
	(segment
		(start 228.578664 -205.47711)
		(end 228.578664 -206.62011)
		(width 0.13208)
		(layer "F.Cu")
		(net "BIC_SEL_FLASH_SW0_R")
	)
	(segment
		(start 217.038936 -188.252354)
		(end 217.038936 -187.612782)
		(width 0.13208)
		(layer "F.Cu")
		(net "BIC_SEL_FLASH_SW0_R")
	)
	(segment
		(start 216.799922 -187.373768)
		(end 216.374218 -187.373768)
		(width 0.13208)
		(layer "F.Cu")
		(net "BIC_SEL_FLASH_SW0_R")
	)
	(segment
		(start 217.038936 -187.612782)
		(end 216.799922 -187.373768)
		(width 0.13208)
		(layer "F.Cu")
		(net "BIC_SEL_FLASH_SW0_R")
	)
	(segment
		(start 216.374218 -187.373768)
		(end 216.114122 -187.113672)
		(width 0.13208)
		(layer "F.Cu")
		(net "BIC_SEL_FLASH_SW0_R")
	)
	(segment
		(start 217.038936 -188.252354)
		(end 216.022936 -188.252354)
		(width 0.13208)
		(layer "F.Cu")
		(net "BIC_SEL_FLASH_SW0_R")
	)
	(segment
		(start 216.114122 -187.113672)
		(end 216.114122 -186.702954)
		(width 0.13208)
		(layer "F.Cu")
		(net "BIC_SEL_FLASH_SW0_R")
	)
	(via
		(at 228.578664 -205.47711)
		(size 0.508)
		(drill 0.254)
		(layers "F.Cu" "B.Cu")
		(net "BIC_SEL_FLASH_SW0_R")
	)
	(via
		(at 217.038936 -187.612782)
		(size 0.508)
		(drill 0.254)
		(layers "F.Cu" "B.Cu")
		(net "BIC_SEL_FLASH_SW0_R")
	)
	(segment
		(start 227.9396 -198.8058)
		(end 225.933 -196.7992)
		(width 0.15494)
		(layer "In5.Cu")
		(net "BIC_SEL_FLASH_SW0_R")
	)
	(segment
		(start 219.837 -191.566546)
		(end 219.837 -189.331346)
		(width 0.15494)
		(layer "In5.Cu")
		(net "BIC_SEL_FLASH_SW0_R")
	)
	(segment
		(start 228.578664 -205.47711)
		(end 228.578664 -204.579982)
		(width 0.15494)
		(layer "In5.Cu")
		(net "BIC_SEL_FLASH_SW0_R")
	)
	(segment
		(start 228.578664 -204.579982)
		(end 228.076252 -204.07757)
		(width 0.15494)
		(layer "In5.Cu")
		(net "BIC_SEL_FLASH_SW0_R")
	)
	(segment
		(start 220.6752 -195.3514)
		(end 219.73794 -194.41414)
		(width 0.15494)
		(layer "In5.Cu")
		(net "BIC_SEL_FLASH_SW0_R")
	)
	(segment
		(start 221.3102 -195.3514)
		(end 220.6752 -195.3514)
		(width 0.15494)
		(layer "In5.Cu")
		(net "BIC_SEL_FLASH_SW0_R")
	)
	(segment
		(start 228.076252 -204.07757)
		(end 228.076252 -202.955652)
		(width 0.15494)
		(layer "In5.Cu")
		(net "BIC_SEL_FLASH_SW0_R")
	)
	(segment
		(start 219.837 -189.331346)
		(end 218.118436 -187.612782)
		(width 0.15494)
		(layer "In5.Cu")
		(net "BIC_SEL_FLASH_SW0_R")
	)
	(segment
		(start 225.933 -196.7992)
		(end 222.758 -196.7992)
		(width 0.15494)
		(layer "In5.Cu")
		(net "BIC_SEL_FLASH_SW0_R")
	)
	(segment
		(start 227.4316 -200.838816)
		(end 227.9396 -200.330816)
		(width 0.15494)
		(layer "In5.Cu")
		(net "BIC_SEL_FLASH_SW0_R")
	)
	(segment
		(start 222.758 -196.7992)
		(end 221.3102 -195.3514)
		(width 0.15494)
		(layer "In5.Cu")
		(net "BIC_SEL_FLASH_SW0_R")
	)
	(segment
		(start 227.9396 -200.330816)
		(end 227.9396 -198.8058)
		(width 0.15494)
		(layer "In5.Cu")
		(net "BIC_SEL_FLASH_SW0_R")
	)
	(segment
		(start 219.73794 -191.665606)
		(end 219.837 -191.566546)
		(width 0.15494)
		(layer "In5.Cu")
		(net "BIC_SEL_FLASH_SW0_R")
	)
	(segment
		(start 227.4316 -202.311)
		(end 227.4316 -200.838816)
		(width 0.15494)
		(layer "In5.Cu")
		(net "BIC_SEL_FLASH_SW0_R")
	)
	(segment
		(start 219.73794 -194.41414)
		(end 219.73794 -191.665606)
		(width 0.15494)
		(layer "In5.Cu")
		(net "BIC_SEL_FLASH_SW0_R")
	)
	(segment
		(start 228.076252 -202.955652)
		(end 227.4316 -202.311)
		(width 0.15494)
		(layer "In5.Cu")
		(net "BIC_SEL_FLASH_SW0_R")
	)
	(segment
		(start 218.118436 -187.612782)
		(end 217.038936 -187.612782)
		(width 0.15494)
		(layer "In5.Cu")
		(net "BIC_SEL_FLASH_SW0_R")
	)
	(segment
		(start 63.824612 -158.480252)
		(end 62.808612 -158.480252)
		(width 0.13208)
		(layer "F.Cu")
		(net "NIC1_PWRBRK_N")
	)
	(segment
		(start 62.808612 -159.248856)
		(end 62.808612 -158.480252)
		(width 0.13208)
		(layer "F.Cu")
		(net "NIC1_PWRBRK_N")
	)
	(segment
		(start 63.241936 -160.981644)
		(end 63.241936 -159.68218)
		(width 0.13208)
		(layer "F.Cu")
		(net "NIC1_PWRBRK_N")
	)
	(segment
		(start 63.241936 -159.68218)
		(end 62.808612 -159.248856)
		(width 0.13208)
		(layer "F.Cu")
		(net "NIC1_PWRBRK_N")
	)
	(via
		(at 63.241936 -159.68218)
		(size 0.762)
		(drill 0.381)
		(layers "F.Cu" "B.Cu")
		(net "NIC1_PWRBRK_N")
	)
	(segment
		(start 145.0086 -34.339276)
		(end 145.0086 -33.961324)
		(width 0.13208)
		(layer "F.Cu")
		(net "SSD5_AUX_P3V3_EN_R")
	)
	(segment
		(start 146.815302 -59.100974)
		(end 147.840192 -58.076084)
		(width 0.13208)
		(layer "F.Cu")
		(net "SSD5_AUX_P3V3_EN_R")
	)
	(segment
		(start 148.241004 -57.16397)
		(end 148.241004 -57.675272)
		(width 0.13208)
		(layer "F.Cu")
		(net "SSD5_AUX_P3V3_EN_R")
	)
	(segment
		(start 142.377922 -39.97198)
		(end 142.377922 -37.84092)
		(width 0.13208)
		(layer "F.Cu")
		(net "SSD5_AUX_P3V3_EN_R")
	)
	(segment
		(start 142.690088 -37.529516)
		(end 143.226282 -37.529516)
		(width 0.13208)
		(layer "F.Cu")
		(net "SSD5_AUX_P3V3_EN_R")
	)
	(segment
		(start 143.226282 -37.529516)
		(end 144.302734 -37.529516)
		(width 0.13208)
		(layer "F.Cu")
		(net "SSD5_AUX_P3V3_EN_R")
	)
	(segment
		(start 146.815302 -59.146186)
		(end 146.815302 -59.100974)
		(width 0.13208)
		(layer "F.Cu")
		(net "SSD5_AUX_P3V3_EN_R")
	)
	(segment
		(start 144.302734 -37.529516)
		(end 144.956276 -36.874958)
		(width 0.13208)
		(layer "F.Cu")
		(net "SSD5_AUX_P3V3_EN_R")
	)
	(segment
		(start 145.0086 -33.961324)
		(end 144.956276 -33.909)
		(width 0.13208)
		(layer "F.Cu")
		(net "SSD5_AUX_P3V3_EN_R")
	)
	(segment
		(start 144.956276 -34.3916)
		(end 145.0086 -34.339276)
		(width 0.13208)
		(layer "F.Cu")
		(net "SSD5_AUX_P3V3_EN_R")
	)
	(segment
		(start 142.377922 -37.84092)
		(end 142.690088 -37.529516)
		(width 0.13208)
		(layer "F.Cu")
		(net "SSD5_AUX_P3V3_EN_R")
	)
	(segment
		(start 144.956276 -33.909)
		(end 144.956276 -33.248092)
		(width 0.13208)
		(layer "F.Cu")
		(net "SSD5_AUX_P3V3_EN_R")
	)
	(segment
		(start 148.241004 -57.675272)
		(end 147.840192 -58.076084)
		(width 0.13208)
		(layer "F.Cu")
		(net "SSD5_AUX_P3V3_EN_R")
	)
	(segment
		(start 144.956276 -36.874958)
		(end 144.956276 -34.3916)
		(width 0.13208)
		(layer "F.Cu")
		(net "SSD5_AUX_P3V3_EN_R")
	)
	(via
		(at 142.377922 -39.97198)
		(size 0.508)
		(drill 0.254)
		(layers "F.Cu" "B.Cu")
		(net "SSD5_AUX_P3V3_EN_R")
	)
	(via
		(at 147.840192 -58.076084)
		(size 0.508)
		(drill 0.254)
		(layers "F.Cu" "B.Cu")
		(net "SSD5_AUX_P3V3_EN_R")
	)
	(segment
		(start 145.844514 -39.97198)
		(end 142.377922 -39.97198)
		(width 0.15494)
		(layer "In5.Cu")
		(net "SSD5_AUX_P3V3_EN_R")
	)
	(segment
		(start 151.7142 -45.841666)
		(end 145.844514 -39.97198)
		(width 0.15494)
		(layer "In5.Cu")
		(net "SSD5_AUX_P3V3_EN_R")
	)
	(segment
		(start 151.7142 -54.202076)
		(end 151.7142 -45.841666)
		(width 0.15494)
		(layer "In5.Cu")
		(net "SSD5_AUX_P3V3_EN_R")
	)
	(segment
		(start 147.840192 -58.076084)
		(end 151.7142 -54.202076)
		(width 0.15494)
		(layer "In5.Cu")
		(net "SSD5_AUX_P3V3_EN_R")
	)
	(segment
		(start 353.75469 -170.811952)
		(end 354.09505 -171.152312)
		(width 0.13208)
		(layer "F.Cu")
		(net "PCA9555_1_PEX2_A0")
	)
	(segment
		(start 349.000064 -170.916092)
		(end 349.807276 -170.916092)
		(width 0.13208)
		(layer "F.Cu")
		(net "PCA9555_1_PEX2_A0")
	)
	(segment
		(start 354.09505 -171.152312)
		(end 354.09505 -171.45)
		(width 0.13208)
		(layer "F.Cu")
		(net "PCA9555_1_PEX2_A0")
	)
	(segment
		(start 349.807276 -170.916092)
		(end 350.224852 -170.498516)
		(width 0.13208)
		(layer "F.Cu")
		(net "PCA9555_1_PEX2_A0")
	)
	(segment
		(start 355.32695 -171.45)
		(end 354.09505 -171.45)
		(width 0.13208)
		(layer "F.Cu")
		(net "PCA9555_1_PEX2_A0")
	)
	(segment
		(start 352.117406 -170.811952)
		(end 353.75469 -170.811952)
		(width 0.13208)
		(layer "F.Cu")
		(net "PCA9555_1_PEX2_A0")
	)
	(segment
		(start 350.224852 -170.498516)
		(end 351.80397 -170.498516)
		(width 0.13208)
		(layer "F.Cu")
		(net "PCA9555_1_PEX2_A0")
	)
	(segment
		(start 351.80397 -170.498516)
		(end 352.117406 -170.811952)
		(width 0.13208)
		(layer "F.Cu")
		(net "PCA9555_1_PEX2_A0")
	)
	(via
		(at 352.117406 -170.811952)
		(size 0.508)
		(drill 0.254)
		(layers "F.Cu" "B.Cu")
		(net "PCA9555_1_PEX2_A0")
	)
	(segment
		(start 370.581936 -207.909922)
		(end 369.580922 -207.909922)
		(width 0.13208)
		(layer "F.Cu")
		(net "RST_PEX_SSD1_PERST_N")
	)
	(segment
		(start 369.580922 -207.909922)
		(end 367.538 -205.867)
		(width 0.13208)
		(layer "F.Cu")
		(net "RST_PEX_SSD1_PERST_N")
	)
	(segment
		(start 367.538 -205.867)
		(end 365.90605 -205.867)
		(width 0.13208)
		(layer "F.Cu")
		(net "RST_PEX_SSD1_PERST_N")
	)
	(via
		(at 367.538 -205.867)
		(size 0.508)
		(drill 0.254)
		(layers "F.Cu" "B.Cu")
		(net "RST_PEX_SSD1_PERST_N")
	)
	(segment
		(start 338.47405 -153.67)
		(end 339.852 -153.67)
		(width 0.13208)
		(layer "F.Cu")
		(net "RST_PEX_SSD13_PERST_N")
	)
	(segment
		(start 341.424768 -155.242768)
		(end 342.071452 -155.242768)
		(width 0.13208)
		(layer "F.Cu")
		(net "RST_PEX_SSD13_PERST_N")
	)
	(segment
		(start 342.122252 -155.242768)
		(end 342.592406 -155.712922)
		(width 0.13208)
		(layer "F.Cu")
		(net "RST_PEX_SSD13_PERST_N")
	)
	(segment
		(start 342.071452 -155.242768)
		(end 342.122252 -155.242768)
		(width 0.13208)
		(layer "F.Cu")
		(net "RST_PEX_SSD13_PERST_N")
	)
	(segment
		(start 342.592406 -155.712922)
		(end 343.149936 -155.712922)
		(width 0.13208)
		(layer "F.Cu")
		(net "RST_PEX_SSD13_PERST_N")
	)
	(segment
		(start 339.852 -153.67)
		(end 341.424768 -155.242768)
		(width 0.13208)
		(layer "F.Cu")
		(net "RST_PEX_SSD13_PERST_N")
	)
	(via
		(at 342.071452 -155.242768)
		(size 0.508)
		(drill 0.254)
		(layers "F.Cu" "B.Cu")
		(net "RST_PEX_SSD13_PERST_N")
	)
	(segment
		(start 354.30079 -253.985014)
		(end 354.30079 -255.105154)
		(width 0.13208)
		(layer "F.Cu")
		(net "P0V8_PEX2_PWM1")
	)
	(segment
		(start 337.911694 -281.438858)
		(end 337.989926 -281.249882)
		(width 0.2032)
		(layer "F.Cu")
		(net "P0V8_PEX2_PWM1")
	)
	(segment
		(start 354.30079 -255.105154)
		(end 353.975924 -255.43002)
		(width 0.13208)
		(layer "F.Cu")
		(net "P0V8_PEX2_PWM1")
	)
	(segment
		(start 353.975924 -255.43002)
		(end 353.975924 -255.994916)
		(width 0.13208)
		(layer "F.Cu")
		(net "P0V8_PEX2_PWM1")
	)
	(segment
		(start 337.989926 -280.897838)
		(end 338.115148 -280.617168)
		(width 0.2032)
		(layer "F.Cu")
		(net "P0V8_PEX2_PWM1")
	)
	(segment
		(start 337.911694 -281.999182)
		(end 337.911694 -281.438858)
		(width 0.2032)
		(layer "F.Cu")
		(net "P0V8_PEX2_PWM1")
	)
	(segment
		(start 337.989926 -281.249882)
		(end 337.989926 -280.897838)
		(width 0.2032)
		(layer "F.Cu")
		(net "P0V8_PEX2_PWM1")
	)
	(via
		(at 354.30079 -253.985014)
		(size 0.508)
		(drill 0.254)
		(layers "F.Cu" "B.Cu")
		(net "P0V8_PEX2_PWM1")
	)
	(via
		(at 338.115148 -280.617168)
		(size 0.508)
		(drill 0.254)
		(layers "F.Cu" "B.Cu")
		(net "P0V8_PEX2_PWM1")
	)
	(segment
		(start 353.234244 -253.985014)
		(end 350.501712 -256.717546)
		(width 0.2032)
		(layer "In5.Cu")
		(net "P0V8_PEX2_PWM1")
	)
	(segment
		(start 337.559396 -280.061416)
		(end 338.115148 -280.617168)
		(width 0.2032)
		(layer "In5.Cu")
		(net "P0V8_PEX2_PWM1")
	)
	(segment
		(start 339.212174 -277.278846)
		(end 337.559396 -278.931624)
		(width 0.2032)
		(layer "In5.Cu")
		(net "P0V8_PEX2_PWM1")
	)
	(segment
		(start 337.559396 -278.931624)
		(end 337.559396 -280.061416)
		(width 0.2032)
		(layer "In5.Cu")
		(net "P0V8_PEX2_PWM1")
	)
	(segment
		(start 342.734138 -266.761722)
		(end 341.239602 -266.761722)
		(width 0.2032)
		(layer "In5.Cu")
		(net "P0V8_PEX2_PWM1")
	)
	(segment
		(start 339.212174 -268.78915)
		(end 339.212174 -277.278846)
		(width 0.2032)
		(layer "In5.Cu")
		(net "P0V8_PEX2_PWM1")
	)
	(segment
		(start 354.30079 -253.985014)
		(end 353.234244 -253.985014)
		(width 0.2032)
		(layer "In5.Cu")
		(net "P0V8_PEX2_PWM1")
	)
	(segment
		(start 350.501712 -258.994148)
		(end 342.734138 -266.761722)
		(width 0.2032)
		(layer "In5.Cu")
		(net "P0V8_PEX2_PWM1")
	)
	(segment
		(start 350.501712 -256.717546)
		(end 350.501712 -258.994148)
		(width 0.2032)
		(layer "In5.Cu")
		(net "P0V8_PEX2_PWM1")
	)
	(segment
		(start 341.239602 -266.761722)
		(end 339.212174 -268.78915)
		(width 0.2032)
		(layer "In5.Cu")
		(net "P0V8_PEX2_PWM1")
	)
	(segment
		(start 214.81415 -186.702954)
		(end 214.81415 -187.449714)
		(width 0.13208)
		(layer "F.Cu")
		(net "BIC_SEL_FLASH_SW1_R")
	)
	(segment
		(start 214.81415 -187.449714)
		(end 215.006936 -187.6425)
		(width 0.13208)
		(layer "F.Cu")
		(net "BIC_SEL_FLASH_SW1_R")
	)
	(segment
		(start 213.990936 -188.252354)
		(end 215.006936 -188.252354)
		(width 0.13208)
		(layer "F.Cu")
		(net "BIC_SEL_FLASH_SW1_R")
	)
	(segment
		(start 215.006936 -187.6425)
		(end 215.006936 -188.252354)
		(width 0.13208)
		(layer "F.Cu")
		(net "BIC_SEL_FLASH_SW1_R")
	)
	(via
		(at 232.207308 -202.55484)
		(size 0.508)
		(drill 0.254)
		(layers "F.Cu" "B.Cu")
		(net "BIC_SEL_FLASH_SW1_R")
	)
	(via
		(at 215.006936 -187.6425)
		(size 0.508)
		(drill 0.254)
		(layers "F.Cu" "B.Cu")
		(net "BIC_SEL_FLASH_SW1_R")
	)
	(segment
		(start 231.247188 -202.82154)
		(end 230.067104 -204.001624)
		(width 0.13208)
		(layer "B.Cu")
		(net "BIC_SEL_FLASH_SW1_R")
	)
	(segment
		(start 230.067104 -204.001624)
		(end 230.067104 -206.629508)
		(width 0.13208)
		(layer "B.Cu")
		(net "BIC_SEL_FLASH_SW1_R")
	)
	(segment
		(start 231.940608 -202.82154)
		(end 231.247188 -202.82154)
		(width 0.13208)
		(layer "B.Cu")
		(net "BIC_SEL_FLASH_SW1_R")
	)
	(segment
		(start 232.207308 -202.55484)
		(end 231.940608 -202.82154)
		(width 0.13208)
		(layer "B.Cu")
		(net "BIC_SEL_FLASH_SW1_R")
	)
	(segment
		(start 230.067104 -206.629508)
		(end 229.556564 -207.140048)
		(width 0.13208)
		(layer "B.Cu")
		(net "BIC_SEL_FLASH_SW1_R")
	)
	(segment
		(start 229.556564 -207.140048)
		(end 229.556564 -208.38541)
		(width 0.13208)
		(layer "B.Cu")
		(net "BIC_SEL_FLASH_SW1_R")
	)
	(segment
		(start 218.185746 -186.4868)
		(end 216.162636 -186.4868)
		(width 0.15494)
		(layer "In5.Cu")
		(net "BIC_SEL_FLASH_SW1_R")
	)
	(segment
		(start 216.162636 -186.4868)
		(end 215.006936 -187.6425)
		(width 0.15494)
		(layer "In5.Cu")
		(net "BIC_SEL_FLASH_SW1_R")
	)
	(segment
		(start 221.858078 -193.740532)
		(end 221.858078 -192.124584)
		(width 0.15494)
		(layer "In5.Cu")
		(net "BIC_SEL_FLASH_SW1_R")
	)
	(segment
		(start 232.207308 -201.930762)
		(end 226.135946 -195.8594)
		(width 0.15494)
		(layer "In5.Cu")
		(net "BIC_SEL_FLASH_SW1_R")
	)
	(segment
		(start 232.207308 -202.55484)
		(end 232.207308 -201.930762)
		(width 0.15494)
		(layer "In5.Cu")
		(net "BIC_SEL_FLASH_SW1_R")
	)
	(segment
		(start 226.135946 -195.8594)
		(end 223.976946 -195.8594)
		(width 0.15494)
		(layer "In5.Cu")
		(net "BIC_SEL_FLASH_SW1_R")
	)
	(segment
		(start 220.62694 -190.893446)
		(end 220.62694 -188.927994)
		(width 0.15494)
		(layer "In5.Cu")
		(net "BIC_SEL_FLASH_SW1_R")
	)
	(segment
		(start 220.62694 -188.927994)
		(end 218.185746 -186.4868)
		(width 0.15494)
		(layer "In5.Cu")
		(net "BIC_SEL_FLASH_SW1_R")
	)
	(segment
		(start 221.858078 -192.124584)
		(end 220.62694 -190.893446)
		(width 0.15494)
		(layer "In5.Cu")
		(net "BIC_SEL_FLASH_SW1_R")
	)
	(segment
		(start 223.976946 -195.8594)
		(end 221.858078 -193.740532)
		(width 0.15494)
		(layer "In5.Cu")
		(net "BIC_SEL_FLASH_SW1_R")
	)
	(segment
		(start 179.924456 -158.480252)
		(end 178.908456 -158.480252)
		(width 0.13208)
		(layer "F.Cu")
		(net "NIC3_PWRBRK_N")
	)
	(segment
		(start 179.34178 -159.68218)
		(end 179.34178 -160.981644)
		(width 0.13208)
		(layer "F.Cu")
		(net "NIC3_PWRBRK_N")
	)
	(segment
		(start 178.908456 -159.248856)
		(end 179.34178 -159.68218)
		(width 0.13208)
		(layer "F.Cu")
		(net "NIC3_PWRBRK_N")
	)
	(segment
		(start 178.908456 -158.480252)
		(end 178.908456 -159.248856)
		(width 0.13208)
		(layer "F.Cu")
		(net "NIC3_PWRBRK_N")
	)
	(via
		(at 179.34178 -159.68218)
		(size 0.762)
		(drill 0.381)
		(layers "F.Cu" "B.Cu")
		(net "NIC3_PWRBRK_N")
	)
	(segment
		(start 336.44205 -173.101)
		(end 337.67395 -173.101)
		(width 0.13208)
		(layer "F.Cu")
		(net "PCA9555_1_PEX2_A1")
	)
	(segment
		(start 341.122 -173.101)
		(end 341.122 -173.090332)
		(width 0.13208)
		(layer "F.Cu")
		(net "PCA9555_1_PEX2_A1")
	)
	(segment
		(start 337.67395 -173.482)
		(end 337.80095 -173.609)
		(width 0.13208)
		(layer "F.Cu")
		(net "PCA9555_1_PEX2_A1")
	)
	(segment
		(start 341.122 -173.090332)
		(end 341.996268 -172.216064)
		(width 0.13208)
		(layer "F.Cu")
		(net "PCA9555_1_PEX2_A1")
	)
	(segment
		(start 340.614 -173.609)
		(end 341.122 -173.101)
		(width 0.13208)
		(layer "F.Cu")
		(net "PCA9555_1_PEX2_A1")
	)
	(segment
		(start 341.996268 -172.216064)
		(end 343.149936 -172.216064)
		(width 0.13208)
		(layer "F.Cu")
		(net "PCA9555_1_PEX2_A1")
	)
	(segment
		(start 337.67395 -173.101)
		(end 337.67395 -173.482)
		(width 0.13208)
		(layer "F.Cu")
		(net "PCA9555_1_PEX2_A1")
	)
	(segment
		(start 337.80095 -173.609)
		(end 340.614 -173.609)
		(width 0.13208)
		(layer "F.Cu")
		(net "PCA9555_1_PEX2_A1")
	)
	(via
		(at 341.122 -173.090332)
		(size 0.508)
		(drill 0.254)
		(layers "F.Cu" "B.Cu")
		(net "PCA9555_1_PEX2_A1")
	)
	(segment
		(start 369.087908 -208.559908)
		(end 370.581936 -208.559908)
		(width 0.13208)
		(layer "F.Cu")
		(net "SSD1_PEX_PWR_EN")
	)
	(segment
		(start 365.90605 -206.883)
		(end 367.411 -206.883)
		(width 0.13208)
		(layer "F.Cu")
		(net "SSD1_PEX_PWR_EN")
	)
	(segment
		(start 367.411 -206.883)
		(end 369.087908 -208.559908)
		(width 0.13208)
		(layer "F.Cu")
		(net "SSD1_PEX_PWR_EN")
	)
	(via
		(at 369.087908 -208.559908)
		(size 0.508)
		(drill 0.254)
		(layers "F.Cu" "B.Cu")
		(net "SSD1_PEX_PWR_EN")
	)
	(segment
		(start 338.47405 -154.686)
		(end 339.852 -154.686)
		(width 0.13208)
		(layer "F.Cu")
		(net "SSD13_PEX_PWR_EN")
	)
	(segment
		(start 339.852 -154.686)
		(end 341.215726 -156.049726)
		(width 0.13208)
		(layer "F.Cu")
		(net "SSD13_PEX_PWR_EN")
	)
	(segment
		(start 341.215726 -156.049726)
		(end 342.28659 -156.049726)
		(width 0.13208)
		(layer "F.Cu")
		(net "SSD13_PEX_PWR_EN")
	)
	(segment
		(start 342.28659 -156.049726)
		(end 342.599772 -156.362908)
		(width 0.13208)
		(layer "F.Cu")
		(net "SSD13_PEX_PWR_EN")
	)
	(segment
		(start 342.599772 -156.362908)
		(end 343.149936 -156.362908)
		(width 0.13208)
		(layer "F.Cu")
		(net "SSD13_PEX_PWR_EN")
	)
	(via
		(at 339.852 -154.686)
		(size 0.508)
		(drill 0.254)
		(layers "F.Cu" "B.Cu")
		(net "SSD13_PEX_PWR_EN")
	)
	(segment
		(start 327.93305 -210.185)
		(end 328.549 -210.185)
		(width 0.13208)
		(layer "F.Cu")
		(net "PRSNT_SSD12_FPGA_N")
	)
	(segment
		(start 335.693766 -213.587076)
		(end 335.29397 -213.18728)
		(width 0.13208)
		(layer "F.Cu")
		(net "PRSNT_SSD12_FPGA_N")
	)
	(via
		(at 328.549 -210.185)
		(size 0.508)
		(drill 0.254)
		(layers "F.Cu" "B.Cu")
		(net "PRSNT_SSD12_FPGA_N")
	)
	(via
		(at 335.29397 -213.18728)
		(size 0.4572)
		(drill 0.254)
		(layers "F.Cu" "B.Cu")
		(net "PRSNT_SSD12_FPGA_N")
	)
	(segment
		(start 331.752702 -211.303362)
		(end 331.752702 -212.558884)
		(width 0.15494)
		(layer "In5.Cu")
		(net "PRSNT_SSD12_FPGA_N")
	)
	(segment
		(start 332.624938 -212.848444)
		(end 332.776322 -212.785706)
		(width 0.15494)
		(layer "In5.Cu")
		(net "PRSNT_SSD12_FPGA_N")
	)
	(segment
		(start 332.776322 -212.785706)
		(end 333.502 -212.785706)
		(width 0.15494)
		(layer "In5.Cu")
		(net "PRSNT_SSD12_FPGA_N")
	)
	(segment
		(start 328.549 -210.185)
		(end 328.81062 -209.92338)
		(width 0.15494)
		(layer "In5.Cu")
		(net "PRSNT_SSD12_FPGA_N")
	)
	(segment
		(start 333.502 -212.785706)
		(end 334.892396 -212.785706)
		(width 0.0889)
		(layer "In5.Cu")
		(net "PRSNT_SSD12_FPGA_N")
	)
	(segment
		(start 330.37272 -209.92338)
		(end 331.752702 -211.303362)
		(width 0.15494)
		(layer "In5.Cu")
		(net "PRSNT_SSD12_FPGA_N")
	)
	(segment
		(start 332.042262 -212.848444)
		(end 332.624938 -212.848444)
		(width 0.15494)
		(layer "In5.Cu")
		(net "PRSNT_SSD12_FPGA_N")
	)
	(segment
		(start 334.892396 -212.785706)
		(end 335.29397 -213.18728)
		(width 0.0889)
		(layer "In5.Cu")
		(net "PRSNT_SSD12_FPGA_N")
	)
	(segment
		(start 331.752702 -212.558884)
		(end 332.042262 -212.848444)
		(width 0.15494)
		(layer "In5.Cu")
		(net "PRSNT_SSD12_FPGA_N")
	)
	(segment
		(start 328.81062 -209.92338)
		(end 330.37272 -209.92338)
		(width 0.15494)
		(layer "In5.Cu")
		(net "PRSNT_SSD12_FPGA_N")
	)
	(segment
		(start 178.609752 -165.270434)
		(end 177.593752 -165.270434)
		(width 0.13208)
		(layer "F.Cu")
		(net "NIC2_PWRBRK_N")
	)
	(segment
		(start 177.841656 -164.0586)
		(end 177.841656 -164.56533)
		(width 0.13208)
		(layer "F.Cu")
		(net "NIC2_PWRBRK_N")
	)
	(segment
		(start 177.841656 -162.781488)
		(end 177.841656 -164.0586)
		(width 0.13208)
		(layer "F.Cu")
		(net "NIC2_PWRBRK_N")
	)
	(segment
		(start 177.593752 -164.813234)
		(end 177.593752 -165.270434)
		(width 0.13208)
		(layer "F.Cu")
		(net "NIC2_PWRBRK_N")
	)
	(segment
		(start 177.841656 -164.56533)
		(end 177.593752 -164.813234)
		(width 0.13208)
		(layer "F.Cu")
		(net "NIC2_PWRBRK_N")
	)
	(via
		(at 177.841656 -164.0586)
		(size 0.762)
		(drill 0.381)
		(layers "F.Cu" "B.Cu")
		(net "NIC2_PWRBRK_N")
	)
	(segment
		(start 144.48028 -39.33571)
		(end 145.202656 -40.058086)
		(width 0.13208)
		(layer "F.Cu")
		(net "SSD5_AUX_P3V3_EN")
	)
	(segment
		(start 143.226282 -39.33571)
		(end 144.48028 -39.33571)
		(width 0.13208)
		(layer "F.Cu")
		(net "SSD5_AUX_P3V3_EN")
	)
	(segment
		(start 146.82089 -40.058086)
		(end 146.94789 -40.185086)
		(width 0.13208)
		(layer "F.Cu")
		(net "SSD5_AUX_P3V3_EN")
	)
	(segment
		(start 143.226282 -38.329616)
		(end 143.226282 -39.33571)
		(width 0.13208)
		(layer "F.Cu")
		(net "SSD5_AUX_P3V3_EN")
	)
	(segment
		(start 146.94789 -40.185086)
		(end 146.94789 -41.137332)
		(width 0.13208)
		(layer "F.Cu")
		(net "SSD5_AUX_P3V3_EN")
	)
	(segment
		(start 145.202656 -40.058086)
		(end 146.82089 -40.058086)
		(width 0.13208)
		(layer "F.Cu")
		(net "SSD5_AUX_P3V3_EN")
	)
	(via
		(at 144.48028 -39.33571)
		(size 0.762)
		(drill 0.381)
		(layers "F.Cu" "B.Cu")
		(net "SSD5_AUX_P3V3_EN")
	)
	(segment
		(start 337.67395 -172.466)
		(end 337.80095 -172.593)
		(width 0.13208)
		(layer "F.Cu")
		(net "PCA9555_1_PEX2_A2")
	)
	(segment
		(start 337.67395 -172.085)
		(end 337.67395 -172.466)
		(width 0.13208)
		(layer "F.Cu")
		(net "PCA9555_1_PEX2_A2")
	)
	(segment
		(start 340.492588 -171.991782)
		(end 340.918292 -171.566078)
		(width 0.13208)
		(layer "F.Cu")
		(net "PCA9555_1_PEX2_A2")
	)
	(segment
		(start 339.89137 -172.593)
		(end 340.492588 -171.991782)
		(width 0.13208)
		(layer "F.Cu")
		(net "PCA9555_1_PEX2_A2")
	)
	(segment
		(start 340.918292 -171.566078)
		(end 343.149936 -171.566078)
		(width 0.13208)
		(layer "F.Cu")
		(net "PCA9555_1_PEX2_A2")
	)
	(segment
		(start 337.80095 -172.593)
		(end 339.89137 -172.593)
		(width 0.13208)
		(layer "F.Cu")
		(net "PCA9555_1_PEX2_A2")
	)
	(segment
		(start 336.44205 -172.085)
		(end 337.67395 -172.085)
		(width 0.13208)
		(layer "F.Cu")
		(net "PCA9555_1_PEX2_A2")
	)
	(via
		(at 340.492588 -171.991782)
		(size 0.508)
		(drill 0.254)
		(layers "F.Cu" "B.Cu")
		(net "PCA9555_1_PEX2_A2")
	)
	(segment
		(start 415.564828 -25.390094)
		(end 414.49117 -25.390094)
		(width 0.13208)
		(layer "F.Cu")
		(net "SSD14_PWRDIS_R")
	)
	(segment
		(start 424.434508 -28.469082)
		(end 424.434508 -28.550108)
		(width 0.13208)
		(layer "F.Cu")
		(net "SSD14_PWRDIS_R")
	)
	(segment
		(start 339.598 -200.76795)
		(end 339.598 -200.152)
		(width 0.13208)
		(layer "F.Cu")
		(net "SSD14_PWRDIS_R")
	)
	(segment
		(start 424.434508 -28.550108)
		(end 424.964352 -29.079952)
		(width 0.13208)
		(layer "F.Cu")
		(net "SSD14_PWRDIS_R")
	)
	(via
		(at 355.658674 -99.125024)
		(size 0.508)
		(drill 0.254)
		(layers "F.Cu" "B.Cu")
		(net "SSD14_PWRDIS_R")
	)
	(via
		(at 414.49117 -25.390094)
		(size 0.508)
		(drill 0.254)
		(layers "F.Cu" "B.Cu")
		(net "SSD14_PWRDIS_R")
	)
	(via
		(at 339.598 -200.152)
		(size 0.508)
		(drill 0.254)
		(layers "F.Cu" "B.Cu")
		(net "SSD14_PWRDIS_R")
	)
	(via
		(at 424.434508 -28.469082)
		(size 0.508)
		(drill 0.254)
		(layers "F.Cu" "B.Cu")
		(net "SSD14_PWRDIS_R")
	)
	(via
		(at 414.195514 -88.247728)
		(size 0.508)
		(drill 0.254)
		(layers "F.Cu" "B.Cu")
		(net "SSD14_PWRDIS_R")
	)
	(segment
		(start 340.157562 -198.860918)
		(end 339.598 -199.42048)
		(width 0.15494)
		(layer "In5.Cu")
		(net "SSD14_PWRDIS_R")
	)
	(segment
		(start 356.029768 -99.496118)
		(end 356.029768 -108.958634)
		(width 0.15494)
		(layer "In5.Cu")
		(net "SSD14_PWRDIS_R")
	)
	(segment
		(start 340.157562 -187.311538)
		(end 340.157562 -198.860918)
		(width 0.15494)
		(layer "In5.Cu")
		(net "SSD14_PWRDIS_R")
	)
	(segment
		(start 414.49117 -25.390094)
		(end 414.846516 -25.034748)
		(width 0.15494)
		(layer "In5.Cu")
		(net "SSD14_PWRDIS_R")
	)
	(segment
		(start 345.783154 -126.99746)
		(end 345.783154 -175.506888)
		(width 0.15494)
		(layer "In5.Cu")
		(net "SSD14_PWRDIS_R")
	)
	(segment
		(start 356.029768 -108.958634)
		(end 349.747332 -115.24107)
		(width 0.15494)
		(layer "In5.Cu")
		(net "SSD14_PWRDIS_R")
	)
	(segment
		(start 436.590186 -67.69227)
		(end 418.488876 -85.79358)
		(width 0.15494)
		(layer "In5.Cu")
		(net "SSD14_PWRDIS_R")
	)
	(segment
		(start 355.658674 -99.125024)
		(end 356.029768 -99.496118)
		(width 0.15494)
		(layer "In5.Cu")
		(net "SSD14_PWRDIS_R")
	)
	(segment
		(start 345.783154 -175.506888)
		(end 339.601048 -181.688994)
		(width 0.15494)
		(layer "In5.Cu")
		(net "SSD14_PWRDIS_R")
	)
	(segment
		(start 414.692084 -85.79358)
		(end 414.195514 -86.29015)
		(width 0.15494)
		(layer "In5.Cu")
		(net "SSD14_PWRDIS_R")
	)
	(segment
		(start 423.698416 -29.707586)
		(end 423.698416 -32.905954)
		(width 0.15494)
		(layer "In5.Cu")
		(net "SSD14_PWRDIS_R")
	)
	(segment
		(start 349.747332 -123.033282)
		(end 345.783154 -126.99746)
		(width 0.15494)
		(layer "In5.Cu")
		(net "SSD14_PWRDIS_R")
	)
	(segment
		(start 419.0365 -27.333448)
		(end 420.237666 -27.333448)
		(width 0.15494)
		(layer "In5.Cu")
		(net "SSD14_PWRDIS_R")
	)
	(segment
		(start 339.598 -199.42048)
		(end 339.598 -200.152)
		(width 0.15494)
		(layer "In5.Cu")
		(net "SSD14_PWRDIS_R")
	)
	(segment
		(start 436.590186 -45.797724)
		(end 436.590186 -67.69227)
		(width 0.15494)
		(layer "In5.Cu")
		(net "SSD14_PWRDIS_R")
	)
	(segment
		(start 416.7378 -25.034748)
		(end 419.0365 -27.333448)
		(width 0.15494)
		(layer "In5.Cu")
		(net "SSD14_PWRDIS_R")
	)
	(segment
		(start 420.925498 -28.02128)
		(end 423.986706 -28.02128)
		(width 0.15494)
		(layer "In5.Cu")
		(net "SSD14_PWRDIS_R")
	)
	(segment
		(start 424.434508 -28.971494)
		(end 423.698416 -29.707586)
		(width 0.15494)
		(layer "In5.Cu")
		(net "SSD14_PWRDIS_R")
	)
	(segment
		(start 420.237666 -27.333448)
		(end 420.925498 -28.02128)
		(width 0.15494)
		(layer "In5.Cu")
		(net "SSD14_PWRDIS_R")
	)
	(segment
		(start 414.195514 -86.29015)
		(end 414.195514 -88.247728)
		(width 0.15494)
		(layer "In5.Cu")
		(net "SSD14_PWRDIS_R")
	)
	(segment
		(start 349.747332 -115.24107)
		(end 349.747332 -123.033282)
		(width 0.15494)
		(layer "In5.Cu")
		(net "SSD14_PWRDIS_R")
	)
	(segment
		(start 414.846516 -25.034748)
		(end 416.7378 -25.034748)
		(width 0.15494)
		(layer "In5.Cu")
		(net "SSD14_PWRDIS_R")
	)
	(segment
		(start 339.601048 -186.755024)
		(end 340.157562 -187.311538)
		(width 0.15494)
		(layer "In5.Cu")
		(net "SSD14_PWRDIS_R")
	)
	(segment
		(start 423.698416 -32.905954)
		(end 436.590186 -45.797724)
		(width 0.15494)
		(layer "In5.Cu")
		(net "SSD14_PWRDIS_R")
	)
	(segment
		(start 423.986706 -28.02128)
		(end 424.434508 -28.469082)
		(width 0.15494)
		(layer "In5.Cu")
		(net "SSD14_PWRDIS_R")
	)
	(segment
		(start 339.601048 -181.688994)
		(end 339.601048 -186.755024)
		(width 0.15494)
		(layer "In5.Cu")
		(net "SSD14_PWRDIS_R")
	)
	(segment
		(start 424.434508 -28.469082)
		(end 424.434508 -28.971494)
		(width 0.15494)
		(layer "In5.Cu")
		(net "SSD14_PWRDIS_R")
	)
	(segment
		(start 418.488876 -85.79358)
		(end 414.692084 -85.79358)
		(width 0.15494)
		(layer "In5.Cu")
		(net "SSD14_PWRDIS_R")
	)
	(segment
		(start 399.999454 -91.2114)
		(end 393.8016 -91.2114)
		(width 0.15494)
		(layer "In15.Cu")
		(net "SSD14_PWRDIS_R")
	)
	(segment
		(start 414.195514 -88.247728)
		(end 413.602678 -88.247728)
		(width 0.15494)
		(layer "In15.Cu")
		(net "SSD14_PWRDIS_R")
	)
	(segment
		(start 369.296188 -97.536)
		(end 368.015266 -98.816922)
		(width 0.15494)
		(layer "In15.Cu")
		(net "SSD14_PWRDIS_R")
	)
	(segment
		(start 379.9078 -97.536)
		(end 369.296188 -97.536)
		(width 0.15494)
		(layer "In15.Cu")
		(net "SSD14_PWRDIS_R")
	)
	(segment
		(start 368.015266 -98.816922)
		(end 357.744522 -98.816922)
		(width 0.15494)
		(layer "In15.Cu")
		(net "SSD14_PWRDIS_R")
	)
	(segment
		(start 393.8016 -91.2114)
		(end 391.7696 -93.2434)
		(width 0.15494)
		(layer "In15.Cu")
		(net "SSD14_PWRDIS_R")
	)
	(segment
		(start 356.006146 -98.6028)
		(end 355.658674 -98.950272)
		(width 0.15494)
		(layer "In15.Cu")
		(net "SSD14_PWRDIS_R")
	)
	(segment
		(start 357.5304 -98.6028)
		(end 356.006146 -98.6028)
		(width 0.15494)
		(layer "In15.Cu")
		(net "SSD14_PWRDIS_R")
	)
	(segment
		(start 357.744522 -98.816922)
		(end 357.5304 -98.6028)
		(width 0.15494)
		(layer "In15.Cu")
		(net "SSD14_PWRDIS_R")
	)
	(segment
		(start 413.602678 -88.247728)
		(end 413.18434 -88.666066)
		(width 0.15494)
		(layer "In15.Cu")
		(net "SSD14_PWRDIS_R")
	)
	(segment
		(start 391.7696 -93.2434)
		(end 384.2004 -93.2434)
		(width 0.15494)
		(layer "In15.Cu")
		(net "SSD14_PWRDIS_R")
	)
	(segment
		(start 355.658674 -98.950272)
		(end 355.658674 -99.125024)
		(width 0.15494)
		(layer "In15.Cu")
		(net "SSD14_PWRDIS_R")
	)
	(segment
		(start 402.544788 -88.666066)
		(end 399.999454 -91.2114)
		(width 0.15494)
		(layer "In15.Cu")
		(net "SSD14_PWRDIS_R")
	)
	(segment
		(start 413.18434 -88.666066)
		(end 402.544788 -88.666066)
		(width 0.15494)
		(layer "In15.Cu")
		(net "SSD14_PWRDIS_R")
	)
	(segment
		(start 384.2004 -93.2434)
		(end 379.9078 -97.536)
		(width 0.15494)
		(layer "In15.Cu")
		(net "SSD14_PWRDIS_R")
	)
	(segment
		(start 353.6188 -261.086854)
		(end 353.6188 -264.316718)
		(width 0.1778)
		(layer "F.Cu")
		(net "P0V8_PEX2_ISEN2")
	)
	(segment
		(start 353.575874 -260.795008)
		(end 353.575874 -261.043928)
		(width 0.1778)
		(layer "F.Cu")
		(net "P0V8_PEX2_ISEN2")
	)
	(segment
		(start 348.309438 -281.217116)
		(end 348.309438 -281.151838)
		(width 0.2286)
		(layer "F.Cu")
		(net "P0V8_PEX2_ISEN2")
	)
	(segment
		(start 353.575874 -261.043928)
		(end 353.6188 -261.086854)
		(width 0.1778)
		(layer "F.Cu")
		(net "P0V8_PEX2_ISEN2")
	)
	(segment
		(start 353.6188 -264.316718)
		(end 352.999548 -264.93597)
		(width 0.1778)
		(layer "F.Cu")
		(net "P0V8_PEX2_ISEN2")
	)
	(segment
		(start 347.872304 -281.65425)
		(end 348.309438 -281.217116)
		(width 0.2286)
		(layer "F.Cu")
		(net "P0V8_PEX2_ISEN2")
	)
	(segment
		(start 347.872304 -281.999182)
		(end 347.872304 -281.65425)
		(width 0.2286)
		(layer "F.Cu")
		(net "P0V8_PEX2_ISEN2")
	)
	(via
		(at 352.999548 -264.93597)
		(size 0.508)
		(drill 0.254)
		(layers "F.Cu" "B.Cu")
		(net "P0V8_PEX2_ISEN2")
	)
	(via
		(at 348.309438 -281.151838)
		(size 0.508)
		(drill 0.254)
		(layers "F.Cu" "B.Cu")
		(net "P0V8_PEX2_ISEN2")
	)
	(segment
		(start 349.317056 -280.663904)
		(end 348.797372 -280.663904)
		(width 0.254)
		(layer "In11.Cu")
		(net "P0V8_PEX2_ISEN2")
	)
	(segment
		(start 350.652588 -269.712186)
		(end 350.652588 -279.328372)
		(width 0.254)
		(layer "In11.Cu")
		(net "P0V8_PEX2_ISEN2")
	)
	(segment
		(start 348.797372 -280.663904)
		(end 348.309438 -281.151838)
		(width 0.254)
		(layer "In11.Cu")
		(net "P0V8_PEX2_ISEN2")
	)
	(segment
		(start 352.999548 -264.93597)
		(end 352.999548 -267.365226)
		(width 0.254)
		(layer "In11.Cu")
		(net "P0V8_PEX2_ISEN2")
	)
	(segment
		(start 352.999548 -267.365226)
		(end 350.652588 -269.712186)
		(width 0.254)
		(layer "In11.Cu")
		(net "P0V8_PEX2_ISEN2")
	)
	(segment
		(start 350.652588 -279.328372)
		(end 349.317056 -280.663904)
		(width 0.254)
		(layer "In11.Cu")
		(net "P0V8_PEX2_ISEN2")
	)
	(segment
		(start 295.441878 -159.68218)
		(end 295.008554 -159.248856)
		(width 0.13208)
		(layer "F.Cu")
		(net "NIC5_PWRBRK_N")
	)
	(segment
		(start 295.008554 -159.248856)
		(end 295.008554 -158.480252)
		(width 0.13208)
		(layer "F.Cu")
		(net "NIC5_PWRBRK_N")
	)
	(segment
		(start 295.441878 -160.981644)
		(end 295.441878 -159.68218)
		(width 0.13208)
		(layer "F.Cu")
		(net "NIC5_PWRBRK_N")
	)
	(segment
		(start 296.024554 -158.480252)
		(end 295.008554 -158.480252)
		(width 0.13208)
		(layer "F.Cu")
		(net "NIC5_PWRBRK_N")
	)
	(via
		(at 295.441878 -159.68218)
		(size 0.762)
		(drill 0.381)
		(layers "F.Cu" "B.Cu")
		(net "NIC5_PWRBRK_N")
	)
	(segment
		(start 207.914748 -218.83878)
		(end 207.773524 -218.697556)
		(width 0.13208)
		(layer "F.Cu")
		(net "UART_MB_BIC_RX_BUF_R")
	)
	(segment
		(start 208.58734 -218.83878)
		(end 207.914748 -218.83878)
		(width 0.13208)
		(layer "F.Cu")
		(net "UART_MB_BIC_RX_BUF_R")
	)
	(segment
		(start 207.270858 -220.0783)
		(end 207.490314 -219.858844)
		(width 0.13208)
		(layer "F.Cu")
		(net "UART_MB_BIC_RX_BUF_R")
	)
	(segment
		(start 209.026252 -219.277692)
		(end 208.58734 -218.83878)
		(width 0.13208)
		(layer "F.Cu")
		(net "UART_MB_BIC_RX_BUF_R")
	)
	(segment
		(start 207.270858 -220.39072)
		(end 207.270858 -220.0783)
		(width 0.13208)
		(layer "F.Cu")
		(net "UART_MB_BIC_RX_BUF_R")
	)
	(segment
		(start 207.773524 -218.697556)
		(end 207.773524 -218.236546)
		(width 0.13208)
		(layer "F.Cu")
		(net "UART_MB_BIC_RX_BUF_R")
	)
	(segment
		(start 208.4451 -219.858844)
		(end 209.026252 -219.277692)
		(width 0.13208)
		(layer "F.Cu")
		(net "UART_MB_BIC_RX_BUF_R")
	)
	(segment
		(start 207.490314 -219.858844)
		(end 208.4451 -219.858844)
		(width 0.13208)
		(layer "F.Cu")
		(net "UART_MB_BIC_RX_BUF_R")
	)
	(via
		(at 209.026252 -219.277692)
		(size 0.508)
		(drill 0.254)
		(layers "F.Cu" "B.Cu")
		(net "UART_MB_BIC_RX_BUF_R")
	)
	(segment
		(start 148.675852 -37.592)
		(end 148.675852 -37.315648)
		(width 0.13208)
		(layer "F.Cu")
		(net "PRSNT_SSD5_R1_N")
	)
	(segment
		(start 145.99793 -38.937184)
		(end 145.99793 -38.16731)
		(width 0.13208)
		(layer "F.Cu")
		(net "PRSNT_SSD5_R1_N")
	)
	(segment
		(start 148.493734 -37.774118)
		(end 148.675852 -37.592)
		(width 0.13208)
		(layer "F.Cu")
		(net "PRSNT_SSD5_R1_N")
	)
	(segment
		(start 146.391122 -37.774118)
		(end 147.946872 -37.774118)
		(width 0.13208)
		(layer "F.Cu")
		(net "PRSNT_SSD5_R1_N")
	)
	(segment
		(start 147.946872 -37.774118)
		(end 148.493734 -37.774118)
		(width 0.13208)
		(layer "F.Cu")
		(net "PRSNT_SSD5_R1_N")
	)
	(segment
		(start 145.99793 -38.16731)
		(end 146.391122 -37.774118)
		(width 0.13208)
		(layer "F.Cu")
		(net "PRSNT_SSD5_R1_N")
	)
	(via
		(at 147.946872 -37.774118)
		(size 0.508)
		(drill 0.254)
		(layers "F.Cu" "B.Cu")
		(net "PRSNT_SSD5_R1_N")
	)
	(segment
		(start 365.110268 -180.217064)
		(end 366.263936 -180.217064)
		(width 0.13208)
		(layer "F.Cu")
		(net "PCA9555_1_PEX1_A1")
	)
	(segment
		(start 360.78795 -181.102)
		(end 360.78795 -181.483)
		(width 0.13208)
		(layer "F.Cu")
		(net "PCA9555_1_PEX1_A1")
	)
	(segment
		(start 360.91495 -181.61)
		(end 363.728 -181.61)
		(width 0.13208)
		(layer "F.Cu")
		(net "PCA9555_1_PEX1_A1")
	)
	(segment
		(start 364.236 -181.091332)
		(end 365.110268 -180.217064)
		(width 0.13208)
		(layer "F.Cu")
		(net "PCA9555_1_PEX1_A1")
	)
	(segment
		(start 360.78795 -181.483)
		(end 360.91495 -181.61)
		(width 0.13208)
		(layer "F.Cu")
		(net "PCA9555_1_PEX1_A1")
	)
	(segment
		(start 359.55605 -181.102)
		(end 360.78795 -181.102)
		(width 0.13208)
		(layer "F.Cu")
		(net "PCA9555_1_PEX1_A1")
	)
	(segment
		(start 364.236 -181.102)
		(end 364.236 -181.091332)
		(width 0.13208)
		(layer "F.Cu")
		(net "PCA9555_1_PEX1_A1")
	)
	(segment
		(start 363.728 -181.61)
		(end 364.236 -181.102)
		(width 0.13208)
		(layer "F.Cu")
		(net "PCA9555_1_PEX1_A1")
	)
	(via
		(at 364.236 -181.091332)
		(size 0.508)
		(drill 0.254)
		(layers "F.Cu" "B.Cu")
		(net "PCA9555_1_PEX1_A1")
	)
	(segment
		(start 124.14123 -170.48988)
		(end 124.14631 -170.4848)
		(width 0.13208)
		(layer "F.Cu")
		(net "NIC1_CLK_EN_R_N")
	)
	(segment
		(start 358.41305 -227.584)
		(end 359.938574 -227.584)
		(width 0.13208)
		(layer "F.Cu")
		(net "NIC1_CLK_EN_R_N")
	)
	(segment
		(start 124.14123 -172.044868)
		(end 124.14123 -170.48988)
		(width 0.13208)
		(layer "F.Cu")
		(net "NIC1_CLK_EN_R_N")
	)
	(segment
		(start 124.14631 -169.474896)
		(end 124.14631 -170.4848)
		(width 0.13208)
		(layer "F.Cu")
		(net "NIC1_CLK_EN_R_N")
	)
	(via
		(at 124.14631 -169.474896)
		(size 0.508)
		(drill 0.254)
		(layers "F.Cu" "B.Cu")
		(net "NIC1_CLK_EN_R_N")
	)
	(via
		(at 359.938574 -227.584)
		(size 0.508)
		(drill 0.254)
		(layers "F.Cu" "B.Cu")
		(net "NIC1_CLK_EN_R_N")
	)
	(via
		(at 296.991024 -176.525682)
		(size 0.508)
		(drill 0.254)
		(layers "F.Cu" "B.Cu")
		(net "NIC1_CLK_EN_R_N")
	)
	(segment
		(start 167.4622 -173.9138)
		(end 149.2504 -173.9138)
		(width 0.15494)
		(layer "In13.Cu")
		(net "NIC1_CLK_EN_R_N")
	)
	(segment
		(start 212.842094 -171.214542)
		(end 209.177636 -174.879)
		(width 0.15494)
		(layer "In13.Cu")
		(net "NIC1_CLK_EN_R_N")
	)
	(segment
		(start 126.69901 -171.769024)
		(end 125.81763 -171.769024)
		(width 0.15494)
		(layer "In13.Cu")
		(net "NIC1_CLK_EN_R_N")
	)
	(segment
		(start 209.177636 -174.879)
		(end 168.4274 -174.879)
		(width 0.15494)
		(layer "In13.Cu")
		(net "NIC1_CLK_EN_R_N")
	)
	(segment
		(start 292.011608 -177.443638)
		(end 272.237962 -177.443638)
		(width 0.15494)
		(layer "In13.Cu")
		(net "NIC1_CLK_EN_R_N")
	)
	(segment
		(start 132.768086 -174.862236)
		(end 129.792222 -174.862236)
		(width 0.15494)
		(layer "In13.Cu")
		(net "NIC1_CLK_EN_R_N")
	)
	(segment
		(start 137.170922 -170.4594)
		(end 132.768086 -174.862236)
		(width 0.15494)
		(layer "In13.Cu")
		(net "NIC1_CLK_EN_R_N")
	)
	(segment
		(start 124.14631 -170.097704)
		(end 124.14631 -169.474896)
		(width 0.15494)
		(layer "In13.Cu")
		(net "NIC1_CLK_EN_R_N")
	)
	(segment
		(start 248.591324 -169.103548)
		(end 247.43664 -170.258232)
		(width 0.15494)
		(layer "In13.Cu")
		(net "NIC1_CLK_EN_R_N")
	)
	(segment
		(start 230.325168 -170.258232)
		(end 229.368858 -171.214542)
		(width 0.15494)
		(layer "In13.Cu")
		(net "NIC1_CLK_EN_R_N")
	)
	(segment
		(start 272.237962 -177.443638)
		(end 263.897872 -169.103548)
		(width 0.15494)
		(layer "In13.Cu")
		(net "NIC1_CLK_EN_R_N")
	)
	(segment
		(start 229.368858 -171.214542)
		(end 212.842094 -171.214542)
		(width 0.15494)
		(layer "In13.Cu")
		(net "NIC1_CLK_EN_R_N")
	)
	(segment
		(start 129.792222 -174.862236)
		(end 126.69901 -171.769024)
		(width 0.15494)
		(layer "In13.Cu")
		(net "NIC1_CLK_EN_R_N")
	)
	(segment
		(start 247.43664 -170.258232)
		(end 230.325168 -170.258232)
		(width 0.15494)
		(layer "In13.Cu")
		(net "NIC1_CLK_EN_R_N")
	)
	(segment
		(start 296.991024 -176.525682)
		(end 292.929564 -176.525682)
		(width 0.15494)
		(layer "In13.Cu")
		(net "NIC1_CLK_EN_R_N")
	)
	(segment
		(start 145.796 -170.4594)
		(end 137.170922 -170.4594)
		(width 0.15494)
		(layer "In13.Cu")
		(net "NIC1_CLK_EN_R_N")
	)
	(segment
		(start 263.897872 -169.103548)
		(end 248.591324 -169.103548)
		(width 0.15494)
		(layer "In13.Cu")
		(net "NIC1_CLK_EN_R_N")
	)
	(segment
		(start 168.4274 -174.879)
		(end 167.4622 -173.9138)
		(width 0.15494)
		(layer "In13.Cu")
		(net "NIC1_CLK_EN_R_N")
	)
	(segment
		(start 292.929564 -176.525682)
		(end 292.011608 -177.443638)
		(width 0.15494)
		(layer "In13.Cu")
		(net "NIC1_CLK_EN_R_N")
	)
	(segment
		(start 125.81763 -171.769024)
		(end 124.14631 -170.097704)
		(width 0.15494)
		(layer "In13.Cu")
		(net "NIC1_CLK_EN_R_N")
	)
	(segment
		(start 149.2504 -173.9138)
		(end 145.796 -170.4594)
		(width 0.15494)
		(layer "In13.Cu")
		(net "NIC1_CLK_EN_R_N")
	)
	(segment
		(start 348.783148 -178.787806)
		(end 346.980256 -176.984914)
		(width 0.15494)
		(layer "In15.Cu")
		(net "NIC1_CLK_EN_R_N")
	)
	(segment
		(start 368.095276 -197.815454)
		(end 368.095276 -189.356746)
		(width 0.15494)
		(layer "In15.Cu")
		(net "NIC1_CLK_EN_R_N")
	)
	(segment
		(start 342.373712 -175.81499)
		(end 297.701716 -175.81499)
		(width 0.15494)
		(layer "In15.Cu")
		(net "NIC1_CLK_EN_R_N")
	)
	(segment
		(start 363.628432 -224.798382)
		(end 365.106458 -224.798382)
		(width 0.15494)
		(layer "In15.Cu")
		(net "NIC1_CLK_EN_R_N")
	)
	(segment
		(start 367.374424 -222.530416)
		(end 367.374424 -212.48243)
		(width 0.15494)
		(layer "In15.Cu")
		(net "NIC1_CLK_EN_R_N")
	)
	(segment
		(start 357.07066 -179.09413)
		(end 356.576122 -179.09413)
		(width 0.15494)
		(layer "In15.Cu")
		(net "NIC1_CLK_EN_R_N")
	)
	(segment
		(start 357.93934 -180.56987)
		(end 357.398828 -180.029358)
		(width 0.15494)
		(layer "In15.Cu")
		(net "NIC1_CLK_EN_R_N")
	)
	(segment
		(start 367.494566 -204.818996)
		(end 367.494566 -198.416164)
		(width 0.15494)
		(layer "In15.Cu")
		(net "NIC1_CLK_EN_R_N")
	)
	(segment
		(start 350.31807 -178.787806)
		(end 348.783148 -178.787806)
		(width 0.15494)
		(layer "In15.Cu")
		(net "NIC1_CLK_EN_R_N")
	)
	(segment
		(start 368.095276 -189.356746)
		(end 359.3084 -180.56987)
		(width 0.15494)
		(layer "In15.Cu")
		(net "NIC1_CLK_EN_R_N")
	)
	(segment
		(start 367.494566 -198.416164)
		(end 368.095276 -197.815454)
		(width 0.15494)
		(layer "In15.Cu")
		(net "NIC1_CLK_EN_R_N")
	)
	(segment
		(start 367.05413 -205.259432)
		(end 367.494566 -204.818996)
		(width 0.15494)
		(layer "In15.Cu")
		(net "NIC1_CLK_EN_R_N")
	)
	(segment
		(start 367.05413 -212.162136)
		(end 367.05413 -205.259432)
		(width 0.15494)
		(layer "In15.Cu")
		(net "NIC1_CLK_EN_R_N")
	)
	(segment
		(start 351.027746 -178.07813)
		(end 350.31807 -178.787806)
		(width 0.15494)
		(layer "In15.Cu")
		(net "NIC1_CLK_EN_R_N")
	)
	(segment
		(start 357.398828 -180.029358)
		(end 357.398828 -179.422298)
		(width 0.15494)
		(layer "In15.Cu")
		(net "NIC1_CLK_EN_R_N")
	)
	(segment
		(start 355.560122 -178.07813)
		(end 351.027746 -178.07813)
		(width 0.15494)
		(layer "In15.Cu")
		(net "NIC1_CLK_EN_R_N")
	)
	(segment
		(start 357.398828 -179.422298)
		(end 357.07066 -179.09413)
		(width 0.15494)
		(layer "In15.Cu")
		(net "NIC1_CLK_EN_R_N")
	)
	(segment
		(start 365.106458 -224.798382)
		(end 367.374424 -222.530416)
		(width 0.15494)
		(layer "In15.Cu")
		(net "NIC1_CLK_EN_R_N")
	)
	(segment
		(start 356.576122 -179.09413)
		(end 355.560122 -178.07813)
		(width 0.15494)
		(layer "In15.Cu")
		(net "NIC1_CLK_EN_R_N")
	)
	(segment
		(start 367.374424 -212.48243)
		(end 367.05413 -212.162136)
		(width 0.15494)
		(layer "In15.Cu")
		(net "NIC1_CLK_EN_R_N")
	)
	(segment
		(start 343.543636 -176.984914)
		(end 342.373712 -175.81499)
		(width 0.15494)
		(layer "In15.Cu")
		(net "NIC1_CLK_EN_R_N")
	)
	(segment
		(start 359.3084 -180.56987)
		(end 357.93934 -180.56987)
		(width 0.15494)
		(layer "In15.Cu")
		(net "NIC1_CLK_EN_R_N")
	)
	(segment
		(start 359.938574 -227.584)
		(end 360.842814 -227.584)
		(width 0.15494)
		(layer "In15.Cu")
		(net "NIC1_CLK_EN_R_N")
	)
	(segment
		(start 360.842814 -227.584)
		(end 363.628432 -224.798382)
		(width 0.15494)
		(layer "In15.Cu")
		(net "NIC1_CLK_EN_R_N")
	)
	(segment
		(start 297.701716 -175.81499)
		(end 296.991024 -176.525682)
		(width 0.15494)
		(layer "In15.Cu")
		(net "NIC1_CLK_EN_R_N")
	)
	(segment
		(start 346.980256 -176.984914)
		(end 343.543636 -176.984914)
		(width 0.15494)
		(layer "In15.Cu")
		(net "NIC1_CLK_EN_R_N")
	)
	(segment
		(start 345.694 -204.83195)
		(end 345.694 -204.216)
		(width 0.13208)
		(layer "F.Cu")
		(net "SSD15_PWRDIS_R")
	)
	(segment
		(start 441.564776 -25.390094)
		(end 440.491118 -25.390094)
		(width 0.13208)
		(layer "F.Cu")
		(net "SSD15_PWRDIS_R")
	)
	(segment
		(start 450.9643 -29.079952)
		(end 450.434456 -28.550108)
		(width 0.13208)
		(layer "F.Cu")
		(net "SSD15_PWRDIS_R")
	)
	(segment
		(start 450.434456 -28.550108)
		(end 450.434456 -28.469082)
		(width 0.13208)
		(layer "F.Cu")
		(net "SSD15_PWRDIS_R")
	)
	(via
		(at 450.434456 -28.469082)
		(size 0.508)
		(drill 0.254)
		(layers "F.Cu" "B.Cu")
		(net "SSD15_PWRDIS_R")
	)
	(via
		(at 440.491118 -25.390094)
		(size 0.508)
		(drill 0.254)
		(layers "F.Cu" "B.Cu")
		(net "SSD15_PWRDIS_R")
	)
	(via
		(at 360.93527 -103.534464)
		(size 0.508)
		(drill 0.254)
		(layers "F.Cu" "B.Cu")
		(net "SSD15_PWRDIS_R")
	)
	(via
		(at 345.694 -204.216)
		(size 0.508)
		(drill 0.254)
		(layers "F.Cu" "B.Cu")
		(net "SSD15_PWRDIS_R")
	)
	(via
		(at 424.262042 -89.797636)
		(size 0.508)
		(drill 0.254)
		(layers "F.Cu" "B.Cu")
		(net "SSD15_PWRDIS_R")
	)
	(segment
		(start 438.597294 -77.64653)
		(end 429.220376 -87.023448)
		(width 0.15494)
		(layer "In5.Cu")
		(net "SSD15_PWRDIS_R")
	)
	(segment
		(start 450.161914 -28.19654)
		(end 447.33845 -28.19654)
		(width 0.15494)
		(layer "In5.Cu")
		(net "SSD15_PWRDIS_R")
	)
	(segment
		(start 425.189396 -88.870282)
		(end 424.262042 -89.797636)
		(width 0.15494)
		(layer "In5.Cu")
		(net "SSD15_PWRDIS_R")
	)
	(segment
		(start 449.698364 -29.64307)
		(end 449.698364 -32.791146)
		(width 0.15494)
		(layer "In5.Cu")
		(net "SSD15_PWRDIS_R")
	)
	(segment
		(start 345.694 -204.216)
		(end 345.694 -203.862686)
		(width 0.15494)
		(layer "In5.Cu")
		(net "SSD15_PWRDIS_R")
	)
	(segment
		(start 456.24496 -75.28814)
		(end 456.24496 -77.443076)
		(width 0.15494)
		(layer "In5.Cu")
		(net "SSD15_PWRDIS_R")
	)
	(segment
		(start 440.881262 -24.99995)
		(end 440.491118 -25.390094)
		(width 0.15494)
		(layer "In5.Cu")
		(net "SSD15_PWRDIS_R")
	)
	(segment
		(start 442.701172 -24.99995)
		(end 440.881262 -24.99995)
		(width 0.15494)
		(layer "In5.Cu")
		(net "SSD15_PWRDIS_R")
	)
	(segment
		(start 347.705426 -201.85126)
		(end 352.760534 -201.85126)
		(width 0.15494)
		(layer "In5.Cu")
		(net "SSD15_PWRDIS_R")
	)
	(segment
		(start 456.041506 -77.64653)
		(end 438.597294 -77.64653)
		(width 0.15494)
		(layer "In5.Cu")
		(net "SSD15_PWRDIS_R")
	)
	(segment
		(start 450.434456 -28.469082)
		(end 450.161914 -28.19654)
		(width 0.15494)
		(layer "In5.Cu")
		(net "SSD15_PWRDIS_R")
	)
	(segment
		(start 349.054674 -128.35382)
		(end 353.018852 -124.389642)
		(width 0.15494)
		(layer "In5.Cu")
		(net "SSD15_PWRDIS_R")
	)
	(segment
		(start 426.695362 -88.870282)
		(end 425.189396 -88.870282)
		(width 0.15494)
		(layer "In5.Cu")
		(net "SSD15_PWRDIS_R")
	)
	(segment
		(start 356.195376 -181.818788)
		(end 349.054674 -174.678086)
		(width 0.15494)
		(layer "In5.Cu")
		(net "SSD15_PWRDIS_R")
	)
	(segment
		(start 429.220376 -87.023448)
		(end 428.542196 -87.023448)
		(width 0.15494)
		(layer "In5.Cu")
		(net "SSD15_PWRDIS_R")
	)
	(segment
		(start 444.358268 -26.657046)
		(end 444.01867 -26.317702)
		(width 0.15494)
		(layer "In5.Cu")
		(net "SSD15_PWRDIS_R")
	)
	(segment
		(start 444.01867 -26.317702)
		(end 443.761876 -25.991312)
		(width 0.15494)
		(layer "In5.Cu")
		(net "SSD15_PWRDIS_R")
	)
	(segment
		(start 443.761876 -25.991312)
		(end 443.338966 -25.637744)
		(width 0.15494)
		(layer "In5.Cu")
		(net "SSD15_PWRDIS_R")
	)
	(segment
		(start 356.195376 -198.416418)
		(end 356.195376 -181.818788)
		(width 0.15494)
		(layer "In5.Cu")
		(net "SSD15_PWRDIS_R")
	)
	(segment
		(start 456.24496 -77.443076)
		(end 456.041506 -77.64653)
		(width 0.15494)
		(layer "In5.Cu")
		(net "SSD15_PWRDIS_R")
	)
	(segment
		(start 428.542196 -87.023448)
		(end 426.695362 -88.870282)
		(width 0.15494)
		(layer "In5.Cu")
		(net "SSD15_PWRDIS_R")
	)
	(segment
		(start 360.93527 -108.688378)
		(end 360.93527 -103.534464)
		(width 0.15494)
		(layer "In5.Cu")
		(net "SSD15_PWRDIS_R")
	)
	(segment
		(start 353.018852 -116.604796)
		(end 360.93527 -108.688378)
		(width 0.15494)
		(layer "In5.Cu")
		(net "SSD15_PWRDIS_R")
	)
	(segment
		(start 345.694 -203.862686)
		(end 347.705426 -201.85126)
		(width 0.15494)
		(layer "In5.Cu")
		(net "SSD15_PWRDIS_R")
	)
	(segment
		(start 455.58329 -74.62647)
		(end 456.24496 -75.28814)
		(width 0.15494)
		(layer "In5.Cu")
		(net "SSD15_PWRDIS_R")
	)
	(segment
		(start 455.58329 -38.676072)
		(end 455.58329 -74.62647)
		(width 0.15494)
		(layer "In5.Cu")
		(net "SSD15_PWRDIS_R")
	)
	(segment
		(start 353.018852 -124.389642)
		(end 353.018852 -116.604796)
		(width 0.15494)
		(layer "In5.Cu")
		(net "SSD15_PWRDIS_R")
	)
	(segment
		(start 443.338966 -25.637744)
		(end 442.701172 -24.99995)
		(width 0.15494)
		(layer "In5.Cu")
		(net "SSD15_PWRDIS_R")
	)
	(segment
		(start 446.495678 -27.353768)
		(end 445.05499 -27.353768)
		(width 0.15494)
		(layer "In5.Cu")
		(net "SSD15_PWRDIS_R")
	)
	(segment
		(start 445.05499 -27.353768)
		(end 444.358268 -26.657046)
		(width 0.15494)
		(layer "In5.Cu")
		(net "SSD15_PWRDIS_R")
	)
	(segment
		(start 450.434456 -28.906978)
		(end 449.698364 -29.64307)
		(width 0.15494)
		(layer "In5.Cu")
		(net "SSD15_PWRDIS_R")
	)
	(segment
		(start 352.760534 -201.85126)
		(end 356.195376 -198.416418)
		(width 0.15494)
		(layer "In5.Cu")
		(net "SSD15_PWRDIS_R")
	)
	(segment
		(start 349.054674 -174.678086)
		(end 349.054674 -128.35382)
		(width 0.15494)
		(layer "In5.Cu")
		(net "SSD15_PWRDIS_R")
	)
	(segment
		(start 447.33845 -28.19654)
		(end 446.495678 -27.353768)
		(width 0.15494)
		(layer "In5.Cu")
		(net "SSD15_PWRDIS_R")
	)
	(segment
		(start 449.698364 -32.791146)
		(end 455.58329 -38.676072)
		(width 0.15494)
		(layer "In5.Cu")
		(net "SSD15_PWRDIS_R")
	)
	(segment
		(start 450.434456 -28.469082)
		(end 450.434456 -28.906978)
		(width 0.15494)
		(layer "In5.Cu")
		(net "SSD15_PWRDIS_R")
	)
	(segment
		(start 407.734008 -91.97975)
		(end 408.857958 -90.8558)
		(width 0.15494)
		(layer "In15.Cu")
		(net "SSD15_PWRDIS_R")
	)
	(segment
		(start 369.937792 -101.49586)
		(end 381.419862 -101.49586)
		(width 0.15494)
		(layer "In15.Cu")
		(net "SSD15_PWRDIS_R")
	)
	(segment
		(start 386.330952 -97.5106)
		(end 395.154912 -97.5106)
		(width 0.15494)
		(layer "In15.Cu")
		(net "SSD15_PWRDIS_R")
	)
	(segment
		(start 385.959858 -97.881694)
		(end 386.330952 -97.5106)
		(width 0.15494)
		(layer "In15.Cu")
		(net "SSD15_PWRDIS_R")
	)
	(segment
		(start 362.209334 -102.2604)
		(end 369.173252 -102.2604)
		(width 0.15494)
		(layer "In15.Cu")
		(net "SSD15_PWRDIS_R")
	)
	(segment
		(start 395.154912 -97.5106)
		(end 395.307312 -97.663)
		(width 0.15494)
		(layer "In15.Cu")
		(net "SSD15_PWRDIS_R")
	)
	(segment
		(start 397.858996 -97.663)
		(end 403.542246 -91.97975)
		(width 0.15494)
		(layer "In15.Cu")
		(net "SSD15_PWRDIS_R")
	)
	(segment
		(start 381.419862 -101.49586)
		(end 385.034028 -97.881694)
		(width 0.15494)
		(layer "In15.Cu")
		(net "SSD15_PWRDIS_R")
	)
	(segment
		(start 385.034028 -97.881694)
		(end 385.959858 -97.881694)
		(width 0.15494)
		(layer "In15.Cu")
		(net "SSD15_PWRDIS_R")
	)
	(segment
		(start 360.93527 -103.534464)
		(end 362.209334 -102.2604)
		(width 0.15494)
		(layer "In15.Cu")
		(net "SSD15_PWRDIS_R")
	)
	(segment
		(start 369.173252 -102.2604)
		(end 369.937792 -101.49586)
		(width 0.15494)
		(layer "In15.Cu")
		(net "SSD15_PWRDIS_R")
	)
	(segment
		(start 423.203878 -90.8558)
		(end 424.262042 -89.797636)
		(width 0.15494)
		(layer "In15.Cu")
		(net "SSD15_PWRDIS_R")
	)
	(segment
		(start 395.307312 -97.663)
		(end 397.858996 -97.663)
		(width 0.15494)
		(layer "In15.Cu")
		(net "SSD15_PWRDIS_R")
	)
	(segment
		(start 408.857958 -90.8558)
		(end 423.203878 -90.8558)
		(width 0.15494)
		(layer "In15.Cu")
		(net "SSD15_PWRDIS_R")
	)
	(segment
		(start 403.542246 -91.97975)
		(end 407.734008 -91.97975)
		(width 0.15494)
		(layer "In15.Cu")
		(net "SSD15_PWRDIS_R")
	)
	(segment
		(start 411.541976 -159.68218)
		(end 411.108652 -159.248856)
		(width 0.13208)
		(layer "F.Cu")
		(net "NIC7_PWRBRK_N")
	)
	(segment
		(start 412.124652 -158.480252)
		(end 411.108652 -158.480252)
		(width 0.13208)
		(layer "F.Cu")
		(net "NIC7_PWRBRK_N")
	)
	(segment
		(start 411.108652 -159.248856)
		(end 411.108652 -158.480252)
		(width 0.13208)
		(layer "F.Cu")
		(net "NIC7_PWRBRK_N")
	)
	(segment
		(start 411.541976 -160.981644)
		(end 411.541976 -159.68218)
		(width 0.13208)
		(layer "F.Cu")
		(net "NIC7_PWRBRK_N")
	)
	(via
		(at 411.541976 -159.68218)
		(size 0.762)
		(drill 0.381)
		(layers "F.Cu" "B.Cu")
		(net "NIC7_PWRBRK_N")
	)
	(segment
		(start 118.956328 -33.8836)
		(end 118.956328 -33.248092)
		(width 0.13208)
		(layer "F.Cu")
		(net "SSD4_AUX_P3V3_EN_R")
	)
	(segment
		(start 117.226334 -37.529516)
		(end 118.302786 -37.529516)
		(width 0.13208)
		(layer "F.Cu")
		(net "SSD4_AUX_P3V3_EN_R")
	)
	(segment
		(start 118.302786 -37.529516)
		(end 118.956328 -36.874958)
		(width 0.13208)
		(layer "F.Cu")
		(net "SSD4_AUX_P3V3_EN_R")
	)
	(segment
		(start 122.241056 -57.675272)
		(end 121.840244 -58.076084)
		(width 0.13208)
		(layer "F.Cu")
		(net "SSD4_AUX_P3V3_EN_R")
	)
	(segment
		(start 122.241056 -57.16397)
		(end 122.241056 -57.675272)
		(width 0.13208)
		(layer "F.Cu")
		(net "SSD4_AUX_P3V3_EN_R")
	)
	(segment
		(start 120.815354 -59.100974)
		(end 120.815354 -59.146186)
		(width 0.13208)
		(layer "F.Cu")
		(net "SSD4_AUX_P3V3_EN_R")
	)
	(segment
		(start 118.999 -34.323528)
		(end 118.999 -33.926272)
		(width 0.13208)
		(layer "F.Cu")
		(net "SSD4_AUX_P3V3_EN_R")
	)
	(segment
		(start 118.999 -33.926272)
		(end 118.956328 -33.8836)
		(width 0.13208)
		(layer "F.Cu")
		(net "SSD4_AUX_P3V3_EN_R")
	)
	(segment
		(start 118.956328 -34.3662)
		(end 118.999 -34.323528)
		(width 0.13208)
		(layer "F.Cu")
		(net "SSD4_AUX_P3V3_EN_R")
	)
	(segment
		(start 116.377974 -39.97198)
		(end 116.377974 -37.84092)
		(width 0.13208)
		(layer "F.Cu")
		(net "SSD4_AUX_P3V3_EN_R")
	)
	(segment
		(start 118.956328 -36.874958)
		(end 118.956328 -34.3662)
		(width 0.13208)
		(layer "F.Cu")
		(net "SSD4_AUX_P3V3_EN_R")
	)
	(segment
		(start 116.377974 -37.84092)
		(end 116.69014 -37.529516)
		(width 0.13208)
		(layer "F.Cu")
		(net "SSD4_AUX_P3V3_EN_R")
	)
	(segment
		(start 121.840244 -58.076084)
		(end 120.815354 -59.100974)
		(width 0.13208)
		(layer "F.Cu")
		(net "SSD4_AUX_P3V3_EN_R")
	)
	(segment
		(start 116.69014 -37.529516)
		(end 117.226334 -37.529516)
		(width 0.13208)
		(layer "F.Cu")
		(net "SSD4_AUX_P3V3_EN_R")
	)
	(via
		(at 121.840244 -58.076084)
		(size 0.508)
		(drill 0.254)
		(layers "F.Cu" "B.Cu")
		(net "SSD4_AUX_P3V3_EN_R")
	)
	(via
		(at 116.377974 -39.97198)
		(size 0.508)
		(drill 0.254)
		(layers "F.Cu" "B.Cu")
		(net "SSD4_AUX_P3V3_EN_R")
	)
	(segment
		(start 116.433854 -40.02786)
		(end 116.433854 -55.953406)
		(width 0.15494)
		(layer "In5.Cu")
		(net "SSD4_AUX_P3V3_EN_R")
	)
	(segment
		(start 118.556532 -58.076084)
		(end 121.840244 -58.076084)
		(width 0.15494)
		(layer "In5.Cu")
		(net "SSD4_AUX_P3V3_EN_R")
	)
	(segment
		(start 116.377974 -39.97198)
		(end 116.433854 -40.02786)
		(width 0.15494)
		(layer "In5.Cu")
		(net "SSD4_AUX_P3V3_EN_R")
	)
	(segment
		(start 116.433854 -55.953406)
		(end 118.556532 -58.076084)
		(width 0.15494)
		(layer "In5.Cu")
		(net "SSD4_AUX_P3V3_EN_R")
	)
	(segment
		(start 91.351354 -310.761888)
		(end 91.351354 -311.004458)
		(width 0.13208)
		(layer "F.Cu")
		(net "PU_PEX0_SIO_BLINK")
	)
	(segment
		(start 91.351354 -311.004458)
		(end 90.947748 -311.408064)
		(width 0.13208)
		(layer "F.Cu")
		(net "PU_PEX0_SIO_BLINK")
	)
	(via
		(at 90.947748 -311.408064)
		(size 0.508)
		(drill 0.254)
		(layers "F.Cu" "B.Cu")
		(net "PU_PEX0_SIO_BLINK")
	)
	(via
		(at 60.599828 -309.199788)
		(size 0.4064)
		(drill 0.2032)
		(layers "F.Cu" "B.Cu")
		(net "PU_PEX0_SIO_BLINK")
	)
	(via
		(at 90.250772 -312.10504)
		(size 0.6604)
		(drill 0.3302)
		(layers "F.Cu" "B.Cu")
		(net "PU_PEX0_SIO_BLINK")
	)
	(segment
		(start 61.095382 -309.695342)
		(end 61.095382 -319.794636)
		(width 0.13208)
		(layer "B.Cu")
		(net "PU_PEX0_SIO_BLINK")
	)
	(segment
		(start 82.112612 -320.2432)
		(end 90.250772 -312.10504)
		(width 0.13208)
		(layer "B.Cu")
		(net "PU_PEX0_SIO_BLINK")
	)
	(segment
		(start 61.543946 -320.2432)
		(end 82.112612 -320.2432)
		(width 0.13208)
		(layer "B.Cu")
		(net "PU_PEX0_SIO_BLINK")
	)
	(segment
		(start 60.599828 -309.199788)
		(end 61.095382 -309.695342)
		(width 0.13208)
		(layer "B.Cu")
		(net "PU_PEX0_SIO_BLINK")
	)
	(segment
		(start 61.095382 -319.794636)
		(end 61.543946 -320.2432)
		(width 0.13208)
		(layer "B.Cu")
		(net "PU_PEX0_SIO_BLINK")
	)
	(segment
		(start 90.250772 -312.10504)
		(end 90.947748 -311.408064)
		(width 0.13208)
		(layer "B.Cu")
		(net "PU_PEX0_SIO_BLINK")
	)
	(segment
		(start 364.032292 -179.567078)
		(end 366.263936 -179.567078)
		(width 0.13208)
		(layer "F.Cu")
		(net "PCA9555_1_PEX1_A2")
	)
	(segment
		(start 359.55605 -180.086)
		(end 360.78795 -180.086)
		(width 0.13208)
		(layer "F.Cu")
		(net "PCA9555_1_PEX1_A2")
	)
	(segment
		(start 363.606588 -179.992782)
		(end 364.032292 -179.567078)
		(width 0.13208)
		(layer "F.Cu")
		(net "PCA9555_1_PEX1_A2")
	)
	(segment
		(start 360.78795 -180.086)
		(end 360.78795 -180.467)
		(width 0.13208)
		(layer "F.Cu")
		(net "PCA9555_1_PEX1_A2")
	)
	(segment
		(start 360.78795 -180.467)
		(end 360.91495 -180.594)
		(width 0.13208)
		(layer "F.Cu")
		(net "PCA9555_1_PEX1_A2")
	)
	(segment
		(start 360.91495 -180.594)
		(end 363.00537 -180.594)
		(width 0.13208)
		(layer "F.Cu")
		(net "PCA9555_1_PEX1_A2")
	)
	(segment
		(start 363.00537 -180.594)
		(end 363.606588 -179.992782)
		(width 0.13208)
		(layer "F.Cu")
		(net "PCA9555_1_PEX1_A2")
	)
	(via
		(at 363.606588 -179.992782)
		(size 0.508)
		(drill 0.254)
		(layers "F.Cu" "B.Cu")
		(net "PCA9555_1_PEX1_A2")
	)
	(segment
		(start 32.31769 -114.936524)
		(end 32.751776 -114.936524)
		(width 0.13208)
		(layer "F.Cu")
		(net "PRSNT_NIC0_R_N")
	)
	(segment
		(start 34.04108 -117.650006)
		(end 35.788092 -117.650006)
		(width 0.13208)
		(layer "F.Cu")
		(net "PRSNT_NIC0_R_N")
	)
	(segment
		(start 33.80613 -117.415056)
		(end 34.04108 -117.650006)
		(width 0.13208)
		(layer "F.Cu")
		(net "PRSNT_NIC0_R_N")
	)
	(segment
		(start 233.067606 -222.304102)
		(end 233.467402 -222.703898)
		(width 0.13208)
		(layer "F.Cu")
		(net "PRSNT_NIC0_R_N")
	)
	(segment
		(start 35.788092 -117.650006)
		(end 36.925504 -116.512594)
		(width 0.13208)
		(layer "F.Cu")
		(net "PRSNT_NIC0_R_N")
	)
	(segment
		(start 32.31769 -114.936524)
		(end 32.31769 -113.958624)
		(width 0.13208)
		(layer "F.Cu")
		(net "PRSNT_NIC0_R_N")
	)
	(segment
		(start 33.1978 -114.4905)
		(end 33.80613 -114.4905)
		(width 0.13208)
		(layer "F.Cu")
		(net "PRSNT_NIC0_R_N")
	)
	(segment
		(start 350.093788 -226.387152)
		(end 350.493584 -226.786948)
		(width 0.13208)
		(layer "F.Cu")
		(net "PRSNT_NIC0_R_N")
	)
	(segment
		(start 33.80613 -114.4905)
		(end 33.80613 -117.415056)
		(width 0.13208)
		(layer "F.Cu")
		(net "PRSNT_NIC0_R_N")
	)
	(segment
		(start 32.751776 -114.936524)
		(end 33.1978 -114.4905)
		(width 0.13208)
		(layer "F.Cu")
		(net "PRSNT_NIC0_R_N")
	)
	(via
		(at 234.026456 -241.617754)
		(size 0.508)
		(drill 0.254)
		(layers "F.Cu" "B.Cu")
		(net "PRSNT_NIC0_R_N")
	)
	(via
		(at 186.109102 -216.88806)
		(size 0.508)
		(drill 0.254)
		(layers "F.Cu" "B.Cu")
		(net "PRSNT_NIC0_R_N")
	)
	(via
		(at 233.467402 -222.703898)
		(size 0.4572)
		(drill 0.254)
		(layers "F.Cu" "B.Cu")
		(net "PRSNT_NIC0_R_N")
	)
	(via
		(at 36.925504 -116.512594)
		(size 0.508)
		(drill 0.254)
		(layers "F.Cu" "B.Cu")
		(net "PRSNT_NIC0_R_N")
	)
	(via
		(at 59.89066 -191.600328)
		(size 0.508)
		(drill 0.254)
		(layers "F.Cu" "B.Cu")
		(net "PRSNT_NIC0_R_N")
	)
	(via
		(at 350.493584 -226.786948)
		(size 0.4572)
		(drill 0.254)
		(layers "F.Cu" "B.Cu")
		(net "PRSNT_NIC0_R_N")
	)
	(segment
		(start 234.026456 -241.617754)
		(end 232.049574 -241.617754)
		(width 0.15494)
		(layer "In5.Cu")
		(net "PRSNT_NIC0_R_N")
	)
	(segment
		(start 232.9942 -223.875092)
		(end 233.069892 -223.7994)
		(width 0.15494)
		(layer "In5.Cu")
		(net "PRSNT_NIC0_R_N")
	)
	(segment
		(start 230.759 -240.32718)
		(end 230.759 -238.520986)
		(width 0.15494)
		(layer "In5.Cu")
		(net "PRSNT_NIC0_R_N")
	)
	(segment
		(start 233.069892 -223.101408)
		(end 233.467402 -222.703898)
		(width 0.0889)
		(layer "In5.Cu")
		(net "PRSNT_NIC0_R_N")
	)
	(segment
		(start 232.339642 -226.45497)
		(end 232.9942 -225.800412)
		(width 0.15494)
		(layer "In5.Cu")
		(net "PRSNT_NIC0_R_N")
	)
	(segment
		(start 232.339642 -236.940344)
		(end 232.339642 -226.45497)
		(width 0.15494)
		(layer "In5.Cu")
		(net "PRSNT_NIC0_R_N")
	)
	(segment
		(start 232.9942 -225.800412)
		(end 232.9942 -223.875092)
		(width 0.15494)
		(layer "In5.Cu")
		(net "PRSNT_NIC0_R_N")
	)
	(segment
		(start 230.759 -238.520986)
		(end 232.339642 -236.940344)
		(width 0.15494)
		(layer "In5.Cu")
		(net "PRSNT_NIC0_R_N")
	)
	(segment
		(start 233.069892 -223.7994)
		(end 233.069892 -223.101408)
		(width 0.0889)
		(layer "In5.Cu")
		(net "PRSNT_NIC0_R_N")
	)
	(segment
		(start 232.049574 -241.617754)
		(end 230.759 -240.32718)
		(width 0.15494)
		(layer "In5.Cu")
		(net "PRSNT_NIC0_R_N")
	)
	(segment
		(start 42.21734 -121.80443)
		(end 36.925504 -116.512594)
		(width 0.15494)
		(layer "In9.Cu")
		(net "PRSNT_NIC0_R_N")
	)
	(segment
		(start 52.0192 -143.129)
		(end 50.585624 -143.129)
		(width 0.15494)
		(layer "In9.Cu")
		(net "PRSNT_NIC0_R_N")
	)
	(segment
		(start 52.7177 -146.722846)
		(end 52.7177 -143.8275)
		(width 0.15494)
		(layer "In9.Cu")
		(net "PRSNT_NIC0_R_N")
	)
	(segment
		(start 47.13097 -144.43837)
		(end 42.21734 -139.52474)
		(width 0.15494)
		(layer "In9.Cu")
		(net "PRSNT_NIC0_R_N")
	)
	(segment
		(start 52.7177 -143.8275)
		(end 52.0192 -143.129)
		(width 0.15494)
		(layer "In9.Cu")
		(net "PRSNT_NIC0_R_N")
	)
	(segment
		(start 61.318648 -186.056016)
		(end 54.1528 -178.890168)
		(width 0.15494)
		(layer "In9.Cu")
		(net "PRSNT_NIC0_R_N")
	)
	(segment
		(start 49.276254 -144.43837)
		(end 47.13097 -144.43837)
		(width 0.15494)
		(layer "In9.Cu")
		(net "PRSNT_NIC0_R_N")
	)
	(segment
		(start 42.21734 -139.52474)
		(end 42.21734 -121.80443)
		(width 0.15494)
		(layer "In9.Cu")
		(net "PRSNT_NIC0_R_N")
	)
	(segment
		(start 59.89066 -191.600328)
		(end 61.318648 -190.17234)
		(width 0.15494)
		(layer "In9.Cu")
		(net "PRSNT_NIC0_R_N")
	)
	(segment
		(start 50.585624 -143.129)
		(end 49.276254 -144.43837)
		(width 0.15494)
		(layer "In9.Cu")
		(net "PRSNT_NIC0_R_N")
	)
	(segment
		(start 54.1528 -178.890168)
		(end 54.1528 -148.157946)
		(width 0.15494)
		(layer "In9.Cu")
		(net "PRSNT_NIC0_R_N")
	)
	(segment
		(start 61.318648 -190.17234)
		(end 61.318648 -186.056016)
		(width 0.15494)
		(layer "In9.Cu")
		(net "PRSNT_NIC0_R_N")
	)
	(segment
		(start 54.1528 -148.157946)
		(end 52.7177 -146.722846)
		(width 0.15494)
		(layer "In9.Cu")
		(net "PRSNT_NIC0_R_N")
	)
	(segment
		(start 238.364014 -243.03228)
		(end 236.11459 -240.782856)
		(width 0.15494)
		(layer "In13.Cu")
		(net "PRSNT_NIC0_R_N")
	)
	(segment
		(start 223.4438 -220.706442)
		(end 232.832402 -220.706442)
		(width 0.0889)
		(layer "In13.Cu")
		(net "PRSNT_NIC0_R_N")
	)
	(segment
		(start 232.832402 -220.706442)
		(end 233.065066 -220.939106)
		(width 0.0889)
		(layer "In13.Cu")
		(net "PRSNT_NIC0_R_N")
	)
	(segment
		(start 326.297036 -246.253)
		(end 304.241454 -246.253)
		(width 0.15494)
		(layer "In13.Cu")
		(net "PRSNT_NIC0_R_N")
	)
	(segment
		(start 344.610182 -240.159032)
		(end 339.786214 -244.983)
		(width 0.15494)
		(layer "In13.Cu")
		(net "PRSNT_NIC0_R_N")
	)
	(segment
		(start 233.065066 -222.301562)
		(end 233.467402 -222.703898)
		(width 0.0889)
		(layer "In13.Cu")
		(net "PRSNT_NIC0_R_N")
	)
	(segment
		(start 350.647 -227.49383)
		(end 350.647 -236.728)
		(width 0.15494)
		(layer "In13.Cu")
		(net "PRSNT_NIC0_R_N")
	)
	(segment
		(start 234.861354 -240.782856)
		(end 234.026456 -241.617754)
		(width 0.15494)
		(layer "In13.Cu")
		(net "PRSNT_NIC0_R_N")
	)
	(segment
		(start 350.493584 -226.786948)
		(end 350.493584 -227.340414)
		(width 0.15494)
		(layer "In13.Cu")
		(net "PRSNT_NIC0_R_N")
	)
	(segment
		(start 349.1738 -238.2012)
		(end 348.132654 -238.2012)
		(width 0.15494)
		(layer "In13.Cu")
		(net "PRSNT_NIC0_R_N")
	)
	(segment
		(start 301.5234 -246.8626)
		(end 299.948092 -245.287292)
		(width 0.15494)
		(layer "In13.Cu")
		(net "PRSNT_NIC0_R_N")
	)
	(segment
		(start 254.876808 -244.569488)
		(end 253.3396 -243.03228)
		(width 0.15494)
		(layer "In13.Cu")
		(net "PRSNT_NIC0_R_N")
	)
	(segment
		(start 191.002666 -221.781624)
		(end 208.319624 -221.781624)
		(width 0.15494)
		(layer "In13.Cu")
		(net "PRSNT_NIC0_R_N")
	)
	(segment
		(start 210.145884 -222.5294)
		(end 210.476084 -222.8596)
		(width 0.15494)
		(layer "In13.Cu")
		(net "PRSNT_NIC0_R_N")
	)
	(segment
		(start 350.647 -236.728)
		(end 349.1738 -238.2012)
		(width 0.15494)
		(layer "In13.Cu")
		(net "PRSNT_NIC0_R_N")
	)
	(segment
		(start 274.653248 -244.569488)
		(end 254.876808 -244.569488)
		(width 0.15494)
		(layer "In13.Cu")
		(net "PRSNT_NIC0_R_N")
	)
	(segment
		(start 210.476084 -222.8596)
		(end 218.933014 -222.8596)
		(width 0.15494)
		(layer "In13.Cu")
		(net "PRSNT_NIC0_R_N")
	)
	(segment
		(start 339.786214 -244.983)
		(end 336.2452 -244.983)
		(width 0.15494)
		(layer "In13.Cu")
		(net "PRSNT_NIC0_R_N")
	)
	(segment
		(start 350.493584 -227.340414)
		(end 350.647 -227.49383)
		(width 0.15494)
		(layer "In13.Cu")
		(net "PRSNT_NIC0_R_N")
	)
	(segment
		(start 218.933014 -222.8596)
		(end 221.086172 -220.706442)
		(width 0.15494)
		(layer "In13.Cu")
		(net "PRSNT_NIC0_R_N")
	)
	(segment
		(start 330.36256 -245.29288)
		(end 329.9587 -245.69674)
		(width 0.15494)
		(layer "In13.Cu")
		(net "PRSNT_NIC0_R_N")
	)
	(segment
		(start 208.319624 -221.781624)
		(end 209.0674 -222.5294)
		(width 0.15494)
		(layer "In13.Cu")
		(net "PRSNT_NIC0_R_N")
	)
	(segment
		(start 336.2452 -244.983)
		(end 335.787238 -245.440962)
		(width 0.15494)
		(layer "In13.Cu")
		(net "PRSNT_NIC0_R_N")
	)
	(segment
		(start 329.9587 -245.69674)
		(end 326.853296 -245.69674)
		(width 0.15494)
		(layer "In13.Cu")
		(net "PRSNT_NIC0_R_N")
	)
	(segment
		(start 299.948092 -245.287292)
		(end 275.371052 -245.287292)
		(width 0.15494)
		(layer "In13.Cu")
		(net "PRSNT_NIC0_R_N")
	)
	(segment
		(start 221.086172 -220.706442)
		(end 223.4438 -220.706442)
		(width 0.15494)
		(layer "In13.Cu")
		(net "PRSNT_NIC0_R_N")
	)
	(segment
		(start 253.3396 -243.03228)
		(end 238.364014 -243.03228)
		(width 0.15494)
		(layer "In13.Cu")
		(net "PRSNT_NIC0_R_N")
	)
	(segment
		(start 335.359756 -245.440962)
		(end 335.211674 -245.29288)
		(width 0.15494)
		(layer "In13.Cu")
		(net "PRSNT_NIC0_R_N")
	)
	(segment
		(start 186.109102 -216.88806)
		(end 191.002666 -221.781624)
		(width 0.15494)
		(layer "In13.Cu")
		(net "PRSNT_NIC0_R_N")
	)
	(segment
		(start 275.371052 -245.287292)
		(end 274.653248 -244.569488)
		(width 0.15494)
		(layer "In13.Cu")
		(net "PRSNT_NIC0_R_N")
	)
	(segment
		(start 348.132654 -238.2012)
		(end 346.174822 -240.159032)
		(width 0.15494)
		(layer "In13.Cu")
		(net "PRSNT_NIC0_R_N")
	)
	(segment
		(start 346.174822 -240.159032)
		(end 344.610182 -240.159032)
		(width 0.15494)
		(layer "In13.Cu")
		(net "PRSNT_NIC0_R_N")
	)
	(segment
		(start 335.787238 -245.440962)
		(end 335.359756 -245.440962)
		(width 0.15494)
		(layer "In13.Cu")
		(net "PRSNT_NIC0_R_N")
	)
	(segment
		(start 303.631854 -246.8626)
		(end 301.5234 -246.8626)
		(width 0.15494)
		(layer "In13.Cu")
		(net "PRSNT_NIC0_R_N")
	)
	(segment
		(start 233.065066 -220.939106)
		(end 233.065066 -222.301562)
		(width 0.0889)
		(layer "In13.Cu")
		(net "PRSNT_NIC0_R_N")
	)
	(segment
		(start 209.0674 -222.5294)
		(end 210.145884 -222.5294)
		(width 0.15494)
		(layer "In13.Cu")
		(net "PRSNT_NIC0_R_N")
	)
	(segment
		(start 326.853296 -245.69674)
		(end 326.297036 -246.253)
		(width 0.15494)
		(layer "In13.Cu")
		(net "PRSNT_NIC0_R_N")
	)
	(segment
		(start 335.211674 -245.29288)
		(end 330.36256 -245.29288)
		(width 0.15494)
		(layer "In13.Cu")
		(net "PRSNT_NIC0_R_N")
	)
	(segment
		(start 236.11459 -240.782856)
		(end 234.861354 -240.782856)
		(width 0.15494)
		(layer "In13.Cu")
		(net "PRSNT_NIC0_R_N")
	)
	(segment
		(start 304.241454 -246.253)
		(end 303.631854 -246.8626)
		(width 0.15494)
		(layer "In13.Cu")
		(net "PRSNT_NIC0_R_N")
	)
	(segment
		(start 117.208046 -202.882246)
		(end 114.34445 -202.882246)
		(width 0.15494)
		(layer "In15.Cu")
		(net "PRSNT_NIC0_R_N")
	)
	(segment
		(start 126.370842 -209.5754)
		(end 123.9012 -209.5754)
		(width 0.15494)
		(layer "In15.Cu")
		(net "PRSNT_NIC0_R_N")
	)
	(segment
		(start 114.34445 -202.882246)
		(end 108.185204 -196.723)
		(width 0.15494)
		(layer "In15.Cu")
		(net "PRSNT_NIC0_R_N")
	)
	(segment
		(start 131.057396 -208.7626)
		(end 127.183642 -208.7626)
		(width 0.15494)
		(layer "In15.Cu")
		(net "PRSNT_NIC0_R_N")
	)
	(segment
		(start 108.185204 -196.723)
		(end 99.565968 -196.723)
		(width 0.15494)
		(layer "In15.Cu")
		(net "PRSNT_NIC0_R_N")
	)
	(segment
		(start 186.109102 -216.88806)
		(end 181.846982 -212.62594)
		(width 0.15494)
		(layer "In15.Cu")
		(net "PRSNT_NIC0_R_N")
	)
	(segment
		(start 143.441166 -212.3186)
		(end 134.613396 -212.3186)
		(width 0.15494)
		(layer "In15.Cu")
		(net "PRSNT_NIC0_R_N")
	)
	(segment
		(start 67.604132 -199.3138)
		(end 59.89066 -191.600328)
		(width 0.15494)
		(layer "In15.Cu")
		(net "PRSNT_NIC0_R_N")
	)
	(segment
		(start 127.183642 -208.7626)
		(end 126.370842 -209.5754)
		(width 0.15494)
		(layer "In15.Cu")
		(net "PRSNT_NIC0_R_N")
	)
	(segment
		(start 143.748506 -212.62594)
		(end 143.441166 -212.3186)
		(width 0.15494)
		(layer "In15.Cu")
		(net "PRSNT_NIC0_R_N")
	)
	(segment
		(start 99.565968 -196.723)
		(end 96.975168 -199.3138)
		(width 0.15494)
		(layer "In15.Cu")
		(net "PRSNT_NIC0_R_N")
	)
	(segment
		(start 134.613396 -212.3186)
		(end 131.057396 -208.7626)
		(width 0.15494)
		(layer "In15.Cu")
		(net "PRSNT_NIC0_R_N")
	)
	(segment
		(start 181.846982 -212.62594)
		(end 143.748506 -212.62594)
		(width 0.15494)
		(layer "In15.Cu")
		(net "PRSNT_NIC0_R_N")
	)
	(segment
		(start 123.9012 -209.5754)
		(end 117.208046 -202.882246)
		(width 0.15494)
		(layer "In15.Cu")
		(net "PRSNT_NIC0_R_N")
	)
	(segment
		(start 96.975168 -199.3138)
		(end 67.604132 -199.3138)
		(width 0.15494)
		(layer "In15.Cu")
		(net "PRSNT_NIC0_R_N")
	)
	(segment
		(start 414.50387 -24.189944)
		(end 415.564828 -24.189944)
		(width 0.13208)
		(layer "F.Cu")
		(net "RST_SSD14_PERST_R_N")
	)
	(via
		(at 352.947478 -107.868212)
		(size 0.508)
		(drill 0.254)
		(layers "F.Cu" "B.Cu")
		(net "RST_SSD14_PERST_R_N")
	)
	(via
		(at 416.97021 -96.4184)
		(size 0.508)
		(drill 0.254)
		(layers "F.Cu" "B.Cu")
		(net "RST_SSD14_PERST_R_N")
	)
	(via
		(at 342.138 -206.15148)
		(size 0.508)
		(drill 0.254)
		(layers "F.Cu" "B.Cu")
		(net "RST_SSD14_PERST_R_N")
	)
	(via
		(at 414.50387 -24.189944)
		(size 0.508)
		(drill 0.254)
		(layers "F.Cu" "B.Cu")
		(net "RST_SSD14_PERST_R_N")
	)
	(segment
		(start 342.138 -206.629)
		(end 342.138 -206.15148)
		(width 0.13208)
		(layer "B.Cu")
		(net "RST_SSD14_PERST_R_N")
	)
	(segment
		(start 342.011 -207.37195)
		(end 342.011 -206.756)
		(width 0.13208)
		(layer "B.Cu")
		(net "RST_SSD14_PERST_R_N")
	)
	(segment
		(start 342.011 -206.756)
		(end 342.138 -206.629)
		(width 0.13208)
		(layer "B.Cu")
		(net "RST_SSD14_PERST_R_N")
	)
	(segment
		(start 420.428166 -26.873708)
		(end 421.115998 -27.56154)
		(width 0.15494)
		(layer "In5.Cu")
		(net "RST_SSD14_PERST_R_N")
	)
	(segment
		(start 415.718752 -86.268306)
		(end 415.091626 -86.895432)
		(width 0.15494)
		(layer "In5.Cu")
		(net "RST_SSD14_PERST_R_N")
	)
	(segment
		(start 419.227 -26.873708)
		(end 420.428166 -26.873708)
		(width 0.15494)
		(layer "In5.Cu")
		(net "RST_SSD14_PERST_R_N")
	)
	(segment
		(start 416.9283 -24.575008)
		(end 419.227 -26.873708)
		(width 0.15494)
		(layer "In5.Cu")
		(net "RST_SSD14_PERST_R_N")
	)
	(segment
		(start 437.049926 -45.607224)
		(end 437.049926 -67.88277)
		(width 0.15494)
		(layer "In5.Cu")
		(net "RST_SSD14_PERST_R_N")
	)
	(segment
		(start 421.115998 -27.56154)
		(end 424.223688 -27.56154)
		(width 0.15494)
		(layer "In5.Cu")
		(net "RST_SSD14_PERST_R_N")
	)
	(segment
		(start 414.50387 -24.189944)
		(end 414.888934 -24.575008)
		(width 0.15494)
		(layer "In5.Cu")
		(net "RST_SSD14_PERST_R_N")
	)
	(segment
		(start 415.091626 -94.539816)
		(end 416.97021 -96.4184)
		(width 0.15494)
		(layer "In5.Cu")
		(net "RST_SSD14_PERST_R_N")
	)
	(segment
		(start 424.918886 -28.256738)
		(end 424.918886 -29.137356)
		(width 0.15494)
		(layer "In5.Cu")
		(net "RST_SSD14_PERST_R_N")
	)
	(segment
		(start 415.091626 -86.895432)
		(end 415.091626 -94.539816)
		(width 0.15494)
		(layer "In5.Cu")
		(net "RST_SSD14_PERST_R_N")
	)
	(segment
		(start 424.158156 -29.898086)
		(end 424.158156 -32.715454)
		(width 0.15494)
		(layer "In5.Cu")
		(net "RST_SSD14_PERST_R_N")
	)
	(segment
		(start 418.66439 -86.268306)
		(end 415.718752 -86.268306)
		(width 0.15494)
		(layer "In5.Cu")
		(net "RST_SSD14_PERST_R_N")
	)
	(segment
		(start 414.888934 -24.575008)
		(end 416.9283 -24.575008)
		(width 0.15494)
		(layer "In5.Cu")
		(net "RST_SSD14_PERST_R_N")
	)
	(segment
		(start 437.049926 -67.88277)
		(end 418.66439 -86.268306)
		(width 0.15494)
		(layer "In5.Cu")
		(net "RST_SSD14_PERST_R_N")
	)
	(segment
		(start 424.918886 -29.137356)
		(end 424.158156 -29.898086)
		(width 0.15494)
		(layer "In5.Cu")
		(net "RST_SSD14_PERST_R_N")
	)
	(segment
		(start 424.158156 -32.715454)
		(end 437.049926 -45.607224)
		(width 0.15494)
		(layer "In5.Cu")
		(net "RST_SSD14_PERST_R_N")
	)
	(segment
		(start 424.223688 -27.56154)
		(end 424.918886 -28.256738)
		(width 0.15494)
		(layer "In5.Cu")
		(net "RST_SSD14_PERST_R_N")
	)
	(segment
		(start 344.4494 -198.2216)
		(end 344.6526 -198.4248)
		(width 0.15494)
		(layer "In9.Cu")
		(net "RST_SSD14_PERST_R_N")
	)
	(segment
		(start 344.4494 -192.024)
		(end 344.4494 -198.2216)
		(width 0.15494)
		(layer "In9.Cu")
		(net "RST_SSD14_PERST_R_N")
	)
	(segment
		(start 343.6366 -203.708)
		(end 343.332054 -203.708)
		(width 0.15494)
		(layer "In9.Cu")
		(net "RST_SSD14_PERST_R_N")
	)
	(segment
		(start 343.154 -205.13548)
		(end 342.138 -206.15148)
		(width 0.15494)
		(layer "In9.Cu")
		(net "RST_SSD14_PERST_R_N")
	)
	(segment
		(start 348.86646 -187.60694)
		(end 344.4494 -192.024)
		(width 0.15494)
		(layer "In9.Cu")
		(net "RST_SSD14_PERST_R_N")
	)
	(segment
		(start 344.6526 -202.692)
		(end 343.6366 -203.708)
		(width 0.15494)
		(layer "In9.Cu")
		(net "RST_SSD14_PERST_R_N")
	)
	(segment
		(start 348.86646 -141.048994)
		(end 348.86646 -187.60694)
		(width 0.15494)
		(layer "In9.Cu")
		(net "RST_SSD14_PERST_R_N")
	)
	(segment
		(start 343.154 -203.886054)
		(end 343.154 -205.13548)
		(width 0.15494)
		(layer "In9.Cu")
		(net "RST_SSD14_PERST_R_N")
	)
	(segment
		(start 352.947478 -107.868212)
		(end 351.79 -109.02569)
		(width 0.15494)
		(layer "In9.Cu")
		(net "RST_SSD14_PERST_R_N")
	)
	(segment
		(start 349.9358 -139.979654)
		(end 348.86646 -141.048994)
		(width 0.15494)
		(layer "In9.Cu")
		(net "RST_SSD14_PERST_R_N")
	)
	(segment
		(start 343.332054 -203.708)
		(end 343.154 -203.886054)
		(width 0.15494)
		(layer "In9.Cu")
		(net "RST_SSD14_PERST_R_N")
	)
	(segment
		(start 344.6526 -198.4248)
		(end 344.6526 -202.692)
		(width 0.15494)
		(layer "In9.Cu")
		(net "RST_SSD14_PERST_R_N")
	)
	(segment
		(start 351.79 -109.02569)
		(end 351.79 -122.4788)
		(width 0.15494)
		(layer "In9.Cu")
		(net "RST_SSD14_PERST_R_N")
	)
	(segment
		(start 349.9358 -124.333)
		(end 349.9358 -139.979654)
		(width 0.15494)
		(layer "In9.Cu")
		(net "RST_SSD14_PERST_R_N")
	)
	(segment
		(start 351.79 -122.4788)
		(end 349.9358 -124.333)
		(width 0.15494)
		(layer "In9.Cu")
		(net "RST_SSD14_PERST_R_N")
	)
	(segment
		(start 361.8992 -107.0864)
		(end 360.0704 -108.9152)
		(width 0.15494)
		(layer "In13.Cu")
		(net "RST_SSD14_PERST_R_N")
	)
	(segment
		(start 355.6 -107.2642)
		(end 353.60737 -107.2642)
		(width 0.15494)
		(layer "In13.Cu")
		(net "RST_SSD14_PERST_R_N")
	)
	(segment
		(start 415.508948 -97.089976)
		(end 414.634172 -96.2152)
		(width 0.15494)
		(layer "In13.Cu")
		(net "RST_SSD14_PERST_R_N")
	)
	(segment
		(start 360.0704 -108.9152)
		(end 357.251 -108.9152)
		(width 0.15494)
		(layer "In13.Cu")
		(net "RST_SSD14_PERST_R_N")
	)
	(segment
		(start 416.298634 -97.089976)
		(end 415.508948 -97.089976)
		(width 0.15494)
		(layer "In13.Cu")
		(net "RST_SSD14_PERST_R_N")
	)
	(segment
		(start 353.60737 -107.2642)
		(end 353.003358 -107.868212)
		(width 0.15494)
		(layer "In13.Cu")
		(net "RST_SSD14_PERST_R_N")
	)
	(segment
		(start 414.634172 -96.2152)
		(end 406.208992 -96.2152)
		(width 0.15494)
		(layer "In13.Cu")
		(net "RST_SSD14_PERST_R_N")
	)
	(segment
		(start 379.117606 -105.488994)
		(end 377.5202 -107.0864)
		(width 0.15494)
		(layer "In13.Cu")
		(net "RST_SSD14_PERST_R_N")
	)
	(segment
		(start 357.251 -108.9152)
		(end 355.6 -107.2642)
		(width 0.15494)
		(layer "In13.Cu")
		(net "RST_SSD14_PERST_R_N")
	)
	(segment
		(start 406.208992 -96.2152)
		(end 405.540972 -95.938594)
		(width 0.15494)
		(layer "In13.Cu")
		(net "RST_SSD14_PERST_R_N")
	)
	(segment
		(start 405.540972 -95.938594)
		(end 399.705068 -95.938594)
		(width 0.15494)
		(layer "In13.Cu")
		(net "RST_SSD14_PERST_R_N")
	)
	(segment
		(start 393.953492 -97.637092)
		(end 390.1694 -93.853)
		(width 0.15494)
		(layer "In13.Cu")
		(net "RST_SSD14_PERST_R_N")
	)
	(segment
		(start 416.97021 -96.4184)
		(end 416.298634 -97.089976)
		(width 0.15494)
		(layer "In13.Cu")
		(net "RST_SSD14_PERST_R_N")
	)
	(segment
		(start 398.00657 -97.637092)
		(end 393.953492 -97.637092)
		(width 0.15494)
		(layer "In13.Cu")
		(net "RST_SSD14_PERST_R_N")
	)
	(segment
		(start 390.1694 -93.853)
		(end 385.55295 -93.853)
		(width 0.15494)
		(layer "In13.Cu")
		(net "RST_SSD14_PERST_R_N")
	)
	(segment
		(start 385.55295 -93.853)
		(end 379.117606 -100.288344)
		(width 0.15494)
		(layer "In13.Cu")
		(net "RST_SSD14_PERST_R_N")
	)
	(segment
		(start 353.003358 -107.868212)
		(end 352.947478 -107.868212)
		(width 0.15494)
		(layer "In13.Cu")
		(net "RST_SSD14_PERST_R_N")
	)
	(segment
		(start 399.705068 -95.938594)
		(end 398.00657 -97.637092)
		(width 0.15494)
		(layer "In13.Cu")
		(net "RST_SSD14_PERST_R_N")
	)
	(segment
		(start 379.117606 -100.288344)
		(end 379.117606 -105.488994)
		(width 0.15494)
		(layer "In13.Cu")
		(net "RST_SSD14_PERST_R_N")
	)
	(segment
		(start 377.5202 -107.0864)
		(end 361.8992 -107.0864)
		(width 0.15494)
		(layer "In13.Cu")
		(net "RST_SSD14_PERST_R_N")
	)
	(segment
		(start 410.041852 -164.56533)
		(end 410.041852 -164.0586)
		(width 0.13208)
		(layer "F.Cu")
		(net "NIC6_PWRBRK_N")
	)
	(segment
		(start 409.793948 -164.813234)
		(end 410.041852 -164.56533)
		(width 0.13208)
		(layer "F.Cu")
		(net "NIC6_PWRBRK_N")
	)
	(segment
		(start 410.809948 -165.270434)
		(end 409.793948 -165.270434)
		(width 0.13208)
		(layer "F.Cu")
		(net "NIC6_PWRBRK_N")
	)
	(segment
		(start 409.793948 -165.270434)
		(end 409.793948 -164.813234)
		(width 0.13208)
		(layer "F.Cu")
		(net "NIC6_PWRBRK_N")
	)
	(segment
		(start 410.041852 -164.0586)
		(end 410.041852 -162.781488)
		(width 0.13208)
		(layer "F.Cu")
		(net "NIC6_PWRBRK_N")
	)
	(via
		(at 410.041852 -164.0586)
		(size 0.762)
		(drill 0.381)
		(layers "F.Cu" "B.Cu")
		(net "NIC6_PWRBRK_N")
	)
	(segment
		(start 206.598266 -220.902022)
		(end 206.887064 -221.19082)
		(width 0.13208)
		(layer "F.Cu")
		(net "UART_MB_BIC_RX_BUF")
	)
	(segment
		(start 206.122778 -222.723456)
		(end 205.74254 -222.343218)
		(width 0.13208)
		(layer "F.Cu")
		(net "UART_MB_BIC_RX_BUF")
	)
	(segment
		(start 206.064866 -220.902022)
		(end 206.598266 -220.902022)
		(width 0.13208)
		(layer "F.Cu")
		(net "UART_MB_BIC_RX_BUF")
	)
	(segment
		(start 206.9592 -222.723456)
		(end 206.122778 -222.723456)
		(width 0.13208)
		(layer "F.Cu")
		(net "UART_MB_BIC_RX_BUF")
	)
	(segment
		(start 205.74254 -221.224348)
		(end 206.064866 -220.902022)
		(width 0.13208)
		(layer "F.Cu")
		(net "UART_MB_BIC_RX_BUF")
	)
	(segment
		(start 205.74254 -222.343218)
		(end 205.74254 -221.224348)
		(width 0.13208)
		(layer "F.Cu")
		(net "UART_MB_BIC_RX_BUF")
	)
	(segment
		(start 206.887064 -221.19082)
		(end 207.270858 -221.19082)
		(width 0.13208)
		(layer "F.Cu")
		(net "UART_MB_BIC_RX_BUF")
	)
	(via
		(at 206.064866 -220.902022)
		(size 0.762)
		(drill 0.381)
		(layers "F.Cu" "B.Cu")
		(net "UART_MB_BIC_RX_BUF")
	)
	(via
		(at 28.043886 -260.119876)
		(size 0.508)
		(drill 0.254)
		(layers "F.Cu" "B.Cu")
		(net "P1V8_VDDA_PEX0_R")
	)
	(segment
		(start 377.08205 -178.917092)
		(end 377.20905 -179.044092)
		(width 0.13208)
		(layer "F.Cu")
		(net "PCA9555_1_PEX1_A0")
	)
	(segment
		(start 378.44095 -179.451)
		(end 377.20905 -179.451)
		(width 0.13208)
		(layer "F.Cu")
		(net "PCA9555_1_PEX1_A0")
	)
	(segment
		(start 375.085864 -178.917092)
		(end 377.08205 -178.917092)
		(width 0.13208)
		(layer "F.Cu")
		(net "PCA9555_1_PEX1_A0")
	)
	(segment
		(start 377.20905 -179.044092)
		(end 377.20905 -179.451)
		(width 0.13208)
		(layer "F.Cu")
		(net "PCA9555_1_PEX1_A0")
	)
	(segment
		(start 372.114064 -178.917092)
		(end 375.085864 -178.917092)
		(width 0.13208)
		(layer "F.Cu")
		(net "PCA9555_1_PEX1_A0")
	)
	(via
		(at 375.085864 -178.917092)
		(size 0.508)
		(drill 0.254)
		(layers "F.Cu" "B.Cu")
		(net "PCA9555_1_PEX1_A0")
	)
	(segment
		(start 358.41305 -229.616)
		(end 359.029 -229.616)
		(width 0.13208)
		(layer "F.Cu")
		(net "RST_NIC1_PERST_R_N")
	)
	(segment
		(start 81.349596 -84.476336)
		(end 80.249776 -84.476336)
		(width 0.13208)
		(layer "F.Cu")
		(net "RST_NIC1_PERST_R_N")
	)
	(via
		(at 96.764602 -185.674)
		(size 0.508)
		(drill 0.254)
		(layers "F.Cu" "B.Cu")
		(net "RST_NIC1_PERST_R_N")
	)
	(via
		(at 359.029 -229.616)
		(size 0.508)
		(drill 0.254)
		(layers "F.Cu" "B.Cu")
		(net "RST_NIC1_PERST_R_N")
	)
	(via
		(at 80.249776 -84.476336)
		(size 0.508)
		(drill 0.254)
		(layers "F.Cu" "B.Cu")
		(net "RST_NIC1_PERST_R_N")
	)
	(segment
		(start 79.655416 -114.658394)
		(end 81.118964 -116.121942)
		(width 0.15494)
		(layer "In5.Cu")
		(net "RST_NIC1_PERST_R_N")
	)
	(segment
		(start 80.249776 -84.476336)
		(end 82.123534 -86.350094)
		(width 0.15494)
		(layer "In5.Cu")
		(net "RST_NIC1_PERST_R_N")
	)
	(segment
		(start 87.28456 -119.418608)
		(end 87.28456 -127.42545)
		(width 0.15494)
		(layer "In5.Cu")
		(net "RST_NIC1_PERST_R_N")
	)
	(segment
		(start 81.118964 -116.121942)
		(end 83.987894 -116.121942)
		(width 0.15494)
		(layer "In5.Cu")
		(net "RST_NIC1_PERST_R_N")
	)
	(segment
		(start 79.655416 -108.928916)
		(end 79.655416 -114.658394)
		(width 0.15494)
		(layer "In5.Cu")
		(net "RST_NIC1_PERST_R_N")
	)
	(segment
		(start 93.81744 -177.90033)
		(end 95.311468 -179.394358)
		(width 0.15494)
		(layer "In5.Cu")
		(net "RST_NIC1_PERST_R_N")
	)
	(segment
		(start 93.81744 -142.100046)
		(end 93.81744 -177.90033)
		(width 0.15494)
		(layer "In5.Cu")
		(net "RST_NIC1_PERST_R_N")
	)
	(segment
		(start 90.45956 -133.993382)
		(end 93.81744 -142.100046)
		(width 0.15494)
		(layer "In5.Cu")
		(net "RST_NIC1_PERST_R_N")
	)
	(segment
		(start 80.927702 -91.211654)
		(end 80.927702 -107.65663)
		(width 0.15494)
		(layer "In5.Cu")
		(net "RST_NIC1_PERST_R_N")
	)
	(segment
		(start 82.123534 -86.350094)
		(end 82.123534 -90.015822)
		(width 0.15494)
		(layer "In5.Cu")
		(net "RST_NIC1_PERST_R_N")
	)
	(segment
		(start 95.311468 -179.394358)
		(end 95.311468 -184.220866)
		(width 0.15494)
		(layer "In5.Cu")
		(net "RST_NIC1_PERST_R_N")
	)
	(segment
		(start 82.123534 -90.015822)
		(end 80.927702 -91.211654)
		(width 0.15494)
		(layer "In5.Cu")
		(net "RST_NIC1_PERST_R_N")
	)
	(segment
		(start 80.927702 -107.65663)
		(end 79.655416 -108.928916)
		(width 0.15494)
		(layer "In5.Cu")
		(net "RST_NIC1_PERST_R_N")
	)
	(segment
		(start 83.987894 -116.121942)
		(end 87.28456 -119.418608)
		(width 0.15494)
		(layer "In5.Cu")
		(net "RST_NIC1_PERST_R_N")
	)
	(segment
		(start 90.45956 -130.60045)
		(end 90.45956 -133.993382)
		(width 0.15494)
		(layer "In5.Cu")
		(net "RST_NIC1_PERST_R_N")
	)
	(segment
		(start 95.311468 -184.220866)
		(end 96.764602 -185.674)
		(width 0.15494)
		(layer "In5.Cu")
		(net "RST_NIC1_PERST_R_N")
	)
	(segment
		(start 87.28456 -127.42545)
		(end 90.45956 -130.60045)
		(width 0.15494)
		(layer "In5.Cu")
		(net "RST_NIC1_PERST_R_N")
	)
	(segment
		(start 232.890568 -174.16145)
		(end 231.564688 -174.16145)
		(width 0.15494)
		(layer "In15.Cu")
		(net "RST_NIC1_PERST_R_N")
	)
	(segment
		(start 259.297424 -174.814738)
		(end 233.543856 -174.814738)
		(width 0.15494)
		(layer "In15.Cu")
		(net "RST_NIC1_PERST_R_N")
	)
	(segment
		(start 371.443758 -224.83953)
		(end 370.410232 -223.806004)
		(width 0.15494)
		(layer "In15.Cu")
		(net "RST_NIC1_PERST_R_N")
	)
	(segment
		(start 112.3442 -189.103)
		(end 103.1494 -189.103)
		(width 0.15494)
		(layer "In15.Cu")
		(net "RST_NIC1_PERST_R_N")
	)
	(segment
		(start 346.389198 -175.450754)
		(end 343.544906 -172.606462)
		(width 0.15494)
		(layer "In15.Cu")
		(net "RST_NIC1_PERST_R_N")
	)
	(segment
		(start 361.90047 -230.6574)
		(end 362.262674 -230.295196)
		(width 0.15494)
		(layer "In15.Cu")
		(net "RST_NIC1_PERST_R_N")
	)
	(segment
		(start 361.195112 -230.6574)
		(end 361.90047 -230.6574)
		(width 0.15494)
		(layer "In15.Cu")
		(net "RST_NIC1_PERST_R_N")
	)
	(segment
		(start 180.21046 -176.212246)
		(end 178.89982 -176.212246)
		(width 0.15494)
		(layer "In15.Cu")
		(net "RST_NIC1_PERST_R_N")
	)
	(segment
		(start 360.162348 -175.48987)
		(end 357.93934 -175.48987)
		(width 0.15494)
		(layer "In15.Cu")
		(net "RST_NIC1_PERST_R_N")
	)
	(segment
		(start 233.543856 -174.814738)
		(end 232.890568 -174.16145)
		(width 0.15494)
		(layer "In15.Cu")
		(net "RST_NIC1_PERST_R_N")
	)
	(segment
		(start 364.337854 -177.683668)
		(end 362.356146 -177.683668)
		(width 0.15494)
		(layer "In15.Cu")
		(net "RST_NIC1_PERST_R_N")
	)
	(segment
		(start 124.069094 -187.848748)
		(end 113.598452 -187.848748)
		(width 0.15494)
		(layer "In15.Cu")
		(net "RST_NIC1_PERST_R_N")
	)
	(segment
		(start 343.544906 -172.606462)
		(end 334.522826 -172.606462)
		(width 0.15494)
		(layer "In15.Cu")
		(net "RST_NIC1_PERST_R_N")
	)
	(segment
		(start 357.900224 -175.450754)
		(end 346.389198 -175.450754)
		(width 0.15494)
		(layer "In15.Cu")
		(net "RST_NIC1_PERST_R_N")
	)
	(segment
		(start 182.513224 -174.626524)
		(end 181.434232 -175.705516)
		(width 0.15494)
		(layer "In15.Cu")
		(net "RST_NIC1_PERST_R_N")
	)
	(segment
		(start 99.5934 -185.547)
		(end 96.891602 -185.547)
		(width 0.15494)
		(layer "In15.Cu")
		(net "RST_NIC1_PERST_R_N")
	)
	(segment
		(start 334.522826 -172.606462)
		(end 333.955898 -173.17339)
		(width 0.15494)
		(layer "In15.Cu")
		(net "RST_NIC1_PERST_R_N")
	)
	(segment
		(start 360.153712 -229.616)
		(end 361.195112 -230.6574)
		(width 0.15494)
		(layer "In15.Cu")
		(net "RST_NIC1_PERST_R_N")
	)
	(segment
		(start 365.172752 -178.271932)
		(end 364.926118 -178.271932)
		(width 0.15494)
		(layer "In15.Cu")
		(net "RST_NIC1_PERST_R_N")
	)
	(segment
		(start 231.564688 -174.16145)
		(end 230.950008 -173.54677)
		(width 0.15494)
		(layer "In15.Cu")
		(net "RST_NIC1_PERST_R_N")
	)
	(segment
		(start 333.955898 -173.17339)
		(end 260.938772 -173.17339)
		(width 0.15494)
		(layer "In15.Cu")
		(net "RST_NIC1_PERST_R_N")
	)
	(segment
		(start 214.380572 -174.626524)
		(end 182.513224 -174.626524)
		(width 0.15494)
		(layer "In15.Cu")
		(net "RST_NIC1_PERST_R_N")
	)
	(segment
		(start 371.443758 -226.601528)
		(end 371.443758 -224.83953)
		(width 0.15494)
		(layer "In15.Cu")
		(net "RST_NIC1_PERST_R_N")
	)
	(segment
		(start 370.805202 -215.252046)
		(end 370.805202 -186.741816)
		(width 0.15494)
		(layer "In15.Cu")
		(net "RST_NIC1_PERST_R_N")
	)
	(segment
		(start 370.805202 -186.741816)
		(end 368.016536 -183.95315)
		(width 0.15494)
		(layer "In15.Cu")
		(net "RST_NIC1_PERST_R_N")
	)
	(segment
		(start 368.016536 -183.95315)
		(end 368.016536 -181.115716)
		(width 0.15494)
		(layer "In15.Cu")
		(net "RST_NIC1_PERST_R_N")
	)
	(segment
		(start 362.356146 -177.683668)
		(end 360.162348 -175.48987)
		(width 0.15494)
		(layer "In15.Cu")
		(net "RST_NIC1_PERST_R_N")
	)
	(segment
		(start 260.938772 -173.17339)
		(end 259.297424 -174.814738)
		(width 0.15494)
		(layer "In15.Cu")
		(net "RST_NIC1_PERST_R_N")
	)
	(segment
		(start 230.950008 -173.54677)
		(end 215.460326 -173.54677)
		(width 0.15494)
		(layer "In15.Cu")
		(net "RST_NIC1_PERST_R_N")
	)
	(segment
		(start 370.410232 -215.647016)
		(end 370.805202 -215.252046)
		(width 0.15494)
		(layer "In15.Cu")
		(net "RST_NIC1_PERST_R_N")
	)
	(segment
		(start 368.016536 -181.115716)
		(end 365.172752 -178.271932)
		(width 0.15494)
		(layer "In15.Cu")
		(net "RST_NIC1_PERST_R_N")
	)
	(segment
		(start 138.877548 -190.7794)
		(end 126.999746 -190.7794)
		(width 0.15494)
		(layer "In15.Cu")
		(net "RST_NIC1_PERST_R_N")
	)
	(segment
		(start 96.891602 -185.547)
		(end 96.764602 -185.674)
		(width 0.15494)
		(layer "In15.Cu")
		(net "RST_NIC1_PERST_R_N")
	)
	(segment
		(start 370.410232 -223.806004)
		(end 370.410232 -215.647016)
		(width 0.15494)
		(layer "In15.Cu")
		(net "RST_NIC1_PERST_R_N")
	)
	(segment
		(start 364.926118 -178.271932)
		(end 364.337854 -177.683668)
		(width 0.15494)
		(layer "In15.Cu")
		(net "RST_NIC1_PERST_R_N")
	)
	(segment
		(start 103.1494 -189.103)
		(end 99.5934 -185.547)
		(width 0.15494)
		(layer "In15.Cu")
		(net "RST_NIC1_PERST_R_N")
	)
	(segment
		(start 139.676124 -191.577976)
		(end 138.877548 -190.7794)
		(width 0.15494)
		(layer "In15.Cu")
		(net "RST_NIC1_PERST_R_N")
	)
	(segment
		(start 178.89982 -176.212246)
		(end 164.650166 -190.4619)
		(width 0.15494)
		(layer "In15.Cu")
		(net "RST_NIC1_PERST_R_N")
	)
	(segment
		(start 113.598452 -187.848748)
		(end 112.3442 -189.103)
		(width 0.15494)
		(layer "In15.Cu")
		(net "RST_NIC1_PERST_R_N")
	)
	(segment
		(start 181.434232 -175.705516)
		(end 180.21046 -176.212246)
		(width 0.15494)
		(layer "In15.Cu")
		(net "RST_NIC1_PERST_R_N")
	)
	(segment
		(start 145.033492 -191.577976)
		(end 139.676124 -191.577976)
		(width 0.15494)
		(layer "In15.Cu")
		(net "RST_NIC1_PERST_R_N")
	)
	(segment
		(start 164.650166 -190.4619)
		(end 146.149568 -190.4619)
		(width 0.15494)
		(layer "In15.Cu")
		(net "RST_NIC1_PERST_R_N")
	)
	(segment
		(start 126.999746 -190.7794)
		(end 124.069094 -187.848748)
		(width 0.15494)
		(layer "In15.Cu")
		(net "RST_NIC1_PERST_R_N")
	)
	(segment
		(start 146.149568 -190.4619)
		(end 145.033492 -191.577976)
		(width 0.15494)
		(layer "In15.Cu")
		(net "RST_NIC1_PERST_R_N")
	)
	(segment
		(start 359.029 -229.616)
		(end 360.153712 -229.616)
		(width 0.15494)
		(layer "In15.Cu")
		(net "RST_NIC1_PERST_R_N")
	)
	(segment
		(start 215.460326 -173.54677)
		(end 214.380572 -174.626524)
		(width 0.15494)
		(layer "In15.Cu")
		(net "RST_NIC1_PERST_R_N")
	)
	(segment
		(start 357.93934 -175.48987)
		(end 357.900224 -175.450754)
		(width 0.15494)
		(layer "In15.Cu")
		(net "RST_NIC1_PERST_R_N")
	)
	(segment
		(start 362.262674 -230.295196)
		(end 367.75009 -230.295196)
		(width 0.15494)
		(layer "In15.Cu")
		(net "RST_NIC1_PERST_R_N")
	)
	(segment
		(start 367.75009 -230.295196)
		(end 371.443758 -226.601528)
		(width 0.15494)
		(layer "In15.Cu")
		(net "RST_NIC1_PERST_R_N")
	)
	(segment
		(start 440.503818 -24.189944)
		(end 441.564776 -24.189944)
		(width 0.13208)
		(layer "F.Cu")
		(net "RST_SSD15_PERST_R_N")
	)
	(segment
		(start 344.678 -204.83195)
		(end 344.678 -204.216)
		(width 0.13208)
		(layer "F.Cu")
		(net "RST_SSD15_PERST_R_N")
	)
	(via
		(at 440.503818 -24.189944)
		(size 0.508)
		(drill 0.254)
		(layers "F.Cu" "B.Cu")
		(net "RST_SSD15_PERST_R_N")
	)
	(via
		(at 425.125642 -89.885774)
		(size 0.508)
		(drill 0.254)
		(layers "F.Cu" "B.Cu")
		(net "RST_SSD15_PERST_R_N")
	)
	(via
		(at 344.678 -204.216)
		(size 0.508)
		(drill 0.254)
		(layers "F.Cu" "B.Cu")
		(net "RST_SSD15_PERST_R_N")
	)
	(via
		(at 359.581196 -107.004612)
		(size 0.508)
		(drill 0.254)
		(layers "F.Cu" "B.Cu")
		(net "RST_SSD15_PERST_R_N")
	)
	(segment
		(start 456.04303 -38.485572)
		(end 450.158104 -32.600646)
		(width 0.15494)
		(layer "In5.Cu")
		(net "RST_SSD15_PERST_R_N")
	)
	(segment
		(start 344.12174 -197.81774)
		(end 344.12174 -180.904388)
		(width 0.15494)
		(layer "In5.Cu")
		(net "RST_SSD15_PERST_R_N")
	)
	(segment
		(start 456.232006 -78.10627)
		(end 456.7047 -77.633576)
		(width 0.15494)
		(layer "In5.Cu")
		(net "RST_SSD15_PERST_R_N")
	)
	(segment
		(start 440.854084 -24.54021)
		(end 440.503818 -24.189944)
		(width 0.15494)
		(layer "In5.Cu")
		(net "RST_SSD15_PERST_R_N")
	)
	(segment
		(start 450.158104 -29.943298)
		(end 451.025768 -29.075634)
		(width 0.15494)
		(layer "In5.Cu")
		(net "RST_SSD15_PERST_R_N")
	)
	(segment
		(start 442.891672 -24.54021)
		(end 440.854084 -24.54021)
		(width 0.15494)
		(layer "In5.Cu")
		(net "RST_SSD15_PERST_R_N")
	)
	(segment
		(start 425.449492 -89.561924)
		(end 426.693838 -89.561924)
		(width 0.15494)
		(layer "In5.Cu")
		(net "RST_SSD15_PERST_R_N")
	)
	(segment
		(start 438.827672 -78.10627)
		(end 456.232006 -78.10627)
		(width 0.15494)
		(layer "In5.Cu")
		(net "RST_SSD15_PERST_R_N")
	)
	(segment
		(start 446.686178 -26.894028)
		(end 445.24549 -26.894028)
		(width 0.15494)
		(layer "In5.Cu")
		(net "RST_SSD15_PERST_R_N")
	)
	(segment
		(start 426.693838 -89.561924)
		(end 428.74438 -87.511382)
		(width 0.15494)
		(layer "In5.Cu")
		(net "RST_SSD15_PERST_R_N")
	)
	(segment
		(start 344.678 -198.374)
		(end 344.12174 -197.81774)
		(width 0.15494)
		(layer "In5.Cu")
		(net "RST_SSD15_PERST_R_N")
	)
	(segment
		(start 352.200972 -116.265706)
		(end 359.581196 -108.885482)
		(width 0.15494)
		(layer "In5.Cu")
		(net "RST_SSD15_PERST_R_N")
	)
	(segment
		(start 445.24549 -26.894028)
		(end 444.397638 -26.046176)
		(width 0.15494)
		(layer "In5.Cu")
		(net "RST_SSD15_PERST_R_N")
	)
	(segment
		(start 456.04303 -74.43597)
		(end 456.04303 -38.485572)
		(width 0.15494)
		(layer "In5.Cu")
		(net "RST_SSD15_PERST_R_N")
	)
	(segment
		(start 348.236794 -176.789334)
		(end 348.236794 -128.01473)
		(width 0.15494)
		(layer "In5.Cu")
		(net "RST_SSD15_PERST_R_N")
	)
	(segment
		(start 359.581196 -108.885482)
		(end 359.581196 -107.004612)
		(width 0.15494)
		(layer "In5.Cu")
		(net "RST_SSD15_PERST_R_N")
	)
	(segment
		(start 450.158104 -32.600646)
		(end 450.158104 -29.943298)
		(width 0.15494)
		(layer "In5.Cu")
		(net "RST_SSD15_PERST_R_N")
	)
	(segment
		(start 344.678 -204.216)
		(end 344.678 -198.374)
		(width 0.15494)
		(layer "In5.Cu")
		(net "RST_SSD15_PERST_R_N")
	)
	(segment
		(start 344.12174 -180.904388)
		(end 348.236794 -176.789334)
		(width 0.15494)
		(layer "In5.Cu")
		(net "RST_SSD15_PERST_R_N")
	)
	(segment
		(start 451.025768 -28.106878)
		(end 450.64172 -27.72283)
		(width 0.15494)
		(layer "In5.Cu")
		(net "RST_SSD15_PERST_R_N")
	)
	(segment
		(start 447.51498 -27.72283)
		(end 446.686178 -26.894028)
		(width 0.15494)
		(layer "In5.Cu")
		(net "RST_SSD15_PERST_R_N")
	)
	(segment
		(start 425.125642 -89.885774)
		(end 425.449492 -89.561924)
		(width 0.15494)
		(layer "In5.Cu")
		(net "RST_SSD15_PERST_R_N")
	)
	(segment
		(start 456.7047 -75.09764)
		(end 456.04303 -74.43597)
		(width 0.15494)
		(layer "In5.Cu")
		(net "RST_SSD15_PERST_R_N")
	)
	(segment
		(start 443.579758 -25.228296)
		(end 442.891672 -24.54021)
		(width 0.15494)
		(layer "In5.Cu")
		(net "RST_SSD15_PERST_R_N")
	)
	(segment
		(start 444.087758 -25.652222)
		(end 443.579758 -25.228296)
		(width 0.15494)
		(layer "In5.Cu")
		(net "RST_SSD15_PERST_R_N")
	)
	(segment
		(start 428.74438 -87.511382)
		(end 429.42256 -87.511382)
		(width 0.15494)
		(layer "In5.Cu")
		(net "RST_SSD15_PERST_R_N")
	)
	(segment
		(start 456.7047 -77.633576)
		(end 456.7047 -75.09764)
		(width 0.15494)
		(layer "In5.Cu")
		(net "RST_SSD15_PERST_R_N")
	)
	(segment
		(start 450.64172 -27.72283)
		(end 447.51498 -27.72283)
		(width 0.15494)
		(layer "In5.Cu")
		(net "RST_SSD15_PERST_R_N")
	)
	(segment
		(start 348.236794 -128.01473)
		(end 352.200972 -124.050552)
		(width 0.15494)
		(layer "In5.Cu")
		(net "RST_SSD15_PERST_R_N")
	)
	(segment
		(start 451.025768 -29.075634)
		(end 451.025768 -28.106878)
		(width 0.15494)
		(layer "In5.Cu")
		(net "RST_SSD15_PERST_R_N")
	)
	(segment
		(start 444.397638 -26.046176)
		(end 444.087758 -25.652222)
		(width 0.15494)
		(layer "In5.Cu")
		(net "RST_SSD15_PERST_R_N")
	)
	(segment
		(start 352.200972 -124.050552)
		(end 352.200972 -116.265706)
		(width 0.15494)
		(layer "In5.Cu")
		(net "RST_SSD15_PERST_R_N")
	)
	(segment
		(start 429.42256 -87.511382)
		(end 438.827672 -78.10627)
		(width 0.15494)
		(layer "In5.Cu")
		(net "RST_SSD15_PERST_R_N")
	)
	(segment
		(start 423.673016 -91.3384)
		(end 425.125642 -89.885774)
		(width 0.15494)
		(layer "In15.Cu")
		(net "RST_SSD15_PERST_R_N")
	)
	(segment
		(start 385.19481 -98.371406)
		(end 392.813794 -98.371406)
		(width 0.15494)
		(layer "In15.Cu")
		(net "RST_SSD15_PERST_R_N")
	)
	(segment
		(start 409.1178 -91.3384)
		(end 423.673016 -91.3384)
		(width 0.15494)
		(layer "In15.Cu")
		(net "RST_SSD15_PERST_R_N")
	)
	(segment
		(start 369.315746 -102.7684)
		(end 370.128546 -101.9556)
		(width 0.15494)
		(layer "In15.Cu")
		(net "RST_SSD15_PERST_R_N")
	)
	(segment
		(start 393.0396 -98.1456)
		(end 398.04213 -98.1456)
		(width 0.15494)
		(layer "In15.Cu")
		(net "RST_SSD15_PERST_R_N")
	)
	(segment
		(start 407.9494 -92.5068)
		(end 409.1178 -91.3384)
		(width 0.15494)
		(layer "In15.Cu")
		(net "RST_SSD15_PERST_R_N")
	)
	(segment
		(start 370.128546 -101.9556)
		(end 381.610616 -101.9556)
		(width 0.15494)
		(layer "In15.Cu")
		(net "RST_SSD15_PERST_R_N")
	)
	(segment
		(start 363.817408 -102.7684)
		(end 369.315746 -102.7684)
		(width 0.15494)
		(layer "In15.Cu")
		(net "RST_SSD15_PERST_R_N")
	)
	(segment
		(start 359.581196 -107.004612)
		(end 363.817408 -102.7684)
		(width 0.15494)
		(layer "In15.Cu")
		(net "RST_SSD15_PERST_R_N")
	)
	(segment
		(start 381.610616 -101.9556)
		(end 385.19481 -98.371406)
		(width 0.15494)
		(layer "In15.Cu")
		(net "RST_SSD15_PERST_R_N")
	)
	(segment
		(start 398.04213 -98.1456)
		(end 403.68093 -92.5068)
		(width 0.15494)
		(layer "In15.Cu")
		(net "RST_SSD15_PERST_R_N")
	)
	(segment
		(start 403.68093 -92.5068)
		(end 407.9494 -92.5068)
		(width 0.15494)
		(layer "In15.Cu")
		(net "RST_SSD15_PERST_R_N")
	)
	(segment
		(start 392.813794 -98.371406)
		(end 393.0396 -98.1456)
		(width 0.15494)
		(layer "In15.Cu")
		(net "RST_SSD15_PERST_R_N")
	)
	(segment
		(start 179.566062 -164.069014)
		(end 179.625752 -164.128704)
		(width 0.13208)
		(layer "F.Cu")
		(net "FM_SYS_THROTTLE_NIC3")
	)
	(segment
		(start 179.123848 -163.6268)
		(end 179.566062 -164.069014)
		(width 0.13208)
		(layer "F.Cu")
		(net "FM_SYS_THROTTLE_NIC3")
	)
	(segment
		(start 179.625752 -164.128704)
		(end 179.625752 -165.270434)
		(width 0.13208)
		(layer "F.Cu")
		(net "FM_SYS_THROTTLE_NIC3")
	)
	(segment
		(start 178.831748 -163.6268)
		(end 179.123848 -163.6268)
		(width 0.13208)
		(layer "F.Cu")
		(net "FM_SYS_THROTTLE_NIC3")
	)
	(segment
		(start 178.591718 -162.781488)
		(end 178.591718 -163.38677)
		(width 0.13208)
		(layer "F.Cu")
		(net "FM_SYS_THROTTLE_NIC3")
	)
	(segment
		(start 178.591718 -163.38677)
		(end 178.831748 -163.6268)
		(width 0.13208)
		(layer "F.Cu")
		(net "FM_SYS_THROTTLE_NIC3")
	)
	(via
		(at 179.566062 -164.069014)
		(size 0.762)
		(drill 0.381)
		(layers "F.Cu" "B.Cu")
		(net "FM_SYS_THROTTLE_NIC3")
	)
	(segment
		(start 207.609186 -224.37217)
		(end 207.609186 -224.923604)
		(width 0.13208)
		(layer "F.Cu")
		(net "UART_MB_BIC_R_RX")
	)
	(segment
		(start 209.2706 -224.049082)
		(end 207.932274 -224.049082)
		(width 0.13208)
		(layer "F.Cu")
		(net "UART_MB_BIC_R_RX")
	)
	(segment
		(start 207.932274 -224.049082)
		(end 207.609186 -224.37217)
		(width 0.13208)
		(layer "F.Cu")
		(net "UART_MB_BIC_R_RX")
	)
	(via
		(at 216.38895 -241.6429)
		(size 0.508)
		(drill 0.254)
		(layers "F.Cu" "B.Cu")
		(net "UART_MB_BIC_R_RX")
	)
	(via
		(at 248.666254 -327.38695)
		(size 0.508)
		(drill 0.254)
		(layers "F.Cu" "B.Cu")
		(net "UART_MB_BIC_R_RX")
	)
	(via
		(at 250.143518 -331.037438)
		(size 0.508)
		(drill 0.254)
		(layers "F.Cu" "B.Cu")
		(net "UART_MB_BIC_R_RX")
	)
	(via
		(at 209.2706 -224.049082)
		(size 0.508)
		(drill 0.254)
		(layers "F.Cu" "B.Cu")
		(net "UART_MB_BIC_R_RX")
	)
	(segment
		(start 361.696 -328.5236)
		(end 360.6038 -329.6158)
		(width 0.13208)
		(layer "B.Cu")
		(net "UART_MB_BIC_R_RX")
	)
	(segment
		(start 240.55832 -241.11331)
		(end 224.708466 -241.11331)
		(width 0.13208)
		(layer "B.Cu")
		(net "UART_MB_BIC_R_RX")
	)
	(segment
		(start 375.183146 -360.387138)
		(end 368.776758 -353.98075)
		(width 0.13208)
		(layer "B.Cu")
		(net "UART_MB_BIC_R_RX")
	)
	(segment
		(start 257.887216 -305.947826)
		(end 257.887216 -285.200344)
		(width 0.13208)
		(layer "B.Cu")
		(net "UART_MB_BIC_R_RX")
	)
	(segment
		(start 356.356158 -332.114652)
		(end 251.220732 -332.114652)
		(width 0.13208)
		(layer "B.Cu")
		(net "UART_MB_BIC_R_RX")
	)
	(segment
		(start 249.43308 -255.542542)
		(end 245.511828 -246.075708)
		(width 0.13208)
		(layer "B.Cu")
		(net "UART_MB_BIC_R_RX")
	)
	(segment
		(start 393.229592 -360.387138)
		(end 375.183146 -360.387138)
		(width 0.13208)
		(layer "B.Cu")
		(net "UART_MB_BIC_R_RX")
	)
	(segment
		(start 365.684562 -329.335638)
		(end 364.872524 -328.5236)
		(width 0.13208)
		(layer "B.Cu")
		(net "UART_MB_BIC_R_RX")
	)
	(segment
		(start 216.438226 -241.692176)
		(end 216.38895 -241.6429)
		(width 0.13208)
		(layer "B.Cu")
		(net "UART_MB_BIC_R_RX")
	)
	(segment
		(start 360.6038 -329.6158)
		(end 358.85501 -329.6158)
		(width 0.13208)
		(layer "B.Cu")
		(net "UART_MB_BIC_R_RX")
	)
	(segment
		(start 240.848642 -241.412522)
		(end 240.848642 -241.403632)
		(width 0.13208)
		(layer "B.Cu")
		(net "UART_MB_BIC_R_RX")
	)
	(segment
		(start 245.511828 -246.075708)
		(end 240.848642 -241.412522)
		(width 0.13208)
		(layer "B.Cu")
		(net "UART_MB_BIC_R_RX")
	)
	(segment
		(start 358.85501 -329.6158)
		(end 356.356158 -332.114652)
		(width 0.13208)
		(layer "B.Cu")
		(net "UART_MB_BIC_R_RX")
	)
	(segment
		(start 251.220732 -332.114652)
		(end 250.143518 -331.037438)
		(width 0.13208)
		(layer "B.Cu")
		(net "UART_MB_BIC_R_RX")
	)
	(segment
		(start 369.7732 -330.073)
		(end 369.035838 -329.335638)
		(width 0.13208)
		(layer "B.Cu")
		(net "UART_MB_BIC_R_RX")
	)
	(segment
		(start 368.776758 -338.8106)
		(end 369.7732 -337.814158)
		(width 0.13208)
		(layer "B.Cu")
		(net "UART_MB_BIC_R_RX")
	)
	(segment
		(start 224.1296 -241.692176)
		(end 216.438226 -241.692176)
		(width 0.13208)
		(layer "B.Cu")
		(net "UART_MB_BIC_R_RX")
	)
	(segment
		(start 249.248422 -326.804782)
		(end 257.887216 -305.947826)
		(width 0.13208)
		(layer "B.Cu")
		(net "UART_MB_BIC_R_RX")
	)
	(segment
		(start 368.776758 -353.98075)
		(end 368.776758 -338.8106)
		(width 0.13208)
		(layer "B.Cu")
		(net "UART_MB_BIC_R_RX")
	)
	(segment
		(start 369.035838 -329.335638)
		(end 365.684562 -329.335638)
		(width 0.13208)
		(layer "B.Cu")
		(net "UART_MB_BIC_R_RX")
	)
	(segment
		(start 248.666254 -327.38695)
		(end 249.248422 -326.804782)
		(width 0.13208)
		(layer "B.Cu")
		(net "UART_MB_BIC_R_RX")
	)
	(segment
		(start 240.848642 -241.403632)
		(end 240.55832 -241.11331)
		(width 0.13208)
		(layer "B.Cu")
		(net "UART_MB_BIC_R_RX")
	)
	(segment
		(start 249.43308 -264.788904)
		(end 249.43308 -255.542542)
		(width 0.13208)
		(layer "B.Cu")
		(net "UART_MB_BIC_R_RX")
	)
	(segment
		(start 369.7732 -337.814158)
		(end 369.7732 -330.073)
		(width 0.13208)
		(layer "B.Cu")
		(net "UART_MB_BIC_R_RX")
	)
	(segment
		(start 224.708466 -241.11331)
		(end 224.1296 -241.692176)
		(width 0.13208)
		(layer "B.Cu")
		(net "UART_MB_BIC_R_RX")
	)
	(segment
		(start 257.887216 -285.200344)
		(end 249.43308 -264.788904)
		(width 0.13208)
		(layer "B.Cu")
		(net "UART_MB_BIC_R_RX")
	)
	(segment
		(start 364.872524 -328.5236)
		(end 361.696 -328.5236)
		(width 0.13208)
		(layer "B.Cu")
		(net "UART_MB_BIC_R_RX")
	)
	(segment
		(start 214.520272 -238.069882)
		(end 215.271604 -239.884458)
		(width 0.15494)
		(layer "In5.Cu")
		(net "UART_MB_BIC_R_RX")
	)
	(segment
		(start 212.573362 -234.308396)
		(end 212.573362 -234.6452)
		(width 0.15494)
		(layer "In5.Cu")
		(net "UART_MB_BIC_R_RX")
	)
	(segment
		(start 212.573362 -234.6452)
		(end 213.618572 -237.168182)
		(width 0.15494)
		(layer "In5.Cu")
		(net "UART_MB_BIC_R_RX")
	)
	(segment
		(start 212.392514 -233.87177)
		(end 212.573362 -234.308396)
		(width 0.15494)
		(layer "In5.Cu")
		(net "UART_MB_BIC_R_RX")
	)
	(segment
		(start 209.2706 -224.049082)
		(end 209.2706 -226.22256)
		(width 0.15494)
		(layer "In5.Cu")
		(net "UART_MB_BIC_R_RX")
	)
	(segment
		(start 215.271604 -239.884458)
		(end 215.935814 -240.548668)
		(width 0.15494)
		(layer "In5.Cu")
		(net "UART_MB_BIC_R_RX")
	)
	(segment
		(start 209.2706 -226.22256)
		(end 208.877662 -226.615498)
		(width 0.15494)
		(layer "In5.Cu")
		(net "UART_MB_BIC_R_RX")
	)
	(segment
		(start 208.877662 -228.85781)
		(end 211.572348 -231.552496)
		(width 0.15494)
		(layer "In5.Cu")
		(net "UART_MB_BIC_R_RX")
	)
	(segment
		(start 208.877662 -226.615498)
		(end 208.877662 -228.85781)
		(width 0.15494)
		(layer "In5.Cu")
		(net "UART_MB_BIC_R_RX")
	)
	(segment
		(start 213.618572 -237.168182)
		(end 214.520272 -238.069882)
		(width 0.15494)
		(layer "In5.Cu")
		(net "UART_MB_BIC_R_RX")
	)
	(segment
		(start 211.572348 -231.552496)
		(end 211.572348 -233.051604)
		(width 0.15494)
		(layer "In5.Cu")
		(net "UART_MB_BIC_R_RX")
	)
	(segment
		(start 215.935814 -240.548668)
		(end 216.38895 -241.6429)
		(width 0.15494)
		(layer "In5.Cu")
		(net "UART_MB_BIC_R_RX")
	)
	(segment
		(start 211.572348 -233.051604)
		(end 212.392514 -233.87177)
		(width 0.15494)
		(layer "In5.Cu")
		(net "UART_MB_BIC_R_RX")
	)
	(segment
		(start 250.143518 -330.949808)
		(end 248.666254 -327.38695)
		(width 0.15494)
		(layer "In7.Cu")
		(net "UART_MB_BIC_R_RX")
	)
	(segment
		(start 250.143518 -331.037438)
		(end 250.143518 -330.949808)
		(width 0.15494)
		(layer "In7.Cu")
		(net "UART_MB_BIC_R_RX")
	)
	(segment
		(start 23.003002 -247.51665)
		(end 23.003002 -253.016766)
		(width 0.508)
		(layer "F.Cu")
		(net "P1V8_PLL0_PEX0")
	)
	(segment
		(start 243.3066 -216.80805)
		(end 243.3066 -217.5002)
		(width 0.4572)
		(layer "F.Cu")
		(net "P1V8_PLL0_PEX0")
	)
	(segment
		(start 20.919948 -210.374738)
		(end 20.919948 -216.170256)
		(width 0.508)
		(layer "F.Cu")
		(net "P1V8_PLL0_PEX0")
	)
	(segment
		(start 19.312382 -208.767172)
		(end 18.884646 -208.767172)
		(width 0.508)
		(layer "F.Cu")
		(net "P1V8_PLL0_PEX0")
	)
	(segment
		(start 23.003002 -253.016766)
		(end 24.084534 -254.098298)
		(width 0.381)
		(layer "F.Cu")
		(net "P1V8_PLL0_PEX0")
	)
	(segment
		(start 29.75483 -240.764822)
		(end 23.003002 -247.51665)
		(width 0.508)
		(layer "F.Cu")
		(net "P1V8_PLL0_PEX0")
	)
	(segment
		(start 25.138634 -254.098298)
		(end 25.72004 -254.679704)
		(width 0.381)
		(layer "F.Cu")
		(net "P1V8_PLL0_PEX0")
	)
	(segment
		(start 29.75483 -219.093542)
		(end 29.75483 -240.764822)
		(width 0.508)
		(layer "F.Cu")
		(net "P1V8_PLL0_PEX0")
	)
	(segment
		(start 28.17241 -217.511122)
		(end 29.75483 -219.093542)
		(width 0.508)
		(layer "F.Cu")
		(net "P1V8_PLL0_PEX0")
	)
	(segment
		(start 24.084534 -254.098298)
		(end 25.138634 -254.098298)
		(width 0.381)
		(layer "F.Cu")
		(net "P1V8_PLL0_PEX0")
	)
	(segment
		(start 20.919948 -216.170256)
		(end 22.260814 -217.511122)
		(width 0.508)
		(layer "F.Cu")
		(net "P1V8_PLL0_PEX0")
	)
	(segment
		(start 19.312382 -208.767172)
		(end 20.919948 -210.374738)
		(width 0.508)
		(layer "F.Cu")
		(net "P1V8_PLL0_PEX0")
	)
	(segment
		(start 22.260814 -217.511122)
		(end 28.17241 -217.511122)
		(width 0.508)
		(layer "F.Cu")
		(net "P1V8_PLL0_PEX0")
	)
	(via
		(at 27.678634 -297.831256)
		(size 0.508)
		(drill 0.254)
		(layers "F.Cu" "B.Cu")
		(net "P1V8_PLL0_PEX0")
	)
	(via
		(at 21.917406 -208.810352)
		(size 0.508)
		(drill 0.254)
		(layers "F.Cu" "B.Cu")
		(net "P1V8_PLL0_PEX0")
	)
	(via
		(at 26.193496 -285.029656)
		(size 0.508)
		(drill 0.254)
		(layers "F.Cu" "B.Cu")
		(net "P1V8_PLL0_PEX0")
	)
	(via
		(at 27.678634 -288.230056)
		(size 0.508)
		(drill 0.254)
		(layers "F.Cu" "B.Cu")
		(net "P1V8_PLL0_PEX0")
	)
	(via
		(at 18.884646 -208.767172)
		(size 0.508)
		(drill 0.254)
		(layers "F.Cu" "B.Cu")
		(net "P1V8_PLL0_PEX0")
	)
	(via
		(at 26.193496 -281.829256)
		(size 0.508)
		(drill 0.254)
		(layers "F.Cu" "B.Cu")
		(net "P1V8_PLL0_PEX0")
	)
	(via
		(at 26.193496 -294.630856)
		(size 0.508)
		(drill 0.254)
		(layers "F.Cu" "B.Cu")
		(net "P1V8_PLL0_PEX0")
	)
	(via
		(at 25.90038 -261.790688)
		(size 0.508)
		(drill 0.254)
		(layers "F.Cu" "B.Cu")
		(net "P1V8_PLL0_PEX0")
	)
	(via
		(at 27.678634 -285.029656)
		(size 0.508)
		(drill 0.254)
		(layers "F.Cu" "B.Cu")
		(net "P1V8_PLL0_PEX0")
	)
	(via
		(at 30.636718 -258.274058)
		(size 0.508)
		(drill 0.254)
		(layers "F.Cu" "B.Cu")
		(net "P1V8_PLL0_PEX0")
	)
	(via
		(at 17.436846 -210.113372)
		(size 0.508)
		(drill 0.254)
		(layers "F.Cu" "B.Cu")
		(net "P1V8_PLL0_PEX0")
	)
	(via
		(at 30.636718 -261.474458)
		(size 0.508)
		(drill 0.254)
		(layers "F.Cu" "B.Cu")
		(net "P1V8_PLL0_PEX0")
	)
	(via
		(at 28.18638 -261.790688)
		(size 0.508)
		(drill 0.254)
		(layers "F.Cu" "B.Cu")
		(net "P1V8_PLL0_PEX0")
	)
	(via
		(at 27.678634 -291.430456)
		(size 0.508)
		(drill 0.254)
		(layers "F.Cu" "B.Cu")
		(net "P1V8_PLL0_PEX0")
	)
	(via
		(at 26.66238 -261.790688)
		(size 0.508)
		(drill 0.254)
		(layers "F.Cu" "B.Cu")
		(net "P1V8_PLL0_PEX0")
	)
	(via
		(at 26.380694 -300.406562)
		(size 0.508)
		(drill 0.254)
		(layers "F.Cu" "B.Cu")
		(net "P1V8_PLL0_PEX0")
	)
	(via
		(at 18.884646 -209.478372)
		(size 0.508)
		(drill 0.254)
		(layers "F.Cu" "B.Cu")
		(net "P1V8_PLL0_PEX0")
	)
	(via
		(at 26.37155 -256.45237)
		(size 0.508)
		(drill 0.254)
		(layers "F.Cu" "B.Cu")
		(net "P1V8_PLL0_PEX0")
	)
	(via
		(at 26.193496 -297.831256)
		(size 0.508)
		(drill 0.254)
		(layers "F.Cu" "B.Cu")
		(net "P1V8_PLL0_PEX0")
	)
	(via
		(at 27.42438 -261.790688)
		(size 0.508)
		(drill 0.254)
		(layers "F.Cu" "B.Cu")
		(net "P1V8_PLL0_PEX0")
	)
	(via
		(at 243.3066 -217.5002)
		(size 0.508)
		(drill 0.254)
		(layers "F.Cu" "B.Cu")
		(net "P1V8_PLL0_PEX0")
	)
	(via
		(at 27.678634 -294.630856)
		(size 0.508)
		(drill 0.254)
		(layers "F.Cu" "B.Cu")
		(net "P1V8_PLL0_PEX0")
	)
	(via
		(at 27.678634 -281.829256)
		(size 0.508)
		(drill 0.254)
		(layers "F.Cu" "B.Cu")
		(net "P1V8_PLL0_PEX0")
	)
	(via
		(at 29.15158 -261.474458)
		(size 0.508)
		(drill 0.254)
		(layers "F.Cu" "B.Cu")
		(net "P1V8_PLL0_PEX0")
	)
	(via
		(at 29.15158 -258.274058)
		(size 0.508)
		(drill 0.254)
		(layers "F.Cu" "B.Cu")
		(net "P1V8_PLL0_PEX0")
	)
	(via
		(at 26.193496 -288.230056)
		(size 0.508)
		(drill 0.254)
		(layers "F.Cu" "B.Cu")
		(net "P1V8_PLL0_PEX0")
	)
	(via
		(at 18.325846 -210.138772)
		(size 0.508)
		(drill 0.254)
		(layers "F.Cu" "B.Cu")
		(net "P1V8_PLL0_PEX0")
	)
	(via
		(at 26.193496 -291.430456)
		(size 0.508)
		(drill 0.254)
		(layers "F.Cu" "B.Cu")
		(net "P1V8_PLL0_PEX0")
	)
	(via
		(at 25.66035 -256.45237)
		(size 0.508)
		(drill 0.254)
		(layers "F.Cu" "B.Cu")
		(net "P1V8_PLL0_PEX0")
	)
	(segment
		(start 21.874226 -208.767172)
		(end 18.884646 -208.767172)
		(width 0.2032)
		(layer "B.Cu")
		(net "P1V8_PLL0_PEX0")
	)
	(segment
		(start 21.917406 -208.810352)
		(end 21.874226 -208.767172)
		(width 0.2032)
		(layer "B.Cu")
		(net "P1V8_PLL0_PEX0")
	)
	(segment
		(start 104.9528 -199.954642)
		(end 103.651558 -198.6534)
		(width 0.508)
		(layer "In15.Cu")
		(net "P1V8_PLL0_PEX0")
	)
	(segment
		(start 141.130274 -217.983054)
		(end 140.597128 -218.5162)
		(width 0.381)
		(layer "In15.Cu")
		(net "P1V8_PLL0_PEX0")
	)
	(segment
		(start 103.651558 -198.6534)
		(end 99.1362 -198.6534)
		(width 0.508)
		(layer "In15.Cu")
		(net "P1V8_PLL0_PEX0")
	)
	(segment
		(start 225.651822 -212.412834)
		(end 225.046794 -213.017862)
		(width 0.508)
		(layer "In15.Cu")
		(net "P1V8_PLL0_PEX0")
	)
	(segment
		(start 239.496854 -210.168744)
		(end 236.656118 -210.168744)
		(width 0.254)
		(layer "In15.Cu")
		(net "P1V8_PLL0_PEX0")
	)
	(segment
		(start 111.665766 -203.2762)
		(end 107.905042 -203.2762)
		(width 0.508)
		(layer "In15.Cu")
		(net "P1V8_PLL0_PEX0")
	)
	(segment
		(start 159.436308 -217.983054)
		(end 141.130274 -217.983054)
		(width 0.381)
		(layer "In15.Cu")
		(net "P1V8_PLL0_PEX0")
	)
	(segment
		(start 221.95155 -214.746586)
		(end 212.614256 -214.746586)
		(width 0.2032)
		(layer "In15.Cu")
		(net "P1V8_PLL0_PEX0")
	)
	(segment
		(start 119.325136 -206.856076)
		(end 118.99138 -206.7179)
		(width 0.254)
		(layer "In15.Cu")
		(net "P1V8_PLL0_PEX0")
	)
	(segment
		(start 243.778278 -212.128608)
		(end 243.778278 -211.684108)
		(width 0.508)
		(layer "In15.Cu")
		(net "P1V8_PLL0_PEX0")
	)
	(segment
		(start 236.656118 -210.168744)
		(end 236.138974 -209.6516)
		(width 0.254)
		(layer "In15.Cu")
		(net "P1V8_PLL0_PEX0")
	)
	(segment
		(start 223.680274 -213.017862)
		(end 221.95155 -214.746586)
		(width 0.508)
		(layer "In15.Cu")
		(net "P1V8_PLL0_PEX0")
	)
	(segment
		(start 225.482404 -210.838288)
		(end 225.651822 -211.007706)
		(width 0.508)
		(layer "In15.Cu")
		(net "P1V8_PLL0_PEX0")
	)
	(segment
		(start 241.546888 -210.836002)
		(end 240.164112 -210.836002)
		(width 0.381)
		(layer "In15.Cu")
		(net "P1V8_PLL0_PEX0")
	)
	(segment
		(start 127.793496 -218.5162)
		(end 126.924816 -218.15679)
		(width 0.381)
		(layer "In15.Cu")
		(net "P1V8_PLL0_PEX0")
	)
	(segment
		(start 95.856806 -200.301352)
		(end 29.014674 -200.301352)
		(width 0.508)
		(layer "In15.Cu")
		(net "P1V8_PLL0_PEX0")
	)
	(segment
		(start 96.096582 -200.541128)
		(end 95.856806 -200.301352)
		(width 0.508)
		(layer "In15.Cu")
		(net "P1V8_PLL0_PEX0")
	)
	(segment
		(start 208.47304 -214.812626)
		(end 207.801972 -215.483694)
		(width 0.508)
		(layer "In15.Cu")
		(net "P1V8_PLL0_PEX0")
	)
	(segment
		(start 126.924816 -218.15679)
		(end 121.04751 -212.279484)
		(width 0.381)
		(layer "In15.Cu")
		(net "P1V8_PLL0_PEX0")
	)
	(segment
		(start 225.651822 -211.007706)
		(end 225.651822 -212.412834)
		(width 0.508)
		(layer "In15.Cu")
		(net "P1V8_PLL0_PEX0")
	)
	(segment
		(start 140.597128 -218.5162)
		(end 127.793496 -218.5162)
		(width 0.381)
		(layer "In15.Cu")
		(net "P1V8_PLL0_PEX0")
	)
	(segment
		(start 243.205 -215.67775)
		(end 243.205 -212.701886)
		(width 0.508)
		(layer "In15.Cu")
		(net "P1V8_PLL0_PEX0")
	)
	(segment
		(start 198.4248 -222.0214)
		(end 163.474654 -222.0214)
		(width 0.381)
		(layer "In15.Cu")
		(net "P1V8_PLL0_PEX0")
	)
	(segment
		(start 236.138974 -209.6516)
		(end 226.008438 -209.6516)
		(width 0.508)
		(layer "In15.Cu")
		(net "P1V8_PLL0_PEX0")
	)
	(segment
		(start 207.801972 -215.483694)
		(end 204.962506 -215.483694)
		(width 0.508)
		(layer "In15.Cu")
		(net "P1V8_PLL0_PEX0")
	)
	(segment
		(start 243.374672 -211.280502)
		(end 241.991388 -211.280502)
		(width 0.2032)
		(layer "In15.Cu")
		(net "P1V8_PLL0_PEX0")
	)
	(segment
		(start 99.1362 -198.6534)
		(end 97.248472 -200.541128)
		(width 0.508)
		(layer "In15.Cu")
		(net "P1V8_PLL0_PEX0")
	)
	(segment
		(start 21.917406 -207.39862)
		(end 21.917406 -208.810352)
		(width 0.508)
		(layer "In15.Cu")
		(net "P1V8_PLL0_PEX0")
	)
	(segment
		(start 120.922288 -208.453228)
		(end 119.325136 -206.856076)
		(width 0.254)
		(layer "In15.Cu")
		(net "P1V8_PLL0_PEX0")
	)
	(segment
		(start 204.962506 -215.483694)
		(end 198.4248 -222.0214)
		(width 0.508)
		(layer "In15.Cu")
		(net "P1V8_PLL0_PEX0")
	)
	(segment
		(start 163.474654 -222.0214)
		(end 159.436308 -217.983054)
		(width 0.381)
		(layer "In15.Cu")
		(net "P1V8_PLL0_PEX0")
	)
	(segment
		(start 240.164112 -210.836002)
		(end 239.496854 -210.168744)
		(width 0.381)
		(layer "In15.Cu")
		(net "P1V8_PLL0_PEX0")
	)
	(segment
		(start 243.205 -212.701886)
		(end 243.778278 -212.128608)
		(width 0.508)
		(layer "In15.Cu")
		(net "P1V8_PLL0_PEX0")
	)
	(segment
		(start 225.482404 -210.177634)
		(end 225.482404 -210.838288)
		(width 0.508)
		(layer "In15.Cu")
		(net "P1V8_PLL0_PEX0")
	)
	(segment
		(start 226.008438 -209.6516)
		(end 225.482404 -210.177634)
		(width 0.508)
		(layer "In15.Cu")
		(net "P1V8_PLL0_PEX0")
	)
	(segment
		(start 121.04751 -212.279484)
		(end 121.04751 -208.755488)
		(width 0.381)
		(layer "In15.Cu")
		(net "P1V8_PLL0_PEX0")
	)
	(segment
		(start 212.548216 -214.812626)
		(end 208.47304 -214.812626)
		(width 0.2032)
		(layer "In15.Cu")
		(net "P1V8_PLL0_PEX0")
	)
	(segment
		(start 212.614256 -214.746586)
		(end 212.548216 -214.812626)
		(width 0.2032)
		(layer "In15.Cu")
		(net "P1V8_PLL0_PEX0")
	)
	(segment
		(start 115.107466 -206.7179)
		(end 111.665766 -203.2762)
		(width 0.508)
		(layer "In15.Cu")
		(net "P1V8_PLL0_PEX0")
	)
	(segment
		(start 29.014674 -200.301352)
		(end 21.917406 -207.39862)
		(width 0.508)
		(layer "In15.Cu")
		(net "P1V8_PLL0_PEX0")
	)
	(segment
		(start 121.04751 -208.755488)
		(end 120.922288 -208.453228)
		(width 0.254)
		(layer "In15.Cu")
		(net "P1V8_PLL0_PEX0")
	)
	(segment
		(start 241.991388 -211.280502)
		(end 241.546888 -210.836002)
		(width 0.381)
		(layer "In15.Cu")
		(net "P1V8_PLL0_PEX0")
	)
	(segment
		(start 107.905042 -203.2762)
		(end 104.9528 -200.323958)
		(width 0.508)
		(layer "In15.Cu")
		(net "P1V8_PLL0_PEX0")
	)
	(segment
		(start 225.046794 -213.017862)
		(end 223.680274 -213.017862)
		(width 0.508)
		(layer "In15.Cu")
		(net "P1V8_PLL0_PEX0")
	)
	(segment
		(start 118.99138 -206.7179)
		(end 115.107466 -206.7179)
		(width 0.381)
		(layer "In15.Cu")
		(net "P1V8_PLL0_PEX0")
	)
	(segment
		(start 243.3066 -215.77935)
		(end 243.205 -215.67775)
		(width 0.508)
		(layer "In15.Cu")
		(net "P1V8_PLL0_PEX0")
	)
	(segment
		(start 243.778278 -211.684108)
		(end 243.374672 -211.280502)
		(width 0.2032)
		(layer "In15.Cu")
		(net "P1V8_PLL0_PEX0")
	)
	(segment
		(start 243.3066 -217.5002)
		(end 243.3066 -215.77935)
		(width 0.508)
		(layer "In15.Cu")
		(net "P1V8_PLL0_PEX0")
	)
	(segment
		(start 104.9528 -200.323958)
		(end 104.9528 -199.954642)
		(width 0.508)
		(layer "In15.Cu")
		(net "P1V8_PLL0_PEX0")
	)
	(segment
		(start 97.248472 -200.541128)
		(end 96.096582 -200.541128)
		(width 0.508)
		(layer "In15.Cu")
		(net "P1V8_PLL0_PEX0")
	)
	(segment
		(start 368.564668 -202.808332)
		(end 369.438936 -201.934064)
		(width 0.13208)
		(layer "F.Cu")
		(net "PCA9555_0_PEX1_A1")
	)
	(segment
		(start 363.87405 -202.819)
		(end 365.10595 -202.819)
		(width 0.13208)
		(layer "F.Cu")
		(net "PCA9555_0_PEX1_A1")
	)
	(segment
		(start 365.23295 -203.327)
		(end 368.046 -203.327)
		(width 0.13208)
		(layer "F.Cu")
		(net "PCA9555_0_PEX1_A1")
	)
	(segment
		(start 368.554 -202.808332)
		(end 368.564668 -202.808332)
		(width 0.13208)
		(layer "F.Cu")
		(net "PCA9555_0_PEX1_A1")
	)
	(segment
		(start 365.10595 -202.819)
		(end 365.10595 -203.2)
		(width 0.13208)
		(layer "F.Cu")
		(net "PCA9555_0_PEX1_A1")
	)
	(segment
		(start 365.10595 -203.2)
		(end 365.23295 -203.327)
		(width 0.13208)
		(layer "F.Cu")
		(net "PCA9555_0_PEX1_A1")
	)
	(segment
		(start 369.438936 -201.934064)
		(end 370.581936 -201.934064)
		(width 0.13208)
		(layer "F.Cu")
		(net "PCA9555_0_PEX1_A1")
	)
	(segment
		(start 368.046 -203.327)
		(end 368.554 -202.819)
		(width 0.13208)
		(layer "F.Cu")
		(net "PCA9555_0_PEX1_A1")
	)
	(segment
		(start 368.554 -202.819)
		(end 368.554 -202.808332)
		(width 0.13208)
		(layer "F.Cu")
		(net "PCA9555_0_PEX1_A1")
	)
	(via
		(at 368.554 -202.808332)
		(size 0.508)
		(drill 0.254)
		(layers "F.Cu" "B.Cu")
		(net "PCA9555_0_PEX1_A1")
	)
	(segment
		(start 207.983074 -214.067136)
		(end 207.983074 -213.313264)
		(width 0.13208)
		(layer "F.Cu")
		(net "UART_BIC_DEBUG_RX")
	)
	(segment
		(start 207.273398 -214.776812)
		(end 207.983074 -214.067136)
		(width 0.13208)
		(layer "F.Cu")
		(net "UART_BIC_DEBUG_RX")
	)
	(segment
		(start 207.282542 -214.776812)
		(end 207.273398 -214.776812)
		(width 0.13208)
		(layer "F.Cu")
		(net "UART_BIC_DEBUG_RX")
	)
	(segment
		(start 207.773524 -215.536526)
		(end 207.773524 -215.267794)
		(width 0.13208)
		(layer "F.Cu")
		(net "UART_BIC_DEBUG_RX")
	)
	(segment
		(start 207.773524 -215.267794)
		(end 207.282542 -214.776812)
		(width 0.13208)
		(layer "F.Cu")
		(net "UART_BIC_DEBUG_RX")
	)
	(via
		(at 207.273398 -214.776812)
		(size 0.508)
		(drill 0.254)
		(layers "F.Cu" "B.Cu")
		(net "UART_BIC_DEBUG_RX")
	)
	(segment
		(start 294.931846 -163.6268)
		(end 295.223946 -163.6268)
		(width 0.13208)
		(layer "F.Cu")
		(net "FM_SYS_THROTTLE_NIC5")
	)
	(segment
		(start 294.691816 -162.781488)
		(end 294.691816 -163.38677)
		(width 0.13208)
		(layer "F.Cu")
		(net "FM_SYS_THROTTLE_NIC5")
	)
	(segment
		(start 294.691816 -163.38677)
		(end 294.931846 -163.6268)
		(width 0.13208)
		(layer "F.Cu")
		(net "FM_SYS_THROTTLE_NIC5")
	)
	(segment
		(start 295.66616 -164.069014)
		(end 295.72585 -164.128704)
		(width 0.13208)
		(layer "F.Cu")
		(net "FM_SYS_THROTTLE_NIC5")
	)
	(segment
		(start 295.72585 -164.128704)
		(end 295.72585 -165.270434)
		(width 0.13208)
		(layer "F.Cu")
		(net "FM_SYS_THROTTLE_NIC5")
	)
	(segment
		(start 295.223946 -163.6268)
		(end 295.66616 -164.069014)
		(width 0.13208)
		(layer "F.Cu")
		(net "FM_SYS_THROTTLE_NIC5")
	)
	(via
		(at 295.66616 -164.069014)
		(size 0.762)
		(drill 0.381)
		(layers "F.Cu" "B.Cu")
		(net "FM_SYS_THROTTLE_NIC5")
	)
	(segment
		(start 208.185766 -226.303586)
		(end 208.185766 -226.70897)
		(width 0.13208)
		(layer "F.Cu")
		(net "BUF_UART_MB_BIC_RX_EN")
	)
	(segment
		(start 208.259172 -226.23018)
		(end 208.185766 -226.303586)
		(width 0.13208)
		(layer "F.Cu")
		(net "BUF_UART_MB_BIC_RX_EN")
	)
	(segment
		(start 208.259172 -224.923604)
		(end 208.259172 -225.89871)
		(width 0.13208)
		(layer "F.Cu")
		(net "BUF_UART_MB_BIC_RX_EN")
	)
	(segment
		(start 208.259172 -225.89871)
		(end 208.259172 -226.23018)
		(width 0.13208)
		(layer "F.Cu")
		(net "BUF_UART_MB_BIC_RX_EN")
	)
	(via
		(at 208.259172 -225.89871)
		(size 0.508)
		(drill 0.254)
		(layers "F.Cu" "B.Cu")
		(net "BUF_UART_MB_BIC_RX_EN")
	)
	(segment
		(start 365.10595 -201.803)
		(end 365.10595 -202.184)
		(width 0.13208)
		(layer "F.Cu")
		(net "PCA9555_0_PEX1_A2")
	)
	(segment
		(start 368.554 -201.538332)
		(end 368.808254 -201.284078)
		(width 0.13208)
		(layer "F.Cu")
		(net "PCA9555_0_PEX1_A2")
	)
	(segment
		(start 365.10595 -202.184)
		(end 365.23295 -202.311)
		(width 0.13208)
		(layer "F.Cu")
		(net "PCA9555_0_PEX1_A2")
	)
	(segment
		(start 367.781332 -202.311)
		(end 368.554 -201.538332)
		(width 0.13208)
		(layer "F.Cu")
		(net "PCA9555_0_PEX1_A2")
	)
	(segment
		(start 368.808254 -201.284078)
		(end 370.581936 -201.284078)
		(width 0.13208)
		(layer "F.Cu")
		(net "PCA9555_0_PEX1_A2")
	)
	(segment
		(start 363.87405 -201.803)
		(end 365.10595 -201.803)
		(width 0.13208)
		(layer "F.Cu")
		(net "PCA9555_0_PEX1_A2")
	)
	(segment
		(start 365.23295 -202.311)
		(end 367.781332 -202.311)
		(width 0.13208)
		(layer "F.Cu")
		(net "PCA9555_0_PEX1_A2")
	)
	(via
		(at 368.554 -201.538332)
		(size 0.508)
		(drill 0.254)
		(layers "F.Cu" "B.Cu")
		(net "PCA9555_0_PEX1_A2")
	)
	(segment
		(start 328.09815 -211.3661)
		(end 327.93305 -211.201)
		(width 0.13208)
		(layer "F.Cu")
		(net "PRSNT_SSD13_FPGA_N")
	)
	(segment
		(start 329.607418 -211.3661)
		(end 328.09815 -211.3661)
		(width 0.13208)
		(layer "F.Cu")
		(net "PRSNT_SSD13_FPGA_N")
	)
	(segment
		(start 334.89392 -213.587076)
		(end 334.494124 -213.18728)
		(width 0.13208)
		(layer "F.Cu")
		(net "PRSNT_SSD13_FPGA_N")
	)
	(via
		(at 334.494124 -213.18728)
		(size 0.4572)
		(drill 0.254)
		(layers "F.Cu" "B.Cu")
		(net "PRSNT_SSD13_FPGA_N")
	)
	(via
		(at 329.607418 -211.3661)
		(size 0.508)
		(drill 0.254)
		(layers "F.Cu" "B.Cu")
		(net "PRSNT_SSD13_FPGA_N")
	)
	(segment
		(start 330.229718 -210.7438)
		(end 329.607418 -211.3661)
		(width 0.15494)
		(layer "In5.Cu")
		(net "PRSNT_SSD13_FPGA_N")
	)
	(segment
		(start 330.68641 -210.7438)
		(end 330.229718 -210.7438)
		(width 0.15494)
		(layer "In5.Cu")
		(net "PRSNT_SSD13_FPGA_N")
	)
	(segment
		(start 332.678024 -213.242144)
		(end 331.929232 -213.242144)
		(width 0.15494)
		(layer "In5.Cu")
		(net "PRSNT_SSD13_FPGA_N")
	)
	(segment
		(start 331.929232 -213.242144)
		(end 331.394562 -212.707474)
		(width 0.15494)
		(layer "In5.Cu")
		(net "PRSNT_SSD13_FPGA_N")
	)
	(segment
		(start 331.394562 -211.451952)
		(end 330.68641 -210.7438)
		(width 0.15494)
		(layer "In5.Cu")
		(net "PRSNT_SSD13_FPGA_N")
	)
	(segment
		(start 334.494124 -213.18728)
		(end 332.810612 -213.18728)
		(width 0.15494)
		(layer "In5.Cu")
		(net "PRSNT_SSD13_FPGA_N")
	)
	(segment
		(start 331.394562 -212.707474)
		(end 331.394562 -211.451952)
		(width 0.15494)
		(layer "In5.Cu")
		(net "PRSNT_SSD13_FPGA_N")
	)
	(segment
		(start 332.810612 -213.18728)
		(end 332.678024 -213.242144)
		(width 0.15494)
		(layer "In5.Cu")
		(net "PRSNT_SSD13_FPGA_N")
	)
	(segment
		(start 351.975928 -254.319532)
		(end 351.975928 -255.994916)
		(width 0.13208)
		(layer "F.Cu")
		(net "NC_P0V8_PEX2_PWM3")
	)
	(segment
		(start 351.946718 -254.290576)
		(end 351.975928 -254.319532)
		(width 0.13208)
		(layer "F.Cu")
		(net "NC_P0V8_PEX2_PWM3")
	)
	(via
		(at 351.946718 -254.290576)
		(size 0.762)
		(drill 0.381)
		(layers "F.Cu" "B.Cu")
		(net "NC_P0V8_PEX2_PWM3")
	)
	(segment
		(start 293.992554 -159.688784)
		(end 293.992554 -158.480252)
		(width 0.13208)
		(layer "F.Cu")
		(net "FM_SYS_THROTTLE_NIC4")
	)
	(segment
		(start 294.691816 -160.981644)
		(end 294.691816 -160.388046)
		(width 0.13208)
		(layer "F.Cu")
		(net "FM_SYS_THROTTLE_NIC4")
	)
	(segment
		(start 294.691816 -160.388046)
		(end 293.992554 -159.688784)
		(width 0.13208)
		(layer "F.Cu")
		(net "FM_SYS_THROTTLE_NIC4")
	)
	(via
		(at 293.992554 -159.688784)
		(size 0.762)
		(drill 0.381)
		(layers "F.Cu" "B.Cu")
		(net "FM_SYS_THROTTLE_NIC4")
	)
	(segment
		(start 118.480332 -39.33571)
		(end 119.202708 -40.058086)
		(width 0.13208)
		(layer "F.Cu")
		(net "SSD4_AUX_P3V3_EN")
	)
	(segment
		(start 120.820942 -40.058086)
		(end 120.947942 -40.185086)
		(width 0.13208)
		(layer "F.Cu")
		(net "SSD4_AUX_P3V3_EN")
	)
	(segment
		(start 117.226334 -38.329616)
		(end 117.226334 -39.33571)
		(width 0.13208)
		(layer "F.Cu")
		(net "SSD4_AUX_P3V3_EN")
	)
	(segment
		(start 117.226334 -39.33571)
		(end 118.480332 -39.33571)
		(width 0.13208)
		(layer "F.Cu")
		(net "SSD4_AUX_P3V3_EN")
	)
	(segment
		(start 120.947942 -40.185086)
		(end 120.947942 -41.137332)
		(width 0.13208)
		(layer "F.Cu")
		(net "SSD4_AUX_P3V3_EN")
	)
	(segment
		(start 119.202708 -40.058086)
		(end 120.820942 -40.058086)
		(width 0.13208)
		(layer "F.Cu")
		(net "SSD4_AUX_P3V3_EN")
	)
	(via
		(at 118.480332 -39.33571)
		(size 0.762)
		(drill 0.381)
		(layers "F.Cu" "B.Cu")
		(net "SSD4_AUX_P3V3_EN")
	)
	(segment
		(start 244.3734 -217.2716)
		(end 244.3734 -213.2203)
		(width 0.2032)
		(layer "F.Cu")
		(net "P1V8_PLL0_PEX1")
	)
	(segment
		(start 247.752108 -240.990628)
		(end 247.752108 -236.03077)
		(width 0.254)
		(layer "F.Cu")
		(net "P1V8_PLL0_PEX1")
	)
	(segment
		(start 243.087906 -231.366568)
		(end 243.087906 -227.345494)
		(width 0.2032)
		(layer "F.Cu")
		(net "P1V8_PLL0_PEX1")
	)
	(segment
		(start 219.373958 -240.0427)
		(end 221.113604 -238.303054)
		(width 0.381)
		(layer "F.Cu")
		(net "P1V8_PLL0_PEX1")
	)
	(segment
		(start 221.113604 -238.303054)
		(end 224.305876 -238.303054)
		(width 0.381)
		(layer "F.Cu")
		(net "P1V8_PLL0_PEX1")
	)
	(segment
		(start 225.030538 -237.578392)
		(end 234.762548 -237.578392)
		(width 0.381)
		(layer "F.Cu")
		(net "P1V8_PLL0_PEX1")
	)
	(segment
		(start 234.762548 -237.578392)
		(end 235.857796 -238.67364)
		(width 0.381)
		(layer "F.Cu")
		(net "P1V8_PLL0_PEX1")
	)
	(segment
		(start 243.350796 -218.294204)
		(end 244.3734 -217.2716)
		(width 0.2032)
		(layer "F.Cu")
		(net "P1V8_PLL0_PEX1")
	)
	(segment
		(start 219.92082 -244.2464)
		(end 219.373958 -243.699538)
		(width 0.381)
		(layer "F.Cu")
		(net "P1V8_PLL0_PEX1")
	)
	(segment
		(start 243.087906 -227.345494)
		(end 243.350796 -227.082604)
		(width 0.2032)
		(layer "F.Cu")
		(net "P1V8_PLL0_PEX1")
	)
	(segment
		(start 235.857796 -240.797842)
		(end 237.471712 -242.411758)
		(width 0.381)
		(layer "F.Cu")
		(net "P1V8_PLL0_PEX1")
	)
	(segment
		(start 247.752108 -236.03077)
		(end 243.136166 -231.414828)
		(width 0.508)
		(layer "F.Cu")
		(net "P1V8_PLL0_PEX1")
	)
	(segment
		(start 243.350796 -227.082604)
		(end 243.350796 -218.294204)
		(width 0.2032)
		(layer "F.Cu")
		(net "P1V8_PLL0_PEX1")
	)
	(segment
		(start 243.3828 -212.98535)
		(end 244.13845 -212.98535)
		(width 0.4572)
		(layer "F.Cu")
		(net "P1V8_PLL0_PEX1")
	)
	(segment
		(start 244.3734 -213.2203)
		(end 244.13845 -212.98535)
		(width 0.2032)
		(layer "F.Cu")
		(net "P1V8_PLL0_PEX1")
	)
	(segment
		(start 224.305876 -238.303054)
		(end 225.030538 -237.578392)
		(width 0.381)
		(layer "F.Cu")
		(net "P1V8_PLL0_PEX1")
	)
	(segment
		(start 237.471712 -242.411758)
		(end 246.330978 -242.411758)
		(width 0.508)
		(layer "F.Cu")
		(net "P1V8_PLL0_PEX1")
	)
	(segment
		(start 235.857796 -238.67364)
		(end 235.857796 -240.797842)
		(width 0.381)
		(layer "F.Cu")
		(net "P1V8_PLL0_PEX1")
	)
	(segment
		(start 246.330978 -242.411758)
		(end 247.752108 -240.990628)
		(width 0.508)
		(layer "F.Cu")
		(net "P1V8_PLL0_PEX1")
	)
	(segment
		(start 219.373958 -243.699538)
		(end 219.373958 -240.0427)
		(width 0.381)
		(layer "F.Cu")
		(net "P1V8_PLL0_PEX1")
	)
	(segment
		(start 243.136166 -231.414828)
		(end 243.087906 -231.366568)
		(width 0.2032)
		(layer "F.Cu")
		(net "P1V8_PLL0_PEX1")
	)
	(via
		(at 142.293594 -285.029656)
		(size 0.508)
		(drill 0.254)
		(layers "F.Cu" "B.Cu")
		(net "P1V8_PLL0_PEX1")
	)
	(via
		(at 142.293594 -291.430456)
		(size 0.508)
		(drill 0.254)
		(layers "F.Cu" "B.Cu")
		(net "P1V8_PLL0_PEX1")
	)
	(via
		(at 150.216362 -238.456978)
		(size 0.508)
		(drill 0.254)
		(layers "F.Cu" "B.Cu")
		(net "P1V8_PLL0_PEX1")
	)
	(via
		(at 146.736816 -261.474458)
		(size 0.508)
		(drill 0.254)
		(layers "F.Cu" "B.Cu")
		(net "P1V8_PLL0_PEX1")
	)
	(via
		(at 145.251678 -258.274058)
		(size 0.508)
		(drill 0.254)
		(layers "F.Cu" "B.Cu")
		(net "P1V8_PLL0_PEX1")
	)
	(via
		(at 143.778732 -288.230056)
		(size 0.508)
		(drill 0.254)
		(layers "F.Cu" "B.Cu")
		(net "P1V8_PLL0_PEX1")
	)
	(via
		(at 142.293594 -281.829256)
		(size 0.508)
		(drill 0.254)
		(layers "F.Cu" "B.Cu")
		(net "P1V8_PLL0_PEX1")
	)
	(via
		(at 244.13845 -212.98535)
		(size 0.508)
		(drill 0.254)
		(layers "F.Cu" "B.Cu")
		(net "P1V8_PLL0_PEX1")
	)
	(via
		(at 143.778732 -297.831256)
		(size 0.508)
		(drill 0.254)
		(layers "F.Cu" "B.Cu")
		(net "P1V8_PLL0_PEX1")
	)
	(via
		(at 143.778732 -294.630856)
		(size 0.508)
		(drill 0.254)
		(layers "F.Cu" "B.Cu")
		(net "P1V8_PLL0_PEX1")
	)
	(via
		(at 143.778732 -285.029656)
		(size 0.508)
		(drill 0.254)
		(layers "F.Cu" "B.Cu")
		(net "P1V8_PLL0_PEX1")
	)
	(via
		(at 150.216362 -237.745778)
		(size 0.508)
		(drill 0.254)
		(layers "F.Cu" "B.Cu")
		(net "P1V8_PLL0_PEX1")
	)
	(via
		(at 219.92082 -244.2464)
		(size 0.508)
		(drill 0.254)
		(layers "F.Cu" "B.Cu")
		(net "P1V8_PLL0_PEX1")
	)
	(via
		(at 143.778732 -301.031656)
		(size 0.508)
		(drill 0.254)
		(layers "F.Cu" "B.Cu")
		(net "P1V8_PLL0_PEX1")
	)
	(via
		(at 143.778732 -281.829256)
		(size 0.508)
		(drill 0.254)
		(layers "F.Cu" "B.Cu")
		(net "P1V8_PLL0_PEX1")
	)
	(via
		(at 142.293594 -288.230056)
		(size 0.508)
		(drill 0.254)
		(layers "F.Cu" "B.Cu")
		(net "P1V8_PLL0_PEX1")
	)
	(via
		(at 143.524478 -261.790688)
		(size 0.508)
		(drill 0.254)
		(layers "F.Cu" "B.Cu")
		(net "P1V8_PLL0_PEX1")
	)
	(via
		(at 144.286478 -261.790688)
		(size 0.508)
		(drill 0.254)
		(layers "F.Cu" "B.Cu")
		(net "P1V8_PLL0_PEX1")
	)
	(via
		(at 142.293594 -301.031656)
		(size 0.508)
		(drill 0.254)
		(layers "F.Cu" "B.Cu")
		(net "P1V8_PLL0_PEX1")
	)
	(via
		(at 142.293594 -294.630856)
		(size 0.508)
		(drill 0.254)
		(layers "F.Cu" "B.Cu")
		(net "P1V8_PLL0_PEX1")
	)
	(via
		(at 141.760448 -256.45237)
		(size 0.508)
		(drill 0.254)
		(layers "F.Cu" "B.Cu")
		(net "P1V8_PLL0_PEX1")
	)
	(via
		(at 143.778732 -291.430456)
		(size 0.508)
		(drill 0.254)
		(layers "F.Cu" "B.Cu")
		(net "P1V8_PLL0_PEX1")
	)
	(via
		(at 142.293594 -297.831256)
		(size 0.508)
		(drill 0.254)
		(layers "F.Cu" "B.Cu")
		(net "P1V8_PLL0_PEX1")
	)
	(via
		(at 148.768562 -239.091978)
		(size 0.508)
		(drill 0.254)
		(layers "F.Cu" "B.Cu")
		(net "P1V8_PLL0_PEX1")
	)
	(via
		(at 145.251678 -261.474458)
		(size 0.508)
		(drill 0.254)
		(layers "F.Cu" "B.Cu")
		(net "P1V8_PLL0_PEX1")
	)
	(via
		(at 149.657562 -239.117378)
		(size 0.508)
		(drill 0.254)
		(layers "F.Cu" "B.Cu")
		(net "P1V8_PLL0_PEX1")
	)
	(via
		(at 146.736816 -258.274058)
		(size 0.508)
		(drill 0.254)
		(layers "F.Cu" "B.Cu")
		(net "P1V8_PLL0_PEX1")
	)
	(via
		(at 142.471648 -256.45237)
		(size 0.508)
		(drill 0.254)
		(layers "F.Cu" "B.Cu")
		(net "P1V8_PLL0_PEX1")
	)
	(segment
		(start 143.778732 -301.031656)
		(end 142.293594 -301.031656)
		(width 0.508)
		(layer "B.Cu")
		(net "P1V8_PLL0_PEX1")
	)
	(segment
		(start 219.92082 -244.2464)
		(end 219.599764 -243.925344)
		(width 0.508)
		(layer "In13.Cu")
		(net "P1V8_PLL0_PEX1")
	)
	(segment
		(start 171.186094 -237.745778)
		(end 150.216362 -237.745778)
		(width 0.508)
		(layer "In13.Cu")
		(net "P1V8_PLL0_PEX1")
	)
	(segment
		(start 209.313526 -243.925344)
		(end 207.855058 -245.383812)
		(width 0.508)
		(layer "In13.Cu")
		(net "P1V8_PLL0_PEX1")
	)
	(segment
		(start 219.599764 -243.925344)
		(end 209.313526 -243.925344)
		(width 0.508)
		(layer "In13.Cu")
		(net "P1V8_PLL0_PEX1")
	)
	(segment
		(start 207.855058 -245.383812)
		(end 178.824128 -245.383812)
		(width 0.508)
		(layer "In13.Cu")
		(net "P1V8_PLL0_PEX1")
	)
	(segment
		(start 178.824128 -245.383812)
		(end 171.186094 -237.745778)
		(width 0.508)
		(layer "In13.Cu")
		(net "P1V8_PLL0_PEX1")
	)
	(segment
		(start 381.40005 -200.634092)
		(end 381.52705 -200.761092)
		(width 0.13208)
		(layer "F.Cu")
		(net "PCA9555_0_PEX1_A0")
	)
	(segment
		(start 379.403864 -200.634092)
		(end 381.40005 -200.634092)
		(width 0.13208)
		(layer "F.Cu")
		(net "PCA9555_0_PEX1_A0")
	)
	(segment
		(start 381.52705 -200.761092)
		(end 381.52705 -201.168)
		(width 0.13208)
		(layer "F.Cu")
		(net "PCA9555_0_PEX1_A0")
	)
	(segment
		(start 376.432064 -200.634092)
		(end 379.403864 -200.634092)
		(width 0.13208)
		(layer "F.Cu")
		(net "PCA9555_0_PEX1_A0")
	)
	(segment
		(start 382.75895 -201.168)
		(end 381.52705 -201.168)
		(width 0.13208)
		(layer "F.Cu")
		(net "PCA9555_0_PEX1_A0")
	)
	(via
		(at 379.403864 -200.634092)
		(size 0.508)
		(drill 0.254)
		(layers "F.Cu" "B.Cu")
		(net "PCA9555_0_PEX1_A0")
	)
	(segment
		(start 327.93305 -212.217)
		(end 328.549 -212.217)
		(width 0.13208)
		(layer "F.Cu")
		(net "PRSNT_SSD11_FPGA_N")
	)
	(segment
		(start 338.893912 -215.987122)
		(end 338.494116 -215.587326)
		(width 0.13208)
		(layer "F.Cu")
		(net "PRSNT_SSD11_FPGA_N")
	)
	(via
		(at 338.494116 -215.587326)
		(size 0.4572)
		(drill 0.254)
		(layers "F.Cu" "B.Cu")
		(net "PRSNT_SSD11_FPGA_N")
	)
	(via
		(at 328.549 -212.217)
		(size 0.508)
		(drill 0.254)
		(layers "F.Cu" "B.Cu")
		(net "PRSNT_SSD11_FPGA_N")
	)
	(segment
		(start 328.549 -212.217)
		(end 329.0316 -212.217)
		(width 0.15494)
		(layer "In5.Cu")
		(net "PRSNT_SSD11_FPGA_N")
	)
	(segment
		(start 329.0316 -212.217)
		(end 330.369926 -213.555326)
		(width 0.15494)
		(layer "In5.Cu")
		(net "PRSNT_SSD11_FPGA_N")
	)
	(segment
		(start 338.110068 -215.203278)
		(end 338.494116 -215.587326)
		(width 0.0889)
		(layer "In5.Cu")
		(net "PRSNT_SSD11_FPGA_N")
	)
	(segment
		(start 337.458304 -215.203278)
		(end 338.110068 -215.203278)
		(width 0.0889)
		(layer "In5.Cu")
		(net "PRSNT_SSD11_FPGA_N")
	)
	(segment
		(start 335.0768 -214.401654)
		(end 337.06943 -214.401654)
		(width 0.0889)
		(layer "In5.Cu")
		(net "PRSNT_SSD11_FPGA_N")
	)
	(segment
		(start 337.301078 -215.046052)
		(end 337.458304 -215.203278)
		(width 0.0889)
		(layer "In5.Cu")
		(net "PRSNT_SSD11_FPGA_N")
	)
	(segment
		(start 330.369926 -213.555326)
		(end 331.167486 -213.555326)
		(width 0.15494)
		(layer "In5.Cu")
		(net "PRSNT_SSD11_FPGA_N")
	)
	(segment
		(start 331.167486 -213.555326)
		(end 332.013814 -214.401654)
		(width 0.15494)
		(layer "In5.Cu")
		(net "PRSNT_SSD11_FPGA_N")
	)
	(segment
		(start 337.301078 -214.633302)
		(end 337.301078 -215.046052)
		(width 0.0889)
		(layer "In5.Cu")
		(net "PRSNT_SSD11_FPGA_N")
	)
	(segment
		(start 332.013814 -214.401654)
		(end 335.0768 -214.401654)
		(width 0.15494)
		(layer "In5.Cu")
		(net "PRSNT_SSD11_FPGA_N")
	)
	(segment
		(start 337.06943 -214.401654)
		(end 337.301078 -214.633302)
		(width 0.0889)
		(layer "In5.Cu")
		(net "PRSNT_SSD11_FPGA_N")
	)
	(segment
		(start 411.031944 -163.6268)
		(end 410.791914 -163.38677)
		(width 0.13208)
		(layer "F.Cu")
		(net "FM_SYS_THROTTLE_NIC7")
	)
	(segment
		(start 410.791914 -163.38677)
		(end 410.791914 -162.781488)
		(width 0.13208)
		(layer "F.Cu")
		(net "FM_SYS_THROTTLE_NIC7")
	)
	(segment
		(start 411.825948 -164.128704)
		(end 411.766258 -164.069014)
		(width 0.13208)
		(layer "F.Cu")
		(net "FM_SYS_THROTTLE_NIC7")
	)
	(segment
		(start 411.324044 -163.6268)
		(end 411.031944 -163.6268)
		(width 0.13208)
		(layer "F.Cu")
		(net "FM_SYS_THROTTLE_NIC7")
	)
	(segment
		(start 411.825948 -165.270434)
		(end 411.825948 -164.128704)
		(width 0.13208)
		(layer "F.Cu")
		(net "FM_SYS_THROTTLE_NIC7")
	)
	(segment
		(start 411.766258 -164.069014)
		(end 411.324044 -163.6268)
		(width 0.13208)
		(layer "F.Cu")
		(net "FM_SYS_THROTTLE_NIC7")
	)
	(via
		(at 411.766258 -164.069014)
		(size 0.762)
		(drill 0.381)
		(layers "F.Cu" "B.Cu")
		(net "FM_SYS_THROTTLE_NIC7")
	)
	(segment
		(start 121.946924 -37.774118)
		(end 122.493786 -37.774118)
		(width 0.13208)
		(layer "F.Cu")
		(net "PRSNT_SSD4_R1_N")
	)
	(segment
		(start 119.997982 -38.16731)
		(end 120.391174 -37.774118)
		(width 0.13208)
		(layer "F.Cu")
		(net "PRSNT_SSD4_R1_N")
	)
	(segment
		(start 122.493786 -37.774118)
		(end 122.675904 -37.592)
		(width 0.13208)
		(layer "F.Cu")
		(net "PRSNT_SSD4_R1_N")
	)
	(segment
		(start 122.675904 -37.592)
		(end 122.675904 -37.315648)
		(width 0.13208)
		(layer "F.Cu")
		(net "PRSNT_SSD4_R1_N")
	)
	(segment
		(start 120.391174 -37.774118)
		(end 121.946924 -37.774118)
		(width 0.13208)
		(layer "F.Cu")
		(net "PRSNT_SSD4_R1_N")
	)
	(segment
		(start 119.997982 -38.937184)
		(end 119.997982 -38.16731)
		(width 0.13208)
		(layer "F.Cu")
		(net "PRSNT_SSD4_R1_N")
	)
	(via
		(at 121.946924 -37.774118)
		(size 0.508)
		(drill 0.254)
		(layers "F.Cu" "B.Cu")
		(net "PRSNT_SSD4_R1_N")
	)
	(via
		(at 144.140936 -260.096762)
		(size 0.508)
		(drill 0.254)
		(layers "F.Cu" "B.Cu")
		(net "P1V8_VDDA_PEX1_R")
	)
	(segment
		(start 329.609704 -122.428762)
		(end 329.609704 -123.381516)
		(width 0.13208)
		(layer "F.Cu")
		(net "HP_NIC5_EN")
	)
	(segment
		(start 346.135706 -115.728242)
		(end 346.135706 -108.361734)
		(width 0.13208)
		(layer "F.Cu")
		(net "HP_NIC5_EN")
	)
	(segment
		(start 346.135706 -108.361734)
		(end 345.622626 -107.848654)
		(width 0.13208)
		(layer "F.Cu")
		(net "HP_NIC5_EN")
	)
	(segment
		(start 320.452242 -115.400836)
		(end 319.842642 -115.400836)
		(width 0.13208)
		(layer "F.Cu")
		(net "HP_NIC5_EN")
	)
	(segment
		(start 330.775564 -123.795028)
		(end 330.775564 -124.262896)
		(width 0.13208)
		(layer "F.Cu")
		(net "HP_NIC5_EN")
	)
	(segment
		(start 313.675014 -139.734798)
		(end 314.314332 -139.734798)
		(width 0.13208)
		(layer "F.Cu")
		(net "HP_NIC5_EN")
	)
	(segment
		(start 328.971402 -122.04192)
		(end 329.222862 -122.04192)
		(width 0.13208)
		(layer "F.Cu")
		(net "HP_NIC5_EN")
	)
	(segment
		(start 314.314332 -139.734798)
		(end 314.91682 -139.13231)
		(width 0.13208)
		(layer "F.Cu")
		(net "HP_NIC5_EN")
	)
	(segment
		(start 316.701932 -139.77239)
		(end 316.701932 -140.050774)
		(width 0.13208)
		(layer "F.Cu")
		(net "HP_NIC5_EN")
	)
	(segment
		(start 330.921614 -124.408946)
		(end 333.077566 -124.408946)
		(width 0.13208)
		(layer "F.Cu")
		(net "HP_NIC5_EN")
	)
	(segment
		(start 330.775564 -123.795028)
		(end 330.023216 -123.795028)
		(width 0.13208)
		(layer "F.Cu")
		(net "HP_NIC5_EN")
	)
	(segment
		(start 333.077566 -124.408946)
		(end 340.5505 -121.313448)
		(width 0.13208)
		(layer "F.Cu")
		(net "HP_NIC5_EN")
	)
	(segment
		(start 333.35214 -94.469712)
		(end 333.065882 -94.183454)
		(width 0.13208)
		(layer "F.Cu")
		(net "HP_NIC5_EN")
	)
	(segment
		(start 329.222862 -122.04192)
		(end 329.609704 -122.428762)
		(width 0.13208)
		(layer "F.Cu")
		(net "HP_NIC5_EN")
	)
	(segment
		(start 340.5505 -121.313448)
		(end 346.135706 -115.728242)
		(width 0.13208)
		(layer "F.Cu")
		(net "HP_NIC5_EN")
	)
	(segment
		(start 314.91682 -139.13231)
		(end 316.061852 -139.13231)
		(width 0.13208)
		(layer "F.Cu")
		(net "HP_NIC5_EN")
	)
	(segment
		(start 329.609704 -123.381516)
		(end 330.023216 -123.795028)
		(width 0.13208)
		(layer "F.Cu")
		(net "HP_NIC5_EN")
	)
	(segment
		(start 345.622626 -107.848654)
		(end 344.911934 -107.848654)
		(width 0.13208)
		(layer "F.Cu")
		(net "HP_NIC5_EN")
	)
	(segment
		(start 316.061852 -139.13231)
		(end 316.701932 -139.77239)
		(width 0.13208)
		(layer "F.Cu")
		(net "HP_NIC5_EN")
	)
	(segment
		(start 330.775564 -124.262896)
		(end 330.921614 -124.408946)
		(width 0.13208)
		(layer "F.Cu")
		(net "HP_NIC5_EN")
	)
	(segment
		(start 333.35214 -94.864174)
		(end 333.35214 -94.469712)
		(width 0.13208)
		(layer "F.Cu")
		(net "HP_NIC5_EN")
	)
	(via
		(at 313.675014 -139.734798)
		(size 0.508)
		(drill 0.254)
		(layers "F.Cu" "B.Cu")
		(net "HP_NIC5_EN")
	)
	(via
		(at 333.065882 -94.183454)
		(size 0.508)
		(drill 0.254)
		(layers "F.Cu" "B.Cu")
		(net "HP_NIC5_EN")
	)
	(via
		(at 330.023216 -123.795028)
		(size 0.508)
		(drill 0.254)
		(layers "F.Cu" "B.Cu")
		(net "HP_NIC5_EN")
	)
	(via
		(at 345.622626 -107.848654)
		(size 0.508)
		(drill 0.254)
		(layers "F.Cu" "B.Cu")
		(net "HP_NIC5_EN")
	)
	(via
		(at 319.842642 -115.400836)
		(size 0.508)
		(drill 0.254)
		(layers "F.Cu" "B.Cu")
		(net "HP_NIC5_EN")
	)
	(segment
		(start 330.023216 -123.795028)
		(end 329.220576 -123.795028)
		(width 0.15494)
		(layer "In5.Cu")
		(net "HP_NIC5_EN")
	)
	(segment
		(start 324.873366 -120.43156)
		(end 319.842642 -115.400836)
		(width 0.15494)
		(layer "In5.Cu")
		(net "HP_NIC5_EN")
	)
	(segment
		(start 325.857108 -120.43156)
		(end 324.873366 -120.43156)
		(width 0.15494)
		(layer "In5.Cu")
		(net "HP_NIC5_EN")
	)
	(segment
		(start 329.220576 -123.795028)
		(end 325.857108 -120.43156)
		(width 0.15494)
		(layer "In5.Cu")
		(net "HP_NIC5_EN")
	)
	(segment
		(start 346.768928 -96.009206)
		(end 346.768928 -106.702352)
		(width 0.15494)
		(layer "In7.Cu")
		(net "HP_NIC5_EN")
	)
	(segment
		(start 333.72171 -93.527626)
		(end 344.287348 -93.527626)
		(width 0.15494)
		(layer "In7.Cu")
		(net "HP_NIC5_EN")
	)
	(segment
		(start 344.287348 -93.527626)
		(end 346.768928 -96.009206)
		(width 0.15494)
		(layer "In7.Cu")
		(net "HP_NIC5_EN")
	)
	(segment
		(start 346.768928 -106.702352)
		(end 345.622626 -107.848654)
		(width 0.15494)
		(layer "In7.Cu")
		(net "HP_NIC5_EN")
	)
	(segment
		(start 333.065882 -94.183454)
		(end 333.72171 -93.527626)
		(width 0.15494)
		(layer "In7.Cu")
		(net "HP_NIC5_EN")
	)
	(segment
		(start 320.440812 -115.999006)
		(end 320.440812 -135.249158)
		(width 0.15494)
		(layer "In15.Cu")
		(net "HP_NIC5_EN")
	)
	(segment
		(start 317.419482 -138.270488)
		(end 315.139324 -138.270488)
		(width 0.15494)
		(layer "In15.Cu")
		(net "HP_NIC5_EN")
	)
	(segment
		(start 320.440812 -135.249158)
		(end 317.419482 -138.270488)
		(width 0.15494)
		(layer "In15.Cu")
		(net "HP_NIC5_EN")
	)
	(segment
		(start 315.139324 -138.270488)
		(end 313.675014 -139.734798)
		(width 0.15494)
		(layer "In15.Cu")
		(net "HP_NIC5_EN")
	)
	(segment
		(start 319.842642 -115.400836)
		(end 320.440812 -115.999006)
		(width 0.15494)
		(layer "In15.Cu")
		(net "HP_NIC5_EN")
	)
	(segment
		(start 233.067606 -215.104218)
		(end 233.467402 -214.704422)
		(width 0.13208)
		(layer "F.Cu")
		(net "CLK_25M_BIC_CLKIN")
	)
	(via
		(at 233.467402 -214.704422)
		(size 0.4572)
		(drill 0.254)
		(layers "F.Cu" "B.Cu")
		(net "CLK_25M_BIC_CLKIN")
	)
	(via
		(at 233.966258 -211.731352)
		(size 0.6604)
		(drill 0.3302)
		(layers "F.Cu" "B.Cu")
		(net "CLK_25M_BIC_CLKIN")
	)
	(segment
		(start 233.966258 -211.731352)
		(end 233.966258 -211.372196)
		(width 0.13208)
		(layer "B.Cu")
		(net "CLK_25M_BIC_CLKIN")
	)
	(segment
		(start 233.871262 -213.482682)
		(end 233.966258 -213.387686)
		(width 0.13208)
		(layer "B.Cu")
		(net "CLK_25M_BIC_CLKIN")
	)
	(segment
		(start 233.966258 -213.387686)
		(end 233.966258 -211.731352)
		(width 0.13208)
		(layer "B.Cu")
		(net "CLK_25M_BIC_CLKIN")
	)
	(segment
		(start 234.13466 -207.784446)
		(end 234.13466 -207.42021)
		(width 0.13208)
		(layer "B.Cu")
		(net "CLK_25M_BIC_CLKIN")
	)
	(segment
		(start 234.867704 -210.47075)
		(end 234.867704 -208.51749)
		(width 0.13208)
		(layer "B.Cu")
		(net "CLK_25M_BIC_CLKIN")
	)
	(segment
		(start 233.467402 -214.704422)
		(end 233.871262 -214.300562)
		(width 0.0889)
		(layer "B.Cu")
		(net "CLK_25M_BIC_CLKIN")
	)
	(segment
		(start 233.966258 -211.372196)
		(end 234.867704 -210.47075)
		(width 0.13208)
		(layer "B.Cu")
		(net "CLK_25M_BIC_CLKIN")
	)
	(segment
		(start 233.871262 -214.300562)
		(end 233.871262 -213.482682)
		(width 0.0889)
		(layer "B.Cu")
		(net "CLK_25M_BIC_CLKIN")
	)
	(segment
		(start 234.867704 -208.51749)
		(end 234.13466 -207.784446)
		(width 0.13208)
		(layer "B.Cu")
		(net "CLK_25M_BIC_CLKIN")
	)
	(segment
		(start 211.610448 -212.51291)
		(end 210.643216 -212.51291)
		(width 0.13208)
		(layer "F.Cu")
		(net "UART_BIC_DEBUG_R_TX")
	)
	(segment
		(start 210.82254 -214.10295)
		(end 210.82254 -215.533986)
		(width 0.13208)
		(layer "F.Cu")
		(net "UART_BIC_DEBUG_R_TX")
	)
	(segment
		(start 210.758278 -214.038688)
		(end 210.82254 -214.10295)
		(width 0.13208)
		(layer "F.Cu")
		(net "UART_BIC_DEBUG_R_TX")
	)
	(segment
		(start 210.643216 -212.51291)
		(end 210.294474 -212.861652)
		(width 0.13208)
		(layer "F.Cu")
		(net "UART_BIC_DEBUG_R_TX")
	)
	(segment
		(start 210.82254 -215.533986)
		(end 210.845908 -215.557354)
		(width 0.13208)
		(layer "F.Cu")
		(net "UART_BIC_DEBUG_R_TX")
	)
	(segment
		(start 210.294474 -213.574884)
		(end 210.758278 -214.038688)
		(width 0.13208)
		(layer "F.Cu")
		(net "UART_BIC_DEBUG_R_TX")
	)
	(segment
		(start 210.294474 -212.861652)
		(end 210.294474 -213.574884)
		(width 0.13208)
		(layer "F.Cu")
		(net "UART_BIC_DEBUG_R_TX")
	)
	(via
		(at 210.758278 -214.038688)
		(size 0.508)
		(drill 0.254)
		(layers "F.Cu" "B.Cu")
		(net "UART_BIC_DEBUG_R_TX")
	)
	(segment
		(start 410.092652 -159.688784)
		(end 410.092652 -158.480252)
		(width 0.13208)
		(layer "F.Cu")
		(net "FM_SYS_THROTTLE_NIC6")
	)
	(segment
		(start 410.791914 -160.388046)
		(end 410.092652 -159.688784)
		(width 0.13208)
		(layer "F.Cu")
		(net "FM_SYS_THROTTLE_NIC6")
	)
	(segment
		(start 410.791914 -160.981644)
		(end 410.791914 -160.388046)
		(width 0.13208)
		(layer "F.Cu")
		(net "FM_SYS_THROTTLE_NIC6")
	)
	(via
		(at 410.092652 -159.688784)
		(size 0.762)
		(drill 0.381)
		(layers "F.Cu" "B.Cu")
		(net "FM_SYS_THROTTLE_NIC6")
	)
	(segment
		(start 80.313784 -37.418264)
		(end 80.197198 -37.53485)
		(width 0.13208)
		(layer "F.Cu")
		(net "SSD3_AUX_P3V3_EN_R")
	)
	(segment
		(start 80.856074 -34.383472)
		(end 80.856074 -36.874958)
		(width 0.13208)
		(layer "F.Cu")
		(net "SSD3_AUX_P3V3_EN_R")
	)
	(segment
		(start 84.140802 -57.16397)
		(end 84.140802 -57.675272)
		(width 0.13208)
		(layer "F.Cu")
		(net "SSD3_AUX_P3V3_EN_R")
	)
	(segment
		(start 80.828388 -33.220406)
		(end 80.856074 -33.248092)
		(width 0.13208)
		(layer "F.Cu")
		(net "SSD3_AUX_P3V3_EN_R")
	)
	(segment
		(start 84.140802 -57.675272)
		(end 83.73999 -58.076084)
		(width 0.13208)
		(layer "F.Cu")
		(net "SSD3_AUX_P3V3_EN_R")
	)
	(segment
		(start 82.7151 -59.100974)
		(end 83.73999 -58.076084)
		(width 0.13208)
		(layer "F.Cu")
		(net "SSD3_AUX_P3V3_EN_R")
	)
	(segment
		(start 79.12608 -37.53485)
		(end 78.584298 -37.53485)
		(width 0.13208)
		(layer "F.Cu")
		(net "SSD3_AUX_P3V3_EN_R")
	)
	(segment
		(start 80.856074 -36.874958)
		(end 80.313784 -37.418264)
		(width 0.13208)
		(layer "F.Cu")
		(net "SSD3_AUX_P3V3_EN_R")
	)
	(segment
		(start 80.9244 -34.315146)
		(end 80.856074 -34.383472)
		(width 0.13208)
		(layer "F.Cu")
		(net "SSD3_AUX_P3V3_EN_R")
	)
	(segment
		(start 80.856074 -33.248092)
		(end 80.856074 -33.8836)
		(width 0.13208)
		(layer "F.Cu")
		(net "SSD3_AUX_P3V3_EN_R")
	)
	(segment
		(start 82.7151 -59.146186)
		(end 82.7151 -59.100974)
		(width 0.13208)
		(layer "F.Cu")
		(net "SSD3_AUX_P3V3_EN_R")
	)
	(segment
		(start 80.856074 -33.8836)
		(end 80.9244 -33.951926)
		(width 0.13208)
		(layer "F.Cu")
		(net "SSD3_AUX_P3V3_EN_R")
	)
	(segment
		(start 80.197198 -37.53485)
		(end 79.12608 -37.53485)
		(width 0.13208)
		(layer "F.Cu")
		(net "SSD3_AUX_P3V3_EN_R")
	)
	(segment
		(start 78.584298 -37.53485)
		(end 78.489048 -37.6301)
		(width 0.13208)
		(layer "F.Cu")
		(net "SSD3_AUX_P3V3_EN_R")
	)
	(segment
		(start 80.9244 -33.951926)
		(end 80.9244 -34.315146)
		(width 0.13208)
		(layer "F.Cu")
		(net "SSD3_AUX_P3V3_EN_R")
	)
	(segment
		(start 78.489048 -37.6301)
		(end 78.27772 -37.84092)
		(width 0.13208)
		(layer "F.Cu")
		(net "SSD3_AUX_P3V3_EN_R")
	)
	(segment
		(start 78.27772 -37.84092)
		(end 78.27772 -39.97198)
		(width 0.13208)
		(layer "F.Cu")
		(net "SSD3_AUX_P3V3_EN_R")
	)
	(via
		(at 83.73999 -58.076084)
		(size 0.508)
		(drill 0.254)
		(layers "F.Cu" "B.Cu")
		(net "SSD3_AUX_P3V3_EN_R")
	)
	(via
		(at 78.27772 -39.97198)
		(size 0.508)
		(drill 0.254)
		(layers "F.Cu" "B.Cu")
		(net "SSD3_AUX_P3V3_EN_R")
	)
	(segment
		(start 87.797132 -54.018942)
		(end 87.797132 -46.877478)
		(width 0.15494)
		(layer "In5.Cu")
		(net "SSD3_AUX_P3V3_EN_R")
	)
	(segment
		(start 87.797132 -46.877478)
		(end 80.891634 -39.97198)
		(width 0.15494)
		(layer "In5.Cu")
		(net "SSD3_AUX_P3V3_EN_R")
	)
	(segment
		(start 80.891634 -39.97198)
		(end 78.27772 -39.97198)
		(width 0.15494)
		(layer "In5.Cu")
		(net "SSD3_AUX_P3V3_EN_R")
	)
	(segment
		(start 83.73999 -58.076084)
		(end 87.797132 -54.018942)
		(width 0.15494)
		(layer "In5.Cu")
		(net "SSD3_AUX_P3V3_EN_R")
	)
	(segment
		(start 363.463332 -191.77)
		(end 364.236 -190.997332)
		(width 0.13208)
		(layer "F.Cu")
		(net "PCA9555_1_PEX0_A2")
	)
	(segment
		(start 364.490254 -190.743078)
		(end 366.263936 -190.743078)
		(width 0.13208)
		(layer "F.Cu")
		(net "PCA9555_1_PEX0_A2")
	)
	(segment
		(start 360.78795 -191.262)
		(end 360.78795 -191.643)
		(width 0.13208)
		(layer "F.Cu")
		(net "PCA9555_1_PEX0_A2")
	)
	(segment
		(start 359.55605 -191.262)
		(end 360.78795 -191.262)
		(width 0.13208)
		(layer "F.Cu")
		(net "PCA9555_1_PEX0_A2")
	)
	(segment
		(start 364.236 -190.997332)
		(end 364.490254 -190.743078)
		(width 0.13208)
		(layer "F.Cu")
		(net "PCA9555_1_PEX0_A2")
	)
	(segment
		(start 360.78795 -191.643)
		(end 360.91495 -191.77)
		(width 0.13208)
		(layer "F.Cu")
		(net "PCA9555_1_PEX0_A2")
	)
	(segment
		(start 360.91495 -191.77)
		(end 363.463332 -191.77)
		(width 0.13208)
		(layer "F.Cu")
		(net "PCA9555_1_PEX0_A2")
	)
	(via
		(at 364.236 -190.997332)
		(size 0.508)
		(drill 0.254)
		(layers "F.Cu" "B.Cu")
		(net "PCA9555_1_PEX0_A2")
	)
	(segment
		(start 351.394522 -262.240268)
		(end 351.394522 -261.306056)
		(width 0.2032)
		(layer "F.Cu")
		(net "P0V8_PEX3_ISEN2")
	)
	(segment
		(start 364.531402 -281.999182)
		(end 364.531402 -281.65425)
		(width 0.2286)
		(layer "F.Cu")
		(net "P0V8_PEX3_ISEN2")
	)
	(segment
		(start 351.735136 -262.580882)
		(end 351.394522 -262.240268)
		(width 0.2032)
		(layer "F.Cu")
		(net "P0V8_PEX3_ISEN2")
	)
	(segment
		(start 351.394522 -261.306056)
		(end 351.575878 -261.1247)
		(width 0.2032)
		(layer "F.Cu")
		(net "P0V8_PEX3_ISEN2")
	)
	(segment
		(start 351.575878 -261.1247)
		(end 351.575878 -260.795008)
		(width 0.2032)
		(layer "F.Cu")
		(net "P0V8_PEX3_ISEN2")
	)
	(segment
		(start 364.531402 -281.65425)
		(end 364.968536 -281.217116)
		(width 0.2286)
		(layer "F.Cu")
		(net "P0V8_PEX3_ISEN2")
	)
	(segment
		(start 364.968536 -281.217116)
		(end 364.968536 -281.151838)
		(width 0.2286)
		(layer "F.Cu")
		(net "P0V8_PEX3_ISEN2")
	)
	(via
		(at 351.735136 -262.580882)
		(size 0.508)
		(drill 0.254)
		(layers "F.Cu" "B.Cu")
		(net "P0V8_PEX3_ISEN2")
	)
	(via
		(at 364.968536 -281.151838)
		(size 0.508)
		(drill 0.254)
		(layers "F.Cu" "B.Cu")
		(net "P0V8_PEX3_ISEN2")
	)
	(segment
		(start 366.320324 -280.148538)
		(end 365.804958 -280.663904)
		(width 0.254)
		(layer "In11.Cu")
		(net "P0V8_PEX3_ISEN2")
	)
	(segment
		(start 365.45647 -280.663904)
		(end 364.968536 -281.151838)
		(width 0.254)
		(layer "In11.Cu")
		(net "P0V8_PEX3_ISEN2")
	)
	(segment
		(start 353.601782 -262.758682)
		(end 354.62972 -261.730744)
		(width 0.254)
		(layer "In11.Cu")
		(net "P0V8_PEX3_ISEN2")
	)
	(segment
		(start 366.320324 -279.135078)
		(end 366.320324 -280.148538)
		(width 0.254)
		(layer "In11.Cu")
		(net "P0V8_PEX3_ISEN2")
	)
	(segment
		(start 355.638862 -261.730744)
		(end 359.136442 -263.17956)
		(width 0.254)
		(layer "In11.Cu")
		(net "P0V8_PEX3_ISEN2")
	)
	(segment
		(start 363.873288 -267.916406)
		(end 363.873288 -275.761196)
		(width 0.254)
		(layer "In11.Cu")
		(net "P0V8_PEX3_ISEN2")
	)
	(segment
		(start 364.528608 -277.343362)
		(end 366.320324 -279.135078)
		(width 0.254)
		(layer "In11.Cu")
		(net "P0V8_PEX3_ISEN2")
	)
	(segment
		(start 354.62972 -261.730744)
		(end 355.638862 -261.730744)
		(width 0.254)
		(layer "In11.Cu")
		(net "P0V8_PEX3_ISEN2")
	)
	(segment
		(start 365.804958 -280.663904)
		(end 365.45647 -280.663904)
		(width 0.254)
		(layer "In11.Cu")
		(net "P0V8_PEX3_ISEN2")
	)
	(segment
		(start 363.873288 -275.761196)
		(end 364.528608 -277.343362)
		(width 0.254)
		(layer "In11.Cu")
		(net "P0V8_PEX3_ISEN2")
	)
	(segment
		(start 351.735136 -262.580882)
		(end 352.164396 -262.758682)
		(width 0.254)
		(layer "In11.Cu")
		(net "P0V8_PEX3_ISEN2")
	)
	(segment
		(start 352.164396 -262.758682)
		(end 353.601782 -262.758682)
		(width 0.254)
		(layer "In11.Cu")
		(net "P0V8_PEX3_ISEN2")
	)
	(segment
		(start 359.136442 -263.17956)
		(end 363.873288 -267.916406)
		(width 0.254)
		(layer "In11.Cu")
		(net "P0V8_PEX3_ISEN2")
	)
	(segment
		(start 229.067614 -214.304118)
		(end 228.667818 -213.904322)
		(width 0.13208)
		(layer "F.Cu")
		(net "BIC_SEL_FLASH_SW1")
	)
	(via
		(at 229.26802 -210.318858)
		(size 0.6604)
		(drill 0.3302)
		(layers "F.Cu" "B.Cu")
		(net "BIC_SEL_FLASH_SW1")
	)
	(via
		(at 228.667818 -213.904322)
		(size 0.4572)
		(drill 0.254)
		(layers "F.Cu" "B.Cu")
		(net "BIC_SEL_FLASH_SW1")
	)
	(segment
		(start 229.26802 -209.474054)
		(end 229.26802 -210.318858)
		(width 0.13208)
		(layer "B.Cu")
		(net "BIC_SEL_FLASH_SW1")
	)
	(segment
		(start 229.26802 -213.30412)
		(end 229.26802 -210.318858)
		(width 0.13208)
		(layer "B.Cu")
		(net "BIC_SEL_FLASH_SW1")
	)
	(segment
		(start 229.556564 -209.18551)
		(end 229.26802 -209.474054)
		(width 0.13208)
		(layer "B.Cu")
		(net "BIC_SEL_FLASH_SW1")
	)
	(segment
		(start 228.667818 -213.904322)
		(end 229.26802 -213.30412)
		(width 0.13208)
		(layer "B.Cu")
		(net "BIC_SEL_FLASH_SW1")
	)
	(segment
		(start 177.892456 -159.688784)
		(end 177.892456 -158.480252)
		(width 0.13208)
		(layer "F.Cu")
		(net "FM_SYS_THROTTLE_NIC2")
	)
	(segment
		(start 178.591718 -160.981644)
		(end 178.591718 -160.388046)
		(width 0.13208)
		(layer "F.Cu")
		(net "FM_SYS_THROTTLE_NIC2")
	)
	(segment
		(start 178.591718 -160.388046)
		(end 177.892456 -159.688784)
		(width 0.13208)
		(layer "F.Cu")
		(net "FM_SYS_THROTTLE_NIC2")
	)
	(via
		(at 177.892456 -159.688784)
		(size 0.762)
		(drill 0.381)
		(layers "F.Cu" "B.Cu")
		(net "FM_SYS_THROTTLE_NIC2")
	)
	(segment
		(start 364.236 -192.267332)
		(end 364.246668 -192.267332)
		(width 0.13208)
		(layer "F.Cu")
		(net "PCA9555_1_PEX0_A1")
	)
	(segment
		(start 365.120936 -191.393064)
		(end 366.263936 -191.393064)
		(width 0.13208)
		(layer "F.Cu")
		(net "PCA9555_1_PEX0_A1")
	)
	(segment
		(start 364.236 -192.278)
		(end 364.236 -192.267332)
		(width 0.13208)
		(layer "F.Cu")
		(net "PCA9555_1_PEX0_A1")
	)
	(segment
		(start 360.91495 -192.786)
		(end 363.728 -192.786)
		(width 0.13208)
		(layer "F.Cu")
		(net "PCA9555_1_PEX0_A1")
	)
	(segment
		(start 363.728 -192.786)
		(end 364.236 -192.278)
		(width 0.13208)
		(layer "F.Cu")
		(net "PCA9555_1_PEX0_A1")
	)
	(segment
		(start 359.55605 -192.278)
		(end 360.78795 -192.278)
		(width 0.13208)
		(layer "F.Cu")
		(net "PCA9555_1_PEX0_A1")
	)
	(segment
		(start 364.246668 -192.267332)
		(end 365.120936 -191.393064)
		(width 0.13208)
		(layer "F.Cu")
		(net "PCA9555_1_PEX0_A1")
	)
	(segment
		(start 360.78795 -192.278)
		(end 360.78795 -192.659)
		(width 0.13208)
		(layer "F.Cu")
		(net "PCA9555_1_PEX0_A1")
	)
	(segment
		(start 360.78795 -192.659)
		(end 360.91495 -192.786)
		(width 0.13208)
		(layer "F.Cu")
		(net "PCA9555_1_PEX0_A1")
	)
	(via
		(at 364.236 -192.267332)
		(size 0.508)
		(drill 0.254)
		(layers "F.Cu" "B.Cu")
		(net "PCA9555_1_PEX0_A1")
	)
	(segment
		(start 125.454156 -170.492674)
		(end 125.446282 -170.4848)
		(width 0.13208)
		(layer "F.Cu")
		(net "NIC0_CLK_EN_R_N")
	)
	(segment
		(start 126.00178 -169.157904)
		(end 125.446282 -169.713402)
		(width 0.13208)
		(layer "F.Cu")
		(net "NIC0_CLK_EN_R_N")
	)
	(segment
		(start 125.446282 -169.713402)
		(end 125.446282 -170.4848)
		(width 0.13208)
		(layer "F.Cu")
		(net "NIC0_CLK_EN_R_N")
	)
	(segment
		(start 125.454156 -172.04944)
		(end 125.454156 -170.492674)
		(width 0.13208)
		(layer "F.Cu")
		(net "NIC0_CLK_EN_R_N")
	)
	(via
		(at 124.870464 -238.447834)
		(size 0.508)
		(drill 0.254)
		(layers "F.Cu" "B.Cu")
		(net "NIC0_CLK_EN_R_N")
	)
	(via
		(at 350.139 -236.347)
		(size 0.508)
		(drill 0.254)
		(layers "F.Cu" "B.Cu")
		(net "NIC0_CLK_EN_R_N")
	)
	(via
		(at 126.00178 -169.157904)
		(size 0.508)
		(drill 0.254)
		(layers "F.Cu" "B.Cu")
		(net "NIC0_CLK_EN_R_N")
	)
	(segment
		(start 351.155 -233.95305)
		(end 351.640394 -234.438444)
		(width 0.13208)
		(layer "B.Cu")
		(net "NIC0_CLK_EN_R_N")
	)
	(segment
		(start 351.640394 -234.438444)
		(end 351.640394 -235.349796)
		(width 0.13208)
		(layer "B.Cu")
		(net "NIC0_CLK_EN_R_N")
	)
	(segment
		(start 351.420176 -235.570014)
		(end 350.915986 -235.570014)
		(width 0.13208)
		(layer "B.Cu")
		(net "NIC0_CLK_EN_R_N")
	)
	(segment
		(start 350.915986 -235.570014)
		(end 350.139 -236.347)
		(width 0.13208)
		(layer "B.Cu")
		(net "NIC0_CLK_EN_R_N")
	)
	(segment
		(start 351.640394 -235.349796)
		(end 351.420176 -235.570014)
		(width 0.13208)
		(layer "B.Cu")
		(net "NIC0_CLK_EN_R_N")
	)
	(segment
		(start 125.1712 -238.147098)
		(end 125.1712 -217.931746)
		(width 0.15494)
		(layer "In5.Cu")
		(net "NIC0_CLK_EN_R_N")
	)
	(segment
		(start 128.887474 -167.204136)
		(end 126.933706 -169.157904)
		(width 0.15494)
		(layer "In5.Cu")
		(net "NIC0_CLK_EN_R_N")
	)
	(segment
		(start 125.1712 -217.931746)
		(end 123.2154 -215.975946)
		(width 0.15494)
		(layer "In5.Cu")
		(net "NIC0_CLK_EN_R_N")
	)
	(segment
		(start 131.638294 -200.72096)
		(end 131.638294 -199.974962)
		(width 0.15494)
		(layer "In5.Cu")
		(net "NIC0_CLK_EN_R_N")
	)
	(segment
		(start 133.822694 -197.790562)
		(end 133.822694 -192.437258)
		(width 0.15494)
		(layer "In5.Cu")
		(net "NIC0_CLK_EN_R_N")
	)
	(segment
		(start 126.933706 -169.157904)
		(end 126.00178 -169.157904)
		(width 0.15494)
		(layer "In5.Cu")
		(net "NIC0_CLK_EN_R_N")
	)
	(segment
		(start 138.067796 -188.192156)
		(end 138.067796 -178.635152)
		(width 0.15494)
		(layer "In5.Cu")
		(net "NIC0_CLK_EN_R_N")
	)
	(segment
		(start 123.2154 -215.975946)
		(end 123.2154 -209.143854)
		(width 0.15494)
		(layer "In5.Cu")
		(net "NIC0_CLK_EN_R_N")
	)
	(segment
		(start 137.569194 -167.707564)
		(end 137.065766 -167.204136)
		(width 0.15494)
		(layer "In5.Cu")
		(net "NIC0_CLK_EN_R_N")
	)
	(segment
		(start 133.822694 -192.437258)
		(end 138.067796 -188.192156)
		(width 0.15494)
		(layer "In5.Cu")
		(net "NIC0_CLK_EN_R_N")
	)
	(segment
		(start 137.380218 -177.947574)
		(end 137.380218 -177.176684)
		(width 0.15494)
		(layer "In5.Cu")
		(net "NIC0_CLK_EN_R_N")
	)
	(segment
		(start 131.638294 -199.974962)
		(end 133.822694 -197.790562)
		(width 0.15494)
		(layer "In5.Cu")
		(net "NIC0_CLK_EN_R_N")
	)
	(segment
		(start 137.899648 -173.933612)
		(end 137.569194 -173.603158)
		(width 0.15494)
		(layer "In5.Cu")
		(net "NIC0_CLK_EN_R_N")
	)
	(segment
		(start 124.870464 -238.447834)
		(end 125.1712 -238.147098)
		(width 0.15494)
		(layer "In5.Cu")
		(net "NIC0_CLK_EN_R_N")
	)
	(segment
		(start 123.2154 -209.143854)
		(end 131.638294 -200.72096)
		(width 0.15494)
		(layer "In5.Cu")
		(net "NIC0_CLK_EN_R_N")
	)
	(segment
		(start 138.067796 -178.635152)
		(end 137.380218 -177.947574)
		(width 0.15494)
		(layer "In5.Cu")
		(net "NIC0_CLK_EN_R_N")
	)
	(segment
		(start 137.065766 -167.204136)
		(end 128.887474 -167.204136)
		(width 0.15494)
		(layer "In5.Cu")
		(net "NIC0_CLK_EN_R_N")
	)
	(segment
		(start 137.899648 -176.657254)
		(end 137.899648 -173.933612)
		(width 0.15494)
		(layer "In5.Cu")
		(net "NIC0_CLK_EN_R_N")
	)
	(segment
		(start 137.569194 -173.603158)
		(end 137.569194 -167.707564)
		(width 0.15494)
		(layer "In5.Cu")
		(net "NIC0_CLK_EN_R_N")
	)
	(segment
		(start 137.380218 -177.176684)
		(end 137.899648 -176.657254)
		(width 0.15494)
		(layer "In5.Cu")
		(net "NIC0_CLK_EN_R_N")
	)
	(segment
		(start 303.923192 -251.469144)
		(end 304.092102 -251.300234)
		(width 0.15494)
		(layer "In15.Cu")
		(net "NIC0_CLK_EN_R_N")
	)
	(segment
		(start 247.550178 -247.549924)
		(end 249.498866 -249.498612)
		(width 0.15494)
		(layer "In15.Cu")
		(net "NIC0_CLK_EN_R_N")
	)
	(segment
		(start 155.024074 -234.7087)
		(end 160.499044 -240.18367)
		(width 0.15494)
		(layer "In15.Cu")
		(net "NIC0_CLK_EN_R_N")
	)
	(segment
		(start 124.870464 -238.447834)
		(end 126.599188 -236.71911)
		(width 0.15494)
		(layer "In15.Cu")
		(net "NIC0_CLK_EN_R_N")
	)
	(segment
		(start 238.385096 -249.586242)
		(end 240.421414 -247.549924)
		(width 0.15494)
		(layer "In15.Cu")
		(net "NIC0_CLK_EN_R_N")
	)
	(segment
		(start 152.574498 -234.22102)
		(end 153.752042 -234.7087)
		(width 0.15494)
		(layer "In15.Cu")
		(net "NIC0_CLK_EN_R_N")
	)
	(segment
		(start 221.3864 -248.816368)
		(end 221.3864 -248.335546)
		(width 0.15494)
		(layer "In15.Cu")
		(net "NIC0_CLK_EN_R_N")
	)
	(segment
		(start 333.461106 -250.85929)
		(end 334.183736 -250.13666)
		(width 0.15494)
		(layer "In15.Cu")
		(net "NIC0_CLK_EN_R_N")
	)
	(segment
		(start 179.770532 -240.18367)
		(end 187.831222 -248.24436)
		(width 0.15494)
		(layer "In15.Cu")
		(net "NIC0_CLK_EN_R_N")
	)
	(segment
		(start 221.812104 -247.909842)
		(end 222.213424 -247.909842)
		(width 0.15494)
		(layer "In15.Cu")
		(net "NIC0_CLK_EN_R_N")
	)
	(segment
		(start 222.648272 -248.34469)
		(end 229.79761 -248.34469)
		(width 0.15494)
		(layer "In15.Cu")
		(net "NIC0_CLK_EN_R_N")
	)
	(segment
		(start 332.47457 -252.381766)
		(end 333.461106 -251.39523)
		(width 0.15494)
		(layer "In15.Cu")
		(net "NIC0_CLK_EN_R_N")
	)
	(segment
		(start 258.24688 -249.498612)
		(end 258.612386 -249.864118)
		(width 0.15494)
		(layer "In15.Cu")
		(net "NIC0_CLK_EN_R_N")
	)
	(segment
		(start 221.2594 -248.943368)
		(end 221.3864 -248.816368)
		(width 0.15494)
		(layer "In15.Cu")
		(net "NIC0_CLK_EN_R_N")
	)
	(segment
		(start 229.79761 -248.34469)
		(end 231.039162 -249.586242)
		(width 0.15494)
		(layer "In15.Cu")
		(net "NIC0_CLK_EN_R_N")
	)
	(segment
		(start 327.38695 -252.381766)
		(end 332.47457 -252.381766)
		(width 0.15494)
		(layer "In15.Cu")
		(net "NIC0_CLK_EN_R_N")
	)
	(segment
		(start 222.213424 -247.909842)
		(end 222.648272 -248.34469)
		(width 0.15494)
		(layer "In15.Cu")
		(net "NIC0_CLK_EN_R_N")
	)
	(segment
		(start 126.599188 -236.71911)
		(end 138.908536 -236.71911)
		(width 0.15494)
		(layer "In15.Cu")
		(net "NIC0_CLK_EN_R_N")
	)
	(segment
		(start 333.461106 -251.39523)
		(end 333.461106 -250.85929)
		(width 0.15494)
		(layer "In15.Cu")
		(net "NIC0_CLK_EN_R_N")
	)
	(segment
		(start 350.541082 -237.387638)
		(end 350.139 -236.985556)
		(width 0.15494)
		(layer "In15.Cu")
		(net "NIC0_CLK_EN_R_N")
	)
	(segment
		(start 240.421414 -247.549924)
		(end 247.550178 -247.549924)
		(width 0.15494)
		(layer "In15.Cu")
		(net "NIC0_CLK_EN_R_N")
	)
	(segment
		(start 258.612386 -249.864118)
		(end 298.658788 -249.864118)
		(width 0.15494)
		(layer "In15.Cu")
		(net "NIC0_CLK_EN_R_N")
	)
	(segment
		(start 151.480774 -234.22102)
		(end 152.574498 -234.22102)
		(width 0.15494)
		(layer "In15.Cu")
		(net "NIC0_CLK_EN_R_N")
	)
	(segment
		(start 221.3864 -248.335546)
		(end 221.812104 -247.909842)
		(width 0.15494)
		(layer "In15.Cu")
		(net "NIC0_CLK_EN_R_N")
	)
	(segment
		(start 187.831222 -248.24436)
		(end 189.578234 -248.24436)
		(width 0.15494)
		(layer "In15.Cu")
		(net "NIC0_CLK_EN_R_N")
	)
	(segment
		(start 138.908536 -236.71911)
		(end 142.117826 -233.50982)
		(width 0.15494)
		(layer "In15.Cu")
		(net "NIC0_CLK_EN_R_N")
	)
	(segment
		(start 350.139 -236.985556)
		(end 350.139 -236.347)
		(width 0.15494)
		(layer "In15.Cu")
		(net "NIC0_CLK_EN_R_N")
	)
	(segment
		(start 300.263814 -251.469144)
		(end 303.923192 -251.469144)
		(width 0.15494)
		(layer "In15.Cu")
		(net "NIC0_CLK_EN_R_N")
	)
	(segment
		(start 153.752042 -234.7087)
		(end 155.024074 -234.7087)
		(width 0.15494)
		(layer "In15.Cu")
		(net "NIC0_CLK_EN_R_N")
	)
	(segment
		(start 350.541082 -239.955832)
		(end 350.541082 -237.387638)
		(width 0.15494)
		(layer "In15.Cu")
		(net "NIC0_CLK_EN_R_N")
	)
	(segment
		(start 190.277242 -248.943368)
		(end 221.2594 -248.943368)
		(width 0.15494)
		(layer "In15.Cu")
		(net "NIC0_CLK_EN_R_N")
	)
	(segment
		(start 326.305418 -251.300234)
		(end 327.38695 -252.381766)
		(width 0.15494)
		(layer "In15.Cu")
		(net "NIC0_CLK_EN_R_N")
	)
	(segment
		(start 249.498866 -249.498612)
		(end 258.24688 -249.498612)
		(width 0.15494)
		(layer "In15.Cu")
		(net "NIC0_CLK_EN_R_N")
	)
	(segment
		(start 298.658788 -249.864118)
		(end 300.263814 -251.469144)
		(width 0.15494)
		(layer "In15.Cu")
		(net "NIC0_CLK_EN_R_N")
	)
	(segment
		(start 231.039162 -249.586242)
		(end 238.385096 -249.586242)
		(width 0.15494)
		(layer "In15.Cu")
		(net "NIC0_CLK_EN_R_N")
	)
	(segment
		(start 160.499044 -240.18367)
		(end 179.770532 -240.18367)
		(width 0.15494)
		(layer "In15.Cu")
		(net "NIC0_CLK_EN_R_N")
	)
	(segment
		(start 142.117826 -233.50982)
		(end 149.763226 -233.50982)
		(width 0.15494)
		(layer "In15.Cu")
		(net "NIC0_CLK_EN_R_N")
	)
	(segment
		(start 304.092102 -251.300234)
		(end 326.305418 -251.300234)
		(width 0.15494)
		(layer "In15.Cu")
		(net "NIC0_CLK_EN_R_N")
	)
	(segment
		(start 189.578234 -248.24436)
		(end 190.277242 -248.943368)
		(width 0.15494)
		(layer "In15.Cu")
		(net "NIC0_CLK_EN_R_N")
	)
	(segment
		(start 334.183736 -250.13666)
		(end 340.360254 -250.13666)
		(width 0.15494)
		(layer "In15.Cu")
		(net "NIC0_CLK_EN_R_N")
	)
	(segment
		(start 149.763226 -233.50982)
		(end 151.480774 -234.22102)
		(width 0.15494)
		(layer "In15.Cu")
		(net "NIC0_CLK_EN_R_N")
	)
	(segment
		(start 340.360254 -250.13666)
		(end 350.541082 -239.955832)
		(width 0.15494)
		(layer "In15.Cu")
		(net "NIC0_CLK_EN_R_N")
	)
	(segment
		(start 62.731904 -163.6268)
		(end 63.024004 -163.6268)
		(width 0.13208)
		(layer "F.Cu")
		(net "FM_SYS_THROTTLE_NIC1")
	)
	(segment
		(start 63.525908 -164.128704)
		(end 63.525908 -165.270434)
		(width 0.13208)
		(layer "F.Cu")
		(net "FM_SYS_THROTTLE_NIC1")
	)
	(segment
		(start 62.491874 -162.781488)
		(end 62.491874 -163.38677)
		(width 0.13208)
		(layer "F.Cu")
		(net "FM_SYS_THROTTLE_NIC1")
	)
	(segment
		(start 63.466218 -164.069014)
		(end 63.525908 -164.128704)
		(width 0.13208)
		(layer "F.Cu")
		(net "FM_SYS_THROTTLE_NIC1")
	)
	(segment
		(start 62.491874 -163.38677)
		(end 62.731904 -163.6268)
		(width 0.13208)
		(layer "F.Cu")
		(net "FM_SYS_THROTTLE_NIC1")
	)
	(segment
		(start 63.024004 -163.6268)
		(end 63.466218 -164.069014)
		(width 0.13208)
		(layer "F.Cu")
		(net "FM_SYS_THROTTLE_NIC1")
	)
	(via
		(at 63.466218 -164.069014)
		(size 0.762)
		(drill 0.381)
		(layers "F.Cu" "B.Cu")
		(net "FM_SYS_THROTTLE_NIC1")
	)
	(segment
		(start 79.12608 -39.33571)
		(end 80.380078 -39.33571)
		(width 0.13208)
		(layer "F.Cu")
		(net "SSD3_AUX_P3V3_EN")
	)
	(segment
		(start 82.847688 -40.185086)
		(end 82.847688 -41.137332)
		(width 0.13208)
		(layer "F.Cu")
		(net "SSD3_AUX_P3V3_EN")
	)
	(segment
		(start 82.720688 -40.058086)
		(end 82.847688 -40.185086)
		(width 0.13208)
		(layer "F.Cu")
		(net "SSD3_AUX_P3V3_EN")
	)
	(segment
		(start 80.380078 -39.33571)
		(end 81.102454 -40.058086)
		(width 0.13208)
		(layer "F.Cu")
		(net "SSD3_AUX_P3V3_EN")
	)
	(segment
		(start 81.102454 -40.058086)
		(end 82.720688 -40.058086)
		(width 0.13208)
		(layer "F.Cu")
		(net "SSD3_AUX_P3V3_EN")
	)
	(segment
		(start 79.12608 -39.33571)
		(end 79.12608 -38.33495)
		(width 0.13208)
		(layer "F.Cu")
		(net "SSD3_AUX_P3V3_EN")
	)
	(via
		(at 80.380078 -39.33571)
		(size 0.762)
		(drill 0.381)
		(layers "F.Cu" "B.Cu")
		(net "SSD3_AUX_P3V3_EN")
	)
	(segment
		(start 373.379238 -189.6618)
		(end 372.947946 -190.093092)
		(width 0.13208)
		(layer "F.Cu")
		(net "PCA9555_1_PEX0_A0")
	)
	(segment
		(start 375.085864 -190.093092)
		(end 377.08205 -190.093092)
		(width 0.13208)
		(layer "F.Cu")
		(net "PCA9555_1_PEX0_A0")
	)
	(segment
		(start 378.44095 -190.627)
		(end 377.20905 -190.627)
		(width 0.13208)
		(layer "F.Cu")
		(net "PCA9555_1_PEX0_A0")
	)
	(segment
		(start 374.654572 -189.6618)
		(end 373.379238 -189.6618)
		(width 0.13208)
		(layer "F.Cu")
		(net "PCA9555_1_PEX0_A0")
	)
	(segment
		(start 377.20905 -190.220092)
		(end 377.20905 -190.627)
		(width 0.13208)
		(layer "F.Cu")
		(net "PCA9555_1_PEX0_A0")
	)
	(segment
		(start 377.08205 -190.093092)
		(end 377.20905 -190.220092)
		(width 0.13208)
		(layer "F.Cu")
		(net "PCA9555_1_PEX0_A0")
	)
	(segment
		(start 372.947946 -190.093092)
		(end 372.114064 -190.093092)
		(width 0.13208)
		(layer "F.Cu")
		(net "PCA9555_1_PEX0_A0")
	)
	(segment
		(start 375.085864 -190.093092)
		(end 374.654572 -189.6618)
		(width 0.13208)
		(layer "F.Cu")
		(net "PCA9555_1_PEX0_A0")
	)
	(via
		(at 375.085864 -190.093092)
		(size 0.508)
		(drill 0.254)
		(layers "F.Cu" "B.Cu")
		(net "PCA9555_1_PEX0_A0")
	)
	(segment
		(start 225.067622 -212.704172)
		(end 225.067622 -212.170772)
		(width 0.13208)
		(layer "F.Cu")
		(net "UART_BIC_DEBUG_R_RX")
	)
	(segment
		(start 207.983074 -212.513164)
		(end 207.983074 -212.094826)
		(width 0.13208)
		(layer "F.Cu")
		(net "UART_BIC_DEBUG_R_RX")
	)
	(segment
		(start 207.244188 -210.829652)
		(end 207.229202 -210.844638)
		(width 0.13208)
		(layer "F.Cu")
		(net "UART_BIC_DEBUG_R_RX")
	)
	(segment
		(start 207.983074 -212.094826)
		(end 207.229202 -211.340954)
		(width 0.13208)
		(layer "F.Cu")
		(net "UART_BIC_DEBUG_R_RX")
	)
	(segment
		(start 207.229202 -211.340954)
		(end 207.229202 -210.844638)
		(width 0.13208)
		(layer "F.Cu")
		(net "UART_BIC_DEBUG_R_RX")
	)
	(segment
		(start 208.066386 -210.829652)
		(end 207.244188 -210.829652)
		(width 0.13208)
		(layer "F.Cu")
		(net "UART_BIC_DEBUG_R_RX")
	)
	(via
		(at 207.229202 -210.844638)
		(size 0.508)
		(drill 0.254)
		(layers "F.Cu" "B.Cu")
		(net "UART_BIC_DEBUG_R_RX")
	)
	(via
		(at 225.067622 -212.170772)
		(size 0.4572)
		(drill 0.254)
		(layers "F.Cu" "B.Cu")
		(net "UART_BIC_DEBUG_R_RX")
	)
	(segment
		(start 211.903056 -211.119974)
		(end 212.457538 -210.565492)
		(width 0.15494)
		(layer "In15.Cu")
		(net "UART_BIC_DEBUG_R_RX")
	)
	(segment
		(start 222.839534 -211.882482)
		(end 224.779332 -211.882482)
		(width 0.15494)
		(layer "In15.Cu")
		(net "UART_BIC_DEBUG_R_RX")
	)
	(segment
		(start 211.024216 -212.077554)
		(end 211.903056 -211.198714)
		(width 0.15494)
		(layer "In15.Cu")
		(net "UART_BIC_DEBUG_R_RX")
	)
	(segment
		(start 207.229202 -210.844638)
		(end 209.38998 -210.844638)
		(width 0.15494)
		(layer "In15.Cu")
		(net "UART_BIC_DEBUG_R_RX")
	)
	(segment
		(start 222.484696 -212.23732)
		(end 222.839534 -211.882482)
		(width 0.15494)
		(layer "In15.Cu")
		(net "UART_BIC_DEBUG_R_RX")
	)
	(segment
		(start 214.752428 -211.722716)
		(end 216.401396 -211.722716)
		(width 0.15494)
		(layer "In15.Cu")
		(net "UART_BIC_DEBUG_R_RX")
	)
	(segment
		(start 211.903056 -211.198714)
		(end 211.903056 -211.119974)
		(width 0.15494)
		(layer "In15.Cu")
		(net "UART_BIC_DEBUG_R_RX")
	)
	(segment
		(start 224.779332 -211.882482)
		(end 225.067622 -212.170772)
		(width 0.15494)
		(layer "In15.Cu")
		(net "UART_BIC_DEBUG_R_RX")
	)
	(segment
		(start 210.622896 -212.077554)
		(end 211.024216 -212.077554)
		(width 0.15494)
		(layer "In15.Cu")
		(net "UART_BIC_DEBUG_R_RX")
	)
	(segment
		(start 209.38998 -210.844638)
		(end 210.622896 -212.077554)
		(width 0.15494)
		(layer "In15.Cu")
		(net "UART_BIC_DEBUG_R_RX")
	)
	(segment
		(start 212.457538 -210.565492)
		(end 213.595204 -210.565492)
		(width 0.15494)
		(layer "In15.Cu")
		(net "UART_BIC_DEBUG_R_RX")
	)
	(segment
		(start 213.595204 -210.565492)
		(end 214.752428 -211.722716)
		(width 0.15494)
		(layer "In15.Cu")
		(net "UART_BIC_DEBUG_R_RX")
	)
	(segment
		(start 216.916 -212.23732)
		(end 222.484696 -212.23732)
		(width 0.15494)
		(layer "In15.Cu")
		(net "UART_BIC_DEBUG_R_RX")
	)
	(segment
		(start 216.401396 -211.722716)
		(end 216.916 -212.23732)
		(width 0.15494)
		(layer "In15.Cu")
		(net "UART_BIC_DEBUG_R_RX")
	)
	(segment
		(start 228.39426 -208.626456)
		(end 228.365812 -208.654904)
		(width 0.13208)
		(layer "F.Cu")
		(net "BIC_SEL_FLASH_SW0")
	)
	(segment
		(start 228.39426 -208.602326)
		(end 228.39426 -208.626456)
		(width 0.13208)
		(layer "F.Cu")
		(net "BIC_SEL_FLASH_SW0")
	)
	(segment
		(start 228.39426 -207.604614)
		(end 228.39426 -208.602326)
		(width 0.13208)
		(layer "F.Cu")
		(net "BIC_SEL_FLASH_SW0")
	)
	(segment
		(start 229.471474 -213.100412)
		(end 229.067614 -213.504272)
		(width 0.13208)
		(layer "F.Cu")
		(net "BIC_SEL_FLASH_SW0")
	)
	(segment
		(start 229.471474 -212.47989)
		(end 229.471474 -213.100412)
		(width 0.13208)
		(layer "F.Cu")
		(net "BIC_SEL_FLASH_SW0")
	)
	(segment
		(start 228.578664 -207.42021)
		(end 228.39426 -207.604614)
		(width 0.13208)
		(layer "F.Cu")
		(net "BIC_SEL_FLASH_SW0")
	)
	(segment
		(start 228.365812 -211.374228)
		(end 229.471474 -212.47989)
		(width 0.13208)
		(layer "F.Cu")
		(net "BIC_SEL_FLASH_SW0")
	)
	(segment
		(start 228.365812 -208.654904)
		(end 228.365812 -211.374228)
		(width 0.13208)
		(layer "F.Cu")
		(net "BIC_SEL_FLASH_SW0")
	)
	(via
		(at 228.39426 -208.602326)
		(size 0.762)
		(drill 0.381)
		(layers "F.Cu" "B.Cu")
		(net "BIC_SEL_FLASH_SW0")
	)
	(segment
		(start 82.29092 -37.774118)
		(end 83.84667 -37.774118)
		(width 0.13208)
		(layer "F.Cu")
		(net "PRSNT_SSD3_R1_N")
	)
	(segment
		(start 83.84667 -37.774118)
		(end 84.393532 -37.774118)
		(width 0.13208)
		(layer "F.Cu")
		(net "PRSNT_SSD3_R1_N")
	)
	(segment
		(start 81.897728 -38.16731)
		(end 82.29092 -37.774118)
		(width 0.13208)
		(layer "F.Cu")
		(net "PRSNT_SSD3_R1_N")
	)
	(segment
		(start 84.393532 -37.774118)
		(end 84.57565 -37.592)
		(width 0.13208)
		(layer "F.Cu")
		(net "PRSNT_SSD3_R1_N")
	)
	(segment
		(start 81.897728 -38.937184)
		(end 81.897728 -38.16731)
		(width 0.13208)
		(layer "F.Cu")
		(net "PRSNT_SSD3_R1_N")
	)
	(segment
		(start 84.57565 -37.592)
		(end 84.57565 -37.315648)
		(width 0.13208)
		(layer "F.Cu")
		(net "PRSNT_SSD3_R1_N")
	)
	(via
		(at 83.84667 -37.774118)
		(size 0.508)
		(drill 0.254)
		(layers "F.Cu" "B.Cu")
		(net "PRSNT_SSD3_R1_N")
	)
	(segment
		(start 368.965226 -212.460078)
		(end 370.581936 -212.460078)
		(width 0.13208)
		(layer "F.Cu")
		(net "PCA9555_0_PEX0_A2")
	)
	(segment
		(start 365.10595 -212.979)
		(end 365.10595 -213.36)
		(width 0.13208)
		(layer "F.Cu")
		(net "PCA9555_0_PEX0_A2")
	)
	(segment
		(start 365.10595 -213.36)
		(end 365.23295 -213.487)
		(width 0.13208)
		(layer "F.Cu")
		(net "PCA9555_0_PEX0_A2")
	)
	(segment
		(start 367.938304 -213.487)
		(end 368.965226 -212.460078)
		(width 0.13208)
		(layer "F.Cu")
		(net "PCA9555_0_PEX0_A2")
	)
	(segment
		(start 363.87405 -212.979)
		(end 365.10595 -212.979)
		(width 0.13208)
		(layer "F.Cu")
		(net "PCA9555_0_PEX0_A2")
	)
	(segment
		(start 365.23295 -213.487)
		(end 367.938304 -213.487)
		(width 0.13208)
		(layer "F.Cu")
		(net "PCA9555_0_PEX0_A2")
	)
	(via
		(at 368.965226 -212.460078)
		(size 0.508)
		(drill 0.254)
		(layers "F.Cu" "B.Cu")
		(net "PCA9555_0_PEX0_A2")
	)
	(via
		(at 64.08547 -211.078572)
		(size 0.508)
		(drill 0.254)
		(layers "F.Cu" "B.Cu")
		(net "RST_NIC0_PERST_R_N")
	)
	(via
		(at 52.96916 -157.884114)
		(size 0.508)
		(drill 0.254)
		(layers "F.Cu" "B.Cu")
		(net "RST_NIC0_PERST_R_N")
	)
	(via
		(at 348.107 -236.347)
		(size 0.508)
		(drill 0.254)
		(layers "F.Cu" "B.Cu")
		(net "RST_NIC0_PERST_R_N")
	)
	(segment
		(start 348.58579 -234.49026)
		(end 348.58579 -235.86821)
		(width 0.13208)
		(layer "B.Cu")
		(net "RST_NIC0_PERST_R_N")
	)
	(segment
		(start 53.298852 -157.554422)
		(end 52.96916 -157.884114)
		(width 0.13208)
		(layer "B.Cu")
		(net "RST_NIC0_PERST_R_N")
	)
	(segment
		(start 348.58579 -235.86821)
		(end 348.107 -236.347)
		(width 0.13208)
		(layer "B.Cu")
		(net "RST_NIC0_PERST_R_N")
	)
	(segment
		(start 56.13146 -157.554422)
		(end 53.298852 -157.554422)
		(width 0.13208)
		(layer "B.Cu")
		(net "RST_NIC0_PERST_R_N")
	)
	(segment
		(start 349.123 -233.95305)
		(end 348.58579 -234.49026)
		(width 0.13208)
		(layer "B.Cu")
		(net "RST_NIC0_PERST_R_N")
	)
	(segment
		(start 60.312046 -157.429962)
		(end 56.25592 -157.429962)
		(width 0.13208)
		(layer "B.Cu")
		(net "RST_NIC0_PERST_R_N")
	)
	(segment
		(start 56.25592 -157.429962)
		(end 56.13146 -157.554422)
		(width 0.13208)
		(layer "B.Cu")
		(net "RST_NIC0_PERST_R_N")
	)
	(segment
		(start 54.677564 -161.896044)
		(end 54.677564 -158.272988)
		(width 0.15494)
		(layer "In5.Cu")
		(net "RST_NIC0_PERST_R_N")
	)
	(segment
		(start 55.434738 -162.653218)
		(end 54.677564 -161.896044)
		(width 0.15494)
		(layer "In5.Cu")
		(net "RST_NIC0_PERST_R_N")
	)
	(segment
		(start 59.182 -184.92089)
		(end 55.434738 -181.173628)
		(width 0.15494)
		(layer "In5.Cu")
		(net "RST_NIC0_PERST_R_N")
	)
	(segment
		(start 55.434738 -181.173628)
		(end 55.434738 -162.653218)
		(width 0.15494)
		(layer "In5.Cu")
		(net "RST_NIC0_PERST_R_N")
	)
	(segment
		(start 59.182 -206.829914)
		(end 59.182 -184.92089)
		(width 0.15494)
		(layer "In5.Cu")
		(net "RST_NIC0_PERST_R_N")
	)
	(segment
		(start 54.28869 -157.884114)
		(end 52.96916 -157.884114)
		(width 0.15494)
		(layer "In5.Cu")
		(net "RST_NIC0_PERST_R_N")
	)
	(segment
		(start 64.08547 -211.078572)
		(end 63.430658 -211.078572)
		(width 0.15494)
		(layer "In5.Cu")
		(net "RST_NIC0_PERST_R_N")
	)
	(segment
		(start 54.677564 -158.272988)
		(end 54.28869 -157.884114)
		(width 0.15494)
		(layer "In5.Cu")
		(net "RST_NIC0_PERST_R_N")
	)
	(segment
		(start 63.430658 -211.078572)
		(end 59.182 -206.829914)
		(width 0.15494)
		(layer "In5.Cu")
		(net "RST_NIC0_PERST_R_N")
	)
	(segment
		(start 331.032358 -249.37085)
		(end 332.779116 -249.37085)
		(width 0.15494)
		(layer "In15.Cu")
		(net "RST_NIC0_PERST_R_N")
	)
	(segment
		(start 330.578968 -249.82424)
		(end 331.032358 -249.37085)
		(width 0.15494)
		(layer "In15.Cu")
		(net "RST_NIC0_PERST_R_N")
	)
	(segment
		(start 141.630146 -232.3338)
		(end 150.004526 -232.3338)
		(width 0.15494)
		(layer "In15.Cu")
		(net "RST_NIC0_PERST_R_N")
	)
	(segment
		(start 220.877638 -246.673878)
		(end 221.175834 -246.375682)
		(width 0.15494)
		(layer "In15.Cu")
		(net "RST_NIC0_PERST_R_N")
	)
	(segment
		(start 76.45273 -206.19593)
		(end 98.637598 -206.19593)
		(width 0.15494)
		(layer "In15.Cu")
		(net "RST_NIC0_PERST_R_N")
	)
	(segment
		(start 151.717502 -233.045)
		(end 152.810972 -233.045)
		(width 0.15494)
		(layer "In15.Cu")
		(net "RST_NIC0_PERST_R_N")
	)
	(segment
		(start 185.227214 -242.367054)
		(end 189.534038 -246.673878)
		(width 0.15494)
		(layer "In15.Cu")
		(net "RST_NIC0_PERST_R_N")
	)
	(segment
		(start 70.93966 -211.709)
		(end 76.45273 -206.19593)
		(width 0.15494)
		(layer "In15.Cu")
		(net "RST_NIC0_PERST_R_N")
	)
	(segment
		(start 98.637598 -206.19593)
		(end 102.156768 -207.653128)
		(width 0.15494)
		(layer "In15.Cu")
		(net "RST_NIC0_PERST_R_N")
	)
	(segment
		(start 109.83722 -207.653128)
		(end 114.55654 -212.372448)
		(width 0.15494)
		(layer "In15.Cu")
		(net "RST_NIC0_PERST_R_N")
	)
	(segment
		(start 139.142216 -234.82173)
		(end 141.630146 -232.3338)
		(width 0.15494)
		(layer "In15.Cu")
		(net "RST_NIC0_PERST_R_N")
	)
	(segment
		(start 230.43388 -246.81053)
		(end 231.675432 -248.052082)
		(width 0.15494)
		(layer "In15.Cu")
		(net "RST_NIC0_PERST_R_N")
	)
	(segment
		(start 298.55922 -247.59412)
		(end 300.017688 -249.052588)
		(width 0.15494)
		(layer "In15.Cu")
		(net "RST_NIC0_PERST_R_N")
	)
	(segment
		(start 303.407318 -249.052588)
		(end 303.626774 -248.961656)
		(width 0.15494)
		(layer "In15.Cu")
		(net "RST_NIC0_PERST_R_N")
	)
	(segment
		(start 114.55654 -212.372448)
		(end 114.55654 -231.869488)
		(width 0.15494)
		(layer "In15.Cu")
		(net "RST_NIC0_PERST_R_N")
	)
	(segment
		(start 223.284542 -246.81053)
		(end 230.43388 -246.81053)
		(width 0.15494)
		(layer "In15.Cu")
		(net "RST_NIC0_PERST_R_N")
	)
	(segment
		(start 248.288048 -246.015764)
		(end 249.524012 -247.251728)
		(width 0.15494)
		(layer "In15.Cu")
		(net "RST_NIC0_PERST_R_N")
	)
	(segment
		(start 119.450612 -236.76356)
		(end 121.925334 -236.76356)
		(width 0.15494)
		(layer "In15.Cu")
		(net "RST_NIC0_PERST_R_N")
	)
	(segment
		(start 273.651472 -247.251728)
		(end 273.993864 -247.59412)
		(width 0.15494)
		(layer "In15.Cu")
		(net "RST_NIC0_PERST_R_N")
	)
	(segment
		(start 237.748826 -248.052082)
		(end 239.785144 -246.015764)
		(width 0.15494)
		(layer "In15.Cu")
		(net "RST_NIC0_PERST_R_N")
	)
	(segment
		(start 221.175834 -246.375682)
		(end 222.849694 -246.375682)
		(width 0.15494)
		(layer "In15.Cu")
		(net "RST_NIC0_PERST_R_N")
	)
	(segment
		(start 249.524012 -247.251728)
		(end 273.651472 -247.251728)
		(width 0.15494)
		(layer "In15.Cu")
		(net "RST_NIC0_PERST_R_N")
	)
	(segment
		(start 348.450662 -238.009684)
		(end 348.107 -237.666022)
		(width 0.15494)
		(layer "In15.Cu")
		(net "RST_NIC0_PERST_R_N")
	)
	(segment
		(start 189.534038 -246.673878)
		(end 220.877638 -246.673878)
		(width 0.15494)
		(layer "In15.Cu")
		(net "RST_NIC0_PERST_R_N")
	)
	(segment
		(start 273.993864 -247.59412)
		(end 298.55922 -247.59412)
		(width 0.15494)
		(layer "In15.Cu")
		(net "RST_NIC0_PERST_R_N")
	)
	(segment
		(start 150.004526 -232.3338)
		(end 151.717502 -233.045)
		(width 0.15494)
		(layer "In15.Cu")
		(net "RST_NIC0_PERST_R_N")
	)
	(segment
		(start 153.987246 -233.53268)
		(end 156.222954 -233.53268)
		(width 0.15494)
		(layer "In15.Cu")
		(net "RST_NIC0_PERST_R_N")
	)
	(segment
		(start 326.13727 -248.961656)
		(end 326.999854 -249.82424)
		(width 0.15494)
		(layer "In15.Cu")
		(net "RST_NIC0_PERST_R_N")
	)
	(segment
		(start 348.107 -237.666022)
		(end 348.107 -236.347)
		(width 0.15494)
		(layer "In15.Cu")
		(net "RST_NIC0_PERST_R_N")
	)
	(segment
		(start 222.849694 -246.375682)
		(end 223.284542 -246.81053)
		(width 0.15494)
		(layer "In15.Cu")
		(net "RST_NIC0_PERST_R_N")
	)
	(segment
		(start 333.547466 -248.6025)
		(end 339.723984 -248.6025)
		(width 0.15494)
		(layer "In15.Cu")
		(net "RST_NIC0_PERST_R_N")
	)
	(segment
		(start 179.61864 -237.1471)
		(end 184.838594 -242.367054)
		(width 0.15494)
		(layer "In15.Cu")
		(net "RST_NIC0_PERST_R_N")
	)
	(segment
		(start 156.222954 -233.53268)
		(end 159.837374 -237.1471)
		(width 0.15494)
		(layer "In15.Cu")
		(net "RST_NIC0_PERST_R_N")
	)
	(segment
		(start 300.017688 -249.052588)
		(end 303.407318 -249.052588)
		(width 0.15494)
		(layer "In15.Cu")
		(net "RST_NIC0_PERST_R_N")
	)
	(segment
		(start 152.810972 -233.045)
		(end 153.987246 -233.53268)
		(width 0.15494)
		(layer "In15.Cu")
		(net "RST_NIC0_PERST_R_N")
	)
	(segment
		(start 121.925334 -236.76356)
		(end 123.867164 -234.82173)
		(width 0.15494)
		(layer "In15.Cu")
		(net "RST_NIC0_PERST_R_N")
	)
	(segment
		(start 231.675432 -248.052082)
		(end 237.748826 -248.052082)
		(width 0.15494)
		(layer "In15.Cu")
		(net "RST_NIC0_PERST_R_N")
	)
	(segment
		(start 239.785144 -246.015764)
		(end 248.288048 -246.015764)
		(width 0.15494)
		(layer "In15.Cu")
		(net "RST_NIC0_PERST_R_N")
	)
	(segment
		(start 326.999854 -249.82424)
		(end 330.578968 -249.82424)
		(width 0.15494)
		(layer "In15.Cu")
		(net "RST_NIC0_PERST_R_N")
	)
	(segment
		(start 102.156768 -207.653128)
		(end 109.83722 -207.653128)
		(width 0.15494)
		(layer "In15.Cu")
		(net "RST_NIC0_PERST_R_N")
	)
	(segment
		(start 114.55654 -231.869488)
		(end 119.450612 -236.76356)
		(width 0.15494)
		(layer "In15.Cu")
		(net "RST_NIC0_PERST_R_N")
	)
	(segment
		(start 303.626774 -248.961656)
		(end 326.13727 -248.961656)
		(width 0.15494)
		(layer "In15.Cu")
		(net "RST_NIC0_PERST_R_N")
	)
	(segment
		(start 332.779116 -249.37085)
		(end 333.547466 -248.6025)
		(width 0.15494)
		(layer "In15.Cu")
		(net "RST_NIC0_PERST_R_N")
	)
	(segment
		(start 348.450662 -239.875822)
		(end 348.450662 -238.009684)
		(width 0.15494)
		(layer "In15.Cu")
		(net "RST_NIC0_PERST_R_N")
	)
	(segment
		(start 64.08547 -211.078572)
		(end 64.715898 -211.709)
		(width 0.15494)
		(layer "In15.Cu")
		(net "RST_NIC0_PERST_R_N")
	)
	(segment
		(start 339.723984 -248.6025)
		(end 348.450662 -239.875822)
		(width 0.15494)
		(layer "In15.Cu")
		(net "RST_NIC0_PERST_R_N")
	)
	(segment
		(start 123.867164 -234.82173)
		(end 139.142216 -234.82173)
		(width 0.15494)
		(layer "In15.Cu")
		(net "RST_NIC0_PERST_R_N")
	)
	(segment
		(start 184.838594 -242.367054)
		(end 185.227214 -242.367054)
		(width 0.15494)
		(layer "In15.Cu")
		(net "RST_NIC0_PERST_R_N")
	)
	(segment
		(start 64.715898 -211.709)
		(end 70.93966 -211.709)
		(width 0.15494)
		(layer "In15.Cu")
		(net "RST_NIC0_PERST_R_N")
	)
	(segment
		(start 159.837374 -237.1471)
		(end 179.61864 -237.1471)
		(width 0.15494)
		(layer "In15.Cu")
		(net "RST_NIC0_PERST_R_N")
	)
	(segment
		(start 229.347014 -141.964918)
		(end 228.855524 -141.473428)
		(width 0.13208)
		(layer "F.Cu")
		(net "TP_CK440_PEX_PFT_IN_DN")
	)
	(segment
		(start 228.019356 -141.473428)
		(end 224.931224 -138.385296)
		(width 0.13208)
		(layer "F.Cu")
		(net "TP_CK440_PEX_PFT_IN_DN")
	)
	(segment
		(start 228.855524 -141.473428)
		(end 228.019356 -141.473428)
		(width 0.13208)
		(layer "F.Cu")
		(net "TP_CK440_PEX_PFT_IN_DN")
	)
	(segment
		(start 229.347014 -143.265398)
		(end 229.347014 -141.964918)
		(width 0.13208)
		(layer "F.Cu")
		(net "TP_CK440_PEX_PFT_IN_DN")
	)
	(segment
		(start 224.931224 -138.385296)
		(end 224.931224 -138.090656)
		(width 0.13208)
		(layer "F.Cu")
		(net "TP_CK440_PEX_PFT_IN_DN")
	)
	(via
		(at 224.931224 -138.090656)
		(size 0.508)
		(drill 0.254)
		(layers "F.Cu" "B.Cu")
		(net "TP_CK440_PEX_PFT_IN_DN")
	)
	(segment
		(start 229.067614 -215.104218)
		(end 228.667818 -214.704422)
		(width 0.13208)
		(layer "F.Cu")
		(net "BIC_SEL_FLASH_SW2")
	)
	(via
		(at 227.999544 -213.209124)
		(size 0.508)
		(drill 0.254)
		(layers "F.Cu" "B.Cu")
		(net "BIC_SEL_FLASH_SW2")
	)
	(via
		(at 228.667818 -214.704422)
		(size 0.4572)
		(drill 0.254)
		(layers "F.Cu" "B.Cu")
		(net "BIC_SEL_FLASH_SW2")
	)
	(segment
		(start 228.2444 -212.115146)
		(end 228.2444 -212.964268)
		(width 0.13208)
		(layer "B.Cu")
		(net "BIC_SEL_FLASH_SW2")
	)
	(segment
		(start 228.264212 -214.300816)
		(end 228.264212 -213.473792)
		(width 0.0889)
		(layer "B.Cu")
		(net "BIC_SEL_FLASH_SW2")
	)
	(segment
		(start 228.553264 -210.552792)
		(end 228.87813 -210.877658)
		(width 0.13208)
		(layer "B.Cu")
		(net "BIC_SEL_FLASH_SW2")
	)
	(segment
		(start 228.87813 -210.877658)
		(end 228.87813 -211.55787)
		(width 0.13208)
		(layer "B.Cu")
		(net "BIC_SEL_FLASH_SW2")
	)
	(segment
		(start 228.667818 -214.704422)
		(end 228.264212 -214.300816)
		(width 0.0889)
		(layer "B.Cu")
		(net "BIC_SEL_FLASH_SW2")
	)
	(segment
		(start 228.553264 -209.18551)
		(end 228.553264 -210.552792)
		(width 0.13208)
		(layer "B.Cu")
		(net "BIC_SEL_FLASH_SW2")
	)
	(segment
		(start 228.479858 -211.879688)
		(end 228.2444 -212.115146)
		(width 0.13208)
		(layer "B.Cu")
		(net "BIC_SEL_FLASH_SW2")
	)
	(segment
		(start 228.556312 -211.879688)
		(end 228.479858 -211.879688)
		(width 0.13208)
		(layer "B.Cu")
		(net "BIC_SEL_FLASH_SW2")
	)
	(segment
		(start 228.87813 -211.55787)
		(end 228.556312 -211.879688)
		(width 0.13208)
		(layer "B.Cu")
		(net "BIC_SEL_FLASH_SW2")
	)
	(segment
		(start 228.2444 -212.964268)
		(end 227.999544 -213.209124)
		(width 0.13208)
		(layer "B.Cu")
		(net "BIC_SEL_FLASH_SW2")
	)
	(segment
		(start 228.264212 -213.473792)
		(end 227.999544 -213.209124)
		(width 0.0889)
		(layer "B.Cu")
		(net "BIC_SEL_FLASH_SW2")
	)
	(segment
		(start 62.491874 -160.981644)
		(end 62.491874 -160.388046)
		(width 0.13208)
		(layer "F.Cu")
		(net "FM_SYS_THROTTLE_NIC0")
	)
	(segment
		(start 61.792612 -159.688784)
		(end 61.792612 -158.480252)
		(width 0.13208)
		(layer "F.Cu")
		(net "FM_SYS_THROTTLE_NIC0")
	)
	(segment
		(start 62.491874 -160.388046)
		(end 61.792612 -159.688784)
		(width 0.13208)
		(layer "F.Cu")
		(net "FM_SYS_THROTTLE_NIC0")
	)
	(via
		(at 61.792612 -159.688784)
		(size 0.762)
		(drill 0.381)
		(layers "F.Cu" "B.Cu")
		(net "FM_SYS_THROTTLE_NIC0")
	)
	(segment
		(start 54.9148 -33.942274)
		(end 54.9148 -34.341054)
		(width 0.13208)
		(layer "F.Cu")
		(net "SSD2_AUX_P3V3_EN_R")
	)
	(segment
		(start 57.740042 -58.076084)
		(end 56.715152 -59.100974)
		(width 0.13208)
		(layer "F.Cu")
		(net "SSD2_AUX_P3V3_EN_R")
	)
	(segment
		(start 52.589938 -37.529516)
		(end 53.126132 -37.529516)
		(width 0.13208)
		(layer "F.Cu")
		(net "SSD2_AUX_P3V3_EN_R")
	)
	(segment
		(start 54.9148 -34.341054)
		(end 54.856126 -34.399728)
		(width 0.13208)
		(layer "F.Cu")
		(net "SSD2_AUX_P3V3_EN_R")
	)
	(segment
		(start 52.277772 -39.97198)
		(end 52.277772 -37.84092)
		(width 0.13208)
		(layer "F.Cu")
		(net "SSD2_AUX_P3V3_EN_R")
	)
	(segment
		(start 54.856126 -34.399728)
		(end 54.856126 -36.874958)
		(width 0.13208)
		(layer "F.Cu")
		(net "SSD2_AUX_P3V3_EN_R")
	)
	(segment
		(start 58.140854 -57.675272)
		(end 57.740042 -58.076084)
		(width 0.13208)
		(layer "F.Cu")
		(net "SSD2_AUX_P3V3_EN_R")
	)
	(segment
		(start 54.856126 -33.248092)
		(end 54.856126 -33.8836)
		(width 0.13208)
		(layer "F.Cu")
		(net "SSD2_AUX_P3V3_EN_R")
	)
	(segment
		(start 52.277772 -37.84092)
		(end 52.589938 -37.529516)
		(width 0.13208)
		(layer "F.Cu")
		(net "SSD2_AUX_P3V3_EN_R")
	)
	(segment
		(start 54.202584 -37.529516)
		(end 53.126132 -37.529516)
		(width 0.13208)
		(layer "F.Cu")
		(net "SSD2_AUX_P3V3_EN_R")
	)
	(segment
		(start 58.140854 -57.16397)
		(end 58.140854 -57.675272)
		(width 0.13208)
		(layer "F.Cu")
		(net "SSD2_AUX_P3V3_EN_R")
	)
	(segment
		(start 56.715152 -59.100974)
		(end 56.715152 -59.146186)
		(width 0.13208)
		(layer "F.Cu")
		(net "SSD2_AUX_P3V3_EN_R")
	)
	(segment
		(start 54.856126 -36.874958)
		(end 54.202584 -37.529516)
		(width 0.13208)
		(layer "F.Cu")
		(net "SSD2_AUX_P3V3_EN_R")
	)
	(segment
		(start 54.856126 -33.8836)
		(end 54.9148 -33.942274)
		(width 0.13208)
		(layer "F.Cu")
		(net "SSD2_AUX_P3V3_EN_R")
	)
	(via
		(at 57.740042 -58.076084)
		(size 0.508)
		(drill 0.254)
		(layers "F.Cu" "B.Cu")
		(net "SSD2_AUX_P3V3_EN_R")
	)
	(via
		(at 52.277772 -39.97198)
		(size 0.508)
		(drill 0.254)
		(layers "F.Cu" "B.Cu")
		(net "SSD2_AUX_P3V3_EN_R")
	)
	(segment
		(start 61.75756 -46.113192)
		(end 55.616348 -39.97198)
		(width 0.15494)
		(layer "In5.Cu")
		(net "SSD2_AUX_P3V3_EN_R")
	)
	(segment
		(start 61.75756 -54.058566)
		(end 61.75756 -46.113192)
		(width 0.15494)
		(layer "In5.Cu")
		(net "SSD2_AUX_P3V3_EN_R")
	)
	(segment
		(start 57.740042 -58.076084)
		(end 61.75756 -54.058566)
		(width 0.15494)
		(layer "In5.Cu")
		(net "SSD2_AUX_P3V3_EN_R")
	)
	(segment
		(start 55.616348 -39.97198)
		(end 52.277772 -39.97198)
		(width 0.15494)
		(layer "In5.Cu")
		(net "SSD2_AUX_P3V3_EN_R")
	)
	(segment
		(start 369.438936 -213.110064)
		(end 370.581936 -213.110064)
		(width 0.13208)
		(layer "F.Cu")
		(net "PCA9555_0_PEX0_A1")
	)
	(segment
		(start 365.633 -214.503)
		(end 368.046 -214.503)
		(width 0.13208)
		(layer "F.Cu")
		(net "PCA9555_0_PEX0_A1")
	)
	(segment
		(start 368.046 -214.503)
		(end 369.438936 -213.110064)
		(width 0.13208)
		(layer "F.Cu")
		(net "PCA9555_0_PEX0_A1")
	)
	(segment
		(start 363.87405 -213.995)
		(end 365.10595 -213.995)
		(width 0.13208)
		(layer "F.Cu")
		(net "PCA9555_0_PEX0_A1")
	)
	(segment
		(start 365.10595 -213.995)
		(end 365.125 -213.995)
		(width 0.13208)
		(layer "F.Cu")
		(net "PCA9555_0_PEX0_A1")
	)
	(segment
		(start 365.125 -213.995)
		(end 365.633 -214.503)
		(width 0.13208)
		(layer "F.Cu")
		(net "PCA9555_0_PEX0_A1")
	)
	(via
		(at 368.046 -214.503)
		(size 0.508)
		(drill 0.254)
		(layers "F.Cu" "B.Cu")
		(net "PCA9555_0_PEX0_A1")
	)
	(segment
		(start 336.493866 -216.786968)
		(end 336.09407 -216.387172)
		(width 0.13208)
		(layer "F.Cu")
		(net "PRSNT_SSD9_FPGA_N")
	)
	(segment
		(start 327.93305 -216.281)
		(end 328.549 -216.281)
		(width 0.13208)
		(layer "F.Cu")
		(net "PRSNT_SSD9_FPGA_N")
	)
	(via
		(at 328.549 -216.281)
		(size 0.508)
		(drill 0.254)
		(layers "F.Cu" "B.Cu")
		(net "PRSNT_SSD9_FPGA_N")
	)
	(via
		(at 336.09407 -216.387172)
		(size 0.4572)
		(drill 0.254)
		(layers "F.Cu" "B.Cu")
		(net "PRSNT_SSD9_FPGA_N")
	)
	(segment
		(start 329.687174 -215.142826)
		(end 330.902564 -215.142826)
		(width 0.15494)
		(layer "In5.Cu")
		(net "PRSNT_SSD9_FPGA_N")
	)
	(segment
		(start 328.549 -216.281)
		(end 329.687174 -215.142826)
		(width 0.15494)
		(layer "In5.Cu")
		(net "PRSNT_SSD9_FPGA_N")
	)
	(segment
		(start 335.083912 -216.770966)
		(end 335.710276 -216.770966)
		(width 0.0889)
		(layer "In5.Cu")
		(net "PRSNT_SSD9_FPGA_N")
	)
	(segment
		(start 332.530704 -216.770966)
		(end 335.083912 -216.770966)
		(width 0.15494)
		(layer "In5.Cu")
		(net "PRSNT_SSD9_FPGA_N")
	)
	(segment
		(start 335.710276 -216.770966)
		(end 336.09407 -216.387172)
		(width 0.0889)
		(layer "In5.Cu")
		(net "PRSNT_SSD9_FPGA_N")
	)
	(segment
		(start 330.902564 -215.142826)
		(end 332.530704 -216.770966)
		(width 0.15494)
		(layer "In5.Cu")
		(net "PRSNT_SSD9_FPGA_N")
	)
	(segment
		(start 228.93147 -141.922246)
		(end 228.756718 -141.747494)
		(width 0.13208)
		(layer "F.Cu")
		(net "TP_CK440_PEX_PFT_IN_DP")
	)
	(segment
		(start 224.351596 -138.355578)
		(end 224.351596 -137.231882)
		(width 0.13208)
		(layer "F.Cu")
		(net "TP_CK440_PEX_PFT_IN_DP")
	)
	(segment
		(start 227.743512 -141.747494)
		(end 224.351596 -138.355578)
		(width 0.13208)
		(layer "F.Cu")
		(net "TP_CK440_PEX_PFT_IN_DP")
	)
	(segment
		(start 228.93147 -142.92453)
		(end 228.93147 -141.922246)
		(width 0.13208)
		(layer "F.Cu")
		(net "TP_CK440_PEX_PFT_IN_DP")
	)
	(segment
		(start 228.846888 -143.265398)
		(end 228.846888 -143.009112)
		(width 0.13208)
		(layer "F.Cu")
		(net "TP_CK440_PEX_PFT_IN_DP")
	)
	(segment
		(start 224.351596 -137.231882)
		(end 224.07753 -136.957816)
		(width 0.13208)
		(layer "F.Cu")
		(net "TP_CK440_PEX_PFT_IN_DP")
	)
	(segment
		(start 228.846888 -143.009112)
		(end 228.93147 -142.92453)
		(width 0.13208)
		(layer "F.Cu")
		(net "TP_CK440_PEX_PFT_IN_DP")
	)
	(segment
		(start 228.756718 -141.747494)
		(end 227.743512 -141.747494)
		(width 0.13208)
		(layer "F.Cu")
		(net "TP_CK440_PEX_PFT_IN_DP")
	)
	(via
		(at 224.07753 -136.957816)
		(size 0.508)
		(drill 0.254)
		(layers "F.Cu" "B.Cu")
		(net "TP_CK440_PEX_PFT_IN_DP")
	)
	(segment
		(start 352.539808 -253.411228)
		(end 352.539808 -254.536448)
		(width 0.13208)
		(layer "F.Cu")
		(net "NC_P0V8_PEX2_PWM4")
	)
	(segment
		(start 352.375978 -254.700278)
		(end 352.375978 -255.994916)
		(width 0.13208)
		(layer "F.Cu")
		(net "NC_P0V8_PEX2_PWM4")
	)
	(segment
		(start 352.539808 -254.536448)
		(end 352.375978 -254.700278)
		(width 0.13208)
		(layer "F.Cu")
		(net "NC_P0V8_PEX2_PWM4")
	)
	(segment
		(start 352.125788 -252.997208)
		(end 352.539808 -253.411228)
		(width 0.13208)
		(layer "F.Cu")
		(net "NC_P0V8_PEX2_PWM4")
	)
	(via
		(at 352.125788 -252.997208)
		(size 0.762)
		(drill 0.381)
		(layers "F.Cu" "B.Cu")
		(net "NC_P0V8_PEX2_PWM4")
	)
	(segment
		(start 379.231652 -211.810092)
		(end 376.432064 -211.810092)
		(width 0.13208)
		(layer "F.Cu")
		(net "PCA9555_0_PEX0_A0")
	)
	(segment
		(start 382.75895 -212.344)
		(end 381.52705 -212.344)
		(width 0.13208)
		(layer "F.Cu")
		(net "PCA9555_0_PEX0_A0")
	)
	(segment
		(start 381.40005 -211.810092)
		(end 379.231652 -211.810092)
		(width 0.13208)
		(layer "F.Cu")
		(net "PCA9555_0_PEX0_A0")
	)
	(segment
		(start 381.52705 -212.344)
		(end 381.52705 -211.937092)
		(width 0.13208)
		(layer "F.Cu")
		(net "PCA9555_0_PEX0_A0")
	)
	(segment
		(start 381.52705 -211.937092)
		(end 381.40005 -211.810092)
		(width 0.13208)
		(layer "F.Cu")
		(net "PCA9555_0_PEX0_A0")
	)
	(via
		(at 379.231652 -211.810092)
		(size 0.508)
		(drill 0.254)
		(layers "F.Cu" "B.Cu")
		(net "PCA9555_0_PEX0_A0")
	)
	(segment
		(start 435.125114 -291.238686)
		(end 434.678582 -291.238686)
		(width 0.13208)
		(layer "F.Cu")
		(net "RST_PEX3_PERST_R_N")
	)
	(segment
		(start 435.44744 -294.9956)
		(end 435.631844 -294.811196)
		(width 0.13208)
		(layer "F.Cu")
		(net "RST_PEX3_PERST_R_N")
	)
	(segment
		(start 434.32984 -294.6908)
		(end 434.63464 -294.9956)
		(width 0.13208)
		(layer "F.Cu")
		(net "RST_PEX3_PERST_R_N")
	)
	(segment
		(start 434.63464 -294.9956)
		(end 435.229 -294.9956)
		(width 0.13208)
		(layer "F.Cu")
		(net "RST_PEX3_PERST_R_N")
	)
	(segment
		(start 435.229 -294.9956)
		(end 435.44744 -294.9956)
		(width 0.13208)
		(layer "F.Cu")
		(net "RST_PEX3_PERST_R_N")
	)
	(segment
		(start 435.229 -295.28516)
		(end 435.229 -294.9956)
		(width 0.13208)
		(layer "F.Cu")
		(net "RST_PEX3_PERST_R_N")
	)
	(segment
		(start 435.631844 -296.623232)
		(end 435.631844 -295.688004)
		(width 0.13208)
		(layer "F.Cu")
		(net "RST_PEX3_PERST_R_N")
	)
	(segment
		(start 435.261766 -291.102034)
		(end 435.125114 -291.238686)
		(width 0.13208)
		(layer "F.Cu")
		(net "RST_PEX3_PERST_R_N")
	)
	(segment
		(start 435.631844 -294.811196)
		(end 435.631844 -292.923468)
		(width 0.13208)
		(layer "F.Cu")
		(net "RST_PEX3_PERST_R_N")
	)
	(segment
		(start 435.63794 -292.917372)
		(end 435.631844 -292.923468)
		(width 0.13208)
		(layer "F.Cu")
		(net "RST_PEX3_PERST_R_N")
	)
	(segment
		(start 434.32984 -292.925246)
		(end 434.32984 -294.6908)
		(width 0.13208)
		(layer "F.Cu")
		(net "RST_PEX3_PERST_R_N")
	)
	(segment
		(start 435.63794 -291.102034)
		(end 435.63794 -292.917372)
		(width 0.13208)
		(layer "F.Cu")
		(net "RST_PEX3_PERST_R_N")
	)
	(segment
		(start 434.331618 -292.923468)
		(end 434.32984 -292.925246)
		(width 0.13208)
		(layer "F.Cu")
		(net "RST_PEX3_PERST_R_N")
	)
	(segment
		(start 435.63794 -291.102034)
		(end 435.261766 -291.102034)
		(width 0.13208)
		(layer "F.Cu")
		(net "RST_PEX3_PERST_R_N")
	)
	(segment
		(start 435.631844 -295.688004)
		(end 435.229 -295.28516)
		(width 0.13208)
		(layer "F.Cu")
		(net "RST_PEX3_PERST_R_N")
	)
	(via
		(at 330.128118 -260.130544)
		(size 0.508)
		(drill 0.254)
		(layers "F.Cu" "B.Cu")
		(net "RST_PEX3_PERST_R_N")
	)
	(via
		(at 444.163958 -252.472444)
		(size 0.508)
		(drill 0.254)
		(layers "F.Cu" "B.Cu")
		(net "RST_PEX3_PERST_R_N")
	)
	(via
		(at 328.549 -222.4532)
		(size 0.508)
		(drill 0.254)
		(layers "F.Cu" "B.Cu")
		(net "RST_PEX3_PERST_R_N")
	)
	(via
		(at 434.678582 -291.238686)
		(size 0.508)
		(drill 0.254)
		(layers "F.Cu" "B.Cu")
		(net "RST_PEX3_PERST_R_N")
	)
	(segment
		(start 444.163958 -252.472444)
		(end 432.05781 -264.578592)
		(width 0.13208)
		(layer "B.Cu")
		(net "RST_PEX3_PERST_R_N")
	)
	(segment
		(start 329.29195 -222.4532)
		(end 328.549 -222.4532)
		(width 0.13208)
		(layer "B.Cu")
		(net "RST_PEX3_PERST_R_N")
	)
	(segment
		(start 432.05781 -273.55038)
		(end 435.012084 -276.504654)
		(width 0.13208)
		(layer "B.Cu")
		(net "RST_PEX3_PERST_R_N")
	)
	(segment
		(start 435.012084 -276.504654)
		(end 435.012084 -289.30981)
		(width 0.13208)
		(layer "B.Cu")
		(net "RST_PEX3_PERST_R_N")
	)
	(segment
		(start 432.05781 -264.578592)
		(end 432.05781 -273.55038)
		(width 0.13208)
		(layer "B.Cu")
		(net "RST_PEX3_PERST_R_N")
	)
	(segment
		(start 434.678582 -289.643312)
		(end 434.678582 -291.238686)
		(width 0.13208)
		(layer "B.Cu")
		(net "RST_PEX3_PERST_R_N")
	)
	(segment
		(start 435.012084 -289.30981)
		(end 434.678582 -289.643312)
		(width 0.13208)
		(layer "B.Cu")
		(net "RST_PEX3_PERST_R_N")
	)
	(segment
		(start 326.37222 -228.139752)
		(end 325.9836 -227.751132)
		(width 0.15494)
		(layer "In7.Cu")
		(net "RST_PEX3_PERST_R_N")
	)
	(segment
		(start 328.566526 -247.228106)
		(end 326.9996 -245.66118)
		(width 0.15494)
		(layer "In7.Cu")
		(net "RST_PEX3_PERST_R_N")
	)
	(segment
		(start 330.2 -260.058662)
		(end 330.2 -248.86158)
		(width 0.15494)
		(layer "In7.Cu")
		(net "RST_PEX3_PERST_R_N")
	)
	(segment
		(start 328.864214 -247.511316)
		(end 328.581004 -247.228106)
		(width 0.15494)
		(layer "In7.Cu")
		(net "RST_PEX3_PERST_R_N")
	)
	(segment
		(start 325.9836 -227.751132)
		(end 325.9836 -226.390454)
		(width 0.15494)
		(layer "In7.Cu")
		(net "RST_PEX3_PERST_R_N")
	)
	(segment
		(start 328.864214 -247.525794)
		(end 328.864214 -247.511316)
		(width 0.15494)
		(layer "In7.Cu")
		(net "RST_PEX3_PERST_R_N")
	)
	(segment
		(start 330.2 -248.86158)
		(end 328.864214 -247.525794)
		(width 0.15494)
		(layer "In7.Cu")
		(net "RST_PEX3_PERST_R_N")
	)
	(segment
		(start 326.9996 -245.66118)
		(end 326.9996 -235.4326)
		(width 0.15494)
		(layer "In7.Cu")
		(net "RST_PEX3_PERST_R_N")
	)
	(segment
		(start 328.581004 -247.228106)
		(end 328.566526 -247.228106)
		(width 0.15494)
		(layer "In7.Cu")
		(net "RST_PEX3_PERST_R_N")
	)
	(segment
		(start 327.46315 -224.910904)
		(end 327.46315 -223.53905)
		(width 0.15494)
		(layer "In7.Cu")
		(net "RST_PEX3_PERST_R_N")
	)
	(segment
		(start 325.9836 -226.390454)
		(end 327.46315 -224.910904)
		(width 0.15494)
		(layer "In7.Cu")
		(net "RST_PEX3_PERST_R_N")
	)
	(segment
		(start 326.720708 -229.513638)
		(end 326.37222 -229.16515)
		(width 0.15494)
		(layer "In7.Cu")
		(net "RST_PEX3_PERST_R_N")
	)
	(segment
		(start 327.46315 -223.53905)
		(end 328.549 -222.4532)
		(width 0.15494)
		(layer "In7.Cu")
		(net "RST_PEX3_PERST_R_N")
	)
	(segment
		(start 326.37222 -229.16515)
		(end 326.37222 -228.139752)
		(width 0.15494)
		(layer "In7.Cu")
		(net "RST_PEX3_PERST_R_N")
	)
	(segment
		(start 326.720708 -235.153708)
		(end 326.720708 -229.513638)
		(width 0.15494)
		(layer "In7.Cu")
		(net "RST_PEX3_PERST_R_N")
	)
	(segment
		(start 326.9996 -235.4326)
		(end 326.720708 -235.153708)
		(width 0.15494)
		(layer "In7.Cu")
		(net "RST_PEX3_PERST_R_N")
	)
	(segment
		(start 330.128118 -260.130544)
		(end 330.2 -260.058662)
		(width 0.15494)
		(layer "In7.Cu")
		(net "RST_PEX3_PERST_R_N")
	)
	(segment
		(start 330.128118 -260.130544)
		(end 331.371702 -258.88696)
		(width 0.15494)
		(layer "In13.Cu")
		(net "RST_PEX3_PERST_R_N")
	)
	(segment
		(start 355.0412 -248.7168)
		(end 362.979208 -248.7168)
		(width 0.15494)
		(layer "In13.Cu")
		(net "RST_PEX3_PERST_R_N")
	)
	(segment
		(start 364.161578 -249.89917)
		(end 370.041424 -249.89917)
		(width 0.15494)
		(layer "In13.Cu")
		(net "RST_PEX3_PERST_R_N")
	)
	(segment
		(start 444.163958 -251.819664)
		(end 444.163958 -252.472444)
		(width 0.15494)
		(layer "In13.Cu")
		(net "RST_PEX3_PERST_R_N")
	)
	(segment
		(start 387.6548 -249.739404)
		(end 387.6548 -248.2342)
		(width 0.15494)
		(layer "In13.Cu")
		(net "RST_PEX3_PERST_R_N")
	)
	(segment
		(start 387.6548 -248.2342)
		(end 388.112 -247.777)
		(width 0.15494)
		(layer "In13.Cu")
		(net "RST_PEX3_PERST_R_N")
	)
	(segment
		(start 349.631 -250.1392)
		(end 353.6188 -250.1392)
		(width 0.15494)
		(layer "In13.Cu")
		(net "RST_PEX3_PERST_R_N")
	)
	(segment
		(start 443.099952 -247.777)
		(end 444.881 -249.558048)
		(width 0.15494)
		(layer "In13.Cu")
		(net "RST_PEX3_PERST_R_N")
	)
	(segment
		(start 386.34035 -250.77293)
		(end 387.139942 -249.973338)
		(width 0.15494)
		(layer "In13.Cu")
		(net "RST_PEX3_PERST_R_N")
	)
	(segment
		(start 387.420866 -249.973338)
		(end 387.6548 -249.739404)
		(width 0.15494)
		(layer "In13.Cu")
		(net "RST_PEX3_PERST_R_N")
	)
	(segment
		(start 444.881 -249.558048)
		(end 444.881 -251.102622)
		(width 0.15494)
		(layer "In13.Cu")
		(net "RST_PEX3_PERST_R_N")
	)
	(segment
		(start 388.112 -247.777)
		(end 443.099952 -247.777)
		(width 0.15494)
		(layer "In13.Cu")
		(net "RST_PEX3_PERST_R_N")
	)
	(segment
		(start 386.003038 -251.840238)
		(end 386.34035 -251.502926)
		(width 0.15494)
		(layer "In13.Cu")
		(net "RST_PEX3_PERST_R_N")
	)
	(segment
		(start 387.139942 -249.973338)
		(end 387.420866 -249.973338)
		(width 0.15494)
		(layer "In13.Cu")
		(net "RST_PEX3_PERST_R_N")
	)
	(segment
		(start 371.982492 -251.840238)
		(end 386.003038 -251.840238)
		(width 0.15494)
		(layer "In13.Cu")
		(net "RST_PEX3_PERST_R_N")
	)
	(segment
		(start 386.34035 -251.502926)
		(end 386.34035 -250.77293)
		(width 0.15494)
		(layer "In13.Cu")
		(net "RST_PEX3_PERST_R_N")
	)
	(segment
		(start 331.371702 -258.88696)
		(end 340.374986 -258.88696)
		(width 0.15494)
		(layer "In13.Cu")
		(net "RST_PEX3_PERST_R_N")
	)
	(segment
		(start 362.979208 -248.7168)
		(end 364.161578 -249.89917)
		(width 0.15494)
		(layer "In13.Cu")
		(net "RST_PEX3_PERST_R_N")
	)
	(segment
		(start 346.6338 -253.1364)
		(end 349.631 -250.1392)
		(width 0.15494)
		(layer "In13.Cu")
		(net "RST_PEX3_PERST_R_N")
	)
	(segment
		(start 353.6188 -250.1392)
		(end 355.0412 -248.7168)
		(width 0.15494)
		(layer "In13.Cu")
		(net "RST_PEX3_PERST_R_N")
	)
	(segment
		(start 370.041424 -249.89917)
		(end 371.982492 -251.840238)
		(width 0.15494)
		(layer "In13.Cu")
		(net "RST_PEX3_PERST_R_N")
	)
	(segment
		(start 444.881 -251.102622)
		(end 444.163958 -251.819664)
		(width 0.15494)
		(layer "In13.Cu")
		(net "RST_PEX3_PERST_R_N")
	)
	(segment
		(start 340.374986 -258.88696)
		(end 346.125546 -253.1364)
		(width 0.15494)
		(layer "In13.Cu")
		(net "RST_PEX3_PERST_R_N")
	)
	(segment
		(start 346.125546 -253.1364)
		(end 346.6338 -253.1364)
		(width 0.15494)
		(layer "In13.Cu")
		(net "RST_PEX3_PERST_R_N")
	)
	(segment
		(start 224.876106 -142.07617)
		(end 225.572574 -142.772638)
		(width 0.13208)
		(layer "F.Cu")
		(net "PU_CK440_PEX_PFT_LOST_N")
	)
	(segment
		(start 227.478844 -142.772638)
		(end 227.596954 -142.890748)
		(width 0.0889)
		(layer "F.Cu")
		(net "PU_CK440_PEX_PFT_LOST_N")
	)
	(segment
		(start 223.555052 -139.599162)
		(end 224.523046 -140.567156)
		(width 0.13208)
		(layer "F.Cu")
		(net "PU_CK440_PEX_PFT_LOST_N")
	)
	(segment
		(start 224.523046 -140.567156)
		(end 224.523046 -140.935202)
		(width 0.13208)
		(layer "F.Cu")
		(net "PU_CK440_PEX_PFT_LOST_N")
	)
	(segment
		(start 227.596954 -142.890748)
		(end 227.596954 -144.01546)
		(width 0.0889)
		(layer "F.Cu")
		(net "PU_CK440_PEX_PFT_LOST_N")
	)
	(segment
		(start 223.51238 -139.641834)
		(end 223.555052 -139.599162)
		(width 0.13208)
		(layer "F.Cu")
		(net "PU_CK440_PEX_PFT_LOST_N")
	)
	(segment
		(start 224.876106 -141.288262)
		(end 224.876106 -142.07617)
		(width 0.13208)
		(layer "F.Cu")
		(net "PU_CK440_PEX_PFT_LOST_N")
	)
	(segment
		(start 221.611952 -139.641834)
		(end 223.51238 -139.641834)
		(width 0.13208)
		(layer "F.Cu")
		(net "PU_CK440_PEX_PFT_LOST_N")
	)
	(segment
		(start 224.523046 -140.935202)
		(end 224.876106 -141.288262)
		(width 0.13208)
		(layer "F.Cu")
		(net "PU_CK440_PEX_PFT_LOST_N")
	)
	(segment
		(start 225.572574 -142.772638)
		(end 227.478844 -142.772638)
		(width 0.13208)
		(layer "F.Cu")
		(net "PU_CK440_PEX_PFT_LOST_N")
	)
	(via
		(at 223.555052 -139.599162)
		(size 0.762)
		(drill 0.381)
		(layers "F.Cu" "B.Cu")
		(net "PU_CK440_PEX_PFT_LOST_N")
	)
	(segment
		(start 339.711792 -281.65425)
		(end 340.148926 -281.217116)
		(width 0.2286)
		(layer "F.Cu")
		(net "P0V8_PEX2_ISEN1")
	)
	(segment
		(start 353.975924 -260.795008)
		(end 353.975924 -265.122406)
		(width 0.1778)
		(layer "F.Cu")
		(net "P0V8_PEX2_ISEN1")
	)
	(segment
		(start 339.711792 -281.999182)
		(end 339.711792 -281.65425)
		(width 0.2286)
		(layer "F.Cu")
		(net "P0V8_PEX2_ISEN1")
	)
	(segment
		(start 340.148926 -281.217116)
		(end 340.148926 -281.151838)
		(width 0.2286)
		(layer "F.Cu")
		(net "P0V8_PEX2_ISEN1")
	)
	(segment
		(start 353.264216 -265.834114)
		(end 351.828608 -265.834114)
		(width 0.1778)
		(layer "F.Cu")
		(net "P0V8_PEX2_ISEN1")
	)
	(segment
		(start 353.975924 -265.122406)
		(end 353.264216 -265.834114)
		(width 0.1778)
		(layer "F.Cu")
		(net "P0V8_PEX2_ISEN1")
	)
	(via
		(at 351.828608 -265.834114)
		(size 0.508)
		(drill 0.254)
		(layers "F.Cu" "B.Cu")
		(net "P0V8_PEX2_ISEN1")
	)
	(via
		(at 340.148926 -281.151838)
		(size 0.508)
		(drill 0.254)
		(layers "F.Cu" "B.Cu")
		(net "P0V8_PEX2_ISEN1")
	)
	(segment
		(start 343.898474 -279.75687)
		(end 345.156282 -278.499062)
		(width 0.254)
		(layer "In11.Cu")
		(net "P0V8_PEX2_ISEN1")
	)
	(segment
		(start 345.156282 -278.499062)
		(end 345.156282 -271.106392)
		(width 0.254)
		(layer "In11.Cu")
		(net "P0V8_PEX2_ISEN1")
	)
	(segment
		(start 351.431352 -265.998706)
		(end 351.828608 -265.834114)
		(width 0.254)
		(layer "In11.Cu")
		(net "P0V8_PEX2_ISEN1")
	)
	(segment
		(start 349.313754 -266.94892)
		(end 350.481138 -266.94892)
		(width 0.254)
		(layer "In11.Cu")
		(net "P0V8_PEX2_ISEN1")
	)
	(segment
		(start 340.975696 -280.663904)
		(end 341.88273 -279.75687)
		(width 0.254)
		(layer "In11.Cu")
		(net "P0V8_PEX2_ISEN1")
	)
	(segment
		(start 341.88273 -279.75687)
		(end 343.898474 -279.75687)
		(width 0.254)
		(layer "In11.Cu")
		(net "P0V8_PEX2_ISEN1")
	)
	(segment
		(start 340.63686 -280.663904)
		(end 340.975696 -280.663904)
		(width 0.254)
		(layer "In11.Cu")
		(net "P0V8_PEX2_ISEN1")
	)
	(segment
		(start 345.156282 -271.106392)
		(end 349.313754 -266.94892)
		(width 0.254)
		(layer "In11.Cu")
		(net "P0V8_PEX2_ISEN1")
	)
	(segment
		(start 350.481138 -266.94892)
		(end 351.431352 -265.998706)
		(width 0.254)
		(layer "In11.Cu")
		(net "P0V8_PEX2_ISEN1")
	)
	(segment
		(start 340.148926 -281.151838)
		(end 340.63686 -280.663904)
		(width 0.254)
		(layer "In11.Cu")
		(net "P0V8_PEX2_ISEN1")
	)
	(segment
		(start 54.38013 -39.33571)
		(end 53.126132 -39.33571)
		(width 0.13208)
		(layer "F.Cu")
		(net "SSD2_AUX_P3V3_EN")
	)
	(segment
		(start 53.126132 -38.329616)
		(end 53.126132 -39.33571)
		(width 0.13208)
		(layer "F.Cu")
		(net "SSD2_AUX_P3V3_EN")
	)
	(segment
		(start 56.84774 -40.185086)
		(end 56.72074 -40.058086)
		(width 0.13208)
		(layer "F.Cu")
		(net "SSD2_AUX_P3V3_EN")
	)
	(segment
		(start 56.84774 -41.137332)
		(end 56.84774 -40.185086)
		(width 0.13208)
		(layer "F.Cu")
		(net "SSD2_AUX_P3V3_EN")
	)
	(segment
		(start 55.102506 -40.058086)
		(end 54.38013 -39.33571)
		(width 0.13208)
		(layer "F.Cu")
		(net "SSD2_AUX_P3V3_EN")
	)
	(segment
		(start 56.72074 -40.058086)
		(end 55.102506 -40.058086)
		(width 0.13208)
		(layer "F.Cu")
		(net "SSD2_AUX_P3V3_EN")
	)
	(via
		(at 54.38013 -39.33571)
		(size 0.762)
		(drill 0.381)
		(layers "F.Cu" "B.Cu")
		(net "SSD2_AUX_P3V3_EN")
	)
	(segment
		(start 66.337434 -158.35503)
		(end 68.65747 -158.35503)
		(width 0.13208)
		(layer "F.Cu")
		(net "NIC1_PWRBRK_R_N")
	)
	(segment
		(start 65.05448 -157.680152)
		(end 65.662556 -157.680152)
		(width 0.13208)
		(layer "F.Cu")
		(net "NIC1_PWRBRK_R_N")
	)
	(segment
		(start 63.824612 -157.680152)
		(end 65.05448 -157.680152)
		(width 0.13208)
		(layer "F.Cu")
		(net "NIC1_PWRBRK_R_N")
	)
	(segment
		(start 65.662556 -157.680152)
		(end 66.337434 -158.35503)
		(width 0.13208)
		(layer "F.Cu")
		(net "NIC1_PWRBRK_R_N")
	)
	(via
		(at 65.05448 -157.680152)
		(size 0.762)
		(drill 0.381)
		(layers "F.Cu" "B.Cu")
		(net "NIC1_PWRBRK_R_N")
	)
	(segment
		(start 57.846722 -37.774118)
		(end 58.393584 -37.774118)
		(width 0.13208)
		(layer "F.Cu")
		(net "PRSNT_SSD2_R1_N")
	)
	(segment
		(start 58.393584 -37.774118)
		(end 58.575702 -37.592)
		(width 0.13208)
		(layer "F.Cu")
		(net "PRSNT_SSD2_R1_N")
	)
	(segment
		(start 58.575702 -37.592)
		(end 58.575702 -37.315648)
		(width 0.13208)
		(layer "F.Cu")
		(net "PRSNT_SSD2_R1_N")
	)
	(segment
		(start 55.89778 -38.937184)
		(end 55.89778 -38.16731)
		(width 0.13208)
		(layer "F.Cu")
		(net "PRSNT_SSD2_R1_N")
	)
	(segment
		(start 55.89778 -38.16731)
		(end 56.290972 -37.774118)
		(width 0.13208)
		(layer "F.Cu")
		(net "PRSNT_SSD2_R1_N")
	)
	(segment
		(start 56.290972 -37.774118)
		(end 57.846722 -37.774118)
		(width 0.13208)
		(layer "F.Cu")
		(net "PRSNT_SSD2_R1_N")
	)
	(via
		(at 57.846722 -37.774118)
		(size 0.508)
		(drill 0.254)
		(layers "F.Cu" "B.Cu")
		(net "PRSNT_SSD2_R1_N")
	)
	(segment
		(start 338.093812 -216.786968)
		(end 337.694016 -216.387172)
		(width 0.13208)
		(layer "F.Cu")
		(net "PRSNT_SSD8_FPGA_N")
	)
	(segment
		(start 327.93305 -214.249)
		(end 328.549 -214.249)
		(width 0.13208)
		(layer "F.Cu")
		(net "PRSNT_SSD8_FPGA_N")
	)
	(via
		(at 337.694016 -216.387172)
		(size 0.4572)
		(drill 0.254)
		(layers "F.Cu" "B.Cu")
		(net "PRSNT_SSD8_FPGA_N")
	)
	(via
		(at 328.549 -214.249)
		(size 0.508)
		(drill 0.254)
		(layers "F.Cu" "B.Cu")
		(net "PRSNT_SSD8_FPGA_N")
	)
	(segment
		(start 335.097628 -215.996774)
		(end 332.52283 -215.996774)
		(width 0.15494)
		(layer "In5.Cu")
		(net "PRSNT_SSD8_FPGA_N")
	)
	(segment
		(start 331.203554 -214.677498)
		(end 328.977498 -214.677498)
		(width 0.15494)
		(layer "In5.Cu")
		(net "PRSNT_SSD8_FPGA_N")
	)
	(segment
		(start 332.52283 -215.996774)
		(end 331.203554 -214.677498)
		(width 0.15494)
		(layer "In5.Cu")
		(net "PRSNT_SSD8_FPGA_N")
	)
	(segment
		(start 328.977498 -214.677498)
		(end 328.549 -214.249)
		(width 0.15494)
		(layer "In5.Cu")
		(net "PRSNT_SSD8_FPGA_N")
	)
	(segment
		(start 337.303618 -215.996774)
		(end 335.097628 -215.996774)
		(width 0.0889)
		(layer "In5.Cu")
		(net "PRSNT_SSD8_FPGA_N")
	)
	(segment
		(start 337.694016 -216.387172)
		(end 337.303618 -215.996774)
		(width 0.0889)
		(layer "In5.Cu")
		(net "PRSNT_SSD8_FPGA_N")
	)
	(segment
		(start 297.862498 -157.680152)
		(end 298.537376 -158.35503)
		(width 0.13208)
		(layer "F.Cu")
		(net "NIC5_PWRBRK_R_N")
	)
	(segment
		(start 296.024554 -157.680152)
		(end 297.254422 -157.680152)
		(width 0.13208)
		(layer "F.Cu")
		(net "NIC5_PWRBRK_R_N")
	)
	(segment
		(start 297.254422 -157.680152)
		(end 297.862498 -157.680152)
		(width 0.13208)
		(layer "F.Cu")
		(net "NIC5_PWRBRK_R_N")
	)
	(segment
		(start 298.537376 -158.35503)
		(end 300.857412 -158.35503)
		(width 0.13208)
		(layer "F.Cu")
		(net "NIC5_PWRBRK_R_N")
	)
	(via
		(at 297.254422 -157.680152)
		(size 0.762)
		(drill 0.381)
		(layers "F.Cu" "B.Cu")
		(net "NIC5_PWRBRK_R_N")
	)
	(segment
		(start 319.118742 -294.9956)
		(end 319.118742 -295.275)
		(width 0.13208)
		(layer "F.Cu")
		(net "RST_PEX2_PERST_R_N")
	)
	(segment
		(start 319.531746 -295.688004)
		(end 319.531746 -296.623232)
		(width 0.13208)
		(layer "F.Cu")
		(net "RST_PEX2_PERST_R_N")
	)
	(segment
		(start 318.534542 -294.9956)
		(end 318.229742 -294.6908)
		(width 0.13208)
		(layer "F.Cu")
		(net "RST_PEX2_PERST_R_N")
	)
	(segment
		(start 319.118742 -295.275)
		(end 319.531746 -295.688004)
		(width 0.13208)
		(layer "F.Cu")
		(net "RST_PEX2_PERST_R_N")
	)
	(segment
		(start 319.531746 -291.10813)
		(end 319.537842 -291.102034)
		(width 0.13208)
		(layer "F.Cu")
		(net "RST_PEX2_PERST_R_N")
	)
	(segment
		(start 319.531746 -292.923468)
		(end 319.531746 -294.811196)
		(width 0.13208)
		(layer "F.Cu")
		(net "RST_PEX2_PERST_R_N")
	)
	(segment
		(start 319.118742 -294.9956)
		(end 318.534542 -294.9956)
		(width 0.13208)
		(layer "F.Cu")
		(net "RST_PEX2_PERST_R_N")
	)
	(segment
		(start 319.347342 -294.9956)
		(end 319.118742 -294.9956)
		(width 0.13208)
		(layer "F.Cu")
		(net "RST_PEX2_PERST_R_N")
	)
	(segment
		(start 318.701166 -291.102034)
		(end 318.5668 -291.2364)
		(width 0.13208)
		(layer "F.Cu")
		(net "RST_PEX2_PERST_R_N")
	)
	(segment
		(start 319.537842 -291.102034)
		(end 318.701166 -291.102034)
		(width 0.13208)
		(layer "F.Cu")
		(net "RST_PEX2_PERST_R_N")
	)
	(segment
		(start 318.229742 -292.925246)
		(end 318.23152 -292.923468)
		(width 0.13208)
		(layer "F.Cu")
		(net "RST_PEX2_PERST_R_N")
	)
	(segment
		(start 319.531746 -294.811196)
		(end 319.347342 -294.9956)
		(width 0.13208)
		(layer "F.Cu")
		(net "RST_PEX2_PERST_R_N")
	)
	(segment
		(start 318.229742 -294.6908)
		(end 318.229742 -292.925246)
		(width 0.13208)
		(layer "F.Cu")
		(net "RST_PEX2_PERST_R_N")
	)
	(segment
		(start 319.531746 -292.923468)
		(end 319.531746 -291.10813)
		(width 0.13208)
		(layer "F.Cu")
		(net "RST_PEX2_PERST_R_N")
	)
	(via
		(at 318.5668 -291.2364)
		(size 0.508)
		(drill 0.254)
		(layers "F.Cu" "B.Cu")
		(net "RST_PEX2_PERST_R_N")
	)
	(via
		(at 318.135 -257.629152)
		(size 0.508)
		(drill 0.254)
		(layers "F.Cu" "B.Cu")
		(net "RST_PEX2_PERST_R_N")
	)
	(via
		(at 328.549 -221.4372)
		(size 0.508)
		(drill 0.254)
		(layers "F.Cu" "B.Cu")
		(net "RST_PEX2_PERST_R_N")
	)
	(segment
		(start 319.451482 -259.37337)
		(end 318.135 -258.056888)
		(width 0.13208)
		(layer "B.Cu")
		(net "RST_PEX2_PERST_R_N")
	)
	(segment
		(start 318.578484 -291.224716)
		(end 318.578484 -289.643312)
		(width 0.13208)
		(layer "B.Cu")
		(net "RST_PEX2_PERST_R_N")
	)
	(segment
		(start 318.911986 -289.30981)
		(end 318.911986 -276.210522)
		(width 0.13208)
		(layer "B.Cu")
		(net "RST_PEX2_PERST_R_N")
	)
	(segment
		(start 318.135 -258.056888)
		(end 318.135 -257.629152)
		(width 0.13208)
		(layer "B.Cu")
		(net "RST_PEX2_PERST_R_N")
	)
	(segment
		(start 316.14618 -267.698982)
		(end 319.451482 -264.39368)
		(width 0.13208)
		(layer "B.Cu")
		(net "RST_PEX2_PERST_R_N")
	)
	(segment
		(start 316.13348 -271.707102)
		(end 316.14618 -271.694402)
		(width 0.13208)
		(layer "B.Cu")
		(net "RST_PEX2_PERST_R_N")
	)
	(segment
		(start 319.451482 -264.39368)
		(end 319.451482 -259.37337)
		(width 0.13208)
		(layer "B.Cu")
		(net "RST_PEX2_PERST_R_N")
	)
	(segment
		(start 316.14618 -271.694402)
		(end 316.14618 -267.698982)
		(width 0.13208)
		(layer "B.Cu")
		(net "RST_PEX2_PERST_R_N")
	)
	(segment
		(start 318.911986 -276.210522)
		(end 316.13348 -273.432016)
		(width 0.13208)
		(layer "B.Cu")
		(net "RST_PEX2_PERST_R_N")
	)
	(segment
		(start 318.5668 -291.2364)
		(end 318.578484 -291.224716)
		(width 0.13208)
		(layer "B.Cu")
		(net "RST_PEX2_PERST_R_N")
	)
	(segment
		(start 318.578484 -289.643312)
		(end 318.911986 -289.30981)
		(width 0.13208)
		(layer "B.Cu")
		(net "RST_PEX2_PERST_R_N")
	)
	(segment
		(start 329.29195 -221.4372)
		(end 328.549 -221.4372)
		(width 0.13208)
		(layer "B.Cu")
		(net "RST_PEX2_PERST_R_N")
	)
	(segment
		(start 316.13348 -273.432016)
		(end 316.13348 -271.707102)
		(width 0.13208)
		(layer "B.Cu")
		(net "RST_PEX2_PERST_R_N")
	)
	(segment
		(start 327.87209 -234.90809)
		(end 327.3044 -234.3404)
		(width 0.15494)
		(layer "In7.Cu")
		(net "RST_PEX2_PERST_R_N")
	)
	(segment
		(start 330.3778 -260.6294)
		(end 330.7842 -260.223)
		(width 0.15494)
		(layer "In7.Cu")
		(net "RST_PEX2_PERST_R_N")
	)
	(segment
		(start 328.554588 -244.59819)
		(end 328.554588 -243.599716)
		(width 0.15494)
		(layer "In7.Cu")
		(net "RST_PEX2_PERST_R_N")
	)
	(segment
		(start 328.0664 -237.5916)
		(end 329.6158 -236.0422)
		(width 0.15494)
		(layer "In7.Cu")
		(net "RST_PEX2_PERST_R_N")
	)
	(segment
		(start 330.7842 -260.223)
		(end 330.7842 -248.6406)
		(width 0.15494)
		(layer "In7.Cu")
		(net "RST_PEX2_PERST_R_N")
	)
	(segment
		(start 330.7842 -248.6406)
		(end 328.131932 -245.988332)
		(width 0.15494)
		(layer "In7.Cu")
		(net "RST_PEX2_PERST_R_N")
	)
	(segment
		(start 328.131932 -245.988332)
		(end 328.131932 -245.020846)
		(width 0.15494)
		(layer "In7.Cu")
		(net "RST_PEX2_PERST_R_N")
	)
	(segment
		(start 327.3044 -234.3404)
		(end 327.3044 -230.649526)
		(width 0.15494)
		(layer "In7.Cu")
		(net "RST_PEX2_PERST_R_N")
	)
	(segment
		(start 329.6666 -260.6294)
		(end 330.3778 -260.6294)
		(width 0.15494)
		(layer "In7.Cu")
		(net "RST_PEX2_PERST_R_N")
	)
	(segment
		(start 318.135 -257.629152)
		(end 326.666352 -257.629152)
		(width 0.15494)
		(layer "In7.Cu")
		(net "RST_PEX2_PERST_R_N")
	)
	(segment
		(start 329.0824 -226.429062)
		(end 329.0824 -221.9706)
		(width 0.15494)
		(layer "In7.Cu")
		(net "RST_PEX2_PERST_R_N")
	)
	(segment
		(start 328.803 -229.150926)
		(end 328.803 -226.708462)
		(width 0.15494)
		(layer "In7.Cu")
		(net "RST_PEX2_PERST_R_N")
	)
	(segment
		(start 329.6158 -236.0422)
		(end 329.6158 -235.3056)
		(width 0.15494)
		(layer "In7.Cu")
		(net "RST_PEX2_PERST_R_N")
	)
	(segment
		(start 326.666352 -257.629152)
		(end 329.6666 -260.6294)
		(width 0.15494)
		(layer "In7.Cu")
		(net "RST_PEX2_PERST_R_N")
	)
	(segment
		(start 328.0664 -243.111528)
		(end 328.0664 -237.5916)
		(width 0.15494)
		(layer "In7.Cu")
		(net "RST_PEX2_PERST_R_N")
	)
	(segment
		(start 329.6158 -235.3056)
		(end 329.21829 -234.90809)
		(width 0.15494)
		(layer "In7.Cu")
		(net "RST_PEX2_PERST_R_N")
	)
	(segment
		(start 328.803 -226.708462)
		(end 329.0824 -226.429062)
		(width 0.15494)
		(layer "In7.Cu")
		(net "RST_PEX2_PERST_R_N")
	)
	(segment
		(start 329.0824 -221.9706)
		(end 328.549 -221.4372)
		(width 0.15494)
		(layer "In7.Cu")
		(net "RST_PEX2_PERST_R_N")
	)
	(segment
		(start 327.3044 -230.649526)
		(end 328.803 -229.150926)
		(width 0.15494)
		(layer "In7.Cu")
		(net "RST_PEX2_PERST_R_N")
	)
	(segment
		(start 328.554588 -243.599716)
		(end 328.0664 -243.111528)
		(width 0.15494)
		(layer "In7.Cu")
		(net "RST_PEX2_PERST_R_N")
	)
	(segment
		(start 328.131932 -245.020846)
		(end 328.554588 -244.59819)
		(width 0.15494)
		(layer "In7.Cu")
		(net "RST_PEX2_PERST_R_N")
	)
	(segment
		(start 329.21829 -234.90809)
		(end 327.87209 -234.90809)
		(width 0.15494)
		(layer "In7.Cu")
		(net "RST_PEX2_PERST_R_N")
	)
	(segment
		(start 258.913884 -191.654684)
		(end 258.94538 -191.654684)
		(width 0.13208)
		(layer "F.Cu")
		(net "JTAG_CONN_TCK")
	)
	(segment
		(start 258.906264 -190.89751)
		(end 258.57581 -190.89751)
		(width 0.13208)
		(layer "F.Cu")
		(net "JTAG_CONN_TCK")
	)
	(segment
		(start 258.57581 -190.89751)
		(end 258.57581 -191.31661)
		(width 0.13208)
		(layer "F.Cu")
		(net "JTAG_CONN_TCK")
	)
	(segment
		(start 261.78129 -191.654684)
		(end 259.663438 -191.654684)
		(width 0.13208)
		(layer "F.Cu")
		(net "JTAG_CONN_TCK")
	)
	(segment
		(start 259.663438 -191.654684)
		(end 258.906264 -190.89751)
		(width 0.13208)
		(layer "F.Cu")
		(net "JTAG_CONN_TCK")
	)
	(segment
		(start 258.57581 -191.31661)
		(end 258.913884 -191.654684)
		(width 0.13208)
		(layer "F.Cu")
		(net "JTAG_CONN_TCK")
	)
	(via
		(at 258.57581 -190.89751)
		(size 0.508)
		(drill 0.254)
		(layers "F.Cu" "B.Cu")
		(net "JTAG_CONN_TCK")
	)
	(segment
		(start 28.9052 -33.932622)
		(end 28.856178 -33.8836)
		(width 0.13208)
		(layer "F.Cu")
		(net "SSD1_AUX_P3V3_EN_R")
	)
	(segment
		(start 28.856178 -34.417)
		(end 28.9052 -34.367978)
		(width 0.13208)
		(layer "F.Cu")
		(net "SSD1_AUX_P3V3_EN_R")
	)
	(segment
		(start 26.58999 -37.529516)
		(end 27.126184 -37.529516)
		(width 0.13208)
		(layer "F.Cu")
		(net "SSD1_AUX_P3V3_EN_R")
	)
	(segment
		(start 30.715204 -59.100974)
		(end 31.740094 -58.076084)
		(width 0.13208)
		(layer "F.Cu")
		(net "SSD1_AUX_P3V3_EN_R")
	)
	(segment
		(start 26.277824 -37.84092)
		(end 26.58999 -37.529516)
		(width 0.13208)
		(layer "F.Cu")
		(net "SSD1_AUX_P3V3_EN_R")
	)
	(segment
		(start 32.140906 -57.675272)
		(end 31.740094 -58.076084)
		(width 0.13208)
		(layer "F.Cu")
		(net "SSD1_AUX_P3V3_EN_R")
	)
	(segment
		(start 28.9052 -34.367978)
		(end 28.9052 -33.932622)
		(width 0.13208)
		(layer "F.Cu")
		(net "SSD1_AUX_P3V3_EN_R")
	)
	(segment
		(start 30.715204 -59.146186)
		(end 30.715204 -59.100974)
		(width 0.13208)
		(layer "F.Cu")
		(net "SSD1_AUX_P3V3_EN_R")
	)
	(segment
		(start 32.140906 -57.16397)
		(end 32.140906 -57.675272)
		(width 0.13208)
		(layer "F.Cu")
		(net "SSD1_AUX_P3V3_EN_R")
	)
	(segment
		(start 28.856178 -36.874958)
		(end 28.856178 -34.417)
		(width 0.13208)
		(layer "F.Cu")
		(net "SSD1_AUX_P3V3_EN_R")
	)
	(segment
		(start 27.126184 -37.529516)
		(end 28.202636 -37.529516)
		(width 0.13208)
		(layer "F.Cu")
		(net "SSD1_AUX_P3V3_EN_R")
	)
	(segment
		(start 26.277824 -39.97198)
		(end 26.277824 -37.84092)
		(width 0.13208)
		(layer "F.Cu")
		(net "SSD1_AUX_P3V3_EN_R")
	)
	(segment
		(start 28.202636 -37.529516)
		(end 28.856178 -36.874958)
		(width 0.13208)
		(layer "F.Cu")
		(net "SSD1_AUX_P3V3_EN_R")
	)
	(segment
		(start 28.856178 -33.8836)
		(end 28.856178 -33.248092)
		(width 0.13208)
		(layer "F.Cu")
		(net "SSD1_AUX_P3V3_EN_R")
	)
	(via
		(at 26.277824 -39.97198)
		(size 0.508)
		(drill 0.254)
		(layers "F.Cu" "B.Cu")
		(net "SSD1_AUX_P3V3_EN_R")
	)
	(via
		(at 31.740094 -58.076084)
		(size 0.508)
		(drill 0.254)
		(layers "F.Cu" "B.Cu")
		(net "SSD1_AUX_P3V3_EN_R")
	)
	(segment
		(start 35.251898 -47.393098)
		(end 27.83078 -39.97198)
		(width 0.15494)
		(layer "In5.Cu")
		(net "SSD1_AUX_P3V3_EN_R")
	)
	(segment
		(start 31.740094 -58.076084)
		(end 35.251898 -54.56428)
		(width 0.15494)
		(layer "In5.Cu")
		(net "SSD1_AUX_P3V3_EN_R")
	)
	(segment
		(start 35.251898 -54.56428)
		(end 35.251898 -47.393098)
		(width 0.15494)
		(layer "In5.Cu")
		(net "SSD1_AUX_P3V3_EN_R")
	)
	(segment
		(start 27.83078 -39.97198)
		(end 26.277824 -39.97198)
		(width 0.15494)
		(layer "In5.Cu")
		(net "SSD1_AUX_P3V3_EN_R")
	)
	(segment
		(start 258.486656 -197.891654)
		(end 258.486656 -197.494398)
		(width 0.13208)
		(layer "F.Cu")
		(net "JTAG_CONN_TMS")
	)
	(segment
		(start 259.81406 -197.557136)
		(end 259.475732 -197.895464)
		(width 0.13208)
		(layer "F.Cu")
		(net "JTAG_CONN_TMS")
	)
	(segment
		(start 258.883658 -197.097396)
		(end 258.94538 -197.097396)
		(width 0.13208)
		(layer "F.Cu")
		(net "JTAG_CONN_TMS")
	)
	(segment
		(start 258.486656 -197.494398)
		(end 258.883658 -197.097396)
		(width 0.13208)
		(layer "F.Cu")
		(net "JTAG_CONN_TMS")
	)
	(segment
		(start 261.78129 -196.734684)
		(end 260.176772 -196.734684)
		(width 0.13208)
		(layer "F.Cu")
		(net "JTAG_CONN_TMS")
	)
	(segment
		(start 259.475732 -197.895464)
		(end 258.490466 -197.895464)
		(width 0.13208)
		(layer "F.Cu")
		(net "JTAG_CONN_TMS")
	)
	(segment
		(start 260.176772 -196.734684)
		(end 259.81406 -197.097396)
		(width 0.13208)
		(layer "F.Cu")
		(net "JTAG_CONN_TMS")
	)
	(segment
		(start 258.490466 -197.895464)
		(end 258.486656 -197.891654)
		(width 0.13208)
		(layer "F.Cu")
		(net "JTAG_CONN_TMS")
	)
	(segment
		(start 259.81406 -197.097396)
		(end 259.81406 -197.557136)
		(width 0.13208)
		(layer "F.Cu")
		(net "JTAG_CONN_TMS")
	)
	(via
		(at 258.486656 -197.891654)
		(size 0.508)
		(drill 0.254)
		(layers "F.Cu" "B.Cu")
		(net "JTAG_CONN_TMS")
	)
	(segment
		(start 202.893168 -291.238686)
		(end 202.47864 -291.238686)
		(width 0.13208)
		(layer "F.Cu")
		(net "RST_PEX1_PERST_R_N")
	)
	(segment
		(start 203.431902 -291.10813)
		(end 203.437998 -291.102034)
		(width 0.13208)
		(layer "F.Cu")
		(net "RST_PEX1_PERST_R_N")
	)
	(segment
		(start 203.018898 -294.9956)
		(end 202.434698 -294.9956)
		(width 0.13208)
		(layer "F.Cu")
		(net "RST_PEX1_PERST_R_N")
	)
	(segment
		(start 203.018898 -295.275)
		(end 203.431902 -295.688004)
		(width 0.13208)
		(layer "F.Cu")
		(net "RST_PEX1_PERST_R_N")
	)
	(segment
		(start 203.437998 -291.102034)
		(end 203.02982 -291.102034)
		(width 0.13208)
		(layer "F.Cu")
		(net "RST_PEX1_PERST_R_N")
	)
	(segment
		(start 202.129898 -292.925246)
		(end 202.131676 -292.923468)
		(width 0.13208)
		(layer "F.Cu")
		(net "RST_PEX1_PERST_R_N")
	)
	(segment
		(start 203.431902 -292.923468)
		(end 203.431902 -291.10813)
		(width 0.13208)
		(layer "F.Cu")
		(net "RST_PEX1_PERST_R_N")
	)
	(segment
		(start 326.593708 -222.956882)
		(end 326.466708 -222.829882)
		(width 0.13208)
		(layer "F.Cu")
		(net "RST_PEX1_PERST_R_N")
	)
	(segment
		(start 202.129898 -294.6908)
		(end 202.129898 -292.925246)
		(width 0.13208)
		(layer "F.Cu")
		(net "RST_PEX1_PERST_R_N")
	)
	(segment
		(start 202.434698 -294.9956)
		(end 202.129898 -294.6908)
		(width 0.13208)
		(layer "F.Cu")
		(net "RST_PEX1_PERST_R_N")
	)
	(segment
		(start 203.018898 -294.9956)
		(end 203.018898 -295.275)
		(width 0.13208)
		(layer "F.Cu")
		(net "RST_PEX1_PERST_R_N")
	)
	(segment
		(start 203.431902 -295.688004)
		(end 203.431902 -296.623232)
		(width 0.13208)
		(layer "F.Cu")
		(net "RST_PEX1_PERST_R_N")
	)
	(segment
		(start 203.247498 -294.9956)
		(end 203.018898 -294.9956)
		(width 0.13208)
		(layer "F.Cu")
		(net "RST_PEX1_PERST_R_N")
	)
	(segment
		(start 327.13168 -222.956882)
		(end 326.593708 -222.956882)
		(width 0.13208)
		(layer "F.Cu")
		(net "RST_PEX1_PERST_R_N")
	)
	(segment
		(start 203.02982 -291.102034)
		(end 202.893168 -291.238686)
		(width 0.13208)
		(layer "F.Cu")
		(net "RST_PEX1_PERST_R_N")
	)
	(segment
		(start 203.431902 -292.923468)
		(end 203.431902 -294.811196)
		(width 0.13208)
		(layer "F.Cu")
		(net "RST_PEX1_PERST_R_N")
	)
	(segment
		(start 203.431902 -294.811196)
		(end 203.247498 -294.9956)
		(width 0.13208)
		(layer "F.Cu")
		(net "RST_PEX1_PERST_R_N")
	)
	(via
		(at 206.502 -204.47)
		(size 0.508)
		(drill 0.254)
		(layers "F.Cu" "B.Cu")
		(net "RST_PEX1_PERST_R_N")
	)
	(via
		(at 326.466708 -222.829882)
		(size 0.508)
		(drill 0.254)
		(layers "F.Cu" "B.Cu")
		(net "RST_PEX1_PERST_R_N")
	)
	(via
		(at 202.47864 -291.238686)
		(size 0.508)
		(drill 0.254)
		(layers "F.Cu" "B.Cu")
		(net "RST_PEX1_PERST_R_N")
	)
	(segment
		(start 200.60158 -217.615262)
		(end 200.60158 -226.025964)
		(width 0.13208)
		(layer "B.Cu")
		(net "RST_PEX1_PERST_R_N")
	)
	(segment
		(start 202.818492 -290.898834)
		(end 202.47864 -291.238686)
		(width 0.13208)
		(layer "B.Cu")
		(net "RST_PEX1_PERST_R_N")
	)
	(segment
		(start 196.488304 -259.102606)
		(end 196.488304 -268.576044)
		(width 0.13208)
		(layer "B.Cu")
		(net "RST_PEX1_PERST_R_N")
	)
	(segment
		(start 198.406258 -257.184652)
		(end 196.488304 -259.102606)
		(width 0.13208)
		(layer "B.Cu")
		(net "RST_PEX1_PERST_R_N")
	)
	(segment
		(start 200.223374 -272.311114)
		(end 200.223374 -273.62531)
		(width 0.13208)
		(layer "B.Cu")
		(net "RST_PEX1_PERST_R_N")
	)
	(segment
		(start 196.77634 -251.17171)
		(end 201.021696 -255.417066)
		(width 0.13208)
		(layer "B.Cu")
		(net "RST_PEX1_PERST_R_N")
	)
	(segment
		(start 200.61428 -217.602562)
		(end 200.60158 -217.615262)
		(width 0.13208)
		(layer "B.Cu")
		(net "RST_PEX1_PERST_R_N")
	)
	(segment
		(start 200.223374 -273.62531)
		(end 202.818492 -276.220428)
		(width 0.13208)
		(layer "B.Cu")
		(net "RST_PEX1_PERST_R_N")
	)
	(segment
		(start 196.77634 -229.851204)
		(end 196.77634 -251.17171)
		(width 0.13208)
		(layer "B.Cu")
		(net "RST_PEX1_PERST_R_N")
	)
	(segment
		(start 199.557132 -257.184652)
		(end 198.406258 -257.184652)
		(width 0.13208)
		(layer "B.Cu")
		(net "RST_PEX1_PERST_R_N")
	)
	(segment
		(start 201.021696 -255.720088)
		(end 199.557132 -257.184652)
		(width 0.13208)
		(layer "B.Cu")
		(net "RST_PEX1_PERST_R_N")
	)
	(segment
		(start 205.359 -207.01)
		(end 200.61428 -211.75472)
		(width 0.13208)
		(layer "B.Cu")
		(net "RST_PEX1_PERST_R_N")
	)
	(segment
		(start 200.61428 -211.75472)
		(end 200.61428 -217.602562)
		(width 0.13208)
		(layer "B.Cu")
		(net "RST_PEX1_PERST_R_N")
	)
	(segment
		(start 202.818492 -276.220428)
		(end 202.818492 -290.898834)
		(width 0.13208)
		(layer "B.Cu")
		(net "RST_PEX1_PERST_R_N")
	)
	(segment
		(start 196.488304 -268.576044)
		(end 200.223374 -272.311114)
		(width 0.13208)
		(layer "B.Cu")
		(net "RST_PEX1_PERST_R_N")
	)
	(segment
		(start 201.021696 -255.417066)
		(end 201.021696 -255.720088)
		(width 0.13208)
		(layer "B.Cu")
		(net "RST_PEX1_PERST_R_N")
	)
	(segment
		(start 200.60158 -226.025964)
		(end 196.77634 -229.851204)
		(width 0.13208)
		(layer "B.Cu")
		(net "RST_PEX1_PERST_R_N")
	)
	(segment
		(start 205.359 -205.613)
		(end 205.359 -207.01)
		(width 0.13208)
		(layer "B.Cu")
		(net "RST_PEX1_PERST_R_N")
	)
	(segment
		(start 206.502 -204.47)
		(end 205.359 -205.613)
		(width 0.13208)
		(layer "B.Cu")
		(net "RST_PEX1_PERST_R_N")
	)
	(segment
		(start 272.72488 -218.03868)
		(end 272.72488 -213.31428)
		(width 0.15494)
		(layer "In13.Cu")
		(net "RST_PEX1_PERST_R_N")
	)
	(segment
		(start 274.740116 -220.053916)
		(end 272.72488 -218.03868)
		(width 0.15494)
		(layer "In13.Cu")
		(net "RST_PEX1_PERST_R_N")
	)
	(segment
		(start 208.534 -204.47)
		(end 206.502 -204.47)
		(width 0.15494)
		(layer "In13.Cu")
		(net "RST_PEX1_PERST_R_N")
	)
	(segment
		(start 295.717214 -221.04096)
		(end 294.73017 -220.053916)
		(width 0.15494)
		(layer "In13.Cu")
		(net "RST_PEX1_PERST_R_N")
	)
	(segment
		(start 325.72833 -221.570804)
		(end 322.55079 -221.570804)
		(width 0.15494)
		(layer "In13.Cu")
		(net "RST_PEX1_PERST_R_N")
	)
	(segment
		(start 263.2202 -209.6008)
		(end 262.255 -210.566)
		(width 0.15494)
		(layer "In13.Cu")
		(net "RST_PEX1_PERST_R_N")
	)
	(segment
		(start 269.011146 -209.600546)
		(end 268.630654 -209.600546)
		(width 0.15494)
		(layer "In13.Cu")
		(net "RST_PEX1_PERST_R_N")
	)
	(segment
		(start 209.06613 -203.93787)
		(end 208.534 -204.47)
		(width 0.15494)
		(layer "In13.Cu")
		(net "RST_PEX1_PERST_R_N")
	)
	(segment
		(start 322.55079 -221.570804)
		(end 322.166234 -221.186248)
		(width 0.15494)
		(layer "In13.Cu")
		(net "RST_PEX1_PERST_R_N")
	)
	(segment
		(start 211.455 -203.93787)
		(end 209.06613 -203.93787)
		(width 0.15494)
		(layer "In13.Cu")
		(net "RST_PEX1_PERST_R_N")
	)
	(segment
		(start 236.199426 -200.950322)
		(end 230.722678 -200.950322)
		(width 0.15494)
		(layer "In13.Cu")
		(net "RST_PEX1_PERST_R_N")
	)
	(segment
		(start 217.954352 -203.68387)
		(end 217.041222 -204.597)
		(width 0.15494)
		(layer "In13.Cu")
		(net "RST_PEX1_PERST_R_N")
	)
	(segment
		(start 230.0224 -201.6506)
		(end 230.0224 -203.327254)
		(width 0.15494)
		(layer "In13.Cu")
		(net "RST_PEX1_PERST_R_N")
	)
	(segment
		(start 322.166234 -221.186248)
		(end 295.86936 -221.186248)
		(width 0.15494)
		(layer "In13.Cu")
		(net "RST_PEX1_PERST_R_N")
	)
	(segment
		(start 230.0224 -203.327254)
		(end 229.403656 -203.945998)
		(width 0.15494)
		(layer "In13.Cu")
		(net "RST_PEX1_PERST_R_N")
	)
	(segment
		(start 241.2746 -199.1868)
		(end 237.962948 -199.1868)
		(width 0.15494)
		(layer "In13.Cu")
		(net "RST_PEX1_PERST_R_N")
	)
	(segment
		(start 212.11413 -204.597)
		(end 211.455 -203.93787)
		(width 0.15494)
		(layer "In13.Cu")
		(net "RST_PEX1_PERST_R_N")
	)
	(segment
		(start 246.972074 -202.801474)
		(end 245.082822 -200.912222)
		(width 0.15494)
		(layer "In13.Cu")
		(net "RST_PEX1_PERST_R_N")
	)
	(segment
		(start 258.741926 -209.268822)
		(end 256.43586 -206.962756)
		(width 0.15494)
		(layer "In13.Cu")
		(net "RST_PEX1_PERST_R_N")
	)
	(segment
		(start 256.43586 -206.962756)
		(end 256.43586 -206.19974)
		(width 0.15494)
		(layer "In13.Cu")
		(net "RST_PEX1_PERST_R_N")
	)
	(segment
		(start 237.962948 -199.1868)
		(end 236.199426 -200.950322)
		(width 0.15494)
		(layer "In13.Cu")
		(net "RST_PEX1_PERST_R_N")
	)
	(segment
		(start 256.43586 -206.19974)
		(end 253.037594 -202.801474)
		(width 0.15494)
		(layer "In13.Cu")
		(net "RST_PEX1_PERST_R_N")
	)
	(segment
		(start 253.037594 -202.801474)
		(end 246.972074 -202.801474)
		(width 0.15494)
		(layer "In13.Cu")
		(net "RST_PEX1_PERST_R_N")
	)
	(segment
		(start 260.736334 -210.566)
		(end 259.439156 -209.268822)
		(width 0.15494)
		(layer "In13.Cu")
		(net "RST_PEX1_PERST_R_N")
	)
	(segment
		(start 326.466708 -222.309182)
		(end 325.72833 -221.570804)
		(width 0.15494)
		(layer "In13.Cu")
		(net "RST_PEX1_PERST_R_N")
	)
	(segment
		(start 241.9858 -199.898)
		(end 241.2746 -199.1868)
		(width 0.15494)
		(layer "In13.Cu")
		(net "RST_PEX1_PERST_R_N")
	)
	(segment
		(start 268.630654 -209.600546)
		(end 268.6304 -209.6008)
		(width 0.15494)
		(layer "In13.Cu")
		(net "RST_PEX1_PERST_R_N")
	)
	(segment
		(start 259.439156 -209.268822)
		(end 258.741926 -209.268822)
		(width 0.15494)
		(layer "In13.Cu")
		(net "RST_PEX1_PERST_R_N")
	)
	(segment
		(start 295.724072 -221.04096)
		(end 295.717214 -221.04096)
		(width 0.15494)
		(layer "In13.Cu")
		(net "RST_PEX1_PERST_R_N")
	)
	(segment
		(start 229.403656 -203.945998)
		(end 220.633798 -203.945998)
		(width 0.15494)
		(layer "In13.Cu")
		(net "RST_PEX1_PERST_R_N")
	)
	(segment
		(start 242.186968 -200.912222)
		(end 241.9858 -200.711054)
		(width 0.15494)
		(layer "In13.Cu")
		(net "RST_PEX1_PERST_R_N")
	)
	(segment
		(start 241.9858 -200.711054)
		(end 241.9858 -199.898)
		(width 0.15494)
		(layer "In13.Cu")
		(net "RST_PEX1_PERST_R_N")
	)
	(segment
		(start 245.082822 -200.912222)
		(end 242.186968 -200.912222)
		(width 0.15494)
		(layer "In13.Cu")
		(net "RST_PEX1_PERST_R_N")
	)
	(segment
		(start 220.633798 -203.945998)
		(end 220.37167 -203.68387)
		(width 0.15494)
		(layer "In13.Cu")
		(net "RST_PEX1_PERST_R_N")
	)
	(segment
		(start 295.86936 -221.186248)
		(end 295.724072 -221.04096)
		(width 0.15494)
		(layer "In13.Cu")
		(net "RST_PEX1_PERST_R_N")
	)
	(segment
		(start 268.6304 -209.6008)
		(end 263.2202 -209.6008)
		(width 0.15494)
		(layer "In13.Cu")
		(net "RST_PEX1_PERST_R_N")
	)
	(segment
		(start 294.73017 -220.053916)
		(end 274.740116 -220.053916)
		(width 0.15494)
		(layer "In13.Cu")
		(net "RST_PEX1_PERST_R_N")
	)
	(segment
		(start 262.255 -210.566)
		(end 260.736334 -210.566)
		(width 0.15494)
		(layer "In13.Cu")
		(net "RST_PEX1_PERST_R_N")
	)
	(segment
		(start 326.466708 -222.829882)
		(end 326.466708 -222.309182)
		(width 0.15494)
		(layer "In13.Cu")
		(net "RST_PEX1_PERST_R_N")
	)
	(segment
		(start 217.041222 -204.597)
		(end 212.11413 -204.597)
		(width 0.15494)
		(layer "In13.Cu")
		(net "RST_PEX1_PERST_R_N")
	)
	(segment
		(start 272.72488 -213.31428)
		(end 269.011146 -209.600546)
		(width 0.15494)
		(layer "In13.Cu")
		(net "RST_PEX1_PERST_R_N")
	)
	(segment
		(start 230.722678 -200.950322)
		(end 230.0224 -201.6506)
		(width 0.15494)
		(layer "In13.Cu")
		(net "RST_PEX1_PERST_R_N")
	)
	(segment
		(start 220.37167 -203.68387)
		(end 217.954352 -203.68387)
		(width 0.15494)
		(layer "In13.Cu")
		(net "RST_PEX1_PERST_R_N")
	)
	(segment
		(start 208.315052 -188.595508)
		(end 208.226152 -188.506608)
		(width 0.13208)
		(layer "F.Cu")
		(net "SMB_IO_DEBUG_CARD_R_SCL")
	)
	(segment
		(start 340.161372 -197.52945)
		(end 339.229192 -196.59727)
		(width 0.13208)
		(layer "F.Cu")
		(net "SMB_IO_DEBUG_CARD_R_SCL")
	)
	(segment
		(start 337.994498 -196.59727)
		(end 337.341718 -195.94449)
		(width 0.13208)
		(layer "F.Cu")
		(net "SMB_IO_DEBUG_CARD_R_SCL")
	)
	(segment
		(start 208.226152 -188.506608)
		(end 208.226152 -187.867036)
		(width 0.13208)
		(layer "F.Cu")
		(net "SMB_IO_DEBUG_CARD_R_SCL")
	)
	(segment
		(start 337.341718 -195.94449)
		(end 335.604612 -195.94449)
		(width 0.13208)
		(layer "F.Cu")
		(net "SMB_IO_DEBUG_CARD_R_SCL")
	)
	(segment
		(start 341.687404 -197.52945)
		(end 340.161372 -197.52945)
		(width 0.13208)
		(layer "F.Cu")
		(net "SMB_IO_DEBUG_CARD_R_SCL")
	)
	(segment
		(start 339.229192 -196.59727)
		(end 337.994498 -196.59727)
		(width 0.13208)
		(layer "F.Cu")
		(net "SMB_IO_DEBUG_CARD_R_SCL")
	)
	(via
		(at 341.687404 -197.52945)
		(size 0.508)
		(drill 0.254)
		(layers "F.Cu" "B.Cu")
		(net "SMB_IO_DEBUG_CARD_R_SCL")
	)
	(via
		(at 208.226152 -187.867036)
		(size 0.508)
		(drill 0.254)
		(layers "F.Cu" "B.Cu")
		(net "SMB_IO_DEBUG_CARD_R_SCL")
	)
	(segment
		(start 254.846074 -188.551312)
		(end 251.993908 -191.403478)
		(width 0.15494)
		(layer "In15.Cu")
		(net "SMB_IO_DEBUG_CARD_R_SCL")
	)
	(segment
		(start 327.03516 -191.423798)
		(end 325.70293 -191.423798)
		(width 0.15494)
		(layer "In15.Cu")
		(net "SMB_IO_DEBUG_CARD_R_SCL")
	)
	(segment
		(start 272.309844 -188.551312)
		(end 254.846074 -188.551312)
		(width 0.15494)
		(layer "In15.Cu")
		(net "SMB_IO_DEBUG_CARD_R_SCL")
	)
	(segment
		(start 209.696304 -186.772296)
		(end 208.601564 -187.867036)
		(width 0.15494)
		(layer "In15.Cu")
		(net "SMB_IO_DEBUG_CARD_R_SCL")
	)
	(segment
		(start 251.993908 -191.403478)
		(end 240.93678 -191.403478)
		(width 0.15494)
		(layer "In15.Cu")
		(net "SMB_IO_DEBUG_CARD_R_SCL")
	)
	(segment
		(start 325.70293 -191.423798)
		(end 325.085964 -190.806832)
		(width 0.15494)
		(layer "In15.Cu")
		(net "SMB_IO_DEBUG_CARD_R_SCL")
	)
	(segment
		(start 325.085964 -190.806832)
		(end 274.565364 -190.806832)
		(width 0.15494)
		(layer "In15.Cu")
		(net "SMB_IO_DEBUG_CARD_R_SCL")
	)
	(segment
		(start 339.26526 -195.107306)
		(end 330.718668 -195.107306)
		(width 0.15494)
		(layer "In15.Cu")
		(net "SMB_IO_DEBUG_CARD_R_SCL")
	)
	(segment
		(start 341.687404 -197.52945)
		(end 339.26526 -195.107306)
		(width 0.15494)
		(layer "In15.Cu")
		(net "SMB_IO_DEBUG_CARD_R_SCL")
	)
	(segment
		(start 208.601564 -187.867036)
		(end 208.226152 -187.867036)
		(width 0.15494)
		(layer "In15.Cu")
		(net "SMB_IO_DEBUG_CARD_R_SCL")
	)
	(segment
		(start 236.305598 -186.772296)
		(end 209.696304 -186.772296)
		(width 0.15494)
		(layer "In15.Cu")
		(net "SMB_IO_DEBUG_CARD_R_SCL")
	)
	(segment
		(start 240.93678 -191.403478)
		(end 236.305598 -186.772296)
		(width 0.15494)
		(layer "In15.Cu")
		(net "SMB_IO_DEBUG_CARD_R_SCL")
	)
	(segment
		(start 330.718668 -195.107306)
		(end 327.03516 -191.423798)
		(width 0.15494)
		(layer "In15.Cu")
		(net "SMB_IO_DEBUG_CARD_R_SCL")
	)
	(segment
		(start 274.565364 -190.806832)
		(end 272.309844 -188.551312)
		(width 0.15494)
		(layer "In15.Cu")
		(net "SMB_IO_DEBUG_CARD_R_SCL")
	)
	(segment
		(start 30.847792 -40.185086)
		(end 30.720792 -40.058086)
		(width 0.13208)
		(layer "F.Cu")
		(net "SSD1_AUX_P3V3_EN")
	)
	(segment
		(start 28.380182 -39.33571)
		(end 27.126184 -39.33571)
		(width 0.13208)
		(layer "F.Cu")
		(net "SSD1_AUX_P3V3_EN")
	)
	(segment
		(start 29.102558 -40.058086)
		(end 28.380182 -39.33571)
		(width 0.13208)
		(layer "F.Cu")
		(net "SSD1_AUX_P3V3_EN")
	)
	(segment
		(start 30.720792 -40.058086)
		(end 29.102558 -40.058086)
		(width 0.13208)
		(layer "F.Cu")
		(net "SSD1_AUX_P3V3_EN")
	)
	(segment
		(start 30.847792 -41.137332)
		(end 30.847792 -40.185086)
		(width 0.13208)
		(layer "F.Cu")
		(net "SSD1_AUX_P3V3_EN")
	)
	(segment
		(start 27.126184 -38.329616)
		(end 27.126184 -39.33571)
		(width 0.13208)
		(layer "F.Cu")
		(net "SSD1_AUX_P3V3_EN")
	)
	(via
		(at 28.380182 -39.33571)
		(size 0.762)
		(drill 0.381)
		(layers "F.Cu" "B.Cu")
		(net "SSD1_AUX_P3V3_EN")
	)
	(segment
		(start 351.975928 -260.795008)
		(end 351.975928 -261.488428)
		(width 0.13208)
		(layer "F.Cu")
		(net "NC_P0V8_PEX2_ISEN3")
	)
	(via
		(at 351.975928 -261.488428)
		(size 0.508)
		(drill 0.254)
		(layers "F.Cu" "B.Cu")
		(net "NC_P0V8_PEX2_ISEN3")
	)
	(via
		(at 352.584512 -260.909308)
		(size 0.6604)
		(drill 0.3302)
		(layers "F.Cu" "B.Cu")
		(net "NC_P0V8_PEX2_ISEN3")
	)
	(segment
		(start 352.584512 -260.909308)
		(end 352.555048 -260.909308)
		(width 0.13208)
		(layer "B.Cu")
		(net "NC_P0V8_PEX2_ISEN3")
	)
	(segment
		(start 353.842574 -260.909308)
		(end 352.584512 -260.909308)
		(width 0.13208)
		(layer "B.Cu")
		(net "NC_P0V8_PEX2_ISEN3")
	)
	(segment
		(start 352.555048 -260.909308)
		(end 351.975928 -261.488428)
		(width 0.13208)
		(layer "B.Cu")
		(net "NC_P0V8_PEX2_ISEN3")
	)
	(segment
		(start 233.867706 -218.30411)
		(end 234.267502 -217.904314)
		(width 0.13208)
		(layer "F.Cu")
		(net "BIC_ADCVREFN1")
	)
	(via
		(at 238.082582 -219.540328)
		(size 0.6604)
		(drill 0.3302)
		(layers "F.Cu" "B.Cu")
		(net "BIC_ADCVREFN1")
	)
	(via
		(at 234.267502 -217.904314)
		(size 0.4572)
		(drill 0.254)
		(layers "F.Cu" "B.Cu")
		(net "BIC_ADCVREFN1")
	)
	(segment
		(start 238.082582 -219.540328)
		(end 237.143798 -219.540328)
		(width 0.254)
		(layer "B.Cu")
		(net "BIC_ADCVREFN1")
	)
	(segment
		(start 239.2553 -219.639134)
		(end 239.209072 -219.685362)
		(width 0.254)
		(layer "B.Cu")
		(net "BIC_ADCVREFN1")
	)
	(segment
		(start 238.560102 -219.540328)
		(end 238.705136 -219.685362)
		(width 0.254)
		(layer "B.Cu")
		(net "BIC_ADCVREFN1")
	)
	(segment
		(start 237.143798 -219.540328)
		(end 236.17555 -218.57208)
		(width 0.254)
		(layer "B.Cu")
		(net "BIC_ADCVREFN1")
	)
	(segment
		(start 234.92841 -218.57208)
		(end 234.267502 -217.911172)
		(width 0.254)
		(layer "B.Cu")
		(net "BIC_ADCVREFN1")
	)
	(segment
		(start 236.17555 -218.57208)
		(end 234.92841 -218.57208)
		(width 0.254)
		(layer "B.Cu")
		(net "BIC_ADCVREFN1")
	)
	(segment
		(start 240.03762 -219.639134)
		(end 239.2553 -219.639134)
		(width 0.254)
		(layer "B.Cu")
		(net "BIC_ADCVREFN1")
	)
	(segment
		(start 238.082582 -219.540328)
		(end 238.560102 -219.540328)
		(width 0.254)
		(layer "B.Cu")
		(net "BIC_ADCVREFN1")
	)
	(segment
		(start 238.705136 -219.685362)
		(end 239.209072 -219.685362)
		(width 0.254)
		(layer "B.Cu")
		(net "BIC_ADCVREFN1")
	)
	(segment
		(start 234.267502 -217.911172)
		(end 234.267502 -217.904314)
		(width 0.254)
		(layer "B.Cu")
		(net "BIC_ADCVREFN1")
	)
	(segment
		(start 259.73659 -202.766168)
		(end 258.640326 -202.766168)
		(width 0.13208)
		(layer "F.Cu")
		(net "JTAG_CONN_TDI")
	)
	(segment
		(start 259.897372 -202.92695)
		(end 259.73659 -202.766168)
		(width 0.13208)
		(layer "F.Cu")
		(net "JTAG_CONN_TDI")
	)
	(segment
		(start 258.590034 -202.81646)
		(end 258.590034 -203.679806)
		(width 0.13208)
		(layer "F.Cu")
		(net "JTAG_CONN_TDI")
	)
	(segment
		(start 258.590034 -203.679806)
		(end 258.806188 -203.89596)
		(width 0.13208)
		(layer "F.Cu")
		(net "JTAG_CONN_TDI")
	)
	(segment
		(start 260.356096 -204.354684)
		(end 259.897372 -203.89596)
		(width 0.13208)
		(layer "F.Cu")
		(net "JTAG_CONN_TDI")
	)
	(segment
		(start 258.640326 -202.766168)
		(end 258.590034 -202.81646)
		(width 0.13208)
		(layer "F.Cu")
		(net "JTAG_CONN_TDI")
	)
	(segment
		(start 261.78129 -204.354684)
		(end 260.356096 -204.354684)
		(width 0.13208)
		(layer "F.Cu")
		(net "JTAG_CONN_TDI")
	)
	(segment
		(start 259.897372 -203.89596)
		(end 259.897372 -202.92695)
		(width 0.13208)
		(layer "F.Cu")
		(net "JTAG_CONN_TDI")
	)
	(via
		(at 258.590034 -202.81646)
		(size 0.508)
		(drill 0.254)
		(layers "F.Cu" "B.Cu")
		(net "JTAG_CONN_TDI")
	)
	(segment
		(start 30.291024 -37.774118)
		(end 31.846774 -37.774118)
		(width 0.13208)
		(layer "F.Cu")
		(net "PRSNT_SSD1_R1_N")
	)
	(segment
		(start 29.897832 -38.16731)
		(end 30.291024 -37.774118)
		(width 0.13208)
		(layer "F.Cu")
		(net "PRSNT_SSD1_R1_N")
	)
	(segment
		(start 32.393636 -37.774118)
		(end 32.575754 -37.592)
		(width 0.13208)
		(layer "F.Cu")
		(net "PRSNT_SSD1_R1_N")
	)
	(segment
		(start 31.846774 -37.774118)
		(end 32.393636 -37.774118)
		(width 0.13208)
		(layer "F.Cu")
		(net "PRSNT_SSD1_R1_N")
	)
	(segment
		(start 32.575754 -37.592)
		(end 32.575754 -37.315648)
		(width 0.13208)
		(layer "F.Cu")
		(net "PRSNT_SSD1_R1_N")
	)
	(segment
		(start 29.897832 -38.937184)
		(end 29.897832 -38.16731)
		(width 0.13208)
		(layer "F.Cu")
		(net "PRSNT_SSD1_R1_N")
	)
	(via
		(at 31.846774 -37.774118)
		(size 0.508)
		(drill 0.254)
		(layers "F.Cu" "B.Cu")
		(net "PRSNT_SSD1_R1_N")
	)
	(segment
		(start 86.031578 -292.923468)
		(end 86.0298 -292.925246)
		(width 0.13208)
		(layer "F.Cu")
		(net "RST_PEX0_PERST_R_N")
	)
	(segment
		(start 86.9188 -295.275)
		(end 87.331804 -295.688004)
		(width 0.13208)
		(layer "F.Cu")
		(net "RST_PEX0_PERST_R_N")
	)
	(segment
		(start 86.0298 -292.925246)
		(end 86.0298 -294.6908)
		(width 0.13208)
		(layer "F.Cu")
		(net "RST_PEX0_PERST_R_N")
	)
	(segment
		(start 87.331804 -295.688004)
		(end 87.331804 -296.623232)
		(width 0.13208)
		(layer "F.Cu")
		(net "RST_PEX0_PERST_R_N")
	)
	(segment
		(start 87.331804 -291.10813)
		(end 87.3379 -291.102034)
		(width 0.13208)
		(layer "F.Cu")
		(net "RST_PEX0_PERST_R_N")
	)
	(segment
		(start 87.331804 -294.811196)
		(end 87.331804 -292.923468)
		(width 0.13208)
		(layer "F.Cu")
		(net "RST_PEX0_PERST_R_N")
	)
	(segment
		(start 327.13168 -223.972882)
		(end 326.466708 -223.972882)
		(width 0.13208)
		(layer "F.Cu")
		(net "RST_PEX0_PERST_R_N")
	)
	(segment
		(start 87.3379 -291.102034)
		(end 86.849966 -291.102034)
		(width 0.13208)
		(layer "F.Cu")
		(net "RST_PEX0_PERST_R_N")
	)
	(segment
		(start 86.849966 -291.102034)
		(end 86.487 -291.465)
		(width 0.13208)
		(layer "F.Cu")
		(net "RST_PEX0_PERST_R_N")
	)
	(segment
		(start 87.1474 -294.9956)
		(end 87.331804 -294.811196)
		(width 0.13208)
		(layer "F.Cu")
		(net "RST_PEX0_PERST_R_N")
	)
	(segment
		(start 87.331804 -292.923468)
		(end 87.331804 -291.10813)
		(width 0.13208)
		(layer "F.Cu")
		(net "RST_PEX0_PERST_R_N")
	)
	(segment
		(start 86.0298 -294.6908)
		(end 86.3346 -294.9956)
		(width 0.13208)
		(layer "F.Cu")
		(net "RST_PEX0_PERST_R_N")
	)
	(segment
		(start 86.9188 -294.9956)
		(end 86.9188 -295.275)
		(width 0.13208)
		(layer "F.Cu")
		(net "RST_PEX0_PERST_R_N")
	)
	(segment
		(start 86.3346 -294.9956)
		(end 86.9188 -294.9956)
		(width 0.13208)
		(layer "F.Cu")
		(net "RST_PEX0_PERST_R_N")
	)
	(segment
		(start 86.9188 -294.9956)
		(end 87.1474 -294.9956)
		(width 0.13208)
		(layer "F.Cu")
		(net "RST_PEX0_PERST_R_N")
	)
	(via
		(at 86.487 -291.465)
		(size 0.508)
		(drill 0.254)
		(layers "F.Cu" "B.Cu")
		(net "RST_PEX0_PERST_R_N")
	)
	(via
		(at 91.958668 -206.952088)
		(size 0.508)
		(drill 0.254)
		(layers "F.Cu" "B.Cu")
		(net "RST_PEX0_PERST_R_N")
	)
	(via
		(at 93.157294 -237.3757)
		(size 0.508)
		(drill 0.254)
		(layers "F.Cu" "B.Cu")
		(net "RST_PEX0_PERST_R_N")
	)
	(via
		(at 326.466708 -223.972882)
		(size 0.508)
		(drill 0.254)
		(layers "F.Cu" "B.Cu")
		(net "RST_PEX0_PERST_R_N")
	)
	(segment
		(start 98.277426 -275.91766)
		(end 92.327222 -281.867864)
		(width 0.13208)
		(layer "B.Cu")
		(net "RST_PEX0_PERST_R_N")
	)
	(segment
		(start 93.055694 -237.3757)
		(end 90.83167 -239.599724)
		(width 0.13208)
		(layer "B.Cu")
		(net "RST_PEX0_PERST_R_N")
	)
	(segment
		(start 99.048062 -263.474454)
		(end 98.277426 -264.24509)
		(width 0.13208)
		(layer "B.Cu")
		(net "RST_PEX0_PERST_R_N")
	)
	(segment
		(start 93.157294 -237.3757)
		(end 93.055694 -237.3757)
		(width 0.13208)
		(layer "B.Cu")
		(net "RST_PEX0_PERST_R_N")
	)
	(segment
		(start 90.83167 -239.599724)
		(end 90.83167 -247.76811)
		(width 0.13208)
		(layer "B.Cu")
		(net "RST_PEX0_PERST_R_N")
	)
	(segment
		(start 95.941642 -252.878082)
		(end 97.28327 -252.878082)
		(width 0.13208)
		(layer "B.Cu")
		(net "RST_PEX0_PERST_R_N")
	)
	(segment
		(start 98.277426 -264.24509)
		(end 98.277426 -275.91766)
		(width 0.13208)
		(layer "B.Cu")
		(net "RST_PEX0_PERST_R_N")
	)
	(segment
		(start 97.28327 -252.878082)
		(end 99.048062 -254.642874)
		(width 0.13208)
		(layer "B.Cu")
		(net "RST_PEX0_PERST_R_N")
	)
	(segment
		(start 87.907368 -290.97986)
		(end 87.422228 -291.465)
		(width 0.13208)
		(layer "B.Cu")
		(net "RST_PEX0_PERST_R_N")
	)
	(segment
		(start 90.21064 -290.97986)
		(end 87.907368 -290.97986)
		(width 0.13208)
		(layer "B.Cu")
		(net "RST_PEX0_PERST_R_N")
	)
	(segment
		(start 92.327222 -288.863278)
		(end 90.21064 -290.97986)
		(width 0.13208)
		(layer "B.Cu")
		(net "RST_PEX0_PERST_R_N")
	)
	(segment
		(start 92.327222 -286.875728)
		(end 92.531946 -287.080452)
		(width 0.13208)
		(layer "B.Cu")
		(net "RST_PEX0_PERST_R_N")
	)
	(segment
		(start 92.531946 -287.080452)
		(end 92.531946 -287.473136)
		(width 0.13208)
		(layer "B.Cu")
		(net "RST_PEX0_PERST_R_N")
	)
	(segment
		(start 90.83167 -247.76811)
		(end 95.941642 -252.878082)
		(width 0.13208)
		(layer "B.Cu")
		(net "RST_PEX0_PERST_R_N")
	)
	(segment
		(start 99.048062 -254.642874)
		(end 99.048062 -263.474454)
		(width 0.13208)
		(layer "B.Cu")
		(net "RST_PEX0_PERST_R_N")
	)
	(segment
		(start 92.327222 -281.867864)
		(end 92.327222 -286.875728)
		(width 0.13208)
		(layer "B.Cu")
		(net "RST_PEX0_PERST_R_N")
	)
	(segment
		(start 92.531946 -287.473136)
		(end 92.327222 -287.67786)
		(width 0.13208)
		(layer "B.Cu")
		(net "RST_PEX0_PERST_R_N")
	)
	(segment
		(start 92.327222 -287.67786)
		(end 92.327222 -288.863278)
		(width 0.13208)
		(layer "B.Cu")
		(net "RST_PEX0_PERST_R_N")
	)
	(segment
		(start 87.422228 -291.465)
		(end 86.487 -291.465)
		(width 0.13208)
		(layer "B.Cu")
		(net "RST_PEX0_PERST_R_N")
	)
	(segment
		(start 91.958668 -206.952088)
		(end 91.958668 -236.177074)
		(width 0.15494)
		(layer "In5.Cu")
		(net "RST_PEX0_PERST_R_N")
	)
	(segment
		(start 91.958668 -236.177074)
		(end 93.157294 -237.3757)
		(width 0.15494)
		(layer "In5.Cu")
		(net "RST_PEX0_PERST_R_N")
	)
	(segment
		(start 216.912698 -205.375764)
		(end 210.963764 -205.375764)
		(width 0.15494)
		(layer "In13.Cu")
		(net "RST_PEX0_PERST_R_N")
	)
	(segment
		(start 220.036136 -204.1906)
		(end 218.097862 -204.1906)
		(width 0.15494)
		(layer "In13.Cu")
		(net "RST_PEX0_PERST_R_N")
	)
	(segment
		(start 241.8842 -204.089)
		(end 241.271044 -204.702156)
		(width 0.15494)
		(layer "In13.Cu")
		(net "RST_PEX0_PERST_R_N")
	)
	(segment
		(start 322.813934 -223.134428)
		(end 322.256912 -222.577406)
		(width 0.15494)
		(layer "In13.Cu")
		(net "RST_PEX0_PERST_R_N")
	)
	(segment
		(start 220.443298 -204.405738)
		(end 220.18117 -204.14361)
		(width 0.15494)
		(layer "In13.Cu")
		(net "RST_PEX0_PERST_R_N")
	)
	(segment
		(start 128.00076 -210.5406)
		(end 127.991616 -210.5406)
		(width 0.15494)
		(layer "In13.Cu")
		(net "RST_PEX0_PERST_R_N")
	)
	(segment
		(start 145.766282 -208.980024)
		(end 143.648176 -208.980024)
		(width 0.15494)
		(layer "In13.Cu")
		(net "RST_PEX0_PERST_R_N")
	)
	(segment
		(start 220.083126 -204.14361)
		(end 220.036136 -204.1906)
		(width 0.15494)
		(layer "In13.Cu")
		(net "RST_PEX0_PERST_R_N")
	)
	(segment
		(start 259.248656 -209.728562)
		(end 258.169664 -209.728562)
		(width 0.15494)
		(layer "In13.Cu")
		(net "RST_PEX0_PERST_R_N")
	)
	(segment
		(start 210.963764 -205.375764)
		(end 210.566 -204.978)
		(width 0.15494)
		(layer "In13.Cu")
		(net "RST_PEX0_PERST_R_N")
	)
	(segment
		(start 220.18117 -204.14361)
		(end 220.083126 -204.14361)
		(width 0.15494)
		(layer "In13.Cu")
		(net "RST_PEX0_PERST_R_N")
	)
	(segment
		(start 276.57679 -222.577406)
		(end 272.26514 -218.265756)
		(width 0.15494)
		(layer "In13.Cu")
		(net "RST_PEX0_PERST_R_N")
	)
	(segment
		(start 127.991616 -210.5406)
		(end 123.241816 -205.7908)
		(width 0.15494)
		(layer "In13.Cu")
		(net "RST_PEX0_PERST_R_N")
	)
	(segment
		(start 241.271044 -205.369922)
		(end 240.555272 -206.085694)
		(width 0.15494)
		(layer "In13.Cu")
		(net "RST_PEX0_PERST_R_N")
	)
	(segment
		(start 218.097862 -204.1906)
		(end 216.912698 -205.375764)
		(width 0.15494)
		(layer "In13.Cu")
		(net "RST_PEX0_PERST_R_N")
	)
	(segment
		(start 104.929432 -204.4446)
		(end 102.327456 -205.522322)
		(width 0.15494)
		(layer "In13.Cu")
		(net "RST_PEX0_PERST_R_N")
	)
	(segment
		(start 230.012494 -203.9874)
		(end 229.594156 -204.405738)
		(width 0.15494)
		(layer "In13.Cu")
		(net "RST_PEX0_PERST_R_N")
	)
	(segment
		(start 235.457492 -203.9874)
		(end 230.012494 -203.9874)
		(width 0.15494)
		(layer "In13.Cu")
		(net "RST_PEX0_PERST_R_N")
	)
	(segment
		(start 138.076686 -210.947)
		(end 136.675114 -210.947)
		(width 0.15494)
		(layer "In13.Cu")
		(net "RST_PEX0_PERST_R_N")
	)
	(segment
		(start 143.648176 -208.980024)
		(end 142.3924 -210.2358)
		(width 0.15494)
		(layer "In13.Cu")
		(net "RST_PEX0_PERST_R_N")
	)
	(segment
		(start 136.675114 -210.947)
		(end 136.271254 -210.54314)
		(width 0.15494)
		(layer "In13.Cu")
		(net "RST_PEX0_PERST_R_N")
	)
	(segment
		(start 138.787886 -210.2358)
		(end 138.076686 -210.947)
		(width 0.15494)
		(layer "In13.Cu")
		(net "RST_PEX0_PERST_R_N")
	)
	(segment
		(start 324.941946 -224.0788)
		(end 323.997574 -223.134428)
		(width 0.15494)
		(layer "In13.Cu")
		(net "RST_PEX0_PERST_R_N")
	)
	(segment
		(start 93.388434 -205.522322)
		(end 91.958668 -206.952088)
		(width 0.15494)
		(layer "In13.Cu")
		(net "RST_PEX0_PERST_R_N")
	)
	(segment
		(start 260.639814 -211.11972)
		(end 259.248656 -209.728562)
		(width 0.15494)
		(layer "In13.Cu")
		(net "RST_PEX0_PERST_R_N")
	)
	(segment
		(start 258.169664 -209.728562)
		(end 253.444502 -205.0034)
		(width 0.15494)
		(layer "In13.Cu")
		(net "RST_PEX0_PERST_R_N")
	)
	(segment
		(start 159.293814 -210.075272)
		(end 159.12846 -210.240626)
		(width 0.15494)
		(layer "In13.Cu")
		(net "RST_PEX0_PERST_R_N")
	)
	(segment
		(start 244.9322 -204.089)
		(end 241.8842 -204.089)
		(width 0.15494)
		(layer "In13.Cu")
		(net "RST_PEX0_PERST_R_N")
	)
	(segment
		(start 119.38 -205.7908)
		(end 118.0338 -204.4446)
		(width 0.15494)
		(layer "In13.Cu")
		(net "RST_PEX0_PERST_R_N")
	)
	(segment
		(start 118.0338 -204.4446)
		(end 104.929432 -204.4446)
		(width 0.15494)
		(layer "In13.Cu")
		(net "RST_PEX0_PERST_R_N")
	)
	(segment
		(start 326.04202 -224.0788)
		(end 324.941946 -224.0788)
		(width 0.15494)
		(layer "In13.Cu")
		(net "RST_PEX0_PERST_R_N")
	)
	(segment
		(start 229.594156 -204.405738)
		(end 220.443298 -204.405738)
		(width 0.15494)
		(layer "In13.Cu")
		(net "RST_PEX0_PERST_R_N")
	)
	(segment
		(start 240.555272 -206.085694)
		(end 238.149384 -206.085694)
		(width 0.15494)
		(layer "In13.Cu")
		(net "RST_PEX0_PERST_R_N")
	)
	(segment
		(start 159.300926 -210.075272)
		(end 159.293814 -210.075272)
		(width 0.15494)
		(layer "In13.Cu")
		(net "RST_PEX0_PERST_R_N")
	)
	(segment
		(start 326.466708 -223.972882)
		(end 326.147938 -223.972882)
		(width 0.15494)
		(layer "In13.Cu")
		(net "RST_PEX0_PERST_R_N")
	)
	(segment
		(start 268.8209 -210.06054)
		(end 263.598914 -210.06054)
		(width 0.15494)
		(layer "In13.Cu")
		(net "RST_PEX0_PERST_R_N")
	)
	(segment
		(start 142.3924 -210.2358)
		(end 138.787886 -210.2358)
		(width 0.15494)
		(layer "In13.Cu")
		(net "RST_PEX0_PERST_R_N")
	)
	(segment
		(start 262.539734 -211.11972)
		(end 260.639814 -211.11972)
		(width 0.15494)
		(layer "In13.Cu")
		(net "RST_PEX0_PERST_R_N")
	)
	(segment
		(start 326.147938 -223.972882)
		(end 326.04202 -224.0788)
		(width 0.15494)
		(layer "In13.Cu")
		(net "RST_PEX0_PERST_R_N")
	)
	(segment
		(start 238.149384 -206.085694)
		(end 237.13567 -205.665578)
		(width 0.15494)
		(layer "In13.Cu")
		(net "RST_PEX0_PERST_R_N")
	)
	(segment
		(start 128.0033 -210.54314)
		(end 128.00076 -210.5406)
		(width 0.15494)
		(layer "In13.Cu")
		(net "RST_PEX0_PERST_R_N")
	)
	(segment
		(start 241.271044 -204.702156)
		(end 241.271044 -205.369922)
		(width 0.15494)
		(layer "In13.Cu")
		(net "RST_PEX0_PERST_R_N")
	)
	(segment
		(start 263.598914 -210.06054)
		(end 262.539734 -211.11972)
		(width 0.15494)
		(layer "In13.Cu")
		(net "RST_PEX0_PERST_R_N")
	)
	(segment
		(start 159.12846 -210.240626)
		(end 147.026884 -210.240626)
		(width 0.15494)
		(layer "In13.Cu")
		(net "RST_PEX0_PERST_R_N")
	)
	(segment
		(start 102.327456 -205.522322)
		(end 93.388434 -205.522322)
		(width 0.15494)
		(layer "In13.Cu")
		(net "RST_PEX0_PERST_R_N")
	)
	(segment
		(start 322.256912 -222.577406)
		(end 276.57679 -222.577406)
		(width 0.15494)
		(layer "In13.Cu")
		(net "RST_PEX0_PERST_R_N")
	)
	(segment
		(start 245.8466 -205.0034)
		(end 244.9322 -204.089)
		(width 0.15494)
		(layer "In13.Cu")
		(net "RST_PEX0_PERST_R_N")
	)
	(segment
		(start 136.271254 -210.54314)
		(end 128.0033 -210.54314)
		(width 0.15494)
		(layer "In13.Cu")
		(net "RST_PEX0_PERST_R_N")
	)
	(segment
		(start 163.90874 -205.467458)
		(end 159.300926 -210.075272)
		(width 0.15494)
		(layer "In13.Cu")
		(net "RST_PEX0_PERST_R_N")
	)
	(segment
		(start 237.13567 -205.665578)
		(end 235.457492 -203.9874)
		(width 0.15494)
		(layer "In13.Cu")
		(net "RST_PEX0_PERST_R_N")
	)
	(segment
		(start 205.867 -204.978)
		(end 205.377542 -205.467458)
		(width 0.15494)
		(layer "In13.Cu")
		(net "RST_PEX0_PERST_R_N")
	)
	(segment
		(start 123.241816 -205.7908)
		(end 119.38 -205.7908)
		(width 0.15494)
		(layer "In13.Cu")
		(net "RST_PEX0_PERST_R_N")
	)
	(segment
		(start 205.377542 -205.467458)
		(end 163.90874 -205.467458)
		(width 0.15494)
		(layer "In13.Cu")
		(net "RST_PEX0_PERST_R_N")
	)
	(segment
		(start 272.26514 -213.50478)
		(end 268.8209 -210.06054)
		(width 0.15494)
		(layer "In13.Cu")
		(net "RST_PEX0_PERST_R_N")
	)
	(segment
		(start 210.566 -204.978)
		(end 205.867 -204.978)
		(width 0.15494)
		(layer "In13.Cu")
		(net "RST_PEX0_PERST_R_N")
	)
	(segment
		(start 323.997574 -223.134428)
		(end 322.813934 -223.134428)
		(width 0.15494)
		(layer "In13.Cu")
		(net "RST_PEX0_PERST_R_N")
	)
	(segment
		(start 272.26514 -218.265756)
		(end 272.26514 -213.50478)
		(width 0.15494)
		(layer "In13.Cu")
		(net "RST_PEX0_PERST_R_N")
	)
	(segment
		(start 147.026884 -210.240626)
		(end 145.766282 -208.980024)
		(width 0.15494)
		(layer "In13.Cu")
		(net "RST_PEX0_PERST_R_N")
	)
	(segment
		(start 253.444502 -205.0034)
		(end 245.8466 -205.0034)
		(width 0.15494)
		(layer "In13.Cu")
		(net "RST_PEX0_PERST_R_N")
	)
	(segment
		(start 337.89493 -190.837312)
		(end 336.687922 -192.04432)
		(width 0.13208)
		(layer "F.Cu")
		(net "RST_PLTRST_N")
	)
	(segment
		(start 339.335618 -190.41745)
		(end 338.945474 -190.807594)
		(width 0.13208)
		(layer "F.Cu")
		(net "RST_PLTRST_N")
	)
	(segment
		(start 336.687922 -192.04432)
		(end 335.604612 -192.04432)
		(width 0.13208)
		(layer "F.Cu")
		(net "RST_PLTRST_N")
	)
	(segment
		(start 340.161372 -190.41745)
		(end 339.335618 -190.41745)
		(width 0.13208)
		(layer "F.Cu")
		(net "RST_PLTRST_N")
	)
	(segment
		(start 337.924648 -190.807594)
		(end 337.89493 -190.837312)
		(width 0.13208)
		(layer "F.Cu")
		(net "RST_PLTRST_N")
	)
	(segment
		(start 338.945474 -190.807594)
		(end 337.924648 -190.807594)
		(width 0.13208)
		(layer "F.Cu")
		(net "RST_PLTRST_N")
	)
	(via
		(at 337.89493 -190.837312)
		(size 0.508)
		(drill 0.254)
		(layers "F.Cu" "B.Cu")
		(net "RST_PLTRST_N")
	)
	(segment
		(start 325.533766 -233.6292)
		(end 325.609966 -233.553)
		(width 0.13208)
		(layer "F.Cu")
		(net "RST_PEX_SYS_BUF_R_N")
	)
	(segment
		(start 325.042022 -233.6292)
		(end 325.533766 -233.6292)
		(width 0.13208)
		(layer "F.Cu")
		(net "RST_PEX_SYS_BUF_R_N")
	)
	(segment
		(start 325.042022 -234.624372)
		(end 325.042022 -233.6292)
		(width 0.13208)
		(layer "F.Cu")
		(net "RST_PEX_SYS_BUF_R_N")
	)
	(segment
		(start 324.991222 -234.675172)
		(end 325.042022 -234.624372)
		(width 0.13208)
		(layer "F.Cu")
		(net "RST_PEX_SYS_BUF_R_N")
	)
	(segment
		(start 324.991222 -234.675172)
		(end 323.975222 -234.675172)
		(width 0.13208)
		(layer "F.Cu")
		(net "RST_PEX_SYS_BUF_R_N")
	)
	(segment
		(start 326.007222 -234.675172)
		(end 324.991222 -234.675172)
		(width 0.13208)
		(layer "F.Cu")
		(net "RST_PEX_SYS_BUF_R_N")
	)
	(segment
		(start 325.609966 -233.553)
		(end 326.11695 -233.553)
		(width 0.13208)
		(layer "F.Cu")
		(net "RST_PEX_SYS_BUF_R_N")
	)
	(segment
		(start 323.975222 -234.675172)
		(end 322.959222 -234.675172)
		(width 0.13208)
		(layer "F.Cu")
		(net "RST_PEX_SYS_BUF_R_N")
	)
	(via
		(at 325.042022 -233.6292)
		(size 0.508)
		(drill 0.254)
		(layers "F.Cu" "B.Cu")
		(net "RST_PEX_SYS_BUF_R_N")
	)
	(segment
		(start 233.867706 -219.10421)
		(end 234.267502 -219.504006)
		(width 0.13208)
		(layer "F.Cu")
		(net "BIC_ADCVREFP1")
	)
	(via
		(at 236.51083 -219.880688)
		(size 0.6604)
		(drill 0.3302)
		(layers "F.Cu" "B.Cu")
		(net "BIC_ADCVREFP1")
	)
	(via
		(at 234.267502 -219.504006)
		(size 0.4572)
		(drill 0.254)
		(layers "F.Cu" "B.Cu")
		(net "BIC_ADCVREFP1")
	)
	(segment
		(start 234.793028 -218.97848)
		(end 234.267502 -219.504006)
		(width 0.254)
		(layer "B.Cu")
		(net "BIC_ADCVREFP1")
	)
	(segment
		(start 236.006894 -218.97848)
		(end 234.793028 -218.97848)
		(width 0.254)
		(layer "B.Cu")
		(net "BIC_ADCVREFP1")
	)
	(segment
		(start 236.51083 -219.482416)
		(end 236.006894 -218.97848)
		(width 0.254)
		(layer "B.Cu")
		(net "BIC_ADCVREFP1")
	)
	(segment
		(start 240.067338 -220.514672)
		(end 239.238282 -220.514672)
		(width 0.254)
		(layer "B.Cu")
		(net "BIC_ADCVREFP1")
	)
	(segment
		(start 236.51083 -219.880688)
		(end 236.81182 -220.181678)
		(width 0.254)
		(layer "B.Cu")
		(net "BIC_ADCVREFP1")
	)
	(segment
		(start 238.893096 -220.485462)
		(end 239.209072 -220.485462)
		(width 0.254)
		(layer "B.Cu")
		(net "BIC_ADCVREFP1")
	)
	(segment
		(start 236.81182 -220.181678)
		(end 238.589312 -220.181678)
		(width 0.254)
		(layer "B.Cu")
		(net "BIC_ADCVREFP1")
	)
	(segment
		(start 239.238282 -220.514672)
		(end 239.209072 -220.485462)
		(width 0.254)
		(layer "B.Cu")
		(net "BIC_ADCVREFP1")
	)
	(segment
		(start 236.51083 -219.880688)
		(end 236.51083 -219.482416)
		(width 0.254)
		(layer "B.Cu")
		(net "BIC_ADCVREFP1")
	)
	(segment
		(start 238.589312 -220.181678)
		(end 238.893096 -220.485462)
		(width 0.254)
		(layer "B.Cu")
		(net "BIC_ADCVREFP1")
	)
	(segment
		(start 259.225034 -206.272638)
		(end 258.56057 -206.272638)
		(width 0.13208)
		(layer "F.Cu")
		(net "JTAG_CONN_TDO")
	)
	(segment
		(start 258.56057 -206.69377)
		(end 258.888484 -207.021684)
		(width 0.13208)
		(layer "F.Cu")
		(net "JTAG_CONN_TDO")
	)
	(segment
		(start 261.78129 -206.894684)
		(end 259.84708 -206.894684)
		(width 0.13208)
		(layer "F.Cu")
		(net "JTAG_CONN_TDO")
	)
	(segment
		(start 258.56057 -206.272638)
		(end 258.56057 -206.69377)
		(width 0.13208)
		(layer "F.Cu")
		(net "JTAG_CONN_TDO")
	)
	(segment
		(start 259.84708 -206.894684)
		(end 259.225034 -206.272638)
		(width 0.13208)
		(layer "F.Cu")
		(net "JTAG_CONN_TDO")
	)
	(segment
		(start 258.888484 -207.021684)
		(end 258.935982 -207.021684)
		(width 0.13208)
		(layer "F.Cu")
		(net "JTAG_CONN_TDO")
	)
	(via
		(at 258.56057 -206.272638)
		(size 0.508)
		(drill 0.254)
		(layers "F.Cu" "B.Cu")
		(net "JTAG_CONN_TDO")
	)
	(segment
		(start 229.867714 -214.304118)
		(end 230.26751 -213.904322)
		(width 0.13208)
		(layer "F.Cu")
		(net "BIC_FWSPIMISO")
	)
	(via
		(at 230.895652 -204.84211)
		(size 0.6604)
		(drill 0.3302)
		(layers "F.Cu" "B.Cu")
		(net "BIC_FWSPIMISO")
	)
	(via
		(at 230.26751 -213.904322)
		(size 0.4572)
		(drill 0.254)
		(layers "F.Cu" "B.Cu")
		(net "BIC_FWSPIMISO")
	)
	(segment
		(start 230.194358 -208.684876)
		(end 230.991664 -207.88757)
		(width 0.13208)
		(layer "B.Cu")
		(net "BIC_FWSPIMISO")
	)
	(segment
		(start 230.991664 -207.42021)
		(end 230.580692 -207.42021)
		(width 0.13208)
		(layer "B.Cu")
		(net "BIC_FWSPIMISO")
	)
	(segment
		(start 230.194358 -210.202526)
		(end 230.194358 -208.684876)
		(width 0.13208)
		(layer "B.Cu")
		(net "BIC_FWSPIMISO")
	)
	(segment
		(start 229.650544 -210.74634)
		(end 230.194358 -210.202526)
		(width 0.13208)
		(layer "B.Cu")
		(net "BIC_FWSPIMISO")
	)
	(segment
		(start 230.26751 -213.904322)
		(end 229.650544 -213.287356)
		(width 0.13208)
		(layer "B.Cu")
		(net "BIC_FWSPIMISO")
	)
	(segment
		(start 230.895652 -204.84211)
		(end 232.083864 -204.84211)
		(width 0.13208)
		(layer "B.Cu")
		(net "BIC_FWSPIMISO")
	)
	(segment
		(start 230.991664 -207.88757)
		(end 230.991664 -207.42021)
		(width 0.13208)
		(layer "B.Cu")
		(net "BIC_FWSPIMISO")
	)
	(segment
		(start 230.447596 -207.287114)
		(end 230.447596 -205.290166)
		(width 0.13208)
		(layer "B.Cu")
		(net "BIC_FWSPIMISO")
	)
	(segment
		(start 230.580692 -207.42021)
		(end 230.447596 -207.287114)
		(width 0.13208)
		(layer "B.Cu")
		(net "BIC_FWSPIMISO")
	)
	(segment
		(start 230.447596 -205.290166)
		(end 230.895652 -204.84211)
		(width 0.13208)
		(layer "B.Cu")
		(net "BIC_FWSPIMISO")
	)
	(segment
		(start 229.650544 -213.287356)
		(end 229.650544 -210.74634)
		(width 0.13208)
		(layer "B.Cu")
		(net "BIC_FWSPIMISO")
	)
	(via
		(at 301.807626 -241.754406)
		(size 0.6604)
		(drill 0.3302)
		(layers "F.Cu" "B.Cu")
		(net "SMB_MB_BMC_ISO_SDA")
	)
	(segment
		(start 303.989486 -245.872)
		(end 304.124868 -245.736618)
		(width 0.13208)
		(layer "B.Cu")
		(net "SMB_MB_BMC_ISO_SDA")
	)
	(segment
		(start 302.46447 -243.04625)
		(end 301.807626 -242.389406)
		(width 0.13208)
		(layer "B.Cu")
		(net "SMB_MB_BMC_ISO_SDA")
	)
	(segment
		(start 301.807626 -242.389406)
		(end 301.807626 -241.754406)
		(width 0.13208)
		(layer "B.Cu")
		(net "SMB_MB_BMC_ISO_SDA")
	)
	(segment
		(start 301.807626 -240.630456)
		(end 302.061626 -240.376456)
		(width 0.13208)
		(layer "B.Cu")
		(net "SMB_MB_BMC_ISO_SDA")
	)
	(segment
		(start 304.124868 -245.445788)
		(end 304.26025 -245.310406)
		(width 0.13208)
		(layer "B.Cu")
		(net "SMB_MB_BMC_ISO_SDA")
	)
	(segment
		(start 302.46447 -244.69725)
		(end 303.077626 -245.310406)
		(width 0.13208)
		(layer "B.Cu")
		(net "SMB_MB_BMC_ISO_SDA")
	)
	(segment
		(start 303.527206 -245.310406)
		(end 303.662588 -245.445788)
		(width 0.13208)
		(layer "B.Cu")
		(net "SMB_MB_BMC_ISO_SDA")
	)
	(segment
		(start 302.46447 -243.737384)
		(end 302.46447 -244.69725)
		(width 0.13208)
		(layer "B.Cu")
		(net "SMB_MB_BMC_ISO_SDA")
	)
	(segment
		(start 303.077626 -245.310406)
		(end 303.527206 -245.310406)
		(width 0.13208)
		(layer "B.Cu")
		(net "SMB_MB_BMC_ISO_SDA")
	)
	(segment
		(start 303.662588 -245.445788)
		(end 303.662588 -245.736618)
		(width 0.13208)
		(layer "B.Cu")
		(net "SMB_MB_BMC_ISO_SDA")
	)
	(segment
		(start 304.124868 -245.736618)
		(end 304.124868 -245.445788)
		(width 0.13208)
		(layer "B.Cu")
		(net "SMB_MB_BMC_ISO_SDA")
	)
	(segment
		(start 305.001676 -245.310406)
		(end 305.490626 -245.799356)
		(width 0.13208)
		(layer "B.Cu")
		(net "SMB_MB_BMC_ISO_SDA")
	)
	(segment
		(start 301.807626 -241.754406)
		(end 301.807626 -240.630456)
		(width 0.13208)
		(layer "B.Cu")
		(net "SMB_MB_BMC_ISO_SDA")
	)
	(segment
		(start 304.26025 -245.310406)
		(end 305.001676 -245.310406)
		(width 0.13208)
		(layer "B.Cu")
		(net "SMB_MB_BMC_ISO_SDA")
	)
	(segment
		(start 303.077626 -240.376456)
		(end 302.061626 -240.376456)
		(width 0.13208)
		(layer "B.Cu")
		(net "SMB_MB_BMC_ISO_SDA")
	)
	(segment
		(start 303.662588 -245.736618)
		(end 303.79797 -245.872)
		(width 0.13208)
		(layer "B.Cu")
		(net "SMB_MB_BMC_ISO_SDA")
	)
	(segment
		(start 302.46447 -243.737384)
		(end 302.46447 -243.04625)
		(width 0.13208)
		(layer "B.Cu")
		(net "SMB_MB_BMC_ISO_SDA")
	)
	(segment
		(start 303.79797 -245.872)
		(end 303.989486 -245.872)
		(width 0.13208)
		(layer "B.Cu")
		(net "SMB_MB_BMC_ISO_SDA")
	)
	(segment
		(start 232.26776 -214.304118)
		(end 232.667556 -213.904322)
		(width 0.13208)
		(layer "F.Cu")
		(net "BIC_FWSPIMOSI")
	)
	(via
		(at 232.302558 -210.091782)
		(size 0.6604)
		(drill 0.3302)
		(layers "F.Cu" "B.Cu")
		(net "BIC_FWSPIMOSI")
	)
	(via
		(at 232.667556 -213.904322)
		(size 0.4572)
		(drill 0.254)
		(layers "F.Cu" "B.Cu")
		(net "BIC_FWSPIMOSI")
	)
	(segment
		(start 232.641648 -210.430872)
		(end 232.302558 -210.091782)
		(width 0.13208)
		(layer "B.Cu")
		(net "BIC_FWSPIMOSI")
	)
	(segment
		(start 232.667556 -213.904322)
		(end 232.93197 -213.639908)
		(width 0.0889)
		(layer "B.Cu")
		(net "BIC_FWSPIMOSI")
	)
	(segment
		(start 232.93197 -213.639908)
		(end 232.93197 -212.765386)
		(width 0.0889)
		(layer "B.Cu")
		(net "BIC_FWSPIMOSI")
	)
	(segment
		(start 232.93197 -212.765386)
		(end 232.641648 -212.475064)
		(width 0.13208)
		(layer "B.Cu")
		(net "BIC_FWSPIMOSI")
	)
	(segment
		(start 232.641648 -212.475064)
		(end 232.641648 -210.430872)
		(width 0.13208)
		(layer "B.Cu")
		(net "BIC_FWSPIMOSI")
	)
	(segment
		(start 368.074956 -215.4936)
		(end 369.708684 -213.859872)
		(width 0.13208)
		(layer "F.Cu")
		(net "PEX0_PCA9555_0_INT_N")
	)
	(segment
		(start 365.10595 -215.011)
		(end 365.10595 -215.3666)
		(width 0.13208)
		(layer "F.Cu")
		(net "PEX0_PCA9555_0_INT_N")
	)
	(segment
		(start 369.708684 -213.859872)
		(end 370.581936 -213.859872)
		(width 0.13208)
		(layer "F.Cu")
		(net "PEX0_PCA9555_0_INT_N")
	)
	(segment
		(start 364.49 -215.011)
		(end 363.87405 -215.011)
		(width 0.13208)
		(layer "F.Cu")
		(net "PEX0_PCA9555_0_INT_N")
	)
	(segment
		(start 365.10595 -215.011)
		(end 364.49 -215.011)
		(width 0.13208)
		(layer "F.Cu")
		(net "PEX0_PCA9555_0_INT_N")
	)
	(segment
		(start 365.23295 -215.4936)
		(end 368.074956 -215.4936)
		(width 0.13208)
		(layer "F.Cu")
		(net "PEX0_PCA9555_0_INT_N")
	)
	(segment
		(start 365.10595 -215.3666)
		(end 365.23295 -215.4936)
		(width 0.13208)
		(layer "F.Cu")
		(net "PEX0_PCA9555_0_INT_N")
	)
	(via
		(at 364.49 -215.011)
		(size 0.508)
		(drill 0.254)
		(layers "F.Cu" "B.Cu")
		(net "PEX0_PCA9555_0_INT_N")
	)
	(segment
		(start 387.882384 -252.756924)
		(end 387.882384 -253.45644)
		(width 0.13208)
		(layer "F.Cu")
		(net "PEX3_PCA9555_INT_R_N")
	)
	(segment
		(start 336.790538 -163.83)
		(end 337.060794 -164.100256)
		(width 0.13208)
		(layer "F.Cu")
		(net "PEX3_PCA9555_INT_R_N")
	)
	(segment
		(start 411.750002 -283.549852)
		(end 412.224982 -284.024832)
		(width 0.1651)
		(layer "F.Cu")
		(net "PEX3_PCA9555_INT_R_N")
	)
	(segment
		(start 336.44205 -163.83)
		(end 336.790538 -163.83)
		(width 0.13208)
		(layer "F.Cu")
		(net "PEX3_PCA9555_INT_R_N")
	)
	(via
		(at 387.882384 -253.45644)
		(size 0.508)
		(drill 0.254)
		(layers "F.Cu" "B.Cu")
		(net "PEX3_PCA9555_INT_R_N")
	)
	(via
		(at 374.577102 -174.052738)
		(size 0.508)
		(drill 0.254)
		(layers "F.Cu" "B.Cu")
		(net "PEX3_PCA9555_INT_R_N")
	)
	(via
		(at 412.224982 -284.024832)
		(size 0.4064)
		(drill 0.2032)
		(layers "F.Cu" "B.Cu")
		(net "PEX3_PCA9555_INT_R_N")
	)
	(via
		(at 337.060794 -164.100256)
		(size 0.508)
		(drill 0.254)
		(layers "F.Cu" "B.Cu")
		(net "PEX3_PCA9555_INT_R_N")
	)
	(segment
		(start 401.070826 -252.97892)
		(end 419.81247 -271.720564)
		(width 0.13208)
		(layer "B.Cu")
		(net "PEX3_PCA9555_INT_R_N")
	)
	(segment
		(start 418.424868 -282.86202)
		(end 418.424868 -284.13964)
		(width 0.13208)
		(layer "B.Cu")
		(net "PEX3_PCA9555_INT_R_N")
	)
	(segment
		(start 419.81247 -271.720564)
		(end 419.81247 -281.786076)
		(width 0.13208)
		(layer "B.Cu")
		(net "PEX3_PCA9555_INT_R_N")
	)
	(segment
		(start 418.719508 -282.56738)
		(end 418.424868 -282.86202)
		(width 0.13208)
		(layer "B.Cu")
		(net "PEX3_PCA9555_INT_R_N")
	)
	(segment
		(start 418.083238 -284.48127)
		(end 412.68142 -284.48127)
		(width 0.13208)
		(layer "B.Cu")
		(net "PEX3_PCA9555_INT_R_N")
	)
	(segment
		(start 388.359904 -252.97892)
		(end 401.070826 -252.97892)
		(width 0.13208)
		(layer "B.Cu")
		(net "PEX3_PCA9555_INT_R_N")
	)
	(segment
		(start 419.031166 -282.56738)
		(end 418.719508 -282.56738)
		(width 0.13208)
		(layer "B.Cu")
		(net "PEX3_PCA9555_INT_R_N")
	)
	(segment
		(start 419.81247 -281.786076)
		(end 419.031166 -282.56738)
		(width 0.13208)
		(layer "B.Cu")
		(net "PEX3_PCA9555_INT_R_N")
	)
	(segment
		(start 418.424868 -284.13964)
		(end 418.083238 -284.48127)
		(width 0.13208)
		(layer "B.Cu")
		(net "PEX3_PCA9555_INT_R_N")
	)
	(segment
		(start 387.882384 -253.45644)
		(end 388.359904 -252.97892)
		(width 0.13208)
		(layer "B.Cu")
		(net "PEX3_PCA9555_INT_R_N")
	)
	(segment
		(start 412.68142 -284.48127)
		(end 412.224982 -284.024832)
		(width 0.13208)
		(layer "B.Cu")
		(net "PEX3_PCA9555_INT_R_N")
	)
	(segment
		(start 389.597392 -251.741432)
		(end 389.597392 -243.168678)
		(width 0.15494)
		(layer "In5.Cu")
		(net "PEX3_PCA9555_INT_R_N")
	)
	(segment
		(start 376.06478 -176.6951)
		(end 375.432066 -176.6951)
		(width 0.15494)
		(layer "In5.Cu")
		(net "PEX3_PCA9555_INT_R_N")
	)
	(segment
		(start 389.597392 -243.168678)
		(end 391.044176 -239.67567)
		(width 0.15494)
		(layer "In5.Cu")
		(net "PEX3_PCA9555_INT_R_N")
	)
	(segment
		(start 389.701278 -231.006396)
		(end 389.701278 -224.006918)
		(width 0.15494)
		(layer "In5.Cu")
		(net "PEX3_PCA9555_INT_R_N")
	)
	(segment
		(start 381.801116 -216.106756)
		(end 378.423932 -216.106756)
		(width 0.15494)
		(layer "In5.Cu")
		(net "PEX3_PCA9555_INT_R_N")
	)
	(segment
		(start 387.882384 -253.45644)
		(end 389.597392 -251.741432)
		(width 0.15494)
		(layer "In5.Cu")
		(net "PEX3_PCA9555_INT_R_N")
	)
	(segment
		(start 375.432066 -176.6951)
		(end 374.577102 -175.840136)
		(width 0.15494)
		(layer "In5.Cu")
		(net "PEX3_PCA9555_INT_R_N")
	)
	(segment
		(start 389.701278 -224.006918)
		(end 381.801116 -216.106756)
		(width 0.15494)
		(layer "In5.Cu")
		(net "PEX3_PCA9555_INT_R_N")
	)
	(segment
		(start 378.423932 -216.106756)
		(end 374.592088 -212.274912)
		(width 0.15494)
		(layer "In5.Cu")
		(net "PEX3_PCA9555_INT_R_N")
	)
	(segment
		(start 374.577102 -175.840136)
		(end 374.577102 -174.052738)
		(width 0.15494)
		(layer "In5.Cu")
		(net "PEX3_PCA9555_INT_R_N")
	)
	(segment
		(start 393.479528 -232.035858)
		(end 390.73074 -232.035858)
		(width 0.15494)
		(layer "In5.Cu")
		(net "PEX3_PCA9555_INT_R_N")
	)
	(segment
		(start 374.592088 -212.274912)
		(end 374.592088 -209.093054)
		(width 0.15494)
		(layer "In5.Cu")
		(net "PEX3_PCA9555_INT_R_N")
	)
	(segment
		(start 391.044176 -239.67567)
		(end 393.842748 -236.877098)
		(width 0.15494)
		(layer "In5.Cu")
		(net "PEX3_PCA9555_INT_R_N")
	)
	(segment
		(start 393.842748 -232.399078)
		(end 393.479528 -232.035858)
		(width 0.15494)
		(layer "In5.Cu")
		(net "PEX3_PCA9555_INT_R_N")
	)
	(segment
		(start 377.0376 -177.66792)
		(end 376.06478 -176.6951)
		(width 0.15494)
		(layer "In5.Cu")
		(net "PEX3_PCA9555_INT_R_N")
	)
	(segment
		(start 374.643142 -194.64401)
		(end 377.0376 -192.249552)
		(width 0.15494)
		(layer "In5.Cu")
		(net "PEX3_PCA9555_INT_R_N")
	)
	(segment
		(start 390.73074 -232.035858)
		(end 389.701278 -231.006396)
		(width 0.15494)
		(layer "In5.Cu")
		(net "PEX3_PCA9555_INT_R_N")
	)
	(segment
		(start 377.0376 -192.249552)
		(end 377.0376 -177.66792)
		(width 0.15494)
		(layer "In5.Cu")
		(net "PEX3_PCA9555_INT_R_N")
	)
	(segment
		(start 374.643142 -209.042)
		(end 374.643142 -194.64401)
		(width 0.15494)
		(layer "In5.Cu")
		(net "PEX3_PCA9555_INT_R_N")
	)
	(segment
		(start 393.842748 -236.877098)
		(end 393.842748 -232.399078)
		(width 0.15494)
		(layer "In5.Cu")
		(net "PEX3_PCA9555_INT_R_N")
	)
	(segment
		(start 374.592088 -209.093054)
		(end 374.643142 -209.042)
		(width 0.15494)
		(layer "In5.Cu")
		(net "PEX3_PCA9555_INT_R_N")
	)
	(segment
		(start 348.535752 -165.765226)
		(end 351.183194 -165.765226)
		(width 0.15494)
		(layer "In13.Cu")
		(net "PEX3_PCA9555_INT_R_N")
	)
	(segment
		(start 351.183194 -165.765226)
		(end 352.50882 -164.4396)
		(width 0.15494)
		(layer "In13.Cu")
		(net "PEX3_PCA9555_INT_R_N")
	)
	(segment
		(start 364.602268 -171.76115)
		(end 371.995446 -171.76115)
		(width 0.15494)
		(layer "In13.Cu")
		(net "PEX3_PCA9555_INT_R_N")
	)
	(segment
		(start 371.995446 -171.76115)
		(end 374.287034 -174.052738)
		(width 0.15494)
		(layer "In13.Cu")
		(net "PEX3_PCA9555_INT_R_N")
	)
	(segment
		(start 355.009704 -164.4396)
		(end 356.669086 -166.098982)
		(width 0.15494)
		(layer "In13.Cu")
		(net "PEX3_PCA9555_INT_R_N")
	)
	(segment
		(start 337.655408 -164.69487)
		(end 347.465396 -164.69487)
		(width 0.15494)
		(layer "In13.Cu")
		(net "PEX3_PCA9555_INT_R_N")
	)
	(segment
		(start 374.287034 -174.052738)
		(end 374.577102 -174.052738)
		(width 0.15494)
		(layer "In13.Cu")
		(net "PEX3_PCA9555_INT_R_N")
	)
	(segment
		(start 356.669086 -166.098982)
		(end 358.9401 -166.098982)
		(width 0.15494)
		(layer "In13.Cu")
		(net "PEX3_PCA9555_INT_R_N")
	)
	(segment
		(start 358.9401 -166.098982)
		(end 364.602268 -171.76115)
		(width 0.15494)
		(layer "In13.Cu")
		(net "PEX3_PCA9555_INT_R_N")
	)
	(segment
		(start 352.50882 -164.4396)
		(end 355.009704 -164.4396)
		(width 0.15494)
		(layer "In13.Cu")
		(net "PEX3_PCA9555_INT_R_N")
	)
	(segment
		(start 347.465396 -164.69487)
		(end 348.535752 -165.765226)
		(width 0.15494)
		(layer "In13.Cu")
		(net "PEX3_PCA9555_INT_R_N")
	)
	(segment
		(start 337.060794 -164.100256)
		(end 337.655408 -164.69487)
		(width 0.15494)
		(layer "In13.Cu")
		(net "PEX3_PCA9555_INT_R_N")
	)
	(via
		(at 305.617626 -244.548406)
		(size 0.6604)
		(drill 0.3302)
		(layers "F.Cu" "B.Cu")
		(net "SMB_MB_BMC_ISO_SCL")
	)
	(segment
		(start 305.109626 -240.376456)
		(end 304.093626 -240.376456)
		(width 0.13208)
		(layer "B.Cu")
		(net "SMB_MB_BMC_ISO_SCL")
	)
	(segment
		(start 303.11471 -244.45849)
		(end 303.11471 -243.737384)
		(width 0.13208)
		(layer "B.Cu")
		(net "SMB_MB_BMC_ISO_SCL")
	)
	(segment
		(start 303.11471 -241.355372)
		(end 303.11471 -243.737384)
		(width 0.13208)
		(layer "B.Cu")
		(net "SMB_MB_BMC_ISO_SCL")
	)
	(segment
		(start 303.204626 -244.548406)
		(end 303.11471 -244.45849)
		(width 0.13208)
		(layer "B.Cu")
		(net "SMB_MB_BMC_ISO_SCL")
	)
	(segment
		(start 306.633626 -245.05666)
		(end 306.125372 -244.548406)
		(width 0.13208)
		(layer "B.Cu")
		(net "SMB_MB_BMC_ISO_SCL")
	)
	(segment
		(start 304.093626 -240.376456)
		(end 303.11471 -241.355372)
		(width 0.13208)
		(layer "B.Cu")
		(net "SMB_MB_BMC_ISO_SCL")
	)
	(segment
		(start 305.617626 -244.548406)
		(end 303.204626 -244.548406)
		(width 0.13208)
		(layer "B.Cu")
		(net "SMB_MB_BMC_ISO_SCL")
	)
	(segment
		(start 306.633626 -245.799356)
		(end 306.633626 -245.05666)
		(width 0.13208)
		(layer "B.Cu")
		(net "SMB_MB_BMC_ISO_SCL")
	)
	(segment
		(start 306.125372 -244.548406)
		(end 305.617626 -244.548406)
		(width 0.13208)
		(layer "B.Cu")
		(net "SMB_MB_BMC_ISO_SCL")
	)
	(segment
		(start 335.026 -162.814)
		(end 335.64195 -162.814)
		(width 0.13208)
		(layer "F.Cu")
		(net "PEX3_PCA9555_INT_N")
	)
	(segment
		(start 335.64195 -151.003)
		(end 334.9244 -151.003)
		(width 0.13208)
		(layer "F.Cu")
		(net "PEX3_PCA9555_INT_N")
	)
	(segment
		(start 334.29575 -151.63165)
		(end 334.29575 -162.08375)
		(width 0.13208)
		(layer "F.Cu")
		(net "PEX3_PCA9555_INT_N")
	)
	(segment
		(start 334.9244 -151.003)
		(end 334.29575 -151.63165)
		(width 0.13208)
		(layer "F.Cu")
		(net "PEX3_PCA9555_INT_N")
	)
	(segment
		(start 334.29575 -162.08375)
		(end 335.026 -162.814)
		(width 0.13208)
		(layer "F.Cu")
		(net "PEX3_PCA9555_INT_N")
	)
	(segment
		(start 335.64195 -162.814)
		(end 335.64195 -163.83)
		(width 0.13208)
		(layer "F.Cu")
		(net "PEX3_PCA9555_INT_N")
	)
	(via
		(at 335.026 -162.814)
		(size 0.508)
		(drill 0.254)
		(layers "F.Cu" "B.Cu")
		(net "PEX3_PCA9555_INT_N")
	)
	(segment
		(start 338.308188 -91.398344)
		(end 338.695538 -91.010994)
		(width 0.13208)
		(layer "F.Cu")
		(net "SSD15_CLK_EN_R_N")
	)
	(segment
		(start 338.695538 -91.010994)
		(end 338.695538 -89.714324)
		(width 0.13208)
		(layer "F.Cu")
		(net "SSD15_CLK_EN_R_N")
	)
	(via
		(at 338.308188 -91.398344)
		(size 0.508)
		(drill 0.254)
		(layers "F.Cu" "B.Cu")
		(net "SSD15_CLK_EN_R_N")
	)
	(via
		(at 345.186 -206.15148)
		(size 0.508)
		(drill 0.254)
		(layers "F.Cu" "B.Cu")
		(net "SSD15_CLK_EN_R_N")
	)
	(via
		(at 365.688626 -88.998298)
		(size 0.508)
		(drill 0.254)
		(layers "F.Cu" "B.Cu")
		(net "SSD15_CLK_EN_R_N")
	)
	(segment
		(start 356.752144 -88.382856)
		(end 357.218488 -88.8492)
		(width 0.13208)
		(layer "B.Cu")
		(net "SSD15_CLK_EN_R_N")
	)
	(segment
		(start 354.317808 -88.382856)
		(end 356.752144 -88.382856)
		(width 0.13208)
		(layer "B.Cu")
		(net "SSD15_CLK_EN_R_N")
	)
	(segment
		(start 338.426044 -91.5162)
		(end 347.479366 -91.5162)
		(width 0.13208)
		(layer "B.Cu")
		(net "SSD15_CLK_EN_R_N")
	)
	(segment
		(start 357.218488 -88.8492)
		(end 365.539528 -88.8492)
		(width 0.13208)
		(layer "B.Cu")
		(net "SSD15_CLK_EN_R_N")
	)
	(segment
		(start 345.44 -207.37195)
		(end 345.44 -206.40548)
		(width 0.13208)
		(layer "B.Cu")
		(net "SSD15_CLK_EN_R_N")
	)
	(segment
		(start 353.551998 -87.617046)
		(end 354.317808 -88.382856)
		(width 0.13208)
		(layer "B.Cu")
		(net "SSD15_CLK_EN_R_N")
	)
	(segment
		(start 347.479366 -91.5162)
		(end 351.37852 -87.617046)
		(width 0.13208)
		(layer "B.Cu")
		(net "SSD15_CLK_EN_R_N")
	)
	(segment
		(start 345.44 -206.40548)
		(end 345.186 -206.15148)
		(width 0.13208)
		(layer "B.Cu")
		(net "SSD15_CLK_EN_R_N")
	)
	(segment
		(start 351.37852 -87.617046)
		(end 353.551998 -87.617046)
		(width 0.13208)
		(layer "B.Cu")
		(net "SSD15_CLK_EN_R_N")
	)
	(segment
		(start 338.308188 -91.398344)
		(end 338.426044 -91.5162)
		(width 0.13208)
		(layer "B.Cu")
		(net "SSD15_CLK_EN_R_N")
	)
	(segment
		(start 365.539528 -88.8492)
		(end 365.688626 -88.998298)
		(width 0.13208)
		(layer "B.Cu")
		(net "SSD15_CLK_EN_R_N")
	)
	(segment
		(start 355.837236 -181.967378)
		(end 348.696534 -174.826676)
		(width 0.15494)
		(layer "In5.Cu")
		(net "SSD15_CLK_EN_R_N")
	)
	(segment
		(start 360.42854 -94.700344)
		(end 365.688626 -89.440258)
		(width 0.15494)
		(layer "In5.Cu")
		(net "SSD15_CLK_EN_R_N")
	)
	(segment
		(start 360.42854 -108.688378)
		(end 360.42854 -94.700344)
		(width 0.15494)
		(layer "In5.Cu")
		(net "SSD15_CLK_EN_R_N")
	)
	(segment
		(start 348.696534 -174.826676)
		(end 348.696534 -128.20523)
		(width 0.15494)
		(layer "In5.Cu")
		(net "SSD15_CLK_EN_R_N")
	)
	(segment
		(start 365.688626 -89.440258)
		(end 365.688626 -88.998298)
		(width 0.15494)
		(layer "In5.Cu")
		(net "SSD15_CLK_EN_R_N")
	)
	(segment
		(start 345.186 -206.15148)
		(end 345.186 -203.752704)
		(width 0.15494)
		(layer "In5.Cu")
		(net "SSD15_CLK_EN_R_N")
	)
	(segment
		(start 348.696534 -128.20523)
		(end 352.660712 -124.241052)
		(width 0.15494)
		(layer "In5.Cu")
		(net "SSD15_CLK_EN_R_N")
	)
	(segment
		(start 347.445584 -201.49312)
		(end 352.611944 -201.49312)
		(width 0.15494)
		(layer "In5.Cu")
		(net "SSD15_CLK_EN_R_N")
	)
	(segment
		(start 345.186 -203.752704)
		(end 347.445584 -201.49312)
		(width 0.15494)
		(layer "In5.Cu")
		(net "SSD15_CLK_EN_R_N")
	)
	(segment
		(start 352.611944 -201.49312)
		(end 355.837236 -198.267828)
		(width 0.15494)
		(layer "In5.Cu")
		(net "SSD15_CLK_EN_R_N")
	)
	(segment
		(start 355.837236 -198.267828)
		(end 355.837236 -181.967378)
		(width 0.15494)
		(layer "In5.Cu")
		(net "SSD15_CLK_EN_R_N")
	)
	(segment
		(start 352.660712 -124.241052)
		(end 352.660712 -116.456206)
		(width 0.15494)
		(layer "In5.Cu")
		(net "SSD15_CLK_EN_R_N")
	)
	(segment
		(start 352.660712 -116.456206)
		(end 360.42854 -108.688378)
		(width 0.15494)
		(layer "In5.Cu")
		(net "SSD15_CLK_EN_R_N")
	)
	(segment
		(start 339.511894 -187.36945)
		(end 340.161372 -187.36945)
		(width 0.13208)
		(layer "F.Cu")
		(net "USB_DEBUG_RST_BTN_N")
	)
	(segment
		(start 335.604612 -189.99454)
		(end 335.971388 -189.99454)
		(width 0.13208)
		(layer "F.Cu")
		(net "USB_DEBUG_RST_BTN_N")
	)
	(segment
		(start 335.971388 -189.99454)
		(end 338.596478 -187.36945)
		(width 0.13208)
		(layer "F.Cu")
		(net "USB_DEBUG_RST_BTN_N")
	)
	(segment
		(start 338.596478 -187.36945)
		(end 339.511894 -187.36945)
		(width 0.13208)
		(layer "F.Cu")
		(net "USB_DEBUG_RST_BTN_N")
	)
	(via
		(at 211.222082 -216.777316)
		(size 0.508)
		(drill 0.254)
		(layers "F.Cu" "B.Cu")
		(net "USB_DEBUG_RST_BTN_N")
	)
	(via
		(at 339.511894 -187.36945)
		(size 0.508)
		(drill 0.254)
		(layers "F.Cu" "B.Cu")
		(net "USB_DEBUG_RST_BTN_N")
	)
	(via
		(at 212.890608 -177.85461)
		(size 0.508)
		(drill 0.254)
		(layers "F.Cu" "B.Cu")
		(net "USB_DEBUG_RST_BTN_N")
	)
	(segment
		(start 211.222082 -215.867742)
		(end 210.996784 -215.642444)
		(width 0.13208)
		(layer "B.Cu")
		(net "USB_DEBUG_RST_BTN_N")
	)
	(segment
		(start 211.222082 -216.777316)
		(end 211.222082 -215.867742)
		(width 0.13208)
		(layer "B.Cu")
		(net "USB_DEBUG_RST_BTN_N")
	)
	(segment
		(start 211.65058 -192.524126)
		(end 211.65058 -209.087212)
		(width 0.15494)
		(layer "In5.Cu")
		(net "USB_DEBUG_RST_BTN_N")
	)
	(segment
		(start 210.19389 -189.352682)
		(end 210.410806 -189.569598)
		(width 0.15494)
		(layer "In5.Cu")
		(net "USB_DEBUG_RST_BTN_N")
	)
	(segment
		(start 210.410806 -189.569598)
		(end 210.410806 -189.883034)
		(width 0.15494)
		(layer "In5.Cu")
		(net "USB_DEBUG_RST_BTN_N")
	)
	(segment
		(start 212.890608 -181.647846)
		(end 211.113116 -183.425338)
		(width 0.15494)
		(layer "In5.Cu")
		(net "USB_DEBUG_RST_BTN_N")
	)
	(segment
		(start 211.113116 -183.425338)
		(end 211.113116 -184.369964)
		(width 0.15494)
		(layer "In5.Cu")
		(net "USB_DEBUG_RST_BTN_N")
	)
	(segment
		(start 209.658458 -189.130686)
		(end 210.19389 -189.352682)
		(width 0.15494)
		(layer "In5.Cu")
		(net "USB_DEBUG_RST_BTN_N")
	)
	(segment
		(start 208.76006 -188.232288)
		(end 209.658458 -189.130686)
		(width 0.15494)
		(layer "In5.Cu")
		(net "USB_DEBUG_RST_BTN_N")
	)
	(segment
		(start 210.253326 -185.643012)
		(end 208.76006 -187.136278)
		(width 0.15494)
		(layer "In5.Cu")
		(net "USB_DEBUG_RST_BTN_N")
	)
	(segment
		(start 208.76006 -187.136278)
		(end 208.76006 -188.232288)
		(width 0.15494)
		(layer "In5.Cu")
		(net "USB_DEBUG_RST_BTN_N")
	)
	(segment
		(start 210.21929 -215.06815)
		(end 211.222082 -216.070942)
		(width 0.15494)
		(layer "In5.Cu")
		(net "USB_DEBUG_RST_BTN_N")
	)
	(segment
		(start 210.410806 -189.883034)
		(end 210.799172 -190.2714)
		(width 0.15494)
		(layer "In5.Cu")
		(net "USB_DEBUG_RST_BTN_N")
	)
	(segment
		(start 210.253326 -185.229754)
		(end 210.253326 -185.643012)
		(width 0.15494)
		(layer "In5.Cu")
		(net "USB_DEBUG_RST_BTN_N")
	)
	(segment
		(start 212.890608 -177.85461)
		(end 212.890608 -181.647846)
		(width 0.15494)
		(layer "In5.Cu")
		(net "USB_DEBUG_RST_BTN_N")
	)
	(segment
		(start 210.21929 -210.518502)
		(end 210.21929 -215.06815)
		(width 0.15494)
		(layer "In5.Cu")
		(net "USB_DEBUG_RST_BTN_N")
	)
	(segment
		(start 211.222082 -216.070942)
		(end 211.222082 -216.777316)
		(width 0.15494)
		(layer "In5.Cu")
		(net "USB_DEBUG_RST_BTN_N")
	)
	(segment
		(start 211.65058 -209.087212)
		(end 210.21929 -210.518502)
		(width 0.15494)
		(layer "In5.Cu")
		(net "USB_DEBUG_RST_BTN_N")
	)
	(segment
		(start 210.799172 -190.2714)
		(end 210.799172 -191.672718)
		(width 0.15494)
		(layer "In5.Cu")
		(net "USB_DEBUG_RST_BTN_N")
	)
	(segment
		(start 210.799172 -191.672718)
		(end 211.65058 -192.524126)
		(width 0.15494)
		(layer "In5.Cu")
		(net "USB_DEBUG_RST_BTN_N")
	)
	(segment
		(start 211.113116 -184.369964)
		(end 210.253326 -185.229754)
		(width 0.15494)
		(layer "In5.Cu")
		(net "USB_DEBUG_RST_BTN_N")
	)
	(segment
		(start 227.105972 -177.06086)
		(end 229.539546 -177.06086)
		(width 0.15494)
		(layer "In13.Cu")
		(net "USB_DEBUG_RST_BTN_N")
	)
	(segment
		(start 216.309194 -178.71948)
		(end 216.309194 -180.410358)
		(width 0.15494)
		(layer "In13.Cu")
		(net "USB_DEBUG_RST_BTN_N")
	)
	(segment
		(start 217.60688 -181.708044)
		(end 219.865702 -181.708044)
		(width 0.15494)
		(layer "In13.Cu")
		(net "USB_DEBUG_RST_BTN_N")
	)
	(segment
		(start 222.300546 -179.2732)
		(end 224.789746 -179.2732)
		(width 0.15494)
		(layer "In13.Cu")
		(net "USB_DEBUG_RST_BTN_N")
	)
	(segment
		(start 276.109176 -187.89142)
		(end 338.989924 -187.89142)
		(width 0.15494)
		(layer "In13.Cu")
		(net "USB_DEBUG_RST_BTN_N")
	)
	(segment
		(start 227.103432 -177.0634)
		(end 227.105972 -177.06086)
		(width 0.15494)
		(layer "In13.Cu")
		(net "USB_DEBUG_RST_BTN_N")
	)
	(segment
		(start 216.309194 -180.410358)
		(end 217.60688 -181.708044)
		(width 0.15494)
		(layer "In13.Cu")
		(net "USB_DEBUG_RST_BTN_N")
	)
	(segment
		(start 229.539546 -177.06086)
		(end 230.379778 -176.220628)
		(width 0.15494)
		(layer "In13.Cu")
		(net "USB_DEBUG_RST_BTN_N")
	)
	(segment
		(start 226.999546 -177.0634)
		(end 227.103432 -177.0634)
		(width 0.15494)
		(layer "In13.Cu")
		(net "USB_DEBUG_RST_BTN_N")
	)
	(segment
		(start 258.639056 -178.520598)
		(end 261.481062 -181.362604)
		(width 0.15494)
		(layer "In13.Cu")
		(net "USB_DEBUG_RST_BTN_N")
	)
	(segment
		(start 224.789746 -179.2732)
		(end 226.999546 -177.0634)
		(width 0.15494)
		(layer "In13.Cu")
		(net "USB_DEBUG_RST_BTN_N")
	)
	(segment
		(start 236.756194 -176.220628)
		(end 237.665514 -175.31334)
		(width 0.15494)
		(layer "In13.Cu")
		(net "USB_DEBUG_RST_BTN_N")
	)
	(segment
		(start 230.379778 -176.220628)
		(end 236.756194 -176.220628)
		(width 0.15494)
		(layer "In13.Cu")
		(net "USB_DEBUG_RST_BTN_N")
	)
	(segment
		(start 219.865702 -181.708044)
		(end 222.300546 -179.2732)
		(width 0.15494)
		(layer "In13.Cu")
		(net "USB_DEBUG_RST_BTN_N")
	)
	(segment
		(start 254.999998 -178.520598)
		(end 258.639056 -178.520598)
		(width 0.15494)
		(layer "In13.Cu")
		(net "USB_DEBUG_RST_BTN_N")
	)
	(segment
		(start 261.481062 -181.362604)
		(end 269.58036 -181.362604)
		(width 0.15494)
		(layer "In13.Cu")
		(net "USB_DEBUG_RST_BTN_N")
	)
	(segment
		(start 338.989924 -187.89142)
		(end 339.511894 -187.36945)
		(width 0.15494)
		(layer "In13.Cu")
		(net "USB_DEBUG_RST_BTN_N")
	)
	(segment
		(start 237.665514 -175.31334)
		(end 251.79274 -175.31334)
		(width 0.15494)
		(layer "In13.Cu")
		(net "USB_DEBUG_RST_BTN_N")
	)
	(segment
		(start 251.79274 -175.31334)
		(end 254.999998 -178.520598)
		(width 0.15494)
		(layer "In13.Cu")
		(net "USB_DEBUG_RST_BTN_N")
	)
	(segment
		(start 269.58036 -181.362604)
		(end 276.109176 -187.89142)
		(width 0.15494)
		(layer "In13.Cu")
		(net "USB_DEBUG_RST_BTN_N")
	)
	(segment
		(start 212.890608 -177.85461)
		(end 215.444324 -177.85461)
		(width 0.15494)
		(layer "In13.Cu")
		(net "USB_DEBUG_RST_BTN_N")
	)
	(segment
		(start 215.444324 -177.85461)
		(end 216.309194 -178.71948)
		(width 0.15494)
		(layer "In13.Cu")
		(net "USB_DEBUG_RST_BTN_N")
	)
	(segment
		(start 339.598 -151.257)
		(end 339.344 -151.511)
		(width 0.13208)
		(layer "F.Cu")
		(net "PEX3_PCA9555_1_INT_N")
	)
	(segment
		(start 339.344 -151.511)
		(end 337.80095 -151.511)
		(width 0.13208)
		(layer "F.Cu")
		(net "PEX3_PCA9555_1_INT_N")
	)
	(segment
		(start 337.67395 -151.384)
		(end 337.67395 -151.003)
		(width 0.13208)
		(layer "F.Cu")
		(net "PEX3_PCA9555_1_INT_N")
	)
	(segment
		(start 343.149936 -149.851872)
		(end 342.159844 -149.851872)
		(width 0.13208)
		(layer "F.Cu")
		(net "PEX3_PCA9555_1_INT_N")
	)
	(segment
		(start 340.754716 -151.257)
		(end 339.598 -151.257)
		(width 0.13208)
		(layer "F.Cu")
		(net "PEX3_PCA9555_1_INT_N")
	)
	(segment
		(start 337.80095 -151.511)
		(end 337.67395 -151.384)
		(width 0.13208)
		(layer "F.Cu")
		(net "PEX3_PCA9555_1_INT_N")
	)
	(segment
		(start 342.159844 -149.851872)
		(end 340.754716 -151.257)
		(width 0.13208)
		(layer "F.Cu")
		(net "PEX3_PCA9555_1_INT_N")
	)
	(segment
		(start 337.058 -151.003)
		(end 336.44205 -151.003)
		(width 0.13208)
		(layer "F.Cu")
		(net "PEX3_PCA9555_1_INT_N")
	)
	(segment
		(start 337.67395 -151.003)
		(end 337.058 -151.003)
		(width 0.13208)
		(layer "F.Cu")
		(net "PEX3_PCA9555_1_INT_N")
	)
	(via
		(at 337.058 -151.003)
		(size 0.508)
		(drill 0.254)
		(layers "F.Cu" "B.Cu")
		(net "PEX3_PCA9555_1_INT_N")
	)
	(segment
		(start 244.221762 -184.037478)
		(end 244.348762 -184.164478)
		(width 0.13208)
		(layer "F.Cu")
		(net "PWRGD_P1V2_AUX_RST")
	)
	(segment
		(start 244.8433 -184.185052)
		(end 244.8433 -185.029602)
		(width 0.13208)
		(layer "F.Cu")
		(net "PWRGD_P1V2_AUX_RST")
	)
	(segment
		(start 244.822726 -184.164478)
		(end 244.8433 -184.185052)
		(width 0.13208)
		(layer "F.Cu")
		(net "PWRGD_P1V2_AUX_RST")
	)
	(segment
		(start 244.348762 -184.164478)
		(end 244.822726 -184.164478)
		(width 0.13208)
		(layer "F.Cu")
		(net "PWRGD_P1V2_AUX_RST")
	)
	(segment
		(start 243.8273 -185.029602)
		(end 244.8433 -185.029602)
		(width 0.13208)
		(layer "F.Cu")
		(net "PWRGD_P1V2_AUX_RST")
	)
	(segment
		(start 244.221762 -183.083962)
		(end 244.221762 -184.037478)
		(width 0.13208)
		(layer "F.Cu")
		(net "PWRGD_P1V2_AUX_RST")
	)
	(via
		(at 244.822726 -184.164478)
		(size 0.508)
		(drill 0.254)
		(layers "F.Cu" "B.Cu")
		(net "PWRGD_P1V2_AUX_RST")
	)
	(segment
		(start 247.089168 -181.760876)
		(end 247.089168 -180.590952)
		(width 0.13208)
		(layer "F.Cu")
		(net "BIC_FWSPICK_R")
	)
	(segment
		(start 247.089168 -179.942236)
		(end 250.404122 -176.627282)
		(width 0.13208)
		(layer "F.Cu")
		(net "BIC_FWSPICK_R")
	)
	(segment
		(start 247.089168 -180.590952)
		(end 247.089168 -179.942236)
		(width 0.13208)
		(layer "F.Cu")
		(net "BIC_FWSPICK_R")
	)
	(segment
		(start 250.404122 -176.627282)
		(end 254.302514 -176.627282)
		(width 0.13208)
		(layer "F.Cu")
		(net "BIC_FWSPICK_R")
	)
	(segment
		(start 247.322848 -181.994556)
		(end 247.089168 -181.760876)
		(width 0.13208)
		(layer "F.Cu")
		(net "BIC_FWSPICK_R")
	)
	(via
		(at 247.089168 -180.590952)
		(size 0.762)
		(drill 0.381)
		(layers "F.Cu" "B.Cu")
		(net "BIC_FWSPICK_R")
	)
	(segment
		(start 340.295484 -90.192098)
		(end 340.295484 -89.714324)
		(width 0.13208)
		(layer "F.Cu")
		(net "SSD14_CLK_EN_R_N")
	)
	(segment
		(start 351.29089 -93.371162)
		(end 343.474548 -93.371162)
		(width 0.13208)
		(layer "F.Cu")
		(net "SSD14_CLK_EN_R_N")
	)
	(segment
		(start 351.526602 -93.13545)
		(end 351.29089 -93.371162)
		(width 0.13208)
		(layer "F.Cu")
		(net "SSD14_CLK_EN_R_N")
	)
	(segment
		(start 343.474548 -93.371162)
		(end 340.295484 -90.192098)
		(width 0.13208)
		(layer "F.Cu")
		(net "SSD14_CLK_EN_R_N")
	)
	(via
		(at 351.526602 -93.13545)
		(size 0.508)
		(drill 0.254)
		(layers "F.Cu" "B.Cu")
		(net "SSD14_CLK_EN_R_N")
	)
	(via
		(at 343.154 -206.15148)
		(size 0.508)
		(drill 0.254)
		(layers "F.Cu" "B.Cu")
		(net "SSD14_CLK_EN_R_N")
	)
	(segment
		(start 343.154 -207.37195)
		(end 343.154 -206.15148)
		(width 0.13208)
		(layer "B.Cu")
		(net "SSD14_CLK_EN_R_N")
	)
	(segment
		(start 349.3262 -173.418754)
		(end 349.3262 -141.402054)
		(width 0.15494)
		(layer "In9.Cu")
		(net "SSD14_CLK_EN_R_N")
	)
	(segment
		(start 346.399358 -201.732642)
		(end 350.387412 -201.732642)
		(width 0.15494)
		(layer "In9.Cu")
		(net "SSD14_CLK_EN_R_N")
	)
	(segment
		(start 350.4184 -140.309854)
		(end 350.4184 -124.511054)
		(width 0.15494)
		(layer "In9.Cu")
		(net "SSD14_CLK_EN_R_N")
	)
	(segment
		(start 355.3206 -191.349122)
		(end 349.758 -185.786522)
		(width 0.15494)
		(layer "In9.Cu")
		(net "SSD14_CLK_EN_R_N")
	)
	(segment
		(start 349.3262 -141.402054)
		(end 350.4184 -140.309854)
		(width 0.15494)
		(layer "In9.Cu")
		(net "SSD14_CLK_EN_R_N")
	)
	(segment
		(start 351.526602 -103.688134)
		(end 351.526602 -93.13545)
		(width 0.15494)
		(layer "In9.Cu")
		(net "SSD14_CLK_EN_R_N")
	)
	(segment
		(start 343.154 -206.15148)
		(end 344.17 -205.13548)
		(width 0.15494)
		(layer "In9.Cu")
		(net "SSD14_CLK_EN_R_N")
	)
	(segment
		(start 350.6216 -174.714154)
		(end 349.3262 -173.418754)
		(width 0.15494)
		(layer "In9.Cu")
		(net "SSD14_CLK_EN_R_N")
	)
	(segment
		(start 349.758 -181.636924)
		(end 350.6216 -180.773324)
		(width 0.15494)
		(layer "In9.Cu")
		(net "SSD14_CLK_EN_R_N")
	)
	(segment
		(start 350.4184 -124.511054)
		(end 352.2726 -122.656854)
		(width 0.15494)
		(layer "In9.Cu")
		(net "SSD14_CLK_EN_R_N")
	)
	(segment
		(start 352.2726 -111.8616)
		(end 354.4062 -109.728)
		(width 0.15494)
		(layer "In9.Cu")
		(net "SSD14_CLK_EN_R_N")
	)
	(segment
		(start 344.17 -203.962)
		(end 346.399358 -201.732642)
		(width 0.15494)
		(layer "In9.Cu")
		(net "SSD14_CLK_EN_R_N")
	)
	(segment
		(start 355.3206 -196.799454)
		(end 355.3206 -191.349122)
		(width 0.15494)
		(layer "In9.Cu")
		(net "SSD14_CLK_EN_R_N")
	)
	(segment
		(start 352.2726 -122.656854)
		(end 352.2726 -111.8616)
		(width 0.15494)
		(layer "In9.Cu")
		(net "SSD14_CLK_EN_R_N")
	)
	(segment
		(start 354.4062 -109.728)
		(end 354.4062 -106.567732)
		(width 0.15494)
		(layer "In9.Cu")
		(net "SSD14_CLK_EN_R_N")
	)
	(segment
		(start 350.387412 -201.732642)
		(end 355.3206 -196.799454)
		(width 0.15494)
		(layer "In9.Cu")
		(net "SSD14_CLK_EN_R_N")
	)
	(segment
		(start 349.758 -185.786522)
		(end 349.758 -181.636924)
		(width 0.15494)
		(layer "In9.Cu")
		(net "SSD14_CLK_EN_R_N")
	)
	(segment
		(start 350.6216 -180.773324)
		(end 350.6216 -174.714154)
		(width 0.15494)
		(layer "In9.Cu")
		(net "SSD14_CLK_EN_R_N")
	)
	(segment
		(start 344.17 -205.13548)
		(end 344.17 -203.962)
		(width 0.15494)
		(layer "In9.Cu")
		(net "SSD14_CLK_EN_R_N")
	)
	(segment
		(start 354.4062 -106.567732)
		(end 351.526602 -103.688134)
		(width 0.15494)
		(layer "In9.Cu")
		(net "SSD14_CLK_EN_R_N")
	)
	(segment
		(start 335.604612 -196.594476)
		(end 336.658204 -196.594476)
		(width 0.13208)
		(layer "F.Cu")
		(net "SMB_IO_DEBUG_CARD_R_SDA")
	)
	(segment
		(start 338.217002 -197.228968)
		(end 339.533484 -198.54545)
		(width 0.13208)
		(layer "F.Cu")
		(net "SMB_IO_DEBUG_CARD_R_SDA")
	)
	(segment
		(start 337.292696 -197.228968)
		(end 338.217002 -197.228968)
		(width 0.13208)
		(layer "F.Cu")
		(net "SMB_IO_DEBUG_CARD_R_SDA")
	)
	(segment
		(start 336.658204 -196.594476)
		(end 337.292696 -197.228968)
		(width 0.13208)
		(layer "F.Cu")
		(net "SMB_IO_DEBUG_CARD_R_SDA")
	)
	(segment
		(start 339.533484 -198.54545)
		(end 340.161372 -198.54545)
		(width 0.13208)
		(layer "F.Cu")
		(net "SMB_IO_DEBUG_CARD_R_SDA")
	)
	(via
		(at 339.533484 -198.54545)
		(size 0.508)
		(drill 0.254)
		(layers "F.Cu" "B.Cu")
		(net "SMB_IO_DEBUG_CARD_R_SDA")
	)
	(segment
		(start 342.807544 -86.578948)
		(end 342.346534 -87.039958)
		(width 0.13208)
		(layer "F.Cu")
		(net "SSD13_CLK_EN_R_N")
	)
	(segment
		(start 342.646 -204.83195)
		(end 342.646 -204.216)
		(width 0.13208)
		(layer "F.Cu")
		(net "SSD13_CLK_EN_R_N")
	)
	(segment
		(start 341.588598 -86.964266)
		(end 341.045546 -86.964266)
		(width 0.13208)
		(layer "F.Cu")
		(net "SSD13_CLK_EN_R_N")
	)
	(segment
		(start 342.346534 -87.039958)
		(end 341.66429 -87.039958)
		(width 0.13208)
		(layer "F.Cu")
		(net "SSD13_CLK_EN_R_N")
	)
	(segment
		(start 341.66429 -87.039958)
		(end 341.588598 -86.964266)
		(width 0.13208)
		(layer "F.Cu")
		(net "SSD13_CLK_EN_R_N")
	)
	(via
		(at 364.413038 -88.16975)
		(size 0.508)
		(drill 0.254)
		(layers "F.Cu" "B.Cu")
		(net "SSD13_CLK_EN_R_N")
	)
	(via
		(at 342.646 -204.216)
		(size 0.508)
		(drill 0.254)
		(layers "F.Cu" "B.Cu")
		(net "SSD13_CLK_EN_R_N")
	)
	(via
		(at 342.807544 -86.578948)
		(size 0.508)
		(drill 0.254)
		(layers "F.Cu" "B.Cu")
		(net "SSD13_CLK_EN_R_N")
	)
	(segment
		(start 350.555814 -86.934802)
		(end 350.555814 -87.771986)
		(width 0.13208)
		(layer "B.Cu")
		(net "SSD13_CLK_EN_R_N")
	)
	(segment
		(start 354.304854 -87.17915)
		(end 353.257104 -86.1314)
		(width 0.13208)
		(layer "B.Cu")
		(net "SSD13_CLK_EN_R_N")
	)
	(segment
		(start 345.9734 -90.9066)
		(end 342.807544 -87.740744)
		(width 0.13208)
		(layer "B.Cu")
		(net "SSD13_CLK_EN_R_N")
	)
	(segment
		(start 353.257104 -86.1314)
		(end 351.840546 -86.1314)
		(width 0.13208)
		(layer "B.Cu")
		(net "SSD13_CLK_EN_R_N")
	)
	(segment
		(start 347.4212 -90.9066)
		(end 345.9734 -90.9066)
		(width 0.13208)
		(layer "B.Cu")
		(net "SSD13_CLK_EN_R_N")
	)
	(segment
		(start 342.807544 -87.740744)
		(end 342.807544 -86.578948)
		(width 0.13208)
		(layer "B.Cu")
		(net "SSD13_CLK_EN_R_N")
	)
	(segment
		(start 364.413038 -88.16975)
		(end 363.422438 -87.17915)
		(width 0.13208)
		(layer "B.Cu")
		(net "SSD13_CLK_EN_R_N")
	)
	(segment
		(start 351.105216 -86.3854)
		(end 350.555814 -86.934802)
		(width 0.13208)
		(layer "B.Cu")
		(net "SSD13_CLK_EN_R_N")
	)
	(segment
		(start 351.586546 -86.3854)
		(end 351.105216 -86.3854)
		(width 0.13208)
		(layer "B.Cu")
		(net "SSD13_CLK_EN_R_N")
	)
	(segment
		(start 350.555814 -87.771986)
		(end 347.4212 -90.9066)
		(width 0.13208)
		(layer "B.Cu")
		(net "SSD13_CLK_EN_R_N")
	)
	(segment
		(start 363.422438 -87.17915)
		(end 354.304854 -87.17915)
		(width 0.13208)
		(layer "B.Cu")
		(net "SSD13_CLK_EN_R_N")
	)
	(segment
		(start 351.840546 -86.1314)
		(end 351.586546 -86.3854)
		(width 0.13208)
		(layer "B.Cu")
		(net "SSD13_CLK_EN_R_N")
	)
	(segment
		(start 342.646 -203.323952)
		(end 342.138 -202.815952)
		(width 0.15494)
		(layer "In5.Cu")
		(net "SSD13_CLK_EN_R_N")
	)
	(segment
		(start 342.646 -204.216)
		(end 342.646 -203.323952)
		(width 0.15494)
		(layer "In5.Cu")
		(net "SSD13_CLK_EN_R_N")
	)
	(segment
		(start 343.1286 -180.740558)
		(end 347.418914 -176.450244)
		(width 0.15494)
		(layer "In5.Cu")
		(net "SSD13_CLK_EN_R_N")
	)
	(segment
		(start 351.383092 -123.711462)
		(end 351.383092 -115.926616)
		(width 0.15494)
		(layer "In5.Cu")
		(net "SSD13_CLK_EN_R_N")
	)
	(segment
		(start 363.916214 -88.666574)
		(end 364.413038 -88.16975)
		(width 0.15494)
		(layer "In5.Cu")
		(net "SSD13_CLK_EN_R_N")
	)
	(segment
		(start 359.747566 -102.680262)
		(end 359.747566 -99.350576)
		(width 0.15494)
		(layer "In5.Cu")
		(net "SSD13_CLK_EN_R_N")
	)
	(segment
		(start 347.418914 -127.67564)
		(end 351.383092 -123.711462)
		(width 0.15494)
		(layer "In5.Cu")
		(net "SSD13_CLK_EN_R_N")
	)
	(segment
		(start 342.138 -199.5424)
		(end 343.1286 -198.5518)
		(width 0.15494)
		(layer "In5.Cu")
		(net "SSD13_CLK_EN_R_N")
	)
	(segment
		(start 342.138 -202.815952)
		(end 342.138 -199.5424)
		(width 0.15494)
		(layer "In5.Cu")
		(net "SSD13_CLK_EN_R_N")
	)
	(segment
		(start 358.520492 -103.907336)
		(end 359.747566 -102.680262)
		(width 0.15494)
		(layer "In5.Cu")
		(net "SSD13_CLK_EN_R_N")
	)
	(segment
		(start 359.747566 -99.350576)
		(end 359.026206 -98.629216)
		(width 0.15494)
		(layer "In5.Cu")
		(net "SSD13_CLK_EN_R_N")
	)
	(segment
		(start 351.383092 -115.926616)
		(end 358.520492 -108.789216)
		(width 0.15494)
		(layer "In5.Cu")
		(net "SSD13_CLK_EN_R_N")
	)
	(segment
		(start 363.916214 -90.241374)
		(end 363.916214 -88.666574)
		(width 0.15494)
		(layer "In5.Cu")
		(net "SSD13_CLK_EN_R_N")
	)
	(segment
		(start 347.418914 -176.450244)
		(end 347.418914 -127.67564)
		(width 0.15494)
		(layer "In5.Cu")
		(net "SSD13_CLK_EN_R_N")
	)
	(segment
		(start 359.026206 -95.131382)
		(end 363.916214 -90.241374)
		(width 0.15494)
		(layer "In5.Cu")
		(net "SSD13_CLK_EN_R_N")
	)
	(segment
		(start 359.026206 -98.629216)
		(end 359.026206 -95.131382)
		(width 0.15494)
		(layer "In5.Cu")
		(net "SSD13_CLK_EN_R_N")
	)
	(segment
		(start 358.520492 -108.789216)
		(end 358.520492 -103.907336)
		(width 0.15494)
		(layer "In5.Cu")
		(net "SSD13_CLK_EN_R_N")
	)
	(segment
		(start 343.1286 -198.5518)
		(end 343.1286 -180.740558)
		(width 0.15494)
		(layer "In5.Cu")
		(net "SSD13_CLK_EN_R_N")
	)
	(segment
		(start 340.754716 -163.068)
		(end 339.598 -163.068)
		(width 0.13208)
		(layer "F.Cu")
		(net "PEX3_PCA9555_0_INT_N")
	)
	(segment
		(start 339.598 -163.068)
		(end 339.344 -163.322)
		(width 0.13208)
		(layer "F.Cu")
		(net "PEX3_PCA9555_0_INT_N")
	)
	(segment
		(start 337.67395 -163.195)
		(end 337.67395 -162.814)
		(width 0.13208)
		(layer "F.Cu")
		(net "PEX3_PCA9555_0_INT_N")
	)
	(segment
		(start 342.159844 -161.662872)
		(end 340.754716 -163.068)
		(width 0.13208)
		(layer "F.Cu")
		(net "PEX3_PCA9555_0_INT_N")
	)
	(segment
		(start 343.149936 -161.662872)
		(end 342.159844 -161.662872)
		(width 0.13208)
		(layer "F.Cu")
		(net "PEX3_PCA9555_0_INT_N")
	)
	(segment
		(start 337.80095 -163.322)
		(end 337.67395 -163.195)
		(width 0.13208)
		(layer "F.Cu")
		(net "PEX3_PCA9555_0_INT_N")
	)
	(segment
		(start 339.344 -163.322)
		(end 337.80095 -163.322)
		(width 0.13208)
		(layer "F.Cu")
		(net "PEX3_PCA9555_0_INT_N")
	)
	(segment
		(start 336.44205 -162.814)
		(end 337.058 -162.814)
		(width 0.13208)
		(layer "F.Cu")
		(net "PEX3_PCA9555_0_INT_N")
	)
	(segment
		(start 337.058 -162.814)
		(end 337.67395 -162.814)
		(width 0.13208)
		(layer "F.Cu")
		(net "PEX3_PCA9555_0_INT_N")
	)
	(via
		(at 337.058 -162.814)
		(size 0.508)
		(drill 0.254)
		(layers "F.Cu" "B.Cu")
		(net "PEX3_PCA9555_0_INT_N")
	)
	(segment
		(start 341.045546 -86.56447)
		(end 341.907622 -86.56447)
		(width 0.13208)
		(layer "F.Cu")
		(net "SSD12_CLK_EN_R_N")
	)
	(segment
		(start 338.582 -200.76795)
		(end 338.582 -200.152)
		(width 0.13208)
		(layer "F.Cu")
		(net "SSD12_CLK_EN_R_N")
	)
	(via
		(at 338.582 -200.152)
		(size 0.508)
		(drill 0.254)
		(layers "F.Cu" "B.Cu")
		(net "SSD12_CLK_EN_R_N")
	)
	(via
		(at 341.907622 -86.56447)
		(size 0.508)
		(drill 0.254)
		(layers "F.Cu" "B.Cu")
		(net "SSD12_CLK_EN_R_N")
	)
	(via
		(at 355.570536 -93.25991)
		(size 0.508)
		(drill 0.254)
		(layers "F.Cu" "B.Cu")
		(net "SSD12_CLK_EN_R_N")
	)
	(segment
		(start 341.168736 -177.439066)
		(end 345.425014 -173.182788)
		(width 0.15494)
		(layer "In5.Cu")
		(net "SSD12_CLK_EN_R_N")
	)
	(segment
		(start 345.425014 -173.182788)
		(end 345.425014 -126.84887)
		(width 0.15494)
		(layer "In5.Cu")
		(net "SSD12_CLK_EN_R_N")
	)
	(segment
		(start 339.038184 -194.731386)
		(end 338.972398 -194.6656)
		(width 0.15494)
		(layer "In5.Cu")
		(net "SSD12_CLK_EN_R_N")
	)
	(segment
		(start 338.263738 -182.145686)
		(end 341.168736 -179.240688)
		(width 0.15494)
		(layer "In5.Cu")
		(net "SSD12_CLK_EN_R_N")
	)
	(segment
		(start 339.038184 -199.695816)
		(end 339.038184 -194.731386)
		(width 0.15494)
		(layer "In5.Cu")
		(net "SSD12_CLK_EN_R_N")
	)
	(segment
		(start 349.389192 -122.884692)
		(end 349.389192 -115.09248)
		(width 0.15494)
		(layer "In5.Cu")
		(net "SSD12_CLK_EN_R_N")
	)
	(segment
		(start 338.582 -200.152)
		(end 339.038184 -199.695816)
		(width 0.15494)
		(layer "In5.Cu")
		(net "SSD12_CLK_EN_R_N")
	)
	(segment
		(start 354.499926 -109.981746)
		(end 354.499926 -104.32669)
		(width 0.15494)
		(layer "In5.Cu")
		(net "SSD12_CLK_EN_R_N")
	)
	(segment
		(start 354.499926 -104.32669)
		(end 351.77222 -101.598984)
		(width 0.15494)
		(layer "In5.Cu")
		(net "SSD12_CLK_EN_R_N")
	)
	(segment
		(start 338.972398 -188.77661)
		(end 338.263738 -188.06795)
		(width 0.15494)
		(layer "In5.Cu")
		(net "SSD12_CLK_EN_R_N")
	)
	(segment
		(start 338.972398 -194.6656)
		(end 338.972398 -188.77661)
		(width 0.15494)
		(layer "In5.Cu")
		(net "SSD12_CLK_EN_R_N")
	)
	(segment
		(start 341.168736 -179.240688)
		(end 341.168736 -177.439066)
		(width 0.15494)
		(layer "In5.Cu")
		(net "SSD12_CLK_EN_R_N")
	)
	(segment
		(start 351.77222 -97.058226)
		(end 355.570536 -93.25991)
		(width 0.15494)
		(layer "In5.Cu")
		(net "SSD12_CLK_EN_R_N")
	)
	(segment
		(start 349.389192 -115.09248)
		(end 354.499926 -109.981746)
		(width 0.15494)
		(layer "In5.Cu")
		(net "SSD12_CLK_EN_R_N")
	)
	(segment
		(start 351.77222 -101.598984)
		(end 351.77222 -97.058226)
		(width 0.15494)
		(layer "In5.Cu")
		(net "SSD12_CLK_EN_R_N")
	)
	(segment
		(start 338.263738 -188.06795)
		(end 338.263738 -182.145686)
		(width 0.15494)
		(layer "In5.Cu")
		(net "SSD12_CLK_EN_R_N")
	)
	(segment
		(start 345.425014 -126.84887)
		(end 349.389192 -122.884692)
		(width 0.15494)
		(layer "In5.Cu")
		(net "SSD12_CLK_EN_R_N")
	)
	(segment
		(start 352.955098 -91.567)
		(end 354.648008 -93.25991)
		(width 0.15494)
		(layer "In15.Cu")
		(net "SSD12_CLK_EN_R_N")
	)
	(segment
		(start 349.8088 -92.3036)
		(end 350.5454 -91.567)
		(width 0.15494)
		(layer "In15.Cu")
		(net "SSD12_CLK_EN_R_N")
	)
	(segment
		(start 341.907622 -86.56447)
		(end 347.646752 -92.3036)
		(width 0.15494)
		(layer "In15.Cu")
		(net "SSD12_CLK_EN_R_N")
	)
	(segment
		(start 350.5454 -91.567)
		(end 352.955098 -91.567)
		(width 0.15494)
		(layer "In15.Cu")
		(net "SSD12_CLK_EN_R_N")
	)
	(segment
		(start 347.646752 -92.3036)
		(end 349.8088 -92.3036)
		(width 0.15494)
		(layer "In15.Cu")
		(net "SSD12_CLK_EN_R_N")
	)
	(segment
		(start 354.648008 -93.25991)
		(end 355.570536 -93.25991)
		(width 0.15494)
		(layer "In15.Cu")
		(net "SSD12_CLK_EN_R_N")
	)
	(segment
		(start 330.19746 -215.265)
		(end 331.323188 -216.390728)
		(width 0.13208)
		(layer "F.Cu")
		(net "PRSNT_SSD10_FPGA_N")
	)
	(segment
		(start 330.19746 -215.265)
		(end 327.93305 -215.265)
		(width 0.13208)
		(layer "F.Cu")
		(net "PRSNT_SSD10_FPGA_N")
	)
	(segment
		(start 331.323188 -216.390728)
		(end 334.49768 -216.390728)
		(width 0.13208)
		(layer "F.Cu")
		(net "PRSNT_SSD10_FPGA_N")
	)
	(segment
		(start 334.49768 -216.390728)
		(end 334.89392 -216.786968)
		(width 0.13208)
		(layer "F.Cu")
		(net "PRSNT_SSD10_FPGA_N")
	)
	(via
		(at 330.19746 -215.265)
		(size 0.762)
		(drill 0.381)
		(layers "F.Cu" "B.Cu")
		(net "PRSNT_SSD10_FPGA_N")
	)
	(segment
		(start 339.511894 -189.40145)
		(end 340.161372 -189.40145)
		(width 0.13208)
		(layer "F.Cu")
		(net "PWRGD_SYS_PWROK")
	)
	(segment
		(start 337.814412 -190.227712)
		(end 336.64779 -191.394334)
		(width 0.13208)
		(layer "F.Cu")
		(net "PWRGD_SYS_PWROK")
	)
	(segment
		(start 338.082636 -190.227712)
		(end 337.814412 -190.227712)
		(width 0.13208)
		(layer "F.Cu")
		(net "PWRGD_SYS_PWROK")
	)
	(segment
		(start 336.64779 -191.394334)
		(end 335.604612 -191.394334)
		(width 0.13208)
		(layer "F.Cu")
		(net "PWRGD_SYS_PWROK")
	)
	(segment
		(start 339.511894 -189.40145)
		(end 338.908898 -189.40145)
		(width 0.13208)
		(layer "F.Cu")
		(net "PWRGD_SYS_PWROK")
	)
	(segment
		(start 338.908898 -189.40145)
		(end 338.082636 -190.227712)
		(width 0.13208)
		(layer "F.Cu")
		(net "PWRGD_SYS_PWROK")
	)
	(via
		(at 339.511894 -189.40145)
		(size 0.508)
		(drill 0.254)
		(layers "F.Cu" "B.Cu")
		(net "PWRGD_SYS_PWROK")
	)
	(segment
		(start 244.386608 -187.85713)
		(end 244.83187 -187.85713)
		(width 0.13208)
		(layer "F.Cu")
		(net "BIC_FWSPICK")
	)
	(segment
		(start 243.225066 -189.018672)
		(end 244.386608 -187.85713)
		(width 0.13208)
		(layer "F.Cu")
		(net "BIC_FWSPICK")
	)
	(segment
		(start 248.802906 -181.994556)
		(end 249.862848 -181.994556)
		(width 0.13208)
		(layer "F.Cu")
		(net "BIC_FWSPICK")
	)
	(segment
		(start 248.61774 -184.07126)
		(end 248.61774 -182.179722)
		(width 0.13208)
		(layer "F.Cu")
		(net "BIC_FWSPICK")
	)
	(segment
		(start 250.270518 -179.167282)
		(end 251.38253 -179.167282)
		(width 0.13208)
		(layer "F.Cu")
		(net "BIC_FWSPICK")
	)
	(segment
		(start 230.66756 -215.904064)
		(end 231.067356 -215.504268)
		(width 0.13208)
		(layer "F.Cu")
		(net "BIC_FWSPICK")
	)
	(segment
		(start 249.862848 -181.994556)
		(end 249.6312 -181.762908)
		(width 0.13208)
		(layer "F.Cu")
		(net "BIC_FWSPICK")
	)
	(segment
		(start 244.83187 -187.85713)
		(end 248.61774 -184.07126)
		(width 0.13208)
		(layer "F.Cu")
		(net "BIC_FWSPICK")
	)
	(segment
		(start 249.6312 -179.8066)
		(end 250.270518 -179.167282)
		(width 0.13208)
		(layer "F.Cu")
		(net "BIC_FWSPICK")
	)
	(segment
		(start 241.216434 -251.159772)
		(end 241.216434 -251.857256)
		(width 0.13208)
		(layer "F.Cu")
		(net "BIC_FWSPICK")
	)
	(segment
		(start 249.6312 -181.762908)
		(end 249.6312 -179.8066)
		(width 0.13208)
		(layer "F.Cu")
		(net "BIC_FWSPICK")
	)
	(segment
		(start 248.61774 -182.179722)
		(end 248.802906 -181.994556)
		(width 0.13208)
		(layer "F.Cu")
		(net "BIC_FWSPICK")
	)
	(via
		(at 241.216434 -251.857256)
		(size 0.508)
		(drill 0.254)
		(layers "F.Cu" "B.Cu")
		(net "BIC_FWSPICK")
	)
	(via
		(at 242.7859 -219.177108)
		(size 0.508)
		(drill 0.254)
		(layers "F.Cu" "B.Cu")
		(net "BIC_FWSPICK")
	)
	(via
		(at 243.225066 -189.018672)
		(size 0.508)
		(drill 0.254)
		(layers "F.Cu" "B.Cu")
		(net "BIC_FWSPICK")
	)
	(via
		(at 231.067356 -215.504268)
		(size 0.4572)
		(drill 0.254)
		(layers "F.Cu" "B.Cu")
		(net "BIC_FWSPICK")
	)
	(segment
		(start 243.52631 -223.71812)
		(end 243.52631 -229.386638)
		(width 0.15494)
		(layer "In5.Cu")
		(net "BIC_FWSPICK")
	)
	(segment
		(start 243.52631 -229.386638)
		(end 244.304566 -230.164894)
		(width 0.15494)
		(layer "In5.Cu")
		(net "BIC_FWSPICK")
	)
	(segment
		(start 242.443 -248.3866)
		(end 241.216434 -249.613166)
		(width 0.15494)
		(layer "In5.Cu")
		(net "BIC_FWSPICK")
	)
	(segment
		(start 244.304566 -233.977434)
		(end 242.951 -235.331)
		(width 0.15494)
		(layer "In5.Cu")
		(net "BIC_FWSPICK")
	)
	(segment
		(start 241.216434 -249.613166)
		(end 241.216434 -251.857256)
		(width 0.15494)
		(layer "In5.Cu")
		(net "BIC_FWSPICK")
	)
	(segment
		(start 242.951 -236.956346)
		(end 242.443 -237.464346)
		(width 0.15494)
		(layer "In5.Cu")
		(net "BIC_FWSPICK")
	)
	(segment
		(start 243.47932 -223.67113)
		(end 243.52631 -223.71812)
		(width 0.15494)
		(layer "In5.Cu")
		(net "BIC_FWSPICK")
	)
	(segment
		(start 243.47932 -219.870528)
		(end 243.47932 -223.67113)
		(width 0.15494)
		(layer "In5.Cu")
		(net "BIC_FWSPICK")
	)
	(segment
		(start 244.304566 -230.164894)
		(end 244.304566 -233.977434)
		(width 0.15494)
		(layer "In5.Cu")
		(net "BIC_FWSPICK")
	)
	(segment
		(start 242.443 -237.464346)
		(end 242.443 -248.3866)
		(width 0.15494)
		(layer "In5.Cu")
		(net "BIC_FWSPICK")
	)
	(segment
		(start 242.951 -235.331)
		(end 242.951 -236.956346)
		(width 0.15494)
		(layer "In5.Cu")
		(net "BIC_FWSPICK")
	)
	(segment
		(start 242.7859 -219.177108)
		(end 243.47932 -219.870528)
		(width 0.15494)
		(layer "In5.Cu")
		(net "BIC_FWSPICK")
	)
	(segment
		(start 236.902498 -206.641446)
		(end 236.174534 -207.36941)
		(width 0.15494)
		(layer "In7.Cu")
		(net "BIC_FWSPICK")
	)
	(segment
		(start 243.70538 -200.31202)
		(end 242.951 -201.0664)
		(width 0.15494)
		(layer "In7.Cu")
		(net "BIC_FWSPICK")
	)
	(segment
		(start 240.518696 -206.641446)
		(end 236.902498 -206.641446)
		(width 0.15494)
		(layer "In7.Cu")
		(net "BIC_FWSPICK")
	)
	(segment
		(start 231.464866 -215.106758)
		(end 231.067356 -215.504268)
		(width 0.0889)
		(layer "In7.Cu")
		(net "BIC_FWSPICK")
	)
	(segment
		(start 231.464866 -212.925406)
		(end 231.464866 -215.106758)
		(width 0.0889)
		(layer "In7.Cu")
		(net "BIC_FWSPICK")
	)
	(segment
		(start 236.172248 -207.794606)
		(end 231.464866 -212.501988)
		(width 0.15494)
		(layer "In7.Cu")
		(net "BIC_FWSPICK")
	)
	(segment
		(start 241.7572 -201.4982)
		(end 241.7572 -202.6666)
		(width 0.15494)
		(layer "In7.Cu")
		(net "BIC_FWSPICK")
	)
	(segment
		(start 243.70538 -189.498986)
		(end 243.70538 -200.31202)
		(width 0.15494)
		(layer "In7.Cu")
		(net "BIC_FWSPICK")
	)
	(segment
		(start 236.174534 -207.36941)
		(end 236.174534 -207.72247)
		(width 0.15494)
		(layer "In7.Cu")
		(net "BIC_FWSPICK")
	)
	(segment
		(start 236.172248 -207.724756)
		(end 236.172248 -207.794606)
		(width 0.15494)
		(layer "In7.Cu")
		(net "BIC_FWSPICK")
	)
	(segment
		(start 241.182144 -203.241656)
		(end 241.182144 -205.977998)
		(width 0.15494)
		(layer "In7.Cu")
		(net "BIC_FWSPICK")
	)
	(segment
		(start 242.951 -201.0664)
		(end 242.189 -201.0664)
		(width 0.15494)
		(layer "In7.Cu")
		(net "BIC_FWSPICK")
	)
	(segment
		(start 241.7572 -202.6666)
		(end 241.182144 -203.241656)
		(width 0.15494)
		(layer "In7.Cu")
		(net "BIC_FWSPICK")
	)
	(segment
		(start 236.174534 -207.72247)
		(end 236.172248 -207.724756)
		(width 0.15494)
		(layer "In7.Cu")
		(net "BIC_FWSPICK")
	)
	(segment
		(start 241.182144 -205.977998)
		(end 240.518696 -206.641446)
		(width 0.15494)
		(layer "In7.Cu")
		(net "BIC_FWSPICK")
	)
	(segment
		(start 242.189 -201.0664)
		(end 241.7572 -201.4982)
		(width 0.15494)
		(layer "In7.Cu")
		(net "BIC_FWSPICK")
	)
	(segment
		(start 243.225066 -189.018672)
		(end 243.70538 -189.498986)
		(width 0.15494)
		(layer "In7.Cu")
		(net "BIC_FWSPICK")
	)
	(segment
		(start 231.464866 -212.501988)
		(end 231.464866 -212.925406)
		(width 0.15494)
		(layer "In7.Cu")
		(net "BIC_FWSPICK")
	)
	(segment
		(start 235.3056 -217.2716)
		(end 237.997492 -217.2716)
		(width 0.15494)
		(layer "In15.Cu")
		(net "BIC_FWSPICK")
	)
	(segment
		(start 237.997492 -217.2716)
		(end 240.186718 -219.460826)
		(width 0.15494)
		(layer "In15.Cu")
		(net "BIC_FWSPICK")
	)
	(segment
		(start 234.613196 -217.506804)
		(end 234.8484 -217.2716)
		(width 0.0889)
		(layer "In15.Cu")
		(net "BIC_FWSPICK")
	)
	(segment
		(start 234.8484 -217.2716)
		(end 235.3056 -217.2716)
		(width 0.0889)
		(layer "In15.Cu")
		(net "BIC_FWSPICK")
	)
	(segment
		(start 231.730804 -217.506804)
		(end 234.613196 -217.506804)
		(width 0.0889)
		(layer "In15.Cu")
		(net "BIC_FWSPICK")
	)
	(segment
		(start 231.4448 -217.2208)
		(end 231.730804 -217.506804)
		(width 0.0889)
		(layer "In15.Cu")
		(net "BIC_FWSPICK")
	)
	(segment
		(start 231.067356 -215.504268)
		(end 231.4448 -215.881712)
		(width 0.0889)
		(layer "In15.Cu")
		(net "BIC_FWSPICK")
	)
	(segment
		(start 231.4448 -215.881712)
		(end 231.4448 -217.2208)
		(width 0.0889)
		(layer "In15.Cu")
		(net "BIC_FWSPICK")
	)
	(segment
		(start 241.818414 -219.460826)
		(end 242.503452 -219.177108)
		(width 0.15494)
		(layer "In15.Cu")
		(net "BIC_FWSPICK")
	)
	(segment
		(start 240.186718 -219.460826)
		(end 241.818414 -219.460826)
		(width 0.15494)
		(layer "In15.Cu")
		(net "BIC_FWSPICK")
	)
	(segment
		(start 242.503452 -219.177108)
		(end 242.7859 -219.177108)
		(width 0.15494)
		(layer "In15.Cu")
		(net "BIC_FWSPICK")
	)
	(segment
		(start 340.295484 -83.814412)
		(end 340.295484 -83.146646)
		(width 0.13208)
		(layer "F.Cu")
		(net "SSD11_CLK_EN_R_N")
	)
	(segment
		(start 340.295484 -83.146646)
		(end 340.656926 -82.785204)
		(width 0.13208)
		(layer "F.Cu")
		(net "SSD11_CLK_EN_R_N")
	)
	(via
		(at 336.042 -206.15148)
		(size 0.508)
		(drill 0.254)
		(layers "F.Cu" "B.Cu")
		(net "SSD11_CLK_EN_R_N")
	)
	(via
		(at 340.656926 -82.785204)
		(size 0.508)
		(drill 0.254)
		(layers "F.Cu" "B.Cu")
		(net "SSD11_CLK_EN_R_N")
	)
	(segment
		(start 336.296 -207.37195)
		(end 336.296 -206.40548)
		(width 0.13208)
		(layer "B.Cu")
		(net "SSD11_CLK_EN_R_N")
	)
	(segment
		(start 336.296 -206.40548)
		(end 336.042 -206.15148)
		(width 0.13208)
		(layer "B.Cu")
		(net "SSD11_CLK_EN_R_N")
	)
	(segment
		(start 338.9884 -189.230254)
		(end 345.5162 -182.702454)
		(width 0.15494)
		(layer "In9.Cu")
		(net "SSD11_CLK_EN_R_N")
	)
	(segment
		(start 345.5162 -182.702454)
		(end 345.5162 -139.6492)
		(width 0.15494)
		(layer "In9.Cu")
		(net "SSD11_CLK_EN_R_N")
	)
	(segment
		(start 346.56522 -138.60018)
		(end 346.56522 -122.924316)
		(width 0.15494)
		(layer "In9.Cu")
		(net "SSD11_CLK_EN_R_N")
	)
	(segment
		(start 336.042 -206.15148)
		(end 336.042 -199.8726)
		(width 0.15494)
		(layer "In9.Cu")
		(net "SSD11_CLK_EN_R_N")
	)
	(segment
		(start 340.656926 -89.93378)
		(end 340.656926 -82.785204)
		(width 0.15494)
		(layer "In9.Cu")
		(net "SSD11_CLK_EN_R_N")
	)
	(segment
		(start 335.8134 -193.700654)
		(end 338.9884 -190.525654)
		(width 0.15494)
		(layer "In9.Cu")
		(net "SSD11_CLK_EN_R_N")
	)
	(segment
		(start 348.0308 -121.458736)
		(end 348.0308 -97.307654)
		(width 0.15494)
		(layer "In9.Cu")
		(net "SSD11_CLK_EN_R_N")
	)
	(segment
		(start 335.8134 -199.644)
		(end 335.8134 -193.700654)
		(width 0.15494)
		(layer "In9.Cu")
		(net "SSD11_CLK_EN_R_N")
	)
	(segment
		(start 346.56522 -122.924316)
		(end 348.0308 -121.458736)
		(width 0.15494)
		(layer "In9.Cu")
		(net "SSD11_CLK_EN_R_N")
	)
	(segment
		(start 336.042 -199.8726)
		(end 335.8134 -199.644)
		(width 0.15494)
		(layer "In9.Cu")
		(net "SSD11_CLK_EN_R_N")
	)
	(segment
		(start 338.9884 -190.525654)
		(end 338.9884 -189.230254)
		(width 0.15494)
		(layer "In9.Cu")
		(net "SSD11_CLK_EN_R_N")
	)
	(segment
		(start 345.5162 -139.6492)
		(end 346.56522 -138.60018)
		(width 0.15494)
		(layer "In9.Cu")
		(net "SSD11_CLK_EN_R_N")
	)
	(segment
		(start 348.0308 -97.307654)
		(end 340.656926 -89.93378)
		(width 0.15494)
		(layer "In9.Cu")
		(net "SSD11_CLK_EN_R_N")
	)
	(segment
		(start 340.161372 -193.46545)
		(end 338.370926 -193.46545)
		(width 0.13208)
		(layer "F.Cu")
		(net "FM_SLPS3_N")
	)
	(segment
		(start 337.841844 -193.994532)
		(end 335.604612 -193.994532)
		(width 0.13208)
		(layer "F.Cu")
		(net "FM_SLPS3_N")
	)
	(segment
		(start 338.370926 -193.46545)
		(end 337.841844 -193.994532)
		(width 0.13208)
		(layer "F.Cu")
		(net "FM_SLPS3_N")
	)
	(via
		(at 337.841844 -193.994532)
		(size 0.508)
		(drill 0.254)
		(layers "F.Cu" "B.Cu")
		(net "FM_SLPS3_N")
	)
	(segment
		(start 283.774896 -307.774848)
		(end 284.249876 -308.249828)
		(width 0.13208)
		(layer "F.Cu")
		(net "RST_PEX2_SYS_N")
	)
	(segment
		(start 326.007222 -235.475272)
		(end 326.007222 -236.183932)
		(width 0.13208)
		(layer "F.Cu")
		(net "RST_PEX2_SYS_N")
	)
	(via
		(at 326.007222 -236.183932)
		(size 0.508)
		(drill 0.254)
		(layers "F.Cu" "B.Cu")
		(net "RST_PEX2_SYS_N")
	)
	(via
		(at 283.774896 -307.774848)
		(size 0.4064)
		(drill 0.2032)
		(layers "F.Cu" "B.Cu")
		(net "RST_PEX2_SYS_N")
	)
	(via
		(at 265.80719 -262.772652)
		(size 0.508)
		(drill 0.254)
		(layers "F.Cu" "B.Cu")
		(net "RST_PEX2_SYS_N")
	)
	(via
		(at 270.987012 -236.704886)
		(size 0.508)
		(drill 0.254)
		(layers "F.Cu" "B.Cu")
		(net "RST_PEX2_SYS_N")
	)
	(segment
		(start 281.168348 -305.399948)
		(end 281.37993 -305.61153)
		(width 0.13208)
		(layer "B.Cu")
		(net "RST_PEX2_SYS_N")
	)
	(segment
		(start 282.981654 -306.3748)
		(end 283.241496 -306.634642)
		(width 0.13208)
		(layer "B.Cu")
		(net "RST_PEX2_SYS_N")
	)
	(segment
		(start 275.209 -303.8602)
		(end 275.336 -303.9872)
		(width 0.13208)
		(layer "B.Cu")
		(net "RST_PEX2_SYS_N")
	)
	(segment
		(start 275.209 -301.3202)
		(end 275.209 -303.8602)
		(width 0.13208)
		(layer "B.Cu")
		(net "RST_PEX2_SYS_N")
	)
	(segment
		(start 270.022574 -296.13352)
		(end 270.022574 -296.540174)
		(width 0.13208)
		(layer "B.Cu")
		(net "RST_PEX2_SYS_N")
	)
	(segment
		(start 278.409146 -304.4444)
		(end 280.162254 -304.4444)
		(width 0.13208)
		(layer "B.Cu")
		(net "RST_PEX2_SYS_N")
	)
	(segment
		(start 270.256 -296.7736)
		(end 270.4846 -296.7736)
		(width 0.13208)
		(layer "B.Cu")
		(net "RST_PEX2_SYS_N")
	)
	(segment
		(start 280.162254 -304.4444)
		(end 280.442162 -304.724308)
		(width 0.13208)
		(layer "B.Cu")
		(net "RST_PEX2_SYS_N")
	)
	(segment
		(start 274.301712 -300.870112)
		(end 274.4978 -301.0662)
		(width 0.13208)
		(layer "B.Cu")
		(net "RST_PEX2_SYS_N")
	)
	(segment
		(start 281.37993 -305.61153)
		(end 281.37993 -306.093876)
		(width 0.13208)
		(layer "B.Cu")
		(net "RST_PEX2_SYS_N")
	)
	(segment
		(start 267.838682 -294.263318)
		(end 267.838682 -294.330882)
		(width 0.13208)
		(layer "B.Cu")
		(net "RST_PEX2_SYS_N")
	)
	(segment
		(start 281.660854 -306.3748)
		(end 282.981654 -306.3748)
		(width 0.13208)
		(layer "B.Cu")
		(net "RST_PEX2_SYS_N")
	)
	(segment
		(start 283.241496 -306.634642)
		(end 283.241496 -307.241448)
		(width 0.13208)
		(layer "B.Cu")
		(net "RST_PEX2_SYS_N")
	)
	(segment
		(start 283.241496 -307.241448)
		(end 283.774896 -307.774848)
		(width 0.13208)
		(layer "B.Cu")
		(net "RST_PEX2_SYS_N")
	)
	(segment
		(start 268.613382 -295.038018)
		(end 269.139416 -295.564052)
		(width 0.13208)
		(layer "B.Cu")
		(net "RST_PEX2_SYS_N")
	)
	(segment
		(start 273.815556 -298.148502)
		(end 273.815556 -300.028356)
		(width 0.13208)
		(layer "B.Cu")
		(net "RST_PEX2_SYS_N")
	)
	(segment
		(start 280.812494 -305.399948)
		(end 281.168348 -305.399948)
		(width 0.13208)
		(layer "B.Cu")
		(net "RST_PEX2_SYS_N")
	)
	(segment
		(start 274.955 -301.0662)
		(end 275.209 -301.3202)
		(width 0.13208)
		(layer "B.Cu")
		(net "RST_PEX2_SYS_N")
	)
	(segment
		(start 270.022574 -296.540174)
		(end 270.256 -296.7736)
		(width 0.13208)
		(layer "B.Cu")
		(net "RST_PEX2_SYS_N")
	)
	(segment
		(start 273.532854 -297.8658)
		(end 273.815556 -298.148502)
		(width 0.13208)
		(layer "B.Cu")
		(net "RST_PEX2_SYS_N")
	)
	(segment
		(start 270.9672 -297.574462)
		(end 271.258538 -297.8658)
		(width 0.13208)
		(layer "B.Cu")
		(net "RST_PEX2_SYS_N")
	)
	(segment
		(start 274.4978 -301.0662)
		(end 274.955 -301.0662)
		(width 0.13208)
		(layer "B.Cu")
		(net "RST_PEX2_SYS_N")
	)
	(segment
		(start 269.139416 -295.564052)
		(end 269.453106 -295.564052)
		(width 0.13208)
		(layer "B.Cu")
		(net "RST_PEX2_SYS_N")
	)
	(segment
		(start 281.37993 -306.093876)
		(end 281.660854 -306.3748)
		(width 0.13208)
		(layer "B.Cu")
		(net "RST_PEX2_SYS_N")
	)
	(segment
		(start 267.838682 -294.330882)
		(end 268.545818 -295.038018)
		(width 0.13208)
		(layer "B.Cu")
		(net "RST_PEX2_SYS_N")
	)
	(segment
		(start 265.80719 -262.772652)
		(end 266.91971 -263.885172)
		(width 0.13208)
		(layer "B.Cu")
		(net "RST_PEX2_SYS_N")
	)
	(segment
		(start 277.951946 -303.9872)
		(end 278.409146 -304.4444)
		(width 0.13208)
		(layer "B.Cu")
		(net "RST_PEX2_SYS_N")
	)
	(segment
		(start 271.258538 -297.8658)
		(end 273.532854 -297.8658)
		(width 0.13208)
		(layer "B.Cu")
		(net "RST_PEX2_SYS_N")
	)
	(segment
		(start 273.815556 -300.028356)
		(end 274.301712 -300.514512)
		(width 0.13208)
		(layer "B.Cu")
		(net "RST_PEX2_SYS_N")
	)
	(segment
		(start 280.442162 -304.724308)
		(end 280.442162 -305.029616)
		(width 0.13208)
		(layer "B.Cu")
		(net "RST_PEX2_SYS_N")
	)
	(segment
		(start 270.9672 -297.2562)
		(end 270.9672 -297.574462)
		(width 0.13208)
		(layer "B.Cu")
		(net "RST_PEX2_SYS_N")
	)
	(segment
		(start 275.336 -303.9872)
		(end 277.951946 -303.9872)
		(width 0.13208)
		(layer "B.Cu")
		(net "RST_PEX2_SYS_N")
	)
	(segment
		(start 269.453106 -295.564052)
		(end 270.022574 -296.13352)
		(width 0.13208)
		(layer "B.Cu")
		(net "RST_PEX2_SYS_N")
	)
	(segment
		(start 280.442162 -305.029616)
		(end 280.812494 -305.399948)
		(width 0.13208)
		(layer "B.Cu")
		(net "RST_PEX2_SYS_N")
	)
	(segment
		(start 270.4846 -296.7736)
		(end 270.9672 -297.2562)
		(width 0.13208)
		(layer "B.Cu")
		(net "RST_PEX2_SYS_N")
	)
	(segment
		(start 274.301712 -300.514512)
		(end 274.301712 -300.870112)
		(width 0.13208)
		(layer "B.Cu")
		(net "RST_PEX2_SYS_N")
	)
	(segment
		(start 268.545818 -295.038018)
		(end 268.613382 -295.038018)
		(width 0.13208)
		(layer "B.Cu")
		(net "RST_PEX2_SYS_N")
	)
	(segment
		(start 266.91971 -293.344346)
		(end 267.838682 -294.263318)
		(width 0.13208)
		(layer "B.Cu")
		(net "RST_PEX2_SYS_N")
	)
	(segment
		(start 266.91971 -263.885172)
		(end 266.91971 -293.344346)
		(width 0.13208)
		(layer "B.Cu")
		(net "RST_PEX2_SYS_N")
	)
	(segment
		(start 272.961354 -265.239754)
		(end 273.75993 -265.239754)
		(width 0.15494)
		(layer "In5.Cu")
		(net "RST_PEX2_SYS_N")
	)
	(segment
		(start 271.242536 -263.520936)
		(end 272.961354 -265.239754)
		(width 0.15494)
		(layer "In5.Cu")
		(net "RST_PEX2_SYS_N")
	)
	(segment
		(start 265.80719 -262.772652)
		(end 265.914632 -262.66521)
		(width 0.15494)
		(layer "In5.Cu")
		(net "RST_PEX2_SYS_N")
	)
	(segment
		(start 273.75993 -265.239754)
		(end 275.215096 -263.784588)
		(width 0.15494)
		(layer "In5.Cu")
		(net "RST_PEX2_SYS_N")
	)
	(segment
		(start 275.215096 -249.260614)
		(end 270.840962 -244.88648)
		(width 0.15494)
		(layer "In5.Cu")
		(net "RST_PEX2_SYS_N")
	)
	(segment
		(start 270.840962 -236.850936)
		(end 270.987012 -236.704886)
		(width 0.15494)
		(layer "In5.Cu")
		(net "RST_PEX2_SYS_N")
	)
	(segment
		(start 271.242536 -263.082532)
		(end 271.242536 -263.520936)
		(width 0.15494)
		(layer "In5.Cu")
		(net "RST_PEX2_SYS_N")
	)
	(segment
		(start 275.215096 -263.784588)
		(end 275.215096 -249.260614)
		(width 0.15494)
		(layer "In5.Cu")
		(net "RST_PEX2_SYS_N")
	)
	(segment
		(start 265.914632 -262.66521)
		(end 270.825214 -262.66521)
		(width 0.15494)
		(layer "In5.Cu")
		(net "RST_PEX2_SYS_N")
	)
	(segment
		(start 270.840962 -244.88648)
		(end 270.840962 -236.850936)
		(width 0.15494)
		(layer "In5.Cu")
		(net "RST_PEX2_SYS_N")
	)
	(segment
		(start 270.825214 -262.66521)
		(end 271.242536 -263.082532)
		(width 0.15494)
		(layer "In5.Cu")
		(net "RST_PEX2_SYS_N")
	)
	(segment
		(start 319.62344 -236.380528)
		(end 320.830194 -237.587282)
		(width 0.15494)
		(layer "In15.Cu")
		(net "RST_PEX2_SYS_N")
	)
	(segment
		(start 323.955918 -237.587282)
		(end 324.876922 -236.667802)
		(width 0.15494)
		(layer "In15.Cu")
		(net "RST_PEX2_SYS_N")
	)
	(segment
		(start 324.876922 -236.667802)
		(end 325.523352 -236.667802)
		(width 0.15494)
		(layer "In15.Cu")
		(net "RST_PEX2_SYS_N")
	)
	(segment
		(start 270.987012 -236.704886)
		(end 271.31137 -236.380528)
		(width 0.15494)
		(layer "In15.Cu")
		(net "RST_PEX2_SYS_N")
	)
	(segment
		(start 320.830194 -237.587282)
		(end 323.955918 -237.587282)
		(width 0.15494)
		(layer "In15.Cu")
		(net "RST_PEX2_SYS_N")
	)
	(segment
		(start 271.31137 -236.380528)
		(end 319.62344 -236.380528)
		(width 0.15494)
		(layer "In15.Cu")
		(net "RST_PEX2_SYS_N")
	)
	(segment
		(start 325.523352 -236.667802)
		(end 326.007222 -236.183932)
		(width 0.15494)
		(layer "In15.Cu")
		(net "RST_PEX2_SYS_N")
	)
	(segment
		(start 342.195912 -82.118454)
		(end 342.38946 -81.924906)
		(width 0.13208)
		(layer "F.Cu")
		(net "SSD10_CLK_EN_R_N")
	)
	(segment
		(start 339.895688 -83.814412)
		(end 339.895688 -82.540602)
		(width 0.13208)
		(layer "F.Cu")
		(net "SSD10_CLK_EN_R_N")
	)
	(segment
		(start 338.582 -204.83195)
		(end 338.582 -204.216)
		(width 0.13208)
		(layer "F.Cu")
		(net "SSD10_CLK_EN_R_N")
	)
	(segment
		(start 339.895688 -82.540602)
		(end 340.317836 -82.118454)
		(width 0.13208)
		(layer "F.Cu")
		(net "SSD10_CLK_EN_R_N")
	)
	(segment
		(start 340.317836 -82.118454)
		(end 342.195912 -82.118454)
		(width 0.13208)
		(layer "F.Cu")
		(net "SSD10_CLK_EN_R_N")
	)
	(via
		(at 342.38946 -81.924906)
		(size 0.508)
		(drill 0.254)
		(layers "F.Cu" "B.Cu")
		(net "SSD10_CLK_EN_R_N")
	)
	(via
		(at 338.582 -204.216)
		(size 0.508)
		(drill 0.254)
		(layers "F.Cu" "B.Cu")
		(net "SSD10_CLK_EN_R_N")
	)
	(segment
		(start 340.916514 -195.22694)
		(end 342.125808 -194.017646)
		(width 0.15494)
		(layer "In9.Cu")
		(net "SSD10_CLK_EN_R_N")
	)
	(segment
		(start 349.8596 -102.082346)
		(end 350.3676 -101.574346)
		(width 0.15494)
		(layer "In9.Cu")
		(net "SSD10_CLK_EN_R_N")
	)
	(segment
		(start 347.0275 -140.244576)
		(end 348.0562 -139.215876)
		(width 0.15494)
		(layer "In9.Cu")
		(net "SSD10_CLK_EN_R_N")
	)
	(segment
		(start 348.0562 -139.215876)
		(end 348.0562 -123.5456)
		(width 0.15494)
		(layer "In9.Cu")
		(net "SSD10_CLK_EN_R_N")
	)
	(segment
		(start 342.38946 -82.715354)
		(end 342.38946 -81.924906)
		(width 0.15494)
		(layer "In9.Cu")
		(net "SSD10_CLK_EN_R_N")
	)
	(segment
		(start 338.582 -204.216)
		(end 340.107524 -202.690476)
		(width 0.15494)
		(layer "In9.Cu")
		(net "SSD10_CLK_EN_R_N")
	)
	(segment
		(start 347.0275 -186.7281)
		(end 347.0275 -140.244576)
		(width 0.15494)
		(layer "In9.Cu")
		(net "SSD10_CLK_EN_R_N")
	)
	(segment
		(start 340.107524 -199.62749)
		(end 340.916514 -198.8185)
		(width 0.15494)
		(layer "In9.Cu")
		(net "SSD10_CLK_EN_R_N")
	)
	(segment
		(start 350.3676 -98.5012)
		(end 344.272108 -92.405708)
		(width 0.15494)
		(layer "In9.Cu")
		(net "SSD10_CLK_EN_R_N")
	)
	(segment
		(start 348.0562 -123.5456)
		(end 349.8596 -121.7422)
		(width 0.15494)
		(layer "In9.Cu")
		(net "SSD10_CLK_EN_R_N")
	)
	(segment
		(start 340.107524 -202.690476)
		(end 340.107524 -199.62749)
		(width 0.15494)
		(layer "In9.Cu")
		(net "SSD10_CLK_EN_R_N")
	)
	(segment
		(start 342.125808 -191.629792)
		(end 347.0275 -186.7281)
		(width 0.15494)
		(layer "In9.Cu")
		(net "SSD10_CLK_EN_R_N")
	)
	(segment
		(start 340.916514 -198.8185)
		(end 340.916514 -195.22694)
		(width 0.15494)
		(layer "In9.Cu")
		(net "SSD10_CLK_EN_R_N")
	)
	(segment
		(start 342.125808 -194.017646)
		(end 342.125808 -191.629792)
		(width 0.15494)
		(layer "In9.Cu")
		(net "SSD10_CLK_EN_R_N")
	)
	(segment
		(start 350.3676 -101.574346)
		(end 350.3676 -98.5012)
		(width 0.15494)
		(layer "In9.Cu")
		(net "SSD10_CLK_EN_R_N")
	)
	(segment
		(start 344.272108 -92.405708)
		(end 344.272108 -84.598002)
		(width 0.15494)
		(layer "In9.Cu")
		(net "SSD10_CLK_EN_R_N")
	)
	(segment
		(start 344.272108 -84.598002)
		(end 342.38946 -82.715354)
		(width 0.15494)
		(layer "In9.Cu")
		(net "SSD10_CLK_EN_R_N")
	)
	(segment
		(start 349.8596 -121.7422)
		(end 349.8596 -102.082346)
		(width 0.15494)
		(layer "In9.Cu")
		(net "SSD10_CLK_EN_R_N")
	)
	(segment
		(start 338.30895 -191.43345)
		(end 339.511894 -191.43345)
		(width 0.13208)
		(layer "F.Cu")
		(net "PWRGD_DSW_PWROK")
	)
	(segment
		(start 335.604612 -192.694306)
		(end 337.048094 -192.694306)
		(width 0.13208)
		(layer "F.Cu")
		(net "PWRGD_DSW_PWROK")
	)
	(segment
		(start 337.048094 -192.694306)
		(end 338.30895 -191.43345)
		(width 0.13208)
		(layer "F.Cu")
		(net "PWRGD_DSW_PWROK")
	)
	(segment
		(start 339.511894 -191.43345)
		(end 340.161372 -191.43345)
		(width 0.13208)
		(layer "F.Cu")
		(net "PWRGD_DSW_PWROK")
	)
	(via
		(at 339.511894 -191.43345)
		(size 0.508)
		(drill 0.254)
		(layers "F.Cu" "B.Cu")
		(net "PWRGD_DSW_PWROK")
	)
	(segment
		(start 399.874994 -307.774848)
		(end 400.349974 -308.249828)
		(width 0.13208)
		(layer "F.Cu")
		(net "RST_PEX3_SYS_N")
	)
	(segment
		(start 323.255894 -236.174534)
		(end 322.959222 -235.877862)
		(width 0.13208)
		(layer "F.Cu")
		(net "RST_PEX3_SYS_N")
	)
	(segment
		(start 322.959222 -235.877862)
		(end 322.959222 -235.475272)
		(width 0.13208)
		(layer "F.Cu")
		(net "RST_PEX3_SYS_N")
	)
	(segment
		(start 323.255894 -236.183932)
		(end 323.255894 -236.174534)
		(width 0.13208)
		(layer "F.Cu")
		(net "RST_PEX3_SYS_N")
	)
	(via
		(at 370.167408 -247.974358)
		(size 0.508)
		(drill 0.254)
		(layers "F.Cu" "B.Cu")
		(net "RST_PEX3_SYS_N")
	)
	(via
		(at 399.874994 -307.774848)
		(size 0.4064)
		(drill 0.2032)
		(layers "F.Cu" "B.Cu")
		(net "RST_PEX3_SYS_N")
	)
	(via
		(at 328.328274 -248.88063)
		(size 0.508)
		(drill 0.254)
		(layers "F.Cu" "B.Cu")
		(net "RST_PEX3_SYS_N")
	)
	(via
		(at 323.255894 -236.183932)
		(size 0.508)
		(drill 0.254)
		(layers "F.Cu" "B.Cu")
		(net "RST_PEX3_SYS_N")
	)
	(via
		(at 381.907288 -262.772652)
		(size 0.508)
		(drill 0.254)
		(layers "F.Cu" "B.Cu")
		(net "RST_PEX3_SYS_N")
	)
	(segment
		(start 386.122672 -296.545762)
		(end 386.122672 -296.157396)
		(width 0.13208)
		(layer "B.Cu")
		(net "RST_PEX3_SYS_N")
	)
	(segment
		(start 394.381482 -304.440082)
		(end 393.9032 -303.9618)
		(width 0.13208)
		(layer "B.Cu")
		(net "RST_PEX3_SYS_N")
	)
	(segment
		(start 385.529328 -295.564052)
		(end 385.098544 -295.564052)
		(width 0.13208)
		(layer "B.Cu")
		(net "RST_PEX3_SYS_N")
	)
	(segment
		(start 390.360662 -299.378116)
		(end 390.836912 -298.901866)
		(width 0.13208)
		(layer "B.Cu")
		(net "RST_PEX3_SYS_N")
	)
	(segment
		(start 387.036056 -297.050968)
		(end 386.758688 -296.7736)
		(width 0.13208)
		(layer "B.Cu")
		(net "RST_PEX3_SYS_N")
	)
	(segment
		(start 386.35051 -296.7736)
		(end 386.122672 -296.545762)
		(width 0.13208)
		(layer "B.Cu")
		(net "RST_PEX3_SYS_N")
	)
	(segment
		(start 390.836912 -297.927522)
		(end 390.709912 -297.800522)
		(width 0.13208)
		(layer "B.Cu")
		(net "RST_PEX3_SYS_N")
	)
	(segment
		(start 390.360662 -300.825408)
		(end 390.360662 -299.378116)
		(width 0.13208)
		(layer "B.Cu")
		(net "RST_PEX3_SYS_N")
	)
	(segment
		(start 380.792482 -291.167312)
		(end 380.792482 -280.19375)
		(width 0.13208)
		(layer "B.Cu")
		(net "RST_PEX3_SYS_N")
	)
	(segment
		(start 397.480028 -306.20208)
		(end 397.480028 -305.526948)
		(width 0.13208)
		(layer "B.Cu")
		(net "RST_PEX3_SYS_N")
	)
	(segment
		(start 382.229106 -278.757126)
		(end 382.229106 -274.174204)
		(width 0.13208)
		(layer "B.Cu")
		(net "RST_PEX3_SYS_N")
	)
	(segment
		(start 383.28727 -264.152634)
		(end 381.907288 -262.772652)
		(width 0.13208)
		(layer "B.Cu")
		(net "RST_PEX3_SYS_N")
	)
	(segment
		(start 382.773174 -293.238682)
		(end 382.773174 -293.148004)
		(width 0.13208)
		(layer "B.Cu")
		(net "RST_PEX3_SYS_N")
	)
	(segment
		(start 383.28727 -273.11604)
		(end 383.28727 -264.152634)
		(width 0.13208)
		(layer "B.Cu")
		(net "RST_PEX3_SYS_N")
	)
	(segment
		(start 391.032746 -301.0662)
		(end 390.601454 -301.0662)
		(width 0.13208)
		(layer "B.Cu")
		(net "RST_PEX3_SYS_N")
	)
	(segment
		(start 399.393664 -307.293518)
		(end 399.393664 -306.600098)
		(width 0.13208)
		(layer "B.Cu")
		(net "RST_PEX3_SYS_N")
	)
	(segment
		(start 385.098544 -295.564052)
		(end 382.773174 -293.238682)
		(width 0.13208)
		(layer "B.Cu")
		(net "RST_PEX3_SYS_N")
	)
	(segment
		(start 390.836912 -298.901866)
		(end 390.836912 -297.927522)
		(width 0.13208)
		(layer "B.Cu")
		(net "RST_PEX3_SYS_N")
	)
	(segment
		(start 396.54226 -305.162204)
		(end 396.54226 -304.703988)
		(width 0.13208)
		(layer "B.Cu")
		(net "RST_PEX3_SYS_N")
	)
	(segment
		(start 380.792482 -280.19375)
		(end 382.229106 -278.757126)
		(width 0.13208)
		(layer "B.Cu")
		(net "RST_PEX3_SYS_N")
	)
	(segment
		(start 396.780004 -305.399948)
		(end 396.54226 -305.162204)
		(width 0.13208)
		(layer "B.Cu")
		(net "RST_PEX3_SYS_N")
	)
	(segment
		(start 386.758688 -296.7736)
		(end 386.35051 -296.7736)
		(width 0.13208)
		(layer "B.Cu")
		(net "RST_PEX3_SYS_N")
	)
	(segment
		(start 393.9032 -303.9618)
		(end 391.4902 -303.9618)
		(width 0.13208)
		(layer "B.Cu")
		(net "RST_PEX3_SYS_N")
	)
	(segment
		(start 382.773174 -293.148004)
		(end 380.792482 -291.167312)
		(width 0.13208)
		(layer "B.Cu")
		(net "RST_PEX3_SYS_N")
	)
	(segment
		(start 391.4902 -303.9618)
		(end 391.3632 -303.8348)
		(width 0.13208)
		(layer "B.Cu")
		(net "RST_PEX3_SYS_N")
	)
	(segment
		(start 386.122672 -296.157396)
		(end 385.529328 -295.564052)
		(width 0.13208)
		(layer "B.Cu")
		(net "RST_PEX3_SYS_N")
	)
	(segment
		(start 399.874994 -307.774848)
		(end 399.393664 -307.293518)
		(width 0.13208)
		(layer "B.Cu")
		(net "RST_PEX3_SYS_N")
	)
	(segment
		(start 391.3632 -301.396654)
		(end 391.032746 -301.0662)
		(width 0.13208)
		(layer "B.Cu")
		(net "RST_PEX3_SYS_N")
	)
	(segment
		(start 397.480028 -305.526948)
		(end 397.353028 -305.399948)
		(width 0.13208)
		(layer "B.Cu")
		(net "RST_PEX3_SYS_N")
	)
	(segment
		(start 387.036056 -297.592242)
		(end 387.036056 -297.050968)
		(width 0.13208)
		(layer "B.Cu")
		(net "RST_PEX3_SYS_N")
	)
	(segment
		(start 391.3632 -303.8348)
		(end 391.3632 -301.396654)
		(width 0.13208)
		(layer "B.Cu")
		(net "RST_PEX3_SYS_N")
	)
	(segment
		(start 382.229106 -274.174204)
		(end 383.28727 -273.11604)
		(width 0.13208)
		(layer "B.Cu")
		(net "RST_PEX3_SYS_N")
	)
	(segment
		(start 397.353028 -305.399948)
		(end 396.780004 -305.399948)
		(width 0.13208)
		(layer "B.Cu")
		(net "RST_PEX3_SYS_N")
	)
	(segment
		(start 396.278354 -304.440082)
		(end 394.381482 -304.440082)
		(width 0.13208)
		(layer "B.Cu")
		(net "RST_PEX3_SYS_N")
	)
	(segment
		(start 390.709912 -297.800522)
		(end 387.244336 -297.800522)
		(width 0.13208)
		(layer "B.Cu")
		(net "RST_PEX3_SYS_N")
	)
	(segment
		(start 399.158714 -306.365148)
		(end 397.643096 -306.365148)
		(width 0.13208)
		(layer "B.Cu")
		(net "RST_PEX3_SYS_N")
	)
	(segment
		(start 399.393664 -306.600098)
		(end 399.158714 -306.365148)
		(width 0.13208)
		(layer "B.Cu")
		(net "RST_PEX3_SYS_N")
	)
	(segment
		(start 387.244336 -297.800522)
		(end 387.036056 -297.592242)
		(width 0.13208)
		(layer "B.Cu")
		(net "RST_PEX3_SYS_N")
	)
	(segment
		(start 397.643096 -306.365148)
		(end 397.480028 -306.20208)
		(width 0.13208)
		(layer "B.Cu")
		(net "RST_PEX3_SYS_N")
	)
	(segment
		(start 396.54226 -304.703988)
		(end 396.278354 -304.440082)
		(width 0.13208)
		(layer "B.Cu")
		(net "RST_PEX3_SYS_N")
	)
	(segment
		(start 390.601454 -301.0662)
		(end 390.360662 -300.825408)
		(width 0.13208)
		(layer "B.Cu")
		(net "RST_PEX3_SYS_N")
	)
	(segment
		(start 369.783614 -257.730752)
		(end 369.783614 -254.723392)
		(width 0.15494)
		(layer "In5.Cu")
		(net "RST_PEX3_SYS_N")
	)
	(segment
		(start 378.488702 -262.351774)
		(end 371.859302 -262.351774)
		(width 0.15494)
		(layer "In5.Cu")
		(net "RST_PEX3_SYS_N")
	)
	(segment
		(start 378.90958 -262.772652)
		(end 378.488702 -262.351774)
		(width 0.15494)
		(layer "In5.Cu")
		(net "RST_PEX3_SYS_N")
	)
	(segment
		(start 369.783614 -254.723392)
		(end 370.565426 -253.94158)
		(width 0.15494)
		(layer "In5.Cu")
		(net "RST_PEX3_SYS_N")
	)
	(segment
		(start 371.859302 -262.351774)
		(end 371.454934 -261.947406)
		(width 0.15494)
		(layer "In5.Cu")
		(net "RST_PEX3_SYS_N")
	)
	(segment
		(start 371.454934 -261.947406)
		(end 371.454934 -259.402072)
		(width 0.15494)
		(layer "In5.Cu")
		(net "RST_PEX3_SYS_N")
	)
	(segment
		(start 370.565426 -252.63856)
		(end 369.783614 -251.856748)
		(width 0.15494)
		(layer "In5.Cu")
		(net "RST_PEX3_SYS_N")
	)
	(segment
		(start 369.783614 -251.856748)
		(end 369.783614 -248.358152)
		(width 0.15494)
		(layer "In5.Cu")
		(net "RST_PEX3_SYS_N")
	)
	(segment
		(start 370.565426 -253.94158)
		(end 370.565426 -252.63856)
		(width 0.15494)
		(layer "In5.Cu")
		(net "RST_PEX3_SYS_N")
	)
	(segment
		(start 371.454934 -259.402072)
		(end 369.783614 -257.730752)
		(width 0.15494)
		(layer "In5.Cu")
		(net "RST_PEX3_SYS_N")
	)
	(segment
		(start 369.783614 -248.358152)
		(end 370.167408 -247.974358)
		(width 0.15494)
		(layer "In5.Cu")
		(net "RST_PEX3_SYS_N")
	)
	(segment
		(start 381.907288 -262.772652)
		(end 378.90958 -262.772652)
		(width 0.15494)
		(layer "In5.Cu")
		(net "RST_PEX3_SYS_N")
	)
	(segment
		(start 326.91578 -248.88063)
		(end 322.959222 -244.924072)
		(width 0.15494)
		(layer "In7.Cu")
		(net "RST_PEX3_SYS_N")
	)
	(segment
		(start 322.959222 -236.471206)
		(end 323.255894 -236.174534)
		(width 0.15494)
		(layer "In7.Cu")
		(net "RST_PEX3_SYS_N")
	)
	(segment
		(start 323.255894 -236.174534)
		(end 323.255894 -236.183932)
		(width 0.15494)
		(layer "In7.Cu")
		(net "RST_PEX3_SYS_N")
	)
	(segment
		(start 328.328274 -248.88063)
		(end 326.91578 -248.88063)
		(width 0.15494)
		(layer "In7.Cu")
		(net "RST_PEX3_SYS_N")
	)
	(segment
		(start 322.959222 -244.924072)
		(end 322.959222 -236.471206)
		(width 0.15494)
		(layer "In7.Cu")
		(net "RST_PEX3_SYS_N")
	)
	(segment
		(start 330.255118 -248.88063)
		(end 328.328274 -248.88063)
		(width 0.15494)
		(layer "In11.Cu")
		(net "RST_PEX3_SYS_N")
	)
	(segment
		(start 370.167408 -247.974358)
		(end 369.58016 -247.38711)
		(width 0.15494)
		(layer "In11.Cu")
		(net "RST_PEX3_SYS_N")
	)
	(segment
		(start 369.58016 -247.38711)
		(end 331.748638 -247.38711)
		(width 0.15494)
		(layer "In11.Cu")
		(net "RST_PEX3_SYS_N")
	)
	(segment
		(start 331.748638 -247.38711)
		(end 330.255118 -248.88063)
		(width 0.15494)
		(layer "In11.Cu")
		(net "RST_PEX3_SYS_N")
	)
	(segment
		(start 237.6932 -216.328244)
		(end 237.21949 -216.328244)
		(width 0.254)
		(layer "F.Cu")
		(net "BIC_ADCVREFN0")
	)
	(segment
		(start 237.044484 -216.153238)
		(end 235.716826 -216.153238)
		(width 0.254)
		(layer "F.Cu")
		(net "BIC_ADCVREFN0")
	)
	(segment
		(start 237.21949 -216.328244)
		(end 237.044484 -216.153238)
		(width 0.254)
		(layer "F.Cu")
		(net "BIC_ADCVREFN0")
	)
	(segment
		(start 239.181894 -218.36888)
		(end 239.181894 -217.816938)
		(width 0.254)
		(layer "F.Cu")
		(net "BIC_ADCVREFN0")
	)
	(segment
		(start 240.675414 -218.80576)
		(end 240.567464 -218.69781)
		(width 0.254)
		(layer "F.Cu")
		(net "BIC_ADCVREFN0")
	)
	(segment
		(start 238.516668 -217.151712)
		(end 237.6932 -216.328244)
		(width 0.254)
		(layer "F.Cu")
		(net "BIC_ADCVREFN0")
	)
	(segment
		(start 239.703864 -218.69781)
		(end 239.510824 -218.69781)
		(width 0.254)
		(layer "F.Cu")
		(net "BIC_ADCVREFN0")
	)
	(segment
		(start 240.567464 -218.69781)
		(end 239.703864 -218.69781)
		(width 0.254)
		(layer "F.Cu")
		(net "BIC_ADCVREFN0")
	)
	(segment
		(start 235.716826 -216.153238)
		(end 235.467652 -215.904064)
		(width 0.254)
		(layer "F.Cu")
		(net "BIC_ADCVREFN0")
	)
	(segment
		(start 239.181894 -217.816938)
		(end 238.516668 -217.151712)
		(width 0.254)
		(layer "F.Cu")
		(net "BIC_ADCVREFN0")
	)
	(segment
		(start 239.510824 -218.69781)
		(end 239.181894 -218.36888)
		(width 0.254)
		(layer "F.Cu")
		(net "BIC_ADCVREFN0")
	)
	(via
		(at 238.516668 -217.151712)
		(size 0.762)
		(drill 0.381)
		(layers "F.Cu" "B.Cu")
		(net "BIC_ADCVREFN0")
	)
	(segment
		(start 337.895692 -82.485484)
		(end 337.895692 -83.814412)
		(width 0.13208)
		(layer "F.Cu")
		(net "SSD9_CLK_EN_R_N")
	)
	(segment
		(start 338.419186 -81.96199)
		(end 337.895692 -82.485484)
		(width 0.13208)
		(layer "F.Cu")
		(net "SSD9_CLK_EN_R_N")
	)
	(segment
		(start 336.55 -204.83195)
		(end 336.55 -204.216)
		(width 0.13208)
		(layer "F.Cu")
		(net "SSD9_CLK_EN_R_N")
	)
	(via
		(at 336.55 -204.216)
		(size 0.508)
		(drill 0.254)
		(layers "F.Cu" "B.Cu")
		(net "SSD9_CLK_EN_R_N")
	)
	(via
		(at 338.419186 -81.96199)
		(size 0.508)
		(drill 0.254)
		(layers "F.Cu" "B.Cu")
		(net "SSD9_CLK_EN_R_N")
	)
	(segment
		(start 337.058 -193.167)
		(end 341.3252 -188.8998)
		(width 0.15494)
		(layer "In9.Cu")
		(net "SSD9_CLK_EN_R_N")
	)
	(segment
		(start 345.8972 -184.988454)
		(end 345.8972 -139.852654)
		(width 0.15494)
		(layer "In9.Cu")
		(net "SSD9_CLK_EN_R_N")
	)
	(segment
		(start 348.4118 -121.584466)
		(end 348.4118 -97.1296)
		(width 0.15494)
		(layer "In9.Cu")
		(net "SSD9_CLK_EN_R_N")
	)
	(segment
		(start 348.4118 -97.1296)
		(end 343.825322 -92.543122)
		(width 0.15494)
		(layer "In9.Cu")
		(net "SSD9_CLK_EN_R_N")
	)
	(segment
		(start 343.825322 -92.543122)
		(end 343.825322 -85.126068)
		(width 0.15494)
		(layer "In9.Cu")
		(net "SSD9_CLK_EN_R_N")
	)
	(segment
		(start 345.8972 -139.852654)
		(end 346.92336 -138.826494)
		(width 0.15494)
		(layer "In9.Cu")
		(net "SSD9_CLK_EN_R_N")
	)
	(segment
		(start 346.92336 -138.826494)
		(end 346.92336 -123.072906)
		(width 0.15494)
		(layer "In9.Cu")
		(net "SSD9_CLK_EN_R_N")
	)
	(segment
		(start 341.3252 -188.8998)
		(end 341.985854 -188.8998)
		(width 0.15494)
		(layer "In9.Cu")
		(net "SSD9_CLK_EN_R_N")
	)
	(segment
		(start 346.92336 -123.072906)
		(end 348.4118 -121.584466)
		(width 0.15494)
		(layer "In9.Cu")
		(net "SSD9_CLK_EN_R_N")
	)
	(segment
		(start 340.661244 -81.96199)
		(end 338.419186 -81.96199)
		(width 0.15494)
		(layer "In9.Cu")
		(net "SSD9_CLK_EN_R_N")
	)
	(segment
		(start 343.825322 -85.126068)
		(end 340.661244 -81.96199)
		(width 0.15494)
		(layer "In9.Cu")
		(net "SSD9_CLK_EN_R_N")
	)
	(segment
		(start 337.058 -203.2)
		(end 337.058 -193.167)
		(width 0.15494)
		(layer "In9.Cu")
		(net "SSD9_CLK_EN_R_N")
	)
	(segment
		(start 336.55 -204.216)
		(end 336.55 -203.708)
		(width 0.15494)
		(layer "In9.Cu")
		(net "SSD9_CLK_EN_R_N")
	)
	(segment
		(start 341.985854 -188.8998)
		(end 345.8972 -184.988454)
		(width 0.15494)
		(layer "In9.Cu")
		(net "SSD9_CLK_EN_R_N")
	)
	(segment
		(start 336.55 -203.708)
		(end 337.058 -203.2)
		(width 0.15494)
		(layer "In9.Cu")
		(net "SSD9_CLK_EN_R_N")
	)
	(segment
		(start 167.675052 -307.774848)
		(end 168.150032 -308.249828)
		(width 0.13208)
		(layer "F.Cu")
		(net "RST_PEX1_SYS_N")
	)
	(segment
		(start 324.991222 -235.475272)
		(end 324.991222 -236.183932)
		(width 0.13208)
		(layer "F.Cu")
		(net "RST_PEX1_SYS_N")
	)
	(via
		(at 324.991222 -236.183932)
		(size 0.508)
		(drill 0.254)
		(layers "F.Cu" "B.Cu")
		(net "RST_PEX1_SYS_N")
	)
	(via
		(at 149.32152 -262.847836)
		(size 0.508)
		(drill 0.254)
		(layers "F.Cu" "B.Cu")
		(net "RST_PEX1_SYS_N")
	)
	(via
		(at 167.675052 -307.774848)
		(size 0.4064)
		(drill 0.2032)
		(layers "F.Cu" "B.Cu")
		(net "RST_PEX1_SYS_N")
	)
	(via
		(at 143.29791 -227.180394)
		(size 0.508)
		(drill 0.254)
		(layers "F.Cu" "B.Cu")
		(net "RST_PEX1_SYS_N")
	)
	(segment
		(start 154.150568 -296.7736)
		(end 153.92273 -296.545762)
		(width 0.13208)
		(layer "B.Cu")
		(net "RST_PEX1_SYS_N")
	)
	(segment
		(start 153.92273 -296.545762)
		(end 153.92273 -296.157396)
		(width 0.13208)
		(layer "B.Cu")
		(net "RST_PEX1_SYS_N")
	)
	(segment
		(start 154.813 -297.569128)
		(end 154.813 -297.027854)
		(width 0.13208)
		(layer "B.Cu")
		(net "RST_PEX1_SYS_N")
	)
	(segment
		(start 164.342318 -305.162204)
		(end 164.342318 -304.703988)
		(width 0.13208)
		(layer "B.Cu")
		(net "RST_PEX1_SYS_N")
	)
	(segment
		(start 150.029164 -274.174204)
		(end 150.876 -273.327368)
		(width 0.13208)
		(layer "B.Cu")
		(net "RST_PEX1_SYS_N")
	)
	(segment
		(start 154.558746 -296.7736)
		(end 154.150568 -296.7736)
		(width 0.13208)
		(layer "B.Cu")
		(net "RST_PEX1_SYS_N")
	)
	(segment
		(start 152.898602 -295.564052)
		(end 150.573232 -293.238682)
		(width 0.13208)
		(layer "B.Cu")
		(net "RST_PEX1_SYS_N")
	)
	(segment
		(start 161.671 -303.911)
		(end 159.254698 -303.911)
		(width 0.13208)
		(layer "B.Cu")
		(net "RST_PEX1_SYS_N")
	)
	(segment
		(start 148.59254 -291.167312)
		(end 148.59254 -280.19375)
		(width 0.13208)
		(layer "B.Cu")
		(net "RST_PEX1_SYS_N")
	)
	(segment
		(start 154.813 -297.027854)
		(end 154.558746 -296.7736)
		(width 0.13208)
		(layer "B.Cu")
		(net "RST_PEX1_SYS_N")
	)
	(segment
		(start 150.573232 -293.238682)
		(end 150.573232 -293.148004)
		(width 0.13208)
		(layer "B.Cu")
		(net "RST_PEX1_SYS_N")
	)
	(segment
		(start 167.675052 -307.774848)
		(end 167.154098 -307.253894)
		(width 0.13208)
		(layer "B.Cu")
		(net "RST_PEX1_SYS_N")
	)
	(segment
		(start 155.033472 -297.7896)
		(end 154.813 -297.569128)
		(width 0.13208)
		(layer "B.Cu")
		(net "RST_PEX1_SYS_N")
	)
	(segment
		(start 150.876 -264.930636)
		(end 149.32152 -263.376156)
		(width 0.13208)
		(layer "B.Cu")
		(net "RST_PEX1_SYS_N")
	)
	(segment
		(start 165.280086 -305.526948)
		(end 165.153086 -305.399948)
		(width 0.13208)
		(layer "B.Cu")
		(net "RST_PEX1_SYS_N")
	)
	(segment
		(start 164.078412 -304.440082)
		(end 162.200082 -304.440082)
		(width 0.13208)
		(layer "B.Cu")
		(net "RST_PEX1_SYS_N")
	)
	(segment
		(start 165.153086 -305.399948)
		(end 164.580062 -305.399948)
		(width 0.13208)
		(layer "B.Cu")
		(net "RST_PEX1_SYS_N")
	)
	(segment
		(start 159.254698 -303.911)
		(end 159.127698 -303.784)
		(width 0.13208)
		(layer "B.Cu")
		(net "RST_PEX1_SYS_N")
	)
	(segment
		(start 164.580062 -305.399948)
		(end 164.342318 -305.162204)
		(width 0.13208)
		(layer "B.Cu")
		(net "RST_PEX1_SYS_N")
	)
	(segment
		(start 165.443154 -306.365148)
		(end 165.280086 -306.20208)
		(width 0.13208)
		(layer "B.Cu")
		(net "RST_PEX1_SYS_N")
	)
	(segment
		(start 150.029164 -278.757126)
		(end 150.029164 -274.174204)
		(width 0.13208)
		(layer "B.Cu")
		(net "RST_PEX1_SYS_N")
	)
	(segment
		(start 167.154098 -307.253894)
		(end 167.154098 -306.679346)
		(width 0.13208)
		(layer "B.Cu")
		(net "RST_PEX1_SYS_N")
	)
	(segment
		(start 150.876 -273.327368)
		(end 150.876 -264.930636)
		(width 0.13208)
		(layer "B.Cu")
		(net "RST_PEX1_SYS_N")
	)
	(segment
		(start 159.127698 -303.784)
		(end 159.127698 -298.341796)
		(width 0.13208)
		(layer "B.Cu")
		(net "RST_PEX1_SYS_N")
	)
	(segment
		(start 148.59254 -280.19375)
		(end 150.029164 -278.757126)
		(width 0.13208)
		(layer "B.Cu")
		(net "RST_PEX1_SYS_N")
	)
	(segment
		(start 166.8399 -306.365148)
		(end 165.443154 -306.365148)
		(width 0.13208)
		(layer "B.Cu")
		(net "RST_PEX1_SYS_N")
	)
	(segment
		(start 159.127698 -298.341796)
		(end 158.575502 -297.7896)
		(width 0.13208)
		(layer "B.Cu")
		(net "RST_PEX1_SYS_N")
	)
	(segment
		(start 149.32152 -263.376156)
		(end 149.32152 -262.847836)
		(width 0.13208)
		(layer "B.Cu")
		(net "RST_PEX1_SYS_N")
	)
	(segment
		(start 153.329386 -295.564052)
		(end 152.898602 -295.564052)
		(width 0.13208)
		(layer "B.Cu")
		(net "RST_PEX1_SYS_N")
	)
	(segment
		(start 153.92273 -296.157396)
		(end 153.329386 -295.564052)
		(width 0.13208)
		(layer "B.Cu")
		(net "RST_PEX1_SYS_N")
	)
	(segment
		(start 165.280086 -306.20208)
		(end 165.280086 -305.526948)
		(width 0.13208)
		(layer "B.Cu")
		(net "RST_PEX1_SYS_N")
	)
	(segment
		(start 162.200082 -304.440082)
		(end 161.671 -303.911)
		(width 0.13208)
		(layer "B.Cu")
		(net "RST_PEX1_SYS_N")
	)
	(segment
		(start 167.154098 -306.679346)
		(end 166.8399 -306.365148)
		(width 0.13208)
		(layer "B.Cu")
		(net "RST_PEX1_SYS_N")
	)
	(segment
		(start 164.342318 -304.703988)
		(end 164.078412 -304.440082)
		(width 0.13208)
		(layer "B.Cu")
		(net "RST_PEX1_SYS_N")
	)
	(segment
		(start 158.575502 -297.7896)
		(end 155.033472 -297.7896)
		(width 0.13208)
		(layer "B.Cu")
		(net "RST_PEX1_SYS_N")
	)
	(segment
		(start 150.573232 -293.148004)
		(end 148.59254 -291.167312)
		(width 0.13208)
		(layer "B.Cu")
		(net "RST_PEX1_SYS_N")
	)
	(segment
		(start 142.8496 -260.990588)
		(end 141.904212 -260.0452)
		(width 0.15494)
		(layer "In5.Cu")
		(net "RST_PEX1_SYS_N")
	)
	(segment
		(start 138.554206 -256.790952)
		(end 137.682732 -255.919478)
		(width 0.15494)
		(layer "In5.Cu")
		(net "RST_PEX1_SYS_N")
	)
	(segment
		(start 138.353292 -242.814602)
		(end 139.987528 -241.180366)
		(width 0.15494)
		(layer "In5.Cu")
		(net "RST_PEX1_SYS_N")
	)
	(segment
		(start 139.743942 -256.790952)
		(end 138.554206 -256.790952)
		(width 0.15494)
		(layer "In5.Cu")
		(net "RST_PEX1_SYS_N")
	)
	(segment
		(start 149.32152 -262.847836)
		(end 148.90369 -262.847836)
		(width 0.15494)
		(layer "In5.Cu")
		(net "RST_PEX1_SYS_N")
	)
	(segment
		(start 137.682732 -254.874522)
		(end 138.353292 -254.203962)
		(width 0.15494)
		(layer "In5.Cu")
		(net "RST_PEX1_SYS_N")
	)
	(segment
		(start 148.90369 -262.847836)
		(end 147.046442 -260.990588)
		(width 0.15494)
		(layer "In5.Cu")
		(net "RST_PEX1_SYS_N")
	)
	(segment
		(start 141.798294 -227.180394)
		(end 143.29791 -227.180394)
		(width 0.15494)
		(layer "In5.Cu")
		(net "RST_PEX1_SYS_N")
	)
	(segment
		(start 137.682732 -255.919478)
		(end 137.682732 -254.874522)
		(width 0.15494)
		(layer "In5.Cu")
		(net "RST_PEX1_SYS_N")
	)
	(segment
		(start 141.904212 -258.951222)
		(end 139.743942 -256.790952)
		(width 0.15494)
		(layer "In5.Cu")
		(net "RST_PEX1_SYS_N")
	)
	(segment
		(start 139.987528 -241.180366)
		(end 139.987528 -228.99116)
		(width 0.15494)
		(layer "In5.Cu")
		(net "RST_PEX1_SYS_N")
	)
	(segment
		(start 147.046442 -260.990588)
		(end 142.8496 -260.990588)
		(width 0.15494)
		(layer "In5.Cu")
		(net "RST_PEX1_SYS_N")
	)
	(segment
		(start 139.987528 -228.99116)
		(end 141.798294 -227.180394)
		(width 0.15494)
		(layer "In5.Cu")
		(net "RST_PEX1_SYS_N")
	)
	(segment
		(start 138.353292 -254.203962)
		(end 138.353292 -242.814602)
		(width 0.15494)
		(layer "In5.Cu")
		(net "RST_PEX1_SYS_N")
	)
	(segment
		(start 141.904212 -260.0452)
		(end 141.904212 -258.951222)
		(width 0.15494)
		(layer "In5.Cu")
		(net "RST_PEX1_SYS_N")
	)
	(segment
		(start 240.496598 -235.210858)
		(end 241.499136 -234.20832)
		(width 0.15494)
		(layer "In15.Cu")
		(net "RST_PEX1_SYS_N")
	)
	(segment
		(start 188.163454 -231.4194)
		(end 192.490344 -235.74629)
		(width 0.15494)
		(layer "In15.Cu")
		(net "RST_PEX1_SYS_N")
	)
	(segment
		(start 264.17524 -230.52532)
		(end 265.2014 -230.52532)
		(width 0.15494)
		(layer "In15.Cu")
		(net "RST_PEX1_SYS_N")
	)
	(segment
		(start 181.1528 -231.4194)
		(end 188.163454 -231.4194)
		(width 0.15494)
		(layer "In15.Cu")
		(net "RST_PEX1_SYS_N")
	)
	(segment
		(start 143.29791 -227.180394)
		(end 144.58061 -227.180394)
		(width 0.15494)
		(layer "In15.Cu")
		(net "RST_PEX1_SYS_N")
	)
	(segment
		(start 209.279236 -235.74629)
		(end 209.930746 -236.3978)
		(width 0.15494)
		(layer "In15.Cu")
		(net "RST_PEX1_SYS_N")
	)
	(segment
		(start 209.930746 -236.3978)
		(end 216.42324 -236.3978)
		(width 0.15494)
		(layer "In15.Cu")
		(net "RST_PEX1_SYS_N")
	)
	(segment
		(start 270.497808 -235.726732)
		(end 321.463924 -235.726732)
		(width 0.15494)
		(layer "In15.Cu")
		(net "RST_PEX1_SYS_N")
	)
	(segment
		(start 246.46128 -234.20832)
		(end 248.81205 -231.85755)
		(width 0.15494)
		(layer "In15.Cu")
		(net "RST_PEX1_SYS_N")
	)
	(segment
		(start 269.903956 -235.227876)
		(end 269.998952 -235.227876)
		(width 0.15494)
		(layer "In15.Cu")
		(net "RST_PEX1_SYS_N")
	)
	(segment
		(start 248.81205 -231.196896)
		(end 249.638566 -230.37038)
		(width 0.15494)
		(layer "In15.Cu")
		(net "RST_PEX1_SYS_N")
	)
	(segment
		(start 269.998952 -235.227876)
		(end 270.497808 -235.726732)
		(width 0.15494)
		(layer "In15.Cu")
		(net "RST_PEX1_SYS_N")
	)
	(segment
		(start 258.500118 -229.41026)
		(end 263.06018 -229.41026)
		(width 0.15494)
		(layer "In15.Cu")
		(net "RST_PEX1_SYS_N")
	)
	(segment
		(start 265.2014 -230.52532)
		(end 269.903956 -235.227876)
		(width 0.15494)
		(layer "In15.Cu")
		(net "RST_PEX1_SYS_N")
	)
	(segment
		(start 263.06018 -229.41026)
		(end 264.17524 -230.52532)
		(width 0.15494)
		(layer "In15.Cu")
		(net "RST_PEX1_SYS_N")
	)
	(segment
		(start 249.638566 -230.37038)
		(end 252.228604 -230.37038)
		(width 0.15494)
		(layer "In15.Cu")
		(net "RST_PEX1_SYS_N")
	)
	(segment
		(start 192.490344 -235.74629)
		(end 209.279236 -235.74629)
		(width 0.15494)
		(layer "In15.Cu")
		(net "RST_PEX1_SYS_N")
	)
	(segment
		(start 216.42324 -236.3978)
		(end 217.610182 -235.210858)
		(width 0.15494)
		(layer "In15.Cu")
		(net "RST_PEX1_SYS_N")
	)
	(segment
		(start 257.862578 -228.77272)
		(end 258.500118 -229.41026)
		(width 0.15494)
		(layer "In15.Cu")
		(net "RST_PEX1_SYS_N")
	)
	(segment
		(start 252.228604 -230.37038)
		(end 253.82855 -228.77272)
		(width 0.15494)
		(layer "In15.Cu")
		(net "RST_PEX1_SYS_N")
	)
	(segment
		(start 248.81205 -231.85755)
		(end 248.81205 -231.196896)
		(width 0.15494)
		(layer "In15.Cu")
		(net "RST_PEX1_SYS_N")
	)
	(segment
		(start 241.499136 -234.20832)
		(end 246.46128 -234.20832)
		(width 0.15494)
		(layer "In15.Cu")
		(net "RST_PEX1_SYS_N")
	)
	(segment
		(start 324.70979 -236.183932)
		(end 324.991222 -236.183932)
		(width 0.15494)
		(layer "In15.Cu")
		(net "RST_PEX1_SYS_N")
	)
	(segment
		(start 321.463924 -235.726732)
		(end 322.864734 -237.127542)
		(width 0.15494)
		(layer "In15.Cu")
		(net "RST_PEX1_SYS_N")
	)
	(segment
		(start 157.52572 -226.08413)
		(end 161.59099 -230.1494)
		(width 0.15494)
		(layer "In15.Cu")
		(net "RST_PEX1_SYS_N")
	)
	(segment
		(start 217.610182 -235.210858)
		(end 240.496598 -235.210858)
		(width 0.15494)
		(layer "In15.Cu")
		(net "RST_PEX1_SYS_N")
	)
	(segment
		(start 323.765672 -237.127542)
		(end 324.70979 -236.183932)
		(width 0.15494)
		(layer "In15.Cu")
		(net "RST_PEX1_SYS_N")
	)
	(segment
		(start 161.59099 -230.1494)
		(end 179.8828 -230.1494)
		(width 0.15494)
		(layer "In15.Cu")
		(net "RST_PEX1_SYS_N")
	)
	(segment
		(start 322.864734 -237.127542)
		(end 323.765672 -237.127542)
		(width 0.15494)
		(layer "In15.Cu")
		(net "RST_PEX1_SYS_N")
	)
	(segment
		(start 145.676874 -226.08413)
		(end 157.52572 -226.08413)
		(width 0.15494)
		(layer "In15.Cu")
		(net "RST_PEX1_SYS_N")
	)
	(segment
		(start 144.58061 -227.180394)
		(end 145.676874 -226.08413)
		(width 0.15494)
		(layer "In15.Cu")
		(net "RST_PEX1_SYS_N")
	)
	(segment
		(start 253.82855 -228.77272)
		(end 257.862578 -228.77272)
		(width 0.15494)
		(layer "In15.Cu")
		(net "RST_PEX1_SYS_N")
	)
	(segment
		(start 179.8828 -230.1494)
		(end 181.1528 -231.4194)
		(width 0.15494)
		(layer "In15.Cu")
		(net "RST_PEX1_SYS_N")
	)
	(segment
		(start 240.675414 -217.78976)
		(end 240.567464 -217.89771)
		(width 0.254)
		(layer "F.Cu")
		(net "BIC_ADCVREFP0")
	)
	(segment
		(start 235.220764 -215.504014)
		(end 235.743242 -215.504014)
		(width 0.13208)
		(layer "F.Cu")
		(net "BIC_ADCVREFP0")
	)
	(segment
		(start 237.134654 -215.746838)
		(end 237.135416 -215.7476)
		(width 0.254)
		(layer "F.Cu")
		(net "BIC_ADCVREFP0")
	)
	(segment
		(start 234.667552 -215.904064)
		(end 235.067602 -215.504014)
		(width 0.254)
		(layer "F.Cu")
		(net "BIC_ADCVREFP0")
	)
	(segment
		(start 239.703864 -217.116152)
		(end 238.71174 -216.124028)
		(width 0.254)
		(layer "F.Cu")
		(net "BIC_ADCVREFP0")
	)
	(segment
		(start 238.377984 -215.7476)
		(end 238.501936 -215.871552)
		(width 0.254)
		(layer "F.Cu")
		(net "BIC_ADCVREFP0")
	)
	(segment
		(start 239.703864 -217.89771)
		(end 239.703864 -217.116152)
		(width 0.254)
		(layer "F.Cu")
		(net "BIC_ADCVREFP0")
	)
	(segment
		(start 235.067602 -215.504014)
		(end 235.220764 -215.504014)
		(width 0.254)
		(layer "F.Cu")
		(net "BIC_ADCVREFP0")
	)
	(segment
		(start 238.71174 -216.081356)
		(end 238.501936 -215.871552)
		(width 0.254)
		(layer "F.Cu")
		(net "BIC_ADCVREFP0")
	)
	(segment
		(start 235.986066 -215.746838)
		(end 237.134654 -215.746838)
		(width 0.254)
		(layer "F.Cu")
		(net "BIC_ADCVREFP0")
	)
	(segment
		(start 235.743242 -215.504014)
		(end 235.986066 -215.746838)
		(width 0.254)
		(layer "F.Cu")
		(net "BIC_ADCVREFP0")
	)
	(segment
		(start 238.71174 -216.124028)
		(end 238.71174 -216.081356)
		(width 0.254)
		(layer "F.Cu")
		(net "BIC_ADCVREFP0")
	)
	(segment
		(start 237.135416 -215.7476)
		(end 238.377984 -215.7476)
		(width 0.254)
		(layer "F.Cu")
		(net "BIC_ADCVREFP0")
	)
	(segment
		(start 240.567464 -217.89771)
		(end 239.703864 -217.89771)
		(width 0.254)
		(layer "F.Cu")
		(net "BIC_ADCVREFP0")
	)
	(via
		(at 238.501936 -215.871552)
		(size 0.762)
		(drill 0.381)
		(layers "F.Cu" "B.Cu")
		(net "BIC_ADCVREFP0")
	)
	(segment
		(start 323.975222 -235.475272)
		(end 323.975222 -236.183932)
		(width 0.13208)
		(layer "F.Cu")
		(net "RST_PEX0_SYS_N")
	)
	(via
		(at 52.049934 -308.249828)
		(size 0.4064)
		(drill 0.2032)
		(layers "F.Cu" "B.Cu")
		(net "RST_PEX0_SYS_N")
	)
	(via
		(at 17.423892 -218.29141)
		(size 0.508)
		(drill 0.254)
		(layers "F.Cu" "B.Cu")
		(net "RST_PEX0_SYS_N")
	)
	(via
		(at 323.975222 -236.183932)
		(size 0.508)
		(drill 0.254)
		(layers "F.Cu" "B.Cu")
		(net "RST_PEX0_SYS_N")
	)
	(via
		(at 33.929066 -278.757126)
		(size 0.508)
		(drill 0.254)
		(layers "F.Cu" "B.Cu")
		(net "RST_PEX0_SYS_N")
	)
	(segment
		(start 46.6852 -304.927)
		(end 47.158148 -305.399948)
		(width 0.13208)
		(layer "B.Cu")
		(net "RST_PEX0_SYS_N")
	)
	(segment
		(start 49.052988 -305.399948)
		(end 49.179988 -305.526948)
		(width 0.13208)
		(layer "B.Cu")
		(net "RST_PEX0_SYS_N")
	)
	(segment
		(start 51.054 -306.679346)
		(end 51.054 -307.253894)
		(width 0.13208)
		(layer "B.Cu")
		(net "RST_PEX0_SYS_N")
	)
	(segment
		(start 37.822632 -296.545762)
		(end 38.05047 -296.7736)
		(width 0.13208)
		(layer "B.Cu")
		(net "RST_PEX0_SYS_N")
	)
	(segment
		(start 49.179988 -305.526948)
		(end 49.179988 -306.20208)
		(width 0.13208)
		(layer "B.Cu")
		(net "RST_PEX0_SYS_N")
	)
	(segment
		(start 32.492442 -280.19375)
		(end 32.492442 -291.167312)
		(width 0.13208)
		(layer "B.Cu")
		(net "RST_PEX0_SYS_N")
	)
	(segment
		(start 34.473134 -293.238682)
		(end 36.798504 -295.564052)
		(width 0.13208)
		(layer "B.Cu")
		(net "RST_PEX0_SYS_N")
	)
	(segment
		(start 43.1546 -304.927)
		(end 46.6852 -304.927)
		(width 0.13208)
		(layer "B.Cu")
		(net "RST_PEX0_SYS_N")
	)
	(segment
		(start 38.907974 -297.7642)
		(end 42.450004 -297.7642)
		(width 0.13208)
		(layer "B.Cu")
		(net "RST_PEX0_SYS_N")
	)
	(segment
		(start 50.739802 -306.365148)
		(end 51.054 -306.679346)
		(width 0.13208)
		(layer "B.Cu")
		(net "RST_PEX0_SYS_N")
	)
	(segment
		(start 43.0276 -304.8)
		(end 43.1546 -304.927)
		(width 0.13208)
		(layer "B.Cu")
		(net "RST_PEX0_SYS_N")
	)
	(segment
		(start 38.05047 -296.7736)
		(end 38.458648 -296.7736)
		(width 0.13208)
		(layer "B.Cu")
		(net "RST_PEX0_SYS_N")
	)
	(segment
		(start 43.0276 -298.341796)
		(end 43.0276 -304.8)
		(width 0.13208)
		(layer "B.Cu")
		(net "RST_PEX0_SYS_N")
	)
	(segment
		(start 38.7604 -297.075352)
		(end 38.7604 -297.616626)
		(width 0.13208)
		(layer "B.Cu")
		(net "RST_PEX0_SYS_N")
	)
	(segment
		(start 37.229288 -295.564052)
		(end 37.822632 -296.157396)
		(width 0.13208)
		(layer "B.Cu")
		(net "RST_PEX0_SYS_N")
	)
	(segment
		(start 34.473134 -293.148004)
		(end 34.473134 -293.238682)
		(width 0.13208)
		(layer "B.Cu")
		(net "RST_PEX0_SYS_N")
	)
	(segment
		(start 51.054 -307.253894)
		(end 52.049934 -308.249828)
		(width 0.13208)
		(layer "B.Cu")
		(net "RST_PEX0_SYS_N")
	)
	(segment
		(start 32.492442 -291.167312)
		(end 34.473134 -293.148004)
		(width 0.13208)
		(layer "B.Cu")
		(net "RST_PEX0_SYS_N")
	)
	(segment
		(start 37.822632 -296.157396)
		(end 37.822632 -296.545762)
		(width 0.13208)
		(layer "B.Cu")
		(net "RST_PEX0_SYS_N")
	)
	(segment
		(start 49.343056 -306.365148)
		(end 50.739802 -306.365148)
		(width 0.13208)
		(layer "B.Cu")
		(net "RST_PEX0_SYS_N")
	)
	(segment
		(start 49.179988 -306.20208)
		(end 49.343056 -306.365148)
		(width 0.13208)
		(layer "B.Cu")
		(net "RST_PEX0_SYS_N")
	)
	(segment
		(start 33.929066 -278.757126)
		(end 32.492442 -280.19375)
		(width 0.13208)
		(layer "B.Cu")
		(net "RST_PEX0_SYS_N")
	)
	(segment
		(start 36.798504 -295.564052)
		(end 37.229288 -295.564052)
		(width 0.13208)
		(layer "B.Cu")
		(net "RST_PEX0_SYS_N")
	)
	(segment
		(start 38.7604 -297.616626)
		(end 38.907974 -297.7642)
		(width 0.13208)
		(layer "B.Cu")
		(net "RST_PEX0_SYS_N")
	)
	(segment
		(start 42.450004 -297.7642)
		(end 43.0276 -298.341796)
		(width 0.13208)
		(layer "B.Cu")
		(net "RST_PEX0_SYS_N")
	)
	(segment
		(start 38.458648 -296.7736)
		(end 38.7604 -297.075352)
		(width 0.13208)
		(layer "B.Cu")
		(net "RST_PEX0_SYS_N")
	)
	(segment
		(start 47.158148 -305.399948)
		(end 49.052988 -305.399948)
		(width 0.13208)
		(layer "B.Cu")
		(net "RST_PEX0_SYS_N")
	)
	(segment
		(start 17.423892 -218.29141)
		(end 14.478 -221.237302)
		(width 0.15494)
		(layer "In5.Cu")
		(net "RST_PEX0_SYS_N")
	)
	(segment
		(start 16.515588 -243.906802)
		(end 16.515588 -263.251442)
		(width 0.15494)
		(layer "In5.Cu")
		(net "RST_PEX0_SYS_N")
	)
	(segment
		(start 14.478 -241.869214)
		(end 16.515588 -243.906802)
		(width 0.15494)
		(layer "In5.Cu")
		(net "RST_PEX0_SYS_N")
	)
	(segment
		(start 14.478 -221.237302)
		(end 14.478 -241.869214)
		(width 0.15494)
		(layer "In5.Cu")
		(net "RST_PEX0_SYS_N")
	)
	(segment
		(start 16.515588 -263.251442)
		(end 21.486876 -268.22273)
		(width 0.15494)
		(layer "In5.Cu")
		(net "RST_PEX0_SYS_N")
	)
	(segment
		(start 28.083764 -278.757126)
		(end 33.929066 -278.757126)
		(width 0.15494)
		(layer "In5.Cu")
		(net "RST_PEX0_SYS_N")
	)
	(segment
		(start 21.486876 -268.22273)
		(end 21.486876 -272.160238)
		(width 0.15494)
		(layer "In5.Cu")
		(net "RST_PEX0_SYS_N")
	)
	(segment
		(start 21.486876 -272.160238)
		(end 28.083764 -278.757126)
		(width 0.15494)
		(layer "In5.Cu")
		(net "RST_PEX0_SYS_N")
	)
	(segment
		(start 240.47577 -234.520486)
		(end 241.977926 -233.01833)
		(width 0.15494)
		(layer "In15.Cu")
		(net "RST_PEX0_SYS_N")
	)
	(segment
		(start 181.3306 -230.9368)
		(end 188.984382 -230.9368)
		(width 0.15494)
		(layer "In15.Cu")
		(net "RST_PEX0_SYS_N")
	)
	(segment
		(start 95.875348 -203.4032)
		(end 98.24593 -203.874624)
		(width 0.15494)
		(layer "In15.Cu")
		(net "RST_PEX0_SYS_N")
	)
	(segment
		(start 128.274826 -226.95281)
		(end 140.499338 -226.95281)
		(width 0.15494)
		(layer "In15.Cu")
		(net "RST_PEX0_SYS_N")
	)
	(segment
		(start 141.611096 -225.841052)
		(end 145.269712 -225.841052)
		(width 0.15494)
		(layer "In15.Cu")
		(net "RST_PEX0_SYS_N")
	)
	(segment
		(start 145.269712 -225.841052)
		(end 146.042634 -225.06813)
		(width 0.15494)
		(layer "In15.Cu")
		(net "RST_PEX0_SYS_N")
	)
	(segment
		(start 252.066044 -229.848156)
		(end 253.601982 -228.31298)
		(width 0.15494)
		(layer "In15.Cu")
		(net "RST_PEX0_SYS_N")
	)
	(segment
		(start 161.739326 -229.647496)
		(end 180.041296 -229.647496)
		(width 0.15494)
		(layer "In15.Cu")
		(net "RST_PEX0_SYS_N")
	)
	(segment
		(start 62.15634 -206.375)
		(end 62.66434 -206.883)
		(width 0.15494)
		(layer "In15.Cu")
		(net "RST_PEX0_SYS_N")
	)
	(segment
		(start 247.622822 -231.9274)
		(end 248.11228 -231.437942)
		(width 0.15494)
		(layer "In15.Cu")
		(net "RST_PEX0_SYS_N")
	)
	(segment
		(start 102.370128 -205.58252)
		(end 110.587282 -205.58252)
		(width 0.15494)
		(layer "In15.Cu")
		(net "RST_PEX0_SYS_N")
	)
	(segment
		(start 32.774128 -206.375)
		(end 62.15634 -206.375)
		(width 0.15494)
		(layer "In15.Cu")
		(net "RST_PEX0_SYS_N")
	)
	(segment
		(start 270.638524 -235.216954)
		(end 321.604386 -235.216954)
		(width 0.15494)
		(layer "In15.Cu")
		(net "RST_PEX0_SYS_N")
	)
	(segment
		(start 243.974112 -231.9274)
		(end 247.622822 -231.9274)
		(width 0.15494)
		(layer "In15.Cu")
		(net "RST_PEX0_SYS_N")
	)
	(segment
		(start 63.434468 -206.883)
		(end 66.914268 -203.4032)
		(width 0.15494)
		(layer "In15.Cu")
		(net "RST_PEX0_SYS_N")
	)
	(segment
		(start 241.977926 -233.01833)
		(end 242.883182 -233.01833)
		(width 0.15494)
		(layer "In15.Cu")
		(net "RST_PEX0_SYS_N")
	)
	(segment
		(start 264.2997 -228.76764)
		(end 264.4267 -228.89464)
		(width 0.15494)
		(layer "In15.Cu")
		(net "RST_PEX0_SYS_N")
	)
	(segment
		(start 262.014462 -228.95052)
		(end 262.197342 -228.76764)
		(width 0.15494)
		(layer "In15.Cu")
		(net "RST_PEX0_SYS_N")
	)
	(segment
		(start 248.11228 -230.402638)
		(end 248.666762 -229.848156)
		(width 0.15494)
		(layer "In15.Cu")
		(net "RST_PEX0_SYS_N")
	)
	(segment
		(start 193.302382 -235.2548)
		(end 209.728054 -235.2548)
		(width 0.15494)
		(layer "In15.Cu")
		(net "RST_PEX0_SYS_N")
	)
	(segment
		(start 258.053078 -228.31298)
		(end 258.690618 -228.95052)
		(width 0.15494)
		(layer "In15.Cu")
		(net "RST_PEX0_SYS_N")
	)
	(segment
		(start 188.984382 -230.9368)
		(end 193.302382 -235.2548)
		(width 0.15494)
		(layer "In15.Cu")
		(net "RST_PEX0_SYS_N")
	)
	(segment
		(start 110.587282 -205.58252)
		(end 116.840762 -211.836)
		(width 0.15494)
		(layer "In15.Cu")
		(net "RST_PEX0_SYS_N")
	)
	(segment
		(start 258.690618 -228.95052)
		(end 262.014462 -228.95052)
		(width 0.15494)
		(layer "In15.Cu")
		(net "RST_PEX0_SYS_N")
	)
	(segment
		(start 262.197342 -228.76764)
		(end 264.2997 -228.76764)
		(width 0.15494)
		(layer "In15.Cu")
		(net "RST_PEX0_SYS_N")
	)
	(segment
		(start 264.5537 -229.743)
		(end 265.16457 -229.743)
		(width 0.15494)
		(layer "In15.Cu")
		(net "RST_PEX0_SYS_N")
	)
	(segment
		(start 323.491352 -236.667802)
		(end 323.975222 -236.183932)
		(width 0.15494)
		(layer "In15.Cu")
		(net "RST_PEX0_SYS_N")
	)
	(segment
		(start 146.042634 -225.06813)
		(end 157.15996 -225.06813)
		(width 0.15494)
		(layer "In15.Cu")
		(net "RST_PEX0_SYS_N")
	)
	(segment
		(start 248.666762 -229.848156)
		(end 252.066044 -229.848156)
		(width 0.15494)
		(layer "In15.Cu")
		(net "RST_PEX0_SYS_N")
	)
	(segment
		(start 66.914268 -203.4032)
		(end 95.875348 -203.4032)
		(width 0.15494)
		(layer "In15.Cu")
		(net "RST_PEX0_SYS_N")
	)
	(segment
		(start 264.4267 -228.89464)
		(end 264.4267 -229.616)
		(width 0.15494)
		(layer "In15.Cu")
		(net "RST_PEX0_SYS_N")
	)
	(segment
		(start 321.604386 -235.216954)
		(end 323.055234 -236.667802)
		(width 0.15494)
		(layer "In15.Cu")
		(net "RST_PEX0_SYS_N")
	)
	(segment
		(start 264.4267 -229.616)
		(end 264.5537 -229.743)
		(width 0.15494)
		(layer "In15.Cu")
		(net "RST_PEX0_SYS_N")
	)
	(segment
		(start 140.499338 -226.95281)
		(end 141.611096 -225.841052)
		(width 0.15494)
		(layer "In15.Cu")
		(net "RST_PEX0_SYS_N")
	)
	(segment
		(start 210.388454 -235.9152)
		(end 215.876886 -235.9152)
		(width 0.15494)
		(layer "In15.Cu")
		(net "RST_PEX0_SYS_N")
	)
	(segment
		(start 323.055234 -236.667802)
		(end 323.491352 -236.667802)
		(width 0.15494)
		(layer "In15.Cu")
		(net "RST_PEX0_SYS_N")
	)
	(segment
		(start 116.840762 -215.518746)
		(end 128.274826 -226.95281)
		(width 0.15494)
		(layer "In15.Cu")
		(net "RST_PEX0_SYS_N")
	)
	(segment
		(start 157.15996 -225.06813)
		(end 161.739326 -229.647496)
		(width 0.15494)
		(layer "In15.Cu")
		(net "RST_PEX0_SYS_N")
	)
	(segment
		(start 62.66434 -206.883)
		(end 63.434468 -206.883)
		(width 0.15494)
		(layer "In15.Cu")
		(net "RST_PEX0_SYS_N")
	)
	(segment
		(start 215.876886 -235.9152)
		(end 217.2716 -234.520486)
		(width 0.15494)
		(layer "In15.Cu")
		(net "RST_PEX0_SYS_N")
	)
	(segment
		(start 265.16457 -229.743)
		(end 270.638524 -235.216954)
		(width 0.15494)
		(layer "In15.Cu")
		(net "RST_PEX0_SYS_N")
	)
	(segment
		(start 116.840762 -211.836)
		(end 116.840762 -215.518746)
		(width 0.15494)
		(layer "In15.Cu")
		(net "RST_PEX0_SYS_N")
	)
	(segment
		(start 253.601982 -228.31298)
		(end 258.053078 -228.31298)
		(width 0.15494)
		(layer "In15.Cu")
		(net "RST_PEX0_SYS_N")
	)
	(segment
		(start 209.728054 -235.2548)
		(end 210.388454 -235.9152)
		(width 0.15494)
		(layer "In15.Cu")
		(net "RST_PEX0_SYS_N")
	)
	(segment
		(start 17.423892 -218.29141)
		(end 20.857718 -218.29141)
		(width 0.15494)
		(layer "In15.Cu")
		(net "RST_PEX0_SYS_N")
	)
	(segment
		(start 248.11228 -231.437942)
		(end 248.11228 -230.402638)
		(width 0.15494)
		(layer "In15.Cu")
		(net "RST_PEX0_SYS_N")
	)
	(segment
		(start 180.041296 -229.647496)
		(end 181.3306 -230.9368)
		(width 0.15494)
		(layer "In15.Cu")
		(net "RST_PEX0_SYS_N")
	)
	(segment
		(start 217.2716 -234.520486)
		(end 240.47577 -234.520486)
		(width 0.15494)
		(layer "In15.Cu")
		(net "RST_PEX0_SYS_N")
	)
	(segment
		(start 20.857718 -218.29141)
		(end 32.774128 -206.375)
		(width 0.15494)
		(layer "In15.Cu")
		(net "RST_PEX0_SYS_N")
	)
	(segment
		(start 98.24593 -203.874624)
		(end 102.370128 -205.58252)
		(width 0.15494)
		(layer "In15.Cu")
		(net "RST_PEX0_SYS_N")
	)
	(segment
		(start 242.883182 -233.01833)
		(end 243.974112 -231.9274)
		(width 0.15494)
		(layer "In15.Cu")
		(net "RST_PEX0_SYS_N")
	)
	(segment
		(start 336.43443 -187.061856)
		(end 337.05038 -187.061856)
		(width 0.13208)
		(layer "F.Cu")
		(net "PEX2_PCA9555_INT_R_N")
	)
	(segment
		(start 271.782286 -252.756924)
		(end 271.782286 -253.45644)
		(width 0.13208)
		(layer "F.Cu")
		(net "PEX2_PCA9555_INT_R_N")
	)
	(segment
		(start 295.649904 -283.549852)
		(end 296.124884 -284.024832)
		(width 0.1651)
		(layer "F.Cu")
		(net "PEX2_PCA9555_INT_R_N")
	)
	(via
		(at 271.782286 -253.45644)
		(size 0.508)
		(drill 0.254)
		(layers "F.Cu" "B.Cu")
		(net "PEX2_PCA9555_INT_R_N")
	)
	(via
		(at 337.05038 -187.061856)
		(size 0.508)
		(drill 0.254)
		(layers "F.Cu" "B.Cu")
		(net "PEX2_PCA9555_INT_R_N")
	)
	(via
		(at 261.59079 -180.787548)
		(size 0.508)
		(drill 0.254)
		(layers "F.Cu" "B.Cu")
		(net "PEX2_PCA9555_INT_R_N")
	)
	(via
		(at 296.124884 -284.024832)
		(size 0.4064)
		(drill 0.2032)
		(layers "F.Cu" "B.Cu")
		(net "PEX2_PCA9555_INT_R_N")
	)
	(segment
		(start 301.98314 -284.48127)
		(end 302.32477 -284.13964)
		(width 0.13208)
		(layer "B.Cu")
		(net "PEX2_PCA9555_INT_R_N")
	)
	(segment
		(start 284.970728 -252.97892)
		(end 272.259806 -252.97892)
		(width 0.13208)
		(layer "B.Cu")
		(net "PEX2_PCA9555_INT_R_N")
	)
	(segment
		(start 302.32477 -284.13964)
		(end 302.32477 -282.86202)
		(width 0.13208)
		(layer "B.Cu")
		(net "PEX2_PCA9555_INT_R_N")
	)
	(segment
		(start 303.712372 -281.750516)
		(end 303.712372 -271.720564)
		(width 0.13208)
		(layer "B.Cu")
		(net "PEX2_PCA9555_INT_R_N")
	)
	(segment
		(start 296.581322 -284.48127)
		(end 301.98314 -284.48127)
		(width 0.13208)
		(layer "B.Cu")
		(net "PEX2_PCA9555_INT_R_N")
	)
	(segment
		(start 302.61941 -282.56738)
		(end 302.895508 -282.56738)
		(width 0.13208)
		(layer "B.Cu")
		(net "PEX2_PCA9555_INT_R_N")
	)
	(segment
		(start 302.895508 -282.56738)
		(end 303.712372 -281.750516)
		(width 0.13208)
		(layer "B.Cu")
		(net "PEX2_PCA9555_INT_R_N")
	)
	(segment
		(start 272.259806 -252.97892)
		(end 271.782286 -253.45644)
		(width 0.13208)
		(layer "B.Cu")
		(net "PEX2_PCA9555_INT_R_N")
	)
	(segment
		(start 303.712372 -271.720564)
		(end 284.970728 -252.97892)
		(width 0.13208)
		(layer "B.Cu")
		(net "PEX2_PCA9555_INT_R_N")
	)
	(segment
		(start 296.124884 -284.024832)
		(end 296.581322 -284.48127)
		(width 0.13208)
		(layer "B.Cu")
		(net "PEX2_PCA9555_INT_R_N")
	)
	(segment
		(start 302.32477 -282.86202)
		(end 302.61941 -282.56738)
		(width 0.13208)
		(layer "B.Cu")
		(net "PEX2_PCA9555_INT_R_N")
	)
	(segment
		(start 268.2748 -225.271076)
		(end 269.002002 -224.543874)
		(width 0.15494)
		(layer "In5.Cu")
		(net "PEX2_PCA9555_INT_R_N")
	)
	(segment
		(start 264.726928 -184.970928)
		(end 261.987538 -182.231538)
		(width 0.15494)
		(layer "In5.Cu")
		(net "PEX2_PCA9555_INT_R_N")
	)
	(segment
		(start 264.9474 -205.8416)
		(end 264.16 -205.0542)
		(width 0.15494)
		(layer "In5.Cu")
		(net "PEX2_PCA9555_INT_R_N")
	)
	(segment
		(start 269.002002 -224.543874)
		(end 269.002002 -212.23732)
		(width 0.15494)
		(layer "In5.Cu")
		(net "PEX2_PCA9555_INT_R_N")
	)
	(segment
		(start 267.778484 -243.775484)
		(end 267.778484 -229.36073)
		(width 0.15494)
		(layer "In5.Cu")
		(net "PEX2_PCA9555_INT_R_N")
	)
	(segment
		(start 261.987538 -181.184296)
		(end 261.59079 -180.787548)
		(width 0.15494)
		(layer "In5.Cu")
		(net "PEX2_PCA9555_INT_R_N")
	)
	(segment
		(start 264.16 -198.753984)
		(end 264.726928 -197.385178)
		(width 0.15494)
		(layer "In5.Cu")
		(net "PEX2_PCA9555_INT_R_N")
	)
	(segment
		(start 264.9474 -208.182718)
		(end 264.9474 -205.8416)
		(width 0.15494)
		(layer "In5.Cu")
		(net "PEX2_PCA9555_INT_R_N")
	)
	(segment
		(start 272.266156 -252.97257)
		(end 272.266156 -248.263156)
		(width 0.15494)
		(layer "In5.Cu")
		(net "PEX2_PCA9555_INT_R_N")
	)
	(segment
		(start 268.2748 -228.864414)
		(end 268.2748 -225.271076)
		(width 0.15494)
		(layer "In5.Cu")
		(net "PEX2_PCA9555_INT_R_N")
	)
	(segment
		(start 272.266156 -248.263156)
		(end 267.778484 -243.775484)
		(width 0.15494)
		(layer "In5.Cu")
		(net "PEX2_PCA9555_INT_R_N")
	)
	(segment
		(start 269.002002 -212.23732)
		(end 264.9474 -208.182718)
		(width 0.15494)
		(layer "In5.Cu")
		(net "PEX2_PCA9555_INT_R_N")
	)
	(segment
		(start 267.778484 -229.36073)
		(end 268.2748 -228.864414)
		(width 0.15494)
		(layer "In5.Cu")
		(net "PEX2_PCA9555_INT_R_N")
	)
	(segment
		(start 271.782286 -253.45644)
		(end 272.266156 -252.97257)
		(width 0.15494)
		(layer "In5.Cu")
		(net "PEX2_PCA9555_INT_R_N")
	)
	(segment
		(start 264.16 -205.0542)
		(end 264.16 -198.753984)
		(width 0.15494)
		(layer "In5.Cu")
		(net "PEX2_PCA9555_INT_R_N")
	)
	(segment
		(start 261.987538 -182.231538)
		(end 261.987538 -181.184296)
		(width 0.15494)
		(layer "In5.Cu")
		(net "PEX2_PCA9555_INT_R_N")
	)
	(segment
		(start 264.726928 -197.385178)
		(end 264.726928 -184.970928)
		(width 0.15494)
		(layer "In5.Cu")
		(net "PEX2_PCA9555_INT_R_N")
	)
	(segment
		(start 261.85114 -180.527198)
		(end 261.59079 -180.787548)
		(width 0.15494)
		(layer "In13.Cu")
		(net "PEX2_PCA9555_INT_R_N")
	)
	(segment
		(start 276.493986 -187.061856)
		(end 269.959328 -180.527198)
		(width 0.15494)
		(layer "In13.Cu")
		(net "PEX2_PCA9555_INT_R_N")
	)
	(segment
		(start 269.959328 -180.527198)
		(end 261.85114 -180.527198)
		(width 0.15494)
		(layer "In13.Cu")
		(net "PEX2_PCA9555_INT_R_N")
	)
	(segment
		(start 337.05038 -187.061856)
		(end 276.493986 -187.061856)
		(width 0.15494)
		(layer "In13.Cu")
		(net "PEX2_PCA9555_INT_R_N")
	)
	(segment
		(start 338.47405 -165.989)
		(end 339.852 -165.989)
		(width 0.13208)
		(layer "F.Cu")
		(net "SSD11_PEX_PWR_EN")
	)
	(segment
		(start 342.599772 -167.665908)
		(end 343.149936 -167.665908)
		(width 0.13208)
		(layer "F.Cu")
		(net "SSD11_PEX_PWR_EN")
	)
	(segment
		(start 340.5505 -166.6875)
		(end 340.6775 -166.6875)
		(width 0.13208)
		(layer "F.Cu")
		(net "SSD11_PEX_PWR_EN")
	)
	(segment
		(start 340.6775 -166.6875)
		(end 341.133684 -167.143684)
		(width 0.13208)
		(layer "F.Cu")
		(net "SSD11_PEX_PWR_EN")
	)
	(segment
		(start 341.133684 -167.143684)
		(end 342.077548 -167.143684)
		(width 0.13208)
		(layer "F.Cu")
		(net "SSD11_PEX_PWR_EN")
	)
	(segment
		(start 339.852 -165.989)
		(end 340.5505 -166.6875)
		(width 0.13208)
		(layer "F.Cu")
		(net "SSD11_PEX_PWR_EN")
	)
	(segment
		(start 342.077548 -167.143684)
		(end 342.599772 -167.665908)
		(width 0.13208)
		(layer "F.Cu")
		(net "SSD11_PEX_PWR_EN")
	)
	(via
		(at 339.852 -165.989)
		(size 0.508)
		(drill 0.254)
		(layers "F.Cu" "B.Cu")
		(net "SSD11_PEX_PWR_EN")
	)
	(segment
		(start 335.145634 -84.96427)
		(end 334.313022 -84.96427)
		(width 0.1778)
		(layer "F.Cu")
		(net "SSD8_CLK_EN_R_N")
	)
	(segment
		(start 334.313022 -84.96427)
		(end 334.110838 -84.762086)
		(width 0.1778)
		(layer "F.Cu")
		(net "SSD8_CLK_EN_R_N")
	)
	(via
		(at 334.110838 -84.762086)
		(size 0.508)
		(drill 0.254)
		(layers "F.Cu" "B.Cu")
		(net "SSD8_CLK_EN_R_N")
	)
	(via
		(at 334.01 -206.15148)
		(size 0.508)
		(drill 0.254)
		(layers "F.Cu" "B.Cu")
		(net "SSD8_CLK_EN_R_N")
	)
	(segment
		(start 334.01 -206.15148)
		(end 334.01 -207.37195)
		(width 0.13208)
		(layer "B.Cu")
		(net "SSD8_CLK_EN_R_N")
	)
	(segment
		(start 334.757014 -89.95156)
		(end 334.757014 -85.408262)
		(width 0.15494)
		(layer "In9.Cu")
		(net "SSD8_CLK_EN_R_N")
	)
	(segment
		(start 342.73744 -93.283786)
		(end 338.08924 -93.283786)
		(width 0.15494)
		(layer "In9.Cu")
		(net "SSD8_CLK_EN_R_N")
	)
	(segment
		(start 347.2688 -97.815146)
		(end 342.73744 -93.283786)
		(width 0.15494)
		(layer "In9.Cu")
		(net "SSD8_CLK_EN_R_N")
	)
	(segment
		(start 339.463888 -186.570112)
		(end 340.581488 -186.570112)
		(width 0.15494)
		(layer "In9.Cu")
		(net "SSD8_CLK_EN_R_N")
	)
	(segment
		(start 334.01 -192.024)
		(end 339.463888 -186.570112)
		(width 0.15494)
		(layer "In9.Cu")
		(net "SSD8_CLK_EN_R_N")
	)
	(segment
		(start 334.757014 -85.408262)
		(end 334.110838 -84.762086)
		(width 0.15494)
		(layer "In9.Cu")
		(net "SSD8_CLK_EN_R_N")
	)
	(segment
		(start 344.7542 -139.3952)
		(end 345.84894 -138.30046)
		(width 0.15494)
		(layer "In9.Cu")
		(net "SSD8_CLK_EN_R_N")
	)
	(segment
		(start 347.2688 -121.207276)
		(end 347.2688 -97.815146)
		(width 0.15494)
		(layer "In9.Cu")
		(net "SSD8_CLK_EN_R_N")
	)
	(segment
		(start 334.01 -206.15148)
		(end 334.01 -192.024)
		(width 0.15494)
		(layer "In9.Cu")
		(net "SSD8_CLK_EN_R_N")
	)
	(segment
		(start 345.84894 -122.627136)
		(end 347.2688 -121.207276)
		(width 0.15494)
		(layer "In9.Cu")
		(net "SSD8_CLK_EN_R_N")
	)
	(segment
		(start 344.7542 -182.3974)
		(end 344.7542 -139.3952)
		(width 0.15494)
		(layer "In9.Cu")
		(net "SSD8_CLK_EN_R_N")
	)
	(segment
		(start 338.08924 -93.283786)
		(end 334.757014 -89.95156)
		(width 0.15494)
		(layer "In9.Cu")
		(net "SSD8_CLK_EN_R_N")
	)
	(segment
		(start 340.581488 -186.570112)
		(end 344.7542 -182.3974)
		(width 0.15494)
		(layer "In9.Cu")
		(net "SSD8_CLK_EN_R_N")
	)
	(segment
		(start 345.84894 -138.30046)
		(end 345.84894 -122.627136)
		(width 0.15494)
		(layer "In9.Cu")
		(net "SSD8_CLK_EN_R_N")
	)
	(segment
		(start 335.64195 -186.055)
		(end 335.63433 -186.06262)
		(width 0.13208)
		(layer "F.Cu")
		(net "PEX2_PCA9555_INT_N")
	)
	(segment
		(start 335.63433 -186.06262)
		(end 335.63433 -187.061856)
		(width 0.13208)
		(layer "F.Cu")
		(net "PEX2_PCA9555_INT_N")
	)
	(segment
		(start 335.64195 -174.117)
		(end 335.026 -174.117)
		(width 0.13208)
		(layer "F.Cu")
		(net "PEX2_PCA9555_INT_N")
	)
	(segment
		(start 335.026 -186.055)
		(end 335.64195 -186.055)
		(width 0.13208)
		(layer "F.Cu")
		(net "PEX2_PCA9555_INT_N")
	)
	(via
		(at 335.026 -186.055)
		(size 0.508)
		(drill 0.254)
		(layers "F.Cu" "B.Cu")
		(net "PEX2_PCA9555_INT_N")
	)
	(via
		(at 335.026 -174.117)
		(size 0.508)
		(drill 0.254)
		(layers "F.Cu" "B.Cu")
		(net "PEX2_PCA9555_INT_N")
	)
	(segment
		(start 333.908654 -186.055)
		(end 335.026 -186.055)
		(width 0.13208)
		(layer "B.Cu")
		(net "PEX2_PCA9555_INT_N")
	)
	(segment
		(start 332.942692 -185.089038)
		(end 333.908654 -186.055)
		(width 0.13208)
		(layer "B.Cu")
		(net "PEX2_PCA9555_INT_N")
	)
	(segment
		(start 335.026 -174.117)
		(end 332.942692 -176.200308)
		(width 0.13208)
		(layer "B.Cu")
		(net "PEX2_PCA9555_INT_N")
	)
	(segment
		(start 332.942692 -176.200308)
		(end 332.942692 -185.089038)
		(width 0.13208)
		(layer "B.Cu")
		(net "PEX2_PCA9555_INT_N")
	)
	(segment
		(start 338.47405 -164.973)
		(end 339.852 -164.973)
		(width 0.13208)
		(layer "F.Cu")
		(net "RST_PEX_SSD11_PERST_N")
	)
	(segment
		(start 342.071452 -166.494968)
		(end 342.592406 -167.015922)
		(width 0.13208)
		(layer "F.Cu")
		(net "RST_PEX_SSD11_PERST_N")
	)
	(segment
		(start 341.373968 -166.494968)
		(end 342.071452 -166.494968)
		(width 0.13208)
		(layer "F.Cu")
		(net "RST_PEX_SSD11_PERST_N")
	)
	(segment
		(start 339.852 -164.973)
		(end 341.373968 -166.494968)
		(width 0.13208)
		(layer "F.Cu")
		(net "RST_PEX_SSD11_PERST_N")
	)
	(segment
		(start 342.592406 -167.015922)
		(end 343.149936 -167.015922)
		(width 0.13208)
		(layer "F.Cu")
		(net "RST_PEX_SSD11_PERST_N")
	)
	(via
		(at 342.071452 -166.494968)
		(size 0.508)
		(drill 0.254)
		(layers "F.Cu" "B.Cu")
		(net "RST_PEX_SSD11_PERST_N")
	)
	(segment
		(start 341.122 -174.439834)
		(end 340.719156 -174.842678)
		(width 0.13208)
		(layer "F.Cu")
		(net "PEX2_PCA9555_1_INT_N")
	)
	(segment
		(start 337.67395 -174.117)
		(end 337.058 -174.117)
		(width 0.13208)
		(layer "F.Cu")
		(net "PEX2_PCA9555_1_INT_N")
	)
	(segment
		(start 337.67395 -174.498)
		(end 337.67395 -174.117)
		(width 0.13208)
		(layer "F.Cu")
		(net "PEX2_PCA9555_1_INT_N")
	)
	(segment
		(start 340.719156 -174.842678)
		(end 338.018628 -174.842678)
		(width 0.13208)
		(layer "F.Cu")
		(net "PEX2_PCA9555_1_INT_N")
	)
	(segment
		(start 342.159844 -172.965872)
		(end 341.122 -174.003716)
		(width 0.13208)
		(layer "F.Cu")
		(net "PEX2_PCA9555_1_INT_N")
	)
	(segment
		(start 343.149936 -172.965872)
		(end 342.159844 -172.965872)
		(width 0.13208)
		(layer "F.Cu")
		(net "PEX2_PCA9555_1_INT_N")
	)
	(segment
		(start 337.058 -174.117)
		(end 336.44205 -174.117)
		(width 0.13208)
		(layer "F.Cu")
		(net "PEX2_PCA9555_1_INT_N")
	)
	(segment
		(start 338.018628 -174.842678)
		(end 337.67395 -174.498)
		(width 0.13208)
		(layer "F.Cu")
		(net "PEX2_PCA9555_1_INT_N")
	)
	(segment
		(start 341.122 -174.003716)
		(end 341.122 -174.439834)
		(width 0.13208)
		(layer "F.Cu")
		(net "PEX2_PCA9555_1_INT_N")
	)
	(via
		(at 337.058 -174.117)
		(size 0.508)
		(drill 0.254)
		(layers "F.Cu" "B.Cu")
		(net "PEX2_PCA9555_1_INT_N")
	)
	(segment
		(start 338.854034 -192.44945)
		(end 338.357718 -192.44945)
		(width 0.13208)
		(layer "F.Cu")
		(net "FM_CPU_CATERR_MSMI_LVT3_N")
	)
	(segment
		(start 337.462876 -193.344292)
		(end 335.604612 -193.344292)
		(width 0.13208)
		(layer "F.Cu")
		(net "FM_CPU_CATERR_MSMI_LVT3_N")
	)
	(segment
		(start 340.161372 -192.44945)
		(end 338.854034 -192.44945)
		(width 0.13208)
		(layer "F.Cu")
		(net "FM_CPU_CATERR_MSMI_LVT3_N")
	)
	(segment
		(start 338.357718 -192.44945)
		(end 337.462876 -193.344292)
		(width 0.13208)
		(layer "F.Cu")
		(net "FM_CPU_CATERR_MSMI_LVT3_N")
	)
	(via
		(at 338.854034 -192.44945)
		(size 0.762)
		(drill 0.381)
		(layers "F.Cu" "B.Cu")
		(net "FM_CPU_CATERR_MSMI_LVT3_N")
	)
	(segment
		(start 333.42326 -221.58706)
		(end 334.09382 -221.58706)
		(width 0.13208)
		(layer "F.Cu")
		(net "LED_POSTCODE_5")
	)
	(segment
		(start 327.606914 -221.990412)
		(end 328.028808 -221.568518)
		(width 0.13208)
		(layer "F.Cu")
		(net "LED_POSTCODE_5")
	)
	(segment
		(start 332.33868 -221.71152)
		(end 333.2988 -221.71152)
		(width 0.13208)
		(layer "F.Cu")
		(net "LED_POSTCODE_5")
	)
	(segment
		(start 328.29627 -192.04432)
		(end 327.660254 -191.408304)
		(width 0.13208)
		(layer "F.Cu")
		(net "LED_POSTCODE_5")
	)
	(segment
		(start 331.291946 -222.0468)
		(end 332.0034 -222.0468)
		(width 0.13208)
		(layer "F.Cu")
		(net "LED_POSTCODE_5")
	)
	(segment
		(start 328.3458 -220.9292)
		(end 328.725784 -220.9292)
		(width 0.13208)
		(layer "F.Cu")
		(net "LED_POSTCODE_5")
	)
	(segment
		(start 332.0034 -222.0468)
		(end 332.33868 -221.71152)
		(width 0.13208)
		(layer "F.Cu")
		(net "LED_POSTCODE_5")
	)
	(segment
		(start 330.860146 -222.4786)
		(end 331.291946 -222.0468)
		(width 0.13208)
		(layer "F.Cu")
		(net "LED_POSTCODE_5")
	)
	(segment
		(start 325.552054 -221.285816)
		(end 326.25665 -221.990412)
		(width 0.13208)
		(layer "F.Cu")
		(net "LED_POSTCODE_5")
	)
	(segment
		(start 328.028808 -221.568518)
		(end 328.028808 -221.246192)
		(width 0.13208)
		(layer "F.Cu")
		(net "LED_POSTCODE_5")
	)
	(segment
		(start 333.2988 -221.71152)
		(end 333.42326 -221.58706)
		(width 0.13208)
		(layer "F.Cu")
		(net "LED_POSTCODE_5")
	)
	(segment
		(start 328.028808 -221.246192)
		(end 328.3458 -220.9292)
		(width 0.13208)
		(layer "F.Cu")
		(net "LED_POSTCODE_5")
	)
	(segment
		(start 329.754484 -192.04432)
		(end 328.29627 -192.04432)
		(width 0.13208)
		(layer "F.Cu")
		(net "LED_POSTCODE_5")
	)
	(segment
		(start 324.98284 -220.143578)
		(end 325.552054 -220.712792)
		(width 0.13208)
		(layer "F.Cu")
		(net "LED_POSTCODE_5")
	)
	(segment
		(start 325.552054 -220.712792)
		(end 325.552054 -221.285816)
		(width 0.13208)
		(layer "F.Cu")
		(net "LED_POSTCODE_5")
	)
	(segment
		(start 326.25665 -221.990412)
		(end 327.606914 -221.990412)
		(width 0.13208)
		(layer "F.Cu")
		(net "LED_POSTCODE_5")
	)
	(segment
		(start 324.98284 -219.579698)
		(end 324.98284 -220.143578)
		(width 0.13208)
		(layer "F.Cu")
		(net "LED_POSTCODE_5")
	)
	(segment
		(start 328.725784 -220.9292)
		(end 330.275184 -222.4786)
		(width 0.13208)
		(layer "F.Cu")
		(net "LED_POSTCODE_5")
	)
	(segment
		(start 324.98284 -219.579698)
		(end 324.317868 -219.579698)
		(width 0.13208)
		(layer "F.Cu")
		(net "LED_POSTCODE_5")
	)
	(segment
		(start 330.275184 -222.4786)
		(end 330.860146 -222.4786)
		(width 0.13208)
		(layer "F.Cu")
		(net "LED_POSTCODE_5")
	)
	(segment
		(start 327.660254 -191.408304)
		(end 325.002906 -191.408304)
		(width 0.13208)
		(layer "F.Cu")
		(net "LED_POSTCODE_5")
	)
	(via
		(at 324.98284 -219.579698)
		(size 0.508)
		(drill 0.254)
		(layers "F.Cu" "B.Cu")
		(net "LED_POSTCODE_5")
	)
	(via
		(at 325.002906 -191.408304)
		(size 0.508)
		(drill 0.254)
		(layers "F.Cu" "B.Cu")
		(net "LED_POSTCODE_5")
	)
	(segment
		(start 324.98284 -218.994228)
		(end 324.98284 -219.579698)
		(width 0.15494)
		(layer "In7.Cu")
		(net "LED_POSTCODE_5")
	)
	(segment
		(start 325.977758 -191.408304)
		(end 327.9902 -193.420746)
		(width 0.15494)
		(layer "In7.Cu")
		(net "LED_POSTCODE_5")
	)
	(segment
		(start 326.62622 -199.79259)
		(end 323.701156 -202.717654)
		(width 0.15494)
		(layer "In7.Cu")
		(net "LED_POSTCODE_5")
	)
	(segment
		(start 327.9902 -193.420746)
		(end 327.9902 -195.325746)
		(width 0.15494)
		(layer "In7.Cu")
		(net "LED_POSTCODE_5")
	)
	(segment
		(start 323.701156 -202.717654)
		(end 323.701156 -217.712544)
		(width 0.15494)
		(layer "In7.Cu")
		(net "LED_POSTCODE_5")
	)
	(segment
		(start 325.002906 -191.408304)
		(end 325.977758 -191.408304)
		(width 0.15494)
		(layer "In7.Cu")
		(net "LED_POSTCODE_5")
	)
	(segment
		(start 327.9902 -195.325746)
		(end 326.62622 -196.689726)
		(width 0.15494)
		(layer "In7.Cu")
		(net "LED_POSTCODE_5")
	)
	(segment
		(start 326.62622 -196.689726)
		(end 326.62622 -199.79259)
		(width 0.15494)
		(layer "In7.Cu")
		(net "LED_POSTCODE_5")
	)
	(segment
		(start 323.701156 -217.712544)
		(end 324.98284 -218.994228)
		(width 0.15494)
		(layer "In7.Cu")
		(net "LED_POSTCODE_5")
	)
	(segment
		(start 327.928986 -231.986074)
		(end 327.928986 -232.918)
		(width 0.13208)
		(layer "F.Cu")
		(net "RST_PEX_SYS_BUF_N")
	)
	(segment
		(start 327.928986 -232.918)
		(end 327.89495 -232.952036)
		(width 0.13208)
		(layer "F.Cu")
		(net "RST_PEX_SYS_BUF_N")
	)
	(segment
		(start 327.89495 -232.952036)
		(end 327.89495 -233.553)
		(width 0.13208)
		(layer "F.Cu")
		(net "RST_PEX_SYS_BUF_N")
	)
	(segment
		(start 326.91705 -233.553)
		(end 327.89495 -233.553)
		(width 0.13208)
		(layer "F.Cu")
		(net "RST_PEX_SYS_BUF_N")
	)
	(via
		(at 327.928986 -232.918)
		(size 0.508)
		(drill 0.254)
		(layers "F.Cu" "B.Cu")
		(net "RST_PEX_SYS_BUF_N")
	)
	(segment
		(start 107.038902 -91.199462)
		(end 106.787188 -91.451176)
		(width 0.13208)
		(layer "F.Cu")
		(net "PU_9ZXL0851_0_7_100M")
	)
	(segment
		(start 106.787188 -91.451176)
		(end 106.787188 -91.968828)
		(width 0.13208)
		(layer "F.Cu")
		(net "PU_9ZXL0851_0_7_100M")
	)
	(segment
		(start 107.038902 -88.928956)
		(end 107.038902 -91.199462)
		(width 0.13208)
		(layer "F.Cu")
		(net "PU_9ZXL0851_0_7_100M")
	)
	(segment
		(start 107.817666 -91.968828)
		(end 106.787188 -91.968828)
		(width 0.13208)
		(layer "F.Cu")
		(net "PU_9ZXL0851_0_7_100M")
	)
	(via
		(at 107.038902 -91.199462)
		(size 0.508)
		(drill 0.254)
		(layers "F.Cu" "B.Cu")
		(net "PU_9ZXL0851_0_7_100M")
	)
	(via
		(at 300.085252 -248.651014)
		(size 0.6604)
		(drill 0.3302)
		(layers "F.Cu" "B.Cu")
		(net "MB_I2C_ISO_EN")
	)
	(segment
		(start 300.085252 -247.601994)
		(end 300.425866 -247.26138)
		(width 0.13208)
		(layer "B.Cu")
		(net "MB_I2C_ISO_EN")
	)
	(segment
		(start 301.739554 -249.05208)
		(end 301.510446 -249.281188)
		(width 0.13208)
		(layer "B.Cu")
		(net "MB_I2C_ISO_EN")
	)
	(segment
		(start 300.425866 -247.26138)
		(end 300.425866 -246.841772)
		(width 0.13208)
		(layer "B.Cu")
		(net "MB_I2C_ISO_EN")
	)
	(segment
		(start 301.510446 -249.281188)
		(end 300.715426 -249.281188)
		(width 0.13208)
		(layer "B.Cu")
		(net "MB_I2C_ISO_EN")
	)
	(segment
		(start 300.085252 -248.651014)
		(end 300.085252 -247.601994)
		(width 0.13208)
		(layer "B.Cu")
		(net "MB_I2C_ISO_EN")
	)
	(segment
		(start 300.715426 -249.281188)
		(end 300.085252 -248.651014)
		(width 0.13208)
		(layer "B.Cu")
		(net "MB_I2C_ISO_EN")
	)
	(segment
		(start 301.739554 -248.087388)
		(end 301.739554 -249.05208)
		(width 0.13208)
		(layer "B.Cu")
		(net "MB_I2C_ISO_EN")
	)
	(segment
		(start 337.67395 -167.005)
		(end 337.058 -167.005)
		(width 0.13208)
		(layer "F.Cu")
		(net "PRSNT_SSD11_FPGA_R_N")
	)
	(segment
		(start 327.13295 -212.217)
		(end 326.517 -212.217)
		(width 0.13208)
		(layer "F.Cu")
		(net "PRSNT_SSD11_FPGA_R_N")
	)
	(via
		(at 337.058 -167.005)
		(size 0.508)
		(drill 0.254)
		(layers "F.Cu" "B.Cu")
		(net "PRSNT_SSD11_FPGA_R_N")
	)
	(via
		(at 326.517 -212.217)
		(size 0.508)
		(drill 0.254)
		(layers "F.Cu" "B.Cu")
		(net "PRSNT_SSD11_FPGA_R_N")
	)
	(segment
		(start 335.6102 -172.593)
		(end 337.058 -171.1452)
		(width 0.15494)
		(layer "In9.Cu")
		(net "PRSNT_SSD11_FPGA_R_N")
	)
	(segment
		(start 337.058 -171.1452)
		(end 337.058 -167.005)
		(width 0.15494)
		(layer "In9.Cu")
		(net "PRSNT_SSD11_FPGA_R_N")
	)
	(segment
		(start 326.6694 -199.568054)
		(end 326.6694 -195.554346)
		(width 0.15494)
		(layer "In9.Cu")
		(net "PRSNT_SSD11_FPGA_R_N")
	)
	(segment
		(start 323.975476 -209.675476)
		(end 323.975476 -204.622654)
		(width 0.15494)
		(layer "In9.Cu")
		(net "PRSNT_SSD11_FPGA_R_N")
	)
	(segment
		(start 323.975476 -204.622654)
		(end 324.203568 -202.033886)
		(width 0.15494)
		(layer "In9.Cu")
		(net "PRSNT_SSD11_FPGA_R_N")
	)
	(segment
		(start 324.203568 -202.033886)
		(end 326.6694 -199.568054)
		(width 0.15494)
		(layer "In9.Cu")
		(net "PRSNT_SSD11_FPGA_R_N")
	)
	(segment
		(start 328.353928 -179.087018)
		(end 334.847946 -172.593)
		(width 0.15494)
		(layer "In9.Cu")
		(net "PRSNT_SSD11_FPGA_R_N")
	)
	(segment
		(start 326.517 -212.217)
		(end 323.975476 -209.675476)
		(width 0.15494)
		(layer "In9.Cu")
		(net "PRSNT_SSD11_FPGA_R_N")
	)
	(segment
		(start 328.353928 -179.442618)
		(end 328.353928 -179.087018)
		(width 0.15494)
		(layer "In9.Cu")
		(net "PRSNT_SSD11_FPGA_R_N")
	)
	(segment
		(start 334.847946 -172.593)
		(end 335.6102 -172.593)
		(width 0.15494)
		(layer "In9.Cu")
		(net "PRSNT_SSD11_FPGA_R_N")
	)
	(segment
		(start 327.533 -180.263546)
		(end 328.353928 -179.442618)
		(width 0.15494)
		(layer "In9.Cu")
		(net "PRSNT_SSD11_FPGA_R_N")
	)
	(segment
		(start 326.6694 -195.554346)
		(end 327.533 -194.690746)
		(width 0.15494)
		(layer "In9.Cu")
		(net "PRSNT_SSD11_FPGA_R_N")
	)
	(segment
		(start 327.533 -194.690746)
		(end 327.533 -180.263546)
		(width 0.15494)
		(layer "In9.Cu")
		(net "PRSNT_SSD11_FPGA_R_N")
	)
	(segment
		(start 236.460284 -230.589328)
		(end 236.887512 -231.016556)
		(width 0.13208)
		(layer "F.Cu")
		(net "SSD6_PWRDIS_BIC")
	)
	(segment
		(start 233.465116 -227.285296)
		(end 233.465116 -227.695252)
		(width 0.13208)
		(layer "F.Cu")
		(net "SSD6_PWRDIS_BIC")
	)
	(segment
		(start 231.86771 -224.304098)
		(end 231.86771 -225.68789)
		(width 0.13208)
		(layer "F.Cu")
		(net "SSD6_PWRDIS_BIC")
	)
	(segment
		(start 233.465116 -229.655116)
		(end 233.8578 -230.0478)
		(width 0.13208)
		(layer "F.Cu")
		(net "SSD6_PWRDIS_BIC")
	)
	(segment
		(start 233.465116 -227.695252)
		(end 233.465116 -229.655116)
		(width 0.13208)
		(layer "F.Cu")
		(net "SSD6_PWRDIS_BIC")
	)
	(segment
		(start 231.86771 -225.68789)
		(end 233.465116 -227.285296)
		(width 0.13208)
		(layer "F.Cu")
		(net "SSD6_PWRDIS_BIC")
	)
	(segment
		(start 233.8578 -230.0478)
		(end 235.416344 -230.0478)
		(width 0.13208)
		(layer "F.Cu")
		(net "SSD6_PWRDIS_BIC")
	)
	(segment
		(start 235.416344 -230.0478)
		(end 235.957872 -230.589328)
		(width 0.13208)
		(layer "F.Cu")
		(net "SSD6_PWRDIS_BIC")
	)
	(segment
		(start 231.46766 -223.904048)
		(end 231.86771 -224.304098)
		(width 0.13208)
		(layer "F.Cu")
		(net "SSD6_PWRDIS_BIC")
	)
	(segment
		(start 235.957872 -230.589328)
		(end 236.460284 -230.589328)
		(width 0.13208)
		(layer "F.Cu")
		(net "SSD6_PWRDIS_BIC")
	)
	(via
		(at 233.465116 -227.695252)
		(size 0.762)
		(drill 0.381)
		(layers "F.Cu" "B.Cu")
		(net "SSD6_PWRDIS_BIC")
	)
	(segment
		(start 326.930004 -193.313304)
		(end 327.611232 -193.994532)
		(width 0.13208)
		(layer "F.Cu")
		(net "LED_POSTCODE_2")
	)
	(segment
		(start 325.764906 -193.313304)
		(end 326.930004 -193.313304)
		(width 0.13208)
		(layer "F.Cu")
		(net "LED_POSTCODE_2")
	)
	(segment
		(start 327.611232 -193.994532)
		(end 329.754484 -193.994532)
		(width 0.13208)
		(layer "F.Cu")
		(net "LED_POSTCODE_2")
	)
	(segment
		(start 336.493866 -221.58706)
		(end 336.093816 -221.98711)
		(width 0.13208)
		(layer "F.Cu")
		(net "LED_POSTCODE_2")
	)
	(segment
		(start 324.317868 -223.389698)
		(end 324.98284 -223.389698)
		(width 0.13208)
		(layer "F.Cu")
		(net "LED_POSTCODE_2")
	)
	(via
		(at 325.764906 -193.313304)
		(size 0.508)
		(drill 0.254)
		(layers "F.Cu" "B.Cu")
		(net "LED_POSTCODE_2")
	)
	(via
		(at 324.98284 -223.389698)
		(size 0.508)
		(drill 0.254)
		(layers "F.Cu" "B.Cu")
		(net "LED_POSTCODE_2")
	)
	(via
		(at 336.093816 -221.98711)
		(size 0.4572)
		(drill 0.254)
		(layers "F.Cu" "B.Cu")
		(net "LED_POSTCODE_2")
	)
	(segment
		(start 324.427596 -222.834454)
		(end 324.427596 -221.881446)
		(width 0.13208)
		(layer "B.Cu")
		(net "LED_POSTCODE_2")
	)
	(segment
		(start 332.55331 -220.726)
		(end 333.100934 -220.726)
		(width 0.13208)
		(layer "B.Cu")
		(net "LED_POSTCODE_2")
	)
	(segment
		(start 333.575406 -221.200472)
		(end 334.484472 -221.200472)
		(width 0.13208)
		(layer "B.Cu")
		(net "LED_POSTCODE_2")
	)
	(segment
		(start 330.613766 -220.589094)
		(end 330.954888 -220.930216)
		(width 0.13208)
		(layer "B.Cu")
		(net "LED_POSTCODE_2")
	)
	(segment
		(start 335.693766 -221.58706)
		(end 336.093816 -221.98711)
		(width 0.0889)
		(layer "B.Cu")
		(net "LED_POSTCODE_2")
	)
	(segment
		(start 334.87106 -221.58706)
		(end 335.693766 -221.58706)
		(width 0.0889)
		(layer "B.Cu")
		(net "LED_POSTCODE_2")
	)
	(segment
		(start 324.427596 -221.881446)
		(end 324.752208 -221.556834)
		(width 0.13208)
		(layer "B.Cu")
		(net "LED_POSTCODE_2")
	)
	(segment
		(start 328.182478 -220.589094)
		(end 330.613766 -220.589094)
		(width 0.13208)
		(layer "B.Cu")
		(net "LED_POSTCODE_2")
	)
	(segment
		(start 334.484472 -221.200472)
		(end 334.87106 -221.58706)
		(width 0.13208)
		(layer "B.Cu")
		(net "LED_POSTCODE_2")
	)
	(segment
		(start 326.28332 -221.556834)
		(end 326.805798 -221.034356)
		(width 0.13208)
		(layer "B.Cu")
		(net "LED_POSTCODE_2")
	)
	(segment
		(start 332.349094 -220.930216)
		(end 332.55331 -220.726)
		(width 0.13208)
		(layer "B.Cu")
		(net "LED_POSTCODE_2")
	)
	(segment
		(start 330.954888 -220.930216)
		(end 332.349094 -220.930216)
		(width 0.13208)
		(layer "B.Cu")
		(net "LED_POSTCODE_2")
	)
	(segment
		(start 324.98284 -223.389698)
		(end 324.427596 -222.834454)
		(width 0.13208)
		(layer "B.Cu")
		(net "LED_POSTCODE_2")
	)
	(segment
		(start 324.752208 -221.556834)
		(end 326.28332 -221.556834)
		(width 0.13208)
		(layer "B.Cu")
		(net "LED_POSTCODE_2")
	)
	(segment
		(start 333.100934 -220.726)
		(end 333.575406 -221.200472)
		(width 0.13208)
		(layer "B.Cu")
		(net "LED_POSTCODE_2")
	)
	(segment
		(start 327.737216 -221.034356)
		(end 328.182478 -220.589094)
		(width 0.13208)
		(layer "B.Cu")
		(net "LED_POSTCODE_2")
	)
	(segment
		(start 326.805798 -221.034356)
		(end 327.737216 -221.034356)
		(width 0.13208)
		(layer "B.Cu")
		(net "LED_POSTCODE_2")
	)
	(segment
		(start 325.5518 -196.723)
		(end 324.358 -196.723)
		(width 0.15494)
		(layer "In7.Cu")
		(net "LED_POSTCODE_2")
	)
	(segment
		(start 326.644 -194.192398)
		(end 326.644 -194.9958)
		(width 0.15494)
		(layer "In7.Cu")
		(net "LED_POSTCODE_2")
	)
	(segment
		(start 323.180456 -222.119698)
		(end 323.71284 -222.119698)
		(width 0.15494)
		(layer "In7.Cu")
		(net "LED_POSTCODE_2")
	)
	(segment
		(start 321.8688 -220.808042)
		(end 323.180456 -222.119698)
		(width 0.15494)
		(layer "In7.Cu")
		(net "LED_POSTCODE_2")
	)
	(segment
		(start 321.8688 -199.2122)
		(end 321.8688 -220.808042)
		(width 0.15494)
		(layer "In7.Cu")
		(net "LED_POSTCODE_2")
	)
	(segment
		(start 324.358 -196.723)
		(end 321.8688 -199.2122)
		(width 0.15494)
		(layer "In7.Cu")
		(net "LED_POSTCODE_2")
	)
	(segment
		(start 323.71284 -222.119698)
		(end 324.98284 -223.389698)
		(width 0.15494)
		(layer "In7.Cu")
		(net "LED_POSTCODE_2")
	)
	(segment
		(start 325.5518 -196.088)
		(end 325.5518 -196.723)
		(width 0.15494)
		(layer "In7.Cu")
		(net "LED_POSTCODE_2")
	)
	(segment
		(start 326.644 -194.9958)
		(end 325.5518 -196.088)
		(width 0.15494)
		(layer "In7.Cu")
		(net "LED_POSTCODE_2")
	)
	(segment
		(start 325.764906 -193.313304)
		(end 326.644 -194.192398)
		(width 0.15494)
		(layer "In7.Cu")
		(net "LED_POSTCODE_2")
	)
	(segment
		(start 231.46766 -222.304102)
		(end 231.867456 -222.703898)
		(width 0.13208)
		(layer "F.Cu")
		(net "SSD3_PWRDIS_BIC")
	)
	(via
		(at 232.206546 -226.076002)
		(size 0.6604)
		(drill 0.3302)
		(layers "F.Cu" "B.Cu")
		(net "SSD3_PWRDIS_BIC")
	)
	(via
		(at 231.867456 -222.703898)
		(size 0.4572)
		(drill 0.254)
		(layers "F.Cu" "B.Cu")
		(net "SSD3_PWRDIS_BIC")
	)
	(segment
		(start 234.520994 -230.058976)
		(end 234.520994 -228.39045)
		(width 0.13208)
		(layer "B.Cu")
		(net "SSD3_PWRDIS_BIC")
	)
	(segment
		(start 232.264712 -226.017836)
		(end 232.206546 -226.076002)
		(width 0.13208)
		(layer "B.Cu")
		(net "SSD3_PWRDIS_BIC")
	)
	(segment
		(start 234.514644 -230.825548)
		(end 234.514644 -230.065326)
		(width 0.13208)
		(layer "B.Cu")
		(net "SSD3_PWRDIS_BIC")
	)
	(segment
		(start 232.264712 -223.101154)
		(end 232.264712 -223.9264)
		(width 0.0889)
		(layer "B.Cu")
		(net "SSD3_PWRDIS_BIC")
	)
	(segment
		(start 231.867456 -222.703898)
		(end 232.264712 -223.101154)
		(width 0.0889)
		(layer "B.Cu")
		(net "SSD3_PWRDIS_BIC")
	)
	(segment
		(start 232.264712 -223.9264)
		(end 232.264712 -226.017836)
		(width 0.13208)
		(layer "B.Cu")
		(net "SSD3_PWRDIS_BIC")
	)
	(segment
		(start 234.520994 -228.39045)
		(end 232.206546 -226.076002)
		(width 0.13208)
		(layer "B.Cu")
		(net "SSD3_PWRDIS_BIC")
	)
	(segment
		(start 234.514644 -230.065326)
		(end 234.520994 -230.058976)
		(width 0.13208)
		(layer "B.Cu")
		(net "SSD3_PWRDIS_BIC")
	)
	(segment
		(start 337.058 -186.055)
		(end 336.44205 -186.055)
		(width 0.13208)
		(layer "F.Cu")
		(net "PEX2_PCA9555_0_INT_N")
	)
	(segment
		(start 337.80095 -186.563)
		(end 337.67395 -186.436)
		(width 0.13208)
		(layer "F.Cu")
		(net "PEX2_PCA9555_0_INT_N")
	)
	(segment
		(start 337.67395 -186.055)
		(end 337.058 -186.055)
		(width 0.13208)
		(layer "F.Cu")
		(net "PEX2_PCA9555_0_INT_N")
	)
	(segment
		(start 339.598 -186.309)
		(end 339.344 -186.563)
		(width 0.13208)
		(layer "F.Cu")
		(net "PEX2_PCA9555_0_INT_N")
	)
	(segment
		(start 340.754716 -186.309)
		(end 339.598 -186.309)
		(width 0.13208)
		(layer "F.Cu")
		(net "PEX2_PCA9555_0_INT_N")
	)
	(segment
		(start 342.159844 -184.903872)
		(end 340.754716 -186.309)
		(width 0.13208)
		(layer "F.Cu")
		(net "PEX2_PCA9555_0_INT_N")
	)
	(segment
		(start 337.67395 -186.436)
		(end 337.67395 -186.055)
		(width 0.13208)
		(layer "F.Cu")
		(net "PEX2_PCA9555_0_INT_N")
	)
	(segment
		(start 339.344 -186.563)
		(end 337.80095 -186.563)
		(width 0.13208)
		(layer "F.Cu")
		(net "PEX2_PCA9555_0_INT_N")
	)
	(segment
		(start 343.149936 -184.903872)
		(end 342.159844 -184.903872)
		(width 0.13208)
		(layer "F.Cu")
		(net "PEX2_PCA9555_0_INT_N")
	)
	(via
		(at 337.058 -186.055)
		(size 0.508)
		(drill 0.254)
		(layers "F.Cu" "B.Cu")
		(net "PEX2_PCA9555_0_INT_N")
	)
	(segment
		(start 338.893912 -220.78696)
		(end 338.494116 -221.186756)
		(width 0.13208)
		(layer "F.Cu")
		(net "LED_POSTCODE_6")
	)
	(segment
		(start 327.834498 -190.773304)
		(end 325.764906 -190.773304)
		(width 0.13208)
		(layer "F.Cu")
		(net "LED_POSTCODE_6")
	)
	(segment
		(start 328.455528 -191.394334)
		(end 327.834498 -190.773304)
		(width 0.13208)
		(layer "F.Cu")
		(net "LED_POSTCODE_6")
	)
	(segment
		(start 329.754484 -191.394334)
		(end 328.455528 -191.394334)
		(width 0.13208)
		(layer "F.Cu")
		(net "LED_POSTCODE_6")
	)
	(segment
		(start 324.317868 -218.309698)
		(end 324.98284 -218.309698)
		(width 0.13208)
		(layer "F.Cu")
		(net "LED_POSTCODE_6")
	)
	(via
		(at 324.98284 -218.309698)
		(size 0.508)
		(drill 0.254)
		(layers "F.Cu" "B.Cu")
		(net "LED_POSTCODE_6")
	)
	(via
		(at 325.764906 -190.773304)
		(size 0.508)
		(drill 0.254)
		(layers "F.Cu" "B.Cu")
		(net "LED_POSTCODE_6")
	)
	(via
		(at 338.494116 -221.186756)
		(size 0.4572)
		(drill 0.254)
		(layers "F.Cu" "B.Cu")
		(net "LED_POSTCODE_6")
	)
	(segment
		(start 334.238092 -221.584266)
		(end 334.128872 -221.693486)
		(width 0.15494)
		(layer "In5.Cu")
		(net "LED_POSTCODE_6")
	)
	(segment
		(start 326.912224 -219.821252)
		(end 326.306942 -219.821252)
		(width 0.15494)
		(layer "In5.Cu")
		(net "LED_POSTCODE_6")
	)
	(segment
		(start 328.671936 -220.726)
		(end 327.816972 -220.726)
		(width 0.15494)
		(layer "In5.Cu")
		(net "LED_POSTCODE_6")
	)
	(segment
		(start 326.2122 -219.72651)
		(end 325.542402 -218.86926)
		(width 0.15494)
		(layer "In5.Cu")
		(net "LED_POSTCODE_6")
	)
	(segment
		(start 326.306942 -219.821252)
		(end 326.2122 -219.72651)
		(width 0.15494)
		(layer "In5.Cu")
		(net "LED_POSTCODE_6")
	)
	(segment
		(start 335.056734 -221.584266)
		(end 334.238092 -221.584266)
		(width 0.15494)
		(layer "In5.Cu")
		(net "LED_POSTCODE_6")
	)
	(segment
		(start 327.816972 -220.726)
		(end 326.912224 -219.821252)
		(width 0.15494)
		(layer "In5.Cu")
		(net "LED_POSTCODE_6")
	)
	(segment
		(start 338.096606 -221.584266)
		(end 335.056734 -221.584266)
		(width 0.0889)
		(layer "In5.Cu")
		(net "LED_POSTCODE_6")
	)
	(segment
		(start 329.639422 -221.693486)
		(end 328.671936 -220.726)
		(width 0.15494)
		(layer "In5.Cu")
		(net "LED_POSTCODE_6")
	)
	(segment
		(start 338.494116 -221.186756)
		(end 338.096606 -221.584266)
		(width 0.0889)
		(layer "In5.Cu")
		(net "LED_POSTCODE_6")
	)
	(segment
		(start 334.128872 -221.693486)
		(end 329.639422 -221.693486)
		(width 0.15494)
		(layer "In5.Cu")
		(net "LED_POSTCODE_6")
	)
	(segment
		(start 325.542402 -218.86926)
		(end 324.98284 -218.309698)
		(width 0.15494)
		(layer "In5.Cu")
		(net "LED_POSTCODE_6")
	)
	(segment
		(start 326.012302 -190.773304)
		(end 328.59726 -193.358262)
		(width 0.15494)
		(layer "In7.Cu")
		(net "LED_POSTCODE_6")
	)
	(segment
		(start 327.739756 -196.705474)
		(end 326.98436 -197.46087)
		(width 0.15494)
		(layer "In7.Cu")
		(net "LED_POSTCODE_6")
	)
	(segment
		(start 326.98436 -197.46087)
		(end 326.98436 -199.94118)
		(width 0.15494)
		(layer "In7.Cu")
		(net "LED_POSTCODE_6")
	)
	(segment
		(start 326.98436 -199.94118)
		(end 324.059296 -202.866244)
		(width 0.15494)
		(layer "In7.Cu")
		(net "LED_POSTCODE_6")
	)
	(segment
		(start 324.059296 -217.386154)
		(end 324.98284 -218.309698)
		(width 0.15494)
		(layer "In7.Cu")
		(net "LED_POSTCODE_6")
	)
	(segment
		(start 328.59726 -193.358262)
		(end 328.59726 -196.235828)
		(width 0.15494)
		(layer "In7.Cu")
		(net "LED_POSTCODE_6")
	)
	(segment
		(start 328.59726 -196.235828)
		(end 328.127614 -196.705474)
		(width 0.15494)
		(layer "In7.Cu")
		(net "LED_POSTCODE_6")
	)
	(segment
		(start 325.764906 -190.773304)
		(end 326.012302 -190.773304)
		(width 0.15494)
		(layer "In7.Cu")
		(net "LED_POSTCODE_6")
	)
	(segment
		(start 324.059296 -202.866244)
		(end 324.059296 -217.386154)
		(width 0.15494)
		(layer "In7.Cu")
		(net "LED_POSTCODE_6")
	)
	(segment
		(start 328.127614 -196.705474)
		(end 327.739756 -196.705474)
		(width 0.15494)
		(layer "In7.Cu")
		(net "LED_POSTCODE_6")
	)
	(segment
		(start 239.48771 -230.837994)
		(end 237.446058 -228.796342)
		(width 0.13208)
		(layer "F.Cu")
		(net "SSD1_PWRDIS_BIC")
	)
	(segment
		(start 239.935512 -231.016556)
		(end 239.75695 -230.837994)
		(width 0.13208)
		(layer "F.Cu")
		(net "SSD1_PWRDIS_BIC")
	)
	(segment
		(start 239.75695 -230.837994)
		(end 239.48771 -230.837994)
		(width 0.13208)
		(layer "F.Cu")
		(net "SSD1_PWRDIS_BIC")
	)
	(segment
		(start 235.370116 -228.796342)
		(end 235.370116 -227.006658)
		(width 0.13208)
		(layer "F.Cu")
		(net "SSD1_PWRDIS_BIC")
	)
	(segment
		(start 237.446058 -228.796342)
		(end 235.370116 -228.796342)
		(width 0.13208)
		(layer "F.Cu")
		(net "SSD1_PWRDIS_BIC")
	)
	(segment
		(start 235.370116 -227.006658)
		(end 233.067606 -224.704148)
		(width 0.13208)
		(layer "F.Cu")
		(net "SSD1_PWRDIS_BIC")
	)
	(via
		(at 235.370116 -228.796342)
		(size 0.762)
		(drill 0.381)
		(layers "F.Cu" "B.Cu")
		(net "SSD1_PWRDIS_BIC")
	)
	(segment
		(start 377.226068 -92.475304)
		(end 381.046736 -92.475304)
		(width 0.13208)
		(layer "F.Cu")
		(net "SMB_BIC_I2C6_SENEOR_SCL")
	)
	(segment
		(start 385.805426 -88.245188)
		(end 385.963922 -88.086692)
		(width 0.13208)
		(layer "F.Cu")
		(net "SMB_BIC_I2C6_SENEOR_SCL")
	)
	(segment
		(start 228.312726 -88.183974)
		(end 226.87915 -86.750398)
		(width 0.13208)
		(layer "F.Cu")
		(net "SMB_BIC_I2C6_SENEOR_SCL")
	)
	(segment
		(start 381.046736 -92.475304)
		(end 385.276852 -88.245188)
		(width 0.13208)
		(layer "F.Cu")
		(net "SMB_BIC_I2C6_SENEOR_SCL")
	)
	(segment
		(start 228.312726 -89.182956)
		(end 228.312726 -88.183974)
		(width 0.13208)
		(layer "F.Cu")
		(net "SMB_BIC_I2C6_SENEOR_SCL")
	)
	(segment
		(start 385.276852 -88.245188)
		(end 385.805426 -88.245188)
		(width 0.13208)
		(layer "F.Cu")
		(net "SMB_BIC_I2C6_SENEOR_SCL")
	)
	(segment
		(start 376.098308 -93.603064)
		(end 377.226068 -92.475304)
		(width 0.13208)
		(layer "F.Cu")
		(net "SMB_BIC_I2C6_SENEOR_SCL")
	)
	(segment
		(start 226.87915 -86.750398)
		(end 226.431348 -86.750398)
		(width 0.13208)
		(layer "F.Cu")
		(net "SMB_BIC_I2C6_SENEOR_SCL")
	)
	(segment
		(start 385.963922 -88.086692)
		(end 388.24027 -88.086692)
		(width 0.13208)
		(layer "F.Cu")
		(net "SMB_BIC_I2C6_SENEOR_SCL")
	)
	(via
		(at 228.312726 -89.182956)
		(size 0.508)
		(drill 0.254)
		(layers "F.Cu" "B.Cu")
		(net "SMB_BIC_I2C6_SENEOR_SCL")
	)
	(via
		(at 376.098308 -93.603064)
		(size 0.508)
		(drill 0.254)
		(layers "F.Cu" "B.Cu")
		(net "SMB_BIC_I2C6_SENEOR_SCL")
	)
	(via
		(at 385.276852 -88.245188)
		(size 0.508)
		(drill 0.254)
		(layers "F.Cu" "B.Cu")
		(net "SMB_BIC_I2C6_SENEOR_SCL")
	)
	(via
		(at 277.835614 -94.31909)
		(size 0.508)
		(drill 0.254)
		(layers "F.Cu" "B.Cu")
		(net "SMB_BIC_I2C6_SENEOR_SCL")
	)
	(segment
		(start 275.040852 -92.145104)
		(end 276.946106 -94.050358)
		(width 0.15494)
		(layer "In9.Cu")
		(net "SMB_BIC_I2C6_SENEOR_SCL")
	)
	(segment
		(start 275.035772 -90.603832)
		(end 275.299678 -90.867738)
		(width 0.15494)
		(layer "In9.Cu")
		(net "SMB_BIC_I2C6_SENEOR_SCL")
	)
	(segment
		(start 277.566882 -94.050358)
		(end 277.835614 -94.31909)
		(width 0.15494)
		(layer "In9.Cu")
		(net "SMB_BIC_I2C6_SENEOR_SCL")
	)
	(segment
		(start 274.776946 -91.58097)
		(end 274.776946 -91.77147)
		(width 0.15494)
		(layer "In9.Cu")
		(net "SMB_BIC_I2C6_SENEOR_SCL")
	)
	(segment
		(start 274.776946 -91.77147)
		(end 275.040852 -92.035376)
		(width 0.15494)
		(layer "In9.Cu")
		(net "SMB_BIC_I2C6_SENEOR_SCL")
	)
	(segment
		(start 274.13204 -91.126564)
		(end 274.32254 -91.126564)
		(width 0.15494)
		(layer "In9.Cu")
		(net "SMB_BIC_I2C6_SENEOR_SCL")
	)
	(segment
		(start 251.442982 -96.643444)
		(end 256.689098 -91.397328)
		(width 0.15494)
		(layer "In9.Cu")
		(net "SMB_BIC_I2C6_SENEOR_SCL")
	)
	(segment
		(start 273.868134 -90.672158)
		(end 273.868134 -90.862658)
		(width 0.15494)
		(layer "In9.Cu")
		(net "SMB_BIC_I2C6_SENEOR_SCL")
	)
	(segment
		(start 231.50195 -96.643444)
		(end 251.442982 -96.643444)
		(width 0.15494)
		(layer "In9.Cu")
		(net "SMB_BIC_I2C6_SENEOR_SCL")
	)
	(segment
		(start 267.050012 -89.4842)
		(end 273.91614 -89.4842)
		(width 0.15494)
		(layer "In9.Cu")
		(net "SMB_BIC_I2C6_SENEOR_SCL")
	)
	(segment
		(start 274.32254 -91.126564)
		(end 274.845272 -90.603832)
		(width 0.15494)
		(layer "In9.Cu")
		(net "SMB_BIC_I2C6_SENEOR_SCL")
	)
	(segment
		(start 275.299678 -90.867738)
		(end 275.299678 -91.058238)
		(width 0.15494)
		(layer "In9.Cu")
		(net "SMB_BIC_I2C6_SENEOR_SCL")
	)
	(segment
		(start 274.390866 -89.958926)
		(end 274.390866 -90.149426)
		(width 0.15494)
		(layer "In9.Cu")
		(net "SMB_BIC_I2C6_SENEOR_SCL")
	)
	(segment
		(start 274.390866 -90.149426)
		(end 273.868134 -90.672158)
		(width 0.15494)
		(layer "In9.Cu")
		(net "SMB_BIC_I2C6_SENEOR_SCL")
	)
	(segment
		(start 273.868134 -90.862658)
		(end 274.13204 -91.126564)
		(width 0.15494)
		(layer "In9.Cu")
		(net "SMB_BIC_I2C6_SENEOR_SCL")
	)
	(segment
		(start 274.845272 -90.603832)
		(end 275.035772 -90.603832)
		(width 0.15494)
		(layer "In9.Cu")
		(net "SMB_BIC_I2C6_SENEOR_SCL")
	)
	(segment
		(start 256.689098 -91.397328)
		(end 265.136884 -91.397328)
		(width 0.15494)
		(layer "In9.Cu")
		(net "SMB_BIC_I2C6_SENEOR_SCL")
	)
	(segment
		(start 275.040852 -92.035376)
		(end 275.040852 -92.145104)
		(width 0.15494)
		(layer "In9.Cu")
		(net "SMB_BIC_I2C6_SENEOR_SCL")
	)
	(segment
		(start 228.312726 -89.182956)
		(end 228.312726 -93.45422)
		(width 0.15494)
		(layer "In9.Cu")
		(net "SMB_BIC_I2C6_SENEOR_SCL")
	)
	(segment
		(start 273.91614 -89.4842)
		(end 274.390866 -89.958926)
		(width 0.15494)
		(layer "In9.Cu")
		(net "SMB_BIC_I2C6_SENEOR_SCL")
	)
	(segment
		(start 275.299678 -91.058238)
		(end 274.776946 -91.58097)
		(width 0.15494)
		(layer "In9.Cu")
		(net "SMB_BIC_I2C6_SENEOR_SCL")
	)
	(segment
		(start 265.136884 -91.397328)
		(end 267.050012 -89.4842)
		(width 0.15494)
		(layer "In9.Cu")
		(net "SMB_BIC_I2C6_SENEOR_SCL")
	)
	(segment
		(start 276.946106 -94.050358)
		(end 277.566882 -94.050358)
		(width 0.15494)
		(layer "In9.Cu")
		(net "SMB_BIC_I2C6_SENEOR_SCL")
	)
	(segment
		(start 228.312726 -93.45422)
		(end 231.50195 -96.643444)
		(width 0.15494)
		(layer "In9.Cu")
		(net "SMB_BIC_I2C6_SENEOR_SCL")
	)
	(segment
		(start 311.77484 -91.641168)
		(end 279.376632 -91.641168)
		(width 0.15494)
		(layer "In13.Cu")
		(net "SMB_BIC_I2C6_SENEOR_SCL")
	)
	(segment
		(start 326.358504 -97.7646)
		(end 325.882 -97.288096)
		(width 0.15494)
		(layer "In13.Cu")
		(net "SMB_BIC_I2C6_SENEOR_SCL")
	)
	(segment
		(start 332.6638 -98.425)
		(end 332.6638 -97.6884)
		(width 0.15494)
		(layer "In13.Cu")
		(net "SMB_BIC_I2C6_SENEOR_SCL")
	)
	(segment
		(start 279.376632 -91.641168)
		(end 277.835614 -93.182186)
		(width 0.15494)
		(layer "In13.Cu")
		(net "SMB_BIC_I2C6_SENEOR_SCL")
	)
	(segment
		(start 317.421768 -97.288096)
		(end 311.77484 -91.641168)
		(width 0.15494)
		(layer "In13.Cu")
		(net "SMB_BIC_I2C6_SENEOR_SCL")
	)
	(segment
		(start 336.2452 -100.741988)
		(end 335.661254 -100.158042)
		(width 0.15494)
		(layer "In13.Cu")
		(net "SMB_BIC_I2C6_SENEOR_SCL")
	)
	(segment
		(start 325.882 -97.288096)
		(end 317.421768 -97.288096)
		(width 0.15494)
		(layer "In13.Cu")
		(net "SMB_BIC_I2C6_SENEOR_SCL")
	)
	(segment
		(start 335.661254 -100.158042)
		(end 334.396842 -100.158042)
		(width 0.15494)
		(layer "In13.Cu")
		(net "SMB_BIC_I2C6_SENEOR_SCL")
	)
	(segment
		(start 328.885296 -97.7646)
		(end 326.358504 -97.7646)
		(width 0.15494)
		(layer "In13.Cu")
		(net "SMB_BIC_I2C6_SENEOR_SCL")
	)
	(segment
		(start 362.428282 -101.599492)
		(end 340.970362 -101.599492)
		(width 0.15494)
		(layer "In13.Cu")
		(net "SMB_BIC_I2C6_SENEOR_SCL")
	)
	(segment
		(start 337.921854 -103.3526)
		(end 336.2452 -101.675946)
		(width 0.15494)
		(layer "In13.Cu")
		(net "SMB_BIC_I2C6_SENEOR_SCL")
	)
	(segment
		(start 336.2452 -101.675946)
		(end 336.2452 -100.741988)
		(width 0.15494)
		(layer "In13.Cu")
		(net "SMB_BIC_I2C6_SENEOR_SCL")
	)
	(segment
		(start 376.098308 -93.603064)
		(end 370.42471 -93.603064)
		(width 0.15494)
		(layer "In13.Cu")
		(net "SMB_BIC_I2C6_SENEOR_SCL")
	)
	(segment
		(start 331.9272 -96.9518)
		(end 329.698096 -96.9518)
		(width 0.15494)
		(layer "In13.Cu")
		(net "SMB_BIC_I2C6_SENEOR_SCL")
	)
	(segment
		(start 339.217254 -103.3526)
		(end 337.921854 -103.3526)
		(width 0.15494)
		(layer "In13.Cu")
		(net "SMB_BIC_I2C6_SENEOR_SCL")
	)
	(segment
		(start 329.698096 -96.9518)
		(end 328.885296 -97.7646)
		(width 0.15494)
		(layer "In13.Cu")
		(net "SMB_BIC_I2C6_SENEOR_SCL")
	)
	(segment
		(start 334.396842 -100.158042)
		(end 332.6638 -98.425)
		(width 0.15494)
		(layer "In13.Cu")
		(net "SMB_BIC_I2C6_SENEOR_SCL")
	)
	(segment
		(start 370.42471 -93.603064)
		(end 362.428282 -101.599492)
		(width 0.15494)
		(layer "In13.Cu")
		(net "SMB_BIC_I2C6_SENEOR_SCL")
	)
	(segment
		(start 332.6638 -97.6884)
		(end 331.9272 -96.9518)
		(width 0.15494)
		(layer "In13.Cu")
		(net "SMB_BIC_I2C6_SENEOR_SCL")
	)
	(segment
		(start 277.835614 -93.182186)
		(end 277.835614 -94.31909)
		(width 0.15494)
		(layer "In13.Cu")
		(net "SMB_BIC_I2C6_SENEOR_SCL")
	)
	(segment
		(start 340.970362 -101.599492)
		(end 339.217254 -103.3526)
		(width 0.15494)
		(layer "In13.Cu")
		(net "SMB_BIC_I2C6_SENEOR_SCL")
	)
	(segment
		(start 332.105 -222.3516)
		(end 332.420468 -222.036132)
		(width 0.13208)
		(layer "F.Cu")
		(net "LED_POSTCODE_4")
	)
	(segment
		(start 330.889356 -222.932244)
		(end 331.47 -222.3516)
		(width 0.13208)
		(layer "F.Cu")
		(net "LED_POSTCODE_4")
	)
	(segment
		(start 327.829672 -222.352108)
		(end 328.26198 -221.9198)
		(width 0.13208)
		(layer "F.Cu")
		(net "LED_POSTCODE_4")
	)
	(segment
		(start 333.539846 -221.9833)
		(end 334.49768 -221.9833)
		(width 0.13208)
		(layer "F.Cu")
		(net "LED_POSTCODE_4")
	)
	(segment
		(start 333.487014 -222.036132)
		(end 333.539846 -221.9833)
		(width 0.13208)
		(layer "F.Cu")
		(net "LED_POSTCODE_4")
	)
	(segment
		(start 331.47 -222.3516)
		(end 332.105 -222.3516)
		(width 0.13208)
		(layer "F.Cu")
		(net "LED_POSTCODE_4")
	)
	(segment
		(start 334.49768 -221.9833)
		(end 334.89392 -221.58706)
		(width 0.13208)
		(layer "F.Cu")
		(net "LED_POSTCODE_4")
	)
	(segment
		(start 329.993244 -222.932244)
		(end 330.889356 -222.932244)
		(width 0.13208)
		(layer "F.Cu")
		(net "LED_POSTCODE_4")
	)
	(segment
		(start 327.281286 -192.043304)
		(end 327.932288 -192.694306)
		(width 0.13208)
		(layer "F.Cu")
		(net "LED_POSTCODE_4")
	)
	(segment
		(start 324.98284 -220.849698)
		(end 324.98284 -221.22257)
		(width 0.13208)
		(layer "F.Cu")
		(net "LED_POSTCODE_4")
	)
	(segment
		(start 326.112378 -222.352108)
		(end 327.829672 -222.352108)
		(width 0.13208)
		(layer "F.Cu")
		(net "LED_POSTCODE_4")
	)
	(segment
		(start 328.26198 -221.9198)
		(end 328.9808 -221.9198)
		(width 0.13208)
		(layer "F.Cu")
		(net "LED_POSTCODE_4")
	)
	(segment
		(start 324.98284 -220.849698)
		(end 324.317868 -220.849698)
		(width 0.13208)
		(layer "F.Cu")
		(net "LED_POSTCODE_4")
	)
	(segment
		(start 332.420468 -222.036132)
		(end 333.487014 -222.036132)
		(width 0.13208)
		(layer "F.Cu")
		(net "LED_POSTCODE_4")
	)
	(segment
		(start 327.932288 -192.694306)
		(end 329.754484 -192.694306)
		(width 0.13208)
		(layer "F.Cu")
		(net "LED_POSTCODE_4")
	)
	(segment
		(start 325.764906 -192.043304)
		(end 327.281286 -192.043304)
		(width 0.13208)
		(layer "F.Cu")
		(net "LED_POSTCODE_4")
	)
	(segment
		(start 328.9808 -221.9198)
		(end 329.993244 -222.932244)
		(width 0.13208)
		(layer "F.Cu")
		(net "LED_POSTCODE_4")
	)
	(segment
		(start 324.98284 -221.22257)
		(end 326.112378 -222.352108)
		(width 0.13208)
		(layer "F.Cu")
		(net "LED_POSTCODE_4")
	)
	(via
		(at 324.98284 -220.849698)
		(size 0.508)
		(drill 0.254)
		(layers "F.Cu" "B.Cu")
		(net "LED_POSTCODE_4")
	)
	(via
		(at 325.764906 -192.043304)
		(size 0.508)
		(drill 0.254)
		(layers "F.Cu" "B.Cu")
		(net "LED_POSTCODE_4")
	)
	(segment
		(start 326.26808 -196.48932)
		(end 326.26808 -199.644)
		(width 0.15494)
		(layer "In7.Cu")
		(net "LED_POSTCODE_4")
	)
	(segment
		(start 327.4568 -195.3006)
		(end 326.26808 -196.48932)
		(width 0.15494)
		(layer "In7.Cu")
		(net "LED_POSTCODE_4")
	)
	(segment
		(start 325.764906 -192.043304)
		(end 326.00265 -192.043304)
		(width 0.15494)
		(layer "In7.Cu")
		(net "LED_POSTCODE_4")
	)
	(segment
		(start 324.468744 -220.335602)
		(end 324.98284 -220.849698)
		(width 0.15494)
		(layer "In7.Cu")
		(net "LED_POSTCODE_4")
	)
	(segment
		(start 323.343016 -217.870786)
		(end 324.468744 -218.996514)
		(width 0.15494)
		(layer "In7.Cu")
		(net "LED_POSTCODE_4")
	)
	(segment
		(start 326.26808 -199.644)
		(end 323.343016 -202.569064)
		(width 0.15494)
		(layer "In7.Cu")
		(net "LED_POSTCODE_4")
	)
	(segment
		(start 326.00265 -192.043304)
		(end 327.4568 -193.497454)
		(width 0.15494)
		(layer "In7.Cu")
		(net "LED_POSTCODE_4")
	)
	(segment
		(start 324.468744 -218.996514)
		(end 324.468744 -220.335602)
		(width 0.15494)
		(layer "In7.Cu")
		(net "LED_POSTCODE_4")
	)
	(segment
		(start 327.4568 -193.497454)
		(end 327.4568 -195.3006)
		(width 0.15494)
		(layer "In7.Cu")
		(net "LED_POSTCODE_4")
	)
	(segment
		(start 323.343016 -202.569064)
		(end 323.343016 -217.870786)
		(width 0.15494)
		(layer "In7.Cu")
		(net "LED_POSTCODE_4")
	)
	(segment
		(start 235.021374 -229.7176)
		(end 234.100116 -228.796342)
		(width 0.13208)
		(layer "F.Cu")
		(net "SSD5_PWRDIS_BIC")
	)
	(segment
		(start 237.903512 -231.016556)
		(end 237.191804 -230.304848)
		(width 0.13208)
		(layer "F.Cu")
		(net "SSD5_PWRDIS_BIC")
	)
	(segment
		(start 234.100116 -227.20046)
		(end 232.26776 -225.368104)
		(width 0.13208)
		(layer "F.Cu")
		(net "SSD5_PWRDIS_BIC")
	)
	(segment
		(start 232.26776 -225.368104)
		(end 232.26776 -224.704148)
		(width 0.13208)
		(layer "F.Cu")
		(net "SSD5_PWRDIS_BIC")
	)
	(segment
		(start 234.100116 -228.796342)
		(end 234.100116 -227.20046)
		(width 0.13208)
		(layer "F.Cu")
		(net "SSD5_PWRDIS_BIC")
	)
	(segment
		(start 235.48848 -229.7176)
		(end 235.021374 -229.7176)
		(width 0.13208)
		(layer "F.Cu")
		(net "SSD5_PWRDIS_BIC")
	)
	(segment
		(start 237.191804 -230.304848)
		(end 236.075728 -230.304848)
		(width 0.13208)
		(layer "F.Cu")
		(net "SSD5_PWRDIS_BIC")
	)
	(segment
		(start 236.075728 -230.304848)
		(end 235.48848 -229.7176)
		(width 0.13208)
		(layer "F.Cu")
		(net "SSD5_PWRDIS_BIC")
	)
	(via
		(at 234.100116 -228.796342)
		(size 0.762)
		(drill 0.381)
		(layers "F.Cu" "B.Cu")
		(net "SSD5_PWRDIS_BIC")
	)
	(segment
		(start 384.746754 -94.231206)
		(end 384.91541 -94.231206)
		(width 0.13208)
		(layer "F.Cu")
		(net "SMB_BIC_I2C6_SENEOR_SDA")
	)
	(segment
		(start 383.050796 -93.64218)
		(end 383.050796 -93.473524)
		(width 0.13208)
		(layer "F.Cu")
		(net "SMB_BIC_I2C6_SENEOR_SDA")
	)
	(segment
		(start 383.050796 -93.473524)
		(end 382.427734 -92.850462)
		(width 0.13208)
		(layer "F.Cu")
		(net "SMB_BIC_I2C6_SENEOR_SDA")
	)
	(segment
		(start 382.702816 -92.406724)
		(end 382.922272 -92.406724)
		(width 0.13208)
		(layer "F.Cu")
		(net "SMB_BIC_I2C6_SENEOR_SDA")
	)
	(segment
		(start 385.190492 -93.787468)
		(end 383.34061 -91.937586)
		(width 0.13208)
		(layer "F.Cu")
		(net "SMB_BIC_I2C6_SENEOR_SDA")
	)
	(segment
		(start 381.81534 -93.2942)
		(end 381.983996 -93.2942)
		(width 0.13208)
		(layer "F.Cu")
		(net "SMB_BIC_I2C6_SENEOR_SDA")
	)
	(segment
		(start 386.372862 -88.736678)
		(end 388.24027 -88.736678)
		(width 0.13208)
		(layer "F.Cu")
		(net "SMB_BIC_I2C6_SENEOR_SDA")
	)
	(segment
		(start 384.91541 -94.231206)
		(end 385.190492 -93.956124)
		(width 0.13208)
		(layer "F.Cu")
		(net "SMB_BIC_I2C6_SENEOR_SDA")
	)
	(segment
		(start 383.34061 -91.76893)
		(end 385.040886 -90.068654)
		(width 0.13208)
		(layer "F.Cu")
		(net "SMB_BIC_I2C6_SENEOR_SDA")
	)
	(segment
		(start 382.427734 -92.850462)
		(end 382.427734 -92.681806)
		(width 0.13208)
		(layer "F.Cu")
		(net "SMB_BIC_I2C6_SENEOR_SDA")
	)
	(segment
		(start 382.775714 -93.917262)
		(end 383.050796 -93.64218)
		(width 0.13208)
		(layer "F.Cu")
		(net "SMB_BIC_I2C6_SENEOR_SDA")
	)
	(segment
		(start 382.427734 -92.681806)
		(end 382.702816 -92.406724)
		(width 0.13208)
		(layer "F.Cu")
		(net "SMB_BIC_I2C6_SENEOR_SDA")
	)
	(segment
		(start 385.190492 -93.956124)
		(end 385.190492 -93.787468)
		(width 0.13208)
		(layer "F.Cu")
		(net "SMB_BIC_I2C6_SENEOR_SDA")
	)
	(segment
		(start 379.244352 -93.618304)
		(end 381.491236 -93.618304)
		(width 0.13208)
		(layer "F.Cu")
		(net "SMB_BIC_I2C6_SENEOR_SDA")
	)
	(segment
		(start 382.922272 -92.406724)
		(end 384.746754 -94.231206)
		(width 0.13208)
		(layer "F.Cu")
		(net "SMB_BIC_I2C6_SENEOR_SDA")
	)
	(segment
		(start 382.607058 -93.917262)
		(end 382.775714 -93.917262)
		(width 0.13208)
		(layer "F.Cu")
		(net "SMB_BIC_I2C6_SENEOR_SDA")
	)
	(segment
		(start 381.491236 -93.618304)
		(end 381.81534 -93.2942)
		(width 0.13208)
		(layer "F.Cu")
		(net "SMB_BIC_I2C6_SENEOR_SDA")
	)
	(segment
		(start 383.34061 -91.937586)
		(end 383.34061 -91.76893)
		(width 0.13208)
		(layer "F.Cu")
		(net "SMB_BIC_I2C6_SENEOR_SDA")
	)
	(segment
		(start 381.983996 -93.2942)
		(end 382.607058 -93.917262)
		(width 0.13208)
		(layer "F.Cu")
		(net "SMB_BIC_I2C6_SENEOR_SDA")
	)
	(segment
		(start 385.040886 -90.068654)
		(end 386.372862 -88.736678)
		(width 0.13208)
		(layer "F.Cu")
		(net "SMB_BIC_I2C6_SENEOR_SDA")
	)
	(via
		(at 385.040886 -90.068654)
		(size 0.508)
		(drill 0.254)
		(layers "F.Cu" "B.Cu")
		(net "SMB_BIC_I2C6_SENEOR_SDA")
	)
	(segment
		(start 335.693766 -221.58706)
		(end 335.29397 -221.986856)
		(width 0.13208)
		(layer "F.Cu")
		(net "LED_POSTCODE_3")
	)
	(segment
		(start 324.317868 -222.119698)
		(end 324.98284 -222.119698)
		(width 0.13208)
		(layer "F.Cu")
		(net "LED_POSTCODE_3")
	)
	(segment
		(start 329.754484 -193.344292)
		(end 327.79589 -193.344292)
		(width 0.13208)
		(layer "F.Cu")
		(net "LED_POSTCODE_3")
	)
	(segment
		(start 327.129902 -192.678304)
		(end 325.002906 -192.678304)
		(width 0.13208)
		(layer "F.Cu")
		(net "LED_POSTCODE_3")
	)
	(segment
		(start 327.79589 -193.344292)
		(end 327.129902 -192.678304)
		(width 0.13208)
		(layer "F.Cu")
		(net "LED_POSTCODE_3")
	)
	(via
		(at 324.98284 -222.119698)
		(size 0.508)
		(drill 0.254)
		(layers "F.Cu" "B.Cu")
		(net "LED_POSTCODE_3")
	)
	(via
		(at 325.002906 -192.678304)
		(size 0.508)
		(drill 0.254)
		(layers "F.Cu" "B.Cu")
		(net "LED_POSTCODE_3")
	)
	(via
		(at 335.29397 -221.986856)
		(size 0.4572)
		(drill 0.254)
		(layers "F.Cu" "B.Cu")
		(net "LED_POSTCODE_3")
	)
	(segment
		(start 324.98284 -222.119698)
		(end 326.35571 -222.119698)
		(width 0.13208)
		(layer "B.Cu")
		(net "LED_POSTCODE_3")
	)
	(segment
		(start 330.812394 -221.241366)
		(end 332.02626 -221.241366)
		(width 0.13208)
		(layer "B.Cu")
		(net "LED_POSTCODE_3")
	)
	(segment
		(start 326.977756 -221.497652)
		(end 327.813416 -221.497652)
		(width 0.13208)
		(layer "B.Cu")
		(net "LED_POSTCODE_3")
	)
	(segment
		(start 330.521818 -220.95079)
		(end 330.812394 -221.241366)
		(width 0.13208)
		(layer "B.Cu")
		(net "LED_POSTCODE_3")
	)
	(segment
		(start 332.02626 -221.241366)
		(end 332.399894 -221.615)
		(width 0.13208)
		(layer "B.Cu")
		(net "LED_POSTCODE_3")
	)
	(segment
		(start 328.360278 -220.95079)
		(end 330.521818 -220.95079)
		(width 0.13208)
		(layer "B.Cu")
		(net "LED_POSTCODE_3")
	)
	(segment
		(start 332.399894 -221.615)
		(end 334.264 -221.615)
		(width 0.13208)
		(layer "B.Cu")
		(net "LED_POSTCODE_3")
	)
	(segment
		(start 334.264 -221.615)
		(end 334.635856 -221.986856)
		(width 0.13208)
		(layer "B.Cu")
		(net "LED_POSTCODE_3")
	)
	(segment
		(start 327.813416 -221.497652)
		(end 328.360278 -220.95079)
		(width 0.13208)
		(layer "B.Cu")
		(net "LED_POSTCODE_3")
	)
	(segment
		(start 326.35571 -222.119698)
		(end 326.977756 -221.497652)
		(width 0.13208)
		(layer "B.Cu")
		(net "LED_POSTCODE_3")
	)
	(segment
		(start 334.635856 -221.986856)
		(end 335.29397 -221.986856)
		(width 0.13208)
		(layer "B.Cu")
		(net "LED_POSTCODE_3")
	)
	(segment
		(start 325.002906 -192.678304)
		(end 325.926958 -192.678304)
		(width 0.15494)
		(layer "In7.Cu")
		(net "LED_POSTCODE_3")
	)
	(segment
		(start 325.90994 -199.49541)
		(end 322.354194 -203.051156)
		(width 0.15494)
		(layer "In7.Cu")
		(net "LED_POSTCODE_3")
	)
	(segment
		(start 324.369684 -221.506542)
		(end 324.98284 -222.119698)
		(width 0.15494)
		(layer "In7.Cu")
		(net "LED_POSTCODE_3")
	)
	(segment
		(start 323.970396 -221.506542)
		(end 324.369684 -221.506542)
		(width 0.15494)
		(layer "In7.Cu")
		(net "LED_POSTCODE_3")
	)
	(segment
		(start 322.984876 -216.308686)
		(end 322.322698 -216.970864)
		(width 0.15494)
		(layer "In7.Cu")
		(net "LED_POSTCODE_3")
	)
	(segment
		(start 322.322698 -216.970864)
		(end 322.322698 -219.858844)
		(width 0.15494)
		(layer "In7.Cu")
		(net "LED_POSTCODE_3")
	)
	(segment
		(start 325.926958 -192.678304)
		(end 327.0504 -193.801746)
		(width 0.15494)
		(layer "In7.Cu")
		(net "LED_POSTCODE_3")
	)
	(segment
		(start 327.0504 -193.801746)
		(end 327.0504 -195.148454)
		(width 0.15494)
		(layer "In7.Cu")
		(net "LED_POSTCODE_3")
	)
	(segment
		(start 325.90994 -196.288914)
		(end 325.90994 -199.49541)
		(width 0.15494)
		(layer "In7.Cu")
		(net "LED_POSTCODE_3")
	)
	(segment
		(start 322.322698 -219.858844)
		(end 323.970396 -221.506542)
		(width 0.15494)
		(layer "In7.Cu")
		(net "LED_POSTCODE_3")
	)
	(segment
		(start 322.354194 -214.283036)
		(end 322.984876 -214.913718)
		(width 0.15494)
		(layer "In7.Cu")
		(net "LED_POSTCODE_3")
	)
	(segment
		(start 327.0504 -195.148454)
		(end 325.90994 -196.288914)
		(width 0.15494)
		(layer "In7.Cu")
		(net "LED_POSTCODE_3")
	)
	(segment
		(start 322.354194 -203.051156)
		(end 322.354194 -214.283036)
		(width 0.15494)
		(layer "In7.Cu")
		(net "LED_POSTCODE_3")
	)
	(segment
		(start 322.984876 -214.913718)
		(end 322.984876 -216.308686)
		(width 0.15494)
		(layer "In7.Cu")
		(net "LED_POSTCODE_3")
	)
	(segment
		(start 233.867706 -220.704156)
		(end 234.267502 -221.103952)
		(width 0.13208)
		(layer "F.Cu")
		(net "SSD13_PWRDIS_BIC")
	)
	(via
		(at 234.668568 -225.825558)
		(size 0.6604)
		(drill 0.3302)
		(layers "F.Cu" "B.Cu")
		(net "SSD13_PWRDIS_BIC")
	)
	(via
		(at 234.267502 -221.103952)
		(size 0.4572)
		(drill 0.254)
		(layers "F.Cu" "B.Cu")
		(net "SSD13_PWRDIS_BIC")
	)
	(segment
		(start 237.179866 -227.299266)
		(end 236.495082 -226.614482)
		(width 0.13208)
		(layer "B.Cu")
		(net "SSD13_PWRDIS_BIC")
	)
	(segment
		(start 234.668568 -221.505018)
		(end 234.267502 -221.103952)
		(width 0.0889)
		(layer "B.Cu")
		(net "SSD13_PWRDIS_BIC")
	)
	(segment
		(start 235.457492 -226.614482)
		(end 234.668568 -225.825558)
		(width 0.13208)
		(layer "B.Cu")
		(net "SSD13_PWRDIS_BIC")
	)
	(segment
		(start 234.668568 -225.3488)
		(end 234.668568 -221.505018)
		(width 0.0889)
		(layer "B.Cu")
		(net "SSD13_PWRDIS_BIC")
	)
	(segment
		(start 237.179866 -230.44277)
		(end 237.179866 -227.299266)
		(width 0.13208)
		(layer "B.Cu")
		(net "SSD13_PWRDIS_BIC")
	)
	(segment
		(start 234.668568 -225.825558)
		(end 234.668568 -225.3488)
		(width 0.13208)
		(layer "B.Cu")
		(net "SSD13_PWRDIS_BIC")
	)
	(segment
		(start 237.562644 -230.825548)
		(end 237.179866 -230.44277)
		(width 0.13208)
		(layer "B.Cu")
		(net "SSD13_PWRDIS_BIC")
	)
	(segment
		(start 236.495082 -226.614482)
		(end 235.457492 -226.614482)
		(width 0.13208)
		(layer "B.Cu")
		(net "SSD13_PWRDIS_BIC")
	)
	(segment
		(start 351.132902 -156.534104)
		(end 351.330006 -156.337)
		(width 0.13208)
		(layer "F.Cu")
		(net "RST_PEX_NIC6_PERST_N")
	)
	(segment
		(start 350.11741 -156.534104)
		(end 351.132902 -156.534104)
		(width 0.13208)
		(layer "F.Cu")
		(net "RST_PEX_NIC6_PERST_N")
	)
	(segment
		(start 350.11741 -155.912312)
		(end 350.11741 -156.534104)
		(width 0.13208)
		(layer "F.Cu")
		(net "RST_PEX_NIC6_PERST_N")
	)
	(segment
		(start 351.330006 -156.337)
		(end 351.832164 -156.337)
		(width 0.13208)
		(layer "F.Cu")
		(net "RST_PEX_NIC6_PERST_N")
	)
	(segment
		(start 349.000064 -155.712922)
		(end 349.91802 -155.712922)
		(width 0.13208)
		(layer "F.Cu")
		(net "RST_PEX_NIC6_PERST_N")
	)
	(segment
		(start 349.91802 -155.712922)
		(end 350.11741 -155.912312)
		(width 0.13208)
		(layer "F.Cu")
		(net "RST_PEX_NIC6_PERST_N")
	)
	(via
		(at 350.11741 -156.534104)
		(size 0.508)
		(drill 0.254)
		(layers "F.Cu" "B.Cu")
		(net "RST_PEX_NIC6_PERST_N")
	)
	(segment
		(start 338.093812 -220.78696)
		(end 337.694016 -221.186756)
		(width 0.13208)
		(layer "F.Cu")
		(net "LED_POSTCODE_7")
	)
	(segment
		(start 324.31482 -216.415366)
		(end 324.7136 -216.415366)
		(width 0.13208)
		(layer "F.Cu")
		(net "LED_POSTCODE_7")
	)
	(segment
		(start 324.7136 -216.415366)
		(end 324.98284 -216.684606)
		(width 0.13208)
		(layer "F.Cu")
		(net "LED_POSTCODE_7")
	)
	(segment
		(start 324.98284 -216.684606)
		(end 324.98284 -217.039698)
		(width 0.13208)
		(layer "F.Cu")
		(net "LED_POSTCODE_7")
	)
	(segment
		(start 329.754484 -190.744348)
		(end 328.694542 -190.744348)
		(width 0.13208)
		(layer "F.Cu")
		(net "LED_POSTCODE_7")
	)
	(segment
		(start 328.088498 -190.138304)
		(end 325.002906 -190.138304)
		(width 0.13208)
		(layer "F.Cu")
		(net "LED_POSTCODE_7")
	)
	(segment
		(start 328.694542 -190.744348)
		(end 328.088498 -190.138304)
		(width 0.13208)
		(layer "F.Cu")
		(net "LED_POSTCODE_7")
	)
	(via
		(at 325.002906 -190.138304)
		(size 0.508)
		(drill 0.254)
		(layers "F.Cu" "B.Cu")
		(net "LED_POSTCODE_7")
	)
	(via
		(at 324.98284 -217.039698)
		(size 0.508)
		(drill 0.254)
		(layers "F.Cu" "B.Cu")
		(net "LED_POSTCODE_7")
	)
	(via
		(at 337.694016 -221.186756)
		(size 0.4572)
		(drill 0.254)
		(layers "F.Cu" "B.Cu")
		(net "LED_POSTCODE_7")
	)
	(segment
		(start 326.270366 -218.811602)
		(end 325.881746 -218.422982)
		(width 0.15494)
		(layer "In5.Cu")
		(net "LED_POSTCODE_7")
	)
	(segment
		(start 334.016604 -220.802962)
		(end 333.896716 -220.683074)
		(width 0.15494)
		(layer "In5.Cu")
		(net "LED_POSTCODE_7")
	)
	(segment
		(start 337.310222 -220.802962)
		(end 335.036668 -220.802962)
		(width 0.0889)
		(layer "In5.Cu")
		(net "LED_POSTCODE_7")
	)
	(segment
		(start 333.896716 -220.683074)
		(end 332.505812 -220.683074)
		(width 0.15494)
		(layer "In5.Cu")
		(net "LED_POSTCODE_7")
	)
	(segment
		(start 328.728578 -220.208602)
		(end 328.25944 -220.208602)
		(width 0.15494)
		(layer "In5.Cu")
		(net "LED_POSTCODE_7")
	)
	(segment
		(start 328.25944 -220.208602)
		(end 326.86244 -218.811602)
		(width 0.15494)
		(layer "In5.Cu")
		(net "LED_POSTCODE_7")
	)
	(segment
		(start 332.079346 -221.10954)
		(end 329.629516 -221.10954)
		(width 0.15494)
		(layer "In5.Cu")
		(net "LED_POSTCODE_7")
	)
	(segment
		(start 329.629516 -221.10954)
		(end 328.728578 -220.208602)
		(width 0.15494)
		(layer "In5.Cu")
		(net "LED_POSTCODE_7")
	)
	(segment
		(start 335.036668 -220.802962)
		(end 334.016604 -220.802962)
		(width 0.15494)
		(layer "In5.Cu")
		(net "LED_POSTCODE_7")
	)
	(segment
		(start 325.881746 -217.938604)
		(end 324.98284 -217.039698)
		(width 0.15494)
		(layer "In5.Cu")
		(net "LED_POSTCODE_7")
	)
	(segment
		(start 332.505812 -220.683074)
		(end 332.079346 -221.10954)
		(width 0.15494)
		(layer "In5.Cu")
		(net "LED_POSTCODE_7")
	)
	(segment
		(start 337.694016 -221.186756)
		(end 337.310222 -220.802962)
		(width 0.0889)
		(layer "In5.Cu")
		(net "LED_POSTCODE_7")
	)
	(segment
		(start 326.86244 -218.811602)
		(end 326.270366 -218.811602)
		(width 0.15494)
		(layer "In5.Cu")
		(net "LED_POSTCODE_7")
	)
	(segment
		(start 325.881746 -218.422982)
		(end 325.881746 -217.938604)
		(width 0.15494)
		(layer "In5.Cu")
		(net "LED_POSTCODE_7")
	)
	(segment
		(start 324.417436 -216.474294)
		(end 324.417436 -203.014834)
		(width 0.15494)
		(layer "In7.Cu")
		(net "LED_POSTCODE_7")
	)
	(segment
		(start 325.884286 -190.138304)
		(end 325.002906 -190.138304)
		(width 0.15494)
		(layer "In7.Cu")
		(net "LED_POSTCODE_7")
	)
	(segment
		(start 329.270868 -193.524886)
		(end 325.884286 -190.138304)
		(width 0.15494)
		(layer "In7.Cu")
		(net "LED_POSTCODE_7")
	)
	(segment
		(start 324.417436 -203.014834)
		(end 329.270868 -198.161402)
		(width 0.15494)
		(layer "In7.Cu")
		(net "LED_POSTCODE_7")
	)
	(segment
		(start 329.270868 -198.161402)
		(end 329.270868 -193.524886)
		(width 0.15494)
		(layer "In7.Cu")
		(net "LED_POSTCODE_7")
	)
	(segment
		(start 324.98284 -217.039698)
		(end 324.417436 -216.474294)
		(width 0.15494)
		(layer "In7.Cu")
		(net "LED_POSTCODE_7")
	)
	(segment
		(start 229.867714 -223.104202)
		(end 230.26751 -223.503998)
		(width 0.13208)
		(layer "F.Cu")
		(net "SSD4_PWRDIS_BIC")
	)
	(via
		(at 231.517698 -227.200714)
		(size 0.6604)
		(drill 0.3302)
		(layers "F.Cu" "B.Cu")
		(net "SSD4_PWRDIS_BIC")
	)
	(via
		(at 230.26751 -223.503998)
		(size 0.4572)
		(drill 0.254)
		(layers "F.Cu" "B.Cu")
		(net "SSD4_PWRDIS_BIC")
	)
	(segment
		(start 232.482644 -228.16566)
		(end 231.517698 -227.200714)
		(width 0.13208)
		(layer "B.Cu")
		(net "SSD4_PWRDIS_BIC")
	)
	(segment
		(start 231.321356 -227.004372)
		(end 231.321356 -224.405444)
		(width 0.13208)
		(layer "B.Cu")
		(net "SSD4_PWRDIS_BIC")
	)
	(segment
		(start 230.41991 -223.503998)
		(end 230.26751 -223.503998)
		(width 0.13208)
		(layer "B.Cu")
		(net "SSD4_PWRDIS_BIC")
	)
	(segment
		(start 232.482644 -230.825548)
		(end 232.482644 -228.16566)
		(width 0.13208)
		(layer "B.Cu")
		(net "SSD4_PWRDIS_BIC")
	)
	(segment
		(start 231.321356 -224.405444)
		(end 230.41991 -223.503998)
		(width 0.13208)
		(layer "B.Cu")
		(net "SSD4_PWRDIS_BIC")
	)
	(segment
		(start 231.517698 -227.200714)
		(end 231.321356 -227.004372)
		(width 0.13208)
		(layer "B.Cu")
		(net "SSD4_PWRDIS_BIC")
	)
	(segment
		(start 225.867722 -215.904064)
		(end 225.467926 -215.504268)
		(width 0.13208)
		(layer "F.Cu")
		(net "RST_BIC_SELF_HW_RST_N")
	)
	(via
		(at 220.951044 -215.114378)
		(size 0.6604)
		(drill 0.3302)
		(layers "F.Cu" "B.Cu")
		(net "RST_BIC_SELF_HW_RST_N")
	)
	(via
		(at 225.467926 -215.504268)
		(size 0.4572)
		(drill 0.254)
		(layers "F.Cu" "B.Cu")
		(net "RST_BIC_SELF_HW_RST_N")
	)
	(segment
		(start 222.897192 -215.114378)
		(end 222.903542 -215.108028)
		(width 0.13208)
		(layer "B.Cu")
		(net "RST_BIC_SELF_HW_RST_N")
	)
	(segment
		(start 222.903542 -215.108028)
		(end 225.071686 -215.108028)
		(width 0.0889)
		(layer "B.Cu")
		(net "RST_BIC_SELF_HW_RST_N")
	)
	(segment
		(start 219.384118 -214.238586)
		(end 220.25991 -215.114378)
		(width 0.13208)
		(layer "B.Cu")
		(net "RST_BIC_SELF_HW_RST_N")
	)
	(segment
		(start 225.071686 -215.108028)
		(end 225.467926 -215.504268)
		(width 0.0889)
		(layer "B.Cu")
		(net "RST_BIC_SELF_HW_RST_N")
	)
	(segment
		(start 220.951044 -215.114378)
		(end 222.897192 -215.114378)
		(width 0.13208)
		(layer "B.Cu")
		(net "RST_BIC_SELF_HW_RST_N")
	)
	(segment
		(start 220.25991 -215.114378)
		(end 220.951044 -215.114378)
		(width 0.13208)
		(layer "B.Cu")
		(net "RST_BIC_SELF_HW_RST_N")
	)
	(segment
		(start 217.635836 -214.238586)
		(end 219.384118 -214.238586)
		(width 0.13208)
		(layer "B.Cu")
		(net "RST_BIC_SELF_HW_RST_N")
	)
	(segment
		(start 349.000064 -155.062936)
		(end 350.11741 -155.062936)
		(width 0.13208)
		(layer "F.Cu")
		(net "NIC6_PEX_PWR_EN")
	)
	(segment
		(start 351.5741 -155.062936)
		(end 351.832164 -155.321)
		(width 0.13208)
		(layer "F.Cu")
		(net "NIC6_PEX_PWR_EN")
	)
	(segment
		(start 350.11741 -155.062936)
		(end 351.5741 -155.062936)
		(width 0.13208)
		(layer "F.Cu")
		(net "NIC6_PEX_PWR_EN")
	)
	(via
		(at 350.11741 -155.062936)
		(size 0.508)
		(drill 0.254)
		(layers "F.Cu" "B.Cu")
		(net "NIC6_PEX_PWR_EN")
	)
	(segment
		(start 337.293966 -222.38716)
		(end 336.89417 -222.786956)
		(width 0.13208)
		(layer "F.Cu")
		(net "LED_POSTCODE_0")
	)
	(segment
		(start 327.611232 -195.294504)
		(end 326.900032 -194.583304)
		(width 0.13208)
		(layer "F.Cu")
		(net "LED_POSTCODE_0")
	)
	(segment
		(start 326.900032 -194.583304)
		(end 325.764906 -194.583304)
		(width 0.13208)
		(layer "F.Cu")
		(net "LED_POSTCODE_0")
	)
	(segment
		(start 324.317868 -225.929698)
		(end 324.98284 -225.929698)
		(width 0.13208)
		(layer "F.Cu")
		(net "LED_POSTCODE_0")
	)
	(segment
		(start 329.754484 -195.294504)
		(end 327.611232 -195.294504)
		(width 0.13208)
		(layer "F.Cu")
		(net "LED_POSTCODE_0")
	)
	(via
		(at 336.89417 -222.786956)
		(size 0.4572)
		(drill 0.254)
		(layers "F.Cu" "B.Cu")
		(net "LED_POSTCODE_0")
	)
	(via
		(at 324.98284 -225.929698)
		(size 0.508)
		(drill 0.254)
		(layers "F.Cu" "B.Cu")
		(net "LED_POSTCODE_0")
	)
	(via
		(at 325.764906 -194.583304)
		(size 0.508)
		(drill 0.254)
		(layers "F.Cu" "B.Cu")
		(net "LED_POSTCODE_0")
	)
	(segment
		(start 330.367894 -222.409766)
		(end 328.798428 -223.979232)
		(width 0.15494)
		(layer "In5.Cu")
		(net "LED_POSTCODE_0")
	)
	(segment
		(start 336.89417 -222.786956)
		(end 336.49666 -223.184466)
		(width 0.0889)
		(layer "In5.Cu")
		(net "LED_POSTCODE_0")
	)
	(segment
		(start 334.055466 -223.184466)
		(end 333.280766 -222.409766)
		(width 0.15494)
		(layer "In5.Cu")
		(net "LED_POSTCODE_0")
	)
	(segment
		(start 326.226932 -225.929698)
		(end 324.98284 -225.929698)
		(width 0.15494)
		(layer "In5.Cu")
		(net "LED_POSTCODE_0")
	)
	(segment
		(start 328.798428 -223.979232)
		(end 328.177398 -223.979232)
		(width 0.15494)
		(layer "In5.Cu")
		(net "LED_POSTCODE_0")
	)
	(segment
		(start 335.084166 -223.184466)
		(end 334.055466 -223.184466)
		(width 0.15494)
		(layer "In5.Cu")
		(net "LED_POSTCODE_0")
	)
	(segment
		(start 328.177398 -223.979232)
		(end 326.226932 -225.929698)
		(width 0.15494)
		(layer "In5.Cu")
		(net "LED_POSTCODE_0")
	)
	(segment
		(start 333.280766 -222.409766)
		(end 330.367894 -222.409766)
		(width 0.15494)
		(layer "In5.Cu")
		(net "LED_POSTCODE_0")
	)
	(segment
		(start 336.49666 -223.184466)
		(end 335.084166 -223.184466)
		(width 0.0889)
		(layer "In5.Cu")
		(net "LED_POSTCODE_0")
	)
	(segment
		(start 321.110864 -198.11619)
		(end 324.64375 -194.583304)
		(width 0.15494)
		(layer "In7.Cu")
		(net "LED_POSTCODE_0")
	)
	(segment
		(start 324.64375 -194.583304)
		(end 325.764906 -194.583304)
		(width 0.15494)
		(layer "In7.Cu")
		(net "LED_POSTCODE_0")
	)
	(segment
		(start 321.110864 -222.057722)
		(end 321.110864 -198.11619)
		(width 0.15494)
		(layer "In7.Cu")
		(net "LED_POSTCODE_0")
	)
	(segment
		(start 324.98284 -225.929698)
		(end 321.110864 -222.057722)
		(width 0.15494)
		(layer "In7.Cu")
		(net "LED_POSTCODE_0")
	)
	(segment
		(start 230.290116 -227.100384)
		(end 229.867714 -226.677982)
		(width 0.13208)
		(layer "F.Cu")
		(net "SSD11_PWRDIS_BIC")
	)
	(segment
		(start 230.90505 -230.5304)
		(end 230.606854 -230.5304)
		(width 0.13208)
		(layer "F.Cu")
		(net "SSD11_PWRDIS_BIC")
	)
	(segment
		(start 230.290116 -230.213662)
		(end 230.290116 -228.796342)
		(width 0.13208)
		(layer "F.Cu")
		(net "SSD11_PWRDIS_BIC")
	)
	(segment
		(start 229.867714 -226.677982)
		(end 229.867714 -224.704148)
		(width 0.13208)
		(layer "F.Cu")
		(net "SSD11_PWRDIS_BIC")
	)
	(segment
		(start 230.290116 -228.796342)
		(end 230.290116 -227.100384)
		(width 0.13208)
		(layer "F.Cu")
		(net "SSD11_PWRDIS_BIC")
	)
	(segment
		(start 230.606854 -230.5304)
		(end 230.290116 -230.213662)
		(width 0.13208)
		(layer "F.Cu")
		(net "SSD11_PWRDIS_BIC")
	)
	(segment
		(start 231.3686 -230.99395)
		(end 230.90505 -230.5304)
		(width 0.13208)
		(layer "F.Cu")
		(net "SSD11_PWRDIS_BIC")
	)
	(via
		(at 230.290116 -228.796342)
		(size 0.762)
		(drill 0.381)
		(layers "F.Cu" "B.Cu")
		(net "SSD11_PWRDIS_BIC")
	)
	(segment
		(start 239.95253 -222.064072)
		(end 239.95253 -221.51467)
		(width 0.381)
		(layer "F.Cu")
		(net "P1V2_BIC_ADCVREFREXT1")
	)
	(segment
		(start 236.69244 -217.774266)
		(end 236.421422 -217.503248)
		(width 0.381)
		(layer "F.Cu")
		(net "P1V2_BIC_ADCVREFREXT1")
	)
	(segment
		(start 239.95253 -222.064072)
		(end 239.95253 -223.066864)
		(width 0.3048)
		(layer "F.Cu")
		(net "P1V2_BIC_ADCVREFREXT1")
	)
	(segment
		(start 236.418882 -217.504264)
		(end 235.467652 -217.504264)
		(width 0.381)
		(layer "F.Cu")
		(net "P1V2_BIC_ADCVREFREXT1")
	)
	(segment
		(start 237.317788 -219.758768)
		(end 236.69244 -218.248992)
		(width 0.381)
		(layer "F.Cu")
		(net "P1V2_BIC_ADCVREFREXT1")
	)
	(segment
		(start 238.264954 -220.705934)
		(end 237.317788 -219.758768)
		(width 0.381)
		(layer "F.Cu")
		(net "P1V2_BIC_ADCVREFREXT1")
	)
	(segment
		(start 239.95253 -221.51467)
		(end 239.143794 -220.705934)
		(width 0.381)
		(layer "F.Cu")
		(net "P1V2_BIC_ADCVREFREXT1")
	)
	(segment
		(start 238.574326 -220.705934)
		(end 238.264954 -220.705934)
		(width 0.381)
		(layer "F.Cu")
		(net "P1V2_BIC_ADCVREFREXT1")
	)
	(segment
		(start 236.69244 -218.248992)
		(end 236.69244 -217.774266)
		(width 0.381)
		(layer "F.Cu")
		(net "P1V2_BIC_ADCVREFREXT1")
	)
	(segment
		(start 239.143794 -220.705934)
		(end 238.574326 -220.705934)
		(width 0.381)
		(layer "F.Cu")
		(net "P1V2_BIC_ADCVREFREXT1")
	)
	(segment
		(start 236.421422 -217.503248)
		(end 236.418882 -217.504264)
		(width 0.381)
		(layer "F.Cu")
		(net "P1V2_BIC_ADCVREFREXT1")
	)
	(via
		(at 238.574326 -220.705934)
		(size 0.762)
		(drill 0.381)
		(layers "F.Cu" "B.Cu")
		(net "P1V2_BIC_ADCVREFREXT1")
	)
	(segment
		(start 217.316558 -175.015906)
		(end 217.334084 -174.99838)
		(width 0.13208)
		(layer "F.Cu")
		(net "RST_BIC_SELF_HW_RST_R_N")
	)
	(segment
		(start 218.398852 -174.99838)
		(end 219.463366 -174.99838)
		(width 0.13208)
		(layer "F.Cu")
		(net "RST_BIC_SELF_HW_RST_R_N")
	)
	(segment
		(start 217.334084 -174.99838)
		(end 218.398852 -174.99838)
		(width 0.13208)
		(layer "F.Cu")
		(net "RST_BIC_SELF_HW_RST_R_N")
	)
	(segment
		(start 215.81872 -175.015906)
		(end 217.316558 -175.015906)
		(width 0.13208)
		(layer "F.Cu")
		(net "RST_BIC_SELF_HW_RST_R_N")
	)
	(via
		(at 219.463366 -174.99838)
		(size 0.508)
		(drill 0.254)
		(layers "F.Cu" "B.Cu")
		(net "RST_BIC_SELF_HW_RST_R_N")
	)
	(via
		(at 216.200736 -214.238586)
		(size 0.508)
		(drill 0.254)
		(layers "F.Cu" "B.Cu")
		(net "RST_BIC_SELF_HW_RST_R_N")
	)
	(segment
		(start 216.835736 -214.238586)
		(end 216.200736 -214.238586)
		(width 0.13208)
		(layer "B.Cu")
		(net "RST_BIC_SELF_HW_RST_R_N")
	)
	(segment
		(start 221.1324 -186.1058)
		(end 219.554298 -184.527698)
		(width 0.15494)
		(layer "In7.Cu")
		(net "RST_BIC_SELF_HW_RST_R_N")
	)
	(segment
		(start 218.694 -208.661)
		(end 219.120466 -208.661)
		(width 0.15494)
		(layer "In7.Cu")
		(net "RST_BIC_SELF_HW_RST_R_N")
	)
	(segment
		(start 217.297 -210.086702)
		(end 218.17203 -209.211672)
		(width 0.15494)
		(layer "In7.Cu")
		(net "RST_BIC_SELF_HW_RST_R_N")
	)
	(segment
		(start 220.890846 -200.35393)
		(end 222.169482 -197.267322)
		(width 0.15494)
		(layer "In7.Cu")
		(net "RST_BIC_SELF_HW_RST_R_N")
	)
	(segment
		(start 220.73616 -204.707236)
		(end 220.1418 -204.112876)
		(width 0.15494)
		(layer "In7.Cu")
		(net "RST_BIC_SELF_HW_RST_R_N")
	)
	(segment
		(start 218.17203 -209.211672)
		(end 218.17203 -209.18297)
		(width 0.15494)
		(layer "In7.Cu")
		(net "RST_BIC_SELF_HW_RST_R_N")
	)
	(segment
		(start 220.73616 -206.209646)
		(end 220.73616 -204.707236)
		(width 0.15494)
		(layer "In7.Cu")
		(net "RST_BIC_SELF_HW_RST_R_N")
	)
	(segment
		(start 219.554298 -184.527698)
		(end 219.554298 -175.720756)
		(width 0.15494)
		(layer "In7.Cu")
		(net "RST_BIC_SELF_HW_RST_R_N")
	)
	(segment
		(start 219.120466 -208.661)
		(end 220.263466 -207.518)
		(width 0.15494)
		(layer "In7.Cu")
		(net "RST_BIC_SELF_HW_RST_R_N")
	)
	(segment
		(start 222.169482 -197.267322)
		(end 222.169482 -192.535048)
		(width 0.15494)
		(layer "In7.Cu")
		(net "RST_BIC_SELF_HW_RST_R_N")
	)
	(segment
		(start 216.200736 -214.238586)
		(end 217.297 -213.142322)
		(width 0.15494)
		(layer "In7.Cu")
		(net "RST_BIC_SELF_HW_RST_R_N")
	)
	(segment
		(start 219.533978 -175.664368)
		(end 219.463366 -175.593756)
		(width 0.15494)
		(layer "In7.Cu")
		(net "RST_BIC_SELF_HW_RST_R_N")
	)
	(segment
		(start 222.169482 -192.535048)
		(end 221.1324 -191.497966)
		(width 0.15494)
		(layer "In7.Cu")
		(net "RST_BIC_SELF_HW_RST_R_N")
	)
	(segment
		(start 220.890846 -201.2823)
		(end 220.890846 -200.35393)
		(width 0.15494)
		(layer "In7.Cu")
		(net "RST_BIC_SELF_HW_RST_R_N")
	)
	(segment
		(start 220.1418 -202.031346)
		(end 220.890846 -201.2823)
		(width 0.15494)
		(layer "In7.Cu")
		(net "RST_BIC_SELF_HW_RST_R_N")
	)
	(segment
		(start 219.533978 -175.700436)
		(end 219.533978 -175.664368)
		(width 0.15494)
		(layer "In7.Cu")
		(net "RST_BIC_SELF_HW_RST_R_N")
	)
	(segment
		(start 217.297 -213.142322)
		(end 217.297 -210.086702)
		(width 0.15494)
		(layer "In7.Cu")
		(net "RST_BIC_SELF_HW_RST_R_N")
	)
	(segment
		(start 220.263466 -207.518)
		(end 220.263466 -206.68234)
		(width 0.15494)
		(layer "In7.Cu")
		(net "RST_BIC_SELF_HW_RST_R_N")
	)
	(segment
		(start 221.1324 -191.497966)
		(end 221.1324 -186.1058)
		(width 0.15494)
		(layer "In7.Cu")
		(net "RST_BIC_SELF_HW_RST_R_N")
	)
	(segment
		(start 219.554298 -175.720756)
		(end 219.533978 -175.700436)
		(width 0.15494)
		(layer "In7.Cu")
		(net "RST_BIC_SELF_HW_RST_R_N")
	)
	(segment
		(start 220.263466 -206.68234)
		(end 220.73616 -206.209646)
		(width 0.15494)
		(layer "In7.Cu")
		(net "RST_BIC_SELF_HW_RST_R_N")
	)
	(segment
		(start 218.17203 -209.18297)
		(end 218.694 -208.661)
		(width 0.15494)
		(layer "In7.Cu")
		(net "RST_BIC_SELF_HW_RST_R_N")
	)
	(segment
		(start 220.1418 -204.112876)
		(end 220.1418 -202.031346)
		(width 0.15494)
		(layer "In7.Cu")
		(net "RST_BIC_SELF_HW_RST_R_N")
	)
	(segment
		(start 219.463366 -175.593756)
		(end 219.463366 -174.99838)
		(width 0.15494)
		(layer "In7.Cu")
		(net "RST_BIC_SELF_HW_RST_R_N")
	)
	(segment
		(start 353.42195 -166.624)
		(end 351.832164 -166.624)
		(width 0.13208)
		(layer "F.Cu")
		(net "NIC5_PEX_PWR_EN")
	)
	(segment
		(start 350.11741 -166.365936)
		(end 349.000064 -166.365936)
		(width 0.13208)
		(layer "F.Cu")
		(net "NIC5_PEX_PWR_EN")
	)
	(segment
		(start 351.5741 -166.365936)
		(end 350.11741 -166.365936)
		(width 0.13208)
		(layer "F.Cu")
		(net "NIC5_PEX_PWR_EN")
	)
	(segment
		(start 351.832164 -166.624)
		(end 351.5741 -166.365936)
		(width 0.13208)
		(layer "F.Cu")
		(net "NIC5_PEX_PWR_EN")
	)
	(via
		(at 350.11741 -166.365936)
		(size 0.508)
		(drill 0.254)
		(layers "F.Cu" "B.Cu")
		(net "NIC5_PEX_PWR_EN")
	)
	(segment
		(start 339.225128 -158.05404)
		(end 341.313008 -158.05404)
		(width 0.13208)
		(layer "F.Cu")
		(net "RST_PEX_SSD12_PERST_N")
	)
	(segment
		(start 341.432896 -157.934152)
		(end 342.245188 -157.934152)
		(width 0.13208)
		(layer "F.Cu")
		(net "RST_PEX_SSD12_PERST_N")
	)
	(segment
		(start 338.47405 -157.734)
		(end 338.79409 -158.05404)
		(width 0.13208)
		(layer "F.Cu")
		(net "RST_PEX_SSD12_PERST_N")
	)
	(segment
		(start 342.624156 -158.31312)
		(end 343.149936 -158.31312)
		(width 0.13208)
		(layer "F.Cu")
		(net "RST_PEX_SSD12_PERST_N")
	)
	(segment
		(start 342.245188 -157.934152)
		(end 342.624156 -158.31312)
		(width 0.13208)
		(layer "F.Cu")
		(net "RST_PEX_SSD12_PERST_N")
	)
	(segment
		(start 341.313008 -158.05404)
		(end 341.432896 -157.934152)
		(width 0.13208)
		(layer "F.Cu")
		(net "RST_PEX_SSD12_PERST_N")
	)
	(segment
		(start 338.79409 -158.05404)
		(end 339.225128 -158.05404)
		(width 0.13208)
		(layer "F.Cu")
		(net "RST_PEX_SSD12_PERST_N")
	)
	(via
		(at 339.225128 -158.05404)
		(size 0.508)
		(drill 0.254)
		(layers "F.Cu" "B.Cu")
		(net "RST_PEX_SSD12_PERST_N")
	)
	(segment
		(start 230.66756 -223.104202)
		(end 231.067356 -223.503998)
		(width 0.13208)
		(layer "F.Cu")
		(net "SSD2_PWRDIS_BIC")
	)
	(via
		(at 231.067356 -223.503998)
		(size 0.4572)
		(drill 0.254)
		(layers "F.Cu" "B.Cu")
		(net "SSD2_PWRDIS_BIC")
	)
	(via
		(at 233.11358 -227.994972)
		(size 0.6604)
		(drill 0.3302)
		(layers "F.Cu" "B.Cu")
		(net "SSD2_PWRDIS_BIC")
	)
	(segment
		(start 233.11358 -227.994972)
		(end 231.622854 -226.504246)
		(width 0.13208)
		(layer "B.Cu")
		(net "SSD2_PWRDIS_BIC")
	)
	(segment
		(start 231.622854 -226.504246)
		(end 231.622854 -224.059496)
		(width 0.13208)
		(layer "B.Cu")
		(net "SSD2_PWRDIS_BIC")
	)
	(segment
		(start 233.11358 -227.994972)
		(end 233.11358 -230.440484)
		(width 0.13208)
		(layer "B.Cu")
		(net "SSD2_PWRDIS_BIC")
	)
	(segment
		(start 231.622854 -224.059496)
		(end 231.067356 -223.503998)
		(width 0.13208)
		(layer "B.Cu")
		(net "SSD2_PWRDIS_BIC")
	)
	(segment
		(start 233.11358 -230.440484)
		(end 233.498644 -230.825548)
		(width 0.13208)
		(layer "B.Cu")
		(net "SSD2_PWRDIS_BIC")
	)
	(segment
		(start 350.11741 -167.215312)
		(end 349.91802 -167.015922)
		(width 0.13208)
		(layer "F.Cu")
		(net "RST_PEX_NIC5_PERST_N")
	)
	(segment
		(start 351.132902 -167.837104)
		(end 350.11741 -167.837104)
		(width 0.13208)
		(layer "F.Cu")
		(net "RST_PEX_NIC5_PERST_N")
	)
	(segment
		(start 349.91802 -167.015922)
		(end 349.000064 -167.015922)
		(width 0.13208)
		(layer "F.Cu")
		(net "RST_PEX_NIC5_PERST_N")
	)
	(segment
		(start 351.330006 -167.64)
		(end 351.132902 -167.837104)
		(width 0.13208)
		(layer "F.Cu")
		(net "RST_PEX_NIC5_PERST_N")
	)
	(segment
		(start 350.11741 -167.837104)
		(end 350.11741 -167.215312)
		(width 0.13208)
		(layer "F.Cu")
		(net "RST_PEX_NIC5_PERST_N")
	)
	(segment
		(start 353.42195 -167.64)
		(end 351.330006 -167.64)
		(width 0.13208)
		(layer "F.Cu")
		(net "RST_PEX_NIC5_PERST_N")
	)
	(via
		(at 350.11741 -167.837104)
		(size 0.508)
		(drill 0.254)
		(layers "F.Cu" "B.Cu")
		(net "RST_PEX_NIC5_PERST_N")
	)
	(segment
		(start 340.359746 -158.75)
		(end 340.572852 -158.963106)
		(width 0.13208)
		(layer "F.Cu")
		(net "SSD12_PEX_PWR_EN")
	)
	(segment
		(start 340.572852 -158.963106)
		(end 340.881462 -158.963106)
		(width 0.13208)
		(layer "F.Cu")
		(net "SSD12_PEX_PWR_EN")
	)
	(segment
		(start 340.881462 -158.963106)
		(end 343.149936 -158.963106)
		(width 0.13208)
		(layer "F.Cu")
		(net "SSD12_PEX_PWR_EN")
	)
	(segment
		(start 338.47405 -158.75)
		(end 340.359746 -158.75)
		(width 0.13208)
		(layer "F.Cu")
		(net "SSD12_PEX_PWR_EN")
	)
	(via
		(at 340.881462 -158.963106)
		(size 0.508)
		(drill 0.254)
		(layers "F.Cu" "B.Cu")
		(net "SSD12_PEX_PWR_EN")
	)
	(segment
		(start 310.575452 -58.072274)
		(end 310.066944 -57.563766)
		(width 0.13208)
		(layer "F.Cu")
		(net "SSD10_PWR_EN_R")
	)
	(segment
		(start 310.066944 -57.563766)
		(end 310.066944 -57.332626)
		(width 0.13208)
		(layer "F.Cu")
		(net "SSD10_PWR_EN_R")
	)
	(segment
		(start 310.066944 -57.332626)
		(end 310.066944 -56.354218)
		(width 0.13208)
		(layer "F.Cu")
		(net "SSD10_PWR_EN_R")
	)
	(segment
		(start 308.858412 -55.144162)
		(end 310.067706 -56.353456)
		(width 0.13208)
		(layer "F.Cu")
		(net "SSD10_PWR_EN_R")
	)
	(segment
		(start 337.566 -204.83195)
		(end 337.566 -204.216)
		(width 0.13208)
		(layer "F.Cu")
		(net "SSD10_PWR_EN_R")
	)
	(segment
		(start 310.066944 -56.354218)
		(end 310.067706 -56.353456)
		(width 0.13208)
		(layer "F.Cu")
		(net "SSD10_PWR_EN_R")
	)
	(segment
		(start 304.714402 -65.92189)
		(end 304.714402 -65.100962)
		(width 0.13208)
		(layer "F.Cu")
		(net "SSD10_PWR_EN_R")
	)
	(segment
		(start 308.34711 -55.144162)
		(end 308.858412 -55.144162)
		(width 0.13208)
		(layer "F.Cu")
		(net "SSD10_PWR_EN_R")
	)
	(via
		(at 304.714402 -65.100962)
		(size 0.508)
		(drill 0.254)
		(layers "F.Cu" "B.Cu")
		(net "SSD10_PWR_EN_R")
	)
	(via
		(at 337.566 -204.216)
		(size 0.508)
		(drill 0.254)
		(layers "F.Cu" "B.Cu")
		(net "SSD10_PWR_EN_R")
	)
	(via
		(at 310.575452 -58.072274)
		(size 0.508)
		(drill 0.254)
		(layers "F.Cu" "B.Cu")
		(net "SSD10_PWR_EN_R")
	)
	(segment
		(start 341.67826 -148.476462)
		(end 341.67826 -150.630636)
		(width 0.15494)
		(layer "In5.Cu")
		(net "SSD10_PWR_EN_R")
	)
	(segment
		(start 340.815422 -151.493474)
		(end 340.815422 -158.259526)
		(width 0.15494)
		(layer "In5.Cu")
		(net "SSD10_PWR_EN_R")
	)
	(segment
		(start 324.138798 -132.627878)
		(end 329.271884 -137.760964)
		(width 0.15494)
		(layer "In5.Cu")
		(net "SSD10_PWR_EN_R")
	)
	(segment
		(start 310.575452 -58.072274)
		(end 310.383174 -58.264552)
		(width 0.15494)
		(layer "In5.Cu")
		(net "SSD10_PWR_EN_R")
	)
	(segment
		(start 324.138798 -128.800352)
		(end 324.138798 -132.627878)
		(width 0.15494)
		(layer "In5.Cu")
		(net "SSD10_PWR_EN_R")
	)
	(segment
		(start 337.03895 -198.119492)
		(end 337.03895 -202.568048)
		(width 0.15494)
		(layer "In5.Cu")
		(net "SSD10_PWR_EN_R")
	)
	(segment
		(start 342.542622 -170.745658)
		(end 342.542622 -172.722794)
		(width 0.15494)
		(layer "In5.Cu")
		(net "SSD10_PWR_EN_R")
	)
	(segment
		(start 310.575452 -58.072274)
		(end 310.874918 -58.37174)
		(width 0.15494)
		(layer "In5.Cu")
		(net "SSD10_PWR_EN_R")
	)
	(segment
		(start 320.672206 -118.94058)
		(end 320.672206 -125.33376)
		(width 0.15494)
		(layer "In5.Cu")
		(net "SSD10_PWR_EN_R")
	)
	(segment
		(start 309.750968 -65.08369)
		(end 306.570126 -65.08369)
		(width 0.15494)
		(layer "In5.Cu")
		(net "SSD10_PWR_EN_R")
	)
	(segment
		(start 329.271884 -137.760964)
		(end 336.894678 -137.760964)
		(width 0.15494)
		(layer "In5.Cu")
		(net "SSD10_PWR_EN_R")
	)
	(segment
		(start 316.455552 -71.830946)
		(end 316.455552 -114.723926)
		(width 0.15494)
		(layer "In5.Cu")
		(net "SSD10_PWR_EN_R")
	)
	(segment
		(start 310.383174 -58.264552)
		(end 310.383174 -64.451484)
		(width 0.15494)
		(layer "In5.Cu")
		(net "SSD10_PWR_EN_R")
	)
	(segment
		(start 320.672206 -125.33376)
		(end 324.138798 -128.800352)
		(width 0.15494)
		(layer "In5.Cu")
		(net "SSD10_PWR_EN_R")
	)
	(segment
		(start 306.570126 -65.08369)
		(end 305.998372 -65.655444)
		(width 0.15494)
		(layer "In5.Cu")
		(net "SSD10_PWR_EN_R")
	)
	(segment
		(start 310.874918 -66.250312)
		(end 316.455552 -71.830946)
		(width 0.15494)
		(layer "In5.Cu")
		(net "SSD10_PWR_EN_R")
	)
	(segment
		(start 341.384128 -148.18233)
		(end 341.67826 -148.476462)
		(width 0.15494)
		(layer "In5.Cu")
		(net "SSD10_PWR_EN_R")
	)
	(segment
		(start 340.377526 -158.697422)
		(end 340.377526 -159.83966)
		(width 0.15494)
		(layer "In5.Cu")
		(net "SSD10_PWR_EN_R")
	)
	(segment
		(start 337.03895 -202.568048)
		(end 337.566 -203.095098)
		(width 0.15494)
		(layer "In5.Cu")
		(net "SSD10_PWR_EN_R")
	)
	(segment
		(start 342.542622 -172.722794)
		(end 341.911686 -173.35373)
		(width 0.15494)
		(layer "In5.Cu")
		(net "SSD10_PWR_EN_R")
	)
	(segment
		(start 310.874918 -58.37174)
		(end 310.874918 -66.250312)
		(width 0.15494)
		(layer "In5.Cu")
		(net "SSD10_PWR_EN_R")
	)
	(segment
		(start 341.042498 -160.504632)
		(end 341.042498 -161.126678)
		(width 0.15494)
		(layer "In5.Cu")
		(net "SSD10_PWR_EN_R")
	)
	(segment
		(start 340.377526 -159.83966)
		(end 341.042498 -160.504632)
		(width 0.15494)
		(layer "In5.Cu")
		(net "SSD10_PWR_EN_R")
	)
	(segment
		(start 341.965534 -170.16857)
		(end 342.542622 -170.745658)
		(width 0.15494)
		(layer "In5.Cu")
		(net "SSD10_PWR_EN_R")
	)
	(segment
		(start 340.59622 -161.572956)
		(end 340.59622 -161.96818)
		(width 0.15494)
		(layer "In5.Cu")
		(net "SSD10_PWR_EN_R")
	)
	(segment
		(start 336.411062 -197.491604)
		(end 337.03895 -198.119492)
		(width 0.15494)
		(layer "In5.Cu")
		(net "SSD10_PWR_EN_R")
	)
	(segment
		(start 337.566 -203.095098)
		(end 337.566 -204.216)
		(width 0.15494)
		(layer "In5.Cu")
		(net "SSD10_PWR_EN_R")
	)
	(segment
		(start 341.67826 -150.630636)
		(end 340.815422 -151.493474)
		(width 0.15494)
		(layer "In5.Cu")
		(net "SSD10_PWR_EN_R")
	)
	(segment
		(start 340.59622 -161.96818)
		(end 340.815422 -162.187382)
		(width 0.15494)
		(layer "In5.Cu")
		(net "SSD10_PWR_EN_R")
	)
	(segment
		(start 340.815422 -169.336974)
		(end 341.647018 -170.16857)
		(width 0.15494)
		(layer "In5.Cu")
		(net "SSD10_PWR_EN_R")
	)
	(segment
		(start 305.998372 -65.655444)
		(end 305.268884 -65.655444)
		(width 0.15494)
		(layer "In5.Cu")
		(net "SSD10_PWR_EN_R")
	)
	(segment
		(start 341.911686 -174.457868)
		(end 336.411062 -179.958492)
		(width 0.15494)
		(layer "In5.Cu")
		(net "SSD10_PWR_EN_R")
	)
	(segment
		(start 316.455552 -114.723926)
		(end 320.672206 -118.94058)
		(width 0.15494)
		(layer "In5.Cu")
		(net "SSD10_PWR_EN_R")
	)
	(segment
		(start 336.411062 -179.958492)
		(end 336.411062 -197.491604)
		(width 0.15494)
		(layer "In5.Cu")
		(net "SSD10_PWR_EN_R")
	)
	(segment
		(start 340.815422 -158.259526)
		(end 340.377526 -158.697422)
		(width 0.15494)
		(layer "In5.Cu")
		(net "SSD10_PWR_EN_R")
	)
	(segment
		(start 341.911686 -173.35373)
		(end 341.911686 -174.457868)
		(width 0.15494)
		(layer "In5.Cu")
		(net "SSD10_PWR_EN_R")
	)
	(segment
		(start 341.384128 -142.250414)
		(end 341.384128 -148.18233)
		(width 0.15494)
		(layer "In5.Cu")
		(net "SSD10_PWR_EN_R")
	)
	(segment
		(start 305.268884 -65.655444)
		(end 304.714402 -65.100962)
		(width 0.15494)
		(layer "In5.Cu")
		(net "SSD10_PWR_EN_R")
	)
	(segment
		(start 336.894678 -137.760964)
		(end 341.384128 -142.250414)
		(width 0.15494)
		(layer "In5.Cu")
		(net "SSD10_PWR_EN_R")
	)
	(segment
		(start 340.815422 -162.187382)
		(end 340.815422 -169.336974)
		(width 0.15494)
		(layer "In5.Cu")
		(net "SSD10_PWR_EN_R")
	)
	(segment
		(start 341.042498 -161.126678)
		(end 340.59622 -161.572956)
		(width 0.15494)
		(layer "In5.Cu")
		(net "SSD10_PWR_EN_R")
	)
	(segment
		(start 310.383174 -64.451484)
		(end 309.750968 -65.08369)
		(width 0.15494)
		(layer "In5.Cu")
		(net "SSD10_PWR_EN_R")
	)
	(segment
		(start 341.647018 -170.16857)
		(end 341.965534 -170.16857)
		(width 0.15494)
		(layer "In5.Cu")
		(net "SSD10_PWR_EN_R")
	)
	(segment
		(start 320.451988 -227.296726)
		(end 320.451226 -227.295964)
		(width 0.13208)
		(layer "F.Cu")
		(net "FPGA_DEBUG_LED_R_N")
	)
	(segment
		(start 319.879472 -224.659698)
		(end 319.879472 -223.389698)
		(width 0.13208)
		(layer "F.Cu")
		(net "FPGA_DEBUG_LED_R_N")
	)
	(segment
		(start 319.879472 -219.579698)
		(end 319.879472 -218.309698)
		(width 0.13208)
		(layer "F.Cu")
		(net "FPGA_DEBUG_LED_R_N")
	)
	(segment
		(start 320.451226 -227.295964)
		(end 320.450464 -227.295202)
		(width 0.13208)
		(layer "F.Cu")
		(net "FPGA_DEBUG_LED_R_N")
	)
	(segment
		(start 319.389252 -225.929698)
		(end 319.879472 -225.929698)
		(width 0.13208)
		(layer "F.Cu")
		(net "FPGA_DEBUG_LED_R_N")
	)
	(segment
		(start 319.879472 -223.389698)
		(end 319.879472 -222.119698)
		(width 0.13208)
		(layer "F.Cu")
		(net "FPGA_DEBUG_LED_R_N")
	)
	(segment
		(start 319.879472 -222.119698)
		(end 319.879472 -220.849698)
		(width 0.13208)
		(layer "F.Cu")
		(net "FPGA_DEBUG_LED_R_N")
	)
	(segment
		(start 319.262252 -227.295202)
		(end 319.262252 -226.056698)
		(width 0.13208)
		(layer "F.Cu")
		(net "FPGA_DEBUG_LED_R_N")
	)
	(segment
		(start 319.879472 -217.039698)
		(end 319.879472 -218.309698)
		(width 0.13208)
		(layer "F.Cu")
		(net "FPGA_DEBUG_LED_R_N")
	)
	(segment
		(start 319.879472 -220.849698)
		(end 319.879472 -219.579698)
		(width 0.13208)
		(layer "F.Cu")
		(net "FPGA_DEBUG_LED_R_N")
	)
	(segment
		(start 320.451988 -228.204268)
		(end 320.451988 -227.296726)
		(width 0.13208)
		(layer "F.Cu")
		(net "FPGA_DEBUG_LED_R_N")
	)
	(segment
		(start 320.450464 -227.295202)
		(end 319.262252 -227.295202)
		(width 0.13208)
		(layer "F.Cu")
		(net "FPGA_DEBUG_LED_R_N")
	)
	(segment
		(start 319.262252 -226.056698)
		(end 319.389252 -225.929698)
		(width 0.13208)
		(layer "F.Cu")
		(net "FPGA_DEBUG_LED_R_N")
	)
	(segment
		(start 319.879472 -225.929698)
		(end 319.879472 -224.659698)
		(width 0.13208)
		(layer "F.Cu")
		(net "FPGA_DEBUG_LED_R_N")
	)
	(via
		(at 319.262252 -227.295202)
		(size 0.762)
		(drill 0.381)
		(layers "F.Cu" "B.Cu")
		(net "FPGA_DEBUG_LED_R_N")
	)
	(segment
		(start 230.925116 -227.695252)
		(end 230.925116 -229.214426)
		(width 0.13208)
		(layer "F.Cu")
		(net "SSD10_PWRDIS_BIC")
	)
	(segment
		(start 229.867714 -223.904048)
		(end 230.267764 -224.304098)
		(width 0.13208)
		(layer "F.Cu")
		(net "SSD10_PWRDIS_BIC")
	)
	(segment
		(start 230.925116 -227.1903)
		(end 230.925116 -227.695252)
		(width 0.13208)
		(layer "F.Cu")
		(net "SSD10_PWRDIS_BIC")
	)
	(segment
		(start 230.925116 -229.214426)
		(end 231.4448 -229.73411)
		(width 0.13208)
		(layer "F.Cu")
		(net "SSD10_PWRDIS_BIC")
	)
	(segment
		(start 230.267764 -224.304098)
		(end 230.267764 -226.532948)
		(width 0.13208)
		(layer "F.Cu")
		(net "SSD10_PWRDIS_BIC")
	)
	(segment
		(start 231.4448 -229.73411)
		(end 231.4448 -230.15575)
		(width 0.13208)
		(layer "F.Cu")
		(net "SSD10_PWRDIS_BIC")
	)
	(segment
		(start 231.4448 -230.15575)
		(end 232.283 -230.99395)
		(width 0.13208)
		(layer "F.Cu")
		(net "SSD10_PWRDIS_BIC")
	)
	(segment
		(start 230.267764 -226.532948)
		(end 230.925116 -227.1903)
		(width 0.13208)
		(layer "F.Cu")
		(net "SSD10_PWRDIS_BIC")
	)
	(via
		(at 230.925116 -227.695252)
		(size 0.762)
		(drill 0.381)
		(layers "F.Cu" "B.Cu")
		(net "SSD10_PWRDIS_BIC")
	)
	(segment
		(start 334.09382 -212.786976)
		(end 333.694024 -212.38718)
		(width 0.13208)
		(layer "F.Cu")
		(net "RST_PEX_SSD12_PERST_R_N")
	)
	(segment
		(start 337.058 -157.734)
		(end 337.67395 -157.734)
		(width 0.13208)
		(layer "F.Cu")
		(net "RST_PEX_SSD12_PERST_R_N")
	)
	(segment
		(start 336.44205 -157.734)
		(end 337.058 -157.734)
		(width 0.13208)
		(layer "F.Cu")
		(net "RST_PEX_SSD12_PERST_R_N")
	)
	(via
		(at 337.058 -157.734)
		(size 0.508)
		(drill 0.254)
		(layers "F.Cu" "B.Cu")
		(net "RST_PEX_SSD12_PERST_R_N")
	)
	(via
		(at 333.694024 -212.38718)
		(size 0.4572)
		(drill 0.254)
		(layers "F.Cu" "B.Cu")
		(net "RST_PEX_SSD12_PERST_R_N")
	)
	(via
		(at 341.54872 -157.24759)
		(size 0.508)
		(drill 0.254)
		(layers "F.Cu" "B.Cu")
		(net "RST_PEX_SSD12_PERST_R_N")
	)
	(segment
		(start 333.297784 -211.99094)
		(end 333.694024 -212.38718)
		(width 0.15494)
		(layer "In9.Cu")
		(net "RST_PEX_SSD12_PERST_R_N")
	)
	(segment
		(start 336.035396 -184.58815)
		(end 336.035396 -186.880754)
		(width 0.15494)
		(layer "In9.Cu")
		(net "RST_PEX_SSD12_PERST_R_N")
	)
	(segment
		(start 329.838812 -207.584548)
		(end 331.713586 -209.459322)
		(width 0.15494)
		(layer "In9.Cu")
		(net "RST_PEX_SSD12_PERST_R_N")
	)
	(segment
		(start 331.713586 -210.94319)
		(end 332.761336 -211.99094)
		(width 0.15494)
		(layer "In9.Cu")
		(net "RST_PEX_SSD12_PERST_R_N")
	)
	(segment
		(start 341.4268 -158.6484)
		(end 341.7062 -158.9278)
		(width 0.15494)
		(layer "In9.Cu")
		(net "RST_PEX_SSD12_PERST_R_N")
	)
	(segment
		(start 338.7598 -181.863746)
		(end 336.035396 -184.58815)
		(width 0.15494)
		(layer "In9.Cu")
		(net "RST_PEX_SSD12_PERST_R_N")
	)
	(segment
		(start 332.761336 -211.99094)
		(end 333.297784 -211.99094)
		(width 0.15494)
		(layer "In9.Cu")
		(net "RST_PEX_SSD12_PERST_R_N")
	)
	(segment
		(start 332.6384 -190.27775)
		(end 332.6384 -197.3072)
		(width 0.15494)
		(layer "In9.Cu")
		(net "RST_PEX_SSD12_PERST_R_N")
	)
	(segment
		(start 332.6384 -197.3072)
		(end 327.1012 -202.8444)
		(width 0.15494)
		(layer "In9.Cu")
		(net "RST_PEX_SSD12_PERST_R_N")
	)
	(segment
		(start 338.7598 -176.9618)
		(end 338.7598 -181.863746)
		(width 0.15494)
		(layer "In9.Cu")
		(net "RST_PEX_SSD12_PERST_R_N")
	)
	(segment
		(start 331.713586 -209.459322)
		(end 331.713586 -210.94319)
		(width 0.15494)
		(layer "In9.Cu")
		(net "RST_PEX_SSD12_PERST_R_N")
	)
	(segment
		(start 341.7062 -158.9278)
		(end 342.2142 -158.9278)
		(width 0.15494)
		(layer "In9.Cu")
		(net "RST_PEX_SSD12_PERST_R_N")
	)
	(segment
		(start 341.4268 -157.36951)
		(end 341.4268 -158.6484)
		(width 0.15494)
		(layer "In9.Cu")
		(net "RST_PEX_SSD12_PERST_R_N")
	)
	(segment
		(start 327.1012 -202.8444)
		(end 327.1012 -205.6384)
		(width 0.15494)
		(layer "In9.Cu")
		(net "RST_PEX_SSD12_PERST_R_N")
	)
	(segment
		(start 341.54872 -157.24759)
		(end 341.4268 -157.36951)
		(width 0.15494)
		(layer "In9.Cu")
		(net "RST_PEX_SSD12_PERST_R_N")
	)
	(segment
		(start 342.2142 -158.9278)
		(end 342.7984 -159.512)
		(width 0.15494)
		(layer "In9.Cu")
		(net "RST_PEX_SSD12_PERST_R_N")
	)
	(segment
		(start 342.7984 -172.9232)
		(end 338.7598 -176.9618)
		(width 0.15494)
		(layer "In9.Cu")
		(net "RST_PEX_SSD12_PERST_R_N")
	)
	(segment
		(start 336.035396 -186.880754)
		(end 332.6384 -190.27775)
		(width 0.15494)
		(layer "In9.Cu")
		(net "RST_PEX_SSD12_PERST_R_N")
	)
	(segment
		(start 327.1012 -205.6384)
		(end 329.047348 -207.584548)
		(width 0.15494)
		(layer "In9.Cu")
		(net "RST_PEX_SSD12_PERST_R_N")
	)
	(segment
		(start 329.047348 -207.584548)
		(end 329.838812 -207.584548)
		(width 0.15494)
		(layer "In9.Cu")
		(net "RST_PEX_SSD12_PERST_R_N")
	)
	(segment
		(start 342.7984 -159.512)
		(end 342.7984 -172.9232)
		(width 0.15494)
		(layer "In9.Cu")
		(net "RST_PEX_SSD12_PERST_R_N")
	)
	(segment
		(start 340.310978 -157.734)
		(end 341.06231 -157.734)
		(width 0.15494)
		(layer "In13.Cu")
		(net "RST_PEX_SSD12_PERST_R_N")
	)
	(segment
		(start 337.058 -157.734)
		(end 338.026756 -157.734)
		(width 0.15494)
		(layer "In13.Cu")
		(net "RST_PEX_SSD12_PERST_R_N")
	)
	(segment
		(start 341.06231 -157.734)
		(end 341.54872 -157.24759)
		(width 0.15494)
		(layer "In13.Cu")
		(net "RST_PEX_SSD12_PERST_R_N")
	)
	(segment
		(start 339.469222 -158.575756)
		(end 340.310978 -157.734)
		(width 0.15494)
		(layer "In13.Cu")
		(net "RST_PEX_SSD12_PERST_R_N")
	)
	(segment
		(start 338.026756 -157.734)
		(end 338.868512 -158.575756)
		(width 0.15494)
		(layer "In13.Cu")
		(net "RST_PEX_SSD12_PERST_R_N")
	)
	(segment
		(start 338.868512 -158.575756)
		(end 339.469222 -158.575756)
		(width 0.15494)
		(layer "In13.Cu")
		(net "RST_PEX_SSD12_PERST_R_N")
	)
	(segment
		(start 372.958614 -55.144162)
		(end 374.167908 -56.353456)
		(width 0.13208)
		(layer "F.Cu")
		(net "SSD12_PWR_EN_R")
	)
	(segment
		(start 374.167146 -57.332626)
		(end 374.167146 -56.354218)
		(width 0.13208)
		(layer "F.Cu")
		(net "SSD12_PWR_EN_R")
	)
	(segment
		(start 368.814604 -65.92189)
		(end 368.814604 -65.100962)
		(width 0.13208)
		(layer "F.Cu")
		(net "SSD12_PWR_EN_R")
	)
	(segment
		(start 374.167146 -56.354218)
		(end 374.167908 -56.353456)
		(width 0.13208)
		(layer "F.Cu")
		(net "SSD12_PWR_EN_R")
	)
	(segment
		(start 374.167146 -57.563766)
		(end 374.167146 -57.332626)
		(width 0.13208)
		(layer "F.Cu")
		(net "SSD12_PWR_EN_R")
	)
	(segment
		(start 372.447312 -55.144162)
		(end 372.958614 -55.144162)
		(width 0.13208)
		(layer "F.Cu")
		(net "SSD12_PWR_EN_R")
	)
	(segment
		(start 374.675654 -58.072274)
		(end 374.167146 -57.563766)
		(width 0.13208)
		(layer "F.Cu")
		(net "SSD12_PWR_EN_R")
	)
	(via
		(at 364.597696 -109.311694)
		(size 0.508)
		(drill 0.254)
		(layers "F.Cu" "B.Cu")
		(net "SSD12_PWR_EN_R")
	)
	(via
		(at 368.814604 -65.100962)
		(size 0.508)
		(drill 0.254)
		(layers "F.Cu" "B.Cu")
		(net "SSD12_PWR_EN_R")
	)
	(via
		(at 349.34144 -109.787436)
		(size 0.508)
		(drill 0.254)
		(layers "F.Cu" "B.Cu")
		(net "SSD12_PWR_EN_R")
	)
	(via
		(at 337.058 -206.15148)
		(size 0.508)
		(drill 0.254)
		(layers "F.Cu" "B.Cu")
		(net "SSD12_PWR_EN_R")
	)
	(via
		(at 374.675654 -58.072274)
		(size 0.508)
		(drill 0.254)
		(layers "F.Cu" "B.Cu")
		(net "SSD12_PWR_EN_R")
	)
	(segment
		(start 337.439 -207.37195)
		(end 337.439 -206.53248)
		(width 0.13208)
		(layer "B.Cu")
		(net "SSD12_PWR_EN_R")
	)
	(segment
		(start 337.439 -206.53248)
		(end 337.058 -206.15148)
		(width 0.13208)
		(layer "B.Cu")
		(net "SSD12_PWR_EN_R")
	)
	(segment
		(start 374.675654 -58.072274)
		(end 374.38584 -58.362088)
		(width 0.15494)
		(layer "In5.Cu")
		(net "SSD12_PWR_EN_R")
	)
	(segment
		(start 374.38584 -58.362088)
		(end 374.38584 -64.041274)
		(width 0.15494)
		(layer "In5.Cu")
		(net "SSD12_PWR_EN_R")
	)
	(segment
		(start 374.38584 -64.041274)
		(end 373.753634 -64.67348)
		(width 0.15494)
		(layer "In5.Cu")
		(net "SSD12_PWR_EN_R")
	)
	(segment
		(start 371.910864 -94.318074)
		(end 368.115596 -98.113342)
		(width 0.15494)
		(layer "In5.Cu")
		(net "SSD12_PWR_EN_R")
	)
	(segment
		(start 375.264172 -58.660792)
		(end 375.264172 -76.84643)
		(width 0.15494)
		(layer "In5.Cu")
		(net "SSD12_PWR_EN_R")
	)
	(segment
		(start 368.115596 -105.793794)
		(end 364.597696 -109.311694)
		(width 0.15494)
		(layer "In5.Cu")
		(net "SSD12_PWR_EN_R")
	)
	(segment
		(start 371.910864 -80.199738)
		(end 371.910864 -94.318074)
		(width 0.15494)
		(layer "In5.Cu")
		(net "SSD12_PWR_EN_R")
	)
	(segment
		(start 369.242086 -64.67348)
		(end 368.814604 -65.100962)
		(width 0.15494)
		(layer "In5.Cu")
		(net "SSD12_PWR_EN_R")
	)
	(segment
		(start 373.753634 -64.67348)
		(end 369.242086 -64.67348)
		(width 0.15494)
		(layer "In5.Cu")
		(net "SSD12_PWR_EN_R")
	)
	(segment
		(start 375.264172 -76.84643)
		(end 371.910864 -80.199738)
		(width 0.15494)
		(layer "In5.Cu")
		(net "SSD12_PWR_EN_R")
	)
	(segment
		(start 368.115596 -98.113342)
		(end 368.115596 -105.793794)
		(width 0.15494)
		(layer "In5.Cu")
		(net "SSD12_PWR_EN_R")
	)
	(segment
		(start 374.675654 -58.072274)
		(end 375.264172 -58.660792)
		(width 0.15494)
		(layer "In5.Cu")
		(net "SSD12_PWR_EN_R")
	)
	(segment
		(start 348.85376 -121.68124)
		(end 348.85376 -110.275116)
		(width 0.15494)
		(layer "In9.Cu")
		(net "SSD12_PWR_EN_R")
	)
	(segment
		(start 340.0552 -191.186054)
		(end 341.325454 -189.9158)
		(width 0.15494)
		(layer "In9.Cu")
		(net "SSD12_PWR_EN_R")
	)
	(segment
		(start 342.239854 -189.9158)
		(end 346.2782 -185.877454)
		(width 0.15494)
		(layer "In9.Cu")
		(net "SSD12_PWR_EN_R")
	)
	(segment
		(start 348.85376 -110.275116)
		(end 349.34144 -109.787436)
		(width 0.15494)
		(layer "In9.Cu")
		(net "SSD12_PWR_EN_R")
	)
	(segment
		(start 338.95665 -198.955152)
		(end 338.95665 -192.812416)
		(width 0.15494)
		(layer "In9.Cu")
		(net "SSD12_PWR_EN_R")
	)
	(segment
		(start 338.079334 -202.889866)
		(end 338.079334 -199.832468)
		(width 0.15494)
		(layer "In9.Cu")
		(net "SSD12_PWR_EN_R")
	)
	(segment
		(start 340.0552 -191.713866)
		(end 340.0552 -191.186054)
		(width 0.15494)
		(layer "In9.Cu")
		(net "SSD12_PWR_EN_R")
	)
	(segment
		(start 337.058 -206.15148)
		(end 337.058 -203.9112)
		(width 0.15494)
		(layer "In9.Cu")
		(net "SSD12_PWR_EN_R")
	)
	(segment
		(start 347.2942 -123.2408)
		(end 348.85376 -121.68124)
		(width 0.15494)
		(layer "In9.Cu")
		(net "SSD12_PWR_EN_R")
	)
	(segment
		(start 347.2942 -138.9634)
		(end 347.2942 -123.2408)
		(width 0.15494)
		(layer "In9.Cu")
		(net "SSD12_PWR_EN_R")
	)
	(segment
		(start 341.325454 -189.9158)
		(end 342.239854 -189.9158)
		(width 0.15494)
		(layer "In9.Cu")
		(net "SSD12_PWR_EN_R")
	)
	(segment
		(start 337.058 -203.9112)
		(end 338.079334 -202.889866)
		(width 0.15494)
		(layer "In9.Cu")
		(net "SSD12_PWR_EN_R")
	)
	(segment
		(start 346.2782 -139.9794)
		(end 347.2942 -138.9634)
		(width 0.15494)
		(layer "In9.Cu")
		(net "SSD12_PWR_EN_R")
	)
	(segment
		(start 346.2782 -185.877454)
		(end 346.2782 -139.9794)
		(width 0.15494)
		(layer "In9.Cu")
		(net "SSD12_PWR_EN_R")
	)
	(segment
		(start 338.95665 -192.812416)
		(end 340.0552 -191.713866)
		(width 0.15494)
		(layer "In9.Cu")
		(net "SSD12_PWR_EN_R")
	)
	(segment
		(start 338.079334 -199.832468)
		(end 338.95665 -198.955152)
		(width 0.15494)
		(layer "In9.Cu")
		(net "SSD12_PWR_EN_R")
	)
	(segment
		(start 360.7054 -110.6424)
		(end 362.036106 -109.311694)
		(width 0.15494)
		(layer "In13.Cu")
		(net "SSD12_PWR_EN_R")
	)
	(segment
		(start 349.34144 -109.787436)
		(end 351.549208 -109.787436)
		(width 0.15494)
		(layer "In13.Cu")
		(net "SSD12_PWR_EN_R")
	)
	(segment
		(start 362.036106 -109.311694)
		(end 364.597696 -109.311694)
		(width 0.15494)
		(layer "In13.Cu")
		(net "SSD12_PWR_EN_R")
	)
	(segment
		(start 352.404172 -110.6424)
		(end 360.7054 -110.6424)
		(width 0.15494)
		(layer "In13.Cu")
		(net "SSD12_PWR_EN_R")
	)
	(segment
		(start 351.549208 -109.787436)
		(end 352.404172 -110.6424)
		(width 0.15494)
		(layer "In13.Cu")
		(net "SSD12_PWR_EN_R")
	)
	(segment
		(start 322.188078 -218.309698)
		(end 323.517768 -218.309698)
		(width 0.13208)
		(layer "F.Cu")
		(net "LED_POSTCODE_R_6")
	)
	(segment
		(start 320.829432 -218.309698)
		(end 322.188078 -218.309698)
		(width 0.13208)
		(layer "F.Cu")
		(net "LED_POSTCODE_R_6")
	)
	(via
		(at 322.188078 -218.309698)
		(size 0.762)
		(drill 0.381)
		(layers "F.Cu" "B.Cu")
		(net "LED_POSTCODE_R_6")
	)
	(segment
		(start 233.7816 -230.4034)
		(end 235.258356 -230.4034)
		(width 0.13208)
		(layer "F.Cu")
		(net "SSD7_PWRDIS_BIC")
	)
	(segment
		(start 231.46766 -225.95967)
		(end 232.830116 -227.322126)
		(width 0.13208)
		(layer "F.Cu")
		(net "SSD7_PWRDIS_BIC")
	)
	(segment
		(start 235.258356 -230.4034)
		(end 235.871512 -231.016556)
		(width 0.13208)
		(layer "F.Cu")
		(net "SSD7_PWRDIS_BIC")
	)
	(segment
		(start 232.830116 -228.796342)
		(end 232.830116 -229.451916)
		(width 0.13208)
		(layer "F.Cu")
		(net "SSD7_PWRDIS_BIC")
	)
	(segment
		(start 231.46766 -224.704148)
		(end 231.46766 -225.95967)
		(width 0.13208)
		(layer "F.Cu")
		(net "SSD7_PWRDIS_BIC")
	)
	(segment
		(start 232.830116 -229.451916)
		(end 233.7816 -230.4034)
		(width 0.13208)
		(layer "F.Cu")
		(net "SSD7_PWRDIS_BIC")
	)
	(segment
		(start 232.830116 -227.322126)
		(end 232.830116 -228.796342)
		(width 0.13208)
		(layer "F.Cu")
		(net "SSD7_PWRDIS_BIC")
	)
	(via
		(at 232.830116 -228.796342)
		(size 0.762)
		(drill 0.381)
		(layers "F.Cu" "B.Cu")
		(net "SSD7_PWRDIS_BIC")
	)
	(segment
		(start 336.44205 -158.75)
		(end 336.789522 -158.75)
		(width 0.13208)
		(layer "F.Cu")
		(net "SSD12_PEX_PWR_EN_R")
	)
	(segment
		(start 336.789522 -158.75)
		(end 337.058762 -158.48076)
		(width 0.13208)
		(layer "F.Cu")
		(net "SSD12_PEX_PWR_EN_R")
	)
	(segment
		(start 336.44205 -159.766)
		(end 336.44205 -158.75)
		(width 0.13208)
		(layer "F.Cu")
		(net "SSD12_PEX_PWR_EN_R")
	)
	(segment
		(start 337.328002 -158.75)
		(end 337.67395 -158.75)
		(width 0.13208)
		(layer "F.Cu")
		(net "SSD12_PEX_PWR_EN_R")
	)
	(segment
		(start 334.09382 -211.98713)
		(end 333.694024 -211.587334)
		(width 0.13208)
		(layer "F.Cu")
		(net "SSD12_PEX_PWR_EN_R")
	)
	(segment
		(start 337.058762 -158.48076)
		(end 337.328002 -158.75)
		(width 0.13208)
		(layer "F.Cu")
		(net "SSD12_PEX_PWR_EN_R")
	)
	(via
		(at 341.980012 -158.428436)
		(size 0.508)
		(drill 0.254)
		(layers "F.Cu" "B.Cu")
		(net "SSD12_PEX_PWR_EN_R")
	)
	(via
		(at 337.058762 -158.48076)
		(size 0.508)
		(drill 0.254)
		(layers "F.Cu" "B.Cu")
		(net "SSD12_PEX_PWR_EN_R")
	)
	(via
		(at 333.694024 -211.587334)
		(size 0.4572)
		(drill 0.254)
		(layers "F.Cu" "B.Cu")
		(net "SSD12_PEX_PWR_EN_R")
	)
	(segment
		(start 329.260454 -206.9846)
		(end 328.20229 -205.926436)
		(width 0.15494)
		(layer "In9.Cu")
		(net "SSD12_PEX_PWR_EN_R")
	)
	(segment
		(start 343.3064 -159.309054)
		(end 342.425782 -158.428436)
		(width 0.15494)
		(layer "In9.Cu")
		(net "SSD12_PEX_PWR_EN_R")
	)
	(segment
		(start 342.425782 -158.428436)
		(end 341.980012 -158.428436)
		(width 0.15494)
		(layer "In9.Cu")
		(net "SSD12_PEX_PWR_EN_R")
	)
	(segment
		(start 337.8962 -183.4388)
		(end 339.292946 -182.042054)
		(width 0.15494)
		(layer "In9.Cu")
		(net "SSD12_PEX_PWR_EN_R")
	)
	(segment
		(start 341.783416 -175.067468)
		(end 341.783416 -174.675038)
		(width 0.15494)
		(layer "In9.Cu")
		(net "SSD12_PEX_PWR_EN_R")
	)
	(segment
		(start 328.20229 -202.429364)
		(end 333.1464 -197.485254)
		(width 0.15494)
		(layer "In9.Cu")
		(net "SSD12_PEX_PWR_EN_R")
	)
	(segment
		(start 339.292946 -182.042054)
		(end 339.292946 -177.557938)
		(width 0.15494)
		(layer "In9.Cu")
		(net "SSD12_PEX_PWR_EN_R")
	)
	(segment
		(start 333.1464 -191.710056)
		(end 337.8962 -186.960256)
		(width 0.15494)
		(layer "In9.Cu")
		(net "SSD12_PEX_PWR_EN_R")
	)
	(segment
		(start 343.3064 -173.152054)
		(end 343.3064 -159.309054)
		(width 0.15494)
		(layer "In9.Cu")
		(net "SSD12_PEX_PWR_EN_R")
	)
	(segment
		(start 341.783416 -174.675038)
		(end 343.3064 -173.152054)
		(width 0.15494)
		(layer "In9.Cu")
		(net "SSD12_PEX_PWR_EN_R")
	)
	(segment
		(start 333.694024 -211.587334)
		(end 334.091534 -211.189824)
		(width 0.0889)
		(layer "In9.Cu")
		(net "SSD12_PEX_PWR_EN_R")
	)
	(segment
		(start 328.20229 -205.926436)
		(end 328.20229 -202.429364)
		(width 0.15494)
		(layer "In9.Cu")
		(net "SSD12_PEX_PWR_EN_R")
	)
	(segment
		(start 339.292946 -177.557938)
		(end 341.783416 -175.067468)
		(width 0.15494)
		(layer "In9.Cu")
		(net "SSD12_PEX_PWR_EN_R")
	)
	(segment
		(start 332.797404 -209.739484)
		(end 330.04252 -206.9846)
		(width 0.15494)
		(layer "In9.Cu")
		(net "SSD12_PEX_PWR_EN_R")
	)
	(segment
		(start 334.091534 -211.189824)
		(end 334.091534 -210.266788)
		(width 0.0889)
		(layer "In9.Cu")
		(net "SSD12_PEX_PWR_EN_R")
	)
	(segment
		(start 337.8962 -186.960256)
		(end 337.8962 -183.4388)
		(width 0.15494)
		(layer "In9.Cu")
		(net "SSD12_PEX_PWR_EN_R")
	)
	(segment
		(start 334.091534 -210.266788)
		(end 333.56423 -209.739484)
		(width 0.15494)
		(layer "In9.Cu")
		(net "SSD12_PEX_PWR_EN_R")
	)
	(segment
		(start 333.1464 -197.485254)
		(end 333.1464 -191.710056)
		(width 0.15494)
		(layer "In9.Cu")
		(net "SSD12_PEX_PWR_EN_R")
	)
	(segment
		(start 330.04252 -206.9846)
		(end 329.260454 -206.9846)
		(width 0.15494)
		(layer "In9.Cu")
		(net "SSD12_PEX_PWR_EN_R")
	)
	(segment
		(start 333.56423 -209.739484)
		(end 332.797404 -209.739484)
		(width 0.15494)
		(layer "In9.Cu")
		(net "SSD12_PEX_PWR_EN_R")
	)
	(segment
		(start 340.336124 -158.428436)
		(end 339.68436 -159.0802)
		(width 0.15494)
		(layer "In13.Cu")
		(net "SSD12_PEX_PWR_EN_R")
	)
	(segment
		(start 339.68436 -159.0802)
		(end 338.34324 -159.0802)
		(width 0.15494)
		(layer "In13.Cu")
		(net "SSD12_PEX_PWR_EN_R")
	)
	(segment
		(start 341.980012 -158.428436)
		(end 340.336124 -158.428436)
		(width 0.15494)
		(layer "In13.Cu")
		(net "SSD12_PEX_PWR_EN_R")
	)
	(segment
		(start 338.34324 -159.0802)
		(end 337.7438 -158.48076)
		(width 0.15494)
		(layer "In13.Cu")
		(net "SSD12_PEX_PWR_EN_R")
	)
	(segment
		(start 337.7438 -158.48076)
		(end 337.058762 -158.48076)
		(width 0.15494)
		(layer "In13.Cu")
		(net "SSD12_PEX_PWR_EN_R")
	)
	(segment
		(start 343.662 -204.83195)
		(end 343.662 -204.216)
		(width 0.13208)
		(layer "F.Cu")
		(net "SSD14_PWR_EN_R")
	)
	(segment
		(start 424.95851 -55.144162)
		(end 426.167804 -56.353456)
		(width 0.13208)
		(layer "F.Cu")
		(net "SSD14_PWR_EN_R")
	)
	(segment
		(start 426.67555 -58.072274)
		(end 426.167042 -57.563766)
		(width 0.13208)
		(layer "F.Cu")
		(net "SSD14_PWR_EN_R")
	)
	(segment
		(start 426.167042 -57.563766)
		(end 426.167042 -57.332626)
		(width 0.13208)
		(layer "F.Cu")
		(net "SSD14_PWR_EN_R")
	)
	(segment
		(start 420.8145 -65.92189)
		(end 420.8145 -65.100962)
		(width 0.13208)
		(layer "F.Cu")
		(net "SSD14_PWR_EN_R")
	)
	(segment
		(start 426.167042 -57.332626)
		(end 426.167042 -56.354218)
		(width 0.13208)
		(layer "F.Cu")
		(net "SSD14_PWR_EN_R")
	)
	(segment
		(start 426.167042 -56.354218)
		(end 426.167804 -56.353456)
		(width 0.13208)
		(layer "F.Cu")
		(net "SSD14_PWR_EN_R")
	)
	(segment
		(start 424.447208 -55.144162)
		(end 424.95851 -55.144162)
		(width 0.13208)
		(layer "F.Cu")
		(net "SSD14_PWR_EN_R")
	)
	(via
		(at 343.662 -204.216)
		(size 0.508)
		(drill 0.254)
		(layers "F.Cu" "B.Cu")
		(net "SSD14_PWR_EN_R")
	)
	(via
		(at 426.67555 -58.072274)
		(size 0.508)
		(drill 0.254)
		(layers "F.Cu" "B.Cu")
		(net "SSD14_PWR_EN_R")
	)
	(via
		(at 416.13836 -96.402144)
		(size 0.508)
		(drill 0.254)
		(layers "F.Cu" "B.Cu")
		(net "SSD14_PWR_EN_R")
	)
	(via
		(at 359.56494 -106.081576)
		(size 0.508)
		(drill 0.254)
		(layers "F.Cu" "B.Cu")
		(net "SSD14_PWR_EN_R")
	)
	(via
		(at 420.8145 -65.100962)
		(size 0.508)
		(drill 0.254)
		(layers "F.Cu" "B.Cu")
		(net "SSD14_PWR_EN_R")
	)
	(segment
		(start 347.777054 -176.598834)
		(end 347.777054 -127.82423)
		(width 0.15494)
		(layer "In5.Cu")
		(net "SSD14_PWR_EN_R")
	)
	(segment
		(start 418.311076 -84.744052)
		(end 414.919922 -84.744052)
		(width 0.15494)
		(layer "In5.Cu")
		(net "SSD14_PWR_EN_R")
	)
	(segment
		(start 427.390052 -58.786776)
		(end 427.390052 -75.665076)
		(width 0.15494)
		(layer "In5.Cu")
		(net "SSD14_PWR_EN_R")
	)
	(segment
		(start 343.1286 -199.7964)
		(end 343.662 -199.263)
		(width 0.15494)
		(layer "In5.Cu")
		(net "SSD14_PWR_EN_R")
	)
	(segment
		(start 351.741232 -116.075206)
		(end 359.065068 -108.75137)
		(width 0.15494)
		(layer "In5.Cu")
		(net "SSD14_PWR_EN_R")
	)
	(segment
		(start 426.483272 -58.264552)
		(end 426.483272 -64.451484)
		(width 0.15494)
		(layer "In5.Cu")
		(net "SSD14_PWR_EN_R")
	)
	(segment
		(start 351.741232 -123.860052)
		(end 351.741232 -116.075206)
		(width 0.15494)
		(layer "In5.Cu")
		(net "SSD14_PWR_EN_R")
	)
	(segment
		(start 343.662 -203.0476)
		(end 343.1286 -202.5142)
		(width 0.15494)
		(layer "In5.Cu")
		(net "SSD14_PWR_EN_R")
	)
	(segment
		(start 426.67555 -58.072274)
		(end 427.390052 -58.786776)
		(width 0.15494)
		(layer "In5.Cu")
		(net "SSD14_PWR_EN_R")
	)
	(segment
		(start 426.67555 -58.072274)
		(end 426.483272 -58.264552)
		(width 0.15494)
		(layer "In5.Cu")
		(net "SSD14_PWR_EN_R")
	)
	(segment
		(start 343.662 -199.263)
		(end 343.662 -180.713888)
		(width 0.15494)
		(layer "In5.Cu")
		(net "SSD14_PWR_EN_R")
	)
	(segment
		(start 421.25392 -64.661542)
		(end 420.8145 -65.100962)
		(width 0.15494)
		(layer "In5.Cu")
		(net "SSD14_PWR_EN_R")
	)
	(segment
		(start 413.532066 -93.79585)
		(end 416.13836 -96.402144)
		(width 0.15494)
		(layer "In5.Cu")
		(net "SSD14_PWR_EN_R")
	)
	(segment
		(start 343.1286 -202.5142)
		(end 343.1286 -199.7964)
		(width 0.15494)
		(layer "In5.Cu")
		(net "SSD14_PWR_EN_R")
	)
	(segment
		(start 343.662 -204.216)
		(end 343.662 -203.0476)
		(width 0.15494)
		(layer "In5.Cu")
		(net "SSD14_PWR_EN_R")
	)
	(segment
		(start 347.777054 -127.82423)
		(end 351.741232 -123.860052)
		(width 0.15494)
		(layer "In5.Cu")
		(net "SSD14_PWR_EN_R")
	)
	(segment
		(start 414.919922 -84.744052)
		(end 413.532066 -86.131908)
		(width 0.15494)
		(layer "In5.Cu")
		(net "SSD14_PWR_EN_R")
	)
	(segment
		(start 343.662 -180.713888)
		(end 347.777054 -176.598834)
		(width 0.15494)
		(layer "In5.Cu")
		(net "SSD14_PWR_EN_R")
	)
	(segment
		(start 359.065068 -106.581448)
		(end 359.56494 -106.081576)
		(width 0.15494)
		(layer "In5.Cu")
		(net "SSD14_PWR_EN_R")
	)
	(segment
		(start 426.483272 -64.451484)
		(end 426.273214 -64.661542)
		(width 0.15494)
		(layer "In5.Cu")
		(net "SSD14_PWR_EN_R")
	)
	(segment
		(start 426.273214 -64.661542)
		(end 421.25392 -64.661542)
		(width 0.15494)
		(layer "In5.Cu")
		(net "SSD14_PWR_EN_R")
	)
	(segment
		(start 413.532066 -86.131908)
		(end 413.532066 -93.79585)
		(width 0.15494)
		(layer "In5.Cu")
		(net "SSD14_PWR_EN_R")
	)
	(segment
		(start 359.065068 -108.75137)
		(end 359.065068 -106.581448)
		(width 0.15494)
		(layer "In5.Cu")
		(net "SSD14_PWR_EN_R")
	)
	(segment
		(start 427.390052 -75.665076)
		(end 418.311076 -84.744052)
		(width 0.15494)
		(layer "In5.Cu")
		(net "SSD14_PWR_EN_R")
	)
	(segment
		(start 414.579816 -94.8436)
		(end 399.643092 -94.8436)
		(width 0.15494)
		(layer "In13.Cu")
		(net "SSD14_PWR_EN_R")
	)
	(segment
		(start 390.685274 -92.9386)
		(end 384.40995 -92.9386)
		(width 0.15494)
		(layer "In13.Cu")
		(net "SSD14_PWR_EN_R")
	)
	(segment
		(start 397.66748 -96.819212)
		(end 394.565886 -96.819212)
		(width 0.15494)
		(layer "In13.Cu")
		(net "SSD14_PWR_EN_R")
	)
	(segment
		(start 384.40995 -92.9386)
		(end 376.669808 -100.678742)
		(width 0.15494)
		(layer "In13.Cu")
		(net "SSD14_PWR_EN_R")
	)
	(segment
		(start 360.399838 -106.081576)
		(end 359.56494 -106.081576)
		(width 0.15494)
		(layer "In13.Cu")
		(net "SSD14_PWR_EN_R")
	)
	(segment
		(start 361.105704 -105.37571)
		(end 360.399838 -106.081576)
		(width 0.15494)
		(layer "In13.Cu")
		(net "SSD14_PWR_EN_R")
	)
	(segment
		(start 376.669808 -103.76916)
		(end 375.063258 -105.37571)
		(width 0.15494)
		(layer "In13.Cu")
		(net "SSD14_PWR_EN_R")
	)
	(segment
		(start 394.565886 -96.819212)
		(end 390.685274 -92.9386)
		(width 0.15494)
		(layer "In13.Cu")
		(net "SSD14_PWR_EN_R")
	)
	(segment
		(start 416.13836 -96.402144)
		(end 414.579816 -94.8436)
		(width 0.15494)
		(layer "In13.Cu")
		(net "SSD14_PWR_EN_R")
	)
	(segment
		(start 399.643092 -94.8436)
		(end 397.66748 -96.819212)
		(width 0.15494)
		(layer "In13.Cu")
		(net "SSD14_PWR_EN_R")
	)
	(segment
		(start 376.669808 -100.678742)
		(end 376.669808 -103.76916)
		(width 0.15494)
		(layer "In13.Cu")
		(net "SSD14_PWR_EN_R")
	)
	(segment
		(start 375.063258 -105.37571)
		(end 361.105704 -105.37571)
		(width 0.15494)
		(layer "In13.Cu")
		(net "SSD14_PWR_EN_R")
	)
	(segment
		(start 322.188078 -222.119698)
		(end 323.517768 -222.119698)
		(width 0.13208)
		(layer "F.Cu")
		(net "LED_POSTCODE_R_3")
	)
	(segment
		(start 320.829432 -222.119698)
		(end 322.188078 -222.119698)
		(width 0.13208)
		(layer "F.Cu")
		(net "LED_POSTCODE_R_3")
	)
	(via
		(at 322.188078 -222.119698)
		(size 0.762)
		(drill 0.381)
		(layers "F.Cu" "B.Cu")
		(net "LED_POSTCODE_R_3")
	)
	(segment
		(start 231.560116 -227.355908)
		(end 230.66756 -226.463352)
		(width 0.13208)
		(layer "F.Cu")
		(net "SSD9_PWRDIS_BIC")
	)
	(segment
		(start 233.179112 -230.99395)
		(end 231.560116 -229.374954)
		(width 0.13208)
		(layer "F.Cu")
		(net "SSD9_PWRDIS_BIC")
	)
	(segment
		(start 231.560116 -228.796342)
		(end 231.560116 -227.355908)
		(width 0.13208)
		(layer "F.Cu")
		(net "SSD9_PWRDIS_BIC")
	)
	(segment
		(start 231.560116 -229.374954)
		(end 231.560116 -228.796342)
		(width 0.13208)
		(layer "F.Cu")
		(net "SSD9_PWRDIS_BIC")
	)
	(segment
		(start 230.66756 -226.463352)
		(end 230.66756 -224.704148)
		(width 0.13208)
		(layer "F.Cu")
		(net "SSD9_PWRDIS_BIC")
	)
	(segment
		(start 233.1974 -230.99395)
		(end 233.179112 -230.99395)
		(width 0.13208)
		(layer "F.Cu")
		(net "SSD9_PWRDIS_BIC")
	)
	(via
		(at 231.560116 -228.796342)
		(size 0.762)
		(drill 0.381)
		(layers "F.Cu" "B.Cu")
		(net "SSD9_PWRDIS_BIC")
	)
	(segment
		(start 452.16699 -57.563766)
		(end 452.16699 -57.332626)
		(width 0.13208)
		(layer "F.Cu")
		(net "SSD15_PWR_EN_R")
	)
	(segment
		(start 450.958458 -55.144162)
		(end 452.167752 -56.353456)
		(width 0.13208)
		(layer "F.Cu")
		(net "SSD15_PWR_EN_R")
	)
	(segment
		(start 341.63 -200.76795)
		(end 341.63 -200.152)
		(width 0.13208)
		(layer "F.Cu")
		(net "SSD15_PWR_EN_R")
	)
	(segment
		(start 446.814448 -65.92189)
		(end 446.814448 -65.100962)
		(width 0.13208)
		(layer "F.Cu")
		(net "SSD15_PWR_EN_R")
	)
	(segment
		(start 450.447156 -55.144162)
		(end 450.958458 -55.144162)
		(width 0.13208)
		(layer "F.Cu")
		(net "SSD15_PWR_EN_R")
	)
	(segment
		(start 452.16699 -56.354218)
		(end 452.167752 -56.353456)
		(width 0.13208)
		(layer "F.Cu")
		(net "SSD15_PWR_EN_R")
	)
	(segment
		(start 452.16699 -57.332626)
		(end 452.16699 -56.354218)
		(width 0.13208)
		(layer "F.Cu")
		(net "SSD15_PWR_EN_R")
	)
	(segment
		(start 452.675498 -58.072274)
		(end 452.16699 -57.563766)
		(width 0.13208)
		(layer "F.Cu")
		(net "SSD15_PWR_EN_R")
	)
	(via
		(at 422.5671 -89.733882)
		(size 0.508)
		(drill 0.254)
		(layers "F.Cu" "B.Cu")
		(net "SSD15_PWR_EN_R")
	)
	(via
		(at 446.814448 -65.100962)
		(size 0.508)
		(drill 0.254)
		(layers "F.Cu" "B.Cu")
		(net "SSD15_PWR_EN_R")
	)
	(via
		(at 341.63 -200.152)
		(size 0.508)
		(drill 0.254)
		(layers "F.Cu" "B.Cu")
		(net "SSD15_PWR_EN_R")
	)
	(via
		(at 452.675498 -58.072274)
		(size 0.508)
		(drill 0.254)
		(layers "F.Cu" "B.Cu")
		(net "SSD15_PWR_EN_R")
	)
	(via
		(at 359.249726 -101.106224)
		(size 0.508)
		(drill 0.254)
		(layers "F.Cu" "B.Cu")
		(net "SSD15_PWR_EN_R")
	)
	(segment
		(start 452.675498 -58.072274)
		(end 454.298304 -59.69508)
		(width 0.15494)
		(layer "In5.Cu")
		(net "SSD15_PWR_EN_R")
	)
	(segment
		(start 437.860694 -76.93025)
		(end 428.794672 -85.996272)
		(width 0.15494)
		(layer "In5.Cu")
		(net "SSD15_PWR_EN_R")
	)
	(segment
		(start 454.298304 -75.508866)
		(end 452.87692 -76.93025)
		(width 0.15494)
		(layer "In5.Cu")
		(net "SSD15_PWR_EN_R")
	)
	(segment
		(start 341.63 -199.4916)
		(end 342.7476 -198.374)
		(width 0.15494)
		(layer "In5.Cu")
		(net "SSD15_PWR_EN_R")
	)
	(segment
		(start 342.7476 -180.586888)
		(end 347.060774 -176.273714)
		(width 0.15494)
		(layer "In5.Cu")
		(net "SSD15_PWR_EN_R")
	)
	(segment
		(start 452.48322 -58.264552)
		(end 452.48322 -64.451484)
		(width 0.15494)
		(layer "In5.Cu")
		(net "SSD15_PWR_EN_R")
	)
	(segment
		(start 452.87692 -76.93025)
		(end 437.860694 -76.93025)
		(width 0.15494)
		(layer "In5.Cu")
		(net "SSD15_PWR_EN_R")
	)
	(segment
		(start 452.675498 -58.072274)
		(end 452.48322 -58.264552)
		(width 0.15494)
		(layer "In5.Cu")
		(net "SSD15_PWR_EN_R")
	)
	(segment
		(start 452.48322 -64.451484)
		(end 451.851014 -65.08369)
		(width 0.15494)
		(layer "In5.Cu")
		(net "SSD15_PWR_EN_R")
	)
	(segment
		(start 454.298304 -59.69508)
		(end 454.298304 -75.508866)
		(width 0.15494)
		(layer "In5.Cu")
		(net "SSD15_PWR_EN_R")
	)
	(segment
		(start 428.116492 -85.996272)
		(end 426.553884 -87.55888)
		(width 0.15494)
		(layer "In5.Cu")
		(net "SSD15_PWR_EN_R")
	)
	(segment
		(start 347.060774 -127.52705)
		(end 351.024952 -123.562872)
		(width 0.15494)
		(layer "In5.Cu")
		(net "SSD15_PWR_EN_R")
	)
	(segment
		(start 359.249726 -102.069392)
		(end 359.249726 -101.106224)
		(width 0.15494)
		(layer "In5.Cu")
		(net "SSD15_PWR_EN_R")
	)
	(segment
		(start 358.082342 -103.236776)
		(end 359.249726 -102.069392)
		(width 0.15494)
		(layer "In5.Cu")
		(net "SSD15_PWR_EN_R")
	)
	(segment
		(start 341.63 -200.152)
		(end 341.63 -199.4916)
		(width 0.15494)
		(layer "In5.Cu")
		(net "SSD15_PWR_EN_R")
	)
	(segment
		(start 358.082342 -108.720636)
		(end 358.082342 -103.236776)
		(width 0.15494)
		(layer "In5.Cu")
		(net "SSD15_PWR_EN_R")
	)
	(segment
		(start 426.553884 -87.55888)
		(end 424.742102 -87.55888)
		(width 0.15494)
		(layer "In5.Cu")
		(net "SSD15_PWR_EN_R")
	)
	(segment
		(start 428.794672 -85.996272)
		(end 428.116492 -85.996272)
		(width 0.15494)
		(layer "In5.Cu")
		(net "SSD15_PWR_EN_R")
	)
	(segment
		(start 347.060774 -176.273714)
		(end 347.060774 -127.52705)
		(width 0.15494)
		(layer "In5.Cu")
		(net "SSD15_PWR_EN_R")
	)
	(segment
		(start 424.742102 -87.55888)
		(end 422.5671 -89.733882)
		(width 0.15494)
		(layer "In5.Cu")
		(net "SSD15_PWR_EN_R")
	)
	(segment
		(start 448.834764 -65.08369)
		(end 448.234054 -65.6844)
		(width 0.15494)
		(layer "In5.Cu")
		(net "SSD15_PWR_EN_R")
	)
	(segment
		(start 447.397886 -65.6844)
		(end 446.814448 -65.100962)
		(width 0.15494)
		(layer "In5.Cu")
		(net "SSD15_PWR_EN_R")
	)
	(segment
		(start 451.851014 -65.08369)
		(end 448.834764 -65.08369)
		(width 0.15494)
		(layer "In5.Cu")
		(net "SSD15_PWR_EN_R")
	)
	(segment
		(start 448.234054 -65.6844)
		(end 447.397886 -65.6844)
		(width 0.15494)
		(layer "In5.Cu")
		(net "SSD15_PWR_EN_R")
	)
	(segment
		(start 342.7476 -198.374)
		(end 342.7476 -180.586888)
		(width 0.15494)
		(layer "In5.Cu")
		(net "SSD15_PWR_EN_R")
	)
	(segment
		(start 351.024952 -123.562872)
		(end 351.024952 -115.778026)
		(width 0.15494)
		(layer "In5.Cu")
		(net "SSD15_PWR_EN_R")
	)
	(segment
		(start 351.024952 -115.778026)
		(end 358.082342 -108.720636)
		(width 0.15494)
		(layer "In5.Cu")
		(net "SSD15_PWR_EN_R")
	)
	(segment
		(start 403.38883 -91.022424)
		(end 407.318464 -91.022424)
		(width 0.15494)
		(layer "In15.Cu")
		(net "SSD15_PWR_EN_R")
	)
	(segment
		(start 385.355084 -95.67037)
		(end 394.488924 -95.67037)
		(width 0.15494)
		(layer "In15.Cu")
		(net "SSD15_PWR_EN_R")
	)
	(segment
		(start 422.207182 -90.0938)
		(end 422.5671 -89.733882)
		(width 0.15494)
		(layer "In15.Cu")
		(net "SSD15_PWR_EN_R")
	)
	(segment
		(start 407.318464 -91.022424)
		(end 408.247088 -90.0938)
		(width 0.15494)
		(layer "In15.Cu")
		(net "SSD15_PWR_EN_R")
	)
	(segment
		(start 380.339854 -100.6856)
		(end 385.355084 -95.67037)
		(width 0.15494)
		(layer "In15.Cu")
		(net "SSD15_PWR_EN_R")
	)
	(segment
		(start 369.734338 -100.6856)
		(end 380.339854 -100.6856)
		(width 0.15494)
		(layer "In15.Cu")
		(net "SSD15_PWR_EN_R")
	)
	(segment
		(start 395.719554 -96.901)
		(end 397.510254 -96.901)
		(width 0.15494)
		(layer "In15.Cu")
		(net "SSD15_PWR_EN_R")
	)
	(segment
		(start 408.247088 -90.0938)
		(end 422.207182 -90.0938)
		(width 0.15494)
		(layer "In15.Cu")
		(net "SSD15_PWR_EN_R")
	)
	(segment
		(start 394.488924 -95.67037)
		(end 395.719554 -96.901)
		(width 0.15494)
		(layer "In15.Cu")
		(net "SSD15_PWR_EN_R")
	)
	(segment
		(start 359.249726 -101.106224)
		(end 369.313714 -101.106224)
		(width 0.15494)
		(layer "In15.Cu")
		(net "SSD15_PWR_EN_R")
	)
	(segment
		(start 369.313714 -101.106224)
		(end 369.734338 -100.6856)
		(width 0.15494)
		(layer "In15.Cu")
		(net "SSD15_PWR_EN_R")
	)
	(segment
		(start 397.510254 -96.901)
		(end 403.38883 -91.022424)
		(width 0.15494)
		(layer "In15.Cu")
		(net "SSD15_PWR_EN_R")
	)
	(segment
		(start 322.81241 -216.415366)
		(end 323.51472 -216.415366)
		(width 0.13208)
		(layer "F.Cu")
		(net "LED_POSTCODE_R_7")
	)
	(segment
		(start 322.188078 -217.039698)
		(end 322.81241 -216.415366)
		(width 0.13208)
		(layer "F.Cu")
		(net "LED_POSTCODE_R_7")
	)
	(segment
		(start 320.829432 -217.039698)
		(end 322.188078 -217.039698)
		(width 0.13208)
		(layer "F.Cu")
		(net "LED_POSTCODE_R_7")
	)
	(via
		(at 322.188078 -217.039698)
		(size 0.762)
		(drill 0.381)
		(layers "F.Cu" "B.Cu")
		(net "LED_POSTCODE_R_7")
	)
	(segment
		(start 231.06761 -226.130866)
		(end 232.195116 -227.258372)
		(width 0.13208)
		(layer "F.Cu")
		(net "SSD8_PWRDIS_BIC")
	)
	(segment
		(start 232.195116 -227.695252)
		(end 232.195116 -229.223316)
		(width 0.13208)
		(layer "F.Cu")
		(net "SSD8_PWRDIS_BIC")
	)
	(segment
		(start 232.195116 -227.258372)
		(end 232.195116 -227.695252)
		(width 0.13208)
		(layer "F.Cu")
		(net "SSD8_PWRDIS_BIC")
	)
	(segment
		(start 230.66756 -223.904048)
		(end 231.06761 -224.304098)
		(width 0.13208)
		(layer "F.Cu")
		(net "SSD8_PWRDIS_BIC")
	)
	(segment
		(start 231.06761 -224.304098)
		(end 231.06761 -226.130866)
		(width 0.13208)
		(layer "F.Cu")
		(net "SSD8_PWRDIS_BIC")
	)
	(segment
		(start 232.195116 -229.223316)
		(end 233.988356 -231.016556)
		(width 0.13208)
		(layer "F.Cu")
		(net "SSD8_PWRDIS_BIC")
	)
	(segment
		(start 233.988356 -231.016556)
		(end 234.855512 -231.016556)
		(width 0.13208)
		(layer "F.Cu")
		(net "SSD8_PWRDIS_BIC")
	)
	(via
		(at 232.195116 -227.695252)
		(size 0.762)
		(drill 0.381)
		(layers "F.Cu" "B.Cu")
		(net "SSD8_PWRDIS_BIC")
	)
	(segment
		(start 252.714506 -65.92189)
		(end 252.714506 -65.100962)
		(width 0.13208)
		(layer "F.Cu")
		(net "SSD8_PWR_EN_R")
	)
	(segment
		(start 258.575556 -58.072274)
		(end 258.067048 -57.563766)
		(width 0.13208)
		(layer "F.Cu")
		(net "SSD8_PWR_EN_R")
	)
	(segment
		(start 333.502 -200.76795)
		(end 333.502 -200.152)
		(width 0.13208)
		(layer "F.Cu")
		(net "SSD8_PWR_EN_R")
	)
	(segment
		(start 258.067048 -57.332626)
		(end 258.067048 -56.354218)
		(width 0.13208)
		(layer "F.Cu")
		(net "SSD8_PWR_EN_R")
	)
	(segment
		(start 256.347214 -55.144162)
		(end 256.858516 -55.144162)
		(width 0.13208)
		(layer "F.Cu")
		(net "SSD8_PWR_EN_R")
	)
	(segment
		(start 256.858516 -55.144162)
		(end 258.06781 -56.353456)
		(width 0.13208)
		(layer "F.Cu")
		(net "SSD8_PWR_EN_R")
	)
	(segment
		(start 258.067048 -56.354218)
		(end 258.06781 -56.353456)
		(width 0.13208)
		(layer "F.Cu")
		(net "SSD8_PWR_EN_R")
	)
	(segment
		(start 258.067048 -57.563766)
		(end 258.067048 -57.332626)
		(width 0.13208)
		(layer "F.Cu")
		(net "SSD8_PWR_EN_R")
	)
	(via
		(at 252.714506 -65.100962)
		(size 0.508)
		(drill 0.254)
		(layers "F.Cu" "B.Cu")
		(net "SSD8_PWR_EN_R")
	)
	(via
		(at 275.027898 -88.519254)
		(size 0.508)
		(drill 0.254)
		(layers "F.Cu" "B.Cu")
		(net "SSD8_PWR_EN_R")
	)
	(via
		(at 311.34177 -93.825314)
		(size 0.508)
		(drill 0.254)
		(layers "F.Cu" "B.Cu")
		(net "SSD8_PWR_EN_R")
	)
	(via
		(at 258.575556 -58.072274)
		(size 0.508)
		(drill 0.254)
		(layers "F.Cu" "B.Cu")
		(net "SSD8_PWR_EN_R")
	)
	(via
		(at 333.502 -200.152)
		(size 0.508)
		(drill 0.254)
		(layers "F.Cu" "B.Cu")
		(net "SSD8_PWR_EN_R")
	)
	(segment
		(start 315.21273 -117.239034)
		(end 313.858402 -117.239034)
		(width 0.15494)
		(layer "In5.Cu")
		(net "SSD8_PWR_EN_R")
	)
	(segment
		(start 258.383278 -64.451484)
		(end 257.751072 -65.08369)
		(width 0.15494)
		(layer "In5.Cu")
		(net "SSD8_PWR_EN_R")
	)
	(segment
		(start 333.502 -200.152)
		(end 333.154274 -199.804274)
		(width 0.15494)
		(layer "In5.Cu")
		(net "SSD8_PWR_EN_R")
	)
	(segment
		(start 253.266448 -65.652904)
		(end 252.714506 -65.100962)
		(width 0.15494)
		(layer "In5.Cu")
		(net "SSD8_PWR_EN_R")
	)
	(segment
		(start 258.89077 -58.387488)
		(end 258.89077 -68.35775)
		(width 0.15494)
		(layer "In5.Cu")
		(net "SSD8_PWR_EN_R")
	)
	(segment
		(start 254.557276 -65.08369)
		(end 253.988062 -65.652904)
		(width 0.15494)
		(layer "In5.Cu")
		(net "SSD8_PWR_EN_R")
	)
	(segment
		(start 268.688058 -78.155038)
		(end 268.688058 -83.347306)
		(width 0.15494)
		(layer "In5.Cu")
		(net "SSD8_PWR_EN_R")
	)
	(segment
		(start 311.669176 -115.049808)
		(end 311.669176 -94.15272)
		(width 0.15494)
		(layer "In5.Cu")
		(net "SSD8_PWR_EN_R")
	)
	(segment
		(start 313.858402 -117.239034)
		(end 311.669176 -115.049808)
		(width 0.15494)
		(layer "In5.Cu")
		(net "SSD8_PWR_EN_R")
	)
	(segment
		(start 329.473052 -141.720062)
		(end 321.481958 -133.728968)
		(width 0.15494)
		(layer "In5.Cu")
		(net "SSD8_PWR_EN_R")
	)
	(segment
		(start 321.481958 -133.728968)
		(end 321.481958 -129.901442)
		(width 0.15494)
		(layer "In5.Cu")
		(net "SSD8_PWR_EN_R")
	)
	(segment
		(start 268.688058 -83.347306)
		(end 273.860006 -88.519254)
		(width 0.15494)
		(layer "In5.Cu")
		(net "SSD8_PWR_EN_R")
	)
	(segment
		(start 318.015366 -126.43485)
		(end 318.015366 -120.04167)
		(width 0.15494)
		(layer "In5.Cu")
		(net "SSD8_PWR_EN_R")
	)
	(segment
		(start 321.481958 -129.901442)
		(end 318.015366 -126.43485)
		(width 0.15494)
		(layer "In5.Cu")
		(net "SSD8_PWR_EN_R")
	)
	(segment
		(start 273.860006 -88.519254)
		(end 275.027898 -88.519254)
		(width 0.15494)
		(layer "In5.Cu")
		(net "SSD8_PWR_EN_R")
	)
	(segment
		(start 257.751072 -65.08369)
		(end 254.557276 -65.08369)
		(width 0.15494)
		(layer "In5.Cu")
		(net "SSD8_PWR_EN_R")
	)
	(segment
		(start 258.575556 -58.072274)
		(end 258.89077 -58.387488)
		(width 0.15494)
		(layer "In5.Cu")
		(net "SSD8_PWR_EN_R")
	)
	(segment
		(start 311.669176 -94.15272)
		(end 311.34177 -93.825314)
		(width 0.15494)
		(layer "In5.Cu")
		(net "SSD8_PWR_EN_R")
	)
	(segment
		(start 331.301598 -141.720062)
		(end 329.473052 -141.720062)
		(width 0.15494)
		(layer "In5.Cu")
		(net "SSD8_PWR_EN_R")
	)
	(segment
		(start 333.154274 -143.572738)
		(end 331.301598 -141.720062)
		(width 0.15494)
		(layer "In5.Cu")
		(net "SSD8_PWR_EN_R")
	)
	(segment
		(start 258.575556 -58.072274)
		(end 258.383278 -58.264552)
		(width 0.15494)
		(layer "In5.Cu")
		(net "SSD8_PWR_EN_R")
	)
	(segment
		(start 258.383278 -58.264552)
		(end 258.383278 -64.451484)
		(width 0.15494)
		(layer "In5.Cu")
		(net "SSD8_PWR_EN_R")
	)
	(segment
		(start 253.988062 -65.652904)
		(end 253.266448 -65.652904)
		(width 0.15494)
		(layer "In5.Cu")
		(net "SSD8_PWR_EN_R")
	)
	(segment
		(start 318.015366 -120.04167)
		(end 315.21273 -117.239034)
		(width 0.15494)
		(layer "In5.Cu")
		(net "SSD8_PWR_EN_R")
	)
	(segment
		(start 258.89077 -68.35775)
		(end 268.688058 -78.155038)
		(width 0.15494)
		(layer "In5.Cu")
		(net "SSD8_PWR_EN_R")
	)
	(segment
		(start 333.154274 -199.804274)
		(end 333.154274 -143.572738)
		(width 0.15494)
		(layer "In5.Cu")
		(net "SSD8_PWR_EN_R")
	)
	(segment
		(start 308.944264 -94.586552)
		(end 302.968914 -88.611202)
		(width 0.15494)
		(layer "In9.Cu")
		(net "SSD8_PWR_EN_R")
	)
	(segment
		(start 310.580532 -94.586552)
		(end 308.944264 -94.586552)
		(width 0.15494)
		(layer "In9.Cu")
		(net "SSD8_PWR_EN_R")
	)
	(segment
		(start 302.968914 -88.611202)
		(end 275.958046 -88.611202)
		(width 0.15494)
		(layer "In9.Cu")
		(net "SSD8_PWR_EN_R")
	)
	(segment
		(start 311.34177 -93.825314)
		(end 310.580532 -94.586552)
		(width 0.15494)
		(layer "In9.Cu")
		(net "SSD8_PWR_EN_R")
	)
	(segment
		(start 275.866098 -88.519254)
		(end 275.027898 -88.519254)
		(width 0.15494)
		(layer "In9.Cu")
		(net "SSD8_PWR_EN_R")
	)
	(segment
		(start 275.958046 -88.611202)
		(end 275.866098 -88.519254)
		(width 0.15494)
		(layer "In9.Cu")
		(net "SSD8_PWR_EN_R")
	)
	(segment
		(start 322.188078 -219.579698)
		(end 323.517768 -219.579698)
		(width 0.13208)
		(layer "F.Cu")
		(net "LED_POSTCODE_R_5")
	)
	(segment
		(start 320.829432 -219.579698)
		(end 322.188078 -219.579698)
		(width 0.13208)
		(layer "F.Cu")
		(net "LED_POSTCODE_R_5")
	)
	(via
		(at 322.188078 -219.579698)
		(size 0.762)
		(drill 0.381)
		(layers "F.Cu" "B.Cu")
		(net "LED_POSTCODE_R_5")
	)
	(segment
		(start 233.067606 -220.704156)
		(end 233.467402 -221.103952)
		(width 0.13208)
		(layer "F.Cu")
		(net "SSD14_PWRDIS_BIC")
	)
	(via
		(at 234.30865 -227.22205)
		(size 0.6604)
		(drill 0.3302)
		(layers "F.Cu" "B.Cu")
		(net "SSD14_PWRDIS_BIC")
	)
	(via
		(at 233.467402 -221.103952)
		(size 0.4572)
		(drill 0.254)
		(layers "F.Cu" "B.Cu")
		(net "SSD14_PWRDIS_BIC")
	)
	(segment
		(start 233.467402 -221.343474)
		(end 233.071162 -221.739714)
		(width 0.0889)
		(layer "B.Cu")
		(net "SSD14_PWRDIS_BIC")
	)
	(segment
		(start 233.071162 -221.739714)
		(end 233.071162 -224.7138)
		(width 0.0889)
		(layer "B.Cu")
		(net "SSD14_PWRDIS_BIC")
	)
	(segment
		(start 235.530644 -230.825548)
		(end 235.530644 -228.444044)
		(width 0.13208)
		(layer "B.Cu")
		(net "SSD14_PWRDIS_BIC")
	)
	(segment
		(start 235.530644 -228.444044)
		(end 234.30865 -227.22205)
		(width 0.13208)
		(layer "B.Cu")
		(net "SSD14_PWRDIS_BIC")
	)
	(segment
		(start 233.071162 -224.7138)
		(end 233.071162 -225.984562)
		(width 0.13208)
		(layer "B.Cu")
		(net "SSD14_PWRDIS_BIC")
	)
	(segment
		(start 233.467402 -221.103952)
		(end 233.467402 -221.343474)
		(width 0.0889)
		(layer "B.Cu")
		(net "SSD14_PWRDIS_BIC")
	)
	(segment
		(start 233.071162 -225.984562)
		(end 234.30865 -227.22205)
		(width 0.13208)
		(layer "B.Cu")
		(net "SSD14_PWRDIS_BIC")
	)
	(segment
		(start 336.5754 -58.072274)
		(end 336.066892 -57.563766)
		(width 0.13208)
		(layer "F.Cu")
		(net "SSD11_PWR_EN_R")
	)
	(segment
		(start 340.614 -200.76795)
		(end 340.614 -200.152)
		(width 0.13208)
		(layer "F.Cu")
		(net "SSD11_PWR_EN_R")
	)
	(segment
		(start 330.71435 -65.92189)
		(end 330.71435 -65.100962)
		(width 0.13208)
		(layer "F.Cu")
		(net "SSD11_PWR_EN_R")
	)
	(segment
		(start 334.347058 -55.144162)
		(end 334.85836 -55.144162)
		(width 0.13208)
		(layer "F.Cu")
		(net "SSD11_PWR_EN_R")
	)
	(segment
		(start 336.066892 -56.354218)
		(end 336.067654 -56.353456)
		(width 0.13208)
		(layer "F.Cu")
		(net "SSD11_PWR_EN_R")
	)
	(segment
		(start 336.066892 -57.332626)
		(end 336.066892 -56.354218)
		(width 0.13208)
		(layer "F.Cu")
		(net "SSD11_PWR_EN_R")
	)
	(segment
		(start 334.85836 -55.144162)
		(end 336.067654 -56.353456)
		(width 0.13208)
		(layer "F.Cu")
		(net "SSD11_PWR_EN_R")
	)
	(segment
		(start 336.066892 -57.563766)
		(end 336.066892 -57.332626)
		(width 0.13208)
		(layer "F.Cu")
		(net "SSD11_PWR_EN_R")
	)
	(via
		(at 356.79126 -92.001086)
		(size 0.508)
		(drill 0.254)
		(layers "F.Cu" "B.Cu")
		(net "SSD11_PWR_EN_R")
	)
	(via
		(at 340.614 -200.152)
		(size 0.508)
		(drill 0.254)
		(layers "F.Cu" "B.Cu")
		(net "SSD11_PWR_EN_R")
	)
	(via
		(at 336.5754 -58.072274)
		(size 0.508)
		(drill 0.254)
		(layers "F.Cu" "B.Cu")
		(net "SSD11_PWR_EN_R")
	)
	(via
		(at 330.71435 -65.100962)
		(size 0.508)
		(drill 0.254)
		(layers "F.Cu" "B.Cu")
		(net "SSD11_PWR_EN_R")
	)
	(via
		(at 348.546928 -91.769692)
		(size 0.508)
		(drill 0.254)
		(layers "F.Cu" "B.Cu")
		(net "SSD11_PWR_EN_R")
	)
	(segment
		(start 341.717122 -185.760106)
		(end 341.717122 -183.41213)
		(width 0.15494)
		(layer "In5.Cu")
		(net "SSD11_PWR_EN_R")
	)
	(segment
		(start 340.614 -200.152)
		(end 341.077042 -199.688958)
		(width 0.15494)
		(layer "In5.Cu")
		(net "SSD11_PWR_EN_R")
	)
	(segment
		(start 341.412068 -72.874124)
		(end 341.412068 -75.830684)
		(width 0.15494)
		(layer "In5.Cu")
		(net "SSD11_PWR_EN_R")
	)
	(segment
		(start 350.666812 -115.62207)
		(end 357.085392 -109.20349)
		(width 0.15494)
		(layer "In5.Cu")
		(net "SSD11_PWR_EN_R")
	)
	(segment
		(start 341.428324 -181.195726)
		(end 346.702634 -175.921416)
		(width 0.15494)
		(layer "In5.Cu")
		(net "SSD11_PWR_EN_R")
	)
	(segment
		(start 332.50505 -65.08369)
		(end 331.944726 -65.644014)
		(width 0.15494)
		(layer "In5.Cu")
		(net "SSD11_PWR_EN_R")
	)
	(segment
		(start 346.702634 -127.37846)
		(end 350.666812 -123.414282)
		(width 0.15494)
		(layer "In5.Cu")
		(net "SSD11_PWR_EN_R")
	)
	(segment
		(start 341.717122 -183.41213)
		(end 341.428324 -183.123332)
		(width 0.15494)
		(layer "In5.Cu")
		(net "SSD11_PWR_EN_R")
	)
	(segment
		(start 338.591398 -68.706746)
		(end 339.609684 -69.725032)
		(width 0.15494)
		(layer "In5.Cu")
		(net "SSD11_PWR_EN_R")
	)
	(segment
		(start 335.750916 -65.08369)
		(end 332.50505 -65.08369)
		(width 0.15494)
		(layer "In5.Cu")
		(net "SSD11_PWR_EN_R")
	)
	(segment
		(start 331.257402 -65.644014)
		(end 330.71435 -65.100962)
		(width 0.15494)
		(layer "In5.Cu")
		(net "SSD11_PWR_EN_R")
	)
	(segment
		(start 341.077042 -186.400186)
		(end 341.717122 -185.760106)
		(width 0.15494)
		(layer "In5.Cu")
		(net "SSD11_PWR_EN_R")
	)
	(segment
		(start 341.077042 -199.688958)
		(end 341.077042 -186.400186)
		(width 0.15494)
		(layer "In5.Cu")
		(net "SSD11_PWR_EN_R")
	)
	(segment
		(start 336.5754 -58.072274)
		(end 336.383122 -58.264552)
		(width 0.15494)
		(layer "In5.Cu")
		(net "SSD11_PWR_EN_R")
	)
	(segment
		(start 357.085392 -92.295218)
		(end 356.79126 -92.001086)
		(width 0.15494)
		(layer "In5.Cu")
		(net "SSD11_PWR_EN_R")
	)
	(segment
		(start 336.383122 -64.451484)
		(end 335.750916 -65.08369)
		(width 0.15494)
		(layer "In5.Cu")
		(net "SSD11_PWR_EN_R")
	)
	(segment
		(start 339.609684 -69.725032)
		(end 339.609684 -71.07174)
		(width 0.15494)
		(layer "In5.Cu")
		(net "SSD11_PWR_EN_R")
	)
	(segment
		(start 337.233768 -58.730642)
		(end 337.233768 -64.93256)
		(width 0.15494)
		(layer "In5.Cu")
		(net "SSD11_PWR_EN_R")
	)
	(segment
		(start 331.944726 -65.644014)
		(end 331.257402 -65.644014)
		(width 0.15494)
		(layer "In5.Cu")
		(net "SSD11_PWR_EN_R")
	)
	(segment
		(start 339.609684 -71.07174)
		(end 341.412068 -72.874124)
		(width 0.15494)
		(layer "In5.Cu")
		(net "SSD11_PWR_EN_R")
	)
	(segment
		(start 341.428324 -183.123332)
		(end 341.428324 -181.195726)
		(width 0.15494)
		(layer "In5.Cu")
		(net "SSD11_PWR_EN_R")
	)
	(segment
		(start 337.233768 -64.93256)
		(end 338.591398 -66.29019)
		(width 0.15494)
		(layer "In5.Cu")
		(net "SSD11_PWR_EN_R")
	)
	(segment
		(start 346.702634 -175.921416)
		(end 346.702634 -127.37846)
		(width 0.15494)
		(layer "In5.Cu")
		(net "SSD11_PWR_EN_R")
	)
	(segment
		(start 350.666812 -123.414282)
		(end 350.666812 -115.62207)
		(width 0.15494)
		(layer "In5.Cu")
		(net "SSD11_PWR_EN_R")
	)
	(segment
		(start 348.546928 -82.965544)
		(end 348.546928 -91.769692)
		(width 0.15494)
		(layer "In5.Cu")
		(net "SSD11_PWR_EN_R")
	)
	(segment
		(start 357.085392 -109.20349)
		(end 357.085392 -92.295218)
		(width 0.15494)
		(layer "In5.Cu")
		(net "SSD11_PWR_EN_R")
	)
	(segment
		(start 336.5754 -58.072274)
		(end 337.233768 -58.730642)
		(width 0.15494)
		(layer "In5.Cu")
		(net "SSD11_PWR_EN_R")
	)
	(segment
		(start 336.383122 -58.264552)
		(end 336.383122 -64.451484)
		(width 0.15494)
		(layer "In5.Cu")
		(net "SSD11_PWR_EN_R")
	)
	(segment
		(start 338.591398 -66.29019)
		(end 338.591398 -68.706746)
		(width 0.15494)
		(layer "In5.Cu")
		(net "SSD11_PWR_EN_R")
	)
	(segment
		(start 341.412068 -75.830684)
		(end 348.546928 -82.965544)
		(width 0.15494)
		(layer "In5.Cu")
		(net "SSD11_PWR_EN_R")
	)
	(segment
		(start 354.637848 -92.43441)
		(end 353.395026 -91.191588)
		(width 0.15494)
		(layer "In15.Cu")
		(net "SSD11_PWR_EN_R")
	)
	(segment
		(start 356.79126 -92.001086)
		(end 356.357936 -92.43441)
		(width 0.15494)
		(layer "In15.Cu")
		(net "SSD11_PWR_EN_R")
	)
	(segment
		(start 349.125032 -91.191588)
		(end 348.546928 -91.769692)
		(width 0.15494)
		(layer "In15.Cu")
		(net "SSD11_PWR_EN_R")
	)
	(segment
		(start 356.357936 -92.43441)
		(end 354.637848 -92.43441)
		(width 0.15494)
		(layer "In15.Cu")
		(net "SSD11_PWR_EN_R")
	)
	(segment
		(start 353.395026 -91.191588)
		(end 349.125032 -91.191588)
		(width 0.15494)
		(layer "In15.Cu")
		(net "SSD11_PWR_EN_R")
	)
	(segment
		(start 324.785228 -227.920296)
		(end 324.359016 -227.494084)
		(width 0.13208)
		(layer "F.Cu")
		(net "FPGA_HEARTBEAT")
	)
	(segment
		(start 324.941946 -228.298502)
		(end 324.785228 -227.920296)
		(width 0.13208)
		(layer "F.Cu")
		(net "FPGA_HEARTBEAT")
	)
	(segment
		(start 325.130668 -229.126542)
		(end 324.941946 -228.93782)
		(width 0.13208)
		(layer "F.Cu")
		(net "FPGA_HEARTBEAT")
	)
	(segment
		(start 324.941946 -228.93782)
		(end 324.941946 -228.298502)
		(width 0.13208)
		(layer "F.Cu")
		(net "FPGA_HEARTBEAT")
	)
	(via
		(at 324.941946 -228.298502)
		(size 0.508)
		(drill 0.254)
		(layers "F.Cu" "B.Cu")
		(net "FPGA_HEARTBEAT")
	)
	(segment
		(start 233.067606 -221.504256)
		(end 233.467402 -221.904052)
		(width 0.13208)
		(layer "F.Cu")
		(net "SSD15_PWRDIS_BIC")
	)
	(via
		(at 233.467402 -221.904052)
		(size 0.4572)
		(drill 0.254)
		(layers "F.Cu" "B.Cu")
		(net "SSD15_PWRDIS_BIC")
	)
	(via
		(at 236.625638 -228.778054)
		(size 0.6604)
		(drill 0.3302)
		(layers "F.Cu" "B.Cu")
		(net "SSD15_PWRDIS_BIC")
	)
	(segment
		(start 235.95076 -230.229664)
		(end 235.95076 -229.452932)
		(width 0.13208)
		(layer "B.Cu")
		(net "SSD15_PWRDIS_BIC")
	)
	(segment
		(start 235.29544 -227.308156)
		(end 235.29544 -227.447856)
		(width 0.13208)
		(layer "B.Cu")
		(net "SSD15_PWRDIS_BIC")
	)
	(segment
		(start 233.863642 -225.4758)
		(end 233.863642 -225.876358)
		(width 0.13208)
		(layer "B.Cu")
		(net "SSD15_PWRDIS_BIC")
	)
	(segment
		(start 233.863642 -225.876358)
		(end 235.29544 -227.308156)
		(width 0.13208)
		(layer "B.Cu")
		(net "SSD15_PWRDIS_BIC")
	)
	(segment
		(start 235.29544 -227.447856)
		(end 236.625638 -228.778054)
		(width 0.13208)
		(layer "B.Cu")
		(net "SSD15_PWRDIS_BIC")
	)
	(segment
		(start 233.467402 -221.904052)
		(end 233.863642 -222.300292)
		(width 0.0889)
		(layer "B.Cu")
		(net "SSD15_PWRDIS_BIC")
	)
	(segment
		(start 235.95076 -229.452932)
		(end 236.625638 -228.778054)
		(width 0.13208)
		(layer "B.Cu")
		(net "SSD15_PWRDIS_BIC")
	)
	(segment
		(start 236.546644 -230.825548)
		(end 235.95076 -230.229664)
		(width 0.13208)
		(layer "B.Cu")
		(net "SSD15_PWRDIS_BIC")
	)
	(segment
		(start 233.863642 -222.300292)
		(end 233.863642 -225.4758)
		(width 0.0889)
		(layer "B.Cu")
		(net "SSD15_PWRDIS_BIC")
	)
	(segment
		(start 234.667552 -216.704164)
		(end 235.067348 -216.304368)
		(width 0.381)
		(layer "F.Cu")
		(net "P1V2_BIC_ADCVREFREXT0")
	)
	(via
		(at 237.163102 -218.642946)
		(size 0.6604)
		(drill 0.3302)
		(layers "F.Cu" "B.Cu")
		(net "P1V2_BIC_ADCVREFREXT0")
	)
	(via
		(at 237.8583 -218.015058)
		(size 0.508)
		(drill 0.254)
		(layers "F.Cu" "B.Cu")
		(net "P1V2_BIC_ADCVREFREXT0")
	)
	(via
		(at 235.067348 -216.304368)
		(size 0.4572)
		(drill 0.254)
		(layers "F.Cu" "B.Cu")
		(net "P1V2_BIC_ADCVREFREXT0")
	)
	(via
		(at 238.137954 -218.643454)
		(size 0.508)
		(drill 0.254)
		(layers "F.Cu" "B.Cu")
		(net "P1V2_BIC_ADCVREFREXT0")
	)
	(segment
		(start 400.675602 -58.072274)
		(end 400.167094 -57.563766)
		(width 0.13208)
		(layer "F.Cu")
		(net "SSD13_PWR_EN_R")
	)
	(segment
		(start 398.44726 -55.144162)
		(end 398.958562 -55.144162)
		(width 0.13208)
		(layer "F.Cu")
		(net "SSD13_PWR_EN_R")
	)
	(segment
		(start 400.167094 -57.332626)
		(end 400.167094 -56.354218)
		(width 0.13208)
		(layer "F.Cu")
		(net "SSD13_PWR_EN_R")
	)
	(segment
		(start 400.167094 -57.563766)
		(end 400.167094 -57.332626)
		(width 0.13208)
		(layer "F.Cu")
		(net "SSD13_PWR_EN_R")
	)
	(segment
		(start 398.958562 -55.144162)
		(end 400.167856 -56.353456)
		(width 0.13208)
		(layer "F.Cu")
		(net "SSD13_PWR_EN_R")
	)
	(segment
		(start 400.167094 -56.354218)
		(end 400.167856 -56.353456)
		(width 0.13208)
		(layer "F.Cu")
		(net "SSD13_PWR_EN_R")
	)
	(segment
		(start 394.814552 -65.92189)
		(end 394.814552 -65.100962)
		(width 0.13208)
		(layer "F.Cu")
		(net "SSD13_PWR_EN_R")
	)
	(via
		(at 373.72925 -110.01121)
		(size 0.508)
		(drill 0.254)
		(layers "F.Cu" "B.Cu")
		(net "SSD13_PWR_EN_R")
	)
	(via
		(at 338.074 -206.15148)
		(size 0.508)
		(drill 0.254)
		(layers "F.Cu" "B.Cu")
		(net "SSD13_PWR_EN_R")
	)
	(via
		(at 400.675602 -58.072274)
		(size 0.508)
		(drill 0.254)
		(layers "F.Cu" "B.Cu")
		(net "SSD13_PWR_EN_R")
	)
	(via
		(at 394.814552 -65.100962)
		(size 0.508)
		(drill 0.254)
		(layers "F.Cu" "B.Cu")
		(net "SSD13_PWR_EN_R")
	)
	(via
		(at 349.3516 -110.538768)
		(size 0.508)
		(drill 0.254)
		(layers "F.Cu" "B.Cu")
		(net "SSD13_PWR_EN_R")
	)
	(segment
		(start 338.582 -206.65948)
		(end 338.074 -206.15148)
		(width 0.13208)
		(layer "B.Cu")
		(net "SSD13_PWR_EN_R")
	)
	(segment
		(start 338.582 -207.37195)
		(end 338.582 -206.65948)
		(width 0.13208)
		(layer "B.Cu")
		(net "SSD13_PWR_EN_R")
	)
	(segment
		(start 395.146784 -65.848992)
		(end 396.05458 -65.848992)
		(width 0.15494)
		(layer "In5.Cu")
		(net "SSD13_PWR_EN_R")
	)
	(segment
		(start 400.167856 -63.717678)
		(end 399.466054 -64.41948)
		(width 0.15494)
		(layer "In5.Cu")
		(net "SSD13_PWR_EN_R")
	)
	(segment
		(start 399.823686 -64.849248)
		(end 401.103846 -63.569088)
		(width 0.15494)
		(layer "In5.Cu")
		(net "SSD13_PWR_EN_R")
	)
	(segment
		(start 395.496034 -64.41948)
		(end 394.814552 -65.100962)
		(width 0.15494)
		(layer "In5.Cu")
		(net "SSD13_PWR_EN_R")
	)
	(segment
		(start 384.399028 -69.136768)
		(end 387.081268 -66.454528)
		(width 0.15494)
		(layer "In5.Cu")
		(net "SSD13_PWR_EN_R")
	)
	(segment
		(start 399.466054 -64.41948)
		(end 395.496034 -64.41948)
		(width 0.15494)
		(layer "In5.Cu")
		(net "SSD13_PWR_EN_R")
	)
	(segment
		(start 400.167856 -58.58002)
		(end 400.167856 -63.717678)
		(width 0.15494)
		(layer "In5.Cu")
		(net "SSD13_PWR_EN_R")
	)
	(segment
		(start 387.081268 -66.454528)
		(end 394.541248 -66.454528)
		(width 0.15494)
		(layer "In5.Cu")
		(net "SSD13_PWR_EN_R")
	)
	(segment
		(start 376.032522 -100.500942)
		(end 384.399028 -92.134436)
		(width 0.15494)
		(layer "In5.Cu")
		(net "SSD13_PWR_EN_R")
	)
	(segment
		(start 394.541248 -66.454528)
		(end 395.146784 -65.848992)
		(width 0.15494)
		(layer "In5.Cu")
		(net "SSD13_PWR_EN_R")
	)
	(segment
		(start 397.054324 -64.849248)
		(end 399.823686 -64.849248)
		(width 0.15494)
		(layer "In5.Cu")
		(net "SSD13_PWR_EN_R")
	)
	(segment
		(start 401.103846 -63.569088)
		(end 401.103846 -58.500518)
		(width 0.15494)
		(layer "In5.Cu")
		(net "SSD13_PWR_EN_R")
	)
	(segment
		(start 373.72925 -108.258102)
		(end 376.032522 -105.95483)
		(width 0.15494)
		(layer "In5.Cu")
		(net "SSD13_PWR_EN_R")
	)
	(segment
		(start 373.72925 -110.01121)
		(end 373.72925 -108.258102)
		(width 0.15494)
		(layer "In5.Cu")
		(net "SSD13_PWR_EN_R")
	)
	(segment
		(start 384.399028 -92.134436)
		(end 384.399028 -69.136768)
		(width 0.15494)
		(layer "In5.Cu")
		(net "SSD13_PWR_EN_R")
	)
	(segment
		(start 396.05458 -65.848992)
		(end 397.054324 -64.849248)
		(width 0.15494)
		(layer "In5.Cu")
		(net "SSD13_PWR_EN_R")
	)
	(segment
		(start 401.103846 -58.500518)
		(end 400.675602 -58.072274)
		(width 0.15494)
		(layer "In5.Cu")
		(net "SSD13_PWR_EN_R")
	)
	(segment
		(start 376.032522 -105.95483)
		(end 376.032522 -100.500942)
		(width 0.15494)
		(layer "In5.Cu")
		(net "SSD13_PWR_EN_R")
	)
	(segment
		(start 400.675602 -58.072274)
		(end 400.167856 -58.58002)
		(width 0.15494)
		(layer "In5.Cu")
		(net "SSD13_PWR_EN_R")
	)
	(segment
		(start 349.3516 -121.691654)
		(end 349.3516 -110.538768)
		(width 0.15494)
		(layer "In9.Cu")
		(net "SSD13_PWR_EN_R")
	)
	(segment
		(start 338.6074 -203.6318)
		(end 339.070696 -203.168504)
		(width 0.15494)
		(layer "In9.Cu")
		(net "SSD13_PWR_EN_R")
	)
	(segment
		(start 346.66936 -186.349894)
		(end 346.66936 -140.095986)
		(width 0.15494)
		(layer "In9.Cu")
		(net "SSD13_PWR_EN_R")
	)
	(segment
		(start 347.6752 -139.090146)
		(end 347.6752 -123.368054)
		(width 0.15494)
		(layer "In9.Cu")
		(net "SSD13_PWR_EN_R")
	)
	(segment
		(start 338.311744 -203.6318)
		(end 338.6074 -203.6318)
		(width 0.15494)
		(layer "In9.Cu")
		(net "SSD13_PWR_EN_R")
	)
	(segment
		(start 341.3252 -190.9318)
		(end 342.087454 -190.9318)
		(width 0.15494)
		(layer "In9.Cu")
		(net "SSD13_PWR_EN_R")
	)
	(segment
		(start 338.074 -206.15148)
		(end 338.074 -203.869544)
		(width 0.15494)
		(layer "In9.Cu")
		(net "SSD13_PWR_EN_R")
	)
	(segment
		(start 346.66936 -140.095986)
		(end 347.6752 -139.090146)
		(width 0.15494)
		(layer "In9.Cu")
		(net "SSD13_PWR_EN_R")
	)
	(segment
		(start 339.070696 -199.803766)
		(end 340.2838 -198.590662)
		(width 0.15494)
		(layer "In9.Cu")
		(net "SSD13_PWR_EN_R")
	)
	(segment
		(start 340.2838 -198.590662)
		(end 340.2838 -192.8876)
		(width 0.15494)
		(layer "In9.Cu")
		(net "SSD13_PWR_EN_R")
	)
	(segment
		(start 347.6752 -123.368054)
		(end 349.3516 -121.691654)
		(width 0.15494)
		(layer "In9.Cu")
		(net "SSD13_PWR_EN_R")
	)
	(segment
		(start 342.087454 -190.9318)
		(end 346.66936 -186.349894)
		(width 0.15494)
		(layer "In9.Cu")
		(net "SSD13_PWR_EN_R")
	)
	(segment
		(start 338.074 -203.869544)
		(end 338.311744 -203.6318)
		(width 0.15494)
		(layer "In9.Cu")
		(net "SSD13_PWR_EN_R")
	)
	(segment
		(start 340.5632 -191.6938)
		(end 341.3252 -190.9318)
		(width 0.15494)
		(layer "In9.Cu")
		(net "SSD13_PWR_EN_R")
	)
	(segment
		(start 340.5632 -192.6082)
		(end 340.5632 -191.6938)
		(width 0.15494)
		(layer "In9.Cu")
		(net "SSD13_PWR_EN_R")
	)
	(segment
		(start 339.070696 -203.168504)
		(end 339.070696 -199.803766)
		(width 0.15494)
		(layer "In9.Cu")
		(net "SSD13_PWR_EN_R")
	)
	(segment
		(start 340.2838 -192.8876)
		(end 340.5632 -192.6082)
		(width 0.15494)
		(layer "In9.Cu")
		(net "SSD13_PWR_EN_R")
	)
	(segment
		(start 373.72925 -110.01121)
		(end 373.19204 -109.474)
		(width 0.15494)
		(layer "In13.Cu")
		(net "SSD13_PWR_EN_R")
	)
	(segment
		(start 371.119146 -109.474)
		(end 370.763546 -109.8296)
		(width 0.15494)
		(layer "In13.Cu")
		(net "SSD13_PWR_EN_R")
	)
	(segment
		(start 360.806746 -111.1504)
		(end 349.963232 -111.1504)
		(width 0.15494)
		(layer "In13.Cu")
		(net "SSD13_PWR_EN_R")
	)
	(segment
		(start 373.19204 -109.474)
		(end 371.119146 -109.474)
		(width 0.15494)
		(layer "In13.Cu")
		(net "SSD13_PWR_EN_R")
	)
	(segment
		(start 362.127546 -109.8296)
		(end 360.806746 -111.1504)
		(width 0.15494)
		(layer "In13.Cu")
		(net "SSD13_PWR_EN_R")
	)
	(segment
		(start 349.963232 -111.1504)
		(end 349.3516 -110.538768)
		(width 0.15494)
		(layer "In13.Cu")
		(net "SSD13_PWR_EN_R")
	)
	(segment
		(start 370.763546 -109.8296)
		(end 362.127546 -109.8296)
		(width 0.15494)
		(layer "In13.Cu")
		(net "SSD13_PWR_EN_R")
	)
	(segment
		(start 322.188078 -224.659698)
		(end 323.517768 -224.659698)
		(width 0.13208)
		(layer "F.Cu")
		(net "LED_POSTCODE_R_1")
	)
	(segment
		(start 320.829432 -224.659698)
		(end 322.188078 -224.659698)
		(width 0.13208)
		(layer "F.Cu")
		(net "LED_POSTCODE_R_1")
	)
	(via
		(at 322.188078 -224.659698)
		(size 0.762)
		(drill 0.381)
		(layers "F.Cu" "B.Cu")
		(net "LED_POSTCODE_R_1")
	)
	(segment
		(start 235.467652 -219.904056)
		(end 236.2962 -220.732604)
		(width 0.13208)
		(layer "F.Cu")
		(net "SSD12_PWRDIS_BIC")
	)
	(segment
		(start 236.2962 -223.246696)
		(end 236.635036 -223.585532)
		(width 0.13208)
		(layer "F.Cu")
		(net "SSD12_PWRDIS_BIC")
	)
	(segment
		(start 236.2962 -220.732604)
		(end 236.2962 -223.246696)
		(width 0.13208)
		(layer "F.Cu")
		(net "SSD12_PWRDIS_BIC")
	)
	(segment
		(start 239.632236 -224.319084)
		(end 238.584486 -223.271334)
		(width 0.13208)
		(layer "F.Cu")
		(net "SSD12_PWRDIS_BIC")
	)
	(segment
		(start 236.635036 -223.585532)
		(end 238.270288 -223.585532)
		(width 0.13208)
		(layer "F.Cu")
		(net "SSD12_PWRDIS_BIC")
	)
	(segment
		(start 239.900206 -224.319084)
		(end 239.632236 -224.319084)
		(width 0.13208)
		(layer "F.Cu")
		(net "SSD12_PWRDIS_BIC")
	)
	(segment
		(start 238.270288 -223.585532)
		(end 238.584486 -223.271334)
		(width 0.13208)
		(layer "F.Cu")
		(net "SSD12_PWRDIS_BIC")
	)
	(via
		(at 238.584486 -223.271334)
		(size 0.762)
		(drill 0.381)
		(layers "F.Cu" "B.Cu")
		(net "SSD12_PWRDIS_BIC")
	)
	(segment
		(start 342.019382 -146.50212)
		(end 343.149936 -146.50212)
		(width 0.13208)
		(layer "F.Cu")
		(net "RST_PEX_SSD14_PERST_N")
	)
	(segment
		(start 340.298786 -146.24304)
		(end 340.557866 -146.50212)
		(width 0.13208)
		(layer "F.Cu")
		(net "RST_PEX_SSD14_PERST_N")
	)
	(segment
		(start 338.79409 -146.24304)
		(end 340.298786 -146.24304)
		(width 0.13208)
		(layer "F.Cu")
		(net "RST_PEX_SSD14_PERST_N")
	)
	(segment
		(start 340.557866 -146.50212)
		(end 342.019382 -146.50212)
		(width 0.13208)
		(layer "F.Cu")
		(net "RST_PEX_SSD14_PERST_N")
	)
	(segment
		(start 338.47405 -145.923)
		(end 338.79409 -146.24304)
		(width 0.13208)
		(layer "F.Cu")
		(net "RST_PEX_SSD14_PERST_N")
	)
	(via
		(at 342.019382 -146.50212)
		(size 0.508)
		(drill 0.254)
		(layers "F.Cu" "B.Cu")
		(net "RST_PEX_SSD14_PERST_N")
	)
	(segment
		(start 284.575504 -57.841134)
		(end 284.066996 -57.332626)
		(width 0.13208)
		(layer "F.Cu")
		(net "SSD9_PWR_EN_R")
	)
	(segment
		(start 284.066996 -56.354218)
		(end 284.067758 -56.353456)
		(width 0.13208)
		(layer "F.Cu")
		(net "SSD9_PWR_EN_R")
	)
	(segment
		(start 284.066996 -57.332626)
		(end 284.066996 -56.354218)
		(width 0.13208)
		(layer "F.Cu")
		(net "SSD9_PWR_EN_R")
	)
	(segment
		(start 278.714454 -65.92189)
		(end 278.714454 -65.100962)
		(width 0.13208)
		(layer "F.Cu")
		(net "SSD9_PWR_EN_R")
	)
	(segment
		(start 282.858464 -55.144162)
		(end 284.067758 -56.353456)
		(width 0.13208)
		(layer "F.Cu")
		(net "SSD9_PWR_EN_R")
	)
	(segment
		(start 284.575504 -58.072274)
		(end 284.575504 -57.841134)
		(width 0.13208)
		(layer "F.Cu")
		(net "SSD9_PWR_EN_R")
	)
	(segment
		(start 282.347162 -55.144162)
		(end 282.858464 -55.144162)
		(width 0.13208)
		(layer "F.Cu")
		(net "SSD9_PWR_EN_R")
	)
	(segment
		(start 334.518 -200.76795)
		(end 334.518 -200.152)
		(width 0.13208)
		(layer "F.Cu")
		(net "SSD9_PWR_EN_R")
	)
	(via
		(at 312.400188 -82.4357)
		(size 0.508)
		(drill 0.254)
		(layers "F.Cu" "B.Cu")
		(net "SSD9_PWR_EN_R")
	)
	(via
		(at 284.575504 -58.072274)
		(size 0.508)
		(drill 0.254)
		(layers "F.Cu" "B.Cu")
		(net "SSD9_PWR_EN_R")
	)
	(via
		(at 334.518 -200.152)
		(size 0.508)
		(drill 0.254)
		(layers "F.Cu" "B.Cu")
		(net "SSD9_PWR_EN_R")
	)
	(via
		(at 298.431966 -81.068418)
		(size 0.508)
		(drill 0.254)
		(layers "F.Cu" "B.Cu")
		(net "SSD9_PWR_EN_R")
	)
	(via
		(at 278.714454 -65.100962)
		(size 0.508)
		(drill 0.254)
		(layers "F.Cu" "B.Cu")
		(net "SSD9_PWR_EN_R")
	)
	(segment
		(start 286.170878 -65.430908)
		(end 291.463984 -65.430908)
		(width 0.15494)
		(layer "In5.Cu")
		(net "SSD9_PWR_EN_R")
	)
	(segment
		(start 335.622138 -141.26464)
		(end 334.609186 -140.251688)
		(width 0.15494)
		(layer "In5.Cu")
		(net "SSD9_PWR_EN_R")
	)
	(segment
		(start 284.383226 -63.922402)
		(end 283.767784 -64.537844)
		(width 0.15494)
		(layer "In5.Cu")
		(net "SSD9_PWR_EN_R")
	)
	(segment
		(start 293.023544 -66.990468)
		(end 293.023544 -76.52893)
		(width 0.15494)
		(layer "In5.Cu")
		(net "SSD9_PWR_EN_R")
	)
	(segment
		(start 285.24962 -64.50965)
		(end 286.170878 -65.430908)
		(width 0.15494)
		(layer "In5.Cu")
		(net "SSD9_PWR_EN_R")
	)
	(segment
		(start 334.609186 -140.251688)
		(end 329.305158 -140.251688)
		(width 0.15494)
		(layer "In5.Cu")
		(net "SSD9_PWR_EN_R")
	)
	(segment
		(start 279.277572 -64.537844)
		(end 278.714454 -65.100962)
		(width 0.15494)
		(layer "In5.Cu")
		(net "SSD9_PWR_EN_R")
	)
	(segment
		(start 334.073754 -199.247506)
		(end 334.073754 -175.912018)
		(width 0.15494)
		(layer "In5.Cu")
		(net "SSD9_PWR_EN_R")
	)
	(segment
		(start 334.518 -199.691752)
		(end 334.073754 -199.247506)
		(width 0.15494)
		(layer "In5.Cu")
		(net "SSD9_PWR_EN_R")
	)
	(segment
		(start 318.934846 -119.66067)
		(end 314.718192 -115.444016)
		(width 0.15494)
		(layer "In5.Cu")
		(net "SSD9_PWR_EN_R")
	)
	(segment
		(start 284.575504 -58.072274)
		(end 285.24962 -58.74639)
		(width 0.15494)
		(layer "In5.Cu")
		(net "SSD9_PWR_EN_R")
	)
	(segment
		(start 293.023544 -76.52893)
		(end 297.563032 -81.068418)
		(width 0.15494)
		(layer "In5.Cu")
		(net "SSD9_PWR_EN_R")
	)
	(segment
		(start 329.305158 -140.251688)
		(end 322.401438 -133.347968)
		(width 0.15494)
		(layer "In5.Cu")
		(net "SSD9_PWR_EN_R")
	)
	(segment
		(start 285.24962 -58.74639)
		(end 285.24962 -64.50965)
		(width 0.15494)
		(layer "In5.Cu")
		(net "SSD9_PWR_EN_R")
	)
	(segment
		(start 322.401438 -133.347968)
		(end 322.401438 -129.520442)
		(width 0.15494)
		(layer "In5.Cu")
		(net "SSD9_PWR_EN_R")
	)
	(segment
		(start 284.575504 -58.072274)
		(end 284.383226 -58.264552)
		(width 0.15494)
		(layer "In5.Cu")
		(net "SSD9_PWR_EN_R")
	)
	(segment
		(start 318.934846 -126.05385)
		(end 318.934846 -119.66067)
		(width 0.15494)
		(layer "In5.Cu")
		(net "SSD9_PWR_EN_R")
	)
	(segment
		(start 335.622138 -174.363634)
		(end 335.622138 -141.26464)
		(width 0.15494)
		(layer "In5.Cu")
		(net "SSD9_PWR_EN_R")
	)
	(segment
		(start 284.383226 -58.264552)
		(end 284.383226 -63.922402)
		(width 0.15494)
		(layer "In5.Cu")
		(net "SSD9_PWR_EN_R")
	)
	(segment
		(start 314.718192 -115.444016)
		(end 314.718192 -84.753704)
		(width 0.15494)
		(layer "In5.Cu")
		(net "SSD9_PWR_EN_R")
	)
	(segment
		(start 314.718192 -84.753704)
		(end 312.400188 -82.4357)
		(width 0.15494)
		(layer "In5.Cu")
		(net "SSD9_PWR_EN_R")
	)
	(segment
		(start 334.073754 -175.912018)
		(end 335.622138 -174.363634)
		(width 0.15494)
		(layer "In5.Cu")
		(net "SSD9_PWR_EN_R")
	)
	(segment
		(start 291.463984 -65.430908)
		(end 293.023544 -66.990468)
		(width 0.15494)
		(layer "In5.Cu")
		(net "SSD9_PWR_EN_R")
	)
	(segment
		(start 334.518 -200.152)
		(end 334.518 -199.691752)
		(width 0.15494)
		(layer "In5.Cu")
		(net "SSD9_PWR_EN_R")
	)
	(segment
		(start 322.401438 -129.520442)
		(end 318.934846 -126.05385)
		(width 0.15494)
		(layer "In5.Cu")
		(net "SSD9_PWR_EN_R")
	)
	(segment
		(start 297.563032 -81.068418)
		(end 298.431966 -81.068418)
		(width 0.15494)
		(layer "In5.Cu")
		(net "SSD9_PWR_EN_R")
	)
	(segment
		(start 283.767784 -64.537844)
		(end 279.277572 -64.537844)
		(width 0.15494)
		(layer "In5.Cu")
		(net "SSD9_PWR_EN_R")
	)
	(segment
		(start 304.3428 -79.756)
		(end 304.5968 -79.502)
		(width 0.15494)
		(layer "In9.Cu")
		(net "SSD9_PWR_EN_R")
	)
	(segment
		(start 308.549548 -79.502)
		(end 310.727852 -81.680304)
		(width 0.15494)
		(layer "In9.Cu")
		(net "SSD9_PWR_EN_R")
	)
	(segment
		(start 299.744384 -79.756)
		(end 304.3428 -79.756)
		(width 0.15494)
		(layer "In9.Cu")
		(net "SSD9_PWR_EN_R")
	)
	(segment
		(start 311.644792 -81.680304)
		(end 312.400188 -82.4357)
		(width 0.15494)
		(layer "In9.Cu")
		(net "SSD9_PWR_EN_R")
	)
	(segment
		(start 304.5968 -79.502)
		(end 308.549548 -79.502)
		(width 0.15494)
		(layer "In9.Cu")
		(net "SSD9_PWR_EN_R")
	)
	(segment
		(start 298.431966 -81.068418)
		(end 299.744384 -79.756)
		(width 0.15494)
		(layer "In9.Cu")
		(net "SSD9_PWR_EN_R")
	)
	(segment
		(start 310.727852 -81.680304)
		(end 311.644792 -81.680304)
		(width 0.15494)
		(layer "In9.Cu")
		(net "SSD9_PWR_EN_R")
	)
	(segment
		(start 179.692046 -167.0558)
		(end 180.677312 -166.070534)
		(width 0.13208)
		(layer "F.Cu")
		(net "FM_SYS_THROTTLE_R")
	)
	(segment
		(start 295.72585 -166.070534)
		(end 295.72585 -166.705534)
		(width 0.13208)
		(layer "F.Cu")
		(net "FM_SYS_THROTTLE_R")
	)
	(segment
		(start 61.792612 -157.680152)
		(end 61.792612 -157.045152)
		(width 0.13208)
		(layer "F.Cu")
		(net "FM_SYS_THROTTLE_R")
	)
	(segment
		(start 295.91 -218.948)
		(end 302.26 -218.948)
		(width 0.13208)
		(layer "F.Cu")
		(net "FM_SYS_THROTTLE_R")
	)
	(segment
		(start 302.26 -218.948)
		(end 303.403 -217.805)
		(width 0.13208)
		(layer "F.Cu")
		(net "FM_SYS_THROTTLE_R")
	)
	(segment
		(start 178.035204 -167.0558)
		(end 179.692046 -167.0558)
		(width 0.13208)
		(layer "F.Cu")
		(net "FM_SYS_THROTTLE_R")
	)
	(segment
		(start 303.403 -204.147166)
		(end 300.863 -198.014844)
		(width 0.13208)
		(layer "F.Cu")
		(net "FM_SYS_THROTTLE_R")
	)
	(segment
		(start 294.611298 -220.752924)
		(end 294.611298 -220.246702)
		(width 0.13208)
		(layer "F.Cu")
		(net "FM_SYS_THROTTLE_R")
	)
	(segment
		(start 303.403 -217.805)
		(end 303.403 -204.147166)
		(width 0.13208)
		(layer "F.Cu")
		(net "FM_SYS_THROTTLE_R")
	)
	(segment
		(start 177.046636 -157.680152)
		(end 176.478692 -158.248096)
		(width 0.13208)
		(layer "F.Cu")
		(net "FM_SYS_THROTTLE_R")
	)
	(segment
		(start 300.863 -171.842684)
		(end 295.72585 -166.705534)
		(width 0.13208)
		(layer "F.Cu")
		(net "FM_SYS_THROTTLE_R")
	)
	(segment
		(start 177.897282 -167.193722)
		(end 178.035204 -167.0558)
		(width 0.13208)
		(layer "F.Cu")
		(net "FM_SYS_THROTTLE_R")
	)
	(segment
		(start 176.478692 -158.248096)
		(end 176.478692 -166.369492)
		(width 0.13208)
		(layer "F.Cu")
		(net "FM_SYS_THROTTLE_R")
	)
	(segment
		(start 300.863 -198.014844)
		(end 300.863 -171.842684)
		(width 0.13208)
		(layer "F.Cu")
		(net "FM_SYS_THROTTLE_R")
	)
	(segment
		(start 176.478692 -166.369492)
		(end 177.302922 -167.193722)
		(width 0.13208)
		(layer "F.Cu")
		(net "FM_SYS_THROTTLE_R")
	)
	(segment
		(start 411.825948 -166.070534)
		(end 411.825948 -166.705534)
		(width 0.13208)
		(layer "F.Cu")
		(net "FM_SYS_THROTTLE_R")
	)
	(segment
		(start 410.092652 -157.680152)
		(end 410.092652 -157.045152)
		(width 0.13208)
		(layer "F.Cu")
		(net "FM_SYS_THROTTLE_R")
	)
	(segment
		(start 177.302922 -167.193722)
		(end 177.897282 -167.193722)
		(width 0.13208)
		(layer "F.Cu")
		(net "FM_SYS_THROTTLE_R")
	)
	(segment
		(start 177.892456 -157.680152)
		(end 177.046636 -157.680152)
		(width 0.13208)
		(layer "F.Cu")
		(net "FM_SYS_THROTTLE_R")
	)
	(segment
		(start 294.611298 -220.246702)
		(end 295.91 -218.948)
		(width 0.13208)
		(layer "F.Cu")
		(net "FM_SYS_THROTTLE_R")
	)
	(segment
		(start 180.677312 -166.070534)
		(end 179.625752 -166.070534)
		(width 0.13208)
		(layer "F.Cu")
		(net "FM_SYS_THROTTLE_R")
	)
	(segment
		(start 293.992554 -157.680152)
		(end 293.992554 -157.045152)
		(width 0.13208)
		(layer "F.Cu")
		(net "FM_SYS_THROTTLE_R")
	)
	(segment
		(start 63.525908 -166.070534)
		(end 63.525908 -166.705534)
		(width 0.13208)
		(layer "F.Cu")
		(net "FM_SYS_THROTTLE_R")
	)
	(via
		(at 295.72585 -166.705534)
		(size 0.508)
		(drill 0.254)
		(layers "F.Cu" "B.Cu")
		(net "FM_SYS_THROTTLE_R")
	)
	(via
		(at 293.992554 -157.045152)
		(size 0.508)
		(drill 0.254)
		(layers "F.Cu" "B.Cu")
		(net "FM_SYS_THROTTLE_R")
	)
	(via
		(at 210.691984 -171.905422)
		(size 0.508)
		(drill 0.254)
		(layers "F.Cu" "B.Cu")
		(net "FM_SYS_THROTTLE_R")
	)
	(via
		(at 180.677312 -166.070534)
		(size 0.508)
		(drill 0.254)
		(layers "F.Cu" "B.Cu")
		(net "FM_SYS_THROTTLE_R")
	)
	(via
		(at 61.792612 -157.045152)
		(size 0.508)
		(drill 0.254)
		(layers "F.Cu" "B.Cu")
		(net "FM_SYS_THROTTLE_R")
	)
	(via
		(at 294.611298 -220.752924)
		(size 0.508)
		(drill 0.254)
		(layers "F.Cu" "B.Cu")
		(net "FM_SYS_THROTTLE_R")
	)
	(via
		(at 411.825948 -166.705534)
		(size 0.508)
		(drill 0.254)
		(layers "F.Cu" "B.Cu")
		(net "FM_SYS_THROTTLE_R")
	)
	(via
		(at 409.274264 -174.1932)
		(size 0.508)
		(drill 0.254)
		(layers "F.Cu" "B.Cu")
		(net "FM_SYS_THROTTLE_R")
	)
	(via
		(at 212.571076 -209.397854)
		(size 0.508)
		(drill 0.254)
		(layers "F.Cu" "B.Cu")
		(net "FM_SYS_THROTTLE_R")
	)
	(via
		(at 328.549 -223.4692)
		(size 0.508)
		(drill 0.254)
		(layers "F.Cu" "B.Cu")
		(net "FM_SYS_THROTTLE_R")
	)
	(via
		(at 63.525908 -166.705534)
		(size 0.508)
		(drill 0.254)
		(layers "F.Cu" "B.Cu")
		(net "FM_SYS_THROTTLE_R")
	)
	(via
		(at 140.07465 -168.022016)
		(size 0.508)
		(drill 0.254)
		(layers "F.Cu" "B.Cu")
		(net "FM_SYS_THROTTLE_R")
	)
	(via
		(at 410.092652 -157.045152)
		(size 0.508)
		(drill 0.254)
		(layers "F.Cu" "B.Cu")
		(net "FM_SYS_THROTTLE_R")
	)
	(via
		(at 255.4732 -161.9504)
		(size 0.508)
		(drill 0.254)
		(layers "F.Cu" "B.Cu")
		(net "FM_SYS_THROTTLE_R")
	)
	(segment
		(start 213.337648 -210.164426)
		(end 212.571076 -209.397854)
		(width 0.13208)
		(layer "B.Cu")
		(net "FM_SYS_THROTTLE_R")
	)
	(segment
		(start 215.080342 -210.164426)
		(end 213.337648 -210.164426)
		(width 0.13208)
		(layer "B.Cu")
		(net "FM_SYS_THROTTLE_R")
	)
	(segment
		(start 329.29195 -223.4692)
		(end 328.549 -223.4692)
		(width 0.13208)
		(layer "B.Cu")
		(net "FM_SYS_THROTTLE_R")
	)
	(segment
		(start 209.17154 -200.76414)
		(end 207.29448 -198.88708)
		(width 0.15494)
		(layer "In7.Cu")
		(net "FM_SYS_THROTTLE_R")
	)
	(segment
		(start 209.64779 -200.84161)
		(end 209.57032 -200.76414)
		(width 0.15494)
		(layer "In7.Cu")
		(net "FM_SYS_THROTTLE_R")
	)
	(segment
		(start 209.57032 -200.76414)
		(end 209.17154 -200.76414)
		(width 0.15494)
		(layer "In7.Cu")
		(net "FM_SYS_THROTTLE_R")
	)
	(segment
		(start 212.31352 -207.111346)
		(end 212.31352 -203.08316)
		(width 0.15494)
		(layer "In7.Cu")
		(net "FM_SYS_THROTTLE_R")
	)
	(segment
		(start 210.07197 -200.84161)
		(end 209.64779 -200.84161)
		(width 0.15494)
		(layer "In7.Cu")
		(net "FM_SYS_THROTTLE_R")
	)
	(segment
		(start 210.293712 -192.96634)
		(end 211.50326 -191.756792)
		(width 0.15494)
		(layer "In7.Cu")
		(net "FM_SYS_THROTTLE_R")
	)
	(segment
		(start 207.29448 -195.965572)
		(end 209.22234 -194.037712)
		(width 0.15494)
		(layer "In7.Cu")
		(net "FM_SYS_THROTTLE_R")
	)
	(segment
		(start 211.89696 -186.145932)
		(end 211.89696 -184.333642)
		(width 0.15494)
		(layer "In7.Cu")
		(net "FM_SYS_THROTTLE_R")
	)
	(segment
		(start 209.9564 -182.393082)
		(end 209.9564 -172.641006)
		(width 0.15494)
		(layer "In7.Cu")
		(net "FM_SYS_THROTTLE_R")
	)
	(segment
		(start 209.22234 -192.68313)
		(end 209.62366 -192.68313)
		(width 0.15494)
		(layer "In7.Cu")
		(net "FM_SYS_THROTTLE_R")
	)
	(segment
		(start 211.50326 -186.539632)
		(end 211.89696 -186.145932)
		(width 0.15494)
		(layer "In7.Cu")
		(net "FM_SYS_THROTTLE_R")
	)
	(segment
		(start 209.22234 -193.65087)
		(end 208.93913 -193.36766)
		(width 0.15494)
		(layer "In7.Cu")
		(net "FM_SYS_THROTTLE_R")
	)
	(segment
		(start 208.93913 -192.96634)
		(end 209.22234 -192.68313)
		(width 0.15494)
		(layer "In7.Cu")
		(net "FM_SYS_THROTTLE_R")
	)
	(segment
		(start 212.571076 -209.397854)
		(end 212.571076 -207.368902)
		(width 0.15494)
		(layer "In7.Cu")
		(net "FM_SYS_THROTTLE_R")
	)
	(segment
		(start 209.9564 -172.641006)
		(end 210.691984 -171.905422)
		(width 0.15494)
		(layer "In7.Cu")
		(net "FM_SYS_THROTTLE_R")
	)
	(segment
		(start 207.29448 -198.88708)
		(end 207.29448 -195.965572)
		(width 0.15494)
		(layer "In7.Cu")
		(net "FM_SYS_THROTTLE_R")
	)
	(segment
		(start 211.89696 -184.333642)
		(end 209.9564 -182.393082)
		(width 0.15494)
		(layer "In7.Cu")
		(net "FM_SYS_THROTTLE_R")
	)
	(segment
		(start 209.90687 -192.96634)
		(end 210.293712 -192.96634)
		(width 0.15494)
		(layer "In7.Cu")
		(net "FM_SYS_THROTTLE_R")
	)
	(segment
		(start 212.571076 -207.368902)
		(end 212.31352 -207.111346)
		(width 0.15494)
		(layer "In7.Cu")
		(net "FM_SYS_THROTTLE_R")
	)
	(segment
		(start 212.31352 -203.08316)
		(end 210.07197 -200.84161)
		(width 0.15494)
		(layer "In7.Cu")
		(net "FM_SYS_THROTTLE_R")
	)
	(segment
		(start 209.22234 -194.037712)
		(end 209.22234 -193.65087)
		(width 0.15494)
		(layer "In7.Cu")
		(net "FM_SYS_THROTTLE_R")
	)
	(segment
		(start 209.62366 -192.68313)
		(end 209.90687 -192.96634)
		(width 0.15494)
		(layer "In7.Cu")
		(net "FM_SYS_THROTTLE_R")
	)
	(segment
		(start 208.93913 -193.36766)
		(end 208.93913 -192.96634)
		(width 0.15494)
		(layer "In7.Cu")
		(net "FM_SYS_THROTTLE_R")
	)
	(segment
		(start 211.50326 -191.756792)
		(end 211.50326 -186.539632)
		(width 0.15494)
		(layer "In7.Cu")
		(net "FM_SYS_THROTTLE_R")
	)
	(segment
		(start 409.1686 -174.087536)
		(end 409.1686 -169.362882)
		(width 0.15494)
		(layer "In9.Cu")
		(net "FM_SYS_THROTTLE_R")
	)
	(segment
		(start 294.46601 -163.270184)
		(end 295.72585 -164.530024)
		(width 0.15494)
		(layer "In9.Cu")
		(net "FM_SYS_THROTTLE_R")
	)
	(segment
		(start 62.266068 -163.270184)
		(end 63.525908 -164.530024)
		(width 0.15494)
		(layer "In9.Cu")
		(net "FM_SYS_THROTTLE_R")
	)
	(segment
		(start 410.566108 -160.970722)
		(end 410.092652 -160.497266)
		(width 0.15494)
		(layer "In9.Cu")
		(net "FM_SYS_THROTTLE_R")
	)
	(segment
		(start 61.792612 -160.497266)
		(end 62.266068 -160.970722)
		(width 0.15494)
		(layer "In9.Cu")
		(net "FM_SYS_THROTTLE_R")
	)
	(segment
		(start 411.825948 -166.705534)
		(end 411.825948 -164.530024)
		(width 0.15494)
		(layer "In9.Cu")
		(net "FM_SYS_THROTTLE_R")
	)
	(segment
		(start 409.274264 -174.1932)
		(end 409.1686 -174.087536)
		(width 0.15494)
		(layer "In9.Cu")
		(net "FM_SYS_THROTTLE_R")
	)
	(segment
		(start 62.266068 -160.970722)
		(end 62.266068 -163.270184)
		(width 0.15494)
		(layer "In9.Cu")
		(net "FM_SYS_THROTTLE_R")
	)
	(segment
		(start 293.992554 -157.045152)
		(end 293.992554 -160.497266)
		(width 0.15494)
		(layer "In9.Cu")
		(net "FM_SYS_THROTTLE_R")
	)
	(segment
		(start 295.72585 -164.530024)
		(end 295.72585 -166.705534)
		(width 0.15494)
		(layer "In9.Cu")
		(net "FM_SYS_THROTTLE_R")
	)
	(segment
		(start 293.992554 -160.497266)
		(end 294.46601 -160.970722)
		(width 0.15494)
		(layer "In9.Cu")
		(net "FM_SYS_THROTTLE_R")
	)
	(segment
		(start 410.092652 -160.497266)
		(end 410.092652 -157.045152)
		(width 0.15494)
		(layer "In9.Cu")
		(net "FM_SYS_THROTTLE_R")
	)
	(segment
		(start 409.1686 -169.362882)
		(end 411.825948 -166.705534)
		(width 0.15494)
		(layer "In9.Cu")
		(net "FM_SYS_THROTTLE_R")
	)
	(segment
		(start 294.46601 -160.970722)
		(end 294.46601 -163.270184)
		(width 0.15494)
		(layer "In9.Cu")
		(net "FM_SYS_THROTTLE_R")
	)
	(segment
		(start 61.792612 -157.045152)
		(end 61.792612 -160.497266)
		(width 0.15494)
		(layer "In9.Cu")
		(net "FM_SYS_THROTTLE_R")
	)
	(segment
		(start 63.525908 -164.530024)
		(end 63.525908 -166.705534)
		(width 0.15494)
		(layer "In9.Cu")
		(net "FM_SYS_THROTTLE_R")
	)
	(segment
		(start 410.566108 -163.270184)
		(end 410.566108 -160.970722)
		(width 0.15494)
		(layer "In9.Cu")
		(net "FM_SYS_THROTTLE_R")
	)
	(segment
		(start 411.825948 -164.530024)
		(end 410.566108 -163.270184)
		(width 0.15494)
		(layer "In9.Cu")
		(net "FM_SYS_THROTTLE_R")
	)
	(segment
		(start 212.6361 -170.217846)
		(end 215.7603 -170.217846)
		(width 0.15494)
		(layer "In13.Cu")
		(net "FM_SYS_THROTTLE_R")
	)
	(segment
		(start 255.4732 -163.9062)
		(end 255.4732 -161.9504)
		(width 0.15494)
		(layer "In13.Cu")
		(net "FM_SYS_THROTTLE_R")
	)
	(segment
		(start 323.004434 -222.674688)
		(end 321.975734 -221.645988)
		(width 0.15494)
		(layer "In13.Cu")
		(net "FM_SYS_THROTTLE_R")
	)
	(segment
		(start 171.061888 -173.615096)
		(end 180.030628 -173.615096)
		(width 0.15494)
		(layer "In13.Cu")
		(net "FM_SYS_THROTTLE_R")
	)
	(segment
		(start 328.549 -223.4692)
		(end 326.398382 -223.4692)
		(width 0.15494)
		(layer "In13.Cu")
		(net "FM_SYS_THROTTLE_R")
	)
	(segment
		(start 295.504362 -221.645988)
		(end 294.611298 -220.752924)
		(width 0.15494)
		(layer "In13.Cu")
		(net "FM_SYS_THROTTLE_R")
	)
	(segment
		(start 210.691984 -171.905422)
		(end 210.948524 -171.905422)
		(width 0.15494)
		(layer "In13.Cu")
		(net "FM_SYS_THROTTLE_R")
	)
	(segment
		(start 321.975734 -221.645988)
		(end 295.504362 -221.645988)
		(width 0.15494)
		(layer "In13.Cu")
		(net "FM_SYS_THROTTLE_R")
	)
	(segment
		(start 180.677312 -172.968412)
		(end 180.677312 -166.070534)
		(width 0.15494)
		(layer "In13.Cu")
		(net "FM_SYS_THROTTLE_R")
	)
	(segment
		(start 140.998702 -168.946068)
		(end 166.39286 -168.946068)
		(width 0.15494)
		(layer "In13.Cu")
		(net "FM_SYS_THROTTLE_R")
	)
	(segment
		(start 253.606808 -165.772592)
		(end 255.4732 -163.9062)
		(width 0.15494)
		(layer "In13.Cu")
		(net "FM_SYS_THROTTLE_R")
	)
	(segment
		(start 210.948524 -171.905422)
		(end 212.6361 -170.217846)
		(width 0.15494)
		(layer "In13.Cu")
		(net "FM_SYS_THROTTLE_R")
	)
	(segment
		(start 166.39286 -168.946068)
		(end 171.061888 -173.615096)
		(width 0.15494)
		(layer "In13.Cu")
		(net "FM_SYS_THROTTLE_R")
	)
	(segment
		(start 325.60387 -222.674688)
		(end 323.004434 -222.674688)
		(width 0.15494)
		(layer "In13.Cu")
		(net "FM_SYS_THROTTLE_R")
	)
	(segment
		(start 220.205554 -165.772592)
		(end 253.606808 -165.772592)
		(width 0.15494)
		(layer "In13.Cu")
		(net "FM_SYS_THROTTLE_R")
	)
	(segment
		(start 140.07465 -168.022016)
		(end 140.998702 -168.946068)
		(width 0.15494)
		(layer "In13.Cu")
		(net "FM_SYS_THROTTLE_R")
	)
	(segment
		(start 195.687696 -171.905422)
		(end 210.691984 -171.905422)
		(width 0.15494)
		(layer "In13.Cu")
		(net "FM_SYS_THROTTLE_R")
	)
	(segment
		(start 215.7603 -170.217846)
		(end 220.205554 -165.772592)
		(width 0.15494)
		(layer "In13.Cu")
		(net "FM_SYS_THROTTLE_R")
	)
	(segment
		(start 180.677312 -166.070534)
		(end 189.852808 -166.070534)
		(width 0.15494)
		(layer "In13.Cu")
		(net "FM_SYS_THROTTLE_R")
	)
	(segment
		(start 326.398382 -223.4692)
		(end 325.60387 -222.674688)
		(width 0.15494)
		(layer "In13.Cu")
		(net "FM_SYS_THROTTLE_R")
	)
	(segment
		(start 180.030628 -173.615096)
		(end 180.677312 -172.968412)
		(width 0.15494)
		(layer "In13.Cu")
		(net "FM_SYS_THROTTLE_R")
	)
	(segment
		(start 189.852808 -166.070534)
		(end 195.687696 -171.905422)
		(width 0.15494)
		(layer "In13.Cu")
		(net "FM_SYS_THROTTLE_R")
	)
	(segment
		(start 399.911316 -173.48581)
		(end 400.618706 -174.1932)
		(width 0.15494)
		(layer "In15.Cu")
		(net "FM_SYS_THROTTLE_R")
	)
	(segment
		(start 368.09299 -172.457364)
		(end 375.2215 -172.457364)
		(width 0.15494)
		(layer "In15.Cu")
		(net "FM_SYS_THROTTLE_R")
	)
	(segment
		(start 126.177294 -171.502832)
		(end 136.593834 -171.502832)
		(width 0.15494)
		(layer "In15.Cu")
		(net "FM_SYS_THROTTLE_R")
	)
	(segment
		(start 264.672572 -161.539174)
		(end 268.325346 -157.8864)
		(width 0.15494)
		(layer "In15.Cu")
		(net "FM_SYS_THROTTLE_R")
	)
	(segment
		(start 295.910254 -166.52113)
		(end 340.88197 -166.52113)
		(width 0.15494)
		(layer "In15.Cu")
		(net "FM_SYS_THROTTLE_R")
	)
	(segment
		(start 63.525908 -166.705534)
		(end 83.998308 -166.705534)
		(width 0.15494)
		(layer "In15.Cu")
		(net "FM_SYS_THROTTLE_R")
	)
	(segment
		(start 283.19349 -156.83611)
		(end 283.6291 -156.4005)
		(width 0.15494)
		(layer "In15.Cu")
		(net "FM_SYS_THROTTLE_R")
	)
	(segment
		(start 106.303318 -186.817)
		(end 111.785654 -186.817)
		(width 0.15494)
		(layer "In15.Cu")
		(net "FM_SYS_THROTTLE_R")
	)
	(segment
		(start 285.190438 -156.0322)
		(end 292.979602 -156.0322)
		(width 0.15494)
		(layer "In15.Cu")
		(net "FM_SYS_THROTTLE_R")
	)
	(segment
		(start 124.711206 -181.65826)
		(end 124.711206 -172.96892)
		(width 0.15494)
		(layer "In15.Cu")
		(net "FM_SYS_THROTTLE_R")
	)
	(segment
		(start 268.325346 -157.8864)
		(end 270.002 -157.8864)
		(width 0.15494)
		(layer "In15.Cu")
		(net "FM_SYS_THROTTLE_R")
	)
	(segment
		(start 341.932768 -167.571928)
		(end 345.301062 -167.571928)
		(width 0.15494)
		(layer "In15.Cu")
		(net "FM_SYS_THROTTLE_R")
	)
	(segment
		(start 111.785654 -186.817)
		(end 112.877854 -185.7248)
		(width 0.15494)
		(layer "In15.Cu")
		(net "FM_SYS_THROTTLE_R")
	)
	(segment
		(start 375.2215 -172.457364)
		(end 376.249946 -173.48581)
		(width 0.15494)
		(layer "In15.Cu")
		(net "FM_SYS_THROTTLE_R")
	)
	(segment
		(start 283.6291 -156.4005)
		(end 284.124908 -156.4005)
		(width 0.15494)
		(layer "In15.Cu")
		(net "FM_SYS_THROTTLE_R")
	)
	(segment
		(start 120.644666 -185.7248)
		(end 124.711206 -181.65826)
		(width 0.15494)
		(layer "In15.Cu")
		(net "FM_SYS_THROTTLE_R")
	)
	(segment
		(start 255.884426 -161.539174)
		(end 264.672572 -161.539174)
		(width 0.15494)
		(layer "In15.Cu")
		(net "FM_SYS_THROTTLE_R")
	)
	(segment
		(start 102.558596 -185.265822)
		(end 106.303318 -186.817)
		(width 0.15494)
		(layer "In15.Cu")
		(net "FM_SYS_THROTTLE_R")
	)
	(segment
		(start 292.979602 -156.0322)
		(end 293.992554 -157.045152)
		(width 0.15494)
		(layer "In15.Cu")
		(net "FM_SYS_THROTTLE_R")
	)
	(segment
		(start 270.002 -157.8864)
		(end 271.05229 -156.83611)
		(width 0.15494)
		(layer "In15.Cu")
		(net "FM_SYS_THROTTLE_R")
	)
	(segment
		(start 112.877854 -185.7248)
		(end 120.644666 -185.7248)
		(width 0.15494)
		(layer "In15.Cu")
		(net "FM_SYS_THROTTLE_R")
	)
	(segment
		(start 255.4732 -161.9504)
		(end 255.884426 -161.539174)
		(width 0.15494)
		(layer "In15.Cu")
		(net "FM_SYS_THROTTLE_R")
	)
	(segment
		(start 284.714696 -156.229304)
		(end 285.190438 -156.0322)
		(width 0.15494)
		(layer "In15.Cu")
		(net "FM_SYS_THROTTLE_R")
	)
	(segment
		(start 365.605568 -169.969942)
		(end 368.09299 -172.457364)
		(width 0.15494)
		(layer "In15.Cu")
		(net "FM_SYS_THROTTLE_R")
	)
	(segment
		(start 340.88197 -166.52113)
		(end 341.932768 -167.571928)
		(width 0.15494)
		(layer "In15.Cu")
		(net "FM_SYS_THROTTLE_R")
	)
	(segment
		(start 295.72585 -166.705534)
		(end 295.910254 -166.52113)
		(width 0.15494)
		(layer "In15.Cu")
		(net "FM_SYS_THROTTLE_R")
	)
	(segment
		(start 347.699076 -169.969942)
		(end 365.605568 -169.969942)
		(width 0.15494)
		(layer "In15.Cu")
		(net "FM_SYS_THROTTLE_R")
	)
	(segment
		(start 400.618706 -174.1932)
		(end 409.274264 -174.1932)
		(width 0.15494)
		(layer "In15.Cu")
		(net "FM_SYS_THROTTLE_R")
	)
	(segment
		(start 284.124908 -156.4005)
		(end 284.296104 -156.229304)
		(width 0.15494)
		(layer "In15.Cu")
		(net "FM_SYS_THROTTLE_R")
	)
	(segment
		(start 83.998308 -166.705534)
		(end 102.558596 -185.265822)
		(width 0.15494)
		(layer "In15.Cu")
		(net "FM_SYS_THROTTLE_R")
	)
	(segment
		(start 136.593834 -171.502832)
		(end 140.07465 -168.022016)
		(width 0.15494)
		(layer "In15.Cu")
		(net "FM_SYS_THROTTLE_R")
	)
	(segment
		(start 271.05229 -156.83611)
		(end 283.19349 -156.83611)
		(width 0.15494)
		(layer "In15.Cu")
		(net "FM_SYS_THROTTLE_R")
	)
	(segment
		(start 284.296104 -156.229304)
		(end 284.714696 -156.229304)
		(width 0.15494)
		(layer "In15.Cu")
		(net "FM_SYS_THROTTLE_R")
	)
	(segment
		(start 124.711206 -172.96892)
		(end 126.177294 -171.502832)
		(width 0.15494)
		(layer "In15.Cu")
		(net "FM_SYS_THROTTLE_R")
	)
	(segment
		(start 345.301062 -167.571928)
		(end 347.699076 -169.969942)
		(width 0.15494)
		(layer "In15.Cu")
		(net "FM_SYS_THROTTLE_R")
	)
	(segment
		(start 376.249946 -173.48581)
		(end 399.911316 -173.48581)
		(width 0.15494)
		(layer "In15.Cu")
		(net "FM_SYS_THROTTLE_R")
	)
	(segment
		(start 320.829432 -220.849698)
		(end 322.188078 -220.849698)
		(width 0.13208)
		(layer "F.Cu")
		(net "LED_POSTCODE_R_4")
	)
	(segment
		(start 322.188078 -220.849698)
		(end 323.517768 -220.849698)
		(width 0.13208)
		(layer "F.Cu")
		(net "LED_POSTCODE_R_4")
	)
	(via
		(at 322.188078 -220.849698)
		(size 0.762)
		(drill 0.381)
		(layers "F.Cu" "B.Cu")
		(net "LED_POSTCODE_R_4")
	)
	(segment
		(start 232.66781 -224.304098)
		(end 232.26776 -223.904048)
		(width 0.13208)
		(layer "F.Cu")
		(net "SSD0_PWRDIS_BIC")
	)
	(segment
		(start 235.90504 -229.16515)
		(end 235.65739 -229.4128)
		(width 0.13208)
		(layer "F.Cu")
		(net "SSD0_PWRDIS_BIC")
	)
	(segment
		(start 234.735116 -227.24364)
		(end 232.66781 -225.176334)
		(width 0.13208)
		(layer "F.Cu")
		(net "SSD0_PWRDIS_BIC")
	)
	(segment
		(start 237.068106 -229.16515)
		(end 235.90504 -229.16515)
		(width 0.13208)
		(layer "F.Cu")
		(net "SSD0_PWRDIS_BIC")
	)
	(segment
		(start 232.66781 -225.176334)
		(end 232.66781 -224.304098)
		(width 0.13208)
		(layer "F.Cu")
		(net "SSD0_PWRDIS_BIC")
	)
	(segment
		(start 235.138468 -229.4128)
		(end 234.735116 -229.009448)
		(width 0.13208)
		(layer "F.Cu")
		(net "SSD0_PWRDIS_BIC")
	)
	(segment
		(start 235.65739 -229.4128)
		(end 235.138468 -229.4128)
		(width 0.13208)
		(layer "F.Cu")
		(net "SSD0_PWRDIS_BIC")
	)
	(segment
		(start 238.919512 -231.016556)
		(end 237.068106 -229.16515)
		(width 0.13208)
		(layer "F.Cu")
		(net "SSD0_PWRDIS_BIC")
	)
	(segment
		(start 234.735116 -229.009448)
		(end 234.735116 -227.695252)
		(width 0.13208)
		(layer "F.Cu")
		(net "SSD0_PWRDIS_BIC")
	)
	(segment
		(start 234.735116 -227.695252)
		(end 234.735116 -227.24364)
		(width 0.13208)
		(layer "F.Cu")
		(net "SSD0_PWRDIS_BIC")
	)
	(via
		(at 234.735116 -227.695252)
		(size 0.762)
		(drill 0.381)
		(layers "F.Cu" "B.Cu")
		(net "SSD0_PWRDIS_BIC")
	)
	(segment
		(start 234.605068 -142.640812)
		(end 235.223558 -142.640812)
		(width 0.13208)
		(layer "F.Cu")
		(net "CK440_PEX_SS_EN")
	)
	(segment
		(start 235.223558 -141.640814)
		(end 235.223558 -142.640812)
		(width 0.13208)
		(layer "F.Cu")
		(net "CK440_PEX_SS_EN")
	)
	(segment
		(start 232.855516 -144.390364)
		(end 232.471976 -144.390364)
		(width 0.13208)
		(layer "F.Cu")
		(net "CK440_PEX_SS_EN")
	)
	(segment
		(start 234.605068 -142.640812)
		(end 232.855516 -144.390364)
		(width 0.13208)
		(layer "F.Cu")
		(net "CK440_PEX_SS_EN")
	)
	(via
		(at 234.605068 -142.640812)
		(size 0.508)
		(drill 0.254)
		(layers "F.Cu" "B.Cu")
		(net "CK440_PEX_SS_EN")
	)
	(segment
		(start 179.55006 -283.549852)
		(end 180.02504 -284.024832)
		(width 0.1651)
		(layer "F.Cu")
		(net "PEX1_PCA9555_INT_R_N")
	)
	(segment
		(start 359.548176 -183.107076)
		(end 360.164126 -183.107076)
		(width 0.13208)
		(layer "F.Cu")
		(net "PEX1_PCA9555_INT_R_N")
	)
	(segment
		(start 155.682442 -252.756924)
		(end 155.682442 -253.45644)
		(width 0.13208)
		(layer "F.Cu")
		(net "PEX1_PCA9555_INT_R_N")
	)
	(via
		(at 155.682442 -253.45644)
		(size 0.508)
		(drill 0.254)
		(layers "F.Cu" "B.Cu")
		(net "PEX1_PCA9555_INT_R_N")
	)
	(via
		(at 180.02504 -284.024832)
		(size 0.4064)
		(drill 0.2032)
		(layers "F.Cu" "B.Cu")
		(net "PEX1_PCA9555_INT_R_N")
	)
	(via
		(at 360.164126 -183.107076)
		(size 0.508)
		(drill 0.254)
		(layers "F.Cu" "B.Cu")
		(net "PEX1_PCA9555_INT_R_N")
	)
	(via
		(at 146.298666 -186.059318)
		(size 0.508)
		(drill 0.254)
		(layers "F.Cu" "B.Cu")
		(net "PEX1_PCA9555_INT_R_N")
	)
	(segment
		(start 156.159962 -252.97892)
		(end 155.682442 -253.45644)
		(width 0.13208)
		(layer "B.Cu")
		(net "PEX1_PCA9555_INT_R_N")
	)
	(segment
		(start 187.612528 -281.750516)
		(end 187.612528 -271.720564)
		(width 0.13208)
		(layer "B.Cu")
		(net "PEX1_PCA9555_INT_R_N")
	)
	(segment
		(start 180.481478 -284.48127)
		(end 185.883296 -284.48127)
		(width 0.13208)
		(layer "B.Cu")
		(net "PEX1_PCA9555_INT_R_N")
	)
	(segment
		(start 168.870884 -252.97892)
		(end 156.159962 -252.97892)
		(width 0.13208)
		(layer "B.Cu")
		(net "PEX1_PCA9555_INT_R_N")
	)
	(segment
		(start 180.02504 -284.024832)
		(end 180.481478 -284.48127)
		(width 0.13208)
		(layer "B.Cu")
		(net "PEX1_PCA9555_INT_R_N")
	)
	(segment
		(start 186.795664 -282.56738)
		(end 187.612528 -281.750516)
		(width 0.13208)
		(layer "B.Cu")
		(net "PEX1_PCA9555_INT_R_N")
	)
	(segment
		(start 186.224926 -282.86202)
		(end 186.519566 -282.56738)
		(width 0.13208)
		(layer "B.Cu")
		(net "PEX1_PCA9555_INT_R_N")
	)
	(segment
		(start 185.883296 -284.48127)
		(end 186.224926 -284.13964)
		(width 0.13208)
		(layer "B.Cu")
		(net "PEX1_PCA9555_INT_R_N")
	)
	(segment
		(start 186.519566 -282.56738)
		(end 186.795664 -282.56738)
		(width 0.13208)
		(layer "B.Cu")
		(net "PEX1_PCA9555_INT_R_N")
	)
	(segment
		(start 186.224926 -284.13964)
		(end 186.224926 -282.86202)
		(width 0.13208)
		(layer "B.Cu")
		(net "PEX1_PCA9555_INT_R_N")
	)
	(segment
		(start 187.612528 -271.720564)
		(end 168.870884 -252.97892)
		(width 0.13208)
		(layer "B.Cu")
		(net "PEX1_PCA9555_INT_R_N")
	)
	(segment
		(start 152.365202 -239.171988)
		(end 152.365202 -234.933744)
		(width 0.15494)
		(layer "In5.Cu")
		(net "PEX1_PCA9555_INT_R_N")
	)
	(segment
		(start 152.809448 -230.482902)
		(end 152.809448 -195.230496)
		(width 0.15494)
		(layer "In5.Cu")
		(net "PEX1_PCA9555_INT_R_N")
	)
	(segment
		(start 154.1272 -233.171746)
		(end 154.1272 -231.800654)
		(width 0.15494)
		(layer "In5.Cu")
		(net "PEX1_PCA9555_INT_R_N")
	)
	(segment
		(start 155.682442 -253.45644)
		(end 155.20543 -252.979428)
		(width 0.15494)
		(layer "In5.Cu")
		(net "PEX1_PCA9555_INT_R_N")
	)
	(segment
		(start 155.20543 -252.979428)
		(end 155.20543 -242.012216)
		(width 0.15494)
		(layer "In5.Cu")
		(net "PEX1_PCA9555_INT_R_N")
	)
	(segment
		(start 154.1272 -231.800654)
		(end 152.809448 -230.482902)
		(width 0.15494)
		(layer "In5.Cu")
		(net "PEX1_PCA9555_INT_R_N")
	)
	(segment
		(start 155.20543 -242.012216)
		(end 152.365202 -239.171988)
		(width 0.15494)
		(layer "In5.Cu")
		(net "PEX1_PCA9555_INT_R_N")
	)
	(segment
		(start 150.928324 -190.688976)
		(end 146.298666 -186.059318)
		(width 0.15494)
		(layer "In5.Cu")
		(net "PEX1_PCA9555_INT_R_N")
	)
	(segment
		(start 152.809448 -195.230496)
		(end 150.928324 -190.688976)
		(width 0.15494)
		(layer "In5.Cu")
		(net "PEX1_PCA9555_INT_R_N")
	)
	(segment
		(start 152.365202 -234.933744)
		(end 154.1272 -233.171746)
		(width 0.15494)
		(layer "In5.Cu")
		(net "PEX1_PCA9555_INT_R_N")
	)
	(segment
		(start 334.535526 -185.523632)
		(end 342.855042 -185.523632)
		(width 0.15494)
		(layer "In13.Cu")
		(net "PEX1_PCA9555_INT_R_N")
	)
	(segment
		(start 216.994232 -178.433222)
		(end 216.994232 -179.883816)
		(width 0.15494)
		(layer "In13.Cu")
		(net "PEX1_PCA9555_INT_R_N")
	)
	(segment
		(start 221.0816 -178.689)
		(end 221.8182 -178.689)
		(width 0.15494)
		(layer "In13.Cu")
		(net "PEX1_PCA9555_INT_R_N")
	)
	(segment
		(start 227.3808 -175.6664)
		(end 229.996238 -175.6664)
		(width 0.15494)
		(layer "In13.Cu")
		(net "PEX1_PCA9555_INT_R_N")
	)
	(segment
		(start 215.70061 -177.1396)
		(end 216.994232 -178.433222)
		(width 0.15494)
		(layer "In13.Cu")
		(net "PEX1_PCA9555_INT_R_N")
	)
	(segment
		(start 261.079234 -180.019706)
		(end 270.114776 -180.019706)
		(width 0.15494)
		(layer "In13.Cu")
		(net "PEX1_PCA9555_INT_R_N")
	)
	(segment
		(start 219.486988 -180.283612)
		(end 221.0816 -178.689)
		(width 0.15494)
		(layer "In13.Cu")
		(net "PEX1_PCA9555_INT_R_N")
	)
	(segment
		(start 211.029804 -177.553366)
		(end 211.44357 -177.1396)
		(width 0.15494)
		(layer "In13.Cu")
		(net "PEX1_PCA9555_INT_R_N")
	)
	(segment
		(start 224.8408 -178.2064)
		(end 227.3808 -175.6664)
		(width 0.15494)
		(layer "In13.Cu")
		(net "PEX1_PCA9555_INT_R_N")
	)
	(segment
		(start 222.3008 -178.2064)
		(end 224.8408 -178.2064)
		(width 0.15494)
		(layer "In13.Cu")
		(net "PEX1_PCA9555_INT_R_N")
	)
	(segment
		(start 255.459992 -177.681636)
		(end 258.741164 -177.681636)
		(width 0.15494)
		(layer "In13.Cu")
		(net "PEX1_PCA9555_INT_R_N")
	)
	(segment
		(start 252.428756 -174.6504)
		(end 255.459992 -177.681636)
		(width 0.15494)
		(layer "In13.Cu")
		(net "PEX1_PCA9555_INT_R_N")
	)
	(segment
		(start 296.734738 -184.2262)
		(end 298.509944 -186.001406)
		(width 0.15494)
		(layer "In13.Cu")
		(net "PEX1_PCA9555_INT_R_N")
	)
	(segment
		(start 221.8182 -178.689)
		(end 222.3008 -178.2064)
		(width 0.15494)
		(layer "In13.Cu")
		(net "PEX1_PCA9555_INT_R_N")
	)
	(segment
		(start 236.481366 -175.557688)
		(end 237.388654 -174.6504)
		(width 0.15494)
		(layer "In13.Cu")
		(net "PEX1_PCA9555_INT_R_N")
	)
	(segment
		(start 146.298666 -186.059318)
		(end 147.592034 -187.352686)
		(width 0.15494)
		(layer "In13.Cu")
		(net "PEX1_PCA9555_INT_R_N")
	)
	(segment
		(start 346.768674 -181.61)
		(end 358.66705 -181.61)
		(width 0.15494)
		(layer "In13.Cu")
		(net "PEX1_PCA9555_INT_R_N")
	)
	(segment
		(start 334.057752 -186.001406)
		(end 334.535526 -185.523632)
		(width 0.15494)
		(layer "In13.Cu")
		(net "PEX1_PCA9555_INT_R_N")
	)
	(segment
		(start 298.509944 -186.001406)
		(end 334.057752 -186.001406)
		(width 0.15494)
		(layer "In13.Cu")
		(net "PEX1_PCA9555_INT_R_N")
	)
	(segment
		(start 258.741164 -177.681636)
		(end 261.079234 -180.019706)
		(width 0.15494)
		(layer "In13.Cu")
		(net "PEX1_PCA9555_INT_R_N")
	)
	(segment
		(start 147.592034 -187.352686)
		(end 178.715162 -187.352686)
		(width 0.15494)
		(layer "In13.Cu")
		(net "PEX1_PCA9555_INT_R_N")
	)
	(segment
		(start 274.32127 -184.2262)
		(end 296.734738 -184.2262)
		(width 0.15494)
		(layer "In13.Cu")
		(net "PEX1_PCA9555_INT_R_N")
	)
	(segment
		(start 229.996238 -175.6664)
		(end 230.10495 -175.557688)
		(width 0.15494)
		(layer "In13.Cu")
		(net "PEX1_PCA9555_INT_R_N")
	)
	(segment
		(start 216.994232 -179.883816)
		(end 217.394028 -180.283612)
		(width 0.15494)
		(layer "In13.Cu")
		(net "PEX1_PCA9555_INT_R_N")
	)
	(segment
		(start 217.394028 -180.283612)
		(end 219.486988 -180.283612)
		(width 0.15494)
		(layer "In13.Cu")
		(net "PEX1_PCA9555_INT_R_N")
	)
	(segment
		(start 178.715162 -187.352686)
		(end 179.607464 -186.460384)
		(width 0.15494)
		(layer "In13.Cu")
		(net "PEX1_PCA9555_INT_R_N")
	)
	(segment
		(start 358.66705 -181.61)
		(end 360.164126 -183.107076)
		(width 0.15494)
		(layer "In13.Cu")
		(net "PEX1_PCA9555_INT_R_N")
	)
	(segment
		(start 192.622932 -186.460384)
		(end 201.52995 -177.553366)
		(width 0.15494)
		(layer "In13.Cu")
		(net "PEX1_PCA9555_INT_R_N")
	)
	(segment
		(start 211.44357 -177.1396)
		(end 215.70061 -177.1396)
		(width 0.15494)
		(layer "In13.Cu")
		(net "PEX1_PCA9555_INT_R_N")
	)
	(segment
		(start 270.114776 -180.019706)
		(end 274.32127 -184.2262)
		(width 0.15494)
		(layer "In13.Cu")
		(net "PEX1_PCA9555_INT_R_N")
	)
	(segment
		(start 230.10495 -175.557688)
		(end 236.481366 -175.557688)
		(width 0.15494)
		(layer "In13.Cu")
		(net "PEX1_PCA9555_INT_R_N")
	)
	(segment
		(start 237.388654 -174.6504)
		(end 252.428756 -174.6504)
		(width 0.15494)
		(layer "In13.Cu")
		(net "PEX1_PCA9555_INT_R_N")
	)
	(segment
		(start 201.52995 -177.553366)
		(end 211.029804 -177.553366)
		(width 0.15494)
		(layer "In13.Cu")
		(net "PEX1_PCA9555_INT_R_N")
	)
	(segment
		(start 179.607464 -186.460384)
		(end 192.622932 -186.460384)
		(width 0.15494)
		(layer "In13.Cu")
		(net "PEX1_PCA9555_INT_R_N")
	)
	(segment
		(start 342.855042 -185.523632)
		(end 346.768674 -181.61)
		(width 0.15494)
		(layer "In13.Cu")
		(net "PEX1_PCA9555_INT_R_N")
	)
	(segment
		(start 320.829432 -225.929698)
		(end 322.188078 -225.929698)
		(width 0.13208)
		(layer "F.Cu")
		(net "LED_POSTCODE_R_0")
	)
	(segment
		(start 322.188078 -225.929698)
		(end 323.517768 -225.929698)
		(width 0.13208)
		(layer "F.Cu")
		(net "LED_POSTCODE_R_0")
	)
	(via
		(at 322.188078 -225.929698)
		(size 0.762)
		(drill 0.381)
		(layers "F.Cu" "B.Cu")
		(net "LED_POSTCODE_R_0")
	)
	(segment
		(start 363.07395 -203.835)
		(end 362.458 -203.835)
		(width 0.13208)
		(layer "F.Cu")
		(net "PEX1_PCA9555_INT_N")
	)
	(segment
		(start 358.75595 -182.118)
		(end 358.14 -182.118)
		(width 0.13208)
		(layer "F.Cu")
		(net "PEX1_PCA9555_INT_N")
	)
	(segment
		(start 358.748076 -182.125874)
		(end 358.75595 -182.118)
		(width 0.13208)
		(layer "F.Cu")
		(net "PEX1_PCA9555_INT_N")
	)
	(segment
		(start 358.748076 -183.107076)
		(end 358.748076 -182.125874)
		(width 0.13208)
		(layer "F.Cu")
		(net "PEX1_PCA9555_INT_N")
	)
	(via
		(at 362.458 -203.835)
		(size 0.508)
		(drill 0.254)
		(layers "F.Cu" "B.Cu")
		(net "PEX1_PCA9555_INT_N")
	)
	(via
		(at 358.14 -182.118)
		(size 0.508)
		(drill 0.254)
		(layers "F.Cu" "B.Cu")
		(net "PEX1_PCA9555_INT_N")
	)
	(segment
		(start 359.249472 -183.227472)
		(end 358.14 -182.118)
		(width 0.13208)
		(layer "B.Cu")
		(net "PEX1_PCA9555_INT_N")
	)
	(segment
		(start 360.585004 -195.764404)
		(end 359.249472 -194.428872)
		(width 0.13208)
		(layer "B.Cu")
		(net "PEX1_PCA9555_INT_N")
	)
	(segment
		(start 361.574588 -203.835)
		(end 360.585004 -202.845416)
		(width 0.13208)
		(layer "B.Cu")
		(net "PEX1_PCA9555_INT_N")
	)
	(segment
		(start 359.249472 -194.428872)
		(end 359.249472 -183.227472)
		(width 0.13208)
		(layer "B.Cu")
		(net "PEX1_PCA9555_INT_N")
	)
	(segment
		(start 362.458 -203.835)
		(end 361.574588 -203.835)
		(width 0.13208)
		(layer "B.Cu")
		(net "PEX1_PCA9555_INT_N")
	)
	(segment
		(start 360.585004 -202.845416)
		(end 360.585004 -195.764404)
		(width 0.13208)
		(layer "B.Cu")
		(net "PEX1_PCA9555_INT_N")
	)
	(segment
		(start 327.279 -228.918516)
		(end 327.279 -229.785926)
		(width 0.13208)
		(layer "F.Cu")
		(net "RST_PEX_SYS_R_N")
	)
	(segment
		(start 328.168 -228.11105)
		(end 327.19137 -228.11105)
		(width 0.13208)
		(layer "F.Cu")
		(net "RST_PEX_SYS_R_N")
	)
	(segment
		(start 326.30237 -228.6)
		(end 326.620886 -228.918516)
		(width 0.13208)
		(layer "F.Cu")
		(net "RST_PEX_SYS_R_N")
	)
	(segment
		(start 327.19137 -228.11105)
		(end 326.30237 -228.11105)
		(width 0.13208)
		(layer "F.Cu")
		(net "RST_PEX_SYS_R_N")
	)
	(segment
		(start 326.30237 -228.11105)
		(end 326.30237 -228.6)
		(width 0.13208)
		(layer "F.Cu")
		(net "RST_PEX_SYS_R_N")
	)
	(segment
		(start 326.620886 -228.918516)
		(end 327.279 -228.918516)
		(width 0.13208)
		(layer "F.Cu")
		(net "RST_PEX_SYS_R_N")
	)
	(via
		(at 327.279 -229.64648)
		(size 0.6604)
		(drill 0.3302)
		(layers "F.Cu" "B.Cu")
		(net "RST_PEX_SYS_R_N")
	)
	(via
		(at 327.279 -228.918516)
		(size 0.508)
		(drill 0.254)
		(layers "F.Cu" "B.Cu")
		(net "RST_PEX_SYS_R_N")
	)
	(segment
		(start 327.279 -228.918516)
		(end 327.279 -229.64648)
		(width 0.13208)
		(layer "B.Cu")
		(net "RST_PEX_SYS_R_N")
	)
	(via
		(at 104.934258 -334.774794)
		(size 0.508)
		(drill 0.254)
		(layers "F.Cu" "B.Cu")
		(net "PEX_REF_CLK_BUFFER_EN_N")
	)
	(via
		(at 105.06456 -328.385424)
		(size 0.508)
		(drill 0.254)
		(layers "F.Cu" "B.Cu")
		(net "PEX_REF_CLK_BUFFER_EN_N")
	)
	(via
		(at 102.764082 -334.297274)
		(size 0.508)
		(drill 0.254)
		(layers "F.Cu" "B.Cu")
		(net "PEX_REF_CLK_BUFFER_EN_N")
	)
	(via
		(at 104.816402 -335.651348)
		(size 0.6604)
		(drill 0.3302)
		(layers "F.Cu" "B.Cu")
		(net "PEX_REF_CLK_BUFFER_EN_N")
	)
	(via
		(at 102.534212 -329.038204)
		(size 0.508)
		(drill 0.254)
		(layers "F.Cu" "B.Cu")
		(net "PEX_REF_CLK_BUFFER_EN_N")
	)
	(segment
		(start 105.06456 -329.175618)
		(end 105.06456 -328.385424)
		(width 0.254)
		(layer "B.Cu")
		(net "PEX_REF_CLK_BUFFER_EN_N")
	)
	(segment
		(start 104.816402 -335.219802)
		(end 104.934258 -335.101946)
		(width 0.13208)
		(layer "B.Cu")
		(net "PEX_REF_CLK_BUFFER_EN_N")
	)
	(segment
		(start 102.764082 -334.297274)
		(end 102.764082 -333.614522)
		(width 0.254)
		(layer "B.Cu")
		(net "PEX_REF_CLK_BUFFER_EN_N")
	)
	(segment
		(start 104.98963 -334.506062)
		(end 104.934258 -334.561434)
		(width 0.254)
		(layer "B.Cu")
		(net "PEX_REF_CLK_BUFFER_EN_N")
	)
	(segment
		(start 105.022142 -334.450182)
		(end 104.98963 -334.482694)
		(width 0.254)
		(layer "B.Cu")
		(net "PEX_REF_CLK_BUFFER_EN_N")
	)
	(segment
		(start 103.078026 -333.300578)
		(end 103.939594 -333.300578)
		(width 0.254)
		(layer "B.Cu")
		(net "PEX_REF_CLK_BUFFER_EN_N")
	)
	(segment
		(start 102.764082 -333.614522)
		(end 103.078026 -333.300578)
		(width 0.254)
		(layer "B.Cu")
		(net "PEX_REF_CLK_BUFFER_EN_N")
	)
	(segment
		(start 102.416356 -329.68311)
		(end 102.575868 -329.842622)
		(width 0.254)
		(layer "B.Cu")
		(net "PEX_REF_CLK_BUFFER_EN_N")
	)
	(segment
		(start 104.934258 -335.101946)
		(end 104.934258 -334.774794)
		(width 0.13208)
		(layer "B.Cu")
		(net "PEX_REF_CLK_BUFFER_EN_N")
	)
	(segment
		(start 105.06456 -333.925418)
		(end 105.06456 -334.252316)
		(width 0.254)
		(layer "B.Cu")
		(net "PEX_REF_CLK_BUFFER_EN_N")
	)
	(segment
		(start 105.06456 -334.252316)
		(end 105.038652 -334.278224)
		(width 0.254)
		(layer "B.Cu")
		(net "PEX_REF_CLK_BUFFER_EN_N")
	)
	(segment
		(start 102.534212 -329.038204)
		(end 102.416356 -329.15606)
		(width 0.254)
		(layer "B.Cu")
		(net "PEX_REF_CLK_BUFFER_EN_N")
	)
	(segment
		(start 102.575868 -329.842622)
		(end 102.94366 -329.847194)
		(width 0.254)
		(layer "B.Cu")
		(net "PEX_REF_CLK_BUFFER_EN_N")
	)
	(segment
		(start 102.94366 -329.847194)
		(end 103.39705 -330.300584)
		(width 0.254)
		(layer "B.Cu")
		(net "PEX_REF_CLK_BUFFER_EN_N")
	)
	(segment
		(start 105.022142 -334.403954)
		(end 105.022142 -334.450182)
		(width 0.254)
		(layer "B.Cu")
		(net "PEX_REF_CLK_BUFFER_EN_N")
	)
	(segment
		(start 104.98963 -334.482694)
		(end 104.98963 -334.506062)
		(width 0.254)
		(layer "B.Cu")
		(net "PEX_REF_CLK_BUFFER_EN_N")
	)
	(segment
		(start 104.934258 -334.561434)
		(end 104.934258 -334.774794)
		(width 0.254)
		(layer "B.Cu")
		(net "PEX_REF_CLK_BUFFER_EN_N")
	)
	(segment
		(start 103.39705 -330.300584)
		(end 103.939594 -330.300584)
		(width 0.254)
		(layer "B.Cu")
		(net "PEX_REF_CLK_BUFFER_EN_N")
	)
	(segment
		(start 104.816402 -335.651348)
		(end 104.816402 -335.219802)
		(width 0.13208)
		(layer "B.Cu")
		(net "PEX_REF_CLK_BUFFER_EN_N")
	)
	(segment
		(start 102.416356 -329.15606)
		(end 102.416356 -329.68311)
		(width 0.254)
		(layer "B.Cu")
		(net "PEX_REF_CLK_BUFFER_EN_N")
	)
	(segment
		(start 105.038652 -334.278224)
		(end 105.038652 -334.387444)
		(width 0.254)
		(layer "B.Cu")
		(net "PEX_REF_CLK_BUFFER_EN_N")
	)
	(segment
		(start 105.038652 -334.387444)
		(end 105.022142 -334.403954)
		(width 0.254)
		(layer "B.Cu")
		(net "PEX_REF_CLK_BUFFER_EN_N")
	)
	(segment
		(start 360.78795 -182.499)
		(end 360.78795 -182.118)
		(width 0.13208)
		(layer "F.Cu")
		(net "PEX1_PCA9555_1_INT_N")
	)
	(segment
		(start 365.273844 -180.966872)
		(end 363.868716 -182.372)
		(width 0.13208)
		(layer "F.Cu")
		(net "PEX1_PCA9555_1_INT_N")
	)
	(segment
		(start 359.55605 -182.118)
		(end 360.172 -182.118)
		(width 0.13208)
		(layer "F.Cu")
		(net "PEX1_PCA9555_1_INT_N")
	)
	(segment
		(start 363.868716 -182.372)
		(end 362.712 -182.372)
		(width 0.13208)
		(layer "F.Cu")
		(net "PEX1_PCA9555_1_INT_N")
	)
	(segment
		(start 362.458 -182.626)
		(end 360.91495 -182.626)
		(width 0.13208)
		(layer "F.Cu")
		(net "PEX1_PCA9555_1_INT_N")
	)
	(segment
		(start 366.263936 -180.966872)
		(end 365.273844 -180.966872)
		(width 0.13208)
		(layer "F.Cu")
		(net "PEX1_PCA9555_1_INT_N")
	)
	(segment
		(start 362.712 -182.372)
		(end 362.458 -182.626)
		(width 0.13208)
		(layer "F.Cu")
		(net "PEX1_PCA9555_1_INT_N")
	)
	(segment
		(start 360.172 -182.118)
		(end 360.78795 -182.118)
		(width 0.13208)
		(layer "F.Cu")
		(net "PEX1_PCA9555_1_INT_N")
	)
	(segment
		(start 360.91495 -182.626)
		(end 360.78795 -182.499)
		(width 0.13208)
		(layer "F.Cu")
		(net "PEX1_PCA9555_1_INT_N")
	)
	(via
		(at 360.172 -182.118)
		(size 0.508)
		(drill 0.254)
		(layers "F.Cu" "B.Cu")
		(net "PEX1_PCA9555_1_INT_N")
	)
	(segment
		(start 320.829432 -223.389698)
		(end 322.188078 -223.389698)
		(width 0.13208)
		(layer "F.Cu")
		(net "LED_POSTCODE_R_2")
	)
	(segment
		(start 322.188078 -223.389698)
		(end 323.517768 -223.389698)
		(width 0.13208)
		(layer "F.Cu")
		(net "LED_POSTCODE_R_2")
	)
	(via
		(at 322.188078 -223.389698)
		(size 0.762)
		(drill 0.381)
		(layers "F.Cu" "B.Cu")
		(net "LED_POSTCODE_R_2")
	)
	(segment
		(start 347.726 -204.83195)
		(end 347.726 -204.216)
		(width 0.13208)
		(layer "F.Cu")
		(net "PRSNT_SSD2_FPGA_R_N")
	)
	(segment
		(start 360.322876 -190.246)
		(end 360.78795 -190.246)
		(width 0.13208)
		(layer "F.Cu")
		(net "PRSNT_SSD2_FPGA_R_N")
	)
	(segment
		(start 357.537766 -190.754)
		(end 359.814876 -190.754)
		(width 0.13208)
		(layer "F.Cu")
		(net "PRSNT_SSD2_FPGA_R_N")
	)
	(segment
		(start 359.814876 -190.754)
		(end 360.322876 -190.246)
		(width 0.13208)
		(layer "F.Cu")
		(net "PRSNT_SSD2_FPGA_R_N")
	)
	(segment
		(start 357.500428 -190.716662)
		(end 357.537766 -190.754)
		(width 0.13208)
		(layer "F.Cu")
		(net "PRSNT_SSD2_FPGA_R_N")
	)
	(via
		(at 357.500428 -190.716662)
		(size 0.508)
		(drill 0.254)
		(layers "F.Cu" "B.Cu")
		(net "PRSNT_SSD2_FPGA_R_N")
	)
	(via
		(at 347.726 -204.216)
		(size 0.508)
		(drill 0.254)
		(layers "F.Cu" "B.Cu")
		(net "PRSNT_SSD2_FPGA_R_N")
	)
	(segment
		(start 357.037386 -191.179704)
		(end 357.500428 -190.716662)
		(width 0.15494)
		(layer "In5.Cu")
		(net "PRSNT_SSD2_FPGA_R_N")
	)
	(segment
		(start 357.037386 -198.426578)
		(end 357.037386 -191.179704)
		(width 0.15494)
		(layer "In5.Cu")
		(net "PRSNT_SSD2_FPGA_R_N")
	)
	(segment
		(start 347.726 -204.216)
		(end 349.37446 -202.56754)
		(width 0.15494)
		(layer "In5.Cu")
		(net "PRSNT_SSD2_FPGA_R_N")
	)
	(segment
		(start 353.057714 -202.56754)
		(end 356.92334 -198.701914)
		(width 0.15494)
		(layer "In5.Cu")
		(net "PRSNT_SSD2_FPGA_R_N")
	)
	(segment
		(start 356.92334 -198.701914)
		(end 357.037386 -198.426578)
		(width 0.15494)
		(layer "In5.Cu")
		(net "PRSNT_SSD2_FPGA_R_N")
	)
	(segment
		(start 349.37446 -202.56754)
		(end 353.057714 -202.56754)
		(width 0.15494)
		(layer "In5.Cu")
		(net "PRSNT_SSD2_FPGA_R_N")
	)
	(segment
		(start 104.395778 -90.612722)
		(end 104.395778 -89.389966)
		(width 0.13208)
		(layer "F.Cu")
		(net "FM_CLK_EN_R")
	)
	(segment
		(start 256.666746 -78.501748)
		(end 256.666746 -79.163672)
		(width 0.13208)
		(layer "F.Cu")
		(net "FM_CLK_EN_R")
	)
	(segment
		(start 233.564176 -144.305782)
		(end 234.190032 -144.305782)
		(width 0.13208)
		(layer "F.Cu")
		(net "FM_CLK_EN_R")
	)
	(segment
		(start 256.666746 -79.163672)
		(end 257.426968 -79.923894)
		(width 0.13208)
		(layer "F.Cu")
		(net "FM_CLK_EN_R")
	)
	(segment
		(start 235.223558 -143.656812)
		(end 235.223558 -144.672812)
		(width 0.13208)
		(layer "F.Cu")
		(net "FM_CLK_EN_R")
	)
	(segment
		(start 234.190032 -144.305782)
		(end 234.557062 -144.672812)
		(width 0.13208)
		(layer "F.Cu")
		(net "FM_CLK_EN_R")
	)
	(segment
		(start 132.47116 -174.900336)
		(end 132.47116 -174.325026)
		(width 0.13208)
		(layer "F.Cu")
		(net "FM_CLK_EN_R")
	)
	(segment
		(start 334.316324 -90.47353)
		(end 333.18323 -91.606624)
		(width 0.13208)
		(layer "F.Cu")
		(net "FM_CLK_EN_R")
	)
	(segment
		(start 232.979468 -144.89049)
		(end 233.564176 -144.305782)
		(width 0.13208)
		(layer "F.Cu")
		(net "FM_CLK_EN_R")
	)
	(segment
		(start 232.471976 -144.89049)
		(end 232.979468 -144.89049)
		(width 0.13208)
		(layer "F.Cu")
		(net "FM_CLK_EN_R")
	)
	(segment
		(start 330.152248 -91.606624)
		(end 328.69632 -90.150696)
		(width 0.13208)
		(layer "F.Cu")
		(net "FM_CLK_EN_R")
	)
	(segment
		(start 335.145634 -88.964262)
		(end 334.86344 -88.964262)
		(width 0.13208)
		(layer "F.Cu")
		(net "FM_CLK_EN_R")
	)
	(segment
		(start 235.223558 -144.672812)
		(end 234.557062 -144.672812)
		(width 0.13208)
		(layer "F.Cu")
		(net "FM_CLK_EN_R")
	)
	(segment
		(start 256.19329 -77.679804)
		(end 257.20929 -77.679804)
		(width 0.13208)
		(layer "F.Cu")
		(net "FM_CLK_EN_R")
	)
	(segment
		(start 334.316324 -89.511378)
		(end 334.316324 -90.47353)
		(width 0.13208)
		(layer "F.Cu")
		(net "FM_CLK_EN_R")
	)
	(segment
		(start 105.60685 -88.178894)
		(end 105.889044 -88.178894)
		(width 0.13208)
		(layer "F.Cu")
		(net "FM_CLK_EN_R")
	)
	(segment
		(start 251.813568 -103.94442)
		(end 251.813568 -104.297734)
		(width 0.13208)
		(layer "F.Cu")
		(net "FM_CLK_EN_R")
	)
	(segment
		(start 257.20929 -77.959204)
		(end 256.666746 -78.501748)
		(width 0.13208)
		(layer "F.Cu")
		(net "FM_CLK_EN_R")
	)
	(segment
		(start 251.813568 -104.297734)
		(end 246.843804 -109.267498)
		(width 0.13208)
		(layer "F.Cu")
		(net "FM_CLK_EN_R")
	)
	(segment
		(start 257.426968 -79.923894)
		(end 257.426968 -80.431386)
		(width 0.13208)
		(layer "F.Cu")
		(net "FM_CLK_EN_R")
	)
	(segment
		(start 334.86344 -88.964262)
		(end 334.316324 -89.511378)
		(width 0.13208)
		(layer "F.Cu")
		(net "FM_CLK_EN_R")
	)
	(segment
		(start 333.18323 -91.606624)
		(end 330.152248 -91.606624)
		(width 0.13208)
		(layer "F.Cu")
		(net "FM_CLK_EN_R")
	)
	(segment
		(start 104.395778 -89.389966)
		(end 105.60685 -88.178894)
		(width 0.13208)
		(layer "F.Cu")
		(net "FM_CLK_EN_R")
	)
	(segment
		(start 328.69632 -90.150696)
		(end 328.69632 -88.85428)
		(width 0.13208)
		(layer "F.Cu")
		(net "FM_CLK_EN_R")
	)
	(segment
		(start 327.13168 -224.988882)
		(end 326.466708 -224.988882)
		(width 0.13208)
		(layer "F.Cu")
		(net "FM_CLK_EN_R")
	)
	(segment
		(start 257.20929 -77.679804)
		(end 257.20929 -77.959204)
		(width 0.13208)
		(layer "F.Cu")
		(net "FM_CLK_EN_R")
	)
	(via
		(at 110.343696 -326.713596)
		(size 0.508)
		(drill 0.254)
		(layers "F.Cu" "B.Cu")
		(net "FM_CLK_EN_R")
	)
	(via
		(at 234.347004 -160.978088)
		(size 0.508)
		(drill 0.254)
		(layers "F.Cu" "B.Cu")
		(net "FM_CLK_EN_R")
	)
	(via
		(at 104.395778 -90.612722)
		(size 0.508)
		(drill 0.254)
		(layers "F.Cu" "B.Cu")
		(net "FM_CLK_EN_R")
	)
	(via
		(at 234.557062 -144.672812)
		(size 0.508)
		(drill 0.254)
		(layers "F.Cu" "B.Cu")
		(net "FM_CLK_EN_R")
	)
	(via
		(at 320.037714 -86.535514)
		(size 0.508)
		(drill 0.254)
		(layers "F.Cu" "B.Cu")
		(net "FM_CLK_EN_R")
	)
	(via
		(at 251.813568 -103.94442)
		(size 0.508)
		(drill 0.254)
		(layers "F.Cu" "B.Cu")
		(net "FM_CLK_EN_R")
	)
	(via
		(at 105.671366 -348.379288)
		(size 0.508)
		(drill 0.254)
		(layers "F.Cu" "B.Cu")
		(net "FM_CLK_EN_R")
	)
	(via
		(at 256.666746 -78.501748)
		(size 0.508)
		(drill 0.254)
		(layers "F.Cu" "B.Cu")
		(net "FM_CLK_EN_R")
	)
	(via
		(at 281.629866 -83.23707)
		(size 0.508)
		(drill 0.254)
		(layers "F.Cu" "B.Cu")
		(net "FM_CLK_EN_R")
	)
	(via
		(at 109.69879 -333.53121)
		(size 0.508)
		(drill 0.254)
		(layers "F.Cu" "B.Cu")
		(net "FM_CLK_EN_R")
	)
	(via
		(at 328.69632 -88.85428)
		(size 0.508)
		(drill 0.254)
		(layers "F.Cu" "B.Cu")
		(net "FM_CLK_EN_R")
	)
	(via
		(at 326.466708 -224.988882)
		(size 0.508)
		(drill 0.254)
		(layers "F.Cu" "B.Cu")
		(net "FM_CLK_EN_R")
	)
	(via
		(at 246.843804 -109.267498)
		(size 0.508)
		(drill 0.254)
		(layers "F.Cu" "B.Cu")
		(net "FM_CLK_EN_R")
	)
	(via
		(at 233.70286 -169.345356)
		(size 0.508)
		(drill 0.254)
		(layers "F.Cu" "B.Cu")
		(net "FM_CLK_EN_R")
	)
	(via
		(at 132.47116 -174.325026)
		(size 0.508)
		(drill 0.254)
		(layers "F.Cu" "B.Cu")
		(net "FM_CLK_EN_R")
	)
	(segment
		(start 105.671366 -348.379288)
		(end 105.440734 -348.60992)
		(width 0.13208)
		(layer "B.Cu")
		(net "FM_CLK_EN_R")
	)
	(segment
		(start 109.69879 -333.53121)
		(end 109.468158 -333.300578)
		(width 0.13208)
		(layer "B.Cu")
		(net "FM_CLK_EN_R")
	)
	(segment
		(start 105.440734 -348.60992)
		(end 105.440734 -349.388684)
		(width 0.13208)
		(layer "B.Cu")
		(net "FM_CLK_EN_R")
	)
	(segment
		(start 109.468158 -333.300578)
		(end 108.689394 -333.300578)
		(width 0.13208)
		(layer "B.Cu")
		(net "FM_CLK_EN_R")
	)
	(segment
		(start 234.557062 -144.672812)
		(end 236.008164 -143.22171)
		(width 0.15494)
		(layer "In5.Cu")
		(net "FM_CLK_EN_R")
	)
	(segment
		(start 234.557062 -144.672812)
		(end 235.6866 -145.80235)
		(width 0.15494)
		(layer "In5.Cu")
		(net "FM_CLK_EN_R")
	)
	(segment
		(start 109.69879 -328.886566)
		(end 109.69879 -333.53121)
		(width 0.15494)
		(layer "In5.Cu")
		(net "FM_CLK_EN_R")
	)
	(segment
		(start 241.928396 -114.182906)
		(end 246.843804 -109.267498)
		(width 0.15494)
		(layer "In5.Cu")
		(net "FM_CLK_EN_R")
	)
	(segment
		(start 235.6866 -159.638492)
		(end 234.347004 -160.978088)
		(width 0.15494)
		(layer "In5.Cu")
		(net "FM_CLK_EN_R")
	)
	(segment
		(start 256.054606 -86.99373)
		(end 255.932432 -87.115904)
		(width 0.15494)
		(layer "In5.Cu")
		(net "FM_CLK_EN_R")
	)
	(segment
		(start 256.666746 -78.501748)
		(end 256.054606 -79.113888)
		(width 0.15494)
		(layer "In5.Cu")
		(net "FM_CLK_EN_R")
	)
	(segment
		(start 110.343696 -328.24166)
		(end 109.69879 -328.886566)
		(width 0.15494)
		(layer "In5.Cu")
		(net "FM_CLK_EN_R")
	)
	(segment
		(start 235.6866 -145.80235)
		(end 235.6866 -159.638492)
		(width 0.15494)
		(layer "In5.Cu")
		(net "FM_CLK_EN_R")
	)
	(segment
		(start 252.753114 -95.810578)
		(end 252.753114 -103.004874)
		(width 0.15494)
		(layer "In5.Cu")
		(net "FM_CLK_EN_R")
	)
	(segment
		(start 252.753114 -103.004874)
		(end 251.813568 -103.94442)
		(width 0.15494)
		(layer "In5.Cu")
		(net "FM_CLK_EN_R")
	)
	(segment
		(start 236.008164 -143.22171)
		(end 236.008164 -125.91669)
		(width 0.15494)
		(layer "In5.Cu")
		(net "FM_CLK_EN_R")
	)
	(segment
		(start 110.343696 -326.713596)
		(end 110.343696 -328.24166)
		(width 0.15494)
		(layer "In5.Cu")
		(net "FM_CLK_EN_R")
	)
	(segment
		(start 236.008164 -125.91669)
		(end 241.928396 -119.996458)
		(width 0.15494)
		(layer "In5.Cu")
		(net "FM_CLK_EN_R")
	)
	(segment
		(start 255.932432 -92.63126)
		(end 252.753114 -95.810578)
		(width 0.15494)
		(layer "In5.Cu")
		(net "FM_CLK_EN_R")
	)
	(segment
		(start 255.932432 -87.115904)
		(end 255.932432 -92.63126)
		(width 0.15494)
		(layer "In5.Cu")
		(net "FM_CLK_EN_R")
	)
	(segment
		(start 256.054606 -79.113888)
		(end 256.054606 -86.99373)
		(width 0.15494)
		(layer "In5.Cu")
		(net "FM_CLK_EN_R")
	)
	(segment
		(start 241.928396 -119.996458)
		(end 241.928396 -114.182906)
		(width 0.15494)
		(layer "In5.Cu")
		(net "FM_CLK_EN_R")
	)
	(segment
		(start 105.291382 -94.694756)
		(end 110.26521 -94.694756)
		(width 0.15494)
		(layer "In7.Cu")
		(net "FM_CLK_EN_R")
	)
	(segment
		(start 121.9708 -121.46788)
		(end 121.581418 -121.857262)
		(width 0.15494)
		(layer "In7.Cu")
		(net "FM_CLK_EN_R")
	)
	(segment
		(start 115.130834 -99.559872)
		(end 116.89842 -101.327458)
		(width 0.15494)
		(layer "In7.Cu")
		(net "FM_CLK_EN_R")
	)
	(segment
		(start 317.64351 -120.116092)
		(end 317.285116 -119.757698)
		(width 0.15494)
		(layer "In7.Cu")
		(net "FM_CLK_EN_R")
	)
	(segment
		(start 317.64351 -133.41985)
		(end 317.64351 -120.116092)
		(width 0.15494)
		(layer "In7.Cu")
		(net "FM_CLK_EN_R")
	)
	(segment
		(start 320.037714 -93.85046)
		(end 320.037714 -86.535514)
		(width 0.15494)
		(layer "In7.Cu")
		(net "FM_CLK_EN_R")
	)
	(segment
		(start 317.285116 -119.757698)
		(end 317.285116 -96.603058)
		(width 0.15494)
		(layer "In7.Cu")
		(net "FM_CLK_EN_R")
	)
	(segment
		(start 322.14439 -137.92073)
		(end 317.64351 -133.41985)
		(width 0.15494)
		(layer "In7.Cu")
		(net "FM_CLK_EN_R")
	)
	(segment
		(start 234.347004 -160.978088)
		(end 233.70286 -161.622232)
		(width 0.15494)
		(layer "In7.Cu")
		(net "FM_CLK_EN_R")
	)
	(segment
		(start 110.26521 -94.694756)
		(end 115.130326 -99.559872)
		(width 0.15494)
		(layer "In7.Cu")
		(net "FM_CLK_EN_R")
	)
	(segment
		(start 325.196454 -226.4918)
		(end 324.662546 -226.4918)
		(width 0.15494)
		(layer "In7.Cu")
		(net "FM_CLK_EN_R")
	)
	(segment
		(start 326.466708 -225.221546)
		(end 325.196454 -226.4918)
		(width 0.15494)
		(layer "In7.Cu")
		(net "FM_CLK_EN_R")
	)
	(segment
		(start 103.82885 -91.17965)
		(end 103.82885 -93.232224)
		(width 0.15494)
		(layer "In7.Cu")
		(net "FM_CLK_EN_R")
	)
	(segment
		(start 121.581418 -145.563844)
		(end 121.19356 -145.951702)
		(width 0.15494)
		(layer "In7.Cu")
		(net "FM_CLK_EN_R")
	)
	(segment
		(start 317.285116 -96.603058)
		(end 320.037714 -93.85046)
		(width 0.15494)
		(layer "In7.Cu")
		(net "FM_CLK_EN_R")
	)
	(segment
		(start 322.14439 -175.092614)
		(end 322.14439 -137.92073)
		(width 0.15494)
		(layer "In7.Cu")
		(net "FM_CLK_EN_R")
	)
	(segment
		(start 320.7258 -193.711322)
		(end 326.594216 -187.842906)
		(width 0.15494)
		(layer "In7.Cu")
		(net "FM_CLK_EN_R")
	)
	(segment
		(start 121.19356 -145.951702)
		(end 121.19356 -160.344612)
		(width 0.15494)
		(layer "In7.Cu")
		(net "FM_CLK_EN_R")
	)
	(segment
		(start 121.9708 -117.47881)
		(end 121.9708 -121.46788)
		(width 0.15494)
		(layer "In7.Cu")
		(net "FM_CLK_EN_R")
	)
	(segment
		(start 326.594216 -179.54244)
		(end 322.14439 -175.092614)
		(width 0.15494)
		(layer "In7.Cu")
		(net "FM_CLK_EN_R")
	)
	(segment
		(start 326.466708 -224.988882)
		(end 326.466708 -225.221546)
		(width 0.15494)
		(layer "In7.Cu")
		(net "FM_CLK_EN_R")
	)
	(segment
		(start 104.395778 -90.612722)
		(end 103.82885 -91.17965)
		(width 0.15494)
		(layer "In7.Cu")
		(net "FM_CLK_EN_R")
	)
	(segment
		(start 115.130326 -99.559872)
		(end 115.130834 -99.559872)
		(width 0.15494)
		(layer "In7.Cu")
		(net "FM_CLK_EN_R")
	)
	(segment
		(start 116.89842 -101.327458)
		(end 116.89842 -112.40643)
		(width 0.15494)
		(layer "In7.Cu")
		(net "FM_CLK_EN_R")
	)
	(segment
		(start 121.581418 -121.857262)
		(end 121.581418 -145.563844)
		(width 0.15494)
		(layer "In7.Cu")
		(net "FM_CLK_EN_R")
	)
	(segment
		(start 133.430772 -169.330116)
		(end 133.430772 -173.365414)
		(width 0.15494)
		(layer "In7.Cu")
		(net "FM_CLK_EN_R")
	)
	(segment
		(start 125.02388 -164.174932)
		(end 128.275588 -164.174932)
		(width 0.15494)
		(layer "In7.Cu")
		(net "FM_CLK_EN_R")
	)
	(segment
		(start 103.82885 -93.232224)
		(end 105.291382 -94.694756)
		(width 0.15494)
		(layer "In7.Cu")
		(net "FM_CLK_EN_R")
	)
	(segment
		(start 128.275588 -164.174932)
		(end 133.430772 -169.330116)
		(width 0.15494)
		(layer "In7.Cu")
		(net "FM_CLK_EN_R")
	)
	(segment
		(start 121.19356 -160.344612)
		(end 125.02388 -164.174932)
		(width 0.15494)
		(layer "In7.Cu")
		(net "FM_CLK_EN_R")
	)
	(segment
		(start 233.70286 -161.622232)
		(end 233.70286 -169.345356)
		(width 0.15494)
		(layer "In7.Cu")
		(net "FM_CLK_EN_R")
	)
	(segment
		(start 320.7258 -222.555054)
		(end 320.7258 -193.711322)
		(width 0.15494)
		(layer "In7.Cu")
		(net "FM_CLK_EN_R")
	)
	(segment
		(start 324.662546 -226.4918)
		(end 320.7258 -222.555054)
		(width 0.15494)
		(layer "In7.Cu")
		(net "FM_CLK_EN_R")
	)
	(segment
		(start 326.594216 -187.842906)
		(end 326.594216 -179.54244)
		(width 0.15494)
		(layer "In7.Cu")
		(net "FM_CLK_EN_R")
	)
	(segment
		(start 116.89842 -112.40643)
		(end 121.9708 -117.47881)
		(width 0.15494)
		(layer "In7.Cu")
		(net "FM_CLK_EN_R")
	)
	(segment
		(start 133.430772 -173.365414)
		(end 132.47116 -174.325026)
		(width 0.15494)
		(layer "In7.Cu")
		(net "FM_CLK_EN_R")
	)
	(segment
		(start 259.317744 -80.63103)
		(end 266.582144 -80.63103)
		(width 0.15494)
		(layer "In9.Cu")
		(net "FM_CLK_EN_R")
	)
	(segment
		(start 257.188462 -78.501748)
		(end 259.317744 -80.63103)
		(width 0.15494)
		(layer "In9.Cu")
		(net "FM_CLK_EN_R")
	)
	(segment
		(start 256.666746 -78.501748)
		(end 257.188462 -78.501748)
		(width 0.15494)
		(layer "In9.Cu")
		(net "FM_CLK_EN_R")
	)
	(segment
		(start 279.611074 -85.255862)
		(end 281.629866 -83.23707)
		(width 0.15494)
		(layer "In9.Cu")
		(net "FM_CLK_EN_R")
	)
	(segment
		(start 271.206976 -85.255862)
		(end 279.611074 -85.255862)
		(width 0.15494)
		(layer "In9.Cu")
		(net "FM_CLK_EN_R")
	)
	(segment
		(start 266.582144 -80.63103)
		(end 271.206976 -85.255862)
		(width 0.15494)
		(layer "In9.Cu")
		(net "FM_CLK_EN_R")
	)
	(segment
		(start 88.783922 -281.671522)
		(end 95.513652 -288.401252)
		(width 0.15494)
		(layer "In11.Cu")
		(net "FM_CLK_EN_R")
	)
	(segment
		(start 97.155 -294.129968)
		(end 97.155 -310.590946)
		(width 0.15494)
		(layer "In11.Cu")
		(net "FM_CLK_EN_R")
	)
	(segment
		(start 122.51944 -182.98033)
		(end 101.20249 -182.98033)
		(width 0.15494)
		(layer "In11.Cu")
		(net "FM_CLK_EN_R")
	)
	(segment
		(start 84.434934 -259.110734)
		(end 84.434934 -271.17167)
		(width 0.15494)
		(layer "In11.Cu")
		(net "FM_CLK_EN_R")
	)
	(segment
		(start 100.49002 -313.925966)
		(end 101.9048 -317.340488)
		(width 0.15494)
		(layer "In11.Cu")
		(net "FM_CLK_EN_R")
	)
	(segment
		(start 98.032316 -179.810156)
		(end 89.776046 -179.810156)
		(width 0.15494)
		(layer "In11.Cu")
		(net "FM_CLK_EN_R")
	)
	(segment
		(start 95.513652 -288.401252)
		(end 95.513652 -292.48862)
		(width 0.15494)
		(layer "In11.Cu")
		(net "FM_CLK_EN_R")
	)
	(segment
		(start 130.794252 -174.645574)
		(end 130.559048 -174.880778)
		(width 0.15494)
		(layer "In11.Cu")
		(net "FM_CLK_EN_R")
	)
	(segment
		(start 101.9048 -324.203568)
		(end 104.091232 -326.39)
		(width 0.15494)
		(layer "In11.Cu")
		(net "FM_CLK_EN_R")
	)
	(segment
		(start 95.513652 -292.48862)
		(end 97.155 -294.129968)
		(width 0.15494)
		(layer "In11.Cu")
		(net "FM_CLK_EN_R")
	)
	(segment
		(start 110.0201 -326.39)
		(end 110.343696 -326.713596)
		(width 0.15494)
		(layer "In11.Cu")
		(net "FM_CLK_EN_R")
	)
	(segment
		(start 78.55966 -191.026542)
		(end 78.55966 -253.23546)
		(width 0.15494)
		(layer "In11.Cu")
		(net "FM_CLK_EN_R")
	)
	(segment
		(start 130.559048 -174.880778)
		(end 126.770892 -174.880778)
		(width 0.15494)
		(layer "In11.Cu")
		(net "FM_CLK_EN_R")
	)
	(segment
		(start 104.091232 -326.39)
		(end 110.0201 -326.39)
		(width 0.15494)
		(layer "In11.Cu")
		(net "FM_CLK_EN_R")
	)
	(segment
		(start 101.9048 -317.340488)
		(end 101.9048 -324.203568)
		(width 0.15494)
		(layer "In11.Cu")
		(net "FM_CLK_EN_R")
	)
	(segment
		(start 126.770892 -174.880778)
		(end 125.50013 -176.15154)
		(width 0.15494)
		(layer "In11.Cu")
		(net "FM_CLK_EN_R")
	)
	(segment
		(start 125.50013 -179.99964)
		(end 122.51944 -182.98033)
		(width 0.15494)
		(layer "In11.Cu")
		(net "FM_CLK_EN_R")
	)
	(segment
		(start 78.55966 -253.23546)
		(end 84.434934 -259.110734)
		(width 0.15494)
		(layer "In11.Cu")
		(net "FM_CLK_EN_R")
	)
	(segment
		(start 132.47116 -174.325026)
		(end 132.150612 -174.645574)
		(width 0.15494)
		(layer "In11.Cu")
		(net "FM_CLK_EN_R")
	)
	(segment
		(start 132.150612 -174.645574)
		(end 130.794252 -174.645574)
		(width 0.15494)
		(layer "In11.Cu")
		(net "FM_CLK_EN_R")
	)
	(segment
		(start 84.434934 -271.17167)
		(end 88.783922 -281.671522)
		(width 0.15494)
		(layer "In11.Cu")
		(net "FM_CLK_EN_R")
	)
	(segment
		(start 89.776046 -179.810156)
		(end 78.55966 -191.026542)
		(width 0.15494)
		(layer "In11.Cu")
		(net "FM_CLK_EN_R")
	)
	(segment
		(start 125.50013 -176.15154)
		(end 125.50013 -179.99964)
		(width 0.15494)
		(layer "In11.Cu")
		(net "FM_CLK_EN_R")
	)
	(segment
		(start 101.20249 -182.98033)
		(end 98.032316 -179.810156)
		(width 0.15494)
		(layer "In11.Cu")
		(net "FM_CLK_EN_R")
	)
	(segment
		(start 97.155 -310.590946)
		(end 100.49002 -313.925966)
		(width 0.15494)
		(layer "In11.Cu")
		(net "FM_CLK_EN_R")
	)
	(segment
		(start 105.671366 -348.379288)
		(end 105.671366 -347.083634)
		(width 0.15494)
		(layer "In13.Cu")
		(net "FM_CLK_EN_R")
	)
	(segment
		(start 305.063398 -85.762846)
		(end 311.596278 -85.762846)
		(width 0.15494)
		(layer "In13.Cu")
		(net "FM_CLK_EN_R")
	)
	(segment
		(start 283.231336 -81.6356)
		(end 292.83025 -81.6356)
		(width 0.15494)
		(layer "In13.Cu")
		(net "FM_CLK_EN_R")
	)
	(segment
		(start 294.234108 -83.039458)
		(end 302.34001 -83.039458)
		(width 0.15494)
		(layer "In13.Cu")
		(net "FM_CLK_EN_R")
	)
	(segment
		(start 105.671366 -347.083634)
		(end 107.5182 -345.2368)
		(width 0.15494)
		(layer "In13.Cu")
		(net "FM_CLK_EN_R")
	)
	(segment
		(start 320.037714 -86.535514)
		(end 323.755004 -86.535514)
		(width 0.15494)
		(layer "In13.Cu")
		(net "FM_CLK_EN_R")
	)
	(segment
		(start 233.70286 -169.345356)
		(end 233.226864 -169.821352)
		(width 0.15494)
		(layer "In13.Cu")
		(net "FM_CLK_EN_R")
	)
	(segment
		(start 292.83025 -81.6356)
		(end 294.234108 -83.039458)
		(width 0.15494)
		(layer "In13.Cu")
		(net "FM_CLK_EN_R")
	)
	(segment
		(start 136.793986 -170.0022)
		(end 132.47116 -174.325026)
		(width 0.15494)
		(layer "In13.Cu")
		(net "FM_CLK_EN_R")
	)
	(segment
		(start 319.451228 -87.122)
		(end 320.037714 -86.535514)
		(width 0.15494)
		(layer "In13.Cu")
		(net "FM_CLK_EN_R")
	)
	(segment
		(start 324.954392 -87.734902)
		(end 327.231502 -87.734902)
		(width 0.15494)
		(layer "In13.Cu")
		(net "FM_CLK_EN_R")
	)
	(segment
		(start 149.428454 -173.482)
		(end 145.948654 -170.0022)
		(width 0.15494)
		(layer "In13.Cu")
		(net "FM_CLK_EN_R")
	)
	(segment
		(start 107.5182 -335.026)
		(end 109.01299 -333.53121)
		(width 0.15494)
		(layer "In13.Cu")
		(net "FM_CLK_EN_R")
	)
	(segment
		(start 168.529254 -174.371)
		(end 167.640254 -173.482)
		(width 0.15494)
		(layer "In13.Cu")
		(net "FM_CLK_EN_R")
	)
	(segment
		(start 209.115406 -174.371)
		(end 168.529254 -174.371)
		(width 0.15494)
		(layer "In13.Cu")
		(net "FM_CLK_EN_R")
	)
	(segment
		(start 328.35088 -88.85428)
		(end 328.69632 -88.85428)
		(width 0.15494)
		(layer "In13.Cu")
		(net "FM_CLK_EN_R")
	)
	(segment
		(start 302.34001 -83.039458)
		(end 305.063398 -85.762846)
		(width 0.15494)
		(layer "In13.Cu")
		(net "FM_CLK_EN_R")
	)
	(segment
		(start 323.755004 -86.535514)
		(end 324.954392 -87.734902)
		(width 0.15494)
		(layer "In13.Cu")
		(net "FM_CLK_EN_R")
	)
	(segment
		(start 229.06863 -170.854116)
		(end 212.63229 -170.854116)
		(width 0.15494)
		(layer "In13.Cu")
		(net "FM_CLK_EN_R")
	)
	(segment
		(start 145.948654 -170.0022)
		(end 136.793986 -170.0022)
		(width 0.15494)
		(layer "In13.Cu")
		(net "FM_CLK_EN_R")
	)
	(segment
		(start 317.656972 -87.122)
		(end 319.451228 -87.122)
		(width 0.15494)
		(layer "In13.Cu")
		(net "FM_CLK_EN_R")
	)
	(segment
		(start 109.01299 -333.53121)
		(end 109.69879 -333.53121)
		(width 0.15494)
		(layer "In13.Cu")
		(net "FM_CLK_EN_R")
	)
	(segment
		(start 327.231502 -87.734902)
		(end 328.35088 -88.85428)
		(width 0.15494)
		(layer "In13.Cu")
		(net "FM_CLK_EN_R")
	)
	(segment
		(start 311.596278 -85.762846)
		(end 312.368946 -86.535514)
		(width 0.15494)
		(layer "In13.Cu")
		(net "FM_CLK_EN_R")
	)
	(segment
		(start 312.368946 -86.535514)
		(end 317.070486 -86.535514)
		(width 0.15494)
		(layer "In13.Cu")
		(net "FM_CLK_EN_R")
	)
	(segment
		(start 281.629866 -83.23707)
		(end 283.231336 -81.6356)
		(width 0.15494)
		(layer "In13.Cu")
		(net "FM_CLK_EN_R")
	)
	(segment
		(start 167.640254 -173.482)
		(end 149.428454 -173.482)
		(width 0.15494)
		(layer "In13.Cu")
		(net "FM_CLK_EN_R")
	)
	(segment
		(start 212.63229 -170.854116)
		(end 209.115406 -174.371)
		(width 0.15494)
		(layer "In13.Cu")
		(net "FM_CLK_EN_R")
	)
	(segment
		(start 107.5182 -345.2368)
		(end 107.5182 -335.026)
		(width 0.15494)
		(layer "In13.Cu")
		(net "FM_CLK_EN_R")
	)
	(segment
		(start 233.226864 -169.821352)
		(end 230.101394 -169.821352)
		(width 0.15494)
		(layer "In13.Cu")
		(net "FM_CLK_EN_R")
	)
	(segment
		(start 317.070486 -86.535514)
		(end 317.656972 -87.122)
		(width 0.15494)
		(layer "In13.Cu")
		(net "FM_CLK_EN_R")
	)
	(segment
		(start 230.101394 -169.821352)
		(end 229.06863 -170.854116)
		(width 0.15494)
		(layer "In13.Cu")
		(net "FM_CLK_EN_R")
	)
	(segment
		(start 317.315088 -288.830766)
		(end 317.735712 -288.830766)
		(width 0.13208)
		(layer "F.Cu")
		(net "RST_PEX2_S0_PERST_R_N")
	)
	(segment
		(start 303.724818 -304.924714)
		(end 304.199798 -304.449734)
		(width 0.13208)
		(layer "F.Cu")
		(net "RST_PEX2_S0_PERST_R_N")
	)
	(segment
		(start 317.010542 -289.516058)
		(end 317.2206 -289.306)
		(width 0.13208)
		(layer "F.Cu")
		(net "RST_PEX2_S0_PERST_R_N")
	)
	(segment
		(start 317.338202 -296.18051)
		(end 317.010542 -295.85285)
		(width 0.13208)
		(layer "F.Cu")
		(net "RST_PEX2_S0_PERST_R_N")
	)
	(segment
		(start 317.010542 -295.85285)
		(end 317.010542 -289.516058)
		(width 0.13208)
		(layer "F.Cu")
		(net "RST_PEX2_S0_PERST_R_N")
	)
	(segment
		(start 317.2206 -288.925254)
		(end 317.315088 -288.830766)
		(width 0.13208)
		(layer "F.Cu")
		(net "RST_PEX2_S0_PERST_R_N")
	)
	(segment
		(start 317.2206 -289.306)
		(end 317.2206 -288.925254)
		(width 0.13208)
		(layer "F.Cu")
		(net "RST_PEX2_S0_PERST_R_N")
	)
	(via
		(at 303.724818 -304.924714)
		(size 0.4064)
		(drill 0.2032)
		(layers "F.Cu" "B.Cu")
		(net "RST_PEX2_S0_PERST_R_N")
	)
	(via
		(at 317.338202 -296.18051)
		(size 0.508)
		(drill 0.254)
		(layers "F.Cu" "B.Cu")
		(net "RST_PEX2_S0_PERST_R_N")
	)
	(segment
		(start 304.202592 -304.44694)
		(end 303.724818 -304.924714)
		(width 0.15494)
		(layer "In5.Cu")
		(net "RST_PEX2_S0_PERST_R_N")
	)
	(segment
		(start 317.338202 -296.37228)
		(end 315.910722 -297.79976)
		(width 0.15494)
		(layer "In5.Cu")
		(net "RST_PEX2_S0_PERST_R_N")
	)
	(segment
		(start 305.0032 -304.44694)
		(end 304.202592 -304.44694)
		(width 0.15494)
		(layer "In5.Cu")
		(net "RST_PEX2_S0_PERST_R_N")
	)
	(segment
		(start 315.910722 -297.79976)
		(end 305.52644 -297.79976)
		(width 0.15494)
		(layer "In5.Cu")
		(net "RST_PEX2_S0_PERST_R_N")
	)
	(segment
		(start 305.1302 -304.31994)
		(end 305.0032 -304.44694)
		(width 0.15494)
		(layer "In5.Cu")
		(net "RST_PEX2_S0_PERST_R_N")
	)
	(segment
		(start 317.338202 -296.18051)
		(end 317.338202 -296.37228)
		(width 0.15494)
		(layer "In5.Cu")
		(net "RST_PEX2_S0_PERST_R_N")
	)
	(segment
		(start 305.52644 -297.79976)
		(end 305.1302 -298.196)
		(width 0.15494)
		(layer "In5.Cu")
		(net "RST_PEX2_S0_PERST_R_N")
	)
	(segment
		(start 305.1302 -298.196)
		(end 305.1302 -304.31994)
		(width 0.15494)
		(layer "In5.Cu")
		(net "RST_PEX2_S0_PERST_R_N")
	)
	(segment
		(start 231.659684 -151.703532)
		(end 231.34701 -151.390858)
		(width 0.13208)
		(layer "F.Cu")
		(net "PEX_REF_CLK_GEN_EN_N")
	)
	(segment
		(start 232.155492 -151.664162)
		(end 231.846882 -151.355552)
		(width 0.13208)
		(layer "F.Cu")
		(net "PEX_REF_CLK_GEN_EN_N")
	)
	(segment
		(start 232.116122 -151.703532)
		(end 231.659684 -151.703532)
		(width 0.13208)
		(layer "F.Cu")
		(net "PEX_REF_CLK_GEN_EN_N")
	)
	(segment
		(start 226.550982 -155.598622)
		(end 227.566982 -155.598622)
		(width 0.13208)
		(layer "F.Cu")
		(net "PEX_REF_CLK_GEN_EN_N")
	)
	(segment
		(start 229.096824 -151.471376)
		(end 229.096824 -150.265384)
		(width 0.0889)
		(layer "F.Cu")
		(net "PEX_REF_CLK_GEN_EN_N")
	)
	(segment
		(start 233.703622 -149.660864)
		(end 233.656886 -149.7076)
		(width 0.13208)
		(layer "F.Cu")
		(net "PEX_REF_CLK_GEN_EN_N")
	)
	(segment
		(start 228.079046 -153.28773)
		(end 228.916484 -152.450292)
		(width 0.13208)
		(layer "F.Cu")
		(net "PEX_REF_CLK_GEN_EN_N")
	)
	(segment
		(start 232.155492 -151.664162)
		(end 232.116122 -151.703532)
		(width 0.13208)
		(layer "F.Cu")
		(net "PEX_REF_CLK_GEN_EN_N")
	)
	(segment
		(start 231.846882 -151.355552)
		(end 231.846882 -151.015446)
		(width 0.13208)
		(layer "F.Cu")
		(net "PEX_REF_CLK_GEN_EN_N")
	)
	(segment
		(start 233.656886 -149.7076)
		(end 233.2736 -149.7076)
		(width 0.13208)
		(layer "F.Cu")
		(net "PEX_REF_CLK_GEN_EN_N")
	)
	(segment
		(start 228.916484 -152.450292)
		(end 228.916484 -151.651716)
		(width 0.13208)
		(layer "F.Cu")
		(net "PEX_REF_CLK_GEN_EN_N")
	)
	(segment
		(start 228.916484 -151.651716)
		(end 229.0064 -151.5618)
		(width 0.13208)
		(layer "F.Cu")
		(net "PEX_REF_CLK_GEN_EN_N")
	)
	(segment
		(start 232.956354 -149.390354)
		(end 232.471976 -149.390354)
		(width 0.13208)
		(layer "F.Cu")
		(net "PEX_REF_CLK_GEN_EN_N")
	)
	(segment
		(start 227.566982 -154.862784)
		(end 227.566982 -155.598622)
		(width 0.13208)
		(layer "F.Cu")
		(net "PEX_REF_CLK_GEN_EN_N")
	)
	(segment
		(start 228.079046 -154.35072)
		(end 228.079046 -153.28773)
		(width 0.13208)
		(layer "F.Cu")
		(net "PEX_REF_CLK_GEN_EN_N")
	)
	(segment
		(start 233.989118 -149.660864)
		(end 233.703622 -149.660864)
		(width 0.13208)
		(layer "F.Cu")
		(net "PEX_REF_CLK_GEN_EN_N")
	)
	(segment
		(start 227.566982 -154.862784)
		(end 228.079046 -154.35072)
		(width 0.13208)
		(layer "F.Cu")
		(net "PEX_REF_CLK_GEN_EN_N")
	)
	(segment
		(start 233.2736 -149.7076)
		(end 232.956354 -149.390354)
		(width 0.13208)
		(layer "F.Cu")
		(net "PEX_REF_CLK_GEN_EN_N")
	)
	(segment
		(start 231.34701 -151.390858)
		(end 231.34701 -151.015446)
		(width 0.13208)
		(layer "F.Cu")
		(net "PEX_REF_CLK_GEN_EN_N")
	)
	(segment
		(start 229.0064 -151.5618)
		(end 229.096824 -151.471376)
		(width 0.0889)
		(layer "F.Cu")
		(net "PEX_REF_CLK_GEN_EN_N")
	)
	(via
		(at 232.155492 -151.664162)
		(size 0.508)
		(drill 0.254)
		(layers "F.Cu" "B.Cu")
		(net "PEX_REF_CLK_GEN_EN_N")
	)
	(via
		(at 233.989118 -149.660864)
		(size 0.508)
		(drill 0.254)
		(layers "F.Cu" "B.Cu")
		(net "PEX_REF_CLK_GEN_EN_N")
	)
	(via
		(at 227.566982 -154.862784)
		(size 0.508)
		(drill 0.254)
		(layers "F.Cu" "B.Cu")
		(net "PEX_REF_CLK_GEN_EN_N")
	)
	(segment
		(start 232.83418 -151.664162)
		(end 233.989118 -150.509224)
		(width 0.15494)
		(layer "In5.Cu")
		(net "PEX_REF_CLK_GEN_EN_N")
	)
	(segment
		(start 233.989118 -150.509224)
		(end 233.989118 -149.660864)
		(width 0.15494)
		(layer "In5.Cu")
		(net "PEX_REF_CLK_GEN_EN_N")
	)
	(segment
		(start 228.322632 -154.107134)
		(end 231.079802 -154.107134)
		(width 0.15494)
		(layer "In5.Cu")
		(net "PEX_REF_CLK_GEN_EN_N")
	)
	(segment
		(start 232.155492 -153.031444)
		(end 232.155492 -151.664162)
		(width 0.15494)
		(layer "In5.Cu")
		(net "PEX_REF_CLK_GEN_EN_N")
	)
	(segment
		(start 232.155492 -151.664162)
		(end 232.83418 -151.664162)
		(width 0.15494)
		(layer "In5.Cu")
		(net "PEX_REF_CLK_GEN_EN_N")
	)
	(segment
		(start 231.079802 -154.107134)
		(end 232.155492 -153.031444)
		(width 0.15494)
		(layer "In5.Cu")
		(net "PEX_REF_CLK_GEN_EN_N")
	)
	(segment
		(start 227.566982 -154.862784)
		(end 228.322632 -154.107134)
		(width 0.15494)
		(layer "In5.Cu")
		(net "PEX_REF_CLK_GEN_EN_N")
	)
	(segment
		(start 363.87405 -203.835)
		(end 364.49 -203.835)
		(width 0.13208)
		(layer "F.Cu")
		(net "PEX1_PCA9555_0_INT_N")
	)
	(segment
		(start 368.151156 -204.089)
		(end 367.03 -204.089)
		(width 0.13208)
		(layer "F.Cu")
		(net "PEX1_PCA9555_0_INT_N")
	)
	(segment
		(start 364.49 -203.835)
		(end 365.10595 -203.835)
		(width 0.13208)
		(layer "F.Cu")
		(net "PEX1_PCA9555_0_INT_N")
	)
	(segment
		(start 365.23295 -204.343)
		(end 365.10595 -204.216)
		(width 0.13208)
		(layer "F.Cu")
		(net "PEX1_PCA9555_0_INT_N")
	)
	(segment
		(start 370.581936 -202.683872)
		(end 369.556284 -202.683872)
		(width 0.13208)
		(layer "F.Cu")
		(net "PEX1_PCA9555_0_INT_N")
	)
	(segment
		(start 366.776 -204.343)
		(end 365.23295 -204.343)
		(width 0.13208)
		(layer "F.Cu")
		(net "PEX1_PCA9555_0_INT_N")
	)
	(segment
		(start 365.10595 -204.216)
		(end 365.10595 -203.835)
		(width 0.13208)
		(layer "F.Cu")
		(net "PEX1_PCA9555_0_INT_N")
	)
	(segment
		(start 367.03 -204.089)
		(end 366.776 -204.343)
		(width 0.13208)
		(layer "F.Cu")
		(net "PEX1_PCA9555_0_INT_N")
	)
	(segment
		(start 369.556284 -202.683872)
		(end 368.151156 -204.089)
		(width 0.13208)
		(layer "F.Cu")
		(net "PEX1_PCA9555_0_INT_N")
	)
	(via
		(at 364.49 -203.835)
		(size 0.508)
		(drill 0.254)
		(layers "F.Cu" "B.Cu")
		(net "PEX1_PCA9555_0_INT_N")
	)
	(segment
		(start 360.78795 -186.182)
		(end 360.172 -186.182)
		(width 0.13208)
		(layer "F.Cu")
		(net "PRSNT_SSD3_FPGA_R_N")
	)
	(via
		(at 346.202 -206.15148)
		(size 0.508)
		(drill 0.254)
		(layers "F.Cu" "B.Cu")
		(net "PRSNT_SSD3_FPGA_R_N")
	)
	(via
		(at 356.679246 -186.907932)
		(size 0.508)
		(drill 0.254)
		(layers "F.Cu" "B.Cu")
		(net "PRSNT_SSD3_FPGA_R_N")
	)
	(via
		(at 360.172 -186.182)
		(size 0.508)
		(drill 0.254)
		(layers "F.Cu" "B.Cu")
		(net "PRSNT_SSD3_FPGA_R_N")
	)
	(segment
		(start 346.583 -207.37195)
		(end 346.583 -206.53248)
		(width 0.13208)
		(layer "B.Cu")
		(net "PRSNT_SSD3_FPGA_R_N")
	)
	(segment
		(start 346.583 -206.53248)
		(end 346.202 -206.15148)
		(width 0.13208)
		(layer "B.Cu")
		(net "PRSNT_SSD3_FPGA_R_N")
	)
	(segment
		(start 356.679246 -198.283576)
		(end 356.56901 -198.549514)
		(width 0.15494)
		(layer "In5.Cu")
		(net "PRSNT_SSD3_FPGA_R_N")
	)
	(segment
		(start 347.927676 -202.2094)
		(end 346.202 -203.935076)
		(width 0.15494)
		(layer "In5.Cu")
		(net "PRSNT_SSD3_FPGA_R_N")
	)
	(segment
		(start 356.56901 -198.549514)
		(end 352.909124 -202.2094)
		(width 0.15494)
		(layer "In5.Cu")
		(net "PRSNT_SSD3_FPGA_R_N")
	)
	(segment
		(start 346.202 -203.935076)
		(end 346.202 -206.15148)
		(width 0.15494)
		(layer "In5.Cu")
		(net "PRSNT_SSD3_FPGA_R_N")
	)
	(segment
		(start 352.909124 -202.2094)
		(end 347.927676 -202.2094)
		(width 0.15494)
		(layer "In5.Cu")
		(net "PRSNT_SSD3_FPGA_R_N")
	)
	(segment
		(start 356.679246 -186.907932)
		(end 356.679246 -198.283576)
		(width 0.15494)
		(layer "In5.Cu")
		(net "PRSNT_SSD3_FPGA_R_N")
	)
	(segment
		(start 359.446068 -186.907932)
		(end 360.172 -186.182)
		(width 0.15494)
		(layer "In13.Cu")
		(net "PRSNT_SSD3_FPGA_R_N")
	)
	(segment
		(start 356.679246 -186.907932)
		(end 359.446068 -186.907932)
		(width 0.15494)
		(layer "In13.Cu")
		(net "PRSNT_SSD3_FPGA_R_N")
	)
	(segment
		(start 433.11064 -289.0774)
		(end 433.11064 -297.63085)
		(width 0.13208)
		(layer "F.Cu")
		(net "RST_PEX3_S0_PERST_R_N")
	)
	(segment
		(start 433.11064 -297.63085)
		(end 433.4383 -297.95851)
		(width 0.13208)
		(layer "F.Cu")
		(net "RST_PEX3_S0_PERST_R_N")
	)
	(segment
		(start 419.824916 -304.924714)
		(end 420.299896 -304.449734)
		(width 0.13208)
		(layer "F.Cu")
		(net "RST_PEX3_S0_PERST_R_N")
	)
	(segment
		(start 433.357274 -288.830766)
		(end 433.11064 -289.0774)
		(width 0.13208)
		(layer "F.Cu")
		(net "RST_PEX3_S0_PERST_R_N")
	)
	(segment
		(start 433.83581 -288.830766)
		(end 433.357274 -288.830766)
		(width 0.13208)
		(layer "F.Cu")
		(net "RST_PEX3_S0_PERST_R_N")
	)
	(via
		(at 419.824916 -304.924714)
		(size 0.4064)
		(drill 0.2032)
		(layers "F.Cu" "B.Cu")
		(net "RST_PEX3_S0_PERST_R_N")
	)
	(via
		(at 433.4383 -297.95851)
		(size 0.508)
		(drill 0.254)
		(layers "F.Cu" "B.Cu")
		(net "RST_PEX3_S0_PERST_R_N")
	)
	(segment
		(start 421.259 -304.31994)
		(end 421.132 -304.44694)
		(width 0.15494)
		(layer "In5.Cu")
		(net "RST_PEX3_S0_PERST_R_N")
	)
	(segment
		(start 433.4383 -297.95851)
		(end 433.162964 -297.95851)
		(width 0.15494)
		(layer "In5.Cu")
		(net "RST_PEX3_S0_PERST_R_N")
	)
	(segment
		(start 433.162964 -297.95851)
		(end 433.004214 -297.79976)
		(width 0.15494)
		(layer "In5.Cu")
		(net "RST_PEX3_S0_PERST_R_N")
	)
	(segment
		(start 421.569642 -297.79976)
		(end 421.259 -298.110402)
		(width 0.15494)
		(layer "In5.Cu")
		(net "RST_PEX3_S0_PERST_R_N")
	)
	(segment
		(start 421.132 -304.44694)
		(end 420.30269 -304.44694)
		(width 0.15494)
		(layer "In5.Cu")
		(net "RST_PEX3_S0_PERST_R_N")
	)
	(segment
		(start 433.004214 -297.79976)
		(end 421.569642 -297.79976)
		(width 0.15494)
		(layer "In5.Cu")
		(net "RST_PEX3_S0_PERST_R_N")
	)
	(segment
		(start 421.259 -298.110402)
		(end 421.259 -304.31994)
		(width 0.15494)
		(layer "In5.Cu")
		(net "RST_PEX3_S0_PERST_R_N")
	)
	(segment
		(start 420.30269 -304.44694)
		(end 419.824916 -304.924714)
		(width 0.15494)
		(layer "In5.Cu")
		(net "RST_PEX3_S0_PERST_R_N")
	)
	(segment
		(start 236.411516 -332.883256)
		(end 234.0356 -335.259172)
		(width 0.13208)
		(layer "F.Cu")
		(net "SMB_ALERT_HSC_R_N")
	)
	(segment
		(start 225.067622 -216.704164)
		(end 224.667826 -216.304368)
		(width 0.13208)
		(layer "F.Cu")
		(net "SMB_ALERT_HSC_R_N")
	)
	(segment
		(start 194.41922 -410.569918)
		(end 194.41922 -410.045408)
		(width 0.13208)
		(layer "F.Cu")
		(net "SMB_ALERT_HSC_R_N")
	)
	(segment
		(start 194.27063 -409.896818)
		(end 193.916808 -409.896818)
		(width 0.13208)
		(layer "F.Cu")
		(net "SMB_ALERT_HSC_R_N")
	)
	(segment
		(start 194.54622 -410.696918)
		(end 194.41922 -410.569918)
		(width 0.13208)
		(layer "F.Cu")
		(net "SMB_ALERT_HSC_R_N")
	)
	(segment
		(start 234.0356 -335.259172)
		(end 234.0356 -344.361516)
		(width 0.13208)
		(layer "F.Cu")
		(net "SMB_ALERT_HSC_R_N")
	)
	(segment
		(start 194.932808 -410.696918)
		(end 194.54622 -410.696918)
		(width 0.13208)
		(layer "F.Cu")
		(net "SMB_ALERT_HSC_R_N")
	)
	(segment
		(start 194.932808 -410.696918)
		(end 195.931282 -410.696918)
		(width 0.13208)
		(layer "F.Cu")
		(net "SMB_ALERT_HSC_R_N")
	)
	(segment
		(start 194.41922 -410.045408)
		(end 194.27063 -409.896818)
		(width 0.13208)
		(layer "F.Cu")
		(net "SMB_ALERT_HSC_R_N")
	)
	(segment
		(start 234.0356 -344.361516)
		(end 235.507022 -345.832938)
		(width 0.13208)
		(layer "F.Cu")
		(net "SMB_ALERT_HSC_R_N")
	)
	(segment
		(start 338.893912 -219.187014)
		(end 338.494116 -218.787218)
		(width 0.13208)
		(layer "F.Cu")
		(net "SMB_ALERT_HSC_R_N")
	)
	(via
		(at 195.931282 -410.696918)
		(size 0.508)
		(drill 0.254)
		(layers "F.Cu" "B.Cu")
		(net "SMB_ALERT_HSC_R_N")
	)
	(via
		(at 241.592354 -185.448194)
		(size 0.508)
		(drill 0.254)
		(layers "F.Cu" "B.Cu")
		(net "SMB_ALERT_HSC_R_N")
	)
	(via
		(at 235.507022 -345.832938)
		(size 0.508)
		(drill 0.254)
		(layers "F.Cu" "B.Cu")
		(net "SMB_ALERT_HSC_R_N")
	)
	(via
		(at 236.411516 -332.883256)
		(size 0.508)
		(drill 0.254)
		(layers "F.Cu" "B.Cu")
		(net "SMB_ALERT_HSC_R_N")
	)
	(via
		(at 228.04755 -252.580902)
		(size 0.508)
		(drill 0.254)
		(layers "F.Cu" "B.Cu")
		(net "SMB_ALERT_HSC_R_N")
	)
	(via
		(at 224.667826 -216.304368)
		(size 0.4572)
		(drill 0.254)
		(layers "F.Cu" "B.Cu")
		(net "SMB_ALERT_HSC_R_N")
	)
	(via
		(at 338.494116 -218.787218)
		(size 0.4572)
		(drill 0.254)
		(layers "F.Cu" "B.Cu")
		(net "SMB_ALERT_HSC_R_N")
	)
	(segment
		(start 220.669104 -360.680508)
		(end 216.002616 -360.680508)
		(width 0.15494)
		(layer "In5.Cu")
		(net "SMB_ALERT_HSC_R_N")
	)
	(segment
		(start 190.636652 -368.342418)
		(end 189.645036 -369.334034)
		(width 0.15494)
		(layer "In5.Cu")
		(net "SMB_ALERT_HSC_R_N")
	)
	(segment
		(start 223.46793 -220.127322)
		(end 223.46793 -218.31427)
		(width 0.15494)
		(layer "In5.Cu")
		(net "SMB_ALERT_HSC_R_N")
	)
	(segment
		(start 223.46031 -220.134942)
		(end 223.46793 -220.127322)
		(width 0.15494)
		(layer "In5.Cu")
		(net "SMB_ALERT_HSC_R_N")
	)
	(segment
		(start 227.240592 -251.773944)
		(end 227.240592 -229.806246)
		(width 0.15494)
		(layer "In5.Cu")
		(net "SMB_ALERT_HSC_R_N")
	)
	(segment
		(start 196.359272 -369.709192)
		(end 194.138296 -369.709192)
		(width 0.15494)
		(layer "In5.Cu")
		(net "SMB_ALERT_HSC_R_N")
	)
	(segment
		(start 194.415918 -410.696918)
		(end 195.931282 -410.696918)
		(width 0.15494)
		(layer "In5.Cu")
		(net "SMB_ALERT_HSC_R_N")
	)
	(segment
		(start 192.771522 -368.342418)
		(end 190.636652 -368.342418)
		(width 0.15494)
		(layer "In5.Cu")
		(net "SMB_ALERT_HSC_R_N")
	)
	(segment
		(start 223.1644 -223.8502)
		(end 223.46031 -223.55429)
		(width 0.15494)
		(layer "In5.Cu")
		(net "SMB_ALERT_HSC_R_N")
	)
	(segment
		(start 227.240592 -229.806246)
		(end 223.46793 -226.033584)
		(width 0.15494)
		(layer "In5.Cu")
		(net "SMB_ALERT_HSC_R_N")
	)
	(segment
		(start 223.46793 -218.31427)
		(end 223.7232 -218.059)
		(width 0.15494)
		(layer "In5.Cu")
		(net "SMB_ALERT_HSC_R_N")
	)
	(segment
		(start 189.645036 -372.566438)
		(end 186.455812 -375.755662)
		(width 0.15494)
		(layer "In5.Cu")
		(net "SMB_ALERT_HSC_R_N")
	)
	(segment
		(start 209.579972 -366.418876)
		(end 209.287618 -366.71123)
		(width 0.15494)
		(layer "In5.Cu")
		(net "SMB_ALERT_HSC_R_N")
	)
	(segment
		(start 194.138296 -369.709192)
		(end 192.771522 -368.342418)
		(width 0.15494)
		(layer "In5.Cu")
		(net "SMB_ALERT_HSC_R_N")
	)
	(segment
		(start 223.46793 -225.29673)
		(end 223.1644 -224.9932)
		(width 0.15494)
		(layer "In5.Cu")
		(net "SMB_ALERT_HSC_R_N")
	)
	(segment
		(start 186.455812 -402.736812)
		(end 194.415918 -410.696918)
		(width 0.15494)
		(layer "In5.Cu")
		(net "SMB_ALERT_HSC_R_N")
	)
	(segment
		(start 197.85965 -368.83721)
		(end 197.231254 -368.83721)
		(width 0.15494)
		(layer "In5.Cu")
		(net "SMB_ALERT_HSC_R_N")
	)
	(segment
		(start 186.455812 -375.755662)
		(end 186.455812 -402.736812)
		(width 0.15494)
		(layer "In5.Cu")
		(net "SMB_ALERT_HSC_R_N")
	)
	(segment
		(start 202.38847 -367.238788)
		(end 199.458072 -367.238788)
		(width 0.15494)
		(layer "In5.Cu")
		(net "SMB_ALERT_HSC_R_N")
	)
	(segment
		(start 202.916028 -366.71123)
		(end 202.38847 -367.238788)
		(width 0.15494)
		(layer "In5.Cu")
		(net "SMB_ALERT_HSC_R_N")
	)
	(segment
		(start 216.002616 -360.680508)
		(end 210.264248 -366.418876)
		(width 0.15494)
		(layer "In5.Cu")
		(net "SMB_ALERT_HSC_R_N")
	)
	(segment
		(start 235.507022 -345.832938)
		(end 227.298758 -354.041202)
		(width 0.15494)
		(layer "In5.Cu")
		(net "SMB_ALERT_HSC_R_N")
	)
	(segment
		(start 223.1644 -224.9932)
		(end 223.1644 -223.8502)
		(width 0.15494)
		(layer "In5.Cu")
		(net "SMB_ALERT_HSC_R_N")
	)
	(segment
		(start 209.287618 -366.71123)
		(end 202.916028 -366.71123)
		(width 0.15494)
		(layer "In5.Cu")
		(net "SMB_ALERT_HSC_R_N")
	)
	(segment
		(start 210.264248 -366.418876)
		(end 209.579972 -366.418876)
		(width 0.15494)
		(layer "In5.Cu")
		(net "SMB_ALERT_HSC_R_N")
	)
	(segment
		(start 189.645036 -369.334034)
		(end 189.645036 -372.566438)
		(width 0.15494)
		(layer "In5.Cu")
		(net "SMB_ALERT_HSC_R_N")
	)
	(segment
		(start 223.46793 -226.033584)
		(end 223.46793 -225.29673)
		(width 0.15494)
		(layer "In5.Cu")
		(net "SMB_ALERT_HSC_R_N")
	)
	(segment
		(start 199.458072 -367.238788)
		(end 197.85965 -368.83721)
		(width 0.15494)
		(layer "In5.Cu")
		(net "SMB_ALERT_HSC_R_N")
	)
	(segment
		(start 227.298758 -354.041202)
		(end 227.298758 -354.050854)
		(width 0.15494)
		(layer "In5.Cu")
		(net "SMB_ALERT_HSC_R_N")
	)
	(segment
		(start 227.298758 -354.050854)
		(end 220.669104 -360.680508)
		(width 0.15494)
		(layer "In5.Cu")
		(net "SMB_ALERT_HSC_R_N")
	)
	(segment
		(start 223.7232 -217.248994)
		(end 224.667826 -216.304368)
		(width 0.15494)
		(layer "In5.Cu")
		(net "SMB_ALERT_HSC_R_N")
	)
	(segment
		(start 223.7232 -218.059)
		(end 223.7232 -217.248994)
		(width 0.15494)
		(layer "In5.Cu")
		(net "SMB_ALERT_HSC_R_N")
	)
	(segment
		(start 197.231254 -368.83721)
		(end 196.359272 -369.709192)
		(width 0.15494)
		(layer "In5.Cu")
		(net "SMB_ALERT_HSC_R_N")
	)
	(segment
		(start 228.04755 -252.580902)
		(end 227.240592 -251.773944)
		(width 0.15494)
		(layer "In5.Cu")
		(net "SMB_ALERT_HSC_R_N")
	)
	(segment
		(start 223.46031 -223.55429)
		(end 223.46031 -220.134942)
		(width 0.15494)
		(layer "In5.Cu")
		(net "SMB_ALERT_HSC_R_N")
	)
	(segment
		(start 240.326672 -197.470776)
		(end 240.326672 -197.469252)
		(width 0.15494)
		(layer "In7.Cu")
		(net "SMB_ALERT_HSC_R_N")
	)
	(segment
		(start 225.0694 -215.902794)
		(end 225.0694 -213.6648)
		(width 0.0889)
		(layer "In7.Cu")
		(net "SMB_ALERT_HSC_R_N")
	)
	(segment
		(start 236.411516 -332.883256)
		(end 234.340146 -330.811886)
		(width 0.15494)
		(layer "In7.Cu")
		(net "SMB_ALERT_HSC_R_N")
	)
	(segment
		(start 234.81157 -205.99273)
		(end 234.81157 -203.544424)
		(width 0.15494)
		(layer "In7.Cu")
		(net "SMB_ALERT_HSC_R_N")
	)
	(segment
		(start 226.0092 -212.725)
		(end 226.0092 -211.377022)
		(width 0.15494)
		(layer "In7.Cu")
		(net "SMB_ALERT_HSC_R_N")
	)
	(segment
		(start 229.45471 -209.355182)
		(end 231.368092 -207.4418)
		(width 0.15494)
		(layer "In7.Cu")
		(net "SMB_ALERT_HSC_R_N")
	)
	(segment
		(start 234.340146 -258.873498)
		(end 228.04755 -252.580902)
		(width 0.15494)
		(layer "In7.Cu")
		(net "SMB_ALERT_HSC_R_N")
	)
	(segment
		(start 231.368092 -207.4418)
		(end 233.3625 -207.4418)
		(width 0.15494)
		(layer "In7.Cu")
		(net "SMB_ALERT_HSC_R_N")
	)
	(segment
		(start 225.594672 -210.962494)
		(end 225.594672 -210.14436)
		(width 0.15494)
		(layer "In7.Cu")
		(net "SMB_ALERT_HSC_R_N")
	)
	(segment
		(start 235.451904 -202.34402)
		(end 237.934754 -199.86117)
		(width 0.15494)
		(layer "In7.Cu")
		(net "SMB_ALERT_HSC_R_N")
	)
	(segment
		(start 225.0694 -213.6648)
		(end 226.0092 -212.725)
		(width 0.15494)
		(layer "In7.Cu")
		(net "SMB_ALERT_HSC_R_N")
	)
	(segment
		(start 240.6396 -186.400948)
		(end 241.592354 -185.448194)
		(width 0.15494)
		(layer "In7.Cu")
		(net "SMB_ALERT_HSC_R_N")
	)
	(segment
		(start 224.667826 -216.304368)
		(end 225.0694 -215.902794)
		(width 0.0889)
		(layer "In7.Cu")
		(net "SMB_ALERT_HSC_R_N")
	)
	(segment
		(start 237.936278 -199.86117)
		(end 240.326672 -197.470776)
		(width 0.15494)
		(layer "In7.Cu")
		(net "SMB_ALERT_HSC_R_N")
	)
	(segment
		(start 226.0092 -211.377022)
		(end 225.594672 -210.962494)
		(width 0.15494)
		(layer "In7.Cu")
		(net "SMB_ALERT_HSC_R_N")
	)
	(segment
		(start 240.326672 -197.469252)
		(end 240.6396 -197.156324)
		(width 0.15494)
		(layer "In7.Cu")
		(net "SMB_ALERT_HSC_R_N")
	)
	(segment
		(start 237.934754 -199.86117)
		(end 237.936278 -199.86117)
		(width 0.15494)
		(layer "In7.Cu")
		(net "SMB_ALERT_HSC_R_N")
	)
	(segment
		(start 225.594672 -210.14436)
		(end 226.38385 -209.355182)
		(width 0.15494)
		(layer "In7.Cu")
		(net "SMB_ALERT_HSC_R_N")
	)
	(segment
		(start 234.340146 -330.811886)
		(end 234.340146 -258.873498)
		(width 0.15494)
		(layer "In7.Cu")
		(net "SMB_ALERT_HSC_R_N")
	)
	(segment
		(start 233.3625 -207.4418)
		(end 234.81157 -205.99273)
		(width 0.15494)
		(layer "In7.Cu")
		(net "SMB_ALERT_HSC_R_N")
	)
	(segment
		(start 235.451904 -202.90409)
		(end 235.451904 -202.34402)
		(width 0.15494)
		(layer "In7.Cu")
		(net "SMB_ALERT_HSC_R_N")
	)
	(segment
		(start 240.6396 -197.156324)
		(end 240.6396 -186.400948)
		(width 0.15494)
		(layer "In7.Cu")
		(net "SMB_ALERT_HSC_R_N")
	)
	(segment
		(start 234.81157 -203.544424)
		(end 235.451904 -202.90409)
		(width 0.15494)
		(layer "In7.Cu")
		(net "SMB_ALERT_HSC_R_N")
	)
	(segment
		(start 226.38385 -209.355182)
		(end 229.45471 -209.355182)
		(width 0.15494)
		(layer "In7.Cu")
		(net "SMB_ALERT_HSC_R_N")
	)
	(segment
		(start 267.04925 -199.434196)
		(end 264.031476 -199.434196)
		(width 0.15494)
		(layer "In13.Cu")
		(net "SMB_ALERT_HSC_R_N")
	)
	(segment
		(start 321.896994 -213.1314)
		(end 319.967864 -211.20227)
		(width 0.15494)
		(layer "In13.Cu")
		(net "SMB_ALERT_HSC_R_N")
	)
	(segment
		(start 328.27214 -215.1634)
		(end 327.70699 -214.59825)
		(width 0.15494)
		(layer "In13.Cu")
		(net "SMB_ALERT_HSC_R_N")
	)
	(segment
		(start 333.043022 -218.828874)
		(end 333.043022 -218.209622)
		(width 0.15494)
		(layer "In13.Cu")
		(net "SMB_ALERT_HSC_R_N")
	)
	(segment
		(start 333.459328 -219.24518)
		(end 333.043022 -218.828874)
		(width 0.15494)
		(layer "In13.Cu")
		(net "SMB_ALERT_HSC_R_N")
	)
	(segment
		(start 260.274054 -197.739508)
		(end 256.84099 -194.306444)
		(width 0.15494)
		(layer "In13.Cu")
		(net "SMB_ALERT_HSC_R_N")
	)
	(segment
		(start 333.043022 -218.209622)
		(end 329.9968 -215.1634)
		(width 0.15494)
		(layer "In13.Cu")
		(net "SMB_ALERT_HSC_R_N")
	)
	(segment
		(start 338.036154 -219.24518)
		(end 333.459328 -219.24518)
		(width 0.15494)
		(layer "In13.Cu")
		(net "SMB_ALERT_HSC_R_N")
	)
	(segment
		(start 329.9968 -215.1634)
		(end 328.27214 -215.1634)
		(width 0.15494)
		(layer "In13.Cu")
		(net "SMB_ALERT_HSC_R_N")
	)
	(segment
		(start 245.94693 -185.448194)
		(end 241.592354 -185.448194)
		(width 0.15494)
		(layer "In13.Cu")
		(net "SMB_ALERT_HSC_R_N")
	)
	(segment
		(start 338.494116 -218.787218)
		(end 338.036154 -219.24518)
		(width 0.15494)
		(layer "In13.Cu")
		(net "SMB_ALERT_HSC_R_N")
	)
	(segment
		(start 256.84099 -193.470276)
		(end 254.864616 -191.493902)
		(width 0.15494)
		(layer "In13.Cu")
		(net "SMB_ALERT_HSC_R_N")
	)
	(segment
		(start 256.84099 -194.306444)
		(end 256.84099 -193.470276)
		(width 0.15494)
		(layer "In13.Cu")
		(net "SMB_ALERT_HSC_R_N")
	)
	(segment
		(start 246.603266 -186.10453)
		(end 245.94693 -185.448194)
		(width 0.15494)
		(layer "In13.Cu")
		(net "SMB_ALERT_HSC_R_N")
	)
	(segment
		(start 251.205492 -186.10453)
		(end 246.603266 -186.10453)
		(width 0.15494)
		(layer "In13.Cu")
		(net "SMB_ALERT_HSC_R_N")
	)
	(segment
		(start 264.031476 -199.434196)
		(end 262.336788 -197.739508)
		(width 0.15494)
		(layer "In13.Cu")
		(net "SMB_ALERT_HSC_R_N")
	)
	(segment
		(start 254.864616 -189.763654)
		(end 251.205492 -186.10453)
		(width 0.15494)
		(layer "In13.Cu")
		(net "SMB_ALERT_HSC_R_N")
	)
	(segment
		(start 327.70699 -214.59825)
		(end 327.70699 -214.14359)
		(width 0.15494)
		(layer "In13.Cu")
		(net "SMB_ALERT_HSC_R_N")
	)
	(segment
		(start 254.864616 -191.493902)
		(end 254.864616 -189.763654)
		(width 0.15494)
		(layer "In13.Cu")
		(net "SMB_ALERT_HSC_R_N")
	)
	(segment
		(start 326.6948 -213.1314)
		(end 321.896994 -213.1314)
		(width 0.15494)
		(layer "In13.Cu")
		(net "SMB_ALERT_HSC_R_N")
	)
	(segment
		(start 278.817324 -211.20227)
		(end 267.04925 -199.434196)
		(width 0.15494)
		(layer "In13.Cu")
		(net "SMB_ALERT_HSC_R_N")
	)
	(segment
		(start 319.967864 -211.20227)
		(end 278.817324 -211.20227)
		(width 0.15494)
		(layer "In13.Cu")
		(net "SMB_ALERT_HSC_R_N")
	)
	(segment
		(start 262.336788 -197.739508)
		(end 260.274054 -197.739508)
		(width 0.15494)
		(layer "In13.Cu")
		(net "SMB_ALERT_HSC_R_N")
	)
	(segment
		(start 327.70699 -214.14359)
		(end 326.6948 -213.1314)
		(width 0.15494)
		(layer "In13.Cu")
		(net "SMB_ALERT_HSC_R_N")
	)
	(segment
		(start 243.716302 -122.667268)
		(end 243.518944 -122.46991)
		(width 0.13208)
		(layer "F.Cu")
		(net "HP_NIC4_EN")
	)
	(segment
		(start 269.524226 -115.803934)
		(end 269.385542 -115.66525)
		(width 0.13208)
		(layer "F.Cu")
		(net "HP_NIC4_EN")
	)
	(segment
		(start 248.63171 -162.404044)
		(end 248.63171 -163.114736)
		(width 0.13208)
		(layer "F.Cu")
		(net "HP_NIC4_EN")
	)
	(segment
		(start 270.030702 -115.803934)
		(end 269.524226 -115.803934)
		(width 0.13208)
		(layer "F.Cu")
		(net "HP_NIC4_EN")
	)
	(segment
		(start 269.385542 -115.66525)
		(end 268.77899 -115.66525)
		(width 0.13208)
		(layer "F.Cu")
		(net "HP_NIC4_EN")
	)
	(segment
		(start 239.413288 -134.042404)
		(end 238.757968 -134.042404)
		(width 0.13208)
		(layer "F.Cu")
		(net "HP_NIC4_EN")
	)
	(segment
		(start 248.004838 -119.541036)
		(end 248.004838 -120.15343)
		(width 0.13208)
		(layer "F.Cu")
		(net "HP_NIC4_EN")
	)
	(segment
		(start 267.753592 -116.690648)
		(end 266.956032 -116.690648)
		(width 0.13208)
		(layer "F.Cu")
		(net "HP_NIC4_EN")
	)
	(segment
		(start 244.431058 -124.394722)
		(end 244.19179 -124.394722)
		(width 0.13208)
		(layer "F.Cu")
		(net "HP_NIC4_EN")
	)
	(segment
		(start 268.77899 -115.66525)
		(end 267.753592 -116.690648)
		(width 0.13208)
		(layer "F.Cu")
		(net "HP_NIC4_EN")
	)
	(segment
		(start 244.19179 -124.394722)
		(end 243.716302 -123.919234)
		(width 0.13208)
		(layer "F.Cu")
		(net "HP_NIC4_EN")
	)
	(segment
		(start 243.716302 -123.919234)
		(end 243.716302 -122.667268)
		(width 0.13208)
		(layer "F.Cu")
		(net "HP_NIC4_EN")
	)
	(segment
		(start 243.518944 -122.46991)
		(end 242.710462 -121.661428)
		(width 0.13208)
		(layer "F.Cu")
		(net "HP_NIC4_EN")
	)
	(via
		(at 248.004838 -120.15343)
		(size 0.508)
		(drill 0.254)
		(layers "F.Cu" "B.Cu")
		(net "HP_NIC4_EN")
	)
	(via
		(at 270.030702 -115.803934)
		(size 0.508)
		(drill 0.254)
		(layers "F.Cu" "B.Cu")
		(net "HP_NIC4_EN")
	)
	(via
		(at 238.757968 -134.042404)
		(size 0.508)
		(drill 0.254)
		(layers "F.Cu" "B.Cu")
		(net "HP_NIC4_EN")
	)
	(via
		(at 243.518944 -122.46991)
		(size 0.508)
		(drill 0.254)
		(layers "F.Cu" "B.Cu")
		(net "HP_NIC4_EN")
	)
	(via
		(at 248.63171 -163.114736)
		(size 0.508)
		(drill 0.254)
		(layers "F.Cu" "B.Cu")
		(net "HP_NIC4_EN")
	)
	(segment
		(start 241.8334 -124.155454)
		(end 243.518944 -122.46991)
		(width 0.15494)
		(layer "In5.Cu")
		(net "HP_NIC4_EN")
	)
	(segment
		(start 238.757968 -134.042404)
		(end 238.757968 -131.994656)
		(width 0.15494)
		(layer "In5.Cu")
		(net "HP_NIC4_EN")
	)
	(segment
		(start 241.3762 -129.376424)
		(end 241.3762 -128.017778)
		(width 0.15494)
		(layer "In5.Cu")
		(net "HP_NIC4_EN")
	)
	(segment
		(start 241.3762 -128.017778)
		(end 241.8334 -127.560578)
		(width 0.15494)
		(layer "In5.Cu")
		(net "HP_NIC4_EN")
	)
	(segment
		(start 238.757968 -131.994656)
		(end 241.3762 -129.376424)
		(width 0.15494)
		(layer "In5.Cu")
		(net "HP_NIC4_EN")
	)
	(segment
		(start 241.8334 -127.560578)
		(end 241.8334 -124.155454)
		(width 0.15494)
		(layer "In5.Cu")
		(net "HP_NIC4_EN")
	)
	(segment
		(start 238.757968 -134.042404)
		(end 238.757968 -134.10311)
		(width 0.15494)
		(layer "In7.Cu")
		(net "HP_NIC4_EN")
	)
	(segment
		(start 242.25885 -164.75837)
		(end 246.988076 -164.75837)
		(width 0.15494)
		(layer "In7.Cu")
		(net "HP_NIC4_EN")
	)
	(segment
		(start 238.352584 -145.819368)
		(end 238.352584 -155.251658)
		(width 0.15494)
		(layer "In7.Cu")
		(net "HP_NIC4_EN")
	)
	(segment
		(start 240.739676 -163.239196)
		(end 242.25885 -164.75837)
		(width 0.15494)
		(layer "In7.Cu")
		(net "HP_NIC4_EN")
	)
	(segment
		(start 238.757968 -134.10311)
		(end 239.304068 -134.64921)
		(width 0.15494)
		(layer "In7.Cu")
		(net "HP_NIC4_EN")
	)
	(segment
		(start 239.304068 -134.64921)
		(end 239.304068 -144.867884)
		(width 0.15494)
		(layer "In7.Cu")
		(net "HP_NIC4_EN")
	)
	(segment
		(start 239.304068 -144.867884)
		(end 238.352584 -145.819368)
		(width 0.15494)
		(layer "In7.Cu")
		(net "HP_NIC4_EN")
	)
	(segment
		(start 238.352584 -155.251658)
		(end 240.739676 -157.63875)
		(width 0.15494)
		(layer "In7.Cu")
		(net "HP_NIC4_EN")
	)
	(segment
		(start 246.988076 -164.75837)
		(end 248.63171 -163.114736)
		(width 0.15494)
		(layer "In7.Cu")
		(net "HP_NIC4_EN")
	)
	(segment
		(start 240.739676 -157.63875)
		(end 240.739676 -163.239196)
		(width 0.15494)
		(layer "In7.Cu")
		(net "HP_NIC4_EN")
	)
	(segment
		(start 248.004838 -120.15343)
		(end 249.008138 -119.15013)
		(width 0.15494)
		(layer "In13.Cu")
		(net "HP_NIC4_EN")
	)
	(segment
		(start 251.11964 -119.15013)
		(end 254.009906 -116.259864)
		(width 0.15494)
		(layer "In13.Cu")
		(net "HP_NIC4_EN")
	)
	(segment
		(start 254.009906 -116.259864)
		(end 268.252956 -116.259864)
		(width 0.15494)
		(layer "In13.Cu")
		(net "HP_NIC4_EN")
	)
	(segment
		(start 268.708886 -115.803934)
		(end 270.030702 -115.803934)
		(width 0.15494)
		(layer "In13.Cu")
		(net "HP_NIC4_EN")
	)
	(segment
		(start 244.491256 -119.316246)
		(end 247.167654 -119.316246)
		(width 0.15494)
		(layer "In13.Cu")
		(net "HP_NIC4_EN")
	)
	(segment
		(start 247.167654 -119.316246)
		(end 248.004838 -120.15343)
		(width 0.15494)
		(layer "In13.Cu")
		(net "HP_NIC4_EN")
	)
	(segment
		(start 244.2972 -119.510302)
		(end 244.491256 -119.316246)
		(width 0.15494)
		(layer "In13.Cu")
		(net "HP_NIC4_EN")
	)
	(segment
		(start 268.252956 -116.259864)
		(end 268.708886 -115.803934)
		(width 0.15494)
		(layer "In13.Cu")
		(net "HP_NIC4_EN")
	)
	(segment
		(start 243.518944 -122.46991)
		(end 244.2972 -121.691654)
		(width 0.15494)
		(layer "In13.Cu")
		(net "HP_NIC4_EN")
	)
	(segment
		(start 244.2972 -121.691654)
		(end 244.2972 -119.510302)
		(width 0.15494)
		(layer "In13.Cu")
		(net "HP_NIC4_EN")
	)
	(segment
		(start 249.008138 -119.15013)
		(end 251.11964 -119.15013)
		(width 0.15494)
		(layer "In13.Cu")
		(net "HP_NIC4_EN")
	)
	(segment
		(start 365.10595 -211.963)
		(end 364.49 -211.963)
		(width 0.13208)
		(layer "F.Cu")
		(net "PRSNT_SSD0_FPGA_R_N")
	)
	(via
		(at 344.17 -206.15148)
		(size 0.508)
		(drill 0.254)
		(layers "F.Cu" "B.Cu")
		(net "PRSNT_SSD0_FPGA_R_N")
	)
	(via
		(at 364.49 -211.963)
		(size 0.508)
		(drill 0.254)
		(layers "F.Cu" "B.Cu")
		(net "PRSNT_SSD0_FPGA_R_N")
	)
	(segment
		(start 344.297 -206.883)
		(end 344.297 -207.37195)
		(width 0.13208)
		(layer "B.Cu")
		(net "PRSNT_SSD0_FPGA_R_N")
	)
	(segment
		(start 344.17 -206.15148)
		(end 344.17 -206.756)
		(width 0.13208)
		(layer "B.Cu")
		(net "PRSNT_SSD0_FPGA_R_N")
	)
	(segment
		(start 344.17 -206.756)
		(end 344.297 -206.883)
		(width 0.13208)
		(layer "B.Cu")
		(net "PRSNT_SSD0_FPGA_R_N")
	)
	(segment
		(start 356.669848 -202.80884)
		(end 363.390434 -209.529426)
		(width 0.15494)
		(layer "In11.Cu")
		(net "PRSNT_SSD0_FPGA_R_N")
	)
	(segment
		(start 345.529916 -204.791564)
		(end 345.985592 -204.791564)
		(width 0.15494)
		(layer "In11.Cu")
		(net "PRSNT_SSD0_FPGA_R_N")
	)
	(segment
		(start 346.214446 -203.962254)
		(end 347.36786 -202.80884)
		(width 0.15494)
		(layer "In11.Cu")
		(net "PRSNT_SSD0_FPGA_R_N")
	)
	(segment
		(start 363.390434 -210.863434)
		(end 364.49 -211.963)
		(width 0.15494)
		(layer "In11.Cu")
		(net "PRSNT_SSD0_FPGA_R_N")
	)
	(segment
		(start 344.17 -206.15148)
		(end 345.529916 -204.791564)
		(width 0.15494)
		(layer "In11.Cu")
		(net "PRSNT_SSD0_FPGA_R_N")
	)
	(segment
		(start 347.36786 -202.80884)
		(end 356.669848 -202.80884)
		(width 0.15494)
		(layer "In11.Cu")
		(net "PRSNT_SSD0_FPGA_R_N")
	)
	(segment
		(start 345.985592 -204.791564)
		(end 346.214446 -204.56271)
		(width 0.15494)
		(layer "In11.Cu")
		(net "PRSNT_SSD0_FPGA_R_N")
	)
	(segment
		(start 346.214446 -204.56271)
		(end 346.214446 -203.962254)
		(width 0.15494)
		(layer "In11.Cu")
		(net "PRSNT_SSD0_FPGA_R_N")
	)
	(segment
		(start 363.390434 -209.529426)
		(end 363.390434 -210.863434)
		(width 0.15494)
		(layer "In11.Cu")
		(net "PRSNT_SSD0_FPGA_R_N")
	)
	(segment
		(start 146.400012 -244.298978)
		(end 147.641564 -244.298978)
		(width 0.13208)
		(layer "F.Cu")
		(net "PWR_EN_PEX_R")
	)
	(segment
		(start 362.77677 -254.724154)
		(end 362.29036 -255.210564)
		(width 0.13208)
		(layer "F.Cu")
		(net "PWR_EN_PEX_R")
	)
	(segment
		(start 360.539284 -248.206768)
		(end 361.174538 -248.842022)
		(width 0.13208)
		(layer "F.Cu")
		(net "PWR_EN_PEX_R")
	)
	(segment
		(start 99.76358 -219.565982)
		(end 99.75723 -219.559632)
		(width 0.13208)
		(layer "F.Cu")
		(net "PWR_EN_PEX_R")
	)
	(segment
		(start 12.005056 -233.590846)
		(end 17.972024 -236.06252)
		(width 0.13208)
		(layer "F.Cu")
		(net "PWR_EN_PEX_R")
	)
	(segment
		(start 363.664246 -255.894078)
		(end 363.664246 -259.971794)
		(width 0.13208)
		(layer "F.Cu")
		(net "PWR_EN_PEX_R")
	)
	(segment
		(start 361.174538 -249.820176)
		(end 362.56341 -251.209048)
		(width 0.13208)
		(layer "F.Cu")
		(net "PWR_EN_PEX_R")
	)
	(segment
		(start 302.82388 -258.935474)
		(end 305.2572 -258.935474)
		(width 0.13208)
		(layer "F.Cu")
		(net "PWR_EN_PEX_R")
	)
	(segment
		(start 99.619054 -221.018354)
		(end 97.19945 -221.018354)
		(width 0.13208)
		(layer "F.Cu")
		(net "PWR_EN_PEX_R")
	)
	(segment
		(start 99.76358 -220.544644)
		(end 99.76358 -220.873828)
		(width 0.13208)
		(layer "F.Cu")
		(net "PWR_EN_PEX_R")
	)
	(segment
		(start 362.980732 -255.210564)
		(end 363.664246 -255.894078)
		(width 0.13208)
		(layer "F.Cu")
		(net "PWR_EN_PEX_R")
	)
	(segment
		(start 259.537708 -243.540788)
		(end 261.733538 -245.736618)
		(width 0.13208)
		(layer "F.Cu")
		(net "PWR_EN_PEX_R")
	)
	(segment
		(start 261.733538 -245.736618)
		(end 298.928028 -245.736618)
		(width 0.13208)
		(layer "F.Cu")
		(net "PWR_EN_PEX_R")
	)
	(segment
		(start 455.330052 -251.37364)
		(end 455.330052 -252.098048)
		(width 0.13208)
		(layer "F.Cu")
		(net "PWR_EN_PEX_R")
	)
	(segment
		(start 362.29036 -261.34568)
		(end 362.29036 -261.814564)
		(width 0.13208)
		(layer "F.Cu")
		(net "PWR_EN_PEX_R")
	)
	(segment
		(start 24.852884 -279.498552)
		(end 24.852884 -302.603916)
		(width 0.13208)
		(layer "F.Cu")
		(net "PWR_EN_PEX_R")
	)
	(segment
		(start 130.090164 -261.814564)
		(end 130.770122 -261.814564)
		(width 0.13208)
		(layer "F.Cu")
		(net "PWR_EN_PEX_R")
	)
	(segment
		(start 20.0152 -274.660868)
		(end 24.852884 -279.498552)
		(width 0.13208)
		(layer "F.Cu")
		(net "PWR_EN_PEX_R")
	)
	(segment
		(start 19.080988 -308.375812)
		(end 16.44904 -308.375812)
		(width 0.13208)
		(layer "F.Cu")
		(net "PWR_EN_PEX_R")
	)
	(segment
		(start 99.76358 -220.873828)
		(end 99.619054 -221.018354)
		(width 0.13208)
		(layer "F.Cu")
		(net "PWR_EN_PEX_R")
	)
	(segment
		(start 20.0152 -246.3292)
		(end 20.0152 -274.660868)
		(width 0.13208)
		(layer "F.Cu")
		(net "PWR_EN_PEX_R")
	)
	(segment
		(start 452.216266 -252.467618)
		(end 451.902322 -252.781562)
		(width 0.13208)
		(layer "F.Cu")
		(net "PWR_EN_PEX_R")
	)
	(segment
		(start 362.29036 -261.814564)
		(end 362.798614 -261.814564)
		(width 0.13208)
		(layer "F.Cu")
		(net "PWR_EN_PEX_R")
	)
	(segment
		(start 363.859826 -252.108716)
		(end 363.859826 -254.385826)
		(width 0.13208)
		(layer "F.Cu")
		(net "PWR_EN_PEX_R")
	)
	(segment
		(start 363.664246 -259.971794)
		(end 362.29036 -261.34568)
		(width 0.13208)
		(layer "F.Cu")
		(net "PWR_EN_PEX_R")
	)
	(segment
		(start 361.174538 -248.842022)
		(end 361.174538 -249.820176)
		(width 0.13208)
		(layer "F.Cu")
		(net "PWR_EN_PEX_R")
	)
	(segment
		(start 15.068296 -215.320372)
		(end 15.887446 -215.320372)
		(width 0.10922)
		(layer "F.Cu")
		(net "PWR_EN_PEX_R")
	)
	(segment
		(start 245.368572 -311.550558)
		(end 244.386862 -310.568848)
		(width 0.13208)
		(layer "F.Cu")
		(net "PWR_EN_PEX_R")
	)
	(segment
		(start 231.966516 -324.779132)
		(end 244.373908 -324.779132)
		(width 0.13208)
		(layer "F.Cu")
		(net "PWR_EN_PEX_R")
	)
	(segment
		(start 230.905558 -313.111896)
		(end 231.098852 -313.30519)
		(width 0.13208)
		(layer "F.Cu")
		(net "PWR_EN_PEX_R")
	)
	(segment
		(start 364.505494 -263.521444)
		(end 366.638586 -263.521444)
		(width 0.13208)
		(layer "F.Cu")
		(net "PWR_EN_PEX_R")
	)
	(segment
		(start 459.576932 -311.511442)
		(end 458.757782 -310.692292)
		(width 0.13208)
		(layer "F.Cu")
		(net "PWR_EN_PEX_R")
	)
	(segment
		(start 300.92142 -247.73001)
		(end 300.92142 -257.033014)
		(width 0.13208)
		(layer "F.Cu")
		(net "PWR_EN_PEX_R")
	)
	(segment
		(start 231.098852 -313.30519)
		(end 231.098852 -323.911468)
		(width 0.13208)
		(layer "F.Cu")
		(net "PWR_EN_PEX_R")
	)
	(segment
		(start 455.330052 -252.098048)
		(end 454.960482 -252.467618)
		(width 0.13208)
		(layer "F.Cu")
		(net "PWR_EN_PEX_R")
	)
	(segment
		(start 148.187664 -245.74119)
		(end 147.853654 -246.0752)
		(width 0.13208)
		(layer "F.Cu")
		(net "PWR_EN_PEX_R")
	)
	(segment
		(start 148.187664 -244.845078)
		(end 148.187664 -245.74119)
		(width 0.13208)
		(layer "F.Cu")
		(net "PWR_EN_PEX_R")
	)
	(segment
		(start 231.098852 -323.911468)
		(end 231.966516 -324.779132)
		(width 0.13208)
		(layer "F.Cu")
		(net "PWR_EN_PEX_R")
	)
	(segment
		(start 230.905558 -313.111896)
		(end 230.905558 -313.023504)
		(width 0.13208)
		(layer "F.Cu")
		(net "PWR_EN_PEX_R")
	)
	(segment
		(start 454.960482 -252.467618)
		(end 452.216266 -252.467618)
		(width 0.13208)
		(layer "F.Cu")
		(net "PWR_EN_PEX_R")
	)
	(segment
		(start 229.270052 -311.387998)
		(end 228.955854 -311.387998)
		(width 0.13208)
		(layer "F.Cu")
		(net "PWR_EN_PEX_R")
	)
	(segment
		(start 147.641564 -244.298978)
		(end 148.187664 -244.845078)
		(width 0.13208)
		(layer "F.Cu")
		(net "PWR_EN_PEX_R")
	)
	(segment
		(start 363.521498 -254.724154)
		(end 362.77677 -254.724154)
		(width 0.13208)
		(layer "F.Cu")
		(net "PWR_EN_PEX_R")
	)
	(segment
		(start 24.852884 -302.603916)
		(end 19.080988 -308.375812)
		(width 0.13208)
		(layer "F.Cu")
		(net "PWR_EN_PEX_R")
	)
	(segment
		(start 101.289104 -220.544644)
		(end 99.76358 -220.544644)
		(width 0.13208)
		(layer "F.Cu")
		(net "PWR_EN_PEX_R")
	)
	(segment
		(start 14.574774 -309.017416)
		(end 13.839444 -308.282086)
		(width 0.13208)
		(layer "F.Cu")
		(net "PWR_EN_PEX_R")
	)
	(segment
		(start 258.570476 -243.540788)
		(end 259.537708 -243.540788)
		(width 0.13208)
		(layer "F.Cu")
		(net "PWR_EN_PEX_R")
	)
	(segment
		(start 362.29036 -255.210564)
		(end 362.980732 -255.210564)
		(width 0.13208)
		(layer "F.Cu")
		(net "PWR_EN_PEX_R")
	)
	(segment
		(start 362.960158 -251.209048)
		(end 363.859826 -252.108716)
		(width 0.13208)
		(layer "F.Cu")
		(net "PWR_EN_PEX_R")
	)
	(segment
		(start 130.090164 -255.210564)
		(end 130.73126 -255.210564)
		(width 0.13208)
		(layer "F.Cu")
		(net "PWR_EN_PEX_R")
	)
	(segment
		(start 244.373908 -324.779132)
		(end 246.939562 -322.213478)
		(width 0.13208)
		(layer "F.Cu")
		(net "PWR_EN_PEX_R")
	)
	(segment
		(start 363.859826 -254.385826)
		(end 363.521498 -254.724154)
		(width 0.13208)
		(layer "F.Cu")
		(net "PWR_EN_PEX_R")
	)
	(segment
		(start 15.887446 -215.320372)
		(end 16.649446 -216.082372)
		(width 0.10922)
		(layer "F.Cu")
		(net "PWR_EN_PEX_R")
	)
	(segment
		(start 246.939562 -312.530744)
		(end 245.959376 -311.550558)
		(width 0.13208)
		(layer "F.Cu")
		(net "PWR_EN_PEX_R")
	)
	(segment
		(start 17.972024 -236.06252)
		(end 21.780246 -239.870742)
		(width 0.13208)
		(layer "F.Cu")
		(net "PWR_EN_PEX_R")
	)
	(segment
		(start 21.780246 -244.564154)
		(end 20.0152 -246.3292)
		(width 0.13208)
		(layer "F.Cu")
		(net "PWR_EN_PEX_R")
	)
	(segment
		(start 136.53643 -246.0752)
		(end 134.740142 -244.278912)
		(width 0.13208)
		(layer "F.Cu")
		(net "PWR_EN_PEX_R")
	)
	(segment
		(start 230.905558 -313.023504)
		(end 229.270052 -311.387998)
		(width 0.13208)
		(layer "F.Cu")
		(net "PWR_EN_PEX_R")
	)
	(segment
		(start 99.76358 -220.544644)
		(end 99.76358 -219.565982)
		(width 0.13208)
		(layer "F.Cu")
		(net "PWR_EN_PEX_R")
	)
	(segment
		(start 300.92142 -257.033014)
		(end 302.82388 -258.935474)
		(width 0.13208)
		(layer "F.Cu")
		(net "PWR_EN_PEX_R")
	)
	(segment
		(start 147.853654 -246.0752)
		(end 136.53643 -246.0752)
		(width 0.13208)
		(layer "F.Cu")
		(net "PWR_EN_PEX_R")
	)
	(segment
		(start 460.116428 -311.511442)
		(end 459.576932 -311.511442)
		(width 0.13208)
		(layer "F.Cu")
		(net "PWR_EN_PEX_R")
	)
	(segment
		(start 228.955854 -311.387998)
		(end 228.136704 -310.568848)
		(width 0.13208)
		(layer "F.Cu")
		(net "PWR_EN_PEX_R")
	)
	(segment
		(start 15.807436 -309.017416)
		(end 14.574774 -309.017416)
		(width 0.13208)
		(layer "F.Cu")
		(net "PWR_EN_PEX_R")
	)
	(segment
		(start 245.959376 -311.550558)
		(end 245.368572 -311.550558)
		(width 0.13208)
		(layer "F.Cu")
		(net "PWR_EN_PEX_R")
	)
	(segment
		(start 246.939562 -322.213478)
		(end 246.939562 -312.530744)
		(width 0.13208)
		(layer "F.Cu")
		(net "PWR_EN_PEX_R")
	)
	(segment
		(start 362.798614 -261.814564)
		(end 364.505494 -263.521444)
		(width 0.13208)
		(layer "F.Cu")
		(net "PWR_EN_PEX_R")
	)
	(segment
		(start 362.56341 -251.209048)
		(end 362.960158 -251.209048)
		(width 0.13208)
		(layer "F.Cu")
		(net "PWR_EN_PEX_R")
	)
	(segment
		(start 298.928028 -245.736618)
		(end 300.92142 -247.73001)
		(width 0.13208)
		(layer "F.Cu")
		(net "PWR_EN_PEX_R")
	)
	(segment
		(start 21.780246 -239.870742)
		(end 21.780246 -244.564154)
		(width 0.13208)
		(layer "F.Cu")
		(net "PWR_EN_PEX_R")
	)
	(segment
		(start 16.44904 -308.375812)
		(end 15.807436 -309.017416)
		(width 0.13208)
		(layer "F.Cu")
		(net "PWR_EN_PEX_R")
	)
	(via
		(at 127.798576 -243.315236)
		(size 0.508)
		(drill 0.254)
		(layers "F.Cu" "B.Cu")
		(net "PWR_EN_PEX_R")
	)
	(via
		(at 130.73126 -255.210564)
		(size 0.508)
		(drill 0.254)
		(layers "F.Cu" "B.Cu")
		(net "PWR_EN_PEX_R")
	)
	(via
		(at 130.770122 -261.814564)
		(size 0.508)
		(drill 0.254)
		(layers "F.Cu" "B.Cu")
		(net "PWR_EN_PEX_R")
	)
	(via
		(at 451.902322 -252.781562)
		(size 0.508)
		(drill 0.254)
		(layers "F.Cu" "B.Cu")
		(net "PWR_EN_PEX_R")
	)
	(via
		(at 97.19945 -221.018354)
		(size 0.508)
		(drill 0.254)
		(layers "F.Cu" "B.Cu")
		(net "PWR_EN_PEX_R")
	)
	(via
		(at 16.649446 -216.082372)
		(size 0.508)
		(drill 0.254)
		(layers "F.Cu" "B.Cu")
		(net "PWR_EN_PEX_R")
	)
	(via
		(at 12.005056 -233.590846)
		(size 0.508)
		(drill 0.254)
		(layers "F.Cu" "B.Cu")
		(net "PWR_EN_PEX_R")
	)
	(via
		(at 360.539284 -248.206768)
		(size 0.508)
		(drill 0.254)
		(layers "F.Cu" "B.Cu")
		(net "PWR_EN_PEX_R")
	)
	(via
		(at 305.2572 -258.935474)
		(size 0.508)
		(drill 0.254)
		(layers "F.Cu" "B.Cu")
		(net "PWR_EN_PEX_R")
	)
	(via
		(at 460.116428 -311.511442)
		(size 0.508)
		(drill 0.254)
		(layers "F.Cu" "B.Cu")
		(net "PWR_EN_PEX_R")
	)
	(via
		(at 134.740142 -244.278912)
		(size 0.508)
		(drill 0.254)
		(layers "F.Cu" "B.Cu")
		(net "PWR_EN_PEX_R")
	)
	(via
		(at 230.905558 -313.111896)
		(size 0.508)
		(drill 0.254)
		(layers "F.Cu" "B.Cu")
		(net "PWR_EN_PEX_R")
	)
	(via
		(at 231.82326 -252.5649)
		(size 0.508)
		(drill 0.254)
		(layers "F.Cu" "B.Cu")
		(net "PWR_EN_PEX_R")
	)
	(segment
		(start 359.9053 -247.572784)
		(end 344.21572 -247.572784)
		(width 0.13208)
		(layer "B.Cu")
		(net "PWR_EN_PEX_R")
	)
	(segment
		(start 307.810408 -252.638814)
		(end 307.792628 -252.638814)
		(width 0.13208)
		(layer "B.Cu")
		(net "PWR_EN_PEX_R")
	)
	(segment
		(start 303.99863 -257.761232)
		(end 305.172872 -258.935474)
		(width 0.13208)
		(layer "B.Cu")
		(net "PWR_EN_PEX_R")
	)
	(segment
		(start 360.539284 -248.206768)
		(end 359.9053 -247.572784)
		(width 0.13208)
		(layer "B.Cu")
		(net "PWR_EN_PEX_R")
	)
	(segment
		(start 303.99863 -257.26009)
		(end 303.99863 -257.761232)
		(width 0.13208)
		(layer "B.Cu")
		(net "PWR_EN_PEX_R")
	)
	(segment
		(start 134.740142 -244.278912)
		(end 128.762252 -244.278912)
		(width 0.13208)
		(layer "B.Cu")
		(net "PWR_EN_PEX_R")
	)
	(segment
		(start 303.98593 -256.445512)
		(end 303.98593 -257.24739)
		(width 0.13208)
		(layer "B.Cu")
		(net "PWR_EN_PEX_R")
	)
	(segment
		(start 303.98593 -257.24739)
		(end 303.99863 -257.26009)
		(width 0.13208)
		(layer "B.Cu")
		(net "PWR_EN_PEX_R")
	)
	(segment
		(start 128.762252 -244.278912)
		(end 127.798576 -243.315236)
		(width 0.13208)
		(layer "B.Cu")
		(net "PWR_EN_PEX_R")
	)
	(segment
		(start 339.303106 -252.485398)
		(end 307.963824 -252.485398)
		(width 0.13208)
		(layer "B.Cu")
		(net "PWR_EN_PEX_R")
	)
	(segment
		(start 307.792628 -252.638814)
		(end 303.98593 -256.445512)
		(width 0.13208)
		(layer "B.Cu")
		(net "PWR_EN_PEX_R")
	)
	(segment
		(start 307.963824 -252.485398)
		(end 307.810408 -252.638814)
		(width 0.13208)
		(layer "B.Cu")
		(net "PWR_EN_PEX_R")
	)
	(segment
		(start 305.172872 -258.935474)
		(end 305.2572 -258.935474)
		(width 0.13208)
		(layer "B.Cu")
		(net "PWR_EN_PEX_R")
	)
	(segment
		(start 344.21572 -247.572784)
		(end 339.303106 -252.485398)
		(width 0.13208)
		(layer "B.Cu")
		(net "PWR_EN_PEX_R")
	)
	(segment
		(start 233.26979 -310.157368)
		(end 233.26979 -281.753056)
		(width 0.15494)
		(layer "In5.Cu")
		(net "PWR_EN_PEX_R")
	)
	(segment
		(start 232.259124 -254.869442)
		(end 231.82326 -254.433578)
		(width 0.15494)
		(layer "In5.Cu")
		(net "PWR_EN_PEX_R")
	)
	(segment
		(start 232.259124 -280.74239)
		(end 232.259124 -254.869442)
		(width 0.15494)
		(layer "In5.Cu")
		(net "PWR_EN_PEX_R")
	)
	(segment
		(start 127.798576 -243.315236)
		(end 131.21513 -246.73179)
		(width 0.15494)
		(layer "In5.Cu")
		(net "PWR_EN_PEX_R")
	)
	(segment
		(start 130.73126 -255.210564)
		(end 130.73126 -257.057398)
		(width 0.15494)
		(layer "In5.Cu")
		(net "PWR_EN_PEX_R")
	)
	(segment
		(start 130.095498 -257.69316)
		(end 130.095498 -261.13994)
		(width 0.15494)
		(layer "In5.Cu")
		(net "PWR_EN_PEX_R")
	)
	(segment
		(start 231.82326 -254.433578)
		(end 231.82326 -252.5649)
		(width 0.15494)
		(layer "In5.Cu")
		(net "PWR_EN_PEX_R")
	)
	(segment
		(start 230.905558 -312.5216)
		(end 233.26979 -310.157368)
		(width 0.15494)
		(layer "In5.Cu")
		(net "PWR_EN_PEX_R")
	)
	(segment
		(start 230.905558 -313.111896)
		(end 230.905558 -312.5216)
		(width 0.15494)
		(layer "In5.Cu")
		(net "PWR_EN_PEX_R")
	)
	(segment
		(start 233.26979 -281.753056)
		(end 232.259124 -280.74239)
		(width 0.15494)
		(layer "In5.Cu")
		(net "PWR_EN_PEX_R")
	)
	(segment
		(start 131.21513 -246.73179)
		(end 131.21513 -254.726694)
		(width 0.15494)
		(layer "In5.Cu")
		(net "PWR_EN_PEX_R")
	)
	(segment
		(start 130.095498 -261.13994)
		(end 130.770122 -261.814564)
		(width 0.15494)
		(layer "In5.Cu")
		(net "PWR_EN_PEX_R")
	)
	(segment
		(start 131.21513 -254.726694)
		(end 130.73126 -255.210564)
		(width 0.15494)
		(layer "In5.Cu")
		(net "PWR_EN_PEX_R")
	)
	(segment
		(start 130.73126 -257.057398)
		(end 130.095498 -257.69316)
		(width 0.15494)
		(layer "In5.Cu")
		(net "PWR_EN_PEX_R")
	)
	(segment
		(start 384.535934 -248.531126)
		(end 383.43586 -249.6312)
		(width 0.15494)
		(layer "In13.Cu")
		(net "PWR_EN_PEX_R")
	)
	(segment
		(start 371.244876 -248.308622)
		(end 370.154454 -247.2182)
		(width 0.15494)
		(layer "In13.Cu")
		(net "PWR_EN_PEX_R")
	)
	(segment
		(start 371.849142 -249.6312)
		(end 371.244876 -249.026934)
		(width 0.15494)
		(layer "In13.Cu")
		(net "PWR_EN_PEX_R")
	)
	(segment
		(start 253.099316 -255.18237)
		(end 270.31315 -255.18237)
		(width 0.15494)
		(layer "In13.Cu")
		(net "PWR_EN_PEX_R")
	)
	(segment
		(start 451.902322 -252.781562)
		(end 451.69328 -252.781562)
		(width 0.15494)
		(layer "In13.Cu")
		(net "PWR_EN_PEX_R")
	)
	(segment
		(start 300.48962 -258.935474)
		(end 305.2572 -258.935474)
		(width 0.15494)
		(layer "In13.Cu")
		(net "PWR_EN_PEX_R")
	)
	(segment
		(start 460.116428 -311.511442)
		(end 460.163164 -311.511442)
		(width 0.15494)
		(layer "In13.Cu")
		(net "PWR_EN_PEX_R")
	)
	(segment
		(start 453.35571 -254.23495)
		(end 451.902322 -252.781562)
		(width 0.15494)
		(layer "In13.Cu")
		(net "PWR_EN_PEX_R")
	)
	(segment
		(start 251.739146 -253.8222)
		(end 253.099316 -255.18237)
		(width 0.15494)
		(layer "In13.Cu")
		(net "PWR_EN_PEX_R")
	)
	(segment
		(start 448.807078 -250.302522)
		(end 444.669164 -246.164608)
		(width 0.15494)
		(layer "In13.Cu")
		(net "PWR_EN_PEX_R")
	)
	(segment
		(start 460.6925 -310.982106)
		(end 460.6925 -310.91886)
		(width 0.15494)
		(layer "In13.Cu")
		(net "PWR_EN_PEX_R")
	)
	(segment
		(start 140.283946 -242.8494)
		(end 142.214346 -244.7798)
		(width 0.15494)
		(layer "In13.Cu")
		(net "PWR_EN_PEX_R")
	)
	(segment
		(start 460.6925 -310.91886)
		(end 462.026254 -309.585106)
		(width 0.15494)
		(layer "In13.Cu")
		(net "PWR_EN_PEX_R")
	)
	(segment
		(start 135.69569 -243.315236)
		(end 136.161526 -242.8494)
		(width 0.15494)
		(layer "In13.Cu")
		(net "PWR_EN_PEX_R")
	)
	(segment
		(start 383.43586 -249.6312)
		(end 371.849142 -249.6312)
		(width 0.15494)
		(layer "In13.Cu")
		(net "PWR_EN_PEX_R")
	)
	(segment
		(start 395.646148 -246.164608)
		(end 394.833856 -245.352316)
		(width 0.15494)
		(layer "In13.Cu")
		(net "PWR_EN_PEX_R")
	)
	(segment
		(start 463.2706 -272.9992)
		(end 463.2706 -260.223)
		(width 0.15494)
		(layer "In13.Cu")
		(net "PWR_EN_PEX_R")
	)
	(segment
		(start 146.614388 -243.529612)
		(end 148.838412 -243.529612)
		(width 0.15494)
		(layer "In13.Cu")
		(net "PWR_EN_PEX_R")
	)
	(segment
		(start 371.244876 -249.026934)
		(end 371.244876 -248.308622)
		(width 0.15494)
		(layer "In13.Cu")
		(net "PWR_EN_PEX_R")
	)
	(segment
		(start 465.4042 -283.93517)
		(end 462.736438 -281.267408)
		(width 0.15494)
		(layer "In13.Cu")
		(net "PWR_EN_PEX_R")
	)
	(segment
		(start 231.82326 -252.5649)
		(end 233.08056 -253.8222)
		(width 0.15494)
		(layer "In13.Cu")
		(net "PWR_EN_PEX_R")
	)
	(segment
		(start 451.216014 -253.258828)
		(end 449.973954 -253.258828)
		(width 0.15494)
		(layer "In13.Cu")
		(net "PWR_EN_PEX_R")
	)
	(segment
		(start 462.026254 -309.585106)
		(end 463.956908 -309.585106)
		(width 0.15494)
		(layer "In13.Cu")
		(net "PWR_EN_PEX_R")
	)
	(segment
		(start 127.798576 -243.315236)
		(end 135.69569 -243.315236)
		(width 0.15494)
		(layer "In13.Cu")
		(net "PWR_EN_PEX_R")
	)
	(segment
		(start 270.31315 -255.18237)
		(end 270.755618 -255.624838)
		(width 0.15494)
		(layer "In13.Cu")
		(net "PWR_EN_PEX_R")
	)
	(segment
		(start 136.161526 -242.8494)
		(end 140.283946 -242.8494)
		(width 0.15494)
		(layer "In13.Cu")
		(net "PWR_EN_PEX_R")
	)
	(segment
		(start 228.938328 -251.9934)
		(end 231.25176 -251.9934)
		(width 0.15494)
		(layer "In13.Cu")
		(net "PWR_EN_PEX_R")
	)
	(segment
		(start 462.736438 -281.267408)
		(end 462.736438 -273.533362)
		(width 0.15494)
		(layer "In13.Cu")
		(net "PWR_EN_PEX_R")
	)
	(segment
		(start 231.25176 -251.9934)
		(end 231.82326 -252.5649)
		(width 0.15494)
		(layer "In13.Cu")
		(net "PWR_EN_PEX_R")
	)
	(segment
		(start 142.214346 -244.7798)
		(end 145.3642 -244.7798)
		(width 0.15494)
		(layer "In13.Cu")
		(net "PWR_EN_PEX_R")
	)
	(segment
		(start 444.669164 -246.164608)
		(end 395.646148 -246.164608)
		(width 0.15494)
		(layer "In13.Cu")
		(net "PWR_EN_PEX_R")
	)
	(segment
		(start 448.807078 -252.091952)
		(end 448.807078 -250.302522)
		(width 0.15494)
		(layer "In13.Cu")
		(net "PWR_EN_PEX_R")
	)
	(segment
		(start 150.10384 -244.79504)
		(end 172.897546 -244.79504)
		(width 0.15494)
		(layer "In13.Cu")
		(net "PWR_EN_PEX_R")
	)
	(segment
		(start 180.400706 -252.2982)
		(end 188.6712 -252.2982)
		(width 0.15494)
		(layer "In13.Cu")
		(net "PWR_EN_PEX_R")
	)
	(segment
		(start 188.6712 -252.2982)
		(end 188.74486 -252.22454)
		(width 0.15494)
		(layer "In13.Cu")
		(net "PWR_EN_PEX_R")
	)
	(segment
		(start 389.93318 -245.352316)
		(end 389.176514 -244.59565)
		(width 0.15494)
		(layer "In13.Cu")
		(net "PWR_EN_PEX_R")
	)
	(segment
		(start 457.28255 -254.23495)
		(end 453.35571 -254.23495)
		(width 0.15494)
		(layer "In13.Cu")
		(net "PWR_EN_PEX_R")
	)
	(segment
		(start 465.4042 -308.137814)
		(end 465.4042 -283.93517)
		(width 0.15494)
		(layer "In13.Cu")
		(net "PWR_EN_PEX_R")
	)
	(segment
		(start 188.74486 -252.22454)
		(end 188.748416 -252.22454)
		(width 0.15494)
		(layer "In13.Cu")
		(net "PWR_EN_PEX_R")
	)
	(segment
		(start 463.2706 -260.223)
		(end 457.28255 -254.23495)
		(width 0.15494)
		(layer "In13.Cu")
		(net "PWR_EN_PEX_R")
	)
	(segment
		(start 385.903216 -246.023638)
		(end 384.535934 -247.39092)
		(width 0.15494)
		(layer "In13.Cu")
		(net "PWR_EN_PEX_R")
	)
	(segment
		(start 386.679186 -244.59565)
		(end 385.903216 -245.37162)
		(width 0.15494)
		(layer "In13.Cu")
		(net "PWR_EN_PEX_R")
	)
	(segment
		(start 394.833856 -245.352316)
		(end 389.93318 -245.352316)
		(width 0.15494)
		(layer "In13.Cu")
		(net "PWR_EN_PEX_R")
	)
	(segment
		(start 462.736438 -273.533362)
		(end 463.2706 -272.9992)
		(width 0.15494)
		(layer "In13.Cu")
		(net "PWR_EN_PEX_R")
	)
	(segment
		(start 172.897546 -244.79504)
		(end 180.400706 -252.2982)
		(width 0.15494)
		(layer "In13.Cu")
		(net "PWR_EN_PEX_R")
	)
	(segment
		(start 384.535934 -247.39092)
		(end 384.535934 -248.531126)
		(width 0.15494)
		(layer "In13.Cu")
		(net "PWR_EN_PEX_R")
	)
	(segment
		(start 189.990476 -250.98248)
		(end 227.927408 -250.98248)
		(width 0.15494)
		(layer "In13.Cu")
		(net "PWR_EN_PEX_R")
	)
	(segment
		(start 361.527852 -247.2182)
		(end 360.539284 -248.206768)
		(width 0.15494)
		(layer "In13.Cu")
		(net "PWR_EN_PEX_R")
	)
	(segment
		(start 145.3642 -244.7798)
		(end 146.614388 -243.529612)
		(width 0.15494)
		(layer "In13.Cu")
		(net "PWR_EN_PEX_R")
	)
	(segment
		(start 148.838412 -243.529612)
		(end 150.10384 -244.79504)
		(width 0.15494)
		(layer "In13.Cu")
		(net "PWR_EN_PEX_R")
	)
	(segment
		(start 385.903216 -245.37162)
		(end 385.903216 -246.023638)
		(width 0.15494)
		(layer "In13.Cu")
		(net "PWR_EN_PEX_R")
	)
	(segment
		(start 389.176514 -244.59565)
		(end 386.679186 -244.59565)
		(width 0.15494)
		(layer "In13.Cu")
		(net "PWR_EN_PEX_R")
	)
	(segment
		(start 297.178984 -255.624838)
		(end 300.48962 -258.935474)
		(width 0.15494)
		(layer "In13.Cu")
		(net "PWR_EN_PEX_R")
	)
	(segment
		(start 188.748416 -252.22454)
		(end 189.990476 -250.98248)
		(width 0.15494)
		(layer "In13.Cu")
		(net "PWR_EN_PEX_R")
	)
	(segment
		(start 451.69328 -252.781562)
		(end 451.216014 -253.258828)
		(width 0.15494)
		(layer "In13.Cu")
		(net "PWR_EN_PEX_R")
	)
	(segment
		(start 463.956908 -309.585106)
		(end 465.4042 -308.137814)
		(width 0.15494)
		(layer "In13.Cu")
		(net "PWR_EN_PEX_R")
	)
	(segment
		(start 227.927408 -250.98248)
		(end 228.938328 -251.9934)
		(width 0.15494)
		(layer "In13.Cu")
		(net "PWR_EN_PEX_R")
	)
	(segment
		(start 270.755618 -255.624838)
		(end 297.178984 -255.624838)
		(width 0.15494)
		(layer "In13.Cu")
		(net "PWR_EN_PEX_R")
	)
	(segment
		(start 460.163164 -311.511442)
		(end 460.6925 -310.982106)
		(width 0.15494)
		(layer "In13.Cu")
		(net "PWR_EN_PEX_R")
	)
	(segment
		(start 233.08056 -253.8222)
		(end 251.739146 -253.8222)
		(width 0.15494)
		(layer "In13.Cu")
		(net "PWR_EN_PEX_R")
	)
	(segment
		(start 370.154454 -247.2182)
		(end 361.527852 -247.2182)
		(width 0.15494)
		(layer "In13.Cu")
		(net "PWR_EN_PEX_R")
	)
	(segment
		(start 449.973954 -253.258828)
		(end 448.807078 -252.091952)
		(width 0.15494)
		(layer "In13.Cu")
		(net "PWR_EN_PEX_R")
	)
	(segment
		(start 98.934524 -212.747098)
		(end 96.875092 -214.80653)
		(width 0.15494)
		(layer "In15.Cu")
		(net "PWR_EN_PEX_R")
	)
	(segment
		(start 17.552924 -224.00895)
		(end 22.385274 -219.1766)
		(width 0.15494)
		(layer "In15.Cu")
		(net "PWR_EN_PEX_R")
	)
	(segment
		(start 94.943168 -218.991688)
		(end 95.648272 -219.696792)
		(width 0.15494)
		(layer "In15.Cu")
		(net "PWR_EN_PEX_R")
	)
	(segment
		(start 11.721084 -233.306874)
		(end 12.005056 -233.590846)
		(width 0.15494)
		(layer "In15.Cu")
		(net "PWR_EN_PEX_R")
	)
	(segment
		(start 19.051016 -231.701594)
		(end 19.041618 -231.692196)
		(width 0.15494)
		(layer "In15.Cu")
		(net "PWR_EN_PEX_R")
	)
	(segment
		(start 110.613952 -232.970832)
		(end 110.613952 -213.115906)
		(width 0.15494)
		(layer "In15.Cu")
		(net "PWR_EN_PEX_R")
	)
	(segment
		(start 19.05254 -232.56113)
		(end 19.05254 -231.716834)
		(width 0.15494)
		(layer "In15.Cu")
		(net "PWR_EN_PEX_R")
	)
	(segment
		(start 127.798576 -243.315236)
		(end 120.958356 -243.315236)
		(width 0.15494)
		(layer "In15.Cu")
		(net "PWR_EN_PEX_R")
	)
	(segment
		(start 31.2293 -219.1766)
		(end 31.28518 -219.12072)
		(width 0.15494)
		(layer "In15.Cu")
		(net "PWR_EN_PEX_R")
	)
	(segment
		(start 100.691188 -212.747098)
		(end 98.934524 -212.747098)
		(width 0.15494)
		(layer "In15.Cu")
		(net "PWR_EN_PEX_R")
	)
	(segment
		(start 96.875092 -214.80653)
		(end 96.875092 -220.693996)
		(width 0.15494)
		(layer "In15.Cu")
		(net "PWR_EN_PEX_R")
	)
	(segment
		(start 100.692712 -212.745574)
		(end 100.691188 -212.747098)
		(width 0.15494)
		(layer "In15.Cu")
		(net "PWR_EN_PEX_R")
	)
	(segment
		(start 13.519658 -232.829862)
		(end 18.783808 -232.829862)
		(width 0.15494)
		(layer "In15.Cu")
		(net "PWR_EN_PEX_R")
	)
	(segment
		(start 12.758674 -233.590846)
		(end 13.519658 -232.829862)
		(width 0.15494)
		(layer "In15.Cu")
		(net "PWR_EN_PEX_R")
	)
	(segment
		(start 12.005056 -233.590846)
		(end 12.758674 -233.590846)
		(width 0.15494)
		(layer "In15.Cu")
		(net "PWR_EN_PEX_R")
	)
	(segment
		(start 95.648272 -220.57233)
		(end 96.094296 -221.018354)
		(width 0.15494)
		(layer "In15.Cu")
		(net "PWR_EN_PEX_R")
	)
	(segment
		(start 19.051016 -231.71531)
		(end 19.051016 -231.701594)
		(width 0.15494)
		(layer "In15.Cu")
		(net "PWR_EN_PEX_R")
	)
	(segment
		(start 110.24362 -212.745574)
		(end 100.692712 -212.745574)
		(width 0.15494)
		(layer "In15.Cu")
		(net "PWR_EN_PEX_R")
	)
	(segment
		(start 31.42869 -218.991688)
		(end 94.943168 -218.991688)
		(width 0.15494)
		(layer "In15.Cu")
		(net "PWR_EN_PEX_R")
	)
	(segment
		(start 96.875092 -220.693996)
		(end 97.19945 -221.018354)
		(width 0.15494)
		(layer "In15.Cu")
		(net "PWR_EN_PEX_R")
	)
	(segment
		(start 96.094296 -221.018354)
		(end 97.19945 -221.018354)
		(width 0.15494)
		(layer "In15.Cu")
		(net "PWR_EN_PEX_R")
	)
	(segment
		(start 19.041618 -231.692196)
		(end 19.041618 -231.690418)
		(width 0.15494)
		(layer "In15.Cu")
		(net "PWR_EN_PEX_R")
	)
	(segment
		(start 120.958356 -243.315236)
		(end 110.613952 -232.970832)
		(width 0.15494)
		(layer "In15.Cu")
		(net "PWR_EN_PEX_R")
	)
	(segment
		(start 11.721084 -217.924126)
		(end 11.721084 -233.306874)
		(width 0.15494)
		(layer "In15.Cu")
		(net "PWR_EN_PEX_R")
	)
	(segment
		(start 13.562838 -216.082372)
		(end 11.721084 -217.924126)
		(width 0.15494)
		(layer "In15.Cu")
		(net "PWR_EN_PEX_R")
	)
	(segment
		(start 19.041618 -231.690418)
		(end 17.552924 -230.201724)
		(width 0.15494)
		(layer "In15.Cu")
		(net "PWR_EN_PEX_R")
	)
	(segment
		(start 31.28518 -219.12072)
		(end 31.299658 -219.12072)
		(width 0.15494)
		(layer "In15.Cu")
		(net "PWR_EN_PEX_R")
	)
	(segment
		(start 18.783808 -232.829862)
		(end 19.05254 -232.56113)
		(width 0.15494)
		(layer "In15.Cu")
		(net "PWR_EN_PEX_R")
	)
	(segment
		(start 31.299658 -219.12072)
		(end 31.42869 -218.991688)
		(width 0.15494)
		(layer "In15.Cu")
		(net "PWR_EN_PEX_R")
	)
	(segment
		(start 110.613952 -213.115906)
		(end 110.24362 -212.745574)
		(width 0.15494)
		(layer "In15.Cu")
		(net "PWR_EN_PEX_R")
	)
	(segment
		(start 17.552924 -230.201724)
		(end 17.552924 -224.00895)
		(width 0.15494)
		(layer "In15.Cu")
		(net "PWR_EN_PEX_R")
	)
	(segment
		(start 16.649446 -216.082372)
		(end 13.562838 -216.082372)
		(width 0.15494)
		(layer "In15.Cu")
		(net "PWR_EN_PEX_R")
	)
	(segment
		(start 22.385274 -219.1766)
		(end 31.2293 -219.1766)
		(width 0.15494)
		(layer "In15.Cu")
		(net "PWR_EN_PEX_R")
	)
	(segment
		(start 95.648272 -219.696792)
		(end 95.648272 -220.57233)
		(width 0.15494)
		(layer "In15.Cu")
		(net "PWR_EN_PEX_R")
	)
	(segment
		(start 19.05254 -231.716834)
		(end 19.051016 -231.71531)
		(width 0.15494)
		(layer "In15.Cu")
		(net "PWR_EN_PEX_R")
	)
	(segment
		(start 435.5338 -299.084746)
		(end 435.5338 -300.5074)
		(width 0.13208)
		(layer "F.Cu")
		(net "RST_PEX3_S1_PERST_R_N")
	)
	(segment
		(start 435.5338 -300.5074)
		(end 436.0291 -301.0027)
		(width 0.13208)
		(layer "F.Cu")
		(net "RST_PEX3_S1_PERST_R_N")
	)
	(segment
		(start 435.162706 -298.713652)
		(end 435.5338 -299.084746)
		(width 0.13208)
		(layer "F.Cu")
		(net "RST_PEX3_S1_PERST_R_N")
	)
	(segment
		(start 420.774876 -305.874928)
		(end 421.249856 -306.349908)
		(width 0.13208)
		(layer "F.Cu")
		(net "RST_PEX3_S1_PERST_R_N")
	)
	(segment
		(start 436.0291 -301.0027)
		(end 436.049674 -301.0027)
		(width 0.13208)
		(layer "F.Cu")
		(net "RST_PEX3_S1_PERST_R_N")
	)
	(via
		(at 435.162706 -298.713652)
		(size 0.508)
		(drill 0.254)
		(layers "F.Cu" "B.Cu")
		(net "RST_PEX3_S1_PERST_R_N")
	)
	(via
		(at 420.774876 -305.874928)
		(size 0.4064)
		(drill 0.2032)
		(layers "F.Cu" "B.Cu")
		(net "RST_PEX3_S1_PERST_R_N")
	)
	(segment
		(start 432.119278 -298.781978)
		(end 432.08702 -298.74972)
		(width 0.15494)
		(layer "In5.Cu")
		(net "RST_PEX3_S1_PERST_R_N")
	)
	(segment
		(start 422.199816 -305.10988)
		(end 421.919146 -305.39055)
		(width 0.15494)
		(layer "In5.Cu")
		(net "RST_PEX3_S1_PERST_R_N")
	)
	(segment
		(start 435.162706 -298.713652)
		(end 433.860702 -298.713652)
		(width 0.15494)
		(layer "In5.Cu")
		(net "RST_PEX3_S1_PERST_R_N")
	)
	(segment
		(start 422.199816 -299.261784)
		(end 422.199816 -305.10988)
		(width 0.15494)
		(layer "In5.Cu")
		(net "RST_PEX3_S1_PERST_R_N")
	)
	(segment
		(start 433.792376 -298.781978)
		(end 432.119278 -298.781978)
		(width 0.15494)
		(layer "In5.Cu")
		(net "RST_PEX3_S1_PERST_R_N")
	)
	(segment
		(start 433.860702 -298.713652)
		(end 433.792376 -298.781978)
		(width 0.15494)
		(layer "In5.Cu")
		(net "RST_PEX3_S1_PERST_R_N")
	)
	(segment
		(start 421.919146 -305.39055)
		(end 421.259254 -305.39055)
		(width 0.15494)
		(layer "In5.Cu")
		(net "RST_PEX3_S1_PERST_R_N")
	)
	(segment
		(start 422.71188 -298.74972)
		(end 422.199816 -299.261784)
		(width 0.15494)
		(layer "In5.Cu")
		(net "RST_PEX3_S1_PERST_R_N")
	)
	(segment
		(start 432.08702 -298.74972)
		(end 422.71188 -298.74972)
		(width 0.15494)
		(layer "In5.Cu")
		(net "RST_PEX3_S1_PERST_R_N")
	)
	(segment
		(start 421.259254 -305.39055)
		(end 420.774876 -305.874928)
		(width 0.15494)
		(layer "In5.Cu")
		(net "RST_PEX3_S1_PERST_R_N")
	)
	(segment
		(start 438.152032 -288.197544)
		(end 438.152032 -288.830766)
		(width 0.13208)
		(layer "F.Cu")
		(net "SMB_PEX3_PCA9555_SDA")
	)
	(segment
		(start 349.928434 -160.913064)
		(end 350.502982 -160.675066)
		(width 0.13208)
		(layer "F.Cu")
		(net "SMB_PEX3_PCA9555_SDA")
	)
	(segment
		(start 350.502982 -160.675066)
		(end 350.5708 -160.6296)
		(width 0.13208)
		(layer "F.Cu")
		(net "SMB_PEX3_PCA9555_SDA")
	)
	(segment
		(start 350.5708 -160.6296)
		(end 350.75495 -160.44545)
		(width 0.13208)
		(layer "F.Cu")
		(net "SMB_PEX3_PCA9555_SDA")
	)
	(segment
		(start 351.688908 -160.44545)
		(end 351.702878 -160.43148)
		(width 0.13208)
		(layer "F.Cu")
		(net "SMB_PEX3_PCA9555_SDA")
	)
	(segment
		(start 350.75495 -160.44545)
		(end 351.688908 -160.44545)
		(width 0.13208)
		(layer "F.Cu")
		(net "SMB_PEX3_PCA9555_SDA")
	)
	(segment
		(start 349.000064 -160.913064)
		(end 349.928434 -160.913064)
		(width 0.13208)
		(layer "F.Cu")
		(net "SMB_PEX3_PCA9555_SDA")
	)
	(segment
		(start 349.000064 -149.102064)
		(end 350.642936 -149.102064)
		(width 0.13208)
		(layer "F.Cu")
		(net "SMB_PEX3_PCA9555_SDA")
	)
	(segment
		(start 350.642936 -149.102064)
		(end 351.282 -148.463)
		(width 0.13208)
		(layer "F.Cu")
		(net "SMB_PEX3_PCA9555_SDA")
	)
	(via
		(at 420.888668 -196.495416)
		(size 0.508)
		(drill 0.254)
		(layers "F.Cu" "B.Cu")
		(net "SMB_PEX3_PCA9555_SDA")
	)
	(via
		(at 438.152032 -288.197544)
		(size 0.508)
		(drill 0.254)
		(layers "F.Cu" "B.Cu")
		(net "SMB_PEX3_PCA9555_SDA")
	)
	(via
		(at 351.702878 -160.43148)
		(size 0.508)
		(drill 0.254)
		(layers "F.Cu" "B.Cu")
		(net "SMB_PEX3_PCA9555_SDA")
	)
	(via
		(at 445.48044 -253.306834)
		(size 0.508)
		(drill 0.254)
		(layers "F.Cu" "B.Cu")
		(net "SMB_PEX3_PCA9555_SDA")
	)
	(via
		(at 351.282 -148.463)
		(size 0.508)
		(drill 0.254)
		(layers "F.Cu" "B.Cu")
		(net "SMB_PEX3_PCA9555_SDA")
	)
	(segment
		(start 438.152032 -285.499556)
		(end 438.152032 -288.197544)
		(width 0.13208)
		(layer "B.Cu")
		(net "SMB_PEX3_PCA9555_SDA")
	)
	(segment
		(start 443.462664 -280.188924)
		(end 438.152032 -285.499556)
		(width 0.13208)
		(layer "B.Cu")
		(net "SMB_PEX3_PCA9555_SDA")
	)
	(segment
		(start 443.462664 -255.32461)
		(end 443.462664 -280.188924)
		(width 0.13208)
		(layer "B.Cu")
		(net "SMB_PEX3_PCA9555_SDA")
	)
	(segment
		(start 445.48044 -253.306834)
		(end 443.462664 -255.32461)
		(width 0.13208)
		(layer "B.Cu")
		(net "SMB_PEX3_PCA9555_SDA")
	)
	(segment
		(start 421.421814 -230.430324)
		(end 421.421814 -197.028562)
		(width 0.15494)
		(layer "In7.Cu")
		(net "SMB_PEX3_PCA9555_SDA")
	)
	(segment
		(start 444.095124 -248.8692)
		(end 439.86069 -248.8692)
		(width 0.15494)
		(layer "In7.Cu")
		(net "SMB_PEX3_PCA9555_SDA")
	)
	(segment
		(start 439.86069 -248.8692)
		(end 421.421814 -230.430324)
		(width 0.15494)
		(layer "In7.Cu")
		(net "SMB_PEX3_PCA9555_SDA")
	)
	(segment
		(start 445.48044 -250.254516)
		(end 444.095124 -248.8692)
		(width 0.15494)
		(layer "In7.Cu")
		(net "SMB_PEX3_PCA9555_SDA")
	)
	(segment
		(start 421.421814 -197.028562)
		(end 420.888668 -196.495416)
		(width 0.15494)
		(layer "In7.Cu")
		(net "SMB_PEX3_PCA9555_SDA")
	)
	(segment
		(start 445.48044 -253.306834)
		(end 445.48044 -250.254516)
		(width 0.15494)
		(layer "In7.Cu")
		(net "SMB_PEX3_PCA9555_SDA")
	)
	(segment
		(start 352.6028 -157.734)
		(end 352.6028 -149.7838)
		(width 0.15494)
		(layer "In9.Cu")
		(net "SMB_PEX3_PCA9555_SDA")
	)
	(segment
		(start 351.702878 -160.43148)
		(end 352.2726 -159.861758)
		(width 0.15494)
		(layer "In9.Cu")
		(net "SMB_PEX3_PCA9555_SDA")
	)
	(segment
		(start 352.6028 -149.7838)
		(end 351.282 -148.463)
		(width 0.15494)
		(layer "In9.Cu")
		(net "SMB_PEX3_PCA9555_SDA")
	)
	(segment
		(start 352.2726 -159.861758)
		(end 352.2726 -158.0642)
		(width 0.15494)
		(layer "In9.Cu")
		(net "SMB_PEX3_PCA9555_SDA")
	)
	(segment
		(start 352.2726 -158.0642)
		(end 352.6028 -157.734)
		(width 0.15494)
		(layer "In9.Cu")
		(net "SMB_PEX3_PCA9555_SDA")
	)
	(segment
		(start 411.861 -194.1576)
		(end 412.3944 -194.691)
		(width 0.15494)
		(layer "In13.Cu")
		(net "SMB_PEX3_PCA9555_SDA")
	)
	(segment
		(start 356.02926 -162.411918)
		(end 357.523542 -163.9062)
		(width 0.15494)
		(layer "In13.Cu")
		(net "SMB_PEX3_PCA9555_SDA")
	)
	(segment
		(start 400.382486 -172.988478)
		(end 405.326342 -172.988478)
		(width 0.15494)
		(layer "In13.Cu")
		(net "SMB_PEX3_PCA9555_SDA")
	)
	(segment
		(start 420.929054 -194.691)
		(end 421.336978 -195.098924)
		(width 0.15494)
		(layer "In13.Cu")
		(net "SMB_PEX3_PCA9555_SDA")
	)
	(segment
		(start 421.336978 -196.047106)
		(end 420.888668 -196.495416)
		(width 0.15494)
		(layer "In13.Cu")
		(net "SMB_PEX3_PCA9555_SDA")
	)
	(segment
		(start 413.2072 -189.5094)
		(end 411.861 -190.8556)
		(width 0.15494)
		(layer "In13.Cu")
		(net "SMB_PEX3_PCA9555_SDA")
	)
	(segment
		(start 357.523542 -163.9062)
		(end 358.673146 -163.9062)
		(width 0.15494)
		(layer "In13.Cu")
		(net "SMB_PEX3_PCA9555_SDA")
	)
	(segment
		(start 396.97533 -170.68673)
		(end 399.13433 -170.68673)
		(width 0.15494)
		(layer "In13.Cu")
		(net "SMB_PEX3_PCA9555_SDA")
	)
	(segment
		(start 400.2024 -172.808392)
		(end 400.382486 -172.988478)
		(width 0.15494)
		(layer "In13.Cu")
		(net "SMB_PEX3_PCA9555_SDA")
	)
	(segment
		(start 411.63621 -176.71161)
		(end 414.7312 -179.8066)
		(width 0.15494)
		(layer "In13.Cu")
		(net "SMB_PEX3_PCA9555_SDA")
	)
	(segment
		(start 414.7312 -182.538878)
		(end 413.2072 -184.062878)
		(width 0.15494)
		(layer "In13.Cu")
		(net "SMB_PEX3_PCA9555_SDA")
	)
	(segment
		(start 413.2072 -184.062878)
		(end 413.2072 -189.5094)
		(width 0.15494)
		(layer "In13.Cu")
		(net "SMB_PEX3_PCA9555_SDA")
	)
	(segment
		(start 414.7312 -179.8066)
		(end 414.7312 -182.538878)
		(width 0.15494)
		(layer "In13.Cu")
		(net "SMB_PEX3_PCA9555_SDA")
	)
	(segment
		(start 409.049474 -176.71161)
		(end 411.63621 -176.71161)
		(width 0.15494)
		(layer "In13.Cu")
		(net "SMB_PEX3_PCA9555_SDA")
	)
	(segment
		(start 364.337346 -169.5704)
		(end 395.859 -169.5704)
		(width 0.15494)
		(layer "In13.Cu")
		(net "SMB_PEX3_PCA9555_SDA")
	)
	(segment
		(start 405.326342 -172.988478)
		(end 409.049474 -176.71161)
		(width 0.15494)
		(layer "In13.Cu")
		(net "SMB_PEX3_PCA9555_SDA")
	)
	(segment
		(start 353.683316 -162.411918)
		(end 356.02926 -162.411918)
		(width 0.15494)
		(layer "In13.Cu")
		(net "SMB_PEX3_PCA9555_SDA")
	)
	(segment
		(start 399.13433 -170.68673)
		(end 400.2024 -171.7548)
		(width 0.15494)
		(layer "In13.Cu")
		(net "SMB_PEX3_PCA9555_SDA")
	)
	(segment
		(start 358.673146 -163.9062)
		(end 364.337346 -169.5704)
		(width 0.15494)
		(layer "In13.Cu")
		(net "SMB_PEX3_PCA9555_SDA")
	)
	(segment
		(start 400.2024 -171.7548)
		(end 400.2024 -172.808392)
		(width 0.15494)
		(layer "In13.Cu")
		(net "SMB_PEX3_PCA9555_SDA")
	)
	(segment
		(start 411.861 -190.8556)
		(end 411.861 -194.1576)
		(width 0.15494)
		(layer "In13.Cu")
		(net "SMB_PEX3_PCA9555_SDA")
	)
	(segment
		(start 421.336978 -195.098924)
		(end 421.336978 -196.047106)
		(width 0.15494)
		(layer "In13.Cu")
		(net "SMB_PEX3_PCA9555_SDA")
	)
	(segment
		(start 395.859 -169.5704)
		(end 396.97533 -170.68673)
		(width 0.15494)
		(layer "In13.Cu")
		(net "SMB_PEX3_PCA9555_SDA")
	)
	(segment
		(start 412.3944 -194.691)
		(end 420.929054 -194.691)
		(width 0.15494)
		(layer "In13.Cu")
		(net "SMB_PEX3_PCA9555_SDA")
	)
	(segment
		(start 351.702878 -160.43148)
		(end 353.683316 -162.411918)
		(width 0.15494)
		(layer "In13.Cu")
		(net "SMB_PEX3_PCA9555_SDA")
	)
	(segment
		(start 365.10595 -207.899)
		(end 364.49 -207.899)
		(width 0.13208)
		(layer "F.Cu")
		(net "PRSNT_SSD1_FPGA_R_N")
	)
	(segment
		(start 346.71 -204.83195)
		(end 346.71 -204.216)
		(width 0.13208)
		(layer "F.Cu")
		(net "PRSNT_SSD1_FPGA_R_N")
	)
	(via
		(at 364.49 -207.899)
		(size 0.508)
		(drill 0.254)
		(layers "F.Cu" "B.Cu")
		(net "PRSNT_SSD1_FPGA_R_N")
	)
	(via
		(at 346.71 -204.216)
		(size 0.508)
		(drill 0.254)
		(layers "F.Cu" "B.Cu")
		(net "PRSNT_SSD1_FPGA_R_N")
	)
	(segment
		(start 347.2942 -203.6318)
		(end 350.882712 -203.6318)
		(width 0.15494)
		(layer "In13.Cu")
		(net "PRSNT_SSD1_FPGA_R_N")
	)
	(segment
		(start 352.330512 -205.0796)
		(end 364.768892 -205.0796)
		(width 0.15494)
		(layer "In13.Cu")
		(net "PRSNT_SSD1_FPGA_R_N")
	)
	(segment
		(start 364.998 -207.391)
		(end 364.49 -207.899)
		(width 0.15494)
		(layer "In13.Cu")
		(net "PRSNT_SSD1_FPGA_R_N")
	)
	(segment
		(start 346.71 -204.216)
		(end 347.2942 -203.6318)
		(width 0.15494)
		(layer "In13.Cu")
		(net "PRSNT_SSD1_FPGA_R_N")
	)
	(segment
		(start 364.998 -205.308708)
		(end 364.998 -207.391)
		(width 0.15494)
		(layer "In13.Cu")
		(net "PRSNT_SSD1_FPGA_R_N")
	)
	(segment
		(start 350.882712 -203.6318)
		(end 352.330512 -205.0796)
		(width 0.15494)
		(layer "In13.Cu")
		(net "PRSNT_SSD1_FPGA_R_N")
	)
	(segment
		(start 364.768892 -205.0796)
		(end 364.998 -205.308708)
		(width 0.15494)
		(layer "In13.Cu")
		(net "PRSNT_SSD1_FPGA_R_N")
	)
	(segment
		(start 217.635836 -213.222586)
		(end 218.002612 -213.589362)
		(width 0.13208)
		(layer "F.Cu")
		(net "SMB_ALERT_PMBUS_R_N")
	)
	(segment
		(start 217.475562 -212.687916)
		(end 217.635836 -212.84819)
		(width 0.13208)
		(layer "F.Cu")
		(net "SMB_ALERT_PMBUS_R_N")
	)
	(segment
		(start 214.866728 -213.175088)
		(end 215.3539 -212.687916)
		(width 0.13208)
		(layer "F.Cu")
		(net "SMB_ALERT_PMBUS_R_N")
	)
	(segment
		(start 220.435932 -214.674196)
		(end 220.770196 -214.674196)
		(width 0.13208)
		(layer "F.Cu")
		(net "SMB_ALERT_PMBUS_R_N")
	)
	(segment
		(start 213.205314 -213.348062)
		(end 213.205314 -213.520782)
		(width 0.13208)
		(layer "F.Cu")
		(net "SMB_ALERT_PMBUS_R_N")
	)
	(segment
		(start 214.866728 -213.180168)
		(end 214.866728 -213.175088)
		(width 0.13208)
		(layer "F.Cu")
		(net "SMB_ALERT_PMBUS_R_N")
	)
	(segment
		(start 220.058234 -214.296498)
		(end 220.435932 -214.674196)
		(width 0.13208)
		(layer "F.Cu")
		(net "SMB_ALERT_PMBUS_R_N")
	)
	(segment
		(start 223.420432 -216.751408)
		(end 223.467676 -216.704164)
		(width 0.13208)
		(layer "F.Cu")
		(net "SMB_ALERT_PMBUS_R_N")
	)
	(segment
		(start 218.002612 -213.589362)
		(end 218.76004 -213.589362)
		(width 0.13208)
		(layer "F.Cu")
		(net "SMB_ALERT_PMBUS_R_N")
	)
	(segment
		(start 213.205314 -213.520782)
		(end 213.40826 -213.723728)
		(width 0.13208)
		(layer "F.Cu")
		(net "SMB_ALERT_PMBUS_R_N")
	)
	(segment
		(start 219.467176 -214.296498)
		(end 220.058234 -214.296498)
		(width 0.13208)
		(layer "F.Cu")
		(net "SMB_ALERT_PMBUS_R_N")
	)
	(segment
		(start 213.40826 -213.723728)
		(end 214.323168 -213.723728)
		(width 0.13208)
		(layer "F.Cu")
		(net "SMB_ALERT_PMBUS_R_N")
	)
	(segment
		(start 217.635836 -212.84819)
		(end 217.635836 -213.222586)
		(width 0.13208)
		(layer "F.Cu")
		(net "SMB_ALERT_PMBUS_R_N")
	)
	(segment
		(start 215.3539 -212.687916)
		(end 217.475562 -212.687916)
		(width 0.13208)
		(layer "F.Cu")
		(net "SMB_ALERT_PMBUS_R_N")
	)
	(segment
		(start 214.323168 -213.723728)
		(end 214.866728 -213.180168)
		(width 0.13208)
		(layer "F.Cu")
		(net "SMB_ALERT_PMBUS_R_N")
	)
	(segment
		(start 220.770196 -214.674196)
		(end 222.847408 -216.751408)
		(width 0.13208)
		(layer "F.Cu")
		(net "SMB_ALERT_PMBUS_R_N")
	)
	(segment
		(start 222.847408 -216.751408)
		(end 223.420432 -216.751408)
		(width 0.13208)
		(layer "F.Cu")
		(net "SMB_ALERT_PMBUS_R_N")
	)
	(segment
		(start 218.76004 -213.589362)
		(end 219.467176 -214.296498)
		(width 0.13208)
		(layer "F.Cu")
		(net "SMB_ALERT_PMBUS_R_N")
	)
	(via
		(at 220.435932 -214.674196)
		(size 0.762)
		(drill 0.381)
		(layers "F.Cu" "B.Cu")
		(net "SMB_ALERT_PMBUS_R_N")
	)
	(segment
		(start 115.98148 -127.614426)
		(end 115.98148 -128.145286)
		(width 0.13208)
		(layer "F.Cu")
		(net "PWR_EN_P3V3_R")
	)
	(segment
		(start 115.98148 -128.145286)
		(end 116.74983 -128.913636)
		(width 0.13208)
		(layer "F.Cu")
		(net "PWR_EN_P3V3_R")
	)
	(segment
		(start 115.200176 -119.077486)
		(end 114.590576 -119.077486)
		(width 0.13208)
		(layer "F.Cu")
		(net "PWR_EN_P3V3_R")
	)
	(segment
		(start 116.74983 -129.409444)
		(end 117.558312 -130.217926)
		(width 0.13208)
		(layer "F.Cu")
		(net "PWR_EN_P3V3_R")
	)
	(segment
		(start 115.47094 -127.404876)
		(end 115.77193 -127.404876)
		(width 0.13208)
		(layer "F.Cu")
		(net "PWR_EN_P3V3_R")
	)
	(segment
		(start 116.74983 -128.913636)
		(end 116.74983 -129.409444)
		(width 0.13208)
		(layer "F.Cu")
		(net "PWR_EN_P3V3_R")
	)
	(segment
		(start 115.77193 -127.404876)
		(end 115.98148 -127.614426)
		(width 0.13208)
		(layer "F.Cu")
		(net "PWR_EN_P3V3_R")
	)
	(segment
		(start 117.558312 -131.218686)
		(end 117.558312 -130.217926)
		(width 0.13208)
		(layer "F.Cu")
		(net "PWR_EN_P3V3_R")
	)
	(via
		(at 116.74983 -129.409444)
		(size 0.508)
		(drill 0.254)
		(layers "F.Cu" "B.Cu")
		(net "PWR_EN_P3V3_R")
	)
	(via
		(at 114.590576 -119.077486)
		(size 0.508)
		(drill 0.254)
		(layers "F.Cu" "B.Cu")
		(net "PWR_EN_P3V3_R")
	)
	(via
		(at 328.549 -224.4852)
		(size 0.508)
		(drill 0.254)
		(layers "F.Cu" "B.Cu")
		(net "PWR_EN_P3V3_R")
	)
	(via
		(at 116.64823 -205.016608)
		(size 0.508)
		(drill 0.254)
		(layers "F.Cu" "B.Cu")
		(net "PWR_EN_P3V3_R")
	)
	(segment
		(start 327.923906 -224.955354)
		(end 328.078846 -224.955354)
		(width 0.13208)
		(layer "B.Cu")
		(net "PWR_EN_P3V3_R")
	)
	(segment
		(start 328.549 -224.4852)
		(end 329.29195 -224.4852)
		(width 0.13208)
		(layer "B.Cu")
		(net "PWR_EN_P3V3_R")
	)
	(segment
		(start 328.078846 -224.955354)
		(end 328.549 -224.4852)
		(width 0.13208)
		(layer "B.Cu")
		(net "PWR_EN_P3V3_R")
	)
	(segment
		(start 111.820452 -191.112902)
		(end 120.527064 -182.40629)
		(width 0.15494)
		(layer "In7.Cu")
		(net "PWR_EN_P3V3_R")
	)
	(segment
		(start 120.527064 -168.467024)
		(end 119.4562 -167.39616)
		(width 0.15494)
		(layer "In7.Cu")
		(net "PWR_EN_P3V3_R")
	)
	(segment
		(start 116.74983 -130.183636)
		(end 116.74983 -129.409444)
		(width 0.15494)
		(layer "In7.Cu")
		(net "PWR_EN_P3V3_R")
	)
	(segment
		(start 119.4562 -145.231358)
		(end 119.844058 -144.8435)
		(width 0.15494)
		(layer "In7.Cu")
		(net "PWR_EN_P3V3_R")
	)
	(segment
		(start 120.527064 -182.40629)
		(end 120.527064 -168.467024)
		(width 0.15494)
		(layer "In7.Cu")
		(net "PWR_EN_P3V3_R")
	)
	(segment
		(start 119.844058 -133.277864)
		(end 116.74983 -130.183636)
		(width 0.15494)
		(layer "In7.Cu")
		(net "PWR_EN_P3V3_R")
	)
	(segment
		(start 111.820452 -200.18883)
		(end 111.820452 -191.112902)
		(width 0.15494)
		(layer "In7.Cu")
		(net "PWR_EN_P3V3_R")
	)
	(segment
		(start 119.844058 -144.8435)
		(end 119.844058 -133.277864)
		(width 0.15494)
		(layer "In7.Cu")
		(net "PWR_EN_P3V3_R")
	)
	(segment
		(start 116.64823 -205.016608)
		(end 111.820452 -200.18883)
		(width 0.15494)
		(layer "In7.Cu")
		(net "PWR_EN_P3V3_R")
	)
	(segment
		(start 119.4562 -167.39616)
		(end 119.4562 -145.231358)
		(width 0.15494)
		(layer "In7.Cu")
		(net "PWR_EN_P3V3_R")
	)
	(segment
		(start 116.332 -128.991614)
		(end 116.332 -120.81891)
		(width 0.15494)
		(layer "In9.Cu")
		(net "PWR_EN_P3V3_R")
	)
	(segment
		(start 116.74983 -129.409444)
		(end 116.332 -128.991614)
		(width 0.15494)
		(layer "In9.Cu")
		(net "PWR_EN_P3V3_R")
	)
	(segment
		(start 116.332 -120.81891)
		(end 114.590576 -119.077486)
		(width 0.15494)
		(layer "In9.Cu")
		(net "PWR_EN_P3V3_R")
	)
	(segment
		(start 214.22487 -206.08798)
		(end 214.477346 -205.835504)
		(width 0.15494)
		(layer "In13.Cu")
		(net "PWR_EN_P3V3_R")
	)
	(segment
		(start 214.22487 -206.489554)
		(end 214.22487 -206.08798)
		(width 0.15494)
		(layer "In13.Cu")
		(net "PWR_EN_P3V3_R")
	)
	(segment
		(start 276.98319 -223.04502)
		(end 322.074286 -223.04502)
		(width 0.15494)
		(layer "In13.Cu")
		(net "PWR_EN_P3V3_R")
	)
	(segment
		(start 325.416926 -225.354134)
		(end 326.28586 -224.4852)
		(width 0.15494)
		(layer "In13.Cu")
		(net "PWR_EN_P3V3_R")
	)
	(segment
		(start 159.491426 -210.535012)
		(end 164.09924 -205.927198)
		(width 0.15494)
		(layer "In13.Cu")
		(net "PWR_EN_P3V3_R")
	)
	(segment
		(start 235.68533 -204.865478)
		(end 236.914436 -206.094584)
		(width 0.15494)
		(layer "In13.Cu")
		(net "PWR_EN_P3V3_R")
	)
	(segment
		(start 257.7592 -210.937856)
		(end 258.327144 -210.937856)
		(width 0.15494)
		(layer "In13.Cu")
		(net "PWR_EN_P3V3_R")
	)
	(segment
		(start 136.347454 -211.4296)
		(end 158.589726 -211.4296)
		(width 0.15494)
		(layer "In13.Cu")
		(net "PWR_EN_P3V3_R")
	)
	(segment
		(start 135.920734 -211.00288)
		(end 136.347454 -211.4296)
		(width 0.15494)
		(layer "In13.Cu")
		(net "PWR_EN_P3V3_R")
	)
	(segment
		(start 255.1938 -207.7466)
		(end 255.1938 -208.372456)
		(width 0.15494)
		(layer "In13.Cu")
		(net "PWR_EN_P3V3_R")
	)
	(segment
		(start 245.9736 -205.5368)
		(end 251.0028 -205.5368)
		(width 0.15494)
		(layer "In13.Cu")
		(net "PWR_EN_P3V3_R")
	)
	(segment
		(start 159.484314 -210.535012)
		(end 159.491426 -210.535012)
		(width 0.15494)
		(layer "In13.Cu")
		(net "PWR_EN_P3V3_R")
	)
	(segment
		(start 236.914436 -206.094584)
		(end 238.002826 -206.545434)
		(width 0.15494)
		(layer "In13.Cu")
		(net "PWR_EN_P3V3_R")
	)
	(segment
		(start 276.38629 -223.037146)
		(end 276.975316 -223.037146)
		(width 0.15494)
		(layer "In13.Cu")
		(net "PWR_EN_P3V3_R")
	)
	(segment
		(start 322.984368 -223.594168)
		(end 324.744334 -225.354134)
		(width 0.15494)
		(layer "In13.Cu")
		(net "PWR_EN_P3V3_R")
	)
	(segment
		(start 218.313 -205.105)
		(end 218.567 -205.359)
		(width 0.15494)
		(layer "In13.Cu")
		(net "PWR_EN_P3V3_R")
	)
	(segment
		(start 255.1938 -208.372456)
		(end 257.7592 -210.937856)
		(width 0.15494)
		(layer "In13.Cu")
		(net "PWR_EN_P3V3_R")
	)
	(segment
		(start 204.842618 -205.927198)
		(end 205.17358 -206.25816)
		(width 0.15494)
		(layer "In13.Cu")
		(net "PWR_EN_P3V3_R")
	)
	(segment
		(start 127.8128 -211.00288)
		(end 135.920734 -211.00288)
		(width 0.15494)
		(layer "In13.Cu")
		(net "PWR_EN_P3V3_R")
	)
	(segment
		(start 259.334254 -210.4644)
		(end 260.449314 -211.57946)
		(width 0.15494)
		(layer "In13.Cu")
		(net "PWR_EN_P3V3_R")
	)
	(segment
		(start 254.0254 -206.5782)
		(end 255.1938 -207.7466)
		(width 0.15494)
		(layer "In13.Cu")
		(net "PWR_EN_P3V3_R")
	)
	(segment
		(start 322.074286 -223.04502)
		(end 322.623434 -223.594168)
		(width 0.15494)
		(layer "In13.Cu")
		(net "PWR_EN_P3V3_R")
	)
	(segment
		(start 252.0442 -206.5782)
		(end 254.0254 -206.5782)
		(width 0.15494)
		(layer "In13.Cu")
		(net "PWR_EN_P3V3_R")
	)
	(segment
		(start 271.8054 -213.69528)
		(end 271.8054 -218.456256)
		(width 0.15494)
		(layer "In13.Cu")
		(net "PWR_EN_P3V3_R")
	)
	(segment
		(start 127.81026 -211.00034)
		(end 127.8128 -211.00288)
		(width 0.15494)
		(layer "In13.Cu")
		(net "PWR_EN_P3V3_R")
	)
	(segment
		(start 164.09924 -205.927198)
		(end 204.842618 -205.927198)
		(width 0.15494)
		(layer "In13.Cu")
		(net "PWR_EN_P3V3_R")
	)
	(segment
		(start 220.407992 -204.865478)
		(end 235.68533 -204.865478)
		(width 0.15494)
		(layer "In13.Cu")
		(net "PWR_EN_P3V3_R")
	)
	(segment
		(start 119.1895 -206.25054)
		(end 123.051316 -206.25054)
		(width 0.15494)
		(layer "In13.Cu")
		(net "PWR_EN_P3V3_R")
	)
	(segment
		(start 262.740394 -211.57946)
		(end 263.780524 -210.53933)
		(width 0.15494)
		(layer "In13.Cu")
		(net "PWR_EN_P3V3_R")
	)
	(segment
		(start 258.327144 -210.937856)
		(end 258.8006 -210.4644)
		(width 0.15494)
		(layer "In13.Cu")
		(net "PWR_EN_P3V3_R")
	)
	(segment
		(start 218.567 -205.359)
		(end 219.91447 -205.359)
		(width 0.15494)
		(layer "In13.Cu")
		(net "PWR_EN_P3V3_R")
	)
	(segment
		(start 205.17358 -206.25816)
		(end 211.0994 -206.25816)
		(width 0.15494)
		(layer "In13.Cu")
		(net "PWR_EN_P3V3_R")
	)
	(segment
		(start 322.623434 -223.594168)
		(end 322.984368 -223.594168)
		(width 0.15494)
		(layer "In13.Cu")
		(net "PWR_EN_P3V3_R")
	)
	(segment
		(start 240.745772 -206.545434)
		(end 241.470434 -205.820772)
		(width 0.15494)
		(layer "In13.Cu")
		(net "PWR_EN_P3V3_R")
	)
	(segment
		(start 217.103198 -205.835504)
		(end 217.833702 -205.105)
		(width 0.15494)
		(layer "In13.Cu")
		(net "PWR_EN_P3V3_R")
	)
	(segment
		(start 127.801116 -211.00034)
		(end 127.81026 -211.00034)
		(width 0.15494)
		(layer "In13.Cu")
		(net "PWR_EN_P3V3_R")
	)
	(segment
		(start 213.94166 -206.772764)
		(end 214.22487 -206.489554)
		(width 0.15494)
		(layer "In13.Cu")
		(net "PWR_EN_P3V3_R")
	)
	(segment
		(start 211.0994 -206.25816)
		(end 211.614004 -206.772764)
		(width 0.15494)
		(layer "In13.Cu")
		(net "PWR_EN_P3V3_R")
	)
	(segment
		(start 217.833702 -205.105)
		(end 218.313 -205.105)
		(width 0.15494)
		(layer "In13.Cu")
		(net "PWR_EN_P3V3_R")
	)
	(segment
		(start 158.589726 -211.4296)
		(end 159.484314 -210.535012)
		(width 0.15494)
		(layer "In13.Cu")
		(net "PWR_EN_P3V3_R")
	)
	(segment
		(start 324.744334 -225.354134)
		(end 325.416926 -225.354134)
		(width 0.15494)
		(layer "In13.Cu")
		(net "PWR_EN_P3V3_R")
	)
	(segment
		(start 260.449314 -211.57946)
		(end 262.740394 -211.57946)
		(width 0.15494)
		(layer "In13.Cu")
		(net "PWR_EN_P3V3_R")
	)
	(segment
		(start 214.477346 -205.835504)
		(end 217.103198 -205.835504)
		(width 0.15494)
		(layer "In13.Cu")
		(net "PWR_EN_P3V3_R")
	)
	(segment
		(start 238.002826 -206.545434)
		(end 240.745772 -206.545434)
		(width 0.15494)
		(layer "In13.Cu")
		(net "PWR_EN_P3V3_R")
	)
	(segment
		(start 219.91447 -205.359)
		(end 220.407992 -204.865478)
		(width 0.15494)
		(layer "In13.Cu")
		(net "PWR_EN_P3V3_R")
	)
	(segment
		(start 251.0028 -205.5368)
		(end 252.0442 -206.5782)
		(width 0.15494)
		(layer "In13.Cu")
		(net "PWR_EN_P3V3_R")
	)
	(segment
		(start 263.780524 -210.53933)
		(end 268.64945 -210.53933)
		(width 0.15494)
		(layer "In13.Cu")
		(net "PWR_EN_P3V3_R")
	)
	(segment
		(start 326.28586 -224.4852)
		(end 328.549 -224.4852)
		(width 0.15494)
		(layer "In13.Cu")
		(net "PWR_EN_P3V3_R")
	)
	(segment
		(start 245.689628 -205.820772)
		(end 245.9736 -205.5368)
		(width 0.15494)
		(layer "In13.Cu")
		(net "PWR_EN_P3V3_R")
	)
	(segment
		(start 258.8006 -210.4644)
		(end 259.334254 -210.4644)
		(width 0.15494)
		(layer "In13.Cu")
		(net "PWR_EN_P3V3_R")
	)
	(segment
		(start 271.8054 -218.456256)
		(end 276.38629 -223.037146)
		(width 0.15494)
		(layer "In13.Cu")
		(net "PWR_EN_P3V3_R")
	)
	(segment
		(start 241.470434 -205.820772)
		(end 245.689628 -205.820772)
		(width 0.15494)
		(layer "In13.Cu")
		(net "PWR_EN_P3V3_R")
	)
	(segment
		(start 116.64823 -205.016608)
		(end 117.955568 -205.016608)
		(width 0.15494)
		(layer "In13.Cu")
		(net "PWR_EN_P3V3_R")
	)
	(segment
		(start 276.975316 -223.037146)
		(end 276.98319 -223.04502)
		(width 0.15494)
		(layer "In13.Cu")
		(net "PWR_EN_P3V3_R")
	)
	(segment
		(start 268.64945 -210.53933)
		(end 271.8054 -213.69528)
		(width 0.15494)
		(layer "In13.Cu")
		(net "PWR_EN_P3V3_R")
	)
	(segment
		(start 117.955568 -205.016608)
		(end 119.1895 -206.25054)
		(width 0.15494)
		(layer "In13.Cu")
		(net "PWR_EN_P3V3_R")
	)
	(segment
		(start 211.614004 -206.772764)
		(end 213.94166 -206.772764)
		(width 0.15494)
		(layer "In13.Cu")
		(net "PWR_EN_P3V3_R")
	)
	(segment
		(start 123.051316 -206.25054)
		(end 127.801116 -211.00034)
		(width 0.15494)
		(layer "In13.Cu")
		(net "PWR_EN_P3V3_R")
	)
	(segment
		(start 349.000064 -148.452078)
		(end 350.255078 -148.452078)
		(width 0.13208)
		(layer "F.Cu")
		(net "SMB_PEX3_PCA9555_SCL")
	)
	(segment
		(start 349.000064 -160.263078)
		(end 350.255078 -160.263078)
		(width 0.13208)
		(layer "F.Cu")
		(net "SMB_PEX3_PCA9555_SCL")
	)
	(segment
		(start 440.184032 -288.830766)
		(end 440.184032 -288.253424)
		(width 0.13208)
		(layer "F.Cu")
		(net "SMB_PEX3_PCA9555_SCL")
	)
	(segment
		(start 440.184032 -288.253424)
		(end 440.151774 -288.221166)
		(width 0.13208)
		(layer "F.Cu")
		(net "SMB_PEX3_PCA9555_SCL")
	)
	(via
		(at 350.255078 -148.452078)
		(size 0.508)
		(drill 0.254)
		(layers "F.Cu" "B.Cu")
		(net "SMB_PEX3_PCA9555_SCL")
	)
	(via
		(at 420.652448 -195.241926)
		(size 0.508)
		(drill 0.254)
		(layers "F.Cu" "B.Cu")
		(net "SMB_PEX3_PCA9555_SCL")
	)
	(via
		(at 446.755774 -252.890782)
		(size 0.508)
		(drill 0.254)
		(layers "F.Cu" "B.Cu")
		(net "SMB_PEX3_PCA9555_SCL")
	)
	(via
		(at 350.255078 -160.263078)
		(size 0.508)
		(drill 0.254)
		(layers "F.Cu" "B.Cu")
		(net "SMB_PEX3_PCA9555_SCL")
	)
	(via
		(at 440.151774 -288.221166)
		(size 0.508)
		(drill 0.254)
		(layers "F.Cu" "B.Cu")
		(net "SMB_PEX3_PCA9555_SCL")
	)
	(segment
		(start 443.899544 -256.044954)
		(end 443.899544 -280.42997)
		(width 0.13208)
		(layer "B.Cu")
		(net "SMB_PEX3_PCA9555_SCL")
	)
	(segment
		(start 446.755774 -252.890782)
		(end 446.755774 -253.188724)
		(width 0.13208)
		(layer "B.Cu")
		(net "SMB_PEX3_PCA9555_SCL")
	)
	(segment
		(start 443.899544 -280.42997)
		(end 440.151774 -284.17774)
		(width 0.13208)
		(layer "B.Cu")
		(net "SMB_PEX3_PCA9555_SCL")
	)
	(segment
		(start 440.151774 -284.17774)
		(end 440.151774 -288.221166)
		(width 0.13208)
		(layer "B.Cu")
		(net "SMB_PEX3_PCA9555_SCL")
	)
	(segment
		(start 446.755774 -253.188724)
		(end 443.899544 -256.044954)
		(width 0.13208)
		(layer "B.Cu")
		(net "SMB_PEX3_PCA9555_SCL")
	)
	(segment
		(start 421.90416 -230.10495)
		(end 421.90416 -196.493638)
		(width 0.15494)
		(layer "In7.Cu")
		(net "SMB_PEX3_PCA9555_SCL")
	)
	(segment
		(start 421.90416 -196.493638)
		(end 420.652448 -195.241926)
		(width 0.15494)
		(layer "In7.Cu")
		(net "SMB_PEX3_PCA9555_SCL")
	)
	(segment
		(start 440.11723 -248.31802)
		(end 421.90416 -230.10495)
		(width 0.15494)
		(layer "In7.Cu")
		(net "SMB_PEX3_PCA9555_SCL")
	)
	(segment
		(start 446.755774 -252.890782)
		(end 446.37198 -252.506988)
		(width 0.15494)
		(layer "In7.Cu")
		(net "SMB_PEX3_PCA9555_SCL")
	)
	(segment
		(start 444.448946 -248.31802)
		(end 440.11723 -248.31802)
		(width 0.15494)
		(layer "In7.Cu")
		(net "SMB_PEX3_PCA9555_SCL")
	)
	(segment
		(start 446.37198 -250.241054)
		(end 444.448946 -248.31802)
		(width 0.15494)
		(layer "In7.Cu")
		(net "SMB_PEX3_PCA9555_SCL")
	)
	(segment
		(start 446.37198 -252.506988)
		(end 446.37198 -250.241054)
		(width 0.15494)
		(layer "In7.Cu")
		(net "SMB_PEX3_PCA9555_SCL")
	)
	(segment
		(start 350.774 -159.744156)
		(end 350.774 -159.1818)
		(width 0.15494)
		(layer "In9.Cu")
		(net "SMB_PEX3_PCA9555_SCL")
	)
	(segment
		(start 350.255078 -153.151078)
		(end 350.255078 -148.452078)
		(width 0.15494)
		(layer "In9.Cu")
		(net "SMB_PEX3_PCA9555_SCL")
	)
	(segment
		(start 350.255078 -160.263078)
		(end 350.774 -159.744156)
		(width 0.15494)
		(layer "In9.Cu")
		(net "SMB_PEX3_PCA9555_SCL")
	)
	(segment
		(start 350.6216 -159.0294)
		(end 350.6216 -153.5176)
		(width 0.15494)
		(layer "In9.Cu")
		(net "SMB_PEX3_PCA9555_SCL")
	)
	(segment
		(start 350.6216 -153.5176)
		(end 350.255078 -153.151078)
		(width 0.15494)
		(layer "In9.Cu")
		(net "SMB_PEX3_PCA9555_SCL")
	)
	(segment
		(start 350.774 -159.1818)
		(end 350.6216 -159.0294)
		(width 0.15494)
		(layer "In9.Cu")
		(net "SMB_PEX3_PCA9555_SCL")
	)
	(segment
		(start 408.914854 -177.292)
		(end 411.565598 -177.292)
		(width 0.15494)
		(layer "In13.Cu")
		(net "SMB_PEX3_PCA9555_SCL")
	)
	(segment
		(start 353.410012 -162.875976)
		(end 355.779324 -162.875976)
		(width 0.15494)
		(layer "In13.Cu")
		(net "SMB_PEX3_PCA9555_SCL")
	)
	(segment
		(start 399.669 -172.009054)
		(end 399.669 -173.227746)
		(width 0.15494)
		(layer "In13.Cu")
		(net "SMB_PEX3_PCA9555_SCL")
	)
	(segment
		(start 399.669 -173.227746)
		(end 399.974054 -173.5328)
		(width 0.15494)
		(layer "In13.Cu")
		(net "SMB_PEX3_PCA9555_SCL")
	)
	(segment
		(start 350.255078 -160.263078)
		(end 350.797114 -160.263078)
		(width 0.15494)
		(layer "In13.Cu")
		(net "SMB_PEX3_PCA9555_SCL")
	)
	(segment
		(start 395.783562 -170.2054)
		(end 396.799562 -171.2214)
		(width 0.15494)
		(layer "In13.Cu")
		(net "SMB_PEX3_PCA9555_SCL")
	)
	(segment
		(start 412.7246 -189.154054)
		(end 411.386528 -190.492126)
		(width 0.15494)
		(layer "In13.Cu")
		(net "SMB_PEX3_PCA9555_SCL")
	)
	(segment
		(start 358.438704 -164.5158)
		(end 364.128304 -170.2054)
		(width 0.15494)
		(layer "In13.Cu")
		(net "SMB_PEX3_PCA9555_SCL")
	)
	(segment
		(start 355.779324 -162.875976)
		(end 357.419148 -164.5158)
		(width 0.15494)
		(layer "In13.Cu")
		(net "SMB_PEX3_PCA9555_SCL")
	)
	(segment
		(start 411.565598 -177.292)
		(end 414.236408 -179.96281)
		(width 0.15494)
		(layer "In13.Cu")
		(net "SMB_PEX3_PCA9555_SCL")
	)
	(segment
		(start 357.419148 -164.5158)
		(end 358.438704 -164.5158)
		(width 0.15494)
		(layer "In13.Cu")
		(net "SMB_PEX3_PCA9555_SCL")
	)
	(segment
		(start 399.974054 -173.5328)
		(end 405.155654 -173.5328)
		(width 0.15494)
		(layer "In13.Cu")
		(net "SMB_PEX3_PCA9555_SCL")
	)
	(segment
		(start 396.799562 -171.2214)
		(end 398.881346 -171.2214)
		(width 0.15494)
		(layer "In13.Cu")
		(net "SMB_PEX3_PCA9555_SCL")
	)
	(segment
		(start 398.881346 -171.2214)
		(end 399.669 -172.009054)
		(width 0.15494)
		(layer "In13.Cu")
		(net "SMB_PEX3_PCA9555_SCL")
	)
	(segment
		(start 411.386528 -194.540886)
		(end 412.087568 -195.241926)
		(width 0.15494)
		(layer "In13.Cu")
		(net "SMB_PEX3_PCA9555_SCL")
	)
	(segment
		(start 414.236408 -182.333392)
		(end 412.7246 -183.8452)
		(width 0.15494)
		(layer "In13.Cu")
		(net "SMB_PEX3_PCA9555_SCL")
	)
	(segment
		(start 350.797114 -160.263078)
		(end 353.410012 -162.875976)
		(width 0.15494)
		(layer "In13.Cu")
		(net "SMB_PEX3_PCA9555_SCL")
	)
	(segment
		(start 405.155654 -173.5328)
		(end 408.914854 -177.292)
		(width 0.15494)
		(layer "In13.Cu")
		(net "SMB_PEX3_PCA9555_SCL")
	)
	(segment
		(start 364.128304 -170.2054)
		(end 395.783562 -170.2054)
		(width 0.15494)
		(layer "In13.Cu")
		(net "SMB_PEX3_PCA9555_SCL")
	)
	(segment
		(start 411.386528 -190.492126)
		(end 411.386528 -194.540886)
		(width 0.15494)
		(layer "In13.Cu")
		(net "SMB_PEX3_PCA9555_SCL")
	)
	(segment
		(start 414.236408 -179.96281)
		(end 414.236408 -182.333392)
		(width 0.15494)
		(layer "In13.Cu")
		(net "SMB_PEX3_PCA9555_SCL")
	)
	(segment
		(start 412.7246 -183.8452)
		(end 412.7246 -189.154054)
		(width 0.15494)
		(layer "In13.Cu")
		(net "SMB_PEX3_PCA9555_SCL")
	)
	(segment
		(start 412.087568 -195.241926)
		(end 420.652448 -195.241926)
		(width 0.15494)
		(layer "In13.Cu")
		(net "SMB_PEX3_PCA9555_SCL")
	)
	(segment
		(start 340.359746 -146.939)
		(end 340.572852 -147.152106)
		(width 0.13208)
		(layer "F.Cu")
		(net "SSD14_PEX_PWR_EN")
	)
	(segment
		(start 340.881462 -147.152106)
		(end 343.149936 -147.152106)
		(width 0.13208)
		(layer "F.Cu")
		(net "SSD14_PEX_PWR_EN")
	)
	(segment
		(start 340.572852 -147.152106)
		(end 340.881462 -147.152106)
		(width 0.13208)
		(layer "F.Cu")
		(net "SSD14_PEX_PWR_EN")
	)
	(segment
		(start 338.47405 -146.939)
		(end 340.359746 -146.939)
		(width 0.13208)
		(layer "F.Cu")
		(net "SSD14_PEX_PWR_EN")
	)
	(via
		(at 340.881462 -147.152106)
		(size 0.508)
		(drill 0.254)
		(layers "F.Cu" "B.Cu")
		(net "SSD14_PEX_PWR_EN")
	)
	(segment
		(start 257.842512 -212.765386)
		(end 257.842512 -211.749386)
		(width 0.13208)
		(layer "F.Cu")
		(net "PWR_EN_P1V2_AUX_R")
	)
	(segment
		(start 256.237232 -212.934296)
		(end 256.406142 -212.765386)
		(width 0.13208)
		(layer "F.Cu")
		(net "PWR_EN_P1V2_AUX_R")
	)
	(segment
		(start 257.226562 -212.765386)
		(end 257.842512 -212.765386)
		(width 0.13208)
		(layer "F.Cu")
		(net "PWR_EN_P1V2_AUX_R")
	)
	(segment
		(start 256.406142 -212.765386)
		(end 257.226562 -212.765386)
		(width 0.13208)
		(layer "F.Cu")
		(net "PWR_EN_P1V2_AUX_R")
	)
	(segment
		(start 255.88976 -212.934296)
		(end 256.237232 -212.934296)
		(width 0.13208)
		(layer "F.Cu")
		(net "PWR_EN_P1V2_AUX_R")
	)
	(via
		(at 328.491088 -225.5012)
		(size 0.508)
		(drill 0.254)
		(layers "F.Cu" "B.Cu")
		(net "PWR_EN_P1V2_AUX_R")
	)
	(via
		(at 257.226562 -212.765386)
		(size 0.508)
		(drill 0.254)
		(layers "F.Cu" "B.Cu")
		(net "PWR_EN_P1V2_AUX_R")
	)
	(via
		(at 267.9446 -223.347534)
		(size 0.508)
		(drill 0.254)
		(layers "F.Cu" "B.Cu")
		(net "PWR_EN_P1V2_AUX_R")
	)
	(segment
		(start 329.29195 -225.5012)
		(end 328.491088 -225.5012)
		(width 0.13208)
		(layer "B.Cu")
		(net "PWR_EN_P1V2_AUX_R")
	)
	(segment
		(start 330.09205 -226.276916)
		(end 330.09205 -226.5172)
		(width 0.13208)
		(layer "B.Cu")
		(net "PWR_EN_P1V2_AUX_R")
	)
	(segment
		(start 329.29195 -225.5012)
		(end 329.29195 -226.007168)
		(width 0.13208)
		(layer "B.Cu")
		(net "PWR_EN_P1V2_AUX_R")
	)
	(segment
		(start 329.895454 -226.08032)
		(end 330.09205 -226.276916)
		(width 0.13208)
		(layer "B.Cu")
		(net "PWR_EN_P1V2_AUX_R")
	)
	(segment
		(start 329.29195 -226.007168)
		(end 329.365102 -226.08032)
		(width 0.13208)
		(layer "B.Cu")
		(net "PWR_EN_P1V2_AUX_R")
	)
	(segment
		(start 329.365102 -226.08032)
		(end 329.895454 -226.08032)
		(width 0.13208)
		(layer "B.Cu")
		(net "PWR_EN_P1V2_AUX_R")
	)
	(segment
		(start 262.947912 -223.347534)
		(end 262.085328 -222.48495)
		(width 0.15494)
		(layer "In5.Cu")
		(net "PWR_EN_P1V2_AUX_R")
	)
	(segment
		(start 257.87731 -211.10702)
		(end 257.226562 -211.757768)
		(width 0.15494)
		(layer "In5.Cu")
		(net "PWR_EN_P1V2_AUX_R")
	)
	(segment
		(start 257.226562 -211.757768)
		(end 257.226562 -212.765386)
		(width 0.15494)
		(layer "In5.Cu")
		(net "PWR_EN_P1V2_AUX_R")
	)
	(segment
		(start 260.163056 -215.22436)
		(end 259.423662 -214.484966)
		(width 0.15494)
		(layer "In5.Cu")
		(net "PWR_EN_P1V2_AUX_R")
	)
	(segment
		(start 262.085328 -222.48495)
		(end 262.085328 -220.112336)
		(width 0.15494)
		(layer "In5.Cu")
		(net "PWR_EN_P1V2_AUX_R")
	)
	(segment
		(start 267.9446 -223.347534)
		(end 262.947912 -223.347534)
		(width 0.15494)
		(layer "In5.Cu")
		(net "PWR_EN_P1V2_AUX_R")
	)
	(segment
		(start 259.821934 -217.162634)
		(end 260.163056 -216.821512)
		(width 0.15494)
		(layer "In5.Cu")
		(net "PWR_EN_P1V2_AUX_R")
	)
	(segment
		(start 259.423662 -213.64448)
		(end 260.062218 -213.005924)
		(width 0.15494)
		(layer "In5.Cu")
		(net "PWR_EN_P1V2_AUX_R")
	)
	(segment
		(start 259.423662 -214.484966)
		(end 259.423662 -213.64448)
		(width 0.15494)
		(layer "In5.Cu")
		(net "PWR_EN_P1V2_AUX_R")
	)
	(segment
		(start 260.062218 -213.005924)
		(end 260.062218 -211.745576)
		(width 0.15494)
		(layer "In5.Cu")
		(net "PWR_EN_P1V2_AUX_R")
	)
	(segment
		(start 259.821934 -217.848942)
		(end 259.821934 -217.162634)
		(width 0.15494)
		(layer "In5.Cu")
		(net "PWR_EN_P1V2_AUX_R")
	)
	(segment
		(start 262.085328 -220.112336)
		(end 259.821934 -217.848942)
		(width 0.15494)
		(layer "In5.Cu")
		(net "PWR_EN_P1V2_AUX_R")
	)
	(segment
		(start 259.423662 -211.10702)
		(end 257.87731 -211.10702)
		(width 0.15494)
		(layer "In5.Cu")
		(net "PWR_EN_P1V2_AUX_R")
	)
	(segment
		(start 260.163056 -216.821512)
		(end 260.163056 -215.22436)
		(width 0.15494)
		(layer "In5.Cu")
		(net "PWR_EN_P1V2_AUX_R")
	)
	(segment
		(start 260.062218 -211.745576)
		(end 259.423662 -211.10702)
		(width 0.15494)
		(layer "In5.Cu")
		(net "PWR_EN_P1V2_AUX_R")
	)
	(segment
		(start 328.491088 -226.776026)
		(end 328.491088 -225.5012)
		(width 0.15494)
		(layer "In15.Cu")
		(net "PWR_EN_P1V2_AUX_R")
	)
	(segment
		(start 328.125328 -227.141786)
		(end 328.491088 -226.776026)
		(width 0.15494)
		(layer "In15.Cu")
		(net "PWR_EN_P1V2_AUX_R")
	)
	(segment
		(start 324.399402 -226.8982)
		(end 326.107044 -226.8982)
		(width 0.15494)
		(layer "In15.Cu")
		(net "PWR_EN_P1V2_AUX_R")
	)
	(segment
		(start 326.107044 -226.8982)
		(end 326.35063 -227.141786)
		(width 0.15494)
		(layer "In15.Cu")
		(net "PWR_EN_P1V2_AUX_R")
	)
	(segment
		(start 320.848736 -223.347534)
		(end 324.399402 -226.8982)
		(width 0.15494)
		(layer "In15.Cu")
		(net "PWR_EN_P1V2_AUX_R")
	)
	(segment
		(start 326.35063 -227.141786)
		(end 328.125328 -227.141786)
		(width 0.15494)
		(layer "In15.Cu")
		(net "PWR_EN_P1V2_AUX_R")
	)
	(segment
		(start 267.9446 -223.347534)
		(end 320.848736 -223.347534)
		(width 0.15494)
		(layer "In15.Cu")
		(net "PWR_EN_P1V2_AUX_R")
	)
	(segment
		(start 437.733694 -290.237164)
		(end 437.726582 -290.230052)
		(width 0.13208)
		(layer "F.Cu")
		(net "PWRGD_P1V8_PEX3_R")
	)
	(segment
		(start 435.440582 -290.230052)
		(end 435.104032 -289.893502)
		(width 0.13208)
		(layer "F.Cu")
		(net "PWRGD_P1V8_PEX3_R")
	)
	(segment
		(start 437.726582 -290.230052)
		(end 435.440582 -290.230052)
		(width 0.13208)
		(layer "F.Cu")
		(net "PWRGD_P1V8_PEX3_R")
	)
	(segment
		(start 437.889396 -290.28009)
		(end 437.84647 -290.237164)
		(width 0.13208)
		(layer "F.Cu")
		(net "PWRGD_P1V8_PEX3_R")
	)
	(segment
		(start 437.889396 -291.297868)
		(end 437.889396 -290.28009)
		(width 0.13208)
		(layer "F.Cu")
		(net "PWRGD_P1V8_PEX3_R")
	)
	(segment
		(start 437.84647 -290.237164)
		(end 437.733694 -290.237164)
		(width 0.13208)
		(layer "F.Cu")
		(net "PWRGD_P1V8_PEX3_R")
	)
	(segment
		(start 435.104032 -289.893502)
		(end 435.104032 -289.630866)
		(width 0.13208)
		(layer "F.Cu")
		(net "PWRGD_P1V8_PEX3_R")
	)
	(via
		(at 437.84647 -290.237164)
		(size 0.508)
		(drill 0.254)
		(layers "F.Cu" "B.Cu")
		(net "PWRGD_P1V8_PEX3_R")
	)
	(segment
		(start 438.614312 -293.724584)
		(end 438.614312 -291.297868)
		(width 0.13208)
		(layer "F.Cu")
		(net "SMB_PEX3_HOST_LS_SDA")
	)
	(segment
		(start 437.699912 -294.016176)
		(end 437.251094 -294.464994)
		(width 0.13208)
		(layer "F.Cu")
		(net "SMB_PEX3_HOST_LS_SDA")
	)
	(segment
		(start 437.251094 -294.464994)
		(end 437.251094 -297.31716)
		(width 0.13208)
		(layer "F.Cu")
		(net "SMB_PEX3_HOST_LS_SDA")
	)
	(segment
		(start 437.251094 -297.31716)
		(end 437.398414 -297.46448)
		(width 0.13208)
		(layer "F.Cu")
		(net "SMB_PEX3_HOST_LS_SDA")
	)
	(segment
		(start 437.136032 -289.630866)
		(end 438.152032 -289.630866)
		(width 0.13208)
		(layer "F.Cu")
		(net "SMB_PEX3_HOST_LS_SDA")
	)
	(segment
		(start 436.120032 -289.630866)
		(end 437.136032 -289.630866)
		(width 0.13208)
		(layer "F.Cu")
		(net "SMB_PEX3_HOST_LS_SDA")
	)
	(segment
		(start 438.614312 -290.093146)
		(end 438.614312 -291.297868)
		(width 0.13208)
		(layer "F.Cu")
		(net "SMB_PEX3_HOST_LS_SDA")
	)
	(segment
		(start 438.152032 -289.630866)
		(end 438.614312 -290.093146)
		(width 0.13208)
		(layer "F.Cu")
		(net "SMB_PEX3_HOST_LS_SDA")
	)
	(segment
		(start 438.32272 -294.016176)
		(end 437.699912 -294.016176)
		(width 0.13208)
		(layer "F.Cu")
		(net "SMB_PEX3_HOST_LS_SDA")
	)
	(segment
		(start 438.32272 -294.016176)
		(end 438.614312 -293.724584)
		(width 0.13208)
		(layer "F.Cu")
		(net "SMB_PEX3_HOST_LS_SDA")
	)
	(via
		(at 438.32272 -294.016176)
		(size 0.508)
		(drill 0.254)
		(layers "F.Cu" "B.Cu")
		(net "SMB_PEX3_HOST_LS_SDA")
	)
	(segment
		(start 364.60938 -196.723)
		(end 365.10595 -196.723)
		(width 0.13208)
		(layer "F.Cu")
		(net "PRSNT_SSD5_FPGA_R_N")
	)
	(segment
		(start 364.49 -196.995288)
		(end 364.49 -196.84238)
		(width 0.13208)
		(layer "F.Cu")
		(net "PRSNT_SSD5_FPGA_R_N")
	)
	(segment
		(start 357.91521 -196.47408)
		(end 361.530138 -196.47408)
		(width 0.13208)
		(layer "F.Cu")
		(net "PRSNT_SSD5_FPGA_R_N")
	)
	(segment
		(start 364.088172 -197.397116)
		(end 364.49 -196.995288)
		(width 0.13208)
		(layer "F.Cu")
		(net "PRSNT_SSD5_FPGA_R_N")
	)
	(segment
		(start 348.742 -204.83195)
		(end 348.742 -204.216)
		(width 0.13208)
		(layer "F.Cu")
		(net "PRSNT_SSD5_FPGA_R_N")
	)
	(segment
		(start 361.530138 -196.47408)
		(end 362.453174 -197.397116)
		(width 0.13208)
		(layer "F.Cu")
		(net "PRSNT_SSD5_FPGA_R_N")
	)
	(segment
		(start 362.453174 -197.397116)
		(end 364.088172 -197.397116)
		(width 0.13208)
		(layer "F.Cu")
		(net "PRSNT_SSD5_FPGA_R_N")
	)
	(segment
		(start 364.49 -196.84238)
		(end 364.60938 -196.723)
		(width 0.13208)
		(layer "F.Cu")
		(net "PRSNT_SSD5_FPGA_R_N")
	)
	(via
		(at 357.91521 -196.47408)
		(size 0.508)
		(drill 0.254)
		(layers "F.Cu" "B.Cu")
		(net "PRSNT_SSD5_FPGA_R_N")
	)
	(via
		(at 348.742 -204.216)
		(size 0.508)
		(drill 0.254)
		(layers "F.Cu" "B.Cu")
		(net "PRSNT_SSD5_FPGA_R_N")
	)
	(segment
		(start 350.03232 -202.92568)
		(end 353.513136 -202.92568)
		(width 0.15494)
		(layer "In5.Cu")
		(net "PRSNT_SSD5_FPGA_R_N")
	)
	(segment
		(start 357.695754 -199.771)
		(end 357.91521 -199.551544)
		(width 0.15494)
		(layer "In5.Cu")
		(net "PRSNT_SSD5_FPGA_R_N")
	)
	(segment
		(start 353.513136 -202.92568)
		(end 356.667816 -199.771)
		(width 0.15494)
		(layer "In5.Cu")
		(net "PRSNT_SSD5_FPGA_R_N")
	)
	(segment
		(start 348.742 -204.216)
		(end 350.03232 -202.92568)
		(width 0.15494)
		(layer "In5.Cu")
		(net "PRSNT_SSD5_FPGA_R_N")
	)
	(segment
		(start 356.667816 -199.771)
		(end 357.695754 -199.771)
		(width 0.15494)
		(layer "In5.Cu")
		(net "PRSNT_SSD5_FPGA_R_N")
	)
	(segment
		(start 357.91521 -199.551544)
		(end 357.91521 -196.47408)
		(width 0.15494)
		(layer "In5.Cu")
		(net "PRSNT_SSD5_FPGA_R_N")
	)
	(segment
		(start 362.29036 -253.178564)
		(end 362.931456 -253.178564)
		(width 0.13208)
		(layer "F.Cu")
		(net "PWRGD_P0V8_PEX2_R")
	)
	(segment
		(start 338.893912 -222.38716)
		(end 338.494116 -222.786956)
		(width 0.13208)
		(layer "F.Cu")
		(net "PWRGD_P0V8_PEX2_R")
	)
	(via
		(at 338.494116 -222.786956)
		(size 0.4572)
		(drill 0.254)
		(layers "F.Cu" "B.Cu")
		(net "PWRGD_P0V8_PEX2_R")
	)
	(via
		(at 362.931456 -253.178564)
		(size 0.508)
		(drill 0.254)
		(layers "F.Cu" "B.Cu")
		(net "PWRGD_P0V8_PEX2_R")
	)
	(via
		(at 332.120494 -250.685554)
		(size 0.508)
		(drill 0.254)
		(layers "F.Cu" "B.Cu")
		(net "PWRGD_P0V8_PEX2_R")
	)
	(segment
		(start 329.8952 -238.377984)
		(end 333.5274 -242.010184)
		(width 0.15494)
		(layer "In7.Cu")
		(net "PWRGD_P0V8_PEX2_R")
	)
	(segment
		(start 331.2414 -233.996484)
		(end 330.835 -234.402884)
		(width 0.15494)
		(layer "In7.Cu")
		(net "PWRGD_P0V8_PEX2_R")
	)
	(segment
		(start 333.5274 -242.010184)
		(end 333.5274 -248.477024)
		(width 0.15494)
		(layer "In7.Cu")
		(net "PWRGD_P0V8_PEX2_R")
	)
	(segment
		(start 330.9874 -227.221796)
		(end 331.18171 -227.416106)
		(width 0.15494)
		(layer "In7.Cu")
		(net "PWRGD_P0V8_PEX2_R")
	)
	(segment
		(start 331.2414 -230.191564)
		(end 331.2414 -233.996484)
		(width 0.15494)
		(layer "In7.Cu")
		(net "PWRGD_P0V8_PEX2_R")
	)
	(segment
		(start 330.9874 -225.6028)
		(end 330.9874 -227.221796)
		(width 0.15494)
		(layer "In7.Cu")
		(net "PWRGD_P0V8_PEX2_R")
	)
	(segment
		(start 330.835 -234.402884)
		(end 330.835 -236.542072)
		(width 0.15494)
		(layer "In7.Cu")
		(net "PWRGD_P0V8_PEX2_R")
	)
	(segment
		(start 333.403448 -223.186752)
		(end 330.9874 -225.6028)
		(width 0.15494)
		(layer "In7.Cu")
		(net "PWRGD_P0V8_PEX2_R")
	)
	(segment
		(start 331.18171 -228.930962)
		(end 330.994512 -229.11816)
		(width 0.15494)
		(layer "In7.Cu")
		(net "PWRGD_P0V8_PEX2_R")
	)
	(segment
		(start 338.09432 -223.186752)
		(end 335.0006 -223.186752)
		(width 0.0889)
		(layer "In7.Cu")
		(net "PWRGD_P0V8_PEX2_R")
	)
	(segment
		(start 333.5274 -248.477024)
		(end 332.120494 -249.88393)
		(width 0.15494)
		(layer "In7.Cu")
		(net "PWRGD_P0V8_PEX2_R")
	)
	(segment
		(start 338.494116 -222.786956)
		(end 338.09432 -223.186752)
		(width 0.0889)
		(layer "In7.Cu")
		(net "PWRGD_P0V8_PEX2_R")
	)
	(segment
		(start 330.994512 -229.944676)
		(end 331.2414 -230.191564)
		(width 0.15494)
		(layer "In7.Cu")
		(net "PWRGD_P0V8_PEX2_R")
	)
	(segment
		(start 331.18171 -227.416106)
		(end 331.18171 -228.930962)
		(width 0.15494)
		(layer "In7.Cu")
		(net "PWRGD_P0V8_PEX2_R")
	)
	(segment
		(start 330.835 -236.542072)
		(end 329.8952 -237.481872)
		(width 0.15494)
		(layer "In7.Cu")
		(net "PWRGD_P0V8_PEX2_R")
	)
	(segment
		(start 329.8952 -237.481872)
		(end 329.8952 -238.377984)
		(width 0.15494)
		(layer "In7.Cu")
		(net "PWRGD_P0V8_PEX2_R")
	)
	(segment
		(start 335.0006 -223.186752)
		(end 333.403448 -223.186752)
		(width 0.15494)
		(layer "In7.Cu")
		(net "PWRGD_P0V8_PEX2_R")
	)
	(segment
		(start 330.994512 -229.11816)
		(end 330.994512 -229.944676)
		(width 0.15494)
		(layer "In7.Cu")
		(net "PWRGD_P0V8_PEX2_R")
	)
	(segment
		(start 332.120494 -249.88393)
		(end 332.120494 -250.685554)
		(width 0.15494)
		(layer "In7.Cu")
		(net "PWRGD_P0V8_PEX2_R")
	)
	(segment
		(start 332.120494 -250.675902)
		(end 332.120494 -250.685554)
		(width 0.15494)
		(layer "In9.Cu")
		(net "PWRGD_P0V8_PEX2_R")
	)
	(segment
		(start 333.179674 -249.616722)
		(end 332.120494 -250.675902)
		(width 0.15494)
		(layer "In9.Cu")
		(net "PWRGD_P0V8_PEX2_R")
	)
	(segment
		(start 362.931456 -253.178564)
		(end 359.369614 -249.616722)
		(width 0.15494)
		(layer "In9.Cu")
		(net "PWRGD_P0V8_PEX2_R")
	)
	(segment
		(start 359.369614 -249.616722)
		(end 333.179674 -249.616722)
		(width 0.15494)
		(layer "In9.Cu")
		(net "PWRGD_P0V8_PEX2_R")
	)
	(segment
		(start 238.116364 -219.978732)
		(end 237.664752 -219.52712)
		(width 0.13208)
		(layer "F.Cu")
		(net "PD_BIC_ADCREXT1")
	)
	(segment
		(start 236.59084 -217.094308)
		(end 235.561378 -217.094308)
		(width 0.13208)
		(layer "F.Cu")
		(net "PD_BIC_ADCREXT1")
	)
	(segment
		(start 240.406428 -220.884496)
		(end 241.058446 -221.536514)
		(width 0.13208)
		(layer "F.Cu")
		(net "PD_BIC_ADCREXT1")
	)
	(segment
		(start 239.500664 -219.978732)
		(end 238.116364 -219.978732)
		(width 0.13208)
		(layer "F.Cu")
		(net "PD_BIC_ADCREXT1")
	)
	(segment
		(start 237.664752 -219.52712)
		(end 237.10138 -218.167204)
		(width 0.13208)
		(layer "F.Cu")
		(net "PD_BIC_ADCREXT1")
	)
	(segment
		(start 237.10138 -217.604848)
		(end 236.59084 -217.094308)
		(width 0.13208)
		(layer "F.Cu")
		(net "PD_BIC_ADCREXT1")
	)
	(segment
		(start 235.544868 -217.101166)
		(end 235.07065 -217.101166)
		(width 0.13208)
		(layer "F.Cu")
		(net "PD_BIC_ADCREXT1")
	)
	(segment
		(start 242.893342 -221.423484)
		(end 242.893342 -221.050612)
		(width 0.13208)
		(layer "F.Cu")
		(net "PD_BIC_ADCREXT1")
	)
	(segment
		(start 237.10138 -218.167204)
		(end 237.10138 -217.604848)
		(width 0.13208)
		(layer "F.Cu")
		(net "PD_BIC_ADCREXT1")
	)
	(segment
		(start 235.561378 -217.094308)
		(end 235.544868 -217.101166)
		(width 0.13208)
		(layer "F.Cu")
		(net "PD_BIC_ADCREXT1")
	)
	(segment
		(start 242.780312 -221.536514)
		(end 242.893342 -221.423484)
		(width 0.13208)
		(layer "F.Cu")
		(net "PD_BIC_ADCREXT1")
	)
	(segment
		(start 235.07065 -217.101166)
		(end 234.667552 -217.504264)
		(width 0.13208)
		(layer "F.Cu")
		(net "PD_BIC_ADCREXT1")
	)
	(segment
		(start 241.058446 -221.536514)
		(end 242.780312 -221.536514)
		(width 0.13208)
		(layer "F.Cu")
		(net "PD_BIC_ADCREXT1")
	)
	(segment
		(start 240.406428 -220.884496)
		(end 239.500664 -219.978732)
		(width 0.13208)
		(layer "F.Cu")
		(net "PD_BIC_ADCREXT1")
	)
	(via
		(at 240.406428 -220.884496)
		(size 0.762)
		(drill 0.381)
		(layers "F.Cu" "B.Cu")
		(net "PD_BIC_ADCREXT1")
	)
	(segment
		(start 441.9092 -297.69562)
		(end 441.73902 -297.8658)
		(width 0.13208)
		(layer "F.Cu")
		(net "SMB_PEX3_HOST_LS_SCL")
	)
	(segment
		(start 441.9092 -294.995346)
		(end 441.9092 -297.69562)
		(width 0.13208)
		(layer "F.Cu")
		(net "SMB_PEX3_HOST_LS_SCL")
	)
	(segment
		(start 439.168032 -289.630866)
		(end 439.264552 -289.727386)
		(width 0.13208)
		(layer "F.Cu")
		(net "SMB_PEX3_HOST_LS_SCL")
	)
	(segment
		(start 441.73902 -297.8658)
		(end 440.37758 -297.8658)
		(width 0.13208)
		(layer "F.Cu")
		(net "SMB_PEX3_HOST_LS_SCL")
	)
	(segment
		(start 441.200032 -289.630866)
		(end 440.184032 -289.630866)
		(width 0.13208)
		(layer "F.Cu")
		(net "SMB_PEX3_HOST_LS_SCL")
	)
	(segment
		(start 439.962798 -293.980616)
		(end 440.89447 -293.980616)
		(width 0.13208)
		(layer "F.Cu")
		(net "SMB_PEX3_HOST_LS_SCL")
	)
	(segment
		(start 440.184032 -289.630866)
		(end 439.168032 -289.630866)
		(width 0.13208)
		(layer "F.Cu")
		(net "SMB_PEX3_HOST_LS_SCL")
	)
	(segment
		(start 440.37758 -297.8658)
		(end 439.97626 -297.46448)
		(width 0.13208)
		(layer "F.Cu")
		(net "SMB_PEX3_HOST_LS_SCL")
	)
	(segment
		(start 439.264552 -293.28237)
		(end 439.264552 -291.297868)
		(width 0.13208)
		(layer "F.Cu")
		(net "SMB_PEX3_HOST_LS_SCL")
	)
	(segment
		(start 439.962798 -293.980616)
		(end 439.264552 -293.28237)
		(width 0.13208)
		(layer "F.Cu")
		(net "SMB_PEX3_HOST_LS_SCL")
	)
	(segment
		(start 440.89447 -293.980616)
		(end 441.9092 -294.995346)
		(width 0.13208)
		(layer "F.Cu")
		(net "SMB_PEX3_HOST_LS_SCL")
	)
	(segment
		(start 439.264552 -289.727386)
		(end 439.264552 -291.297868)
		(width 0.13208)
		(layer "F.Cu")
		(net "SMB_PEX3_HOST_LS_SCL")
	)
	(via
		(at 439.962798 -293.980616)
		(size 0.508)
		(drill 0.254)
		(layers "F.Cu" "B.Cu")
		(net "SMB_PEX3_HOST_LS_SCL")
	)
	(segment
		(start 347.218 -203.9112)
		(end 348.437962 -202.691238)
		(width 0.13208)
		(layer "F.Cu")
		(net "PRSNT_SSD4_FPGA_R_N")
	)
	(segment
		(start 364.654338 -200.787)
		(end 365.10595 -200.787)
		(width 0.13208)
		(layer "F.Cu")
		(net "PRSNT_SSD4_FPGA_R_N")
	)
	(segment
		(start 348.437962 -202.691238)
		(end 358.975914 -202.691238)
		(width 0.13208)
		(layer "F.Cu")
		(net "PRSNT_SSD4_FPGA_R_N")
	)
	(segment
		(start 358.975914 -202.691238)
		(end 360.389424 -201.277728)
		(width 0.13208)
		(layer "F.Cu")
		(net "PRSNT_SSD4_FPGA_R_N")
	)
	(segment
		(start 360.389424 -201.277728)
		(end 364.16361 -201.277728)
		(width 0.13208)
		(layer "F.Cu")
		(net "PRSNT_SSD4_FPGA_R_N")
	)
	(segment
		(start 364.16361 -201.277728)
		(end 364.654338 -200.787)
		(width 0.13208)
		(layer "F.Cu")
		(net "PRSNT_SSD4_FPGA_R_N")
	)
	(segment
		(start 347.218 -206.15148)
		(end 347.218 -203.9112)
		(width 0.13208)
		(layer "F.Cu")
		(net "PRSNT_SSD4_FPGA_R_N")
	)
	(via
		(at 347.218 -206.15148)
		(size 0.508)
		(drill 0.254)
		(layers "F.Cu" "B.Cu")
		(net "PRSNT_SSD4_FPGA_R_N")
	)
	(segment
		(start 347.726 -206.65948)
		(end 347.218 -206.15148)
		(width 0.13208)
		(layer "B.Cu")
		(net "PRSNT_SSD4_FPGA_R_N")
	)
	(segment
		(start 347.726 -207.37195)
		(end 347.726 -206.65948)
		(width 0.13208)
		(layer "B.Cu")
		(net "PRSNT_SSD4_FPGA_R_N")
	)
	(segment
		(start 330.620878 -228.378766)
		(end 331.606144 -227.3935)
		(width 0.13208)
		(layer "F.Cu")
		(net "PWRGD_P0V8_PEX3_R")
	)
	(segment
		(start 362.29036 -259.147564)
		(end 362.921042 -259.147564)
		(width 0.13208)
		(layer "F.Cu")
		(net "PWRGD_P0V8_PEX3_R")
	)
	(segment
		(start 333.087472 -227.3935)
		(end 334.09382 -226.387152)
		(width 0.13208)
		(layer "F.Cu")
		(net "PWRGD_P0V8_PEX3_R")
	)
	(segment
		(start 331.606144 -227.3935)
		(end 333.087472 -227.3935)
		(width 0.13208)
		(layer "F.Cu")
		(net "PWRGD_P0V8_PEX3_R")
	)
	(via
		(at 362.921042 -259.147564)
		(size 0.508)
		(drill 0.254)
		(layers "F.Cu" "B.Cu")
		(net "PWRGD_P0V8_PEX3_R")
	)
	(via
		(at 332.157578 -248.88698)
		(size 0.508)
		(drill 0.254)
		(layers "F.Cu" "B.Cu")
		(net "PWRGD_P0V8_PEX3_R")
	)
	(via
		(at 330.620878 -228.378766)
		(size 0.508)
		(drill 0.254)
		(layers "F.Cu" "B.Cu")
		(net "PWRGD_P0V8_PEX3_R")
	)
	(segment
		(start 330.620878 -229.04323)
		(end 330.620878 -228.378766)
		(width 0.15494)
		(layer "In7.Cu")
		(net "PWRGD_P0V8_PEX3_R")
	)
	(segment
		(start 332.157578 -248.88698)
		(end 332.157578 -247.22328)
		(width 0.15494)
		(layer "In7.Cu")
		(net "PWRGD_P0V8_PEX3_R")
	)
	(segment
		(start 330.2 -236.372654)
		(end 330.2 -229.464108)
		(width 0.15494)
		(layer "In7.Cu")
		(net "PWRGD_P0V8_PEX3_R")
	)
	(segment
		(start 328.549 -239.374172)
		(end 328.549 -238.023654)
		(width 0.15494)
		(layer "In7.Cu")
		(net "PWRGD_P0V8_PEX3_R")
	)
	(segment
		(start 328.549 -238.023654)
		(end 330.2 -236.372654)
		(width 0.15494)
		(layer "In7.Cu")
		(net "PWRGD_P0V8_PEX3_R")
	)
	(segment
		(start 330.2 -229.464108)
		(end 330.620878 -229.04323)
		(width 0.15494)
		(layer "In7.Cu")
		(net "PWRGD_P0V8_PEX3_R")
	)
	(segment
		(start 332.486 -243.311172)
		(end 328.549 -239.374172)
		(width 0.15494)
		(layer "In7.Cu")
		(net "PWRGD_P0V8_PEX3_R")
	)
	(segment
		(start 332.157578 -247.22328)
		(end 332.486 -246.894858)
		(width 0.15494)
		(layer "In7.Cu")
		(net "PWRGD_P0V8_PEX3_R")
	)
	(segment
		(start 332.486 -246.894858)
		(end 332.486 -243.311172)
		(width 0.15494)
		(layer "In7.Cu")
		(net "PWRGD_P0V8_PEX3_R")
	)
	(segment
		(start 362.921042 -259.147564)
		(end 363.428788 -258.639818)
		(width 0.15494)
		(layer "In9.Cu")
		(net "PWRGD_P0V8_PEX3_R")
	)
	(segment
		(start 359.37698 -248.88698)
		(end 332.157578 -248.88698)
		(width 0.15494)
		(layer "In9.Cu")
		(net "PWRGD_P0V8_PEX3_R")
	)
	(segment
		(start 363.428788 -252.938788)
		(end 359.37698 -248.88698)
		(width 0.15494)
		(layer "In9.Cu")
		(net "PWRGD_P0V8_PEX3_R")
	)
	(segment
		(start 363.428788 -258.639818)
		(end 363.428788 -252.938788)
		(width 0.15494)
		(layer "In9.Cu")
		(net "PWRGD_P0V8_PEX3_R")
	)
	(segment
		(start 239.500664 -219.674948)
		(end 239.148112 -219.322396)
		(width 0.13208)
		(layer "F.Cu")
		(net "PD_BIC_ADCREXT0")
	)
	(segment
		(start 237.178342 -216.691972)
		(end 237.38586 -216.89949)
		(width 0.13208)
		(layer "F.Cu")
		(net "PD_BIC_ADCREXT0")
	)
	(segment
		(start 237.814866 -219.145866)
		(end 237.991396 -219.322396)
		(width 0.13208)
		(layer "F.Cu")
		(net "PD_BIC_ADCREXT0")
	)
	(segment
		(start 239.916208 -219.674948)
		(end 239.500664 -219.674948)
		(width 0.13208)
		(layer "F.Cu")
		(net "PD_BIC_ADCREXT0")
	)
	(segment
		(start 237.38586 -218.110054)
		(end 237.814866 -219.145866)
		(width 0.13208)
		(layer "F.Cu")
		(net "PD_BIC_ADCREXT0")
	)
	(segment
		(start 235.467652 -216.704164)
		(end 235.65739 -216.514426)
		(width 0.13208)
		(layer "F.Cu")
		(net "PD_BIC_ADCREXT0")
	)
	(segment
		(start 236.892338 -216.691972)
		(end 237.178342 -216.691972)
		(width 0.13208)
		(layer "F.Cu")
		(net "PD_BIC_ADCREXT0")
	)
	(segment
		(start 239.148112 -219.322396)
		(end 238.506 -219.322396)
		(width 0.13208)
		(layer "F.Cu")
		(net "PD_BIC_ADCREXT0")
	)
	(segment
		(start 237.991396 -219.322396)
		(end 238.506 -219.322396)
		(width 0.13208)
		(layer "F.Cu")
		(net "PD_BIC_ADCREXT0")
	)
	(segment
		(start 235.65739 -216.514426)
		(end 236.714792 -216.514426)
		(width 0.13208)
		(layer "F.Cu")
		(net "PD_BIC_ADCREXT0")
	)
	(segment
		(start 236.714792 -216.514426)
		(end 236.892338 -216.691972)
		(width 0.13208)
		(layer "F.Cu")
		(net "PD_BIC_ADCREXT0")
	)
	(segment
		(start 237.38586 -216.89949)
		(end 237.38586 -218.110054)
		(width 0.13208)
		(layer "F.Cu")
		(net "PD_BIC_ADCREXT0")
	)
	(via
		(at 238.506 -219.322396)
		(size 0.762)
		(drill 0.381)
		(layers "F.Cu" "B.Cu")
		(net "PD_BIC_ADCREXT0")
	)
	(segment
		(start 439.17616 -297.46448)
		(end 439.21934 -297.4213)
		(width 0.13208)
		(layer "F.Cu")
		(net "I2C_PEX3_HOST_R_SCL")
	)
	(segment
		(start 439.264552 -296.56786)
		(end 439.264552 -295.647872)
		(width 0.13208)
		(layer "F.Cu")
		(net "I2C_PEX3_HOST_R_SCL")
	)
	(segment
		(start 439.21934 -296.613072)
		(end 439.264552 -296.56786)
		(width 0.13208)
		(layer "F.Cu")
		(net "I2C_PEX3_HOST_R_SCL")
	)
	(segment
		(start 440.689746 -298.485052)
		(end 439.673746 -298.485052)
		(width 0.13208)
		(layer "F.Cu")
		(net "I2C_PEX3_HOST_R_SCL")
	)
	(segment
		(start 439.17616 -298.358052)
		(end 439.17616 -297.46448)
		(width 0.13208)
		(layer "F.Cu")
		(net "I2C_PEX3_HOST_R_SCL")
	)
	(segment
		(start 439.21934 -297.4213)
		(end 439.21934 -296.613072)
		(width 0.13208)
		(layer "F.Cu")
		(net "I2C_PEX3_HOST_R_SCL")
	)
	(segment
		(start 439.673746 -298.485052)
		(end 439.30316 -298.485052)
		(width 0.13208)
		(layer "F.Cu")
		(net "I2C_PEX3_HOST_R_SCL")
	)
	(segment
		(start 439.30316 -298.485052)
		(end 439.17616 -298.358052)
		(width 0.13208)
		(layer "F.Cu")
		(net "I2C_PEX3_HOST_R_SCL")
	)
	(via
		(at 439.21934 -296.613072)
		(size 0.508)
		(drill 0.254)
		(layers "F.Cu" "B.Cu")
		(net "I2C_PEX3_HOST_R_SCL")
	)
	(segment
		(start 325.442326 -212.214968)
		(end 326.460358 -213.233)
		(width 0.13208)
		(layer "F.Cu")
		(net "PRSNT_SSD7_FPGA_R_N")
	)
	(segment
		(start 360.78795 -175.006)
		(end 360.172 -175.006)
		(width 0.13208)
		(layer "F.Cu")
		(net "PRSNT_SSD7_FPGA_R_N")
	)
	(segment
		(start 326.460358 -213.233)
		(end 327.13295 -213.233)
		(width 0.13208)
		(layer "F.Cu")
		(net "PRSNT_SSD7_FPGA_R_N")
	)
	(via
		(at 325.442326 -212.214968)
		(size 0.508)
		(drill 0.254)
		(layers "F.Cu" "B.Cu")
		(net "PRSNT_SSD7_FPGA_R_N")
	)
	(via
		(at 325.9836 -181.737)
		(size 0.508)
		(drill 0.254)
		(layers "F.Cu" "B.Cu")
		(net "PRSNT_SSD7_FPGA_R_N")
	)
	(via
		(at 360.172 -175.006)
		(size 0.508)
		(drill 0.254)
		(layers "F.Cu" "B.Cu")
		(net "PRSNT_SSD7_FPGA_R_N")
	)
	(segment
		(start 325.442326 -212.158326)
		(end 323.617336 -210.333336)
		(width 0.15494)
		(layer "In9.Cu")
		(net "PRSNT_SSD7_FPGA_R_N")
	)
	(segment
		(start 327.17486 -182.92826)
		(end 325.9836 -181.737)
		(width 0.15494)
		(layer "In9.Cu")
		(net "PRSNT_SSD7_FPGA_R_N")
	)
	(segment
		(start 327.17486 -194.542156)
		(end 327.17486 -182.92826)
		(width 0.15494)
		(layer "In9.Cu")
		(net "PRSNT_SSD7_FPGA_R_N")
	)
	(segment
		(start 325.442326 -212.214968)
		(end 325.442326 -212.158326)
		(width 0.15494)
		(layer "In9.Cu")
		(net "PRSNT_SSD7_FPGA_R_N")
	)
	(segment
		(start 323.617336 -204.606906)
		(end 323.858128 -201.871072)
		(width 0.15494)
		(layer "In9.Cu")
		(net "PRSNT_SSD7_FPGA_R_N")
	)
	(segment
		(start 323.617336 -210.333336)
		(end 323.617336 -204.606906)
		(width 0.15494)
		(layer "In9.Cu")
		(net "PRSNT_SSD7_FPGA_R_N")
	)
	(segment
		(start 326.31126 -195.405756)
		(end 327.17486 -194.542156)
		(width 0.15494)
		(layer "In9.Cu")
		(net "PRSNT_SSD7_FPGA_R_N")
	)
	(segment
		(start 323.858128 -201.871072)
		(end 326.31126 -199.41794)
		(width 0.15494)
		(layer "In9.Cu")
		(net "PRSNT_SSD7_FPGA_R_N")
	)
	(segment
		(start 326.31126 -199.41794)
		(end 326.31126 -195.405756)
		(width 0.15494)
		(layer "In9.Cu")
		(net "PRSNT_SSD7_FPGA_R_N")
	)
	(segment
		(start 356.170992 -175.016668)
		(end 356.69474 -174.49292)
		(width 0.15494)
		(layer "In13.Cu")
		(net "PRSNT_SSD7_FPGA_R_N")
	)
	(segment
		(start 356.69474 -174.49292)
		(end 359.65892 -174.49292)
		(width 0.15494)
		(layer "In13.Cu")
		(net "PRSNT_SSD7_FPGA_R_N")
	)
	(segment
		(start 334.441292 -175.016668)
		(end 356.170992 -175.016668)
		(width 0.15494)
		(layer "In13.Cu")
		(net "PRSNT_SSD7_FPGA_R_N")
	)
	(segment
		(start 359.65892 -174.49292)
		(end 360.172 -175.006)
		(width 0.15494)
		(layer "In13.Cu")
		(net "PRSNT_SSD7_FPGA_R_N")
	)
	(segment
		(start 325.9836 -181.737)
		(end 327.72096 -181.737)
		(width 0.15494)
		(layer "In13.Cu")
		(net "PRSNT_SSD7_FPGA_R_N")
	)
	(segment
		(start 327.72096 -181.737)
		(end 334.441292 -175.016668)
		(width 0.15494)
		(layer "In13.Cu")
		(net "PRSNT_SSD7_FPGA_R_N")
	)
	(segment
		(start 130.090164 -253.178564)
		(end 130.73126 -253.178564)
		(width 0.13208)
		(layer "F.Cu")
		(net "PWRGD_P0V8_PEX0_R")
	)
	(segment
		(start 337.293966 -223.987106)
		(end 336.89417 -224.386902)
		(width 0.13208)
		(layer "F.Cu")
		(net "PWRGD_P0V8_PEX0_R")
	)
	(via
		(at 126.620778 -219.809568)
		(size 0.508)
		(drill 0.254)
		(layers "F.Cu" "B.Cu")
		(net "PWRGD_P0V8_PEX0_R")
	)
	(via
		(at 336.89417 -224.386902)
		(size 0.4572)
		(drill 0.254)
		(layers "F.Cu" "B.Cu")
		(net "PWRGD_P0V8_PEX0_R")
	)
	(via
		(at 130.73126 -253.178564)
		(size 0.508)
		(drill 0.254)
		(layers "F.Cu" "B.Cu")
		(net "PWRGD_P0V8_PEX0_R")
	)
	(segment
		(start 126.620778 -243.207286)
		(end 126.620778 -219.809568)
		(width 0.15494)
		(layer "In5.Cu")
		(net "PWRGD_P0V8_PEX0_R")
	)
	(segment
		(start 130.73126 -253.178564)
		(end 130.73126 -247.317768)
		(width 0.15494)
		(layer "In5.Cu")
		(net "PWRGD_P0V8_PEX0_R")
	)
	(segment
		(start 130.73126 -247.317768)
		(end 126.620778 -243.207286)
		(width 0.15494)
		(layer "In5.Cu")
		(net "PWRGD_P0V8_PEX0_R")
	)
	(segment
		(start 239.089184 -224.264728)
		(end 238.216186 -225.137726)
		(width 0.15494)
		(layer "In15.Cu")
		(net "PWRGD_P0V8_PEX0_R")
	)
	(segment
		(start 260.38429 -220.097096)
		(end 259.293614 -219.00642)
		(width 0.15494)
		(layer "In15.Cu")
		(net "PWRGD_P0V8_PEX0_R")
	)
	(segment
		(start 128.347216 -219.492576)
		(end 128.030224 -219.809568)
		(width 0.15494)
		(layer "In15.Cu")
		(net "PWRGD_P0V8_PEX0_R")
	)
	(segment
		(start 325.731378 -226.10445)
		(end 325.42226 -226.413568)
		(width 0.15494)
		(layer "In15.Cu")
		(net "PWRGD_P0V8_PEX0_R")
	)
	(segment
		(start 334.3656 -224.9678)
		(end 334.36433 -224.96907)
		(width 0.15494)
		(layer "In15.Cu")
		(net "PWRGD_P0V8_PEX0_R")
	)
	(segment
		(start 250.027694 -219.53728)
		(end 248.120408 -219.53728)
		(width 0.15494)
		(layer "In15.Cu")
		(net "PWRGD_P0V8_PEX0_R")
	)
	(segment
		(start 217.20429 -226.863656)
		(end 215.874346 -228.1936)
		(width 0.15494)
		(layer "In15.Cu")
		(net "PWRGD_P0V8_PEX0_R")
	)
	(segment
		(start 215.874346 -228.1936)
		(end 215.366854 -228.1936)
		(width 0.15494)
		(layer "In15.Cu")
		(net "PWRGD_P0V8_PEX0_R")
	)
	(segment
		(start 212.2932 -227.9904)
		(end 209.88274 -225.57994)
		(width 0.15494)
		(layer "In15.Cu")
		(net "PWRGD_P0V8_PEX0_R")
	)
	(segment
		(start 141.26464 -219.492576)
		(end 128.347216 -219.492576)
		(width 0.15494)
		(layer "In15.Cu")
		(net "PWRGD_P0V8_PEX0_R")
	)
	(segment
		(start 236.21238 -226.812856)
		(end 234.6198 -226.812856)
		(width 0.15494)
		(layer "In15.Cu")
		(net "PWRGD_P0V8_PEX0_R")
	)
	(segment
		(start 334.5434 -224.79)
		(end 334.3656 -224.9678)
		(width 0.0889)
		(layer "In15.Cu")
		(net "PWRGD_P0V8_PEX0_R")
	)
	(segment
		(start 237.157514 -226.97694)
		(end 236.376464 -226.97694)
		(width 0.15494)
		(layer "In15.Cu")
		(net "PWRGD_P0V8_PEX0_R")
	)
	(segment
		(start 215.163654 -227.9904)
		(end 212.2932 -227.9904)
		(width 0.15494)
		(layer "In15.Cu")
		(net "PWRGD_P0V8_PEX0_R")
	)
	(segment
		(start 141.944852 -218.812364)
		(end 141.26464 -219.492576)
		(width 0.15494)
		(layer "In15.Cu")
		(net "PWRGD_P0V8_PEX0_R")
	)
	(segment
		(start 328.201528 -224.96907)
		(end 327.066148 -226.10445)
		(width 0.15494)
		(layer "In15.Cu")
		(net "PWRGD_P0V8_PEX0_R")
	)
	(segment
		(start 336.491072 -224.79)
		(end 334.5434 -224.79)
		(width 0.0889)
		(layer "In15.Cu")
		(net "PWRGD_P0V8_PEX0_R")
	)
	(segment
		(start 242.272312 -224.264728)
		(end 239.089184 -224.264728)
		(width 0.15494)
		(layer "In15.Cu")
		(net "PWRGD_P0V8_PEX0_R")
	)
	(segment
		(start 209.273648 -225.57994)
		(end 206.700882 -223.007174)
		(width 0.15494)
		(layer "In15.Cu")
		(net "PWRGD_P0V8_PEX0_R")
	)
	(segment
		(start 334.36433 -224.96907)
		(end 328.201528 -224.96907)
		(width 0.15494)
		(layer "In15.Cu")
		(net "PWRGD_P0V8_PEX0_R")
	)
	(segment
		(start 209.88274 -225.57994)
		(end 209.273648 -225.57994)
		(width 0.15494)
		(layer "In15.Cu")
		(net "PWRGD_P0V8_PEX0_R")
	)
	(segment
		(start 263.543288 -222.807022)
		(end 260.833362 -220.097096)
		(width 0.15494)
		(layer "In15.Cu")
		(net "PWRGD_P0V8_PEX0_R")
	)
	(segment
		(start 215.366854 -228.1936)
		(end 215.163654 -227.9904)
		(width 0.15494)
		(layer "In15.Cu")
		(net "PWRGD_P0V8_PEX0_R")
	)
	(segment
		(start 238.216186 -225.137726)
		(end 238.216186 -225.918268)
		(width 0.15494)
		(layer "In15.Cu")
		(net "PWRGD_P0V8_PEX0_R")
	)
	(segment
		(start 327.066148 -226.10445)
		(end 325.731378 -226.10445)
		(width 0.15494)
		(layer "In15.Cu")
		(net "PWRGD_P0V8_PEX0_R")
	)
	(segment
		(start 260.833362 -220.097096)
		(end 260.38429 -220.097096)
		(width 0.15494)
		(layer "In15.Cu")
		(net "PWRGD_P0V8_PEX0_R")
	)
	(segment
		(start 246.017542 -221.640146)
		(end 244.896894 -221.640146)
		(width 0.15494)
		(layer "In15.Cu")
		(net "PWRGD_P0V8_PEX0_R")
	)
	(segment
		(start 234.6198 -226.812856)
		(end 234.569 -226.863656)
		(width 0.15494)
		(layer "In15.Cu")
		(net "PWRGD_P0V8_PEX0_R")
	)
	(segment
		(start 250.558554 -219.00642)
		(end 250.027694 -219.53728)
		(width 0.15494)
		(layer "In15.Cu")
		(net "PWRGD_P0V8_PEX0_R")
	)
	(segment
		(start 238.216186 -225.918268)
		(end 237.157514 -226.97694)
		(width 0.15494)
		(layer "In15.Cu")
		(net "PWRGD_P0V8_PEX0_R")
	)
	(segment
		(start 325.42226 -226.413568)
		(end 324.57644 -226.413568)
		(width 0.15494)
		(layer "In15.Cu")
		(net "PWRGD_P0V8_PEX0_R")
	)
	(segment
		(start 162.902138 -223.007174)
		(end 158.707328 -218.812364)
		(width 0.15494)
		(layer "In15.Cu")
		(net "PWRGD_P0V8_PEX0_R")
	)
	(segment
		(start 206.700882 -223.007174)
		(end 162.902138 -223.007174)
		(width 0.15494)
		(layer "In15.Cu")
		(net "PWRGD_P0V8_PEX0_R")
	)
	(segment
		(start 128.030224 -219.809568)
		(end 126.620778 -219.809568)
		(width 0.15494)
		(layer "In15.Cu")
		(net "PWRGD_P0V8_PEX0_R")
	)
	(segment
		(start 244.896894 -221.640146)
		(end 242.272312 -224.264728)
		(width 0.15494)
		(layer "In15.Cu")
		(net "PWRGD_P0V8_PEX0_R")
	)
	(segment
		(start 234.569 -226.863656)
		(end 217.20429 -226.863656)
		(width 0.15494)
		(layer "In15.Cu")
		(net "PWRGD_P0V8_PEX0_R")
	)
	(segment
		(start 259.293614 -219.00642)
		(end 250.558554 -219.00642)
		(width 0.15494)
		(layer "In15.Cu")
		(net "PWRGD_P0V8_PEX0_R")
	)
	(segment
		(start 336.89417 -224.386902)
		(end 336.491072 -224.79)
		(width 0.0889)
		(layer "In15.Cu")
		(net "PWRGD_P0V8_PEX0_R")
	)
	(segment
		(start 320.969894 -222.807022)
		(end 263.543288 -222.807022)
		(width 0.15494)
		(layer "In15.Cu")
		(net "PWRGD_P0V8_PEX0_R")
	)
	(segment
		(start 248.120408 -219.53728)
		(end 246.017542 -221.640146)
		(width 0.15494)
		(layer "In15.Cu")
		(net "PWRGD_P0V8_PEX0_R")
	)
	(segment
		(start 158.707328 -218.812364)
		(end 141.944852 -218.812364)
		(width 0.15494)
		(layer "In15.Cu")
		(net "PWRGD_P0V8_PEX0_R")
	)
	(segment
		(start 324.57644 -226.413568)
		(end 320.969894 -222.807022)
		(width 0.15494)
		(layer "In15.Cu")
		(net "PWRGD_P0V8_PEX0_R")
	)
	(segment
		(start 236.376464 -226.97694)
		(end 236.21238 -226.812856)
		(width 0.15494)
		(layer "In15.Cu")
		(net "PWRGD_P0V8_PEX0_R")
	)
	(segment
		(start 360.78795 -179.07)
		(end 360.172 -179.07)
		(width 0.13208)
		(layer "F.Cu")
		(net "PRSNT_SSD6_FPGA_R_N")
	)
	(segment
		(start 350.774 -204.83195)
		(end 350.774 -204.216)
		(width 0.13208)
		(layer "F.Cu")
		(net "PRSNT_SSD6_FPGA_R_N")
	)
	(via
		(at 360.172 -179.07)
		(size 0.508)
		(drill 0.254)
		(layers "F.Cu" "B.Cu")
		(net "PRSNT_SSD6_FPGA_R_N")
	)
	(via
		(at 350.774 -204.216)
		(size 0.508)
		(drill 0.254)
		(layers "F.Cu" "B.Cu")
		(net "PRSNT_SSD6_FPGA_R_N")
	)
	(segment
		(start 351.70618 -203.28382)
		(end 350.774 -204.216)
		(width 0.15494)
		(layer "In5.Cu")
		(net "PRSNT_SSD6_FPGA_R_N")
	)
	(segment
		(start 358.81945 -199.154034)
		(end 357.821484 -200.152)
		(width 0.15494)
		(layer "In5.Cu")
		(net "PRSNT_SSD6_FPGA_R_N")
	)
	(segment
		(start 353.661726 -203.28382)
		(end 351.70618 -203.28382)
		(width 0.15494)
		(layer "In5.Cu")
		(net "PRSNT_SSD6_FPGA_R_N")
	)
	(segment
		(start 358.81945 -180.42255)
		(end 358.81945 -199.154034)
		(width 0.15494)
		(layer "In5.Cu")
		(net "PRSNT_SSD6_FPGA_R_N")
	)
	(segment
		(start 356.793546 -200.152)
		(end 353.661726 -203.28382)
		(width 0.15494)
		(layer "In5.Cu")
		(net "PRSNT_SSD6_FPGA_R_N")
	)
	(segment
		(start 360.172 -179.07)
		(end 358.81945 -180.42255)
		(width 0.15494)
		(layer "In5.Cu")
		(net "PRSNT_SSD6_FPGA_R_N")
	)
	(segment
		(start 357.821484 -200.152)
		(end 356.793546 -200.152)
		(width 0.15494)
		(layer "In5.Cu")
		(net "PRSNT_SSD6_FPGA_R_N")
	)
	(segment
		(start 130.090164 -259.147564)
		(end 130.720846 -259.147564)
		(width 0.13208)
		(layer "F.Cu")
		(net "PWRGD_P0V8_PEX1_R")
	)
	(segment
		(start 338.093812 -223.187006)
		(end 337.694016 -223.586802)
		(width 0.13208)
		(layer "F.Cu")
		(net "PWRGD_P0V8_PEX1_R")
	)
	(via
		(at 130.720846 -259.147564)
		(size 0.508)
		(drill 0.254)
		(layers "F.Cu" "B.Cu")
		(net "PWRGD_P0V8_PEX1_R")
	)
	(via
		(at 337.694016 -223.586802)
		(size 0.4572)
		(drill 0.254)
		(layers "F.Cu" "B.Cu")
		(net "PWRGD_P0V8_PEX1_R")
	)
	(via
		(at 127.859282 -219.20835)
		(size 0.508)
		(drill 0.254)
		(layers "F.Cu" "B.Cu")
		(net "PWRGD_P0V8_PEX1_R")
	)
	(segment
		(start 127.897382 -241.919506)
		(end 127.897382 -219.24645)
		(width 0.15494)
		(layer "In5.Cu")
		(net "PWRGD_P0V8_PEX1_R")
	)
	(segment
		(start 131.57327 -245.595394)
		(end 127.897382 -241.919506)
		(width 0.15494)
		(layer "In5.Cu")
		(net "PWRGD_P0V8_PEX1_R")
	)
	(segment
		(start 131.57327 -258.29514)
		(end 131.57327 -245.595394)
		(width 0.15494)
		(layer "In5.Cu")
		(net "PWRGD_P0V8_PEX1_R")
	)
	(segment
		(start 127.897382 -219.24645)
		(end 127.859282 -219.20835)
		(width 0.15494)
		(layer "In5.Cu")
		(net "PWRGD_P0V8_PEX1_R")
	)
	(segment
		(start 130.720846 -259.147564)
		(end 131.57327 -258.29514)
		(width 0.15494)
		(layer "In5.Cu")
		(net "PWRGD_P0V8_PEX1_R")
	)
	(segment
		(start 259.442204 -218.64828)
		(end 250.409964 -218.64828)
		(width 0.15494)
		(layer "In15.Cu")
		(net "PWRGD_P0V8_PEX1_R")
	)
	(segment
		(start 140.82014 -219.1258)
		(end 127.941832 -219.1258)
		(width 0.15494)
		(layer "In15.Cu")
		(net "PWRGD_P0V8_PEX1_R")
	)
	(segment
		(start 334.8482 -223.1898)
		(end 334.130904 -223.1898)
		(width 0.15494)
		(layer "In15.Cu")
		(net "PWRGD_P0V8_PEX1_R")
	)
	(segment
		(start 213.9188 -226.1616)
		(end 212.725 -226.1616)
		(width 0.15494)
		(layer "In15.Cu")
		(net "PWRGD_P0V8_PEX1_R")
	)
	(segment
		(start 325.437246 -224.063306)
		(end 323.751956 -224.063306)
		(width 0.15494)
		(layer "In15.Cu")
		(net "PWRGD_P0V8_PEX1_R")
	)
	(segment
		(start 163.084256 -222.567754)
		(end 158.970726 -218.454224)
		(width 0.15494)
		(layer "In15.Cu")
		(net "PWRGD_P0V8_PEX1_R")
	)
	(segment
		(start 236.36097 -226.454716)
		(end 216.65565 -226.454716)
		(width 0.15494)
		(layer "In15.Cu")
		(net "PWRGD_P0V8_PEX1_R")
	)
	(segment
		(start 260.53288 -219.738956)
		(end 259.442204 -218.64828)
		(width 0.15494)
		(layer "In15.Cu")
		(net "PWRGD_P0V8_PEX1_R")
	)
	(segment
		(start 326.876918 -224.456752)
		(end 325.830692 -224.456752)
		(width 0.15494)
		(layer "In15.Cu")
		(net "PWRGD_P0V8_PEX1_R")
	)
	(segment
		(start 337.694016 -223.586802)
		(end 337.297014 -223.1898)
		(width 0.0889)
		(layer "In15.Cu")
		(net "PWRGD_P0V8_PEX1_R")
	)
	(segment
		(start 242.123722 -223.906588)
		(end 238.940594 -223.906588)
		(width 0.15494)
		(layer "In15.Cu")
		(net "PWRGD_P0V8_PEX1_R")
	)
	(segment
		(start 141.491716 -218.454224)
		(end 140.82014 -219.1258)
		(width 0.15494)
		(layer "In15.Cu")
		(net "PWRGD_P0V8_PEX1_R")
	)
	(segment
		(start 238.940594 -223.906588)
		(end 237.858046 -224.989136)
		(width 0.15494)
		(layer "In15.Cu")
		(net "PWRGD_P0V8_PEX1_R")
	)
	(segment
		(start 214.9856 -226.8474)
		(end 214.6046 -226.8474)
		(width 0.15494)
		(layer "In15.Cu")
		(net "PWRGD_P0V8_PEX1_R")
	)
	(segment
		(start 262.771636 -220.706696)
		(end 261.803896 -219.738956)
		(width 0.15494)
		(layer "In15.Cu")
		(net "PWRGD_P0V8_PEX1_R")
	)
	(segment
		(start 334.130904 -223.1898)
		(end 333.394304 -223.9264)
		(width 0.15494)
		(layer "In15.Cu")
		(net "PWRGD_P0V8_PEX1_R")
	)
	(segment
		(start 329.176634 -222.98533)
		(end 328.34834 -222.98533)
		(width 0.15494)
		(layer "In15.Cu")
		(net "PWRGD_P0V8_PEX1_R")
	)
	(segment
		(start 212.725 -226.1616)
		(end 211.7852 -225.2218)
		(width 0.15494)
		(layer "In15.Cu")
		(net "PWRGD_P0V8_PEX1_R")
	)
	(segment
		(start 249.879104 -219.17914)
		(end 247.971818 -219.17914)
		(width 0.15494)
		(layer "In15.Cu")
		(net "PWRGD_P0V8_PEX1_R")
	)
	(segment
		(start 261.803896 -219.738956)
		(end 260.53288 -219.738956)
		(width 0.15494)
		(layer "In15.Cu")
		(net "PWRGD_P0V8_PEX1_R")
	)
	(segment
		(start 215.907366 -227.203)
		(end 215.3412 -227.203)
		(width 0.15494)
		(layer "In15.Cu")
		(net "PWRGD_P0V8_PEX1_R")
	)
	(segment
		(start 158.970726 -218.454224)
		(end 141.491716 -218.454224)
		(width 0.15494)
		(layer "In15.Cu")
		(net "PWRGD_P0V8_PEX1_R")
	)
	(segment
		(start 328.34834 -222.98533)
		(end 326.876918 -224.456752)
		(width 0.15494)
		(layer "In15.Cu")
		(net "PWRGD_P0V8_PEX1_R")
	)
	(segment
		(start 321.751198 -222.062548)
		(end 265.274552 -222.062548)
		(width 0.15494)
		(layer "In15.Cu")
		(net "PWRGD_P0V8_PEX1_R")
	)
	(segment
		(start 333.394304 -223.9264)
		(end 330.117704 -223.9264)
		(width 0.15494)
		(layer "In15.Cu")
		(net "PWRGD_P0V8_PEX1_R")
	)
	(segment
		(start 265.274552 -222.062548)
		(end 263.9187 -220.706696)
		(width 0.15494)
		(layer "In15.Cu")
		(net "PWRGD_P0V8_PEX1_R")
	)
	(segment
		(start 245.868952 -221.282006)
		(end 244.748304 -221.282006)
		(width 0.15494)
		(layer "In15.Cu")
		(net "PWRGD_P0V8_PEX1_R")
	)
	(segment
		(start 209.486246 -225.2218)
		(end 206.8322 -222.567754)
		(width 0.15494)
		(layer "In15.Cu")
		(net "PWRGD_P0V8_PEX1_R")
	)
	(segment
		(start 236.525054 -226.6188)
		(end 236.36097 -226.454716)
		(width 0.15494)
		(layer "In15.Cu")
		(net "PWRGD_P0V8_PEX1_R")
	)
	(segment
		(start 206.8322 -222.567754)
		(end 163.084256 -222.567754)
		(width 0.15494)
		(layer "In15.Cu")
		(net "PWRGD_P0V8_PEX1_R")
	)
	(segment
		(start 323.751956 -224.063306)
		(end 321.751198 -222.062548)
		(width 0.15494)
		(layer "In15.Cu")
		(net "PWRGD_P0V8_PEX1_R")
	)
	(segment
		(start 237.858046 -224.989136)
		(end 237.858046 -225.7425)
		(width 0.15494)
		(layer "In15.Cu")
		(net "PWRGD_P0V8_PEX1_R")
	)
	(segment
		(start 247.971818 -219.17914)
		(end 245.868952 -221.282006)
		(width 0.15494)
		(layer "In15.Cu")
		(net "PWRGD_P0V8_PEX1_R")
	)
	(segment
		(start 250.409964 -218.64828)
		(end 249.879104 -219.17914)
		(width 0.15494)
		(layer "In15.Cu")
		(net "PWRGD_P0V8_PEX1_R")
	)
	(segment
		(start 337.297014 -223.1898)
		(end 334.8482 -223.1898)
		(width 0.0889)
		(layer "In15.Cu")
		(net "PWRGD_P0V8_PEX1_R")
	)
	(segment
		(start 211.7852 -225.2218)
		(end 209.486246 -225.2218)
		(width 0.15494)
		(layer "In15.Cu")
		(net "PWRGD_P0V8_PEX1_R")
	)
	(segment
		(start 214.6046 -226.8474)
		(end 213.9188 -226.1616)
		(width 0.15494)
		(layer "In15.Cu")
		(net "PWRGD_P0V8_PEX1_R")
	)
	(segment
		(start 330.117704 -223.9264)
		(end 329.176634 -222.98533)
		(width 0.15494)
		(layer "In15.Cu")
		(net "PWRGD_P0V8_PEX1_R")
	)
	(segment
		(start 215.3412 -227.203)
		(end 214.9856 -226.8474)
		(width 0.15494)
		(layer "In15.Cu")
		(net "PWRGD_P0V8_PEX1_R")
	)
	(segment
		(start 127.941832 -219.1258)
		(end 127.859282 -219.20835)
		(width 0.15494)
		(layer "In15.Cu")
		(net "PWRGD_P0V8_PEX1_R")
	)
	(segment
		(start 236.981746 -226.6188)
		(end 236.525054 -226.6188)
		(width 0.15494)
		(layer "In15.Cu")
		(net "PWRGD_P0V8_PEX1_R")
	)
	(segment
		(start 325.830692 -224.456752)
		(end 325.437246 -224.063306)
		(width 0.15494)
		(layer "In15.Cu")
		(net "PWRGD_P0V8_PEX1_R")
	)
	(segment
		(start 244.748304 -221.282006)
		(end 242.123722 -223.906588)
		(width 0.15494)
		(layer "In15.Cu")
		(net "PWRGD_P0V8_PEX1_R")
	)
	(segment
		(start 237.858046 -225.7425)
		(end 236.981746 -226.6188)
		(width 0.15494)
		(layer "In15.Cu")
		(net "PWRGD_P0V8_PEX1_R")
	)
	(segment
		(start 263.9187 -220.706696)
		(end 262.771636 -220.706696)
		(width 0.15494)
		(layer "In15.Cu")
		(net "PWRGD_P0V8_PEX1_R")
	)
	(segment
		(start 216.65565 -226.454716)
		(end 215.907366 -227.203)
		(width 0.15494)
		(layer "In15.Cu")
		(net "PWRGD_P0V8_PEX1_R")
	)
	(segment
		(start 438.321196 -298.47286)
		(end 438.321196 -298.190412)
		(width 0.13208)
		(layer "F.Cu")
		(net "I2C_PEX3_HOST_R_SDA")
	)
	(segment
		(start 438.198514 -298.06773)
		(end 438.198514 -297.46448)
		(width 0.13208)
		(layer "F.Cu")
		(net "I2C_PEX3_HOST_R_SDA")
	)
	(segment
		(start 438.321196 -298.190412)
		(end 438.198514 -298.06773)
		(width 0.13208)
		(layer "F.Cu")
		(net "I2C_PEX3_HOST_R_SDA")
	)
	(segment
		(start 438.198514 -297.46448)
		(end 438.198514 -296.867072)
		(width 0.13208)
		(layer "F.Cu")
		(net "I2C_PEX3_HOST_R_SDA")
	)
	(segment
		(start 438.614312 -295.647872)
		(end 438.614312 -296.359834)
		(width 0.13208)
		(layer "F.Cu")
		(net "I2C_PEX3_HOST_R_SDA")
	)
	(segment
		(start 438.198514 -296.867072)
		(end 437.944514 -296.613072)
		(width 0.13208)
		(layer "F.Cu")
		(net "I2C_PEX3_HOST_R_SDA")
	)
	(segment
		(start 438.361074 -296.613072)
		(end 437.944514 -296.613072)
		(width 0.13208)
		(layer "F.Cu")
		(net "I2C_PEX3_HOST_R_SDA")
	)
	(segment
		(start 438.614312 -296.359834)
		(end 438.361074 -296.613072)
		(width 0.13208)
		(layer "F.Cu")
		(net "I2C_PEX3_HOST_R_SDA")
	)
	(segment
		(start 437.305196 -298.47286)
		(end 438.321196 -298.47286)
		(width 0.13208)
		(layer "F.Cu")
		(net "I2C_PEX3_HOST_R_SDA")
	)
	(via
		(at 437.944514 -296.613072)
		(size 0.508)
		(drill 0.254)
		(layers "F.Cu" "B.Cu")
		(net "I2C_PEX3_HOST_R_SDA")
	)
	(segment
		(start 284.176724 -97.045018)
		(end 282.842462 -97.045018)
		(width 0.13208)
		(layer "F.Cu")
		(net "NIC4_PWRBRK_R_N")
	)
	(segment
		(start 294.70985 -166.070534)
		(end 294.70985 -166.705534)
		(width 0.13208)
		(layer "F.Cu")
		(net "NIC4_PWRBRK_R_N")
	)
	(segment
		(start 284.187392 -97.055686)
		(end 284.176724 -97.045018)
		(width 0.13208)
		(layer "F.Cu")
		(net "NIC4_PWRBRK_R_N")
	)
	(via
		(at 294.70985 -166.705534)
		(size 0.508)
		(drill 0.254)
		(layers "F.Cu" "B.Cu")
		(net "NIC4_PWRBRK_R_N")
	)
	(via
		(at 284.187392 -97.055686)
		(size 0.508)
		(drill 0.254)
		(layers "F.Cu" "B.Cu")
		(net "NIC4_PWRBRK_R_N")
	)
	(segment
		(start 284.187392 -97.055686)
		(end 283.2354 -98.007678)
		(width 0.15494)
		(layer "In9.Cu")
		(net "NIC4_PWRBRK_R_N")
	)
	(segment
		(start 287.129982 -115.959128)
		(end 289.5346 -118.363746)
		(width 0.15494)
		(layer "In9.Cu")
		(net "NIC4_PWRBRK_R_N")
	)
	(segment
		(start 287.782 -134.112254)
		(end 287.782 -145.234152)
		(width 0.15494)
		(layer "In9.Cu")
		(net "NIC4_PWRBRK_R_N")
	)
	(segment
		(start 289.494214 -161.489898)
		(end 294.70985 -166.705534)
		(width 0.15494)
		(layer "In9.Cu")
		(net "NIC4_PWRBRK_R_N")
	)
	(segment
		(start 289.5346 -132.359654)
		(end 287.782 -134.112254)
		(width 0.15494)
		(layer "In9.Cu")
		(net "NIC4_PWRBRK_R_N")
	)
	(segment
		(start 283.2354 -113.502948)
		(end 285.69158 -115.959128)
		(width 0.15494)
		(layer "In9.Cu")
		(net "NIC4_PWRBRK_R_N")
	)
	(segment
		(start 283.2354 -98.007678)
		(end 283.2354 -113.502948)
		(width 0.15494)
		(layer "In9.Cu")
		(net "NIC4_PWRBRK_R_N")
	)
	(segment
		(start 285.69158 -115.959128)
		(end 287.129982 -115.959128)
		(width 0.15494)
		(layer "In9.Cu")
		(net "NIC4_PWRBRK_R_N")
	)
	(segment
		(start 289.5346 -118.363746)
		(end 289.5346 -132.359654)
		(width 0.15494)
		(layer "In9.Cu")
		(net "NIC4_PWRBRK_R_N")
	)
	(segment
		(start 289.494214 -146.946366)
		(end 289.494214 -161.489898)
		(width 0.15494)
		(layer "In9.Cu")
		(net "NIC4_PWRBRK_R_N")
	)
	(segment
		(start 287.782 -145.234152)
		(end 289.494214 -146.946366)
		(width 0.15494)
		(layer "In9.Cu")
		(net "NIC4_PWRBRK_R_N")
	)
	(segment
		(start 329.9714 -317.544196)
		(end 326.678798 -314.251594)
		(width 0.13208)
		(layer "F.Cu")
		(net "PWRGD_P12V_AUX_R")
	)
	(segment
		(start 326.678798 -314.251594)
		(end 326.678798 -279.604978)
		(width 0.13208)
		(layer "F.Cu")
		(net "PWRGD_P12V_AUX_R")
	)
	(segment
		(start 194.303142 -368.735102)
		(end 194.303142 -367.64214)
		(width 0.13208)
		(layer "F.Cu")
		(net "PWRGD_P12V_AUX_R")
	)
	(segment
		(start 359.725976 -240.435892)
		(end 360.987086 -241.697002)
		(width 0.13208)
		(layer "F.Cu")
		(net "PWRGD_P12V_AUX_R")
	)
	(segment
		(start 195.278248 -369.139724)
		(end 194.707764 -369.139724)
		(width 0.13208)
		(layer "F.Cu")
		(net "PWRGD_P12V_AUX_R")
	)
	(segment
		(start 330.833984 -275.449792)
		(end 330.833984 -266.447016)
		(width 0.13208)
		(layer "F.Cu")
		(net "PWRGD_P12V_AUX_R")
	)
	(segment
		(start 359.725976 -239.34039)
		(end 359.725976 -240.435892)
		(width 0.13208)
		(layer "F.Cu")
		(net "PWRGD_P12V_AUX_R")
	)
	(segment
		(start 329.9714 -325.9328)
		(end 329.9714 -317.544196)
		(width 0.13208)
		(layer "F.Cu")
		(net "PWRGD_P12V_AUX_R")
	)
	(segment
		(start 194.707764 -369.139724)
		(end 194.303142 -368.735102)
		(width 0.13208)
		(layer "F.Cu")
		(net "PWRGD_P12V_AUX_R")
	)
	(segment
		(start 336.546952 -258.422648)
		(end 355.62921 -239.34039)
		(width 0.13208)
		(layer "F.Cu")
		(net "PWRGD_P12V_AUX_R")
	)
	(segment
		(start 194.502024 -367.443258)
		(end 194.948048 -367.443258)
		(width 0.13208)
		(layer "F.Cu")
		(net "PWRGD_P12V_AUX_R")
	)
	(segment
		(start 355.62921 -239.34039)
		(end 359.725976 -239.34039)
		(width 0.13208)
		(layer "F.Cu")
		(net "PWRGD_P12V_AUX_R")
	)
	(segment
		(start 336.546952 -264.43432)
		(end 336.546952 -258.422648)
		(width 0.13208)
		(layer "F.Cu")
		(net "PWRGD_P12V_AUX_R")
	)
	(segment
		(start 330.833984 -266.447016)
		(end 331.91196 -265.36904)
		(width 0.13208)
		(layer "F.Cu")
		(net "PWRGD_P12V_AUX_R")
	)
	(segment
		(start 335.612232 -265.36904)
		(end 336.546952 -264.43432)
		(width 0.13208)
		(layer "F.Cu")
		(net "PWRGD_P12V_AUX_R")
	)
	(segment
		(start 360.987086 -241.697002)
		(end 361.951524 -241.697002)
		(width 0.13208)
		(layer "F.Cu")
		(net "PWRGD_P12V_AUX_R")
	)
	(segment
		(start 331.1906 -327.152)
		(end 329.9714 -325.9328)
		(width 0.13208)
		(layer "F.Cu")
		(net "PWRGD_P12V_AUX_R")
	)
	(segment
		(start 194.303142 -367.64214)
		(end 194.502024 -367.443258)
		(width 0.13208)
		(layer "F.Cu")
		(net "PWRGD_P12V_AUX_R")
	)
	(segment
		(start 326.678798 -279.604978)
		(end 330.833984 -275.449792)
		(width 0.13208)
		(layer "F.Cu")
		(net "PWRGD_P12V_AUX_R")
	)
	(segment
		(start 331.91196 -265.36904)
		(end 335.612232 -265.36904)
		(width 0.13208)
		(layer "F.Cu")
		(net "PWRGD_P12V_AUX_R")
	)
	(via
		(at 251.151136 -345.941396)
		(size 0.508)
		(drill 0.254)
		(layers "F.Cu" "B.Cu")
		(net "PWRGD_P12V_AUX_R")
	)
	(via
		(at 322.382134 -227.26904)
		(size 0.508)
		(drill 0.254)
		(layers "F.Cu" "B.Cu")
		(net "PWRGD_P12V_AUX_R")
	)
	(via
		(at 357.58755 -362.45165)
		(size 0.508)
		(drill 0.254)
		(layers "F.Cu" "B.Cu")
		(net "PWRGD_P12V_AUX_R")
	)
	(via
		(at 24.266906 -168.768522)
		(size 0.508)
		(drill 0.254)
		(layers "F.Cu" "B.Cu")
		(net "PWRGD_P12V_AUX_R")
	)
	(via
		(at 331.1906 -327.152)
		(size 0.508)
		(drill 0.254)
		(layers "F.Cu" "B.Cu")
		(net "PWRGD_P12V_AUX_R")
	)
	(via
		(at 27.836114 -202.41387)
		(size 0.508)
		(drill 0.254)
		(layers "F.Cu" "B.Cu")
		(net "PWRGD_P12V_AUX_R")
	)
	(via
		(at 276.95525 -228.357938)
		(size 0.508)
		(drill 0.254)
		(layers "F.Cu" "B.Cu")
		(net "PWRGD_P12V_AUX_R")
	)
	(via
		(at 195.278248 -369.139724)
		(size 0.508)
		(drill 0.254)
		(layers "F.Cu" "B.Cu")
		(net "PWRGD_P12V_AUX_R")
	)
	(via
		(at 359.725976 -239.34039)
		(size 0.508)
		(drill 0.254)
		(layers "F.Cu" "B.Cu")
		(net "PWRGD_P12V_AUX_R")
	)
	(segment
		(start 351.93097 -238.643668)
		(end 358.191562 -238.643668)
		(width 0.13208)
		(layer "B.Cu")
		(net "PWRGD_P12V_AUX_R")
	)
	(segment
		(start 336.82051 -239.00511)
		(end 344.232992 -239.00511)
		(width 0.13208)
		(layer "B.Cu")
		(net "PWRGD_P12V_AUX_R")
	)
	(segment
		(start 254.514096 -347.681296)
		(end 254.514096 -350.61525)
		(width 0.13208)
		(layer "B.Cu")
		(net "PWRGD_P12V_AUX_R")
	)
	(segment
		(start 348.937072 -239.664494)
		(end 350.910144 -239.664494)
		(width 0.13208)
		(layer "B.Cu")
		(net "PWRGD_P12V_AUX_R")
	)
	(segment
		(start 336.50682 -238.69142)
		(end 336.82051 -239.00511)
		(width 0.13208)
		(layer "B.Cu")
		(net "PWRGD_P12V_AUX_R")
	)
	(segment
		(start 347.320362 -239.335818)
		(end 347.612716 -239.043464)
		(width 0.13208)
		(layer "B.Cu")
		(net "PWRGD_P12V_AUX_R")
	)
	(segment
		(start 251.151136 -346.009976)
		(end 252.00229 -346.86113)
		(width 0.13208)
		(layer "B.Cu")
		(net "PWRGD_P12V_AUX_R")
	)
	(segment
		(start 329.642724 -235.383578)
		(end 329.642724 -236.031532)
		(width 0.13208)
		(layer "B.Cu")
		(net "PWRGD_P12V_AUX_R")
	)
	(segment
		(start 329.364594 -235.105448)
		(end 329.642724 -235.383578)
		(width 0.13208)
		(layer "B.Cu")
		(net "PWRGD_P12V_AUX_R")
	)
	(segment
		(start 320.729102 -228.232208)
		(end 320.729102 -233.80319)
		(width 0.13208)
		(layer "B.Cu")
		(net "PWRGD_P12V_AUX_R")
	)
	(segment
		(start 326.510396 -235.501942)
		(end 326.90689 -235.105448)
		(width 0.13208)
		(layer "B.Cu")
		(net "PWRGD_P12V_AUX_R")
	)
	(segment
		(start 345.426538 -239.025176)
		(end 346.215208 -239.025176)
		(width 0.13208)
		(layer "B.Cu")
		(net "PWRGD_P12V_AUX_R")
	)
	(segment
		(start 357.58755 -361.6198)
		(end 357.58755 -362.45165)
		(width 0.13208)
		(layer "B.Cu")
		(net "PWRGD_P12V_AUX_R")
	)
	(segment
		(start 330.97597 -237.885732)
		(end 331.781658 -238.69142)
		(width 0.13208)
		(layer "B.Cu")
		(net "PWRGD_P12V_AUX_R")
	)
	(segment
		(start 347.612716 -239.043464)
		(end 348.316042 -239.043464)
		(width 0.13208)
		(layer "B.Cu")
		(net "PWRGD_P12V_AUX_R")
	)
	(segment
		(start 253.288546 -351.8408)
		(end 252.41885 -351.8408)
		(width 0.13208)
		(layer "B.Cu")
		(net "PWRGD_P12V_AUX_R")
	)
	(segment
		(start 326.90689 -235.105448)
		(end 329.364594 -235.105448)
		(width 0.13208)
		(layer "B.Cu")
		(net "PWRGD_P12V_AUX_R")
	)
	(segment
		(start 24.266906 -168.768522)
		(end 22.544024 -168.768522)
		(width 0.13208)
		(layer "B.Cu")
		(net "PWRGD_P12V_AUX_R")
	)
	(segment
		(start 331.781658 -238.69142)
		(end 336.50682 -238.69142)
		(width 0.13208)
		(layer "B.Cu")
		(net "PWRGD_P12V_AUX_R")
	)
	(segment
		(start 320.729102 -233.80319)
		(end 322.427854 -235.501942)
		(width 0.13208)
		(layer "B.Cu")
		(net "PWRGD_P12V_AUX_R")
	)
	(segment
		(start 322.35902 -227.245926)
		(end 321.715384 -227.245926)
		(width 0.13208)
		(layer "B.Cu")
		(net "PWRGD_P12V_AUX_R")
	)
	(segment
		(start 330.97597 -237.364778)
		(end 330.97597 -237.885732)
		(width 0.13208)
		(layer "B.Cu")
		(net "PWRGD_P12V_AUX_R")
	)
	(segment
		(start 321.715384 -227.245926)
		(end 320.729102 -228.232208)
		(width 0.13208)
		(layer "B.Cu")
		(net "PWRGD_P12V_AUX_R")
	)
	(segment
		(start 346.215208 -239.025176)
		(end 346.52585 -239.335818)
		(width 0.13208)
		(layer "B.Cu")
		(net "PWRGD_P12V_AUX_R")
	)
	(segment
		(start 350.910144 -239.664494)
		(end 351.93097 -238.643668)
		(width 0.13208)
		(layer "B.Cu")
		(net "PWRGD_P12V_AUX_R")
	)
	(segment
		(start 254.514096 -350.61525)
		(end 253.288546 -351.8408)
		(width 0.13208)
		(layer "B.Cu")
		(net "PWRGD_P12V_AUX_R")
	)
	(segment
		(start 329.642724 -236.031532)
		(end 330.97597 -237.364778)
		(width 0.13208)
		(layer "B.Cu")
		(net "PWRGD_P12V_AUX_R")
	)
	(segment
		(start 358.191562 -238.643668)
		(end 358.888284 -239.34039)
		(width 0.13208)
		(layer "B.Cu")
		(net "PWRGD_P12V_AUX_R")
	)
	(segment
		(start 252.00229 -346.86113)
		(end 253.69393 -346.86113)
		(width 0.13208)
		(layer "B.Cu")
		(net "PWRGD_P12V_AUX_R")
	)
	(segment
		(start 344.232992 -239.00511)
		(end 344.43797 -239.210088)
		(width 0.13208)
		(layer "B.Cu")
		(net "PWRGD_P12V_AUX_R")
	)
	(segment
		(start 344.43797 -239.210088)
		(end 345.241626 -239.210088)
		(width 0.13208)
		(layer "B.Cu")
		(net "PWRGD_P12V_AUX_R")
	)
	(segment
		(start 322.382134 -227.26904)
		(end 322.35902 -227.245926)
		(width 0.13208)
		(layer "B.Cu")
		(net "PWRGD_P12V_AUX_R")
	)
	(segment
		(start 345.241626 -239.210088)
		(end 345.426538 -239.025176)
		(width 0.13208)
		(layer "B.Cu")
		(net "PWRGD_P12V_AUX_R")
	)
	(segment
		(start 253.69393 -346.86113)
		(end 254.514096 -347.681296)
		(width 0.13208)
		(layer "B.Cu")
		(net "PWRGD_P12V_AUX_R")
	)
	(segment
		(start 348.316042 -239.043464)
		(end 348.937072 -239.664494)
		(width 0.13208)
		(layer "B.Cu")
		(net "PWRGD_P12V_AUX_R")
	)
	(segment
		(start 358.888284 -239.34039)
		(end 359.725976 -239.34039)
		(width 0.13208)
		(layer "B.Cu")
		(net "PWRGD_P12V_AUX_R")
	)
	(segment
		(start 251.151136 -345.941396)
		(end 251.151136 -346.009976)
		(width 0.13208)
		(layer "B.Cu")
		(net "PWRGD_P12V_AUX_R")
	)
	(segment
		(start 346.52585 -239.335818)
		(end 347.320362 -239.335818)
		(width 0.13208)
		(layer "B.Cu")
		(net "PWRGD_P12V_AUX_R")
	)
	(segment
		(start 322.427854 -235.501942)
		(end 326.510396 -235.501942)
		(width 0.13208)
		(layer "B.Cu")
		(net "PWRGD_P12V_AUX_R")
	)
	(segment
		(start 27.836114 -202.41387)
		(end 27.836114 -196.70395)
		(width 0.15494)
		(layer "In5.Cu")
		(net "PWRGD_P12V_AUX_R")
	)
	(segment
		(start 277.054056 -266.94257)
		(end 273.39417 -270.602456)
		(width 0.15494)
		(layer "In5.Cu")
		(net "PWRGD_P12V_AUX_R")
	)
	(segment
		(start 277.054056 -240.013744)
		(end 277.054056 -266.94257)
		(width 0.15494)
		(layer "In5.Cu")
		(net "PWRGD_P12V_AUX_R")
	)
	(segment
		(start 273.39417 -270.602456)
		(end 270.97609 -270.602456)
		(width 0.15494)
		(layer "In5.Cu")
		(net "PWRGD_P12V_AUX_R")
	)
	(segment
		(start 201.702416 -365.631476)
		(end 198.940928 -365.631476)
		(width 0.15494)
		(layer "In5.Cu")
		(net "PWRGD_P12V_AUX_R")
	)
	(segment
		(start 27.836114 -196.70395)
		(end 24.266906 -193.134742)
		(width 0.15494)
		(layer "In5.Cu")
		(net "PWRGD_P12V_AUX_R")
	)
	(segment
		(start 263.269222 -278.309324)
		(end 259.154676 -278.309324)
		(width 0.15494)
		(layer "In5.Cu")
		(net "PWRGD_P12V_AUX_R")
	)
	(segment
		(start 198.940928 -365.631476)
		(end 197.741286 -366.831118)
		(width 0.15494)
		(layer "In5.Cu")
		(net "PWRGD_P12V_AUX_R")
	)
	(segment
		(start 257.58394 -279.88006)
		(end 257.58394 -298.40047)
		(width 0.15494)
		(layer "In5.Cu")
		(net "PWRGD_P12V_AUX_R")
	)
	(segment
		(start 204.135228 -365.38154)
		(end 201.952352 -365.38154)
		(width 0.15494)
		(layer "In5.Cu")
		(net "PWRGD_P12V_AUX_R")
	)
	(segment
		(start 24.266906 -193.134742)
		(end 24.266906 -168.768522)
		(width 0.15494)
		(layer "In5.Cu")
		(net "PWRGD_P12V_AUX_R")
	)
	(segment
		(start 270.97609 -270.602456)
		(end 263.269222 -278.309324)
		(width 0.15494)
		(layer "In5.Cu")
		(net "PWRGD_P12V_AUX_R")
	)
	(segment
		(start 278.384 -238.6838)
		(end 277.054056 -240.013744)
		(width 0.15494)
		(layer "In5.Cu")
		(net "PWRGD_P12V_AUX_R")
	)
	(segment
		(start 278.384 -229.786688)
		(end 278.384 -238.6838)
		(width 0.15494)
		(layer "In5.Cu")
		(net "PWRGD_P12V_AUX_R")
	)
	(segment
		(start 205.2066 -364.310168)
		(end 204.135228 -365.38154)
		(width 0.15494)
		(layer "In5.Cu")
		(net "PWRGD_P12V_AUX_R")
	)
	(segment
		(start 196.754242 -367.66373)
		(end 195.278248 -369.139724)
		(width 0.15494)
		(layer "In5.Cu")
		(net "PWRGD_P12V_AUX_R")
	)
	(segment
		(start 205.2066 -363.51718)
		(end 205.2066 -364.310168)
		(width 0.15494)
		(layer "In5.Cu")
		(net "PWRGD_P12V_AUX_R")
	)
	(segment
		(start 250.89358 -345.941396)
		(end 249.820684 -344.8685)
		(width 0.15494)
		(layer "In5.Cu")
		(net "PWRGD_P12V_AUX_R")
	)
	(segment
		(start 251.151136 -345.941396)
		(end 250.89358 -345.941396)
		(width 0.15494)
		(layer "In5.Cu")
		(net "PWRGD_P12V_AUX_R")
	)
	(segment
		(start 255.341628 -303.813972)
		(end 253.088902 -306.066698)
		(width 0.15494)
		(layer "In5.Cu")
		(net "PWRGD_P12V_AUX_R")
	)
	(segment
		(start 336.374486 -333.306928)
		(end 347.632528 -333.306928)
		(width 0.15494)
		(layer "In5.Cu")
		(net "PWRGD_P12V_AUX_R")
	)
	(segment
		(start 246.943626 -320.9036)
		(end 246.943626 -328.567034)
		(width 0.15494)
		(layer "In5.Cu")
		(net "PWRGD_P12V_AUX_R")
	)
	(segment
		(start 197.741286 -366.831118)
		(end 197.174358 -366.831118)
		(width 0.15494)
		(layer "In5.Cu")
		(net "PWRGD_P12V_AUX_R")
	)
	(segment
		(start 205.790546 -362.933234)
		(end 205.2066 -363.51718)
		(width 0.15494)
		(layer "In5.Cu")
		(net "PWRGD_P12V_AUX_R")
	)
	(segment
		(start 331.1906 -327.152)
		(end 331.1906 -329.1332)
		(width 0.15494)
		(layer "In5.Cu")
		(net "PWRGD_P12V_AUX_R")
	)
	(segment
		(start 253.088902 -306.066698)
		(end 246.943626 -320.9036)
		(width 0.15494)
		(layer "In5.Cu")
		(net "PWRGD_P12V_AUX_R")
	)
	(segment
		(start 205.790546 -362.126022)
		(end 205.790546 -362.933234)
		(width 0.15494)
		(layer "In5.Cu")
		(net "PWRGD_P12V_AUX_R")
	)
	(segment
		(start 276.95525 -228.357938)
		(end 278.384 -229.786688)
		(width 0.15494)
		(layer "In5.Cu")
		(net "PWRGD_P12V_AUX_R")
	)
	(segment
		(start 249.820684 -344.8685)
		(end 235.269024 -344.8685)
		(width 0.15494)
		(layer "In5.Cu")
		(net "PWRGD_P12V_AUX_R")
	)
	(segment
		(start 251.151136 -345.183968)
		(end 251.151136 -345.941396)
		(width 0.15494)
		(layer "In5.Cu")
		(net "PWRGD_P12V_AUX_R")
	)
	(segment
		(start 201.952352 -365.38154)
		(end 201.702416 -365.631476)
		(width 0.15494)
		(layer "In5.Cu")
		(net "PWRGD_P12V_AUX_R")
	)
	(segment
		(start 331.1906 -329.1332)
		(end 334.65008 -332.59268)
		(width 0.15494)
		(layer "In5.Cu")
		(net "PWRGD_P12V_AUX_R")
	)
	(segment
		(start 246.943626 -328.567034)
		(end 250.590558 -332.213966)
		(width 0.15494)
		(layer "In5.Cu")
		(net "PWRGD_P12V_AUX_R")
	)
	(segment
		(start 259.154676 -278.309324)
		(end 257.58394 -279.88006)
		(width 0.15494)
		(layer "In5.Cu")
		(net "PWRGD_P12V_AUX_R")
	)
	(segment
		(start 250.590558 -332.213966)
		(end 250.590558 -344.62339)
		(width 0.15494)
		(layer "In5.Cu")
		(net "PWRGD_P12V_AUX_R")
	)
	(segment
		(start 235.269024 -344.8685)
		(end 220.173296 -359.964228)
		(width 0.15494)
		(layer "In5.Cu")
		(net "PWRGD_P12V_AUX_R")
	)
	(segment
		(start 197.174358 -366.831118)
		(end 196.754242 -367.251234)
		(width 0.15494)
		(layer "In5.Cu")
		(net "PWRGD_P12V_AUX_R")
	)
	(segment
		(start 250.590558 -344.62339)
		(end 251.151136 -345.183968)
		(width 0.15494)
		(layer "In5.Cu")
		(net "PWRGD_P12V_AUX_R")
	)
	(segment
		(start 357.58755 -343.26195)
		(end 357.58755 -362.45165)
		(width 0.15494)
		(layer "In5.Cu")
		(net "PWRGD_P12V_AUX_R")
	)
	(segment
		(start 347.632528 -333.306928)
		(end 357.58755 -343.26195)
		(width 0.15494)
		(layer "In5.Cu")
		(net "PWRGD_P12V_AUX_R")
	)
	(segment
		(start 207.95234 -359.964228)
		(end 205.790546 -362.126022)
		(width 0.15494)
		(layer "In5.Cu")
		(net "PWRGD_P12V_AUX_R")
	)
	(segment
		(start 257.58394 -298.40047)
		(end 255.341628 -303.813972)
		(width 0.15494)
		(layer "In5.Cu")
		(net "PWRGD_P12V_AUX_R")
	)
	(segment
		(start 220.173296 -359.964228)
		(end 207.95234 -359.964228)
		(width 0.15494)
		(layer "In5.Cu")
		(net "PWRGD_P12V_AUX_R")
	)
	(segment
		(start 196.754242 -367.251234)
		(end 196.754242 -367.66373)
		(width 0.15494)
		(layer "In5.Cu")
		(net "PWRGD_P12V_AUX_R")
	)
	(segment
		(start 334.65008 -332.59268)
		(end 336.374486 -333.306928)
		(width 0.15494)
		(layer "In5.Cu")
		(net "PWRGD_P12V_AUX_R")
	)
	(segment
		(start 189.245494 -223.835214)
		(end 194.13728 -228.727)
		(width 0.15494)
		(layer "In15.Cu")
		(net "PWRGD_P12V_AUX_R")
	)
	(segment
		(start 251.8537 -219.7227)
		(end 257.001772 -219.7227)
		(width 0.15494)
		(layer "In15.Cu")
		(net "PWRGD_P12V_AUX_R")
	)
	(segment
		(start 249.764804 -221.811596)
		(end 251.8537 -219.7227)
		(width 0.15494)
		(layer "In15.Cu")
		(net "PWRGD_P12V_AUX_R")
	)
	(segment
		(start 260.669786 -220.94698)
		(end 263.246108 -223.523302)
		(width 0.15494)
		(layer "In15.Cu")
		(net "PWRGD_P12V_AUX_R")
	)
	(segment
		(start 119.949976 -212.500718)
		(end 122.596402 -215.147144)
		(width 0.15494)
		(layer "In15.Cu")
		(net "PWRGD_P12V_AUX_R")
	)
	(segment
		(start 241.414808 -227.25634)
		(end 246.859552 -221.811596)
		(width 0.15494)
		(layer "In15.Cu")
		(net "PWRGD_P12V_AUX_R")
	)
	(segment
		(start 237.891574 -227.25634)
		(end 241.414808 -227.25634)
		(width 0.15494)
		(layer "In15.Cu")
		(net "PWRGD_P12V_AUX_R")
	)
	(segment
		(start 215.069674 -228.90988)
		(end 218.6178 -228.90988)
		(width 0.15494)
		(layer "In15.Cu")
		(net "PWRGD_P12V_AUX_R")
	)
	(segment
		(start 236.968538 -228.179376)
		(end 237.891574 -227.25634)
		(width 0.15494)
		(layer "In15.Cu")
		(net "PWRGD_P12V_AUX_R")
	)
	(segment
		(start 128.70561 -220.262196)
		(end 141.50848 -220.262196)
		(width 0.15494)
		(layer "In15.Cu")
		(net "PWRGD_P12V_AUX_R")
	)
	(segment
		(start 141.50848 -220.262196)
		(end 142.041372 -219.729304)
		(width 0.15494)
		(layer "In15.Cu")
		(net "PWRGD_P12V_AUX_R")
	)
	(segment
		(start 320.737992 -227.26904)
		(end 319.412366 -225.943414)
		(width 0.15494)
		(layer "In15.Cu")
		(net "PWRGD_P12V_AUX_R")
	)
	(segment
		(start 31.743142 -201.542142)
		(end 96.718628 -201.542142)
		(width 0.15494)
		(layer "In15.Cu")
		(net "PWRGD_P12V_AUX_R")
	)
	(segment
		(start 128.316228 -220.651578)
		(end 128.70561 -220.262196)
		(width 0.15494)
		(layer "In15.Cu")
		(net "PWRGD_P12V_AUX_R")
	)
	(segment
		(start 27.836114 -202.41387)
		(end 29.132784 -201.1172)
		(width 0.15494)
		(layer "In15.Cu")
		(net "PWRGD_P12V_AUX_R")
	)
	(segment
		(start 288.986722 -225.943414)
		(end 286.572198 -228.357938)
		(width 0.15494)
		(layer "In15.Cu")
		(net "PWRGD_P12V_AUX_R")
	)
	(segment
		(start 228.172772 -228.224588)
		(end 228.871272 -228.224588)
		(width 0.15494)
		(layer "In15.Cu")
		(net "PWRGD_P12V_AUX_R")
	)
	(segment
		(start 218.6178 -228.90988)
		(end 219.947744 -227.579936)
		(width 0.15494)
		(layer "In15.Cu")
		(net "PWRGD_P12V_AUX_R")
	)
	(segment
		(start 272.906998 -224.312988)
		(end 276.95525 -228.357938)
		(width 0.15494)
		(layer "In15.Cu")
		(net "PWRGD_P12V_AUX_R")
	)
	(segment
		(start 119.949976 -212.356192)
		(end 119.949976 -212.500718)
		(width 0.15494)
		(layer "In15.Cu")
		(net "PWRGD_P12V_AUX_R")
	)
	(segment
		(start 228.871272 -228.224588)
		(end 229.515924 -227.579936)
		(width 0.15494)
		(layer "In15.Cu")
		(net "PWRGD_P12V_AUX_R")
	)
	(segment
		(start 267.71854 -224.312988)
		(end 272.906998 -224.312988)
		(width 0.15494)
		(layer "In15.Cu")
		(net "PWRGD_P12V_AUX_R")
	)
	(segment
		(start 286.572198 -228.357938)
		(end 276.95525 -228.357938)
		(width 0.15494)
		(layer "In15.Cu")
		(net "PWRGD_P12V_AUX_R")
	)
	(segment
		(start 214.886794 -228.727)
		(end 215.069674 -228.90988)
		(width 0.15494)
		(layer "In15.Cu")
		(net "PWRGD_P12V_AUX_R")
	)
	(segment
		(start 111.555784 -203.962)
		(end 119.949976 -212.356192)
		(width 0.15494)
		(layer "In15.Cu")
		(net "PWRGD_P12V_AUX_R")
	)
	(segment
		(start 96.718628 -201.542142)
		(end 102.562406 -203.962)
		(width 0.15494)
		(layer "In15.Cu")
		(net "PWRGD_P12V_AUX_R")
	)
	(segment
		(start 219.947744 -227.579936)
		(end 227.52812 -227.579936)
		(width 0.15494)
		(layer "In15.Cu")
		(net "PWRGD_P12V_AUX_R")
	)
	(segment
		(start 156.813504 -219.729304)
		(end 160.919414 -223.835214)
		(width 0.15494)
		(layer "In15.Cu")
		(net "PWRGD_P12V_AUX_R")
	)
	(segment
		(start 126.271528 -220.651578)
		(end 128.316228 -220.651578)
		(width 0.15494)
		(layer "In15.Cu")
		(net "PWRGD_P12V_AUX_R")
	)
	(segment
		(start 29.132784 -201.1172)
		(end 31.3182 -201.1172)
		(width 0.15494)
		(layer "In15.Cu")
		(net "PWRGD_P12V_AUX_R")
	)
	(segment
		(start 235.66247 -228.179376)
		(end 236.968538 -228.179376)
		(width 0.15494)
		(layer "In15.Cu")
		(net "PWRGD_P12V_AUX_R")
	)
	(segment
		(start 257.001772 -219.7227)
		(end 258.226052 -220.94698)
		(width 0.15494)
		(layer "In15.Cu")
		(net "PWRGD_P12V_AUX_R")
	)
	(segment
		(start 266.928854 -223.523302)
		(end 267.71854 -224.312988)
		(width 0.15494)
		(layer "In15.Cu")
		(net "PWRGD_P12V_AUX_R")
	)
	(segment
		(start 319.412366 -225.943414)
		(end 288.986722 -225.943414)
		(width 0.15494)
		(layer "In15.Cu")
		(net "PWRGD_P12V_AUX_R")
	)
	(segment
		(start 227.52812 -227.579936)
		(end 228.172772 -228.224588)
		(width 0.15494)
		(layer "In15.Cu")
		(net "PWRGD_P12V_AUX_R")
	)
	(segment
		(start 194.13728 -228.727)
		(end 214.886794 -228.727)
		(width 0.15494)
		(layer "In15.Cu")
		(net "PWRGD_P12V_AUX_R")
	)
	(segment
		(start 142.041372 -219.729304)
		(end 156.813504 -219.729304)
		(width 0.15494)
		(layer "In15.Cu")
		(net "PWRGD_P12V_AUX_R")
	)
	(segment
		(start 235.06303 -227.579936)
		(end 235.66247 -228.179376)
		(width 0.15494)
		(layer "In15.Cu")
		(net "PWRGD_P12V_AUX_R")
	)
	(segment
		(start 122.596402 -216.976452)
		(end 126.271528 -220.651578)
		(width 0.15494)
		(layer "In15.Cu")
		(net "PWRGD_P12V_AUX_R")
	)
	(segment
		(start 322.382134 -227.26904)
		(end 320.737992 -227.26904)
		(width 0.15494)
		(layer "In15.Cu")
		(net "PWRGD_P12V_AUX_R")
	)
	(segment
		(start 31.3182 -201.1172)
		(end 31.743142 -201.542142)
		(width 0.15494)
		(layer "In15.Cu")
		(net "PWRGD_P12V_AUX_R")
	)
	(segment
		(start 160.919414 -223.835214)
		(end 189.245494 -223.835214)
		(width 0.15494)
		(layer "In15.Cu")
		(net "PWRGD_P12V_AUX_R")
	)
	(segment
		(start 102.562406 -203.962)
		(end 111.555784 -203.962)
		(width 0.15494)
		(layer "In15.Cu")
		(net "PWRGD_P12V_AUX_R")
	)
	(segment
		(start 229.515924 -227.579936)
		(end 235.06303 -227.579936)
		(width 0.15494)
		(layer "In15.Cu")
		(net "PWRGD_P12V_AUX_R")
	)
	(segment
		(start 122.596402 -215.147144)
		(end 122.596402 -216.976452)
		(width 0.15494)
		(layer "In15.Cu")
		(net "PWRGD_P12V_AUX_R")
	)
	(segment
		(start 246.859552 -221.811596)
		(end 249.764804 -221.811596)
		(width 0.15494)
		(layer "In15.Cu")
		(net "PWRGD_P12V_AUX_R")
	)
	(segment
		(start 263.246108 -223.523302)
		(end 266.928854 -223.523302)
		(width 0.15494)
		(layer "In15.Cu")
		(net "PWRGD_P12V_AUX_R")
	)
	(segment
		(start 258.226052 -220.94698)
		(end 260.669786 -220.94698)
		(width 0.15494)
		(layer "In15.Cu")
		(net "PWRGD_P12V_AUX_R")
	)
	(segment
		(start 204.018388 -372.112794)
		(end 203.881736 -372.249446)
		(width 0.13208)
		(layer "F.Cu")
		(net "HSC_ALERT1_N")
	)
	(segment
		(start 203.68133 -373.259604)
		(end 203.881736 -373.059198)
		(width 0.13208)
		(layer "F.Cu")
		(net "HSC_ALERT1_N")
	)
	(segment
		(start 203.174854 -373.259604)
		(end 203.68133 -373.259604)
		(width 0.13208)
		(layer "F.Cu")
		(net "HSC_ALERT1_N")
	)
	(segment
		(start 204.018388 -371.194584)
		(end 204.018388 -372.112794)
		(width 0.13208)
		(layer "F.Cu")
		(net "HSC_ALERT1_N")
	)
	(segment
		(start 203.881736 -373.059198)
		(end 203.881736 -372.249446)
		(width 0.13208)
		(layer "F.Cu")
		(net "HSC_ALERT1_N")
	)
	(via
		(at 203.881736 -372.249446)
		(size 0.508)
		(drill 0.254)
		(layers "F.Cu" "B.Cu")
		(net "HSC_ALERT1_N")
	)
	(segment
		(start 203.814426 -372.182136)
		(end 203.814426 -371.088666)
		(width 0.13208)
		(layer "B.Cu")
		(net "HSC_ALERT1_N")
	)
	(segment
		(start 203.881736 -372.249446)
		(end 203.814426 -372.182136)
		(width 0.13208)
		(layer "B.Cu")
		(net "HSC_ALERT1_N")
	)
	(segment
		(start 441.320428 -299.475652)
		(end 441.129928 -299.285152)
		(width 0.13208)
		(layer "F.Cu")
		(net "I2C_PEX3_HOST_SCL")
	)
	(segment
		(start 441.320428 -299.77969)
		(end 441.320428 -299.475652)
		(width 0.13208)
		(layer "F.Cu")
		(net "I2C_PEX3_HOST_SCL")
	)
	(segment
		(start 440.677808 -300.240954)
		(end 440.687206 -300.250352)
		(width 0.13208)
		(layer "F.Cu")
		(net "I2C_PEX3_HOST_SCL")
	)
	(segment
		(start 441.320428 -300.05909)
		(end 441.320428 -299.77969)
		(width 0.13208)
		(layer "F.Cu")
		(net "I2C_PEX3_HOST_SCL")
	)
	(segment
		(start 440.687206 -300.250352)
		(end 441.129166 -300.250352)
		(width 0.13208)
		(layer "F.Cu")
		(net "I2C_PEX3_HOST_SCL")
	)
	(segment
		(start 441.129166 -300.250352)
		(end 441.320428 -300.05909)
		(width 0.13208)
		(layer "F.Cu")
		(net "I2C_PEX3_HOST_SCL")
	)
	(segment
		(start 441.129928 -299.285152)
		(end 440.689746 -299.285152)
		(width 0.13208)
		(layer "F.Cu")
		(net "I2C_PEX3_HOST_SCL")
	)
	(segment
		(start 439.679334 -300.240954)
		(end 440.677808 -300.240954)
		(width 0.13208)
		(layer "F.Cu")
		(net "I2C_PEX3_HOST_SCL")
	)
	(via
		(at 441.320428 -299.77969)
		(size 0.508)
		(drill 0.254)
		(layers "F.Cu" "B.Cu")
		(net "I2C_PEX3_HOST_SCL")
	)
	(segment
		(start 223.186244 -177.53838)
		(end 222.576644 -177.53838)
		(width 0.13208)
		(layer "F.Cu")
		(net "PWRGD_P1V2_AUX_R")
	)
	(segment
		(start 255.845564 -209.125058)
		(end 257.962908 -211.242402)
		(width 0.13208)
		(layer "F.Cu")
		(net "PWRGD_P1V2_AUX_R")
	)
	(segment
		(start 338.893912 -223.187006)
		(end 338.494116 -223.586802)
		(width 0.13208)
		(layer "F.Cu")
		(net "PWRGD_P1V2_AUX_R")
	)
	(segment
		(start 250.044458 -209.125058)
		(end 255.845564 -209.125058)
		(width 0.13208)
		(layer "F.Cu")
		(net "PWRGD_P1V2_AUX_R")
	)
	(segment
		(start 259.565902 -211.242402)
		(end 261.12724 -212.80374)
		(width 0.13208)
		(layer "F.Cu")
		(net "PWRGD_P1V2_AUX_R")
	)
	(segment
		(start 262.289036 -212.80374)
		(end 265.76528 -216.279984)
		(width 0.13208)
		(layer "F.Cu")
		(net "PWRGD_P1V2_AUX_R")
	)
	(segment
		(start 249.5042 -209.419698)
		(end 249.5042 -208.5848)
		(width 0.13208)
		(layer "F.Cu")
		(net "PWRGD_P1V2_AUX_R")
	)
	(segment
		(start 261.12724 -212.80374)
		(end 262.289036 -212.80374)
		(width 0.13208)
		(layer "F.Cu")
		(net "PWRGD_P1V2_AUX_R")
	)
	(segment
		(start 265.76528 -216.279984)
		(end 265.76528 -219.329)
		(width 0.13208)
		(layer "F.Cu")
		(net "PWRGD_P1V2_AUX_R")
	)
	(segment
		(start 265.76528 -219.329)
		(end 268.77137 -222.33509)
		(width 0.13208)
		(layer "F.Cu")
		(net "PWRGD_P1V2_AUX_R")
	)
	(segment
		(start 268.77137 -222.33509)
		(end 268.77137 -225.45929)
		(width 0.13208)
		(layer "F.Cu")
		(net "PWRGD_P1V2_AUX_R")
	)
	(segment
		(start 257.962908 -211.242402)
		(end 259.565902 -211.242402)
		(width 0.13208)
		(layer "F.Cu")
		(net "PWRGD_P1V2_AUX_R")
	)
	(segment
		(start 249.5042 -208.5848)
		(end 250.044458 -209.125058)
		(width 0.13208)
		(layer "F.Cu")
		(net "PWRGD_P1V2_AUX_R")
	)
	(segment
		(start 249.333512 -209.590386)
		(end 249.5042 -209.419698)
		(width 0.13208)
		(layer "F.Cu")
		(net "PWRGD_P1V2_AUX_R")
	)
	(via
		(at 338.494116 -223.586802)
		(size 0.4572)
		(drill 0.254)
		(layers "F.Cu" "B.Cu")
		(net "PWRGD_P1V2_AUX_R")
	)
	(via
		(at 249.5042 -208.5848)
		(size 0.508)
		(drill 0.254)
		(layers "F.Cu" "B.Cu")
		(net "PWRGD_P1V2_AUX_R")
	)
	(via
		(at 222.576644 -177.53838)
		(size 0.508)
		(drill 0.254)
		(layers "F.Cu" "B.Cu")
		(net "PWRGD_P1V2_AUX_R")
	)
	(via
		(at 268.77137 -225.45929)
		(size 0.508)
		(drill 0.254)
		(layers "F.Cu" "B.Cu")
		(net "PWRGD_P1V2_AUX_R")
	)
	(via
		(at 259.55879 -177.539396)
		(size 0.508)
		(drill 0.254)
		(layers "F.Cu" "B.Cu")
		(net "PWRGD_P1V2_AUX_R")
	)
	(segment
		(start 250.9266 -205.1558)
		(end 250.1392 -205.9432)
		(width 0.15494)
		(layer "In7.Cu")
		(net "PWRGD_P1V2_AUX_R")
	)
	(segment
		(start 259.55879 -177.539396)
		(end 259.55879 -194.103752)
		(width 0.15494)
		(layer "In7.Cu")
		(net "PWRGD_P1V2_AUX_R")
	)
	(segment
		(start 250.1392 -205.9432)
		(end 250.1392 -207.9498)
		(width 0.15494)
		(layer "In7.Cu")
		(net "PWRGD_P1V2_AUX_R")
	)
	(segment
		(start 250.1392 -207.9498)
		(end 249.5042 -208.5848)
		(width 0.15494)
		(layer "In7.Cu")
		(net "PWRGD_P1V2_AUX_R")
	)
	(segment
		(start 250.9266 -202.735942)
		(end 250.9266 -205.1558)
		(width 0.15494)
		(layer "In7.Cu")
		(net "PWRGD_P1V2_AUX_R")
	)
	(segment
		(start 259.55879 -194.103752)
		(end 250.9266 -202.735942)
		(width 0.15494)
		(layer "In7.Cu")
		(net "PWRGD_P1V2_AUX_R")
	)
	(segment
		(start 228.284532 -174.178468)
		(end 234.484418 -174.178468)
		(width 0.15494)
		(layer "In13.Cu")
		(net "PWRGD_P1V2_AUX_R")
	)
	(segment
		(start 249.275854 -170.7642)
		(end 258.854702 -170.7642)
		(width 0.15494)
		(layer "In13.Cu")
		(net "PWRGD_P1V2_AUX_R")
	)
	(segment
		(start 234.484418 -174.178468)
		(end 235.18495 -174.879)
		(width 0.15494)
		(layer "In13.Cu")
		(net "PWRGD_P1V2_AUX_R")
	)
	(segment
		(start 258.854702 -170.7642)
		(end 259.25272 -171.162218)
		(width 0.15494)
		(layer "In13.Cu")
		(net "PWRGD_P1V2_AUX_R")
	)
	(segment
		(start 224.92462 -177.53838)
		(end 228.284532 -174.178468)
		(width 0.15494)
		(layer "In13.Cu")
		(net "PWRGD_P1V2_AUX_R")
	)
	(segment
		(start 222.576644 -177.53838)
		(end 224.92462 -177.53838)
		(width 0.15494)
		(layer "In13.Cu")
		(net "PWRGD_P1V2_AUX_R")
	)
	(segment
		(start 259.25272 -171.162218)
		(end 259.25272 -177.233326)
		(width 0.15494)
		(layer "In13.Cu")
		(net "PWRGD_P1V2_AUX_R")
	)
	(segment
		(start 259.25272 -177.233326)
		(end 259.55879 -177.539396)
		(width 0.15494)
		(layer "In13.Cu")
		(net "PWRGD_P1V2_AUX_R")
	)
	(segment
		(start 248.132854 -171.9072)
		(end 249.275854 -170.7642)
		(width 0.15494)
		(layer "In13.Cu")
		(net "PWRGD_P1V2_AUX_R")
	)
	(segment
		(start 236.5756 -174.879)
		(end 239.5474 -171.9072)
		(width 0.15494)
		(layer "In13.Cu")
		(net "PWRGD_P1V2_AUX_R")
	)
	(segment
		(start 235.18495 -174.879)
		(end 236.5756 -174.879)
		(width 0.15494)
		(layer "In13.Cu")
		(net "PWRGD_P1V2_AUX_R")
	)
	(segment
		(start 239.5474 -171.9072)
		(end 248.132854 -171.9072)
		(width 0.15494)
		(layer "In13.Cu")
		(net "PWRGD_P1V2_AUX_R")
	)
	(segment
		(start 325.810118 -227.758244)
		(end 323.462396 -227.758244)
		(width 0.15494)
		(layer "In15.Cu")
		(net "PWRGD_P1V2_AUX_R")
	)
	(segment
		(start 338.894166 -227.054156)
		(end 338.605114 -227.343208)
		(width 0.15494)
		(layer "In15.Cu")
		(net "PWRGD_P1V2_AUX_R")
	)
	(segment
		(start 323.462396 -227.758244)
		(end 322.883022 -228.337618)
		(width 0.15494)
		(layer "In15.Cu")
		(net "PWRGD_P1V2_AUX_R")
	)
	(segment
		(start 291.232082 -227.971604)
		(end 289.968686 -229.235)
		(width 0.15494)
		(layer "In15.Cu")
		(net "PWRGD_P1V2_AUX_R")
	)
	(segment
		(start 338.494116 -223.586802)
		(end 338.894166 -223.986852)
		(width 0.0889)
		(layer "In15.Cu")
		(net "PWRGD_P1V2_AUX_R")
	)
	(segment
		(start 330.277724 -227.343208)
		(end 329.661266 -227.959666)
		(width 0.15494)
		(layer "In15.Cu")
		(net "PWRGD_P1V2_AUX_R")
	)
	(segment
		(start 272.54708 -229.235)
		(end 268.77137 -225.45929)
		(width 0.15494)
		(layer "In15.Cu")
		(net "PWRGD_P1V2_AUX_R")
	)
	(segment
		(start 326.01154 -227.959666)
		(end 325.810118 -227.758244)
		(width 0.15494)
		(layer "In15.Cu")
		(net "PWRGD_P1V2_AUX_R")
	)
	(segment
		(start 338.894166 -223.986852)
		(end 338.894166 -227.054156)
		(width 0.0889)
		(layer "In15.Cu")
		(net "PWRGD_P1V2_AUX_R")
	)
	(segment
		(start 322.883022 -228.337618)
		(end 307.001164 -228.337618)
		(width 0.15494)
		(layer "In15.Cu")
		(net "PWRGD_P1V2_AUX_R")
	)
	(segment
		(start 305.936142 -227.272596)
		(end 301.064676 -227.272596)
		(width 0.15494)
		(layer "In15.Cu")
		(net "PWRGD_P1V2_AUX_R")
	)
	(segment
		(start 301.064676 -227.272596)
		(end 300.365668 -227.971604)
		(width 0.15494)
		(layer "In15.Cu")
		(net "PWRGD_P1V2_AUX_R")
	)
	(segment
		(start 329.661266 -227.959666)
		(end 326.01154 -227.959666)
		(width 0.15494)
		(layer "In15.Cu")
		(net "PWRGD_P1V2_AUX_R")
	)
	(segment
		(start 307.001164 -228.337618)
		(end 305.936142 -227.272596)
		(width 0.15494)
		(layer "In15.Cu")
		(net "PWRGD_P1V2_AUX_R")
	)
	(segment
		(start 338.605114 -227.343208)
		(end 330.277724 -227.343208)
		(width 0.15494)
		(layer "In15.Cu")
		(net "PWRGD_P1V2_AUX_R")
	)
	(segment
		(start 289.968686 -229.235)
		(end 272.54708 -229.235)
		(width 0.15494)
		(layer "In15.Cu")
		(net "PWRGD_P1V2_AUX_R")
	)
	(segment
		(start 300.365668 -227.971604)
		(end 291.232082 -227.971604)
		(width 0.15494)
		(layer "In15.Cu")
		(net "PWRGD_P1V2_AUX_R")
	)
	(segment
		(start 207.12938 -193.066416)
		(end 207.28559 -193.443606)
		(width 0.13208)
		(layer "F.Cu")
		(net "UART_FIO_DEBUG_R_TX")
	)
	(segment
		(start 205.73492 -217.31732)
		(end 209.948272 -217.31732)
		(width 0.13208)
		(layer "F.Cu")
		(net "UART_FIO_DEBUG_R_TX")
	)
	(segment
		(start 210.346036 -217.715084)
		(end 210.346036 -218.257374)
		(width 0.13208)
		(layer "F.Cu")
		(net "UART_FIO_DEBUG_R_TX")
	)
	(segment
		(start 207.12938 -195.95719)
		(end 204.5462 -202.193652)
		(width 0.13208)
		(layer "F.Cu")
		(net "UART_FIO_DEBUG_R_TX")
	)
	(segment
		(start 207.12938 -193.989198)
		(end 207.12938 -195.95719)
		(width 0.13208)
		(layer "F.Cu")
		(net "UART_FIO_DEBUG_R_TX")
	)
	(segment
		(start 204.5462 -202.193652)
		(end 204.5462 -216.1286)
		(width 0.13208)
		(layer "F.Cu")
		(net "UART_FIO_DEBUG_R_TX")
	)
	(segment
		(start 207.28559 -193.443606)
		(end 207.28559 -193.612262)
		(width 0.13208)
		(layer "F.Cu")
		(net "UART_FIO_DEBUG_R_TX")
	)
	(segment
		(start 229.437438 -66.60007)
		(end 228.180646 -66.60007)
		(width 0.13208)
		(layer "F.Cu")
		(net "UART_FIO_DEBUG_R_TX")
	)
	(segment
		(start 228.180646 -66.60007)
		(end 227.839016 -66.25844)
		(width 0.13208)
		(layer "F.Cu")
		(net "UART_FIO_DEBUG_R_TX")
	)
	(segment
		(start 207.61071 -192.234058)
		(end 207.12938 -192.715388)
		(width 0.13208)
		(layer "F.Cu")
		(net "UART_FIO_DEBUG_R_TX")
	)
	(segment
		(start 207.28559 -193.612262)
		(end 207.12938 -193.989198)
		(width 0.13208)
		(layer "F.Cu")
		(net "UART_FIO_DEBUG_R_TX")
	)
	(segment
		(start 209.948272 -217.31732)
		(end 210.346036 -217.715084)
		(width 0.13208)
		(layer "F.Cu")
		(net "UART_FIO_DEBUG_R_TX")
	)
	(segment
		(start 207.12938 -192.715388)
		(end 207.12938 -193.066416)
		(width 0.13208)
		(layer "F.Cu")
		(net "UART_FIO_DEBUG_R_TX")
	)
	(segment
		(start 204.5462 -216.1286)
		(end 205.73492 -217.31732)
		(width 0.13208)
		(layer "F.Cu")
		(net "UART_FIO_DEBUG_R_TX")
	)
	(segment
		(start 227.839016 -66.25844)
		(end 226.690936 -66.25844)
		(width 0.13208)
		(layer "F.Cu")
		(net "UART_FIO_DEBUG_R_TX")
	)
	(via
		(at 226.690936 -66.25844)
		(size 0.508)
		(drill 0.254)
		(layers "F.Cu" "B.Cu")
		(net "UART_FIO_DEBUG_R_TX")
	)
	(via
		(at 222.370142 -188.482224)
		(size 0.508)
		(drill 0.254)
		(layers "F.Cu" "B.Cu")
		(net "UART_FIO_DEBUG_R_TX")
	)
	(via
		(at 207.61071 -192.234058)
		(size 0.508)
		(drill 0.254)
		(layers "F.Cu" "B.Cu")
		(net "UART_FIO_DEBUG_R_TX")
	)
	(segment
		(start 226.8601 -179.895754)
		(end 227.457 -179.298854)
		(width 0.15494)
		(layer "In5.Cu")
		(net "UART_FIO_DEBUG_R_TX")
	)
	(segment
		(start 226.133406 -68.969128)
		(end 226.690936 -68.411598)
		(width 0.15494)
		(layer "In5.Cu")
		(net "UART_FIO_DEBUG_R_TX")
	)
	(segment
		(start 233.567478 -164.8206)
		(end 253.746 -164.8206)
		(width 0.15494)
		(layer "In5.Cu")
		(net "UART_FIO_DEBUG_R_TX")
	)
	(segment
		(start 226.309428 -71.299578)
		(end 226.133406 -71.123556)
		(width 0.15494)
		(layer "In5.Cu")
		(net "UART_FIO_DEBUG_R_TX")
	)
	(segment
		(start 225.386646 -179.895754)
		(end 226.8601 -179.895754)
		(width 0.15494)
		(layer "In5.Cu")
		(net "UART_FIO_DEBUG_R_TX")
	)
	(segment
		(start 227.457 -170.931078)
		(end 233.567478 -164.8206)
		(width 0.15494)
		(layer "In5.Cu")
		(net "UART_FIO_DEBUG_R_TX")
	)
	(segment
		(start 222.370142 -182.912258)
		(end 225.386646 -179.895754)
		(width 0.15494)
		(layer "In5.Cu")
		(net "UART_FIO_DEBUG_R_TX")
	)
	(segment
		(start 227.457 -179.298854)
		(end 227.457 -170.931078)
		(width 0.15494)
		(layer "In5.Cu")
		(net "UART_FIO_DEBUG_R_TX")
	)
	(segment
		(start 227.363274 -96.239838)
		(end 226.309428 -95.185992)
		(width 0.15494)
		(layer "In5.Cu")
		(net "UART_FIO_DEBUG_R_TX")
	)
	(segment
		(start 256.217166 -116.034566)
		(end 237.075218 -96.892618)
		(width 0.15494)
		(layer "In5.Cu")
		(net "UART_FIO_DEBUG_R_TX")
	)
	(segment
		(start 226.133406 -71.123556)
		(end 226.133406 -68.969128)
		(width 0.15494)
		(layer "In5.Cu")
		(net "UART_FIO_DEBUG_R_TX")
	)
	(segment
		(start 222.370142 -188.482224)
		(end 222.370142 -182.912258)
		(width 0.15494)
		(layer "In5.Cu")
		(net "UART_FIO_DEBUG_R_TX")
	)
	(segment
		(start 253.746 -164.8206)
		(end 256.217166 -162.349434)
		(width 0.15494)
		(layer "In5.Cu")
		(net "UART_FIO_DEBUG_R_TX")
	)
	(segment
		(start 226.309428 -95.185992)
		(end 226.309428 -71.299578)
		(width 0.15494)
		(layer "In5.Cu")
		(net "UART_FIO_DEBUG_R_TX")
	)
	(segment
		(start 226.690936 -68.411598)
		(end 226.690936 -66.25844)
		(width 0.15494)
		(layer "In5.Cu")
		(net "UART_FIO_DEBUG_R_TX")
	)
	(segment
		(start 237.075218 -96.892618)
		(end 230.619554 -96.892618)
		(width 0.15494)
		(layer "In5.Cu")
		(net "UART_FIO_DEBUG_R_TX")
	)
	(segment
		(start 230.619554 -96.892618)
		(end 229.966774 -96.239838)
		(width 0.15494)
		(layer "In5.Cu")
		(net "UART_FIO_DEBUG_R_TX")
	)
	(segment
		(start 229.966774 -96.239838)
		(end 227.363274 -96.239838)
		(width 0.15494)
		(layer "In5.Cu")
		(net "UART_FIO_DEBUG_R_TX")
	)
	(segment
		(start 256.217166 -162.349434)
		(end 256.217166 -116.034566)
		(width 0.15494)
		(layer "In5.Cu")
		(net "UART_FIO_DEBUG_R_TX")
	)
	(segment
		(start 220.398594 -189.591188)
		(end 221.507558 -188.482224)
		(width 0.15494)
		(layer "In15.Cu")
		(net "UART_FIO_DEBUG_R_TX")
	)
	(segment
		(start 217.622882 -189.178184)
		(end 218.035886 -189.591188)
		(width 0.15494)
		(layer "In15.Cu")
		(net "UART_FIO_DEBUG_R_TX")
	)
	(segment
		(start 218.035886 -189.591188)
		(end 220.398594 -189.591188)
		(width 0.15494)
		(layer "In15.Cu")
		(net "UART_FIO_DEBUG_R_TX")
	)
	(segment
		(start 211.11591 -190.63589)
		(end 212.573616 -189.178184)
		(width 0.15494)
		(layer "In15.Cu")
		(net "UART_FIO_DEBUG_R_TX")
	)
	(segment
		(start 207.884522 -192.50787)
		(end 209.62366 -192.50787)
		(width 0.15494)
		(layer "In15.Cu")
		(net "UART_FIO_DEBUG_R_TX")
	)
	(segment
		(start 211.11591 -191.01562)
		(end 211.11591 -190.63589)
		(width 0.15494)
		(layer "In15.Cu")
		(net "UART_FIO_DEBUG_R_TX")
	)
	(segment
		(start 207.61071 -192.234058)
		(end 207.884522 -192.50787)
		(width 0.15494)
		(layer "In15.Cu")
		(net "UART_FIO_DEBUG_R_TX")
	)
	(segment
		(start 212.573616 -189.178184)
		(end 217.622882 -189.178184)
		(width 0.15494)
		(layer "In15.Cu")
		(net "UART_FIO_DEBUG_R_TX")
	)
	(segment
		(start 209.62366 -192.50787)
		(end 211.11591 -191.01562)
		(width 0.15494)
		(layer "In15.Cu")
		(net "UART_FIO_DEBUG_R_TX")
	)
	(segment
		(start 221.507558 -188.482224)
		(end 222.370142 -188.482224)
		(width 0.15494)
		(layer "In15.Cu")
		(net "UART_FIO_DEBUG_R_TX")
	)
	(segment
		(start 436.851044 -299.27296)
		(end 436.72379 -299.400214)
		(width 0.13208)
		(layer "F.Cu")
		(net "I2C_PEX3_HOST_SDA")
	)
	(segment
		(start 436.72379 -300.03877)
		(end 436.92699 -300.24197)
		(width 0.13208)
		(layer "F.Cu")
		(net "I2C_PEX3_HOST_SDA")
	)
	(segment
		(start 436.72379 -299.76445)
		(end 436.72379 -300.03877)
		(width 0.13208)
		(layer "F.Cu")
		(net "I2C_PEX3_HOST_SDA")
	)
	(segment
		(start 437.305196 -299.27296)
		(end 436.851044 -299.27296)
		(width 0.13208)
		(layer "F.Cu")
		(net "I2C_PEX3_HOST_SDA")
	)
	(segment
		(start 438.328308 -300.24197)
		(end 437.312308 -300.24197)
		(width 0.13208)
		(layer "F.Cu")
		(net "I2C_PEX3_HOST_SDA")
	)
	(segment
		(start 436.92699 -300.24197)
		(end 437.312308 -300.24197)
		(width 0.13208)
		(layer "F.Cu")
		(net "I2C_PEX3_HOST_SDA")
	)
	(segment
		(start 436.72379 -299.400214)
		(end 436.72379 -299.76445)
		(width 0.13208)
		(layer "F.Cu")
		(net "I2C_PEX3_HOST_SDA")
	)
	(via
		(at 436.72379 -299.76445)
		(size 0.508)
		(drill 0.254)
		(layers "F.Cu" "B.Cu")
		(net "I2C_PEX3_HOST_SDA")
	)
	(segment
		(start 341.133684 -179.081684)
		(end 342.077548 -179.081684)
		(width 0.13208)
		(layer "F.Cu")
		(net "SSD9_PEX_PWR_EN")
	)
	(segment
		(start 342.077548 -179.081684)
		(end 342.599772 -179.603908)
		(width 0.13208)
		(layer "F.Cu")
		(net "SSD9_PEX_PWR_EN")
	)
	(segment
		(start 340.5505 -178.6255)
		(end 340.6775 -178.6255)
		(width 0.13208)
		(layer "F.Cu")
		(net "SSD9_PEX_PWR_EN")
	)
	(segment
		(start 342.599772 -179.603908)
		(end 343.149936 -179.603908)
		(width 0.13208)
		(layer "F.Cu")
		(net "SSD9_PEX_PWR_EN")
	)
	(segment
		(start 339.852 -177.927)
		(end 340.5505 -178.6255)
		(width 0.13208)
		(layer "F.Cu")
		(net "SSD9_PEX_PWR_EN")
	)
	(segment
		(start 340.6775 -178.6255)
		(end 341.133684 -179.081684)
		(width 0.13208)
		(layer "F.Cu")
		(net "SSD9_PEX_PWR_EN")
	)
	(segment
		(start 338.47405 -177.927)
		(end 339.852 -177.927)
		(width 0.13208)
		(layer "F.Cu")
		(net "SSD9_PEX_PWR_EN")
	)
	(via
		(at 339.852 -177.927)
		(size 0.508)
		(drill 0.254)
		(layers "F.Cu" "B.Cu")
		(net "SSD9_PEX_PWR_EN")
	)
	(segment
		(start 226.907852 -369.957604)
		(end 226.907852 -371.233954)
		(width 0.13208)
		(layer "F.Cu")
		(net "HSC_SS")
	)
	(segment
		(start 201.099674 -369.74653)
		(end 201.214228 -369.631976)
		(width 0.1524)
		(layer "F.Cu")
		(net "HSC_SS")
	)
	(segment
		(start 226.907852 -371.233954)
		(end 227.055426 -371.381528)
		(width 0.13208)
		(layer "F.Cu")
		(net "HSC_SS")
	)
	(segment
		(start 228.056948 -369.707668)
		(end 227.157788 -369.707668)
		(width 0.13208)
		(layer "F.Cu")
		(net "HSC_SS")
	)
	(segment
		(start 227.055426 -371.736366)
		(end 226.717606 -372.074186)
		(width 0.13208)
		(layer "F.Cu")
		(net "HSC_SS")
	)
	(segment
		(start 216.525094 -369.707668)
		(end 216.063576 -370.169186)
		(width 0.13208)
		(layer "F.Cu")
		(net "HSC_SS")
	)
	(segment
		(start 227.157788 -369.707668)
		(end 226.907852 -369.957604)
		(width 0.13208)
		(layer "F.Cu")
		(net "HSC_SS")
	)
	(segment
		(start 201.214228 -369.631976)
		(end 202.130914 -369.631976)
		(width 0.1524)
		(layer "F.Cu")
		(net "HSC_SS")
	)
	(segment
		(start 200.911206 -369.74653)
		(end 201.099674 -369.74653)
		(width 0.1524)
		(layer "F.Cu")
		(net "HSC_SS")
	)
	(segment
		(start 215.453976 -370.321586)
		(end 214.711026 -370.321586)
		(width 0.13208)
		(layer "F.Cu")
		(net "HSC_SS")
	)
	(segment
		(start 227.055426 -371.381528)
		(end 227.055426 -371.736366)
		(width 0.13208)
		(layer "F.Cu")
		(net "HSC_SS")
	)
	(segment
		(start 215.606376 -370.169186)
		(end 215.453976 -370.321586)
		(width 0.13208)
		(layer "F.Cu")
		(net "HSC_SS")
	)
	(segment
		(start 226.717606 -372.074186)
		(end 225.252026 -372.074186)
		(width 0.13208)
		(layer "F.Cu")
		(net "HSC_SS")
	)
	(segment
		(start 217.388948 -369.707668)
		(end 216.525094 -369.707668)
		(width 0.13208)
		(layer "F.Cu")
		(net "HSC_SS")
	)
	(segment
		(start 216.063576 -370.169186)
		(end 215.606376 -370.169186)
		(width 0.13208)
		(layer "F.Cu")
		(net "HSC_SS")
	)
	(via
		(at 216.063576 -370.169186)
		(size 0.508)
		(drill 0.254)
		(layers "F.Cu" "B.Cu")
		(net "HSC_SS")
	)
	(via
		(at 200.911206 -369.74653)
		(size 0.762)
		(drill 0.254)
		(layers "F.Cu" "B.Cu")
		(net "HSC_SS")
	)
	(via
		(at 227.055426 -371.381528)
		(size 0.508)
		(drill 0.254)
		(layers "F.Cu" "B.Cu")
		(net "HSC_SS")
	)
	(segment
		(start 201.11593 -369.459764)
		(end 199.551544 -367.895378)
		(width 0.13208)
		(layer "B.Cu")
		(net "HSC_SS")
	)
	(segment
		(start 199.551544 -367.895378)
		(end 199.551544 -366.96269)
		(width 0.13208)
		(layer "B.Cu")
		(net "HSC_SS")
	)
	(segment
		(start 199.551544 -366.96269)
		(end 198.949818 -366.360964)
		(width 0.13208)
		(layer "B.Cu")
		(net "HSC_SS")
	)
	(segment
		(start 200.911206 -369.74653)
		(end 201.11593 -369.541806)
		(width 0.13208)
		(layer "B.Cu")
		(net "HSC_SS")
	)
	(segment
		(start 201.11593 -369.541806)
		(end 201.11593 -369.459764)
		(width 0.13208)
		(layer "B.Cu")
		(net "HSC_SS")
	)
	(segment
		(start 198.949818 -366.360964)
		(end 198.949818 -366.339628)
		(width 0.13208)
		(layer "B.Cu")
		(net "HSC_SS")
	)
	(segment
		(start 223.718374 -361.077764)
		(end 225.016822 -362.376212)
		(width 0.15494)
		(layer "In11.Cu")
		(net "HSC_SS")
	)
	(segment
		(start 199.143874 -369.74653)
		(end 200.911206 -369.74653)
		(width 0.15494)
		(layer "In11.Cu")
		(net "HSC_SS")
	)
	(segment
		(start 215.869012 -362.31703)
		(end 217.108278 -361.077764)
		(width 0.15494)
		(layer "In11.Cu")
		(net "HSC_SS")
	)
	(segment
		(start 216.966546 -370.7384)
		(end 217.3224 -370.382546)
		(width 0.15494)
		(layer "In11.Cu")
		(net "HSC_SS")
	)
	(segment
		(start 211.398358 -358.11587)
		(end 202.821794 -358.11587)
		(width 0.15494)
		(layer "In11.Cu")
		(net "HSC_SS")
	)
	(segment
		(start 226.828858 -371.608096)
		(end 227.055426 -371.381528)
		(width 0.15494)
		(layer "In11.Cu")
		(net "HSC_SS")
	)
	(segment
		(start 215.869012 -366.5474)
		(end 215.869012 -362.31703)
		(width 0.15494)
		(layer "In11.Cu")
		(net "HSC_SS")
	)
	(segment
		(start 212.482938 -369.700302)
		(end 211.883752 -369.101116)
		(width 0.15494)
		(layer "In11.Cu")
		(net "HSC_SS")
	)
	(segment
		(start 201.577194 -357.730298)
		(end 198.403972 -360.90352)
		(width 0.15494)
		(layer "In11.Cu")
		(net "HSC_SS")
	)
	(segment
		(start 211.883752 -369.101116)
		(end 211.883752 -358.601264)
		(width 0.15494)
		(layer "In11.Cu")
		(net "HSC_SS")
	)
	(segment
		(start 216.437464 -370.7384)
		(end 216.966546 -370.7384)
		(width 0.15494)
		(layer "In11.Cu")
		(net "HSC_SS")
	)
	(segment
		(start 198.403972 -369.006628)
		(end 199.143874 -369.74653)
		(width 0.15494)
		(layer "In11.Cu")
		(net "HSC_SS")
	)
	(segment
		(start 217.3224 -370.382546)
		(end 217.3224 -369.443)
		(width 0.15494)
		(layer "In11.Cu")
		(net "HSC_SS")
	)
	(segment
		(start 225.537268 -371.608096)
		(end 226.828858 -371.608096)
		(width 0.15494)
		(layer "In11.Cu")
		(net "HSC_SS")
	)
	(segment
		(start 198.403972 -360.90352)
		(end 198.403972 -369.006628)
		(width 0.15494)
		(layer "In11.Cu")
		(net "HSC_SS")
	)
	(segment
		(start 216.851484 -368.972084)
		(end 216.851484 -367.529872)
		(width 0.15494)
		(layer "In11.Cu")
		(net "HSC_SS")
	)
	(segment
		(start 215.594438 -370.638324)
		(end 214.776812 -370.638324)
		(width 0.15494)
		(layer "In11.Cu")
		(net "HSC_SS")
	)
	(segment
		(start 217.3224 -369.443)
		(end 216.851484 -368.972084)
		(width 0.15494)
		(layer "In11.Cu")
		(net "HSC_SS")
	)
	(segment
		(start 216.063576 -370.169186)
		(end 215.594438 -370.638324)
		(width 0.15494)
		(layer "In11.Cu")
		(net "HSC_SS")
	)
	(segment
		(start 216.063576 -370.364512)
		(end 216.437464 -370.7384)
		(width 0.15494)
		(layer "In11.Cu")
		(net "HSC_SS")
	)
	(segment
		(start 211.883752 -358.601264)
		(end 211.398358 -358.11587)
		(width 0.15494)
		(layer "In11.Cu")
		(net "HSC_SS")
	)
	(segment
		(start 213.83879 -369.700302)
		(end 212.482938 -369.700302)
		(width 0.15494)
		(layer "In11.Cu")
		(net "HSC_SS")
	)
	(segment
		(start 202.436222 -357.730298)
		(end 201.577194 -357.730298)
		(width 0.15494)
		(layer "In11.Cu")
		(net "HSC_SS")
	)
	(segment
		(start 225.016822 -371.08765)
		(end 225.537268 -371.608096)
		(width 0.15494)
		(layer "In11.Cu")
		(net "HSC_SS")
	)
	(segment
		(start 225.016822 -362.376212)
		(end 225.016822 -371.08765)
		(width 0.15494)
		(layer "In11.Cu")
		(net "HSC_SS")
	)
	(segment
		(start 214.776812 -370.638324)
		(end 213.83879 -369.700302)
		(width 0.15494)
		(layer "In11.Cu")
		(net "HSC_SS")
	)
	(segment
		(start 202.821794 -358.11587)
		(end 202.436222 -357.730298)
		(width 0.15494)
		(layer "In11.Cu")
		(net "HSC_SS")
	)
	(segment
		(start 216.851484 -367.529872)
		(end 215.869012 -366.5474)
		(width 0.15494)
		(layer "In11.Cu")
		(net "HSC_SS")
	)
	(segment
		(start 217.108278 -361.077764)
		(end 223.718374 -361.077764)
		(width 0.15494)
		(layer "In11.Cu")
		(net "HSC_SS")
	)
	(segment
		(start 216.063576 -370.169186)
		(end 216.063576 -370.364512)
		(width 0.15494)
		(layer "In11.Cu")
		(net "HSC_SS")
	)
	(segment
		(start 440.687206 -301.050452)
		(end 441.373006 -301.050452)
		(width 0.13208)
		(layer "F.Cu")
		(net "I2C0_PEX3_SHPC_SCL")
	)
	(segment
		(start 412.224982 -307.774594)
		(end 411.750002 -308.249828)
		(width 0.13208)
		(layer "F.Cu")
		(net "I2C0_PEX3_SHPC_SCL")
	)
	(via
		(at 412.224982 -307.774594)
		(size 0.4064)
		(drill 0.2032)
		(layers "F.Cu" "B.Cu")
		(net "I2C0_PEX3_SHPC_SCL")
	)
	(via
		(at 441.373006 -301.050452)
		(size 0.508)
		(drill 0.254)
		(layers "F.Cu" "B.Cu")
		(net "I2C0_PEX3_SHPC_SCL")
	)
	(segment
		(start 432.200558 -299.258482)
		(end 436.42788 -299.258482)
		(width 0.15494)
		(layer "In5.Cu")
		(net "I2C0_PEX3_SHPC_SCL")
	)
	(segment
		(start 439.699654 -299.991272)
		(end 440.758834 -301.050452)
		(width 0.15494)
		(layer "In5.Cu")
		(net "I2C0_PEX3_SHPC_SCL")
	)
	(segment
		(start 422.6052 -305.303682)
		(end 422.6052 -302.7934)
		(width 0.15494)
		(layer "In5.Cu")
		(net "I2C0_PEX3_SHPC_SCL")
	)
	(segment
		(start 412.224982 -307.738018)
		(end 412.663132 -307.299868)
		(width 0.15494)
		(layer "In5.Cu")
		(net "I2C0_PEX3_SHPC_SCL")
	)
	(segment
		(start 422.0972 -306.324)
		(end 422.2242 -306.197)
		(width 0.15494)
		(layer "In5.Cu")
		(net "I2C0_PEX3_SHPC_SCL")
	)
	(segment
		(start 412.663132 -307.299868)
		(end 420.00297 -307.299868)
		(width 0.15494)
		(layer "In5.Cu")
		(net "I2C0_PEX3_SHPC_SCL")
	)
	(segment
		(start 436.42788 -299.258482)
		(end 436.557674 -299.128688)
		(width 0.15494)
		(layer "In5.Cu")
		(net "I2C0_PEX3_SHPC_SCL")
	)
	(segment
		(start 423.1386 -300.0756)
		(end 423.497502 -299.716698)
		(width 0.15494)
		(layer "In5.Cu")
		(net "I2C0_PEX3_SHPC_SCL")
	)
	(segment
		(start 422.2242 -306.197)
		(end 422.2242 -305.684682)
		(width 0.15494)
		(layer "In5.Cu")
		(net "I2C0_PEX3_SHPC_SCL")
	)
	(segment
		(start 420.00297 -307.299868)
		(end 420.294816 -307.008022)
		(width 0.15494)
		(layer "In5.Cu")
		(net "I2C0_PEX3_SHPC_SCL")
	)
	(segment
		(start 423.497502 -299.716698)
		(end 431.742342 -299.716698)
		(width 0.15494)
		(layer "In5.Cu")
		(net "I2C0_PEX3_SHPC_SCL")
	)
	(segment
		(start 436.557674 -299.128688)
		(end 436.878476 -299.128688)
		(width 0.15494)
		(layer "In5.Cu")
		(net "I2C0_PEX3_SHPC_SCL")
	)
	(segment
		(start 422.6052 -302.7934)
		(end 423.1386 -302.26)
		(width 0.15494)
		(layer "In5.Cu")
		(net "I2C0_PEX3_SHPC_SCL")
	)
	(segment
		(start 440.758834 -301.050452)
		(end 441.373006 -301.050452)
		(width 0.15494)
		(layer "In5.Cu")
		(net "I2C0_PEX3_SHPC_SCL")
	)
	(segment
		(start 423.1386 -302.26)
		(end 423.1386 -300.0756)
		(width 0.15494)
		(layer "In5.Cu")
		(net "I2C0_PEX3_SHPC_SCL")
	)
	(segment
		(start 422.2242 -305.684682)
		(end 422.6052 -305.303682)
		(width 0.15494)
		(layer "In5.Cu")
		(net "I2C0_PEX3_SHPC_SCL")
	)
	(segment
		(start 437.74106 -299.991272)
		(end 439.699654 -299.991272)
		(width 0.15494)
		(layer "In5.Cu")
		(net "I2C0_PEX3_SHPC_SCL")
	)
	(segment
		(start 431.742342 -299.716698)
		(end 432.200558 -299.258482)
		(width 0.15494)
		(layer "In5.Cu")
		(net "I2C0_PEX3_SHPC_SCL")
	)
	(segment
		(start 420.294816 -306.561744)
		(end 420.53256 -306.324)
		(width 0.15494)
		(layer "In5.Cu")
		(net "I2C0_PEX3_SHPC_SCL")
	)
	(segment
		(start 436.878476 -299.128688)
		(end 437.74106 -299.991272)
		(width 0.15494)
		(layer "In5.Cu")
		(net "I2C0_PEX3_SHPC_SCL")
	)
	(segment
		(start 420.294816 -307.008022)
		(end 420.294816 -306.561744)
		(width 0.15494)
		(layer "In5.Cu")
		(net "I2C0_PEX3_SHPC_SCL")
	)
	(segment
		(start 412.224982 -307.774594)
		(end 412.224982 -307.738018)
		(width 0.15494)
		(layer "In5.Cu")
		(net "I2C0_PEX3_SHPC_SCL")
	)
	(segment
		(start 420.53256 -306.324)
		(end 422.0972 -306.324)
		(width 0.15494)
		(layer "In5.Cu")
		(net "I2C0_PEX3_SHPC_SCL")
	)
	(segment
		(start 342.592406 -178.953922)
		(end 343.149936 -178.953922)
		(width 0.13208)
		(layer "F.Cu")
		(net "RST_PEX_SSD9_PERST_N")
	)
	(segment
		(start 339.852 -176.911)
		(end 341.373968 -178.432968)
		(width 0.13208)
		(layer "F.Cu")
		(net "RST_PEX_SSD9_PERST_N")
	)
	(segment
		(start 341.373968 -178.432968)
		(end 342.071452 -178.432968)
		(width 0.13208)
		(layer "F.Cu")
		(net "RST_PEX_SSD9_PERST_N")
	)
	(segment
		(start 342.071452 -178.432968)
		(end 342.592406 -178.953922)
		(width 0.13208)
		(layer "F.Cu")
		(net "RST_PEX_SSD9_PERST_N")
	)
	(segment
		(start 338.47405 -176.911)
		(end 339.852 -176.911)
		(width 0.13208)
		(layer "F.Cu")
		(net "RST_PEX_SSD9_PERST_N")
	)
	(via
		(at 342.071452 -178.432968)
		(size 0.508)
		(drill 0.254)
		(layers "F.Cu" "B.Cu")
		(net "RST_PEX_SSD9_PERST_N")
	)
	(segment
		(start 334.33131 -171.56176)
		(end 337.18119 -171.56176)
		(width 0.13208)
		(layer "F.Cu")
		(net "PRSNT_SSD10_FPGA_R_N")
	)
	(segment
		(start 333.750666 -172.142404)
		(end 334.33131 -171.56176)
		(width 0.13208)
		(layer "F.Cu")
		(net "PRSNT_SSD10_FPGA_R_N")
	)
	(segment
		(start 337.18119 -171.56176)
		(end 337.67395 -171.069)
		(width 0.13208)
		(layer "F.Cu")
		(net "PRSNT_SSD10_FPGA_R_N")
	)
	(segment
		(start 326.517 -215.265)
		(end 327.13295 -215.265)
		(width 0.13208)
		(layer "F.Cu")
		(net "PRSNT_SSD10_FPGA_R_N")
	)
	(segment
		(start 325.458074 -214.206074)
		(end 326.517 -215.265)
		(width 0.13208)
		(layer "F.Cu")
		(net "PRSNT_SSD10_FPGA_R_N")
	)
	(via
		(at 333.750666 -172.142404)
		(size 0.508)
		(drill 0.254)
		(layers "F.Cu" "B.Cu")
		(net "PRSNT_SSD10_FPGA_R_N")
	)
	(via
		(at 325.458074 -214.206074)
		(size 0.508)
		(drill 0.254)
		(layers "F.Cu" "B.Cu")
		(net "PRSNT_SSD10_FPGA_R_N")
	)
	(segment
		(start 325.458074 -214.206074)
		(end 322.901056 -211.649056)
		(width 0.15494)
		(layer "In9.Cu")
		(net "PRSNT_SSD10_FPGA_R_N")
	)
	(segment
		(start 325.4248 -181.755288)
		(end 326.335644 -179.557426)
		(width 0.15494)
		(layer "In9.Cu")
		(net "PRSNT_SSD10_FPGA_R_N")
	)
	(segment
		(start 325.5772 -187.706)
		(end 325.5772 -183.134)
		(width 0.15494)
		(layer "In9.Cu")
		(net "PRSNT_SSD10_FPGA_R_N")
	)
	(segment
		(start 324.0786 -200.63714)
		(end 324.0786 -193.132964)
		(width 0.15494)
		(layer "In9.Cu")
		(net "PRSNT_SSD10_FPGA_R_N")
	)
	(segment
		(start 324.521576 -188.761624)
		(end 325.5772 -187.706)
		(width 0.15494)
		(layer "In9.Cu")
		(net "PRSNT_SSD10_FPGA_R_N")
	)
	(segment
		(start 326.335644 -179.557426)
		(end 333.750666 -172.142404)
		(width 0.15494)
		(layer "In9.Cu")
		(net "PRSNT_SSD10_FPGA_R_N")
	)
	(segment
		(start 322.901056 -204.57541)
		(end 323.16674 -201.549)
		(width 0.15494)
		(layer "In9.Cu")
		(net "PRSNT_SSD10_FPGA_R_N")
	)
	(segment
		(start 324.0786 -193.132964)
		(end 324.505828 -188.799978)
		(width 0.15494)
		(layer "In9.Cu")
		(net "PRSNT_SSD10_FPGA_R_N")
	)
	(segment
		(start 322.901056 -211.649056)
		(end 322.901056 -204.57541)
		(width 0.15494)
		(layer "In9.Cu")
		(net "PRSNT_SSD10_FPGA_R_N")
	)
	(segment
		(start 325.5772 -183.134)
		(end 325.4248 -182.9816)
		(width 0.15494)
		(layer "In9.Cu")
		(net "PRSNT_SSD10_FPGA_R_N")
	)
	(segment
		(start 324.505828 -188.799978)
		(end 324.521576 -188.761624)
		(width 0.15494)
		(layer "In9.Cu")
		(net "PRSNT_SSD10_FPGA_R_N")
	)
	(segment
		(start 325.4248 -182.9816)
		(end 325.4248 -181.755288)
		(width 0.15494)
		(layer "In9.Cu")
		(net "PRSNT_SSD10_FPGA_R_N")
	)
	(segment
		(start 323.16674 -201.549)
		(end 324.0786 -200.63714)
		(width 0.15494)
		(layer "In9.Cu")
		(net "PRSNT_SSD10_FPGA_R_N")
	)
	(segment
		(start 234.099862 -373.9134)
		(end 234.099862 -375.150634)
		(width 0.13208)
		(layer "F.Cu")
		(net "HSC_MODE_2")
	)
	(segment
		(start 233.575606 -374.626378)
		(end 233.575606 -372.009924)
		(width 0.13208)
		(layer "F.Cu")
		(net "HSC_MODE_2")
	)
	(segment
		(start 233.102658 -371.536976)
		(end 233.102658 -370.945664)
		(width 0.13208)
		(layer "F.Cu")
		(net "HSC_MODE_2")
	)
	(segment
		(start 233.575606 -372.009924)
		(end 233.102658 -371.536976)
		(width 0.13208)
		(layer "F.Cu")
		(net "HSC_MODE_2")
	)
	(segment
		(start 234.099862 -375.150634)
		(end 233.575606 -374.626378)
		(width 0.13208)
		(layer "F.Cu")
		(net "HSC_MODE_2")
	)
	(segment
		(start 232.86466 -370.707666)
		(end 232.54462 -370.707666)
		(width 0.13208)
		(layer "F.Cu")
		(net "HSC_MODE_2")
	)
	(segment
		(start 233.102658 -370.945664)
		(end 232.86466 -370.707666)
		(width 0.13208)
		(layer "F.Cu")
		(net "HSC_MODE_2")
	)
	(via
		(at 234.099862 -375.150634)
		(size 0.762)
		(drill 0.381)
		(layers "F.Cu" "B.Cu")
		(net "HSC_MODE_2")
	)
	(segment
		(start 211.240116 -219.980002)
		(end 211.240116 -219.581476)
		(width 0.13208)
		(layer "F.Cu")
		(net "UART_MB_BIC_TX")
	)
	(segment
		(start 210.845908 -218.669108)
		(end 210.845908 -218.257374)
		(width 0.13208)
		(layer "F.Cu")
		(net "UART_MB_BIC_TX")
	)
	(segment
		(start 211.55152 -220.291406)
		(end 211.240116 -219.980002)
		(width 0.13208)
		(layer "F.Cu")
		(net "UART_MB_BIC_TX")
	)
	(segment
		(start 211.240116 -219.063316)
		(end 210.845908 -218.669108)
		(width 0.13208)
		(layer "F.Cu")
		(net "UART_MB_BIC_TX")
	)
	(segment
		(start 211.240116 -219.581476)
		(end 211.240116 -219.063316)
		(width 0.13208)
		(layer "F.Cu")
		(net "UART_MB_BIC_TX")
	)
	(via
		(at 211.240116 -219.581476)
		(size 0.508)
		(drill 0.254)
		(layers "F.Cu" "B.Cu")
		(net "UART_MB_BIC_TX")
	)
	(segment
		(start 411.274768 -307.774594)
		(end 410.799788 -308.249828)
		(width 0.13208)
		(layer "F.Cu")
		(net "I2C0_PEX3_SHPC_SDA")
	)
	(segment
		(start 436.801768 -301.55261)
		(end 437.312308 -301.04207)
		(width 0.13208)
		(layer "F.Cu")
		(net "I2C0_PEX3_SHPC_SDA")
	)
	(via
		(at 436.801768 -301.55261)
		(size 0.508)
		(drill 0.254)
		(layers "F.Cu" "B.Cu")
		(net "I2C0_PEX3_SHPC_SDA")
	)
	(via
		(at 411.274768 -307.774594)
		(size 0.4064)
		(drill 0.2032)
		(layers "F.Cu" "B.Cu")
		(net "I2C0_PEX3_SHPC_SDA")
	)
	(segment
		(start 422.529 -309.199788)
		(end 422.966388 -308.7624)
		(width 0.15494)
		(layer "In5.Cu")
		(net "I2C0_PEX3_SHPC_SDA")
	)
	(segment
		(start 418.569902 -309.199788)
		(end 422.529 -309.199788)
		(width 0.15494)
		(layer "In5.Cu")
		(net "I2C0_PEX3_SHPC_SDA")
	)
	(segment
		(start 427.482 -303.8094)
		(end 427.609 -303.6824)
		(width 0.15494)
		(layer "In5.Cu")
		(net "I2C0_PEX3_SHPC_SDA")
	)
	(segment
		(start 433.730654 -301.3202)
		(end 435.83098 -301.3202)
		(width 0.15494)
		(layer "In5.Cu")
		(net "I2C0_PEX3_SHPC_SDA")
	)
	(segment
		(start 427.482 -308.330854)
		(end 427.482 -303.8094)
		(width 0.15494)
		(layer "In5.Cu")
		(net "I2C0_PEX3_SHPC_SDA")
	)
	(segment
		(start 431.368454 -303.6824)
		(end 433.730654 -301.3202)
		(width 0.15494)
		(layer "In5.Cu")
		(net "I2C0_PEX3_SHPC_SDA")
	)
	(segment
		(start 427.609 -303.6824)
		(end 431.368454 -303.6824)
		(width 0.15494)
		(layer "In5.Cu")
		(net "I2C0_PEX3_SHPC_SDA")
	)
	(segment
		(start 422.966388 -308.7624)
		(end 427.050454 -308.7624)
		(width 0.15494)
		(layer "In5.Cu")
		(net "I2C0_PEX3_SHPC_SDA")
	)
	(segment
		(start 427.050454 -308.7624)
		(end 427.482 -308.330854)
		(width 0.15494)
		(layer "In5.Cu")
		(net "I2C0_PEX3_SHPC_SDA")
	)
	(segment
		(start 418.36721 -308.461918)
		(end 418.36721 -308.997096)
		(width 0.15494)
		(layer "In5.Cu")
		(net "I2C0_PEX3_SHPC_SDA")
	)
	(segment
		(start 411.274768 -307.774594)
		(end 411.750002 -308.249828)
		(width 0.15494)
		(layer "In5.Cu")
		(net "I2C0_PEX3_SHPC_SDA")
	)
	(segment
		(start 418.15512 -308.249828)
		(end 418.36721 -308.461918)
		(width 0.15494)
		(layer "In5.Cu")
		(net "I2C0_PEX3_SHPC_SDA")
	)
	(segment
		(start 435.83098 -301.3202)
		(end 436.06339 -301.55261)
		(width 0.15494)
		(layer "In5.Cu")
		(net "I2C0_PEX3_SHPC_SDA")
	)
	(segment
		(start 411.750002 -308.249828)
		(end 418.15512 -308.249828)
		(width 0.15494)
		(layer "In5.Cu")
		(net "I2C0_PEX3_SHPC_SDA")
	)
	(segment
		(start 436.06339 -301.55261)
		(end 436.801768 -301.55261)
		(width 0.15494)
		(layer "In5.Cu")
		(net "I2C0_PEX3_SHPC_SDA")
	)
	(segment
		(start 418.36721 -308.997096)
		(end 418.569902 -309.199788)
		(width 0.15494)
		(layer "In5.Cu")
		(net "I2C0_PEX3_SHPC_SDA")
	)
	(segment
		(start 335.693766 -218.387168)
		(end 335.29397 -217.987372)
		(width 0.13208)
		(layer "F.Cu")
		(net "NIC7_PEX_PWR_EN_R")
	)
	(segment
		(start 353.248214 -143.51)
		(end 352.632264 -143.51)
		(width 0.13208)
		(layer "F.Cu")
		(net "NIC7_PEX_PWR_EN_R")
	)
	(via
		(at 353.248214 -143.51)
		(size 0.508)
		(drill 0.254)
		(layers "F.Cu" "B.Cu")
		(net "NIC7_PEX_PWR_EN_R")
	)
	(via
		(at 330.503276 -143.641572)
		(size 0.508)
		(drill 0.254)
		(layers "F.Cu" "B.Cu")
		(net "NIC7_PEX_PWR_EN_R")
	)
	(via
		(at 335.29397 -217.987372)
		(size 0.4572)
		(drill 0.254)
		(layers "F.Cu" "B.Cu")
		(net "NIC7_PEX_PWR_EN_R")
	)
	(segment
		(start 352.046032 -143.51)
		(end 353.248214 -143.51)
		(width 0.13208)
		(layer "B.Cu")
		(net "NIC7_PEX_PWR_EN_R")
	)
	(segment
		(start 352.046032 -142.494)
		(end 352.046032 -143.51)
		(width 0.13208)
		(layer "B.Cu")
		(net "NIC7_PEX_PWR_EN_R")
	)
	(segment
		(start 331.111098 -144.249394)
		(end 330.503276 -143.641572)
		(width 0.15494)
		(layer "In5.Cu")
		(net "NIC7_PEX_PWR_EN_R")
	)
	(segment
		(start 328.66203 -193.86296)
		(end 328.66203 -152.632918)
		(width 0.15494)
		(layer "In5.Cu")
		(net "NIC7_PEX_PWR_EN_R")
	)
	(segment
		(start 331.111098 -150.18385)
		(end 331.111098 -144.249394)
		(width 0.15494)
		(layer "In5.Cu")
		(net "NIC7_PEX_PWR_EN_R")
	)
	(segment
		(start 327.75779 -216.21242)
		(end 327.75779 -210.496404)
		(width 0.15494)
		(layer "In5.Cu")
		(net "NIC7_PEX_PWR_EN_R")
	)
	(segment
		(start 324.952106 -201.567288)
		(end 326.488552 -200.030842)
		(width 0.15494)
		(layer "In5.Cu")
		(net "NIC7_PEX_PWR_EN_R")
	)
	(segment
		(start 328.66203 -152.632918)
		(end 331.111098 -150.18385)
		(width 0.15494)
		(layer "In5.Cu")
		(net "NIC7_PEX_PWR_EN_R")
	)
	(segment
		(start 333.47406 -217.589862)
		(end 332.55585 -217.589862)
		(width 0.15494)
		(layer "In5.Cu")
		(net "NIC7_PEX_PWR_EN_R")
	)
	(segment
		(start 328.344784 -216.799414)
		(end 327.75779 -216.21242)
		(width 0.15494)
		(layer "In5.Cu")
		(net "NIC7_PEX_PWR_EN_R")
	)
	(segment
		(start 328.794618 -216.799414)
		(end 328.344784 -216.799414)
		(width 0.15494)
		(layer "In5.Cu")
		(net "NIC7_PEX_PWR_EN_R")
	)
	(segment
		(start 324.952106 -207.69072)
		(end 324.952106 -201.567288)
		(width 0.15494)
		(layer "In5.Cu")
		(net "NIC7_PEX_PWR_EN_R")
	)
	(segment
		(start 327.75779 -210.496404)
		(end 324.952106 -207.69072)
		(width 0.15494)
		(layer "In5.Cu")
		(net "NIC7_PEX_PWR_EN_R")
	)
	(segment
		(start 334.89646 -217.589862)
		(end 333.47406 -217.589862)
		(width 0.0889)
		(layer "In5.Cu")
		(net "NIC7_PEX_PWR_EN_R")
	)
	(segment
		(start 329.879198 -215.714834)
		(end 328.794618 -216.799414)
		(width 0.15494)
		(layer "In5.Cu")
		(net "NIC7_PEX_PWR_EN_R")
	)
	(segment
		(start 326.488552 -200.030842)
		(end 326.488552 -196.036438)
		(width 0.15494)
		(layer "In5.Cu")
		(net "NIC7_PEX_PWR_EN_R")
	)
	(segment
		(start 326.488552 -196.036438)
		(end 328.66203 -193.86296)
		(width 0.15494)
		(layer "In5.Cu")
		(net "NIC7_PEX_PWR_EN_R")
	)
	(segment
		(start 335.29397 -217.987372)
		(end 334.89646 -217.589862)
		(width 0.0889)
		(layer "In5.Cu")
		(net "NIC7_PEX_PWR_EN_R")
	)
	(segment
		(start 330.680822 -215.714834)
		(end 329.879198 -215.714834)
		(width 0.15494)
		(layer "In5.Cu")
		(net "NIC7_PEX_PWR_EN_R")
	)
	(segment
		(start 332.55585 -217.589862)
		(end 330.680822 -215.714834)
		(width 0.15494)
		(layer "In5.Cu")
		(net "NIC7_PEX_PWR_EN_R")
	)
	(segment
		(start 353.248214 -143.51)
		(end 352.371406 -142.633192)
		(width 0.15494)
		(layer "In13.Cu")
		(net "NIC7_PEX_PWR_EN_R")
	)
	(segment
		(start 352.371406 -142.633192)
		(end 349.3389 -142.633192)
		(width 0.15494)
		(layer "In13.Cu")
		(net "NIC7_PEX_PWR_EN_R")
	)
	(segment
		(start 347.545406 -140.839698)
		(end 333.30515 -140.839698)
		(width 0.15494)
		(layer "In13.Cu")
		(net "NIC7_PEX_PWR_EN_R")
	)
	(segment
		(start 333.30515 -140.839698)
		(end 330.503276 -143.641572)
		(width 0.15494)
		(layer "In13.Cu")
		(net "NIC7_PEX_PWR_EN_R")
	)
	(segment
		(start 349.3389 -142.633192)
		(end 347.545406 -140.839698)
		(width 0.15494)
		(layer "In13.Cu")
		(net "NIC7_PEX_PWR_EN_R")
	)
	(segment
		(start 337.058 -179.120546)
		(end 337.058 -179.06238)
		(width 0.13208)
		(layer "F.Cu")
		(net "PRSNT_SSD9_FPGA_R_N")
	)
	(segment
		(start 336.617818 -179.560728)
		(end 337.058 -179.120546)
		(width 0.13208)
		(layer "F.Cu")
		(net "PRSNT_SSD9_FPGA_R_N")
	)
	(segment
		(start 327.13295 -216.281)
		(end 326.517 -216.281)
		(width 0.13208)
		(layer "F.Cu")
		(net "PRSNT_SSD9_FPGA_R_N")
	)
	(segment
		(start 337.17738 -178.943)
		(end 337.67395 -178.943)
		(width 0.13208)
		(layer "F.Cu")
		(net "PRSNT_SSD9_FPGA_R_N")
	)
	(segment
		(start 337.058 -179.06238)
		(end 337.17738 -178.943)
		(width 0.13208)
		(layer "F.Cu")
		(net "PRSNT_SSD9_FPGA_R_N")
	)
	(segment
		(start 327.486518 -179.560728)
		(end 336.617818 -179.560728)
		(width 0.13208)
		(layer "F.Cu")
		(net "PRSNT_SSD9_FPGA_R_N")
	)
	(via
		(at 326.517 -216.281)
		(size 0.508)
		(drill 0.254)
		(layers "F.Cu" "B.Cu")
		(net "PRSNT_SSD9_FPGA_R_N")
	)
	(via
		(at 327.486518 -179.560728)
		(size 0.508)
		(drill 0.254)
		(layers "F.Cu" "B.Cu")
		(net "PRSNT_SSD9_FPGA_R_N")
	)
	(segment
		(start 325.173848 -214.937848)
		(end 326.255126 -214.937848)
		(width 0.15494)
		(layer "In5.Cu")
		(net "PRSNT_SSD9_FPGA_R_N")
	)
	(segment
		(start 324.032626 -201.186288)
		(end 324.032626 -213.796626)
		(width 0.15494)
		(layer "In5.Cu")
		(net "PRSNT_SSD9_FPGA_R_N")
	)
	(segment
		(start 326.255126 -214.937848)
		(end 326.517 -215.199722)
		(width 0.15494)
		(layer "In5.Cu")
		(net "PRSNT_SSD9_FPGA_R_N")
	)
	(segment
		(start 325.569072 -199.649842)
		(end 324.032626 -201.186288)
		(width 0.15494)
		(layer "In5.Cu")
		(net "PRSNT_SSD9_FPGA_R_N")
	)
	(segment
		(start 327.486518 -179.560728)
		(end 327.486518 -193.737992)
		(width 0.15494)
		(layer "In5.Cu")
		(net "PRSNT_SSD9_FPGA_R_N")
	)
	(segment
		(start 326.517 -215.199722)
		(end 326.517 -216.281)
		(width 0.15494)
		(layer "In5.Cu")
		(net "PRSNT_SSD9_FPGA_R_N")
	)
	(segment
		(start 327.486518 -193.737992)
		(end 325.569072 -195.655438)
		(width 0.15494)
		(layer "In5.Cu")
		(net "PRSNT_SSD9_FPGA_R_N")
	)
	(segment
		(start 325.569072 -195.655438)
		(end 325.569072 -199.649842)
		(width 0.15494)
		(layer "In5.Cu")
		(net "PRSNT_SSD9_FPGA_R_N")
	)
	(segment
		(start 324.032626 -213.796626)
		(end 325.173848 -214.937848)
		(width 0.15494)
		(layer "In5.Cu")
		(net "PRSNT_SSD9_FPGA_R_N")
	)
	(segment
		(start 233.80446 -370.187474)
		(end 233.49839 -369.881404)
		(width 0.13208)
		(layer "F.Cu")
		(net "HSC_FAULT_N")
	)
	(segment
		(start 210.496912 -368.007646)
		(end 209.890614 -368.613944)
		(width 0.13208)
		(layer "F.Cu")
		(net "HSC_FAULT_N")
	)
	(segment
		(start 234.154472 -370.187474)
		(end 233.80446 -370.187474)
		(width 0.13208)
		(layer "F.Cu")
		(net "HSC_FAULT_N")
	)
	(segment
		(start 211.106766 -368.007646)
		(end 210.496912 -368.007646)
		(width 0.13208)
		(layer "F.Cu")
		(net "HSC_FAULT_N")
	)
	(segment
		(start 209.322416 -369.182142)
		(end 208.605882 -369.182142)
		(width 0.13208)
		(layer "F.Cu")
		(net "HSC_FAULT_N")
	)
	(segment
		(start 209.890614 -368.613944)
		(end 209.322416 -369.182142)
		(width 0.13208)
		(layer "F.Cu")
		(net "HSC_FAULT_N")
	)
	(via
		(at 233.49839 -369.881404)
		(size 0.508)
		(drill 0.254)
		(layers "F.Cu" "B.Cu")
		(net "HSC_FAULT_N")
	)
	(via
		(at 209.890614 -368.613944)
		(size 0.508)
		(drill 0.254)
		(layers "F.Cu" "B.Cu")
		(net "HSC_FAULT_N")
	)
	(segment
		(start 226.6569 -369.3033)
		(end 227.505514 -368.454686)
		(width 0.13208)
		(layer "B.Cu")
		(net "HSC_FAULT_N")
	)
	(segment
		(start 222.663004 -361.734354)
		(end 222.663004 -368.29111)
		(width 0.13208)
		(layer "B.Cu")
		(net "HSC_FAULT_N")
	)
	(segment
		(start 228.252782 -361.206288)
		(end 232.686606 -361.206288)
		(width 0.13208)
		(layer "B.Cu")
		(net "HSC_FAULT_N")
	)
	(segment
		(start 221.939866 -369.014248)
		(end 221.939866 -370.775484)
		(width 0.13208)
		(layer "B.Cu")
		(net "HSC_FAULT_N")
	)
	(segment
		(start 209.890614 -368.613944)
		(end 210.498436 -368.006122)
		(width 0.13208)
		(layer "B.Cu")
		(net "HSC_FAULT_N")
	)
	(segment
		(start 222.262192 -361.333542)
		(end 222.663004 -361.734354)
		(width 0.13208)
		(layer "B.Cu")
		(net "HSC_FAULT_N")
	)
	(segment
		(start 225.248724 -371.055138)
		(end 225.248724 -371.40388)
		(width 0.13208)
		(layer "B.Cu")
		(net "HSC_FAULT_N")
	)
	(segment
		(start 233.14787 -367.142014)
		(end 233.14787 -368.422174)
		(width 0.13208)
		(layer "B.Cu")
		(net "HSC_FAULT_N")
	)
	(segment
		(start 225.431604 -371.58676)
		(end 226.121468 -371.58676)
		(width 0.13208)
		(layer "B.Cu")
		(net "HSC_FAULT_N")
	)
	(segment
		(start 221.939866 -370.775484)
		(end 222.73387 -371.569488)
		(width 0.13208)
		(layer "B.Cu")
		(net "HSC_FAULT_N")
	)
	(segment
		(start 232.594404 -369.488974)
		(end 232.986834 -369.881404)
		(width 0.13208)
		(layer "B.Cu")
		(net "HSC_FAULT_N")
	)
	(segment
		(start 233.458766 -366.831118)
		(end 233.14787 -367.142014)
		(width 0.13208)
		(layer "B.Cu")
		(net "HSC_FAULT_N")
	)
	(segment
		(start 226.6569 -371.051328)
		(end 226.6569 -369.3033)
		(width 0.13208)
		(layer "B.Cu")
		(net "HSC_FAULT_N")
	)
	(segment
		(start 225.248724 -371.40388)
		(end 225.431604 -371.58676)
		(width 0.13208)
		(layer "B.Cu")
		(net "HSC_FAULT_N")
	)
	(segment
		(start 210.498436 -368.006122)
		(end 211.810092 -368.006122)
		(width 0.13208)
		(layer "B.Cu")
		(net "HSC_FAULT_N")
	)
	(segment
		(start 222.73387 -371.569488)
		(end 224.734374 -371.569488)
		(width 0.13208)
		(layer "B.Cu")
		(net "HSC_FAULT_N")
	)
	(segment
		(start 213.75243 -367.5126)
		(end 216.279476 -364.985554)
		(width 0.13208)
		(layer "B.Cu")
		(net "HSC_FAULT_N")
	)
	(segment
		(start 227.505514 -361.953556)
		(end 228.252782 -361.206288)
		(width 0.13208)
		(layer "B.Cu")
		(net "HSC_FAULT_N")
	)
	(segment
		(start 232.594404 -368.97564)
		(end 232.594404 -369.488974)
		(width 0.13208)
		(layer "B.Cu")
		(net "HSC_FAULT_N")
	)
	(segment
		(start 224.734374 -371.569488)
		(end 225.248724 -371.055138)
		(width 0.13208)
		(layer "B.Cu")
		(net "HSC_FAULT_N")
	)
	(segment
		(start 232.686606 -361.206288)
		(end 233.458766 -361.978448)
		(width 0.13208)
		(layer "B.Cu")
		(net "HSC_FAULT_N")
	)
	(segment
		(start 216.90838 -361.333542)
		(end 222.262192 -361.333542)
		(width 0.13208)
		(layer "B.Cu")
		(net "HSC_FAULT_N")
	)
	(segment
		(start 227.505514 -368.454686)
		(end 227.505514 -361.953556)
		(width 0.13208)
		(layer "B.Cu")
		(net "HSC_FAULT_N")
	)
	(segment
		(start 233.14787 -368.422174)
		(end 232.594404 -368.97564)
		(width 0.13208)
		(layer "B.Cu")
		(net "HSC_FAULT_N")
	)
	(segment
		(start 232.986834 -369.881404)
		(end 233.49839 -369.881404)
		(width 0.13208)
		(layer "B.Cu")
		(net "HSC_FAULT_N")
	)
	(segment
		(start 216.279476 -364.985554)
		(end 216.279476 -361.962446)
		(width 0.13208)
		(layer "B.Cu")
		(net "HSC_FAULT_N")
	)
	(segment
		(start 226.121468 -371.58676)
		(end 226.6569 -371.051328)
		(width 0.13208)
		(layer "B.Cu")
		(net "HSC_FAULT_N")
	)
	(segment
		(start 212.303614 -367.5126)
		(end 213.75243 -367.5126)
		(width 0.13208)
		(layer "B.Cu")
		(net "HSC_FAULT_N")
	)
	(segment
		(start 222.663004 -368.29111)
		(end 221.939866 -369.014248)
		(width 0.13208)
		(layer "B.Cu")
		(net "HSC_FAULT_N")
	)
	(segment
		(start 216.279476 -361.962446)
		(end 216.90838 -361.333542)
		(width 0.13208)
		(layer "B.Cu")
		(net "HSC_FAULT_N")
	)
	(segment
		(start 211.810092 -368.006122)
		(end 212.303614 -367.5126)
		(width 0.13208)
		(layer "B.Cu")
		(net "HSC_FAULT_N")
	)
	(segment
		(start 233.458766 -361.978448)
		(end 233.458766 -366.831118)
		(width 0.13208)
		(layer "B.Cu")
		(net "HSC_FAULT_N")
	)
	(segment
		(start 232.26776 -219.10421)
		(end 232.667556 -219.504006)
		(width 0.381)
		(layer "F.Cu")
		(net "P3V3_BIC_ADCAV33")
	)
	(segment
		(start 232.26776 -219.904056)
		(end 232.667556 -220.303852)
		(width 0.381)
		(layer "F.Cu")
		(net "P3V3_BIC_ADCAV33")
	)
	(via
		(at 236.809026 -221.393004)
		(size 0.508)
		(drill 0.254)
		(layers "F.Cu" "B.Cu")
		(net "P3V3_BIC_ADCAV33")
	)
	(via
		(at 236.683804 -222.130874)
		(size 0.6604)
		(drill 0.3302)
		(layers "F.Cu" "B.Cu")
		(net "P3V3_BIC_ADCAV33")
	)
	(via
		(at 232.667556 -219.504006)
		(size 0.4572)
		(drill 0.254)
		(layers "F.Cu" "B.Cu")
		(net "P3V3_BIC_ADCAV33")
	)
	(via
		(at 232.667556 -220.303852)
		(size 0.4572)
		(drill 0.254)
		(layers "F.Cu" "B.Cu")
		(net "P3V3_BIC_ADCAV33")
	)
	(via
		(at 237.471712 -221.418658)
		(size 0.508)
		(drill 0.254)
		(layers "F.Cu" "B.Cu")
		(net "P3V3_BIC_ADCAV33")
	)
	(segment
		(start 232.26776 -220.704156)
		(end 232.26776 -220.703648)
		(width 0.3048)
		(layer "B.Cu")
		(net "P3V3_BIC_ADCAV33")
	)
	(segment
		(start 232.26776 -219.903802)
		(end 232.667556 -219.504006)
		(width 0.3048)
		(layer "B.Cu")
		(net "P3V3_BIC_ADCAV33")
	)
	(segment
		(start 232.26776 -219.904056)
		(end 232.26776 -219.903802)
		(width 0.3048)
		(layer "B.Cu")
		(net "P3V3_BIC_ADCAV33")
	)
	(segment
		(start 232.26776 -220.703648)
		(end 232.667556 -220.303852)
		(width 0.3048)
		(layer "B.Cu")
		(net "P3V3_BIC_ADCAV33")
	)
	(segment
		(start 229.437438 -63.000128)
		(end 227.893372 -63.000128)
		(width 0.13208)
		(layer "F.Cu")
		(net "RST_SMB_FIO_R_N")
	)
	(segment
		(start 227.893372 -63.000128)
		(end 227.346256 -63.547244)
		(width 0.13208)
		(layer "F.Cu")
		(net "RST_SMB_FIO_R_N")
	)
	(via
		(at 225.530664 -205.47711)
		(size 0.508)
		(drill 0.254)
		(layers "F.Cu" "B.Cu")
		(net "RST_SMB_FIO_R_N")
	)
	(via
		(at 227.346256 -63.547244)
		(size 0.508)
		(drill 0.254)
		(layers "F.Cu" "B.Cu")
		(net "RST_SMB_FIO_R_N")
	)
	(segment
		(start 225.530664 -208.36001)
		(end 225.530664 -205.47711)
		(width 0.13208)
		(layer "B.Cu")
		(net "RST_SMB_FIO_R_N")
	)
	(segment
		(start 225.556064 -208.38541)
		(end 225.530664 -208.36001)
		(width 0.13208)
		(layer "B.Cu")
		(net "RST_SMB_FIO_R_N")
	)
	(segment
		(start 225.530664 -205.47711)
		(end 225.530664 -204.84211)
		(width 0.13208)
		(layer "B.Cu")
		(net "RST_SMB_FIO_R_N")
	)
	(segment
		(start 226.1362 -167.741092)
		(end 223.9264 -165.531292)
		(width 0.15494)
		(layer "In7.Cu")
		(net "RST_SMB_FIO_R_N")
	)
	(segment
		(start 228.909372 -88.056466)
		(end 229.323646 -87.642192)
		(width 0.15494)
		(layer "In7.Cu")
		(net "RST_SMB_FIO_R_N")
	)
	(segment
		(start 226.398328 -202.56246)
		(end 226.398328 -201.932032)
		(width 0.15494)
		(layer "In7.Cu")
		(net "RST_SMB_FIO_R_N")
	)
	(segment
		(start 229.323646 -82.258916)
		(end 226.729036 -79.664306)
		(width 0.15494)
		(layer "In7.Cu")
		(net "RST_SMB_FIO_R_N")
	)
	(segment
		(start 226.205542 -70.327774)
		(end 226.205542 -65.694306)
		(width 0.15494)
		(layer "In7.Cu")
		(net "RST_SMB_FIO_R_N")
	)
	(segment
		(start 226.0346 -203.749656)
		(end 226.0346 -202.926188)
		(width 0.15494)
		(layer "In7.Cu")
		(net "RST_SMB_FIO_R_N")
	)
	(segment
		(start 241.8842 -118.993158)
		(end 241.8842 -102.320598)
		(width 0.15494)
		(layer "In7.Cu")
		(net "RST_SMB_FIO_R_N")
	)
	(segment
		(start 234.639358 -126.238)
		(end 241.8842 -118.993158)
		(width 0.15494)
		(layer "In7.Cu")
		(net "RST_SMB_FIO_R_N")
	)
	(segment
		(start 229.323646 -87.642192)
		(end 229.323646 -82.258916)
		(width 0.15494)
		(layer "In7.Cu")
		(net "RST_SMB_FIO_R_N")
	)
	(segment
		(start 223.012 -138.94435)
		(end 223.012 -136.017)
		(width 0.15494)
		(layer "In7.Cu")
		(net "RST_SMB_FIO_R_N")
	)
	(segment
		(start 227.203 -191.91224)
		(end 227.203 -185.750454)
		(width 0.15494)
		(layer "In7.Cu")
		(net "RST_SMB_FIO_R_N")
	)
	(segment
		(start 219.6338 -154.066494)
		(end 219.6338 -140.690092)
		(width 0.15494)
		(layer "In7.Cu")
		(net "RST_SMB_FIO_R_N")
	)
	(segment
		(start 231.009444 -97.720404)
		(end 228.909372 -95.620332)
		(width 0.15494)
		(layer "In7.Cu")
		(net "RST_SMB_FIO_R_N")
	)
	(segment
		(start 227.346256 -63.995808)
		(end 227.346256 -63.547244)
		(width 0.15494)
		(layer "In7.Cu")
		(net "RST_SMB_FIO_R_N")
	)
	(segment
		(start 226.729036 -70.851268)
		(end 226.205542 -70.327774)
		(width 0.15494)
		(layer "In7.Cu")
		(net "RST_SMB_FIO_R_N")
	)
	(segment
		(start 227.41763 -199.613774)
		(end 227.41763 -198.917814)
		(width 0.15494)
		(layer "In7.Cu")
		(net "RST_SMB_FIO_R_N")
	)
	(segment
		(start 226.7458 -200.304654)
		(end 227.3808 -199.669654)
		(width 0.15494)
		(layer "In7.Cu")
		(net "RST_SMB_FIO_R_N")
	)
	(segment
		(start 237.284006 -97.720404)
		(end 231.009444 -97.720404)
		(width 0.15494)
		(layer "In7.Cu")
		(net "RST_SMB_FIO_R_N")
	)
	(segment
		(start 226.398328 -201.932032)
		(end 226.7458 -201.58456)
		(width 0.15494)
		(layer "In7.Cu")
		(net "RST_SMB_FIO_R_N")
	)
	(segment
		(start 241.8842 -102.320598)
		(end 237.284006 -97.720404)
		(width 0.15494)
		(layer "In7.Cu")
		(net "RST_SMB_FIO_R_N")
	)
	(segment
		(start 232.791 -126.238)
		(end 234.639358 -126.238)
		(width 0.15494)
		(layer "In7.Cu")
		(net "RST_SMB_FIO_R_N")
	)
	(segment
		(start 223.9264 -158.359094)
		(end 219.6338 -154.066494)
		(width 0.15494)
		(layer "In7.Cu")
		(net "RST_SMB_FIO_R_N")
	)
	(segment
		(start 224.6376 -183.185054)
		(end 224.6376 -180.972968)
		(width 0.15494)
		(layer "In7.Cu")
		(net "RST_SMB_FIO_R_N")
	)
	(segment
		(start 223.9264 -165.531292)
		(end 223.9264 -158.359094)
		(width 0.15494)
		(layer "In7.Cu")
		(net "RST_SMB_FIO_R_N")
	)
	(segment
		(start 221.802452 -140.153898)
		(end 223.012 -138.94435)
		(width 0.15494)
		(layer "In7.Cu")
		(net "RST_SMB_FIO_R_N")
	)
	(segment
		(start 227.41763 -198.917814)
		(end 226.79914 -198.299324)
		(width 0.15494)
		(layer "In7.Cu")
		(net "RST_SMB_FIO_R_N")
	)
	(segment
		(start 226.1362 -177.636932)
		(end 226.1362 -167.741092)
		(width 0.15494)
		(layer "In7.Cu")
		(net "RST_SMB_FIO_R_N")
	)
	(segment
		(start 226.205542 -65.694306)
		(end 227.42144 -64.478408)
		(width 0.15494)
		(layer "In7.Cu")
		(net "RST_SMB_FIO_R_N")
	)
	(segment
		(start 227.3808 -199.650604)
		(end 227.41763 -199.613774)
		(width 0.15494)
		(layer "In7.Cu")
		(net "RST_SMB_FIO_R_N")
	)
	(segment
		(start 225.4504 -178.322732)
		(end 226.1362 -177.636932)
		(width 0.15494)
		(layer "In7.Cu")
		(net "RST_SMB_FIO_R_N")
	)
	(segment
		(start 228.909372 -95.620332)
		(end 228.909372 -88.056466)
		(width 0.15494)
		(layer "In7.Cu")
		(net "RST_SMB_FIO_R_N")
	)
	(segment
		(start 226.79914 -198.299324)
		(end 226.79914 -192.3161)
		(width 0.15494)
		(layer "In7.Cu")
		(net "RST_SMB_FIO_R_N")
	)
	(segment
		(start 225.530664 -204.253592)
		(end 226.0346 -203.749656)
		(width 0.15494)
		(layer "In7.Cu")
		(net "RST_SMB_FIO_R_N")
	)
	(segment
		(start 219.6338 -140.690092)
		(end 220.169994 -140.153898)
		(width 0.15494)
		(layer "In7.Cu")
		(net "RST_SMB_FIO_R_N")
	)
	(segment
		(start 226.0346 -202.926188)
		(end 226.398328 -202.56246)
		(width 0.15494)
		(layer "In7.Cu")
		(net "RST_SMB_FIO_R_N")
	)
	(segment
		(start 227.42144 -64.070992)
		(end 227.346256 -63.995808)
		(width 0.15494)
		(layer "In7.Cu")
		(net "RST_SMB_FIO_R_N")
	)
	(segment
		(start 227.203 -185.750454)
		(end 224.6376 -183.185054)
		(width 0.15494)
		(layer "In7.Cu")
		(net "RST_SMB_FIO_R_N")
	)
	(segment
		(start 225.530664 -205.47711)
		(end 225.530664 -204.253592)
		(width 0.15494)
		(layer "In7.Cu")
		(net "RST_SMB_FIO_R_N")
	)
	(segment
		(start 225.4504 -180.160168)
		(end 225.4504 -178.322732)
		(width 0.15494)
		(layer "In7.Cu")
		(net "RST_SMB_FIO_R_N")
	)
	(segment
		(start 224.6376 -180.972968)
		(end 225.4504 -180.160168)
		(width 0.15494)
		(layer "In7.Cu")
		(net "RST_SMB_FIO_R_N")
	)
	(segment
		(start 226.7458 -201.58456)
		(end 226.7458 -200.304654)
		(width 0.15494)
		(layer "In7.Cu")
		(net "RST_SMB_FIO_R_N")
	)
	(segment
		(start 226.79914 -192.3161)
		(end 227.203 -191.91224)
		(width 0.15494)
		(layer "In7.Cu")
		(net "RST_SMB_FIO_R_N")
	)
	(segment
		(start 226.729036 -79.664306)
		(end 226.729036 -70.851268)
		(width 0.15494)
		(layer "In7.Cu")
		(net "RST_SMB_FIO_R_N")
	)
	(segment
		(start 227.3808 -199.669654)
		(end 227.3808 -199.650604)
		(width 0.15494)
		(layer "In7.Cu")
		(net "RST_SMB_FIO_R_N")
	)
	(segment
		(start 223.012 -136.017)
		(end 232.791 -126.238)
		(width 0.15494)
		(layer "In7.Cu")
		(net "RST_SMB_FIO_R_N")
	)
	(segment
		(start 227.42144 -64.478408)
		(end 227.42144 -64.070992)
		(width 0.15494)
		(layer "In7.Cu")
		(net "RST_SMB_FIO_R_N")
	)
	(segment
		(start 220.169994 -140.153898)
		(end 221.802452 -140.153898)
		(width 0.15494)
		(layer "In7.Cu")
		(net "RST_SMB_FIO_R_N")
	)
	(segment
		(start 420.774876 -306.824888)
		(end 420.299896 -307.299868)
		(width 0.13208)
		(layer "F.Cu")
		(net "SMB_PEX3_SLAVE_SCL")
	)
	(segment
		(start 434.29428 -303.91481)
		(end 434.964078 -303.91481)
		(width 0.13208)
		(layer "F.Cu")
		(net "SMB_PEX3_SLAVE_SCL")
	)
	(segment
		(start 434.964078 -303.91481)
		(end 434.985668 -303.9364)
		(width 0.13208)
		(layer "F.Cu")
		(net "SMB_PEX3_SLAVE_SCL")
	)
	(via
		(at 420.774876 -306.824888)
		(size 0.4064)
		(drill 0.2032)
		(layers "F.Cu" "B.Cu")
		(net "SMB_PEX3_SLAVE_SCL")
	)
	(via
		(at 433.00904 -305.3588)
		(size 0.6604)
		(drill 0.3302)
		(layers "F.Cu" "B.Cu")
		(net "SMB_PEX3_SLAVE_SCL")
	)
	(via
		(at 434.985668 -303.9364)
		(size 0.508)
		(drill 0.254)
		(layers "F.Cu" "B.Cu")
		(net "SMB_PEX3_SLAVE_SCL")
	)
	(segment
		(start 432.632866 -304.982626)
		(end 422.459658 -304.982626)
		(width 0.13208)
		(layer "B.Cu")
		(net "SMB_PEX3_SLAVE_SCL")
	)
	(segment
		(start 434.5432 -304.378868)
		(end 434.5432 -304.753264)
		(width 0.13208)
		(layer "B.Cu")
		(net "SMB_PEX3_SLAVE_SCL")
	)
	(segment
		(start 434.5432 -304.753264)
		(end 433.937664 -305.3588)
		(width 0.13208)
		(layer "B.Cu")
		(net "SMB_PEX3_SLAVE_SCL")
	)
	(segment
		(start 433.937664 -305.3588)
		(end 433.00904 -305.3588)
		(width 0.13208)
		(layer "B.Cu")
		(net "SMB_PEX3_SLAVE_SCL")
	)
	(segment
		(start 421.517318 -305.43373)
		(end 421.2463 -305.704748)
		(width 0.13208)
		(layer "B.Cu")
		(net "SMB_PEX3_SLAVE_SCL")
	)
	(segment
		(start 433.00904 -305.3588)
		(end 432.632866 -304.982626)
		(width 0.13208)
		(layer "B.Cu")
		(net "SMB_PEX3_SLAVE_SCL")
	)
	(segment
		(start 422.008554 -305.43373)
		(end 421.517318 -305.43373)
		(width 0.13208)
		(layer "B.Cu")
		(net "SMB_PEX3_SLAVE_SCL")
	)
	(segment
		(start 434.985668 -303.9364)
		(end 434.5432 -304.378868)
		(width 0.13208)
		(layer "B.Cu")
		(net "SMB_PEX3_SLAVE_SCL")
	)
	(segment
		(start 421.2463 -305.704748)
		(end 421.2463 -306.353464)
		(width 0.13208)
		(layer "B.Cu")
		(net "SMB_PEX3_SLAVE_SCL")
	)
	(segment
		(start 422.459658 -304.982626)
		(end 422.008554 -305.43373)
		(width 0.13208)
		(layer "B.Cu")
		(net "SMB_PEX3_SLAVE_SCL")
	)
	(segment
		(start 421.2463 -306.353464)
		(end 420.774876 -306.824888)
		(width 0.13208)
		(layer "B.Cu")
		(net "SMB_PEX3_SLAVE_SCL")
	)
	(segment
		(start 337.157314 -183.523636)
		(end 337.67395 -183.007)
		(width 0.13208)
		(layer "F.Cu")
		(net "PRSNT_SSD8_FPGA_R_N")
	)
	(segment
		(start 327.13295 -214.249)
		(end 326.517 -214.249)
		(width 0.13208)
		(layer "F.Cu")
		(net "PRSNT_SSD8_FPGA_R_N")
	)
	(segment
		(start 325.9836 -182.8038)
		(end 326.703436 -183.523636)
		(width 0.13208)
		(layer "F.Cu")
		(net "PRSNT_SSD8_FPGA_R_N")
	)
	(segment
		(start 326.703436 -183.523636)
		(end 337.157314 -183.523636)
		(width 0.13208)
		(layer "F.Cu")
		(net "PRSNT_SSD8_FPGA_R_N")
	)
	(via
		(at 326.517 -214.249)
		(size 0.508)
		(drill 0.254)
		(layers "F.Cu" "B.Cu")
		(net "PRSNT_SSD8_FPGA_R_N")
	)
	(via
		(at 325.9836 -182.8038)
		(size 0.508)
		(drill 0.254)
		(layers "F.Cu" "B.Cu")
		(net "PRSNT_SSD8_FPGA_R_N")
	)
	(segment
		(start 324.802246 -198.798434)
		(end 325.660766 -198.798434)
		(width 0.15494)
		(layer "In9.Cu")
		(net "PRSNT_SSD8_FPGA_R_N")
	)
	(segment
		(start 324.519036 -199.081644)
		(end 324.802246 -198.798434)
		(width 0.15494)
		(layer "In9.Cu")
		(net "PRSNT_SSD8_FPGA_R_N")
	)
	(segment
		(start 325.95312 -198.50608)
		(end 325.95312 -195.257166)
		(width 0.15494)
		(layer "In9.Cu")
		(net "PRSNT_SSD8_FPGA_R_N")
	)
	(segment
		(start 326.517 -214.249)
		(end 323.259196 -210.991196)
		(width 0.15494)
		(layer "In9.Cu")
		(net "PRSNT_SSD8_FPGA_R_N")
	)
	(segment
		(start 326.81672 -194.393566)
		(end 326.81672 -183.63692)
		(width 0.15494)
		(layer "In9.Cu")
		(net "PRSNT_SSD8_FPGA_R_N")
	)
	(segment
		(start 323.259196 -210.991196)
		(end 323.259196 -204.591158)
		(width 0.15494)
		(layer "In9.Cu")
		(net "PRSNT_SSD8_FPGA_R_N")
	)
	(segment
		(start 324.519036 -200.703434)
		(end 324.519036 -199.081644)
		(width 0.15494)
		(layer "In9.Cu")
		(net "PRSNT_SSD8_FPGA_R_N")
	)
	(segment
		(start 326.81672 -183.63692)
		(end 325.9836 -182.8038)
		(width 0.15494)
		(layer "In9.Cu")
		(net "PRSNT_SSD8_FPGA_R_N")
	)
	(segment
		(start 323.259196 -204.591158)
		(end 323.512434 -201.710036)
		(width 0.15494)
		(layer "In9.Cu")
		(net "PRSNT_SSD8_FPGA_R_N")
	)
	(segment
		(start 323.512434 -201.710036)
		(end 324.519036 -200.703434)
		(width 0.15494)
		(layer "In9.Cu")
		(net "PRSNT_SSD8_FPGA_R_N")
	)
	(segment
		(start 325.660766 -198.798434)
		(end 325.95312 -198.50608)
		(width 0.15494)
		(layer "In9.Cu")
		(net "PRSNT_SSD8_FPGA_R_N")
	)
	(segment
		(start 325.95312 -195.257166)
		(end 326.81672 -194.393566)
		(width 0.15494)
		(layer "In9.Cu")
		(net "PRSNT_SSD8_FPGA_R_N")
	)
	(segment
		(start 223.83623 -373.090186)
		(end 223.07423 -372.328186)
		(width 0.13208)
		(layer "F.Cu")
		(net "HSC_FLT_TYPE_1")
	)
	(segment
		(start 223.07423 -370.651786)
		(end 222.130112 -369.707668)
		(width 0.13208)
		(layer "F.Cu")
		(net "HSC_FLT_TYPE_1")
	)
	(segment
		(start 222.130112 -369.707668)
		(end 221.86392 -369.707668)
		(width 0.13208)
		(layer "F.Cu")
		(net "HSC_FLT_TYPE_1")
	)
	(segment
		(start 223.07423 -372.328186)
		(end 223.07423 -370.651786)
		(width 0.13208)
		(layer "F.Cu")
		(net "HSC_FLT_TYPE_1")
	)
	(segment
		(start 224.451926 -373.090186)
		(end 223.83623 -373.090186)
		(width 0.13208)
		(layer "F.Cu")
		(net "HSC_FLT_TYPE_1")
	)
	(via
		(at 223.07423 -372.328186)
		(size 0.762)
		(drill 0.381)
		(layers "F.Cu" "B.Cu")
		(net "HSC_FLT_TYPE_1")
	)
	(segment
		(start 224.514664 -205.47711)
		(end 224.514664 -206.62011)
		(width 0.13208)
		(layer "F.Cu")
		(net "RST_SMB_FPGA_R_N")
	)
	(segment
		(start 342.893904 -214.387176)
		(end 343.2937 -213.98738)
		(width 0.13208)
		(layer "F.Cu")
		(net "RST_SMB_FPGA_R_N")
	)
	(via
		(at 224.514664 -205.47711)
		(size 0.508)
		(drill 0.254)
		(layers "F.Cu" "B.Cu")
		(net "RST_SMB_FPGA_R_N")
	)
	(via
		(at 343.2937 -213.98738)
		(size 0.4572)
		(drill 0.254)
		(layers "F.Cu" "B.Cu")
		(net "RST_SMB_FPGA_R_N")
	)
	(via
		(at 218.236546 -189.107318)
		(size 0.508)
		(drill 0.254)
		(layers "F.Cu" "B.Cu")
		(net "RST_SMB_FPGA_R_N")
	)
	(segment
		(start 223.8248 -202.818746)
		(end 219.158566 -198.152512)
		(width 0.15494)
		(layer "In5.Cu")
		(net "RST_SMB_FPGA_R_N")
	)
	(segment
		(start 224.514664 -205.47711)
		(end 223.8248 -204.787246)
		(width 0.15494)
		(layer "In5.Cu")
		(net "RST_SMB_FPGA_R_N")
	)
	(segment
		(start 217.551 -195.2498)
		(end 217.551 -189.792864)
		(width 0.15494)
		(layer "In5.Cu")
		(net "RST_SMB_FPGA_R_N")
	)
	(segment
		(start 219.158566 -196.857366)
		(end 217.551 -195.2498)
		(width 0.15494)
		(layer "In5.Cu")
		(net "RST_SMB_FPGA_R_N")
	)
	(segment
		(start 223.8248 -204.787246)
		(end 223.8248 -202.818746)
		(width 0.15494)
		(layer "In5.Cu")
		(net "RST_SMB_FPGA_R_N")
	)
	(segment
		(start 217.551 -189.792864)
		(end 218.236546 -189.107318)
		(width 0.15494)
		(layer "In5.Cu")
		(net "RST_SMB_FPGA_R_N")
	)
	(segment
		(start 219.158566 -198.152512)
		(end 219.158566 -196.857366)
		(width 0.15494)
		(layer "In5.Cu")
		(net "RST_SMB_FPGA_R_N")
	)
	(segment
		(start 225.56597 -182.870094)
		(end 224.93732 -183.498744)
		(width 0.15494)
		(layer "In13.Cu")
		(net "RST_SMB_FPGA_R_N")
	)
	(segment
		(start 235.468414 -181.23154)
		(end 234.023154 -182.6768)
		(width 0.15494)
		(layer "In13.Cu")
		(net "RST_SMB_FPGA_R_N")
	)
	(segment
		(start 337.34883 -206.6798)
		(end 331.952092 -206.6798)
		(width 0.15494)
		(layer "In13.Cu")
		(net "RST_SMB_FPGA_R_N")
	)
	(segment
		(start 331.952092 -206.6798)
		(end 330.033122 -207.474058)
		(width 0.15494)
		(layer "In13.Cu")
		(net "RST_SMB_FPGA_R_N")
	)
	(segment
		(start 229.014528 -182.33009)
		(end 228.474524 -182.870094)
		(width 0.15494)
		(layer "In13.Cu")
		(net "RST_SMB_FPGA_R_N")
	)
	(segment
		(start 342.479884 -211.810854)
		(end 342.101678 -211.432648)
		(width 0.15494)
		(layer "In13.Cu")
		(net "RST_SMB_FPGA_R_N")
	)
	(segment
		(start 341.848694 -211.179664)
		(end 337.34883 -206.6798)
		(width 0.15494)
		(layer "In13.Cu")
		(net "RST_SMB_FPGA_R_N")
	)
	(segment
		(start 228.474524 -182.870094)
		(end 225.56597 -182.870094)
		(width 0.15494)
		(layer "In13.Cu")
		(net "RST_SMB_FPGA_R_N")
	)
	(segment
		(start 342.479884 -213.173564)
		(end 342.479884 -211.810854)
		(width 0.15494)
		(layer "In13.Cu")
		(net "RST_SMB_FPGA_R_N")
	)
	(segment
		(start 343.2937 -213.98738)
		(end 342.479884 -213.173564)
		(width 0.15494)
		(layer "In13.Cu")
		(net "RST_SMB_FPGA_R_N")
	)
	(segment
		(start 282.003246 -207.51927)
		(end 263.462262 -188.978286)
		(width 0.15494)
		(layer "In13.Cu")
		(net "RST_SMB_FPGA_R_N")
	)
	(segment
		(start 327.956418 -207.474058)
		(end 326.313038 -205.830678)
		(width 0.15494)
		(layer "In13.Cu")
		(net "RST_SMB_FPGA_R_N")
	)
	(segment
		(start 224.93732 -183.498744)
		(end 223.84512 -183.498744)
		(width 0.15494)
		(layer "In13.Cu")
		(net "RST_SMB_FPGA_R_N")
	)
	(segment
		(start 330.033122 -207.474058)
		(end 327.956418 -207.474058)
		(width 0.15494)
		(layer "In13.Cu")
		(net "RST_SMB_FPGA_R_N")
	)
	(segment
		(start 263.462262 -188.978286)
		(end 258.904486 -188.978286)
		(width 0.15494)
		(layer "In13.Cu")
		(net "RST_SMB_FPGA_R_N")
	)
	(segment
		(start 342.101678 -211.418424)
		(end 341.862918 -211.179664)
		(width 0.15494)
		(layer "In13.Cu")
		(net "RST_SMB_FPGA_R_N")
	)
	(segment
		(start 251.15774 -181.23154)
		(end 235.468414 -181.23154)
		(width 0.15494)
		(layer "In13.Cu")
		(net "RST_SMB_FPGA_R_N")
	)
	(segment
		(start 300.8376 -205.830678)
		(end 299.149008 -207.51927)
		(width 0.15494)
		(layer "In13.Cu")
		(net "RST_SMB_FPGA_R_N")
	)
	(segment
		(start 299.149008 -207.51927)
		(end 282.003246 -207.51927)
		(width 0.15494)
		(layer "In13.Cu")
		(net "RST_SMB_FPGA_R_N")
	)
	(segment
		(start 230.984044 -182.6768)
		(end 230.637334 -182.33009)
		(width 0.15494)
		(layer "In13.Cu")
		(net "RST_SMB_FPGA_R_N")
	)
	(segment
		(start 341.862918 -211.179664)
		(end 341.848694 -211.179664)
		(width 0.15494)
		(layer "In13.Cu")
		(net "RST_SMB_FPGA_R_N")
	)
	(segment
		(start 258.904486 -188.978286)
		(end 251.15774 -181.23154)
		(width 0.15494)
		(layer "In13.Cu")
		(net "RST_SMB_FPGA_R_N")
	)
	(segment
		(start 342.101678 -211.432648)
		(end 342.101678 -211.418424)
		(width 0.15494)
		(layer "In13.Cu")
		(net "RST_SMB_FPGA_R_N")
	)
	(segment
		(start 234.023154 -182.6768)
		(end 230.984044 -182.6768)
		(width 0.15494)
		(layer "In13.Cu")
		(net "RST_SMB_FPGA_R_N")
	)
	(segment
		(start 223.84512 -183.498744)
		(end 218.236546 -189.107318)
		(width 0.15494)
		(layer "In13.Cu")
		(net "RST_SMB_FPGA_R_N")
	)
	(segment
		(start 326.313038 -205.830678)
		(end 300.8376 -205.830678)
		(width 0.15494)
		(layer "In13.Cu")
		(net "RST_SMB_FPGA_R_N")
	)
	(segment
		(start 230.637334 -182.33009)
		(end 229.014528 -182.33009)
		(width 0.15494)
		(layer "In13.Cu")
		(net "RST_SMB_FPGA_R_N")
	)
	(segment
		(start 436.53075 -305.355244)
		(end 436.53075 -304.752756)
		(width 0.13208)
		(layer "F.Cu")
		(net "SMB_PEX3_SLAVE_SDA")
	)
	(segment
		(start 436.262272 -305.623722)
		(end 436.53075 -305.355244)
		(width 0.13208)
		(layer "F.Cu")
		(net "SMB_PEX3_SLAVE_SDA")
	)
	(segment
		(start 420.774876 -308.724808)
		(end 421.249856 -309.199788)
		(width 0.13208)
		(layer "F.Cu")
		(net "SMB_PEX3_SLAVE_SDA")
	)
	(via
		(at 420.774876 -308.724808)
		(size 0.4064)
		(drill 0.2032)
		(layers "F.Cu" "B.Cu")
		(net "SMB_PEX3_SLAVE_SDA")
	)
	(via
		(at 436.53075 -304.752756)
		(size 0.508)
		(drill 0.254)
		(layers "F.Cu" "B.Cu")
		(net "SMB_PEX3_SLAVE_SDA")
	)
	(via
		(at 435.692296 -305.59121)
		(size 0.6604)
		(drill 0.3302)
		(layers "F.Cu" "B.Cu")
		(net "SMB_PEX3_SLAVE_SDA")
	)
	(segment
		(start 434.036216 -307.117496)
		(end 434.302662 -307.516022)
		(width 0.13208)
		(layer "B.Cu")
		(net "SMB_PEX3_SLAVE_SDA")
	)
	(segment
		(start 434.115464 -307.79593)
		(end 433.937156 -307.76037)
		(width 0.13208)
		(layer "B.Cu")
		(net "SMB_PEX3_SLAVE_SDA")
	)
	(segment
		(start 433.67071 -307.361844)
		(end 433.492402 -307.326284)
		(width 0.13208)
		(layer "B.Cu")
		(net "SMB_PEX3_SLAVE_SDA")
	)
	(segment
		(start 434.668168 -307.271674)
		(end 434.401722 -306.873148)
		(width 0.13208)
		(layer "B.Cu")
		(net "SMB_PEX3_SLAVE_SDA")
	)
	(segment
		(start 433.53609 -308.183026)
		(end 433.384452 -308.284626)
		(width 0.13208)
		(layer "B.Cu")
		(net "SMB_PEX3_SLAVE_SDA")
	)
	(segment
		(start 434.302662 -307.516022)
		(end 434.267102 -307.69433)
		(width 0.13208)
		(layer "B.Cu")
		(net "SMB_PEX3_SLAVE_SDA")
	)
	(segment
		(start 434.998114 -307.205634)
		(end 434.846476 -307.307234)
		(width 0.13208)
		(layer "B.Cu")
		(net "SMB_PEX3_SLAVE_SDA")
	)
	(segment
		(start 433.937156 -307.76037)
		(end 433.67071 -307.361844)
		(width 0.13208)
		(layer "B.Cu")
		(net "SMB_PEX3_SLAVE_SDA")
	)
	(segment
		(start 434.846476 -307.307234)
		(end 434.668168 -307.271674)
		(width 0.13208)
		(layer "B.Cu")
		(net "SMB_PEX3_SLAVE_SDA")
	)
	(segment
		(start 434.892196 -306.39131)
		(end 434.802788 -306.450746)
		(width 0.13208)
		(layer "B.Cu")
		(net "SMB_PEX3_SLAVE_SDA")
	)
	(segment
		(start 434.767228 -306.6288)
		(end 435.033674 -307.027326)
		(width 0.13208)
		(layer "B.Cu")
		(net "SMB_PEX3_SLAVE_SDA")
	)
	(segment
		(start 421.238426 -308.261258)
		(end 420.774876 -308.724808)
		(width 0.13208)
		(layer "B.Cu")
		(net "SMB_PEX3_SLAVE_SDA")
	)
	(segment
		(start 434.802788 -306.450746)
		(end 434.767228 -306.6288)
		(width 0.13208)
		(layer "B.Cu")
		(net "SMB_PEX3_SLAVE_SDA")
	)
	(segment
		(start 435.692296 -305.59121)
		(end 436.53075 -304.752756)
		(width 0.13208)
		(layer "B.Cu")
		(net "SMB_PEX3_SLAVE_SDA")
	)
	(segment
		(start 433.57165 -308.004718)
		(end 433.53609 -308.183026)
		(width 0.13208)
		(layer "B.Cu")
		(net "SMB_PEX3_SLAVE_SDA")
	)
	(segment
		(start 435.692296 -305.59121)
		(end 434.892196 -306.39131)
		(width 0.13208)
		(layer "B.Cu")
		(net "SMB_PEX3_SLAVE_SDA")
	)
	(segment
		(start 422.464484 -307.815234)
		(end 422.01846 -308.261258)
		(width 0.13208)
		(layer "B.Cu")
		(net "SMB_PEX3_SLAVE_SDA")
	)
	(segment
		(start 435.033674 -307.027326)
		(end 434.998114 -307.205634)
		(width 0.13208)
		(layer "B.Cu")
		(net "SMB_PEX3_SLAVE_SDA")
	)
	(segment
		(start 434.071776 -306.939188)
		(end 434.036216 -307.117496)
		(width 0.13208)
		(layer "B.Cu")
		(net "SMB_PEX3_SLAVE_SDA")
	)
	(segment
		(start 433.492402 -307.326284)
		(end 433.340764 -307.427884)
		(width 0.13208)
		(layer "B.Cu")
		(net "SMB_PEX3_SLAVE_SDA")
	)
	(segment
		(start 432.939698 -307.85054)
		(end 432.761136 -307.815234)
		(width 0.13208)
		(layer "B.Cu")
		(net "SMB_PEX3_SLAVE_SDA")
	)
	(segment
		(start 434.267102 -307.69433)
		(end 434.115464 -307.79593)
		(width 0.13208)
		(layer "B.Cu")
		(net "SMB_PEX3_SLAVE_SDA")
	)
	(segment
		(start 433.340764 -307.427884)
		(end 433.305204 -307.606192)
		(width 0.13208)
		(layer "B.Cu")
		(net "SMB_PEX3_SLAVE_SDA")
	)
	(segment
		(start 422.01846 -308.261258)
		(end 421.238426 -308.261258)
		(width 0.13208)
		(layer "B.Cu")
		(net "SMB_PEX3_SLAVE_SDA")
	)
	(segment
		(start 434.223414 -306.837588)
		(end 434.071776 -306.939188)
		(width 0.13208)
		(layer "B.Cu")
		(net "SMB_PEX3_SLAVE_SDA")
	)
	(segment
		(start 433.206144 -308.249066)
		(end 432.939698 -307.85054)
		(width 0.13208)
		(layer "B.Cu")
		(net "SMB_PEX3_SLAVE_SDA")
	)
	(segment
		(start 432.761136 -307.815234)
		(end 422.464484 -307.815234)
		(width 0.13208)
		(layer "B.Cu")
		(net "SMB_PEX3_SLAVE_SDA")
	)
	(segment
		(start 433.305204 -307.606192)
		(end 433.57165 -308.004718)
		(width 0.13208)
		(layer "B.Cu")
		(net "SMB_PEX3_SLAVE_SDA")
	)
	(segment
		(start 433.384452 -308.284626)
		(end 433.206144 -308.249066)
		(width 0.13208)
		(layer "B.Cu")
		(net "SMB_PEX3_SLAVE_SDA")
	)
	(segment
		(start 434.401722 -306.873148)
		(end 434.223414 -306.837588)
		(width 0.13208)
		(layer "B.Cu")
		(net "SMB_PEX3_SLAVE_SDA")
	)
	(segment
		(start 337.293966 -221.58706)
		(end 336.89417 -221.986856)
		(width 0.13208)
		(layer "F.Cu")
		(net "LED_POSTCODE_1")
	)
	(segment
		(start 324.317868 -224.659698)
		(end 324.98284 -224.659698)
		(width 0.13208)
		(layer "F.Cu")
		(net "LED_POSTCODE_1")
	)
	(segment
		(start 326.915018 -193.948304)
		(end 325.002906 -193.948304)
		(width 0.13208)
		(layer "F.Cu")
		(net "LED_POSTCODE_1")
	)
	(segment
		(start 327.611232 -194.644518)
		(end 326.915018 -193.948304)
		(width 0.13208)
		(layer "F.Cu")
		(net "LED_POSTCODE_1")
	)
	(segment
		(start 329.754484 -194.644518)
		(end 327.611232 -194.644518)
		(width 0.13208)
		(layer "F.Cu")
		(net "LED_POSTCODE_1")
	)
	(via
		(at 336.89417 -221.986856)
		(size 0.4572)
		(drill 0.254)
		(layers "F.Cu" "B.Cu")
		(net "LED_POSTCODE_1")
	)
	(via
		(at 324.98284 -224.659698)
		(size 0.508)
		(drill 0.254)
		(layers "F.Cu" "B.Cu")
		(net "LED_POSTCODE_1")
	)
	(via
		(at 325.002906 -193.948304)
		(size 0.508)
		(drill 0.254)
		(layers "F.Cu" "B.Cu")
		(net "LED_POSTCODE_1")
	)
	(segment
		(start 335.077308 -222.38462)
		(end 334.27162 -222.38462)
		(width 0.15494)
		(layer "In5.Cu")
		(net "LED_POSTCODE_1")
	)
	(segment
		(start 336.89417 -221.986856)
		(end 336.496406 -222.38462)
		(width 0.0889)
		(layer "In5.Cu")
		(net "LED_POSTCODE_1")
	)
	(segment
		(start 328.261472 -222.946468)
		(end 326.744584 -224.463356)
		(width 0.15494)
		(layer "In5.Cu")
		(net "LED_POSTCODE_1")
	)
	(segment
		(start 326.744584 -224.463356)
		(end 325.179182 -224.463356)
		(width 0.15494)
		(layer "In5.Cu")
		(net "LED_POSTCODE_1")
	)
	(segment
		(start 334.27162 -222.38462)
		(end 333.938626 -222.051626)
		(width 0.15494)
		(layer "In5.Cu")
		(net "LED_POSTCODE_1")
	)
	(segment
		(start 330.017374 -222.051626)
		(end 329.122532 -222.946468)
		(width 0.15494)
		(layer "In5.Cu")
		(net "LED_POSTCODE_1")
	)
	(segment
		(start 325.179182 -224.463356)
		(end 324.98284 -224.659698)
		(width 0.15494)
		(layer "In5.Cu")
		(net "LED_POSTCODE_1")
	)
	(segment
		(start 329.122532 -222.946468)
		(end 328.261472 -222.946468)
		(width 0.15494)
		(layer "In5.Cu")
		(net "LED_POSTCODE_1")
	)
	(segment
		(start 336.496406 -222.38462)
		(end 335.077308 -222.38462)
		(width 0.0889)
		(layer "In5.Cu")
		(net "LED_POSTCODE_1")
	)
	(segment
		(start 333.938626 -222.051626)
		(end 330.017374 -222.051626)
		(width 0.15494)
		(layer "In5.Cu")
		(net "LED_POSTCODE_1")
	)
	(segment
		(start 324.98284 -224.659698)
		(end 321.4878 -221.164658)
		(width 0.15494)
		(layer "In7.Cu")
		(net "LED_POSTCODE_1")
	)
	(segment
		(start 321.4878 -198.882254)
		(end 324.637654 -195.7324)
		(width 0.15494)
		(layer "In7.Cu")
		(net "LED_POSTCODE_1")
	)
	(segment
		(start 321.4878 -221.164658)
		(end 321.4878 -198.882254)
		(width 0.15494)
		(layer "In7.Cu")
		(net "LED_POSTCODE_1")
	)
	(segment
		(start 326.263 -194.360546)
		(end 325.850758 -193.948304)
		(width 0.15494)
		(layer "In7.Cu")
		(net "LED_POSTCODE_1")
	)
	(segment
		(start 325.374254 -195.7324)
		(end 326.263 -194.843654)
		(width 0.15494)
		(layer "In7.Cu")
		(net "LED_POSTCODE_1")
	)
	(segment
		(start 326.263 -194.843654)
		(end 326.263 -194.360546)
		(width 0.15494)
		(layer "In7.Cu")
		(net "LED_POSTCODE_1")
	)
	(segment
		(start 325.850758 -193.948304)
		(end 325.002906 -193.948304)
		(width 0.15494)
		(layer "In7.Cu")
		(net "LED_POSTCODE_1")
	)
	(segment
		(start 324.637654 -195.7324)
		(end 325.374254 -195.7324)
		(width 0.15494)
		(layer "In7.Cu")
		(net "LED_POSTCODE_1")
	)
	(segment
		(start 235.477558 -373.481092)
		(end 235.477558 -375.023888)
		(width 0.13208)
		(layer "F.Cu")
		(net "HSC_FLT_TYPE_R")
	)
	(segment
		(start 235.477558 -375.023888)
		(end 235.06049 -375.440956)
		(width 0.13208)
		(layer "F.Cu")
		(net "HSC_FLT_TYPE_R")
	)
	(segment
		(start 225.252026 -373.090186)
		(end 225.867976 -373.090186)
		(width 0.13208)
		(layer "F.Cu")
		(net "HSC_FLT_TYPE_R")
	)
	(segment
		(start 234.893866 -372.8974)
		(end 235.477558 -373.481092)
		(width 0.13208)
		(layer "F.Cu")
		(net "HSC_FLT_TYPE_R")
	)
	(via
		(at 225.867976 -373.090186)
		(size 0.508)
		(drill 0.254)
		(layers "F.Cu" "B.Cu")
		(net "HSC_FLT_TYPE_R")
	)
	(via
		(at 235.06049 -375.440956)
		(size 0.508)
		(drill 0.254)
		(layers "F.Cu" "B.Cu")
		(net "HSC_FLT_TYPE_R")
	)
	(via
		(at 211.95665 -370.854986)
		(size 0.508)
		(drill 0.254)
		(layers "F.Cu" "B.Cu")
		(net "HSC_FLT_TYPE_R")
	)
	(segment
		(start 211.953348 -371.77726)
		(end 211.953348 -370.858288)
		(width 0.13208)
		(layer "B.Cu")
		(net "HSC_FLT_TYPE_R")
	)
	(segment
		(start 211.953348 -370.858288)
		(end 211.95665 -370.854986)
		(width 0.13208)
		(layer "B.Cu")
		(net "HSC_FLT_TYPE_R")
	)
	(segment
		(start 217.210132 -368.806984)
		(end 217.7034 -369.300252)
		(width 0.15494)
		(layer "In11.Cu")
		(net "HSC_FLT_TYPE_R")
	)
	(segment
		(start 213.8299 -370.8146)
		(end 211.997036 -370.8146)
		(width 0.15494)
		(layer "In11.Cu")
		(net "HSC_FLT_TYPE_R")
	)
	(segment
		(start 224.606866 -362.605066)
		(end 223.4438 -361.442)
		(width 0.15494)
		(layer "In11.Cu")
		(net "HSC_FLT_TYPE_R")
	)
	(segment
		(start 217.7034 -370.6114)
		(end 217.17 -371.1448)
		(width 0.15494)
		(layer "In11.Cu")
		(net "HSC_FLT_TYPE_R")
	)
	(segment
		(start 217.210132 -367.293398)
		(end 217.210132 -368.806984)
		(width 0.15494)
		(layer "In11.Cu")
		(net "HSC_FLT_TYPE_R")
	)
	(segment
		(start 224.606866 -371.829076)
		(end 224.606866 -362.605066)
		(width 0.15494)
		(layer "In11.Cu")
		(net "HSC_FLT_TYPE_R")
	)
	(segment
		(start 214.1601 -371.1448)
		(end 213.8299 -370.8146)
		(width 0.15494)
		(layer "In11.Cu")
		(net "HSC_FLT_TYPE_R")
	)
	(segment
		(start 211.997036 -370.8146)
		(end 211.95665 -370.854986)
		(width 0.15494)
		(layer "In11.Cu")
		(net "HSC_FLT_TYPE_R")
	)
	(segment
		(start 217.17 -371.1448)
		(end 214.1601 -371.1448)
		(width 0.15494)
		(layer "In11.Cu")
		(net "HSC_FLT_TYPE_R")
	)
	(segment
		(start 217.7034 -369.300252)
		(end 217.7034 -370.6114)
		(width 0.15494)
		(layer "In11.Cu")
		(net "HSC_FLT_TYPE_R")
	)
	(segment
		(start 217.327734 -361.442)
		(end 216.23147 -362.538264)
		(width 0.15494)
		(layer "In11.Cu")
		(net "HSC_FLT_TYPE_R")
	)
	(segment
		(start 225.867976 -373.090186)
		(end 224.606866 -371.829076)
		(width 0.15494)
		(layer "In11.Cu")
		(net "HSC_FLT_TYPE_R")
	)
	(segment
		(start 216.23147 -362.538264)
		(end 216.23147 -366.314736)
		(width 0.15494)
		(layer "In11.Cu")
		(net "HSC_FLT_TYPE_R")
	)
	(segment
		(start 223.4438 -361.442)
		(end 217.327734 -361.442)
		(width 0.15494)
		(layer "In11.Cu")
		(net "HSC_FLT_TYPE_R")
	)
	(segment
		(start 216.23147 -366.314736)
		(end 217.210132 -367.293398)
		(width 0.15494)
		(layer "In11.Cu")
		(net "HSC_FLT_TYPE_R")
	)
	(segment
		(start 234.5944 -362.86567)
		(end 234.5944 -368.691922)
		(width 0.15494)
		(layer "In13.Cu")
		(net "HSC_FLT_TYPE_R")
	)
	(segment
		(start 226.041712 -373.090186)
		(end 227.996496 -371.135402)
		(width 0.15494)
		(layer "In13.Cu")
		(net "HSC_FLT_TYPE_R")
	)
	(segment
		(start 228.406452 -361.360212)
		(end 233.088942 -361.360212)
		(width 0.15494)
		(layer "In13.Cu")
		(net "HSC_FLT_TYPE_R")
	)
	(segment
		(start 234.414822 -375.440956)
		(end 235.06049 -375.440956)
		(width 0.15494)
		(layer "In13.Cu")
		(net "HSC_FLT_TYPE_R")
	)
	(segment
		(start 234.129326 -369.156996)
		(end 234.129326 -375.15546)
		(width 0.15494)
		(layer "In13.Cu")
		(net "HSC_FLT_TYPE_R")
	)
	(segment
		(start 227.996496 -361.770168)
		(end 228.406452 -361.360212)
		(width 0.15494)
		(layer "In13.Cu")
		(net "HSC_FLT_TYPE_R")
	)
	(segment
		(start 227.996496 -371.135402)
		(end 227.996496 -361.770168)
		(width 0.15494)
		(layer "In13.Cu")
		(net "HSC_FLT_TYPE_R")
	)
	(segment
		(start 225.867976 -373.090186)
		(end 226.041712 -373.090186)
		(width 0.15494)
		(layer "In13.Cu")
		(net "HSC_FLT_TYPE_R")
	)
	(segment
		(start 233.088942 -361.360212)
		(end 234.5944 -362.86567)
		(width 0.15494)
		(layer "In13.Cu")
		(net "HSC_FLT_TYPE_R")
	)
	(segment
		(start 234.5944 -368.691922)
		(end 234.129326 -369.156996)
		(width 0.15494)
		(layer "In13.Cu")
		(net "HSC_FLT_TYPE_R")
	)
	(segment
		(start 234.129326 -375.15546)
		(end 234.414822 -375.440956)
		(width 0.15494)
		(layer "In13.Cu")
		(net "HSC_FLT_TYPE_R")
	)
	(segment
		(start 294.27043 -40.18153)
		(end 309.725822 -40.18153)
		(width 0.13208)
		(layer "F.Cu")
		(net "RST_SMB_SSD_R_N")
	)
	(segment
		(start 399.8214 -40.2336)
		(end 399.8214 -37.67455)
		(width 0.13208)
		(layer "F.Cu")
		(net "RST_SMB_SSD_R_N")
	)
	(segment
		(start 320.446908 -40.005)
		(end 318.403732 -42.048176)
		(width 0.13208)
		(layer "F.Cu")
		(net "RST_SMB_SSD_R_N")
	)
	(segment
		(start 398.526508 -37.54755)
		(end 398.381982 -37.403024)
		(width 0.13208)
		(layer "F.Cu")
		(net "RST_SMB_SSD_R_N")
	)
	(segment
		(start 283.868114 -40.38346)
		(end 285.53283 -42.048176)
		(width 0.13208)
		(layer "F.Cu")
		(net "RST_SMB_SSD_R_N")
	)
	(segment
		(start 283.726128 -40.181276)
		(end 283.868114 -40.323262)
		(width 0.13208)
		(layer "F.Cu")
		(net "RST_SMB_SSD_R_N")
	)
	(segment
		(start 308.281832 -37.403024)
		(end 308.426358 -37.54755)
		(width 0.13208)
		(layer "F.Cu")
		(net "RST_SMB_SSD_R_N")
	)
	(segment
		(start 167.626284 -37.67455)
		(end 167.499284 -37.54755)
		(width 0.13208)
		(layer "F.Cu")
		(net "RST_SMB_SSD_R_N")
	)
	(segment
		(start 192.326514 -37.54755)
		(end 192.181988 -37.403024)
		(width 0.13208)
		(layer "F.Cu")
		(net "RST_SMB_SSD_R_N")
	)
	(segment
		(start 25.720294 -37.67455)
		(end 25.593294 -37.54755)
		(width 0.13208)
		(layer "F.Cu")
		(net "RST_SMB_SSD_R_N")
	)
	(segment
		(start 282.281884 -37.403024)
		(end 282.281884 -37.025072)
		(width 0.13208)
		(layer "F.Cu")
		(net "RST_SMB_SSD_R_N")
	)
	(segment
		(start 60.346844 -42.0624)
		(end 62.228222 -40.181022)
		(width 0.13208)
		(layer "F.Cu")
		(net "RST_SMB_SSD_R_N")
	)
	(segment
		(start 27.355546 -42.0878)
		(end 25.720294 -40.452548)
		(width 0.13208)
		(layer "F.Cu")
		(net "RST_SMB_SSD_R_N")
	)
	(segment
		(start 347.7514 -40.005)
		(end 320.446908 -40.005)
		(width 0.13208)
		(layer "F.Cu")
		(net "RST_SMB_SSD_R_N")
	)
	(segment
		(start 25.593294 -37.54755)
		(end 24.239728 -37.54755)
		(width 0.13208)
		(layer "F.Cu")
		(net "RST_SMB_SSD_R_N")
	)
	(segment
		(start 372.382034 -37.403024)
		(end 372.382034 -37.025072)
		(width 0.13208)
		(layer "F.Cu")
		(net "RST_SMB_SSD_R_N")
	)
	(segment
		(start 193.625978 -40.18153)
		(end 193.626232 -40.181276)
		(width 0.13208)
		(layer "F.Cu")
		(net "RST_SMB_SSD_R_N")
	)
	(segment
		(start 152.170638 -40.18153)
		(end 167.62603 -40.18153)
		(width 0.13208)
		(layer "F.Cu")
		(net "RST_SMB_SSD_R_N")
	)
	(segment
		(start 51.525932 -40.181022)
		(end 36.228274 -40.181022)
		(width 0.13208)
		(layer "F.Cu")
		(net "RST_SMB_SSD_R_N")
	)
	(segment
		(start 115.626388 -37.67455)
		(end 115.499388 -37.54755)
		(width 0.13208)
		(layer "F.Cu")
		(net "RST_SMB_SSD_R_N")
	)
	(segment
		(start 77.66812 -40.38092)
		(end 79.335376 -42.048176)
		(width 0.13208)
		(layer "F.Cu")
		(net "RST_SMB_SSD_R_N")
	)
	(segment
		(start 256.426462 -37.54755)
		(end 256.281936 -37.403024)
		(width 0.13208)
		(layer "F.Cu")
		(net "RST_SMB_SSD_R_N")
	)
	(segment
		(start 356.503986 -42.048176)
		(end 358.370632 -40.18153)
		(width 0.13208)
		(layer "F.Cu")
		(net "RST_SMB_SSD_R_N")
	)
	(segment
		(start 204.170534 -40.18153)
		(end 228.491542 -40.18153)
		(width 0.13208)
		(layer "F.Cu")
		(net "RST_SMB_SSD_R_N")
	)
	(segment
		(start 424.38193 -37.403024)
		(end 424.526456 -37.54755)
		(width 0.13208)
		(layer "F.Cu")
		(net "RST_SMB_SSD_R_N")
	)
	(segment
		(start 282.803346 -40.18153)
		(end 282.8036 -40.181276)
		(width 0.13208)
		(layer "F.Cu")
		(net "RST_SMB_SSD_R_N")
	)
	(segment
		(start 253.7206 -39.9288)
		(end 242.523264 -39.9288)
		(width 0.13208)
		(layer "F.Cu")
		(net "RST_SMB_SSD_R_N")
	)
	(segment
		(start 51.399186 -37.54755)
		(end 50.226468 -37.54755)
		(width 0.13208)
		(layer "F.Cu")
		(net "RST_SMB_SSD_R_N")
	)
	(segment
		(start 347.7514 -40.005)
		(end 347.7514 -37.67455)
		(width 0.13208)
		(layer "F.Cu")
		(net "RST_SMB_SSD_R_N")
	)
	(segment
		(start 50.081942 -37.403024)
		(end 50.081942 -37.025072)
		(width 0.13208)
		(layer "F.Cu")
		(net "RST_SMB_SSD_R_N")
	)
	(segment
		(start 399.8214 -37.67455)
		(end 399.6944 -37.54755)
		(width 0.13208)
		(layer "F.Cu")
		(net "RST_SMB_SSD_R_N")
	)
	(segment
		(start 398.381982 -37.403024)
		(end 398.381982 -37.025072)
		(width 0.13208)
		(layer "F.Cu")
		(net "RST_SMB_SSD_R_N")
	)
	(segment
		(start 347.7514 -37.67455)
		(end 347.6244 -37.54755)
		(width 0.13208)
		(layer "F.Cu")
		(net "RST_SMB_SSD_R_N")
	)
	(segment
		(start 231.726232 -37.67455)
		(end 231.599232 -37.54755)
		(width 0.13208)
		(layer "F.Cu")
		(net "RST_SMB_SSD_R_N")
	)
	(segment
		(start 166.18204 -37.403024)
		(end 166.18204 -37.025072)
		(width 0.13208)
		(layer "F.Cu")
		(net "RST_SMB_SSD_R_N")
	)
	(segment
		(start 257.68808 -37.67455)
		(end 257.56108 -37.54755)
		(width 0.13208)
		(layer "F.Cu")
		(net "RST_SMB_SSD_R_N")
	)
	(segment
		(start 266.403836 -42.048176)
		(end 268.270482 -40.18153)
		(width 0.13208)
		(layer "F.Cu")
		(net "RST_SMB_SSD_R_N")
	)
	(segment
		(start 285.53283 -42.048176)
		(end 292.403784 -42.048176)
		(width 0.13208)
		(layer "F.Cu")
		(net "RST_SMB_SSD_R_N")
	)
	(segment
		(start 292.403784 -42.048176)
		(end 294.27043 -40.18153)
		(width 0.13208)
		(layer "F.Cu")
		(net "RST_SMB_SSD_R_N")
	)
	(segment
		(start 167.76827 -40.323262)
		(end 167.76827 -40.387524)
		(width 0.13208)
		(layer "F.Cu")
		(net "RST_SMB_SSD_R_N")
	)
	(segment
		(start 76.226416 -37.54755)
		(end 76.08189 -37.403024)
		(width 0.13208)
		(layer "F.Cu")
		(net "RST_SMB_SSD_R_N")
	)
	(segment
		(start 399.8214 -40.2336)
		(end 384.31851 -40.2336)
		(width 0.13208)
		(layer "F.Cu")
		(net "RST_SMB_SSD_R_N")
	)
	(segment
		(start 86.20379 -42.048176)
		(end 88.07069 -40.181276)
		(width 0.13208)
		(layer "F.Cu")
		(net "RST_SMB_SSD_R_N")
	)
	(segment
		(start 23.453598 -36.619688)
		(end 23.834344 -36.777422)
		(width 0.13208)
		(layer "F.Cu")
		(net "RST_SMB_SSD_R_N")
	)
	(segment
		(start 347.85935 -40.26535)
		(end 349.642176 -42.048176)
		(width 0.13208)
		(layer "F.Cu")
		(net "RST_SMB_SSD_R_N")
	)
	(segment
		(start 193.768218 -40.323262)
		(end 193.768218 -40.377364)
		(width 0.13208)
		(layer "F.Cu")
		(net "RST_SMB_SSD_R_N")
	)
	(segment
		(start 51.526186 -40.181276)
		(end 51.526186 -40.66794)
		(width 0.13208)
		(layer "F.Cu")
		(net "RST_SMB_SSD_R_N")
	)
	(segment
		(start 260.113272 -41.703244)
		(end 260.458204 -42.048176)
		(width 0.13208)
		(layer "F.Cu")
		(net "RST_SMB_SSD_R_N")
	)
	(segment
		(start 401.635976 -42.048176)
		(end 399.8214 -40.2336)
		(width 0.13208)
		(layer "F.Cu")
		(net "RST_SMB_SSD_R_N")
	)
	(segment
		(start 231.726232 -40.181276)
		(end 231.725978 -40.18153)
		(width 0.13208)
		(layer "F.Cu")
		(net "RST_SMB_SSD_R_N")
	)
	(segment
		(start 309.725822 -40.18153)
		(end 309.726076 -40.181276)
		(width 0.13208)
		(layer "F.Cu")
		(net "RST_SMB_SSD_R_N")
	)
	(segment
		(start 167.499284 -37.54755)
		(end 166.326566 -37.54755)
		(width 0.13208)
		(layer "F.Cu")
		(net "RST_SMB_SSD_R_N")
	)
	(segment
		(start 410.370528 -40.18153)
		(end 408.503882 -42.048176)
		(width 0.13208)
		(layer "F.Cu")
		(net "RST_SMB_SSD_R_N")
	)
	(segment
		(start 373.75973 -37.67455)
		(end 373.63273 -37.54755)
		(width 0.13208)
		(layer "F.Cu")
		(net "RST_SMB_SSD_R_N")
	)
	(segment
		(start 309.726076 -37.67455)
		(end 309.726076 -40.181276)
		(width 0.13208)
		(layer "F.Cu")
		(net "RST_SMB_SSD_R_N")
	)
	(segment
		(start 51.526186 -37.67455)
		(end 51.399186 -37.54755)
		(width 0.13208)
		(layer "F.Cu")
		(net "RST_SMB_SSD_R_N")
	)
	(segment
		(start 77.52588 -40.181022)
		(end 77.526134 -40.181276)
		(width 0.13208)
		(layer "F.Cu")
		(net "RST_SMB_SSD_R_N")
	)
	(segment
		(start 382.503934 -42.048176)
		(end 375.626376 -42.048176)
		(width 0.13208)
		(layer "F.Cu")
		(net "RST_SMB_SSD_R_N")
	)
	(segment
		(start 311.541922 -42.048176)
		(end 309.868062 -40.374316)
		(width 0.13208)
		(layer "F.Cu")
		(net "RST_SMB_SSD_R_N")
	)
	(segment
		(start 193.626232 -37.67455)
		(end 193.499232 -37.54755)
		(width 0.13208)
		(layer "F.Cu")
		(net "RST_SMB_SSD_R_N")
	)
	(segment
		(start 124.304044 -42.048176)
		(end 126.17069 -40.18153)
		(width 0.13208)
		(layer "F.Cu")
		(net "RST_SMB_SSD_R_N")
	)
	(segment
		(start 77.66812 -40.323262)
		(end 77.66812 -40.38092)
		(width 0.13208)
		(layer "F.Cu")
		(net "RST_SMB_SSD_R_N")
	)
	(segment
		(start 309.599076 -37.54755)
		(end 309.726076 -37.67455)
		(width 0.13208)
		(layer "F.Cu")
		(net "RST_SMB_SSD_R_N")
	)
	(segment
		(start 349.642176 -42.048176)
		(end 356.503986 -42.048176)
		(width 0.13208)
		(layer "F.Cu")
		(net "RST_SMB_SSD_R_N")
	)
	(segment
		(start 309.868062 -40.323262)
		(end 309.726076 -40.181276)
		(width 0.13208)
		(layer "F.Cu")
		(net "RST_SMB_SSD_R_N")
	)
	(segment
		(start 25.720294 -40.452548)
		(end 25.720294 -37.67455)
		(width 0.13208)
		(layer "F.Cu")
		(net "RST_SMB_SSD_R_N")
	)
	(segment
		(start 259.197094 -41.703244)
		(end 260.113272 -41.703244)
		(width 0.13208)
		(layer "F.Cu")
		(net "RST_SMB_SSD_R_N")
	)
	(segment
		(start 143.44523 -42.048176)
		(end 150.303992 -42.048176)
		(width 0.13208)
		(layer "F.Cu")
		(net "RST_SMB_SSD_R_N")
	)
	(segment
		(start 126.17069 -40.18153)
		(end 141.626082 -40.18153)
		(width 0.13208)
		(layer "F.Cu")
		(net "RST_SMB_SSD_R_N")
	)
	(segment
		(start 346.382086 -37.403024)
		(end 346.382086 -37.025072)
		(width 0.13208)
		(layer "F.Cu")
		(net "RST_SMB_SSD_R_N")
	)
	(segment
		(start 76.08189 -37.403024)
		(end 76.08189 -37.025072)
		(width 0.13208)
		(layer "F.Cu")
		(net "RST_SMB_SSD_R_N")
	)
	(segment
		(start 283.726128 -37.67455)
		(end 283.599128 -37.54755)
		(width 0.13208)
		(layer "F.Cu")
		(net "RST_SMB_SSD_R_N")
	)
	(segment
		(start 77.526134 -37.67455)
		(end 77.399134 -37.54755)
		(width 0.13208)
		(layer "F.Cu")
		(net "RST_SMB_SSD_R_N")
	)
	(segment
		(start 230.426514 -37.54755)
		(end 230.281988 -37.403024)
		(width 0.13208)
		(layer "F.Cu")
		(net "RST_SMB_SSD_R_N")
	)
	(segment
		(start 24.081994 -37.389816)
		(end 24.081994 -37.025072)
		(width 0.13208)
		(layer "F.Cu")
		(net "RST_SMB_SSD_R_N")
	)
	(segment
		(start 256.281936 -37.403024)
		(end 256.281936 -37.025072)
		(width 0.13208)
		(layer "F.Cu")
		(net "RST_SMB_SSD_R_N")
	)
	(segment
		(start 77.526134 -40.181276)
		(end 77.66812 -40.323262)
		(width 0.13208)
		(layer "F.Cu")
		(net "RST_SMB_SSD_R_N")
	)
	(segment
		(start 283.868114 -40.323262)
		(end 283.868114 -40.38346)
		(width 0.13208)
		(layer "F.Cu")
		(net "RST_SMB_SSD_R_N")
	)
	(segment
		(start 309.868062 -40.374316)
		(end 309.868062 -40.323262)
		(width 0.13208)
		(layer "F.Cu")
		(net "RST_SMB_SSD_R_N")
	)
	(segment
		(start 140.326618 -37.54755)
		(end 141.499336 -37.54755)
		(width 0.13208)
		(layer "F.Cu")
		(net "RST_SMB_SSD_R_N")
	)
	(segment
		(start 399.6944 -37.54755)
		(end 398.526508 -37.54755)
		(width 0.13208)
		(layer "F.Cu")
		(net "RST_SMB_SSD_R_N")
	)
	(segment
		(start 117.435122 -42.048176)
		(end 124.304044 -42.048176)
		(width 0.13208)
		(layer "F.Cu")
		(net "RST_SMB_SSD_R_N")
	)
	(segment
		(start 231.868218 -40.428164)
		(end 231.868218 -40.323262)
		(width 0.13208)
		(layer "F.Cu")
		(net "RST_SMB_SSD_R_N")
	)
	(segment
		(start 141.626336 -40.229282)
		(end 143.44523 -42.048176)
		(width 0.13208)
		(layer "F.Cu")
		(net "RST_SMB_SSD_R_N")
	)
	(segment
		(start 372.52656 -37.54755)
		(end 372.382034 -37.403024)
		(width 0.13208)
		(layer "F.Cu")
		(net "RST_SMB_SSD_R_N")
	)
	(segment
		(start 193.626232 -40.181276)
		(end 193.626232 -37.67455)
		(width 0.13208)
		(layer "F.Cu")
		(net "RST_SMB_SSD_R_N")
	)
	(segment
		(start 193.626232 -40.181276)
		(end 193.768218 -40.323262)
		(width 0.13208)
		(layer "F.Cu")
		(net "RST_SMB_SSD_R_N")
	)
	(segment
		(start 167.76827 -40.387524)
		(end 169.428922 -42.048176)
		(width 0.13208)
		(layer "F.Cu")
		(net "RST_SMB_SSD_R_N")
	)
	(segment
		(start 167.626284 -40.181276)
		(end 167.76827 -40.323262)
		(width 0.13208)
		(layer "F.Cu")
		(net "RST_SMB_SSD_R_N")
	)
	(segment
		(start 115.626388 -40.181276)
		(end 115.768374 -40.323262)
		(width 0.13208)
		(layer "F.Cu")
		(net "RST_SMB_SSD_R_N")
	)
	(segment
		(start 77.526134 -40.181276)
		(end 77.526134 -37.67455)
		(width 0.13208)
		(layer "F.Cu")
		(net "RST_SMB_SSD_R_N")
	)
	(segment
		(start 424.38193 -37.025072)
		(end 424.38193 -37.403024)
		(width 0.13208)
		(layer "F.Cu")
		(net "RST_SMB_SSD_R_N")
	)
	(segment
		(start 114.182144 -37.403024)
		(end 114.182144 -37.025072)
		(width 0.13208)
		(layer "F.Cu")
		(net "RST_SMB_SSD_R_N")
	)
	(segment
		(start 141.626336 -37.67455)
		(end 141.626336 -40.181276)
		(width 0.13208)
		(layer "F.Cu")
		(net "RST_SMB_SSD_R_N")
	)
	(segment
		(start 257.68808 -40.19423)
		(end 259.197094 -41.703244)
		(width 0.13208)
		(layer "F.Cu")
		(net "RST_SMB_SSD_R_N")
	)
	(segment
		(start 231.726232 -40.181276)
		(end 231.726232 -37.67455)
		(width 0.13208)
		(layer "F.Cu")
		(net "RST_SMB_SSD_R_N")
	)
	(segment
		(start 223.498664 -205.47711)
		(end 223.498664 -206.62011)
		(width 0.13208)
		(layer "F.Cu")
		(net "RST_SMB_SSD_R_N")
	)
	(segment
		(start 193.499232 -37.54755)
		(end 192.326514 -37.54755)
		(width 0.13208)
		(layer "F.Cu")
		(net "RST_SMB_SSD_R_N")
	)
	(segment
		(start 178.170586 -40.18153)
		(end 193.625978 -40.18153)
		(width 0.13208)
		(layer "F.Cu")
		(net "RST_SMB_SSD_R_N")
	)
	(segment
		(start 202.303888 -42.048176)
		(end 204.170534 -40.18153)
		(width 0.13208)
		(layer "F.Cu")
		(net "RST_SMB_SSD_R_N")
	)
	(segment
		(start 283.726128 -40.181276)
		(end 283.726128 -37.67455)
		(width 0.13208)
		(layer "F.Cu")
		(net "RST_SMB_SSD_R_N")
	)
	(segment
		(start 375.626376 -42.048176)
		(end 373.75973 -40.18153)
		(width 0.13208)
		(layer "F.Cu")
		(net "RST_SMB_SSD_R_N")
	)
	(segment
		(start 36.228274 -40.181022)
		(end 34.321496 -42.0878)
		(width 0.13208)
		(layer "F.Cu")
		(net "RST_SMB_SSD_R_N")
	)
	(segment
		(start 408.503882 -42.048176)
		(end 401.635976 -42.048176)
		(width 0.13208)
		(layer "F.Cu")
		(net "RST_SMB_SSD_R_N")
	)
	(segment
		(start 425.699174 -37.54755)
		(end 425.826174 -37.67455)
		(width 0.13208)
		(layer "F.Cu")
		(net "RST_SMB_SSD_R_N")
	)
	(segment
		(start 347.6244 -37.54755)
		(end 346.526612 -37.54755)
		(width 0.13208)
		(layer "F.Cu")
		(net "RST_SMB_SSD_R_N")
	)
	(segment
		(start 50.226468 -37.54755)
		(end 50.081942 -37.403024)
		(width 0.13208)
		(layer "F.Cu")
		(net "RST_SMB_SSD_R_N")
	)
	(segment
		(start 2.11709 -72.165972)
		(end 2.11709 -71.288402)
		(width 0.13208)
		(layer "F.Cu")
		(net "RST_SMB_SSD_R_N")
	)
	(segment
		(start 52.920646 -42.0624)
		(end 60.346844 -42.0624)
		(width 0.13208)
		(layer "F.Cu")
		(net "RST_SMB_SSD_R_N")
	)
	(segment
		(start 115.499388 -37.54755)
		(end 114.32667 -37.54755)
		(width 0.13208)
		(layer "F.Cu")
		(net "RST_SMB_SSD_R_N")
	)
	(segment
		(start 242.523264 -39.9288)
		(end 240.403888 -42.048176)
		(width 0.13208)
		(layer "F.Cu")
		(net "RST_SMB_SSD_R_N")
	)
	(segment
		(start 257.56108 -37.54755)
		(end 256.426462 -37.54755)
		(width 0.13208)
		(layer "F.Cu")
		(net "RST_SMB_SSD_R_N")
	)
	(segment
		(start 425.49318 -40.18153)
		(end 410.370528 -40.18153)
		(width 0.13208)
		(layer "F.Cu")
		(net "RST_SMB_SSD_R_N")
	)
	(segment
		(start 140.182092 -37.025072)
		(end 140.182092 -37.403024)
		(width 0.13208)
		(layer "F.Cu")
		(net "RST_SMB_SSD_R_N")
	)
	(segment
		(start 231.868218 -40.323262)
		(end 231.726232 -40.181276)
		(width 0.13208)
		(layer "F.Cu")
		(net "RST_SMB_SSD_R_N")
	)
	(segment
		(start 169.428922 -42.048176)
		(end 176.30394 -42.048176)
		(width 0.13208)
		(layer "F.Cu")
		(net "RST_SMB_SSD_R_N")
	)
	(segment
		(start 260.458204 -42.048176)
		(end 266.403836 -42.048176)
		(width 0.13208)
		(layer "F.Cu")
		(net "RST_SMB_SSD_R_N")
	)
	(segment
		(start 176.30394 -42.048176)
		(end 178.170586 -40.18153)
		(width 0.13208)
		(layer "F.Cu")
		(net "RST_SMB_SSD_R_N")
	)
	(segment
		(start 34.321496 -42.0878)
		(end 27.355546 -42.0878)
		(width 0.13208)
		(layer "F.Cu")
		(net "RST_SMB_SSD_R_N")
	)
	(segment
		(start 318.403732 -42.048176)
		(end 311.541922 -42.048176)
		(width 0.13208)
		(layer "F.Cu")
		(net "RST_SMB_SSD_R_N")
	)
	(segment
		(start 62.228222 -40.181022)
		(end 77.52588 -40.181022)
		(width 0.13208)
		(layer "F.Cu")
		(net "RST_SMB_SSD_R_N")
	)
	(segment
		(start 79.335376 -42.048176)
		(end 86.20379 -42.048176)
		(width 0.13208)
		(layer "F.Cu")
		(net "RST_SMB_SSD_R_N")
	)
	(segment
		(start 257.68808 -40.19423)
		(end 253.98603 -40.19423)
		(width 0.13208)
		(layer "F.Cu")
		(net "RST_SMB_SSD_R_N")
	)
	(segment
		(start 24.239728 -37.54755)
		(end 24.081994 -37.389816)
		(width 0.13208)
		(layer "F.Cu")
		(net "RST_SMB_SSD_R_N")
	)
	(segment
		(start 115.626388 -40.181276)
		(end 115.626388 -37.67455)
		(width 0.13208)
		(layer "F.Cu")
		(net "RST_SMB_SSD_R_N")
	)
	(segment
		(start 358.370632 -40.18153)
		(end 373.75973 -40.18153)
		(width 0.13208)
		(layer "F.Cu")
		(net "RST_SMB_SSD_R_N")
	)
	(segment
		(start 141.626336 -40.181276)
		(end 141.626336 -40.229282)
		(width 0.13208)
		(layer "F.Cu")
		(net "RST_SMB_SSD_R_N")
	)
	(segment
		(start 140.182092 -37.403024)
		(end 140.326618 -37.54755)
		(width 0.13208)
		(layer "F.Cu")
		(net "RST_SMB_SSD_R_N")
	)
	(segment
		(start 150.303992 -42.048176)
		(end 152.170638 -40.18153)
		(width 0.13208)
		(layer "F.Cu")
		(net "RST_SMB_SSD_R_N")
	)
	(segment
		(start 51.526186 -40.66794)
		(end 52.920646 -42.0624)
		(width 0.13208)
		(layer "F.Cu")
		(net "RST_SMB_SSD_R_N")
	)
	(segment
		(start 283.599128 -37.54755)
		(end 282.42641 -37.54755)
		(width 0.13208)
		(layer "F.Cu")
		(net "RST_SMB_SSD_R_N")
	)
	(segment
		(start 373.75973 -40.18153)
		(end 373.75973 -37.67455)
		(width 0.13208)
		(layer "F.Cu")
		(net "RST_SMB_SSD_R_N")
	)
	(segment
		(start 425.826174 -39.848536)
		(end 425.49318 -40.18153)
		(width 0.13208)
		(layer "F.Cu")
		(net "RST_SMB_SSD_R_N")
	)
	(segment
		(start 167.62603 -40.18153)
		(end 167.626284 -40.181276)
		(width 0.13208)
		(layer "F.Cu")
		(net "RST_SMB_SSD_R_N")
	)
	(segment
		(start 268.270482 -40.18153)
		(end 282.803346 -40.18153)
		(width 0.13208)
		(layer "F.Cu")
		(net "RST_SMB_SSD_R_N")
	)
	(segment
		(start 347.7514 -40.005)
		(end 347.85935 -40.26535)
		(width 0.13208)
		(layer "F.Cu")
		(net "RST_SMB_SSD_R_N")
	)
	(segment
		(start 233.48823 -42.048176)
		(end 231.868218 -40.428164)
		(width 0.13208)
		(layer "F.Cu")
		(net "RST_SMB_SSD_R_N")
	)
	(segment
		(start 88.07069 -40.181276)
		(end 115.626388 -40.181276)
		(width 0.13208)
		(layer "F.Cu")
		(net "RST_SMB_SSD_R_N")
	)
	(segment
		(start 308.426358 -37.54755)
		(end 309.599076 -37.54755)
		(width 0.13208)
		(layer "F.Cu")
		(net "RST_SMB_SSD_R_N")
	)
	(segment
		(start 253.98603 -40.19423)
		(end 253.7206 -39.9288)
		(width 0.13208)
		(layer "F.Cu")
		(net "RST_SMB_SSD_R_N")
	)
	(segment
		(start 282.42641 -37.54755)
		(end 282.281884 -37.403024)
		(width 0.13208)
		(layer "F.Cu")
		(net "RST_SMB_SSD_R_N")
	)
	(segment
		(start 373.63273 -37.54755)
		(end 372.52656 -37.54755)
		(width 0.13208)
		(layer "F.Cu")
		(net "RST_SMB_SSD_R_N")
	)
	(segment
		(start 51.526186 -40.181276)
		(end 51.526186 -37.67455)
		(width 0.13208)
		(layer "F.Cu")
		(net "RST_SMB_SSD_R_N")
	)
	(segment
		(start 23.834344 -36.777422)
		(end 24.081994 -37.025072)
		(width 0.13208)
		(layer "F.Cu")
		(net "RST_SMB_SSD_R_N")
	)
	(segment
		(start 195.43903 -42.048176)
		(end 202.303888 -42.048176)
		(width 0.13208)
		(layer "F.Cu")
		(net "RST_SMB_SSD_R_N")
	)
	(segment
		(start 115.768374 -40.323262)
		(end 115.768374 -40.381428)
		(width 0.13208)
		(layer "F.Cu")
		(net "RST_SMB_SSD_R_N")
	)
	(segment
		(start 308.281832 -37.025072)
		(end 308.281832 -37.403024)
		(width 0.13208)
		(layer "F.Cu")
		(net "RST_SMB_SSD_R_N")
	)
	(segment
		(start 282.8036 -40.181276)
		(end 283.726128 -40.181276)
		(width 0.13208)
		(layer "F.Cu")
		(net "RST_SMB_SSD_R_N")
	)
	(segment
		(start 114.32667 -37.54755)
		(end 114.182144 -37.403024)
		(width 0.13208)
		(layer "F.Cu")
		(net "RST_SMB_SSD_R_N")
	)
	(segment
		(start 257.68808 -40.19423)
		(end 257.68808 -37.67455)
		(width 0.13208)
		(layer "F.Cu")
		(net "RST_SMB_SSD_R_N")
	)
	(segment
		(start 115.768374 -40.381428)
		(end 117.435122 -42.048176)
		(width 0.13208)
		(layer "F.Cu")
		(net "RST_SMB_SSD_R_N")
	)
	(segment
		(start 346.526612 -37.54755)
		(end 346.382086 -37.403024)
		(width 0.13208)
		(layer "F.Cu")
		(net "RST_SMB_SSD_R_N")
	)
	(segment
		(start 166.326566 -37.54755)
		(end 166.18204 -37.403024)
		(width 0.13208)
		(layer "F.Cu")
		(net "RST_SMB_SSD_R_N")
	)
	(segment
		(start 231.725978 -40.18153)
		(end 228.491542 -40.18153)
		(width 0.13208)
		(layer "F.Cu")
		(net "RST_SMB_SSD_R_N")
	)
	(segment
		(start 425.826174 -37.67455)
		(end 425.826174 -39.848536)
		(width 0.13208)
		(layer "F.Cu")
		(net "RST_SMB_SSD_R_N")
	)
	(segment
		(start 384.31851 -40.2336)
		(end 382.503934 -42.048176)
		(width 0.13208)
		(layer "F.Cu")
		(net "RST_SMB_SSD_R_N")
	)
	(segment
		(start 231.599232 -37.54755)
		(end 230.426514 -37.54755)
		(width 0.13208)
		(layer "F.Cu")
		(net "RST_SMB_SSD_R_N")
	)
	(segment
		(start 230.281988 -37.403024)
		(end 230.281988 -37.025072)
		(width 0.13208)
		(layer "F.Cu")
		(net "RST_SMB_SSD_R_N")
	)
	(segment
		(start 193.768218 -40.377364)
		(end 195.43903 -42.048176)
		(width 0.13208)
		(layer "F.Cu")
		(net "RST_SMB_SSD_R_N")
	)
	(segment
		(start 141.499336 -37.54755)
		(end 141.626336 -37.67455)
		(width 0.13208)
		(layer "F.Cu")
		(net "RST_SMB_SSD_R_N")
	)
	(segment
		(start 141.626082 -40.18153)
		(end 141.626336 -40.181276)
		(width 0.13208)
		(layer "F.Cu")
		(net "RST_SMB_SSD_R_N")
	)
	(segment
		(start 167.626284 -40.181276)
		(end 167.626284 -37.67455)
		(width 0.13208)
		(layer "F.Cu")
		(net "RST_SMB_SSD_R_N")
	)
	(segment
		(start 424.526456 -37.54755)
		(end 425.699174 -37.54755)
		(width 0.13208)
		(layer "F.Cu")
		(net "RST_SMB_SSD_R_N")
	)
	(segment
		(start 240.403888 -42.048176)
		(end 233.48823 -42.048176)
		(width 0.13208)
		(layer "F.Cu")
		(net "RST_SMB_SSD_R_N")
	)
	(segment
		(start 192.181988 -37.403024)
		(end 192.181988 -37.025072)
		(width 0.13208)
		(layer "F.Cu")
		(net "RST_SMB_SSD_R_N")
	)
	(segment
		(start 77.399134 -37.54755)
		(end 76.226416 -37.54755)
		(width 0.13208)
		(layer "F.Cu")
		(net "RST_SMB_SSD_R_N")
	)
	(segment
		(start 51.526186 -40.181276)
		(end 51.525932 -40.181022)
		(width 0.13208)
		(layer "F.Cu")
		(net "RST_SMB_SSD_R_N")
	)
	(via
		(at 228.491542 -40.18153)
		(size 0.508)
		(drill 0.254)
		(layers "F.Cu" "B.Cu")
		(net "RST_SMB_SSD_R_N")
	)
	(via
		(at 23.453598 -36.619688)
		(size 0.508)
		(drill 0.254)
		(layers "F.Cu" "B.Cu")
		(net "RST_SMB_SSD_R_N")
	)
	(via
		(at 2.11709 -71.288402)
		(size 0.508)
		(drill 0.254)
		(layers "F.Cu" "B.Cu")
		(net "RST_SMB_SSD_R_N")
	)
	(via
		(at 223.498664 -205.47711)
		(size 0.508)
		(drill 0.254)
		(layers "F.Cu" "B.Cu")
		(net "RST_SMB_SSD_R_N")
	)
	(segment
		(start 6.848856 -61.4934)
		(end 9.195054 -61.4934)
		(width 0.15494)
		(layer "In5.Cu")
		(net "RST_SMB_SSD_R_N")
	)
	(segment
		(start 9.195054 -61.4934)
		(end 9.678924 -61.00953)
		(width 0.15494)
		(layer "In5.Cu")
		(net "RST_SMB_SSD_R_N")
	)
	(segment
		(start 11.010138 -42.7736)
		(end 11.963146 -42.7736)
		(width 0.15494)
		(layer "In5.Cu")
		(net "RST_SMB_SSD_R_N")
	)
	(segment
		(start 11.963146 -42.7736)
		(end 18.135346 -36.6014)
		(width 0.15494)
		(layer "In5.Cu")
		(net "RST_SMB_SSD_R_N")
	)
	(segment
		(start 2.11709 -70.730364)
		(end 2.77114 -70.076314)
		(width 0.15494)
		(layer "In5.Cu")
		(net "RST_SMB_SSD_R_N")
	)
	(segment
		(start 2.77114 -70.076314)
		(end 2.77114 -65.571116)
		(width 0.15494)
		(layer "In5.Cu")
		(net "RST_SMB_SSD_R_N")
	)
	(segment
		(start 9.678924 -61.00953)
		(end 9.678924 -44.104814)
		(width 0.15494)
		(layer "In5.Cu")
		(net "RST_SMB_SSD_R_N")
	)
	(segment
		(start 19.176746 -36.6014)
		(end 19.569176 -36.99383)
		(width 0.15494)
		(layer "In5.Cu")
		(net "RST_SMB_SSD_R_N")
	)
	(segment
		(start 21.65223 -36.619688)
		(end 23.453598 -36.619688)
		(width 0.15494)
		(layer "In5.Cu")
		(net "RST_SMB_SSD_R_N")
	)
	(segment
		(start 18.135346 -36.6014)
		(end 19.176746 -36.6014)
		(width 0.15494)
		(layer "In5.Cu")
		(net "RST_SMB_SSD_R_N")
	)
	(segment
		(start 9.678924 -44.104814)
		(end 11.010138 -42.7736)
		(width 0.15494)
		(layer "In5.Cu")
		(net "RST_SMB_SSD_R_N")
	)
	(segment
		(start 2.11709 -71.288402)
		(end 2.11709 -70.730364)
		(width 0.15494)
		(layer "In5.Cu")
		(net "RST_SMB_SSD_R_N")
	)
	(segment
		(start 2.77114 -65.571116)
		(end 6.848856 -61.4934)
		(width 0.15494)
		(layer "In5.Cu")
		(net "RST_SMB_SSD_R_N")
	)
	(segment
		(start 21.278088 -36.99383)
		(end 21.65223 -36.619688)
		(width 0.15494)
		(layer "In5.Cu")
		(net "RST_SMB_SSD_R_N")
	)
	(segment
		(start 19.569176 -36.99383)
		(end 21.278088 -36.99383)
		(width 0.15494)
		(layer "In5.Cu")
		(net "RST_SMB_SSD_R_N")
	)
	(segment
		(start 222.6564 -180.7464)
		(end 222.96755 -180.43525)
		(width 0.15494)
		(layer "In7.Cu")
		(net "RST_SMB_SSD_R_N")
	)
	(segment
		(start 226.2124 -191.5414)
		(end 226.2124 -187.452)
		(width 0.15494)
		(layer "In7.Cu")
		(net "RST_SMB_SSD_R_N")
	)
	(segment
		(start 224.2566 -200.7616)
		(end 224.7138 -200.3044)
		(width 0.15494)
		(layer "In7.Cu")
		(net "RST_SMB_SSD_R_N")
	)
	(segment
		(start 225.35261 -59.969654)
		(end 225.35261 -53.473858)
		(width 0.15494)
		(layer "In7.Cu")
		(net "RST_SMB_SSD_R_N")
	)
	(segment
		(start 223.8756 -186.5122)
		(end 222.6564 -185.293)
		(width 0.15494)
		(layer "In7.Cu")
		(net "RST_SMB_SSD_R_N")
	)
	(segment
		(start 224.7138 -197.586346)
		(end 225.8568 -196.443346)
		(width 0.15494)
		(layer "In7.Cu")
		(net "RST_SMB_SSD_R_N")
	)
	(segment
		(start 228.8286 -85.532214)
		(end 228.8286 -82.41411)
		(width 0.15494)
		(layer "In7.Cu")
		(net "RST_SMB_SSD_R_N")
	)
	(segment
		(start 226.960176 -61.57722)
		(end 225.35261 -59.969654)
		(width 0.15494)
		(layer "In7.Cu")
		(net "RST_SMB_SSD_R_N")
	)
	(segment
		(start 216.918286 -102.611682)
		(end 217.4748 -101.268022)
		(width 0.15494)
		(layer "In7.Cu")
		(net "RST_SMB_SSD_R_N")
	)
	(segment
		(start 226.960176 -62.94374)
		(end 226.960176 -61.57722)
		(width 0.15494)
		(layer "In7.Cu")
		(net "RST_SMB_SSD_R_N")
	)
	(segment
		(start 225.702114 -70.494144)
		(end 225.702114 -64.201802)
		(width 0.15494)
		(layer "In7.Cu")
		(net "RST_SMB_SSD_R_N")
	)
	(segment
		(start 226.2124 -187.452)
		(end 225.2726 -186.5122)
		(width 0.15494)
		(layer "In7.Cu")
		(net "RST_SMB_SSD_R_N")
	)
	(segment
		(start 217.4748 -101.268022)
		(end 217.4748 -94.7166)
		(width 0.15494)
		(layer "In7.Cu")
		(net "RST_SMB_SSD_R_N")
	)
	(segment
		(start 226.269296 -79.84998)
		(end 226.248214 -79.828898)
		(width 0.15494)
		(layer "In7.Cu")
		(net "RST_SMB_SSD_R_N")
	)
	(segment
		(start 223.498664 -203.55052)
		(end 223.842072 -203.207112)
		(width 0.15494)
		(layer "In7.Cu")
		(net "RST_SMB_SSD_R_N")
	)
	(segment
		(start 224.7138 -200.3044)
		(end 224.7138 -197.586346)
		(width 0.15494)
		(layer "In7.Cu")
		(net "RST_SMB_SSD_R_N")
	)
	(segment
		(start 215.377268 -116.774722)
		(end 214.8586 -116.256054)
		(width 0.15494)
		(layer "In7.Cu")
		(net "RST_SMB_SSD_R_N")
	)
	(segment
		(start 225.2726 -186.5122)
		(end 223.8756 -186.5122)
		(width 0.15494)
		(layer "In7.Cu")
		(net "RST_SMB_SSD_R_N")
	)
	(segment
		(start 222.96755 -180.43525)
		(end 222.96755 -178.982878)
		(width 0.15494)
		(layer "In7.Cu")
		(net "RST_SMB_SSD_R_N")
	)
	(segment
		(start 220.81998 -93.540834)
		(end 228.8286 -85.532214)
		(width 0.15494)
		(layer "In7.Cu")
		(net "RST_SMB_SSD_R_N")
	)
	(segment
		(start 226.248214 -71.040244)
		(end 225.702114 -70.494144)
		(width 0.15494)
		(layer "In7.Cu")
		(net "RST_SMB_SSD_R_N")
	)
	(segment
		(start 223.842072 -202.496928)
		(end 224.2566 -202.0824)
		(width 0.15494)
		(layer "In7.Cu")
		(net "RST_SMB_SSD_R_N")
	)
	(segment
		(start 223.842072 -203.207112)
		(end 223.842072 -202.496928)
		(width 0.15494)
		(layer "In7.Cu")
		(net "RST_SMB_SSD_R_N")
	)
	(segment
		(start 228.491542 -50.334926)
		(end 228.491542 -40.18153)
		(width 0.15494)
		(layer "In7.Cu")
		(net "RST_SMB_SSD_R_N")
	)
	(segment
		(start 222.6564 -185.293)
		(end 222.6564 -180.7464)
		(width 0.15494)
		(layer "In7.Cu")
		(net "RST_SMB_SSD_R_N")
	)
	(segment
		(start 221.6404 -157.374082)
		(end 216.789 -152.522682)
		(width 0.15494)
		(layer "In7.Cu")
		(net "RST_SMB_SSD_R_N")
	)
	(segment
		(start 222.96755 -178.982878)
		(end 223.8502 -178.100228)
		(width 0.15494)
		(layer "In7.Cu")
		(net "RST_SMB_SSD_R_N")
	)
	(segment
		(start 214.8586 -116.256054)
		(end 214.8586 -104.671368)
		(width 0.15494)
		(layer "In7.Cu")
		(net "RST_SMB_SSD_R_N")
	)
	(segment
		(start 216.789 -131.7498)
		(end 215.377268 -130.338068)
		(width 0.15494)
		(layer "In7.Cu")
		(net "RST_SMB_SSD_R_N")
	)
	(segment
		(start 226.269296 -79.854806)
		(end 226.269296 -79.84998)
		(width 0.15494)
		(layer "In7.Cu")
		(net "RST_SMB_SSD_R_N")
	)
	(segment
		(start 224.2566 -202.0824)
		(end 224.2566 -200.7616)
		(width 0.15494)
		(layer "In7.Cu")
		(net "RST_SMB_SSD_R_N")
	)
	(segment
		(start 228.8286 -82.41411)
		(end 226.269296 -79.854806)
		(width 0.15494)
		(layer "In7.Cu")
		(net "RST_SMB_SSD_R_N")
	)
	(segment
		(start 221.6404 -165.229032)
		(end 221.6404 -157.374082)
		(width 0.15494)
		(layer "In7.Cu")
		(net "RST_SMB_SSD_R_N")
	)
	(segment
		(start 225.8568 -196.443346)
		(end 225.8568 -191.897)
		(width 0.15494)
		(layer "In7.Cu")
		(net "RST_SMB_SSD_R_N")
	)
	(segment
		(start 215.377268 -130.338068)
		(end 215.377268 -116.774722)
		(width 0.15494)
		(layer "In7.Cu")
		(net "RST_SMB_SSD_R_N")
	)
	(segment
		(start 225.35261 -53.473858)
		(end 228.491542 -50.334926)
		(width 0.15494)
		(layer "In7.Cu")
		(net "RST_SMB_SSD_R_N")
	)
	(segment
		(start 218.650566 -93.540834)
		(end 220.81998 -93.540834)
		(width 0.15494)
		(layer "In7.Cu")
		(net "RST_SMB_SSD_R_N")
	)
	(segment
		(start 223.8502 -178.100228)
		(end 223.8502 -167.438832)
		(width 0.15494)
		(layer "In7.Cu")
		(net "RST_SMB_SSD_R_N")
	)
	(segment
		(start 226.248214 -79.828898)
		(end 226.248214 -71.040244)
		(width 0.15494)
		(layer "In7.Cu")
		(net "RST_SMB_SSD_R_N")
	)
	(segment
		(start 225.702114 -64.201802)
		(end 226.960176 -62.94374)
		(width 0.15494)
		(layer "In7.Cu")
		(net "RST_SMB_SSD_R_N")
	)
	(segment
		(start 223.498664 -205.47711)
		(end 223.498664 -203.55052)
		(width 0.15494)
		(layer "In7.Cu")
		(net "RST_SMB_SSD_R_N")
	)
	(segment
		(start 214.8586 -104.671368)
		(end 216.918286 -102.611682)
		(width 0.15494)
		(layer "In7.Cu")
		(net "RST_SMB_SSD_R_N")
	)
	(segment
		(start 216.789 -152.522682)
		(end 216.789 -131.7498)
		(width 0.15494)
		(layer "In7.Cu")
		(net "RST_SMB_SSD_R_N")
	)
	(segment
		(start 225.8568 -191.897)
		(end 226.2124 -191.5414)
		(width 0.15494)
		(layer "In7.Cu")
		(net "RST_SMB_SSD_R_N")
	)
	(segment
		(start 223.8502 -167.438832)
		(end 221.6404 -165.229032)
		(width 0.15494)
		(layer "In7.Cu")
		(net "RST_SMB_SSD_R_N")
	)
	(segment
		(start 217.4748 -94.7166)
		(end 218.650566 -93.540834)
		(width 0.15494)
		(layer "In7.Cu")
		(net "RST_SMB_SSD_R_N")
	)
	(segment
		(start 439.679334 -301.041054)
		(end 440.195208 -301.556928)
		(width 0.13208)
		(layer "F.Cu")
		(net "I2C0_PEX3_SCL")
	)
	(segment
		(start 440.195208 -301.556928)
		(end 440.195208 -301.57674)
		(width 0.13208)
		(layer "F.Cu")
		(net "I2C0_PEX3_SCL")
	)
	(segment
		(start 417.924996 -307.774848)
		(end 417.450016 -308.249828)
		(width 0.13208)
		(layer "F.Cu")
		(net "I2C0_PEX3_SCL")
	)
	(via
		(at 440.195208 -301.57674)
		(size 0.508)
		(drill 0.254)
		(layers "F.Cu" "B.Cu")
		(net "I2C0_PEX3_SCL")
	)
	(via
		(at 417.924996 -307.774848)
		(size 0.4064)
		(drill 0.2032)
		(layers "F.Cu" "B.Cu")
		(net "I2C0_PEX3_SCL")
	)
	(segment
		(start 420.04869 -308.249828)
		(end 418.798248 -308.249828)
		(width 0.15494)
		(layer "In5.Cu")
		(net "I2C0_PEX3_SCL")
	)
	(segment
		(start 420.284402 -308.014116)
		(end 420.04869 -308.249828)
		(width 0.15494)
		(layer "In5.Cu")
		(net "I2C0_PEX3_SCL")
	)
	(segment
		(start 431.986944 -300.2788)
		(end 431.614834 -300.65091)
		(width 0.15494)
		(layer "In5.Cu")
		(net "I2C0_PEX3_SCL")
	)
	(segment
		(start 436.365904 -300.2788)
		(end 431.986944 -300.2788)
		(width 0.15494)
		(layer "In5.Cu")
		(net "I2C0_PEX3_SCL")
	)
	(segment
		(start 420.51732 -307.34)
		(end 420.284402 -307.572918)
		(width 0.15494)
		(layer "In5.Cu")
		(net "I2C0_PEX3_SCL")
	)
	(segment
		(start 440.195208 -301.57674)
		(end 440.195208 -301.215044)
		(width 0.15494)
		(layer "In5.Cu")
		(net "I2C0_PEX3_SCL")
	)
	(segment
		(start 425.099734 -300.955202)
		(end 425.099734 -303.372266)
		(width 0.15494)
		(layer "In5.Cu")
		(net "I2C0_PEX3_SCL")
	)
	(segment
		(start 440.195208 -301.215044)
		(end 439.487564 -300.5074)
		(width 0.15494)
		(layer "In5.Cu")
		(net "I2C0_PEX3_SCL")
	)
	(segment
		(start 436.594504 -300.5074)
		(end 436.365904 -300.2788)
		(width 0.15494)
		(layer "In5.Cu")
		(net "I2C0_PEX3_SCL")
	)
	(segment
		(start 425.099734 -303.372266)
		(end 424.6372 -303.8348)
		(width 0.15494)
		(layer "In5.Cu")
		(net "I2C0_PEX3_SCL")
	)
	(segment
		(start 418.323268 -307.774848)
		(end 417.924996 -307.774848)
		(width 0.15494)
		(layer "In5.Cu")
		(net "I2C0_PEX3_SCL")
	)
	(segment
		(start 424.6372 -303.8348)
		(end 424.6372 -306.457604)
		(width 0.15494)
		(layer "In5.Cu")
		(net "I2C0_PEX3_SCL")
	)
	(segment
		(start 418.798248 -308.249828)
		(end 418.323268 -307.774848)
		(width 0.15494)
		(layer "In5.Cu")
		(net "I2C0_PEX3_SCL")
	)
	(segment
		(start 431.614834 -300.65091)
		(end 425.404026 -300.65091)
		(width 0.15494)
		(layer "In5.Cu")
		(net "I2C0_PEX3_SCL")
	)
	(segment
		(start 422.5798 -306.8066)
		(end 422.0464 -307.34)
		(width 0.15494)
		(layer "In5.Cu")
		(net "I2C0_PEX3_SCL")
	)
	(segment
		(start 424.6372 -306.457604)
		(end 424.288204 -306.8066)
		(width 0.15494)
		(layer "In5.Cu")
		(net "I2C0_PEX3_SCL")
	)
	(segment
		(start 420.284402 -307.572918)
		(end 420.284402 -308.014116)
		(width 0.15494)
		(layer "In5.Cu")
		(net "I2C0_PEX3_SCL")
	)
	(segment
		(start 424.288204 -306.8066)
		(end 422.5798 -306.8066)
		(width 0.15494)
		(layer "In5.Cu")
		(net "I2C0_PEX3_SCL")
	)
	(segment
		(start 425.404026 -300.65091)
		(end 425.099734 -300.955202)
		(width 0.15494)
		(layer "In5.Cu")
		(net "I2C0_PEX3_SCL")
	)
	(segment
		(start 439.487564 -300.5074)
		(end 436.594504 -300.5074)
		(width 0.15494)
		(layer "In5.Cu")
		(net "I2C0_PEX3_SCL")
	)
	(segment
		(start 422.0464 -307.34)
		(end 420.51732 -307.34)
		(width 0.15494)
		(layer "In5.Cu")
		(net "I2C0_PEX3_SCL")
	)
	(segment
		(start 438.999122 -301.04207)
		(end 438.328308 -301.04207)
		(width 0.13208)
		(layer "F.Cu")
		(net "I2C0_PEX3_SDA")
	)
	(segment
		(start 420.774876 -307.774848)
		(end 421.249856 -308.249828)
		(width 0.13208)
		(layer "F.Cu")
		(net "I2C0_PEX3_SDA")
	)
	(via
		(at 438.999122 -301.04207)
		(size 0.508)
		(drill 0.254)
		(layers "F.Cu" "B.Cu")
		(net "I2C0_PEX3_SDA")
	)
	(via
		(at 420.774876 -307.774848)
		(size 0.4064)
		(drill 0.2032)
		(layers "F.Cu" "B.Cu")
		(net "I2C0_PEX3_SDA")
	)
	(segment
		(start 436.27548 -301.04207)
		(end 438.999122 -301.04207)
		(width 0.15494)
		(layer "In5.Cu")
		(net "I2C0_PEX3_SDA")
	)
	(segment
		(start 426.026326 -301.740062)
		(end 426.153326 -301.613062)
		(width 0.15494)
		(layer "In5.Cu")
		(net "I2C0_PEX3_SDA")
	)
	(segment
		(start 431.503074 -301.613062)
		(end 432.303936 -300.8122)
		(width 0.15494)
		(layer "In5.Cu")
		(net "I2C0_PEX3_SDA")
	)
	(segment
		(start 426.153326 -301.613062)
		(end 431.503074 -301.613062)
		(width 0.15494)
		(layer "In5.Cu")
		(net "I2C0_PEX3_SDA")
	)
	(segment
		(start 421.249856 -308.249828)
		(end 422.529 -308.249828)
		(width 0.15494)
		(layer "In5.Cu")
		(net "I2C0_PEX3_SDA")
	)
	(segment
		(start 426.4406 -307.542946)
		(end 426.4406 -303.926748)
		(width 0.15494)
		(layer "In5.Cu")
		(net "I2C0_PEX3_SDA")
	)
	(segment
		(start 426.186346 -307.7972)
		(end 426.4406 -307.542946)
		(width 0.15494)
		(layer "In5.Cu")
		(net "I2C0_PEX3_SDA")
	)
	(segment
		(start 422.529 -308.249828)
		(end 422.981628 -307.7972)
		(width 0.15494)
		(layer "In5.Cu")
		(net "I2C0_PEX3_SDA")
	)
	(segment
		(start 432.303936 -300.8122)
		(end 436.04561 -300.8122)
		(width 0.15494)
		(layer "In5.Cu")
		(net "I2C0_PEX3_SDA")
	)
	(segment
		(start 422.981628 -307.7972)
		(end 426.186346 -307.7972)
		(width 0.15494)
		(layer "In5.Cu")
		(net "I2C0_PEX3_SDA")
	)
	(segment
		(start 426.026326 -303.512474)
		(end 426.026326 -301.740062)
		(width 0.15494)
		(layer "In5.Cu")
		(net "I2C0_PEX3_SDA")
	)
	(segment
		(start 426.4406 -303.926748)
		(end 426.026326 -303.512474)
		(width 0.15494)
		(layer "In5.Cu")
		(net "I2C0_PEX3_SDA")
	)
	(segment
		(start 420.774876 -307.774848)
		(end 421.249856 -308.249828)
		(width 0.15494)
		(layer "In5.Cu")
		(net "I2C0_PEX3_SDA")
	)
	(segment
		(start 436.04561 -300.8122)
		(end 436.27548 -301.04207)
		(width 0.15494)
		(layer "In5.Cu")
		(net "I2C0_PEX3_SDA")
	)
	(segment
		(start 336.493866 -218.387168)
		(end 336.09407 -217.987372)
		(width 0.13208)
		(layer "F.Cu")
		(net "RST_PEX_NIC7_PERST_R_N")
	)
	(segment
		(start 353.248214 -144.526)
		(end 352.632264 -144.526)
		(width 0.13208)
		(layer "F.Cu")
		(net "RST_PEX_NIC7_PERST_R_N")
	)
	(via
		(at 353.248214 -144.526)
		(size 0.508)
		(drill 0.254)
		(layers "F.Cu" "B.Cu")
		(net "RST_PEX_NIC7_PERST_R_N")
	)
	(via
		(at 336.09407 -217.987372)
		(size 0.4572)
		(drill 0.254)
		(layers "F.Cu" "B.Cu")
		(net "RST_PEX_NIC7_PERST_R_N")
	)
	(via
		(at 330.407518 -144.43329)
		(size 0.508)
		(drill 0.254)
		(layers "F.Cu" "B.Cu")
		(net "RST_PEX_NIC7_PERST_R_N")
	)
	(segment
		(start 352.046032 -144.526)
		(end 353.248214 -144.526)
		(width 0.13208)
		(layer "B.Cu")
		(net "RST_PEX_NIC7_PERST_R_N")
	)
	(segment
		(start 333.43596 -218.398598)
		(end 333.163672 -218.12631)
		(width 0.15494)
		(layer "In5.Cu")
		(net "RST_PEX_NIC7_PERST_R_N")
	)
	(segment
		(start 333.163672 -218.12631)
		(end 331.846936 -218.12631)
		(width 0.15494)
		(layer "In5.Cu")
		(net "RST_PEX_NIC7_PERST_R_N")
	)
	(segment
		(start 335.124806 -218.398598)
		(end 333.43596 -218.398598)
		(width 0.15494)
		(layer "In5.Cu")
		(net "RST_PEX_NIC7_PERST_R_N")
	)
	(segment
		(start 326.028812 -195.845938)
		(end 328.20229 -193.67246)
		(width 0.15494)
		(layer "In5.Cu")
		(net "RST_PEX_NIC7_PERST_R_N")
	)
	(segment
		(start 328.483214 -151.41829)
		(end 328.483214 -146.357594)
		(width 0.15494)
		(layer "In5.Cu")
		(net "RST_PEX_NIC7_PERST_R_N")
	)
	(segment
		(start 327.29805 -216.50325)
		(end 327.29805 -211.931758)
		(width 0.15494)
		(layer "In5.Cu")
		(net "RST_PEX_NIC7_PERST_R_N")
	)
	(segment
		(start 336.09407 -217.987372)
		(end 335.682844 -218.398598)
		(width 0.0889)
		(layer "In5.Cu")
		(net "RST_PEX_NIC7_PERST_R_N")
	)
	(segment
		(start 331.354176 -217.63355)
		(end 328.42835 -217.63355)
		(width 0.15494)
		(layer "In5.Cu")
		(net "RST_PEX_NIC7_PERST_R_N")
	)
	(segment
		(start 326.028812 -199.840342)
		(end 326.028812 -195.845938)
		(width 0.15494)
		(layer "In5.Cu")
		(net "RST_PEX_NIC7_PERST_R_N")
	)
	(segment
		(start 324.492366 -210.749134)
		(end 324.492366 -201.376788)
		(width 0.15494)
		(layer "In5.Cu")
		(net "RST_PEX_NIC7_PERST_R_N")
	)
	(segment
		(start 335.682844 -218.398598)
		(end 335.124806 -218.398598)
		(width 0.0889)
		(layer "In5.Cu")
		(net "RST_PEX_NIC7_PERST_R_N")
	)
	(segment
		(start 326.480424 -211.114132)
		(end 324.857364 -211.114132)
		(width 0.15494)
		(layer "In5.Cu")
		(net "RST_PEX_NIC7_PERST_R_N")
	)
	(segment
		(start 324.857364 -211.114132)
		(end 324.492366 -210.749134)
		(width 0.15494)
		(layer "In5.Cu")
		(net "RST_PEX_NIC7_PERST_R_N")
	)
	(segment
		(start 327.29805 -211.931758)
		(end 326.480424 -211.114132)
		(width 0.15494)
		(layer "In5.Cu")
		(net "RST_PEX_NIC7_PERST_R_N")
	)
	(segment
		(start 324.492366 -201.376788)
		(end 326.028812 -199.840342)
		(width 0.15494)
		(layer "In5.Cu")
		(net "RST_PEX_NIC7_PERST_R_N")
	)
	(segment
		(start 328.42835 -217.63355)
		(end 327.29805 -216.50325)
		(width 0.15494)
		(layer "In5.Cu")
		(net "RST_PEX_NIC7_PERST_R_N")
	)
	(segment
		(start 328.20229 -193.67246)
		(end 328.20229 -151.699214)
		(width 0.15494)
		(layer "In5.Cu")
		(net "RST_PEX_NIC7_PERST_R_N")
	)
	(segment
		(start 328.483214 -146.357594)
		(end 330.407518 -144.43329)
		(width 0.15494)
		(layer "In5.Cu")
		(net "RST_PEX_NIC7_PERST_R_N")
	)
	(segment
		(start 331.846936 -218.12631)
		(end 331.354176 -217.63355)
		(width 0.15494)
		(layer "In5.Cu")
		(net "RST_PEX_NIC7_PERST_R_N")
	)
	(segment
		(start 328.20229 -151.699214)
		(end 328.483214 -151.41829)
		(width 0.15494)
		(layer "In5.Cu")
		(net "RST_PEX_NIC7_PERST_R_N")
	)
	(segment
		(start 341.368126 -144.237964)
		(end 340.672928 -144.933162)
		(width 0.15494)
		(layer "In13.Cu")
		(net "RST_PEX_NIC7_PERST_R_N")
	)
	(segment
		(start 340.672928 -144.933162)
		(end 330.90739 -144.933162)
		(width 0.15494)
		(layer "In13.Cu")
		(net "RST_PEX_NIC7_PERST_R_N")
	)
	(segment
		(start 330.90739 -144.933162)
		(end 330.407518 -144.43329)
		(width 0.15494)
		(layer "In13.Cu")
		(net "RST_PEX_NIC7_PERST_R_N")
	)
	(segment
		(start 353.248214 -144.526)
		(end 352.960178 -144.237964)
		(width 0.15494)
		(layer "In13.Cu")
		(net "RST_PEX_NIC7_PERST_R_N")
	)
	(segment
		(start 352.960178 -144.237964)
		(end 341.368126 -144.237964)
		(width 0.15494)
		(layer "In13.Cu")
		(net "RST_PEX_NIC7_PERST_R_N")
	)
	(segment
		(start 201.34072 -369.05565)
		(end 199.837802 -369.05565)
		(width 0.254)
		(layer "F.Cu")
		(net "HSC_VDD_R")
	)
	(segment
		(start 201.646028 -369.182142)
		(end 201.34072 -369.05565)
		(width 0.254)
		(layer "F.Cu")
		(net "HSC_VDD_R")
	)
	(segment
		(start 202.130914 -369.182142)
		(end 201.646028 -369.182142)
		(width 0.2032)
		(layer "F.Cu")
		(net "HSC_VDD_R")
	)
	(segment
		(start 199.794114 -369.011962)
		(end 199.776588 -368.994436)
		(width 0.254)
		(layer "F.Cu")
		(net "HSC_VDD_R")
	)
	(segment
		(start 198.938896 -368.994436)
		(end 198.93661 -368.99215)
		(width 0.254)
		(layer "F.Cu")
		(net "HSC_VDD_R")
	)
	(segment
		(start 199.837802 -369.05565)
		(end 199.794114 -369.011962)
		(width 0.254)
		(layer "F.Cu")
		(net "HSC_VDD_R")
	)
	(segment
		(start 199.776588 -368.994436)
		(end 198.938896 -368.994436)
		(width 0.254)
		(layer "F.Cu")
		(net "HSC_VDD_R")
	)
	(via
		(at 199.794114 -369.011962)
		(size 0.508)
		(drill 0.254)
		(layers "F.Cu" "B.Cu")
		(net "HSC_VDD_R")
	)
	(via
		(at 203.976478 -368.086132)
		(size 0.508)
		(drill 0.254)
		(layers "F.Cu" "B.Cu")
		(net "HSC_VDD_R")
	)
	(via
		(at 202.960478 -368.086132)
		(size 0.508)
		(drill 0.254)
		(layers "F.Cu" "B.Cu")
		(net "HSC_VDD_R")
	)
	(via
		(at 203.468478 -367.578132)
		(size 0.508)
		(drill 0.254)
		(layers "F.Cu" "B.Cu")
		(net "HSC_VDD_R")
	)
	(segment
		(start 201.859388 -369.900708)
		(end 201.859388 -370.336318)
		(width 0.254)
		(layer "B.Cu")
		(net "HSC_VDD_R")
	)
	(segment
		(start 198.939658 -368.157506)
		(end 199.794114 -369.011962)
		(width 0.254)
		(layer "B.Cu")
		(net "HSC_VDD_R")
	)
	(segment
		(start 200.782174 -370.510308)
		(end 199.794114 -369.522248)
		(width 0.254)
		(layer "B.Cu")
		(net "HSC_VDD_R")
	)
	(segment
		(start 198.939658 -367.333276)
		(end 198.939658 -368.157506)
		(width 0.254)
		(layer "B.Cu")
		(net "HSC_VDD_R")
	)
	(segment
		(start 201.859388 -370.336318)
		(end 201.685398 -370.510308)
		(width 0.254)
		(layer "B.Cu")
		(net "HSC_VDD_R")
	)
	(segment
		(start 201.685398 -370.510308)
		(end 200.782174 -370.510308)
		(width 0.254)
		(layer "B.Cu")
		(net "HSC_VDD_R")
	)
	(segment
		(start 199.794114 -369.522248)
		(end 199.794114 -369.011962)
		(width 0.254)
		(layer "B.Cu")
		(net "HSC_VDD_R")
	)
	(segment
		(start 434.84419 -141.804898)
		(end 434.398166 -142.250922)
		(width 0.13208)
		(layer "F.Cu")
		(net "PRSNT_NIC7_R_N")
	)
	(segment
		(start 434.398166 -142.250922)
		(end 433.75199 -142.250922)
		(width 0.13208)
		(layer "F.Cu")
		(net "PRSNT_NIC7_R_N")
	)
	(segment
		(start 433.055776 -141.306296)
		(end 433.75199 -142.00251)
		(width 0.13208)
		(layer "F.Cu")
		(net "PRSNT_NIC7_R_N")
	)
	(segment
		(start 431.473864 -140.288264)
		(end 432.491896 -141.306296)
		(width 0.13208)
		(layer "F.Cu")
		(net "PRSNT_NIC7_R_N")
	)
	(segment
		(start 435.24043 -141.804898)
		(end 435.24043 -142.782798)
		(width 0.13208)
		(layer "F.Cu")
		(net "PRSNT_NIC7_R_N")
	)
	(segment
		(start 432.491896 -141.306296)
		(end 433.055776 -141.306296)
		(width 0.13208)
		(layer "F.Cu")
		(net "PRSNT_NIC7_R_N")
	)
	(segment
		(start 234.667552 -223.904048)
		(end 235.067348 -224.303844)
		(width 0.13208)
		(layer "F.Cu")
		(net "PRSNT_NIC7_R_N")
	)
	(segment
		(start 431.473864 -139.71651)
		(end 431.473864 -140.288264)
		(width 0.13208)
		(layer "F.Cu")
		(net "PRSNT_NIC7_R_N")
	)
	(segment
		(start 435.24043 -141.804898)
		(end 434.84419 -141.804898)
		(width 0.13208)
		(layer "F.Cu")
		(net "PRSNT_NIC7_R_N")
	)
	(segment
		(start 433.75199 -142.00251)
		(end 433.75199 -142.250922)
		(width 0.13208)
		(layer "F.Cu")
		(net "PRSNT_NIC7_R_N")
	)
	(segment
		(start 350.893888 -218.387168)
		(end 351.293684 -217.987372)
		(width 0.13208)
		(layer "F.Cu")
		(net "PRSNT_NIC7_R_N")
	)
	(via
		(at 354.48367 -141.279118)
		(size 0.508)
		(drill 0.254)
		(layers "F.Cu" "B.Cu")
		(net "PRSNT_NIC7_R_N")
	)
	(via
		(at 251.046234 -194.092322)
		(size 0.508)
		(drill 0.254)
		(layers "F.Cu" "B.Cu")
		(net "PRSNT_NIC7_R_N")
	)
	(via
		(at 351.293684 -217.987372)
		(size 0.4572)
		(drill 0.254)
		(layers "F.Cu" "B.Cu")
		(net "PRSNT_NIC7_R_N")
	)
	(via
		(at 431.473864 -139.71651)
		(size 0.508)
		(drill 0.254)
		(layers "F.Cu" "B.Cu")
		(net "PRSNT_NIC7_R_N")
	)
	(via
		(at 235.067348 -224.303844)
		(size 0.4572)
		(drill 0.254)
		(layers "F.Cu" "B.Cu")
		(net "PRSNT_NIC7_R_N")
	)
	(segment
		(start 361.43184 -213.47176)
		(end 363.15904 -213.47176)
		(width 0.15494)
		(layer "In5.Cu")
		(net "PRSNT_NIC7_R_N")
	)
	(segment
		(start 360.02976 -214.87384)
		(end 361.43184 -213.47176)
		(width 0.15494)
		(layer "In5.Cu")
		(net "PRSNT_NIC7_R_N")
	)
	(segment
		(start 369.740688 -180.959506)
		(end 366.994186 -178.213004)
		(width 0.15494)
		(layer "In5.Cu")
		(net "PRSNT_NIC7_R_N")
	)
	(segment
		(start 357.52024 -215.4428)
		(end 357.9368 -215.4428)
		(width 0.15494)
		(layer "In5.Cu")
		(net "PRSNT_NIC7_R_N")
	)
	(segment
		(start 354.004118 -161.421572)
		(end 354.004118 -141.75867)
		(width 0.15494)
		(layer "In5.Cu")
		(net "PRSNT_NIC7_R_N")
	)
	(segment
		(start 363.15904 -213.47176)
		(end 363.7788 -212.852)
		(width 0.15494)
		(layer "In5.Cu")
		(net "PRSNT_NIC7_R_N")
	)
	(segment
		(start 356.47884 -216.4842)
		(end 357.52024 -215.4428)
		(width 0.15494)
		(layer "In5.Cu")
		(net "PRSNT_NIC7_R_N")
	)
	(segment
		(start 369.740688 -190.831724)
		(end 369.740688 -180.959506)
		(width 0.15494)
		(layer "In5.Cu")
		(net "PRSNT_NIC7_R_N")
	)
	(segment
		(start 354.004118 -141.75867)
		(end 354.48367 -141.279118)
		(width 0.15494)
		(layer "In5.Cu")
		(net "PRSNT_NIC7_R_N")
	)
	(segment
		(start 366.994186 -172.488352)
		(end 361.419394 -166.91356)
		(width 0.15494)
		(layer "In5.Cu")
		(net "PRSNT_NIC7_R_N")
	)
	(segment
		(start 361.419394 -166.91356)
		(end 359.496106 -166.91356)
		(width 0.15494)
		(layer "In5.Cu")
		(net "PRSNT_NIC7_R_N")
	)
	(segment
		(start 351.293684 -217.987372)
		(end 351.887028 -217.987372)
		(width 0.15494)
		(layer "In5.Cu")
		(net "PRSNT_NIC7_R_N")
	)
	(segment
		(start 363.7788 -212.852)
		(end 363.7788 -211.90331)
		(width 0.15494)
		(layer "In5.Cu")
		(net "PRSNT_NIC7_R_N")
	)
	(segment
		(start 359.496106 -166.91356)
		(end 354.004118 -161.421572)
		(width 0.15494)
		(layer "In5.Cu")
		(net "PRSNT_NIC7_R_N")
	)
	(segment
		(start 371.419882 -205.035404)
		(end 371.419882 -192.510918)
		(width 0.15494)
		(layer "In5.Cu")
		(net "PRSNT_NIC7_R_N")
	)
	(segment
		(start 363.7788 -211.90331)
		(end 364.25124 -211.43087)
		(width 0.15494)
		(layer "In5.Cu")
		(net "PRSNT_NIC7_R_N")
	)
	(segment
		(start 364.25124 -211.43087)
		(end 365.024416 -211.43087)
		(width 0.15494)
		(layer "In5.Cu")
		(net "PRSNT_NIC7_R_N")
	)
	(segment
		(start 354.345748 -216.4842)
		(end 356.47884 -216.4842)
		(width 0.15494)
		(layer "In5.Cu")
		(net "PRSNT_NIC7_R_N")
	)
	(segment
		(start 365.024416 -211.43087)
		(end 371.419882 -205.035404)
		(width 0.15494)
		(layer "In5.Cu")
		(net "PRSNT_NIC7_R_N")
	)
	(segment
		(start 371.419882 -192.510918)
		(end 369.740688 -190.831724)
		(width 0.15494)
		(layer "In5.Cu")
		(net "PRSNT_NIC7_R_N")
	)
	(segment
		(start 366.994186 -178.213004)
		(end 366.994186 -172.488352)
		(width 0.15494)
		(layer "In5.Cu")
		(net "PRSNT_NIC7_R_N")
	)
	(segment
		(start 357.9368 -215.4428)
		(end 358.50576 -214.87384)
		(width 0.15494)
		(layer "In5.Cu")
		(net "PRSNT_NIC7_R_N")
	)
	(segment
		(start 352.494088 -217.380312)
		(end 353.449636 -217.380312)
		(width 0.15494)
		(layer "In5.Cu")
		(net "PRSNT_NIC7_R_N")
	)
	(segment
		(start 358.50576 -214.87384)
		(end 360.02976 -214.87384)
		(width 0.15494)
		(layer "In5.Cu")
		(net "PRSNT_NIC7_R_N")
	)
	(segment
		(start 353.449636 -217.380312)
		(end 354.345748 -216.4842)
		(width 0.15494)
		(layer "In5.Cu")
		(net "PRSNT_NIC7_R_N")
	)
	(segment
		(start 351.887028 -217.987372)
		(end 352.494088 -217.380312)
		(width 0.15494)
		(layer "In5.Cu")
		(net "PRSNT_NIC7_R_N")
	)
	(segment
		(start 240.3094 -218.8718)
		(end 240.3094 -222.250254)
		(width 0.15494)
		(layer "In7.Cu")
		(net "PRSNT_NIC7_R_N")
	)
	(segment
		(start 249.1486 -196.919342)
		(end 246.956834 -199.111108)
		(width 0.15494)
		(layer "In7.Cu")
		(net "PRSNT_NIC7_R_N")
	)
	(segment
		(start 240.3094 -222.250254)
		(end 238.506254 -224.0534)
		(width 0.15494)
		(layer "In7.Cu")
		(net "PRSNT_NIC7_R_N")
	)
	(segment
		(start 235.444792 -223.9264)
		(end 235.067348 -224.303844)
		(width 0.0889)
		(layer "In7.Cu")
		(net "PRSNT_NIC7_R_N")
	)
	(segment
		(start 246.41048 -208.66735)
		(end 246.4054 -208.67243)
		(width 0.15494)
		(layer "In7.Cu")
		(net "PRSNT_NIC7_R_N")
	)
	(segment
		(start 244.98046 -212.242654)
		(end 244.98046 -213.3346)
		(width 0.15494)
		(layer "In7.Cu")
		(net "PRSNT_NIC7_R_N")
	)
	(segment
		(start 246.41048 -207.663796)
		(end 246.41048 -208.66735)
		(width 0.15494)
		(layer "In7.Cu")
		(net "PRSNT_NIC7_R_N")
	)
	(segment
		(start 249.580146 -193.7766)
		(end 249.1486 -194.208146)
		(width 0.15494)
		(layer "In7.Cu")
		(net "PRSNT_NIC7_R_N")
	)
	(segment
		(start 247.6246 -204.6732)
		(end 246.71909 -205.57871)
		(width 0.15494)
		(layer "In7.Cu")
		(net "PRSNT_NIC7_R_N")
	)
	(segment
		(start 246.956834 -201.059034)
		(end 247.6246 -201.7268)
		(width 0.15494)
		(layer "In7.Cu")
		(net "PRSNT_NIC7_R_N")
	)
	(segment
		(start 246.4054 -208.67243)
		(end 246.4054 -209.620358)
		(width 0.15494)
		(layer "In7.Cu")
		(net "PRSNT_NIC7_R_N")
	)
	(segment
		(start 243.86286 -214.4522)
		(end 243.3066 -214.4522)
		(width 0.15494)
		(layer "In7.Cu")
		(net "PRSNT_NIC7_R_N")
	)
	(segment
		(start 243.3066 -214.4522)
		(end 241.5286 -216.2302)
		(width 0.15494)
		(layer "In7.Cu")
		(net "PRSNT_NIC7_R_N")
	)
	(segment
		(start 246.436896 -209.651854)
		(end 246.436896 -210.786218)
		(width 0.15494)
		(layer "In7.Cu")
		(net "PRSNT_NIC7_R_N")
	)
	(segment
		(start 246.71909 -207.355186)
		(end 246.41048 -207.663796)
		(width 0.15494)
		(layer "In7.Cu")
		(net "PRSNT_NIC7_R_N")
	)
	(segment
		(start 247.6246 -201.7268)
		(end 247.6246 -204.6732)
		(width 0.15494)
		(layer "In7.Cu")
		(net "PRSNT_NIC7_R_N")
	)
	(segment
		(start 246.71909 -205.57871)
		(end 246.71909 -207.355186)
		(width 0.15494)
		(layer "In7.Cu")
		(net "PRSNT_NIC7_R_N")
	)
	(segment
		(start 236.3724 -224.0534)
		(end 236.2454 -223.9264)
		(width 0.15494)
		(layer "In7.Cu")
		(net "PRSNT_NIC7_R_N")
	)
	(segment
		(start 251.046234 -194.092322)
		(end 250.730512 -193.7766)
		(width 0.15494)
		(layer "In7.Cu")
		(net "PRSNT_NIC7_R_N")
	)
	(segment
		(start 244.98046 -213.3346)
		(end 243.86286 -214.4522)
		(width 0.15494)
		(layer "In7.Cu")
		(net "PRSNT_NIC7_R_N")
	)
	(segment
		(start 238.506254 -224.0534)
		(end 236.3724 -224.0534)
		(width 0.15494)
		(layer "In7.Cu")
		(net "PRSNT_NIC7_R_N")
	)
	(segment
		(start 241.5286 -217.6526)
		(end 240.3094 -218.8718)
		(width 0.15494)
		(layer "In7.Cu")
		(net "PRSNT_NIC7_R_N")
	)
	(segment
		(start 236.2454 -223.9264)
		(end 235.444792 -223.9264)
		(width 0.0889)
		(layer "In7.Cu")
		(net "PRSNT_NIC7_R_N")
	)
	(segment
		(start 246.4054 -209.620358)
		(end 246.436896 -209.651854)
		(width 0.15494)
		(layer "In7.Cu")
		(net "PRSNT_NIC7_R_N")
	)
	(segment
		(start 246.436896 -210.786218)
		(end 244.98046 -212.242654)
		(width 0.15494)
		(layer "In7.Cu")
		(net "PRSNT_NIC7_R_N")
	)
	(segment
		(start 249.1486 -194.208146)
		(end 249.1486 -196.919342)
		(width 0.15494)
		(layer "In7.Cu")
		(net "PRSNT_NIC7_R_N")
	)
	(segment
		(start 246.956834 -199.111108)
		(end 246.956834 -201.059034)
		(width 0.15494)
		(layer "In7.Cu")
		(net "PRSNT_NIC7_R_N")
	)
	(segment
		(start 241.5286 -216.2302)
		(end 241.5286 -217.6526)
		(width 0.15494)
		(layer "In7.Cu")
		(net "PRSNT_NIC7_R_N")
	)
	(segment
		(start 250.730512 -193.7766)
		(end 249.580146 -193.7766)
		(width 0.15494)
		(layer "In7.Cu")
		(net "PRSNT_NIC7_R_N")
	)
	(segment
		(start 403.979634 -135.2042)
		(end 401.388834 -137.795)
		(width 0.15494)
		(layer "In13.Cu")
		(net "PRSNT_NIC7_R_N")
	)
	(segment
		(start 390.62787 -134.1882)
		(end 387.246622 -137.569448)
		(width 0.15494)
		(layer "In13.Cu")
		(net "PRSNT_NIC7_R_N")
	)
	(segment
		(start 431.473864 -139.71651)
		(end 429.2346 -137.477246)
		(width 0.15494)
		(layer "In13.Cu")
		(net "PRSNT_NIC7_R_N")
	)
	(segment
		(start 387.246622 -137.569448)
		(end 379.494796 -137.569448)
		(width 0.15494)
		(layer "In13.Cu")
		(net "PRSNT_NIC7_R_N")
	)
	(segment
		(start 379.494796 -137.569448)
		(end 377.036584 -140.02766)
		(width 0.15494)
		(layer "In13.Cu")
		(net "PRSNT_NIC7_R_N")
	)
	(segment
		(start 412.541466 -137.477246)
		(end 410.26842 -135.2042)
		(width 0.15494)
		(layer "In13.Cu")
		(net "PRSNT_NIC7_R_N")
	)
	(segment
		(start 377.036584 -140.02766)
		(end 362.721144 -140.02766)
		(width 0.15494)
		(layer "In13.Cu")
		(net "PRSNT_NIC7_R_N")
	)
	(segment
		(start 354.800916 -141.596364)
		(end 354.48367 -141.279118)
		(width 0.15494)
		(layer "In13.Cu")
		(net "PRSNT_NIC7_R_N")
	)
	(segment
		(start 361.15244 -141.596364)
		(end 354.800916 -141.596364)
		(width 0.15494)
		(layer "In13.Cu")
		(net "PRSNT_NIC7_R_N")
	)
	(segment
		(start 398.22628 -137.795)
		(end 394.61948 -134.1882)
		(width 0.15494)
		(layer "In13.Cu")
		(net "PRSNT_NIC7_R_N")
	)
	(segment
		(start 362.721144 -140.02766)
		(end 361.15244 -141.596364)
		(width 0.15494)
		(layer "In13.Cu")
		(net "PRSNT_NIC7_R_N")
	)
	(segment
		(start 410.26842 -135.2042)
		(end 403.979634 -135.2042)
		(width 0.15494)
		(layer "In13.Cu")
		(net "PRSNT_NIC7_R_N")
	)
	(segment
		(start 401.388834 -137.795)
		(end 398.22628 -137.795)
		(width 0.15494)
		(layer "In13.Cu")
		(net "PRSNT_NIC7_R_N")
	)
	(segment
		(start 429.2346 -137.477246)
		(end 412.541466 -137.477246)
		(width 0.15494)
		(layer "In13.Cu")
		(net "PRSNT_NIC7_R_N")
	)
	(segment
		(start 394.61948 -134.1882)
		(end 390.62787 -134.1882)
		(width 0.15494)
		(layer "In13.Cu")
		(net "PRSNT_NIC7_R_N")
	)
	(segment
		(start 324.839838 -195.750434)
		(end 326.07885 -195.750434)
		(width 0.15494)
		(layer "In15.Cu")
		(net "PRSNT_NIC7_R_N")
	)
	(segment
		(start 271.657064 -190.212472)
		(end 276.874224 -195.429632)
		(width 0.15494)
		(layer "In15.Cu")
		(net "PRSNT_NIC7_R_N")
	)
	(segment
		(start 353.80803 -208.725516)
		(end 353.73056 -208.802986)
		(width 0.15494)
		(layer "In15.Cu")
		(net "PRSNT_NIC7_R_N")
	)
	(segment
		(start 276.874224 -195.429632)
		(end 324.519036 -195.429632)
		(width 0.15494)
		(layer "In15.Cu")
		(net "PRSNT_NIC7_R_N")
	)
	(segment
		(start 326.07885 -195.750434)
		(end 326.856344 -194.97294)
		(width 0.15494)
		(layer "In15.Cu")
		(net "PRSNT_NIC7_R_N")
	)
	(segment
		(start 324.519036 -195.429632)
		(end 324.839838 -195.750434)
		(width 0.15494)
		(layer "In15.Cu")
		(net "PRSNT_NIC7_R_N")
	)
	(segment
		(start 251.859034 -194.092322)
		(end 255.738884 -190.212472)
		(width 0.15494)
		(layer "In15.Cu")
		(net "PRSNT_NIC7_R_N")
	)
	(segment
		(start 328.777092 -194.97294)
		(end 330.189078 -196.384926)
		(width 0.15494)
		(layer "In15.Cu")
		(net "PRSNT_NIC7_R_N")
	)
	(segment
		(start 346.713302 -202.009248)
		(end 350.682052 -202.009248)
		(width 0.15494)
		(layer "In15.Cu")
		(net "PRSNT_NIC7_R_N")
	)
	(segment
		(start 341.221822 -199.30491)
		(end 344.008964 -199.30491)
		(width 0.15494)
		(layer "In15.Cu")
		(net "PRSNT_NIC7_R_N")
	)
	(segment
		(start 353.73056 -208.802986)
		(end 353.73056 -215.550496)
		(width 0.15494)
		(layer "In15.Cu")
		(net "PRSNT_NIC7_R_N")
	)
	(segment
		(start 344.008964 -199.30491)
		(end 346.713302 -202.009248)
		(width 0.15494)
		(layer "In15.Cu")
		(net "PRSNT_NIC7_R_N")
	)
	(segment
		(start 352.712528 -204.039724)
		(end 352.712528 -204.335126)
		(width 0.15494)
		(layer "In15.Cu")
		(net "PRSNT_NIC7_R_N")
	)
	(segment
		(start 353.73056 -215.550496)
		(end 351.293684 -217.987372)
		(width 0.15494)
		(layer "In15.Cu")
		(net "PRSNT_NIC7_R_N")
	)
	(segment
		(start 353.80803 -205.430628)
		(end 353.80803 -208.725516)
		(width 0.15494)
		(layer "In15.Cu")
		(net "PRSNT_NIC7_R_N")
	)
	(segment
		(start 330.189078 -196.384926)
		(end 338.301838 -196.384926)
		(width 0.15494)
		(layer "In15.Cu")
		(net "PRSNT_NIC7_R_N")
	)
	(segment
		(start 251.046234 -194.092322)
		(end 251.859034 -194.092322)
		(width 0.15494)
		(layer "In15.Cu")
		(net "PRSNT_NIC7_R_N")
	)
	(segment
		(start 326.856344 -194.97294)
		(end 328.777092 -194.97294)
		(width 0.15494)
		(layer "In15.Cu")
		(net "PRSNT_NIC7_R_N")
	)
	(segment
		(start 352.712528 -204.335126)
		(end 353.80803 -205.430628)
		(width 0.15494)
		(layer "In15.Cu")
		(net "PRSNT_NIC7_R_N")
	)
	(segment
		(start 338.301838 -196.384926)
		(end 341.221822 -199.30491)
		(width 0.15494)
		(layer "In15.Cu")
		(net "PRSNT_NIC7_R_N")
	)
	(segment
		(start 255.738884 -190.212472)
		(end 271.657064 -190.212472)
		(width 0.15494)
		(layer "In15.Cu")
		(net "PRSNT_NIC7_R_N")
	)
	(segment
		(start 350.682052 -202.009248)
		(end 352.712528 -204.039724)
		(width 0.15494)
		(layer "In15.Cu")
		(net "PRSNT_NIC7_R_N")
	)
	(segment
		(start 215.58758 -365.320326)
		(end 216.63279 -366.365536)
		(width 0.13208)
		(layer "F.Cu")
		(net "HSC_OCREF")
	)
	(segment
		(start 226.629976 -365.978186)
		(end 227.859336 -367.207546)
		(width 0.13208)
		(layer "F.Cu")
		(net "HSC_OCREF")
	)
	(segment
		(start 201.674476 -366.140746)
		(end 202.089512 -366.140746)
		(width 0.13208)
		(layer "F.Cu")
		(net "HSC_OCREF")
	)
	(segment
		(start 216.63279 -366.365536)
		(end 216.63279 -366.906048)
		(width 0.13208)
		(layer "F.Cu")
		(net "HSC_OCREF")
	)
	(segment
		(start 216.934288 -367.207546)
		(end 217.376248 -367.207546)
		(width 0.13208)
		(layer "F.Cu")
		(net "HSC_OCREF")
	)
	(segment
		(start 202.089512 -366.140746)
		(end 202.668378 -366.719612)
		(width 0.13208)
		(layer "F.Cu")
		(net "HSC_OCREF")
	)
	(segment
		(start 216.63279 -366.906048)
		(end 216.934288 -367.207546)
		(width 0.13208)
		(layer "F.Cu")
		(net "HSC_OCREF")
	)
	(segment
		(start 214.707724 -365.978186)
		(end 214.707724 -365.320326)
		(width 0.13208)
		(layer "F.Cu")
		(net "HSC_OCREF")
	)
	(segment
		(start 226.629976 -365.978186)
		(end 225.252026 -365.978186)
		(width 0.13208)
		(layer "F.Cu")
		(net "HSC_OCREF")
	)
	(segment
		(start 227.859336 -367.207546)
		(end 228.044248 -367.207546)
		(width 0.13208)
		(layer "F.Cu")
		(net "HSC_OCREF")
	)
	(segment
		(start 214.707724 -365.320326)
		(end 215.58758 -365.320326)
		(width 0.13208)
		(layer "F.Cu")
		(net "HSC_OCREF")
	)
	(via
		(at 201.674476 -366.140746)
		(size 0.508)
		(drill 0.254)
		(layers "F.Cu" "B.Cu")
		(net "HSC_OCREF")
	)
	(via
		(at 214.707724 -365.320326)
		(size 0.508)
		(drill 0.254)
		(layers "F.Cu" "B.Cu")
		(net "HSC_OCREF")
	)
	(via
		(at 226.629976 -365.978186)
		(size 0.508)
		(drill 0.254)
		(layers "F.Cu" "B.Cu")
		(net "HSC_OCREF")
	)
	(segment
		(start 211.737956 -360.426)
		(end 203.409296 -360.426)
		(width 0.15494)
		(layer "In7.Cu")
		(net "HSC_OCREF")
	)
	(segment
		(start 203.409296 -360.426)
		(end 201.006964 -362.828332)
		(width 0.15494)
		(layer "In7.Cu")
		(net "HSC_OCREF")
	)
	(segment
		(start 214.707724 -363.395768)
		(end 217.58021 -360.523282)
		(width 0.15494)
		(layer "In7.Cu")
		(net "HSC_OCREF")
	)
	(segment
		(start 201.006964 -362.828332)
		(end 201.006964 -365.473234)
		(width 0.15494)
		(layer "In7.Cu")
		(net "HSC_OCREF")
	)
	(segment
		(start 226.629976 -363.564932)
		(end 226.629976 -365.978186)
		(width 0.15494)
		(layer "In7.Cu")
		(net "HSC_OCREF")
	)
	(segment
		(start 214.707724 -365.320326)
		(end 214.707724 -363.395768)
		(width 0.15494)
		(layer "In7.Cu")
		(net "HSC_OCREF")
	)
	(segment
		(start 223.588326 -360.523282)
		(end 226.629976 -363.564932)
		(width 0.15494)
		(layer "In7.Cu")
		(net "HSC_OCREF")
	)
	(segment
		(start 214.707724 -363.395768)
		(end 211.737956 -360.426)
		(width 0.15494)
		(layer "In7.Cu")
		(net "HSC_OCREF")
	)
	(segment
		(start 217.58021 -360.523282)
		(end 223.588326 -360.523282)
		(width 0.15494)
		(layer "In7.Cu")
		(net "HSC_OCREF")
	)
	(segment
		(start 201.006964 -365.473234)
		(end 201.674476 -366.140746)
		(width 0.15494)
		(layer "In7.Cu")
		(net "HSC_OCREF")
	)
	(segment
		(start 226.551744 -368.852704)
		(end 226.528376 -368.829336)
		(width 0.254)
		(layer "F.Cu")
		(net "HSC_VDD_2")
	)
	(segment
		(start 225.99015 -368.84991)
		(end 226.507802 -368.84991)
		(width 0.254)
		(layer "F.Cu")
		(net "HSC_VDD_2")
	)
	(segment
		(start 226.507802 -368.84991)
		(end 226.528376 -368.829336)
		(width 0.254)
		(layer "F.Cu")
		(net "HSC_VDD_2")
	)
	(segment
		(start 226.96297 -368.70767)
		(end 226.817936 -368.852704)
		(width 0.254)
		(layer "F.Cu")
		(net "HSC_VDD_2")
	)
	(segment
		(start 225.891344 -368.948716)
		(end 225.99015 -368.84991)
		(width 0.254)
		(layer "F.Cu")
		(net "HSC_VDD_2")
	)
	(segment
		(start 226.817936 -368.852704)
		(end 226.551744 -368.852704)
		(width 0.254)
		(layer "F.Cu")
		(net "HSC_VDD_2")
	)
	(segment
		(start 228.056948 -368.70767)
		(end 226.96297 -368.70767)
		(width 0.254)
		(layer "F.Cu")
		(net "HSC_VDD_2")
	)
	(via
		(at 225.891344 -368.948716)
		(size 0.508)
		(drill 0.254)
		(layers "F.Cu" "B.Cu")
		(net "HSC_VDD_2")
	)
	(segment
		(start 225.891344 -368.948716)
		(end 225.891344 -369.333018)
		(width 0.254)
		(layer "B.Cu")
		(net "HSC_VDD_2")
	)
	(segment
		(start 225.252026 -369.972336)
		(end 225.252026 -370.042186)
		(width 0.254)
		(layer "B.Cu")
		(net "HSC_VDD_2")
	)
	(segment
		(start 225.891344 -369.333018)
		(end 225.252026 -369.972336)
		(width 0.254)
		(layer "B.Cu")
		(net "HSC_VDD_2")
	)
	(segment
		(start 336.44205 -153.67)
		(end 337.058 -153.67)
		(width 0.13208)
		(layer "F.Cu")
		(net "RST_PEX_SSD13_PERST_R_N")
	)
	(segment
		(start 337.058 -153.67)
		(end 337.67395 -153.67)
		(width 0.13208)
		(layer "F.Cu")
		(net "RST_PEX_SSD13_PERST_R_N")
	)
	(segment
		(start 336.493866 -215.187022)
		(end 336.09407 -214.787226)
		(width 0.13208)
		(layer "F.Cu")
		(net "RST_PEX_SSD13_PERST_R_N")
	)
	(via
		(at 336.09407 -214.787226)
		(size 0.4572)
		(drill 0.254)
		(layers "F.Cu" "B.Cu")
		(net "RST_PEX_SSD13_PERST_R_N")
	)
	(via
		(at 337.058 -153.67)
		(size 0.508)
		(drill 0.254)
		(layers "F.Cu" "B.Cu")
		(net "RST_PEX_SSD13_PERST_R_N")
	)
	(segment
		(start 335.5594 -208.687416)
		(end 335.5594 -211.87918)
		(width 0.15494)
		(layer "In7.Cu")
		(net "RST_PEX_SSD13_PERST_R_N")
	)
	(segment
		(start 336.57413 -182.24627)
		(end 335.28127 -183.53913)
		(width 0.15494)
		(layer "In7.Cu")
		(net "RST_PEX_SSD13_PERST_R_N")
	)
	(segment
		(start 336.57413 -180.92166)
		(end 336.58429 -180.93182)
		(width 0.15494)
		(layer "In7.Cu")
		(net "RST_PEX_SSD13_PERST_R_N")
	)
	(segment
		(start 340.919816 -174.105062)
		(end 340.919816 -174.11954)
		(width 0.15494)
		(layer "In7.Cu")
		(net "RST_PEX_SSD13_PERST_R_N")
	)
	(segment
		(start 338.00161 -178.31816)
		(end 336.58429 -179.73548)
		(width 0.15494)
		(layer "In7.Cu")
		(net "RST_PEX_SSD13_PERST_R_N")
	)
	(segment
		(start 336.58429 -180.51018)
		(end 336.57413 -180.52034)
		(width 0.15494)
		(layer "In7.Cu")
		(net "RST_PEX_SSD13_PERST_R_N")
	)
	(segment
		(start 336.58429 -181.78018)
		(end 336.57413 -181.79034)
		(width 0.15494)
		(layer "In7.Cu")
		(net "RST_PEX_SSD13_PERST_R_N")
	)
	(segment
		(start 336.1944 -154.5336)
		(end 336.1944 -172.4406)
		(width 0.15494)
		(layer "In7.Cu")
		(net "RST_PEX_SSD13_PERST_R_N")
	)
	(segment
		(start 340.636606 -173.821852)
		(end 340.919816 -174.105062)
		(width 0.15494)
		(layer "In7.Cu")
		(net "RST_PEX_SSD13_PERST_R_N")
	)
	(segment
		(start 334.30591 -183.54929)
		(end 333.01813 -184.83707)
		(width 0.15494)
		(layer "In7.Cu")
		(net "RST_PEX_SSD13_PERST_R_N")
	)
	(segment
		(start 340.9442 -174.143924)
		(end 340.9442 -175.19904)
		(width 0.15494)
		(layer "In7.Cu")
		(net "RST_PEX_SSD13_PERST_R_N")
	)
	(segment
		(start 340.919816 -174.11954)
		(end 340.9442 -174.143924)
		(width 0.15494)
		(layer "In7.Cu")
		(net "RST_PEX_SSD13_PERST_R_N")
	)
	(segment
		(start 336.57413 -181.79034)
		(end 336.57413 -182.24627)
		(width 0.15494)
		(layer "In7.Cu")
		(net "RST_PEX_SSD13_PERST_R_N")
	)
	(segment
		(start 337.357974 -173.604174)
		(end 340.40445 -173.604174)
		(width 0.15494)
		(layer "In7.Cu")
		(net "RST_PEX_SSD13_PERST_R_N")
	)
	(segment
		(start 337.058 -153.67)
		(end 336.1944 -154.5336)
		(width 0.15494)
		(layer "In7.Cu")
		(net "RST_PEX_SSD13_PERST_R_N")
	)
	(segment
		(start 336.58429 -179.73548)
		(end 336.58429 -180.51018)
		(width 0.15494)
		(layer "In7.Cu")
		(net "RST_PEX_SSD13_PERST_R_N")
	)
	(segment
		(start 336.57413 -180.52034)
		(end 336.57413 -180.92166)
		(width 0.15494)
		(layer "In7.Cu")
		(net "RST_PEX_SSD13_PERST_R_N")
	)
	(segment
		(start 335.69402 -214.387176)
		(end 336.09407 -214.787226)
		(width 0.0889)
		(layer "In7.Cu")
		(net "RST_PEX_SSD13_PERST_R_N")
	)
	(segment
		(start 340.9442 -175.19904)
		(end 338.00161 -178.14163)
		(width 0.15494)
		(layer "In7.Cu")
		(net "RST_PEX_SSD13_PERST_R_N")
	)
	(segment
		(start 336.58429 -180.93182)
		(end 336.58429 -181.78018)
		(width 0.15494)
		(layer "In7.Cu")
		(net "RST_PEX_SSD13_PERST_R_N")
	)
	(segment
		(start 338.00161 -178.14163)
		(end 338.00161 -178.31816)
		(width 0.15494)
		(layer "In7.Cu")
		(net "RST_PEX_SSD13_PERST_R_N")
	)
	(segment
		(start 340.40445 -173.604174)
		(end 340.622128 -173.821852)
		(width 0.15494)
		(layer "In7.Cu")
		(net "RST_PEX_SSD13_PERST_R_N")
	)
	(segment
		(start 333.01813 -184.83707)
		(end 333.01813 -206.146146)
		(width 0.15494)
		(layer "In7.Cu")
		(net "RST_PEX_SSD13_PERST_R_N")
	)
	(segment
		(start 335.28127 -183.53913)
		(end 334.82534 -183.53913)
		(width 0.15494)
		(layer "In7.Cu")
		(net "RST_PEX_SSD13_PERST_R_N")
	)
	(segment
		(start 335.5594 -211.87918)
		(end 335.69402 -212.0138)
		(width 0.15494)
		(layer "In7.Cu")
		(net "RST_PEX_SSD13_PERST_R_N")
	)
	(segment
		(start 334.82534 -183.53913)
		(end 334.81518 -183.54929)
		(width 0.15494)
		(layer "In7.Cu")
		(net "RST_PEX_SSD13_PERST_R_N")
	)
	(segment
		(start 333.01813 -206.146146)
		(end 335.5594 -208.687416)
		(width 0.15494)
		(layer "In7.Cu")
		(net "RST_PEX_SSD13_PERST_R_N")
	)
	(segment
		(start 334.81518 -183.54929)
		(end 334.30591 -183.54929)
		(width 0.15494)
		(layer "In7.Cu")
		(net "RST_PEX_SSD13_PERST_R_N")
	)
	(segment
		(start 335.69402 -212.0138)
		(end 335.69402 -214.387176)
		(width 0.0889)
		(layer "In7.Cu")
		(net "RST_PEX_SSD13_PERST_R_N")
	)
	(segment
		(start 336.1944 -172.4406)
		(end 337.357974 -173.604174)
		(width 0.15494)
		(layer "In7.Cu")
		(net "RST_PEX_SSD13_PERST_R_N")
	)
	(segment
		(start 340.622128 -173.821852)
		(end 340.636606 -173.821852)
		(width 0.15494)
		(layer "In7.Cu")
		(net "RST_PEX_SSD13_PERST_R_N")
	)
	(segment
		(start 337.67395 -155.702)
		(end 337.058 -155.702)
		(width 0.13208)
		(layer "F.Cu")
		(net "PRSNT_SSD13_FPGA_R_N")
	)
	(segment
		(start 326.517 -211.201)
		(end 325.472552 -210.156552)
		(width 0.13208)
		(layer "F.Cu")
		(net "PRSNT_SSD13_FPGA_R_N")
	)
	(segment
		(start 327.13295 -211.201)
		(end 326.517 -211.201)
		(width 0.13208)
		(layer "F.Cu")
		(net "PRSNT_SSD13_FPGA_R_N")
	)
	(via
		(at 337.058 -155.702)
		(size 0.508)
		(drill 0.254)
		(layers "F.Cu" "B.Cu")
		(net "PRSNT_SSD13_FPGA_R_N")
	)
	(via
		(at 325.472552 -210.156552)
		(size 0.508)
		(drill 0.254)
		(layers "F.Cu" "B.Cu")
		(net "PRSNT_SSD13_FPGA_R_N")
	)
	(segment
		(start 324.333616 -209.017616)
		(end 324.333616 -204.638402)
		(width 0.15494)
		(layer "In9.Cu")
		(net "PRSNT_SSD13_FPGA_R_N")
	)
	(segment
		(start 336.5246 -160.1724)
		(end 336.5246 -156.2354)
		(width 0.15494)
		(layer "In9.Cu")
		(net "PRSNT_SSD13_FPGA_R_N")
	)
	(segment
		(start 336.5246 -156.2354)
		(end 337.058 -155.702)
		(width 0.15494)
		(layer "In9.Cu")
		(net "PRSNT_SSD13_FPGA_R_N")
	)
	(segment
		(start 337.32851 -171.97832)
		(end 338.24799 -171.05884)
		(width 0.15494)
		(layer "In9.Cu")
		(net "PRSNT_SSD13_FPGA_R_N")
	)
	(segment
		(start 336.322416 -173.482)
		(end 337.32851 -172.47616)
		(width 0.15494)
		(layer "In9.Cu")
		(net "PRSNT_SSD13_FPGA_R_N")
	)
	(segment
		(start 327.914 -180.542946)
		(end 334.872076 -173.58487)
		(width 0.15494)
		(layer "In9.Cu")
		(net "PRSNT_SSD13_FPGA_R_N")
	)
	(segment
		(start 338.24799 -161.89579)
		(end 336.5246 -160.1724)
		(width 0.15494)
		(layer "In9.Cu")
		(net "PRSNT_SSD13_FPGA_R_N")
	)
	(segment
		(start 325.472552 -210.156552)
		(end 324.333616 -209.017616)
		(width 0.15494)
		(layer "In9.Cu")
		(net "PRSNT_SSD13_FPGA_R_N")
	)
	(segment
		(start 327.1774 -199.5678)
		(end 327.1774 -195.605146)
		(width 0.15494)
		(layer "In9.Cu")
		(net "PRSNT_SSD13_FPGA_R_N")
	)
	(segment
		(start 338.24799 -171.05884)
		(end 338.24799 -161.89579)
		(width 0.15494)
		(layer "In9.Cu")
		(net "PRSNT_SSD13_FPGA_R_N")
	)
	(segment
		(start 334.872076 -173.58487)
		(end 336.219546 -173.58487)
		(width 0.15494)
		(layer "In9.Cu")
		(net "PRSNT_SSD13_FPGA_R_N")
	)
	(segment
		(start 327.914 -194.868546)
		(end 327.914 -180.542946)
		(width 0.15494)
		(layer "In9.Cu")
		(net "PRSNT_SSD13_FPGA_R_N")
	)
	(segment
		(start 327.1774 -195.605146)
		(end 327.914 -194.868546)
		(width 0.15494)
		(layer "In9.Cu")
		(net "PRSNT_SSD13_FPGA_R_N")
	)
	(segment
		(start 324.549008 -202.196192)
		(end 327.1774 -199.5678)
		(width 0.15494)
		(layer "In9.Cu")
		(net "PRSNT_SSD13_FPGA_R_N")
	)
	(segment
		(start 336.219546 -173.58487)
		(end 336.322416 -173.482)
		(width 0.15494)
		(layer "In9.Cu")
		(net "PRSNT_SSD13_FPGA_R_N")
	)
	(segment
		(start 337.32851 -172.47616)
		(end 337.32851 -171.97832)
		(width 0.15494)
		(layer "In9.Cu")
		(net "PRSNT_SSD13_FPGA_R_N")
	)
	(segment
		(start 324.333616 -204.638402)
		(end 324.549008 -202.196192)
		(width 0.15494)
		(layer "In9.Cu")
		(net "PRSNT_SSD13_FPGA_R_N")
	)
	(segment
		(start 199.907652 -370.975382)
		(end 200.462642 -370.975382)
		(width 0.13208)
		(layer "F.Cu")
		(net "HSC_VIN_UVW_N")
	)
	(segment
		(start 202.033886 -370.532152)
		(end 202.130914 -370.532152)
		(width 0.13208)
		(layer "F.Cu")
		(net "HSC_VIN_UVW_N")
	)
	(segment
		(start 201.772774 -370.793264)
		(end 202.033886 -370.532152)
		(width 0.13208)
		(layer "F.Cu")
		(net "HSC_VIN_UVW_N")
	)
	(segment
		(start 200.462642 -370.975382)
		(end 200.64476 -370.793264)
		(width 0.13208)
		(layer "F.Cu")
		(net "HSC_VIN_UVW_N")
	)
	(segment
		(start 200.64476 -370.793264)
		(end 201.772774 -370.793264)
		(width 0.13208)
		(layer "F.Cu")
		(net "HSC_VIN_UVW_N")
	)
	(via
		(at 199.907652 -370.975382)
		(size 0.762)
		(drill 0.254)
		(layers "F.Cu" "B.Cu")
		(net "HSC_VIN_UVW_N")
	)
	(segment
		(start 199.515984 -370.446046)
		(end 199.515984 -369.927886)
		(width 0.13208)
		(layer "B.Cu")
		(net "HSC_VIN_UVW_N")
	)
	(segment
		(start 199.515984 -369.927886)
		(end 198.709788 -369.12169)
		(width 0.13208)
		(layer "B.Cu")
		(net "HSC_VIN_UVW_N")
	)
	(segment
		(start 199.907652 -370.975382)
		(end 199.6821 -370.74983)
		(width 0.13208)
		(layer "B.Cu")
		(net "HSC_VIN_UVW_N")
	)
	(segment
		(start 198.709788 -369.12169)
		(end 198.280274 -369.12169)
		(width 0.13208)
		(layer "B.Cu")
		(net "HSC_VIN_UVW_N")
	)
	(segment
		(start 199.6821 -370.74983)
		(end 199.6821 -370.612162)
		(width 0.13208)
		(layer "B.Cu")
		(net "HSC_VIN_UVW_N")
	)
	(segment
		(start 199.6821 -370.612162)
		(end 199.515984 -370.446046)
		(width 0.13208)
		(layer "B.Cu")
		(net "HSC_VIN_UVW_N")
	)
	(segment
		(start 85.103208 -59.171586)
		(end 84.944204 -59.012582)
		(width 0.13208)
		(layer "F.Cu")
		(net "P3V3_SSD3_OCP")
	)
	(segment
		(start 85.1408 -58.364628)
		(end 84.944204 -58.561224)
		(width 0.13208)
		(layer "F.Cu")
		(net "P3V3_SSD3_OCP")
	)
	(segment
		(start 84.944204 -59.012582)
		(end 84.944204 -58.561224)
		(width 0.13208)
		(layer "F.Cu")
		(net "P3V3_SSD3_OCP")
	)
	(segment
		(start 85.1408 -57.16397)
		(end 85.1408 -58.364628)
		(width 0.13208)
		(layer "F.Cu")
		(net "P3V3_SSD3_OCP")
	)
	(via
		(at 84.944204 -58.561224)
		(size 0.508)
		(drill 0.254)
		(layers "F.Cu" "B.Cu")
		(net "P3V3_SSD3_OCP")
	)
	(segment
		(start 352.632264 -142.494)
		(end 353.248214 -142.494)
		(width 0.13208)
		(layer "F.Cu")
		(net "PRSNT_NIC7_FPGA_R_N")
	)
	(segment
		(start 327.13295 -217.297)
		(end 326.517 -217.297)
		(width 0.13208)
		(layer "F.Cu")
		(net "PRSNT_NIC7_FPGA_R_N")
	)
	(via
		(at 326.517 -217.297)
		(size 0.508)
		(drill 0.254)
		(layers "F.Cu" "B.Cu")
		(net "PRSNT_NIC7_FPGA_R_N")
	)
	(via
		(at 353.248214 -142.494)
		(size 0.508)
		(drill 0.254)
		(layers "F.Cu" "B.Cu")
		(net "PRSNT_NIC7_FPGA_R_N")
	)
	(via
		(at 338.098384 -139.682474)
		(size 0.508)
		(drill 0.254)
		(layers "F.Cu" "B.Cu")
		(net "PRSNT_NIC7_FPGA_R_N")
	)
	(segment
		(start 335.5848 -152.228042)
		(end 336.04708 -151.765762)
		(width 0.15494)
		(layer "In9.Cu")
		(net "PRSNT_NIC7_FPGA_R_N")
	)
	(segment
		(start 323.70268 -199.878696)
		(end 323.70268 -193.800984)
		(width 0.15494)
		(layer "In9.Cu")
		(net "PRSNT_NIC7_FPGA_R_N")
	)
	(segment
		(start 324.172834 -188.524134)
		(end 324.26783 -188.308234)
		(width 0.15494)
		(layer "In9.Cu")
		(net "PRSNT_NIC7_FPGA_R_N")
	)
	(segment
		(start 324.952106 -181.098698)
		(end 325.858124 -178.911504)
		(width 0.15494)
		(layer "In9.Cu")
		(net "PRSNT_NIC7_FPGA_R_N")
	)
	(segment
		(start 338.098384 -149.15261)
		(end 338.098384 -139.682474)
		(width 0.15494)
		(layer "In9.Cu")
		(net "PRSNT_NIC7_FPGA_R_N")
	)
	(segment
		(start 326.517 -217.297)
		(end 322.542916 -213.322916)
		(width 0.15494)
		(layer "In9.Cu")
		(net "PRSNT_NIC7_FPGA_R_N")
	)
	(segment
		(start 323.72046 -193.620136)
		(end 323.72046 -193.115184)
		(width 0.15494)
		(layer "In9.Cu")
		(net "PRSNT_NIC7_FPGA_R_N")
	)
	(segment
		(start 323.702934 -200.473056)
		(end 323.702934 -199.87895)
		(width 0.15494)
		(layer "In9.Cu")
		(net "PRSNT_NIC7_FPGA_R_N")
	)
	(segment
		(start 322.542916 -213.322916)
		(end 322.542916 -204.559662)
		(width 0.15494)
		(layer "In9.Cu")
		(net "PRSNT_NIC7_FPGA_R_N")
	)
	(segment
		(start 324.85584 -182.077106)
		(end 324.952106 -181.098698)
		(width 0.15494)
		(layer "In9.Cu")
		(net "PRSNT_NIC7_FPGA_R_N")
	)
	(segment
		(start 322.542916 -204.559662)
		(end 322.824348 -201.351896)
		(width 0.15494)
		(layer "In9.Cu")
		(net "PRSNT_NIC7_FPGA_R_N")
	)
	(segment
		(start 325.1708 -187.48121)
		(end 325.1708 -183.258714)
		(width 0.15494)
		(layer "In9.Cu")
		(net "PRSNT_NIC7_FPGA_R_N")
	)
	(segment
		(start 322.824348 -201.351896)
		(end 323.702934 -200.473056)
		(width 0.15494)
		(layer "In9.Cu")
		(net "PRSNT_NIC7_FPGA_R_N")
	)
	(segment
		(start 335.28 -170.561)
		(end 335.5848 -170.2562)
		(width 0.15494)
		(layer "In9.Cu")
		(net "PRSNT_NIC7_FPGA_R_N")
	)
	(segment
		(start 335.5848 -170.2562)
		(end 335.5848 -152.228042)
		(width 0.15494)
		(layer "In9.Cu")
		(net "PRSNT_NIC7_FPGA_R_N")
	)
	(segment
		(start 324.85584 -182.943754)
		(end 324.85584 -182.077106)
		(width 0.15494)
		(layer "In9.Cu")
		(net "PRSNT_NIC7_FPGA_R_N")
	)
	(segment
		(start 323.72046 -193.115184)
		(end 324.172834 -188.524134)
		(width 0.15494)
		(layer "In9.Cu")
		(net "PRSNT_NIC7_FPGA_R_N")
	)
	(segment
		(start 336.04708 -151.765762)
		(end 336.04708 -151.203914)
		(width 0.15494)
		(layer "In9.Cu")
		(net "PRSNT_NIC7_FPGA_R_N")
	)
	(segment
		(start 323.70268 -193.800984)
		(end 323.72046 -193.620136)
		(width 0.15494)
		(layer "In9.Cu")
		(net "PRSNT_NIC7_FPGA_R_N")
	)
	(segment
		(start 334.208628 -170.561)
		(end 335.28 -170.561)
		(width 0.15494)
		(layer "In9.Cu")
		(net "PRSNT_NIC7_FPGA_R_N")
	)
	(segment
		(start 336.04708 -151.203914)
		(end 338.098384 -149.15261)
		(width 0.15494)
		(layer "In9.Cu")
		(net "PRSNT_NIC7_FPGA_R_N")
	)
	(segment
		(start 324.26783 -188.308234)
		(end 325.1708 -187.48121)
		(width 0.15494)
		(layer "In9.Cu")
		(net "PRSNT_NIC7_FPGA_R_N")
	)
	(segment
		(start 325.1708 -183.258714)
		(end 324.85584 -182.943754)
		(width 0.15494)
		(layer "In9.Cu")
		(net "PRSNT_NIC7_FPGA_R_N")
	)
	(segment
		(start 323.702934 -199.87895)
		(end 323.70268 -199.878696)
		(width 0.15494)
		(layer "In9.Cu")
		(net "PRSNT_NIC7_FPGA_R_N")
	)
	(segment
		(start 325.858124 -178.911504)
		(end 334.208628 -170.561)
		(width 0.15494)
		(layer "In9.Cu")
		(net "PRSNT_NIC7_FPGA_R_N")
	)
	(segment
		(start 353.248214 -141.190218)
		(end 353.248214 -142.494)
		(width 0.15494)
		(layer "In13.Cu")
		(net "PRSNT_NIC7_FPGA_R_N")
	)
	(segment
		(start 339.44941 -138.331448)
		(end 350.389444 -138.331448)
		(width 0.15494)
		(layer "In13.Cu")
		(net "PRSNT_NIC7_FPGA_R_N")
	)
	(segment
		(start 350.389444 -138.331448)
		(end 353.248214 -141.190218)
		(width 0.15494)
		(layer "In13.Cu")
		(net "PRSNT_NIC7_FPGA_R_N")
	)
	(segment
		(start 338.098384 -139.682474)
		(end 339.44941 -138.331448)
		(width 0.15494)
		(layer "In13.Cu")
		(net "PRSNT_NIC7_FPGA_R_N")
	)
	(segment
		(start 227.467668 -214.304118)
		(end 227.067872 -213.904322)
		(width 0.13208)
		(layer "F.Cu")
		(net "RST_SMB_FIO_N")
	)
	(via
		(at 225.06051 -210.340448)
		(size 0.6604)
		(drill 0.3302)
		(layers "F.Cu" "B.Cu")
		(net "RST_SMB_FIO_N")
	)
	(via
		(at 227.067872 -213.904322)
		(size 0.4572)
		(drill 0.254)
		(layers "F.Cu" "B.Cu")
		(net "RST_SMB_FIO_N")
	)
	(segment
		(start 225.06051 -210.340448)
		(end 225.06051 -209.681064)
		(width 0.13208)
		(layer "B.Cu")
		(net "RST_SMB_FIO_N")
	)
	(segment
		(start 227.067872 -213.904322)
		(end 227.067872 -213.665054)
		(width 0.0889)
		(layer "B.Cu")
		(net "RST_SMB_FIO_N")
	)
	(segment
		(start 225.06051 -209.681064)
		(end 225.556064 -209.18551)
		(width 0.13208)
		(layer "B.Cu")
		(net "RST_SMB_FIO_N")
	)
	(segment
		(start 227.067872 -213.665054)
		(end 226.671632 -213.268814)
		(width 0.0889)
		(layer "B.Cu")
		(net "RST_SMB_FIO_N")
	)
	(segment
		(start 226.671632 -211.95157)
		(end 225.06051 -210.340448)
		(width 0.13208)
		(layer "B.Cu")
		(net "RST_SMB_FIO_N")
	)
	(segment
		(start 226.671632 -213.268814)
		(end 226.671632 -211.95157)
		(width 0.0889)
		(layer "B.Cu")
		(net "RST_SMB_FIO_N")
	)
	(segment
		(start 338.093812 -219.187014)
		(end 337.694016 -218.787218)
		(width 0.13208)
		(layer "F.Cu")
		(net "RST_PEX_NIC6_PERST_R_N")
	)
	(segment
		(start 353.248214 -156.337)
		(end 352.632264 -156.337)
		(width 0.13208)
		(layer "F.Cu")
		(net "RST_PEX_NIC6_PERST_R_N")
	)
	(via
		(at 353.248214 -156.337)
		(size 0.508)
		(drill 0.254)
		(layers "F.Cu" "B.Cu")
		(net "RST_PEX_NIC6_PERST_R_N")
	)
	(via
		(at 337.694016 -218.787218)
		(size 0.4572)
		(drill 0.254)
		(layers "F.Cu" "B.Cu")
		(net "RST_PEX_NIC6_PERST_R_N")
	)
	(via
		(at 338.638896 -156.332936)
		(size 0.508)
		(drill 0.254)
		(layers "F.Cu" "B.Cu")
		(net "RST_PEX_NIC6_PERST_R_N")
	)
	(segment
		(start 352.046032 -156.337)
		(end 353.248214 -156.337)
		(width 0.13208)
		(layer "B.Cu")
		(net "RST_PEX_NIC6_PERST_R_N")
	)
	(segment
		(start 340.61146 -166.19474)
		(end 340.61146 -163.6522)
		(width 0.15494)
		(layer "In9.Cu")
		(net "RST_PEX_NIC6_PERST_R_N")
	)
	(segment
		(start 327.140316 -207.811116)
		(end 325.755 -206.4258)
		(width 0.15494)
		(layer "In9.Cu")
		(net "RST_PEX_NIC6_PERST_R_N")
	)
	(segment
		(start 339.598 -170.8658)
		(end 339.598 -167.2082)
		(width 0.15494)
		(layer "In9.Cu")
		(net "RST_PEX_NIC6_PERST_R_N")
	)
	(segment
		(start 336.85734 -219.623894)
		(end 330.12253 -219.623894)
		(width 0.15494)
		(layer "In9.Cu")
		(net "RST_PEX_NIC6_PERST_R_N")
	)
	(segment
		(start 340.008718 -159.931862)
		(end 338.638896 -158.56204)
		(width 0.15494)
		(layer "In9.Cu")
		(net "RST_PEX_NIC6_PERST_R_N")
	)
	(segment
		(start 338.638896 -158.56204)
		(end 338.638896 -156.332936)
		(width 0.15494)
		(layer "In9.Cu")
		(net "RST_PEX_NIC6_PERST_R_N")
	)
	(segment
		(start 339.598 -167.2082)
		(end 340.61146 -166.19474)
		(width 0.15494)
		(layer "In9.Cu")
		(net "RST_PEX_NIC6_PERST_R_N")
	)
	(segment
		(start 330.12253 -219.623894)
		(end 327.140316 -216.64168)
		(width 0.15494)
		(layer "In9.Cu")
		(net "RST_PEX_NIC6_PERST_R_N")
	)
	(segment
		(start 338.14639 -174.07001)
		(end 338.14639 -172.31741)
		(width 0.15494)
		(layer "In9.Cu")
		(net "RST_PEX_NIC6_PERST_R_N")
	)
	(segment
		(start 335.8388 -176.3776)
		(end 338.14639 -174.07001)
		(width 0.15494)
		(layer "In9.Cu")
		(net "RST_PEX_NIC6_PERST_R_N")
	)
	(segment
		(start 338.14639 -172.31741)
		(end 339.598 -170.8658)
		(width 0.15494)
		(layer "In9.Cu")
		(net "RST_PEX_NIC6_PERST_R_N")
	)
	(segment
		(start 334.137 -176.3776)
		(end 335.8388 -176.3776)
		(width 0.15494)
		(layer "In9.Cu")
		(net "RST_PEX_NIC6_PERST_R_N")
	)
	(segment
		(start 328.7776 -199.288146)
		(end 328.7776 -181.737)
		(width 0.15494)
		(layer "In9.Cu")
		(net "RST_PEX_NIC6_PERST_R_N")
	)
	(segment
		(start 337.694016 -218.787218)
		(end 336.85734 -219.623894)
		(width 0.15494)
		(layer "In9.Cu")
		(net "RST_PEX_NIC6_PERST_R_N")
	)
	(segment
		(start 325.755 -202.310746)
		(end 328.7776 -199.288146)
		(width 0.15494)
		(layer "In9.Cu")
		(net "RST_PEX_NIC6_PERST_R_N")
	)
	(segment
		(start 328.7776 -181.737)
		(end 334.137 -176.3776)
		(width 0.15494)
		(layer "In9.Cu")
		(net "RST_PEX_NIC6_PERST_R_N")
	)
	(segment
		(start 327.140316 -216.64168)
		(end 327.140316 -207.811116)
		(width 0.15494)
		(layer "In9.Cu")
		(net "RST_PEX_NIC6_PERST_R_N")
	)
	(segment
		(start 340.61146 -163.6522)
		(end 340.008718 -163.049458)
		(width 0.15494)
		(layer "In9.Cu")
		(net "RST_PEX_NIC6_PERST_R_N")
	)
	(segment
		(start 325.755 -206.4258)
		(end 325.755 -202.310746)
		(width 0.15494)
		(layer "In9.Cu")
		(net "RST_PEX_NIC6_PERST_R_N")
	)
	(segment
		(start 340.008718 -163.049458)
		(end 340.008718 -159.931862)
		(width 0.15494)
		(layer "In9.Cu")
		(net "RST_PEX_NIC6_PERST_R_N")
	)
	(segment
		(start 353.248214 -156.337)
		(end 350.849692 -156.337)
		(width 0.15494)
		(layer "In13.Cu")
		(net "RST_PEX_NIC6_PERST_R_N")
	)
	(segment
		(start 341.283544 -155.697174)
		(end 339.274658 -155.697174)
		(width 0.15494)
		(layer "In13.Cu")
		(net "RST_PEX_NIC6_PERST_R_N")
	)
	(segment
		(start 341.395304 -155.808934)
		(end 341.283544 -155.697174)
		(width 0.15494)
		(layer "In13.Cu")
		(net "RST_PEX_NIC6_PERST_R_N")
	)
	(segment
		(start 339.274658 -155.697174)
		(end 338.638896 -156.332936)
		(width 0.15494)
		(layer "In13.Cu")
		(net "RST_PEX_NIC6_PERST_R_N")
	)
	(segment
		(start 350.849692 -156.337)
		(end 350.321626 -155.808934)
		(width 0.15494)
		(layer "In13.Cu")
		(net "RST_PEX_NIC6_PERST_R_N")
	)
	(segment
		(start 350.321626 -155.808934)
		(end 341.395304 -155.808934)
		(width 0.15494)
		(layer "In13.Cu")
		(net "RST_PEX_NIC6_PERST_R_N")
	)
	(segment
		(start 352.632264 -154.305)
		(end 353.248214 -154.305)
		(width 0.13208)
		(layer "F.Cu")
		(net "PRSNT_NIC6_FPGA_R_N")
	)
	(segment
		(start 327.13295 -218.313)
		(end 326.517 -218.313)
		(width 0.13208)
		(layer "F.Cu")
		(net "PRSNT_NIC6_FPGA_R_N")
	)
	(via
		(at 353.248214 -154.305)
		(size 0.508)
		(drill 0.254)
		(layers "F.Cu" "B.Cu")
		(net "PRSNT_NIC6_FPGA_R_N")
	)
	(via
		(at 335.108042 -152.007316)
		(size 0.508)
		(drill 0.254)
		(layers "F.Cu" "B.Cu")
		(net "PRSNT_NIC6_FPGA_R_N")
	)
	(via
		(at 326.517 -218.313)
		(size 0.508)
		(drill 0.254)
		(layers "F.Cu" "B.Cu")
		(net "PRSNT_NIC6_FPGA_R_N")
	)
	(segment
		(start 322.478654 -201.190606)
		(end 322.184776 -204.543914)
		(width 0.15494)
		(layer "In9.Cu")
		(net "PRSNT_NIC6_FPGA_R_N")
	)
	(segment
		(start 325.914512 -217.710512)
		(end 326.517 -218.313)
		(width 0.15494)
		(layer "In9.Cu")
		(net "PRSNT_NIC6_FPGA_R_N")
	)
	(segment
		(start 323.34454 -200.027286)
		(end 323.344794 -200.02754)
		(width 0.15494)
		(layer "In9.Cu")
		(net "PRSNT_NIC6_FPGA_R_N")
	)
	(segment
		(start 322.184776 -213.471506)
		(end 323.342 -214.62873)
		(width 0.15494)
		(layer "In9.Cu")
		(net "PRSNT_NIC6_FPGA_R_N")
	)
	(segment
		(start 334.518 -152.597358)
		(end 334.518 -169.621454)
		(width 0.15494)
		(layer "In9.Cu")
		(net "PRSNT_NIC6_FPGA_R_N")
	)
	(segment
		(start 324.986142 -179.153312)
		(end 324.25132 -180.928518)
		(width 0.15494)
		(layer "In9.Cu")
		(net "PRSNT_NIC6_FPGA_R_N")
	)
	(segment
		(start 324.182232 -217.019886)
		(end 324.872858 -217.710512)
		(width 0.15494)
		(layer "In9.Cu")
		(net "PRSNT_NIC6_FPGA_R_N")
	)
	(segment
		(start 335.108042 -152.007316)
		(end 334.518 -152.597358)
		(width 0.15494)
		(layer "In9.Cu")
		(net "PRSNT_NIC6_FPGA_R_N")
	)
	(segment
		(start 323.342 -214.632794)
		(end 324.182232 -215.473026)
		(width 0.15494)
		(layer "In9.Cu")
		(net "PRSNT_NIC6_FPGA_R_N")
	)
	(segment
		(start 323.344794 -200.324466)
		(end 322.478654 -201.190606)
		(width 0.15494)
		(layer "In9.Cu")
		(net "PRSNT_NIC6_FPGA_R_N")
	)
	(segment
		(start 323.34708 -191.259206)
		(end 323.34708 -192.584832)
		(width 0.15494)
		(layer "In9.Cu")
		(net "PRSNT_NIC6_FPGA_R_N")
	)
	(segment
		(start 323.34708 -192.584832)
		(end 323.34454 -192.61201)
		(width 0.15494)
		(layer "In9.Cu")
		(net "PRSNT_NIC6_FPGA_R_N")
	)
	(segment
		(start 323.34454 -192.61201)
		(end 323.34454 -200.027286)
		(width 0.15494)
		(layer "In9.Cu")
		(net "PRSNT_NIC6_FPGA_R_N")
	)
	(segment
		(start 323.342 -214.62873)
		(end 323.342 -214.632794)
		(width 0.15494)
		(layer "In9.Cu")
		(net "PRSNT_NIC6_FPGA_R_N")
	)
	(segment
		(start 334.518 -169.621454)
		(end 324.986142 -179.153312)
		(width 0.15494)
		(layer "In9.Cu")
		(net "PRSNT_NIC6_FPGA_R_N")
	)
	(segment
		(start 322.184776 -204.543914)
		(end 322.184776 -213.471506)
		(width 0.15494)
		(layer "In9.Cu")
		(net "PRSNT_NIC6_FPGA_R_N")
	)
	(segment
		(start 323.344794 -200.02754)
		(end 323.344794 -200.324466)
		(width 0.15494)
		(layer "In9.Cu")
		(net "PRSNT_NIC6_FPGA_R_N")
	)
	(segment
		(start 324.182232 -215.473026)
		(end 324.182232 -217.019886)
		(width 0.15494)
		(layer "In9.Cu")
		(net "PRSNT_NIC6_FPGA_R_N")
	)
	(segment
		(start 324.872858 -217.710512)
		(end 325.914512 -217.710512)
		(width 0.15494)
		(layer "In9.Cu")
		(net "PRSNT_NIC6_FPGA_R_N")
	)
	(segment
		(start 324.25132 -180.928518)
		(end 323.34708 -191.259206)
		(width 0.15494)
		(layer "In9.Cu")
		(net "PRSNT_NIC6_FPGA_R_N")
	)
	(segment
		(start 350.95053 -152.007316)
		(end 353.248214 -154.305)
		(width 0.15494)
		(layer "In13.Cu")
		(net "PRSNT_NIC6_FPGA_R_N")
	)
	(segment
		(start 335.108042 -152.007316)
		(end 350.95053 -152.007316)
		(width 0.15494)
		(layer "In13.Cu")
		(net "PRSNT_NIC6_FPGA_R_N")
	)
	(segment
		(start 201.634598 -367.282984)
		(end 200.851516 -366.499902)
		(width 0.13208)
		(layer "F.Cu")
		(net "HSC_IMON")
	)
	(segment
		(start 225.245676 -368.876834)
		(end 225.914966 -368.207544)
		(width 0.13208)
		(layer "F.Cu")
		(net "HSC_IMON")
	)
	(segment
		(start 202.010518 -367.382044)
		(end 201.911458 -367.282984)
		(width 0.13208)
		(layer "F.Cu")
		(net "HSC_IMON")
	)
	(segment
		(start 198.964296 -362.567728)
		(end 198.964296 -363.583728)
		(width 0.13208)
		(layer "F.Cu")
		(net "HSC_IMON")
	)
	(segment
		(start 216.038176 -367.679986)
		(end 216.565734 -368.207544)
		(width 0.13208)
		(layer "F.Cu")
		(net "HSC_IMON")
	)
	(segment
		(start 216.565734 -368.207544)
		(end 217.388948 -368.207544)
		(width 0.13208)
		(layer "F.Cu")
		(net "HSC_IMON")
	)
	(segment
		(start 215.432132 -367.28908)
		(end 215.64727 -367.28908)
		(width 0.13208)
		(layer "F.Cu")
		(net "HSC_IMON")
	)
	(segment
		(start 225.245676 -368.976402)
		(end 225.245676 -368.876834)
		(width 0.13208)
		(layer "F.Cu")
		(net "HSC_IMON")
	)
	(segment
		(start 225.914966 -368.207544)
		(end 226.629976 -368.207544)
		(width 0.13208)
		(layer "F.Cu")
		(net "HSC_IMON")
	)
	(segment
		(start 214.711026 -368.010186)
		(end 215.432132 -367.28908)
		(width 0.13208)
		(layer "F.Cu")
		(net "HSC_IMON")
	)
	(segment
		(start 200.056242 -363.583728)
		(end 200.851516 -364.379002)
		(width 0.13208)
		(layer "F.Cu")
		(net "HSC_IMON")
	)
	(segment
		(start 201.911458 -367.282984)
		(end 201.634598 -367.282984)
		(width 0.13208)
		(layer "F.Cu")
		(net "HSC_IMON")
	)
	(segment
		(start 214.711026 -368.035586)
		(end 214.711026 -368.010186)
		(width 0.13208)
		(layer "F.Cu")
		(net "HSC_IMON")
	)
	(segment
		(start 200.851516 -364.379002)
		(end 200.851516 -366.115346)
		(width 0.13208)
		(layer "F.Cu")
		(net "HSC_IMON")
	)
	(segment
		(start 215.64727 -367.28908)
		(end 216.038176 -367.679986)
		(width 0.13208)
		(layer "F.Cu")
		(net "HSC_IMON")
	)
	(segment
		(start 200.851516 -366.499902)
		(end 200.851516 -366.115346)
		(width 0.13208)
		(layer "F.Cu")
		(net "HSC_IMON")
	)
	(segment
		(start 228.056948 -368.207544)
		(end 226.629976 -368.207544)
		(width 0.13208)
		(layer "F.Cu")
		(net "HSC_IMON")
	)
	(segment
		(start 198.964296 -363.583728)
		(end 200.056242 -363.583728)
		(width 0.13208)
		(layer "F.Cu")
		(net "HSC_IMON")
	)
	(segment
		(start 202.130914 -367.382044)
		(end 202.010518 -367.382044)
		(width 0.13208)
		(layer "F.Cu")
		(net "HSC_IMON")
	)
	(via
		(at 216.038176 -367.679986)
		(size 0.508)
		(drill 0.254)
		(layers "F.Cu" "B.Cu")
		(net "HSC_IMON")
	)
	(via
		(at 200.851516 -366.115346)
		(size 0.762)
		(drill 0.254)
		(layers "F.Cu" "B.Cu")
		(net "HSC_IMON")
	)
	(via
		(at 226.629976 -368.207544)
		(size 0.508)
		(drill 0.254)
		(layers "F.Cu" "B.Cu")
		(net "HSC_IMON")
	)
	(segment
		(start 224.888298 -362.480098)
		(end 224.888298 -366.834166)
		(width 0.15494)
		(layer "In7.Cu")
		(net "HSC_IMON")
	)
	(segment
		(start 201.929746 -366.649)
		(end 201.497946 -366.649)
		(width 0.15494)
		(layer "In7.Cu")
		(net "HSC_IMON")
	)
	(segment
		(start 200.964292 -366.115346)
		(end 200.851516 -366.115346)
		(width 0.15494)
		(layer "In7.Cu")
		(net "HSC_IMON")
	)
	(segment
		(start 202.313286 -366.26546)
		(end 201.929746 -366.649)
		(width 0.15494)
		(layer "In7.Cu")
		(net "HSC_IMON")
	)
	(segment
		(start 226.261676 -368.207544)
		(end 226.629976 -368.207544)
		(width 0.15494)
		(layer "In7.Cu")
		(net "HSC_IMON")
	)
	(segment
		(start 201.497946 -366.649)
		(end 200.964292 -366.115346)
		(width 0.15494)
		(layer "In7.Cu")
		(net "HSC_IMON")
	)
	(segment
		(start 217.7034 -360.934)
		(end 223.3422 -360.934)
		(width 0.15494)
		(layer "In7.Cu")
		(net "HSC_IMON")
	)
	(segment
		(start 223.3422 -360.934)
		(end 224.888298 -362.480098)
		(width 0.15494)
		(layer "In7.Cu")
		(net "HSC_IMON")
	)
	(segment
		(start 214.191342 -365.833152)
		(end 214.191342 -363.441742)
		(width 0.15494)
		(layer "In7.Cu")
		(net "HSC_IMON")
	)
	(segment
		(start 216.038176 -367.679986)
		(end 216.038176 -362.599224)
		(width 0.15494)
		(layer "In7.Cu")
		(net "HSC_IMON")
	)
	(segment
		(start 204.067156 -360.801666)
		(end 202.313286 -362.555536)
		(width 0.15494)
		(layer "In7.Cu")
		(net "HSC_IMON")
	)
	(segment
		(start 211.551266 -360.801666)
		(end 204.067156 -360.801666)
		(width 0.15494)
		(layer "In7.Cu")
		(net "HSC_IMON")
	)
	(segment
		(start 216.038176 -367.679986)
		(end 214.191342 -365.833152)
		(width 0.15494)
		(layer "In7.Cu")
		(net "HSC_IMON")
	)
	(segment
		(start 202.313286 -362.555536)
		(end 202.313286 -366.26546)
		(width 0.15494)
		(layer "In7.Cu")
		(net "HSC_IMON")
	)
	(segment
		(start 214.191342 -363.441742)
		(end 211.551266 -360.801666)
		(width 0.15494)
		(layer "In7.Cu")
		(net "HSC_IMON")
	)
	(segment
		(start 216.038176 -362.599224)
		(end 217.7034 -360.934)
		(width 0.15494)
		(layer "In7.Cu")
		(net "HSC_IMON")
	)
	(segment
		(start 224.888298 -366.834166)
		(end 226.261676 -368.207544)
		(width 0.15494)
		(layer "In7.Cu")
		(net "HSC_IMON")
	)
	(segment
		(start 224.040954 -209.169762)
		(end 224.58426 -208.626456)
		(width 0.13208)
		(layer "F.Cu")
		(net "RST_SMB_SSD_N")
	)
	(segment
		(start 225.467672 -213.104222)
		(end 225.467672 -211.907374)
		(width 0.0889)
		(layer "F.Cu")
		(net "RST_SMB_SSD_N")
	)
	(segment
		(start 223.498664 -207.42021)
		(end 223.498664 -207.466438)
		(width 0.13208)
		(layer "F.Cu")
		(net "RST_SMB_SSD_N")
	)
	(segment
		(start 224.040954 -210.480656)
		(end 224.040954 -209.169762)
		(width 0.13208)
		(layer "F.Cu")
		(net "RST_SMB_SSD_N")
	)
	(segment
		(start 224.58426 -208.552034)
		(end 224.58426 -208.626456)
		(width 0.13208)
		(layer "F.Cu")
		(net "RST_SMB_SSD_N")
	)
	(segment
		(start 225.467672 -211.907374)
		(end 224.040954 -210.480656)
		(width 0.13208)
		(layer "F.Cu")
		(net "RST_SMB_SSD_N")
	)
	(segment
		(start 225.867722 -213.504272)
		(end 225.467672 -213.104222)
		(width 0.0889)
		(layer "F.Cu")
		(net "RST_SMB_SSD_N")
	)
	(segment
		(start 223.498664 -207.466438)
		(end 224.58426 -208.552034)
		(width 0.13208)
		(layer "F.Cu")
		(net "RST_SMB_SSD_N")
	)
	(via
		(at 224.58426 -208.626456)
		(size 0.762)
		(drill 0.381)
		(layers "F.Cu" "B.Cu")
		(net "RST_SMB_SSD_N")
	)
	(segment
		(start 87.140542 -290.230052)
		(end 89.426542 -290.230052)
		(width 0.13208)
		(layer "F.Cu")
		(net "PWRGD_P1V8_PEX0_R")
	)
	(segment
		(start 89.589356 -290.28009)
		(end 89.54643 -290.237164)
		(width 0.13208)
		(layer "F.Cu")
		(net "PWRGD_P1V8_PEX0_R")
	)
	(segment
		(start 89.433654 -290.237164)
		(end 89.54643 -290.237164)
		(width 0.13208)
		(layer "F.Cu")
		(net "PWRGD_P1V8_PEX0_R")
	)
	(segment
		(start 89.589356 -291.297868)
		(end 89.589356 -290.28009)
		(width 0.13208)
		(layer "F.Cu")
		(net "PWRGD_P1V8_PEX0_R")
	)
	(segment
		(start 86.803992 -289.893502)
		(end 87.140542 -290.230052)
		(width 0.13208)
		(layer "F.Cu")
		(net "PWRGD_P1V8_PEX0_R")
	)
	(segment
		(start 86.803992 -289.630866)
		(end 86.803992 -289.893502)
		(width 0.13208)
		(layer "F.Cu")
		(net "PWRGD_P1V8_PEX0_R")
	)
	(segment
		(start 89.426542 -290.230052)
		(end 89.433654 -290.237164)
		(width 0.13208)
		(layer "F.Cu")
		(net "PWRGD_P1V8_PEX0_R")
	)
	(via
		(at 89.54643 -290.237164)
		(size 0.508)
		(drill 0.254)
		(layers "F.Cu" "B.Cu")
		(net "PWRGD_P1V8_PEX0_R")
	)
	(segment
		(start 439.651394 -311.004458)
		(end 439.247788 -311.408064)
		(width 0.13208)
		(layer "F.Cu")
		(net "PU_PEX3_SIO_BLINK")
	)
	(segment
		(start 439.651394 -310.761888)
		(end 439.651394 -311.004458)
		(width 0.13208)
		(layer "F.Cu")
		(net "PU_PEX3_SIO_BLINK")
	)
	(via
		(at 438.550812 -312.10504)
		(size 0.6604)
		(drill 0.3302)
		(layers "F.Cu" "B.Cu")
		(net "PU_PEX3_SIO_BLINK")
	)
	(via
		(at 408.899868 -309.199788)
		(size 0.4064)
		(drill 0.2032)
		(layers "F.Cu" "B.Cu")
		(net "PU_PEX3_SIO_BLINK")
	)
	(via
		(at 439.247788 -311.408064)
		(size 0.508)
		(drill 0.254)
		(layers "F.Cu" "B.Cu")
		(net "PU_PEX3_SIO_BLINK")
	)
	(segment
		(start 438.550812 -312.10504)
		(end 439.247788 -311.408064)
		(width 0.13208)
		(layer "B.Cu")
		(net "PU_PEX3_SIO_BLINK")
	)
	(segment
		(start 430.311052 -320.3448)
		(end 438.550812 -312.10504)
		(width 0.13208)
		(layer "B.Cu")
		(net "PU_PEX3_SIO_BLINK")
	)
	(segment
		(start 409.395422 -309.695342)
		(end 409.395422 -319.911476)
		(width 0.13208)
		(layer "B.Cu")
		(net "PU_PEX3_SIO_BLINK")
	)
	(segment
		(start 408.899868 -309.199788)
		(end 409.395422 -309.695342)
		(width 0.13208)
		(layer "B.Cu")
		(net "PU_PEX3_SIO_BLINK")
	)
	(segment
		(start 409.828746 -320.3448)
		(end 430.311052 -320.3448)
		(width 0.13208)
		(layer "B.Cu")
		(net "PU_PEX3_SIO_BLINK")
	)
	(segment
		(start 409.395422 -319.911476)
		(end 409.828746 -320.3448)
		(width 0.13208)
		(layer "B.Cu")
		(net "PU_PEX3_SIO_BLINK")
	)
	(segment
		(start 337.394804 -147.955)
		(end 337.058 -148.291804)
		(width 0.13208)
		(layer "F.Cu")
		(net "PRSNT_SSD14_FPGA_R_N")
	)
	(segment
		(start 327.13295 -219.329)
		(end 326.517 -219.329)
		(width 0.13208)
		(layer "F.Cu")
		(net "PRSNT_SSD14_FPGA_R_N")
	)
	(segment
		(start 337.67395 -147.955)
		(end 337.394804 -147.955)
		(width 0.13208)
		(layer "F.Cu")
		(net "PRSNT_SSD14_FPGA_R_N")
	)
	(via
		(at 337.058 -148.291804)
		(size 0.508)
		(drill 0.254)
		(layers "F.Cu" "B.Cu")
		(net "PRSNT_SSD14_FPGA_R_N")
	)
	(via
		(at 326.517 -219.329)
		(size 0.508)
		(drill 0.254)
		(layers "F.Cu" "B.Cu")
		(net "PRSNT_SSD14_FPGA_R_N")
	)
	(segment
		(start 322.9864 -200.17613)
		(end 322.133214 -201.02957)
		(width 0.15494)
		(layer "In9.Cu")
		(net "PRSNT_SSD14_FPGA_R_N")
	)
	(segment
		(start 322.133214 -201.02957)
		(end 321.826636 -204.528166)
		(width 0.15494)
		(layer "In9.Cu")
		(net "PRSNT_SSD14_FPGA_R_N")
	)
	(segment
		(start 322.98894 -191.243458)
		(end 322.98894 -192.56756)
		(width 0.15494)
		(layer "In9.Cu")
		(net "PRSNT_SSD14_FPGA_R_N")
	)
	(segment
		(start 334.137 -152.221946)
		(end 334.137 -169.44848)
		(width 0.15494)
		(layer "In9.Cu")
		(net "PRSNT_SSD14_FPGA_R_N")
	)
	(segment
		(start 324.8406 -218.872054)
		(end 326.060054 -218.872054)
		(width 0.15494)
		(layer "In9.Cu")
		(net "PRSNT_SSD14_FPGA_R_N")
	)
	(segment
		(start 334.98282 -151.376126)
		(end 334.137 -152.221946)
		(width 0.15494)
		(layer "In9.Cu")
		(net "PRSNT_SSD14_FPGA_R_N")
	)
	(segment
		(start 326.060054 -218.872054)
		(end 326.517 -219.329)
		(width 0.15494)
		(layer "In9.Cu")
		(net "PRSNT_SSD14_FPGA_R_N")
	)
	(segment
		(start 337.058 -148.291804)
		(end 337.058 -149.681946)
		(width 0.15494)
		(layer "In9.Cu")
		(net "PRSNT_SSD14_FPGA_R_N")
	)
	(segment
		(start 323.449442 -215.476836)
		(end 323.449442 -217.480896)
		(width 0.15494)
		(layer "In9.Cu")
		(net "PRSNT_SSD14_FPGA_R_N")
	)
	(segment
		(start 322.9864 -192.593976)
		(end 322.9864 -200.17613)
		(width 0.15494)
		(layer "In9.Cu")
		(net "PRSNT_SSD14_FPGA_R_N")
	)
	(segment
		(start 335.36382 -151.376126)
		(end 334.98282 -151.376126)
		(width 0.15494)
		(layer "In9.Cu")
		(net "PRSNT_SSD14_FPGA_R_N")
	)
	(segment
		(start 334.137 -169.44848)
		(end 324.715378 -178.870102)
		(width 0.15494)
		(layer "In9.Cu")
		(net "PRSNT_SSD14_FPGA_R_N")
	)
	(segment
		(start 321.826636 -204.528166)
		(end 321.826636 -213.85403)
		(width 0.15494)
		(layer "In9.Cu")
		(net "PRSNT_SSD14_FPGA_R_N")
	)
	(segment
		(start 324.715378 -178.870102)
		(end 323.899276 -180.841904)
		(width 0.15494)
		(layer "In9.Cu")
		(net "PRSNT_SSD14_FPGA_R_N")
	)
	(segment
		(start 337.058 -149.681946)
		(end 335.36382 -151.376126)
		(width 0.15494)
		(layer "In9.Cu")
		(net "PRSNT_SSD14_FPGA_R_N")
	)
	(segment
		(start 323.899276 -180.841904)
		(end 322.98894 -191.243458)
		(width 0.15494)
		(layer "In9.Cu")
		(net "PRSNT_SSD14_FPGA_R_N")
	)
	(segment
		(start 322.98894 -192.56756)
		(end 322.9864 -192.593976)
		(width 0.15494)
		(layer "In9.Cu")
		(net "PRSNT_SSD14_FPGA_R_N")
	)
	(segment
		(start 321.826636 -213.85403)
		(end 323.449442 -215.476836)
		(width 0.15494)
		(layer "In9.Cu")
		(net "PRSNT_SSD14_FPGA_R_N")
	)
	(segment
		(start 323.449442 -217.480896)
		(end 324.8406 -218.872054)
		(width 0.15494)
		(layer "In9.Cu")
		(net "PRSNT_SSD14_FPGA_R_N")
	)
	(segment
		(start 200.22185 -370.311426)
		(end 200.329292 -370.418868)
		(width 0.13208)
		(layer "F.Cu")
		(net "HSC_VTEMP")
	)
	(segment
		(start 228.056948 -370.20754)
		(end 227.391976 -370.20754)
		(width 0.13208)
		(layer "F.Cu")
		(net "HSC_VTEMP")
	)
	(segment
		(start 195.99529 -370.01323)
		(end 196.260212 -370.278152)
		(width 0.13208)
		(layer "F.Cu")
		(net "HSC_VTEMP")
	)
	(segment
		(start 198.520812 -370.348764)
		(end 199.03948 -370.867432)
		(width 0.13208)
		(layer "F.Cu")
		(net "HSC_VTEMP")
	)
	(segment
		(start 197.57263 -370.821712)
		(end 198.047864 -370.821712)
		(width 0.13208)
		(layer "F.Cu")
		(net "HSC_VTEMP")
	)
	(segment
		(start 201.63409 -370.418868)
		(end 201.970894 -370.082064)
		(width 0.13208)
		(layer "F.Cu")
		(net "HSC_VTEMP")
	)
	(segment
		(start 217.388948 -370.20754)
		(end 216.792556 -370.20754)
		(width 0.13208)
		(layer "F.Cu")
		(net "HSC_VTEMP")
	)
	(segment
		(start 196.260212 -370.278152)
		(end 197.57263 -370.821712)
		(width 0.13208)
		(layer "F.Cu")
		(net "HSC_VTEMP")
	)
	(segment
		(start 199.595486 -370.311426)
		(end 200.22185 -370.311426)
		(width 0.13208)
		(layer "F.Cu")
		(net "HSC_VTEMP")
	)
	(segment
		(start 201.970894 -370.082064)
		(end 202.130914 -370.082064)
		(width 0.13208)
		(layer "F.Cu")
		(net "HSC_VTEMP")
	)
	(segment
		(start 198.047864 -370.821712)
		(end 198.520812 -370.348764)
		(width 0.13208)
		(layer "F.Cu")
		(net "HSC_VTEMP")
	)
	(segment
		(start 200.329292 -370.418868)
		(end 201.63409 -370.418868)
		(width 0.13208)
		(layer "F.Cu")
		(net "HSC_VTEMP")
	)
	(segment
		(start 199.03948 -370.867432)
		(end 199.595486 -370.311426)
		(width 0.13208)
		(layer "F.Cu")
		(net "HSC_VTEMP")
	)
	(segment
		(start 195.99529 -369.39347)
		(end 195.99529 -370.01323)
		(width 0.13208)
		(layer "F.Cu")
		(net "HSC_VTEMP")
	)
	(via
		(at 216.792556 -370.20754)
		(size 0.508)
		(drill 0.254)
		(layers "F.Cu" "B.Cu")
		(net "HSC_VTEMP")
	)
	(via
		(at 227.391976 -370.20754)
		(size 0.508)
		(drill 0.254)
		(layers "F.Cu" "B.Cu")
		(net "HSC_VTEMP")
	)
	(via
		(at 199.03948 -370.867432)
		(size 0.508)
		(drill 0.254)
		(layers "F.Cu" "B.Cu")
		(net "HSC_VTEMP")
	)
	(segment
		(start 213.949026 -369.132612)
		(end 214.887302 -370.070888)
		(width 0.15494)
		(layer "In11.Cu")
		(net "HSC_VTEMP")
	)
	(segment
		(start 196.835268 -361.955334)
		(end 201.61631 -357.174292)
		(width 0.15494)
		(layer "In11.Cu")
		(net "HSC_VTEMP")
	)
	(segment
		(start 215.754458 -369.684554)
		(end 216.26957 -369.684554)
		(width 0.15494)
		(layer "In11.Cu")
		(net "HSC_VTEMP")
	)
	(segment
		(start 227.391976 -370.20754)
		(end 227.391976 -364.183422)
		(width 0.15494)
		(layer "In11.Cu")
		(net "HSC_VTEMP")
	)
	(segment
		(start 199.03948 -370.867432)
		(end 198.838312 -371.0686)
		(width 0.15494)
		(layer "In11.Cu")
		(net "HSC_VTEMP")
	)
	(segment
		(start 196.835268 -369.885468)
		(end 196.835268 -361.955334)
		(width 0.15494)
		(layer "In11.Cu")
		(net "HSC_VTEMP")
	)
	(segment
		(start 201.61631 -357.174292)
		(end 202.416664 -357.174292)
		(width 0.15494)
		(layer "In11.Cu")
		(net "HSC_VTEMP")
	)
	(segment
		(start 216.92489 -360.69778)
		(end 215.470486 -362.152184)
		(width 0.15494)
		(layer "In11.Cu")
		(net "HSC_VTEMP")
	)
	(segment
		(start 215.470486 -367.816384)
		(end 216.432384 -368.778282)
		(width 0.15494)
		(layer "In11.Cu")
		(net "HSC_VTEMP")
	)
	(segment
		(start 198.838312 -371.0686)
		(end 198.0184 -371.0686)
		(width 0.15494)
		(layer "In11.Cu")
		(net "HSC_VTEMP")
	)
	(segment
		(start 216.432384 -369.156742)
		(end 216.792556 -369.516914)
		(width 0.15494)
		(layer "In11.Cu")
		(net "HSC_VTEMP")
	)
	(segment
		(start 214.887302 -370.070888)
		(end 215.368124 -370.070888)
		(width 0.15494)
		(layer "In11.Cu")
		(net "HSC_VTEMP")
	)
	(segment
		(start 216.432384 -368.778282)
		(end 216.432384 -369.156742)
		(width 0.15494)
		(layer "In11.Cu")
		(net "HSC_VTEMP")
	)
	(segment
		(start 211.666582 -357.753412)
		(end 213.949026 -360.035856)
		(width 0.15494)
		(layer "In11.Cu")
		(net "HSC_VTEMP")
	)
	(segment
		(start 202.995784 -357.753412)
		(end 211.666582 -357.753412)
		(width 0.15494)
		(layer "In11.Cu")
		(net "HSC_VTEMP")
	)
	(segment
		(start 213.949026 -360.035856)
		(end 213.949026 -369.132612)
		(width 0.15494)
		(layer "In11.Cu")
		(net "HSC_VTEMP")
	)
	(segment
		(start 223.906334 -360.69778)
		(end 216.92489 -360.69778)
		(width 0.15494)
		(layer "In11.Cu")
		(net "HSC_VTEMP")
	)
	(segment
		(start 216.26957 -369.684554)
		(end 216.792556 -370.20754)
		(width 0.15494)
		(layer "In11.Cu")
		(net "HSC_VTEMP")
	)
	(segment
		(start 215.368124 -370.070888)
		(end 215.754458 -369.684554)
		(width 0.15494)
		(layer "In11.Cu")
		(net "HSC_VTEMP")
	)
	(segment
		(start 198.0184 -371.0686)
		(end 196.835268 -369.885468)
		(width 0.15494)
		(layer "In11.Cu")
		(net "HSC_VTEMP")
	)
	(segment
		(start 227.391976 -364.183422)
		(end 223.906334 -360.69778)
		(width 0.15494)
		(layer "In11.Cu")
		(net "HSC_VTEMP")
	)
	(segment
		(start 202.416664 -357.174292)
		(end 202.995784 -357.753412)
		(width 0.15494)
		(layer "In11.Cu")
		(net "HSC_VTEMP")
	)
	(segment
		(start 216.792556 -369.516914)
		(end 216.792556 -370.20754)
		(width 0.15494)
		(layer "In11.Cu")
		(net "HSC_VTEMP")
	)
	(segment
		(start 215.470486 -362.152184)
		(end 215.470486 -367.816384)
		(width 0.15494)
		(layer "In11.Cu")
		(net "HSC_VTEMP")
	)
	(segment
		(start 432.440842 -57.675272)
		(end 432.04003 -58.076084)
		(width 0.13208)
		(layer "F.Cu")
		(net "SSD15_AUX_P3V3_EN_R")
	)
	(segment
		(start 426.57776 -39.97198)
		(end 426.57776 -37.84092)
		(width 0.13208)
		(layer "F.Cu")
		(net "SSD15_AUX_P3V3_EN_R")
	)
	(segment
		(start 426.889926 -37.529516)
		(end 427.42612 -37.529516)
		(width 0.13208)
		(layer "F.Cu")
		(net "SSD15_AUX_P3V3_EN_R")
	)
	(segment
		(start 428.502572 -37.529516)
		(end 429.1838 -36.847272)
		(width 0.13208)
		(layer "F.Cu")
		(net "SSD15_AUX_P3V3_EN_R")
	)
	(segment
		(start 429.1838 -33.275778)
		(end 429.156114 -33.248092)
		(width 0.13208)
		(layer "F.Cu")
		(net "SSD15_AUX_P3V3_EN_R")
	)
	(segment
		(start 427.42612 -37.529516)
		(end 428.502572 -37.529516)
		(width 0.13208)
		(layer "F.Cu")
		(net "SSD15_AUX_P3V3_EN_R")
	)
	(segment
		(start 432.440842 -57.16397)
		(end 432.440842 -57.675272)
		(width 0.13208)
		(layer "F.Cu")
		(net "SSD15_AUX_P3V3_EN_R")
	)
	(segment
		(start 431.01514 -59.146186)
		(end 431.01514 -59.100974)
		(width 0.13208)
		(layer "F.Cu")
		(net "SSD15_AUX_P3V3_EN_R")
	)
	(segment
		(start 429.1838 -36.847272)
		(end 429.1838 -33.275778)
		(width 0.13208)
		(layer "F.Cu")
		(net "SSD15_AUX_P3V3_EN_R")
	)
	(segment
		(start 426.57776 -37.84092)
		(end 426.889926 -37.529516)
		(width 0.13208)
		(layer "F.Cu")
		(net "SSD15_AUX_P3V3_EN_R")
	)
	(segment
		(start 431.01514 -59.100974)
		(end 432.04003 -58.076084)
		(width 0.13208)
		(layer "F.Cu")
		(net "SSD15_AUX_P3V3_EN_R")
	)
	(via
		(at 426.57776 -39.97198)
		(size 0.508)
		(drill 0.254)
		(layers "F.Cu" "B.Cu")
		(net "SSD15_AUX_P3V3_EN_R")
	)
	(via
		(at 432.04003 -58.076084)
		(size 0.508)
		(drill 0.254)
		(layers "F.Cu" "B.Cu")
		(net "SSD15_AUX_P3V3_EN_R")
	)
	(segment
		(start 435.772814 -54.3433)
		(end 432.04003 -58.076084)
		(width 0.15494)
		(layer "In5.Cu")
		(net "SSD15_AUX_P3V3_EN_R")
	)
	(segment
		(start 429.750982 -39.97198)
		(end 435.772814 -45.993812)
		(width 0.15494)
		(layer "In5.Cu")
		(net "SSD15_AUX_P3V3_EN_R")
	)
	(segment
		(start 426.57776 -39.97198)
		(end 429.750982 -39.97198)
		(width 0.15494)
		(layer "In5.Cu")
		(net "SSD15_AUX_P3V3_EN_R")
	)
	(segment
		(start 435.772814 -45.993812)
		(end 435.772814 -54.3433)
		(width 0.15494)
		(layer "In5.Cu")
		(net "SSD15_AUX_P3V3_EN_R")
	)
	(segment
		(start 358.41305 -222.504)
		(end 359.029 -222.504)
		(width 0.13208)
		(layer "F.Cu")
		(net "RST_NIC4_PERST_R_N")
	)
	(segment
		(start 282.39339 -173.229524)
		(end 282.39339 -174.490634)
		(width 0.13208)
		(layer "F.Cu")
		(net "RST_NIC4_PERST_R_N")
	)
	(via
		(at 359.029 -222.504)
		(size 0.508)
		(drill 0.254)
		(layers "F.Cu" "B.Cu")
		(net "RST_NIC4_PERST_R_N")
	)
	(via
		(at 282.39339 -174.490634)
		(size 0.508)
		(drill 0.254)
		(layers "F.Cu" "B.Cu")
		(net "RST_NIC4_PERST_R_N")
	)
	(via
		(at 292.738048 -185.049922)
		(size 0.508)
		(drill 0.254)
		(layers "F.Cu" "B.Cu")
		(net "RST_NIC4_PERST_R_N")
	)
	(segment
		(start 292.738048 -183.847994)
		(end 292.738048 -185.049922)
		(width 0.15494)
		(layer "In9.Cu")
		(net "RST_NIC4_PERST_R_N")
	)
	(segment
		(start 283.380688 -174.490634)
		(end 292.738048 -183.847994)
		(width 0.15494)
		(layer "In9.Cu")
		(net "RST_NIC4_PERST_R_N")
	)
	(segment
		(start 282.39339 -174.490634)
		(end 283.380688 -174.490634)
		(width 0.15494)
		(layer "In9.Cu")
		(net "RST_NIC4_PERST_R_N")
	)
	(segment
		(start 348.097856 -187.132468)
		(end 352.8949 -187.132468)
		(width 0.15494)
		(layer "In15.Cu")
		(net "RST_NIC4_PERST_R_N")
	)
	(segment
		(start 361.04703 -219.193872)
		(end 359.837228 -222.115126)
		(width 0.15494)
		(layer "In15.Cu")
		(net "RST_NIC4_PERST_R_N")
	)
	(segment
		(start 346.488258 -185.52287)
		(end 348.097856 -187.132468)
		(width 0.15494)
		(layer "In15.Cu")
		(net "RST_NIC4_PERST_R_N")
	)
	(segment
		(start 292.738048 -185.049922)
		(end 334.352392 -185.049922)
		(width 0.15494)
		(layer "In15.Cu")
		(net "RST_NIC4_PERST_R_N")
	)
	(segment
		(start 357.19893 -196.486526)
		(end 361.04703 -200.334626)
		(width 0.15494)
		(layer "In15.Cu")
		(net "RST_NIC4_PERST_R_N")
	)
	(segment
		(start 352.8949 -187.132468)
		(end 357.19893 -191.436498)
		(width 0.15494)
		(layer "In15.Cu")
		(net "RST_NIC4_PERST_R_N")
	)
	(segment
		(start 334.352392 -185.049922)
		(end 334.82534 -185.52287)
		(width 0.15494)
		(layer "In15.Cu")
		(net "RST_NIC4_PERST_R_N")
	)
	(segment
		(start 334.82534 -185.52287)
		(end 346.488258 -185.52287)
		(width 0.15494)
		(layer "In15.Cu")
		(net "RST_NIC4_PERST_R_N")
	)
	(segment
		(start 359.837228 -222.115126)
		(end 359.448354 -222.504)
		(width 0.15494)
		(layer "In15.Cu")
		(net "RST_NIC4_PERST_R_N")
	)
	(segment
		(start 357.19893 -191.436498)
		(end 357.19893 -196.486526)
		(width 0.15494)
		(layer "In15.Cu")
		(net "RST_NIC4_PERST_R_N")
	)
	(segment
		(start 361.04703 -200.334626)
		(end 361.04703 -219.193872)
		(width 0.15494)
		(layer "In15.Cu")
		(net "RST_NIC4_PERST_R_N")
	)
	(segment
		(start 359.448354 -222.504)
		(end 359.029 -222.504)
		(width 0.15494)
		(layer "In15.Cu")
		(net "RST_NIC4_PERST_R_N")
	)
	(segment
		(start 327.00595 -220.345)
		(end 326.517 -220.345)
		(width 0.13208)
		(layer "F.Cu")
		(net "PRSNT_SSD15_FPGA_R_N")
	)
	(segment
		(start 337.67395 -143.891)
		(end 337.401408 -143.891)
		(width 0.13208)
		(layer "F.Cu")
		(net "PRSNT_SSD15_FPGA_R_N")
	)
	(segment
		(start 327.13295 -220.218)
		(end 327.00595 -220.345)
		(width 0.13208)
		(layer "F.Cu")
		(net "PRSNT_SSD15_FPGA_R_N")
	)
	(segment
		(start 337.401408 -143.891)
		(end 337.044284 -144.248124)
		(width 0.13208)
		(layer "F.Cu")
		(net "PRSNT_SSD15_FPGA_R_N")
	)
	(via
		(at 326.517 -220.345)
		(size 0.508)
		(drill 0.254)
		(layers "F.Cu" "B.Cu")
		(net "PRSNT_SSD15_FPGA_R_N")
	)
	(via
		(at 337.044284 -144.248124)
		(size 0.508)
		(drill 0.254)
		(layers "F.Cu" "B.Cu")
		(net "PRSNT_SSD15_FPGA_R_N")
	)
	(segment
		(start 334.705452 -150.9776)
		(end 333.7052 -151.977852)
		(width 0.15494)
		(layer "In9.Cu")
		(net "PRSNT_SSD15_FPGA_R_N")
	)
	(segment
		(start 325.2216 -220.345)
		(end 325.3232 -220.4466)
		(width 0.15494)
		(layer "In9.Cu")
		(net "PRSNT_SSD15_FPGA_R_N")
	)
	(segment
		(start 324.566788 -220.345)
		(end 325.2216 -220.345)
		(width 0.15494)
		(layer "In9.Cu")
		(net "PRSNT_SSD15_FPGA_R_N")
	)
	(segment
		(start 333.7052 -169.3418)
		(end 324.375526 -178.671474)
		(width 0.15494)
		(layer "In9.Cu")
		(net "PRSNT_SSD15_FPGA_R_N")
	)
	(segment
		(start 322.62826 -200.02754)
		(end 321.78752 -200.86828)
		(width 0.15494)
		(layer "In9.Cu")
		(net "PRSNT_SSD15_FPGA_R_N")
	)
	(segment
		(start 337.334098 -144.248124)
		(end 337.670648 -144.584674)
		(width 0.15494)
		(layer "In9.Cu")
		(net "PRSNT_SSD15_FPGA_R_N")
	)
	(segment
		(start 322.62826 -192.575942)
		(end 322.62826 -200.02754)
		(width 0.15494)
		(layer "In9.Cu")
		(net "PRSNT_SSD15_FPGA_R_N")
	)
	(segment
		(start 333.7052 -151.977852)
		(end 333.7052 -169.3418)
		(width 0.15494)
		(layer "In9.Cu")
		(net "PRSNT_SSD15_FPGA_R_N")
	)
	(segment
		(start 337.370166 -147.620228)
		(end 336.859372 -147.620228)
		(width 0.15494)
		(layer "In9.Cu")
		(net "PRSNT_SSD15_FPGA_R_N")
	)
	(segment
		(start 324.375526 -178.671474)
		(end 323.556376 -180.648864)
		(width 0.15494)
		(layer "In9.Cu")
		(net "PRSNT_SSD15_FPGA_R_N")
	)
	(segment
		(start 323.556376 -180.648864)
		(end 322.6308 -191.22771)
		(width 0.15494)
		(layer "In9.Cu")
		(net "PRSNT_SSD15_FPGA_R_N")
	)
	(segment
		(start 335.2292 -150.9776)
		(end 334.705452 -150.9776)
		(width 0.15494)
		(layer "In9.Cu")
		(net "PRSNT_SSD15_FPGA_R_N")
	)
	(segment
		(start 321.468496 -204.512418)
		(end 321.468496 -219.34551)
		(width 0.15494)
		(layer "In9.Cu")
		(net "PRSNT_SSD15_FPGA_R_N")
	)
	(segment
		(start 325.3232 -220.4466)
		(end 325.9328 -220.4466)
		(width 0.15494)
		(layer "In9.Cu")
		(net "PRSNT_SSD15_FPGA_R_N")
	)
	(segment
		(start 336.397854 -149.808946)
		(end 335.2292 -150.9776)
		(width 0.15494)
		(layer "In9.Cu")
		(net "PRSNT_SSD15_FPGA_R_N")
	)
	(segment
		(start 325.9328 -220.4466)
		(end 326.0344 -220.345)
		(width 0.15494)
		(layer "In9.Cu")
		(net "PRSNT_SSD15_FPGA_R_N")
	)
	(segment
		(start 322.6308 -192.550034)
		(end 322.62826 -192.575942)
		(width 0.15494)
		(layer "In9.Cu")
		(net "PRSNT_SSD15_FPGA_R_N")
	)
	(segment
		(start 322.6308 -191.22771)
		(end 322.6308 -192.550034)
		(width 0.15494)
		(layer "In9.Cu")
		(net "PRSNT_SSD15_FPGA_R_N")
	)
	(segment
		(start 324.108064 -220.803724)
		(end 324.566788 -220.345)
		(width 0.15494)
		(layer "In9.Cu")
		(net "PRSNT_SSD15_FPGA_R_N")
	)
	(segment
		(start 321.78752 -200.86828)
		(end 321.468496 -204.512418)
		(width 0.15494)
		(layer "In9.Cu")
		(net "PRSNT_SSD15_FPGA_R_N")
	)
	(segment
		(start 337.670648 -147.319746)
		(end 337.370166 -147.620228)
		(width 0.15494)
		(layer "In9.Cu")
		(net "PRSNT_SSD15_FPGA_R_N")
	)
	(segment
		(start 337.670648 -144.584674)
		(end 337.670648 -147.319746)
		(width 0.15494)
		(layer "In9.Cu")
		(net "PRSNT_SSD15_FPGA_R_N")
	)
	(segment
		(start 321.468496 -219.34551)
		(end 322.92671 -220.803724)
		(width 0.15494)
		(layer "In9.Cu")
		(net "PRSNT_SSD15_FPGA_R_N")
	)
	(segment
		(start 326.0344 -220.345)
		(end 326.517 -220.345)
		(width 0.15494)
		(layer "In9.Cu")
		(net "PRSNT_SSD15_FPGA_R_N")
	)
	(segment
		(start 336.397854 -148.081746)
		(end 336.397854 -149.808946)
		(width 0.15494)
		(layer "In9.Cu")
		(net "PRSNT_SSD15_FPGA_R_N")
	)
	(segment
		(start 336.859372 -147.620228)
		(end 336.397854 -148.081746)
		(width 0.15494)
		(layer "In9.Cu")
		(net "PRSNT_SSD15_FPGA_R_N")
	)
	(segment
		(start 322.92671 -220.803724)
		(end 324.108064 -220.803724)
		(width 0.15494)
		(layer "In9.Cu")
		(net "PRSNT_SSD15_FPGA_R_N")
	)
	(segment
		(start 337.044284 -144.248124)
		(end 337.334098 -144.248124)
		(width 0.15494)
		(layer "In9.Cu")
		(net "PRSNT_SSD15_FPGA_R_N")
	)
	(segment
		(start 222.249238 -372.900448)
		(end 223.073976 -373.725186)
		(width 0.13208)
		(layer "F.Cu")
		(net "HSC_MODE_1")
	)
	(segment
		(start 224.451926 -374.106186)
		(end 223.454976 -374.106186)
		(width 0.13208)
		(layer "F.Cu")
		(net "HSC_MODE_1")
	)
	(segment
		(start 221.87662 -370.707666)
		(end 222.104204 -370.707666)
		(width 0.13208)
		(layer "F.Cu")
		(net "HSC_MODE_1")
	)
	(segment
		(start 222.249238 -370.8527)
		(end 222.249238 -372.900448)
		(width 0.13208)
		(layer "F.Cu")
		(net "HSC_MODE_1")
	)
	(segment
		(start 222.104204 -370.707666)
		(end 222.249238 -370.8527)
		(width 0.13208)
		(layer "F.Cu")
		(net "HSC_MODE_1")
	)
	(segment
		(start 223.454976 -374.106186)
		(end 223.073976 -373.725186)
		(width 0.13208)
		(layer "F.Cu")
		(net "HSC_MODE_1")
	)
	(via
		(at 223.073976 -373.725186)
		(size 0.762)
		(drill 0.381)
		(layers "F.Cu" "B.Cu")
		(net "HSC_MODE_1")
	)
	(segment
		(start 327.13295 -210.185)
		(end 326.517 -210.185)
		(width 0.13208)
		(layer "F.Cu")
		(net "PRSNT_SSD12_FPGA_R_N")
	)
	(segment
		(start 337.67395 -159.766)
		(end 337.058 -159.766)
		(width 0.13208)
		(layer "F.Cu")
		(net "PRSNT_SSD12_FPGA_R_N")
	)
	(via
		(at 326.517 -210.185)
		(size 0.508)
		(drill 0.254)
		(layers "F.Cu" "B.Cu")
		(net "PRSNT_SSD12_FPGA_R_N")
	)
	(via
		(at 337.058 -159.766)
		(size 0.508)
		(drill 0.254)
		(layers "F.Cu" "B.Cu")
		(net "PRSNT_SSD12_FPGA_R_N")
	)
	(segment
		(start 334.39354 -175.91786)
		(end 337.68665 -172.62475)
		(width 0.15494)
		(layer "In9.Cu")
		(net "PRSNT_SSD12_FPGA_R_N")
	)
	(segment
		(start 338.60613 -161.31413)
		(end 337.058 -159.766)
		(width 0.15494)
		(layer "In9.Cu")
		(net "PRSNT_SSD12_FPGA_R_N")
	)
	(segment
		(start 325.2724 -207.949546)
		(end 325.2724 -202.1078)
		(width 0.15494)
		(layer "In9.Cu")
		(net "PRSNT_SSD12_FPGA_R_N")
	)
	(segment
		(start 333.91094 -175.91786)
		(end 334.39354 -175.91786)
		(width 0.15494)
		(layer "In9.Cu")
		(net "PRSNT_SSD12_FPGA_R_N")
	)
	(segment
		(start 326.517 -210.185)
		(end 326.517 -209.194146)
		(width 0.15494)
		(layer "In9.Cu")
		(net "PRSNT_SSD12_FPGA_R_N")
	)
	(segment
		(start 328.295 -195.0212)
		(end 328.295 -181.5338)
		(width 0.15494)
		(layer "In9.Cu")
		(net "PRSNT_SSD12_FPGA_R_N")
	)
	(segment
		(start 338.60613 -171.20743)
		(end 338.60613 -161.31413)
		(width 0.15494)
		(layer "In9.Cu")
		(net "PRSNT_SSD12_FPGA_R_N")
	)
	(segment
		(start 328.295 -181.5338)
		(end 333.91094 -175.91786)
		(width 0.15494)
		(layer "In9.Cu")
		(net "PRSNT_SSD12_FPGA_R_N")
	)
	(segment
		(start 327.5584 -199.8218)
		(end 327.5584 -195.7578)
		(width 0.15494)
		(layer "In9.Cu")
		(net "PRSNT_SSD12_FPGA_R_N")
	)
	(segment
		(start 337.68665 -172.12691)
		(end 338.60613 -171.20743)
		(width 0.15494)
		(layer "In9.Cu")
		(net "PRSNT_SSD12_FPGA_R_N")
	)
	(segment
		(start 325.2724 -202.1078)
		(end 327.5584 -199.8218)
		(width 0.15494)
		(layer "In9.Cu")
		(net "PRSNT_SSD12_FPGA_R_N")
	)
	(segment
		(start 327.5584 -195.7578)
		(end 328.295 -195.0212)
		(width 0.15494)
		(layer "In9.Cu")
		(net "PRSNT_SSD12_FPGA_R_N")
	)
	(segment
		(start 337.68665 -172.62475)
		(end 337.68665 -172.12691)
		(width 0.15494)
		(layer "In9.Cu")
		(net "PRSNT_SSD12_FPGA_R_N")
	)
	(segment
		(start 326.517 -209.194146)
		(end 325.2724 -207.949546)
		(width 0.15494)
		(layer "In9.Cu")
		(net "PRSNT_SSD12_FPGA_R_N")
	)
	(segment
		(start 232.692448 -369.707668)
		(end 232.53192 -369.707668)
		(width 0.13208)
		(layer "F.Cu")
		(net "HSC_FLT_TYPE_2")
	)
	(segment
		(start 232.969816 -369.985036)
		(end 232.692448 -369.707668)
		(width 0.13208)
		(layer "F.Cu")
		(net "HSC_FLT_TYPE_2")
	)
	(segment
		(start 233.560112 -370.926868)
		(end 232.969816 -370.336572)
		(width 0.13208)
		(layer "F.Cu")
		(net "HSC_FLT_TYPE_2")
	)
	(segment
		(start 234.093766 -372.8974)
		(end 234.093766 -371.66169)
		(width 0.13208)
		(layer "F.Cu")
		(net "HSC_FLT_TYPE_2")
	)
	(segment
		(start 234.093766 -371.66169)
		(end 233.560112 -371.128036)
		(width 0.13208)
		(layer "F.Cu")
		(net "HSC_FLT_TYPE_2")
	)
	(segment
		(start 232.969816 -370.336572)
		(end 232.969816 -369.985036)
		(width 0.13208)
		(layer "F.Cu")
		(net "HSC_FLT_TYPE_2")
	)
	(segment
		(start 233.560112 -371.128036)
		(end 233.560112 -370.926868)
		(width 0.13208)
		(layer "F.Cu")
		(net "HSC_FLT_TYPE_2")
	)
	(via
		(at 234.093766 -371.66169)
		(size 0.762)
		(drill 0.381)
		(layers "F.Cu" "B.Cu")
		(net "HSC_FLT_TYPE_2")
	)
	(segment
		(start 225.011488 -205.097634)
		(end 224.755964 -204.84211)
		(width 0.13208)
		(layer "F.Cu")
		(net "RST_SMB_NIC_MUX_N")
	)
	(segment
		(start 225.591116 -210.799934)
		(end 225.591116 -210.223608)
		(width 0.13208)
		(layer "F.Cu")
		(net "RST_SMB_NIC_MUX_N")
	)
	(segment
		(start 225.011488 -207.595216)
		(end 225.011488 -205.097634)
		(width 0.13208)
		(layer "F.Cu")
		(net "RST_SMB_NIC_MUX_N")
	)
	(segment
		(start 226.667568 -213.504272)
		(end 226.267518 -213.104222)
		(width 0.0889)
		(layer "F.Cu")
		(net "RST_SMB_NIC_MUX_N")
	)
	(segment
		(start 224.755964 -204.84211)
		(end 224.514664 -204.84211)
		(width 0.13208)
		(layer "F.Cu")
		(net "RST_SMB_NIC_MUX_N")
	)
	(segment
		(start 225.822002 -209.992722)
		(end 225.822002 -208.658714)
		(width 0.13208)
		(layer "F.Cu")
		(net "RST_SMB_NIC_MUX_N")
	)
	(segment
		(start 226.3902 -211.842604)
		(end 226.3902 -211.599018)
		(width 0.13208)
		(layer "F.Cu")
		(net "RST_SMB_NIC_MUX_N")
	)
	(segment
		(start 226.267518 -213.104222)
		(end 226.267518 -212.139022)
		(width 0.0889)
		(layer "F.Cu")
		(net "RST_SMB_NIC_MUX_N")
	)
	(segment
		(start 226.267518 -212.139022)
		(end 226.3902 -211.842604)
		(width 0.13208)
		(layer "F.Cu")
		(net "RST_SMB_NIC_MUX_N")
	)
	(segment
		(start 225.72091 -208.304638)
		(end 225.011488 -207.595216)
		(width 0.13208)
		(layer "F.Cu")
		(net "RST_SMB_NIC_MUX_N")
	)
	(segment
		(start 225.591116 -210.223608)
		(end 225.822002 -209.992722)
		(width 0.13208)
		(layer "F.Cu")
		(net "RST_SMB_NIC_MUX_N")
	)
	(segment
		(start 225.822002 -208.658714)
		(end 225.85426 -208.626456)
		(width 0.13208)
		(layer "F.Cu")
		(net "RST_SMB_NIC_MUX_N")
	)
	(segment
		(start 225.85426 -208.626456)
		(end 225.72091 -208.304638)
		(width 0.13208)
		(layer "F.Cu")
		(net "RST_SMB_NIC_MUX_N")
	)
	(segment
		(start 226.3902 -211.599018)
		(end 225.591116 -210.799934)
		(width 0.13208)
		(layer "F.Cu")
		(net "RST_SMB_NIC_MUX_N")
	)
	(via
		(at 225.85426 -208.626456)
		(size 0.762)
		(drill 0.381)
		(layers "F.Cu" "B.Cu")
		(net "RST_SMB_NIC_MUX_N")
	)
	(segment
		(start 428.680118 -39.33571)
		(end 427.42612 -39.33571)
		(width 0.13208)
		(layer "F.Cu")
		(net "SSD15_AUX_P3V3_EN")
	)
	(segment
		(start 431.147728 -40.185086)
		(end 431.020728 -40.058086)
		(width 0.13208)
		(layer "F.Cu")
		(net "SSD15_AUX_P3V3_EN")
	)
	(segment
		(start 427.42612 -38.329616)
		(end 427.42612 -39.33571)
		(width 0.13208)
		(layer "F.Cu")
		(net "SSD15_AUX_P3V3_EN")
	)
	(segment
		(start 431.020728 -40.058086)
		(end 429.402494 -40.058086)
		(width 0.13208)
		(layer "F.Cu")
		(net "SSD15_AUX_P3V3_EN")
	)
	(segment
		(start 429.402494 -40.058086)
		(end 428.680118 -39.33571)
		(width 0.13208)
		(layer "F.Cu")
		(net "SSD15_AUX_P3V3_EN")
	)
	(segment
		(start 431.147728 -41.137332)
		(end 431.147728 -40.185086)
		(width 0.13208)
		(layer "F.Cu")
		(net "SSD15_AUX_P3V3_EN")
	)
	(via
		(at 428.680118 -39.33571)
		(size 0.762)
		(drill 0.381)
		(layers "F.Cu" "B.Cu")
		(net "SSD15_AUX_P3V3_EN")
	)
	(segment
		(start 226.724464 -367.415318)
		(end 227.016818 -367.707672)
		(width 0.13208)
		(layer "F.Cu")
		(net "HSC_CS_2")
	)
	(segment
		(start 225.252026 -368.010186)
		(end 225.67011 -368.010186)
		(width 0.13208)
		(layer "F.Cu")
		(net "HSC_CS_2")
	)
	(segment
		(start 225.67011 -368.010186)
		(end 226.264978 -367.415318)
		(width 0.13208)
		(layer "F.Cu")
		(net "HSC_CS_2")
	)
	(segment
		(start 226.264978 -367.415318)
		(end 226.724464 -367.415318)
		(width 0.13208)
		(layer "F.Cu")
		(net "HSC_CS_2")
	)
	(segment
		(start 227.016818 -367.707672)
		(end 228.056948 -367.707672)
		(width 0.13208)
		(layer "F.Cu")
		(net "HSC_CS_2")
	)
	(via
		(at 226.724464 -367.415318)
		(size 0.762)
		(drill 0.381)
		(layers "F.Cu" "B.Cu")
		(net "HSC_CS_2")
	)
	(segment
		(start 432.14671 -37.774118)
		(end 432.693572 -37.774118)
		(width 0.13208)
		(layer "F.Cu")
		(net "PRSNT_SSD15_R1_N")
	)
	(segment
		(start 430.197768 -38.16731)
		(end 430.59096 -37.774118)
		(width 0.13208)
		(layer "F.Cu")
		(net "PRSNT_SSD15_R1_N")
	)
	(segment
		(start 430.197768 -38.937184)
		(end 430.197768 -38.16731)
		(width 0.13208)
		(layer "F.Cu")
		(net "PRSNT_SSD15_R1_N")
	)
	(segment
		(start 432.87569 -37.592)
		(end 432.87569 -37.315648)
		(width 0.13208)
		(layer "F.Cu")
		(net "PRSNT_SSD15_R1_N")
	)
	(segment
		(start 432.693572 -37.774118)
		(end 432.87569 -37.592)
		(width 0.13208)
		(layer "F.Cu")
		(net "PRSNT_SSD15_R1_N")
	)
	(segment
		(start 430.59096 -37.774118)
		(end 432.14671 -37.774118)
		(width 0.13208)
		(layer "F.Cu")
		(net "PRSNT_SSD15_R1_N")
	)
	(via
		(at 432.14671 -37.774118)
		(size 0.508)
		(drill 0.254)
		(layers "F.Cu" "B.Cu")
		(net "PRSNT_SSD15_R1_N")
	)
	(segment
		(start 204.991716 -356.811326)
		(end 204.382116 -356.811326)
		(width 0.254)
		(layer "F.Cu")
		(net "HSC_D_OC")
	)
	(segment
		(start 225.252026 -366.994186)
		(end 225.867976 -366.994186)
		(width 0.13208)
		(layer "F.Cu")
		(net "HSC_D_OC")
	)
	(segment
		(start 209.855816 -365.935006)
		(end 209.23123 -366.559592)
		(width 0.13208)
		(layer "F.Cu")
		(net "HSC_D_OC")
	)
	(segment
		(start 208.816194 -368.28222)
		(end 208.605882 -368.28222)
		(width 0.13208)
		(layer "F.Cu")
		(net "HSC_D_OC")
	)
	(segment
		(start 235.05541 -368.182144)
		(end 234.333034 -367.459768)
		(width 0.13208)
		(layer "F.Cu")
		(net "HSC_D_OC")
	)
	(segment
		(start 209.23123 -367.867184)
		(end 208.816194 -368.28222)
		(width 0.13208)
		(layer "F.Cu")
		(net "HSC_D_OC")
	)
	(segment
		(start 211.066126 -365.935006)
		(end 209.855816 -365.935006)
		(width 0.13208)
		(layer "F.Cu")
		(net "HSC_D_OC")
	)
	(segment
		(start 211.106766 -365.975646)
		(end 211.066126 -365.935006)
		(width 0.13208)
		(layer "F.Cu")
		(net "HSC_D_OC")
	)
	(segment
		(start 234.333034 -367.459768)
		(end 234.060492 -367.459768)
		(width 0.13208)
		(layer "F.Cu")
		(net "HSC_D_OC")
	)
	(segment
		(start 209.23123 -366.559592)
		(end 209.23123 -367.867184)
		(width 0.13208)
		(layer "F.Cu")
		(net "HSC_D_OC")
	)
	(via
		(at 204.382116 -356.811326)
		(size 0.508)
		(drill 0.254)
		(layers "F.Cu" "B.Cu")
		(net "HSC_D_OC")
	)
	(via
		(at 234.060492 -367.459768)
		(size 0.508)
		(drill 0.254)
		(layers "F.Cu" "B.Cu")
		(net "HSC_D_OC")
	)
	(via
		(at 209.855816 -365.935006)
		(size 0.508)
		(drill 0.254)
		(layers "F.Cu" "B.Cu")
		(net "HSC_D_OC")
	)
	(via
		(at 225.867976 -366.994186)
		(size 0.508)
		(drill 0.254)
		(layers "F.Cu" "B.Cu")
		(net "HSC_D_OC")
	)
	(segment
		(start 213.291674 -360.661712)
		(end 211.804758 -362.148628)
		(width 0.13208)
		(layer "B.Cu")
		(net "HSC_D_OC")
	)
	(segment
		(start 225.867976 -362.598208)
		(end 228.024944 -360.44124)
		(width 0.13208)
		(layer "B.Cu")
		(net "HSC_D_OC")
	)
	(segment
		(start 208.67878 -361.10799)
		(end 204.382116 -356.811326)
		(width 0.13208)
		(layer "B.Cu")
		(net "HSC_D_OC")
	)
	(segment
		(start 222.68307 -360.661712)
		(end 213.291674 -360.661712)
		(width 0.13208)
		(layer "B.Cu")
		(net "HSC_D_OC")
	)
	(segment
		(start 232.726484 -360.44124)
		(end 234.027726 -361.742482)
		(width 0.13208)
		(layer "B.Cu")
		(net "HSC_D_OC")
	)
	(segment
		(start 223.575118 -361.55376)
		(end 222.68307 -360.661712)
		(width 0.13208)
		(layer "B.Cu")
		(net "HSC_D_OC")
	)
	(segment
		(start 211.203032 -365.935006)
		(end 209.855816 -365.935006)
		(width 0.13208)
		(layer "B.Cu")
		(net "HSC_D_OC")
	)
	(segment
		(start 223.575118 -364.701328)
		(end 223.575118 -361.55376)
		(width 0.13208)
		(layer "B.Cu")
		(net "HSC_D_OC")
	)
	(segment
		(start 225.867976 -366.994186)
		(end 223.575118 -364.701328)
		(width 0.13208)
		(layer "B.Cu")
		(net "HSC_D_OC")
	)
	(segment
		(start 210.76412 -361.10799)
		(end 208.67878 -361.10799)
		(width 0.13208)
		(layer "B.Cu")
		(net "HSC_D_OC")
	)
	(segment
		(start 234.027726 -367.427002)
		(end 234.060492 -367.459768)
		(width 0.13208)
		(layer "B.Cu")
		(net "HSC_D_OC")
	)
	(segment
		(start 211.804758 -365.33328)
		(end 211.203032 -365.935006)
		(width 0.13208)
		(layer "B.Cu")
		(net "HSC_D_OC")
	)
	(segment
		(start 211.804758 -362.148628)
		(end 210.76412 -361.10799)
		(width 0.13208)
		(layer "B.Cu")
		(net "HSC_D_OC")
	)
	(segment
		(start 211.804758 -362.148628)
		(end 211.804758 -365.33328)
		(width 0.13208)
		(layer "B.Cu")
		(net "HSC_D_OC")
	)
	(segment
		(start 228.024944 -360.44124)
		(end 232.726484 -360.44124)
		(width 0.13208)
		(layer "B.Cu")
		(net "HSC_D_OC")
	)
	(segment
		(start 234.027726 -361.742482)
		(end 234.027726 -367.427002)
		(width 0.13208)
		(layer "B.Cu")
		(net "HSC_D_OC")
	)
	(segment
		(start 225.867976 -366.994186)
		(end 225.867976 -362.598208)
		(width 0.13208)
		(layer "B.Cu")
		(net "HSC_D_OC")
	)
	(segment
		(start 276.073616 -405.474424)
		(end 276.073616 -406.147016)
		(width 0.13208)
		(layer "F.Cu")
		(net "BIC_SYS_READY_R2_N")
	)
	(segment
		(start 342.893904 -223.987106)
		(end 343.2937 -224.386902)
		(width 0.13208)
		(layer "F.Cu")
		(net "BIC_SYS_READY_R2_N")
	)
	(via
		(at 210.823556 -211.593684)
		(size 0.508)
		(drill 0.254)
		(layers "F.Cu" "B.Cu")
		(net "BIC_SYS_READY_R2_N")
	)
	(via
		(at 331.560424 -229.259638)
		(size 0.508)
		(drill 0.254)
		(layers "F.Cu" "B.Cu")
		(net "BIC_SYS_READY_R2_N")
	)
	(via
		(at 247.64619 -327.9013)
		(size 0.508)
		(drill 0.254)
		(layers "F.Cu" "B.Cu")
		(net "BIC_SYS_READY_R2_N")
	)
	(via
		(at 276.073616 -406.147016)
		(size 0.508)
		(drill 0.254)
		(layers "F.Cu" "B.Cu")
		(net "BIC_SYS_READY_R2_N")
	)
	(via
		(at 343.2937 -224.386902)
		(size 0.4572)
		(drill 0.254)
		(layers "F.Cu" "B.Cu")
		(net "BIC_SYS_READY_R2_N")
	)
	(segment
		(start 216.523824 -227.708968)
		(end 216.056464 -228.176328)
		(width 0.13208)
		(layer "B.Cu")
		(net "BIC_SYS_READY_R2_N")
	)
	(segment
		(start 249.79376 -264.717022)
		(end 249.79376 -255.470406)
		(width 0.13208)
		(layer "B.Cu")
		(net "BIC_SYS_READY_R2_N")
	)
	(segment
		(start 249.558048 -327.005696)
		(end 258.865878 -304.533808)
		(width 0.13208)
		(layer "B.Cu")
		(net "BIC_SYS_READY_R2_N")
	)
	(segment
		(start 236.334554 -236.379258)
		(end 224.175828 -236.379258)
		(width 0.13208)
		(layer "B.Cu")
		(net "BIC_SYS_READY_R2_N")
	)
	(segment
		(start 207.522572 -228.314758)
		(end 205.831186 -226.623372)
		(width 0.13208)
		(layer "B.Cu")
		(net "BIC_SYS_READY_R2_N")
	)
	(segment
		(start 220.671136 -232.874566)
		(end 220.671136 -229.882192)
		(width 0.13208)
		(layer "B.Cu")
		(net "BIC_SYS_READY_R2_N")
	)
	(segment
		(start 211.470748 -227.67036)
		(end 210.608672 -227.67036)
		(width 0.13208)
		(layer "B.Cu")
		(net "BIC_SYS_READY_R2_N")
	)
	(segment
		(start 208.890108 -228.74097)
		(end 208.463896 -228.314758)
		(width 0.13208)
		(layer "B.Cu")
		(net "BIC_SYS_READY_R2_N")
	)
	(segment
		(start 210.086448 -228.382068)
		(end 209.727546 -228.74097)
		(width 0.13208)
		(layer "B.Cu")
		(net "BIC_SYS_READY_R2_N")
	)
	(segment
		(start 210.086448 -228.192584)
		(end 210.086448 -228.382068)
		(width 0.13208)
		(layer "B.Cu")
		(net "BIC_SYS_READY_R2_N")
	)
	(segment
		(start 217.43797 -227.621338)
		(end 217.35034 -227.708968)
		(width 0.13208)
		(layer "B.Cu")
		(net "BIC_SYS_READY_R2_N")
	)
	(segment
		(start 208.261204 -214.564976)
		(end 208.261204 -212.914484)
		(width 0.13208)
		(layer "B.Cu")
		(net "BIC_SYS_READY_R2_N")
	)
	(segment
		(start 249.353324 -327.21042)
		(end 249.558048 -327.005696)
		(width 0.13208)
		(layer "B.Cu")
		(net "BIC_SYS_READY_R2_N")
	)
	(segment
		(start 209.727546 -228.74097)
		(end 208.890108 -228.74097)
		(width 0.13208)
		(layer "B.Cu")
		(net "BIC_SYS_READY_R2_N")
	)
	(segment
		(start 216.056464 -228.176328)
		(end 211.976716 -228.176328)
		(width 0.13208)
		(layer "B.Cu")
		(net "BIC_SYS_READY_R2_N")
	)
	(segment
		(start 248.820178 -327.9013)
		(end 249.241818 -327.47966)
		(width 0.13208)
		(layer "B.Cu")
		(net "BIC_SYS_READY_R2_N")
	)
	(segment
		(start 247.64619 -327.9013)
		(end 248.820178 -327.9013)
		(width 0.13208)
		(layer "B.Cu")
		(net "BIC_SYS_READY_R2_N")
	)
	(segment
		(start 211.976716 -228.176328)
		(end 211.470748 -227.67036)
		(width 0.13208)
		(layer "B.Cu")
		(net "BIC_SYS_READY_R2_N")
	)
	(segment
		(start 208.463896 -228.314758)
		(end 207.522572 -228.314758)
		(width 0.13208)
		(layer "B.Cu")
		(net "BIC_SYS_READY_R2_N")
	)
	(segment
		(start 206.714852 -215.776302)
		(end 207.049878 -215.776302)
		(width 0.13208)
		(layer "B.Cu")
		(net "BIC_SYS_READY_R2_N")
	)
	(segment
		(start 220.671136 -229.882192)
		(end 218.410282 -227.621338)
		(width 0.13208)
		(layer "B.Cu")
		(net "BIC_SYS_READY_R2_N")
	)
	(segment
		(start 258.865878 -284.833822)
		(end 257.603244 -283.571188)
		(width 0.13208)
		(layer "B.Cu")
		(net "BIC_SYS_READY_R2_N")
	)
	(segment
		(start 249.241818 -327.47966)
		(end 249.353324 -327.21042)
		(width 0.13208)
		(layer "B.Cu")
		(net "BIC_SYS_READY_R2_N")
	)
	(segment
		(start 258.865878 -304.533808)
		(end 258.865878 -284.833822)
		(width 0.13208)
		(layer "B.Cu")
		(net "BIC_SYS_READY_R2_N")
	)
	(segment
		(start 249.79376 -255.470406)
		(end 245.811802 -245.856506)
		(width 0.13208)
		(layer "B.Cu")
		(net "BIC_SYS_READY_R2_N")
	)
	(segment
		(start 224.175828 -236.379258)
		(end 220.671136 -232.874566)
		(width 0.13208)
		(layer "B.Cu")
		(net "BIC_SYS_READY_R2_N")
	)
	(segment
		(start 210.608672 -227.67036)
		(end 210.086448 -228.192584)
		(width 0.13208)
		(layer "B.Cu")
		(net "BIC_SYS_READY_R2_N")
	)
	(segment
		(start 205.831186 -216.659968)
		(end 206.714852 -215.776302)
		(width 0.13208)
		(layer "B.Cu")
		(net "BIC_SYS_READY_R2_N")
	)
	(segment
		(start 257.603244 -283.571188)
		(end 255.603502 -278.74341)
		(width 0.13208)
		(layer "B.Cu")
		(net "BIC_SYS_READY_R2_N")
	)
	(segment
		(start 245.811802 -245.856506)
		(end 236.334554 -236.379258)
		(width 0.13208)
		(layer "B.Cu")
		(net "BIC_SYS_READY_R2_N")
	)
	(segment
		(start 255.603502 -278.74341)
		(end 249.79376 -264.717022)
		(width 0.13208)
		(layer "B.Cu")
		(net "BIC_SYS_READY_R2_N")
	)
	(segment
		(start 217.35034 -227.708968)
		(end 216.523824 -227.708968)
		(width 0.13208)
		(layer "B.Cu")
		(net "BIC_SYS_READY_R2_N")
	)
	(segment
		(start 205.831186 -226.623372)
		(end 205.831186 -216.659968)
		(width 0.13208)
		(layer "B.Cu")
		(net "BIC_SYS_READY_R2_N")
	)
	(segment
		(start 209.582004 -211.593684)
		(end 210.823556 -211.593684)
		(width 0.13208)
		(layer "B.Cu")
		(net "BIC_SYS_READY_R2_N")
	)
	(segment
		(start 218.410282 -227.621338)
		(end 217.43797 -227.621338)
		(width 0.13208)
		(layer "B.Cu")
		(net "BIC_SYS_READY_R2_N")
	)
	(segment
		(start 208.261204 -212.914484)
		(end 209.582004 -211.593684)
		(width 0.13208)
		(layer "B.Cu")
		(net "BIC_SYS_READY_R2_N")
	)
	(segment
		(start 207.049878 -215.776302)
		(end 208.261204 -214.564976)
		(width 0.13208)
		(layer "B.Cu")
		(net "BIC_SYS_READY_R2_N")
	)
	(segment
		(start 342.873838 -222.11157)
		(end 342.34882 -221.586552)
		(width 0.0889)
		(layer "In5.Cu")
		(net "BIC_SYS_READY_R2_N")
	)
	(segment
		(start 336.49285 -224.865692)
		(end 336.49285 -226.936046)
		(width 0.0889)
		(layer "In5.Cu")
		(net "BIC_SYS_READY_R2_N")
	)
	(segment
		(start 336.001614 -227.568252)
		(end 332.471268 -227.568252)
		(width 0.15494)
		(layer "In5.Cu")
		(net "BIC_SYS_READY_R2_N")
	)
	(segment
		(start 338.894674 -221.723712)
		(end 338.894674 -222.171006)
		(width 0.0889)
		(layer "In5.Cu")
		(net "BIC_SYS_READY_R2_N")
	)
	(segment
		(start 332.198726 -228.621336)
		(end 331.560424 -229.259638)
		(width 0.15494)
		(layer "In5.Cu")
		(net "BIC_SYS_READY_R2_N")
	)
	(segment
		(start 343.2937 -224.386902)
		(end 342.873838 -223.96704)
		(width 0.0889)
		(layer "In5.Cu")
		(net "BIC_SYS_READY_R2_N")
	)
	(segment
		(start 336.49285 -226.936046)
		(end 336.49285 -227.077016)
		(width 0.15494)
		(layer "In5.Cu")
		(net "BIC_SYS_READY_R2_N")
	)
	(segment
		(start 342.873838 -223.96704)
		(end 342.873838 -222.11157)
		(width 0.0889)
		(layer "In5.Cu")
		(net "BIC_SYS_READY_R2_N")
	)
	(segment
		(start 342.34882 -221.586552)
		(end 339.031834 -221.586552)
		(width 0.0889)
		(layer "In5.Cu")
		(net "BIC_SYS_READY_R2_N")
	)
	(segment
		(start 336.49285 -227.077016)
		(end 336.001614 -227.568252)
		(width 0.15494)
		(layer "In5.Cu")
		(net "BIC_SYS_READY_R2_N")
	)
	(segment
		(start 336.573876 -224.784666)
		(end 336.49285 -224.865692)
		(width 0.0889)
		(layer "In5.Cu")
		(net "BIC_SYS_READY_R2_N")
	)
	(segment
		(start 338.894674 -222.171006)
		(end 338.67979 -222.38589)
		(width 0.0889)
		(layer "In5.Cu")
		(net "BIC_SYS_READY_R2_N")
	)
	(segment
		(start 338.310728 -222.38589)
		(end 338.095844 -222.600774)
		(width 0.0889)
		(layer "In5.Cu")
		(net "BIC_SYS_READY_R2_N")
	)
	(segment
		(start 338.67979 -222.38589)
		(end 338.310728 -222.38589)
		(width 0.0889)
		(layer "In5.Cu")
		(net "BIC_SYS_READY_R2_N")
	)
	(segment
		(start 332.471268 -227.568252)
		(end 332.198726 -227.840794)
		(width 0.15494)
		(layer "In5.Cu")
		(net "BIC_SYS_READY_R2_N")
	)
	(segment
		(start 338.095844 -222.600774)
		(end 338.095844 -224.605342)
		(width 0.0889)
		(layer "In5.Cu")
		(net "BIC_SYS_READY_R2_N")
	)
	(segment
		(start 337.91652 -224.784666)
		(end 336.573876 -224.784666)
		(width 0.0889)
		(layer "In5.Cu")
		(net "BIC_SYS_READY_R2_N")
	)
	(segment
		(start 338.095844 -224.605342)
		(end 337.91652 -224.784666)
		(width 0.0889)
		(layer "In5.Cu")
		(net "BIC_SYS_READY_R2_N")
	)
	(segment
		(start 332.198726 -227.840794)
		(end 332.198726 -228.621336)
		(width 0.15494)
		(layer "In5.Cu")
		(net "BIC_SYS_READY_R2_N")
	)
	(segment
		(start 339.031834 -221.586552)
		(end 338.894674 -221.723712)
		(width 0.0889)
		(layer "In5.Cu")
		(net "BIC_SYS_READY_R2_N")
	)
	(segment
		(start 268.1732 -360.68)
		(end 264.9982 -357.505)
		(width 0.15494)
		(layer "In7.Cu")
		(net "BIC_SYS_READY_R2_N")
	)
	(segment
		(start 278.9428 -398.9832)
		(end 276.5552 -396.5956)
		(width 0.15494)
		(layer "In7.Cu")
		(net "BIC_SYS_READY_R2_N")
	)
	(segment
		(start 255.741932 -335.934304)
		(end 251.756418 -331.94879)
		(width 0.15494)
		(layer "In7.Cu")
		(net "BIC_SYS_READY_R2_N")
	)
	(segment
		(start 277.725632 -404.495)
		(end 279.4508 -404.495)
		(width 0.15494)
		(layer "In7.Cu")
		(net "BIC_SYS_READY_R2_N")
	)
	(segment
		(start 276.073616 -406.147016)
		(end 277.725632 -404.495)
		(width 0.15494)
		(layer "In7.Cu")
		(net "BIC_SYS_READY_R2_N")
	)
	(segment
		(start 250.062492 -331.94879)
		(end 247.64619 -329.532488)
		(width 0.15494)
		(layer "In7.Cu")
		(net "BIC_SYS_READY_R2_N")
	)
	(segment
		(start 276.5552 -396.5956)
		(end 276.5552 -391.0584)
		(width 0.15494)
		(layer "In7.Cu")
		(net "BIC_SYS_READY_R2_N")
	)
	(segment
		(start 256.22377 -337.09737)
		(end 255.741932 -335.934304)
		(width 0.15494)
		(layer "In7.Cu")
		(net "BIC_SYS_READY_R2_N")
	)
	(segment
		(start 264.9982 -357.505)
		(end 264.9982 -345.8718)
		(width 0.15494)
		(layer "In7.Cu")
		(net "BIC_SYS_READY_R2_N")
	)
	(segment
		(start 251.756418 -331.94879)
		(end 250.062492 -331.94879)
		(width 0.15494)
		(layer "In7.Cu")
		(net "BIC_SYS_READY_R2_N")
	)
	(segment
		(start 279.9842 -403.0472)
		(end 278.9428 -402.0058)
		(width 0.15494)
		(layer "In7.Cu")
		(net "BIC_SYS_READY_R2_N")
	)
	(segment
		(start 247.64619 -329.532488)
		(end 247.64619 -327.9013)
		(width 0.15494)
		(layer "In7.Cu")
		(net "BIC_SYS_READY_R2_N")
	)
	(segment
		(start 268.1732 -374.2436)
		(end 268.1732 -360.68)
		(width 0.15494)
		(layer "In7.Cu")
		(net "BIC_SYS_READY_R2_N")
	)
	(segment
		(start 266.446 -375.9708)
		(end 268.1732 -374.2436)
		(width 0.15494)
		(layer "In7.Cu")
		(net "BIC_SYS_READY_R2_N")
	)
	(segment
		(start 264.9982 -345.8718)
		(end 256.22377 -337.09737)
		(width 0.15494)
		(layer "In7.Cu")
		(net "BIC_SYS_READY_R2_N")
	)
	(segment
		(start 278.9428 -402.0058)
		(end 278.9428 -398.9832)
		(width 0.15494)
		(layer "In7.Cu")
		(net "BIC_SYS_READY_R2_N")
	)
	(segment
		(start 279.4508 -404.495)
		(end 279.9842 -403.9616)
		(width 0.15494)
		(layer "In7.Cu")
		(net "BIC_SYS_READY_R2_N")
	)
	(segment
		(start 279.9842 -403.9616)
		(end 279.9842 -403.0472)
		(width 0.15494)
		(layer "In7.Cu")
		(net "BIC_SYS_READY_R2_N")
	)
	(segment
		(start 276.5552 -391.0584)
		(end 266.446 -380.9492)
		(width 0.15494)
		(layer "In7.Cu")
		(net "BIC_SYS_READY_R2_N")
	)
	(segment
		(start 266.446 -380.9492)
		(end 266.446 -375.9708)
		(width 0.15494)
		(layer "In7.Cu")
		(net "BIC_SYS_READY_R2_N")
	)
	(segment
		(start 241.66449 -209.28457)
		(end 240.929668 -210.019392)
		(width 0.15494)
		(layer "In13.Cu")
		(net "BIC_SYS_READY_R2_N")
	)
	(segment
		(start 246.849646 -214.613744)
		(end 246.408194 -214.613744)
		(width 0.15494)
		(layer "In13.Cu")
		(net "BIC_SYS_READY_R2_N")
	)
	(segment
		(start 326.900794 -229.28834)
		(end 324.411086 -229.28834)
		(width 0.15494)
		(layer "In13.Cu")
		(net "BIC_SYS_READY_R2_N")
	)
	(segment
		(start 238.2266 -208.8134)
		(end 236.02315 -208.8134)
		(width 0.15494)
		(layer "In13.Cu")
		(net "BIC_SYS_READY_R2_N")
	)
	(segment
		(start 240.52403 -210.015328)
		(end 240.033302 -209.5246)
		(width 0.15494)
		(layer "In13.Cu")
		(net "BIC_SYS_READY_R2_N")
	)
	(segment
		(start 220.47327 -211.065618)
		(end 219.448888 -212.09)
		(width 0.15494)
		(layer "In13.Cu")
		(net "BIC_SYS_READY_R2_N")
	)
	(segment
		(start 230.699564 -207.92948)
		(end 222.728028 -207.92948)
		(width 0.15494)
		(layer "In13.Cu")
		(net "BIC_SYS_READY_R2_N")
	)
	(segment
		(start 301.313342 -228.242114)
		(end 279.784048 -228.242114)
		(width 0.15494)
		(layer "In13.Cu")
		(net "BIC_SYS_READY_R2_N")
	)
	(segment
		(start 240.929668 -210.019392)
		(end 240.92535 -210.015328)
		(width 0.15494)
		(layer "In13.Cu")
		(net "BIC_SYS_READY_R2_N")
	)
	(segment
		(start 327.101454 -229.489)
		(end 326.900794 -229.28834)
		(width 0.15494)
		(layer "In13.Cu")
		(net "BIC_SYS_READY_R2_N")
	)
	(segment
		(start 246.375682 -214.581232)
		(end 246.1895 -214.581232)
		(width 0.15494)
		(layer "In13.Cu")
		(net "BIC_SYS_READY_R2_N")
	)
	(segment
		(start 238.9378 -209.5246)
		(end 238.2266 -208.8134)
		(width 0.15494)
		(layer "In13.Cu")
		(net "BIC_SYS_READY_R2_N")
	)
	(segment
		(start 215.08593 -210.5406)
		(end 211.87664 -210.5406)
		(width 0.15494)
		(layer "In13.Cu")
		(net "BIC_SYS_READY_R2_N")
	)
	(segment
		(start 240.033302 -209.5246)
		(end 238.9378 -209.5246)
		(width 0.15494)
		(layer "In13.Cu")
		(net "BIC_SYS_READY_R2_N")
	)
	(segment
		(start 279.784048 -228.242114)
		(end 269.635732 -218.093798)
		(width 0.15494)
		(layer "In13.Cu")
		(net "BIC_SYS_READY_R2_N")
	)
	(segment
		(start 240.92535 -210.015328)
		(end 240.52403 -210.015328)
		(width 0.15494)
		(layer "In13.Cu")
		(net "BIC_SYS_READY_R2_N")
	)
	(segment
		(start 331.560424 -229.259638)
		(end 331.331062 -229.489)
		(width 0.15494)
		(layer "In13.Cu")
		(net "BIC_SYS_READY_R2_N")
	)
	(segment
		(start 245.26875 -213.4743)
		(end 245.201186 -213.406736)
		(width 0.15494)
		(layer "In13.Cu")
		(net "BIC_SYS_READY_R2_N")
	)
	(segment
		(start 232.528364 -208.6864)
		(end 230.699564 -207.92948)
		(width 0.15494)
		(layer "In13.Cu")
		(net "BIC_SYS_READY_R2_N")
	)
	(segment
		(start 243.976144 -211.402676)
		(end 243.976144 -211.366354)
		(width 0.15494)
		(layer "In13.Cu")
		(net "BIC_SYS_READY_R2_N")
	)
	(segment
		(start 247.918732 -213.544658)
		(end 246.849646 -214.613744)
		(width 0.15494)
		(layer "In13.Cu")
		(net "BIC_SYS_READY_R2_N")
	)
	(segment
		(start 258.349242 -215.460072)
		(end 254.691134 -215.460072)
		(width 0.15494)
		(layer "In13.Cu")
		(net "BIC_SYS_READY_R2_N")
	)
	(segment
		(start 324.027546 -228.9048)
		(end 306.677314 -228.9048)
		(width 0.15494)
		(layer "In13.Cu")
		(net "BIC_SYS_READY_R2_N")
	)
	(segment
		(start 222.0341 -208.216754)
		(end 220.47327 -209.777584)
		(width 0.15494)
		(layer "In13.Cu")
		(net "BIC_SYS_READY_R2_N")
	)
	(segment
		(start 245.134638 -212.704172)
		(end 245.134638 -212.56117)
		(width 0.15494)
		(layer "In13.Cu")
		(net "BIC_SYS_READY_R2_N")
	)
	(segment
		(start 235.716318 -208.6864)
		(end 232.528364 -208.6864)
		(width 0.15494)
		(layer "In13.Cu")
		(net "BIC_SYS_READY_R2_N")
	)
	(segment
		(start 222.728028 -207.92948)
		(end 222.0341 -208.216754)
		(width 0.15494)
		(layer "In13.Cu")
		(net "BIC_SYS_READY_R2_N")
	)
	(segment
		(start 216.226644 -210.709256)
		(end 215.254586 -210.709256)
		(width 0.15494)
		(layer "In13.Cu")
		(net "BIC_SYS_READY_R2_N")
	)
	(segment
		(start 305.593496 -227.820982)
		(end 301.734474 -227.820982)
		(width 0.15494)
		(layer "In13.Cu")
		(net "BIC_SYS_READY_R2_N")
	)
	(segment
		(start 260.982968 -218.093798)
		(end 258.349242 -215.460072)
		(width 0.15494)
		(layer "In13.Cu")
		(net "BIC_SYS_READY_R2_N")
	)
	(segment
		(start 219.448888 -212.09)
		(end 217.607388 -212.09)
		(width 0.15494)
		(layer "In13.Cu")
		(net "BIC_SYS_READY_R2_N")
	)
	(segment
		(start 324.411086 -229.28834)
		(end 324.027546 -228.9048)
		(width 0.15494)
		(layer "In13.Cu")
		(net "BIC_SYS_READY_R2_N")
	)
	(segment
		(start 236.02315 -208.8134)
		(end 235.716318 -208.6864)
		(width 0.15494)
		(layer "In13.Cu")
		(net "BIC_SYS_READY_R2_N")
	)
	(segment
		(start 254.691134 -215.460072)
		(end 252.77572 -213.544658)
		(width 0.15494)
		(layer "In13.Cu")
		(net "BIC_SYS_READY_R2_N")
	)
	(segment
		(start 245.90629 -214.298022)
		(end 245.90629 -214.120222)
		(width 0.15494)
		(layer "In13.Cu")
		(net "BIC_SYS_READY_R2_N")
	)
	(segment
		(start 306.677314 -228.9048)
		(end 305.593496 -227.820982)
		(width 0.15494)
		(layer "In13.Cu")
		(net "BIC_SYS_READY_R2_N")
	)
	(segment
		(start 245.134638 -212.56117)
		(end 243.976144 -211.402676)
		(width 0.15494)
		(layer "In13.Cu")
		(net "BIC_SYS_READY_R2_N")
	)
	(segment
		(start 269.635732 -218.093798)
		(end 260.982968 -218.093798)
		(width 0.15494)
		(layer "In13.Cu")
		(net "BIC_SYS_READY_R2_N")
	)
	(segment
		(start 245.201186 -213.406736)
		(end 245.201186 -212.77072)
		(width 0.15494)
		(layer "In13.Cu")
		(net "BIC_SYS_READY_R2_N")
	)
	(segment
		(start 246.1895 -214.581232)
		(end 245.90629 -214.298022)
		(width 0.15494)
		(layer "In13.Cu")
		(net "BIC_SYS_READY_R2_N")
	)
	(segment
		(start 243.969032 -209.847942)
		(end 243.40566 -209.28457)
		(width 0.15494)
		(layer "In13.Cu")
		(net "BIC_SYS_READY_R2_N")
	)
	(segment
		(start 215.254586 -210.709256)
		(end 215.08593 -210.5406)
		(width 0.15494)
		(layer "In13.Cu")
		(net "BIC_SYS_READY_R2_N")
	)
	(segment
		(start 243.969032 -211.359242)
		(end 243.969032 -209.847942)
		(width 0.15494)
		(layer "In13.Cu")
		(net "BIC_SYS_READY_R2_N")
	)
	(segment
		(start 211.87664 -210.5406)
		(end 210.823556 -211.593684)
		(width 0.15494)
		(layer "In13.Cu")
		(net "BIC_SYS_READY_R2_N")
	)
	(segment
		(start 245.90629 -214.120222)
		(end 245.26875 -213.482682)
		(width 0.15494)
		(layer "In13.Cu")
		(net "BIC_SYS_READY_R2_N")
	)
	(segment
		(start 331.331062 -229.489)
		(end 327.101454 -229.489)
		(width 0.15494)
		(layer "In13.Cu")
		(net "BIC_SYS_READY_R2_N")
	)
	(segment
		(start 220.47327 -209.777584)
		(end 220.47327 -211.065618)
		(width 0.15494)
		(layer "In13.Cu")
		(net "BIC_SYS_READY_R2_N")
	)
	(segment
		(start 246.408194 -214.613744)
		(end 246.375682 -214.581232)
		(width 0.15494)
		(layer "In13.Cu")
		(net "BIC_SYS_READY_R2_N")
	)
	(segment
		(start 252.77572 -213.544658)
		(end 247.918732 -213.544658)
		(width 0.15494)
		(layer "In13.Cu")
		(net "BIC_SYS_READY_R2_N")
	)
	(segment
		(start 243.976144 -211.366354)
		(end 243.969032 -211.359242)
		(width 0.15494)
		(layer "In13.Cu")
		(net "BIC_SYS_READY_R2_N")
	)
	(segment
		(start 245.26875 -213.482682)
		(end 245.26875 -213.4743)
		(width 0.15494)
		(layer "In13.Cu")
		(net "BIC_SYS_READY_R2_N")
	)
	(segment
		(start 301.734474 -227.820982)
		(end 301.313342 -228.242114)
		(width 0.15494)
		(layer "In13.Cu")
		(net "BIC_SYS_READY_R2_N")
	)
	(segment
		(start 243.40566 -209.28457)
		(end 241.66449 -209.28457)
		(width 0.15494)
		(layer "In13.Cu")
		(net "BIC_SYS_READY_R2_N")
	)
	(segment
		(start 217.607388 -212.09)
		(end 216.226644 -210.709256)
		(width 0.15494)
		(layer "In13.Cu")
		(net "BIC_SYS_READY_R2_N")
	)
	(segment
		(start 245.201186 -212.77072)
		(end 245.134638 -212.704172)
		(width 0.15494)
		(layer "In13.Cu")
		(net "BIC_SYS_READY_R2_N")
	)
	(segment
		(start 403.156166 -36.874958)
		(end 403.156166 -34.409888)
		(width 0.13208)
		(layer "F.Cu")
		(net "SSD14_AUX_P3V3_EN_R")
	)
	(segment
		(start 403.1996 -33.654746)
		(end 403.156166 -33.611312)
		(width 0.13208)
		(layer "F.Cu")
		(net "SSD14_AUX_P3V3_EN_R")
	)
	(segment
		(start 402.502624 -37.529516)
		(end 403.156166 -36.874958)
		(width 0.13208)
		(layer "F.Cu")
		(net "SSD14_AUX_P3V3_EN_R")
	)
	(segment
		(start 400.577812 -37.84092)
		(end 400.889978 -37.529516)
		(width 0.13208)
		(layer "F.Cu")
		(net "SSD14_AUX_P3V3_EN_R")
	)
	(segment
		(start 400.889978 -37.529516)
		(end 401.426172 -37.529516)
		(width 0.13208)
		(layer "F.Cu")
		(net "SSD14_AUX_P3V3_EN_R")
	)
	(segment
		(start 401.426172 -37.529516)
		(end 402.502624 -37.529516)
		(width 0.13208)
		(layer "F.Cu")
		(net "SSD14_AUX_P3V3_EN_R")
	)
	(segment
		(start 400.577812 -39.97198)
		(end 400.577812 -37.84092)
		(width 0.13208)
		(layer "F.Cu")
		(net "SSD14_AUX_P3V3_EN_R")
	)
	(segment
		(start 403.1996 -34.366454)
		(end 403.1996 -33.654746)
		(width 0.13208)
		(layer "F.Cu")
		(net "SSD14_AUX_P3V3_EN_R")
	)
	(segment
		(start 406.440894 -57.675272)
		(end 406.040082 -58.076084)
		(width 0.13208)
		(layer "F.Cu")
		(net "SSD14_AUX_P3V3_EN_R")
	)
	(segment
		(start 405.015192 -59.100974)
		(end 406.040082 -58.076084)
		(width 0.13208)
		(layer "F.Cu")
		(net "SSD14_AUX_P3V3_EN_R")
	)
	(segment
		(start 403.156166 -34.409888)
		(end 403.1996 -34.366454)
		(width 0.13208)
		(layer "F.Cu")
		(net "SSD14_AUX_P3V3_EN_R")
	)
	(segment
		(start 403.156166 -33.611312)
		(end 403.156166 -33.248092)
		(width 0.13208)
		(layer "F.Cu")
		(net "SSD14_AUX_P3V3_EN_R")
	)
	(segment
		(start 405.015192 -59.146186)
		(end 405.015192 -59.100974)
		(width 0.13208)
		(layer "F.Cu")
		(net "SSD14_AUX_P3V3_EN_R")
	)
	(segment
		(start 406.440894 -57.16397)
		(end 406.440894 -57.675272)
		(width 0.13208)
		(layer "F.Cu")
		(net "SSD14_AUX_P3V3_EN_R")
	)
	(via
		(at 400.577812 -39.97198)
		(size 0.508)
		(drill 0.254)
		(layers "F.Cu" "B.Cu")
		(net "SSD14_AUX_P3V3_EN_R")
	)
	(via
		(at 406.040082 -58.076084)
		(size 0.508)
		(drill 0.254)
		(layers "F.Cu" "B.Cu")
		(net "SSD14_AUX_P3V3_EN_R")
	)
	(segment
		(start 400.577812 -39.97198)
		(end 403.779736 -39.97198)
		(width 0.15494)
		(layer "In5.Cu")
		(net "SSD14_AUX_P3V3_EN_R")
	)
	(segment
		(start 409.786582 -45.978826)
		(end 409.786582 -54.329584)
		(width 0.15494)
		(layer "In5.Cu")
		(net "SSD14_AUX_P3V3_EN_R")
	)
	(segment
		(start 409.786582 -54.329584)
		(end 406.040082 -58.076084)
		(width 0.15494)
		(layer "In5.Cu")
		(net "SSD14_AUX_P3V3_EN_R")
	)
	(segment
		(start 403.779736 -39.97198)
		(end 409.786582 -45.978826)
		(width 0.15494)
		(layer "In5.Cu")
		(net "SSD14_AUX_P3V3_EN_R")
	)
	(segment
		(start 209.855816 -366.951006)
		(end 209.855816 -367.74628)
		(width 0.13208)
		(layer "F.Cu")
		(net "HSC_ON_R")
	)
	(segment
		(start 208.870042 -368.732054)
		(end 208.605882 -368.732054)
		(width 0.13208)
		(layer "F.Cu")
		(net "HSC_ON_R")
	)
	(segment
		(start 211.066126 -366.951006)
		(end 209.855816 -366.951006)
		(width 0.13208)
		(layer "F.Cu")
		(net "HSC_ON_R")
	)
	(segment
		(start 209.855816 -367.74628)
		(end 208.870042 -368.732054)
		(width 0.13208)
		(layer "F.Cu")
		(net "HSC_ON_R")
	)
	(segment
		(start 211.106766 -366.991646)
		(end 211.066126 -366.951006)
		(width 0.13208)
		(layer "F.Cu")
		(net "HSC_ON_R")
	)
	(via
		(at 209.855816 -366.951006)
		(size 0.762)
		(drill 0.254)
		(layers "F.Cu" "B.Cu")
		(net "HSC_ON_R")
	)
	(segment
		(start 402.68017 -39.33571)
		(end 403.402546 -40.058086)
		(width 0.13208)
		(layer "F.Cu")
		(net "SSD14_AUX_P3V3_EN")
	)
	(segment
		(start 401.426172 -38.329616)
		(end 401.426172 -39.33571)
		(width 0.13208)
		(layer "F.Cu")
		(net "SSD14_AUX_P3V3_EN")
	)
	(segment
		(start 403.402546 -40.058086)
		(end 405.02078 -40.058086)
		(width 0.13208)
		(layer "F.Cu")
		(net "SSD14_AUX_P3V3_EN")
	)
	(segment
		(start 405.14778 -40.185086)
		(end 405.14778 -41.137332)
		(width 0.13208)
		(layer "F.Cu")
		(net "SSD14_AUX_P3V3_EN")
	)
	(segment
		(start 405.02078 -40.058086)
		(end 405.14778 -40.185086)
		(width 0.13208)
		(layer "F.Cu")
		(net "SSD14_AUX_P3V3_EN")
	)
	(segment
		(start 401.426172 -39.33571)
		(end 402.68017 -39.33571)
		(width 0.13208)
		(layer "F.Cu")
		(net "SSD14_AUX_P3V3_EN")
	)
	(via
		(at 402.68017 -39.33571)
		(size 0.762)
		(drill 0.381)
		(layers "F.Cu" "B.Cu")
		(net "SSD14_AUX_P3V3_EN")
	)
	(segment
		(start 406.693624 -37.774118)
		(end 406.875742 -37.592)
		(width 0.13208)
		(layer "F.Cu")
		(net "PRSNT_SSD14_R1_N")
	)
	(segment
		(start 404.19782 -38.16731)
		(end 404.591012 -37.774118)
		(width 0.13208)
		(layer "F.Cu")
		(net "PRSNT_SSD14_R1_N")
	)
	(segment
		(start 406.146762 -37.774118)
		(end 406.693624 -37.774118)
		(width 0.13208)
		(layer "F.Cu")
		(net "PRSNT_SSD14_R1_N")
	)
	(segment
		(start 404.19782 -38.937184)
		(end 404.19782 -38.16731)
		(width 0.13208)
		(layer "F.Cu")
		(net "PRSNT_SSD14_R1_N")
	)
	(segment
		(start 406.875742 -37.592)
		(end 406.875742 -37.315648)
		(width 0.13208)
		(layer "F.Cu")
		(net "PRSNT_SSD14_R1_N")
	)
	(segment
		(start 404.591012 -37.774118)
		(end 406.146762 -37.774118)
		(width 0.13208)
		(layer "F.Cu")
		(net "PRSNT_SSD14_R1_N")
	)
	(via
		(at 406.146762 -37.774118)
		(size 0.508)
		(drill 0.254)
		(layers "F.Cu" "B.Cu")
		(net "PRSNT_SSD14_R1_N")
	)
	(segment
		(start 233.294682 -366.647222)
		(end 233.73969 -366.647222)
		(width 0.13208)
		(layer "F.Cu")
		(net "HSC_D_OC_2")
	)
	(segment
		(start 232.962704 -368.207544)
		(end 233.08056 -368.089688)
		(width 0.13208)
		(layer "F.Cu")
		(net "HSC_D_OC_2")
	)
	(segment
		(start 233.779822 -368.182144)
		(end 233.533188 -367.93551)
		(width 0.13208)
		(layer "F.Cu")
		(net "HSC_D_OC_2")
	)
	(segment
		(start 233.73969 -367.009426)
		(end 233.73969 -366.647222)
		(width 0.13208)
		(layer "F.Cu")
		(net "HSC_D_OC_2")
	)
	(segment
		(start 233.08056 -366.861344)
		(end 233.294682 -366.647222)
		(width 0.13208)
		(layer "F.Cu")
		(net "HSC_D_OC_2")
	)
	(segment
		(start 233.533188 -367.215928)
		(end 233.73969 -367.009426)
		(width 0.13208)
		(layer "F.Cu")
		(net "HSC_D_OC_2")
	)
	(segment
		(start 232.53192 -368.207544)
		(end 232.962704 -368.207544)
		(width 0.13208)
		(layer "F.Cu")
		(net "HSC_D_OC_2")
	)
	(segment
		(start 233.533188 -367.93551)
		(end 233.533188 -367.215928)
		(width 0.13208)
		(layer "F.Cu")
		(net "HSC_D_OC_2")
	)
	(segment
		(start 234.25531 -368.182144)
		(end 233.779822 -368.182144)
		(width 0.13208)
		(layer "F.Cu")
		(net "HSC_D_OC_2")
	)
	(segment
		(start 233.08056 -368.089688)
		(end 233.08056 -366.861344)
		(width 0.13208)
		(layer "F.Cu")
		(net "HSC_D_OC_2")
	)
	(via
		(at 233.73969 -366.647222)
		(size 0.762)
		(drill 0.381)
		(layers "F.Cu" "B.Cu")
		(net "HSC_D_OC_2")
	)
	(segment
		(start 377.156218 -33.248092)
		(end 377.19 -33.281874)
		(width 0.13208)
		(layer "F.Cu")
		(net "SSD13_AUX_P3V3_EN_R")
	)
	(segment
		(start 379.015244 -59.100974)
		(end 380.040134 -58.076084)
		(width 0.13208)
		(layer "F.Cu")
		(net "SSD13_AUX_P3V3_EN_R")
	)
	(segment
		(start 380.440946 -57.675272)
		(end 380.040134 -58.076084)
		(width 0.13208)
		(layer "F.Cu")
		(net "SSD13_AUX_P3V3_EN_R")
	)
	(segment
		(start 376.502676 -37.529516)
		(end 375.426224 -37.529516)
		(width 0.13208)
		(layer "F.Cu")
		(net "SSD13_AUX_P3V3_EN_R")
	)
	(segment
		(start 374.577864 -39.97198)
		(end 374.577864 -37.84092)
		(width 0.13208)
		(layer "F.Cu")
		(net "SSD13_AUX_P3V3_EN_R")
	)
	(segment
		(start 377.19 -33.281874)
		(end 377.19 -36.841176)
		(width 0.13208)
		(layer "F.Cu")
		(net "SSD13_AUX_P3V3_EN_R")
	)
	(segment
		(start 374.577864 -37.84092)
		(end 374.89003 -37.529516)
		(width 0.13208)
		(layer "F.Cu")
		(net "SSD13_AUX_P3V3_EN_R")
	)
	(segment
		(start 379.015244 -59.146186)
		(end 379.015244 -59.100974)
		(width 0.13208)
		(layer "F.Cu")
		(net "SSD13_AUX_P3V3_EN_R")
	)
	(segment
		(start 377.19 -36.841176)
		(end 376.502676 -37.529516)
		(width 0.13208)
		(layer "F.Cu")
		(net "SSD13_AUX_P3V3_EN_R")
	)
	(segment
		(start 374.89003 -37.529516)
		(end 375.426224 -37.529516)
		(width 0.13208)
		(layer "F.Cu")
		(net "SSD13_AUX_P3V3_EN_R")
	)
	(segment
		(start 380.440946 -57.16397)
		(end 380.440946 -57.675272)
		(width 0.13208)
		(layer "F.Cu")
		(net "SSD13_AUX_P3V3_EN_R")
	)
	(via
		(at 374.577864 -39.97198)
		(size 0.508)
		(drill 0.254)
		(layers "F.Cu" "B.Cu")
		(net "SSD13_AUX_P3V3_EN_R")
	)
	(via
		(at 380.040134 -58.076084)
		(size 0.508)
		(drill 0.254)
		(layers "F.Cu" "B.Cu")
		(net "SSD13_AUX_P3V3_EN_R")
	)
	(segment
		(start 383.81305 -54.303168)
		(end 380.040134 -58.076084)
		(width 0.15494)
		(layer "In5.Cu")
		(net "SSD13_AUX_P3V3_EN_R")
	)
	(segment
		(start 377.751086 -39.97198)
		(end 383.81305 -46.033944)
		(width 0.15494)
		(layer "In5.Cu")
		(net "SSD13_AUX_P3V3_EN_R")
	)
	(segment
		(start 383.81305 -46.033944)
		(end 383.81305 -54.303168)
		(width 0.15494)
		(layer "In5.Cu")
		(net "SSD13_AUX_P3V3_EN_R")
	)
	(segment
		(start 374.577864 -39.97198)
		(end 377.751086 -39.97198)
		(width 0.15494)
		(layer "In5.Cu")
		(net "SSD13_AUX_P3V3_EN_R")
	)
	(segment
		(start 216.937844 -367.707672)
		(end 217.388948 -367.707672)
		(width 0.13208)
		(layer "F.Cu")
		(net "HSC_CS_1")
	)
	(segment
		(start 214.711026 -367.019586)
		(end 214.965026 -366.765586)
		(width 0.13208)
		(layer "F.Cu")
		(net "HSC_CS_1")
	)
	(segment
		(start 215.995758 -366.765586)
		(end 216.937844 -367.707672)
		(width 0.13208)
		(layer "F.Cu")
		(net "HSC_CS_1")
	)
	(segment
		(start 214.965026 -366.765586)
		(end 215.995758 -366.765586)
		(width 0.13208)
		(layer "F.Cu")
		(net "HSC_CS_1")
	)
	(via
		(at 215.995758 -366.765586)
		(size 0.762)
		(drill 0.381)
		(layers "F.Cu" "B.Cu")
		(net "HSC_CS_1")
	)
	(segment
		(start 276.073616 -404.674324)
		(end 275.3106 -404.674324)
		(width 0.13208)
		(layer "F.Cu")
		(net "BIC_SYS_READY_R_N")
	)
	(segment
		(start 277.089616 -404.674324)
		(end 276.073616 -404.674324)
		(width 0.13208)
		(layer "F.Cu")
		(net "BIC_SYS_READY_R_N")
	)
	(segment
		(start 227.562664 -205.47711)
		(end 227.562664 -206.62011)
		(width 0.13208)
		(layer "F.Cu")
		(net "BIC_SYS_READY_R_N")
	)
	(segment
		(start 278.105616 -404.674324)
		(end 277.089616 -404.674324)
		(width 0.13208)
		(layer "F.Cu")
		(net "BIC_SYS_READY_R_N")
	)
	(via
		(at 221.534482 -252.47092)
		(size 0.508)
		(drill 0.254)
		(layers "F.Cu" "B.Cu")
		(net "BIC_SYS_READY_R_N")
	)
	(via
		(at 227.562664 -205.47711)
		(size 0.508)
		(drill 0.254)
		(layers "F.Cu" "B.Cu")
		(net "BIC_SYS_READY_R_N")
	)
	(via
		(at 275.3106 -404.674324)
		(size 0.508)
		(drill 0.254)
		(layers "F.Cu" "B.Cu")
		(net "BIC_SYS_READY_R_N")
	)
	(via
		(at 225.991166 -329.061064)
		(size 0.508)
		(drill 0.254)
		(layers "F.Cu" "B.Cu")
		(net "BIC_SYS_READY_R_N")
	)
	(segment
		(start 217.884248 -253.183898)
		(end 220.821504 -253.183898)
		(width 0.13208)
		(layer "B.Cu")
		(net "BIC_SYS_READY_R_N")
	)
	(segment
		(start 215.316308 -257.695446)
		(end 215.316308 -255.751838)
		(width 0.13208)
		(layer "B.Cu")
		(net "BIC_SYS_READY_R_N")
	)
	(segment
		(start 212.270086 -315.70168)
		(end 212.270086 -284.727904)
		(width 0.13208)
		(layer "B.Cu")
		(net "BIC_SYS_READY_R_N")
	)
	(segment
		(start 214.73033 -258.281424)
		(end 215.316308 -257.695446)
		(width 0.13208)
		(layer "B.Cu")
		(net "BIC_SYS_READY_R_N")
	)
	(segment
		(start 215.316308 -255.751838)
		(end 217.884248 -253.183898)
		(width 0.13208)
		(layer "B.Cu")
		(net "BIC_SYS_READY_R_N")
	)
	(segment
		(start 214.73033 -282.26766)
		(end 214.73033 -258.281424)
		(width 0.13208)
		(layer "B.Cu")
		(net "BIC_SYS_READY_R_N")
	)
	(segment
		(start 220.821504 -253.183898)
		(end 221.534482 -252.47092)
		(width 0.13208)
		(layer "B.Cu")
		(net "BIC_SYS_READY_R_N")
	)
	(segment
		(start 225.991166 -329.061064)
		(end 225.62947 -329.061064)
		(width 0.13208)
		(layer "B.Cu")
		(net "BIC_SYS_READY_R_N")
	)
	(segment
		(start 225.62947 -329.061064)
		(end 212.270086 -315.70168)
		(width 0.13208)
		(layer "B.Cu")
		(net "BIC_SYS_READY_R_N")
	)
	(segment
		(start 212.270086 -284.727904)
		(end 214.73033 -282.26766)
		(width 0.13208)
		(layer "B.Cu")
		(net "BIC_SYS_READY_R_N")
	)
	(segment
		(start 220.472 -225.7044)
		(end 220.472 -225.675952)
		(width 0.15494)
		(layer "In5.Cu")
		(net "BIC_SYS_READY_R_N")
	)
	(segment
		(start 220.762322 -225.994722)
		(end 220.472 -225.7044)
		(width 0.15494)
		(layer "In5.Cu")
		(net "BIC_SYS_READY_R_N")
	)
	(segment
		(start 222.6564 -238.331248)
		(end 222.6564 -237.375446)
		(width 0.15494)
		(layer "In5.Cu")
		(net "BIC_SYS_READY_R_N")
	)
	(segment
		(start 220.46184 -223.685354)
		(end 220.461586 -223.6851)
		(width 0.15494)
		(layer "In5.Cu")
		(net "BIC_SYS_READY_R_N")
	)
	(segment
		(start 222.765112 -208.866486)
		(end 222.77959 -208.866486)
		(width 0.15494)
		(layer "In5.Cu")
		(net "BIC_SYS_READY_R_N")
	)
	(segment
		(start 222.74022 -239.84458)
		(end 222.142304 -239.246664)
		(width 0.15494)
		(layer "In5.Cu")
		(net "BIC_SYS_READY_R_N")
	)
	(segment
		(start 219.97416 -216.3064)
		(end 219.97416 -211.671916)
		(width 0.15494)
		(layer "In5.Cu")
		(net "BIC_SYS_READY_R_N")
	)
	(segment
		(start 220.762322 -235.481368)
		(end 220.762322 -225.994722)
		(width 0.15494)
		(layer "In5.Cu")
		(net "BIC_SYS_READY_R_N")
	)
	(segment
		(start 220.461586 -223.6851)
		(end 220.461586 -220.222826)
		(width 0.15494)
		(layer "In5.Cu")
		(net "BIC_SYS_READY_R_N")
	)
	(segment
		(start 222.4024 -247.344946)
		(end 222.4024 -246.4943)
		(width 0.15494)
		(layer "In5.Cu")
		(net "BIC_SYS_READY_R_N")
	)
	(segment
		(start 220.472 -225.675952)
		(end 220.46184 -225.665792)
		(width 0.15494)
		(layer "In5.Cu")
		(net "BIC_SYS_READY_R_N")
	)
	(segment
		(start 222.7326 -251.272802)
		(end 222.7326 -247.675146)
		(width 0.15494)
		(layer "In5.Cu")
		(net "BIC_SYS_READY_R_N")
	)
	(segment
		(start 221.534482 -252.47092)
		(end 222.7326 -251.272802)
		(width 0.15494)
		(layer "In5.Cu")
		(net "BIC_SYS_READY_R_N")
	)
	(segment
		(start 220.461586 -220.222826)
		(end 221.096586 -219.587826)
		(width 0.15494)
		(layer "In5.Cu")
		(net "BIC_SYS_READY_R_N")
	)
	(segment
		(start 222.4024 -246.4943)
		(end 222.74022 -246.15648)
		(width 0.15494)
		(layer "In5.Cu")
		(net "BIC_SYS_READY_R_N")
	)
	(segment
		(start 224.566226 -208.473548)
		(end 227.562664 -205.47711)
		(width 0.15494)
		(layer "In5.Cu")
		(net "BIC_SYS_READY_R_N")
	)
	(segment
		(start 222.481902 -209.164174)
		(end 222.481902 -209.149696)
		(width 0.15494)
		(layer "In5.Cu")
		(net "BIC_SYS_READY_R_N")
	)
	(segment
		(start 222.77959 -208.866486)
		(end 223.172528 -208.473548)
		(width 0.15494)
		(layer "In5.Cu")
		(net "BIC_SYS_READY_R_N")
	)
	(segment
		(start 222.74022 -246.15648)
		(end 222.74022 -239.84458)
		(width 0.15494)
		(layer "In5.Cu")
		(net "BIC_SYS_READY_R_N")
	)
	(segment
		(start 222.7326 -247.675146)
		(end 222.4024 -247.344946)
		(width 0.15494)
		(layer "In5.Cu")
		(net "BIC_SYS_READY_R_N")
	)
	(segment
		(start 223.172528 -208.473548)
		(end 224.566226 -208.473548)
		(width 0.15494)
		(layer "In5.Cu")
		(net "BIC_SYS_READY_R_N")
	)
	(segment
		(start 222.6564 -237.375446)
		(end 220.762322 -235.481368)
		(width 0.15494)
		(layer "In5.Cu")
		(net "BIC_SYS_READY_R_N")
	)
	(segment
		(start 222.142304 -238.845344)
		(end 222.6564 -238.331248)
		(width 0.15494)
		(layer "In5.Cu")
		(net "BIC_SYS_READY_R_N")
	)
	(segment
		(start 219.97416 -211.671916)
		(end 222.481902 -209.164174)
		(width 0.15494)
		(layer "In5.Cu")
		(net "BIC_SYS_READY_R_N")
	)
	(segment
		(start 220.46184 -225.665792)
		(end 220.46184 -223.685354)
		(width 0.15494)
		(layer "In5.Cu")
		(net "BIC_SYS_READY_R_N")
	)
	(segment
		(start 221.096586 -219.587826)
		(end 221.096586 -217.428826)
		(width 0.15494)
		(layer "In5.Cu")
		(net "BIC_SYS_READY_R_N")
	)
	(segment
		(start 222.142304 -239.246664)
		(end 222.142304 -238.845344)
		(width 0.15494)
		(layer "In5.Cu")
		(net "BIC_SYS_READY_R_N")
	)
	(segment
		(start 221.096586 -217.428826)
		(end 219.97416 -216.3064)
		(width 0.15494)
		(layer "In5.Cu")
		(net "BIC_SYS_READY_R_N")
	)
	(segment
		(start 222.481902 -209.149696)
		(end 222.765112 -208.866486)
		(width 0.15494)
		(layer "In5.Cu")
		(net "BIC_SYS_READY_R_N")
	)
	(segment
		(start 282.355036 -402.301964)
		(end 282.355036 -370.986304)
		(width 0.15494)
		(layer "In9.Cu")
		(net "BIC_SYS_READY_R_N")
	)
	(segment
		(start 264.080752 -343.176352)
		(end 236.307884 -343.176352)
		(width 0.15494)
		(layer "In9.Cu")
		(net "BIC_SYS_READY_R_N")
	)
	(segment
		(start 266.598654 -355.229922)
		(end 266.598654 -345.694254)
		(width 0.15494)
		(layer "In9.Cu")
		(net "BIC_SYS_READY_R_N")
	)
	(segment
		(start 236.307884 -343.176352)
		(end 227.33 -334.198468)
		(width 0.15494)
		(layer "In9.Cu")
		(net "BIC_SYS_READY_R_N")
	)
	(segment
		(start 227.33 -334.198468)
		(end 227.33 -330.399898)
		(width 0.15494)
		(layer "In9.Cu")
		(net "BIC_SYS_READY_R_N")
	)
	(segment
		(start 227.33 -330.399898)
		(end 225.991166 -329.061064)
		(width 0.15494)
		(layer "In9.Cu")
		(net "BIC_SYS_READY_R_N")
	)
	(segment
		(start 266.598654 -345.694254)
		(end 264.080752 -343.176352)
		(width 0.15494)
		(layer "In9.Cu")
		(net "BIC_SYS_READY_R_N")
	)
	(segment
		(start 279.982676 -404.674324)
		(end 282.355036 -402.301964)
		(width 0.15494)
		(layer "In9.Cu")
		(net "BIC_SYS_READY_R_N")
	)
	(segment
		(start 275.3106 -404.674324)
		(end 279.982676 -404.674324)
		(width 0.15494)
		(layer "In9.Cu")
		(net "BIC_SYS_READY_R_N")
	)
	(segment
		(start 282.355036 -370.986304)
		(end 266.598654 -355.229922)
		(width 0.15494)
		(layer "In9.Cu")
		(net "BIC_SYS_READY_R_N")
	)
	(segment
		(start 319.079372 -298.700698)
		(end 319.180718 -298.700698)
		(width 0.13208)
		(layer "F.Cu")
		(net "RST_PEX2_S1_PERST_R_N")
	)
	(segment
		(start 319.4304 -300.8122)
		(end 319.6209 -301.0027)
		(width 0.13208)
		(layer "F.Cu")
		(net "RST_PEX2_S1_PERST_R_N")
	)
	(segment
		(start 319.6209 -301.0027)
		(end 319.949576 -301.0027)
		(width 0.13208)
		(layer "F.Cu")
		(net "RST_PEX2_S1_PERST_R_N")
	)
	(segment
		(start 319.180718 -298.700698)
		(end 319.4304 -298.95038)
		(width 0.13208)
		(layer "F.Cu")
		(net "RST_PEX2_S1_PERST_R_N")
	)
	(segment
		(start 304.674778 -305.874928)
		(end 305.149758 -306.349908)
		(width 0.13208)
		(layer "F.Cu")
		(net "RST_PEX2_S1_PERST_R_N")
	)
	(segment
		(start 319.4304 -298.95038)
		(end 319.4304 -300.8122)
		(width 0.13208)
		(layer "F.Cu")
		(net "RST_PEX2_S1_PERST_R_N")
	)
	(via
		(at 319.079372 -298.700698)
		(size 0.508)
		(drill 0.254)
		(layers "F.Cu" "B.Cu")
		(net "RST_PEX2_S1_PERST_R_N")
	)
	(via
		(at 304.674778 -305.874928)
		(size 0.4064)
		(drill 0.2032)
		(layers "F.Cu" "B.Cu")
		(net "RST_PEX2_S1_PERST_R_N")
	)
	(segment
		(start 319.079372 -298.700698)
		(end 318.944752 -298.566078)
		(width 0.15494)
		(layer "In5.Cu")
		(net "RST_PEX2_S1_PERST_R_N")
	)
	(segment
		(start 317.724536 -298.74972)
		(end 306.329334 -298.74972)
		(width 0.15494)
		(layer "In5.Cu")
		(net "RST_PEX2_S1_PERST_R_N")
	)
	(segment
		(start 305.5112 -305.038506)
		(end 304.674778 -305.874928)
		(width 0.15494)
		(layer "In5.Cu")
		(net "RST_PEX2_S1_PERST_R_N")
	)
	(segment
		(start 306.329334 -298.74972)
		(end 306.099718 -298.979336)
		(width 0.15494)
		(layer "In5.Cu")
		(net "RST_PEX2_S1_PERST_R_N")
	)
	(segment
		(start 305.5112 -304.393854)
		(end 305.5112 -305.038506)
		(width 0.15494)
		(layer "In5.Cu")
		(net "RST_PEX2_S1_PERST_R_N")
	)
	(segment
		(start 317.908178 -298.566078)
		(end 317.724536 -298.74972)
		(width 0.15494)
		(layer "In5.Cu")
		(net "RST_PEX2_S1_PERST_R_N")
	)
	(segment
		(start 318.944752 -298.566078)
		(end 317.908178 -298.566078)
		(width 0.15494)
		(layer "In5.Cu")
		(net "RST_PEX2_S1_PERST_R_N")
	)
	(segment
		(start 306.099718 -298.979336)
		(end 306.099718 -303.805336)
		(width 0.15494)
		(layer "In5.Cu")
		(net "RST_PEX2_S1_PERST_R_N")
	)
	(segment
		(start 306.099718 -303.805336)
		(end 305.5112 -304.393854)
		(width 0.15494)
		(layer "In5.Cu")
		(net "RST_PEX2_S1_PERST_R_N")
	)
	(segment
		(start 379.020832 -40.058086)
		(end 379.147832 -40.185086)
		(width 0.13208)
		(layer "F.Cu")
		(net "SSD13_AUX_P3V3_EN")
	)
	(segment
		(start 376.680222 -39.33571)
		(end 377.402598 -40.058086)
		(width 0.13208)
		(layer "F.Cu")
		(net "SSD13_AUX_P3V3_EN")
	)
	(segment
		(start 377.402598 -40.058086)
		(end 379.020832 -40.058086)
		(width 0.13208)
		(layer "F.Cu")
		(net "SSD13_AUX_P3V3_EN")
	)
	(segment
		(start 375.426224 -39.33571)
		(end 376.680222 -39.33571)
		(width 0.13208)
		(layer "F.Cu")
		(net "SSD13_AUX_P3V3_EN")
	)
	(segment
		(start 379.147832 -40.185086)
		(end 379.147832 -41.137332)
		(width 0.13208)
		(layer "F.Cu")
		(net "SSD13_AUX_P3V3_EN")
	)
	(segment
		(start 375.426224 -38.329616)
		(end 375.426224 -39.33571)
		(width 0.13208)
		(layer "F.Cu")
		(net "SSD13_AUX_P3V3_EN")
	)
	(via
		(at 376.680222 -39.33571)
		(size 0.762)
		(drill 0.381)
		(layers "F.Cu" "B.Cu")
		(net "SSD13_AUX_P3V3_EN")
	)
	(segment
		(start 334.09382 -218.387168)
		(end 333.694024 -217.987372)
		(width 0.13208)
		(layer "F.Cu")
		(net "NIC6_PEX_PWR_EN_R")
	)
	(segment
		(start 353.248214 -155.321)
		(end 352.632264 -155.321)
		(width 0.13208)
		(layer "F.Cu")
		(net "NIC6_PEX_PWR_EN_R")
	)
	(via
		(at 341.485982 -152.705054)
		(size 0.508)
		(drill 0.254)
		(layers "F.Cu" "B.Cu")
		(net "NIC6_PEX_PWR_EN_R")
	)
	(via
		(at 333.694024 -217.987372)
		(size 0.4572)
		(drill 0.254)
		(layers "F.Cu" "B.Cu")
		(net "NIC6_PEX_PWR_EN_R")
	)
	(via
		(at 353.248214 -155.321)
		(size 0.508)
		(drill 0.254)
		(layers "F.Cu" "B.Cu")
		(net "NIC6_PEX_PWR_EN_R")
	)
	(segment
		(start 352.046032 -155.321)
		(end 353.248214 -155.321)
		(width 0.13208)
		(layer "B.Cu")
		(net "NIC6_PEX_PWR_EN_R")
	)
	(segment
		(start 352.046032 -154.305)
		(end 352.046032 -155.321)
		(width 0.13208)
		(layer "B.Cu")
		(net "NIC6_PEX_PWR_EN_R")
	)
	(segment
		(start 340.0298 -157.607)
		(end 339.179916 -156.757116)
		(width 0.15494)
		(layer "In9.Cu")
		(net "NIC6_PEX_PWR_EN_R")
	)
	(segment
		(start 339.57387 -172.15993)
		(end 340.397592 -171.336208)
		(width 0.15494)
		(layer "In9.Cu")
		(net "NIC6_PEX_PWR_EN_R")
	)
	(segment
		(start 333.694024 -217.987372)
		(end 333.395066 -217.688414)
		(width 0.15494)
		(layer "In9.Cu")
		(net "NIC6_PEX_PWR_EN_R")
	)
	(segment
		(start 327.9648 -208.8388)
		(end 327.664318 -208.538318)
		(width 0.15494)
		(layer "In9.Cu")
		(net "NIC6_PEX_PWR_EN_R")
	)
	(segment
		(start 341.0712 -163.449)
		(end 340.63813 -163.01593)
		(width 0.15494)
		(layer "In9.Cu")
		(net "NIC6_PEX_PWR_EN_R")
	)
	(segment
		(start 333.847948 -177.419)
		(end 335.5086 -177.419)
		(width 0.15494)
		(layer "In9.Cu")
		(net "NIC6_PEX_PWR_EN_R")
	)
	(segment
		(start 329.248008 -182.01894)
		(end 333.847948 -177.419)
		(width 0.15494)
		(layer "In9.Cu")
		(net "NIC6_PEX_PWR_EN_R")
	)
	(segment
		(start 326.2376 -202.4888)
		(end 329.248008 -199.478392)
		(width 0.15494)
		(layer "In9.Cu")
		(net "NIC6_PEX_PWR_EN_R")
	)
	(segment
		(start 327.9648 -216.5096)
		(end 327.9648 -208.8388)
		(width 0.15494)
		(layer "In9.Cu")
		(net "NIC6_PEX_PWR_EN_R")
	)
	(segment
		(start 333.395066 -217.688414)
		(end 329.143614 -217.688414)
		(width 0.15494)
		(layer "In9.Cu")
		(net "NIC6_PEX_PWR_EN_R")
	)
	(segment
		(start 339.29066 -172.56887)
		(end 339.57387 -172.28566)
		(width 0.15494)
		(layer "In9.Cu")
		(net "NIC6_PEX_PWR_EN_R")
	)
	(segment
		(start 337.8708 -175.8442)
		(end 338.60613 -175.10887)
		(width 0.15494)
		(layer "In9.Cu")
		(net "NIC6_PEX_PWR_EN_R")
	)
	(segment
		(start 340.0298 -159.302704)
		(end 340.0298 -157.607)
		(width 0.15494)
		(layer "In9.Cu")
		(net "NIC6_PEX_PWR_EN_R")
	)
	(segment
		(start 340.397592 -171.336208)
		(end 340.397592 -170.065446)
		(width 0.15494)
		(layer "In9.Cu")
		(net "NIC6_PEX_PWR_EN_R")
	)
	(segment
		(start 338.9376 -172.56887)
		(end 339.29066 -172.56887)
		(width 0.15494)
		(layer "In9.Cu")
		(net "NIC6_PEX_PWR_EN_R")
	)
	(segment
		(start 327.664318 -208.538318)
		(end 327.664318 -207.634586)
		(width 0.15494)
		(layer "In9.Cu")
		(net "NIC6_PEX_PWR_EN_R")
	)
	(segment
		(start 341.0712 -169.391838)
		(end 341.0712 -163.449)
		(width 0.15494)
		(layer "In9.Cu")
		(net "NIC6_PEX_PWR_EN_R")
	)
	(segment
		(start 326.2376 -206.207868)
		(end 326.2376 -202.4888)
		(width 0.15494)
		(layer "In9.Cu")
		(net "NIC6_PEX_PWR_EN_R")
	)
	(segment
		(start 339.179916 -156.757116)
		(end 339.179916 -154.207464)
		(width 0.15494)
		(layer "In9.Cu")
		(net "NIC6_PEX_PWR_EN_R")
	)
	(segment
		(start 327.664318 -207.634586)
		(end 326.2376 -206.207868)
		(width 0.15494)
		(layer "In9.Cu")
		(net "NIC6_PEX_PWR_EN_R")
	)
	(segment
		(start 341.0204 -160.293304)
		(end 340.0298 -159.302704)
		(width 0.15494)
		(layer "In9.Cu")
		(net "NIC6_PEX_PWR_EN_R")
	)
	(segment
		(start 340.682326 -152.705054)
		(end 341.485982 -152.705054)
		(width 0.15494)
		(layer "In9.Cu")
		(net "NIC6_PEX_PWR_EN_R")
	)
	(segment
		(start 340.63813 -161.586672)
		(end 341.0204 -161.204402)
		(width 0.15494)
		(layer "In9.Cu")
		(net "NIC6_PEX_PWR_EN_R")
	)
	(segment
		(start 335.5086 -177.419)
		(end 337.0834 -175.8442)
		(width 0.15494)
		(layer "In9.Cu")
		(net "NIC6_PEX_PWR_EN_R")
	)
	(segment
		(start 338.60613 -175.10887)
		(end 338.60613 -172.90034)
		(width 0.15494)
		(layer "In9.Cu")
		(net "NIC6_PEX_PWR_EN_R")
	)
	(segment
		(start 340.63813 -163.01593)
		(end 340.63813 -161.586672)
		(width 0.15494)
		(layer "In9.Cu")
		(net "NIC6_PEX_PWR_EN_R")
	)
	(segment
		(start 329.248008 -199.478392)
		(end 329.248008 -182.01894)
		(width 0.15494)
		(layer "In9.Cu")
		(net "NIC6_PEX_PWR_EN_R")
	)
	(segment
		(start 329.143614 -217.688414)
		(end 327.9648 -216.5096)
		(width 0.15494)
		(layer "In9.Cu")
		(net "NIC6_PEX_PWR_EN_R")
	)
	(segment
		(start 338.60613 -172.90034)
		(end 338.9376 -172.56887)
		(width 0.15494)
		(layer "In9.Cu")
		(net "NIC6_PEX_PWR_EN_R")
	)
	(segment
		(start 341.0204 -161.204402)
		(end 341.0204 -160.293304)
		(width 0.15494)
		(layer "In9.Cu")
		(net "NIC6_PEX_PWR_EN_R")
	)
	(segment
		(start 339.57387 -172.28566)
		(end 339.57387 -172.15993)
		(width 0.15494)
		(layer "In9.Cu")
		(net "NIC6_PEX_PWR_EN_R")
	)
	(segment
		(start 337.0834 -175.8442)
		(end 337.8708 -175.8442)
		(width 0.15494)
		(layer "In9.Cu")
		(net "NIC6_PEX_PWR_EN_R")
	)
	(segment
		(start 340.397592 -170.065446)
		(end 341.0712 -169.391838)
		(width 0.15494)
		(layer "In9.Cu")
		(net "NIC6_PEX_PWR_EN_R")
	)
	(segment
		(start 339.179916 -154.207464)
		(end 340.682326 -152.705054)
		(width 0.15494)
		(layer "In9.Cu")
		(net "NIC6_PEX_PWR_EN_R")
	)
	(segment
		(start 341.485982 -152.705054)
		(end 347.256608 -152.705054)
		(width 0.15494)
		(layer "In13.Cu")
		(net "NIC6_PEX_PWR_EN_R")
	)
	(segment
		(start 349.059754 -154.5082)
		(end 352.435414 -154.5082)
		(width 0.15494)
		(layer "In13.Cu")
		(net "NIC6_PEX_PWR_EN_R")
	)
	(segment
		(start 352.435414 -154.5082)
		(end 353.248214 -155.321)
		(width 0.15494)
		(layer "In13.Cu")
		(net "NIC6_PEX_PWR_EN_R")
	)
	(segment
		(start 347.256608 -152.705054)
		(end 349.059754 -154.5082)
		(width 0.15494)
		(layer "In13.Cu")
		(net "NIC6_PEX_PWR_EN_R")
	)
	(segment
		(start 200.683876 -367.76533)
		(end 200.751694 -367.76533)
		(width 0.13208)
		(layer "F.Cu")
		(net "HSC_VDD18")
	)
	(segment
		(start 201.953114 -368.28222)
		(end 202.130914 -368.28222)
		(width 0.13208)
		(layer "F.Cu")
		(net "HSC_VDD18")
	)
	(segment
		(start 198.964296 -365.615728)
		(end 199.309228 -365.615728)
		(width 0.13208)
		(layer "F.Cu")
		(net "HSC_VDD18")
	)
	(segment
		(start 199.517508 -366.598962)
		(end 200.683876 -367.76533)
		(width 0.13208)
		(layer "F.Cu")
		(net "HSC_VDD18")
	)
	(segment
		(start 199.309228 -365.615728)
		(end 199.517508 -365.824008)
		(width 0.13208)
		(layer "F.Cu")
		(net "HSC_VDD18")
	)
	(segment
		(start 200.751694 -367.76533)
		(end 201.01052 -368.024156)
		(width 0.13208)
		(layer "F.Cu")
		(net "HSC_VDD18")
	)
	(segment
		(start 201.69505 -368.024156)
		(end 201.953114 -368.28222)
		(width 0.13208)
		(layer "F.Cu")
		(net "HSC_VDD18")
	)
	(segment
		(start 199.517508 -365.824008)
		(end 199.517508 -366.598962)
		(width 0.13208)
		(layer "F.Cu")
		(net "HSC_VDD18")
	)
	(segment
		(start 201.01052 -368.024156)
		(end 201.69505 -368.024156)
		(width 0.13208)
		(layer "F.Cu")
		(net "HSC_VDD18")
	)
	(via
		(at 200.751694 -367.76533)
		(size 0.762)
		(drill 0.254)
		(layers "F.Cu" "B.Cu")
		(net "HSC_VDD18")
	)
	(segment
		(start 228.003608 -209.910934)
		(end 228.003608 -210.876896)
		(width 0.13208)
		(layer "F.Cu")
		(net "BIC_SYS_READY_N")
	)
	(segment
		(start 227.562664 -207.79486)
		(end 227.75926 -207.991456)
		(width 0.13208)
		(layer "F.Cu")
		(net "BIC_SYS_READY_N")
	)
	(segment
		(start 227.63226 -209.53222)
		(end 227.624894 -209.53222)
		(width 0.13208)
		(layer "F.Cu")
		(net "BIC_SYS_READY_N")
	)
	(segment
		(start 227.867718 -213.104222)
		(end 228.267768 -213.504272)
		(width 0.13208)
		(layer "F.Cu")
		(net "BIC_SYS_READY_N")
	)
	(segment
		(start 227.75926 -207.991456)
		(end 227.75926 -209.40522)
		(width 0.13208)
		(layer "F.Cu")
		(net "BIC_SYS_READY_N")
	)
	(segment
		(start 228.003608 -210.876896)
		(end 227.867718 -211.012786)
		(width 0.13208)
		(layer "F.Cu")
		(net "BIC_SYS_READY_N")
	)
	(segment
		(start 227.75926 -209.40522)
		(end 227.63226 -209.53222)
		(width 0.13208)
		(layer "F.Cu")
		(net "BIC_SYS_READY_N")
	)
	(segment
		(start 227.562664 -207.42021)
		(end 227.562664 -207.79486)
		(width 0.13208)
		(layer "F.Cu")
		(net "BIC_SYS_READY_N")
	)
	(segment
		(start 227.624894 -209.53222)
		(end 228.003608 -209.910934)
		(width 0.13208)
		(layer "F.Cu")
		(net "BIC_SYS_READY_N")
	)
	(segment
		(start 227.867718 -211.012786)
		(end 227.867718 -213.104222)
		(width 0.13208)
		(layer "F.Cu")
		(net "BIC_SYS_READY_N")
	)
	(via
		(at 227.624894 -209.53222)
		(size 0.762)
		(drill 0.381)
		(layers "F.Cu" "B.Cu")
		(net "BIC_SYS_READY_N")
	)
	(segment
		(start 380.693676 -37.774118)
		(end 380.875794 -37.592)
		(width 0.13208)
		(layer "F.Cu")
		(net "PRSNT_SSD13_R1_N")
	)
	(segment
		(start 378.591064 -37.774118)
		(end 380.146814 -37.774118)
		(width 0.13208)
		(layer "F.Cu")
		(net "PRSNT_SSD13_R1_N")
	)
	(segment
		(start 380.875794 -37.592)
		(end 380.875794 -37.315648)
		(width 0.13208)
		(layer "F.Cu")
		(net "PRSNT_SSD13_R1_N")
	)
	(segment
		(start 380.146814 -37.774118)
		(end 380.693676 -37.774118)
		(width 0.13208)
		(layer "F.Cu")
		(net "PRSNT_SSD13_R1_N")
	)
	(segment
		(start 378.197872 -38.937184)
		(end 378.197872 -38.16731)
		(width 0.13208)
		(layer "F.Cu")
		(net "PRSNT_SSD13_R1_N")
	)
	(segment
		(start 378.197872 -38.16731)
		(end 378.591064 -37.774118)
		(width 0.13208)
		(layer "F.Cu")
		(net "PRSNT_SSD13_R1_N")
	)
	(via
		(at 380.146814 -37.774118)
		(size 0.508)
		(drill 0.254)
		(layers "F.Cu" "B.Cu")
		(net "PRSNT_SSD13_R1_N")
	)
	(segment
		(start 336.44205 -155.702)
		(end 336.44205 -154.686)
		(width 0.13208)
		(layer "F.Cu")
		(net "SSD13_PEX_PWR_EN_R")
	)
	(segment
		(start 337.058 -154.686)
		(end 337.67395 -154.686)
		(width 0.13208)
		(layer "F.Cu")
		(net "SSD13_PEX_PWR_EN_R")
	)
	(segment
		(start 334.09382 -213.587076)
		(end 333.348584 -213.587076)
		(width 0.0889)
		(layer "F.Cu")
		(net "SSD13_PEX_PWR_EN_R")
	)
	(segment
		(start 336.44205 -154.686)
		(end 337.058 -154.686)
		(width 0.13208)
		(layer "F.Cu")
		(net "SSD13_PEX_PWR_EN_R")
	)
	(segment
		(start 333.348584 -213.587076)
		(end 332.986634 -213.949026)
		(width 0.13208)
		(layer "F.Cu")
		(net "SSD13_PEX_PWR_EN_R")
	)
	(via
		(at 341.408766 -154.156156)
		(size 0.508)
		(drill 0.254)
		(layers "F.Cu" "B.Cu")
		(net "SSD13_PEX_PWR_EN_R")
	)
	(via
		(at 337.058 -154.686)
		(size 0.508)
		(drill 0.254)
		(layers "F.Cu" "B.Cu")
		(net "SSD13_PEX_PWR_EN_R")
	)
	(via
		(at 332.986634 -213.949026)
		(size 0.508)
		(drill 0.254)
		(layers "F.Cu" "B.Cu")
		(net "SSD13_PEX_PWR_EN_R")
	)
	(segment
		(start 332.105 -197.1802)
		(end 332.105 -189.977014)
		(width 0.15494)
		(layer "In9.Cu")
		(net "SSD13_PEX_PWR_EN_R")
	)
	(segment
		(start 331.672692 -211.760054)
		(end 328.2188 -208.306162)
		(width 0.15494)
		(layer "In9.Cu")
		(net "SSD13_PEX_PWR_EN_R")
	)
	(segment
		(start 328.2188 -207.442054)
		(end 326.6186 -205.841854)
		(width 0.15494)
		(layer "In9.Cu")
		(net "SSD13_PEX_PWR_EN_R")
	)
	(segment
		(start 339.725 -175.34636)
		(end 339.725 -173.5582)
		(width 0.15494)
		(layer "In9.Cu")
		(net "SSD13_PEX_PWR_EN_R")
	)
	(segment
		(start 340.799166 -158.360872)
		(end 340.799166 -154.765756)
		(width 0.15494)
		(layer "In9.Cu")
		(net "SSD13_PEX_PWR_EN_R")
	)
	(segment
		(start 341.535512 -166.346378)
		(end 341.787226 -166.094664)
		(width 0.15494)
		(layer "In9.Cu")
		(net "SSD13_PEX_PWR_EN_R")
	)
	(segment
		(start 332.986634 -213.949026)
		(end 331.672692 -212.635084)
		(width 0.15494)
		(layer "In9.Cu")
		(net "SSD13_PEX_PWR_EN_R")
	)
	(segment
		(start 332.105 -189.977014)
		(end 335.545176 -186.536838)
		(width 0.15494)
		(layer "In9.Cu")
		(net "SSD13_PEX_PWR_EN_R")
	)
	(segment
		(start 338.094066 -181.852316)
		(end 338.094066 -176.977294)
		(width 0.15494)
		(layer "In9.Cu")
		(net "SSD13_PEX_PWR_EN_R")
	)
	(segment
		(start 335.545176 -186.536838)
		(end 335.545176 -184.401206)
		(width 0.15494)
		(layer "In9.Cu")
		(net "SSD13_PEX_PWR_EN_R")
	)
	(segment
		(start 328.2188 -208.306162)
		(end 328.2188 -207.442054)
		(width 0.15494)
		(layer "In9.Cu")
		(net "SSD13_PEX_PWR_EN_R")
	)
	(segment
		(start 340.397592 -159.163766)
		(end 340.397592 -158.762446)
		(width 0.15494)
		(layer "In9.Cu")
		(net "SSD13_PEX_PWR_EN_R")
	)
	(segment
		(start 331.672692 -212.635084)
		(end 331.672692 -211.760054)
		(width 0.15494)
		(layer "In9.Cu")
		(net "SSD13_PEX_PWR_EN_R")
	)
	(segment
		(start 340.397592 -158.762446)
		(end 340.799166 -158.360872)
		(width 0.15494)
		(layer "In9.Cu")
		(net "SSD13_PEX_PWR_EN_R")
	)
	(segment
		(start 341.787226 -166.094664)
		(end 341.787226 -160.5534)
		(width 0.15494)
		(layer "In9.Cu")
		(net "SSD13_PEX_PWR_EN_R")
	)
	(segment
		(start 338.094066 -176.977294)
		(end 339.725 -175.34636)
		(width 0.15494)
		(layer "In9.Cu")
		(net "SSD13_PEX_PWR_EN_R")
	)
	(segment
		(start 326.6186 -205.841854)
		(end 326.6186 -202.6666)
		(width 0.15494)
		(layer "In9.Cu")
		(net "SSD13_PEX_PWR_EN_R")
	)
	(segment
		(start 341.535512 -171.747688)
		(end 341.535512 -166.346378)
		(width 0.15494)
		(layer "In9.Cu")
		(net "SSD13_PEX_PWR_EN_R")
	)
	(segment
		(start 326.6186 -202.6666)
		(end 332.105 -197.1802)
		(width 0.15494)
		(layer "In9.Cu")
		(net "SSD13_PEX_PWR_EN_R")
	)
	(segment
		(start 340.799166 -154.765756)
		(end 341.408766 -154.156156)
		(width 0.15494)
		(layer "In9.Cu")
		(net "SSD13_PEX_PWR_EN_R")
	)
	(segment
		(start 335.545176 -184.401206)
		(end 338.094066 -181.852316)
		(width 0.15494)
		(layer "In9.Cu")
		(net "SSD13_PEX_PWR_EN_R")
	)
	(segment
		(start 341.787226 -160.5534)
		(end 340.397592 -159.163766)
		(width 0.15494)
		(layer "In9.Cu")
		(net "SSD13_PEX_PWR_EN_R")
	)
	(segment
		(start 339.725 -173.5582)
		(end 341.535512 -171.747688)
		(width 0.15494)
		(layer "In9.Cu")
		(net "SSD13_PEX_PWR_EN_R")
	)
	(segment
		(start 337.587844 -154.156156)
		(end 337.058 -154.686)
		(width 0.15494)
		(layer "In13.Cu")
		(net "SSD13_PEX_PWR_EN_R")
	)
	(segment
		(start 341.408766 -154.156156)
		(end 337.587844 -154.156156)
		(width 0.15494)
		(layer "In13.Cu")
		(net "SSD13_PEX_PWR_EN_R")
	)
	(segment
		(start 221.651322 -141.910562)
		(end 221.651322 -142.926562)
		(width 0.13208)
		(layer "F.Cu")
		(net "FM_CK440_PEX_DEV_25M_EN")
	)
	(segment
		(start 225.347022 -143.265398)
		(end 225.347022 -143.110966)
		(width 0.13208)
		(layer "F.Cu")
		(net "FM_CK440_PEX_DEV_25M_EN")
	)
	(segment
		(start 223.380046 -142.926562)
		(end 221.651322 -142.926562)
		(width 0.13208)
		(layer "F.Cu")
		(net "FM_CK440_PEX_DEV_25M_EN")
	)
	(segment
		(start 225.162618 -142.926562)
		(end 223.380046 -142.926562)
		(width 0.13208)
		(layer "F.Cu")
		(net "FM_CK440_PEX_DEV_25M_EN")
	)
	(segment
		(start 221.651322 -140.894562)
		(end 221.651322 -141.910562)
		(width 0.13208)
		(layer "F.Cu")
		(net "FM_CK440_PEX_DEV_25M_EN")
	)
	(segment
		(start 225.347022 -143.110966)
		(end 225.162618 -142.926562)
		(width 0.13208)
		(layer "F.Cu")
		(net "FM_CK440_PEX_DEV_25M_EN")
	)
	(via
		(at 223.380046 -142.926562)
		(size 0.762)
		(drill 0.381)
		(layers "F.Cu" "B.Cu")
		(net "FM_CK440_PEX_DEV_25M_EN")
	)
	(segment
		(start 222.798386 -368.207544)
		(end 223.254316 -367.751614)
		(width 0.13208)
		(layer "F.Cu")
		(net "HSC_D_OC_1")
	)
	(segment
		(start 223.254316 -367.393728)
		(end 223.653858 -366.994186)
		(width 0.13208)
		(layer "F.Cu")
		(net "HSC_D_OC_1")
	)
	(segment
		(start 223.254316 -367.751614)
		(end 223.254316 -367.393728)
		(width 0.13208)
		(layer "F.Cu")
		(net "HSC_D_OC_1")
	)
	(segment
		(start 221.86392 -368.207544)
		(end 222.798386 -368.207544)
		(width 0.13208)
		(layer "F.Cu")
		(net "HSC_D_OC_1")
	)
	(segment
		(start 223.653858 -366.994186)
		(end 224.451926 -366.994186)
		(width 0.13208)
		(layer "F.Cu")
		(net "HSC_D_OC_1")
	)
	(via
		(at 223.254316 -367.393728)
		(size 0.762)
		(drill 0.381)
		(layers "F.Cu" "B.Cu")
		(net "HSC_D_OC_1")
	)
	(segment
		(start 353.015296 -59.100974)
		(end 354.040186 -58.076084)
		(width 0.13208)
		(layer "F.Cu")
		(net "SSD12_AUX_P3V3_EN_R")
	)
	(segment
		(start 348.577916 -39.97198)
		(end 348.577916 -37.84092)
		(width 0.13208)
		(layer "F.Cu")
		(net "SSD12_AUX_P3V3_EN_R")
	)
	(segment
		(start 351.15627 -33.248092)
		(end 351.1804 -33.272222)
		(width 0.13208)
		(layer "F.Cu")
		(net "SSD12_AUX_P3V3_EN_R")
	)
	(segment
		(start 348.577916 -37.84092)
		(end 348.890082 -37.529516)
		(width 0.13208)
		(layer "F.Cu")
		(net "SSD12_AUX_P3V3_EN_R")
	)
	(segment
		(start 354.440998 -57.16397)
		(end 354.440998 -57.675272)
		(width 0.13208)
		(layer "F.Cu")
		(net "SSD12_AUX_P3V3_EN_R")
	)
	(segment
		(start 351.1804 -36.850828)
		(end 350.502728 -37.529516)
		(width 0.13208)
		(layer "F.Cu")
		(net "SSD12_AUX_P3V3_EN_R")
	)
	(segment
		(start 350.502728 -37.529516)
		(end 349.426276 -37.529516)
		(width 0.13208)
		(layer "F.Cu")
		(net "SSD12_AUX_P3V3_EN_R")
	)
	(segment
		(start 353.015296 -59.146186)
		(end 353.015296 -59.100974)
		(width 0.13208)
		(layer "F.Cu")
		(net "SSD12_AUX_P3V3_EN_R")
	)
	(segment
		(start 351.1804 -33.272222)
		(end 351.1804 -36.850828)
		(width 0.13208)
		(layer "F.Cu")
		(net "SSD12_AUX_P3V3_EN_R")
	)
	(segment
		(start 348.890082 -37.529516)
		(end 349.426276 -37.529516)
		(width 0.13208)
		(layer "F.Cu")
		(net "SSD12_AUX_P3V3_EN_R")
	)
	(segment
		(start 354.440998 -57.675272)
		(end 354.040186 -58.076084)
		(width 0.13208)
		(layer "F.Cu")
		(net "SSD12_AUX_P3V3_EN_R")
	)
	(via
		(at 348.577916 -39.97198)
		(size 0.508)
		(drill 0.254)
		(layers "F.Cu" "B.Cu")
		(net "SSD12_AUX_P3V3_EN_R")
	)
	(via
		(at 354.040186 -58.076084)
		(size 0.508)
		(drill 0.254)
		(layers "F.Cu" "B.Cu")
		(net "SSD12_AUX_P3V3_EN_R")
	)
	(segment
		(start 350.751648 -39.97198)
		(end 357.798878 -47.01921)
		(width 0.15494)
		(layer "In5.Cu")
		(net "SSD12_AUX_P3V3_EN_R")
	)
	(segment
		(start 348.577916 -39.97198)
		(end 350.751648 -39.97198)
		(width 0.15494)
		(layer "In5.Cu")
		(net "SSD12_AUX_P3V3_EN_R")
	)
	(segment
		(start 357.798878 -47.01921)
		(end 357.798878 -54.317392)
		(width 0.15494)
		(layer "In5.Cu")
		(net "SSD12_AUX_P3V3_EN_R")
	)
	(segment
		(start 357.798878 -54.317392)
		(end 354.040186 -58.076084)
		(width 0.15494)
		(layer "In5.Cu")
		(net "SSD12_AUX_P3V3_EN_R")
	)
	(segment
		(start 209.859626 -369.631976)
		(end 208.605882 -369.631976)
		(width 0.13208)
		(layer "F.Cu")
		(net "HSC_FLT_TYPE")
	)
	(via
		(at 209.859626 -369.631976)
		(size 0.762)
		(drill 0.254)
		(layers "F.Cu" "B.Cu")
		(net "HSC_FLT_TYPE")
	)
	(segment
		(start 209.859626 -369.631976)
		(end 210.5279 -370.30025)
		(width 0.13208)
		(layer "B.Cu")
		(net "HSC_FLT_TYPE")
	)
	(segment
		(start 210.5279 -371.151912)
		(end 211.153248 -371.77726)
		(width 0.13208)
		(layer "B.Cu")
		(net "HSC_FLT_TYPE")
	)
	(segment
		(start 210.5279 -370.30025)
		(end 210.5279 -371.151912)
		(width 0.13208)
		(layer "B.Cu")
		(net "HSC_FLT_TYPE")
	)
	(segment
		(start 353.147884 -40.185086)
		(end 353.020884 -40.058086)
		(width 0.13208)
		(layer "F.Cu")
		(net "SSD12_AUX_P3V3_EN")
	)
	(segment
		(start 353.147884 -41.137332)
		(end 353.147884 -40.185086)
		(width 0.13208)
		(layer "F.Cu")
		(net "SSD12_AUX_P3V3_EN")
	)
	(segment
		(start 349.426276 -38.329616)
		(end 349.426276 -39.33571)
		(width 0.13208)
		(layer "F.Cu")
		(net "SSD12_AUX_P3V3_EN")
	)
	(segment
		(start 350.680274 -39.33571)
		(end 349.426276 -39.33571)
		(width 0.13208)
		(layer "F.Cu")
		(net "SSD12_AUX_P3V3_EN")
	)
	(segment
		(start 351.40265 -40.058086)
		(end 350.680274 -39.33571)
		(width 0.13208)
		(layer "F.Cu")
		(net "SSD12_AUX_P3V3_EN")
	)
	(segment
		(start 353.020884 -40.058086)
		(end 351.40265 -40.058086)
		(width 0.13208)
		(layer "F.Cu")
		(net "SSD12_AUX_P3V3_EN")
	)
	(via
		(at 350.680274 -39.33571)
		(size 0.762)
		(drill 0.381)
		(layers "F.Cu" "B.Cu")
		(net "SSD12_AUX_P3V3_EN")
	)
	(segment
		(start 309.13578 -48.30699)
		(end 309.13578 -48.69942)
		(width 0.13208)
		(layer "F.Cu")
		(net "SMB_SSD10_ADC_SDA")
	)
	(segment
		(start 308.445916 -47.193962)
		(end 308.445916 -48.076612)
		(width 0.13208)
		(layer "F.Cu")
		(net "SMB_SSD10_ADC_SDA")
	)
	(segment
		(start 307.91531 -42.853102)
		(end 307.91531 -43.566842)
		(width 0.13208)
		(layer "F.Cu")
		(net "SMB_SSD10_ADC_SDA")
	)
	(segment
		(start 310.043576 -48.93691)
		(end 310.043576 -49.95291)
		(width 0.13208)
		(layer "F.Cu")
		(net "SMB_SSD10_ADC_SDA")
	)
	(segment
		(start 308.445916 -48.076612)
		(end 308.676294 -48.30699)
		(width 0.13208)
		(layer "F.Cu")
		(net "SMB_SSD10_ADC_SDA")
	)
	(segment
		(start 309.37327 -48.93691)
		(end 310.043576 -48.93691)
		(width 0.13208)
		(layer "F.Cu")
		(net "SMB_SSD10_ADC_SDA")
	)
	(segment
		(start 308.676294 -48.30699)
		(end 309.13578 -48.30699)
		(width 0.13208)
		(layer "F.Cu")
		(net "SMB_SSD10_ADC_SDA")
	)
	(segment
		(start 309.13578 -48.69942)
		(end 309.37327 -48.93691)
		(width 0.13208)
		(layer "F.Cu")
		(net "SMB_SSD10_ADC_SDA")
	)
	(via
		(at 307.91531 -43.566842)
		(size 0.508)
		(drill 0.254)
		(layers "F.Cu" "B.Cu")
		(net "SMB_SSD10_ADC_SDA")
	)
	(via
		(at 309.13578 -48.30699)
		(size 0.508)
		(drill 0.254)
		(layers "F.Cu" "B.Cu")
		(net "SMB_SSD10_ADC_SDA")
	)
	(segment
		(start 308.589172 -44.240704)
		(end 307.91531 -43.566842)
		(width 0.15494)
		(layer "In5.Cu")
		(net "SMB_SSD10_ADC_SDA")
	)
	(segment
		(start 308.589172 -47.760382)
		(end 308.589172 -44.240704)
		(width 0.15494)
		(layer "In5.Cu")
		(net "SMB_SSD10_ADC_SDA")
	)
	(segment
		(start 309.13578 -48.30699)
		(end 308.589172 -47.760382)
		(width 0.15494)
		(layer "In5.Cu")
		(net "SMB_SSD10_ADC_SDA")
	)
	(segment
		(start 225.915474 -137.122662)
		(end 225.915474 -137.069322)
		(width 0.13208)
		(layer "F.Cu")
		(net "SMB_CK440_PEX_CLK_SCL")
	)
	(segment
		(start 229.2096 -139.540234)
		(end 229.2096 -140.970762)
		(width 0.13208)
		(layer "F.Cu")
		(net "SMB_CK440_PEX_CLK_SCL")
	)
	(segment
		(start 226.74961 -137.956798)
		(end 225.915474 -137.122662)
		(width 0.13208)
		(layer "F.Cu")
		(net "SMB_CK440_PEX_CLK_SCL")
	)
	(segment
		(start 229.2096 -140.970762)
		(end 229.846886 -141.608048)
		(width 0.13208)
		(layer "F.Cu")
		(net "SMB_CK440_PEX_CLK_SCL")
	)
	(segment
		(start 228.013006 -138.34364)
		(end 229.2096 -139.540234)
		(width 0.13208)
		(layer "F.Cu")
		(net "SMB_CK440_PEX_CLK_SCL")
	)
	(segment
		(start 228.013006 -138.34364)
		(end 227.626164 -137.956798)
		(width 0.13208)
		(layer "F.Cu")
		(net "SMB_CK440_PEX_CLK_SCL")
	)
	(segment
		(start 229.846886 -141.608048)
		(end 229.846886 -143.265398)
		(width 0.13208)
		(layer "F.Cu")
		(net "SMB_CK440_PEX_CLK_SCL")
	)
	(segment
		(start 227.626164 -137.956798)
		(end 226.74961 -137.956798)
		(width 0.13208)
		(layer "F.Cu")
		(net "SMB_CK440_PEX_CLK_SCL")
	)
	(via
		(at 228.013006 -138.34364)
		(size 0.762)
		(drill 0.381)
		(layers "F.Cu" "B.Cu")
		(net "SMB_CK440_PEX_CLK_SCL")
	)
	(segment
		(start 211.906866 -366.991646)
		(end 212.532976 -366.991646)
		(width 0.13208)
		(layer "F.Cu")
		(net "HSC_ON")
	)
	(segment
		(start 224.451926 -371.058186)
		(end 224.059242 -371.058186)
		(width 0.13208)
		(layer "F.Cu")
		(net "HSC_ON")
	)
	(segment
		(start 233.741976 -368.70767)
		(end 234.454954 -368.70767)
		(width 0.13208)
		(layer "F.Cu")
		(net "HSC_ON")
	)
	(segment
		(start 233.741976 -368.70767)
		(end 232.53192 -368.70767)
		(width 0.13208)
		(layer "F.Cu")
		(net "HSC_ON")
	)
	(segment
		(start 224.059242 -371.058186)
		(end 223.073976 -370.07292)
		(width 0.13208)
		(layer "F.Cu")
		(net "HSC_ON")
	)
	(segment
		(start 234.454954 -368.70767)
		(end 235.127038 -369.379754)
		(width 0.13208)
		(layer "F.Cu")
		(net "HSC_ON")
	)
	(segment
		(start 223.073976 -368.70767)
		(end 221.86392 -368.70767)
		(width 0.13208)
		(layer "F.Cu")
		(net "HSC_ON")
	)
	(segment
		(start 223.073976 -370.07292)
		(end 223.073976 -368.70767)
		(width 0.13208)
		(layer "F.Cu")
		(net "HSC_ON")
	)
	(via
		(at 223.073976 -368.70767)
		(size 0.508)
		(drill 0.254)
		(layers "F.Cu" "B.Cu")
		(net "HSC_ON")
	)
	(via
		(at 233.741976 -368.70767)
		(size 0.508)
		(drill 0.254)
		(layers "F.Cu" "B.Cu")
		(net "HSC_ON")
	)
	(via
		(at 212.532976 -366.991646)
		(size 0.508)
		(drill 0.254)
		(layers "F.Cu" "B.Cu")
		(net "HSC_ON")
	)
	(segment
		(start 232.740708 -360.8578)
		(end 233.743246 -361.860338)
		(width 0.13208)
		(layer "B.Cu")
		(net "HSC_ON")
	)
	(segment
		(start 233.586528 -368.552222)
		(end 233.741976 -368.70767)
		(width 0.13208)
		(layer "B.Cu")
		(net "HSC_ON")
	)
	(segment
		(start 223.073976 -361.674156)
		(end 223.073976 -368.70767)
		(width 0.13208)
		(layer "B.Cu")
		(net "HSC_ON")
	)
	(segment
		(start 225.325178 -368.505994)
		(end 227.112322 -366.71885)
		(width 0.13208)
		(layer "B.Cu")
		(net "HSC_ON")
	)
	(segment
		(start 215.942672 -364.860332)
		(end 215.942672 -361.754928)
		(width 0.13208)
		(layer "B.Cu")
		(net "HSC_ON")
	)
	(segment
		(start 222.358966 -360.959146)
		(end 223.073976 -361.674156)
		(width 0.13208)
		(layer "B.Cu")
		(net "HSC_ON")
	)
	(segment
		(start 228.149658 -360.8578)
		(end 232.740708 -360.8578)
		(width 0.13208)
		(layer "B.Cu")
		(net "HSC_ON")
	)
	(segment
		(start 223.073976 -368.70767)
		(end 223.275652 -368.505994)
		(width 0.13208)
		(layer "B.Cu")
		(net "HSC_ON")
	)
	(segment
		(start 213.041738 -366.482884)
		(end 214.32012 -366.482884)
		(width 0.13208)
		(layer "B.Cu")
		(net "HSC_ON")
	)
	(segment
		(start 212.532976 -366.991646)
		(end 213.041738 -366.482884)
		(width 0.13208)
		(layer "B.Cu")
		(net "HSC_ON")
	)
	(segment
		(start 227.112322 -366.71885)
		(end 227.112322 -361.895136)
		(width 0.13208)
		(layer "B.Cu")
		(net "HSC_ON")
	)
	(segment
		(start 215.942672 -361.754928)
		(end 216.738454 -360.959146)
		(width 0.13208)
		(layer "B.Cu")
		(net "HSC_ON")
	)
	(segment
		(start 214.32012 -366.482884)
		(end 215.942672 -364.860332)
		(width 0.13208)
		(layer "B.Cu")
		(net "HSC_ON")
	)
	(segment
		(start 233.743246 -361.860338)
		(end 233.743246 -366.949228)
		(width 0.13208)
		(layer "B.Cu")
		(net "HSC_ON")
	)
	(segment
		(start 233.743246 -366.949228)
		(end 233.586528 -367.105946)
		(width 0.13208)
		(layer "B.Cu")
		(net "HSC_ON")
	)
	(segment
		(start 216.738454 -360.959146)
		(end 222.358966 -360.959146)
		(width 0.13208)
		(layer "B.Cu")
		(net "HSC_ON")
	)
	(segment
		(start 227.112322 -361.895136)
		(end 228.149658 -360.8578)
		(width 0.13208)
		(layer "B.Cu")
		(net "HSC_ON")
	)
	(segment
		(start 233.586528 -367.105946)
		(end 233.586528 -368.552222)
		(width 0.13208)
		(layer "B.Cu")
		(net "HSC_ON")
	)
	(segment
		(start 223.275652 -368.505994)
		(end 225.325178 -368.505994)
		(width 0.13208)
		(layer "B.Cu")
		(net "HSC_ON")
	)
	(segment
		(start 354.875846 -37.592)
		(end 354.875846 -37.315648)
		(width 0.13208)
		(layer "F.Cu")
		(net "PRSNT_SSD12_R1_N")
	)
	(segment
		(start 352.197924 -38.937184)
		(end 352.197924 -38.16731)
		(width 0.13208)
		(layer "F.Cu")
		(net "PRSNT_SSD12_R1_N")
	)
	(segment
		(start 352.591116 -37.774118)
		(end 354.146866 -37.774118)
		(width 0.13208)
		(layer "F.Cu")
		(net "PRSNT_SSD12_R1_N")
	)
	(segment
		(start 354.693728 -37.774118)
		(end 354.875846 -37.592)
		(width 0.13208)
		(layer "F.Cu")
		(net "PRSNT_SSD12_R1_N")
	)
	(segment
		(start 354.146866 -37.774118)
		(end 354.693728 -37.774118)
		(width 0.13208)
		(layer "F.Cu")
		(net "PRSNT_SSD12_R1_N")
	)
	(segment
		(start 352.197924 -38.16731)
		(end 352.591116 -37.774118)
		(width 0.13208)
		(layer "F.Cu")
		(net "PRSNT_SSD12_R1_N")
	)
	(via
		(at 354.146866 -37.774118)
		(size 0.508)
		(drill 0.254)
		(layers "F.Cu" "B.Cu")
		(net "PRSNT_SSD12_R1_N")
	)
	(segment
		(start 96.692974 -239.728248)
		(end 97.753424 -240.788698)
		(width 0.13208)
		(layer "F.Cu")
		(net "SMB_PEX_P1V8_ADC_SCL")
	)
	(segment
		(start 97.753424 -240.788698)
		(end 97.753424 -241.83721)
		(width 0.13208)
		(layer "F.Cu")
		(net "SMB_PEX_P1V8_ADC_SCL")
	)
	(segment
		(start 95.505778 -239.728248)
		(end 96.692974 -239.728248)
		(width 0.13208)
		(layer "F.Cu")
		(net "SMB_PEX_P1V8_ADC_SCL")
	)
	(segment
		(start 95.505778 -238.753904)
		(end 95.505778 -239.728248)
		(width 0.13208)
		(layer "F.Cu")
		(net "SMB_PEX_P1V8_ADC_SCL")
	)
	(via
		(at 97.753424 -240.788698)
		(size 0.508)
		(drill 0.254)
		(layers "F.Cu" "B.Cu")
		(net "SMB_PEX_P1V8_ADC_SCL")
	)
	(segment
		(start 234.594146 -147.720812)
		(end 233.418634 -147.720812)
		(width 0.13208)
		(layer "F.Cu")
		(net "CLK_GEN_CK440_PEX_OE4_N")
	)
	(segment
		(start 233.418634 -147.720812)
		(end 232.999026 -148.14042)
		(width 0.13208)
		(layer "F.Cu")
		(net "CLK_GEN_CK440_PEX_OE4_N")
	)
	(segment
		(start 232.999026 -148.14042)
		(end 232.850182 -148.14042)
		(width 0.13208)
		(layer "F.Cu")
		(net "CLK_GEN_CK440_PEX_OE4_N")
	)
	(segment
		(start 232.850182 -148.14042)
		(end 231.721914 -148.14042)
		(width 0.0889)
		(layer "F.Cu")
		(net "CLK_GEN_CK440_PEX_OE4_N")
	)
	(segment
		(start 234.594146 -147.720812)
		(end 235.223558 -147.720812)
		(width 0.13208)
		(layer "F.Cu")
		(net "CLK_GEN_CK440_PEX_OE4_N")
	)
	(via
		(at 234.594146 -147.720812)
		(size 0.508)
		(drill 0.254)
		(layers "F.Cu" "B.Cu")
		(net "CLK_GEN_CK440_PEX_OE4_N")
	)
	(segment
		(start 194.948048 -368.243358)
		(end 195.18884 -368.243358)
		(width 0.13208)
		(layer "F.Cu")
		(net "FM_HSC_PWROK")
	)
	(segment
		(start 195.18884 -368.243358)
		(end 195.665852 -368.72037)
		(width 0.13208)
		(layer "F.Cu")
		(net "FM_HSC_PWROK")
	)
	(segment
		(start 196.980048 -367.344198)
		(end 197.42404 -367.344198)
		(width 0.13208)
		(layer "F.Cu")
		(net "FM_HSC_PWROK")
	)
	(segment
		(start 196.775578 -367.548668)
		(end 196.980048 -367.344198)
		(width 0.13208)
		(layer "F.Cu")
		(net "FM_HSC_PWROK")
	)
	(segment
		(start 196.775578 -368.26698)
		(end 196.775578 -367.548668)
		(width 0.13208)
		(layer "F.Cu")
		(net "FM_HSC_PWROK")
	)
	(segment
		(start 195.665852 -368.72037)
		(end 196.322188 -368.72037)
		(width 0.13208)
		(layer "F.Cu")
		(net "FM_HSC_PWROK")
	)
	(segment
		(start 201.083672 -371.370098)
		(end 202.626468 -371.370098)
		(width 0.13208)
		(layer "F.Cu")
		(net "FM_HSC_PWROK")
	)
	(segment
		(start 200.735184 -371.718586)
		(end 201.083672 -371.370098)
		(width 0.13208)
		(layer "F.Cu")
		(net "FM_HSC_PWROK")
	)
	(segment
		(start 202.668378 -371.328188)
		(end 202.668378 -371.194584)
		(width 0.13208)
		(layer "F.Cu")
		(net "FM_HSC_PWROK")
	)
	(segment
		(start 196.322188 -368.72037)
		(end 196.775578 -368.26698)
		(width 0.13208)
		(layer "F.Cu")
		(net "FM_HSC_PWROK")
	)
	(segment
		(start 202.626468 -371.370098)
		(end 202.668378 -371.328188)
		(width 0.13208)
		(layer "F.Cu")
		(net "FM_HSC_PWROK")
	)
	(via
		(at 200.735184 -371.718586)
		(size 0.762)
		(drill 0.254)
		(layers "F.Cu" "B.Cu")
		(net "FM_HSC_PWROK")
	)
	(via
		(at 197.42404 -367.344198)
		(size 0.508)
		(drill 0.254)
		(layers "F.Cu" "B.Cu")
		(net "FM_HSC_PWROK")
	)
	(segment
		(start 196.231002 -368.899694)
		(end 196.689218 -369.35791)
		(width 0.13208)
		(layer "B.Cu")
		(net "FM_HSC_PWROK")
	)
	(segment
		(start 200.735184 -371.718586)
		(end 200.27773 -371.718586)
		(width 0.13208)
		(layer "B.Cu")
		(net "FM_HSC_PWROK")
	)
	(segment
		(start 200.117202 -371.879114)
		(end 197.92823 -371.879114)
		(width 0.13208)
		(layer "B.Cu")
		(net "FM_HSC_PWROK")
	)
	(segment
		(start 197.42404 -367.344198)
		(end 196.94906 -367.344198)
		(width 0.13208)
		(layer "B.Cu")
		(net "FM_HSC_PWROK")
	)
	(segment
		(start 196.231002 -368.062256)
		(end 196.231002 -368.899694)
		(width 0.13208)
		(layer "B.Cu")
		(net "FM_HSC_PWROK")
	)
	(segment
		(start 196.28358 -370.234464)
		(end 196.28358 -369.497356)
		(width 0.13208)
		(layer "B.Cu")
		(net "FM_HSC_PWROK")
	)
	(segment
		(start 197.92823 -371.879114)
		(end 196.28358 -370.234464)
		(width 0.13208)
		(layer "B.Cu")
		(net "FM_HSC_PWROK")
	)
	(segment
		(start 196.94906 -367.344198)
		(end 196.231002 -368.062256)
		(width 0.13208)
		(layer "B.Cu")
		(net "FM_HSC_PWROK")
	)
	(segment
		(start 196.28358 -369.497356)
		(end 196.423026 -369.35791)
		(width 0.13208)
		(layer "B.Cu")
		(net "FM_HSC_PWROK")
	)
	(segment
		(start 200.27773 -371.718586)
		(end 200.117202 -371.879114)
		(width 0.13208)
		(layer "B.Cu")
		(net "FM_HSC_PWROK")
	)
	(segment
		(start 196.423026 -369.35791)
		(end 196.689218 -369.35791)
		(width 0.13208)
		(layer "B.Cu")
		(net "FM_HSC_PWROK")
	)
	(segment
		(start 235.909358 -211.587588)
		(end 235.909358 -210.784186)
		(width 0.2032)
		(layer "F.Cu")
		(net "P12V_AUX_SCALED")
	)
	(segment
		(start 239.754664 -206.91221)
		(end 238.738664 -206.91221)
		(width 0.2032)
		(layer "F.Cu")
		(net "P12V_AUX_SCALED")
	)
	(segment
		(start 236.261402 -208.988152)
		(end 237.722664 -207.52689)
		(width 0.2032)
		(layer "F.Cu")
		(net "P12V_AUX_SCALED")
	)
	(segment
		(start 236.261402 -210.37042)
		(end 236.261402 -208.988152)
		(width 0.2032)
		(layer "F.Cu")
		(net "P12V_AUX_SCALED")
	)
	(segment
		(start 236.16666 -210.526884)
		(end 236.16666 -210.465162)
		(width 0.2032)
		(layer "F.Cu")
		(net "P12V_AUX_SCALED")
	)
	(segment
		(start 235.067602 -212.429344)
		(end 235.909358 -211.587588)
		(width 0.2032)
		(layer "F.Cu")
		(net "P12V_AUX_SCALED")
	)
	(segment
		(start 235.909358 -210.784186)
		(end 236.16666 -210.526884)
		(width 0.2032)
		(layer "F.Cu")
		(net "P12V_AUX_SCALED")
	)
	(segment
		(start 237.722664 -207.52689)
		(end 237.722664 -206.91221)
		(width 0.2032)
		(layer "F.Cu")
		(net "P12V_AUX_SCALED")
	)
	(segment
		(start 236.16666 -210.465162)
		(end 236.261402 -210.37042)
		(width 0.2032)
		(layer "F.Cu")
		(net "P12V_AUX_SCALED")
	)
	(segment
		(start 234.667552 -213.504272)
		(end 235.067602 -213.104222)
		(width 0.2032)
		(layer "F.Cu")
		(net "P12V_AUX_SCALED")
	)
	(segment
		(start 235.067602 -213.104222)
		(end 235.067602 -212.429344)
		(width 0.1143)
		(layer "F.Cu")
		(net "P12V_AUX_SCALED")
	)
	(segment
		(start 238.738664 -206.91221)
		(end 237.722664 -206.91221)
		(width 0.2032)
		(layer "F.Cu")
		(net "P12V_AUX_SCALED")
	)
	(via
		(at 236.16666 -210.465162)
		(size 0.508)
		(drill 0.254)
		(layers "F.Cu" "B.Cu")
		(net "P12V_AUX_SCALED")
	)
	(segment
		(start 313.1058 -34.3662)
		(end 313.056016 -34.415984)
		(width 0.13208)
		(layer "F.Cu")
		(net "SSD11_AUX_P3V3_EN_R")
	)
	(segment
		(start 316.340744 -57.16397)
		(end 316.340744 -57.675272)
		(width 0.13208)
		(layer "F.Cu")
		(net "SSD11_AUX_P3V3_EN_R")
	)
	(segment
		(start 313.1058 -33.628584)
		(end 313.1058 -34.3662)
		(width 0.13208)
		(layer "F.Cu")
		(net "SSD11_AUX_P3V3_EN_R")
	)
	(segment
		(start 316.340744 -57.675272)
		(end 315.939932 -58.076084)
		(width 0.13208)
		(layer "F.Cu")
		(net "SSD11_AUX_P3V3_EN_R")
	)
	(segment
		(start 315.939932 -58.076084)
		(end 314.915042 -59.100974)
		(width 0.13208)
		(layer "F.Cu")
		(net "SSD11_AUX_P3V3_EN_R")
	)
	(segment
		(start 310.789828 -37.529516)
		(end 311.326022 -37.529516)
		(width 0.13208)
		(layer "F.Cu")
		(net "SSD11_AUX_P3V3_EN_R")
	)
	(segment
		(start 312.402474 -37.529516)
		(end 311.326022 -37.529516)
		(width 0.13208)
		(layer "F.Cu")
		(net "SSD11_AUX_P3V3_EN_R")
	)
	(segment
		(start 313.056016 -33.248092)
		(end 313.056016 -33.5788)
		(width 0.13208)
		(layer "F.Cu")
		(net "SSD11_AUX_P3V3_EN_R")
	)
	(segment
		(start 313.056016 -34.415984)
		(end 313.056016 -36.874958)
		(width 0.13208)
		(layer "F.Cu")
		(net "SSD11_AUX_P3V3_EN_R")
	)
	(segment
		(start 310.477662 -39.97198)
		(end 310.477662 -37.84092)
		(width 0.13208)
		(layer "F.Cu")
		(net "SSD11_AUX_P3V3_EN_R")
	)
	(segment
		(start 310.477662 -37.84092)
		(end 310.789828 -37.529516)
		(width 0.13208)
		(layer "F.Cu")
		(net "SSD11_AUX_P3V3_EN_R")
	)
	(segment
		(start 314.915042 -59.100974)
		(end 314.915042 -59.146186)
		(width 0.13208)
		(layer "F.Cu")
		(net "SSD11_AUX_P3V3_EN_R")
	)
	(segment
		(start 313.056016 -36.874958)
		(end 312.402474 -37.529516)
		(width 0.13208)
		(layer "F.Cu")
		(net "SSD11_AUX_P3V3_EN_R")
	)
	(segment
		(start 313.056016 -33.5788)
		(end 313.1058 -33.628584)
		(width 0.13208)
		(layer "F.Cu")
		(net "SSD11_AUX_P3V3_EN_R")
	)
	(via
		(at 315.939932 -58.076084)
		(size 0.508)
		(drill 0.254)
		(layers "F.Cu" "B.Cu")
		(net "SSD11_AUX_P3V3_EN_R")
	)
	(via
		(at 310.477662 -39.97198)
		(size 0.508)
		(drill 0.254)
		(layers "F.Cu" "B.Cu")
		(net "SSD11_AUX_P3V3_EN_R")
	)
	(segment
		(start 319.712848 -46.254162)
		(end 313.430666 -39.97198)
		(width 0.15494)
		(layer "In5.Cu")
		(net "SSD11_AUX_P3V3_EN_R")
	)
	(segment
		(start 315.939932 -58.076084)
		(end 319.712848 -54.303168)
		(width 0.15494)
		(layer "In5.Cu")
		(net "SSD11_AUX_P3V3_EN_R")
	)
	(segment
		(start 313.430666 -39.97198)
		(end 310.477662 -39.97198)
		(width 0.15494)
		(layer "In5.Cu")
		(net "SSD11_AUX_P3V3_EN_R")
	)
	(segment
		(start 319.712848 -54.303168)
		(end 319.712848 -46.254162)
		(width 0.15494)
		(layer "In5.Cu")
		(net "SSD11_AUX_P3V3_EN_R")
	)
	(segment
		(start 221.86392 -369.207542)
		(end 222.438976 -369.207542)
		(width 0.13208)
		(layer "F.Cu")
		(net "HSC_FAULT_N_1")
	)
	(via
		(at 223.310196 -370.725954)
		(size 0.6604)
		(drill 0.3302)
		(layers "F.Cu" "B.Cu")
		(net "HSC_FAULT_N_1")
	)
	(via
		(at 222.438976 -369.207542)
		(size 0.508)
		(drill 0.254)
		(layers "F.Cu" "B.Cu")
		(net "HSC_FAULT_N_1")
	)
	(segment
		(start 222.803974 -369.207542)
		(end 222.438976 -369.207542)
		(width 0.13208)
		(layer "B.Cu")
		(net "HSC_FAULT_N_1")
	)
	(segment
		(start 224.448624 -371.055138)
		(end 223.53397 -371.055138)
		(width 0.13208)
		(layer "B.Cu")
		(net "HSC_FAULT_N_1")
	)
	(segment
		(start 223.310196 -370.725954)
		(end 223.310196 -369.713764)
		(width 0.13208)
		(layer "B.Cu")
		(net "HSC_FAULT_N_1")
	)
	(segment
		(start 223.310196 -369.713764)
		(end 222.803974 -369.207542)
		(width 0.13208)
		(layer "B.Cu")
		(net "HSC_FAULT_N_1")
	)
	(segment
		(start 223.53397 -371.055138)
		(end 223.310196 -370.831364)
		(width 0.13208)
		(layer "B.Cu")
		(net "HSC_FAULT_N_1")
	)
	(segment
		(start 223.310196 -370.831364)
		(end 223.310196 -370.725954)
		(width 0.13208)
		(layer "B.Cu")
		(net "HSC_FAULT_N_1")
	)
	(segment
		(start 232.84815 -145.640298)
		(end 233.112056 -145.640298)
		(width 0.13208)
		(layer "F.Cu")
		(net "CLK_GEN_CK440_PEX_OE6_N")
	)
	(segment
		(start 235.223558 -145.688812)
		(end 234.57281 -145.688812)
		(width 0.13208)
		(layer "F.Cu")
		(net "CLK_GEN_CK440_PEX_OE6_N")
	)
	(segment
		(start 234.57281 -145.688812)
		(end 233.818176 -144.934178)
		(width 0.13208)
		(layer "F.Cu")
		(net "CLK_GEN_CK440_PEX_OE6_N")
	)
	(segment
		(start 233.112056 -145.640298)
		(end 233.818176 -144.934178)
		(width 0.13208)
		(layer "F.Cu")
		(net "CLK_GEN_CK440_PEX_OE6_N")
	)
	(segment
		(start 231.721914 -145.640298)
		(end 232.84815 -145.640298)
		(width 0.0889)
		(layer "F.Cu")
		(net "CLK_GEN_CK440_PEX_OE6_N")
	)
	(via
		(at 233.818176 -144.934178)
		(size 0.762)
		(drill 0.381)
		(layers "F.Cu" "B.Cu")
		(net "CLK_GEN_CK440_PEX_OE6_N")
	)
	(segment
		(start 204.018388 -366.719612)
		(end 204.018388 -365.612172)
		(width 0.13208)
		(layer "F.Cu")
		(net "HSC_SCREF")
	)
	(segment
		(start 224.451926 -375.122186)
		(end 223.835976 -375.122186)
		(width 0.13208)
		(layer "F.Cu")
		(net "HSC_SCREF")
	)
	(segment
		(start 213.910926 -371.337586)
		(end 213.294976 -371.337586)
		(width 0.13208)
		(layer "F.Cu")
		(net "HSC_SCREF")
	)
	(segment
		(start 204.018388 -365.612172)
		(end 203.595986 -365.18977)
		(width 0.13208)
		(layer "F.Cu")
		(net "HSC_SCREF")
	)
	(segment
		(start 203.595986 -365.18977)
		(end 203.595986 -364.396274)
		(width 0.13208)
		(layer "F.Cu")
		(net "HSC_SCREF")
	)
	(segment
		(start 203.595986 -364.396274)
		(end 202.844654 -363.644942)
		(width 0.13208)
		(layer "F.Cu")
		(net "HSC_SCREF")
	)
	(via
		(at 202.844654 -363.644942)
		(size 0.508)
		(drill 0.254)
		(layers "F.Cu" "B.Cu")
		(net "HSC_SCREF")
	)
	(via
		(at 223.835976 -375.122186)
		(size 0.508)
		(drill 0.254)
		(layers "F.Cu" "B.Cu")
		(net "HSC_SCREF")
	)
	(via
		(at 213.294976 -371.337586)
		(size 0.508)
		(drill 0.254)
		(layers "F.Cu" "B.Cu")
		(net "HSC_SCREF")
	)
	(segment
		(start 221.869 -367.613692)
		(end 222.935546 -366.547146)
		(width 0.15494)
		(layer "In13.Cu")
		(net "HSC_SCREF")
	)
	(segment
		(start 212.913976 -371.718586)
		(end 210.985354 -371.718586)
		(width 0.15494)
		(layer "In13.Cu")
		(net "HSC_SCREF")
	)
	(segment
		(start 223.835976 -375.122186)
		(end 221.869 -373.15521)
		(width 0.15494)
		(layer "In13.Cu")
		(net "HSC_SCREF")
	)
	(segment
		(start 205.097888 -361.391708)
		(end 202.844654 -363.644942)
		(width 0.15494)
		(layer "In13.Cu")
		(net "HSC_SCREF")
	)
	(segment
		(start 222.525844 -361.076494)
		(end 217.3859 -361.076494)
		(width 0.15494)
		(layer "In13.Cu")
		(net "HSC_SCREF")
	)
	(segment
		(start 217.3859 -361.076494)
		(end 216.944702 -361.517692)
		(width 0.15494)
		(layer "In13.Cu")
		(net "HSC_SCREF")
	)
	(segment
		(start 216.944702 -361.517692)
		(end 216.944702 -368.249708)
		(width 0.15494)
		(layer "In13.Cu")
		(net "HSC_SCREF")
	)
	(segment
		(start 212.104478 -362.243116)
		(end 211.25307 -361.391708)
		(width 0.15494)
		(layer "In13.Cu")
		(net "HSC_SCREF")
	)
	(segment
		(start 210.575398 -371.30863)
		(end 210.575398 -366.074198)
		(width 0.15494)
		(layer "In13.Cu")
		(net "HSC_SCREF")
	)
	(segment
		(start 222.935546 -361.486196)
		(end 222.525844 -361.076494)
		(width 0.15494)
		(layer "In13.Cu")
		(net "HSC_SCREF")
	)
	(segment
		(start 211.25307 -361.391708)
		(end 205.097888 -361.391708)
		(width 0.15494)
		(layer "In13.Cu")
		(net "HSC_SCREF")
	)
	(segment
		(start 212.104478 -364.545118)
		(end 212.104478 -362.243116)
		(width 0.15494)
		(layer "In13.Cu")
		(net "HSC_SCREF")
	)
	(segment
		(start 221.869 -373.15521)
		(end 221.869 -367.613692)
		(width 0.15494)
		(layer "In13.Cu")
		(net "HSC_SCREF")
	)
	(segment
		(start 210.985354 -371.718586)
		(end 210.575398 -371.30863)
		(width 0.15494)
		(layer "In13.Cu")
		(net "HSC_SCREF")
	)
	(segment
		(start 213.856824 -371.337586)
		(end 213.294976 -371.337586)
		(width 0.15494)
		(layer "In13.Cu")
		(net "HSC_SCREF")
	)
	(segment
		(start 210.575398 -366.074198)
		(end 212.104478 -364.545118)
		(width 0.15494)
		(layer "In13.Cu")
		(net "HSC_SCREF")
	)
	(segment
		(start 216.944702 -368.249708)
		(end 213.856824 -371.337586)
		(width 0.15494)
		(layer "In13.Cu")
		(net "HSC_SCREF")
	)
	(segment
		(start 222.935546 -366.547146)
		(end 222.935546 -361.486196)
		(width 0.15494)
		(layer "In13.Cu")
		(net "HSC_SCREF")
	)
	(segment
		(start 213.294976 -371.337586)
		(end 212.913976 -371.718586)
		(width 0.15494)
		(layer "In13.Cu")
		(net "HSC_SCREF")
	)
	(segment
		(start 237.02645 -202.760834)
		(end 236.418374 -202.760834)
		(width 0.13208)
		(layer "F.Cu")
		(net "BMC_HEARTBEAT_N_D")
	)
	(segment
		(start 237.033054 -202.767438)
		(end 237.02645 -202.760834)
		(width 0.13208)
		(layer "F.Cu")
		(net "BMC_HEARTBEAT_N_D")
	)
	(segment
		(start 237.033054 -203.552044)
		(end 237.033054 -202.767438)
		(width 0.13208)
		(layer "F.Cu")
		(net "BMC_HEARTBEAT_N_D")
	)
	(segment
		(start 236.757718 -203.82738)
		(end 237.033054 -203.552044)
		(width 0.13208)
		(layer "F.Cu")
		(net "BMC_HEARTBEAT_N_D")
	)
	(via
		(at 237.033054 -202.767438)
		(size 0.508)
		(drill 0.254)
		(layers "F.Cu" "B.Cu")
		(net "BMC_HEARTBEAT_N_D")
	)
	(segment
		(start 315.04763 -40.185086)
		(end 314.92063 -40.058086)
		(width 0.13208)
		(layer "F.Cu")
		(net "SSD11_AUX_P3V3_EN")
	)
	(segment
		(start 313.302396 -40.058086)
		(end 312.58002 -39.33571)
		(width 0.13208)
		(layer "F.Cu")
		(net "SSD11_AUX_P3V3_EN")
	)
	(segment
		(start 312.58002 -39.33571)
		(end 311.326022 -39.33571)
		(width 0.13208)
		(layer "F.Cu")
		(net "SSD11_AUX_P3V3_EN")
	)
	(segment
		(start 314.92063 -40.058086)
		(end 313.302396 -40.058086)
		(width 0.13208)
		(layer "F.Cu")
		(net "SSD11_AUX_P3V3_EN")
	)
	(segment
		(start 311.326022 -38.329616)
		(end 311.326022 -39.33571)
		(width 0.13208)
		(layer "F.Cu")
		(net "SSD11_AUX_P3V3_EN")
	)
	(segment
		(start 315.04763 -41.137332)
		(end 315.04763 -40.185086)
		(width 0.13208)
		(layer "F.Cu")
		(net "SSD11_AUX_P3V3_EN")
	)
	(via
		(at 312.58002 -39.33571)
		(size 0.762)
		(drill 0.381)
		(layers "F.Cu" "B.Cu")
		(net "SSD11_AUX_P3V3_EN")
	)
	(segment
		(start 228.347016 -142.895828)
		(end 228.347016 -143.265398)
		(width 0.0889)
		(layer "F.Cu")
		(net "TP_CLK_CK440_PEX_PFT_OUT_DN")
	)
	(segment
		(start 227.289868 -142.1638)
		(end 227.616512 -142.1638)
		(width 0.13208)
		(layer "F.Cu")
		(net "TP_CLK_CK440_PEX_PFT_OUT_DN")
	)
	(segment
		(start 226.958144 -141.832076)
		(end 227.289868 -142.1638)
		(width 0.13208)
		(layer "F.Cu")
		(net "TP_CLK_CK440_PEX_PFT_OUT_DN")
	)
	(segment
		(start 227.643944 -142.192756)
		(end 228.347016 -142.895828)
		(width 0.0889)
		(layer "F.Cu")
		(net "TP_CLK_CK440_PEX_PFT_OUT_DN")
	)
	(segment
		(start 227.616512 -142.1638)
		(end 227.643944 -142.191232)
		(width 0.0889)
		(layer "F.Cu")
		(net "TP_CLK_CK440_PEX_PFT_OUT_DN")
	)
	(segment
		(start 227.643944 -142.191232)
		(end 227.643944 -142.192756)
		(width 0.0889)
		(layer "F.Cu")
		(net "TP_CLK_CK440_PEX_PFT_OUT_DN")
	)
	(via
		(at 226.958144 -141.832076)
		(size 0.762)
		(drill 0.381)
		(layers "F.Cu" "B.Cu")
		(net "TP_CLK_CK440_PEX_PFT_OUT_DN")
	)
	(segment
		(start 203.5683 -366.167162)
		(end 203.354178 -365.95304)
		(width 0.13208)
		(layer "F.Cu")
		(net "HSC_VOSEN")
	)
	(segment
		(start 203.354178 -365.95304)
		(end 203.052426 -365.651288)
		(width 0.13208)
		(layer "F.Cu")
		(net "HSC_VOSEN")
	)
	(segment
		(start 203.052426 -365.651288)
		(end 203.052426 -364.885986)
		(width 0.13208)
		(layer "F.Cu")
		(net "HSC_VOSEN")
	)
	(segment
		(start 203.5683 -366.719612)
		(end 203.5683 -366.167162)
		(width 0.13208)
		(layer "F.Cu")
		(net "HSC_VOSEN")
	)
	(via
		(at 203.354178 -365.95304)
		(size 0.508)
		(drill 0.254)
		(layers "F.Cu" "B.Cu")
		(net "HSC_VOSEN")
	)
	(segment
		(start 203.027026 -365.674148)
		(end 203.270358 -365.91748)
		(width 0.13208)
		(layer "B.Cu")
		(net "HSC_VOSEN")
	)
	(segment
		(start 203.318618 -365.91748)
		(end 203.354178 -365.95304)
		(width 0.13208)
		(layer "B.Cu")
		(net "HSC_VOSEN")
	)
	(segment
		(start 203.270358 -365.91748)
		(end 203.318618 -365.91748)
		(width 0.13208)
		(layer "B.Cu")
		(net "HSC_VOSEN")
	)
	(segment
		(start 203.027026 -365.268256)
		(end 203.027026 -365.674148)
		(width 0.13208)
		(layer "B.Cu")
		(net "HSC_VOSEN")
	)
	(segment
		(start 203.033122 -364.80496)
		(end 203.033122 -365.26216)
		(width 0.13208)
		(layer "B.Cu")
		(net "HSC_VOSEN")
	)
	(segment
		(start 203.033122 -365.26216)
		(end 203.027026 -365.268256)
		(width 0.13208)
		(layer "B.Cu")
		(net "HSC_VOSEN")
	)
	(segment
		(start 204.030326 -364.80496)
		(end 203.033122 -364.80496)
		(width 0.13208)
		(layer "B.Cu")
		(net "HSC_VOSEN")
	)
	(segment
		(start 316.046612 -37.774118)
		(end 316.593474 -37.774118)
		(width 0.13208)
		(layer "F.Cu")
		(net "PRSNT_SSD11_R1_N")
	)
	(segment
		(start 316.775592 -37.592)
		(end 316.775592 -37.315648)
		(width 0.13208)
		(layer "F.Cu")
		(net "PRSNT_SSD11_R1_N")
	)
	(segment
		(start 314.09767 -38.16731)
		(end 314.490862 -37.774118)
		(width 0.13208)
		(layer "F.Cu")
		(net "PRSNT_SSD11_R1_N")
	)
	(segment
		(start 314.09767 -38.937184)
		(end 314.09767 -38.16731)
		(width 0.13208)
		(layer "F.Cu")
		(net "PRSNT_SSD11_R1_N")
	)
	(segment
		(start 314.490862 -37.774118)
		(end 316.046612 -37.774118)
		(width 0.13208)
		(layer "F.Cu")
		(net "PRSNT_SSD11_R1_N")
	)
	(segment
		(start 316.593474 -37.774118)
		(end 316.775592 -37.592)
		(width 0.13208)
		(layer "F.Cu")
		(net "PRSNT_SSD11_R1_N")
	)
	(via
		(at 316.046612 -37.774118)
		(size 0.508)
		(drill 0.254)
		(layers "F.Cu" "B.Cu")
		(net "PRSNT_SSD11_R1_N")
	)
	(segment
		(start 214.965026 -368.600736)
		(end 215.784176 -368.600736)
		(width 0.254)
		(layer "F.Cu")
		(net "HSC_VDD_1")
	)
	(segment
		(start 215.89111 -368.70767)
		(end 217.388948 -368.70767)
		(width 0.254)
		(layer "F.Cu")
		(net "HSC_VDD_1")
	)
	(segment
		(start 215.784176 -368.600736)
		(end 215.89111 -368.70767)
		(width 0.254)
		(layer "F.Cu")
		(net "HSC_VDD_1")
	)
	(segment
		(start 214.895176 -368.670586)
		(end 214.965026 -368.600736)
		(width 0.254)
		(layer "F.Cu")
		(net "HSC_VDD_1")
	)
	(via
		(at 214.895176 -368.670586)
		(size 0.508)
		(drill 0.254)
		(layers "F.Cu" "B.Cu")
		(net "HSC_VDD_1")
	)
	(via
		(at 214.2871 -368.184684)
		(size 0.6604)
		(drill 0.3302)
		(layers "F.Cu" "B.Cu")
		(net "HSC_VDD_1")
	)
	(segment
		(start 214.431626 -369.356386)
		(end 214.2871 -369.21186)
		(width 0.254)
		(layer "B.Cu")
		(net "HSC_VDD_1")
	)
	(segment
		(start 214.2871 -368.184684)
		(end 214.409274 -368.184684)
		(width 0.254)
		(layer "B.Cu")
		(net "HSC_VDD_1")
	)
	(segment
		(start 214.2871 -369.21186)
		(end 214.2871 -368.184684)
		(width 0.254)
		(layer "B.Cu")
		(net "HSC_VDD_1")
	)
	(segment
		(start 214.409274 -368.184684)
		(end 214.895176 -368.670586)
		(width 0.254)
		(layer "B.Cu")
		(net "HSC_VDD_1")
	)
	(segment
		(start 287.056068 -33.248092)
		(end 287.0962 -33.288224)
		(width 0.13208)
		(layer "F.Cu")
		(net "SSD10_AUX_P3V3_EN_R")
	)
	(segment
		(start 288.915094 -59.100974)
		(end 289.939984 -58.076084)
		(width 0.13208)
		(layer "F.Cu")
		(net "SSD10_AUX_P3V3_EN_R")
	)
	(segment
		(start 287.0962 -33.288224)
		(end 287.0962 -36.834826)
		(width 0.13208)
		(layer "F.Cu")
		(net "SSD10_AUX_P3V3_EN_R")
	)
	(segment
		(start 284.78988 -37.529516)
		(end 285.326074 -37.529516)
		(width 0.13208)
		(layer "F.Cu")
		(net "SSD10_AUX_P3V3_EN_R")
	)
	(segment
		(start 290.340796 -57.16397)
		(end 290.340796 -57.675272)
		(width 0.13208)
		(layer "F.Cu")
		(net "SSD10_AUX_P3V3_EN_R")
	)
	(segment
		(start 284.477714 -37.84092)
		(end 284.78988 -37.529516)
		(width 0.13208)
		(layer "F.Cu")
		(net "SSD10_AUX_P3V3_EN_R")
	)
	(segment
		(start 287.0962 -36.834826)
		(end 286.402526 -37.529516)
		(width 0.13208)
		(layer "F.Cu")
		(net "SSD10_AUX_P3V3_EN_R")
	)
	(segment
		(start 284.477714 -39.97198)
		(end 284.477714 -37.84092)
		(width 0.13208)
		(layer "F.Cu")
		(net "SSD10_AUX_P3V3_EN_R")
	)
	(segment
		(start 290.340796 -57.675272)
		(end 289.939984 -58.076084)
		(width 0.13208)
		(layer "F.Cu")
		(net "SSD10_AUX_P3V3_EN_R")
	)
	(segment
		(start 286.402526 -37.529516)
		(end 285.326074 -37.529516)
		(width 0.13208)
		(layer "F.Cu")
		(net "SSD10_AUX_P3V3_EN_R")
	)
	(segment
		(start 288.915094 -59.146186)
		(end 288.915094 -59.100974)
		(width 0.13208)
		(layer "F.Cu")
		(net "SSD10_AUX_P3V3_EN_R")
	)
	(via
		(at 289.939984 -58.076084)
		(size 0.508)
		(drill 0.254)
		(layers "F.Cu" "B.Cu")
		(net "SSD10_AUX_P3V3_EN_R")
	)
	(via
		(at 284.477714 -39.97198)
		(size 0.508)
		(drill 0.254)
		(layers "F.Cu" "B.Cu")
		(net "SSD10_AUX_P3V3_EN_R")
	)
	(segment
		(start 293.67226 -54.343808)
		(end 293.67226 -45.993304)
		(width 0.15494)
		(layer "In5.Cu")
		(net "SSD10_AUX_P3V3_EN_R")
	)
	(segment
		(start 287.650936 -39.97198)
		(end 284.477714 -39.97198)
		(width 0.15494)
		(layer "In5.Cu")
		(net "SSD10_AUX_P3V3_EN_R")
	)
	(segment
		(start 289.939984 -58.076084)
		(end 293.67226 -54.343808)
		(width 0.15494)
		(layer "In5.Cu")
		(net "SSD10_AUX_P3V3_EN_R")
	)
	(segment
		(start 293.67226 -45.993304)
		(end 287.650936 -39.97198)
		(width 0.15494)
		(layer "In5.Cu")
		(net "SSD10_AUX_P3V3_EN_R")
	)
	(segment
		(start 246.5832 -278.668988)
		(end 246.5832 -279.440386)
		(width 0.13208)
		(layer "F.Cu")
		(net "SMB_PEX2_P1V25_ADC_SDA")
	)
	(segment
		(start 246.5832 -279.440386)
		(end 246.7102 -279.567386)
		(width 0.13208)
		(layer "F.Cu")
		(net "SMB_PEX2_P1V25_ADC_SDA")
	)
	(segment
		(start 247.694704 -279.567386)
		(end 247.085104 -279.567386)
		(width 0.13208)
		(layer "F.Cu")
		(net "SMB_PEX2_P1V25_ADC_SDA")
	)
	(segment
		(start 246.097044 -278.541988)
		(end 246.4562 -278.541988)
		(width 0.13208)
		(layer "F.Cu")
		(net "SMB_PEX2_P1V25_ADC_SDA")
	)
	(segment
		(start 246.7102 -279.567386)
		(end 247.085104 -279.567386)
		(width 0.13208)
		(layer "F.Cu")
		(net "SMB_PEX2_P1V25_ADC_SDA")
	)
	(segment
		(start 246.4562 -278.541988)
		(end 246.5832 -278.668988)
		(width 0.13208)
		(layer "F.Cu")
		(net "SMB_PEX2_P1V25_ADC_SDA")
	)
	(via
		(at 247.085104 -279.567386)
		(size 0.508)
		(drill 0.254)
		(layers "F.Cu" "B.Cu")
		(net "SMB_PEX2_P1V25_ADC_SDA")
	)
	(segment
		(start 224.096072 -145.520918)
		(end 224.226628 -145.390362)
		(width 0.0889)
		(layer "F.Cu")
		(net "TP_CK440_PEX_SBI_DATA_OUT")
	)
	(segment
		(start 222.844106 -145.899632)
		(end 223.22282 -145.520918)
		(width 0.13208)
		(layer "F.Cu")
		(net "TP_CK440_PEX_SBI_DATA_OUT")
	)
	(segment
		(start 224.226628 -145.390362)
		(end 224.721928 -145.390362)
		(width 0.0889)
		(layer "F.Cu")
		(net "TP_CK440_PEX_SBI_DATA_OUT")
	)
	(segment
		(start 223.22282 -145.520918)
		(end 223.90354 -145.520918)
		(width 0.13208)
		(layer "F.Cu")
		(net "TP_CK440_PEX_SBI_DATA_OUT")
	)
	(segment
		(start 223.90354 -145.520918)
		(end 224.096072 -145.520918)
		(width 0.0889)
		(layer "F.Cu")
		(net "TP_CK440_PEX_SBI_DATA_OUT")
	)
	(via
		(at 222.844106 -145.899632)
		(size 0.762)
		(drill 0.381)
		(layers "F.Cu" "B.Cu")
		(net "TP_CK440_PEX_SBI_DATA_OUT")
	)
	(segment
		(start 211.906866 -365.975646)
		(end 212.522816 -365.975646)
		(width 0.13208)
		(layer "F.Cu")
		(net "HSC_VDD")
	)
	(via
		(at 223.835976 -370.042186)
		(size 0.508)
		(drill 0.254)
		(layers "F.Cu" "B.Cu")
		(net "HSC_VDD")
	)
	(via
		(at 197.54215 -368.349022)
		(size 0.508)
		(drill 0.254)
		(layers "F.Cu" "B.Cu")
		(net "HSC_VDD")
	)
	(via
		(at 212.522816 -365.975646)
		(size 0.508)
		(drill 0.254)
		(layers "F.Cu" "B.Cu")
		(net "HSC_VDD")
	)
	(via
		(at 212.210396 -370.178838)
		(size 0.508)
		(drill 0.254)
		(layers "F.Cu" "B.Cu")
		(net "HSC_VDD")
	)
	(segment
		(start 198.139558 -367.333276)
		(end 198.280274 -367.473992)
		(width 0.254)
		(layer "B.Cu")
		(net "HSC_VDD")
	)
	(segment
		(start 213.631526 -369.494816)
		(end 213.498938 -369.627404)
		(width 0.254)
		(layer "B.Cu")
		(net "HSC_VDD")
	)
	(segment
		(start 213.631526 -369.356386)
		(end 213.631526 -369.494816)
		(width 0.254)
		(layer "B.Cu")
		(net "HSC_VDD")
	)
	(segment
		(start 198.280274 -367.473992)
		(end 198.280274 -368.32159)
		(width 0.254)
		(layer "B.Cu")
		(net "HSC_VDD")
	)
	(segment
		(start 213.498938 -369.627404)
		(end 213.079076 -369.627404)
		(width 0.254)
		(layer "B.Cu")
		(net "HSC_VDD")
	)
	(segment
		(start 198.252842 -368.349022)
		(end 197.54215 -368.349022)
		(width 0.254)
		(layer "B.Cu")
		(net "HSC_VDD")
	)
	(segment
		(start 212.527642 -370.178838)
		(end 212.210396 -370.178838)
		(width 0.254)
		(layer "B.Cu")
		(net "HSC_VDD")
	)
	(segment
		(start 211.810092 -369.778534)
		(end 212.210396 -370.178838)
		(width 0.4572)
		(layer "B.Cu")
		(net "HSC_VDD")
	)
	(segment
		(start 213.079076 -369.627404)
		(end 212.527642 -370.178838)
		(width 0.254)
		(layer "B.Cu")
		(net "HSC_VDD")
	)
	(segment
		(start 198.280274 -368.32159)
		(end 198.252842 -368.349022)
		(width 0.254)
		(layer "B.Cu")
		(net "HSC_VDD")
	)
	(segment
		(start 211.810092 -368.806222)
		(end 211.810092 -369.778534)
		(width 0.4572)
		(layer "B.Cu")
		(net "HSC_VDD")
	)
	(segment
		(start 224.451926 -370.042186)
		(end 223.835976 -370.042186)
		(width 0.254)
		(layer "B.Cu")
		(net "HSC_VDD")
	)
	(segment
		(start 211.94903 -366.549432)
		(end 211.94903 -369.917472)
		(width 0.15494)
		(layer "In7.Cu")
		(net "HSC_VDD")
	)
	(segment
		(start 212.522816 -365.975646)
		(end 211.94903 -366.549432)
		(width 0.15494)
		(layer "In7.Cu")
		(net "HSC_VDD")
	)
	(segment
		(start 211.94903 -369.917472)
		(end 212.210396 -370.178838)
		(width 0.15494)
		(layer "In7.Cu")
		(net "HSC_VDD")
	)
	(segment
		(start 199.526652 -369.825524)
		(end 200.138284 -369.825524)
		(width 0.254)
		(layer "In9.Cu")
		(net "HSC_VDD")
	)
	(segment
		(start 200.138284 -369.825524)
		(end 201.439526 -371.126766)
		(width 0.254)
		(layer "In9.Cu")
		(net "HSC_VDD")
	)
	(segment
		(start 212.630766 -369.758468)
		(end 213.956646 -369.758468)
		(width 0.254)
		(layer "In9.Cu")
		(net "HSC_VDD")
	)
	(segment
		(start 222.55226 -371.325902)
		(end 223.835976 -370.042186)
		(width 0.254)
		(layer "In9.Cu")
		(net "HSC_VDD")
	)
	(segment
		(start 211.465414 -370.178838)
		(end 212.210396 -370.178838)
		(width 0.254)
		(layer "In9.Cu")
		(net "HSC_VDD")
	)
	(segment
		(start 201.439526 -371.126766)
		(end 210.517486 -371.126766)
		(width 0.254)
		(layer "In9.Cu")
		(net "HSC_VDD")
	)
	(segment
		(start 213.956646 -369.758468)
		(end 215.52408 -371.325902)
		(width 0.254)
		(layer "In9.Cu")
		(net "HSC_VDD")
	)
	(segment
		(start 197.54215 -368.349022)
		(end 198.05015 -368.349022)
		(width 0.254)
		(layer "In9.Cu")
		(net "HSC_VDD")
	)
	(segment
		(start 198.05015 -368.349022)
		(end 199.526652 -369.825524)
		(width 0.254)
		(layer "In9.Cu")
		(net "HSC_VDD")
	)
	(segment
		(start 215.52408 -371.325902)
		(end 222.55226 -371.325902)
		(width 0.254)
		(layer "In9.Cu")
		(net "HSC_VDD")
	)
	(segment
		(start 212.210396 -370.178838)
		(end 212.630766 -369.758468)
		(width 0.254)
		(layer "In9.Cu")
		(net "HSC_VDD")
	)
	(segment
		(start 210.517486 -371.126766)
		(end 211.465414 -370.178838)
		(width 0.254)
		(layer "In9.Cu")
		(net "HSC_VDD")
	)
	(segment
		(start 233.54792 -369.207542)
		(end 233.727752 -369.387374)
		(width 0.13208)
		(layer "F.Cu")
		(net "HSC_FAULT_N_2")
	)
	(segment
		(start 233.106976 -369.207542)
		(end 233.54792 -369.207542)
		(width 0.13208)
		(layer "F.Cu")
		(net "HSC_FAULT_N_2")
	)
	(segment
		(start 233.727752 -369.387374)
		(end 234.154472 -369.387374)
		(width 0.13208)
		(layer "F.Cu")
		(net "HSC_FAULT_N_2")
	)
	(segment
		(start 232.53192 -369.207542)
		(end 233.106976 -369.207542)
		(width 0.1524)
		(layer "F.Cu")
		(net "HSC_FAULT_N_2")
	)
	(via
		(at 233.106976 -369.207542)
		(size 0.508)
		(drill 0.254)
		(layers "F.Cu" "B.Cu")
		(net "HSC_FAULT_N_2")
	)
	(segment
		(start 8.256778 -45.851318)
		(end 8.684514 -45.851318)
		(width 0.13208)
		(layer "F.Cu")
		(net "PRSNT_SSD0_R1_N")
	)
	(segment
		(start 8.684514 -45.851318)
		(end 8.861806 -45.674026)
		(width 0.13208)
		(layer "F.Cu")
		(net "PRSNT_SSD0_R1_N")
	)
	(segment
		(start 8.256778 -45.071792)
		(end 8.256778 -45.851318)
		(width 0.13208)
		(layer "F.Cu")
		(net "PRSNT_SSD0_R1_N")
	)
	(segment
		(start 8.861806 -45.674026)
		(end 8.861806 -45.071792)
		(width 0.13208)
		(layer "F.Cu")
		(net "PRSNT_SSD0_R1_N")
	)
	(segment
		(start 8.861806 -45.071792)
		(end 10.013442 -43.920156)
		(width 0.13208)
		(layer "F.Cu")
		(net "PRSNT_SSD0_R1_N")
	)
	(segment
		(start 10.013442 -43.920156)
		(end 10.013442 -43.368976)
		(width 0.13208)
		(layer "F.Cu")
		(net "PRSNT_SSD0_R1_N")
	)
	(via
		(at 8.256778 -45.851318)
		(size 0.508)
		(drill 0.254)
		(layers "F.Cu" "B.Cu")
		(net "PRSNT_SSD0_R1_N")
	)
	(segment
		(start 289.047682 -40.185086)
		(end 289.047682 -41.137332)
		(width 0.13208)
		(layer "F.Cu")
		(net "SSD10_AUX_P3V3_EN")
	)
	(segment
		(start 285.326074 -38.329616)
		(end 285.326074 -39.33571)
		(width 0.13208)
		(layer "F.Cu")
		(net "SSD10_AUX_P3V3_EN")
	)
	(segment
		(start 285.326074 -39.33571)
		(end 286.580072 -39.33571)
		(width 0.13208)
		(layer "F.Cu")
		(net "SSD10_AUX_P3V3_EN")
	)
	(segment
		(start 287.302448 -40.058086)
		(end 288.920682 -40.058086)
		(width 0.13208)
		(layer "F.Cu")
		(net "SSD10_AUX_P3V3_EN")
	)
	(segment
		(start 288.920682 -40.058086)
		(end 289.047682 -40.185086)
		(width 0.13208)
		(layer "F.Cu")
		(net "SSD10_AUX_P3V3_EN")
	)
	(segment
		(start 286.580072 -39.33571)
		(end 287.302448 -40.058086)
		(width 0.13208)
		(layer "F.Cu")
		(net "SSD10_AUX_P3V3_EN")
	)
	(via
		(at 286.580072 -39.33571)
		(size 0.762)
		(drill 0.381)
		(layers "F.Cu" "B.Cu")
		(net "SSD10_AUX_P3V3_EN")
	)
	(segment
		(start 211.111338 -370.11102)
		(end 211.111338 -369.44935)
		(width 0.13208)
		(layer "F.Cu")
		(net "HSC_MODE")
	)
	(segment
		(start 209.399378 -370.082064)
		(end 209.89671 -370.579396)
		(width 0.13208)
		(layer "F.Cu")
		(net "HSC_MODE")
	)
	(segment
		(start 209.89671 -370.579396)
		(end 210.642962 -370.579396)
		(width 0.13208)
		(layer "F.Cu")
		(net "HSC_MODE")
	)
	(segment
		(start 210.642962 -370.579396)
		(end 211.111338 -370.11102)
		(width 0.13208)
		(layer "F.Cu")
		(net "HSC_MODE")
	)
	(segment
		(start 208.605882 -370.082064)
		(end 209.399378 -370.082064)
		(width 0.13208)
		(layer "F.Cu")
		(net "HSC_MODE")
	)
	(via
		(at 209.89671 -370.579396)
		(size 0.508)
		(drill 0.254)
		(layers "F.Cu" "B.Cu")
		(net "HSC_MODE")
	)
	(segment
		(start 288.490914 -37.774118)
		(end 290.046664 -37.774118)
		(width 0.13208)
		(layer "F.Cu")
		(net "PRSNT_SSD10_R1_N")
	)
	(segment
		(start 290.775644 -37.592)
		(end 290.775644 -37.315648)
		(width 0.13208)
		(layer "F.Cu")
		(net "PRSNT_SSD10_R1_N")
	)
	(segment
		(start 290.046664 -37.774118)
		(end 290.593526 -37.774118)
		(width 0.13208)
		(layer "F.Cu")
		(net "PRSNT_SSD10_R1_N")
	)
	(segment
		(start 290.593526 -37.774118)
		(end 290.775644 -37.592)
		(width 0.13208)
		(layer "F.Cu")
		(net "PRSNT_SSD10_R1_N")
	)
	(segment
		(start 288.097722 -38.16731)
		(end 288.490914 -37.774118)
		(width 0.13208)
		(layer "F.Cu")
		(net "PRSNT_SSD10_R1_N")
	)
	(segment
		(start 288.097722 -38.937184)
		(end 288.097722 -38.16731)
		(width 0.13208)
		(layer "F.Cu")
		(net "PRSNT_SSD10_R1_N")
	)
	(via
		(at 290.046664 -37.774118)
		(size 0.508)
		(drill 0.254)
		(layers "F.Cu" "B.Cu")
		(net "PRSNT_SSD10_R1_N")
	)
	(segment
		(start 205.105508 -373.25554)
		(end 205.124304 -373.274336)
		(width 0.13208)
		(layer "F.Cu")
		(net "HSC_VINSEN")
	)
	(segment
		(start 204.468476 -372.198138)
		(end 204.472286 -372.201948)
		(width 0.13208)
		(layer "F.Cu")
		(net "HSC_VINSEN")
	)
	(segment
		(start 204.45222 -375.060464)
		(end 204.45222 -374.779032)
		(width 0.13208)
		(layer "F.Cu")
		(net "HSC_VINSEN")
	)
	(segment
		(start 204.472286 -373.25554)
		(end 205.105508 -373.25554)
		(width 0.13208)
		(layer "F.Cu")
		(net "HSC_VINSEN")
	)
	(segment
		(start 204.45222 -374.779032)
		(end 205.124304 -374.106948)
		(width 0.13208)
		(layer "F.Cu")
		(net "HSC_VINSEN")
	)
	(segment
		(start 205.124304 -374.106948)
		(end 205.124304 -373.274336)
		(width 0.13208)
		(layer "F.Cu")
		(net "HSC_VINSEN")
	)
	(segment
		(start 204.472286 -372.201948)
		(end 204.472286 -373.25554)
		(width 0.13208)
		(layer "F.Cu")
		(net "HSC_VINSEN")
	)
	(segment
		(start 204.468476 -371.194584)
		(end 204.468476 -372.198138)
		(width 0.13208)
		(layer "F.Cu")
		(net "HSC_VINSEN")
	)
	(via
		(at 205.124304 -373.274336)
		(size 0.508)
		(drill 0.254)
		(layers "F.Cu" "B.Cu")
		(net "HSC_VINSEN")
	)
	(segment
		(start 203.707492 -373.631714)
		(end 204.766926 -373.631714)
		(width 0.13208)
		(layer "B.Cu")
		(net "HSC_VINSEN")
	)
	(segment
		(start 204.766926 -373.631714)
		(end 205.124304 -373.274336)
		(width 0.13208)
		(layer "B.Cu")
		(net "HSC_VINSEN")
	)
	(segment
		(start 12.21359 -43.352466)
		(end 12.77239 -43.911266)
		(width 0.13208)
		(layer "F.Cu")
		(net "SSD0_AUX_P3V3_EN")
	)
	(segment
		(start 12.77239 -43.911266)
		(end 12.232894 -43.911266)
		(width 0.13208)
		(layer "F.Cu")
		(net "SSD0_AUX_P3V3_EN")
	)
	(segment
		(start 11.512804 -44.631356)
		(end 11.512804 -45.111924)
		(width 0.13208)
		(layer "F.Cu")
		(net "SSD0_AUX_P3V3_EN")
	)
	(segment
		(start 12.232894 -43.911266)
		(end 11.512804 -44.631356)
		(width 0.13208)
		(layer "F.Cu")
		(net "SSD0_AUX_P3V3_EN")
	)
	(segment
		(start 12.21359 -42.419016)
		(end 12.21359 -43.352466)
		(width 0.13208)
		(layer "F.Cu")
		(net "SSD0_AUX_P3V3_EN")
	)
	(segment
		(start 10.44321 -45.111924)
		(end 11.512804 -45.111924)
		(width 0.13208)
		(layer "F.Cu")
		(net "SSD0_AUX_P3V3_EN")
	)
	(via
		(at 12.77239 -43.911266)
		(size 0.762)
		(drill 0.381)
		(layers "F.Cu" "B.Cu")
		(net "SSD0_AUX_P3V3_EN")
	)
	(segment
		(start 258.477766 -37.84092)
		(end 258.789932 -37.529516)
		(width 0.13208)
		(layer "F.Cu")
		(net "SSD9_AUX_P3V3_EN_R")
	)
	(segment
		(start 262.915146 -59.100974)
		(end 262.915146 -59.146186)
		(width 0.13208)
		(layer "F.Cu")
		(net "SSD9_AUX_P3V3_EN_R")
	)
	(segment
		(start 258.477766 -39.97198)
		(end 258.477766 -37.84092)
		(width 0.13208)
		(layer "F.Cu")
		(net "SSD9_AUX_P3V3_EN_R")
	)
	(segment
		(start 264.340848 -57.675272)
		(end 263.940036 -58.076084)
		(width 0.13208)
		(layer "F.Cu")
		(net "SSD9_AUX_P3V3_EN_R")
	)
	(segment
		(start 261.0866 -33.278572)
		(end 261.0866 -36.844478)
		(width 0.13208)
		(layer "F.Cu")
		(net "SSD9_AUX_P3V3_EN_R")
	)
	(segment
		(start 260.402578 -37.529516)
		(end 259.326126 -37.529516)
		(width 0.13208)
		(layer "F.Cu")
		(net "SSD9_AUX_P3V3_EN_R")
	)
	(segment
		(start 258.789932 -37.529516)
		(end 259.326126 -37.529516)
		(width 0.13208)
		(layer "F.Cu")
		(net "SSD9_AUX_P3V3_EN_R")
	)
	(segment
		(start 263.940036 -58.076084)
		(end 262.915146 -59.100974)
		(width 0.13208)
		(layer "F.Cu")
		(net "SSD9_AUX_P3V3_EN_R")
	)
	(segment
		(start 264.340848 -57.16397)
		(end 264.340848 -57.675272)
		(width 0.13208)
		(layer "F.Cu")
		(net "SSD9_AUX_P3V3_EN_R")
	)
	(segment
		(start 261.05612 -33.248092)
		(end 261.0866 -33.278572)
		(width 0.13208)
		(layer "F.Cu")
		(net "SSD9_AUX_P3V3_EN_R")
	)
	(segment
		(start 261.0866 -36.844478)
		(end 260.402578 -37.529516)
		(width 0.13208)
		(layer "F.Cu")
		(net "SSD9_AUX_P3V3_EN_R")
	)
	(via
		(at 258.477766 -39.97198)
		(size 0.508)
		(drill 0.254)
		(layers "F.Cu" "B.Cu")
		(net "SSD9_AUX_P3V3_EN_R")
	)
	(via
		(at 263.940036 -58.076084)
		(size 0.508)
		(drill 0.254)
		(layers "F.Cu" "B.Cu")
		(net "SSD9_AUX_P3V3_EN_R")
	)
	(segment
		(start 267.692632 -54.323488)
		(end 267.692632 -46.013624)
		(width 0.15494)
		(layer "In5.Cu")
		(net "SSD9_AUX_P3V3_EN_R")
	)
	(segment
		(start 261.650988 -39.97198)
		(end 258.477766 -39.97198)
		(width 0.15494)
		(layer "In5.Cu")
		(net "SSD9_AUX_P3V3_EN_R")
	)
	(segment
		(start 267.692632 -46.013624)
		(end 261.650988 -39.97198)
		(width 0.15494)
		(layer "In5.Cu")
		(net "SSD9_AUX_P3V3_EN_R")
	)
	(segment
		(start 263.940036 -58.076084)
		(end 267.692632 -54.323488)
		(width 0.15494)
		(layer "In5.Cu")
		(net "SSD9_AUX_P3V3_EN_R")
	)
	(segment
		(start 234.545886 -138.25855)
		(end 233.123994 -138.25855)
		(width 0.13208)
		(layer "F.Cu")
		(net "XTAL_CK440_PEX_25M_R_XIN")
	)
	(segment
		(start 233.123994 -138.25855)
		(end 233.123994 -139.026392)
		(width 0.13208)
		(layer "F.Cu")
		(net "XTAL_CK440_PEX_25M_R_XIN")
	)
	(segment
		(start 234.685586 -137.288524)
		(end 234.685586 -138.11885)
		(width 0.13208)
		(layer "F.Cu")
		(net "XTAL_CK440_PEX_25M_R_XIN")
	)
	(segment
		(start 233.673904 -137.161524)
		(end 234.558586 -137.161524)
		(width 0.13208)
		(layer "F.Cu")
		(net "XTAL_CK440_PEX_25M_R_XIN")
	)
	(segment
		(start 233.123994 -139.026392)
		(end 232.9815 -139.168886)
		(width 0.13208)
		(layer "F.Cu")
		(net "XTAL_CK440_PEX_25M_R_XIN")
	)
	(segment
		(start 234.558586 -137.161524)
		(end 234.685586 -137.288524)
		(width 0.13208)
		(layer "F.Cu")
		(net "XTAL_CK440_PEX_25M_R_XIN")
	)
	(segment
		(start 232.9815 -139.168886)
		(end 232.9815 -140.09243)
		(width 0.13208)
		(layer "F.Cu")
		(net "XTAL_CK440_PEX_25M_R_XIN")
	)
	(segment
		(start 234.685586 -138.11885)
		(end 234.545886 -138.25855)
		(width 0.13208)
		(layer "F.Cu")
		(net "XTAL_CK440_PEX_25M_R_XIN")
	)
	(via
		(at 233.123994 -138.25855)
		(size 0.508)
		(drill 0.254)
		(layers "F.Cu" "B.Cu")
		(net "XTAL_CK440_PEX_25M_R_XIN")
	)
	(segment
		(start 226.593654 -372.770908)
		(end 226.510596 -372.853966)
		(width 0.13208)
		(layer "F.Cu")
		(net "HSC_SCREF_2")
	)
	(segment
		(start 228.044248 -370.707666)
		(end 228.044248 -371.320314)
		(width 0.13208)
		(layer "F.Cu")
		(net "HSC_SCREF_2")
	)
	(segment
		(start 226.510596 -374.146318)
		(end 225.534728 -375.122186)
		(width 0.13208)
		(layer "F.Cu")
		(net "HSC_SCREF_2")
	)
	(segment
		(start 226.510596 -372.853966)
		(end 226.510596 -374.146318)
		(width 0.13208)
		(layer "F.Cu")
		(net "HSC_SCREF_2")
	)
	(segment
		(start 228.044248 -371.320314)
		(end 226.593654 -372.770908)
		(width 0.13208)
		(layer "F.Cu")
		(net "HSC_SCREF_2")
	)
	(segment
		(start 225.534728 -375.122186)
		(end 225.252026 -375.122186)
		(width 0.13208)
		(layer "F.Cu")
		(net "HSC_SCREF_2")
	)
	(via
		(at 226.593654 -372.770908)
		(size 0.762)
		(drill 0.381)
		(layers "F.Cu" "B.Cu")
		(net "HSC_SCREF_2")
	)
	(segment
		(start 460.723742 -280.70683)
		(end 462.065624 -280.70683)
		(width 0.13208)
		(layer "F.Cu")
		(net "SMB_PEX3_P1V25_ADC_SCL")
	)
	(segment
		(start 460.640938 -280.624026)
		(end 460.723742 -280.70683)
		(width 0.13208)
		(layer "F.Cu")
		(net "SMB_PEX3_P1V25_ADC_SCL")
	)
	(segment
		(start 459.817978 -279.315418)
		(end 459.817978 -280.623264)
		(width 0.13208)
		(layer "F.Cu")
		(net "SMB_PEX3_P1V25_ADC_SCL")
	)
	(segment
		(start 459.817978 -280.623264)
		(end 459.81874 -280.624026)
		(width 0.13208)
		(layer "F.Cu")
		(net "SMB_PEX3_P1V25_ADC_SCL")
	)
	(segment
		(start 459.81874 -280.624026)
		(end 460.640938 -280.624026)
		(width 0.13208)
		(layer "F.Cu")
		(net "SMB_PEX3_P1V25_ADC_SCL")
	)
	(via
		(at 459.81874 -280.624026)
		(size 0.508)
		(drill 0.254)
		(layers "F.Cu" "B.Cu")
		(net "SMB_PEX3_P1V25_ADC_SCL")
	)
	(segment
		(start 361.58805 -172.974)
		(end 362.966 -172.974)
		(width 0.13208)
		(layer "F.Cu")
		(net "RST_PEX_SSD7_PERST_N")
	)
	(segment
		(start 362.966 -172.974)
		(end 364.487968 -174.495968)
		(width 0.13208)
		(layer "F.Cu")
		(net "RST_PEX_SSD7_PERST_N")
	)
	(segment
		(start 364.487968 -174.495968)
		(end 365.185452 -174.495968)
		(width 0.13208)
		(layer "F.Cu")
		(net "RST_PEX_SSD7_PERST_N")
	)
	(segment
		(start 365.706406 -175.016922)
		(end 366.263936 -175.016922)
		(width 0.13208)
		(layer "F.Cu")
		(net "RST_PEX_SSD7_PERST_N")
	)
	(segment
		(start 365.185452 -174.495968)
		(end 365.706406 -175.016922)
		(width 0.13208)
		(layer "F.Cu")
		(net "RST_PEX_SSD7_PERST_N")
	)
	(via
		(at 365.185452 -174.495968)
		(size 0.508)
		(drill 0.254)
		(layers "F.Cu" "B.Cu")
		(net "RST_PEX_SSD7_PERST_N")
	)
	(segment
		(start 227.84689 -142.729712)
		(end 227.84689 -143.265398)
		(width 0.0889)
		(layer "F.Cu")
		(net "TP_CLK_CK440_PEX_PFT_OUT_DP")
	)
	(segment
		(start 227.635816 -142.518638)
		(end 227.84689 -142.729712)
		(width 0.0889)
		(layer "F.Cu")
		(net "TP_CLK_CK440_PEX_PFT_OUT_DP")
	)
	(segment
		(start 225.536506 -141.817852)
		(end 226.153726 -142.435072)
		(width 0.13208)
		(layer "F.Cu")
		(net "TP_CLK_CK440_PEX_PFT_OUT_DP")
	)
	(segment
		(start 227.55225 -142.435072)
		(end 227.635816 -142.518638)
		(width 0.13208)
		(layer "F.Cu")
		(net "TP_CLK_CK440_PEX_PFT_OUT_DP")
	)
	(segment
		(start 226.153726 -142.435072)
		(end 227.55225 -142.435072)
		(width 0.13208)
		(layer "F.Cu")
		(net "TP_CLK_CK440_PEX_PFT_OUT_DP")
	)
	(via
		(at 225.536506 -141.817852)
		(size 0.762)
		(drill 0.381)
		(layers "F.Cu" "B.Cu")
		(net "TP_CLK_CK440_PEX_PFT_OUT_DP")
	)
	(segment
		(start 216.088976 -371.337586)
		(end 214.711026 -371.337586)
		(width 0.13208)
		(layer "F.Cu")
		(net "HSC_SCREF_1")
	)
	(segment
		(start 217.376248 -370.707666)
		(end 217.325448 -370.707666)
		(width 0.13208)
		(layer "F.Cu")
		(net "HSC_SCREF_1")
	)
	(segment
		(start 216.695528 -371.337586)
		(end 216.088976 -371.337586)
		(width 0.13208)
		(layer "F.Cu")
		(net "HSC_SCREF_1")
	)
	(segment
		(start 217.325448 -370.707666)
		(end 216.695528 -371.337586)
		(width 0.13208)
		(layer "F.Cu")
		(net "HSC_SCREF_1")
	)
	(via
		(at 216.088976 -371.337586)
		(size 0.762)
		(drill 0.381)
		(layers "F.Cu" "B.Cu")
		(net "HSC_SCREF_1")
	)
	(segment
		(start 260.580124 -39.33571)
		(end 261.3025 -40.058086)
		(width 0.13208)
		(layer "F.Cu")
		(net "SSD9_AUX_P3V3_EN")
	)
	(segment
		(start 263.047734 -40.185086)
		(end 263.047734 -41.137332)
		(width 0.13208)
		(layer "F.Cu")
		(net "SSD9_AUX_P3V3_EN")
	)
	(segment
		(start 262.920734 -40.058086)
		(end 263.047734 -40.185086)
		(width 0.13208)
		(layer "F.Cu")
		(net "SSD9_AUX_P3V3_EN")
	)
	(segment
		(start 259.326126 -38.329616)
		(end 259.326126 -39.33571)
		(width 0.13208)
		(layer "F.Cu")
		(net "SSD9_AUX_P3V3_EN")
	)
	(segment
		(start 259.326126 -39.33571)
		(end 260.580124 -39.33571)
		(width 0.13208)
		(layer "F.Cu")
		(net "SSD9_AUX_P3V3_EN")
	)
	(segment
		(start 261.3025 -40.058086)
		(end 262.920734 -40.058086)
		(width 0.13208)
		(layer "F.Cu")
		(net "SSD9_AUX_P3V3_EN")
	)
	(via
		(at 260.580124 -39.33571)
		(size 0.762)
		(drill 0.381)
		(layers "F.Cu" "B.Cu")
		(net "SSD9_AUX_P3V3_EN")
	)
	(segment
		(start 337.293966 -218.387168)
		(end 336.89417 -217.987372)
		(width 0.13208)
		(layer "F.Cu")
		(net "SSD10_PWRDIS_BIC_R")
	)
	(segment
		(start 232.823512 -233.912156)
		(end 233.295952 -233.439716)
		(width 0.13208)
		(layer "F.Cu")
		(net "SSD10_PWRDIS_BIC_R")
	)
	(segment
		(start 233.295952 -232.943908)
		(end 232.823512 -232.471468)
		(width 0.13208)
		(layer "F.Cu")
		(net "SSD10_PWRDIS_BIC_R")
	)
	(segment
		(start 232.823512 -232.471468)
		(end 232.283 -231.930956)
		(width 0.13208)
		(layer "F.Cu")
		(net "SSD10_PWRDIS_BIC_R")
	)
	(segment
		(start 232.823512 -234.327954)
		(end 232.823512 -233.912156)
		(width 0.13208)
		(layer "F.Cu")
		(net "SSD10_PWRDIS_BIC_R")
	)
	(segment
		(start 233.295952 -233.439716)
		(end 233.295952 -232.943908)
		(width 0.13208)
		(layer "F.Cu")
		(net "SSD10_PWRDIS_BIC_R")
	)
	(segment
		(start 232.283 -231.930956)
		(end 232.283 -231.79405)
		(width 0.13208)
		(layer "F.Cu")
		(net "SSD10_PWRDIS_BIC_R")
	)
	(via
		(at 336.89417 -217.987372)
		(size 0.4572)
		(drill 0.254)
		(layers "F.Cu" "B.Cu")
		(net "SSD10_PWRDIS_BIC_R")
	)
	(via
		(at 232.823512 -232.471468)
		(size 0.508)
		(drill 0.254)
		(layers "F.Cu" "B.Cu")
		(net "SSD10_PWRDIS_BIC_R")
	)
	(via
		(at 246.455946 -216.858342)
		(size 0.508)
		(drill 0.254)
		(layers "F.Cu" "B.Cu")
		(net "SSD10_PWRDIS_BIC_R")
	)
	(segment
		(start 232.823512 -232.471468)
		(end 232.823512 -231.920288)
		(width 0.15494)
		(layer "In7.Cu")
		(net "SSD10_PWRDIS_BIC_R")
	)
	(segment
		(start 235.9152 -228.8286)
		(end 237.256828 -228.8286)
		(width 0.15494)
		(layer "In7.Cu")
		(net "SSD10_PWRDIS_BIC_R")
	)
	(segment
		(start 246.888 -219.024454)
		(end 246.455946 -218.5924)
		(width 0.15494)
		(layer "In7.Cu")
		(net "SSD10_PWRDIS_BIC_R")
	)
	(segment
		(start 232.823512 -231.920288)
		(end 235.9152 -228.8286)
		(width 0.15494)
		(layer "In7.Cu")
		(net "SSD10_PWRDIS_BIC_R")
	)
	(segment
		(start 246.888 -222.5802)
		(end 246.888 -219.024454)
		(width 0.15494)
		(layer "In7.Cu")
		(net "SSD10_PWRDIS_BIC_R")
	)
	(segment
		(start 241.3254 -228.1428)
		(end 246.888 -222.5802)
		(width 0.15494)
		(layer "In7.Cu")
		(net "SSD10_PWRDIS_BIC_R")
	)
	(segment
		(start 246.455946 -218.5924)
		(end 246.455946 -216.858342)
		(width 0.15494)
		(layer "In7.Cu")
		(net "SSD10_PWRDIS_BIC_R")
	)
	(segment
		(start 237.256828 -228.8286)
		(end 237.942628 -228.1428)
		(width 0.15494)
		(layer "In7.Cu")
		(net "SSD10_PWRDIS_BIC_R")
	)
	(segment
		(start 237.942628 -228.1428)
		(end 241.3254 -228.1428)
		(width 0.15494)
		(layer "In7.Cu")
		(net "SSD10_PWRDIS_BIC_R")
	)
	(segment
		(start 247.847358 -216.2048)
		(end 250.264422 -213.787736)
		(width 0.15494)
		(layer "In15.Cu")
		(net "SSD10_PWRDIS_BIC_R")
	)
	(segment
		(start 322.173346 -213.5124)
		(end 326.46493 -213.5124)
		(width 0.15494)
		(layer "In15.Cu")
		(net "SSD10_PWRDIS_BIC_R")
	)
	(segment
		(start 262.697468 -217.049096)
		(end 265.462258 -217.049096)
		(width 0.15494)
		(layer "In15.Cu")
		(net "SSD10_PWRDIS_BIC_R")
	)
	(segment
		(start 330.756514 -215.33866)
		(end 333.007208 -217.589354)
		(width 0.15494)
		(layer "In15.Cu")
		(net "SSD10_PWRDIS_BIC_R")
	)
	(segment
		(start 328.14641 -215.62314)
		(end 329.35926 -215.62314)
		(width 0.15494)
		(layer "In15.Cu")
		(net "SSD10_PWRDIS_BIC_R")
	)
	(segment
		(start 262.577072 -217.169492)
		(end 262.697468 -217.049096)
		(width 0.15494)
		(layer "In15.Cu")
		(net "SSD10_PWRDIS_BIC_R")
	)
	(segment
		(start 333.082392 -217.589354)
		(end 336.496152 -217.589354)
		(width 0.0889)
		(layer "In15.Cu")
		(net "SSD10_PWRDIS_BIC_R")
	)
	(segment
		(start 326.46493 -213.5124)
		(end 327.07072 -214.11819)
		(width 0.15494)
		(layer "In15.Cu")
		(net "SSD10_PWRDIS_BIC_R")
	)
	(segment
		(start 327.07072 -214.11819)
		(end 327.07072 -214.54745)
		(width 0.15494)
		(layer "In15.Cu")
		(net "SSD10_PWRDIS_BIC_R")
	)
	(segment
		(start 329.64374 -215.33866)
		(end 330.756514 -215.33866)
		(width 0.15494)
		(layer "In15.Cu")
		(net "SSD10_PWRDIS_BIC_R")
	)
	(segment
		(start 286.470852 -216.753694)
		(end 291.187886 -212.03666)
		(width 0.15494)
		(layer "In15.Cu")
		(net "SSD10_PWRDIS_BIC_R")
	)
	(segment
		(start 247.5738 -216.2048)
		(end 247.847358 -216.2048)
		(width 0.15494)
		(layer "In15.Cu")
		(net "SSD10_PWRDIS_BIC_R")
	)
	(segment
		(start 258.253992 -215.12149)
		(end 259.18922 -216.056718)
		(width 0.15494)
		(layer "In15.Cu")
		(net "SSD10_PWRDIS_BIC_R")
	)
	(segment
		(start 256.805176 -215.12149)
		(end 258.253992 -215.12149)
		(width 0.15494)
		(layer "In15.Cu")
		(net "SSD10_PWRDIS_BIC_R")
	)
	(segment
		(start 333.007208 -217.589354)
		(end 333.082392 -217.589354)
		(width 0.15494)
		(layer "In15.Cu")
		(net "SSD10_PWRDIS_BIC_R")
	)
	(segment
		(start 255.471422 -213.787736)
		(end 256.805176 -215.12149)
		(width 0.15494)
		(layer "In15.Cu")
		(net "SSD10_PWRDIS_BIC_R")
	)
	(segment
		(start 327.07072 -214.54745)
		(end 328.14641 -215.62314)
		(width 0.15494)
		(layer "In15.Cu")
		(net "SSD10_PWRDIS_BIC_R")
	)
	(segment
		(start 246.455946 -216.858342)
		(end 246.920258 -216.858342)
		(width 0.15494)
		(layer "In15.Cu")
		(net "SSD10_PWRDIS_BIC_R")
	)
	(segment
		(start 259.18922 -216.056718)
		(end 260.458204 -216.056718)
		(width 0.15494)
		(layer "In15.Cu")
		(net "SSD10_PWRDIS_BIC_R")
	)
	(segment
		(start 320.697606 -212.03666)
		(end 322.173346 -213.5124)
		(width 0.15494)
		(layer "In15.Cu")
		(net "SSD10_PWRDIS_BIC_R")
	)
	(segment
		(start 266.17676 -216.753694)
		(end 286.470852 -216.753694)
		(width 0.15494)
		(layer "In15.Cu")
		(net "SSD10_PWRDIS_BIC_R")
	)
	(segment
		(start 260.458204 -216.056718)
		(end 261.570978 -217.169492)
		(width 0.15494)
		(layer "In15.Cu")
		(net "SSD10_PWRDIS_BIC_R")
	)
	(segment
		(start 250.264422 -213.787736)
		(end 255.471422 -213.787736)
		(width 0.15494)
		(layer "In15.Cu")
		(net "SSD10_PWRDIS_BIC_R")
	)
	(segment
		(start 261.570978 -217.169492)
		(end 262.577072 -217.169492)
		(width 0.15494)
		(layer "In15.Cu")
		(net "SSD10_PWRDIS_BIC_R")
	)
	(segment
		(start 336.496152 -217.589354)
		(end 336.89417 -217.987372)
		(width 0.0889)
		(layer "In15.Cu")
		(net "SSD10_PWRDIS_BIC_R")
	)
	(segment
		(start 246.920258 -216.858342)
		(end 247.5738 -216.2048)
		(width 0.15494)
		(layer "In15.Cu")
		(net "SSD10_PWRDIS_BIC_R")
	)
	(segment
		(start 291.187886 -212.03666)
		(end 320.697606 -212.03666)
		(width 0.15494)
		(layer "In15.Cu")
		(net "SSD10_PWRDIS_BIC_R")
	)
	(segment
		(start 265.462258 -217.049096)
		(end 266.17676 -216.753694)
		(width 0.15494)
		(layer "In15.Cu")
		(net "SSD10_PWRDIS_BIC_R")
	)
	(segment
		(start 329.35926 -215.62314)
		(end 329.64374 -215.33866)
		(width 0.15494)
		(layer "In15.Cu")
		(net "SSD10_PWRDIS_BIC_R")
	)
	(segment
		(start 228.627178 -140.849096)
		(end 227.927154 -139.159234)
		(width 0.13208)
		(layer "F.Cu")
		(net "SMB_CK440_PEX_CLK_SDA")
	)
	(segment
		(start 229.59695 -141.818868)
		(end 228.627178 -140.849096)
		(width 0.13208)
		(layer "F.Cu")
		(net "SMB_CK440_PEX_CLK_SDA")
	)
	(segment
		(start 225.911156 -138.407394)
		(end 225.911156 -137.954004)
		(width 0.13208)
		(layer "F.Cu")
		(net "SMB_CK440_PEX_CLK_SDA")
	)
	(segment
		(start 227.927154 -139.159234)
		(end 227.252276 -138.484356)
		(width 0.13208)
		(layer "F.Cu")
		(net "SMB_CK440_PEX_CLK_SDA")
	)
	(segment
		(start 226.364546 -138.407394)
		(end 225.911156 -138.407394)
		(width 0.13208)
		(layer "F.Cu")
		(net "SMB_CK440_PEX_CLK_SDA")
	)
	(segment
		(start 229.59695 -142.887192)
		(end 229.59695 -141.818868)
		(width 0.13208)
		(layer "F.Cu")
		(net "SMB_CK440_PEX_CLK_SDA")
	)
	(segment
		(start 229.59695 -144.01546)
		(end 229.59695 -142.887192)
		(width 0.0889)
		(layer "F.Cu")
		(net "SMB_CK440_PEX_CLK_SDA")
	)
	(segment
		(start 226.441508 -138.484356)
		(end 226.364546 -138.407394)
		(width 0.13208)
		(layer "F.Cu")
		(net "SMB_CK440_PEX_CLK_SDA")
	)
	(segment
		(start 227.252276 -138.484356)
		(end 226.441508 -138.484356)
		(width 0.13208)
		(layer "F.Cu")
		(net "SMB_CK440_PEX_CLK_SDA")
	)
	(segment
		(start 225.911156 -137.954004)
		(end 225.026474 -137.069322)
		(width 0.13208)
		(layer "F.Cu")
		(net "SMB_CK440_PEX_CLK_SDA")
	)
	(via
		(at 225.911156 -138.407394)
		(size 0.762)
		(drill 0.381)
		(layers "F.Cu" "B.Cu")
		(net "SMB_CK440_PEX_CLK_SDA")
	)
	(segment
		(start 192.989708 -405.133556)
		(end 192.989708 -404.079456)
		(width 0.13208)
		(layer "F.Cu")
		(net "FM_HSC_FAULT_N")
	)
	(segment
		(start 211.906866 -368.007646)
		(end 212.522816 -368.007646)
		(width 0.13208)
		(layer "F.Cu")
		(net "FM_HSC_FAULT_N")
	)
	(via
		(at 253.6444 -347.7768)
		(size 0.508)
		(drill 0.254)
		(layers "F.Cu" "B.Cu")
		(net "FM_HSC_FAULT_N")
	)
	(via
		(at 212.522816 -368.007646)
		(size 0.508)
		(drill 0.254)
		(layers "F.Cu" "B.Cu")
		(net "FM_HSC_FAULT_N")
	)
	(via
		(at 192.989708 -404.079456)
		(size 0.508)
		(drill 0.254)
		(layers "F.Cu" "B.Cu")
		(net "FM_HSC_FAULT_N")
	)
	(segment
		(start 252.41885 -347.7768)
		(end 253.6444 -347.7768)
		(width 0.13208)
		(layer "B.Cu")
		(net "FM_HSC_FAULT_N")
	)
	(segment
		(start 197.394576 -371.215158)
		(end 192.01003 -371.215158)
		(width 0.15494)
		(layer "In5.Cu")
		(net "FM_HSC_FAULT_N")
	)
	(segment
		(start 192.989708 -399.68551)
		(end 192.989708 -404.079456)
		(width 0.15494)
		(layer "In5.Cu")
		(net "FM_HSC_FAULT_N")
	)
	(segment
		(start 201.000868 -368.252502)
		(end 199.746108 -368.252502)
		(width 0.15494)
		(layer "In5.Cu")
		(net "FM_HSC_FAULT_N")
	)
	(segment
		(start 213.99246 -363.197394)
		(end 216.151206 -361.038648)
		(width 0.15494)
		(layer "In5.Cu")
		(net "FM_HSC_FAULT_N")
	)
	(segment
		(start 198.449184 -370.16055)
		(end 197.394576 -371.215158)
		(width 0.15494)
		(layer "In5.Cu")
		(net "FM_HSC_FAULT_N")
	)
	(segment
		(start 221.027752 -361.038648)
		(end 236.48162 -345.58478)
		(width 0.15494)
		(layer "In5.Cu")
		(net "FM_HSC_FAULT_N")
	)
	(segment
		(start 212.522816 -368.007646)
		(end 209.67192 -368.007646)
		(width 0.15494)
		(layer "In5.Cu")
		(net "FM_HSC_FAULT_N")
	)
	(segment
		(start 252.511306 -348.909894)
		(end 253.6444 -347.7768)
		(width 0.15494)
		(layer "In5.Cu")
		(net "FM_HSC_FAULT_N")
	)
	(segment
		(start 201.61631 -367.63706)
		(end 201.000868 -368.252502)
		(width 0.15494)
		(layer "In5.Cu")
		(net "FM_HSC_FAULT_N")
	)
	(segment
		(start 213.86546 -367.521236)
		(end 213.99246 -367.394236)
		(width 0.15494)
		(layer "In5.Cu")
		(net "FM_HSC_FAULT_N")
	)
	(segment
		(start 203.290424 -367.070894)
		(end 202.724258 -367.63706)
		(width 0.15494)
		(layer "In5.Cu")
		(net "FM_HSC_FAULT_N")
	)
	(segment
		(start 199.746108 -368.252502)
		(end 198.449184 -369.549426)
		(width 0.15494)
		(layer "In5.Cu")
		(net "FM_HSC_FAULT_N")
	)
	(segment
		(start 213.99246 -367.394236)
		(end 213.99246 -363.197394)
		(width 0.15494)
		(layer "In5.Cu")
		(net "FM_HSC_FAULT_N")
	)
	(segment
		(start 202.724258 -367.63706)
		(end 201.61631 -367.63706)
		(width 0.15494)
		(layer "In5.Cu")
		(net "FM_HSC_FAULT_N")
	)
	(segment
		(start 198.449184 -369.549426)
		(end 198.449184 -370.16055)
		(width 0.15494)
		(layer "In5.Cu")
		(net "FM_HSC_FAULT_N")
	)
	(segment
		(start 248.395236 -347.194124)
		(end 250.195334 -347.194124)
		(width 0.15494)
		(layer "In5.Cu")
		(net "FM_HSC_FAULT_N")
	)
	(segment
		(start 187.172092 -393.867894)
		(end 192.989708 -399.68551)
		(width 0.15494)
		(layer "In5.Cu")
		(net "FM_HSC_FAULT_N")
	)
	(segment
		(start 192.01003 -371.215158)
		(end 187.172092 -376.053096)
		(width 0.15494)
		(layer "In5.Cu")
		(net "FM_HSC_FAULT_N")
	)
	(segment
		(start 246.785892 -345.58478)
		(end 248.395236 -347.194124)
		(width 0.15494)
		(layer "In5.Cu")
		(net "FM_HSC_FAULT_N")
	)
	(segment
		(start 250.195334 -347.194124)
		(end 251.911104 -348.909894)
		(width 0.15494)
		(layer "In5.Cu")
		(net "FM_HSC_FAULT_N")
	)
	(segment
		(start 209.67192 -368.007646)
		(end 208.735168 -367.070894)
		(width 0.15494)
		(layer "In5.Cu")
		(net "FM_HSC_FAULT_N")
	)
	(segment
		(start 187.172092 -376.053096)
		(end 187.172092 -393.867894)
		(width 0.15494)
		(layer "In5.Cu")
		(net "FM_HSC_FAULT_N")
	)
	(segment
		(start 236.48162 -345.58478)
		(end 246.785892 -345.58478)
		(width 0.15494)
		(layer "In5.Cu")
		(net "FM_HSC_FAULT_N")
	)
	(segment
		(start 212.522816 -368.007646)
		(end 213.009226 -367.521236)
		(width 0.15494)
		(layer "In5.Cu")
		(net "FM_HSC_FAULT_N")
	)
	(segment
		(start 213.009226 -367.521236)
		(end 213.86546 -367.521236)
		(width 0.15494)
		(layer "In5.Cu")
		(net "FM_HSC_FAULT_N")
	)
	(segment
		(start 251.911104 -348.909894)
		(end 252.511306 -348.909894)
		(width 0.15494)
		(layer "In5.Cu")
		(net "FM_HSC_FAULT_N")
	)
	(segment
		(start 216.151206 -361.038648)
		(end 221.027752 -361.038648)
		(width 0.15494)
		(layer "In5.Cu")
		(net "FM_HSC_FAULT_N")
	)
	(segment
		(start 208.735168 -367.070894)
		(end 203.290424 -367.070894)
		(width 0.15494)
		(layer "In5.Cu")
		(net "FM_HSC_FAULT_N")
	)
	(segment
		(start 235.110782 -178.844194)
		(end 235.331762 -178.623214)
		(width 0.13208)
		(layer "F.Cu")
		(net "RST_FPGA_BIC_R1_N")
	)
	(segment
		(start 235.331762 -178.623214)
		(end 235.882688 -178.623214)
		(width 0.13208)
		(layer "F.Cu")
		(net "RST_FPGA_BIC_R1_N")
	)
	(segment
		(start 234.70235 -178.844194)
		(end 235.110782 -178.844194)
		(width 0.13208)
		(layer "F.Cu")
		(net "RST_FPGA_BIC_R1_N")
	)
	(segment
		(start 235.882688 -178.623214)
		(end 235.882688 -177.008282)
		(width 0.13208)
		(layer "F.Cu")
		(net "RST_FPGA_BIC_R1_N")
	)
	(via
		(at 235.882688 -178.623214)
		(size 0.762)
		(drill 0.381)
		(layers "F.Cu" "B.Cu")
		(net "RST_FPGA_BIC_R1_N")
	)
	(segment
		(start 264.775696 -37.315648)
		(end 264.775696 -37.592)
		(width 0.13208)
		(layer "F.Cu")
		(net "PRSNT_SSD9_R1_N")
	)
	(segment
		(start 264.046716 -37.774118)
		(end 262.490966 -37.774118)
		(width 0.13208)
		(layer "F.Cu")
		(net "PRSNT_SSD9_R1_N")
	)
	(segment
		(start 262.490966 -37.774118)
		(end 262.097774 -38.16731)
		(width 0.13208)
		(layer "F.Cu")
		(net "PRSNT_SSD9_R1_N")
	)
	(segment
		(start 264.775696 -37.592)
		(end 264.593578 -37.774118)
		(width 0.13208)
		(layer "F.Cu")
		(net "PRSNT_SSD9_R1_N")
	)
	(segment
		(start 264.593578 -37.774118)
		(end 264.046716 -37.774118)
		(width 0.13208)
		(layer "F.Cu")
		(net "PRSNT_SSD9_R1_N")
	)
	(segment
		(start 262.097774 -38.16731)
		(end 262.097774 -38.937184)
		(width 0.13208)
		(layer "F.Cu")
		(net "PRSNT_SSD9_R1_N")
	)
	(via
		(at 264.046716 -37.774118)
		(size 0.508)
		(drill 0.254)
		(layers "F.Cu" "B.Cu")
		(net "PRSNT_SSD9_R1_N")
	)
	(segment
		(start 235.871512 -232.471468)
		(end 236.343952 -232.943908)
		(width 0.13208)
		(layer "F.Cu")
		(net "SSD7_PWRDIS_BIC_R")
	)
	(segment
		(start 235.871512 -232.471468)
		(end 235.871512 -231.816656)
		(width 0.13208)
		(layer "F.Cu")
		(net "SSD7_PWRDIS_BIC_R")
	)
	(segment
		(start 236.343952 -233.439716)
		(end 235.871512 -233.912156)
		(width 0.13208)
		(layer "F.Cu")
		(net "SSD7_PWRDIS_BIC_R")
	)
	(segment
		(start 335.693766 -215.987122)
		(end 335.29397 -215.587326)
		(width 0.13208)
		(layer "F.Cu")
		(net "SSD7_PWRDIS_BIC_R")
	)
	(segment
		(start 236.343952 -232.943908)
		(end 236.343952 -233.439716)
		(width 0.13208)
		(layer "F.Cu")
		(net "SSD7_PWRDIS_BIC_R")
	)
	(segment
		(start 235.871512 -233.912156)
		(end 235.871512 -234.327954)
		(width 0.13208)
		(layer "F.Cu")
		(net "SSD7_PWRDIS_BIC_R")
	)
	(via
		(at 335.29397 -215.587326)
		(size 0.4572)
		(drill 0.254)
		(layers "F.Cu" "B.Cu")
		(net "SSD7_PWRDIS_BIC_R")
	)
	(via
		(at 252.499876 -210.566)
		(size 0.508)
		(drill 0.254)
		(layers "F.Cu" "B.Cu")
		(net "SSD7_PWRDIS_BIC_R")
	)
	(via
		(at 235.871512 -232.471468)
		(size 0.508)
		(drill 0.254)
		(layers "F.Cu" "B.Cu")
		(net "SSD7_PWRDIS_BIC_R")
	)
	(segment
		(start 252.5014 -210.566)
		(end 253.5682 -211.6328)
		(width 0.15494)
		(layer "In7.Cu")
		(net "SSD7_PWRDIS_BIC_R")
	)
	(segment
		(start 251.9172 -215.3666)
		(end 250.444 -216.8398)
		(width 0.15494)
		(layer "In7.Cu")
		(net "SSD7_PWRDIS_BIC_R")
	)
	(segment
		(start 252.499876 -210.566)
		(end 252.5014 -210.566)
		(width 0.15494)
		(layer "In7.Cu")
		(net "SSD7_PWRDIS_BIC_R")
	)
	(segment
		(start 248.2596 -223.164146)
		(end 242.8494 -228.574346)
		(width 0.15494)
		(layer "In7.Cu")
		(net "SSD7_PWRDIS_BIC_R")
	)
	(segment
		(start 242.8494 -228.574346)
		(end 242.8494 -229.4636)
		(width 0.15494)
		(layer "In7.Cu")
		(net "SSD7_PWRDIS_BIC_R")
	)
	(segment
		(start 251.9172 -214.3252)
		(end 251.9172 -215.3666)
		(width 0.15494)
		(layer "In7.Cu")
		(net "SSD7_PWRDIS_BIC_R")
	)
	(segment
		(start 249.47499 -221.214188)
		(end 248.2596 -222.429578)
		(width 0.15494)
		(layer "In7.Cu")
		(net "SSD7_PWRDIS_BIC_R")
	)
	(segment
		(start 237.353602 -230.632)
		(end 235.871512 -232.11409)
		(width 0.15494)
		(layer "In7.Cu")
		(net "SSD7_PWRDIS_BIC_R")
	)
	(segment
		(start 242.8494 -229.4636)
		(end 241.681 -230.632)
		(width 0.15494)
		(layer "In7.Cu")
		(net "SSD7_PWRDIS_BIC_R")
	)
	(segment
		(start 235.871512 -232.11409)
		(end 235.871512 -232.471468)
		(width 0.15494)
		(layer "In7.Cu")
		(net "SSD7_PWRDIS_BIC_R")
	)
	(segment
		(start 241.681 -230.632)
		(end 237.353602 -230.632)
		(width 0.15494)
		(layer "In7.Cu")
		(net "SSD7_PWRDIS_BIC_R")
	)
	(segment
		(start 248.2596 -222.429578)
		(end 248.2596 -223.164146)
		(width 0.15494)
		(layer "In7.Cu")
		(net "SSD7_PWRDIS_BIC_R")
	)
	(segment
		(start 249.47499 -220.518228)
		(end 249.47499 -221.214188)
		(width 0.15494)
		(layer "In7.Cu")
		(net "SSD7_PWRDIS_BIC_R")
	)
	(segment
		(start 253.5682 -211.6328)
		(end 253.5682 -212.6742)
		(width 0.15494)
		(layer "In7.Cu")
		(net "SSD7_PWRDIS_BIC_R")
	)
	(segment
		(start 253.5682 -212.6742)
		(end 251.9172 -214.3252)
		(width 0.15494)
		(layer "In7.Cu")
		(net "SSD7_PWRDIS_BIC_R")
	)
	(segment
		(start 250.444 -219.549218)
		(end 249.47499 -220.518228)
		(width 0.15494)
		(layer "In7.Cu")
		(net "SSD7_PWRDIS_BIC_R")
	)
	(segment
		(start 250.444 -216.8398)
		(end 250.444 -219.549218)
		(width 0.15494)
		(layer "In7.Cu")
		(net "SSD7_PWRDIS_BIC_R")
	)
	(segment
		(start 328.34834 -214.73287)
		(end 329.03033 -214.73287)
		(width 0.15494)
		(layer "In15.Cu")
		(net "SSD7_PWRDIS_BIC_R")
	)
	(segment
		(start 290.40074 -211.22386)
		(end 320.978784 -211.22386)
		(width 0.15494)
		(layer "In15.Cu")
		(net "SSD7_PWRDIS_BIC_R")
	)
	(segment
		(start 262.400288 -216.332816)
		(end 265.31951 -216.332816)
		(width 0.15494)
		(layer "In15.Cu")
		(net "SSD7_PWRDIS_BIC_R")
	)
	(segment
		(start 334.8863 -215.994996)
		(end 335.29397 -215.587326)
		(width 0.15494)
		(layer "In15.Cu")
		(net "SSD7_PWRDIS_BIC_R")
	)
	(segment
		(start 285.587186 -216.037414)
		(end 290.40074 -211.22386)
		(width 0.15494)
		(layer "In15.Cu")
		(net "SSD7_PWRDIS_BIC_R")
	)
	(segment
		(start 326.89673 -212.725)
		(end 328.041 -213.86927)
		(width 0.15494)
		(layer "In15.Cu")
		(net "SSD7_PWRDIS_BIC_R")
	)
	(segment
		(start 255.711706 -210.566)
		(end 259.936996 -214.79129)
		(width 0.15494)
		(layer "In15.Cu")
		(net "SSD7_PWRDIS_BIC_R")
	)
	(segment
		(start 260.552946 -215.138)
		(end 261.868158 -216.453212)
		(width 0.15494)
		(layer "In15.Cu")
		(net "SSD7_PWRDIS_BIC_R")
	)
	(segment
		(start 261.868158 -216.453212)
		(end 262.279892 -216.453212)
		(width 0.15494)
		(layer "In15.Cu")
		(net "SSD7_PWRDIS_BIC_R")
	)
	(segment
		(start 265.31951 -216.332816)
		(end 266.03325 -216.037414)
		(width 0.15494)
		(layer "In15.Cu")
		(net "SSD7_PWRDIS_BIC_R")
	)
	(segment
		(start 328.041 -214.42553)
		(end 328.34834 -214.73287)
		(width 0.15494)
		(layer "In15.Cu")
		(net "SSD7_PWRDIS_BIC_R")
	)
	(segment
		(start 259.936996 -214.79129)
		(end 259.936996 -214.928196)
		(width 0.15494)
		(layer "In15.Cu")
		(net "SSD7_PWRDIS_BIC_R")
	)
	(segment
		(start 259.936996 -214.928196)
		(end 260.1468 -215.138)
		(width 0.15494)
		(layer "In15.Cu")
		(net "SSD7_PWRDIS_BIC_R")
	)
	(segment
		(start 332.472792 -215.994996)
		(end 334.8863 -215.994996)
		(width 0.15494)
		(layer "In15.Cu")
		(net "SSD7_PWRDIS_BIC_R")
	)
	(segment
		(start 328.041 -213.86927)
		(end 328.041 -214.42553)
		(width 0.15494)
		(layer "In15.Cu")
		(net "SSD7_PWRDIS_BIC_R")
	)
	(segment
		(start 262.279892 -216.453212)
		(end 262.400288 -216.332816)
		(width 0.15494)
		(layer "In15.Cu")
		(net "SSD7_PWRDIS_BIC_R")
	)
	(segment
		(start 322.479924 -212.725)
		(end 326.89673 -212.725)
		(width 0.15494)
		(layer "In15.Cu")
		(net "SSD7_PWRDIS_BIC_R")
	)
	(segment
		(start 320.978784 -211.22386)
		(end 322.479924 -212.725)
		(width 0.15494)
		(layer "In15.Cu")
		(net "SSD7_PWRDIS_BIC_R")
	)
	(segment
		(start 329.03033 -214.73287)
		(end 329.18654 -214.57666)
		(width 0.15494)
		(layer "In15.Cu")
		(net "SSD7_PWRDIS_BIC_R")
	)
	(segment
		(start 266.03325 -216.037414)
		(end 285.587186 -216.037414)
		(width 0.15494)
		(layer "In15.Cu")
		(net "SSD7_PWRDIS_BIC_R")
	)
	(segment
		(start 329.18654 -214.57666)
		(end 331.054456 -214.57666)
		(width 0.15494)
		(layer "In15.Cu")
		(net "SSD7_PWRDIS_BIC_R")
	)
	(segment
		(start 260.1468 -215.138)
		(end 260.552946 -215.138)
		(width 0.15494)
		(layer "In15.Cu")
		(net "SSD7_PWRDIS_BIC_R")
	)
	(segment
		(start 331.054456 -214.57666)
		(end 332.472792 -215.994996)
		(width 0.15494)
		(layer "In15.Cu")
		(net "SSD7_PWRDIS_BIC_R")
	)
	(segment
		(start 252.499876 -210.566)
		(end 255.711706 -210.566)
		(width 0.15494)
		(layer "In15.Cu")
		(net "SSD7_PWRDIS_BIC_R")
	)
	(segment
		(start 174.650908 -248.022872)
		(end 188.238384 -261.610348)
		(width 0.13208)
		(layer "F.Cu")
		(net "SMB_HOTSWAP_SDA_R")
	)
	(segment
		(start 194.491102 -365.262414)
		(end 192.599564 -367.153952)
		(width 0.13208)
		(layer "F.Cu")
		(net "SMB_HOTSWAP_SDA_R")
	)
	(segment
		(start 130.51663 -246.362982)
		(end 131.573778 -246.362982)
		(width 0.13208)
		(layer "F.Cu")
		(net "SMB_HOTSWAP_SDA_R")
	)
	(segment
		(start 207.431132 -261.610348)
		(end 212.665818 -256.375662)
		(width 0.13208)
		(layer "F.Cu")
		(net "SMB_HOTSWAP_SDA_R")
	)
	(segment
		(start 131.573778 -246.362982)
		(end 133.233668 -248.022872)
		(width 0.13208)
		(layer "F.Cu")
		(net "SMB_HOTSWAP_SDA_R")
	)
	(segment
		(start 203.118466 -371.53088)
		(end 203.118466 -371.194584)
		(width 0.13208)
		(layer "F.Cu")
		(net "SMB_HOTSWAP_SDA_R")
	)
	(segment
		(start 213.784942 -256.375662)
		(end 214.390732 -256.981452)
		(width 0.13208)
		(layer "F.Cu")
		(net "SMB_HOTSWAP_SDA_R")
	)
	(segment
		(start 188.238384 -261.610348)
		(end 207.431132 -261.610348)
		(width 0.13208)
		(layer "F.Cu")
		(net "SMB_HOTSWAP_SDA_R")
	)
	(segment
		(start 212.665818 -256.375662)
		(end 213.784942 -256.375662)
		(width 0.13208)
		(layer "F.Cu")
		(net "SMB_HOTSWAP_SDA_R")
	)
	(segment
		(start 201.67727 -371.901212)
		(end 202.748134 -371.901212)
		(width 0.13208)
		(layer "F.Cu")
		(net "SMB_HOTSWAP_SDA_R")
	)
	(segment
		(start 194.491102 -365.09071)
		(end 194.491102 -365.262414)
		(width 0.13208)
		(layer "F.Cu")
		(net "SMB_HOTSWAP_SDA_R")
	)
	(segment
		(start 190.844678 -367.153952)
		(end 189.872112 -366.181386)
		(width 0.13208)
		(layer "F.Cu")
		(net "SMB_HOTSWAP_SDA_R")
	)
	(segment
		(start 133.233668 -248.022872)
		(end 174.650908 -248.022872)
		(width 0.13208)
		(layer "F.Cu")
		(net "SMB_HOTSWAP_SDA_R")
	)
	(segment
		(start 192.599564 -367.153952)
		(end 190.844678 -367.153952)
		(width 0.13208)
		(layer "F.Cu")
		(net "SMB_HOTSWAP_SDA_R")
	)
	(segment
		(start 202.748134 -371.901212)
		(end 203.118466 -371.53088)
		(width 0.13208)
		(layer "F.Cu")
		(net "SMB_HOTSWAP_SDA_R")
	)
	(via
		(at 201.67727 -371.901212)
		(size 0.508)
		(drill 0.254)
		(layers "F.Cu" "B.Cu")
		(net "SMB_HOTSWAP_SDA_R")
	)
	(via
		(at 225.384868 -334.00746)
		(size 0.508)
		(drill 0.254)
		(layers "F.Cu" "B.Cu")
		(net "SMB_HOTSWAP_SDA_R")
	)
	(via
		(at 214.390732 -256.981452)
		(size 0.508)
		(drill 0.254)
		(layers "F.Cu" "B.Cu")
		(net "SMB_HOTSWAP_SDA_R")
	)
	(via
		(at 194.491102 -365.09071)
		(size 0.508)
		(drill 0.254)
		(layers "F.Cu" "B.Cu")
		(net "SMB_HOTSWAP_SDA_R")
	)
	(segment
		(start 226.105212 -331.917294)
		(end 225.936556 -331.917294)
		(width 0.13208)
		(layer "B.Cu")
		(net "SMB_HOTSWAP_SDA_R")
	)
	(segment
		(start 227.36683 -332.024482)
		(end 227.198174 -332.024482)
		(width 0.13208)
		(layer "B.Cu")
		(net "SMB_HOTSWAP_SDA_R")
	)
	(segment
		(start 227.498148 -332.324456)
		(end 227.498148 -332.1558)
		(width 0.13208)
		(layer "B.Cu")
		(net "SMB_HOTSWAP_SDA_R")
	)
	(segment
		(start 225.936556 -331.917294)
		(end 224.460308 -330.441046)
		(width 0.13208)
		(layer "B.Cu")
		(net "SMB_HOTSWAP_SDA_R")
	)
	(segment
		(start 226.778566 -334.370934)
		(end 227.172012 -333.977488)
		(width 0.13208)
		(layer "B.Cu")
		(net "SMB_HOTSWAP_SDA_R")
	)
	(segment
		(start 211.544662 -316.199012)
		(end 211.544662 -284.43301)
		(width 0.13208)
		(layer "B.Cu")
		(net "SMB_HOTSWAP_SDA_R")
	)
	(segment
		(start 226.766882 -331.424534)
		(end 226.598226 -331.424534)
		(width 0.13208)
		(layer "B.Cu")
		(net "SMB_HOTSWAP_SDA_R")
	)
	(segment
		(start 227.172012 -333.15275)
		(end 227.005134 -332.985872)
		(width 0.13208)
		(layer "B.Cu")
		(net "SMB_HOTSWAP_SDA_R")
	)
	(segment
		(start 211.544662 -284.43301)
		(end 214.00897 -281.968702)
		(width 0.13208)
		(layer "B.Cu")
		(net "SMB_HOTSWAP_SDA_R")
	)
	(segment
		(start 226.70516 -332.517242)
		(end 226.536504 -332.517242)
		(width 0.13208)
		(layer "B.Cu")
		(net "SMB_HOTSWAP_SDA_R")
	)
	(segment
		(start 224.460308 -330.441046)
		(end 224.460308 -329.114658)
		(width 0.13208)
		(layer "B.Cu")
		(net "SMB_HOTSWAP_SDA_R")
	)
	(segment
		(start 226.598226 -331.424534)
		(end 226.105212 -331.917294)
		(width 0.13208)
		(layer "B.Cu")
		(net "SMB_HOTSWAP_SDA_R")
	)
	(segment
		(start 226.8982 -331.724508)
		(end 226.8982 -331.555852)
		(width 0.13208)
		(layer "B.Cu")
		(net "SMB_HOTSWAP_SDA_R")
	)
	(segment
		(start 227.172012 -333.977488)
		(end 227.172012 -333.15275)
		(width 0.13208)
		(layer "B.Cu")
		(net "SMB_HOTSWAP_SDA_R")
	)
	(segment
		(start 226.536504 -332.517242)
		(end 226.405186 -332.385924)
		(width 0.13208)
		(layer "B.Cu")
		(net "SMB_HOTSWAP_SDA_R")
	)
	(segment
		(start 226.8982 -331.555852)
		(end 226.766882 -331.424534)
		(width 0.13208)
		(layer "B.Cu")
		(net "SMB_HOTSWAP_SDA_R")
	)
	(segment
		(start 225.384868 -334.00746)
		(end 225.748342 -334.370934)
		(width 0.13208)
		(layer "B.Cu")
		(net "SMB_HOTSWAP_SDA_R")
	)
	(segment
		(start 227.005134 -332.985872)
		(end 227.005134 -332.817216)
		(width 0.13208)
		(layer "B.Cu")
		(net "SMB_HOTSWAP_SDA_R")
	)
	(segment
		(start 227.198174 -332.024482)
		(end 226.70516 -332.517242)
		(width 0.13208)
		(layer "B.Cu")
		(net "SMB_HOTSWAP_SDA_R")
	)
	(segment
		(start 225.748342 -334.370934)
		(end 226.778566 -334.370934)
		(width 0.13208)
		(layer "B.Cu")
		(net "SMB_HOTSWAP_SDA_R")
	)
	(segment
		(start 214.00897 -257.363214)
		(end 214.390732 -256.981452)
		(width 0.13208)
		(layer "B.Cu")
		(net "SMB_HOTSWAP_SDA_R")
	)
	(segment
		(start 214.00897 -281.968702)
		(end 214.00897 -257.363214)
		(width 0.13208)
		(layer "B.Cu")
		(net "SMB_HOTSWAP_SDA_R")
	)
	(segment
		(start 226.405186 -332.385924)
		(end 226.405186 -332.217268)
		(width 0.13208)
		(layer "B.Cu")
		(net "SMB_HOTSWAP_SDA_R")
	)
	(segment
		(start 227.498148 -332.1558)
		(end 227.36683 -332.024482)
		(width 0.13208)
		(layer "B.Cu")
		(net "SMB_HOTSWAP_SDA_R")
	)
	(segment
		(start 226.405186 -332.217268)
		(end 226.8982 -331.724508)
		(width 0.13208)
		(layer "B.Cu")
		(net "SMB_HOTSWAP_SDA_R")
	)
	(segment
		(start 227.005134 -332.817216)
		(end 227.498148 -332.324456)
		(width 0.13208)
		(layer "B.Cu")
		(net "SMB_HOTSWAP_SDA_R")
	)
	(segment
		(start 224.460308 -329.114658)
		(end 211.544662 -316.199012)
		(width 0.13208)
		(layer "B.Cu")
		(net "SMB_HOTSWAP_SDA_R")
	)
	(segment
		(start 218.636596 -353.69754)
		(end 225.881438 -346.452698)
		(width 0.15494)
		(layer "In5.Cu")
		(net "SMB_HOTSWAP_SDA_R")
	)
	(segment
		(start 200.001886 -358.833166)
		(end 200.001886 -358.189276)
		(width 0.15494)
		(layer "In5.Cu")
		(net "SMB_HOTSWAP_SDA_R")
	)
	(segment
		(start 194.491102 -365.09071)
		(end 194.491102 -363.943392)
		(width 0.15494)
		(layer "In5.Cu")
		(net "SMB_HOTSWAP_SDA_R")
	)
	(segment
		(start 197.776592 -360.657902)
		(end 198.17715 -360.657902)
		(width 0.15494)
		(layer "In5.Cu")
		(net "SMB_HOTSWAP_SDA_R")
	)
	(segment
		(start 198.17715 -360.657902)
		(end 200.001886 -358.833166)
		(width 0.15494)
		(layer "In5.Cu")
		(net "SMB_HOTSWAP_SDA_R")
	)
	(segment
		(start 204.493622 -353.69754)
		(end 218.636596 -353.69754)
		(width 0.15494)
		(layer "In5.Cu")
		(net "SMB_HOTSWAP_SDA_R")
	)
	(segment
		(start 225.881438 -346.452698)
		(end 225.881438 -334.50403)
		(width 0.15494)
		(layer "In5.Cu")
		(net "SMB_HOTSWAP_SDA_R")
	)
	(segment
		(start 225.881438 -334.50403)
		(end 225.384868 -334.00746)
		(width 0.15494)
		(layer "In5.Cu")
		(net "SMB_HOTSWAP_SDA_R")
	)
	(segment
		(start 200.001886 -358.189276)
		(end 204.493622 -353.69754)
		(width 0.15494)
		(layer "In5.Cu")
		(net "SMB_HOTSWAP_SDA_R")
	)
	(segment
		(start 194.491102 -363.943392)
		(end 197.776592 -360.657902)
		(width 0.15494)
		(layer "In5.Cu")
		(net "SMB_HOTSWAP_SDA_R")
	)
	(segment
		(start 200.515728 -371.250718)
		(end 200.216008 -371.550438)
		(width 0.15494)
		(layer "In7.Cu")
		(net "SMB_HOTSWAP_SDA_R")
	)
	(segment
		(start 194.491102 -365.09071)
		(end 196.563996 -367.163604)
		(width 0.15494)
		(layer "In7.Cu")
		(net "SMB_HOTSWAP_SDA_R")
	)
	(segment
		(start 198.941944 -369.135914)
		(end 200.515728 -370.709698)
		(width 0.15494)
		(layer "In7.Cu")
		(net "SMB_HOTSWAP_SDA_R")
	)
	(segment
		(start 200.216008 -371.970554)
		(end 200.45426 -372.208806)
		(width 0.15494)
		(layer "In7.Cu")
		(net "SMB_HOTSWAP_SDA_R")
	)
	(segment
		(start 200.216008 -371.550438)
		(end 200.216008 -371.970554)
		(width 0.15494)
		(layer "In7.Cu")
		(net "SMB_HOTSWAP_SDA_R")
	)
	(segment
		(start 198.114666 -367.829592)
		(end 198.941944 -368.65687)
		(width 0.15494)
		(layer "In7.Cu")
		(net "SMB_HOTSWAP_SDA_R")
	)
	(segment
		(start 200.45426 -372.208806)
		(end 201.369676 -372.208806)
		(width 0.15494)
		(layer "In7.Cu")
		(net "SMB_HOTSWAP_SDA_R")
	)
	(segment
		(start 198.941944 -368.65687)
		(end 198.941944 -369.135914)
		(width 0.15494)
		(layer "In7.Cu")
		(net "SMB_HOTSWAP_SDA_R")
	)
	(segment
		(start 196.563996 -367.163604)
		(end 196.563996 -367.582196)
		(width 0.15494)
		(layer "In7.Cu")
		(net "SMB_HOTSWAP_SDA_R")
	)
	(segment
		(start 200.515728 -370.709698)
		(end 200.515728 -371.250718)
		(width 0.15494)
		(layer "In7.Cu")
		(net "SMB_HOTSWAP_SDA_R")
	)
	(segment
		(start 196.563996 -367.582196)
		(end 196.811392 -367.829592)
		(width 0.15494)
		(layer "In7.Cu")
		(net "SMB_HOTSWAP_SDA_R")
	)
	(segment
		(start 201.369676 -372.208806)
		(end 201.67727 -371.901212)
		(width 0.15494)
		(layer "In7.Cu")
		(net "SMB_HOTSWAP_SDA_R")
	)
	(segment
		(start 196.811392 -367.829592)
		(end 198.114666 -367.829592)
		(width 0.15494)
		(layer "In7.Cu")
		(net "SMB_HOTSWAP_SDA_R")
	)
	(segment
		(start 232.24871 -178.844194)
		(end 231.65181 -179.441094)
		(width 0.13208)
		(layer "F.Cu")
		(net "RST_FPGA_BIC_R_N")
	)
	(segment
		(start 231.65181 -179.441094)
		(end 231.65181 -181.094888)
		(width 0.13208)
		(layer "F.Cu")
		(net "RST_FPGA_BIC_R_N")
	)
	(segment
		(start 231.65181 -181.094888)
		(end 231.964738 -181.407816)
		(width 0.13208)
		(layer "F.Cu")
		(net "RST_FPGA_BIC_R_N")
	)
	(segment
		(start 231.964738 -181.725824)
		(end 233.263694 -183.02478)
		(width 0.13208)
		(layer "F.Cu")
		(net "RST_FPGA_BIC_R_N")
	)
	(segment
		(start 233.90225 -178.844194)
		(end 232.24871 -178.844194)
		(width 0.13208)
		(layer "F.Cu")
		(net "RST_FPGA_BIC_R_N")
	)
	(segment
		(start 231.964738 -181.407816)
		(end 231.964738 -181.725824)
		(width 0.13208)
		(layer "F.Cu")
		(net "RST_FPGA_BIC_R_N")
	)
	(via
		(at 348.234 -206.15148)
		(size 0.508)
		(drill 0.254)
		(layers "F.Cu" "B.Cu")
		(net "RST_FPGA_BIC_R_N")
	)
	(via
		(at 231.964738 -181.407816)
		(size 0.508)
		(drill 0.254)
		(layers "F.Cu" "B.Cu")
		(net "RST_FPGA_BIC_R_N")
	)
	(segment
		(start 348.869 -206.78648)
		(end 348.234 -206.15148)
		(width 0.13208)
		(layer "B.Cu")
		(net "RST_FPGA_BIC_R_N")
	)
	(segment
		(start 348.869 -207.37195)
		(end 348.869 -206.78648)
		(width 0.13208)
		(layer "B.Cu")
		(net "RST_FPGA_BIC_R_N")
	)
	(segment
		(start 326.60844 -201.58075)
		(end 332.16215 -201.58075)
		(width 0.15494)
		(layer "In13.Cu")
		(net "RST_FPGA_BIC_R_N")
	)
	(segment
		(start 333.98587 -203.40447)
		(end 333.98587 -204.52207)
		(width 0.15494)
		(layer "In13.Cu")
		(net "RST_FPGA_BIC_R_N")
	)
	(segment
		(start 263.748012 -188.518546)
		(end 280.600404 -205.370938)
		(width 0.15494)
		(layer "In13.Cu")
		(net "RST_FPGA_BIC_R_N")
	)
	(segment
		(start 347.50248 -206.883)
		(end 348.234 -206.15148)
		(width 0.15494)
		(layer "In13.Cu")
		(net "RST_FPGA_BIC_R_N")
	)
	(segment
		(start 280.600404 -205.370938)
		(end 299.225208 -205.370938)
		(width 0.15494)
		(layer "In13.Cu")
		(net "RST_FPGA_BIC_R_N")
	)
	(segment
		(start 339.466936 -205.5876)
		(end 340.762336 -206.883)
		(width 0.15494)
		(layer "In13.Cu")
		(net "RST_FPGA_BIC_R_N")
	)
	(segment
		(start 333.98587 -204.52207)
		(end 335.0514 -205.5876)
		(width 0.15494)
		(layer "In13.Cu")
		(net "RST_FPGA_BIC_R_N")
	)
	(segment
		(start 335.0514 -205.5876)
		(end 339.466936 -205.5876)
		(width 0.15494)
		(layer "In13.Cu")
		(net "RST_FPGA_BIC_R_N")
	)
	(segment
		(start 340.762336 -206.883)
		(end 347.50248 -206.883)
		(width 0.15494)
		(layer "In13.Cu")
		(net "RST_FPGA_BIC_R_N")
	)
	(segment
		(start 231.964738 -181.407816)
		(end 232.600754 -180.7718)
		(width 0.15494)
		(layer "In13.Cu")
		(net "RST_FPGA_BIC_R_N")
	)
	(segment
		(start 299.234606 -205.36154)
		(end 322.82765 -205.36154)
		(width 0.15494)
		(layer "In13.Cu")
		(net "RST_FPGA_BIC_R_N")
	)
	(segment
		(start 232.600754 -180.7718)
		(end 251.34824 -180.7718)
		(width 0.15494)
		(layer "In13.Cu")
		(net "RST_FPGA_BIC_R_N")
	)
	(segment
		(start 299.225208 -205.370938)
		(end 299.234606 -205.36154)
		(width 0.15494)
		(layer "In13.Cu")
		(net "RST_FPGA_BIC_R_N")
	)
	(segment
		(start 332.16215 -201.58075)
		(end 333.98587 -203.40447)
		(width 0.15494)
		(layer "In13.Cu")
		(net "RST_FPGA_BIC_R_N")
	)
	(segment
		(start 322.82765 -205.36154)
		(end 326.60844 -201.58075)
		(width 0.15494)
		(layer "In13.Cu")
		(net "RST_FPGA_BIC_R_N")
	)
	(segment
		(start 251.34824 -180.7718)
		(end 259.094986 -188.518546)
		(width 0.15494)
		(layer "In13.Cu")
		(net "RST_FPGA_BIC_R_N")
	)
	(segment
		(start 259.094986 -188.518546)
		(end 263.748012 -188.518546)
		(width 0.15494)
		(layer "In13.Cu")
		(net "RST_FPGA_BIC_R_N")
	)
	(segment
		(start 232.789984 -37.529516)
		(end 233.326178 -37.529516)
		(width 0.13208)
		(layer "F.Cu")
		(net "SSD8_AUX_P3V3_EN_R")
	)
	(segment
		(start 235.056172 -33.8836)
		(end 235.1024 -33.929828)
		(width 0.13208)
		(layer "F.Cu")
		(net "SSD8_AUX_P3V3_EN_R")
	)
	(segment
		(start 235.1024 -34.3662)
		(end 235.056172 -34.412428)
		(width 0.13208)
		(layer "F.Cu")
		(net "SSD8_AUX_P3V3_EN_R")
	)
	(segment
		(start 238.510064 -53.397404)
		(end 238.510064 -53.908706)
		(width 0.13208)
		(layer "F.Cu")
		(net "SSD8_AUX_P3V3_EN_R")
	)
	(segment
		(start 232.477818 -39.97198)
		(end 232.477818 -37.84092)
		(width 0.13208)
		(layer "F.Cu")
		(net "SSD8_AUX_P3V3_EN_R")
	)
	(segment
		(start 238.510064 -53.908706)
		(end 238.109252 -54.309518)
		(width 0.13208)
		(layer "F.Cu")
		(net "SSD8_AUX_P3V3_EN_R")
	)
	(segment
		(start 232.477818 -37.84092)
		(end 232.789984 -37.529516)
		(width 0.13208)
		(layer "F.Cu")
		(net "SSD8_AUX_P3V3_EN_R")
	)
	(segment
		(start 235.056172 -34.412428)
		(end 235.056172 -36.874958)
		(width 0.13208)
		(layer "F.Cu")
		(net "SSD8_AUX_P3V3_EN_R")
	)
	(segment
		(start 235.1024 -33.929828)
		(end 235.1024 -34.3662)
		(width 0.13208)
		(layer "F.Cu")
		(net "SSD8_AUX_P3V3_EN_R")
	)
	(segment
		(start 235.056172 -33.248092)
		(end 235.056172 -33.8836)
		(width 0.13208)
		(layer "F.Cu")
		(net "SSD8_AUX_P3V3_EN_R")
	)
	(segment
		(start 234.40263 -37.529516)
		(end 233.326178 -37.529516)
		(width 0.13208)
		(layer "F.Cu")
		(net "SSD8_AUX_P3V3_EN_R")
	)
	(segment
		(start 235.056172 -36.874958)
		(end 234.40263 -37.529516)
		(width 0.13208)
		(layer "F.Cu")
		(net "SSD8_AUX_P3V3_EN_R")
	)
	(via
		(at 232.477818 -39.97198)
		(size 0.508)
		(drill 0.254)
		(layers "F.Cu" "B.Cu")
		(net "SSD8_AUX_P3V3_EN_R")
	)
	(via
		(at 238.109252 -54.309518)
		(size 0.508)
		(drill 0.254)
		(layers "F.Cu" "B.Cu")
		(net "SSD8_AUX_P3V3_EN_R")
	)
	(segment
		(start 238.106712 -52.907692)
		(end 238.106712 -54.306978)
		(width 0.13208)
		(layer "B.Cu")
		(net "SSD8_AUX_P3V3_EN_R")
	)
	(segment
		(start 238.106712 -54.306978)
		(end 238.109252 -54.309518)
		(width 0.13208)
		(layer "B.Cu")
		(net "SSD8_AUX_P3V3_EN_R")
	)
	(segment
		(start 232.477818 -39.97198)
		(end 236.648498 -39.97198)
		(width 0.15494)
		(layer "In5.Cu")
		(net "SSD8_AUX_P3V3_EN_R")
	)
	(segment
		(start 236.648498 -39.97198)
		(end 241.6556 -44.979082)
		(width 0.15494)
		(layer "In5.Cu")
		(net "SSD8_AUX_P3V3_EN_R")
	)
	(segment
		(start 241.6556 -50.76317)
		(end 238.109252 -54.309518)
		(width 0.15494)
		(layer "In5.Cu")
		(net "SSD8_AUX_P3V3_EN_R")
	)
	(segment
		(start 241.6556 -44.979082)
		(end 241.6556 -50.76317)
		(width 0.15494)
		(layer "In5.Cu")
		(net "SSD8_AUX_P3V3_EN_R")
	)
	(segment
		(start 233.839512 -232.471468)
		(end 233.839512 -232.436162)
		(width 0.13208)
		(layer "F.Cu")
		(net "SSD9_PWRDIS_BIC_R")
	)
	(segment
		(start 234.311952 -232.943908)
		(end 233.839512 -232.471468)
		(width 0.13208)
		(layer "F.Cu")
		(net "SSD9_PWRDIS_BIC_R")
	)
	(segment
		(start 233.839512 -233.912156)
		(end 234.311952 -233.439716)
		(width 0.13208)
		(layer "F.Cu")
		(net "SSD9_PWRDIS_BIC_R")
	)
	(segment
		(start 233.839512 -232.436162)
		(end 233.1974 -231.79405)
		(width 0.13208)
		(layer "F.Cu")
		(net "SSD9_PWRDIS_BIC_R")
	)
	(segment
		(start 337.293966 -217.587068)
		(end 336.89417 -217.187272)
		(width 0.13208)
		(layer "F.Cu")
		(net "SSD9_PWRDIS_BIC_R")
	)
	(segment
		(start 234.311952 -233.439716)
		(end 234.311952 -232.943908)
		(width 0.13208)
		(layer "F.Cu")
		(net "SSD9_PWRDIS_BIC_R")
	)
	(segment
		(start 233.839512 -234.327954)
		(end 233.839512 -233.912156)
		(width 0.13208)
		(layer "F.Cu")
		(net "SSD9_PWRDIS_BIC_R")
	)
	(via
		(at 233.839512 -232.471468)
		(size 0.508)
		(drill 0.254)
		(layers "F.Cu" "B.Cu")
		(net "SSD9_PWRDIS_BIC_R")
	)
	(via
		(at 336.89417 -217.187272)
		(size 0.4572)
		(drill 0.254)
		(layers "F.Cu" "B.Cu")
		(net "SSD9_PWRDIS_BIC_R")
	)
	(via
		(at 247.506998 -215.68156)
		(size 0.508)
		(drill 0.254)
		(layers "F.Cu" "B.Cu")
		(net "SSD9_PWRDIS_BIC_R")
	)
	(segment
		(start 247.3198 -220.459554)
		(end 247.3198 -222.681546)
		(width 0.15494)
		(layer "In7.Cu")
		(net "SSD9_PWRDIS_BIC_R")
	)
	(segment
		(start 248.48947 -219.289884)
		(end 247.3198 -220.459554)
		(width 0.15494)
		(layer "In7.Cu")
		(net "SSD9_PWRDIS_BIC_R")
	)
	(segment
		(start 233.839512 -231.716834)
		(end 233.839512 -232.471468)
		(width 0.15494)
		(layer "In7.Cu")
		(net "SSD9_PWRDIS_BIC_R")
	)
	(segment
		(start 247.3198 -222.681546)
		(end 240.307876 -229.69347)
		(width 0.15494)
		(layer "In7.Cu")
		(net "SSD9_PWRDIS_BIC_R")
	)
	(segment
		(start 240.307876 -229.69347)
		(end 238.101632 -229.69347)
		(width 0.15494)
		(layer "In7.Cu")
		(net "SSD9_PWRDIS_BIC_R")
	)
	(segment
		(start 236.270546 -229.2858)
		(end 233.839512 -231.716834)
		(width 0.15494)
		(layer "In7.Cu")
		(net "SSD9_PWRDIS_BIC_R")
	)
	(segment
		(start 248.48947 -216.664032)
		(end 248.48947 -219.289884)
		(width 0.15494)
		(layer "In7.Cu")
		(net "SSD9_PWRDIS_BIC_R")
	)
	(segment
		(start 247.506998 -215.68156)
		(end 248.48947 -216.664032)
		(width 0.15494)
		(layer "In7.Cu")
		(net "SSD9_PWRDIS_BIC_R")
	)
	(segment
		(start 237.693962 -229.2858)
		(end 236.270546 -229.2858)
		(width 0.15494)
		(layer "In7.Cu")
		(net "SSD9_PWRDIS_BIC_R")
	)
	(segment
		(start 238.101632 -229.69347)
		(end 237.693962 -229.2858)
		(width 0.15494)
		(layer "In7.Cu")
		(net "SSD9_PWRDIS_BIC_R")
	)
	(segment
		(start 336.495898 -216.789)
		(end 335.0514 -216.789)
		(width 0.0889)
		(layer "In15.Cu")
		(net "SSD9_PWRDIS_BIC_R")
	)
	(segment
		(start 259.99821 -215.49614)
		(end 257.81127 -213.3092)
		(width 0.15494)
		(layer "In15.Cu")
		(net "SSD9_PWRDIS_BIC_R")
	)
	(segment
		(start 266.105132 -216.395554)
		(end 265.390884 -216.690956)
		(width 0.15494)
		(layer "In15.Cu")
		(net "SSD9_PWRDIS_BIC_R")
	)
	(segment
		(start 327.6346 -213.9696)
		(end 326.7964 -213.1314)
		(width 0.15494)
		(layer "In15.Cu")
		(net "SSD9_PWRDIS_BIC_R")
	)
	(segment
		(start 329.0824 -215.265)
		(end 328.295 -215.265)
		(width 0.15494)
		(layer "In15.Cu")
		(net "SSD9_PWRDIS_BIC_R")
	)
	(segment
		(start 260.404356 -215.49614)
		(end 259.99821 -215.49614)
		(width 0.15494)
		(layer "In15.Cu")
		(net "SSD9_PWRDIS_BIC_R")
	)
	(segment
		(start 334.391 -216.5096)
		(end 332.509368 -216.5096)
		(width 0.15494)
		(layer "In15.Cu")
		(net "SSD9_PWRDIS_BIC_R")
	)
	(segment
		(start 262.428482 -216.811352)
		(end 261.719568 -216.811352)
		(width 0.15494)
		(layer "In15.Cu")
		(net "SSD9_PWRDIS_BIC_R")
	)
	(segment
		(start 247.506998 -214.864696)
		(end 247.506998 -215.68156)
		(width 0.15494)
		(layer "In15.Cu")
		(net "SSD9_PWRDIS_BIC_R")
	)
	(segment
		(start 286.028892 -216.395554)
		(end 266.105132 -216.395554)
		(width 0.15494)
		(layer "In15.Cu")
		(net "SSD9_PWRDIS_BIC_R")
	)
	(segment
		(start 290.842446 -211.582)
		(end 286.028892 -216.395554)
		(width 0.15494)
		(layer "In15.Cu")
		(net "SSD9_PWRDIS_BIC_R")
	)
	(segment
		(start 320.830194 -211.582)
		(end 290.842446 -211.582)
		(width 0.15494)
		(layer "In15.Cu")
		(net "SSD9_PWRDIS_BIC_R")
	)
	(segment
		(start 332.330806 -216.35974)
		(end 330.905866 -214.9348)
		(width 0.15494)
		(layer "In15.Cu")
		(net "SSD9_PWRDIS_BIC_R")
	)
	(segment
		(start 327.6346 -214.6046)
		(end 327.6346 -213.9696)
		(width 0.15494)
		(layer "In15.Cu")
		(net "SSD9_PWRDIS_BIC_R")
	)
	(segment
		(start 330.905866 -214.9348)
		(end 329.4126 -214.9348)
		(width 0.15494)
		(layer "In15.Cu")
		(net "SSD9_PWRDIS_BIC_R")
	)
	(segment
		(start 255.97993 -212.535516)
		(end 252.224286 -212.535516)
		(width 0.15494)
		(layer "In15.Cu")
		(net "SSD9_PWRDIS_BIC_R")
	)
	(segment
		(start 334.772 -216.5096)
		(end 334.391 -216.5096)
		(width 0.0889)
		(layer "In15.Cu")
		(net "SSD9_PWRDIS_BIC_R")
	)
	(segment
		(start 328.295 -215.265)
		(end 327.6346 -214.6046)
		(width 0.15494)
		(layer "In15.Cu")
		(net "SSD9_PWRDIS_BIC_R")
	)
	(segment
		(start 265.390884 -216.690956)
		(end 262.548878 -216.690956)
		(width 0.15494)
		(layer "In15.Cu")
		(net "SSD9_PWRDIS_BIC_R")
	)
	(segment
		(start 332.359508 -216.35974)
		(end 332.330806 -216.35974)
		(width 0.15494)
		(layer "In15.Cu")
		(net "SSD9_PWRDIS_BIC_R")
	)
	(segment
		(start 251.59081 -211.90204)
		(end 250.834398 -211.90204)
		(width 0.15494)
		(layer "In15.Cu")
		(net "SSD9_PWRDIS_BIC_R")
	)
	(segment
		(start 261.719568 -216.811352)
		(end 260.404356 -215.49614)
		(width 0.15494)
		(layer "In15.Cu")
		(net "SSD9_PWRDIS_BIC_R")
	)
	(segment
		(start 322.379594 -213.1314)
		(end 320.830194 -211.582)
		(width 0.15494)
		(layer "In15.Cu")
		(net "SSD9_PWRDIS_BIC_R")
	)
	(segment
		(start 250.834398 -211.90204)
		(end 248.458482 -214.277956)
		(width 0.15494)
		(layer "In15.Cu")
		(net "SSD9_PWRDIS_BIC_R")
	)
	(segment
		(start 248.093738 -214.277956)
		(end 247.506998 -214.864696)
		(width 0.15494)
		(layer "In15.Cu")
		(net "SSD9_PWRDIS_BIC_R")
	)
	(segment
		(start 257.81127 -213.3092)
		(end 256.753614 -213.3092)
		(width 0.15494)
		(layer "In15.Cu")
		(net "SSD9_PWRDIS_BIC_R")
	)
	(segment
		(start 252.224286 -212.535516)
		(end 251.59081 -211.90204)
		(width 0.15494)
		(layer "In15.Cu")
		(net "SSD9_PWRDIS_BIC_R")
	)
	(segment
		(start 256.753614 -213.3092)
		(end 255.97993 -212.535516)
		(width 0.15494)
		(layer "In15.Cu")
		(net "SSD9_PWRDIS_BIC_R")
	)
	(segment
		(start 248.458482 -214.277956)
		(end 248.093738 -214.277956)
		(width 0.15494)
		(layer "In15.Cu")
		(net "SSD9_PWRDIS_BIC_R")
	)
	(segment
		(start 336.89417 -217.187272)
		(end 336.495898 -216.789)
		(width 0.0889)
		(layer "In15.Cu")
		(net "SSD9_PWRDIS_BIC_R")
	)
	(segment
		(start 329.4126 -214.9348)
		(end 329.0824 -215.265)
		(width 0.15494)
		(layer "In15.Cu")
		(net "SSD9_PWRDIS_BIC_R")
	)
	(segment
		(start 262.548878 -216.690956)
		(end 262.428482 -216.811352)
		(width 0.15494)
		(layer "In15.Cu")
		(net "SSD9_PWRDIS_BIC_R")
	)
	(segment
		(start 335.0514 -216.789)
		(end 334.772 -216.5096)
		(width 0.0889)
		(layer "In15.Cu")
		(net "SSD9_PWRDIS_BIC_R")
	)
	(segment
		(start 326.7964 -213.1314)
		(end 322.379594 -213.1314)
		(width 0.15494)
		(layer "In15.Cu")
		(net "SSD9_PWRDIS_BIC_R")
	)
	(segment
		(start 332.509368 -216.5096)
		(end 332.359508 -216.35974)
		(width 0.15494)
		(layer "In15.Cu")
		(net "SSD9_PWRDIS_BIC_R")
	)
	(segment
		(start 234.762548 -146.243802)
		(end 235.223558 -146.704812)
		(width 0.13208)
		(layer "F.Cu")
		(net "CLK_GEN_CK440_PEX_OE5_N")
	)
	(segment
		(start 232.850182 -146.140424)
		(end 233.178096 -146.140424)
		(width 0.13208)
		(layer "F.Cu")
		(net "CLK_GEN_CK440_PEX_OE5_N")
	)
	(segment
		(start 233.281474 -146.243802)
		(end 233.90098 -146.243802)
		(width 0.13208)
		(layer "F.Cu")
		(net "CLK_GEN_CK440_PEX_OE5_N")
	)
	(segment
		(start 231.721914 -146.140424)
		(end 232.850182 -146.140424)
		(width 0.0889)
		(layer "F.Cu")
		(net "CLK_GEN_CK440_PEX_OE5_N")
	)
	(segment
		(start 233.90098 -146.243802)
		(end 234.762548 -146.243802)
		(width 0.13208)
		(layer "F.Cu")
		(net "CLK_GEN_CK440_PEX_OE5_N")
	)
	(segment
		(start 233.178096 -146.140424)
		(end 233.281474 -146.243802)
		(width 0.13208)
		(layer "F.Cu")
		(net "CLK_GEN_CK440_PEX_OE5_N")
	)
	(via
		(at 233.90098 -146.243802)
		(size 0.762)
		(drill 0.381)
		(layers "F.Cu" "B.Cu")
		(net "CLK_GEN_CK440_PEX_OE5_N")
	)
	(segment
		(start 198.964296 -364.599728)
		(end 199.469248 -364.599728)
		(width 0.13208)
		(layer "F.Cu")
		(net "HSC_CS")
	)
	(segment
		(start 201.953876 -367.832132)
		(end 202.130914 -367.832132)
		(width 0.13208)
		(layer "F.Cu")
		(net "HSC_CS")
	)
	(segment
		(start 201.494898 -367.63452)
		(end 201.756264 -367.63452)
		(width 0.13208)
		(layer "F.Cu")
		(net "HSC_CS")
	)
	(segment
		(start 200.074276 -365.204756)
		(end 200.074276 -366.458246)
		(width 0.13208)
		(layer "F.Cu")
		(net "HSC_CS")
	)
	(segment
		(start 201.756264 -367.63452)
		(end 201.953876 -367.832132)
		(width 0.13208)
		(layer "F.Cu")
		(net "HSC_CS")
	)
	(segment
		(start 200.749916 -367.133886)
		(end 200.994264 -367.133886)
		(width 0.13208)
		(layer "F.Cu")
		(net "HSC_CS")
	)
	(segment
		(start 200.074276 -366.458246)
		(end 200.749916 -367.133886)
		(width 0.13208)
		(layer "F.Cu")
		(net "HSC_CS")
	)
	(segment
		(start 200.994264 -367.133886)
		(end 201.494898 -367.63452)
		(width 0.13208)
		(layer "F.Cu")
		(net "HSC_CS")
	)
	(segment
		(start 199.469248 -364.599728)
		(end 200.074276 -365.204756)
		(width 0.13208)
		(layer "F.Cu")
		(net "HSC_CS")
	)
	(via
		(at 200.074276 -366.458246)
		(size 0.508)
		(drill 0.254)
		(layers "F.Cu" "B.Cu")
		(net "HSC_CS")
	)
	(segment
		(start 4.244086 -44.689522)
		(end 5.884164 -46.3296)
		(width 0.13208)
		(layer "F.Cu")
		(net "SSD0_AUX_P3V3_EN_R")
	)
	(segment
		(start 6.140958 -57.675272)
		(end 5.740146 -58.076084)
		(width 0.13208)
		(layer "F.Cu")
		(net "SSD0_AUX_P3V3_EN_R")
	)
	(segment
		(start 5.0292 -58.78703)
		(end 5.740146 -58.076084)
		(width 0.13208)
		(layer "F.Cu")
		(net "SSD0_AUX_P3V3_EN_R")
	)
	(segment
		(start 9.04367 -46.3296)
		(end 9.64311 -45.73016)
		(width 0.13208)
		(layer "F.Cu")
		(net "SSD0_AUX_P3V3_EN_R")
	)
	(segment
		(start 5.884164 -46.3296)
		(end 9.04367 -46.3296)
		(width 0.13208)
		(layer "F.Cu")
		(net "SSD0_AUX_P3V3_EN_R")
	)
	(segment
		(start 6.140958 -57.16397)
		(end 6.140958 -57.675272)
		(width 0.13208)
		(layer "F.Cu")
		(net "SSD0_AUX_P3V3_EN_R")
	)
	(segment
		(start 4.244086 -44.689522)
		(end 4.244086 -44.037758)
		(width 0.13208)
		(layer "F.Cu")
		(net "SSD0_AUX_P3V3_EN_R")
	)
	(segment
		(start 4.781804 -59.157108)
		(end 5.0292 -58.78703)
		(width 0.13208)
		(layer "F.Cu")
		(net "SSD0_AUX_P3V3_EN_R")
	)
	(segment
		(start 9.64311 -45.73016)
		(end 9.64311 -45.111924)
		(width 0.13208)
		(layer "F.Cu")
		(net "SSD0_AUX_P3V3_EN_R")
	)
	(via
		(at 5.740146 -58.076084)
		(size 0.508)
		(drill 0.254)
		(layers "F.Cu" "B.Cu")
		(net "SSD0_AUX_P3V3_EN_R")
	)
	(via
		(at 4.244086 -44.689522)
		(size 0.508)
		(drill 0.254)
		(layers "F.Cu" "B.Cu")
		(net "SSD0_AUX_P3V3_EN_R")
	)
	(segment
		(start 4.244086 -44.689522)
		(end 2.121916 -46.811692)
		(width 0.15494)
		(layer "In5.Cu")
		(net "SSD0_AUX_P3V3_EN_R")
	)
	(segment
		(start 2.121916 -58.343038)
		(end 2.485136 -58.706258)
		(width 0.15494)
		(layer "In5.Cu")
		(net "SSD0_AUX_P3V3_EN_R")
	)
	(segment
		(start 5.109972 -58.706258)
		(end 5.740146 -58.076084)
		(width 0.15494)
		(layer "In5.Cu")
		(net "SSD0_AUX_P3V3_EN_R")
	)
	(segment
		(start 2.485136 -58.706258)
		(end 5.109972 -58.706258)
		(width 0.15494)
		(layer "In5.Cu")
		(net "SSD0_AUX_P3V3_EN_R")
	)
	(segment
		(start 2.121916 -46.811692)
		(end 2.121916 -58.343038)
		(width 0.15494)
		(layer "In5.Cu")
		(net "SSD0_AUX_P3V3_EN_R")
	)
	(segment
		(start 234.855512 -232.471468)
		(end 234.855512 -231.816656)
		(width 0.13208)
		(layer "F.Cu")
		(net "SSD8_PWRDIS_BIC_R")
	)
	(segment
		(start 235.327952 -233.439716)
		(end 235.327952 -232.943908)
		(width 0.13208)
		(layer "F.Cu")
		(net "SSD8_PWRDIS_BIC_R")
	)
	(segment
		(start 234.855512 -234.327954)
		(end 234.855512 -233.912156)
		(width 0.13208)
		(layer "F.Cu")
		(net "SSD8_PWRDIS_BIC_R")
	)
	(segment
		(start 235.327952 -232.943908)
		(end 234.855512 -232.471468)
		(width 0.13208)
		(layer "F.Cu")
		(net "SSD8_PWRDIS_BIC_R")
	)
	(segment
		(start 234.855512 -233.912156)
		(end 235.327952 -233.439716)
		(width 0.13208)
		(layer "F.Cu")
		(net "SSD8_PWRDIS_BIC_R")
	)
	(segment
		(start 338.893912 -217.587068)
		(end 338.494116 -217.187272)
		(width 0.13208)
		(layer "F.Cu")
		(net "SSD8_PWRDIS_BIC_R")
	)
	(via
		(at 234.855512 -232.471468)
		(size 0.508)
		(drill 0.254)
		(layers "F.Cu" "B.Cu")
		(net "SSD8_PWRDIS_BIC_R")
	)
	(via
		(at 264.926064 -198.668894)
		(size 0.508)
		(drill 0.254)
		(layers "F.Cu" "B.Cu")
		(net "SSD8_PWRDIS_BIC_R")
	)
	(via
		(at 338.494116 -217.187272)
		(size 0.4572)
		(drill 0.254)
		(layers "F.Cu" "B.Cu")
		(net "SSD8_PWRDIS_BIC_R")
	)
	(segment
		(start 241.4778 -229.108)
		(end 247.79605 -222.78975)
		(width 0.15494)
		(layer "In7.Cu")
		(net "SSD8_PWRDIS_BIC_R")
	)
	(segment
		(start 255.0668 -200.7108)
		(end 255.819148 -200.7108)
		(width 0.15494)
		(layer "In7.Cu")
		(net "SSD8_PWRDIS_BIC_R")
	)
	(segment
		(start 255.980184 -200.549764)
		(end 263.045194 -200.549764)
		(width 0.15494)
		(layer "In7.Cu")
		(net "SSD8_PWRDIS_BIC_R")
	)
	(segment
		(start 249.7836 -216.027254)
		(end 249.7836 -214.401146)
		(width 0.15494)
		(layer "In7.Cu")
		(net "SSD8_PWRDIS_BIC_R")
	)
	(segment
		(start 250.545346 -213.6394)
		(end 251.1806 -213.6394)
		(width 0.15494)
		(layer "In7.Cu")
		(net "SSD8_PWRDIS_BIC_R")
	)
	(segment
		(start 237.27537 -230.05161)
		(end 240.813844 -230.05161)
		(width 0.15494)
		(layer "In7.Cu")
		(net "SSD8_PWRDIS_BIC_R")
	)
	(segment
		(start 248.84761 -216.963244)
		(end 249.7836 -216.027254)
		(width 0.15494)
		(layer "In7.Cu")
		(net "SSD8_PWRDIS_BIC_R")
	)
	(segment
		(start 241.4778 -229.387654)
		(end 241.4778 -229.108)
		(width 0.15494)
		(layer "In7.Cu")
		(net "SSD8_PWRDIS_BIC_R")
	)
	(segment
		(start 240.813844 -230.05161)
		(end 241.4778 -229.387654)
		(width 0.15494)
		(layer "In7.Cu")
		(net "SSD8_PWRDIS_BIC_R")
	)
	(segment
		(start 255.819148 -200.7108)
		(end 255.980184 -200.549764)
		(width 0.15494)
		(layer "In7.Cu")
		(net "SSD8_PWRDIS_BIC_R")
	)
	(segment
		(start 248.84761 -219.438474)
		(end 248.84761 -216.963244)
		(width 0.15494)
		(layer "In7.Cu")
		(net "SSD8_PWRDIS_BIC_R")
	)
	(segment
		(start 247.79605 -220.490034)
		(end 248.84761 -219.438474)
		(width 0.15494)
		(layer "In7.Cu")
		(net "SSD8_PWRDIS_BIC_R")
	)
	(segment
		(start 247.79605 -222.78975)
		(end 247.79605 -220.490034)
		(width 0.15494)
		(layer "In7.Cu")
		(net "SSD8_PWRDIS_BIC_R")
	)
	(segment
		(start 234.855512 -232.471468)
		(end 237.27537 -230.05161)
		(width 0.15494)
		(layer "In7.Cu")
		(net "SSD8_PWRDIS_BIC_R")
	)
	(segment
		(start 251.1806 -213.6394)
		(end 251.669804 -213.150196)
		(width 0.15494)
		(layer "In7.Cu")
		(net "SSD8_PWRDIS_BIC_R")
	)
	(segment
		(start 263.045194 -200.549764)
		(end 264.926064 -198.668894)
		(width 0.15494)
		(layer "In7.Cu")
		(net "SSD8_PWRDIS_BIC_R")
	)
	(segment
		(start 251.669804 -213.150196)
		(end 251.669804 -204.107796)
		(width 0.15494)
		(layer "In7.Cu")
		(net "SSD8_PWRDIS_BIC_R")
	)
	(segment
		(start 249.7836 -214.401146)
		(end 250.545346 -213.6394)
		(width 0.15494)
		(layer "In7.Cu")
		(net "SSD8_PWRDIS_BIC_R")
	)
	(segment
		(start 251.669804 -204.107796)
		(end 255.0668 -200.7108)
		(width 0.15494)
		(layer "In7.Cu")
		(net "SSD8_PWRDIS_BIC_R")
	)
	(segment
		(start 328.34834 -214.73287)
		(end 328.06513 -214.44966)
		(width 0.15494)
		(layer "In13.Cu")
		(net "SSD8_PWRDIS_BIC_R")
	)
	(segment
		(start 320.955162 -211.263992)
		(end 320.536316 -211.263992)
		(width 0.15494)
		(layer "In13.Cu")
		(net "SSD8_PWRDIS_BIC_R")
	)
	(segment
		(start 322.46443 -212.77326)
		(end 320.955162 -211.263992)
		(width 0.15494)
		(layer "In13.Cu")
		(net "SSD8_PWRDIS_BIC_R")
	)
	(segment
		(start 330.388722 -214.742776)
		(end 328.372724 -214.742776)
		(width 0.15494)
		(layer "In13.Cu")
		(net "SSD8_PWRDIS_BIC_R")
	)
	(segment
		(start 333.24038 -217.594434)
		(end 330.388722 -214.742776)
		(width 0.15494)
		(layer "In13.Cu")
		(net "SSD8_PWRDIS_BIC_R")
	)
	(segment
		(start 320.116454 -210.84413)
		(end 279.67813 -210.84413)
		(width 0.15494)
		(layer "In13.Cu")
		(net "SSD8_PWRDIS_BIC_R")
	)
	(segment
		(start 328.372724 -214.742776)
		(end 328.362818 -214.73287)
		(width 0.15494)
		(layer "In13.Cu")
		(net "SSD8_PWRDIS_BIC_R")
	)
	(segment
		(start 279.67813 -210.84413)
		(end 267.502894 -198.668894)
		(width 0.15494)
		(layer "In13.Cu")
		(net "SSD8_PWRDIS_BIC_R")
	)
	(segment
		(start 328.06513 -214.44966)
		(end 328.06513 -213.739476)
		(width 0.15494)
		(layer "In13.Cu")
		(net "SSD8_PWRDIS_BIC_R")
	)
	(segment
		(start 338.494116 -217.187272)
		(end 338.086954 -217.594434)
		(width 0.0889)
		(layer "In13.Cu")
		(net "SSD8_PWRDIS_BIC_R")
	)
	(segment
		(start 328.06513 -213.739476)
		(end 327.098914 -212.77326)
		(width 0.15494)
		(layer "In13.Cu")
		(net "SSD8_PWRDIS_BIC_R")
	)
	(segment
		(start 338.086954 -217.594434)
		(end 333.24038 -217.594434)
		(width 0.0889)
		(layer "In13.Cu")
		(net "SSD8_PWRDIS_BIC_R")
	)
	(segment
		(start 328.362818 -214.73287)
		(end 328.34834 -214.73287)
		(width 0.15494)
		(layer "In13.Cu")
		(net "SSD8_PWRDIS_BIC_R")
	)
	(segment
		(start 267.502894 -198.668894)
		(end 264.926064 -198.668894)
		(width 0.15494)
		(layer "In13.Cu")
		(net "SSD8_PWRDIS_BIC_R")
	)
	(segment
		(start 320.536316 -211.263992)
		(end 320.116454 -210.84413)
		(width 0.15494)
		(layer "In13.Cu")
		(net "SSD8_PWRDIS_BIC_R")
	)
	(segment
		(start 327.098914 -212.77326)
		(end 322.46443 -212.77326)
		(width 0.15494)
		(layer "In13.Cu")
		(net "SSD8_PWRDIS_BIC_R")
	)
	(segment
		(start 230.498396 -141.937232)
		(end 230.498396 -139.422886)
		(width 0.13208)
		(layer "F.Cu")
		(net "CLK_CK440_PEX_SMB_ADDR0")
	)
	(segment
		(start 230.347012 -142.820136)
		(end 230.374952 -142.792196)
		(width 0.13208)
		(layer "F.Cu")
		(net "CLK_CK440_PEX_SMB_ADDR0")
	)
	(segment
		(start 229.879398 -138.803888)
		(end 229.879398 -138.610086)
		(width 0.13208)
		(layer "F.Cu")
		(net "CLK_CK440_PEX_SMB_ADDR0")
	)
	(segment
		(start 230.347012 -143.265398)
		(end 230.347012 -142.820136)
		(width 0.13208)
		(layer "F.Cu")
		(net "CLK_CK440_PEX_SMB_ADDR0")
	)
	(segment
		(start 230.498396 -139.422886)
		(end 229.879398 -138.803888)
		(width 0.13208)
		(layer "F.Cu")
		(net "CLK_CK440_PEX_SMB_ADDR0")
	)
	(segment
		(start 228.582474 -137.069322)
		(end 229.471474 -137.069322)
		(width 0.13208)
		(layer "F.Cu")
		(net "CLK_CK440_PEX_SMB_ADDR0")
	)
	(segment
		(start 229.471474 -137.069322)
		(end 229.471474 -137.79881)
		(width 0.13208)
		(layer "F.Cu")
		(net "CLK_CK440_PEX_SMB_ADDR0")
	)
	(segment
		(start 229.54234 -137.869676)
		(end 229.54234 -138.273028)
		(width 0.13208)
		(layer "F.Cu")
		(net "CLK_CK440_PEX_SMB_ADDR0")
	)
	(segment
		(start 229.471474 -137.79881)
		(end 229.54234 -137.869676)
		(width 0.13208)
		(layer "F.Cu")
		(net "CLK_CK440_PEX_SMB_ADDR0")
	)
	(segment
		(start 229.879398 -138.610086)
		(end 229.54234 -138.273028)
		(width 0.13208)
		(layer "F.Cu")
		(net "CLK_CK440_PEX_SMB_ADDR0")
	)
	(segment
		(start 230.374952 -142.060676)
		(end 230.498396 -141.937232)
		(width 0.13208)
		(layer "F.Cu")
		(net "CLK_CK440_PEX_SMB_ADDR0")
	)
	(segment
		(start 230.374952 -142.792196)
		(end 230.374952 -142.060676)
		(width 0.13208)
		(layer "F.Cu")
		(net "CLK_CK440_PEX_SMB_ADDR0")
	)
	(via
		(at 229.54234 -138.273028)
		(size 0.762)
		(drill 0.381)
		(layers "F.Cu" "B.Cu")
		(net "CLK_CK440_PEX_SMB_ADDR0")
	)
	(segment
		(start 348.493842 -213.587076)
		(end 348.893892 -213.187026)
		(width 0.13208)
		(layer "F.Cu")
		(net "RST_FPGA_BIC_N")
	)
	(via
		(at 349.37192 -209.48523)
		(size 0.6604)
		(drill 0.3302)
		(layers "F.Cu" "B.Cu")
		(net "RST_FPGA_BIC_N")
	)
	(via
		(at 348.893892 -213.187026)
		(size 0.4572)
		(drill 0.254)
		(layers "F.Cu" "B.Cu")
		(net "RST_FPGA_BIC_N")
	)
	(segment
		(start 348.869 -208.605882)
		(end 348.869 -208.17205)
		(width 0.13208)
		(layer "B.Cu")
		(net "RST_FPGA_BIC_N")
	)
	(segment
		(start 349.37192 -209.48523)
		(end 349.37192 -209.108802)
		(width 0.13208)
		(layer "B.Cu")
		(net "RST_FPGA_BIC_N")
	)
	(segment
		(start 349.37192 -209.866992)
		(end 349.37192 -209.48523)
		(width 0.13208)
		(layer "B.Cu")
		(net "RST_FPGA_BIC_N")
	)
	(segment
		(start 349.37192 -209.108802)
		(end 348.869 -208.605882)
		(width 0.13208)
		(layer "B.Cu")
		(net "RST_FPGA_BIC_N")
	)
	(segment
		(start 348.720156 -210.518756)
		(end 349.37192 -209.866992)
		(width 0.13208)
		(layer "B.Cu")
		(net "RST_FPGA_BIC_N")
	)
	(segment
		(start 348.495112 -212.788246)
		(end 348.495112 -210.7438)
		(width 0.0889)
		(layer "B.Cu")
		(net "RST_FPGA_BIC_N")
	)
	(segment
		(start 348.495112 -210.7438)
		(end 348.720156 -210.518756)
		(width 0.0889)
		(layer "B.Cu")
		(net "RST_FPGA_BIC_N")
	)
	(segment
		(start 348.893892 -213.187026)
		(end 348.495112 -212.788246)
		(width 0.0889)
		(layer "B.Cu")
		(net "RST_FPGA_BIC_N")
	)
	(segment
		(start 350.012 -208.17205)
		(end 348.869 -208.17205)
		(width 0.13208)
		(layer "B.Cu")
		(net "RST_FPGA_BIC_N")
	)
	(segment
		(start 235.302552 -40.058086)
		(end 234.580176 -39.33571)
		(width 0.13208)
		(layer "F.Cu")
		(net "SSD8_AUX_P3V3_EN")
	)
	(segment
		(start 237.047786 -41.137332)
		(end 237.047786 -40.185086)
		(width 0.13208)
		(layer "F.Cu")
		(net "SSD8_AUX_P3V3_EN")
	)
	(segment
		(start 234.580176 -39.33571)
		(end 233.326178 -39.33571)
		(width 0.13208)
		(layer "F.Cu")
		(net "SSD8_AUX_P3V3_EN")
	)
	(segment
		(start 233.326178 -38.329616)
		(end 233.326178 -39.33571)
		(width 0.13208)
		(layer "F.Cu")
		(net "SSD8_AUX_P3V3_EN")
	)
	(segment
		(start 236.920786 -40.058086)
		(end 235.302552 -40.058086)
		(width 0.13208)
		(layer "F.Cu")
		(net "SSD8_AUX_P3V3_EN")
	)
	(segment
		(start 237.047786 -40.185086)
		(end 236.920786 -40.058086)
		(width 0.13208)
		(layer "F.Cu")
		(net "SSD8_AUX_P3V3_EN")
	)
	(via
		(at 234.580176 -39.33571)
		(size 0.762)
		(drill 0.381)
		(layers "F.Cu" "B.Cu")
		(net "SSD8_AUX_P3V3_EN")
	)
	(segment
		(start 238.046768 -37.774118)
		(end 236.491018 -37.774118)
		(width 0.13208)
		(layer "F.Cu")
		(net "PRSNT_SSD8_R1_N")
	)
	(segment
		(start 236.097826 -38.16731)
		(end 236.097826 -38.937184)
		(width 0.13208)
		(layer "F.Cu")
		(net "PRSNT_SSD8_R1_N")
	)
	(segment
		(start 238.59363 -37.774118)
		(end 238.046768 -37.774118)
		(width 0.13208)
		(layer "F.Cu")
		(net "PRSNT_SSD8_R1_N")
	)
	(segment
		(start 238.775748 -37.592)
		(end 238.59363 -37.774118)
		(width 0.13208)
		(layer "F.Cu")
		(net "PRSNT_SSD8_R1_N")
	)
	(segment
		(start 236.491018 -37.774118)
		(end 236.097826 -38.16731)
		(width 0.13208)
		(layer "F.Cu")
		(net "PRSNT_SSD8_R1_N")
	)
	(segment
		(start 238.775748 -37.315648)
		(end 238.775748 -37.592)
		(width 0.13208)
		(layer "F.Cu")
		(net "PRSNT_SSD8_R1_N")
	)
	(via
		(at 238.046768 -37.774118)
		(size 0.508)
		(drill 0.254)
		(layers "F.Cu" "B.Cu")
		(net "PRSNT_SSD8_R1_N")
	)
	(segment
		(start 222.635826 -146.990562)
		(end 223.696276 -145.930112)
		(width 0.13208)
		(layer "F.Cu")
		(net "PU_CK440_PEX_SHFT_LD_N")
	)
	(segment
		(start 224.029016 -145.930112)
		(end 224.146364 -145.812764)
		(width 0.13208)
		(layer "F.Cu")
		(net "PU_CK440_PEX_SHFT_LD_N")
	)
	(segment
		(start 223.696276 -145.930112)
		(end 224.029016 -145.930112)
		(width 0.13208)
		(layer "F.Cu")
		(net "PU_CK440_PEX_SHFT_LD_N")
	)
	(segment
		(start 221.651322 -146.990562)
		(end 221.651322 -145.974562)
		(width 0.13208)
		(layer "F.Cu")
		(net "PU_CK440_PEX_SHFT_LD_N")
	)
	(segment
		(start 221.651322 -146.990562)
		(end 222.32366 -146.990562)
		(width 0.13208)
		(layer "F.Cu")
		(net "PU_CK440_PEX_SHFT_LD_N")
	)
	(segment
		(start 222.32366 -146.990562)
		(end 222.635826 -146.990562)
		(width 0.13208)
		(layer "F.Cu")
		(net "PU_CK440_PEX_SHFT_LD_N")
	)
	(segment
		(start 224.31883 -145.640298)
		(end 225.47199 -145.640298)
		(width 0.0889)
		(layer "F.Cu")
		(net "PU_CK440_PEX_SHFT_LD_N")
	)
	(segment
		(start 224.146364 -145.812764)
		(end 224.31883 -145.640298)
		(width 0.0889)
		(layer "F.Cu")
		(net "PU_CK440_PEX_SHFT_LD_N")
	)
	(via
		(at 222.32366 -146.990562)
		(size 0.508)
		(drill 0.254)
		(layers "F.Cu" "B.Cu")
		(net "PU_CK440_PEX_SHFT_LD_N")
	)
	(segment
		(start 231.706928 -135.561324)
		(end 232.565448 -136.419844)
		(width 0.13208)
		(layer "F.Cu")
		(net "XTAL_CK440_PEX_25M_XOUT")
	)
	(segment
		(start 232.086912 -138.447018)
		(end 232.086912 -139.026392)
		(width 0.13208)
		(layer "F.Cu")
		(net "XTAL_CK440_PEX_25M_XOUT")
	)
	(segment
		(start 231.32034 -142.347696)
		(end 231.269794 -142.46987)
		(width 0.13208)
		(layer "F.Cu")
		(net "XTAL_CK440_PEX_25M_XOUT")
	)
	(segment
		(start 231.269794 -142.46987)
		(end 231.097074 -142.887192)
		(width 0.0889)
		(layer "F.Cu")
		(net "XTAL_CK440_PEX_25M_XOUT")
	)
	(segment
		(start 232.565448 -137.804398)
		(end 232.449624 -138.084306)
		(width 0.13208)
		(layer "F.Cu")
		(net "XTAL_CK440_PEX_25M_XOUT")
	)
	(segment
		(start 232.086912 -140.659104)
		(end 231.32034 -141.425676)
		(width 0.13208)
		(layer "F.Cu")
		(net "XTAL_CK440_PEX_25M_XOUT")
	)
	(segment
		(start 232.086912 -139.82573)
		(end 232.086912 -139.026392)
		(width 0.13208)
		(layer "F.Cu")
		(net "XTAL_CK440_PEX_25M_XOUT")
	)
	(segment
		(start 232.086912 -139.82573)
		(end 232.086912 -140.659104)
		(width 0.13208)
		(layer "F.Cu")
		(net "XTAL_CK440_PEX_25M_XOUT")
	)
	(segment
		(start 231.55402 -135.561324)
		(end 231.706928 -135.561324)
		(width 0.13208)
		(layer "F.Cu")
		(net "XTAL_CK440_PEX_25M_XOUT")
	)
	(segment
		(start 231.097074 -142.887192)
		(end 231.097074 -144.01546)
		(width 0.0889)
		(layer "F.Cu")
		(net "XTAL_CK440_PEX_25M_XOUT")
	)
	(segment
		(start 232.449624 -138.084306)
		(end 232.086912 -138.447018)
		(width 0.13208)
		(layer "F.Cu")
		(net "XTAL_CK440_PEX_25M_XOUT")
	)
	(segment
		(start 232.565448 -136.419844)
		(end 232.565448 -137.804398)
		(width 0.13208)
		(layer "F.Cu")
		(net "XTAL_CK440_PEX_25M_XOUT")
	)
	(segment
		(start 231.32034 -141.425676)
		(end 231.32034 -142.347696)
		(width 0.13208)
		(layer "F.Cu")
		(net "XTAL_CK440_PEX_25M_XOUT")
	)
	(via
		(at 232.086912 -139.82573)
		(size 0.508)
		(drill 0.254)
		(layers "F.Cu" "B.Cu")
		(net "XTAL_CK440_PEX_25M_XOUT")
	)
	(segment
		(start 213.509606 -121.158762)
		(end 213.509606 -122.04573)
		(width 0.13208)
		(layer "F.Cu")
		(net "HP_NIC3_EN")
	)
	(segment
		(start 238.524796 -111.999268)
		(end 239.235488 -111.999268)
		(width 0.13208)
		(layer "F.Cu")
		(net "HP_NIC3_EN")
	)
	(segment
		(start 213.509606 -122.04573)
		(end 213.988904 -122.525028)
		(width 0.13208)
		(layer "F.Cu")
		(net "HP_NIC3_EN")
	)
	(segment
		(start 212.871304 -120.77192)
		(end 213.122764 -120.77192)
		(width 0.13208)
		(layer "F.Cu")
		(net "HP_NIC3_EN")
	)
	(segment
		(start 228.024944 -97.96907)
		(end 228.024944 -97.31375)
		(width 0.13208)
		(layer "F.Cu")
		(net "HP_NIC3_EN")
	)
	(segment
		(start 200.601834 -140.050774)
		(end 199.531986 -140.050774)
		(width 0.13208)
		(layer "F.Cu")
		(net "HP_NIC3_EN")
	)
	(segment
		(start 198.214234 -138.70305)
		(end 198.214234 -139.734798)
		(width 0.13208)
		(layer "F.Cu")
		(net "HP_NIC3_EN")
	)
	(segment
		(start 199.531986 -140.050774)
		(end 199.21601 -139.734798)
		(width 0.13208)
		(layer "F.Cu")
		(net "HP_NIC3_EN")
	)
	(segment
		(start 204.352144 -113.876836)
		(end 203.742544 -113.876836)
		(width 0.13208)
		(layer "F.Cu")
		(net "HP_NIC3_EN")
	)
	(segment
		(start 213.988904 -122.525028)
		(end 214.675466 -122.525028)
		(width 0.13208)
		(layer "F.Cu")
		(net "HP_NIC3_EN")
	)
	(segment
		(start 213.122764 -120.77192)
		(end 213.509606 -121.158762)
		(width 0.13208)
		(layer "F.Cu")
		(net "HP_NIC3_EN")
	)
	(segment
		(start 198.482966 -138.434318)
		(end 198.214234 -138.70305)
		(width 0.13208)
		(layer "F.Cu")
		(net "HP_NIC3_EN")
	)
	(segment
		(start 199.21601 -139.734798)
		(end 198.214234 -139.734798)
		(width 0.13208)
		(layer "F.Cu")
		(net "HP_NIC3_EN")
	)
	(via
		(at 198.482966 -138.434318)
		(size 0.508)
		(drill 0.254)
		(layers "F.Cu" "B.Cu")
		(net "HP_NIC3_EN")
	)
	(via
		(at 213.988904 -122.525028)
		(size 0.508)
		(drill 0.254)
		(layers "F.Cu" "B.Cu")
		(net "HP_NIC3_EN")
	)
	(via
		(at 228.024944 -97.31375)
		(size 0.508)
		(drill 0.254)
		(layers "F.Cu" "B.Cu")
		(net "HP_NIC3_EN")
	)
	(via
		(at 203.742544 -113.876836)
		(size 0.508)
		(drill 0.254)
		(layers "F.Cu" "B.Cu")
		(net "HP_NIC3_EN")
	)
	(via
		(at 239.235488 -111.999268)
		(size 0.508)
		(drill 0.254)
		(layers "F.Cu" "B.Cu")
		(net "HP_NIC3_EN")
	)
	(segment
		(start 233.706924 -99.128072)
		(end 229.839266 -99.128072)
		(width 0.13208)
		(layer "B.Cu")
		(net "HP_NIC3_EN")
	)
	(segment
		(start 239.235488 -111.999268)
		(end 239.235488 -104.656636)
		(width 0.13208)
		(layer "B.Cu")
		(net "HP_NIC3_EN")
	)
	(segment
		(start 239.235488 -104.656636)
		(end 233.706924 -99.128072)
		(width 0.13208)
		(layer "B.Cu")
		(net "HP_NIC3_EN")
	)
	(segment
		(start 229.839266 -99.128072)
		(end 228.024944 -97.31375)
		(width 0.13208)
		(layer "B.Cu")
		(net "HP_NIC3_EN")
	)
	(segment
		(start 216.521792 -127.43688)
		(end 213.988904 -124.903992)
		(width 0.15494)
		(layer "In9.Cu")
		(net "HP_NIC3_EN")
	)
	(segment
		(start 237.512352 -122.129042)
		(end 232.204514 -127.43688)
		(width 0.15494)
		(layer "In9.Cu")
		(net "HP_NIC3_EN")
	)
	(segment
		(start 214.781892 -115.3795)
		(end 210.874356 -111.471964)
		(width 0.15494)
		(layer "In9.Cu")
		(net "HP_NIC3_EN")
	)
	(segment
		(start 213.934294 -121.574306)
		(end 214.781892 -120.726708)
		(width 0.15494)
		(layer "In9.Cu")
		(net "HP_NIC3_EN")
	)
	(segment
		(start 232.204514 -127.43688)
		(end 216.521792 -127.43688)
		(width 0.15494)
		(layer "In9.Cu")
		(net "HP_NIC3_EN")
	)
	(segment
		(start 239.235488 -111.999268)
		(end 239.963198 -112.726978)
		(width 0.15494)
		(layer "In9.Cu")
		(net "HP_NIC3_EN")
	)
	(segment
		(start 210.874356 -111.471964)
		(end 206.147416 -111.471964)
		(width 0.15494)
		(layer "In9.Cu")
		(net "HP_NIC3_EN")
	)
	(segment
		(start 237.512352 -120.86336)
		(end 237.512352 -122.129042)
		(width 0.15494)
		(layer "In9.Cu")
		(net "HP_NIC3_EN")
	)
	(segment
		(start 239.963198 -112.726978)
		(end 239.963198 -118.412514)
		(width 0.15494)
		(layer "In9.Cu")
		(net "HP_NIC3_EN")
	)
	(segment
		(start 213.934294 -122.470418)
		(end 213.934294 -121.574306)
		(width 0.15494)
		(layer "In9.Cu")
		(net "HP_NIC3_EN")
	)
	(segment
		(start 206.147416 -111.471964)
		(end 203.742544 -113.876836)
		(width 0.15494)
		(layer "In9.Cu")
		(net "HP_NIC3_EN")
	)
	(segment
		(start 214.781892 -120.726708)
		(end 214.781892 -115.3795)
		(width 0.15494)
		(layer "In9.Cu")
		(net "HP_NIC3_EN")
	)
	(segment
		(start 213.988904 -124.903992)
		(end 213.988904 -122.525028)
		(width 0.15494)
		(layer "In9.Cu")
		(net "HP_NIC3_EN")
	)
	(segment
		(start 213.988904 -122.525028)
		(end 213.934294 -122.470418)
		(width 0.15494)
		(layer "In9.Cu")
		(net "HP_NIC3_EN")
	)
	(segment
		(start 239.963198 -118.412514)
		(end 237.512352 -120.86336)
		(width 0.15494)
		(layer "In9.Cu")
		(net "HP_NIC3_EN")
	)
	(segment
		(start 212.6742 -134.819898)
		(end 212.6742 -136.142222)
		(width 0.15494)
		(layer "In15.Cu")
		(net "HP_NIC3_EN")
	)
	(segment
		(start 210.382104 -138.434318)
		(end 198.482966 -138.434318)
		(width 0.15494)
		(layer "In15.Cu")
		(net "HP_NIC3_EN")
	)
	(segment
		(start 204.2414 -114.375692)
		(end 204.2414 -126.387098)
		(width 0.15494)
		(layer "In15.Cu")
		(net "HP_NIC3_EN")
	)
	(segment
		(start 204.2414 -126.387098)
		(end 212.6742 -134.819898)
		(width 0.15494)
		(layer "In15.Cu")
		(net "HP_NIC3_EN")
	)
	(segment
		(start 212.6742 -136.142222)
		(end 210.382104 -138.434318)
		(width 0.15494)
		(layer "In15.Cu")
		(net "HP_NIC3_EN")
	)
	(segment
		(start 203.742544 -113.876836)
		(end 204.2414 -114.375692)
		(width 0.15494)
		(layer "In15.Cu")
		(net "HP_NIC3_EN")
	)
	(segment
		(start 225.845116 -227.695252)
		(end 225.930714 -227.48875)
		(width 0.13208)
		(layer "F.Cu")
		(net "REV_ID0")
	)
	(segment
		(start 224.695512 -230.466392)
		(end 225.845116 -229.316788)
		(width 0.13208)
		(layer "F.Cu")
		(net "REV_ID0")
	)
	(segment
		(start 227.067618 -226.351846)
		(end 227.067618 -224.304098)
		(width 0.13208)
		(layer "F.Cu")
		(net "REV_ID0")
	)
	(segment
		(start 225.930714 -227.48875)
		(end 227.067618 -226.351846)
		(width 0.13208)
		(layer "F.Cu")
		(net "REV_ID0")
	)
	(segment
		(start 225.845116 -229.316788)
		(end 225.845116 -227.695252)
		(width 0.13208)
		(layer "F.Cu")
		(net "REV_ID0")
	)
	(segment
		(start 227.067618 -224.304098)
		(end 227.467668 -223.904048)
		(width 0.13208)
		(layer "F.Cu")
		(net "REV_ID0")
	)
	(segment
		(start 223.679512 -231.016556)
		(end 224.695512 -231.016556)
		(width 0.13208)
		(layer "F.Cu")
		(net "REV_ID0")
	)
	(segment
		(start 224.695512 -231.016556)
		(end 224.695512 -230.466392)
		(width 0.13208)
		(layer "F.Cu")
		(net "REV_ID0")
	)
	(via
		(at 225.845116 -227.695252)
		(size 0.762)
		(drill 0.381)
		(layers "F.Cu" "B.Cu")
		(net "REV_ID0")
	)
	(segment
		(start 232.26776 -216.704164)
		(end 232.667556 -216.304368)
		(width 0.381)
		(layer "F.Cu")
		(net "P3V3_BIC_USB2AV33")
	)
	(via
		(at 232.667556 -216.304368)
		(size 0.4572)
		(drill 0.254)
		(layers "F.Cu" "B.Cu")
		(net "P3V3_BIC_USB2AV33")
	)
	(via
		(at 237.069376 -208.751932)
		(size 0.6604)
		(drill 0.3302)
		(layers "F.Cu" "B.Cu")
		(net "P3V3_BIC_USB2AV33")
	)
	(via
		(at 237.556548 -209.58429)
		(size 0.508)
		(drill 0.254)
		(layers "F.Cu" "B.Cu")
		(net "P3V3_BIC_USB2AV33")
	)
	(via
		(at 236.834172 -209.58429)
		(size 0.508)
		(drill 0.254)
		(layers "F.Cu" "B.Cu")
		(net "P3V3_BIC_USB2AV33")
	)
	(segment
		(start 336.44205 -143.891)
		(end 336.44205 -142.875)
		(width 0.13208)
		(layer "F.Cu")
		(net "SSD15_PEX_PWR_EN_R")
	)
	(segment
		(start 337.058 -142.875)
		(end 337.67395 -142.875)
		(width 0.13208)
		(layer "F.Cu")
		(net "SSD15_PEX_PWR_EN_R")
	)
	(segment
		(start 336.44205 -142.875)
		(end 337.058 -142.875)
		(width 0.13208)
		(layer "F.Cu")
		(net "SSD15_PEX_PWR_EN_R")
	)
	(segment
		(start 338.093812 -219.987114)
		(end 337.694016 -220.38691)
		(width 0.13208)
		(layer "F.Cu")
		(net "SSD15_PEX_PWR_EN_R")
	)
	(via
		(at 337.058 -142.875)
		(size 0.508)
		(drill 0.254)
		(layers "F.Cu" "B.Cu")
		(net "SSD15_PEX_PWR_EN_R")
	)
	(via
		(at 337.694016 -220.38691)
		(size 0.4572)
		(drill 0.254)
		(layers "F.Cu" "B.Cu")
		(net "SSD15_PEX_PWR_EN_R")
	)
	(segment
		(start 337.50631 -142.875)
		(end 337.058 -142.875)
		(width 0.15494)
		(layer "In7.Cu")
		(net "SSD15_PEX_PWR_EN_R")
	)
	(segment
		(start 338.60486 -143.97355)
		(end 337.50631 -142.875)
		(width 0.15494)
		(layer "In7.Cu")
		(net "SSD15_PEX_PWR_EN_R")
	)
	(segment
		(start 332.3336 -155.466288)
		(end 335.591912 -152.207976)
		(width 0.15494)
		(layer "In7.Cu")
		(net "SSD15_PEX_PWR_EN_R")
	)
	(segment
		(start 331.0636 -216.718896)
		(end 331.0636 -216.2556)
		(width 0.15494)
		(layer "In7.Cu")
		(net "SSD15_PEX_PWR_EN_R")
	)
	(segment
		(start 338.60486 -147.552664)
		(end 338.60486 -143.97355)
		(width 0.15494)
		(layer "In7.Cu")
		(net "SSD15_PEX_PWR_EN_R")
	)
	(segment
		(start 331.585824 -198.30415)
		(end 331.585824 -168.692322)
		(width 0.15494)
		(layer "In7.Cu")
		(net "SSD15_PEX_PWR_EN_R")
	)
	(segment
		(start 330.38034 -215.57234)
		(end 330.38034 -215.085676)
		(width 0.15494)
		(layer "In7.Cu")
		(net "SSD15_PEX_PWR_EN_R")
	)
	(segment
		(start 338.074 -148.083524)
		(end 338.60486 -147.552664)
		(width 0.15494)
		(layer "In7.Cu")
		(net "SSD15_PEX_PWR_EN_R")
	)
	(segment
		(start 333.546704 -219.202)
		(end 331.0636 -216.718896)
		(width 0.15494)
		(layer "In7.Cu")
		(net "SSD15_PEX_PWR_EN_R")
	)
	(segment
		(start 335.591912 -151.364188)
		(end 338.074 -148.8821)
		(width 0.15494)
		(layer "In7.Cu")
		(net "SSD15_PEX_PWR_EN_R")
	)
	(segment
		(start 335.591912 -152.207976)
		(end 335.591912 -151.364188)
		(width 0.15494)
		(layer "In7.Cu")
		(net "SSD15_PEX_PWR_EN_R")
	)
	(segment
		(start 327.533 -210.91652)
		(end 327.533 -206.720186)
		(width 0.15494)
		(layer "In7.Cu")
		(net "SSD15_PEX_PWR_EN_R")
	)
	(segment
		(start 331.0636 -216.2556)
		(end 330.38034 -215.57234)
		(width 0.15494)
		(layer "In7.Cu")
		(net "SSD15_PEX_PWR_EN_R")
	)
	(segment
		(start 327.96988 -212.675216)
		(end 327.96988 -211.3534)
		(width 0.15494)
		(layer "In7.Cu")
		(net "SSD15_PEX_PWR_EN_R")
	)
	(segment
		(start 327.96988 -211.3534)
		(end 327.533 -210.91652)
		(width 0.15494)
		(layer "In7.Cu")
		(net "SSD15_PEX_PWR_EN_R")
	)
	(segment
		(start 326.64781 -205.834996)
		(end 326.64781 -203.242164)
		(width 0.15494)
		(layer "In7.Cu")
		(net "SSD15_PEX_PWR_EN_R")
	)
	(segment
		(start 326.64781 -203.242164)
		(end 331.585824 -198.30415)
		(width 0.15494)
		(layer "In7.Cu")
		(net "SSD15_PEX_PWR_EN_R")
	)
	(segment
		(start 332.3336 -167.944546)
		(end 332.3336 -155.466288)
		(width 0.15494)
		(layer "In7.Cu")
		(net "SSD15_PEX_PWR_EN_R")
	)
	(segment
		(start 336.509106 -219.202)
		(end 333.546704 -219.202)
		(width 0.15494)
		(layer "In7.Cu")
		(net "SSD15_PEX_PWR_EN_R")
	)
	(segment
		(start 327.533 -206.720186)
		(end 326.64781 -205.834996)
		(width 0.15494)
		(layer "In7.Cu")
		(net "SSD15_PEX_PWR_EN_R")
	)
	(segment
		(start 330.38034 -215.085676)
		(end 327.96988 -212.675216)
		(width 0.15494)
		(layer "In7.Cu")
		(net "SSD15_PEX_PWR_EN_R")
	)
	(segment
		(start 337.694016 -220.38691)
		(end 336.509106 -219.202)
		(width 0.15494)
		(layer "In7.Cu")
		(net "SSD15_PEX_PWR_EN_R")
	)
	(segment
		(start 331.585824 -168.692322)
		(end 332.3336 -167.944546)
		(width 0.15494)
		(layer "In7.Cu")
		(net "SSD15_PEX_PWR_EN_R")
	)
	(segment
		(start 338.074 -148.8821)
		(end 338.074 -148.083524)
		(width 0.15494)
		(layer "In7.Cu")
		(net "SSD15_PEX_PWR_EN_R")
	)
	(segment
		(start 232.26776 -215.904064)
		(end 232.667556 -215.504268)
		(width 0.381)
		(layer "F.Cu")
		(net "P1V2_BIC_USB2AV12")
	)
	(via
		(at 236.379004 -213.966044)
		(size 0.6604)
		(drill 0.3302)
		(layers "F.Cu" "B.Cu")
		(net "P1V2_BIC_USB2AV12")
	)
	(via
		(at 232.667556 -215.504268)
		(size 0.4572)
		(drill 0.254)
		(layers "F.Cu" "B.Cu")
		(net "P1V2_BIC_USB2AV12")
	)
	(via
		(at 236.995716 -214.326216)
		(size 0.508)
		(drill 0.254)
		(layers "F.Cu" "B.Cu")
		(net "P1V2_BIC_USB2AV12")
	)
	(via
		(at 236.987334 -213.586822)
		(size 0.508)
		(drill 0.254)
		(layers "F.Cu" "B.Cu")
		(net "P1V2_BIC_USB2AV12")
	)
	(segment
		(start 230.349044 -174.69358)
		(end 230.349044 -173.67758)
		(width 0.13208)
		(layer "F.Cu")
		(net "ADM1085_ENOUT")
	)
	(segment
		(start 229.787196 -175.70958)
		(end 229.167944 -175.090328)
		(width 0.13208)
		(layer "F.Cu")
		(net "ADM1085_ENOUT")
	)
	(segment
		(start 230.349044 -175.70958)
		(end 229.787196 -175.70958)
		(width 0.13208)
		(layer "F.Cu")
		(net "ADM1085_ENOUT")
	)
	(segment
		(start 229.035864 -173.838362)
		(end 227.911914 -173.838362)
		(width 0.13208)
		(layer "F.Cu")
		(net "ADM1085_ENOUT")
	)
	(segment
		(start 230.349044 -173.67758)
		(end 229.196646 -173.67758)
		(width 0.13208)
		(layer "F.Cu")
		(net "ADM1085_ENOUT")
	)
	(segment
		(start 229.167944 -175.090328)
		(end 228.602032 -175.65624)
		(width 0.13208)
		(layer "F.Cu")
		(net "ADM1085_ENOUT")
	)
	(segment
		(start 230.349044 -175.70958)
		(end 230.349044 -174.69358)
		(width 0.13208)
		(layer "F.Cu")
		(net "ADM1085_ENOUT")
	)
	(segment
		(start 228.602032 -175.65624)
		(end 227.520754 -175.65624)
		(width 0.13208)
		(layer "F.Cu")
		(net "ADM1085_ENOUT")
	)
	(segment
		(start 229.196646 -173.67758)
		(end 229.035864 -173.838362)
		(width 0.13208)
		(layer "F.Cu")
		(net "ADM1085_ENOUT")
	)
	(via
		(at 229.167944 -175.090328)
		(size 0.762)
		(drill 0.254)
		(layers "F.Cu" "B.Cu")
		(net "ADM1085_ENOUT")
	)
	(segment
		(start 230.015542 -175.937926)
		(end 229.167944 -175.090328)
		(width 0.13208)
		(layer "B.Cu")
		(net "ADM1085_ENOUT")
	)
	(segment
		(start 227.901246 -176.938432)
		(end 229.62235 -176.938432)
		(width 0.13208)
		(layer "B.Cu")
		(net "ADM1085_ENOUT")
	)
	(segment
		(start 229.62235 -176.938432)
		(end 230.015542 -176.54524)
		(width 0.13208)
		(layer "B.Cu")
		(net "ADM1085_ENOUT")
	)
	(segment
		(start 227.071936 -176.80305)
		(end 227.765864 -176.80305)
		(width 0.13208)
		(layer "B.Cu")
		(net "ADM1085_ENOUT")
	)
	(segment
		(start 227.765864 -176.80305)
		(end 227.901246 -176.938432)
		(width 0.13208)
		(layer "B.Cu")
		(net "ADM1085_ENOUT")
	)
	(segment
		(start 230.015542 -176.54524)
		(end 230.015542 -175.937926)
		(width 0.13208)
		(layer "B.Cu")
		(net "ADM1085_ENOUT")
	)
	(segment
		(start 366.218724 -150.71344)
		(end 366.218724 -150.903432)
		(width 0.13208)
		(layer "F.Cu")
		(net "SMB_NIC6_ADC_SDA")
	)
	(segment
		(start 365.054896 -151.0919)
		(end 364.475776 -151.67102)
		(width 0.13208)
		(layer "F.Cu")
		(net "SMB_NIC6_ADC_SDA")
	)
	(segment
		(start 366.218724 -150.903432)
		(end 366.030256 -151.0919)
		(width 0.13208)
		(layer "F.Cu")
		(net "SMB_NIC6_ADC_SDA")
	)
	(segment
		(start 366.030256 -151.0919)
		(end 365.054896 -151.0919)
		(width 0.13208)
		(layer "F.Cu")
		(net "SMB_NIC6_ADC_SDA")
	)
	(segment
		(start 364.475776 -151.67102)
		(end 364.475776 -152.3111)
		(width 0.13208)
		(layer "F.Cu")
		(net "SMB_NIC6_ADC_SDA")
	)
	(via
		(at 364.475776 -151.67102)
		(size 0.508)
		(drill 0.254)
		(layers "F.Cu" "B.Cu")
		(net "SMB_NIC6_ADC_SDA")
	)
	(segment
		(start 365.478822 -152.674066)
		(end 364.475776 -151.67102)
		(width 0.13208)
		(layer "B.Cu")
		(net "SMB_NIC6_ADC_SDA")
	)
	(segment
		(start 366.257332 -152.674066)
		(end 365.478822 -152.674066)
		(width 0.13208)
		(layer "B.Cu")
		(net "SMB_NIC6_ADC_SDA")
	)
	(segment
		(start 335.693766 -220.78696)
		(end 335.29397 -221.186756)
		(width 0.13208)
		(layer "F.Cu")
		(net "SSD14_PWRDIS_BIC_R")
	)
	(via
		(at 235.871512 -233.182668)
		(size 0.508)
		(drill 0.254)
		(layers "F.Cu" "B.Cu")
		(net "SSD14_PWRDIS_BIC_R")
	)
	(via
		(at 335.29397 -221.186756)
		(size 0.4572)
		(drill 0.254)
		(layers "F.Cu" "B.Cu")
		(net "SSD14_PWRDIS_BIC_R")
	)
	(via
		(at 255.162558 -216.834466)
		(size 0.508)
		(drill 0.254)
		(layers "F.Cu" "B.Cu")
		(net "SSD14_PWRDIS_BIC_R")
	)
	(segment
		(start 235.871512 -233.182668)
		(end 235.397548 -232.708704)
		(width 0.13208)
		(layer "B.Cu")
		(net "SSD14_PWRDIS_BIC_R")
	)
	(segment
		(start 235.397548 -231.758744)
		(end 235.530644 -231.625648)
		(width 0.13208)
		(layer "B.Cu")
		(net "SSD14_PWRDIS_BIC_R")
	)
	(segment
		(start 235.871512 -234.327954)
		(end 235.871512 -233.182668)
		(width 0.13208)
		(layer "B.Cu")
		(net "SSD14_PWRDIS_BIC_R")
	)
	(segment
		(start 235.397548 -232.708704)
		(end 235.397548 -231.758744)
		(width 0.13208)
		(layer "B.Cu")
		(net "SSD14_PWRDIS_BIC_R")
	)
	(segment
		(start 248.615708 -228.839776)
		(end 248.601484 -228.854)
		(width 0.15494)
		(layer "In7.Cu")
		(net "SSD14_PWRDIS_BIC_R")
	)
	(segment
		(start 247.988074 -228.854)
		(end 244.254274 -232.5878)
		(width 0.15494)
		(layer "In7.Cu")
		(net "SSD14_PWRDIS_BIC_R")
	)
	(segment
		(start 248.601484 -228.854)
		(end 247.988074 -228.854)
		(width 0.15494)
		(layer "In7.Cu")
		(net "SSD14_PWRDIS_BIC_R")
	)
	(segment
		(start 252.0442 -225.577146)
		(end 252.0442 -226.466146)
		(width 0.15494)
		(layer "In7.Cu")
		(net "SSD14_PWRDIS_BIC_R")
	)
	(segment
		(start 250.340876 -227.50907)
		(end 250.340876 -228.772466)
		(width 0.15494)
		(layer "In7.Cu")
		(net "SSD14_PWRDIS_BIC_R")
	)
	(segment
		(start 250.340876 -228.772466)
		(end 249.870214 -229.243128)
		(width 0.15494)
		(layer "In7.Cu")
		(net "SSD14_PWRDIS_BIC_R")
	)
	(segment
		(start 236.713522 -234.024678)
		(end 235.871512 -233.182668)
		(width 0.15494)
		(layer "In7.Cu")
		(net "SSD14_PWRDIS_BIC_R")
	)
	(segment
		(start 249.870214 -229.243128)
		(end 249.42038 -229.243128)
		(width 0.15494)
		(layer "In7.Cu")
		(net "SSD14_PWRDIS_BIC_R")
	)
	(segment
		(start 254.4318 -223.189546)
		(end 252.0442 -225.577146)
		(width 0.15494)
		(layer "In7.Cu")
		(net "SSD14_PWRDIS_BIC_R")
	)
	(segment
		(start 244.254274 -232.5878)
		(end 243.687346 -232.5878)
		(width 0.15494)
		(layer "In7.Cu")
		(net "SSD14_PWRDIS_BIC_R")
	)
	(segment
		(start 249.017028 -228.839776)
		(end 248.615708 -228.839776)
		(width 0.15494)
		(layer "In7.Cu")
		(net "SSD14_PWRDIS_BIC_R")
	)
	(segment
		(start 252.0442 -226.466146)
		(end 251.671582 -226.838764)
		(width 0.15494)
		(layer "In7.Cu")
		(net "SSD14_PWRDIS_BIC_R")
	)
	(segment
		(start 255.162558 -220.147388)
		(end 254.4318 -220.878146)
		(width 0.15494)
		(layer "In7.Cu")
		(net "SSD14_PWRDIS_BIC_R")
	)
	(segment
		(start 255.162558 -216.834466)
		(end 255.162558 -220.147388)
		(width 0.15494)
		(layer "In7.Cu")
		(net "SSD14_PWRDIS_BIC_R")
	)
	(segment
		(start 251.671582 -226.838764)
		(end 251.011182 -226.838764)
		(width 0.15494)
		(layer "In7.Cu")
		(net "SSD14_PWRDIS_BIC_R")
	)
	(segment
		(start 243.687346 -232.5878)
		(end 242.250468 -234.024678)
		(width 0.15494)
		(layer "In7.Cu")
		(net "SSD14_PWRDIS_BIC_R")
	)
	(segment
		(start 254.4318 -220.878146)
		(end 254.4318 -223.189546)
		(width 0.15494)
		(layer "In7.Cu")
		(net "SSD14_PWRDIS_BIC_R")
	)
	(segment
		(start 251.011182 -226.838764)
		(end 250.340876 -227.50907)
		(width 0.15494)
		(layer "In7.Cu")
		(net "SSD14_PWRDIS_BIC_R")
	)
	(segment
		(start 242.250468 -234.024678)
		(end 236.713522 -234.024678)
		(width 0.15494)
		(layer "In7.Cu")
		(net "SSD14_PWRDIS_BIC_R")
	)
	(segment
		(start 249.42038 -229.243128)
		(end 249.017028 -228.839776)
		(width 0.15494)
		(layer "In7.Cu")
		(net "SSD14_PWRDIS_BIC_R")
	)
	(segment
		(start 329.56119 -219.997782)
		(end 331.203808 -221.6404)
		(width 0.15494)
		(layer "In15.Cu")
		(net "SSD14_PWRDIS_BIC_R")
	)
	(segment
		(start 259.74294 -217.932)
		(end 260.833616 -219.022676)
		(width 0.15494)
		(layer "In15.Cu")
		(net "SSD14_PWRDIS_BIC_R")
	)
	(segment
		(start 333.136494 -221.6404)
		(end 333.590138 -221.186756)
		(width 0.15494)
		(layer "In15.Cu")
		(net "SSD14_PWRDIS_BIC_R")
	)
	(segment
		(start 321.460876 -219.538296)
		(end 324.031356 -219.538296)
		(width 0.15494)
		(layer "In15.Cu")
		(net "SSD14_PWRDIS_BIC_R")
	)
	(segment
		(start 289.514788 -219.82684)
		(end 305.632104 -219.82684)
		(width 0.15494)
		(layer "In15.Cu")
		(net "SSD14_PWRDIS_BIC_R")
	)
	(segment
		(start 264.21588 -219.990416)
		(end 264.531094 -220.30563)
		(width 0.15494)
		(layer "In15.Cu")
		(net "SSD14_PWRDIS_BIC_R")
	)
	(segment
		(start 289.035998 -220.30563)
		(end 289.514788 -219.82684)
		(width 0.15494)
		(layer "In15.Cu")
		(net "SSD14_PWRDIS_BIC_R")
	)
	(segment
		(start 331.203808 -221.6404)
		(end 333.136494 -221.6404)
		(width 0.15494)
		(layer "In15.Cu")
		(net "SSD14_PWRDIS_BIC_R")
	)
	(segment
		(start 326.00519 -220.88602)
		(end 326.958452 -220.88602)
		(width 0.15494)
		(layer "In15.Cu")
		(net "SSD14_PWRDIS_BIC_R")
	)
	(segment
		(start 333.590138 -221.186756)
		(end 335.29397 -221.186756)
		(width 0.15494)
		(layer "In15.Cu")
		(net "SSD14_PWRDIS_BIC_R")
	)
	(segment
		(start 262.101076 -219.022676)
		(end 263.068816 -219.990416)
		(width 0.15494)
		(layer "In15.Cu")
		(net "SSD14_PWRDIS_BIC_R")
	)
	(segment
		(start 324.685914 -220.192854)
		(end 325.312024 -220.192854)
		(width 0.15494)
		(layer "In15.Cu")
		(net "SSD14_PWRDIS_BIC_R")
	)
	(segment
		(start 320.237866 -218.315286)
		(end 321.460876 -219.538296)
		(width 0.15494)
		(layer "In15.Cu")
		(net "SSD14_PWRDIS_BIC_R")
	)
	(segment
		(start 307.143658 -218.315286)
		(end 320.237866 -218.315286)
		(width 0.15494)
		(layer "In15.Cu")
		(net "SSD14_PWRDIS_BIC_R")
	)
	(segment
		(start 305.632104 -219.82684)
		(end 307.143658 -218.315286)
		(width 0.15494)
		(layer "In15.Cu")
		(net "SSD14_PWRDIS_BIC_R")
	)
	(segment
		(start 256.260092 -217.932)
		(end 259.74294 -217.932)
		(width 0.15494)
		(layer "In15.Cu")
		(net "SSD14_PWRDIS_BIC_R")
	)
	(segment
		(start 263.068816 -219.990416)
		(end 264.21588 -219.990416)
		(width 0.15494)
		(layer "In15.Cu")
		(net "SSD14_PWRDIS_BIC_R")
	)
	(segment
		(start 327.84669 -219.997782)
		(end 329.56119 -219.997782)
		(width 0.15494)
		(layer "In15.Cu")
		(net "SSD14_PWRDIS_BIC_R")
	)
	(segment
		(start 255.162558 -216.834466)
		(end 256.260092 -217.932)
		(width 0.15494)
		(layer "In15.Cu")
		(net "SSD14_PWRDIS_BIC_R")
	)
	(segment
		(start 326.958452 -220.88602)
		(end 327.84669 -219.997782)
		(width 0.15494)
		(layer "In15.Cu")
		(net "SSD14_PWRDIS_BIC_R")
	)
	(segment
		(start 324.031356 -219.538296)
		(end 324.685914 -220.192854)
		(width 0.15494)
		(layer "In15.Cu")
		(net "SSD14_PWRDIS_BIC_R")
	)
	(segment
		(start 264.531094 -220.30563)
		(end 289.035998 -220.30563)
		(width 0.15494)
		(layer "In15.Cu")
		(net "SSD14_PWRDIS_BIC_R")
	)
	(segment
		(start 325.312024 -220.192854)
		(end 326.00519 -220.88602)
		(width 0.15494)
		(layer "In15.Cu")
		(net "SSD14_PWRDIS_BIC_R")
	)
	(segment
		(start 260.833616 -219.022676)
		(end 262.101076 -219.022676)
		(width 0.15494)
		(layer "In15.Cu")
		(net "SSD14_PWRDIS_BIC_R")
	)
	(segment
		(start 223.27997 -148.038312)
		(end 221.651322 -148.038312)
		(width 0.13208)
		(layer "F.Cu")
		(net "FM_CK440_PEX_MXCK_25M_100M")
	)
	(segment
		(start 224.257616 -147.640294)
		(end 225.47199 -147.640294)
		(width 0.0889)
		(layer "F.Cu")
		(net "FM_CK440_PEX_MXCK_25M_100M")
	)
	(segment
		(start 221.651322 -149.054312)
		(end 221.651322 -148.038312)
		(width 0.13208)
		(layer "F.Cu")
		(net "FM_CK440_PEX_MXCK_25M_100M")
	)
	(segment
		(start 223.27997 -148.038312)
		(end 223.677988 -147.640294)
		(width 0.13208)
		(layer "F.Cu")
		(net "FM_CK440_PEX_MXCK_25M_100M")
	)
	(segment
		(start 223.677988 -147.640294)
		(end 224.257616 -147.640294)
		(width 0.13208)
		(layer "F.Cu")
		(net "FM_CK440_PEX_MXCK_25M_100M")
	)
	(via
		(at 223.27997 -148.038312)
		(size 0.762)
		(drill 0.381)
		(layers "F.Cu" "B.Cu")
		(net "FM_CK440_PEX_MXCK_25M_100M")
	)
	(segment
		(start 337.362038 -145.923)
		(end 337.068922 -145.629884)
		(width 0.13208)
		(layer "F.Cu")
		(net "RST_PEX_SSD14_PERST_R_N")
	)
	(segment
		(start 336.775806 -145.923)
		(end 336.44205 -145.923)
		(width 0.13208)
		(layer "F.Cu")
		(net "RST_PEX_SSD14_PERST_R_N")
	)
	(segment
		(start 337.67395 -145.923)
		(end 337.362038 -145.923)
		(width 0.13208)
		(layer "F.Cu")
		(net "RST_PEX_SSD14_PERST_R_N")
	)
	(segment
		(start 337.068922 -145.629884)
		(end 336.775806 -145.923)
		(width 0.13208)
		(layer "F.Cu")
		(net "RST_PEX_SSD14_PERST_R_N")
	)
	(segment
		(start 336.493866 -220.78696)
		(end 336.09407 -221.186756)
		(width 0.13208)
		(layer "F.Cu")
		(net "RST_PEX_SSD14_PERST_R_N")
	)
	(via
		(at 336.09407 -221.186756)
		(size 0.4572)
		(drill 0.254)
		(layers "F.Cu" "B.Cu")
		(net "RST_PEX_SSD14_PERST_R_N")
	)
	(via
		(at 337.068922 -145.629884)
		(size 0.508)
		(drill 0.254)
		(layers "F.Cu" "B.Cu")
		(net "RST_PEX_SSD14_PERST_R_N")
	)
	(segment
		(start 330.081636 -169.162476)
		(end 328.64171 -167.72255)
		(width 0.15494)
		(layer "In7.Cu")
		(net "RST_PEX_SSD14_PERST_R_N")
	)
	(segment
		(start 325.72833 -206.826612)
		(end 325.72833 -202.861164)
		(width 0.15494)
		(layer "In7.Cu")
		(net "RST_PEX_SSD14_PERST_R_N")
	)
	(segment
		(start 330.088748 -193.270124)
		(end 330.081636 -193.263012)
		(width 0.15494)
		(layer "In7.Cu")
		(net "RST_PEX_SSD14_PERST_R_N")
	)
	(segment
		(start 330.081636 -193.263012)
		(end 330.081636 -169.162476)
		(width 0.15494)
		(layer "In7.Cu")
		(net "RST_PEX_SSD14_PERST_R_N")
	)
	(segment
		(start 328.64171 -153.19629)
		(end 334.388714 -147.449286)
		(width 0.15494)
		(layer "In7.Cu")
		(net "RST_PEX_SSD14_PERST_R_N")
	)
	(segment
		(start 337.6168 -147.193)
		(end 337.6168 -146.177762)
		(width 0.15494)
		(layer "In7.Cu")
		(net "RST_PEX_SSD14_PERST_R_N")
	)
	(segment
		(start 334.771746 -220.9546)
		(end 334.1116 -220.9546)
		(width 0.15494)
		(layer "In7.Cu")
		(net "RST_PEX_SSD14_PERST_R_N")
	)
	(segment
		(start 330.088748 -198.500746)
		(end 330.088748 -193.270124)
		(width 0.15494)
		(layer "In7.Cu")
		(net "RST_PEX_SSD14_PERST_R_N")
	)
	(segment
		(start 334.388714 -147.449286)
		(end 337.360514 -147.449286)
		(width 0.15494)
		(layer "In7.Cu")
		(net "RST_PEX_SSD14_PERST_R_N")
	)
	(segment
		(start 326.165972 -209.258916)
		(end 326.165972 -208.741518)
		(width 0.15494)
		(layer "In7.Cu")
		(net "RST_PEX_SSD14_PERST_R_N")
	)
	(segment
		(start 325.72833 -202.861164)
		(end 330.088748 -198.500746)
		(width 0.15494)
		(layer "In7.Cu")
		(net "RST_PEX_SSD14_PERST_R_N")
	)
	(segment
		(start 326.165972 -208.741518)
		(end 325.929498 -208.505044)
		(width 0.15494)
		(layer "In7.Cu")
		(net "RST_PEX_SSD14_PERST_R_N")
	)
	(segment
		(start 326.009 -209.415888)
		(end 326.165972 -209.258916)
		(width 0.15494)
		(layer "In7.Cu")
		(net "RST_PEX_SSD14_PERST_R_N")
	)
	(segment
		(start 326.212708 -207.66913)
		(end 326.212708 -207.31099)
		(width 0.15494)
		(layer "In7.Cu")
		(net "RST_PEX_SSD14_PERST_R_N")
	)
	(segment
		(start 325.929498 -208.505044)
		(end 325.929498 -207.95234)
		(width 0.15494)
		(layer "In7.Cu")
		(net "RST_PEX_SSD14_PERST_R_N")
	)
	(segment
		(start 334.93964 -220.786706)
		(end 334.771746 -220.9546)
		(width 0.15494)
		(layer "In7.Cu")
		(net "RST_PEX_SSD14_PERST_R_N")
	)
	(segment
		(start 327.46315 -213.595204)
		(end 327.0504 -213.182454)
		(width 0.15494)
		(layer "In7.Cu")
		(net "RST_PEX_SSD14_PERST_R_N")
	)
	(segment
		(start 325.929498 -207.95234)
		(end 326.212708 -207.66913)
		(width 0.15494)
		(layer "In7.Cu")
		(net "RST_PEX_SSD14_PERST_R_N")
	)
	(segment
		(start 337.6168 -146.177762)
		(end 337.068922 -145.629884)
		(width 0.15494)
		(layer "In7.Cu")
		(net "RST_PEX_SSD14_PERST_R_N")
	)
	(segment
		(start 326.212708 -207.31099)
		(end 325.72833 -206.826612)
		(width 0.15494)
		(layer "In7.Cu")
		(net "RST_PEX_SSD14_PERST_R_N")
	)
	(segment
		(start 336.09407 -221.186756)
		(end 335.69402 -220.786706)
		(width 0.0889)
		(layer "In7.Cu")
		(net "RST_PEX_SSD14_PERST_R_N")
	)
	(segment
		(start 332.193646 -221.757748)
		(end 327.46315 -217.027252)
		(width 0.15494)
		(layer "In7.Cu")
		(net "RST_PEX_SSD14_PERST_R_N")
	)
	(segment
		(start 327.46315 -217.027252)
		(end 327.46315 -213.595204)
		(width 0.15494)
		(layer "In7.Cu")
		(net "RST_PEX_SSD14_PERST_R_N")
	)
	(segment
		(start 335.69402 -220.786706)
		(end 334.93964 -220.786706)
		(width 0.0889)
		(layer "In7.Cu")
		(net "RST_PEX_SSD14_PERST_R_N")
	)
	(segment
		(start 327.0504 -213.182454)
		(end 327.0504 -211.7344)
		(width 0.15494)
		(layer "In7.Cu")
		(net "RST_PEX_SSD14_PERST_R_N")
	)
	(segment
		(start 333.308452 -221.757748)
		(end 332.193646 -221.757748)
		(width 0.15494)
		(layer "In7.Cu")
		(net "RST_PEX_SSD14_PERST_R_N")
	)
	(segment
		(start 328.64171 -167.72255)
		(end 328.64171 -153.19629)
		(width 0.15494)
		(layer "In7.Cu")
		(net "RST_PEX_SSD14_PERST_R_N")
	)
	(segment
		(start 327.0504 -211.7344)
		(end 326.009 -210.693)
		(width 0.15494)
		(layer "In7.Cu")
		(net "RST_PEX_SSD14_PERST_R_N")
	)
	(segment
		(start 337.360514 -147.449286)
		(end 337.6168 -147.193)
		(width 0.15494)
		(layer "In7.Cu")
		(net "RST_PEX_SSD14_PERST_R_N")
	)
	(segment
		(start 334.1116 -220.9546)
		(end 333.308452 -221.757748)
		(width 0.15494)
		(layer "In7.Cu")
		(net "RST_PEX_SSD14_PERST_R_N")
	)
	(segment
		(start 326.009 -210.693)
		(end 326.009 -209.415888)
		(width 0.15494)
		(layer "In7.Cu")
		(net "RST_PEX_SSD14_PERST_R_N")
	)
	(segment
		(start 223.380046 -144.491202)
		(end 222.831406 -143.942562)
		(width 0.13208)
		(layer "F.Cu")
		(net "PD_CK440_PEX_SBI_CLK")
	)
	(segment
		(start 224.721928 -144.89049)
		(end 224.4852 -144.89049)
		(width 0.13208)
		(layer "F.Cu")
		(net "PD_CK440_PEX_SBI_CLK")
	)
	(segment
		(start 224.085912 -144.491202)
		(end 223.380046 -144.491202)
		(width 0.13208)
		(layer "F.Cu")
		(net "PD_CK440_PEX_SBI_CLK")
	)
	(segment
		(start 224.4852 -144.89049)
		(end 224.085912 -144.491202)
		(width 0.13208)
		(layer "F.Cu")
		(net "PD_CK440_PEX_SBI_CLK")
	)
	(segment
		(start 222.831406 -143.942562)
		(end 221.651322 -143.942562)
		(width 0.13208)
		(layer "F.Cu")
		(net "PD_CK440_PEX_SBI_CLK")
	)
	(via
		(at 223.380046 -144.491202)
		(size 0.762)
		(drill 0.381)
		(layers "F.Cu" "B.Cu")
		(net "PD_CK440_PEX_SBI_CLK")
	)
	(segment
		(start 340.881462 -170.266106)
		(end 343.149936 -170.266106)
		(width 0.13208)
		(layer "F.Cu")
		(net "SSD10_PEX_PWR_EN")
	)
	(segment
		(start 338.47405 -170.053)
		(end 340.359746 -170.053)
		(width 0.13208)
		(layer "F.Cu")
		(net "SSD10_PEX_PWR_EN")
	)
	(segment
		(start 340.572852 -170.266106)
		(end 340.881462 -170.266106)
		(width 0.13208)
		(layer "F.Cu")
		(net "SSD10_PEX_PWR_EN")
	)
	(segment
		(start 340.359746 -170.053)
		(end 340.572852 -170.266106)
		(width 0.13208)
		(layer "F.Cu")
		(net "SSD10_PEX_PWR_EN")
	)
	(via
		(at 340.881462 -170.266106)
		(size 0.508)
		(drill 0.254)
		(layers "F.Cu" "B.Cu")
		(net "SSD10_PEX_PWR_EN")
	)
	(segment
		(start 203.327 -300.7614)
		(end 203.5683 -301.0027)
		(width 0.13208)
		(layer "F.Cu")
		(net "RST_PEX1_S1_PERST_R_N")
	)
	(segment
		(start 188.574934 -305.874928)
		(end 189.049914 -306.349908)
		(width 0.13208)
		(layer "F.Cu")
		(net "RST_PEX1_S1_PERST_R_N")
	)
	(segment
		(start 203.077826 -298.69765)
		(end 203.327 -298.946824)
		(width 0.13208)
		(layer "F.Cu")
		(net "RST_PEX1_S1_PERST_R_N")
	)
	(segment
		(start 202.95108 -298.69765)
		(end 203.077826 -298.69765)
		(width 0.13208)
		(layer "F.Cu")
		(net "RST_PEX1_S1_PERST_R_N")
	)
	(segment
		(start 203.5683 -301.0027)
		(end 203.849732 -301.0027)
		(width 0.13208)
		(layer "F.Cu")
		(net "RST_PEX1_S1_PERST_R_N")
	)
	(segment
		(start 203.327 -298.946824)
		(end 203.327 -300.7614)
		(width 0.13208)
		(layer "F.Cu")
		(net "RST_PEX1_S1_PERST_R_N")
	)
	(via
		(at 188.574934 -305.874928)
		(size 0.4064)
		(drill 0.2032)
		(layers "F.Cu" "B.Cu")
		(net "RST_PEX1_S1_PERST_R_N")
	)
	(via
		(at 202.95108 -298.69765)
		(size 0.508)
		(drill 0.254)
		(layers "F.Cu" "B.Cu")
		(net "RST_PEX1_S1_PERST_R_N")
	)
	(segment
		(start 188.06922 -305.11496)
		(end 188.06922 -298.97451)
		(width 0.15494)
		(layer "In5.Cu")
		(net "RST_PEX1_S1_PERST_R_N")
	)
	(segment
		(start 190.96228 -298.076112)
		(end 191.277748 -297.760644)
		(width 0.15494)
		(layer "In5.Cu")
		(net "RST_PEX1_S1_PERST_R_N")
	)
	(segment
		(start 201.568812 -298.8056)
		(end 201.808334 -298.566078)
		(width 0.15494)
		(layer "In5.Cu")
		(net "RST_PEX1_S1_PERST_R_N")
	)
	(segment
		(start 188.06922 -298.97451)
		(end 188.289946 -298.753784)
		(width 0.15494)
		(layer "In5.Cu")
		(net "RST_PEX1_S1_PERST_R_N")
	)
	(segment
		(start 188.289946 -298.753784)
		(end 190.77305 -298.753784)
		(width 0.15494)
		(layer "In5.Cu")
		(net "RST_PEX1_S1_PERST_R_N")
	)
	(segment
		(start 188.574934 -305.620674)
		(end 188.06922 -305.11496)
		(width 0.15494)
		(layer "In5.Cu")
		(net "RST_PEX1_S1_PERST_R_N")
	)
	(segment
		(start 191.277748 -297.760644)
		(end 199.220074 -297.760644)
		(width 0.15494)
		(layer "In5.Cu")
		(net "RST_PEX1_S1_PERST_R_N")
	)
	(segment
		(start 199.40905 -297.94962)
		(end 199.40905 -298.43095)
		(width 0.15494)
		(layer "In5.Cu")
		(net "RST_PEX1_S1_PERST_R_N")
	)
	(segment
		(start 188.574934 -305.874928)
		(end 188.574934 -305.620674)
		(width 0.15494)
		(layer "In5.Cu")
		(net "RST_PEX1_S1_PERST_R_N")
	)
	(segment
		(start 190.77305 -298.753784)
		(end 190.96228 -298.564554)
		(width 0.15494)
		(layer "In5.Cu")
		(net "RST_PEX1_S1_PERST_R_N")
	)
	(segment
		(start 202.819508 -298.566078)
		(end 202.95108 -298.69765)
		(width 0.15494)
		(layer "In5.Cu")
		(net "RST_PEX1_S1_PERST_R_N")
	)
	(segment
		(start 201.808334 -298.566078)
		(end 202.819508 -298.566078)
		(width 0.15494)
		(layer "In5.Cu")
		(net "RST_PEX1_S1_PERST_R_N")
	)
	(segment
		(start 199.220074 -297.760644)
		(end 199.40905 -297.94962)
		(width 0.15494)
		(layer "In5.Cu")
		(net "RST_PEX1_S1_PERST_R_N")
	)
	(segment
		(start 190.96228 -298.564554)
		(end 190.96228 -298.076112)
		(width 0.15494)
		(layer "In5.Cu")
		(net "RST_PEX1_S1_PERST_R_N")
	)
	(segment
		(start 199.7837 -298.8056)
		(end 201.568812 -298.8056)
		(width 0.15494)
		(layer "In5.Cu")
		(net "RST_PEX1_S1_PERST_R_N")
	)
	(segment
		(start 199.40905 -298.43095)
		(end 199.7837 -298.8056)
		(width 0.15494)
		(layer "In5.Cu")
		(net "RST_PEX1_S1_PERST_R_N")
	)
	(segment
		(start 224.507552 -172.6184)
		(end 225.727514 -173.838362)
		(width 0.13208)
		(layer "F.Cu")
		(net "ADM1085_CEXT")
	)
	(segment
		(start 224.765362 -176.956212)
		(end 225.882962 -176.956212)
		(width 0.13208)
		(layer "F.Cu")
		(net "ADM1085_CEXT")
	)
	(segment
		(start 222.093028 -173.666912)
		(end 222.475298 -173.284642)
		(width 0.13208)
		(layer "F.Cu")
		(net "ADM1085_CEXT")
	)
	(segment
		(start 222.093028 -177.840386)
		(end 222.093028 -173.666912)
		(width 0.13208)
		(layer "F.Cu")
		(net "ADM1085_CEXT")
	)
	(segment
		(start 224.731072 -176.956212)
		(end 224.765362 -176.956212)
		(width 0.13208)
		(layer "F.Cu")
		(net "ADM1085_CEXT")
	)
	(segment
		(start 223.986344 -176.52238)
		(end 223.986344 -177.53838)
		(width 0.13208)
		(layer "F.Cu")
		(net "ADM1085_CEXT")
	)
	(segment
		(start 223.14154 -172.6184)
		(end 224.507552 -172.6184)
		(width 0.13208)
		(layer "F.Cu")
		(net "ADM1085_CEXT")
	)
	(segment
		(start 222.475298 -173.284642)
		(end 223.14154 -172.6184)
		(width 0.13208)
		(layer "F.Cu")
		(net "ADM1085_CEXT")
	)
	(segment
		(start 223.588072 -178.278282)
		(end 222.530924 -178.278282)
		(width 0.13208)
		(layer "F.Cu")
		(net "ADM1085_CEXT")
	)
	(segment
		(start 223.986344 -176.52238)
		(end 224.29724 -176.52238)
		(width 0.13208)
		(layer "F.Cu")
		(net "ADM1085_CEXT")
	)
	(segment
		(start 223.986344 -177.53838)
		(end 223.986344 -177.88001)
		(width 0.13208)
		(layer "F.Cu")
		(net "ADM1085_CEXT")
	)
	(segment
		(start 222.530924 -178.278282)
		(end 222.093028 -177.840386)
		(width 0.13208)
		(layer "F.Cu")
		(net "ADM1085_CEXT")
	)
	(segment
		(start 224.29724 -176.52238)
		(end 224.731072 -176.956212)
		(width 0.13208)
		(layer "F.Cu")
		(net "ADM1085_CEXT")
	)
	(segment
		(start 223.986344 -177.88001)
		(end 223.588072 -178.278282)
		(width 0.13208)
		(layer "F.Cu")
		(net "ADM1085_CEXT")
	)
	(via
		(at 222.475298 -173.284642)
		(size 0.762)
		(drill 0.381)
		(layers "F.Cu" "B.Cu")
		(net "ADM1085_CEXT")
	)
	(via
		(at 224.765362 -176.956212)
		(size 0.508)
		(drill 0.254)
		(layers "F.Cu" "B.Cu")
		(net "ADM1085_CEXT")
	)
	(segment
		(start 224.525586 -175.833278)
		(end 225.256598 -175.833278)
		(width 0.13208)
		(layer "B.Cu")
		(net "ADM1085_CEXT")
	)
	(segment
		(start 224.433638 -176.956212)
		(end 224.28073 -176.803304)
		(width 0.13208)
		(layer "B.Cu")
		(net "ADM1085_CEXT")
	)
	(segment
		(start 224.28073 -176.803304)
		(end 224.28073 -176.078134)
		(width 0.13208)
		(layer "B.Cu")
		(net "ADM1085_CEXT")
	)
	(segment
		(start 224.28073 -176.078134)
		(end 224.525586 -175.833278)
		(width 0.13208)
		(layer "B.Cu")
		(net "ADM1085_CEXT")
	)
	(segment
		(start 224.765362 -176.956212)
		(end 224.433638 -176.956212)
		(width 0.13208)
		(layer "B.Cu")
		(net "ADM1085_CEXT")
	)
	(segment
		(start 225.256598 -175.833278)
		(end 225.286824 -175.803052)
		(width 0.13208)
		(layer "B.Cu")
		(net "ADM1085_CEXT")
	)
	(segment
		(start 225.286824 -175.803052)
		(end 226.317048 -175.803052)
		(width 0.13208)
		(layer "B.Cu")
		(net "ADM1085_CEXT")
	)
	(segment
		(start 340.557866 -169.61612)
		(end 342.019382 -169.61612)
		(width 0.13208)
		(layer "F.Cu")
		(net "RST_PEX_SSD10_PERST_N")
	)
	(segment
		(start 342.019382 -169.61612)
		(end 343.149936 -169.61612)
		(width 0.13208)
		(layer "F.Cu")
		(net "RST_PEX_SSD10_PERST_N")
	)
	(segment
		(start 338.47405 -169.037)
		(end 338.79409 -169.35704)
		(width 0.13208)
		(layer "F.Cu")
		(net "RST_PEX_SSD10_PERST_N")
	)
	(segment
		(start 340.298786 -169.35704)
		(end 340.557866 -169.61612)
		(width 0.13208)
		(layer "F.Cu")
		(net "RST_PEX_SSD10_PERST_N")
	)
	(segment
		(start 338.79409 -169.35704)
		(end 340.298786 -169.35704)
		(width 0.13208)
		(layer "F.Cu")
		(net "RST_PEX_SSD10_PERST_N")
	)
	(via
		(at 342.019382 -169.61612)
		(size 0.508)
		(drill 0.254)
		(layers "F.Cu" "B.Cu")
		(net "RST_PEX_SSD10_PERST_N")
	)
	(segment
		(start 200.910698 -289.0774)
		(end 201.157332 -288.830766)
		(width 0.13208)
		(layer "F.Cu")
		(net "RST_PEX1_S0_PERST_R_N")
	)
	(segment
		(start 201.238358 -297.95851)
		(end 200.910698 -297.63085)
		(width 0.13208)
		(layer "F.Cu")
		(net "RST_PEX1_S0_PERST_R_N")
	)
	(segment
		(start 187.624974 -304.924714)
		(end 188.099954 -304.449734)
		(width 0.13208)
		(layer "F.Cu")
		(net "RST_PEX1_S0_PERST_R_N")
	)
	(segment
		(start 200.910698 -297.63085)
		(end 200.910698 -289.0774)
		(width 0.13208)
		(layer "F.Cu")
		(net "RST_PEX1_S0_PERST_R_N")
	)
	(segment
		(start 201.157332 -288.830766)
		(end 201.635868 -288.830766)
		(width 0.13208)
		(layer "F.Cu")
		(net "RST_PEX1_S0_PERST_R_N")
	)
	(via
		(at 187.624974 -304.924714)
		(size 0.4064)
		(drill 0.2032)
		(layers "F.Cu" "B.Cu")
		(net "RST_PEX1_S0_PERST_R_N")
	)
	(via
		(at 201.238358 -297.95851)
		(size 0.508)
		(drill 0.254)
		(layers "F.Cu" "B.Cu")
		(net "RST_PEX1_S0_PERST_R_N")
	)
	(segment
		(start 187.209938 -298.067984)
		(end 187.430664 -297.847258)
		(width 0.15494)
		(layer "In5.Cu")
		(net "RST_PEX1_S0_PERST_R_N")
	)
	(segment
		(start 200.40727 -297.95851)
		(end 201.238358 -297.95851)
		(width 0.15494)
		(layer "In5.Cu")
		(net "RST_PEX1_S0_PERST_R_N")
	)
	(segment
		(start 190.90386 -297.658028)
		(end 190.90386 -297.165268)
		(width 0.15494)
		(layer "In5.Cu")
		(net "RST_PEX1_S0_PERST_R_N")
	)
	(segment
		(start 187.430664 -297.847258)
		(end 190.71463 -297.847258)
		(width 0.15494)
		(layer "In5.Cu")
		(net "RST_PEX1_S0_PERST_R_N")
	)
	(segment
		(start 191.222884 -296.846244)
		(end 199.295004 -296.846244)
		(width 0.15494)
		(layer "In5.Cu")
		(net "RST_PEX1_S0_PERST_R_N")
	)
	(segment
		(start 187.209938 -304.509678)
		(end 187.209938 -298.067984)
		(width 0.15494)
		(layer "In5.Cu")
		(net "RST_PEX1_S0_PERST_R_N")
	)
	(segment
		(start 190.71463 -297.847258)
		(end 190.90386 -297.658028)
		(width 0.15494)
		(layer "In5.Cu")
		(net "RST_PEX1_S0_PERST_R_N")
	)
	(segment
		(start 199.295004 -296.846244)
		(end 200.40727 -297.95851)
		(width 0.15494)
		(layer "In5.Cu")
		(net "RST_PEX1_S0_PERST_R_N")
	)
	(segment
		(start 190.90386 -297.165268)
		(end 191.222884 -296.846244)
		(width 0.15494)
		(layer "In5.Cu")
		(net "RST_PEX1_S0_PERST_R_N")
	)
	(segment
		(start 187.624974 -304.924714)
		(end 187.209938 -304.509678)
		(width 0.15494)
		(layer "In5.Cu")
		(net "RST_PEX1_S0_PERST_R_N")
	)
	(segment
		(start 88.835992 -289.630866)
		(end 87.819992 -289.630866)
		(width 0.13208)
		(layer "F.Cu")
		(net "SMB_PEX0_HOST_LS_SDA")
	)
	(segment
		(start 90.02268 -294.016176)
		(end 90.314272 -293.724584)
		(width 0.13208)
		(layer "F.Cu")
		(net "SMB_PEX0_HOST_LS_SDA")
	)
	(segment
		(start 88.951054 -294.47109)
		(end 88.951054 -297.31716)
		(width 0.13208)
		(layer "F.Cu")
		(net "SMB_PEX0_HOST_LS_SDA")
	)
	(segment
		(start 88.951054 -297.31716)
		(end 89.098374 -297.46448)
		(width 0.13208)
		(layer "F.Cu")
		(net "SMB_PEX0_HOST_LS_SDA")
	)
	(segment
		(start 90.314272 -291.297868)
		(end 90.314272 -290.093146)
		(width 0.13208)
		(layer "F.Cu")
		(net "SMB_PEX0_HOST_LS_SDA")
	)
	(segment
		(start 88.835992 -289.630866)
		(end 89.851992 -289.630866)
		(width 0.13208)
		(layer "F.Cu")
		(net "SMB_PEX0_HOST_LS_SDA")
	)
	(segment
		(start 89.405968 -294.016176)
		(end 88.951054 -294.47109)
		(width 0.13208)
		(layer "F.Cu")
		(net "SMB_PEX0_HOST_LS_SDA")
	)
	(segment
		(start 90.314272 -290.093146)
		(end 89.851992 -289.630866)
		(width 0.13208)
		(layer "F.Cu")
		(net "SMB_PEX0_HOST_LS_SDA")
	)
	(segment
		(start 90.314272 -293.724584)
		(end 90.314272 -291.297868)
		(width 0.13208)
		(layer "F.Cu")
		(net "SMB_PEX0_HOST_LS_SDA")
	)
	(segment
		(start 90.02268 -294.016176)
		(end 89.405968 -294.016176)
		(width 0.13208)
		(layer "F.Cu")
		(net "SMB_PEX0_HOST_LS_SDA")
	)
	(via
		(at 90.02268 -294.016176)
		(size 0.508)
		(drill 0.254)
		(layers "F.Cu" "B.Cu")
		(net "SMB_PEX0_HOST_LS_SDA")
	)
	(segment
		(start 338.47405 -180.975)
		(end 338.79409 -181.29504)
		(width 0.13208)
		(layer "F.Cu")
		(net "RST_PEX_SSD8_PERST_N")
	)
	(segment
		(start 340.298786 -181.29504)
		(end 340.557866 -181.55412)
		(width 0.13208)
		(layer "F.Cu")
		(net "RST_PEX_SSD8_PERST_N")
	)
	(segment
		(start 342.019382 -181.55412)
		(end 343.149936 -181.55412)
		(width 0.13208)
		(layer "F.Cu")
		(net "RST_PEX_SSD8_PERST_N")
	)
	(segment
		(start 338.79409 -181.29504)
		(end 340.298786 -181.29504)
		(width 0.13208)
		(layer "F.Cu")
		(net "RST_PEX_SSD8_PERST_N")
	)
	(segment
		(start 340.557866 -181.55412)
		(end 342.019382 -181.55412)
		(width 0.13208)
		(layer "F.Cu")
		(net "RST_PEX_SSD8_PERST_N")
	)
	(via
		(at 342.019382 -181.55412)
		(size 0.508)
		(drill 0.254)
		(layers "F.Cu" "B.Cu")
		(net "RST_PEX_SSD8_PERST_N")
	)
	(segment
		(start 337.058 -146.939)
		(end 337.67395 -146.939)
		(width 0.13208)
		(layer "F.Cu")
		(net "SSD14_PEX_PWR_EN_R")
	)
	(segment
		(start 337.293966 -220.78696)
		(end 336.89417 -221.186756)
		(width 0.13208)
		(layer "F.Cu")
		(net "SSD14_PEX_PWR_EN_R")
	)
	(segment
		(start 336.44205 -147.955)
		(end 336.44205 -146.939)
		(width 0.13208)
		(layer "F.Cu")
		(net "SSD14_PEX_PWR_EN_R")
	)
	(segment
		(start 336.44205 -146.939)
		(end 337.058 -146.939)
		(width 0.13208)
		(layer "F.Cu")
		(net "SSD14_PEX_PWR_EN_R")
	)
	(via
		(at 337.058 -146.939)
		(size 0.508)
		(drill 0.254)
		(layers "F.Cu" "B.Cu")
		(net "SSD14_PEX_PWR_EN_R")
	)
	(via
		(at 336.89417 -221.186756)
		(size 0.4572)
		(drill 0.254)
		(layers "F.Cu" "B.Cu")
		(net "SSD14_PEX_PWR_EN_R")
	)
	(segment
		(start 328.18197 -167.91305)
		(end 328.18197 -152.36063)
		(width 0.15494)
		(layer "In7.Cu")
		(net "SSD14_PEX_PWR_EN_R")
	)
	(segment
		(start 334.018128 -221.58706)
		(end 333.366872 -222.238316)
		(width 0.15494)
		(layer "In7.Cu")
		(net "SSD14_PEX_PWR_EN_R")
	)
	(segment
		(start 336.89417 -221.186756)
		(end 336.493866 -221.58706)
		(width 0.0889)
		(layer "In7.Cu")
		(net "SSD14_PEX_PWR_EN_R")
	)
	(segment
		(start 329.621896 -169.352976)
		(end 328.18197 -167.91305)
		(width 0.15494)
		(layer "In7.Cu")
		(net "SSD14_PEX_PWR_EN_R")
	)
	(segment
		(start 325.9328 -212.725)
		(end 325.9328 -211.835746)
		(width 0.15494)
		(layer "In7.Cu")
		(net "SSD14_PEX_PWR_EN_R")
	)
	(segment
		(start 336.57413 -146.45513)
		(end 337.058 -146.939)
		(width 0.15494)
		(layer "In7.Cu")
		(net "SSD14_PEX_PWR_EN_R")
	)
	(segment
		(start 328.18197 -152.36063)
		(end 334.08747 -146.45513)
		(width 0.15494)
		(layer "In7.Cu")
		(net "SSD14_PEX_PWR_EN_R")
	)
	(segment
		(start 334.08747 -146.45513)
		(end 336.57413 -146.45513)
		(width 0.15494)
		(layer "In7.Cu")
		(net "SSD14_PEX_PWR_EN_R")
	)
	(segment
		(start 324.8406 -210.743546)
		(end 324.8406 -203.098654)
		(width 0.15494)
		(layer "In7.Cu")
		(net "SSD14_PEX_PWR_EN_R")
	)
	(segment
		(start 327.001632 -218.391232)
		(end 327.001632 -213.793832)
		(width 0.15494)
		(layer "In7.Cu")
		(net "SSD14_PEX_PWR_EN_R")
	)
	(segment
		(start 330.848716 -222.238316)
		(end 327.001632 -218.391232)
		(width 0.15494)
		(layer "In7.Cu")
		(net "SSD14_PEX_PWR_EN_R")
	)
	(segment
		(start 329.629008 -198.310246)
		(end 329.629008 -193.460624)
		(width 0.15494)
		(layer "In7.Cu")
		(net "SSD14_PEX_PWR_EN_R")
	)
	(segment
		(start 327.001632 -213.793832)
		(end 325.9328 -212.725)
		(width 0.15494)
		(layer "In7.Cu")
		(net "SSD14_PEX_PWR_EN_R")
	)
	(segment
		(start 336.493866 -221.58706)
		(end 334.89646 -221.58706)
		(width 0.0889)
		(layer "In7.Cu")
		(net "SSD14_PEX_PWR_EN_R")
	)
	(segment
		(start 329.629008 -193.460624)
		(end 329.621896 -193.453512)
		(width 0.15494)
		(layer "In7.Cu")
		(net "SSD14_PEX_PWR_EN_R")
	)
	(segment
		(start 324.8406 -203.098654)
		(end 329.629008 -198.310246)
		(width 0.15494)
		(layer "In7.Cu")
		(net "SSD14_PEX_PWR_EN_R")
	)
	(segment
		(start 333.366872 -222.238316)
		(end 330.848716 -222.238316)
		(width 0.15494)
		(layer "In7.Cu")
		(net "SSD14_PEX_PWR_EN_R")
	)
	(segment
		(start 325.9328 -211.835746)
		(end 324.8406 -210.743546)
		(width 0.15494)
		(layer "In7.Cu")
		(net "SSD14_PEX_PWR_EN_R")
	)
	(segment
		(start 334.89646 -221.58706)
		(end 334.018128 -221.58706)
		(width 0.15494)
		(layer "In7.Cu")
		(net "SSD14_PEX_PWR_EN_R")
	)
	(segment
		(start 329.621896 -193.453512)
		(end 329.621896 -169.352976)
		(width 0.15494)
		(layer "In7.Cu")
		(net "SSD14_PEX_PWR_EN_R")
	)
	(segment
		(start 222.745046 -145.140426)
		(end 223.980756 -145.140426)
		(width 0.13208)
		(layer "F.Cu")
		(net "PD_CK440_PEX_SBI_DATA_IN")
	)
	(segment
		(start 222.196406 -144.958562)
		(end 222.37827 -145.140426)
		(width 0.13208)
		(layer "F.Cu")
		(net "PD_CK440_PEX_SBI_DATA_IN")
	)
	(segment
		(start 221.651322 -144.958562)
		(end 222.196406 -144.958562)
		(width 0.13208)
		(layer "F.Cu")
		(net "PD_CK440_PEX_SBI_DATA_IN")
	)
	(segment
		(start 222.37827 -145.140426)
		(end 222.745046 -145.140426)
		(width 0.13208)
		(layer "F.Cu")
		(net "PD_CK440_PEX_SBI_DATA_IN")
	)
	(segment
		(start 223.980756 -145.140426)
		(end 225.47199 -145.140426)
		(width 0.0889)
		(layer "F.Cu")
		(net "PD_CK440_PEX_SBI_DATA_IN")
	)
	(via
		(at 222.745046 -145.140426)
		(size 0.508)
		(drill 0.254)
		(layers "F.Cu" "B.Cu")
		(net "PD_CK440_PEX_SBI_DATA_IN")
	)
	(segment
		(start 442.319918 -99.459288)
		(end 441.012072 -99.459288)
		(width 0.13208)
		(layer "F.Cu")
		(net "SMB_NIC7_ADC_SCL")
	)
	(segment
		(start 442.32068 -98.636328)
		(end 442.32068 -99.458526)
		(width 0.13208)
		(layer "F.Cu")
		(net "SMB_NIC7_ADC_SCL")
	)
	(segment
		(start 442.32068 -99.458526)
		(end 442.319918 -99.459288)
		(width 0.13208)
		(layer "F.Cu")
		(net "SMB_NIC7_ADC_SCL")
	)
	(segment
		(start 442.403484 -97.211642)
		(end 442.705998 -97.211642)
		(width 0.13208)
		(layer "F.Cu")
		(net "SMB_NIC7_ADC_SCL")
	)
	(segment
		(start 442.403484 -97.211642)
		(end 442.405262 -97.21342)
		(width 0.13208)
		(layer "F.Cu")
		(net "SMB_NIC7_ADC_SCL")
	)
	(segment
		(start 442.405262 -97.21342)
		(end 442.405262 -98.551746)
		(width 0.13208)
		(layer "F.Cu")
		(net "SMB_NIC7_ADC_SCL")
	)
	(segment
		(start 442.705998 -97.211642)
		(end 443.02172 -97.527364)
		(width 0.13208)
		(layer "F.Cu")
		(net "SMB_NIC7_ADC_SCL")
	)
	(segment
		(start 442.405262 -98.551746)
		(end 442.32068 -98.636328)
		(width 0.13208)
		(layer "F.Cu")
		(net "SMB_NIC7_ADC_SCL")
	)
	(via
		(at 444.723266 -137.65276)
		(size 0.508)
		(drill 0.254)
		(layers "F.Cu" "B.Cu")
		(net "SMB_NIC7_ADC_SCL")
	)
	(via
		(at 442.32068 -99.458526)
		(size 0.508)
		(drill 0.254)
		(layers "F.Cu" "B.Cu")
		(net "SMB_NIC7_ADC_SCL")
	)
	(via
		(at 443.02172 -97.527364)
		(size 0.508)
		(drill 0.254)
		(layers "F.Cu" "B.Cu")
		(net "SMB_NIC7_ADC_SCL")
	)
	(via
		(at 363.474 -150.114)
		(size 0.508)
		(drill 0.254)
		(layers "F.Cu" "B.Cu")
		(net "SMB_NIC7_ADC_SCL")
	)
	(segment
		(start 363.474 -150.114)
		(end 363.474 -150.988776)
		(width 0.13208)
		(layer "B.Cu")
		(net "SMB_NIC7_ADC_SCL")
	)
	(segment
		(start 363.474 -150.988776)
		(end 363.332776 -151.13)
		(width 0.13208)
		(layer "B.Cu")
		(net "SMB_NIC7_ADC_SCL")
	)
	(segment
		(start 363.332776 -151.13)
		(end 363.332776 -152.3111)
		(width 0.13208)
		(layer "B.Cu")
		(net "SMB_NIC7_ADC_SCL")
	)
	(segment
		(start 443.66688 -96.882204)
		(end 443.66688 -95.91421)
		(width 0.15494)
		(layer "In5.Cu")
		(net "SMB_NIC7_ADC_SCL")
	)
	(segment
		(start 444.435738 -137.65276)
		(end 444.723266 -137.65276)
		(width 0.15494)
		(layer "In5.Cu")
		(net "SMB_NIC7_ADC_SCL")
	)
	(segment
		(start 436.270654 -119.481346)
		(end 436.270654 -128.467866)
		(width 0.15494)
		(layer "In5.Cu")
		(net "SMB_NIC7_ADC_SCL")
	)
	(segment
		(start 441.305696 -93.553026)
		(end 437.039004 -93.553026)
		(width 0.15494)
		(layer "In5.Cu")
		(net "SMB_NIC7_ADC_SCL")
	)
	(segment
		(start 436.993284 -130.210306)
		(end 444.435738 -137.65276)
		(width 0.15494)
		(layer "In5.Cu")
		(net "SMB_NIC7_ADC_SCL")
	)
	(segment
		(start 429.915828 -108.284264)
		(end 433.76088 -112.129316)
		(width 0.15494)
		(layer "In5.Cu")
		(net "SMB_NIC7_ADC_SCL")
	)
	(segment
		(start 443.02172 -97.527364)
		(end 443.66688 -96.882204)
		(width 0.15494)
		(layer "In5.Cu")
		(net "SMB_NIC7_ADC_SCL")
	)
	(segment
		(start 429.915828 -100.676202)
		(end 429.915828 -108.284264)
		(width 0.15494)
		(layer "In5.Cu")
		(net "SMB_NIC7_ADC_SCL")
	)
	(segment
		(start 433.76088 -112.129316)
		(end 433.76088 -116.971572)
		(width 0.15494)
		(layer "In5.Cu")
		(net "SMB_NIC7_ADC_SCL")
	)
	(segment
		(start 443.66688 -95.91421)
		(end 441.305696 -93.553026)
		(width 0.15494)
		(layer "In5.Cu")
		(net "SMB_NIC7_ADC_SCL")
	)
	(segment
		(start 436.270654 -128.467866)
		(end 436.993284 -130.210306)
		(width 0.15494)
		(layer "In5.Cu")
		(net "SMB_NIC7_ADC_SCL")
	)
	(segment
		(start 437.039004 -93.553026)
		(end 429.915828 -100.676202)
		(width 0.15494)
		(layer "In5.Cu")
		(net "SMB_NIC7_ADC_SCL")
	)
	(segment
		(start 433.76088 -116.971572)
		(end 436.270654 -119.481346)
		(width 0.15494)
		(layer "In5.Cu")
		(net "SMB_NIC7_ADC_SCL")
	)
	(segment
		(start 394.39977 -134.715504)
		(end 398.012666 -138.3284)
		(width 0.15494)
		(layer "In13.Cu")
		(net "SMB_NIC7_ADC_SCL")
	)
	(segment
		(start 410.18079 -135.781796)
		(end 412.364428 -137.965434)
		(width 0.15494)
		(layer "In13.Cu")
		(net "SMB_NIC7_ADC_SCL")
	)
	(segment
		(start 383.533904 -139.741656)
		(end 384.076702 -139.198858)
		(width 0.15494)
		(layer "In13.Cu")
		(net "SMB_NIC7_ADC_SCL")
	)
	(segment
		(start 404.100284 -135.781796)
		(end 410.18079 -135.781796)
		(width 0.15494)
		(layer "In13.Cu")
		(net "SMB_NIC7_ADC_SCL")
	)
	(segment
		(start 412.364428 -137.965434)
		(end 425.724828 -137.965434)
		(width 0.15494)
		(layer "In13.Cu")
		(net "SMB_NIC7_ADC_SCL")
	)
	(segment
		(start 391.561574 -134.715504)
		(end 394.39977 -134.715504)
		(width 0.15494)
		(layer "In13.Cu")
		(net "SMB_NIC7_ADC_SCL")
	)
	(segment
		(start 401.55368 -138.3284)
		(end 404.100284 -135.781796)
		(width 0.15494)
		(layer "In13.Cu")
		(net "SMB_NIC7_ADC_SCL")
	)
	(segment
		(start 363.474 -150.114)
		(end 363.474 -151.765)
		(width 0.15494)
		(layer "In13.Cu")
		(net "SMB_NIC7_ADC_SCL")
	)
	(segment
		(start 386.838952 -138.0744)
		(end 388.202678 -138.0744)
		(width 0.15494)
		(layer "In13.Cu")
		(net "SMB_NIC7_ADC_SCL")
	)
	(segment
		(start 372.5418 -152.2476)
		(end 383.533904 -141.255496)
		(width 0.15494)
		(layer "In13.Cu")
		(net "SMB_NIC7_ADC_SCL")
	)
	(segment
		(start 428.043594 -140.2842)
		(end 431.876454 -140.2842)
		(width 0.15494)
		(layer "In13.Cu")
		(net "SMB_NIC7_ADC_SCL")
	)
	(segment
		(start 433.146454 -139.0142)
		(end 443.361826 -139.0142)
		(width 0.15494)
		(layer "In13.Cu")
		(net "SMB_NIC7_ADC_SCL")
	)
	(segment
		(start 384.076702 -139.198858)
		(end 385.714494 -139.198858)
		(width 0.15494)
		(layer "In13.Cu")
		(net "SMB_NIC7_ADC_SCL")
	)
	(segment
		(start 383.533904 -141.255496)
		(end 383.533904 -139.741656)
		(width 0.15494)
		(layer "In13.Cu")
		(net "SMB_NIC7_ADC_SCL")
	)
	(segment
		(start 363.9566 -152.2476)
		(end 372.5418 -152.2476)
		(width 0.15494)
		(layer "In13.Cu")
		(net "SMB_NIC7_ADC_SCL")
	)
	(segment
		(start 363.474 -151.765)
		(end 363.9566 -152.2476)
		(width 0.15494)
		(layer "In13.Cu")
		(net "SMB_NIC7_ADC_SCL")
	)
	(segment
		(start 385.714494 -139.198858)
		(end 386.838952 -138.0744)
		(width 0.15494)
		(layer "In13.Cu")
		(net "SMB_NIC7_ADC_SCL")
	)
	(segment
		(start 398.012666 -138.3284)
		(end 401.55368 -138.3284)
		(width 0.15494)
		(layer "In13.Cu")
		(net "SMB_NIC7_ADC_SCL")
	)
	(segment
		(start 443.361826 -139.0142)
		(end 444.723266 -137.65276)
		(width 0.15494)
		(layer "In13.Cu")
		(net "SMB_NIC7_ADC_SCL")
	)
	(segment
		(start 388.202678 -138.0744)
		(end 391.561574 -134.715504)
		(width 0.15494)
		(layer "In13.Cu")
		(net "SMB_NIC7_ADC_SCL")
	)
	(segment
		(start 425.724828 -137.965434)
		(end 428.043594 -140.2842)
		(width 0.15494)
		(layer "In13.Cu")
		(net "SMB_NIC7_ADC_SCL")
	)
	(segment
		(start 431.876454 -140.2842)
		(end 433.146454 -139.0142)
		(width 0.15494)
		(layer "In13.Cu")
		(net "SMB_NIC7_ADC_SCL")
	)
	(segment
		(start 363.7915 -174.6885)
		(end 363.6645 -174.6885)
		(width 0.13208)
		(layer "F.Cu")
		(net "SSD7_PEX_PWR_EN")
	)
	(segment
		(start 366.263936 -175.666908)
		(end 365.713772 -175.666908)
		(width 0.13208)
		(layer "F.Cu")
		(net "SSD7_PEX_PWR_EN")
	)
	(segment
		(start 365.191548 -175.144684)
		(end 364.247684 -175.144684)
		(width 0.13208)
		(layer "F.Cu")
		(net "SSD7_PEX_PWR_EN")
	)
	(segment
		(start 364.247684 -175.144684)
		(end 363.7915 -174.6885)
		(width 0.13208)
		(layer "F.Cu")
		(net "SSD7_PEX_PWR_EN")
	)
	(segment
		(start 365.713772 -175.666908)
		(end 365.191548 -175.144684)
		(width 0.13208)
		(layer "F.Cu")
		(net "SSD7_PEX_PWR_EN")
	)
	(segment
		(start 363.6645 -174.6885)
		(end 362.966 -173.99)
		(width 0.13208)
		(layer "F.Cu")
		(net "SSD7_PEX_PWR_EN")
	)
	(segment
		(start 362.966 -173.99)
		(end 361.58805 -173.99)
		(width 0.13208)
		(layer "F.Cu")
		(net "SSD7_PEX_PWR_EN")
	)
	(via
		(at 362.966 -173.99)
		(size 0.508)
		(drill 0.254)
		(layers "F.Cu" "B.Cu")
		(net "SSD7_PEX_PWR_EN")
	)
	(segment
		(start 336.44205 -141.551152)
		(end 336.44205 -141.859)
		(width 0.13208)
		(layer "F.Cu")
		(net "RST_PEX_SSD15_PERST_R_N")
	)
	(segment
		(start 337.67395 -141.859)
		(end 337.67395 -141.551152)
		(width 0.13208)
		(layer "F.Cu")
		(net "RST_PEX_SSD15_PERST_R_N")
	)
	(segment
		(start 337.056222 -141.424152)
		(end 336.56905 -141.424152)
		(width 0.13208)
		(layer "F.Cu")
		(net "RST_PEX_SSD15_PERST_R_N")
	)
	(segment
		(start 337.293966 -219.987114)
		(end 336.89417 -220.38691)
		(width 0.13208)
		(layer "F.Cu")
		(net "RST_PEX_SSD15_PERST_R_N")
	)
	(segment
		(start 337.54695 -141.424152)
		(end 337.056222 -141.424152)
		(width 0.13208)
		(layer "F.Cu")
		(net "RST_PEX_SSD15_PERST_R_N")
	)
	(segment
		(start 337.67395 -141.551152)
		(end 337.54695 -141.424152)
		(width 0.13208)
		(layer "F.Cu")
		(net "RST_PEX_SSD15_PERST_R_N")
	)
	(segment
		(start 336.56905 -141.424152)
		(end 336.44205 -141.551152)
		(width 0.13208)
		(layer "F.Cu")
		(net "RST_PEX_SSD15_PERST_R_N")
	)
	(via
		(at 336.89417 -220.38691)
		(size 0.4572)
		(drill 0.254)
		(layers "F.Cu" "B.Cu")
		(net "RST_PEX_SSD15_PERST_R_N")
	)
	(via
		(at 337.056222 -141.424152)
		(size 0.508)
		(drill 0.254)
		(layers "F.Cu" "B.Cu")
		(net "RST_PEX_SSD15_PERST_R_N")
	)
	(segment
		(start 338.14512 -144.308068)
		(end 337.366864 -143.529812)
		(width 0.15494)
		(layer "In7.Cu")
		(net "RST_PEX_SSD15_PERST_R_N")
	)
	(segment
		(start 336.89417 -220.38691)
		(end 336.258662 -219.751402)
		(width 0.15494)
		(layer "In7.Cu")
		(net "RST_PEX_SSD15_PERST_R_N")
	)
	(segment
		(start 330.849732 -154.974036)
		(end 334.729582 -151.094186)
		(width 0.15494)
		(layer "In7.Cu")
		(net "RST_PEX_SSD15_PERST_R_N")
	)
	(segment
		(start 330.555346 -168.213532)
		(end 330.849732 -167.919146)
		(width 0.15494)
		(layer "In7.Cu")
		(net "RST_PEX_SSD15_PERST_R_N")
	)
	(segment
		(start 327.994518 -213.476332)
		(end 327.51014 -212.991954)
		(width 0.15494)
		(layer "In7.Cu")
		(net "RST_PEX_SSD15_PERST_R_N")
	)
	(segment
		(start 329.088496 -217.715084)
		(end 327.994518 -216.621106)
		(width 0.15494)
		(layer "In7.Cu")
		(net "RST_PEX_SSD15_PERST_R_N")
	)
	(segment
		(start 331.344016 -217.715084)
		(end 329.088496 -217.715084)
		(width 0.15494)
		(layer "In7.Cu")
		(net "RST_PEX_SSD15_PERST_R_N")
	)
	(segment
		(start 334.729582 -151.094186)
		(end 335.211674 -151.094186)
		(width 0.15494)
		(layer "In7.Cu")
		(net "RST_PEX_SSD15_PERST_R_N")
	)
	(segment
		(start 326.18807 -206.636112)
		(end 326.18807 -203.051664)
		(width 0.15494)
		(layer "In7.Cu")
		(net "RST_PEX_SSD15_PERST_R_N")
	)
	(segment
		(start 327.51014 -211.5439)
		(end 327.0504 -211.08416)
		(width 0.15494)
		(layer "In7.Cu")
		(net "RST_PEX_SSD15_PERST_R_N")
	)
	(segment
		(start 336.423 -142.057374)
		(end 337.056222 -141.424152)
		(width 0.15494)
		(layer "In7.Cu")
		(net "RST_PEX_SSD15_PERST_R_N")
	)
	(segment
		(start 327.0504 -211.08416)
		(end 327.0504 -207.498442)
		(width 0.15494)
		(layer "In7.Cu")
		(net "RST_PEX_SSD15_PERST_R_N")
	)
	(segment
		(start 337.566 -147.941284)
		(end 338.14512 -147.362164)
		(width 0.15494)
		(layer "In7.Cu")
		(net "RST_PEX_SSD15_PERST_R_N")
	)
	(segment
		(start 336.423 -143.186404)
		(end 336.423 -142.057374)
		(width 0.15494)
		(layer "In7.Cu")
		(net "RST_PEX_SSD15_PERST_R_N")
	)
	(segment
		(start 338.14512 -147.362164)
		(end 338.14512 -144.308068)
		(width 0.15494)
		(layer "In7.Cu")
		(net "RST_PEX_SSD15_PERST_R_N")
	)
	(segment
		(start 336.258662 -219.751402)
		(end 333.380334 -219.751402)
		(width 0.15494)
		(layer "In7.Cu")
		(net "RST_PEX_SSD15_PERST_R_N")
	)
	(segment
		(start 337.366864 -143.529812)
		(end 336.766408 -143.529812)
		(width 0.15494)
		(layer "In7.Cu")
		(net "RST_PEX_SSD15_PERST_R_N")
	)
	(segment
		(start 327.0504 -207.498442)
		(end 326.18807 -206.636112)
		(width 0.15494)
		(layer "In7.Cu")
		(net "RST_PEX_SSD15_PERST_R_N")
	)
	(segment
		(start 330.849732 -167.919146)
		(end 330.849732 -154.974036)
		(width 0.15494)
		(layer "In7.Cu")
		(net "RST_PEX_SSD15_PERST_R_N")
	)
	(segment
		(start 333.380334 -219.751402)
		(end 331.344016 -217.715084)
		(width 0.15494)
		(layer "In7.Cu")
		(net "RST_PEX_SSD15_PERST_R_N")
	)
	(segment
		(start 336.766408 -143.529812)
		(end 336.423 -143.186404)
		(width 0.15494)
		(layer "In7.Cu")
		(net "RST_PEX_SSD15_PERST_R_N")
	)
	(segment
		(start 337.566 -148.73986)
		(end 337.566 -147.941284)
		(width 0.15494)
		(layer "In7.Cu")
		(net "RST_PEX_SSD15_PERST_R_N")
	)
	(segment
		(start 327.994518 -216.621106)
		(end 327.994518 -213.476332)
		(width 0.15494)
		(layer "In7.Cu")
		(net "RST_PEX_SSD15_PERST_R_N")
	)
	(segment
		(start 330.555346 -198.684388)
		(end 330.555346 -168.213532)
		(width 0.15494)
		(layer "In7.Cu")
		(net "RST_PEX_SSD15_PERST_R_N")
	)
	(segment
		(start 326.18807 -203.051664)
		(end 330.555346 -198.684388)
		(width 0.15494)
		(layer "In7.Cu")
		(net "RST_PEX_SSD15_PERST_R_N")
	)
	(segment
		(start 335.211674 -151.094186)
		(end 337.566 -148.73986)
		(width 0.15494)
		(layer "In7.Cu")
		(net "RST_PEX_SSD15_PERST_R_N")
	)
	(segment
		(start 327.51014 -212.991954)
		(end 327.51014 -211.5439)
		(width 0.15494)
		(layer "In7.Cu")
		(net "RST_PEX_SSD15_PERST_R_N")
	)
	(segment
		(start 230.097076 -142.707868)
		(end 230.103172 -142.701772)
		(width 0.13208)
		(layer "F.Cu")
		(net "CLK_CK440_PEX_SMB_ADDR1")
	)
	(segment
		(start 229.898956 -139.499594)
		(end 228.728524 -138.329162)
		(width 0.13208)
		(layer "F.Cu")
		(net "CLK_CK440_PEX_SMB_ADDR1")
	)
	(segment
		(start 229.898956 -140.908786)
		(end 229.898956 -140.150342)
		(width 0.13208)
		(layer "F.Cu")
		(net "CLK_CK440_PEX_SMB_ADDR1")
	)
	(segment
		(start 229.898956 -140.150342)
		(end 229.898956 -139.499594)
		(width 0.13208)
		(layer "F.Cu")
		(net "CLK_CK440_PEX_SMB_ADDR1")
	)
	(segment
		(start 226.804474 -137.069322)
		(end 227.693474 -137.069322)
		(width 0.13208)
		(layer "F.Cu")
		(net "CLK_CK440_PEX_SMB_ADDR1")
	)
	(segment
		(start 230.103172 -141.113002)
		(end 229.898956 -140.908786)
		(width 0.13208)
		(layer "F.Cu")
		(net "CLK_CK440_PEX_SMB_ADDR1")
	)
	(segment
		(start 228.728524 -138.104372)
		(end 227.693474 -137.069322)
		(width 0.13208)
		(layer "F.Cu")
		(net "CLK_CK440_PEX_SMB_ADDR1")
	)
	(segment
		(start 228.728524 -138.329162)
		(end 228.728524 -138.104372)
		(width 0.13208)
		(layer "F.Cu")
		(net "CLK_CK440_PEX_SMB_ADDR1")
	)
	(segment
		(start 230.103172 -142.701772)
		(end 230.103172 -141.113002)
		(width 0.13208)
		(layer "F.Cu")
		(net "CLK_CK440_PEX_SMB_ADDR1")
	)
	(segment
		(start 230.097076 -144.01546)
		(end 230.097076 -142.707868)
		(width 0.0889)
		(layer "F.Cu")
		(net "CLK_CK440_PEX_SMB_ADDR1")
	)
	(via
		(at 229.898956 -140.150342)
		(size 0.762)
		(drill 0.381)
		(layers "F.Cu" "B.Cu")
		(net "CLK_CK440_PEX_SMB_ADDR1")
	)
	(segment
		(start 226.892104 -204.84211)
		(end 226.546664 -204.84211)
		(width 0.13208)
		(layer "F.Cu")
		(net "JTAG_BIC_TDI")
	)
	(segment
		(start 227.3427 -210.451192)
		(end 227.019104 -210.127596)
		(width 0.13208)
		(layer "F.Cu")
		(net "JTAG_BIC_TDI")
	)
	(segment
		(start 227.019104 -204.96911)
		(end 226.892104 -204.84211)
		(width 0.13208)
		(layer "F.Cu")
		(net "JTAG_BIC_TDI")
	)
	(segment
		(start 227.019104 -210.127596)
		(end 227.019104 -204.96911)
		(width 0.13208)
		(layer "F.Cu")
		(net "JTAG_BIC_TDI")
	)
	(segment
		(start 228.267768 -214.304118)
		(end 227.867972 -213.904322)
		(width 0.13208)
		(layer "F.Cu")
		(net "JTAG_BIC_TDI")
	)
	(via
		(at 227.3427 -210.451192)
		(size 0.508)
		(drill 0.254)
		(layers "F.Cu" "B.Cu")
		(net "JTAG_BIC_TDI")
	)
	(via
		(at 227.867972 -213.904322)
		(size 0.4572)
		(drill 0.254)
		(layers "F.Cu" "B.Cu")
		(net "JTAG_BIC_TDI")
	)
	(segment
		(start 227.3427 -210.451192)
		(end 227.3427 -210.704938)
		(width 0.15494)
		(layer "In7.Cu")
		(net "JTAG_BIC_TDI")
	)
	(segment
		(start 227.867972 -211.23021)
		(end 227.867972 -213.904322)
		(width 0.15494)
		(layer "In7.Cu")
		(net "JTAG_BIC_TDI")
	)
	(segment
		(start 227.3427 -210.704938)
		(end 227.867972 -211.23021)
		(width 0.15494)
		(layer "In7.Cu")
		(net "JTAG_BIC_TDI")
	)
	(segment
		(start 92.176092 -297.8658)
		(end 91.681808 -297.371516)
		(width 0.13208)
		(layer "F.Cu")
		(net "SMB_PEX0_HOST_LS_SCL")
	)
	(segment
		(start 91.662758 -293.980616)
		(end 92.35567 -293.980616)
		(width 0.13208)
		(layer "F.Cu")
		(net "SMB_PEX0_HOST_LS_SCL")
	)
	(segment
		(start 93.43898 -297.8658)
		(end 92.176092 -297.8658)
		(width 0.13208)
		(layer "F.Cu")
		(net "SMB_PEX0_HOST_LS_SCL")
	)
	(segment
		(start 90.964512 -289.727386)
		(end 90.867992 -289.630866)
		(width 0.13208)
		(layer "F.Cu")
		(net "SMB_PEX0_HOST_LS_SCL")
	)
	(segment
		(start 91.681808 -297.371516)
		(end 91.681808 -297.279314)
		(width 0.13208)
		(layer "F.Cu")
		(net "SMB_PEX0_HOST_LS_SCL")
	)
	(segment
		(start 90.964512 -291.297868)
		(end 90.964512 -289.727386)
		(width 0.13208)
		(layer "F.Cu")
		(net "SMB_PEX0_HOST_LS_SCL")
	)
	(segment
		(start 92.35567 -293.980616)
		(end 93.599 -295.223946)
		(width 0.13208)
		(layer "F.Cu")
		(net "SMB_PEX0_HOST_LS_SCL")
	)
	(segment
		(start 93.599 -297.70578)
		(end 93.43898 -297.8658)
		(width 0.13208)
		(layer "F.Cu")
		(net "SMB_PEX0_HOST_LS_SCL")
	)
	(segment
		(start 90.964512 -293.28237)
		(end 90.964512 -291.297868)
		(width 0.13208)
		(layer "F.Cu")
		(net "SMB_PEX0_HOST_LS_SCL")
	)
	(segment
		(start 93.599 -295.223946)
		(end 93.599 -297.70578)
		(width 0.13208)
		(layer "F.Cu")
		(net "SMB_PEX0_HOST_LS_SCL")
	)
	(segment
		(start 91.883992 -289.630866)
		(end 90.867992 -289.630866)
		(width 0.13208)
		(layer "F.Cu")
		(net "SMB_PEX0_HOST_LS_SCL")
	)
	(segment
		(start 92.899992 -289.630866)
		(end 91.883992 -289.630866)
		(width 0.13208)
		(layer "F.Cu")
		(net "SMB_PEX0_HOST_LS_SCL")
	)
	(segment
		(start 91.662758 -293.980616)
		(end 90.964512 -293.28237)
		(width 0.13208)
		(layer "F.Cu")
		(net "SMB_PEX0_HOST_LS_SCL")
	)
	(segment
		(start 91.681808 -297.279314)
		(end 91.687142 -297.27398)
		(width 0.13208)
		(layer "F.Cu")
		(net "SMB_PEX0_HOST_LS_SCL")
	)
	(via
		(at 91.662758 -293.980616)
		(size 0.508)
		(drill 0.254)
		(layers "F.Cu" "B.Cu")
		(net "SMB_PEX0_HOST_LS_SCL")
	)
	(segment
		(start 340.881462 -182.204106)
		(end 343.149936 -182.204106)
		(width 0.13208)
		(layer "F.Cu")
		(net "SSD8_PEX_PWR_EN")
	)
	(segment
		(start 340.359746 -181.991)
		(end 340.572852 -182.204106)
		(width 0.13208)
		(layer "F.Cu")
		(net "SSD8_PEX_PWR_EN")
	)
	(segment
		(start 340.572852 -182.204106)
		(end 340.881462 -182.204106)
		(width 0.13208)
		(layer "F.Cu")
		(net "SSD8_PEX_PWR_EN")
	)
	(segment
		(start 338.47405 -181.991)
		(end 340.359746 -181.991)
		(width 0.13208)
		(layer "F.Cu")
		(net "SSD8_PEX_PWR_EN")
	)
	(via
		(at 340.881462 -182.204106)
		(size 0.508)
		(drill 0.254)
		(layers "F.Cu" "B.Cu")
		(net "SSD8_PEX_PWR_EN")
	)
	(segment
		(start 265.397742 -114.4905)
		(end 266.006072 -114.4905)
		(width 0.13208)
		(layer "F.Cu")
		(net "PRSNT_NIC4_R_N")
	)
	(segment
		(start 234.667552 -223.104202)
		(end 235.067348 -223.503998)
		(width 0.13208)
		(layer "F.Cu")
		(net "PRSNT_NIC4_R_N")
	)
	(segment
		(start 266.269216 -117.6782)
		(end 266.006072 -117.415056)
		(width 0.13208)
		(layer "F.Cu")
		(net "PRSNT_NIC4_R_N")
	)
	(segment
		(start 264.517632 -114.936524)
		(end 264.517632 -113.958624)
		(width 0.13208)
		(layer "F.Cu")
		(net "PRSNT_NIC4_R_N")
	)
	(segment
		(start 269.125446 -116.512594)
		(end 267.95984 -117.6782)
		(width 0.13208)
		(layer "F.Cu")
		(net "PRSNT_NIC4_R_N")
	)
	(segment
		(start 267.95984 -117.6782)
		(end 266.269216 -117.6782)
		(width 0.13208)
		(layer "F.Cu")
		(net "PRSNT_NIC4_R_N")
	)
	(segment
		(start 264.951718 -114.936524)
		(end 265.397742 -114.4905)
		(width 0.13208)
		(layer "F.Cu")
		(net "PRSNT_NIC4_R_N")
	)
	(segment
		(start 350.093788 -221.58706)
		(end 350.493584 -221.986856)
		(width 0.13208)
		(layer "F.Cu")
		(net "PRSNT_NIC4_R_N")
	)
	(segment
		(start 266.006072 -117.415056)
		(end 266.006072 -114.4905)
		(width 0.13208)
		(layer "F.Cu")
		(net "PRSNT_NIC4_R_N")
	)
	(segment
		(start 264.517632 -114.936524)
		(end 264.951718 -114.936524)
		(width 0.13208)
		(layer "F.Cu")
		(net "PRSNT_NIC4_R_N")
	)
	(via
		(at 303.722278 -250.985274)
		(size 0.508)
		(drill 0.254)
		(layers "F.Cu" "B.Cu")
		(net "PRSNT_NIC4_R_N")
	)
	(via
		(at 235.067348 -223.503998)
		(size 0.4572)
		(drill 0.254)
		(layers "F.Cu" "B.Cu")
		(net "PRSNT_NIC4_R_N")
	)
	(via
		(at 235.406184 -245.439438)
		(size 0.508)
		(drill 0.254)
		(layers "F.Cu" "B.Cu")
		(net "PRSNT_NIC4_R_N")
	)
	(via
		(at 350.493584 -221.986856)
		(size 0.4572)
		(drill 0.254)
		(layers "F.Cu" "B.Cu")
		(net "PRSNT_NIC4_R_N")
	)
	(via
		(at 269.125446 -116.512594)
		(size 0.508)
		(drill 0.254)
		(layers "F.Cu" "B.Cu")
		(net "PRSNT_NIC4_R_N")
	)
	(segment
		(start 238.38789 -242.457732)
		(end 235.406184 -245.439438)
		(width 0.15494)
		(layer "In5.Cu")
		(net "PRSNT_NIC4_R_N")
	)
	(segment
		(start 236.2962 -226.774756)
		(end 237.126526 -227.605082)
		(width 0.15494)
		(layer "In5.Cu")
		(net "PRSNT_NIC4_R_N")
	)
	(segment
		(start 237.126526 -229.55123)
		(end 237.476284 -229.900988)
		(width 0.15494)
		(layer "In5.Cu")
		(net "PRSNT_NIC4_R_N")
	)
	(segment
		(start 237.126526 -227.605082)
		(end 237.126526 -229.55123)
		(width 0.15494)
		(layer "In5.Cu")
		(net "PRSNT_NIC4_R_N")
	)
	(segment
		(start 235.067348 -223.503998)
		(end 235.350558 -223.621346)
		(width 0.0889)
		(layer "In5.Cu")
		(net "PRSNT_NIC4_R_N")
	)
	(segment
		(start 235.350558 -223.621346)
		(end 235.634784 -223.905572)
		(width 0.0889)
		(layer "In5.Cu")
		(net "PRSNT_NIC4_R_N")
	)
	(segment
		(start 238.38789 -231.855518)
		(end 238.38789 -242.457732)
		(width 0.15494)
		(layer "In5.Cu")
		(net "PRSNT_NIC4_R_N")
	)
	(segment
		(start 236.2962 -224.032572)
		(end 236.2962 -226.774756)
		(width 0.15494)
		(layer "In5.Cu")
		(net "PRSNT_NIC4_R_N")
	)
	(segment
		(start 237.476284 -229.900988)
		(end 237.476284 -230.943912)
		(width 0.15494)
		(layer "In5.Cu")
		(net "PRSNT_NIC4_R_N")
	)
	(segment
		(start 235.634784 -223.905572)
		(end 236.1692 -223.905572)
		(width 0.0889)
		(layer "In5.Cu")
		(net "PRSNT_NIC4_R_N")
	)
	(segment
		(start 237.476284 -230.943912)
		(end 238.38789 -231.855518)
		(width 0.15494)
		(layer "In5.Cu")
		(net "PRSNT_NIC4_R_N")
	)
	(segment
		(start 236.1692 -223.905572)
		(end 236.2962 -224.032572)
		(width 0.0889)
		(layer "In5.Cu")
		(net "PRSNT_NIC4_R_N")
	)
	(segment
		(start 269.125446 -116.512594)
		(end 274.417282 -121.80443)
		(width 0.15494)
		(layer "In9.Cu")
		(net "PRSNT_NIC4_R_N")
	)
	(segment
		(start 277.26894 -154.180794)
		(end 277.26894 -167.221916)
		(width 0.15494)
		(layer "In9.Cu")
		(net "PRSNT_NIC4_R_N")
	)
	(segment
		(start 283.57957 -173.920912)
		(end 299.6438 -189.985142)
		(width 0.15494)
		(layer "In9.Cu")
		(net "PRSNT_NIC4_R_N")
	)
	(segment
		(start 297.7642 -232.79735)
		(end 300.33468 -236.643926)
		(width 0.15494)
		(layer "In9.Cu")
		(net "PRSNT_NIC4_R_N")
	)
	(segment
		(start 303.709832 -250.972828)
		(end 303.722278 -250.985274)
		(width 0.15494)
		(layer "In9.Cu")
		(net "PRSNT_NIC4_R_N")
	)
	(segment
		(start 282.353512 -173.920912)
		(end 283.57957 -173.920912)
		(width 0.15494)
		(layer "In9.Cu")
		(net "PRSNT_NIC4_R_N")
	)
	(segment
		(start 278.410416 -169.977816)
		(end 282.353512 -173.920912)
		(width 0.15494)
		(layer "In9.Cu")
		(net "PRSNT_NIC4_R_N")
	)
	(segment
		(start 297.7642 -209.182208)
		(end 297.7642 -232.79735)
		(width 0.15494)
		(layer "In9.Cu")
		(net "PRSNT_NIC4_R_N")
	)
	(segment
		(start 299.6438 -204.644244)
		(end 297.7642 -209.182208)
		(width 0.15494)
		(layer "In9.Cu")
		(net "PRSNT_NIC4_R_N")
	)
	(segment
		(start 274.417282 -151.329136)
		(end 277.26894 -154.180794)
		(width 0.15494)
		(layer "In9.Cu")
		(net "PRSNT_NIC4_R_N")
	)
	(segment
		(start 274.417282 -121.80443)
		(end 274.417282 -151.329136)
		(width 0.15494)
		(layer "In9.Cu")
		(net "PRSNT_NIC4_R_N")
	)
	(segment
		(start 299.6438 -189.985142)
		(end 299.6438 -204.644244)
		(width 0.15494)
		(layer "In9.Cu")
		(net "PRSNT_NIC4_R_N")
	)
	(segment
		(start 303.709832 -244.7925)
		(end 303.709832 -250.972828)
		(width 0.15494)
		(layer "In9.Cu")
		(net "PRSNT_NIC4_R_N")
	)
	(segment
		(start 300.33468 -236.643926)
		(end 303.709832 -244.7925)
		(width 0.15494)
		(layer "In9.Cu")
		(net "PRSNT_NIC4_R_N")
	)
	(segment
		(start 277.26894 -167.221916)
		(end 278.410416 -169.977816)
		(width 0.15494)
		(layer "In9.Cu")
		(net "PRSNT_NIC4_R_N")
	)
	(segment
		(start 345.45143 -242.39982)
		(end 339.29955 -248.5517)
		(width 0.15494)
		(layer "In13.Cu")
		(net "PRSNT_NIC4_R_N")
	)
	(segment
		(start 354.670868 -234.685332)
		(end 354.670868 -236.358684)
		(width 0.15494)
		(layer "In13.Cu")
		(net "PRSNT_NIC4_R_N")
	)
	(segment
		(start 236.017054 -246.3038)
		(end 235.406184 -245.69293)
		(width 0.15494)
		(layer "In13.Cu")
		(net "PRSNT_NIC4_R_N")
	)
	(segment
		(start 239.141 -245.364)
		(end 238.53394 -245.97106)
		(width 0.15494)
		(layer "In13.Cu")
		(net "PRSNT_NIC4_R_N")
	)
	(segment
		(start 355.7778 -233.5784)
		(end 354.670868 -234.685332)
		(width 0.15494)
		(layer "In13.Cu")
		(net "PRSNT_NIC4_R_N")
	)
	(segment
		(start 350.493584 -221.986856)
		(end 350.891094 -221.589346)
		(width 0.0889)
		(layer "In13.Cu")
		(net "PRSNT_NIC4_R_N")
	)
	(segment
		(start 354.670868 -236.358684)
		(end 348.629732 -242.39982)
		(width 0.15494)
		(layer "In13.Cu")
		(net "PRSNT_NIC4_R_N")
	)
	(segment
		(start 351.79 -221.869)
		(end 351.79 -222.0468)
		(width 0.15494)
		(layer "In13.Cu")
		(net "PRSNT_NIC4_R_N")
	)
	(segment
		(start 303.960276 -250.747276)
		(end 303.722278 -250.985274)
		(width 0.15494)
		(layer "In13.Cu")
		(net "PRSNT_NIC4_R_N")
	)
	(segment
		(start 351.510346 -221.589346)
		(end 351.79 -221.869)
		(width 0.15494)
		(layer "In13.Cu")
		(net "PRSNT_NIC4_R_N")
	)
	(segment
		(start 306.441602 -250.554998)
		(end 306.249324 -250.747276)
		(width 0.15494)
		(layer "In13.Cu")
		(net "PRSNT_NIC4_R_N")
	)
	(segment
		(start 352.3234 -222.5802)
		(end 352.5012 -222.5802)
		(width 0.15494)
		(layer "In13.Cu")
		(net "PRSNT_NIC4_R_N")
	)
	(segment
		(start 355.451664 -231.169464)
		(end 355.7778 -231.4956)
		(width 0.15494)
		(layer "In13.Cu")
		(net "PRSNT_NIC4_R_N")
	)
	(segment
		(start 329.7682 -250.554998)
		(end 306.441602 -250.554998)
		(width 0.15494)
		(layer "In13.Cu")
		(net "PRSNT_NIC4_R_N")
	)
	(segment
		(start 351.79 -222.0468)
		(end 352.3234 -222.5802)
		(width 0.15494)
		(layer "In13.Cu")
		(net "PRSNT_NIC4_R_N")
	)
	(segment
		(start 273.491452 -246.718328)
		(end 251.646182 -246.718328)
		(width 0.15494)
		(layer "In13.Cu")
		(net "PRSNT_NIC4_R_N")
	)
	(segment
		(start 352.5012 -222.5802)
		(end 355.451664 -225.530664)
		(width 0.15494)
		(layer "In13.Cu")
		(net "PRSNT_NIC4_R_N")
	)
	(segment
		(start 334.4926 -248.5517)
		(end 334.28686 -248.34596)
		(width 0.15494)
		(layer "In13.Cu")
		(net "PRSNT_NIC4_R_N")
	)
	(segment
		(start 235.406184 -245.69293)
		(end 235.406184 -245.439438)
		(width 0.15494)
		(layer "In13.Cu")
		(net "PRSNT_NIC4_R_N")
	)
	(segment
		(start 348.629732 -242.39982)
		(end 345.45143 -242.39982)
		(width 0.15494)
		(layer "In13.Cu")
		(net "PRSNT_NIC4_R_N")
	)
	(segment
		(start 250.291854 -245.364)
		(end 239.141 -245.364)
		(width 0.15494)
		(layer "In13.Cu")
		(net "PRSNT_NIC4_R_N")
	)
	(segment
		(start 350.891094 -221.589346)
		(end 351.510346 -221.589346)
		(width 0.0889)
		(layer "In13.Cu")
		(net "PRSNT_NIC4_R_N")
	)
	(segment
		(start 236.49686 -246.3038)
		(end 236.017054 -246.3038)
		(width 0.15494)
		(layer "In13.Cu")
		(net "PRSNT_NIC4_R_N")
	)
	(segment
		(start 303.722278 -250.985274)
		(end 303.445926 -251.261626)
		(width 0.15494)
		(layer "In13.Cu")
		(net "PRSNT_NIC4_R_N")
	)
	(segment
		(start 238.53394 -245.97106)
		(end 236.8296 -245.97106)
		(width 0.15494)
		(layer "In13.Cu")
		(net "PRSNT_NIC4_R_N")
	)
	(segment
		(start 339.29955 -248.5517)
		(end 334.4926 -248.5517)
		(width 0.15494)
		(layer "In13.Cu")
		(net "PRSNT_NIC4_R_N")
	)
	(segment
		(start 334.28686 -248.34596)
		(end 331.977238 -248.34596)
		(width 0.15494)
		(layer "In13.Cu")
		(net "PRSNT_NIC4_R_N")
	)
	(segment
		(start 331.977238 -248.34596)
		(end 329.7682 -250.554998)
		(width 0.15494)
		(layer "In13.Cu")
		(net "PRSNT_NIC4_R_N")
	)
	(segment
		(start 299.178472 -248.462292)
		(end 275.235416 -248.462292)
		(width 0.15494)
		(layer "In13.Cu")
		(net "PRSNT_NIC4_R_N")
	)
	(segment
		(start 355.7778 -231.4956)
		(end 355.7778 -233.5784)
		(width 0.15494)
		(layer "In13.Cu")
		(net "PRSNT_NIC4_R_N")
	)
	(segment
		(start 301.977806 -251.261626)
		(end 299.178472 -248.462292)
		(width 0.15494)
		(layer "In13.Cu")
		(net "PRSNT_NIC4_R_N")
	)
	(segment
		(start 355.451664 -225.530664)
		(end 355.451664 -231.169464)
		(width 0.15494)
		(layer "In13.Cu")
		(net "PRSNT_NIC4_R_N")
	)
	(segment
		(start 251.646182 -246.718328)
		(end 250.291854 -245.364)
		(width 0.15494)
		(layer "In13.Cu")
		(net "PRSNT_NIC4_R_N")
	)
	(segment
		(start 236.8296 -245.97106)
		(end 236.49686 -246.3038)
		(width 0.15494)
		(layer "In13.Cu")
		(net "PRSNT_NIC4_R_N")
	)
	(segment
		(start 303.445926 -251.261626)
		(end 301.977806 -251.261626)
		(width 0.15494)
		(layer "In13.Cu")
		(net "PRSNT_NIC4_R_N")
	)
	(segment
		(start 275.235416 -248.462292)
		(end 273.491452 -246.718328)
		(width 0.15494)
		(layer "In13.Cu")
		(net "PRSNT_NIC4_R_N")
	)
	(segment
		(start 306.249324 -250.747276)
		(end 303.960276 -250.747276)
		(width 0.15494)
		(layer "In13.Cu")
		(net "PRSNT_NIC4_R_N")
	)
	(segment
		(start 376.432064 -213.110064)
		(end 378.621798 -213.110064)
		(width 0.13208)
		(layer "F.Cu")
		(net "SMB_PEX0_PCA9555_SDA")
	)
	(segment
		(start 373.864378 -191.285622)
		(end 373.756936 -191.393064)
		(width 0.13208)
		(layer "F.Cu")
		(net "SMB_PEX0_PCA9555_SDA")
	)
	(segment
		(start 378.621798 -213.110064)
		(end 379.051566 -212.680296)
		(width 0.13208)
		(layer "F.Cu")
		(net "SMB_PEX0_PCA9555_SDA")
	)
	(segment
		(start 89.851992 -288.221166)
		(end 89.851992 -288.830766)
		(width 0.13208)
		(layer "F.Cu")
		(net "SMB_PEX0_PCA9555_SDA")
	)
	(segment
		(start 379.051566 -212.680296)
		(end 379.12675 -212.680296)
		(width 0.13208)
		(layer "F.Cu")
		(net "SMB_PEX0_PCA9555_SDA")
	)
	(segment
		(start 373.756936 -191.393064)
		(end 372.114064 -191.393064)
		(width 0.13208)
		(layer "F.Cu")
		(net "SMB_PEX0_PCA9555_SDA")
	)
	(segment
		(start 374.396 -191.285622)
		(end 373.864378 -191.285622)
		(width 0.13208)
		(layer "F.Cu")
		(net "SMB_PEX0_PCA9555_SDA")
	)
	(via
		(at 97.14611 -257.15722)
		(size 0.508)
		(drill 0.254)
		(layers "F.Cu" "B.Cu")
		(net "SMB_PEX0_PCA9555_SDA")
	)
	(via
		(at 89.851992 -288.221166)
		(size 0.508)
		(drill 0.254)
		(layers "F.Cu" "B.Cu")
		(net "SMB_PEX0_PCA9555_SDA")
	)
	(via
		(at 379.12675 -212.680296)
		(size 0.508)
		(drill 0.254)
		(layers "F.Cu" "B.Cu")
		(net "SMB_PEX0_PCA9555_SDA")
	)
	(via
		(at 374.396 -191.285622)
		(size 0.508)
		(drill 0.254)
		(layers "F.Cu" "B.Cu")
		(net "SMB_PEX0_PCA9555_SDA")
	)
	(segment
		(start 96.499934 -263.53643)
		(end 96.499934 -274.740878)
		(width 0.13208)
		(layer "B.Cu")
		(net "SMB_PEX0_PCA9555_SDA")
	)
	(segment
		(start 96.499934 -274.740878)
		(end 90.505026 -280.735786)
		(width 0.13208)
		(layer "B.Cu")
		(net "SMB_PEX0_PCA9555_SDA")
	)
	(segment
		(start 90.505026 -280.73604)
		(end 89.851992 -281.389074)
		(width 0.13208)
		(layer "B.Cu")
		(net "SMB_PEX0_PCA9555_SDA")
	)
	(segment
		(start 90.505026 -280.735786)
		(end 90.505026 -280.73604)
		(width 0.13208)
		(layer "B.Cu")
		(net "SMB_PEX0_PCA9555_SDA")
	)
	(segment
		(start 97.14611 -262.890254)
		(end 96.499934 -263.53643)
		(width 0.13208)
		(layer "B.Cu")
		(net "SMB_PEX0_PCA9555_SDA")
	)
	(segment
		(start 97.14611 -257.15722)
		(end 97.14611 -262.890254)
		(width 0.13208)
		(layer "B.Cu")
		(net "SMB_PEX0_PCA9555_SDA")
	)
	(segment
		(start 89.851992 -281.389074)
		(end 89.851992 -288.221166)
		(width 0.13208)
		(layer "B.Cu")
		(net "SMB_PEX0_PCA9555_SDA")
	)
	(segment
		(start 378.858272 -212.270594)
		(end 378.858272 -212.411818)
		(width 0.15494)
		(layer "In9.Cu")
		(net "SMB_PEX0_PCA9555_SDA")
	)
	(segment
		(start 378.858272 -212.411818)
		(end 379.12675 -212.680296)
		(width 0.15494)
		(layer "In9.Cu")
		(net "SMB_PEX0_PCA9555_SDA")
	)
	(segment
		(start 373.790464 -207.202786)
		(end 378.858272 -212.270594)
		(width 0.15494)
		(layer "In9.Cu")
		(net "SMB_PEX0_PCA9555_SDA")
	)
	(segment
		(start 373.790464 -191.891158)
		(end 373.790464 -207.202786)
		(width 0.15494)
		(layer "In9.Cu")
		(net "SMB_PEX0_PCA9555_SDA")
	)
	(segment
		(start 374.396 -191.285622)
		(end 373.790464 -191.891158)
		(width 0.15494)
		(layer "In9.Cu")
		(net "SMB_PEX0_PCA9555_SDA")
	)
	(segment
		(start 360.579416 -232.41)
		(end 367.370614 -232.41)
		(width 0.15494)
		(layer "In13.Cu")
		(net "SMB_PEX0_PCA9555_SDA")
	)
	(segment
		(start 377.799854 -213.3854)
		(end 378.421646 -213.3854)
		(width 0.15494)
		(layer "In13.Cu")
		(net "SMB_PEX0_PCA9555_SDA")
	)
	(segment
		(start 332.9686 -251.527564)
		(end 332.9686 -250.4694)
		(width 0.15494)
		(layer "In13.Cu")
		(net "SMB_PEX0_PCA9555_SDA")
	)
	(segment
		(start 214.659464 -245.9736)
		(end 229.6922 -245.9736)
		(width 0.15494)
		(layer "In13.Cu")
		(net "SMB_PEX0_PCA9555_SDA")
	)
	(segment
		(start 274.360386 -251.11964)
		(end 298.1198 -251.11964)
		(width 0.15494)
		(layer "In13.Cu")
		(net "SMB_PEX0_PCA9555_SDA")
	)
	(segment
		(start 301.55642 -254.55626)
		(end 305.66614 -254.55626)
		(width 0.15494)
		(layer "In13.Cu")
		(net "SMB_PEX0_PCA9555_SDA")
	)
	(segment
		(start 246.213884 -247.904)
		(end 247.544336 -249.234452)
		(width 0.15494)
		(layer "In13.Cu")
		(net "SMB_PEX0_PCA9555_SDA")
	)
	(segment
		(start 150.63343 -240.80343)
		(end 152.6794 -242.8494)
		(width 0.15494)
		(layer "In13.Cu")
		(net "SMB_PEX0_PCA9555_SDA")
	)
	(segment
		(start 235.41228 -249.2248)
		(end 238.6838 -249.2248)
		(width 0.15494)
		(layer "In13.Cu")
		(net "SMB_PEX0_PCA9555_SDA")
	)
	(segment
		(start 254.131826 -249.5804)
		(end 272.821146 -249.5804)
		(width 0.15494)
		(layer "In13.Cu")
		(net "SMB_PEX0_PCA9555_SDA")
	)
	(segment
		(start 152.6794 -242.8494)
		(end 174.065946 -242.8494)
		(width 0.15494)
		(layer "In13.Cu")
		(net "SMB_PEX0_PCA9555_SDA")
	)
	(segment
		(start 332.9686 -250.4694)
		(end 333.60868 -249.82932)
		(width 0.15494)
		(layer "In13.Cu")
		(net "SMB_PEX0_PCA9555_SDA")
	)
	(segment
		(start 332.394814 -252.10135)
		(end 332.9686 -251.527564)
		(width 0.15494)
		(layer "In13.Cu")
		(net "SMB_PEX0_PCA9555_SDA")
	)
	(segment
		(start 97.14611 -257.15722)
		(end 98.951034 -257.15722)
		(width 0.15494)
		(layer "In13.Cu")
		(net "SMB_PEX0_PCA9555_SDA")
	)
	(segment
		(start 240.0046 -247.904)
		(end 246.213884 -247.904)
		(width 0.15494)
		(layer "In13.Cu")
		(net "SMB_PEX0_PCA9555_SDA")
	)
	(segment
		(start 247.544336 -249.234452)
		(end 253.785878 -249.234452)
		(width 0.15494)
		(layer "In13.Cu")
		(net "SMB_PEX0_PCA9555_SDA")
	)
	(segment
		(start 229.6922 -245.9736)
		(end 231.928416 -248.209816)
		(width 0.15494)
		(layer "In13.Cu")
		(net "SMB_PEX0_PCA9555_SDA")
	)
	(segment
		(start 339.82914 -249.82932)
		(end 345.98102 -243.67744)
		(width 0.15494)
		(layer "In13.Cu")
		(net "SMB_PEX0_PCA9555_SDA")
	)
	(segment
		(start 174.065946 -242.8494)
		(end 178.080416 -246.86387)
		(width 0.15494)
		(layer "In13.Cu")
		(net "SMB_PEX0_PCA9555_SDA")
	)
	(segment
		(start 372.25351 -227.527104)
		(end 372.25351 -225.312224)
		(width 0.15494)
		(layer "In13.Cu")
		(net "SMB_PEX0_PCA9555_SDA")
	)
	(segment
		(start 231.928416 -248.209816)
		(end 234.397296 -248.209816)
		(width 0.15494)
		(layer "In13.Cu")
		(net "SMB_PEX0_PCA9555_SDA")
	)
	(segment
		(start 372.94693 -224.618804)
		(end 372.94693 -218.238324)
		(width 0.15494)
		(layer "In13.Cu")
		(net "SMB_PEX0_PCA9555_SDA")
	)
	(segment
		(start 253.785878 -249.234452)
		(end 254.131826 -249.5804)
		(width 0.15494)
		(layer "In13.Cu")
		(net "SMB_PEX0_PCA9555_SDA")
	)
	(segment
		(start 272.821146 -249.5804)
		(end 274.360386 -251.11964)
		(width 0.15494)
		(layer "In13.Cu")
		(net "SMB_PEX0_PCA9555_SDA")
	)
	(segment
		(start 308.12105 -252.10135)
		(end 332.394814 -252.10135)
		(width 0.15494)
		(layer "In13.Cu")
		(net "SMB_PEX0_PCA9555_SDA")
	)
	(segment
		(start 372.25351 -225.312224)
		(end 372.94693 -224.618804)
		(width 0.15494)
		(layer "In13.Cu")
		(net "SMB_PEX0_PCA9555_SDA")
	)
	(segment
		(start 178.080416 -246.86387)
		(end 213.769194 -246.86387)
		(width 0.15494)
		(layer "In13.Cu")
		(net "SMB_PEX0_PCA9555_SDA")
	)
	(segment
		(start 345.98102 -243.67744)
		(end 349.311976 -243.67744)
		(width 0.15494)
		(layer "In13.Cu")
		(net "SMB_PEX0_PCA9555_SDA")
	)
	(segment
		(start 333.60868 -249.82932)
		(end 339.82914 -249.82932)
		(width 0.15494)
		(layer "In13.Cu")
		(net "SMB_PEX0_PCA9555_SDA")
	)
	(segment
		(start 238.6838 -249.2248)
		(end 240.0046 -247.904)
		(width 0.15494)
		(layer "In13.Cu")
		(net "SMB_PEX0_PCA9555_SDA")
	)
	(segment
		(start 378.421646 -213.3854)
		(end 379.12675 -212.680296)
		(width 0.15494)
		(layer "In13.Cu")
		(net "SMB_PEX0_PCA9555_SDA")
	)
	(segment
		(start 367.370614 -232.41)
		(end 372.25351 -227.527104)
		(width 0.15494)
		(layer "In13.Cu")
		(net "SMB_PEX0_PCA9555_SDA")
	)
	(segment
		(start 115.304824 -240.80343)
		(end 150.63343 -240.80343)
		(width 0.15494)
		(layer "In13.Cu")
		(net "SMB_PEX0_PCA9555_SDA")
	)
	(segment
		(start 349.311976 -243.67744)
		(end 360.579416 -232.41)
		(width 0.15494)
		(layer "In13.Cu")
		(net "SMB_PEX0_PCA9555_SDA")
	)
	(segment
		(start 298.1198 -251.11964)
		(end 301.55642 -254.55626)
		(width 0.15494)
		(layer "In13.Cu")
		(net "SMB_PEX0_PCA9555_SDA")
	)
	(segment
		(start 372.94693 -218.238324)
		(end 377.799854 -213.3854)
		(width 0.15494)
		(layer "In13.Cu")
		(net "SMB_PEX0_PCA9555_SDA")
	)
	(segment
		(start 305.66614 -254.55626)
		(end 308.12105 -252.10135)
		(width 0.15494)
		(layer "In13.Cu")
		(net "SMB_PEX0_PCA9555_SDA")
	)
	(segment
		(start 213.769194 -246.86387)
		(end 214.659464 -245.9736)
		(width 0.15494)
		(layer "In13.Cu")
		(net "SMB_PEX0_PCA9555_SDA")
	)
	(segment
		(start 98.951034 -257.15722)
		(end 115.304824 -240.80343)
		(width 0.15494)
		(layer "In13.Cu")
		(net "SMB_PEX0_PCA9555_SDA")
	)
	(segment
		(start 234.397296 -248.209816)
		(end 235.41228 -249.2248)
		(width 0.15494)
		(layer "In13.Cu")
		(net "SMB_PEX0_PCA9555_SDA")
	)
	(segment
		(start 83.173824 -139.71651)
		(end 83.173824 -140.919708)
		(width 0.13208)
		(layer "F.Cu")
		(net "PRSNT_NIC1_R_N")
	)
	(segment
		(start 83.560412 -141.306296)
		(end 84.755736 -141.306296)
		(width 0.13208)
		(layer "F.Cu")
		(net "PRSNT_NIC1_R_N")
	)
	(segment
		(start 350.893888 -224.786952)
		(end 351.293684 -225.186748)
		(width 0.13208)
		(layer "F.Cu")
		(net "PRSNT_NIC1_R_N")
	)
	(segment
		(start 233.067606 -223.104202)
		(end 233.467402 -223.503998)
		(width 0.13208)
		(layer "F.Cu")
		(net "PRSNT_NIC1_R_N")
	)
	(segment
		(start 85.45195 -142.250922)
		(end 86.098126 -142.250922)
		(width 0.13208)
		(layer "F.Cu")
		(net "PRSNT_NIC1_R_N")
	)
	(segment
		(start 86.098126 -142.250922)
		(end 86.54415 -141.804898)
		(width 0.13208)
		(layer "F.Cu")
		(net "PRSNT_NIC1_R_N")
	)
	(segment
		(start 85.45195 -142.00251)
		(end 85.45195 -142.250922)
		(width 0.13208)
		(layer "F.Cu")
		(net "PRSNT_NIC1_R_N")
	)
	(segment
		(start 83.173824 -140.919708)
		(end 83.560412 -141.306296)
		(width 0.13208)
		(layer "F.Cu")
		(net "PRSNT_NIC1_R_N")
	)
	(segment
		(start 86.54415 -141.804898)
		(end 86.94039 -141.804898)
		(width 0.13208)
		(layer "F.Cu")
		(net "PRSNT_NIC1_R_N")
	)
	(segment
		(start 84.755736 -141.306296)
		(end 85.45195 -142.00251)
		(width 0.13208)
		(layer "F.Cu")
		(net "PRSNT_NIC1_R_N")
	)
	(segment
		(start 86.94039 -141.804898)
		(end 86.94039 -142.782798)
		(width 0.13208)
		(layer "F.Cu")
		(net "PRSNT_NIC1_R_N")
	)
	(via
		(at 235.769658 -241.58575)
		(size 0.508)
		(drill 0.254)
		(layers "F.Cu" "B.Cu")
		(net "PRSNT_NIC1_R_N")
	)
	(via
		(at 233.467402 -223.503998)
		(size 0.4572)
		(drill 0.254)
		(layers "F.Cu" "B.Cu")
		(net "PRSNT_NIC1_R_N")
	)
	(via
		(at 210.131914 -135.4074)
		(size 0.508)
		(drill 0.254)
		(layers "F.Cu" "B.Cu")
		(net "PRSNT_NIC1_R_N")
	)
	(via
		(at 152.009348 -128.189736)
		(size 0.508)
		(drill 0.254)
		(layers "F.Cu" "B.Cu")
		(net "PRSNT_NIC1_R_N")
	)
	(via
		(at 95.727774 -131.715256)
		(size 0.508)
		(drill 0.254)
		(layers "F.Cu" "B.Cu")
		(net "PRSNT_NIC1_R_N")
	)
	(via
		(at 351.293684 -225.186748)
		(size 0.4572)
		(drill 0.254)
		(layers "F.Cu" "B.Cu")
		(net "PRSNT_NIC1_R_N")
	)
	(via
		(at 83.173824 -139.71651)
		(size 0.508)
		(drill 0.254)
		(layers "F.Cu" "B.Cu")
		(net "PRSNT_NIC1_R_N")
	)
	(segment
		(start 149.892766 -128.189736)
		(end 152.009348 -128.189736)
		(width 0.13208)
		(layer "B.Cu")
		(net "PRSNT_NIC1_R_N")
	)
	(segment
		(start 113.843308 -115.417092)
		(end 122.435112 -115.417092)
		(width 0.13208)
		(layer "B.Cu")
		(net "PRSNT_NIC1_R_N")
	)
	(segment
		(start 143.086582 -113.179606)
		(end 148.754592 -118.847616)
		(width 0.13208)
		(layer "B.Cu")
		(net "PRSNT_NIC1_R_N")
	)
	(segment
		(start 103.2002 -128.3716)
		(end 103.2002 -126.0602)
		(width 0.13208)
		(layer "B.Cu")
		(net "PRSNT_NIC1_R_N")
	)
	(segment
		(start 103.2002 -126.0602)
		(end 113.843308 -115.417092)
		(width 0.13208)
		(layer "B.Cu")
		(net "PRSNT_NIC1_R_N")
	)
	(segment
		(start 126.681484 -111.17072)
		(end 137.423398 -111.17072)
		(width 0.13208)
		(layer "B.Cu")
		(net "PRSNT_NIC1_R_N")
	)
	(segment
		(start 148.754592 -127.051562)
		(end 149.892766 -128.189736)
		(width 0.13208)
		(layer "B.Cu")
		(net "PRSNT_NIC1_R_N")
	)
	(segment
		(start 137.423398 -111.17072)
		(end 139.432284 -113.179606)
		(width 0.13208)
		(layer "B.Cu")
		(net "PRSNT_NIC1_R_N")
	)
	(segment
		(start 139.432284 -113.179606)
		(end 143.086582 -113.179606)
		(width 0.13208)
		(layer "B.Cu")
		(net "PRSNT_NIC1_R_N")
	)
	(segment
		(start 122.435112 -115.417092)
		(end 126.681484 -111.17072)
		(width 0.13208)
		(layer "B.Cu")
		(net "PRSNT_NIC1_R_N")
	)
	(segment
		(start 148.754592 -118.847616)
		(end 148.754592 -127.051562)
		(width 0.13208)
		(layer "B.Cu")
		(net "PRSNT_NIC1_R_N")
	)
	(segment
		(start 95.727774 -131.715256)
		(end 99.856544 -131.715256)
		(width 0.13208)
		(layer "B.Cu")
		(net "PRSNT_NIC1_R_N")
	)
	(segment
		(start 99.856544 -131.715256)
		(end 103.2002 -128.3716)
		(width 0.13208)
		(layer "B.Cu")
		(net "PRSNT_NIC1_R_N")
	)
	(segment
		(start 235.769658 -241.58575)
		(end 234.709716 -240.525808)
		(width 0.15494)
		(layer "In5.Cu")
		(net "PRSNT_NIC1_R_N")
	)
	(segment
		(start 233.400854 -231.03967)
		(end 233.400854 -227.268786)
		(width 0.15494)
		(layer "In5.Cu")
		(net "PRSNT_NIC1_R_N")
	)
	(segment
		(start 234.363768 -232.002584)
		(end 233.400854 -231.03967)
		(width 0.15494)
		(layer "In5.Cu")
		(net "PRSNT_NIC1_R_N")
	)
	(segment
		(start 233.864912 -225.4758)
		(end 233.864912 -223.901508)
		(width 0.0889)
		(layer "In5.Cu")
		(net "PRSNT_NIC1_R_N")
	)
	(segment
		(start 233.864912 -223.901508)
		(end 233.467402 -223.503998)
		(width 0.0889)
		(layer "In5.Cu")
		(net "PRSNT_NIC1_R_N")
	)
	(segment
		(start 233.400854 -227.268786)
		(end 233.864912 -226.804728)
		(width 0.15494)
		(layer "In5.Cu")
		(net "PRSNT_NIC1_R_N")
	)
	(segment
		(start 234.709716 -240.441988)
		(end 234.363768 -240.09604)
		(width 0.15494)
		(layer "In5.Cu")
		(net "PRSNT_NIC1_R_N")
	)
	(segment
		(start 233.864912 -226.804728)
		(end 233.864912 -225.4758)
		(width 0.15494)
		(layer "In5.Cu")
		(net "PRSNT_NIC1_R_N")
	)
	(segment
		(start 234.709716 -240.525808)
		(end 234.709716 -240.441988)
		(width 0.15494)
		(layer "In5.Cu")
		(net "PRSNT_NIC1_R_N")
	)
	(segment
		(start 234.363768 -240.09604)
		(end 234.363768 -232.002584)
		(width 0.15494)
		(layer "In5.Cu")
		(net "PRSNT_NIC1_R_N")
	)
	(segment
		(start 209.39506 -164.468302)
		(end 209.39506 -136.14146)
		(width 0.15494)
		(layer "In7.Cu")
		(net "PRSNT_NIC1_R_N")
	)
	(segment
		(start 87.195152 -135.17372)
		(end 83.757262 -138.61161)
		(width 0.15494)
		(layer "In7.Cu")
		(net "PRSNT_NIC1_R_N")
	)
	(segment
		(start 83.757262 -139.133072)
		(end 83.173824 -139.71651)
		(width 0.15494)
		(layer "In7.Cu")
		(net "PRSNT_NIC1_R_N")
	)
	(segment
		(start 92.26931 -135.17372)
		(end 87.195152 -135.17372)
		(width 0.15494)
		(layer "In7.Cu")
		(net "PRSNT_NIC1_R_N")
	)
	(segment
		(start 200.92162 -192.34785)
		(end 205.092808 -188.176662)
		(width 0.15494)
		(layer "In7.Cu")
		(net "PRSNT_NIC1_R_N")
	)
	(segment
		(start 207.9244 -229.5144)
		(end 200.92162 -222.51162)
		(width 0.15494)
		(layer "In7.Cu")
		(net "PRSNT_NIC1_R_N")
	)
	(segment
		(start 209.39506 -136.14146)
		(end 210.12912 -135.4074)
		(width 0.15494)
		(layer "In7.Cu")
		(net "PRSNT_NIC1_R_N")
	)
	(segment
		(start 205.092808 -168.770554)
		(end 209.39506 -164.468302)
		(width 0.15494)
		(layer "In7.Cu")
		(net "PRSNT_NIC1_R_N")
	)
	(segment
		(start 95.727774 -131.715256)
		(end 92.26931 -135.17372)
		(width 0.15494)
		(layer "In7.Cu")
		(net "PRSNT_NIC1_R_N")
	)
	(segment
		(start 233.467402 -223.725994)
		(end 227.678996 -229.5144)
		(width 0.15494)
		(layer "In7.Cu")
		(net "PRSNT_NIC1_R_N")
	)
	(segment
		(start 205.092808 -188.176662)
		(end 205.092808 -168.770554)
		(width 0.15494)
		(layer "In7.Cu")
		(net "PRSNT_NIC1_R_N")
	)
	(segment
		(start 83.757262 -138.61161)
		(end 83.757262 -139.133072)
		(width 0.15494)
		(layer "In7.Cu")
		(net "PRSNT_NIC1_R_N")
	)
	(segment
		(start 233.467402 -223.503998)
		(end 233.467402 -223.725994)
		(width 0.15494)
		(layer "In7.Cu")
		(net "PRSNT_NIC1_R_N")
	)
	(segment
		(start 210.12912 -135.4074)
		(end 210.131914 -135.4074)
		(width 0.15494)
		(layer "In7.Cu")
		(net "PRSNT_NIC1_R_N")
	)
	(segment
		(start 227.678996 -229.5144)
		(end 207.9244 -229.5144)
		(width 0.15494)
		(layer "In7.Cu")
		(net "PRSNT_NIC1_R_N")
	)
	(segment
		(start 200.92162 -222.51162)
		(end 200.92162 -192.34785)
		(width 0.15494)
		(layer "In7.Cu")
		(net "PRSNT_NIC1_R_N")
	)
	(segment
		(start 330.520294 -246.918734)
		(end 331.719428 -245.7196)
		(width 0.15494)
		(layer "In13.Cu")
		(net "PRSNT_NIC1_R_N")
	)
	(segment
		(start 344.800428 -240.517172)
		(end 346.323666 -240.517172)
		(width 0.15494)
		(layer "In13.Cu")
		(net "PRSNT_NIC1_R_N")
	)
	(segment
		(start 331.719428 -245.7196)
		(end 334.461866 -245.7196)
		(width 0.15494)
		(layer "In13.Cu")
		(net "PRSNT_NIC1_R_N")
	)
	(segment
		(start 347.776038 -239.0648)
		(end 348.309946 -239.0648)
		(width 0.15494)
		(layer "In13.Cu")
		(net "PRSNT_NIC1_R_N")
	)
	(segment
		(start 326.445626 -246.61114)
		(end 326.803766 -246.253)
		(width 0.15494)
		(layer "In13.Cu")
		(net "PRSNT_NIC1_R_N")
	)
	(segment
		(start 351.7138 -236.739938)
		(end 351.7138 -227.838508)
		(width 0.15494)
		(layer "In13.Cu")
		(net "PRSNT_NIC1_R_N")
	)
	(segment
		(start 338.5566 -246.761)
		(end 344.800428 -240.517172)
		(width 0.15494)
		(layer "In13.Cu")
		(net "PRSNT_NIC1_R_N")
	)
	(segment
		(start 350.896174 -227.020882)
		(end 350.896174 -225.584258)
		(width 0.0889)
		(layer "In13.Cu")
		(net "PRSNT_NIC1_R_N")
	)
	(segment
		(start 235.769658 -241.58575)
		(end 237.622588 -243.43868)
		(width 0.15494)
		(layer "In13.Cu")
		(net "PRSNT_NIC1_R_N")
	)
	(segment
		(start 274.504658 -244.927628)
		(end 275.943822 -246.366792)
		(width 0.15494)
		(layer "In13.Cu")
		(net "PRSNT_NIC1_R_N")
	)
	(segment
		(start 253.029466 -244.927628)
		(end 274.504658 -244.927628)
		(width 0.15494)
		(layer "In13.Cu")
		(net "PRSNT_NIC1_R_N")
	)
	(segment
		(start 300.046898 -246.366792)
		(end 301.368968 -247.688862)
		(width 0.15494)
		(layer "In13.Cu")
		(net "PRSNT_NIC1_R_N")
	)
	(segment
		(start 304.89906 -246.61114)
		(end 326.445626 -246.61114)
		(width 0.15494)
		(layer "In13.Cu")
		(net "PRSNT_NIC1_R_N")
	)
	(segment
		(start 301.368968 -247.688862)
		(end 303.821338 -247.688862)
		(width 0.15494)
		(layer "In13.Cu")
		(net "PRSNT_NIC1_R_N")
	)
	(segment
		(start 348.640146 -239.395)
		(end 349.058738 -239.395)
		(width 0.15494)
		(layer "In13.Cu")
		(net "PRSNT_NIC1_R_N")
	)
	(segment
		(start 303.821338 -247.688862)
		(end 304.89906 -246.61114)
		(width 0.15494)
		(layer "In13.Cu")
		(net "PRSNT_NIC1_R_N")
	)
	(segment
		(start 251.540518 -243.43868)
		(end 253.029466 -244.927628)
		(width 0.15494)
		(layer "In13.Cu")
		(net "PRSNT_NIC1_R_N")
	)
	(segment
		(start 237.622588 -243.43868)
		(end 251.540518 -243.43868)
		(width 0.15494)
		(layer "In13.Cu")
		(net "PRSNT_NIC1_R_N")
	)
	(segment
		(start 351.7138 -227.838508)
		(end 350.896174 -227.020882)
		(width 0.15494)
		(layer "In13.Cu")
		(net "PRSNT_NIC1_R_N")
	)
	(segment
		(start 326.803766 -246.253)
		(end 328.5744 -246.253)
		(width 0.15494)
		(layer "In13.Cu")
		(net "PRSNT_NIC1_R_N")
	)
	(segment
		(start 329.240134 -246.918734)
		(end 330.520294 -246.918734)
		(width 0.15494)
		(layer "In13.Cu")
		(net "PRSNT_NIC1_R_N")
	)
	(segment
		(start 349.058738 -239.395)
		(end 351.7138 -236.739938)
		(width 0.15494)
		(layer "In13.Cu")
		(net "PRSNT_NIC1_R_N")
	)
	(segment
		(start 328.5744 -246.253)
		(end 329.240134 -246.918734)
		(width 0.15494)
		(layer "In13.Cu")
		(net "PRSNT_NIC1_R_N")
	)
	(segment
		(start 346.323666 -240.517172)
		(end 347.776038 -239.0648)
		(width 0.15494)
		(layer "In13.Cu")
		(net "PRSNT_NIC1_R_N")
	)
	(segment
		(start 275.943822 -246.366792)
		(end 300.046898 -246.366792)
		(width 0.15494)
		(layer "In13.Cu")
		(net "PRSNT_NIC1_R_N")
	)
	(segment
		(start 348.309946 -239.0648)
		(end 348.640146 -239.395)
		(width 0.15494)
		(layer "In13.Cu")
		(net "PRSNT_NIC1_R_N")
	)
	(segment
		(start 350.896174 -225.584258)
		(end 351.293684 -225.186748)
		(width 0.0889)
		(layer "In13.Cu")
		(net "PRSNT_NIC1_R_N")
	)
	(segment
		(start 335.503266 -246.761)
		(end 338.5566 -246.761)
		(width 0.15494)
		(layer "In13.Cu")
		(net "PRSNT_NIC1_R_N")
	)
	(segment
		(start 334.461866 -245.7196)
		(end 335.503266 -246.761)
		(width 0.15494)
		(layer "In13.Cu")
		(net "PRSNT_NIC1_R_N")
	)
	(segment
		(start 207.596486 -137.940034)
		(end 196.614288 -137.940034)
		(width 0.15494)
		(layer "In15.Cu")
		(net "PRSNT_NIC1_R_N")
	)
	(segment
		(start 210.12912 -135.4074)
		(end 207.596486 -137.940034)
		(width 0.15494)
		(layer "In15.Cu")
		(net "PRSNT_NIC1_R_N")
	)
	(segment
		(start 210.131914 -135.4074)
		(end 210.12912 -135.4074)
		(width 0.15494)
		(layer "In15.Cu")
		(net "PRSNT_NIC1_R_N")
	)
	(segment
		(start 172.7454 -129.4384)
		(end 166.228268 -129.4384)
		(width 0.15494)
		(layer "In15.Cu")
		(net "PRSNT_NIC1_R_N")
	)
	(segment
		(start 165.054026 -129.121916)
		(end 164.69487 -129.481072)
		(width 0.15494)
		(layer "In15.Cu")
		(net "PRSNT_NIC1_R_N")
	)
	(segment
		(start 195.808854 -137.1346)
		(end 180.4416 -137.1346)
		(width 0.15494)
		(layer "In15.Cu")
		(net "PRSNT_NIC1_R_N")
	)
	(segment
		(start 196.614288 -137.940034)
		(end 195.808854 -137.1346)
		(width 0.15494)
		(layer "In15.Cu")
		(net "PRSNT_NIC1_R_N")
	)
	(segment
		(start 180.4416 -137.1346)
		(end 172.7454 -129.4384)
		(width 0.15494)
		(layer "In15.Cu")
		(net "PRSNT_NIC1_R_N")
	)
	(segment
		(start 153.300684 -129.481072)
		(end 152.009348 -128.189736)
		(width 0.15494)
		(layer "In15.Cu")
		(net "PRSNT_NIC1_R_N")
	)
	(segment
		(start 165.911784 -129.121916)
		(end 165.054026 -129.121916)
		(width 0.15494)
		(layer "In15.Cu")
		(net "PRSNT_NIC1_R_N")
	)
	(segment
		(start 164.69487 -129.481072)
		(end 153.300684 -129.481072)
		(width 0.15494)
		(layer "In15.Cu")
		(net "PRSNT_NIC1_R_N")
	)
	(segment
		(start 166.228268 -129.4384)
		(end 165.911784 -129.121916)
		(width 0.15494)
		(layer "In15.Cu")
		(net "PRSNT_NIC1_R_N")
	)
	(segment
		(start 232.231184 -141.768322)
		(end 231.639364 -142.360142)
		(width 0.13208)
		(layer "F.Cu")
		(net "XTAL_CK440_PEX_25M_XIN")
	)
	(segment
		(start 232.587292 -141.412214)
		(end 232.231184 -141.768322)
		(width 0.13208)
		(layer "F.Cu")
		(net "XTAL_CK440_PEX_25M_XIN")
	)
	(segment
		(start 231.34701 -143.066008)
		(end 231.34701 -143.265398)
		(width 0.13208)
		(layer "F.Cu")
		(net "XTAL_CK440_PEX_25M_XIN")
	)
	(segment
		(start 231.639364 -142.360142)
		(end 231.34701 -143.066008)
		(width 0.13208)
		(layer "F.Cu")
		(net "XTAL_CK440_PEX_25M_XIN")
	)
	(segment
		(start 232.587292 -141.286738)
		(end 232.587292 -141.412214)
		(width 0.13208)
		(layer "F.Cu")
		(net "XTAL_CK440_PEX_25M_XIN")
	)
	(segment
		(start 232.9815 -140.89253)
		(end 232.587292 -141.286738)
		(width 0.13208)
		(layer "F.Cu")
		(net "XTAL_CK440_PEX_25M_XIN")
	)
	(via
		(at 232.231184 -141.768322)
		(size 0.508)
		(drill 0.254)
		(layers "F.Cu" "B.Cu")
		(net "XTAL_CK440_PEX_25M_XIN")
	)
	(segment
		(start 350.11741 -141.93393)
		(end 350.67748 -142.494)
		(width 0.13208)
		(layer "F.Cu")
		(net "PRSNT_NIC7_FPGA_PCA9555_N")
	)
	(segment
		(start 350.67748 -142.494)
		(end 351.832164 -142.494)
		(width 0.13208)
		(layer "F.Cu")
		(net "PRSNT_NIC7_FPGA_PCA9555_N")
	)
	(segment
		(start 350.11741 -142.26667)
		(end 350.11741 -141.93393)
		(width 0.13208)
		(layer "F.Cu")
		(net "PRSNT_NIC7_FPGA_PCA9555_N")
	)
	(segment
		(start 349.000064 -142.502128)
		(end 349.881952 -142.502128)
		(width 0.13208)
		(layer "F.Cu")
		(net "PRSNT_NIC7_FPGA_PCA9555_N")
	)
	(segment
		(start 349.881952 -142.502128)
		(end 350.11741 -142.26667)
		(width 0.13208)
		(layer "F.Cu")
		(net "PRSNT_NIC7_FPGA_PCA9555_N")
	)
	(via
		(at 350.11741 -141.93393)
		(size 0.508)
		(drill 0.254)
		(layers "F.Cu" "B.Cu")
		(net "PRSNT_NIC7_FPGA_PCA9555_N")
	)
	(segment
		(start 315.373766 -139.71651)
		(end 315.373766 -140.265912)
		(width 0.13208)
		(layer "F.Cu")
		(net "PRSNT_NIC5_R_N")
	)
	(segment
		(start 317.651892 -142.00251)
		(end 317.651892 -142.250922)
		(width 0.13208)
		(layer "F.Cu")
		(net "PRSNT_NIC5_R_N")
	)
	(segment
		(start 317.651892 -142.250922)
		(end 318.298068 -142.250922)
		(width 0.13208)
		(layer "F.Cu")
		(net "PRSNT_NIC5_R_N")
	)
	(segment
		(start 318.744092 -141.804898)
		(end 319.140332 -141.804898)
		(width 0.13208)
		(layer "F.Cu")
		(net "PRSNT_NIC5_R_N")
	)
	(segment
		(start 316.41415 -141.306296)
		(end 316.955678 -141.306296)
		(width 0.13208)
		(layer "F.Cu")
		(net "PRSNT_NIC5_R_N")
	)
	(segment
		(start 315.373766 -140.265912)
		(end 316.41415 -141.306296)
		(width 0.13208)
		(layer "F.Cu")
		(net "PRSNT_NIC5_R_N")
	)
	(segment
		(start 319.140332 -141.804898)
		(end 319.140332 -142.782798)
		(width 0.13208)
		(layer "F.Cu")
		(net "PRSNT_NIC5_R_N")
	)
	(segment
		(start 233.867706 -223.104202)
		(end 234.267502 -223.503998)
		(width 0.13208)
		(layer "F.Cu")
		(net "PRSNT_NIC5_R_N")
	)
	(segment
		(start 316.955678 -141.306296)
		(end 317.651892 -142.00251)
		(width 0.13208)
		(layer "F.Cu")
		(net "PRSNT_NIC5_R_N")
	)
	(segment
		(start 318.298068 -142.250922)
		(end 318.744092 -141.804898)
		(width 0.13208)
		(layer "F.Cu")
		(net "PRSNT_NIC5_R_N")
	)
	(segment
		(start 346.893896 -219.987114)
		(end 347.293692 -220.38691)
		(width 0.13208)
		(layer "F.Cu")
		(net "PRSNT_NIC5_R_N")
	)
	(via
		(at 234.515406 -245.30812)
		(size 0.508)
		(drill 0.254)
		(layers "F.Cu" "B.Cu")
		(net "PRSNT_NIC5_R_N")
	)
	(via
		(at 315.373766 -139.71651)
		(size 0.508)
		(drill 0.254)
		(layers "F.Cu" "B.Cu")
		(net "PRSNT_NIC5_R_N")
	)
	(via
		(at 347.293692 -220.38691)
		(size 0.4572)
		(drill 0.254)
		(layers "F.Cu" "B.Cu")
		(net "PRSNT_NIC5_R_N")
	)
	(via
		(at 351.423224 -140.814552)
		(size 0.508)
		(drill 0.254)
		(layers "F.Cu" "B.Cu")
		(net "PRSNT_NIC5_R_N")
	)
	(via
		(at 234.267502 -223.503998)
		(size 0.4572)
		(drill 0.254)
		(layers "F.Cu" "B.Cu")
		(net "PRSNT_NIC5_R_N")
	)
	(segment
		(start 234.879642 -231.246934)
		(end 234.879642 -227.181918)
		(width 0.15494)
		(layer "In5.Cu")
		(net "PRSNT_NIC5_R_N")
	)
	(segment
		(start 235.464858 -226.596702)
		(end 235.464858 -225.4758)
		(width 0.15494)
		(layer "In5.Cu")
		(net "PRSNT_NIC5_R_N")
	)
	(segment
		(start 234.879642 -227.181918)
		(end 235.464858 -226.596702)
		(width 0.15494)
		(layer "In5.Cu")
		(net "PRSNT_NIC5_R_N")
	)
	(segment
		(start 235.464858 -224.138998)
		(end 235.229654 -223.903794)
		(width 0.0889)
		(layer "In5.Cu")
		(net "PRSNT_NIC5_R_N")
	)
	(segment
		(start 235.387642 -237.952788)
		(end 235.387642 -231.754934)
		(width 0.15494)
		(layer "In5.Cu")
		(net "PRSNT_NIC5_R_N")
	)
	(segment
		(start 235.464858 -225.4758)
		(end 235.464858 -224.138998)
		(width 0.0889)
		(layer "In5.Cu")
		(net "PRSNT_NIC5_R_N")
	)
	(segment
		(start 236.930946 -239.496092)
		(end 235.387642 -237.952788)
		(width 0.15494)
		(layer "In5.Cu")
		(net "PRSNT_NIC5_R_N")
	)
	(segment
		(start 235.387642 -231.754934)
		(end 234.879642 -231.246934)
		(width 0.15494)
		(layer "In5.Cu")
		(net "PRSNT_NIC5_R_N")
	)
	(segment
		(start 234.515406 -245.30812)
		(end 236.930946 -242.89258)
		(width 0.15494)
		(layer "In5.Cu")
		(net "PRSNT_NIC5_R_N")
	)
	(segment
		(start 235.229654 -223.903794)
		(end 234.667298 -223.903794)
		(width 0.0889)
		(layer "In5.Cu")
		(net "PRSNT_NIC5_R_N")
	)
	(segment
		(start 234.667298 -223.903794)
		(end 234.267502 -223.503998)
		(width 0.0889)
		(layer "In5.Cu")
		(net "PRSNT_NIC5_R_N")
	)
	(segment
		(start 236.930946 -242.89258)
		(end 236.930946 -239.496092)
		(width 0.15494)
		(layer "In5.Cu")
		(net "PRSNT_NIC5_R_N")
	)
	(segment
		(start 364.735364 -207.391)
		(end 366.200944 -205.92542)
		(width 0.15494)
		(layer "In7.Cu")
		(net "PRSNT_NIC5_R_N")
	)
	(segment
		(start 371.031262 -175.82134)
		(end 366.400588 -171.190666)
		(width 0.15494)
		(layer "In7.Cu")
		(net "PRSNT_NIC5_R_N")
	)
	(segment
		(start 350.296226 -140.814552)
		(end 351.423224 -140.814552)
		(width 0.15494)
		(layer "In7.Cu")
		(net "PRSNT_NIC5_R_N")
	)
	(segment
		(start 349.587566 -161.830766)
		(end 349.587566 -141.523212)
		(width 0.15494)
		(layer "In7.Cu")
		(net "PRSNT_NIC5_R_N")
	)
	(segment
		(start 371.754908 -191.567308)
		(end 371.5258 -191.3382)
		(width 0.15494)
		(layer "In7.Cu")
		(net "PRSNT_NIC5_R_N")
	)
	(segment
		(start 366.200944 -205.468728)
		(end 366.847628 -204.822044)
		(width 0.15494)
		(layer "In7.Cu")
		(net "PRSNT_NIC5_R_N")
	)
	(segment
		(start 371.5258 -191.3382)
		(end 371.5258 -185.71591)
		(width 0.15494)
		(layer "In7.Cu")
		(net "PRSNT_NIC5_R_N")
	)
	(segment
		(start 371.5258 -185.71591)
		(end 371.9576 -185.28411)
		(width 0.15494)
		(layer "In7.Cu")
		(net "PRSNT_NIC5_R_N")
	)
	(segment
		(start 357.508048 -215.363298)
		(end 357.508048 -209.445352)
		(width 0.15494)
		(layer "In7.Cu")
		(net "PRSNT_NIC5_R_N")
	)
	(segment
		(start 371.031262 -183.595264)
		(end 371.031262 -175.82134)
		(width 0.15494)
		(layer "In7.Cu")
		(net "PRSNT_NIC5_R_N")
	)
	(segment
		(start 352.2472 -164.4904)
		(end 349.587566 -161.830766)
		(width 0.15494)
		(layer "In7.Cu")
		(net "PRSNT_NIC5_R_N")
	)
	(segment
		(start 371.9576 -185.28411)
		(end 371.9576 -184.521602)
		(width 0.15494)
		(layer "In7.Cu")
		(net "PRSNT_NIC5_R_N")
	)
	(segment
		(start 371.754908 -201.548492)
		(end 371.754908 -191.567308)
		(width 0.15494)
		(layer "In7.Cu")
		(net "PRSNT_NIC5_R_N")
	)
	(segment
		(start 354.5586 -168.2242)
		(end 352.2472 -165.9128)
		(width 0.15494)
		(layer "In7.Cu")
		(net "PRSNT_NIC5_R_N")
	)
	(segment
		(start 347.733366 -219.947236)
		(end 352.92411 -219.947236)
		(width 0.15494)
		(layer "In7.Cu")
		(net "PRSNT_NIC5_R_N")
	)
	(segment
		(start 368.481356 -204.822044)
		(end 371.754908 -201.548492)
		(width 0.15494)
		(layer "In7.Cu")
		(net "PRSNT_NIC5_R_N")
	)
	(segment
		(start 366.200944 -205.92542)
		(end 366.200944 -205.468728)
		(width 0.15494)
		(layer "In7.Cu")
		(net "PRSNT_NIC5_R_N")
	)
	(segment
		(start 366.847628 -204.822044)
		(end 368.481356 -204.822044)
		(width 0.15494)
		(layer "In7.Cu")
		(net "PRSNT_NIC5_R_N")
	)
	(segment
		(start 361.5436 -207.7466)
		(end 361.8992 -207.391)
		(width 0.15494)
		(layer "In7.Cu")
		(net "PRSNT_NIC5_R_N")
	)
	(segment
		(start 361.8992 -207.391)
		(end 364.735364 -207.391)
		(width 0.15494)
		(layer "In7.Cu")
		(net "PRSNT_NIC5_R_N")
	)
	(segment
		(start 364.14329 -166.14648)
		(end 360.09072 -166.14648)
		(width 0.15494)
		(layer "In7.Cu")
		(net "PRSNT_NIC5_R_N")
	)
	(segment
		(start 349.587566 -141.523212)
		(end 350.296226 -140.814552)
		(width 0.15494)
		(layer "In7.Cu")
		(net "PRSNT_NIC5_R_N")
	)
	(segment
		(start 366.400588 -171.190666)
		(end 366.400588 -168.403778)
		(width 0.15494)
		(layer "In7.Cu")
		(net "PRSNT_NIC5_R_N")
	)
	(segment
		(start 358.013 -168.2242)
		(end 354.5586 -168.2242)
		(width 0.15494)
		(layer "In7.Cu")
		(net "PRSNT_NIC5_R_N")
	)
	(segment
		(start 359.2068 -207.7466)
		(end 361.5436 -207.7466)
		(width 0.15494)
		(layer "In7.Cu")
		(net "PRSNT_NIC5_R_N")
	)
	(segment
		(start 360.09072 -166.14648)
		(end 358.013 -168.2242)
		(width 0.15494)
		(layer "In7.Cu")
		(net "PRSNT_NIC5_R_N")
	)
	(segment
		(start 357.508048 -209.445352)
		(end 359.2068 -207.7466)
		(width 0.15494)
		(layer "In7.Cu")
		(net "PRSNT_NIC5_R_N")
	)
	(segment
		(start 366.400588 -168.403778)
		(end 364.14329 -166.14648)
		(width 0.15494)
		(layer "In7.Cu")
		(net "PRSNT_NIC5_R_N")
	)
	(segment
		(start 347.293692 -220.38691)
		(end 347.733366 -219.947236)
		(width 0.15494)
		(layer "In7.Cu")
		(net "PRSNT_NIC5_R_N")
	)
	(segment
		(start 371.9576 -184.521602)
		(end 371.031262 -183.595264)
		(width 0.15494)
		(layer "In7.Cu")
		(net "PRSNT_NIC5_R_N")
	)
	(segment
		(start 352.92411 -219.947236)
		(end 357.508048 -215.363298)
		(width 0.15494)
		(layer "In7.Cu")
		(net "PRSNT_NIC5_R_N")
	)
	(segment
		(start 352.2472 -165.9128)
		(end 352.2472 -164.4904)
		(width 0.15494)
		(layer "In7.Cu")
		(net "PRSNT_NIC5_R_N")
	)
	(segment
		(start 357.48087 -227.38334)
		(end 357.48087 -227.78466)
		(width 0.15494)
		(layer "In13.Cu")
		(net "PRSNT_NIC5_R_N")
	)
	(segment
		(start 356.51313 -223.72066)
		(end 356.79634 -224.00387)
		(width 0.15494)
		(layer "In13.Cu")
		(net "PRSNT_NIC5_R_N")
	)
	(segment
		(start 357.47071 -226.680014)
		(end 357.47071 -227.37318)
		(width 0.15494)
		(layer "In13.Cu")
		(net "PRSNT_NIC5_R_N")
	)
	(segment
		(start 329.741276 -251.18187)
		(end 307.74005 -251.18187)
		(width 0.15494)
		(layer "In13.Cu")
		(net "PRSNT_NIC5_R_N")
	)
	(segment
		(start 238.793528 -246.514112)
		(end 236.98708 -246.514112)
		(width 0.15494)
		(layer "In13.Cu")
		(net "PRSNT_NIC5_R_N")
	)
	(segment
		(start 347.792802 -219.8878)
		(end 351.537524 -219.8878)
		(width 0.15494)
		(layer "In13.Cu")
		(net "PRSNT_NIC5_R_N")
	)
	(segment
		(start 357.47071 -227.37318)
		(end 357.48087 -227.38334)
		(width 0.15494)
		(layer "In13.Cu")
		(net "PRSNT_NIC5_R_N")
	)
	(segment
		(start 331.444346 -249.4788)
		(end 329.741276 -251.18187)
		(width 0.15494)
		(layer "In13.Cu")
		(net "PRSNT_NIC5_R_N")
	)
	(segment
		(start 234.515406 -245.606316)
		(end 234.515406 -245.30812)
		(width 0.15494)
		(layer "In13.Cu")
		(net "PRSNT_NIC5_R_N")
	)
	(segment
		(start 357.197914 -226.03587)
		(end 357.451406 -226.289362)
		(width 0.15494)
		(layer "In13.Cu")
		(net "PRSNT_NIC5_R_N")
	)
	(segment
		(start 236.98708 -246.514112)
		(end 236.663992 -246.8372)
		(width 0.15494)
		(layer "In13.Cu")
		(net "PRSNT_NIC5_R_N")
	)
	(segment
		(start 301.829216 -251.619766)
		(end 299.28185 -249.0724)
		(width 0.15494)
		(layer "In13.Cu")
		(net "PRSNT_NIC5_R_N")
	)
	(segment
		(start 332.95336 -248.90984)
		(end 332.3844 -249.4788)
		(width 0.15494)
		(layer "In13.Cu")
		(net "PRSNT_NIC5_R_N")
	)
	(segment
		(start 337.706462 -140.220192)
		(end 350.828864 -140.220192)
		(width 0.15494)
		(layer "In13.Cu")
		(net "PRSNT_NIC5_R_N")
	)
	(segment
		(start 348.930976 -242.75796)
		(end 345.60002 -242.75796)
		(width 0.15494)
		(layer "In13.Cu")
		(net "PRSNT_NIC5_R_N")
	)
	(segment
		(start 350.828864 -140.220192)
		(end 351.423224 -140.814552)
		(width 0.15494)
		(layer "In13.Cu")
		(net "PRSNT_NIC5_R_N")
	)
	(segment
		(start 357.48087 -227.78466)
		(end 357.47071 -227.79482)
		(width 0.15494)
		(layer "In13.Cu")
		(net "PRSNT_NIC5_R_N")
	)
	(segment
		(start 345.60002 -242.75796)
		(end 339.44814 -248.90984)
		(width 0.15494)
		(layer "In13.Cu")
		(net "PRSNT_NIC5_R_N")
	)
	(segment
		(start 357.451406 -222.77959)
		(end 357.451406 -222.782638)
		(width 0.15494)
		(layer "In13.Cu")
		(net "PRSNT_NIC5_R_N")
	)
	(segment
		(start 275.183854 -249.0724)
		(end 273.187922 -247.076468)
		(width 0.15494)
		(layer "In13.Cu")
		(net "PRSNT_NIC5_R_N")
	)
	(segment
		(start 357.48087 -229.41534)
		(end 357.48087 -229.81666)
		(width 0.15494)
		(layer "In13.Cu")
		(net "PRSNT_NIC5_R_N")
	)
	(segment
		(start 356.79634 -223.03613)
		(end 356.51313 -223.31934)
		(width 0.15494)
		(layer "In13.Cu")
		(net "PRSNT_NIC5_R_N")
	)
	(segment
		(start 332.3844 -249.4788)
		(end 331.444346 -249.4788)
		(width 0.15494)
		(layer "In13.Cu")
		(net "PRSNT_NIC5_R_N")
	)
	(segment
		(start 306.605178 -251.40666)
		(end 306.392072 -251.619766)
		(width 0.15494)
		(layer "In13.Cu")
		(net "PRSNT_NIC5_R_N")
	)
	(segment
		(start 307.74005 -251.18187)
		(end 307.51526 -251.40666)
		(width 0.15494)
		(layer "In13.Cu")
		(net "PRSNT_NIC5_R_N")
	)
	(segment
		(start 239.2426 -246.06504)
		(end 238.793528 -246.514112)
		(width 0.15494)
		(layer "In13.Cu")
		(net "PRSNT_NIC5_R_N")
	)
	(segment
		(start 357.19766 -224.00387)
		(end 357.19766 -224.66681)
		(width 0.15494)
		(layer "In13.Cu")
		(net "PRSNT_NIC5_R_N")
	)
	(segment
		(start 307.51526 -251.40666)
		(end 306.605178 -251.40666)
		(width 0.15494)
		(layer "In13.Cu")
		(net "PRSNT_NIC5_R_N")
	)
	(segment
		(start 247.987312 -247.076468)
		(end 246.975884 -246.06504)
		(width 0.15494)
		(layer "In13.Cu")
		(net "PRSNT_NIC5_R_N")
	)
	(segment
		(start 339.44814 -248.90984)
		(end 332.95336 -248.90984)
		(width 0.15494)
		(layer "In13.Cu")
		(net "PRSNT_NIC5_R_N")
	)
	(segment
		(start 357.19766 -224.66681)
		(end 356.51313 -225.35134)
		(width 0.15494)
		(layer "In13.Cu")
		(net "PRSNT_NIC5_R_N")
	)
	(segment
		(start 357.197914 -223.03613)
		(end 356.79634 -223.03613)
		(width 0.15494)
		(layer "In13.Cu")
		(net "PRSNT_NIC5_R_N")
	)
	(segment
		(start 357.451406 -226.66071)
		(end 357.47071 -226.680014)
		(width 0.15494)
		(layer "In13.Cu")
		(net "PRSNT_NIC5_R_N")
	)
	(segment
		(start 357.451406 -226.289362)
		(end 357.451406 -226.66071)
		(width 0.15494)
		(layer "In13.Cu")
		(net "PRSNT_NIC5_R_N")
	)
	(segment
		(start 357.47071 -227.79482)
		(end 357.47071 -229.40518)
		(width 0.15494)
		(layer "In13.Cu")
		(net "PRSNT_NIC5_R_N")
	)
	(segment
		(start 299.28185 -249.0724)
		(end 275.183854 -249.0724)
		(width 0.15494)
		(layer "In13.Cu")
		(net "PRSNT_NIC5_R_N")
	)
	(segment
		(start 356.51313 -225.75266)
		(end 356.79634 -226.03587)
		(width 0.15494)
		(layer "In13.Cu")
		(net "PRSNT_NIC5_R_N")
	)
	(segment
		(start 337.20278 -139.71651)
		(end 337.706462 -140.220192)
		(width 0.15494)
		(layer "In13.Cu")
		(net "PRSNT_NIC5_R_N")
	)
	(segment
		(start 273.187922 -247.076468)
		(end 247.987312 -247.076468)
		(width 0.15494)
		(layer "In13.Cu")
		(net "PRSNT_NIC5_R_N")
	)
	(segment
		(start 246.975884 -246.06504)
		(end 239.2426 -246.06504)
		(width 0.15494)
		(layer "In13.Cu")
		(net "PRSNT_NIC5_R_N")
	)
	(segment
		(start 315.373766 -139.71651)
		(end 337.20278 -139.71651)
		(width 0.15494)
		(layer "In13.Cu")
		(net "PRSNT_NIC5_R_N")
	)
	(segment
		(start 357.47071 -229.40518)
		(end 357.48087 -229.41534)
		(width 0.15494)
		(layer "In13.Cu")
		(net "PRSNT_NIC5_R_N")
	)
	(segment
		(start 236.663992 -246.8372)
		(end 235.74629 -246.8372)
		(width 0.15494)
		(layer "In13.Cu")
		(net "PRSNT_NIC5_R_N")
	)
	(segment
		(start 347.293692 -220.38691)
		(end 347.792802 -219.8878)
		(width 0.15494)
		(layer "In13.Cu")
		(net "PRSNT_NIC5_R_N")
	)
	(segment
		(start 357.451406 -222.782638)
		(end 357.197914 -223.03613)
		(width 0.15494)
		(layer "In13.Cu")
		(net "PRSNT_NIC5_R_N")
	)
	(segment
		(start 357.48087 -229.81666)
		(end 357.47071 -229.82682)
		(width 0.15494)
		(layer "In13.Cu")
		(net "PRSNT_NIC5_R_N")
	)
	(segment
		(start 352.987864 -221.33814)
		(end 356.009956 -221.33814)
		(width 0.15494)
		(layer "In13.Cu")
		(net "PRSNT_NIC5_R_N")
	)
	(segment
		(start 306.392072 -251.619766)
		(end 301.829216 -251.619766)
		(width 0.15494)
		(layer "In13.Cu")
		(net "PRSNT_NIC5_R_N")
	)
	(segment
		(start 351.537524 -219.8878)
		(end 352.987864 -221.33814)
		(width 0.15494)
		(layer "In13.Cu")
		(net "PRSNT_NIC5_R_N")
	)
	(segment
		(start 356.79634 -226.03587)
		(end 357.197914 -226.03587)
		(width 0.15494)
		(layer "In13.Cu")
		(net "PRSNT_NIC5_R_N")
	)
	(segment
		(start 356.79634 -224.00387)
		(end 357.19766 -224.00387)
		(width 0.15494)
		(layer "In13.Cu")
		(net "PRSNT_NIC5_R_N")
	)
	(segment
		(start 357.47071 -234.218226)
		(end 348.930976 -242.75796)
		(width 0.15494)
		(layer "In13.Cu")
		(net "PRSNT_NIC5_R_N")
	)
	(segment
		(start 357.47071 -229.82682)
		(end 357.47071 -234.218226)
		(width 0.15494)
		(layer "In13.Cu")
		(net "PRSNT_NIC5_R_N")
	)
	(segment
		(start 356.009956 -221.33814)
		(end 357.451406 -222.77959)
		(width 0.15494)
		(layer "In13.Cu")
		(net "PRSNT_NIC5_R_N")
	)
	(segment
		(start 356.51313 -223.31934)
		(end 356.51313 -223.72066)
		(width 0.15494)
		(layer "In13.Cu")
		(net "PRSNT_NIC5_R_N")
	)
	(segment
		(start 356.51313 -225.35134)
		(end 356.51313 -225.75266)
		(width 0.15494)
		(layer "In13.Cu")
		(net "PRSNT_NIC5_R_N")
	)
	(segment
		(start 235.74629 -246.8372)
		(end 234.515406 -245.606316)
		(width 0.15494)
		(layer "In13.Cu")
		(net "PRSNT_NIC5_R_N")
	)
	(segment
		(start 179.924456 -157.680152)
		(end 181.154324 -157.680152)
		(width 0.13208)
		(layer "F.Cu")
		(net "NIC3_PWRBRK_R_N")
	)
	(segment
		(start 181.154324 -157.680152)
		(end 181.7624 -157.680152)
		(width 0.13208)
		(layer "F.Cu")
		(net "NIC3_PWRBRK_R_N")
	)
	(segment
		(start 181.7624 -157.680152)
		(end 182.437278 -158.35503)
		(width 0.13208)
		(layer "F.Cu")
		(net "NIC3_PWRBRK_R_N")
	)
	(segment
		(start 182.437278 -158.35503)
		(end 184.757314 -158.35503)
		(width 0.13208)
		(layer "F.Cu")
		(net "NIC3_PWRBRK_R_N")
	)
	(via
		(at 181.154324 -157.680152)
		(size 0.762)
		(drill 0.381)
		(layers "F.Cu" "B.Cu")
		(net "NIC3_PWRBRK_R_N")
	)
	(segment
		(start 134.018528 -150.903432)
		(end 133.83006 -151.0919)
		(width 0.13208)
		(layer "F.Cu")
		(net "SMB_NIC2_ADC_SDA")
	)
	(segment
		(start 133.83006 -151.0919)
		(end 132.8547 -151.0919)
		(width 0.13208)
		(layer "F.Cu")
		(net "SMB_NIC2_ADC_SDA")
	)
	(segment
		(start 132.27558 -151.67102)
		(end 132.27558 -152.3111)
		(width 0.13208)
		(layer "F.Cu")
		(net "SMB_NIC2_ADC_SDA")
	)
	(segment
		(start 132.8547 -151.0919)
		(end 132.27558 -151.67102)
		(width 0.13208)
		(layer "F.Cu")
		(net "SMB_NIC2_ADC_SDA")
	)
	(segment
		(start 134.018528 -150.71344)
		(end 134.018528 -150.903432)
		(width 0.13208)
		(layer "F.Cu")
		(net "SMB_NIC2_ADC_SDA")
	)
	(via
		(at 132.27558 -151.67102)
		(size 0.508)
		(drill 0.254)
		(layers "F.Cu" "B.Cu")
		(net "SMB_NIC2_ADC_SDA")
	)
	(segment
		(start 133.580632 -152.60066)
		(end 133.20522 -152.60066)
		(width 0.13208)
		(layer "B.Cu")
		(net "SMB_NIC2_ADC_SDA")
	)
	(segment
		(start 133.20522 -152.60066)
		(end 132.27558 -151.67102)
		(width 0.13208)
		(layer "B.Cu")
		(net "SMB_NIC2_ADC_SDA")
	)
	(segment
		(start 372.114064 -190.743078)
		(end 373.369078 -190.743078)
		(width 0.13208)
		(layer "F.Cu")
		(net "SMB_PEX0_PCA9555_SCL")
	)
	(segment
		(start 90.867992 -288.221166)
		(end 90.867992 -288.830766)
		(width 0.13208)
		(layer "F.Cu")
		(net "SMB_PEX0_PCA9555_SCL")
	)
	(segment
		(start 376.432064 -212.460078)
		(end 377.687078 -212.460078)
		(width 0.13208)
		(layer "F.Cu")
		(net "SMB_PEX0_PCA9555_SCL")
	)
	(via
		(at 97.46234 -255.849882)
		(size 0.508)
		(drill 0.254)
		(layers "F.Cu" "B.Cu")
		(net "SMB_PEX0_PCA9555_SCL")
	)
	(via
		(at 373.369078 -190.743078)
		(size 0.508)
		(drill 0.254)
		(layers "F.Cu" "B.Cu")
		(net "SMB_PEX0_PCA9555_SCL")
	)
	(via
		(at 377.687078 -212.460078)
		(size 0.508)
		(drill 0.254)
		(layers "F.Cu" "B.Cu")
		(net "SMB_PEX0_PCA9555_SCL")
	)
	(via
		(at 90.867992 -288.221166)
		(size 0.508)
		(drill 0.254)
		(layers "F.Cu" "B.Cu")
		(net "SMB_PEX0_PCA9555_SCL")
	)
	(segment
		(start 97.729802 -262.9281)
		(end 97.729802 -256.117344)
		(width 0.13208)
		(layer "B.Cu")
		(net "SMB_PEX0_PCA9555_SCL")
	)
	(segment
		(start 90.867992 -286.644842)
		(end 90.867992 -281.098752)
		(width 0.13208)
		(layer "B.Cu")
		(net "SMB_PEX0_PCA9555_SCL")
	)
	(segment
		(start 96.939354 -275.02739)
		(end 96.939354 -263.718548)
		(width 0.13208)
		(layer "B.Cu")
		(net "SMB_PEX0_PCA9555_SCL")
	)
	(segment
		(start 90.913966 -286.690816)
		(end 90.867992 -286.644842)
		(width 0.13208)
		(layer "B.Cu")
		(net "SMB_PEX0_PCA9555_SCL")
	)
	(segment
		(start 97.729802 -256.117344)
		(end 97.46234 -255.849882)
		(width 0.13208)
		(layer "B.Cu")
		(net "SMB_PEX0_PCA9555_SCL")
	)
	(segment
		(start 90.913966 -288.175192)
		(end 90.913966 -286.690816)
		(width 0.13208)
		(layer "B.Cu")
		(net "SMB_PEX0_PCA9555_SCL")
	)
	(segment
		(start 90.867992 -281.098752)
		(end 96.939354 -275.02739)
		(width 0.13208)
		(layer "B.Cu")
		(net "SMB_PEX0_PCA9555_SCL")
	)
	(segment
		(start 96.939354 -263.718548)
		(end 97.729802 -262.9281)
		(width 0.13208)
		(layer "B.Cu")
		(net "SMB_PEX0_PCA9555_SCL")
	)
	(segment
		(start 90.867992 -288.221166)
		(end 90.913966 -288.175192)
		(width 0.13208)
		(layer "B.Cu")
		(net "SMB_PEX0_PCA9555_SCL")
	)
	(segment
		(start 373.369078 -191.297052)
		(end 373.284496 -191.381634)
		(width 0.15494)
		(layer "In9.Cu")
		(net "SMB_PEX0_PCA9555_SCL")
	)
	(segment
		(start 373.369078 -190.743078)
		(end 373.369078 -191.297052)
		(width 0.15494)
		(layer "In9.Cu")
		(net "SMB_PEX0_PCA9555_SCL")
	)
	(segment
		(start 377.687078 -211.850478)
		(end 377.687078 -212.460078)
		(width 0.15494)
		(layer "In9.Cu")
		(net "SMB_PEX0_PCA9555_SCL")
	)
	(segment
		(start 373.284496 -207.447896)
		(end 377.687078 -211.850478)
		(width 0.15494)
		(layer "In9.Cu")
		(net "SMB_PEX0_PCA9555_SCL")
	)
	(segment
		(start 373.284496 -191.381634)
		(end 373.284496 -207.447896)
		(width 0.15494)
		(layer "In9.Cu")
		(net "SMB_PEX0_PCA9555_SCL")
	)
	(segment
		(start 214.14994 -245.51386)
		(end 231.34574 -245.51386)
		(width 0.15494)
		(layer "In13.Cu")
		(net "SMB_PEX0_PCA9555_SCL")
	)
	(segment
		(start 238.476028 -247.481852)
		(end 239.4331 -246.52478)
		(width 0.15494)
		(layer "In13.Cu")
		(net "SMB_PEX0_PCA9555_SCL")
	)
	(segment
		(start 333.14386 -249.36958)
		(end 339.63864 -249.36958)
		(width 0.15494)
		(layer "In13.Cu")
		(net "SMB_PEX0_PCA9555_SCL")
	)
	(segment
		(start 246.785384 -246.52478)
		(end 247.796812 -247.536208)
		(width 0.15494)
		(layer "In13.Cu")
		(net "SMB_PEX0_PCA9555_SCL")
	)
	(segment
		(start 330.018136 -251.64161)
		(end 331.721206 -249.93854)
		(width 0.15494)
		(layer "In13.Cu")
		(net "SMB_PEX0_PCA9555_SCL")
	)
	(segment
		(start 331.721206 -249.93854)
		(end 332.5749 -249.93854)
		(width 0.15494)
		(layer "In13.Cu")
		(net "SMB_PEX0_PCA9555_SCL")
	)
	(segment
		(start 150.952454 -240.3094)
		(end 152.959054 -242.316)
		(width 0.15494)
		(layer "In13.Cu")
		(net "SMB_PEX0_PCA9555_SCL")
	)
	(segment
		(start 339.63864 -249.36958)
		(end 345.79052 -243.2177)
		(width 0.15494)
		(layer "In13.Cu")
		(net "SMB_PEX0_PCA9555_SCL")
	)
	(segment
		(start 307.93055 -251.64161)
		(end 330.018136 -251.64161)
		(width 0.15494)
		(layer "In13.Cu")
		(net "SMB_PEX0_PCA9555_SCL")
	)
	(segment
		(start 209.687668 -246.21363)
		(end 209.87258 -246.398542)
		(width 0.15494)
		(layer "In13.Cu")
		(net "SMB_PEX0_PCA9555_SCL")
	)
	(segment
		(start 231.34574 -245.51386)
		(end 232.432352 -244.427248)
		(width 0.15494)
		(layer "In13.Cu")
		(net "SMB_PEX0_PCA9555_SCL")
	)
	(segment
		(start 275.056854 -249.6058)
		(end 299.049186 -249.6058)
		(width 0.15494)
		(layer "In13.Cu")
		(net "SMB_PEX0_PCA9555_SCL")
	)
	(segment
		(start 99.503738 -255.849882)
		(end 115.04422 -240.3094)
		(width 0.15494)
		(layer "In13.Cu")
		(net "SMB_PEX0_PCA9555_SCL")
	)
	(segment
		(start 306.795678 -251.8664)
		(end 307.70576 -251.8664)
		(width 0.15494)
		(layer "In13.Cu")
		(net "SMB_PEX0_PCA9555_SCL")
	)
	(segment
		(start 371.73789 -225.662236)
		(end 371.73789 -224.784412)
		(width 0.15494)
		(layer "In13.Cu")
		(net "SMB_PEX0_PCA9555_SCL")
	)
	(segment
		(start 272.987262 -247.536208)
		(end 275.056854 -249.6058)
		(width 0.15494)
		(layer "In13.Cu")
		(net "SMB_PEX0_PCA9555_SCL")
	)
	(segment
		(start 299.049186 -249.6058)
		(end 302.046386 -252.603)
		(width 0.15494)
		(layer "In13.Cu")
		(net "SMB_PEX0_PCA9555_SCL")
	)
	(segment
		(start 178.14925 -246.21363)
		(end 209.687668 -246.21363)
		(width 0.15494)
		(layer "In13.Cu")
		(net "SMB_PEX0_PCA9555_SCL")
	)
	(segment
		(start 370.12753 -228.56825)
		(end 370.12753 -227.272596)
		(width 0.15494)
		(layer "In13.Cu")
		(net "SMB_PEX0_PCA9555_SCL")
	)
	(segment
		(start 247.796812 -247.536208)
		(end 272.987262 -247.536208)
		(width 0.15494)
		(layer "In13.Cu")
		(net "SMB_PEX0_PCA9555_SCL")
	)
	(segment
		(start 360.411776 -231.9274)
		(end 366.76838 -231.9274)
		(width 0.15494)
		(layer "In13.Cu")
		(net "SMB_PEX0_PCA9555_SCL")
	)
	(segment
		(start 213.265258 -246.398542)
		(end 214.14994 -245.51386)
		(width 0.15494)
		(layer "In13.Cu")
		(net "SMB_PEX0_PCA9555_SCL")
	)
	(segment
		(start 307.70576 -251.8664)
		(end 307.93055 -251.64161)
		(width 0.15494)
		(layer "In13.Cu")
		(net "SMB_PEX0_PCA9555_SCL")
	)
	(segment
		(start 239.4331 -246.52478)
		(end 246.785384 -246.52478)
		(width 0.15494)
		(layer "In13.Cu")
		(net "SMB_PEX0_PCA9555_SCL")
	)
	(segment
		(start 372.371874 -217.775282)
		(end 377.687078 -212.460078)
		(width 0.15494)
		(layer "In13.Cu")
		(net "SMB_PEX0_PCA9555_SCL")
	)
	(segment
		(start 152.959054 -242.316)
		(end 174.25162 -242.316)
		(width 0.15494)
		(layer "In13.Cu")
		(net "SMB_PEX0_PCA9555_SCL")
	)
	(segment
		(start 209.87258 -246.398542)
		(end 213.265258 -246.398542)
		(width 0.15494)
		(layer "In13.Cu")
		(net "SMB_PEX0_PCA9555_SCL")
	)
	(segment
		(start 332.5749 -249.93854)
		(end 333.14386 -249.36958)
		(width 0.15494)
		(layer "In13.Cu")
		(net "SMB_PEX0_PCA9555_SCL")
	)
	(segment
		(start 306.059078 -252.603)
		(end 306.795678 -251.8664)
		(width 0.15494)
		(layer "In13.Cu")
		(net "SMB_PEX0_PCA9555_SCL")
	)
	(segment
		(start 366.76838 -231.9274)
		(end 370.12753 -228.56825)
		(width 0.15494)
		(layer "In13.Cu")
		(net "SMB_PEX0_PCA9555_SCL")
	)
	(segment
		(start 302.046386 -252.603)
		(end 306.059078 -252.603)
		(width 0.15494)
		(layer "In13.Cu")
		(net "SMB_PEX0_PCA9555_SCL")
	)
	(segment
		(start 97.46234 -255.849882)
		(end 99.503738 -255.849882)
		(width 0.15494)
		(layer "In13.Cu")
		(net "SMB_PEX0_PCA9555_SCL")
	)
	(segment
		(start 235.740702 -247.481852)
		(end 238.476028 -247.481852)
		(width 0.15494)
		(layer "In13.Cu")
		(net "SMB_PEX0_PCA9555_SCL")
	)
	(segment
		(start 233.537252 -244.427248)
		(end 233.820462 -244.710458)
		(width 0.15494)
		(layer "In13.Cu")
		(net "SMB_PEX0_PCA9555_SCL")
	)
	(segment
		(start 233.820462 -245.561612)
		(end 235.740702 -247.481852)
		(width 0.15494)
		(layer "In13.Cu")
		(net "SMB_PEX0_PCA9555_SCL")
	)
	(segment
		(start 115.04422 -240.3094)
		(end 150.952454 -240.3094)
		(width 0.15494)
		(layer "In13.Cu")
		(net "SMB_PEX0_PCA9555_SCL")
	)
	(segment
		(start 371.73789 -224.784412)
		(end 372.371874 -224.150428)
		(width 0.15494)
		(layer "In13.Cu")
		(net "SMB_PEX0_PCA9555_SCL")
	)
	(segment
		(start 233.820462 -244.710458)
		(end 233.820462 -245.561612)
		(width 0.15494)
		(layer "In13.Cu")
		(net "SMB_PEX0_PCA9555_SCL")
	)
	(segment
		(start 174.25162 -242.316)
		(end 178.14925 -246.21363)
		(width 0.15494)
		(layer "In13.Cu")
		(net "SMB_PEX0_PCA9555_SCL")
	)
	(segment
		(start 345.79052 -243.2177)
		(end 349.121476 -243.2177)
		(width 0.15494)
		(layer "In13.Cu")
		(net "SMB_PEX0_PCA9555_SCL")
	)
	(segment
		(start 349.121476 -243.2177)
		(end 360.411776 -231.9274)
		(width 0.15494)
		(layer "In13.Cu")
		(net "SMB_PEX0_PCA9555_SCL")
	)
	(segment
		(start 370.12753 -227.272596)
		(end 371.73789 -225.662236)
		(width 0.15494)
		(layer "In13.Cu")
		(net "SMB_PEX0_PCA9555_SCL")
	)
	(segment
		(start 372.371874 -224.150428)
		(end 372.371874 -217.775282)
		(width 0.15494)
		(layer "In13.Cu")
		(net "SMB_PEX0_PCA9555_SCL")
	)
	(segment
		(start 232.432352 -244.427248)
		(end 233.537252 -244.427248)
		(width 0.15494)
		(layer "In13.Cu")
		(net "SMB_PEX0_PCA9555_SCL")
	)
	(segment
		(start 202.90409 -289.893502)
		(end 203.24064 -290.230052)
		(width 0.13208)
		(layer "F.Cu")
		(net "PWRGD_P1V8_PEX1_R")
	)
	(segment
		(start 203.24064 -290.230052)
		(end 205.52664 -290.230052)
		(width 0.13208)
		(layer "F.Cu")
		(net "PWRGD_P1V8_PEX1_R")
	)
	(segment
		(start 205.533752 -290.237164)
		(end 205.646528 -290.237164)
		(width 0.13208)
		(layer "F.Cu")
		(net "PWRGD_P1V8_PEX1_R")
	)
	(segment
		(start 202.90409 -289.630866)
		(end 202.90409 -289.893502)
		(width 0.13208)
		(layer "F.Cu")
		(net "PWRGD_P1V8_PEX1_R")
	)
	(segment
		(start 205.646528 -290.237164)
		(end 205.689454 -290.28009)
		(width 0.13208)
		(layer "F.Cu")
		(net "PWRGD_P1V8_PEX1_R")
	)
	(segment
		(start 205.689454 -290.28009)
		(end 205.689454 -291.297868)
		(width 0.13208)
		(layer "F.Cu")
		(net "PWRGD_P1V8_PEX1_R")
	)
	(segment
		(start 205.52664 -290.230052)
		(end 205.533752 -290.237164)
		(width 0.13208)
		(layer "F.Cu")
		(net "PWRGD_P1V8_PEX1_R")
	)
	(via
		(at 205.646528 -290.237164)
		(size 0.508)
		(drill 0.254)
		(layers "F.Cu" "B.Cu")
		(net "PWRGD_P1V8_PEX1_R")
	)
	(segment
		(start 349.881952 -154.313128)
		(end 350.11741 -154.07767)
		(width 0.13208)
		(layer "F.Cu")
		(net "PRSNT_NIC6_FPGA_PCA9555_N")
	)
	(segment
		(start 350.11741 -154.07767)
		(end 350.11741 -153.74493)
		(width 0.13208)
		(layer "F.Cu")
		(net "PRSNT_NIC6_FPGA_PCA9555_N")
	)
	(segment
		(start 350.67748 -154.305)
		(end 351.832164 -154.305)
		(width 0.13208)
		(layer "F.Cu")
		(net "PRSNT_NIC6_FPGA_PCA9555_N")
	)
	(segment
		(start 349.000064 -154.313128)
		(end 349.881952 -154.313128)
		(width 0.13208)
		(layer "F.Cu")
		(net "PRSNT_NIC6_FPGA_PCA9555_N")
	)
	(segment
		(start 350.11741 -153.74493)
		(end 350.67748 -154.305)
		(width 0.13208)
		(layer "F.Cu")
		(net "PRSNT_NIC6_FPGA_PCA9555_N")
	)
	(via
		(at 350.11741 -153.74493)
		(size 0.508)
		(drill 0.254)
		(layers "F.Cu" "B.Cu")
		(net "PRSNT_NIC6_FPGA_PCA9555_N")
	)
	(segment
		(start 336.44205 -178.943)
		(end 336.44205 -177.927)
		(width 0.13208)
		(layer "F.Cu")
		(net "SSD9_PEX_PWR_EN_R")
	)
	(segment
		(start 335.693766 -216.786968)
		(end 335.29397 -216.387172)
		(width 0.13208)
		(layer "F.Cu")
		(net "SSD9_PEX_PWR_EN_R")
	)
	(segment
		(start 337.67395 -177.927)
		(end 337.058 -177.927)
		(width 0.13208)
		(layer "F.Cu")
		(net "SSD9_PEX_PWR_EN_R")
	)
	(segment
		(start 337.058 -177.927)
		(end 336.44205 -177.927)
		(width 0.13208)
		(layer "F.Cu")
		(net "SSD9_PEX_PWR_EN_R")
	)
	(via
		(at 337.058 -177.927)
		(size 0.508)
		(drill 0.254)
		(layers "F.Cu" "B.Cu")
		(net "SSD9_PEX_PWR_EN_R")
	)
	(via
		(at 335.29397 -216.387172)
		(size 0.4572)
		(drill 0.254)
		(layers "F.Cu" "B.Cu")
		(net "SSD9_PEX_PWR_EN_R")
	)
	(segment
		(start 325.875142 -201.962512)
		(end 325.875142 -206.653384)
		(width 0.15494)
		(layer "In11.Cu")
		(net "SSD9_PEX_PWR_EN_R")
	)
	(segment
		(start 335.01457 -216.666572)
		(end 335.29397 -216.387172)
		(width 0.15494)
		(layer "In11.Cu")
		(net "SSD9_PEX_PWR_EN_R")
	)
	(segment
		(start 327.278746 -211.881212)
		(end 332.064106 -216.666572)
		(width 0.15494)
		(layer "In11.Cu")
		(net "SSD9_PEX_PWR_EN_R")
	)
	(segment
		(start 327.278746 -208.056988)
		(end 327.278746 -211.881212)
		(width 0.15494)
		(layer "In11.Cu")
		(net "SSD9_PEX_PWR_EN_R")
	)
	(segment
		(start 332.064106 -216.666572)
		(end 335.01457 -216.666572)
		(width 0.15494)
		(layer "In11.Cu")
		(net "SSD9_PEX_PWR_EN_R")
	)
	(segment
		(start 337.058 -179.964588)
		(end 335.5594 -181.463188)
		(width 0.15494)
		(layer "In11.Cu")
		(net "SSD9_PEX_PWR_EN_R")
	)
	(segment
		(start 325.875142 -206.653384)
		(end 327.278746 -208.056988)
		(width 0.15494)
		(layer "In11.Cu")
		(net "SSD9_PEX_PWR_EN_R")
	)
	(segment
		(start 335.5594 -192.278254)
		(end 325.875142 -201.962512)
		(width 0.15494)
		(layer "In11.Cu")
		(net "SSD9_PEX_PWR_EN_R")
	)
	(segment
		(start 337.058 -177.927)
		(end 337.058 -179.964588)
		(width 0.15494)
		(layer "In11.Cu")
		(net "SSD9_PEX_PWR_EN_R")
	)
	(segment
		(start 335.5594 -181.463188)
		(end 335.5594 -192.278254)
		(width 0.15494)
		(layer "In11.Cu")
		(net "SSD9_PEX_PWR_EN_R")
	)
	(segment
		(start 340.179406 -156.200094)
		(end 340.5251 -156.545788)
		(width 0.13208)
		(layer "F.Cu")
		(net "PRSNT_SSD13_FPGA_PCA9555_N")
	)
	(segment
		(start 338.47405 -155.702)
		(end 338.80552 -155.702)
		(width 0.13208)
		(layer "F.Cu")
		(net "PRSNT_SSD13_FPGA_PCA9555_N")
	)
	(segment
		(start 340.5251 -156.545788)
		(end 340.525608 -156.545788)
		(width 0.13208)
		(layer "F.Cu")
		(net "PRSNT_SSD13_FPGA_PCA9555_N")
	)
	(segment
		(start 340.525608 -156.545788)
		(end 340.525862 -156.545534)
		(width 0.13208)
		(layer "F.Cu")
		(net "PRSNT_SSD13_FPGA_PCA9555_N")
	)
	(segment
		(start 341.930228 -156.545534)
		(end 342.397588 -157.012894)
		(width 0.13208)
		(layer "F.Cu")
		(net "PRSNT_SSD13_FPGA_PCA9555_N")
	)
	(segment
		(start 340.525862 -156.545534)
		(end 341.930228 -156.545534)
		(width 0.13208)
		(layer "F.Cu")
		(net "PRSNT_SSD13_FPGA_PCA9555_N")
	)
	(segment
		(start 339.303614 -156.200094)
		(end 340.179406 -156.200094)
		(width 0.13208)
		(layer "F.Cu")
		(net "PRSNT_SSD13_FPGA_PCA9555_N")
	)
	(segment
		(start 342.397588 -157.012894)
		(end 343.149936 -157.012894)
		(width 0.13208)
		(layer "F.Cu")
		(net "PRSNT_SSD13_FPGA_PCA9555_N")
	)
	(segment
		(start 338.80552 -155.702)
		(end 339.303614 -156.200094)
		(width 0.13208)
		(layer "F.Cu")
		(net "PRSNT_SSD13_FPGA_PCA9555_N")
	)
	(via
		(at 340.179406 -156.200094)
		(size 0.508)
		(drill 0.254)
		(layers "F.Cu" "B.Cu")
		(net "PRSNT_SSD13_FPGA_PCA9555_N")
	)
	(segment
		(start 208.684876 -136.74725)
		(end 203.627228 -141.804898)
		(width 0.13208)
		(layer "F.Cu")
		(net "PRSNT_NIC3_R_N")
	)
	(segment
		(start 202.643994 -141.804898)
		(end 203.040234 -141.804898)
		(width 0.13208)
		(layer "F.Cu")
		(net "PRSNT_NIC3_R_N")
	)
	(segment
		(start 201.551794 -142.250922)
		(end 202.19797 -142.250922)
		(width 0.13208)
		(layer "F.Cu")
		(net "PRSNT_NIC3_R_N")
	)
	(segment
		(start 203.040234 -141.804898)
		(end 203.040234 -142.782798)
		(width 0.13208)
		(layer "F.Cu")
		(net "PRSNT_NIC3_R_N")
	)
	(segment
		(start 232.26776 -223.104202)
		(end 232.667556 -223.503998)
		(width 0.13208)
		(layer "F.Cu")
		(net "PRSNT_NIC3_R_N")
	)
	(segment
		(start 202.19797 -142.250922)
		(end 202.643994 -141.804898)
		(width 0.13208)
		(layer "F.Cu")
		(net "PRSNT_NIC3_R_N")
	)
	(segment
		(start 203.627228 -141.804898)
		(end 203.040234 -141.804898)
		(width 0.13208)
		(layer "F.Cu")
		(net "PRSNT_NIC3_R_N")
	)
	(segment
		(start 348.493842 -222.38716)
		(end 348.893638 -222.786956)
		(width 0.13208)
		(layer "F.Cu")
		(net "PRSNT_NIC3_R_N")
	)
	(segment
		(start 210.381088 -136.007348)
		(end 209.641186 -136.74725)
		(width 0.13208)
		(layer "F.Cu")
		(net "PRSNT_NIC3_R_N")
	)
	(segment
		(start 209.641186 -136.74725)
		(end 208.684876 -136.74725)
		(width 0.13208)
		(layer "F.Cu")
		(net "PRSNT_NIC3_R_N")
	)
	(via
		(at 232.667556 -223.503998)
		(size 0.4572)
		(drill 0.254)
		(layers "F.Cu" "B.Cu")
		(net "PRSNT_NIC3_R_N")
	)
	(via
		(at 231.091994 -244.4496)
		(size 0.508)
		(drill 0.254)
		(layers "F.Cu" "B.Cu")
		(net "PRSNT_NIC3_R_N")
	)
	(via
		(at 348.893638 -222.786956)
		(size 0.4572)
		(drill 0.254)
		(layers "F.Cu" "B.Cu")
		(net "PRSNT_NIC3_R_N")
	)
	(via
		(at 210.381088 -136.007348)
		(size 0.508)
		(drill 0.254)
		(layers "F.Cu" "B.Cu")
		(net "PRSNT_NIC3_R_N")
	)
	(segment
		(start 232.3846 -225.58502)
		(end 231.902 -226.06762)
		(width 0.15494)
		(layer "In5.Cu")
		(net "PRSNT_NIC3_R_N")
	)
	(segment
		(start 231.902 -226.06762)
		(end 231.902 -231.394)
		(width 0.15494)
		(layer "In5.Cu")
		(net "PRSNT_NIC3_R_N")
	)
	(segment
		(start 231.3178 -236.9566)
		(end 230.123238 -238.151162)
		(width 0.15494)
		(layer "In5.Cu")
		(net "PRSNT_NIC3_R_N")
	)
	(segment
		(start 232.667556 -223.503998)
		(end 232.3846 -223.786954)
		(width 0.15494)
		(layer "In5.Cu")
		(net "PRSNT_NIC3_R_N")
	)
	(segment
		(start 231.3178 -231.9782)
		(end 231.3178 -236.9566)
		(width 0.15494)
		(layer "In5.Cu")
		(net "PRSNT_NIC3_R_N")
	)
	(segment
		(start 232.3846 -223.786954)
		(end 232.3846 -225.58502)
		(width 0.15494)
		(layer "In5.Cu")
		(net "PRSNT_NIC3_R_N")
	)
	(segment
		(start 231.902 -231.394)
		(end 231.3178 -231.9782)
		(width 0.15494)
		(layer "In5.Cu")
		(net "PRSNT_NIC3_R_N")
	)
	(segment
		(start 230.123238 -238.151162)
		(end 230.123238 -240.486184)
		(width 0.15494)
		(layer "In5.Cu")
		(net "PRSNT_NIC3_R_N")
	)
	(segment
		(start 230.123238 -240.486184)
		(end 231.091994 -241.45494)
		(width 0.15494)
		(layer "In5.Cu")
		(net "PRSNT_NIC3_R_N")
	)
	(segment
		(start 231.091994 -241.45494)
		(end 231.091994 -244.4496)
		(width 0.15494)
		(layer "In5.Cu")
		(net "PRSNT_NIC3_R_N")
	)
	(segment
		(start 210.409028 -136.796018)
		(end 210.409028 -136.035288)
		(width 0.15494)
		(layer "In7.Cu")
		(net "PRSNT_NIC3_R_N")
	)
	(segment
		(start 205.450948 -168.919144)
		(end 209.7532 -164.616892)
		(width 0.15494)
		(layer "In7.Cu")
		(net "PRSNT_NIC3_R_N")
	)
	(segment
		(start 209.7532 -164.616892)
		(end 209.7532 -137.451846)
		(width 0.15494)
		(layer "In7.Cu")
		(net "PRSNT_NIC3_R_N")
	)
	(segment
		(start 227.508308 -229.153466)
		(end 208.071466 -229.153466)
		(width 0.15494)
		(layer "In7.Cu")
		(net "PRSNT_NIC3_R_N")
	)
	(segment
		(start 209.7532 -137.451846)
		(end 210.409028 -136.796018)
		(width 0.15494)
		(layer "In7.Cu")
		(net "PRSNT_NIC3_R_N")
	)
	(segment
		(start 210.409028 -136.035288)
		(end 210.381088 -136.007348)
		(width 0.15494)
		(layer "In7.Cu")
		(net "PRSNT_NIC3_R_N")
	)
	(segment
		(start 201.27976 -222.36176)
		(end 201.27976 -192.49644)
		(width 0.15494)
		(layer "In7.Cu")
		(net "PRSNT_NIC3_R_N")
	)
	(segment
		(start 232.667556 -223.994218)
		(end 227.508308 -229.153466)
		(width 0.15494)
		(layer "In7.Cu")
		(net "PRSNT_NIC3_R_N")
	)
	(segment
		(start 201.27976 -192.49644)
		(end 205.450948 -188.325252)
		(width 0.15494)
		(layer "In7.Cu")
		(net "PRSNT_NIC3_R_N")
	)
	(segment
		(start 208.071466 -229.153466)
		(end 201.27976 -222.36176)
		(width 0.15494)
		(layer "In7.Cu")
		(net "PRSNT_NIC3_R_N")
	)
	(segment
		(start 205.450948 -188.325252)
		(end 205.450948 -168.919144)
		(width 0.15494)
		(layer "In7.Cu")
		(net "PRSNT_NIC3_R_N")
	)
	(segment
		(start 232.667556 -223.503998)
		(end 232.667556 -223.994218)
		(width 0.15494)
		(layer "In7.Cu")
		(net "PRSNT_NIC3_R_N")
	)
	(segment
		(start 351.50933 -222.389446)
		(end 355.019356 -225.899472)
		(width 0.15494)
		(layer "In13.Cu")
		(net "PRSNT_NIC3_R_N")
	)
	(segment
		(start 355.2952 -233.425746)
		(end 354.05568 -234.665266)
		(width 0.15494)
		(layer "In13.Cu")
		(net "PRSNT_NIC3_R_N")
	)
	(segment
		(start 237.027974 -245.61292)
		(end 235.128054 -243.713)
		(width 0.15494)
		(layer "In13.Cu")
		(net "PRSNT_NIC3_R_N")
	)
	(segment
		(start 345.30284 -242.04168)
		(end 339.15096 -248.19356)
		(width 0.15494)
		(layer "In13.Cu")
		(net "PRSNT_NIC3_R_N")
	)
	(segment
		(start 355.019356 -225.899472)
		(end 355.019356 -231.422702)
		(width 0.15494)
		(layer "In13.Cu")
		(net "PRSNT_NIC3_R_N")
	)
	(segment
		(start 329.96886 -249.779536)
		(end 304.127916 -249.779536)
		(width 0.15494)
		(layer "In13.Cu")
		(net "PRSNT_NIC3_R_N")
	)
	(segment
		(start 251.871988 -246.360188)
		(end 250.4694 -244.9576)
		(width 0.15494)
		(layer "In13.Cu")
		(net "PRSNT_NIC3_R_N")
	)
	(segment
		(start 348.481142 -242.04168)
		(end 345.30284 -242.04168)
		(width 0.15494)
		(layer "In13.Cu")
		(net "PRSNT_NIC3_R_N")
	)
	(segment
		(start 275.384006 -248.104152)
		(end 273.640042 -246.360188)
		(width 0.15494)
		(layer "In13.Cu")
		(net "PRSNT_NIC3_R_N")
	)
	(segment
		(start 354.05568 -234.665266)
		(end 354.05568 -236.467142)
		(width 0.15494)
		(layer "In13.Cu")
		(net "PRSNT_NIC3_R_N")
	)
	(segment
		(start 348.893638 -222.786956)
		(end 349.291148 -222.389446)
		(width 0.0889)
		(layer "In13.Cu")
		(net "PRSNT_NIC3_R_N")
	)
	(segment
		(start 355.019356 -231.422702)
		(end 355.2952 -231.698546)
		(width 0.15494)
		(layer "In13.Cu")
		(net "PRSNT_NIC3_R_N")
	)
	(segment
		(start 339.15096 -248.19356)
		(end 334.908906 -248.19356)
		(width 0.15494)
		(layer "In13.Cu")
		(net "PRSNT_NIC3_R_N")
	)
	(segment
		(start 334.908906 -248.19356)
		(end 334.703166 -247.98782)
		(width 0.15494)
		(layer "In13.Cu")
		(net "PRSNT_NIC3_R_N")
	)
	(segment
		(start 355.2952 -231.698546)
		(end 355.2952 -233.425746)
		(width 0.15494)
		(layer "In13.Cu")
		(net "PRSNT_NIC3_R_N")
	)
	(segment
		(start 301.10811 -249.8852)
		(end 299.327062 -248.104152)
		(width 0.15494)
		(layer "In13.Cu")
		(net "PRSNT_NIC3_R_N")
	)
	(segment
		(start 273.640042 -246.360188)
		(end 251.871988 -246.360188)
		(width 0.15494)
		(layer "In13.Cu")
		(net "PRSNT_NIC3_R_N")
	)
	(segment
		(start 231.828594 -243.713)
		(end 231.091994 -244.4496)
		(width 0.15494)
		(layer "In13.Cu")
		(net "PRSNT_NIC3_R_N")
	)
	(segment
		(start 235.128054 -243.713)
		(end 231.828594 -243.713)
		(width 0.15494)
		(layer "In13.Cu")
		(net "PRSNT_NIC3_R_N")
	)
	(segment
		(start 250.4694 -244.9576)
		(end 239.04067 -244.9576)
		(width 0.15494)
		(layer "In13.Cu")
		(net "PRSNT_NIC3_R_N")
	)
	(segment
		(start 304.127916 -249.779536)
		(end 304.022252 -249.8852)
		(width 0.15494)
		(layer "In13.Cu")
		(net "PRSNT_NIC3_R_N")
	)
	(segment
		(start 331.760576 -247.98782)
		(end 329.96886 -249.779536)
		(width 0.15494)
		(layer "In13.Cu")
		(net "PRSNT_NIC3_R_N")
	)
	(segment
		(start 304.022252 -249.8852)
		(end 301.10811 -249.8852)
		(width 0.15494)
		(layer "In13.Cu")
		(net "PRSNT_NIC3_R_N")
	)
	(segment
		(start 238.38535 -245.61292)
		(end 237.027974 -245.61292)
		(width 0.15494)
		(layer "In13.Cu")
		(net "PRSNT_NIC3_R_N")
	)
	(segment
		(start 349.291148 -222.389446)
		(end 351.50933 -222.389446)
		(width 0.0889)
		(layer "In13.Cu")
		(net "PRSNT_NIC3_R_N")
	)
	(segment
		(start 334.703166 -247.98782)
		(end 331.760576 -247.98782)
		(width 0.15494)
		(layer "In13.Cu")
		(net "PRSNT_NIC3_R_N")
	)
	(segment
		(start 239.04067 -244.9576)
		(end 238.38535 -245.61292)
		(width 0.15494)
		(layer "In13.Cu")
		(net "PRSNT_NIC3_R_N")
	)
	(segment
		(start 354.05568 -236.467142)
		(end 348.481142 -242.04168)
		(width 0.15494)
		(layer "In13.Cu")
		(net "PRSNT_NIC3_R_N")
	)
	(segment
		(start 299.327062 -248.104152)
		(end 275.384006 -248.104152)
		(width 0.15494)
		(layer "In13.Cu")
		(net "PRSNT_NIC3_R_N")
	)
	(segment
		(start 338.47405 -159.766)
		(end 340.36 -159.766)
		(width 0.13208)
		(layer "F.Cu")
		(net "PRSNT_SSD12_FPGA_PCA9555_N")
	)
	(segment
		(start 340.36 -159.766)
		(end 340.512908 -159.613092)
		(width 0.13208)
		(layer "F.Cu")
		(net "PRSNT_SSD12_FPGA_PCA9555_N")
	)
	(segment
		(start 340.512908 -159.613092)
		(end 342.019382 -159.613092)
		(width 0.13208)
		(layer "F.Cu")
		(net "PRSNT_SSD12_FPGA_PCA9555_N")
	)
	(segment
		(start 342.019382 -159.613092)
		(end 343.149936 -159.613092)
		(width 0.13208)
		(layer "F.Cu")
		(net "PRSNT_SSD12_FPGA_PCA9555_N")
	)
	(via
		(at 342.019382 -159.613092)
		(size 0.508)
		(drill 0.254)
		(layers "F.Cu" "B.Cu")
		(net "PRSNT_SSD12_FPGA_PCA9555_N")
	)
	(segment
		(start 148.85162 -114.936524)
		(end 149.297644 -114.4905)
		(width 0.13208)
		(layer "F.Cu")
		(net "PRSNT_NIC2_R_N")
	)
	(segment
		(start 148.417534 -114.936524)
		(end 148.85162 -114.936524)
		(width 0.13208)
		(layer "F.Cu")
		(net "PRSNT_NIC2_R_N")
	)
	(segment
		(start 235.867448 -223.503998)
		(end 235.467652 -223.104202)
		(width 0.13208)
		(layer "F.Cu")
		(net "PRSNT_NIC2_R_N")
	)
	(segment
		(start 153.025348 -116.512594)
		(end 151.859742 -117.6782)
		(width 0.13208)
		(layer "F.Cu")
		(net "PRSNT_NIC2_R_N")
	)
	(segment
		(start 150.169118 -117.6782)
		(end 149.905974 -117.415056)
		(width 0.13208)
		(layer "F.Cu")
		(net "PRSNT_NIC2_R_N")
	)
	(segment
		(start 151.859742 -117.6782)
		(end 150.169118 -117.6782)
		(width 0.13208)
		(layer "F.Cu")
		(net "PRSNT_NIC2_R_N")
	)
	(segment
		(start 149.297644 -114.4905)
		(end 149.905974 -114.4905)
		(width 0.13208)
		(layer "F.Cu")
		(net "PRSNT_NIC2_R_N")
	)
	(segment
		(start 148.417534 -114.936524)
		(end 148.417534 -113.958624)
		(width 0.13208)
		(layer "F.Cu")
		(net "PRSNT_NIC2_R_N")
	)
	(segment
		(start 350.093788 -223.187006)
		(end 350.493584 -223.586802)
		(width 0.13208)
		(layer "F.Cu")
		(net "PRSNT_NIC2_R_N")
	)
	(segment
		(start 149.905974 -117.415056)
		(end 149.905974 -114.4905)
		(width 0.13208)
		(layer "F.Cu")
		(net "PRSNT_NIC2_R_N")
	)
	(via
		(at 237.55477 -244.53215)
		(size 0.508)
		(drill 0.254)
		(layers "F.Cu" "B.Cu")
		(net "PRSNT_NIC2_R_N")
	)
	(via
		(at 350.493584 -223.586802)
		(size 0.4572)
		(drill 0.254)
		(layers "F.Cu" "B.Cu")
		(net "PRSNT_NIC2_R_N")
	)
	(via
		(at 207.779874 -230.567738)
		(size 0.508)
		(drill 0.254)
		(layers "F.Cu" "B.Cu")
		(net "PRSNT_NIC2_R_N")
	)
	(via
		(at 153.025348 -116.512594)
		(size 0.508)
		(drill 0.254)
		(layers "F.Cu" "B.Cu")
		(net "PRSNT_NIC2_R_N")
	)
	(via
		(at 235.867448 -223.503998)
		(size 0.4572)
		(drill 0.254)
		(layers "F.Cu" "B.Cu")
		(net "PRSNT_NIC2_R_N")
	)
	(via
		(at 184.075578 -226.858322)
		(size 0.508)
		(drill 0.254)
		(layers "F.Cu" "B.Cu")
		(net "PRSNT_NIC2_R_N")
	)
	(segment
		(start 235.867448 -223.503998)
		(end 236.559598 -223.503998)
		(width 0.15494)
		(layer "In5.Cu")
		(net "PRSNT_NIC2_R_N")
	)
	(segment
		(start 236.559598 -223.503998)
		(end 237.7948 -224.7392)
		(width 0.15494)
		(layer "In5.Cu")
		(net "PRSNT_NIC2_R_N")
	)
	(segment
		(start 241.140742 -234.443524)
		(end 240.591848 -234.992418)
		(width 0.15494)
		(layer "In5.Cu")
		(net "PRSNT_NIC2_R_N")
	)
	(segment
		(start 238.231426 -229.914704)
		(end 239.342676 -229.914704)
		(width 0.15494)
		(layer "In5.Cu")
		(net "PRSNT_NIC2_R_N")
	)
	(segment
		(start 237.7948 -229.478078)
		(end 238.231426 -229.914704)
		(width 0.15494)
		(layer "In5.Cu")
		(net "PRSNT_NIC2_R_N")
	)
	(segment
		(start 241.140742 -231.71277)
		(end 241.140742 -234.443524)
		(width 0.15494)
		(layer "In5.Cu")
		(net "PRSNT_NIC2_R_N")
	)
	(segment
		(start 237.87227 -244.53215)
		(end 237.55477 -244.53215)
		(width 0.15494)
		(layer "In5.Cu")
		(net "PRSNT_NIC2_R_N")
	)
	(segment
		(start 240.591848 -234.992418)
		(end 240.591848 -239.315498)
		(width 0.15494)
		(layer "In5.Cu")
		(net "PRSNT_NIC2_R_N")
	)
	(segment
		(start 240.591848 -239.315498)
		(end 239.589818 -240.317528)
		(width 0.15494)
		(layer "In5.Cu")
		(net "PRSNT_NIC2_R_N")
	)
	(segment
		(start 239.589818 -240.317528)
		(end 239.589818 -242.814602)
		(width 0.15494)
		(layer "In5.Cu")
		(net "PRSNT_NIC2_R_N")
	)
	(segment
		(start 237.7948 -224.7392)
		(end 237.7948 -229.478078)
		(width 0.15494)
		(layer "In5.Cu")
		(net "PRSNT_NIC2_R_N")
	)
	(segment
		(start 239.589818 -242.814602)
		(end 237.87227 -244.53215)
		(width 0.15494)
		(layer "In5.Cu")
		(net "PRSNT_NIC2_R_N")
	)
	(segment
		(start 239.342676 -229.914704)
		(end 241.140742 -231.71277)
		(width 0.15494)
		(layer "In5.Cu")
		(net "PRSNT_NIC2_R_N")
	)
	(segment
		(start 234.6452 -223.3168)
		(end 234.8484 -223.1136)
		(width 0.0889)
		(layer "In7.Cu")
		(net "PRSNT_NIC2_R_N")
	)
	(segment
		(start 222.100648 -231.1146)
		(end 227.601526 -231.1146)
		(width 0.15494)
		(layer "In7.Cu")
		(net "PRSNT_NIC2_R_N")
	)
	(segment
		(start 234.027726 -224.6884)
		(end 234.5563 -224.6884)
		(width 0.0889)
		(layer "In7.Cu")
		(net "PRSNT_NIC2_R_N")
	)
	(segment
		(start 234.5563 -224.6884)
		(end 234.6452 -224.5995)
		(width 0.0889)
		(layer "In7.Cu")
		(net "PRSNT_NIC2_R_N")
	)
	(segment
		(start 227.601526 -231.1146)
		(end 234.014772 -224.701354)
		(width 0.15494)
		(layer "In7.Cu")
		(net "PRSNT_NIC2_R_N")
	)
	(segment
		(start 235.47705 -223.1136)
		(end 235.867448 -223.503998)
		(width 0.0889)
		(layer "In7.Cu")
		(net "PRSNT_NIC2_R_N")
	)
	(segment
		(start 234.014772 -224.701354)
		(end 234.027726 -224.6884)
		(width 0.0889)
		(layer "In7.Cu")
		(net "PRSNT_NIC2_R_N")
	)
	(segment
		(start 234.6452 -224.5995)
		(end 234.6452 -223.3168)
		(width 0.0889)
		(layer "In7.Cu")
		(net "PRSNT_NIC2_R_N")
	)
	(segment
		(start 234.8484 -223.1136)
		(end 235.47705 -223.1136)
		(width 0.0889)
		(layer "In7.Cu")
		(net "PRSNT_NIC2_R_N")
	)
	(segment
		(start 207.779874 -230.567738)
		(end 221.553786 -230.567738)
		(width 0.15494)
		(layer "In7.Cu")
		(net "PRSNT_NIC2_R_N")
	)
	(segment
		(start 221.553786 -230.567738)
		(end 222.100648 -231.1146)
		(width 0.15494)
		(layer "In7.Cu")
		(net "PRSNT_NIC2_R_N")
	)
	(segment
		(start 158.317438 -148.40585)
		(end 160.090104 -150.178516)
		(width 0.15494)
		(layer "In9.Cu")
		(net "PRSNT_NIC2_R_N")
	)
	(segment
		(start 183.5531 -226.335844)
		(end 184.075578 -226.858322)
		(width 0.15494)
		(layer "In9.Cu")
		(net "PRSNT_NIC2_R_N")
	)
	(segment
		(start 183.006746 -220.500448)
		(end 183.006746 -221.212156)
		(width 0.15494)
		(layer "In9.Cu")
		(net "PRSNT_NIC2_R_N")
	)
	(segment
		(start 153.025348 -116.512594)
		(end 158.317438 -121.804684)
		(width 0.15494)
		(layer "In9.Cu")
		(net "PRSNT_NIC2_R_N")
	)
	(segment
		(start 183.465724 -220.04147)
		(end 183.006746 -220.500448)
		(width 0.15494)
		(layer "In9.Cu")
		(net "PRSNT_NIC2_R_N")
	)
	(segment
		(start 160.090104 -150.178516)
		(end 160.090104 -160.074356)
		(width 0.15494)
		(layer "In9.Cu")
		(net "PRSNT_NIC2_R_N")
	)
	(segment
		(start 183.5531 -221.75851)
		(end 183.5531 -226.335844)
		(width 0.15494)
		(layer "In9.Cu")
		(net "PRSNT_NIC2_R_N")
	)
	(segment
		(start 158.317438 -121.804684)
		(end 158.317438 -148.40585)
		(width 0.15494)
		(layer "In9.Cu")
		(net "PRSNT_NIC2_R_N")
	)
	(segment
		(start 160.090104 -160.074356)
		(end 162.42919 -171.833286)
		(width 0.15494)
		(layer "In9.Cu")
		(net "PRSNT_NIC2_R_N")
	)
	(segment
		(start 183.006746 -221.212156)
		(end 183.5531 -221.75851)
		(width 0.15494)
		(layer "In9.Cu")
		(net "PRSNT_NIC2_R_N")
	)
	(segment
		(start 183.465724 -208.856072)
		(end 183.465724 -220.04147)
		(width 0.15494)
		(layer "In9.Cu")
		(net "PRSNT_NIC2_R_N")
	)
	(segment
		(start 173.73346 -199.123808)
		(end 183.465724 -208.856072)
		(width 0.15494)
		(layer "In9.Cu")
		(net "PRSNT_NIC2_R_N")
	)
	(segment
		(start 162.42919 -171.833286)
		(end 173.73346 -199.123808)
		(width 0.15494)
		(layer "In9.Cu")
		(net "PRSNT_NIC2_R_N")
	)
	(segment
		(start 354.150676 -226.402392)
		(end 351.732596 -223.984312)
		(width 0.15494)
		(layer "In13.Cu")
		(net "PRSNT_NIC2_R_N")
	)
	(segment
		(start 350.891094 -223.984312)
		(end 350.493584 -223.586802)
		(width 0.0889)
		(layer "In13.Cu")
		(net "PRSNT_NIC2_R_N")
	)
	(segment
		(start 338.85378 -247.47728)
		(end 345.00566 -241.3254)
		(width 0.15494)
		(layer "In13.Cu")
		(net "PRSNT_NIC2_R_N")
	)
	(segment
		(start 207.779874 -230.567738)
		(end 205.716632 -228.504496)
		(width 0.15494)
		(layer "In13.Cu")
		(net "PRSNT_NIC2_R_N")
	)
	(segment
		(start 275.643086 -247.245632)
		(end 299.682662 -247.245632)
		(width 0.15494)
		(layer "In13.Cu")
		(net "PRSNT_NIC2_R_N")
	)
	(segment
		(start 185.721752 -228.504496)
		(end 184.075578 -226.858322)
		(width 0.15494)
		(layer "In13.Cu")
		(net "PRSNT_NIC2_R_N")
	)
	(segment
		(start 353.3394 -236.169962)
		(end 353.3394 -232.3592)
		(width 0.15494)
		(layer "In13.Cu")
		(net "PRSNT_NIC2_R_N")
	)
	(segment
		(start 301.25543 -248.8184)
		(end 303.906682 -248.8184)
		(width 0.15494)
		(layer "In13.Cu")
		(net "PRSNT_NIC2_R_N")
	)
	(segment
		(start 351.732596 -223.984312)
		(end 350.891094 -223.984312)
		(width 0.0889)
		(layer "In13.Cu")
		(net "PRSNT_NIC2_R_N")
	)
	(segment
		(start 353.3394 -232.3592)
		(end 354.120196 -231.578404)
		(width 0.15494)
		(layer "In13.Cu")
		(net "PRSNT_NIC2_R_N")
	)
	(segment
		(start 237.55477 -244.53215)
		(end 237.932976 -244.15496)
		(width 0.15494)
		(layer "In13.Cu")
		(net "PRSNT_NIC2_R_N")
	)
	(segment
		(start 251.01296 -244.15496)
		(end 252.501908 -245.643908)
		(width 0.15494)
		(layer "In13.Cu")
		(net "PRSNT_NIC2_R_N")
	)
	(segment
		(start 274.041362 -245.643908)
		(end 275.643086 -247.245632)
		(width 0.15494)
		(layer "In13.Cu")
		(net "PRSNT_NIC2_R_N")
	)
	(segment
		(start 345.00566 -241.3254)
		(end 348.183962 -241.3254)
		(width 0.15494)
		(layer "In13.Cu")
		(net "PRSNT_NIC2_R_N")
	)
	(segment
		(start 331.348588 -247.27154)
		(end 335.000346 -247.27154)
		(width 0.15494)
		(layer "In13.Cu")
		(net "PRSNT_NIC2_R_N")
	)
	(segment
		(start 205.716632 -228.504496)
		(end 185.721752 -228.504496)
		(width 0.15494)
		(layer "In13.Cu")
		(net "PRSNT_NIC2_R_N")
	)
	(segment
		(start 354.120196 -227.182172)
		(end 354.150676 -227.151692)
		(width 0.15494)
		(layer "In13.Cu")
		(net "PRSNT_NIC2_R_N")
	)
	(segment
		(start 252.501908 -245.643908)
		(end 274.041362 -245.643908)
		(width 0.15494)
		(layer "In13.Cu")
		(net "PRSNT_NIC2_R_N")
	)
	(segment
		(start 330.335128 -248.285)
		(end 331.348588 -247.27154)
		(width 0.15494)
		(layer "In13.Cu")
		(net "PRSNT_NIC2_R_N")
	)
	(segment
		(start 304.440082 -248.285)
		(end 330.335128 -248.285)
		(width 0.15494)
		(layer "In13.Cu")
		(net "PRSNT_NIC2_R_N")
	)
	(segment
		(start 348.183962 -241.3254)
		(end 353.3394 -236.169962)
		(width 0.15494)
		(layer "In13.Cu")
		(net "PRSNT_NIC2_R_N")
	)
	(segment
		(start 303.906682 -248.8184)
		(end 304.440082 -248.285)
		(width 0.15494)
		(layer "In13.Cu")
		(net "PRSNT_NIC2_R_N")
	)
	(segment
		(start 354.150676 -227.151692)
		(end 354.150676 -226.402392)
		(width 0.15494)
		(layer "In13.Cu")
		(net "PRSNT_NIC2_R_N")
	)
	(segment
		(start 299.682662 -247.245632)
		(end 301.25543 -248.8184)
		(width 0.15494)
		(layer "In13.Cu")
		(net "PRSNT_NIC2_R_N")
	)
	(segment
		(start 354.120196 -231.578404)
		(end 354.120196 -227.182172)
		(width 0.15494)
		(layer "In13.Cu")
		(net "PRSNT_NIC2_R_N")
	)
	(segment
		(start 237.932976 -244.15496)
		(end 251.01296 -244.15496)
		(width 0.15494)
		(layer "In13.Cu")
		(net "PRSNT_NIC2_R_N")
	)
	(segment
		(start 335.206086 -247.47728)
		(end 338.85378 -247.47728)
		(width 0.15494)
		(layer "In13.Cu")
		(net "PRSNT_NIC2_R_N")
	)
	(segment
		(start 335.000346 -247.27154)
		(end 335.206086 -247.47728)
		(width 0.15494)
		(layer "In13.Cu")
		(net "PRSNT_NIC2_R_N")
	)
	(segment
		(start 350.67748 -165.608)
		(end 350.11741 -165.04793)
		(width 0.13208)
		(layer "F.Cu")
		(net "PRSNT_NIC5_FPGA_PCA9555_N")
	)
	(segment
		(start 350.11741 -165.38067)
		(end 349.881952 -165.616128)
		(width 0.13208)
		(layer "F.Cu")
		(net "PRSNT_NIC5_FPGA_PCA9555_N")
	)
	(segment
		(start 349.881952 -165.616128)
		(end 349.000064 -165.616128)
		(width 0.13208)
		(layer "F.Cu")
		(net "PRSNT_NIC5_FPGA_PCA9555_N")
	)
	(segment
		(start 353.42195 -165.608)
		(end 350.67748 -165.608)
		(width 0.13208)
		(layer "F.Cu")
		(net "PRSNT_NIC5_FPGA_PCA9555_N")
	)
	(segment
		(start 350.11741 -165.04793)
		(end 350.11741 -165.38067)
		(width 0.13208)
		(layer "F.Cu")
		(net "PRSNT_NIC5_FPGA_PCA9555_N")
	)
	(via
		(at 350.11741 -165.04793)
		(size 0.508)
		(drill 0.254)
		(layers "F.Cu" "B.Cu")
		(net "PRSNT_NIC5_FPGA_PCA9555_N")
	)
	(segment
		(start 226.142804 -210.451192)
		(end 226.293426 -210.30057)
		(width 0.13208)
		(layer "F.Cu")
		(net "JTAG_BIC_NTRST_N")
	)
	(segment
		(start 226.293426 -209.551778)
		(end 226.48926 -209.355944)
		(width 0.13208)
		(layer "F.Cu")
		(net "JTAG_BIC_NTRST_N")
	)
	(segment
		(start 226.667568 -212.235796)
		(end 226.667568 -212.704172)
		(width 0.0889)
		(layer "F.Cu")
		(net "JTAG_BIC_NTRST_N")
	)
	(segment
		(start 226.48926 -208.378806)
		(end 225.530664 -207.42021)
		(width 0.13208)
		(layer "F.Cu")
		(net "JTAG_BIC_NTRST_N")
	)
	(segment
		(start 226.293426 -210.30057)
		(end 226.293426 -209.551778)
		(width 0.13208)
		(layer "F.Cu")
		(net "JTAG_BIC_NTRST_N")
	)
	(segment
		(start 226.8474 -211.450936)
		(end 226.8474 -211.801456)
		(width 0.13208)
		(layer "F.Cu")
		(net "JTAG_BIC_NTRST_N")
	)
	(segment
		(start 226.8474 -211.801456)
		(end 226.667568 -212.235796)
		(width 0.0889)
		(layer "F.Cu")
		(net "JTAG_BIC_NTRST_N")
	)
	(segment
		(start 226.142804 -210.74634)
		(end 226.8474 -211.450936)
		(width 0.13208)
		(layer "F.Cu")
		(net "JTAG_BIC_NTRST_N")
	)
	(segment
		(start 226.142804 -210.451192)
		(end 226.142804 -210.74634)
		(width 0.13208)
		(layer "F.Cu")
		(net "JTAG_BIC_NTRST_N")
	)
	(segment
		(start 226.48926 -209.355944)
		(end 226.48926 -208.378806)
		(width 0.13208)
		(layer "F.Cu")
		(net "JTAG_BIC_NTRST_N")
	)
	(via
		(at 226.142804 -210.451192)
		(size 0.508)
		(drill 0.254)
		(layers "F.Cu" "B.Cu")
		(net "JTAG_BIC_NTRST_N")
	)
	(segment
		(start 87.982298 -305.66487)
		(end 87.982298 -304.611024)
		(width 0.13208)
		(layer "F.Cu")
		(net "SMB_PEX0_SLAVE_SDA")
	)
	(segment
		(start 72.474836 -308.724808)
		(end 72.949816 -309.199788)
		(width 0.13208)
		(layer "F.Cu")
		(net "SMB_PEX0_SLAVE_SDA")
	)
	(via
		(at 72.474836 -308.724808)
		(size 0.4064)
		(drill 0.2032)
		(layers "F.Cu" "B.Cu")
		(net "SMB_PEX0_SLAVE_SDA")
	)
	(via
		(at 87.392256 -305.59121)
		(size 0.6604)
		(drill 0.3302)
		(layers "F.Cu" "B.Cu")
		(net "SMB_PEX0_SLAVE_SDA")
	)
	(via
		(at 87.982298 -304.611024)
		(size 0.508)
		(drill 0.254)
		(layers "F.Cu" "B.Cu")
		(net "SMB_PEX0_SLAVE_SDA")
	)
	(segment
		(start 74.3204 -308.203854)
		(end 74.3204 -308.432454)
		(width 0.13208)
		(layer "B.Cu")
		(net "SMB_PEX0_SLAVE_SDA")
	)
	(segment
		(start 74.70902 -307.815234)
		(end 74.3204 -308.203854)
		(width 0.13208)
		(layer "B.Cu")
		(net "SMB_PEX0_SLAVE_SDA")
	)
	(segment
		(start 87.982298 -304.611024)
		(end 87.842852 -304.75047)
		(width 0.13208)
		(layer "B.Cu")
		(net "SMB_PEX0_SLAVE_SDA")
	)
	(segment
		(start 85.346286 -308.272688)
		(end 85.167978 -308.237128)
		(width 0.13208)
		(layer "B.Cu")
		(net "SMB_PEX0_SLAVE_SDA")
	)
	(segment
		(start 86.80831 -307.295296)
		(end 86.630002 -307.259736)
		(width 0.13208)
		(layer "B.Cu")
		(net "SMB_PEX0_SLAVE_SDA")
	)
	(segment
		(start 87.842852 -304.75047)
		(end 87.842852 -305.140614)
		(width 0.13208)
		(layer "B.Cu")
		(net "SMB_PEX0_SLAVE_SDA")
	)
	(segment
		(start 86.630002 -307.259736)
		(end 86.243668 -306.681632)
		(width 0.13208)
		(layer "B.Cu")
		(net "SMB_PEX0_SLAVE_SDA")
	)
	(segment
		(start 85.334348 -307.134768)
		(end 85.18271 -307.236368)
		(width 0.13208)
		(layer "B.Cu")
		(net "SMB_PEX0_SLAVE_SDA")
	)
	(segment
		(start 85.14715 -307.414676)
		(end 85.533484 -307.99278)
		(width 0.13208)
		(layer "B.Cu")
		(net "SMB_PEX0_SLAVE_SDA")
	)
	(segment
		(start 86.995508 -307.015388)
		(end 86.959948 -307.193696)
		(width 0.13208)
		(layer "B.Cu")
		(net "SMB_PEX0_SLAVE_SDA")
	)
	(segment
		(start 86.243668 -306.681632)
		(end 86.06536 -306.646072)
		(width 0.13208)
		(layer "B.Cu")
		(net "SMB_PEX0_SLAVE_SDA")
	)
	(segment
		(start 86.264496 -307.504084)
		(end 86.228936 -307.682392)
		(width 0.13208)
		(layer "B.Cu")
		(net "SMB_PEX0_SLAVE_SDA")
	)
	(segment
		(start 87.392256 -305.59121)
		(end 86.884002 -306.099464)
		(width 0.13208)
		(layer "B.Cu")
		(net "SMB_PEX0_SLAVE_SDA")
	)
	(segment
		(start 85.497924 -308.171088)
		(end 85.346286 -308.272688)
		(width 0.13208)
		(layer "B.Cu")
		(net "SMB_PEX0_SLAVE_SDA")
	)
	(segment
		(start 85.18271 -307.236368)
		(end 85.14715 -307.414676)
		(width 0.13208)
		(layer "B.Cu")
		(net "SMB_PEX0_SLAVE_SDA")
	)
	(segment
		(start 86.077298 -307.783992)
		(end 85.89899 -307.748432)
		(width 0.13208)
		(layer "B.Cu")
		(net "SMB_PEX0_SLAVE_SDA")
	)
	(segment
		(start 85.89899 -307.748432)
		(end 85.512656 -307.170328)
		(width 0.13208)
		(layer "B.Cu")
		(net "SMB_PEX0_SLAVE_SDA")
	)
	(segment
		(start 85.167978 -308.237128)
		(end 84.781644 -307.659024)
		(width 0.13208)
		(layer "B.Cu")
		(net "SMB_PEX0_SLAVE_SDA")
	)
	(segment
		(start 86.644734 -306.258976)
		(end 86.609174 -306.437284)
		(width 0.13208)
		(layer "B.Cu")
		(net "SMB_PEX0_SLAVE_SDA")
	)
	(segment
		(start 85.533484 -307.99278)
		(end 85.497924 -308.171088)
		(width 0.13208)
		(layer "B.Cu")
		(net "SMB_PEX0_SLAVE_SDA")
	)
	(segment
		(start 86.959948 -307.193696)
		(end 86.80831 -307.295296)
		(width 0.13208)
		(layer "B.Cu")
		(net "SMB_PEX0_SLAVE_SDA")
	)
	(segment
		(start 86.06536 -306.646072)
		(end 85.913722 -306.747672)
		(width 0.13208)
		(layer "B.Cu")
		(net "SMB_PEX0_SLAVE_SDA")
	)
	(segment
		(start 86.228936 -307.682392)
		(end 86.077298 -307.783992)
		(width 0.13208)
		(layer "B.Cu")
		(net "SMB_PEX0_SLAVE_SDA")
	)
	(segment
		(start 84.781644 -307.659024)
		(end 84.603336 -307.623464)
		(width 0.13208)
		(layer "B.Cu")
		(net "SMB_PEX0_SLAVE_SDA")
	)
	(segment
		(start 84.316316 -307.815234)
		(end 74.70902 -307.815234)
		(width 0.13208)
		(layer "B.Cu")
		(net "SMB_PEX0_SLAVE_SDA")
	)
	(segment
		(start 85.913722 -306.747672)
		(end 85.878162 -306.92598)
		(width 0.13208)
		(layer "B.Cu")
		(net "SMB_PEX0_SLAVE_SDA")
	)
	(segment
		(start 74.028046 -308.724808)
		(end 72.474836 -308.724808)
		(width 0.13208)
		(layer "B.Cu")
		(net "SMB_PEX0_SLAVE_SDA")
	)
	(segment
		(start 85.512656 -307.170328)
		(end 85.334348 -307.134768)
		(width 0.13208)
		(layer "B.Cu")
		(net "SMB_PEX0_SLAVE_SDA")
	)
	(segment
		(start 85.878162 -306.92598)
		(end 86.264496 -307.504084)
		(width 0.13208)
		(layer "B.Cu")
		(net "SMB_PEX0_SLAVE_SDA")
	)
	(segment
		(start 87.842852 -305.140614)
		(end 87.392256 -305.59121)
		(width 0.13208)
		(layer "B.Cu")
		(net "SMB_PEX0_SLAVE_SDA")
	)
	(segment
		(start 74.3204 -308.432454)
		(end 74.028046 -308.724808)
		(width 0.13208)
		(layer "B.Cu")
		(net "SMB_PEX0_SLAVE_SDA")
	)
	(segment
		(start 86.884002 -306.099464)
		(end 86.644734 -306.258976)
		(width 0.13208)
		(layer "B.Cu")
		(net "SMB_PEX0_SLAVE_SDA")
	)
	(segment
		(start 84.603336 -307.623464)
		(end 84.316316 -307.815234)
		(width 0.13208)
		(layer "B.Cu")
		(net "SMB_PEX0_SLAVE_SDA")
	)
	(segment
		(start 86.609174 -306.437284)
		(end 86.995508 -307.015388)
		(width 0.13208)
		(layer "B.Cu")
		(net "SMB_PEX0_SLAVE_SDA")
	)
	(segment
		(start 331.682344 -167.642286)
		(end 336.31505 -167.642286)
		(width 0.13208)
		(layer "F.Cu")
		(net "SSD11_PEX_PWR_EN_R")
	)
	(segment
		(start 337.293966 -214.387176)
		(end 336.89417 -213.98738)
		(width 0.13208)
		(layer "F.Cu")
		(net "SSD11_PEX_PWR_EN_R")
	)
	(segment
		(start 336.44205 -167.005)
		(end 336.44205 -165.989)
		(width 0.13208)
		(layer "F.Cu")
		(net "SSD11_PEX_PWR_EN_R")
	)
	(segment
		(start 336.31505 -167.642286)
		(end 336.44205 -167.515286)
		(width 0.13208)
		(layer "F.Cu")
		(net "SSD11_PEX_PWR_EN_R")
	)
	(segment
		(start 336.44205 -167.515286)
		(end 336.44205 -167.005)
		(width 0.13208)
		(layer "F.Cu")
		(net "SSD11_PEX_PWR_EN_R")
	)
	(segment
		(start 336.44205 -165.989)
		(end 337.67395 -165.989)
		(width 0.13208)
		(layer "F.Cu")
		(net "SSD11_PEX_PWR_EN_R")
	)
	(via
		(at 331.682344 -167.642286)
		(size 0.508)
		(drill 0.254)
		(layers "F.Cu" "B.Cu")
		(net "SSD11_PEX_PWR_EN_R")
	)
	(via
		(at 336.89417 -213.98738)
		(size 0.4572)
		(drill 0.254)
		(layers "F.Cu" "B.Cu")
		(net "SSD11_PEX_PWR_EN_R")
	)
	(segment
		(start 336.89417 -213.98738)
		(end 336.49158 -213.58479)
		(width 0.0889)
		(layer "In5.Cu")
		(net "SSD11_PEX_PWR_EN_R")
	)
	(segment
		(start 336.49158 -212.217)
		(end 336.49158 -212.02142)
		(width 0.15494)
		(layer "In5.Cu")
		(net "SSD11_PEX_PWR_EN_R")
	)
	(segment
		(start 327.073514 -205.445868)
		(end 327.073514 -202.480418)
		(width 0.15494)
		(layer "In5.Cu")
		(net "SSD11_PEX_PWR_EN_R")
	)
	(segment
		(start 332.568296 -206.91729)
		(end 331.922628 -207.562958)
		(width 0.15494)
		(layer "In5.Cu")
		(net "SSD11_PEX_PWR_EN_R")
	)
	(segment
		(start 331.95641 -167.916352)
		(end 331.682344 -167.642286)
		(width 0.15494)
		(layer "In5.Cu")
		(net "SSD11_PEX_PWR_EN_R")
	)
	(segment
		(start 333.5274 -206.91729)
		(end 332.568296 -206.91729)
		(width 0.15494)
		(layer "In5.Cu")
		(net "SSD11_PEX_PWR_EN_R")
	)
	(segment
		(start 327.073514 -202.480418)
		(end 331.95641 -197.597522)
		(width 0.15494)
		(layer "In5.Cu")
		(net "SSD11_PEX_PWR_EN_R")
	)
	(segment
		(start 336.49158 -213.58479)
		(end 336.49158 -212.217)
		(width 0.0889)
		(layer "In5.Cu")
		(net "SSD11_PEX_PWR_EN_R")
	)
	(segment
		(start 336.49158 -212.02142)
		(end 336.53603 -211.97697)
		(width 0.15494)
		(layer "In5.Cu")
		(net "SSD11_PEX_PWR_EN_R")
	)
	(segment
		(start 331.922628 -207.562958)
		(end 329.190604 -207.562958)
		(width 0.15494)
		(layer "In5.Cu")
		(net "SSD11_PEX_PWR_EN_R")
	)
	(segment
		(start 329.190604 -207.562958)
		(end 327.073514 -205.445868)
		(width 0.15494)
		(layer "In5.Cu")
		(net "SSD11_PEX_PWR_EN_R")
	)
	(segment
		(start 331.95641 -197.597522)
		(end 331.95641 -167.916352)
		(width 0.15494)
		(layer "In5.Cu")
		(net "SSD11_PEX_PWR_EN_R")
	)
	(segment
		(start 336.53603 -211.97697)
		(end 336.53603 -209.92592)
		(width 0.15494)
		(layer "In5.Cu")
		(net "SSD11_PEX_PWR_EN_R")
	)
	(segment
		(start 336.53603 -209.92592)
		(end 333.5274 -206.91729)
		(width 0.15494)
		(layer "In5.Cu")
		(net "SSD11_PEX_PWR_EN_R")
	)
	(segment
		(start 340.992206 -168.315894)
		(end 343.149936 -168.315894)
		(width 0.13208)
		(layer "F.Cu")
		(net "PRSNT_SSD11_FPGA_PCA9555_N")
	)
	(segment
		(start 340.179406 -167.503094)
		(end 340.992206 -168.315894)
		(width 0.13208)
		(layer "F.Cu")
		(net "PRSNT_SSD11_FPGA_PCA9555_N")
	)
	(segment
		(start 339.681312 -167.005)
		(end 340.179406 -167.503094)
		(width 0.13208)
		(layer "F.Cu")
		(net "PRSNT_SSD11_FPGA_PCA9555_N")
	)
	(segment
		(start 338.47405 -167.005)
		(end 339.681312 -167.005)
		(width 0.13208)
		(layer "F.Cu")
		(net "PRSNT_SSD11_FPGA_PCA9555_N")
	)
	(via
		(at 340.179406 -167.503094)
		(size 0.508)
		(drill 0.254)
		(layers "F.Cu" "B.Cu")
		(net "PRSNT_SSD11_FPGA_PCA9555_N")
	)
	(segment
		(start 228.904292 -183.232044)
		(end 229.499922 -183.827674)
		(width 0.13208)
		(layer "F.Cu")
		(net "RST_BJT_Q15_C")
	)
	(segment
		(start 230.460296 -181.969156)
		(end 230.552244 -182.061104)
		(width 0.13208)
		(layer "F.Cu")
		(net "RST_BJT_Q15_C")
	)
	(segment
		(start 230.552244 -183.515508)
		(end 230.552244 -182.61838)
		(width 0.13208)
		(layer "F.Cu")
		(net "RST_BJT_Q15_C")
	)
	(segment
		(start 230.552244 -182.061104)
		(end 230.552244 -182.61838)
		(width 0.13208)
		(layer "F.Cu")
		(net "RST_BJT_Q15_C")
	)
	(segment
		(start 230.460296 -181.23154)
		(end 230.460296 -181.969156)
		(width 0.13208)
		(layer "F.Cu")
		(net "RST_BJT_Q15_C")
	)
	(segment
		(start 228.904292 -182.61838)
		(end 228.904292 -183.232044)
		(width 0.13208)
		(layer "F.Cu")
		(net "RST_BJT_Q15_C")
	)
	(segment
		(start 229.499922 -183.827674)
		(end 230.240078 -183.827674)
		(width 0.13208)
		(layer "F.Cu")
		(net "RST_BJT_Q15_C")
	)
	(segment
		(start 230.240078 -183.827674)
		(end 230.552244 -183.515508)
		(width 0.13208)
		(layer "F.Cu")
		(net "RST_BJT_Q15_C")
	)
	(via
		(at 230.240078 -183.827674)
		(size 0.762)
		(drill 0.381)
		(layers "F.Cu" "B.Cu")
		(net "RST_BJT_Q15_C")
	)
	(segment
		(start 220.493844 -96.901)
		(end 220.493844 -96.53905)
		(width 0.13208)
		(layer "F.Cu")
		(net "SMB_NIC3_ADC_SCL")
	)
	(segment
		(start 220.348302 -101.491542)
		(end 220.620844 -101.219)
		(width 0.13208)
		(layer "F.Cu")
		(net "SMB_NIC3_ADC_SCL")
	)
	(segment
		(start 220.620844 -101.219)
		(end 220.874844 -100.965)
		(width 0.13208)
		(layer "F.Cu")
		(net "SMB_NIC3_ADC_SCL")
	)
	(segment
		(start 219.903802 -101.491542)
		(end 220.348302 -101.491542)
		(width 0.13208)
		(layer "F.Cu")
		(net "SMB_NIC3_ADC_SCL")
	)
	(segment
		(start 220.874844 -97.282)
		(end 220.493844 -96.901)
		(width 0.13208)
		(layer "F.Cu")
		(net "SMB_NIC3_ADC_SCL")
	)
	(segment
		(start 220.874844 -100.965)
		(end 220.874844 -97.282)
		(width 0.13208)
		(layer "F.Cu")
		(net "SMB_NIC3_ADC_SCL")
	)
	(via
		(at 220.620844 -101.219)
		(size 0.508)
		(drill 0.254)
		(layers "F.Cu" "B.Cu")
		(net "SMB_NIC3_ADC_SCL")
	)
	(segment
		(start 219.701364 -98.61423)
		(end 220.692472 -98.61423)
		(width 0.13208)
		(layer "B.Cu")
		(net "SMB_NIC3_ADC_SCL")
	)
	(segment
		(start 220.940884 -100.89896)
		(end 220.620844 -101.219)
		(width 0.13208)
		(layer "B.Cu")
		(net "SMB_NIC3_ADC_SCL")
	)
	(segment
		(start 220.692472 -98.61423)
		(end 220.940884 -98.862642)
		(width 0.13208)
		(layer "B.Cu")
		(net "SMB_NIC3_ADC_SCL")
	)
	(segment
		(start 220.940884 -98.862642)
		(end 220.940884 -100.89896)
		(width 0.13208)
		(layer "B.Cu")
		(net "SMB_NIC3_ADC_SCL")
	)
	(segment
		(start 86.24316 -305.011074)
		(end 86.24316 -304.011076)
		(width 0.13208)
		(layer "F.Cu")
		(net "SMB_PEX0_SLAVE_SCL")
	)
	(segment
		(start 72.474836 -306.824888)
		(end 71.999856 -307.299868)
		(width 0.13208)
		(layer "F.Cu")
		(net "SMB_PEX0_SLAVE_SCL")
	)
	(segment
		(start 86.906608 -305.674522)
		(end 86.24316 -305.011074)
		(width 0.13208)
		(layer "F.Cu")
		(net "SMB_PEX0_SLAVE_SCL")
	)
	(via
		(at 86.24316 -304.011076)
		(size 0.508)
		(drill 0.254)
		(layers "F.Cu" "B.Cu")
		(net "SMB_PEX0_SLAVE_SCL")
	)
	(via
		(at 72.474836 -306.824888)
		(size 0.4064)
		(drill 0.2032)
		(layers "F.Cu" "B.Cu")
		(net "SMB_PEX0_SLAVE_SCL")
	)
	(via
		(at 84.709 -305.3588)
		(size 0.6604)
		(drill 0.3302)
		(layers "F.Cu" "B.Cu")
		(net "SMB_PEX0_SLAVE_SCL")
	)
	(segment
		(start 73.477374 -304.982626)
		(end 72.94626 -305.51374)
		(width 0.13208)
		(layer "B.Cu")
		(net "SMB_PEX0_SLAVE_SCL")
	)
	(segment
		(start 84.332826 -304.982626)
		(end 73.477374 -304.982626)
		(width 0.13208)
		(layer "B.Cu")
		(net "SMB_PEX0_SLAVE_SCL")
	)
	(segment
		(start 86.24316 -305.096672)
		(end 85.981032 -305.3588)
		(width 0.13208)
		(layer "B.Cu")
		(net "SMB_PEX0_SLAVE_SCL")
	)
	(segment
		(start 72.94626 -305.51374)
		(end 72.94626 -306.353464)
		(width 0.13208)
		(layer "B.Cu")
		(net "SMB_PEX0_SLAVE_SCL")
	)
	(segment
		(start 84.709 -305.3588)
		(end 84.332826 -304.982626)
		(width 0.13208)
		(layer "B.Cu")
		(net "SMB_PEX0_SLAVE_SCL")
	)
	(segment
		(start 72.94626 -306.353464)
		(end 72.474836 -306.824888)
		(width 0.13208)
		(layer "B.Cu")
		(net "SMB_PEX0_SLAVE_SCL")
	)
	(segment
		(start 86.24316 -304.011076)
		(end 86.24316 -305.096672)
		(width 0.13208)
		(layer "B.Cu")
		(net "SMB_PEX0_SLAVE_SCL")
	)
	(segment
		(start 85.981032 -305.3588)
		(end 84.709 -305.3588)
		(width 0.13208)
		(layer "B.Cu")
		(net "SMB_PEX0_SLAVE_SCL")
	)
	(segment
		(start 340.512908 -170.916092)
		(end 342.019382 -170.916092)
		(width 0.13208)
		(layer "F.Cu")
		(net "PRSNT_SSD10_FPGA_PCA9555_N")
	)
	(segment
		(start 342.019382 -170.916092)
		(end 343.149936 -170.916092)
		(width 0.13208)
		(layer "F.Cu")
		(net "PRSNT_SSD10_FPGA_PCA9555_N")
	)
	(segment
		(start 340.36 -171.069)
		(end 340.512908 -170.916092)
		(width 0.13208)
		(layer "F.Cu")
		(net "PRSNT_SSD10_FPGA_PCA9555_N")
	)
	(segment
		(start 338.47405 -171.069)
		(end 340.36 -171.069)
		(width 0.13208)
		(layer "F.Cu")
		(net "PRSNT_SSD10_FPGA_PCA9555_N")
	)
	(via
		(at 342.019382 -170.916092)
		(size 0.508)
		(drill 0.254)
		(layers "F.Cu" "B.Cu")
		(net "PRSNT_SSD10_FPGA_PCA9555_N")
	)
	(segment
		(start 225.75139 -184.078626)
		(end 225.256344 -183.58358)
		(width 0.13208)
		(layer "F.Cu")
		(net "RST_BJT_Q15_B")
	)
	(segment
		(start 226.904296 -183.56834)
		(end 226.904296 -184.463944)
		(width 0.13208)
		(layer "F.Cu")
		(net "RST_BJT_Q15_B")
	)
	(segment
		(start 225.75139 -184.223914)
		(end 225.75139 -184.078626)
		(width 0.13208)
		(layer "F.Cu")
		(net "RST_BJT_Q15_B")
	)
	(segment
		(start 226.904296 -184.463944)
		(end 226.447858 -184.920382)
		(width 0.13208)
		(layer "F.Cu")
		(net "RST_BJT_Q15_B")
	)
	(segment
		(start 226.447858 -184.920382)
		(end 225.75139 -184.223914)
		(width 0.13208)
		(layer "F.Cu")
		(net "RST_BJT_Q15_B")
	)
	(via
		(at 226.447858 -184.920382)
		(size 0.762)
		(drill 0.381)
		(layers "F.Cu" "B.Cu")
		(net "RST_BJT_Q15_B")
	)
	(segment
		(start 146.098006 -197.2818)
		(end 146.098006 -197.405752)
		(width 0.13208)
		(layer "F.Cu")
		(net "UART_PEX0_CLI_R_RX")
	)
	(segment
		(start 109.0422 -203.7588)
		(end 105.565194 -203.7588)
		(width 0.13208)
		(layer "F.Cu")
		(net "UART_PEX0_CLI_R_RX")
	)
	(segment
		(start 71.7042 -235.290106)
		(end 70.932294 -235.290106)
		(width 0.13208)
		(layer "F.Cu")
		(net "UART_PEX0_CLI_R_RX")
	)
	(segment
		(start 146.098006 -197.405752)
		(end 148.3868 -199.694546)
		(width 0.13208)
		(layer "F.Cu")
		(net "UART_PEX0_CLI_R_RX")
	)
	(segment
		(start 148.3868 -200.98639)
		(end 148.85924 -201.45883)
		(width 0.13208)
		(layer "F.Cu")
		(net "UART_PEX0_CLI_R_RX")
	)
	(segment
		(start 110.2614 -202.5396)
		(end 109.0422 -203.7588)
		(width 0.13208)
		(layer "F.Cu")
		(net "UART_PEX0_CLI_R_RX")
	)
	(segment
		(start 105.565194 -203.7588)
		(end 104.6734 -202.867006)
		(width 0.13208)
		(layer "F.Cu")
		(net "UART_PEX0_CLI_R_RX")
	)
	(segment
		(start 148.3868 -199.694546)
		(end 148.3868 -200.860914)
		(width 0.13208)
		(layer "F.Cu")
		(net "UART_PEX0_CLI_R_RX")
	)
	(segment
		(start 148.3868 -200.860914)
		(end 148.3868 -200.98639)
		(width 0.13208)
		(layer "F.Cu")
		(net "UART_PEX0_CLI_R_RX")
	)
	(via
		(at 110.2614 -202.5396)
		(size 0.508)
		(drill 0.254)
		(layers "F.Cu" "B.Cu")
		(net "UART_PEX0_CLI_R_RX")
	)
	(via
		(at 148.3868 -200.860914)
		(size 0.762)
		(drill 0.381)
		(layers "F.Cu" "B.Cu")
		(net "UART_PEX0_CLI_R_RX")
	)
	(via
		(at 148.85924 -201.45883)
		(size 0.508)
		(drill 0.254)
		(layers "F.Cu" "B.Cu")
		(net "UART_PEX0_CLI_R_RX")
	)
	(via
		(at 70.932294 -235.290106)
		(size 0.508)
		(drill 0.254)
		(layers "F.Cu" "B.Cu")
		(net "UART_PEX0_CLI_R_RX")
	)
	(segment
		(start 110.2614 -201.3712)
		(end 107.6452 -198.755)
		(width 0.13208)
		(layer "B.Cu")
		(net "UART_PEX0_CLI_R_RX")
	)
	(segment
		(start 103.0732 -198.755)
		(end 102.36073 -199.46747)
		(width 0.13208)
		(layer "B.Cu")
		(net "UART_PEX0_CLI_R_RX")
	)
	(segment
		(start 68.8594 -226.0346)
		(end 68.8594 -231.723946)
		(width 0.13208)
		(layer "B.Cu")
		(net "UART_PEX0_CLI_R_RX")
	)
	(segment
		(start 102.36073 -203.81087)
		(end 98.2218 -207.9498)
		(width 0.13208)
		(layer "B.Cu")
		(net "UART_PEX0_CLI_R_RX")
	)
	(segment
		(start 148.85924 -202.466194)
		(end 148.85924 -201.45883)
		(width 0.13208)
		(layer "B.Cu")
		(net "UART_PEX0_CLI_R_RX")
	)
	(segment
		(start 146.05 -200.66)
		(end 146.05 -205.9432)
		(width 0.13208)
		(layer "B.Cu")
		(net "UART_PEX0_CLI_R_RX")
	)
	(segment
		(start 98.2218 -207.9498)
		(end 91.4654 -207.9498)
		(width 0.13208)
		(layer "B.Cu")
		(net "UART_PEX0_CLI_R_RX")
	)
	(segment
		(start 148.619464 -201.219054)
		(end 148.619464 -199.978264)
		(width 0.13208)
		(layer "B.Cu")
		(net "UART_PEX0_CLI_R_RX")
	)
	(segment
		(start 107.6452 -198.755)
		(end 103.0732 -198.755)
		(width 0.13208)
		(layer "B.Cu")
		(net "UART_PEX0_CLI_R_RX")
	)
	(segment
		(start 148.619464 -199.978264)
		(end 148.209 -199.5678)
		(width 0.13208)
		(layer "B.Cu")
		(net "UART_PEX0_CLI_R_RX")
	)
	(segment
		(start 146.05 -205.9432)
		(end 144.907 -207.0862)
		(width 0.13208)
		(layer "B.Cu")
		(net "UART_PEX0_CLI_R_RX")
	)
	(segment
		(start 148.209 -199.5678)
		(end 147.1422 -199.5678)
		(width 0.13208)
		(layer "B.Cu")
		(net "UART_PEX0_CLI_R_RX")
	)
	(segment
		(start 68.8594 -231.723946)
		(end 70.932294 -233.79684)
		(width 0.13208)
		(layer "B.Cu")
		(net "UART_PEX0_CLI_R_RX")
	)
	(segment
		(start 140.7922 -207.0862)
		(end 138.7856 -205.0796)
		(width 0.13208)
		(layer "B.Cu")
		(net "UART_PEX0_CLI_R_RX")
	)
	(segment
		(start 137.883392 -205.0796)
		(end 134.3406 -208.622392)
		(width 0.13208)
		(layer "B.Cu")
		(net "UART_PEX0_CLI_R_RX")
	)
	(segment
		(start 102.36073 -199.46747)
		(end 102.36073 -203.81087)
		(width 0.13208)
		(layer "B.Cu")
		(net "UART_PEX0_CLI_R_RX")
	)
	(segment
		(start 148.85924 -201.45883)
		(end 148.619464 -201.219054)
		(width 0.13208)
		(layer "B.Cu")
		(net "UART_PEX0_CLI_R_RX")
	)
	(segment
		(start 144.907 -207.0862)
		(end 140.7922 -207.0862)
		(width 0.13208)
		(layer "B.Cu")
		(net "UART_PEX0_CLI_R_RX")
	)
	(segment
		(start 132.2832 -210.0326)
		(end 130.7592 -208.5086)
		(width 0.13208)
		(layer "B.Cu")
		(net "UART_PEX0_CLI_R_RX")
	)
	(segment
		(start 138.7856 -205.0796)
		(end 137.883392 -205.0796)
		(width 0.13208)
		(layer "B.Cu")
		(net "UART_PEX0_CLI_R_RX")
	)
	(segment
		(start 125.1966 -208.5086)
		(end 121.031 -204.343)
		(width 0.13208)
		(layer "B.Cu")
		(net "UART_PEX0_CLI_R_RX")
	)
	(segment
		(start 134.3406 -208.622392)
		(end 134.3406 -209.6008)
		(width 0.13208)
		(layer "B.Cu")
		(net "UART_PEX0_CLI_R_RX")
	)
	(segment
		(start 75.8444 -223.5708)
		(end 71.3232 -223.5708)
		(width 0.13208)
		(layer "B.Cu")
		(net "UART_PEX0_CLI_R_RX")
	)
	(segment
		(start 71.3232 -223.5708)
		(end 68.8594 -226.0346)
		(width 0.13208)
		(layer "B.Cu")
		(net "UART_PEX0_CLI_R_RX")
	)
	(segment
		(start 70.932294 -233.79684)
		(end 70.932294 -235.290106)
		(width 0.13208)
		(layer "B.Cu")
		(net "UART_PEX0_CLI_R_RX")
	)
	(segment
		(start 121.031 -204.343)
		(end 112.0648 -204.343)
		(width 0.13208)
		(layer "B.Cu")
		(net "UART_PEX0_CLI_R_RX")
	)
	(segment
		(start 134.3406 -209.6008)
		(end 133.9088 -210.0326)
		(width 0.13208)
		(layer "B.Cu")
		(net "UART_PEX0_CLI_R_RX")
	)
	(segment
		(start 112.0648 -204.343)
		(end 110.2614 -202.5396)
		(width 0.13208)
		(layer "B.Cu")
		(net "UART_PEX0_CLI_R_RX")
	)
	(segment
		(start 110.2614 -202.5396)
		(end 110.2614 -201.3712)
		(width 0.13208)
		(layer "B.Cu")
		(net "UART_PEX0_CLI_R_RX")
	)
	(segment
		(start 133.9088 -210.0326)
		(end 132.2832 -210.0326)
		(width 0.13208)
		(layer "B.Cu")
		(net "UART_PEX0_CLI_R_RX")
	)
	(segment
		(start 147.1422 -199.5678)
		(end 146.05 -200.66)
		(width 0.13208)
		(layer "B.Cu")
		(net "UART_PEX0_CLI_R_RX")
	)
	(segment
		(start 130.7592 -208.5086)
		(end 125.1966 -208.5086)
		(width 0.13208)
		(layer "B.Cu")
		(net "UART_PEX0_CLI_R_RX")
	)
	(segment
		(start 91.4654 -207.9498)
		(end 75.8444 -223.5708)
		(width 0.13208)
		(layer "B.Cu")
		(net "UART_PEX0_CLI_R_RX")
	)
	(segment
		(start 349.881952 -177.554128)
		(end 350.11741 -177.31867)
		(width 0.13208)
		(layer "F.Cu")
		(net "PRSNT_NIC4_FPGA_PCA9555_N")
	)
	(segment
		(start 350.11741 -176.98593)
		(end 350.67748 -177.546)
		(width 0.13208)
		(layer "F.Cu")
		(net "PRSNT_NIC4_FPGA_PCA9555_N")
	)
	(segment
		(start 350.67748 -177.546)
		(end 353.42195 -177.546)
		(width 0.13208)
		(layer "F.Cu")
		(net "PRSNT_NIC4_FPGA_PCA9555_N")
	)
	(segment
		(start 349.000064 -177.554128)
		(end 349.881952 -177.554128)
		(width 0.13208)
		(layer "F.Cu")
		(net "PRSNT_NIC4_FPGA_PCA9555_N")
	)
	(segment
		(start 350.11741 -177.31867)
		(end 350.11741 -176.98593)
		(width 0.13208)
		(layer "F.Cu")
		(net "PRSNT_NIC4_FPGA_PCA9555_N")
	)
	(via
		(at 350.11741 -176.98593)
		(size 0.508)
		(drill 0.254)
		(layers "F.Cu" "B.Cu")
		(net "PRSNT_NIC4_FPGA_PCA9555_N")
	)
	(segment
		(start 358.41305 -210.312)
		(end 359.029 -210.312)
		(width 0.13208)
		(layer "F.Cu")
		(net "PRSNT_NIC5_FPGA_R_N")
	)
	(segment
		(start 354.22205 -165.608)
		(end 354.838 -165.608)
		(width 0.13208)
		(layer "F.Cu")
		(net "PRSNT_NIC5_FPGA_R_N")
	)
	(via
		(at 354.838 -165.608)
		(size 0.508)
		(drill 0.254)
		(layers "F.Cu" "B.Cu")
		(net "PRSNT_NIC5_FPGA_R_N")
	)
	(via
		(at 359.029 -210.312)
		(size 0.508)
		(drill 0.254)
		(layers "F.Cu" "B.Cu")
		(net "PRSNT_NIC5_FPGA_R_N")
	)
	(via
		(at 370.868194 -173.618144)
		(size 0.508)
		(drill 0.254)
		(layers "F.Cu" "B.Cu")
		(net "PRSNT_NIC5_FPGA_R_N")
	)
	(segment
		(start 365.295688 -209.22488)
		(end 367.310924 -207.209644)
		(width 0.15494)
		(layer "In7.Cu")
		(net "PRSNT_NIC5_FPGA_R_N")
	)
	(segment
		(start 359.1306 -210.4136)
		(end 362.25607 -210.4136)
		(width 0.15494)
		(layer "In7.Cu")
		(net "PRSNT_NIC5_FPGA_R_N")
	)
	(segment
		(start 362.25734 -210.41487)
		(end 362.65866 -210.41487)
		(width 0.15494)
		(layer "In7.Cu")
		(net "PRSNT_NIC5_FPGA_R_N")
	)
	(segment
		(start 362.25607 -210.4136)
		(end 362.25734 -210.41487)
		(width 0.15494)
		(layer "In7.Cu")
		(net "PRSNT_NIC5_FPGA_R_N")
	)
	(segment
		(start 372.7704 -186.216798)
		(end 373.20474 -185.782458)
		(width 0.15494)
		(layer "In7.Cu")
		(net "PRSNT_NIC5_FPGA_R_N")
	)
	(segment
		(start 367.8301 -207.209644)
		(end 373.134636 -201.905108)
		(width 0.15494)
		(layer "In7.Cu")
		(net "PRSNT_NIC5_FPGA_R_N")
	)
	(segment
		(start 372.7704 -190.90386)
		(end 372.7704 -186.216798)
		(width 0.15494)
		(layer "In7.Cu")
		(net "PRSNT_NIC5_FPGA_R_N")
	)
	(segment
		(start 373.134636 -201.905108)
		(end 373.134636 -191.268096)
		(width 0.15494)
		(layer "In7.Cu")
		(net "PRSNT_NIC5_FPGA_R_N")
	)
	(segment
		(start 373.20474 -185.782458)
		(end 373.20474 -183.847994)
		(width 0.15494)
		(layer "In7.Cu")
		(net "PRSNT_NIC5_FPGA_R_N")
	)
	(segment
		(start 364.677452 -210.4136)
		(end 365.295688 -209.795364)
		(width 0.15494)
		(layer "In7.Cu")
		(net "PRSNT_NIC5_FPGA_R_N")
	)
	(segment
		(start 365.295688 -209.795364)
		(end 365.295688 -209.22488)
		(width 0.15494)
		(layer "In7.Cu")
		(net "PRSNT_NIC5_FPGA_R_N")
	)
	(segment
		(start 367.310924 -207.209644)
		(end 367.8301 -207.209644)
		(width 0.15494)
		(layer "In7.Cu")
		(net "PRSNT_NIC5_FPGA_R_N")
	)
	(segment
		(start 359.029 -210.312)
		(end 359.1306 -210.4136)
		(width 0.15494)
		(layer "In7.Cu")
		(net "PRSNT_NIC5_FPGA_R_N")
	)
	(segment
		(start 372.268242 -175.018192)
		(end 370.868194 -173.618144)
		(width 0.15494)
		(layer "In7.Cu")
		(net "PRSNT_NIC5_FPGA_R_N")
	)
	(segment
		(start 362.65866 -210.41487)
		(end 362.65993 -210.4136)
		(width 0.15494)
		(layer "In7.Cu")
		(net "PRSNT_NIC5_FPGA_R_N")
	)
	(segment
		(start 362.65993 -210.4136)
		(end 364.677452 -210.4136)
		(width 0.15494)
		(layer "In7.Cu")
		(net "PRSNT_NIC5_FPGA_R_N")
	)
	(segment
		(start 372.268242 -182.911496)
		(end 372.268242 -175.018192)
		(width 0.15494)
		(layer "In7.Cu")
		(net "PRSNT_NIC5_FPGA_R_N")
	)
	(segment
		(start 373.134636 -191.268096)
		(end 372.7704 -190.90386)
		(width 0.15494)
		(layer "In7.Cu")
		(net "PRSNT_NIC5_FPGA_R_N")
	)
	(segment
		(start 373.20474 -183.847994)
		(end 372.268242 -182.911496)
		(width 0.15494)
		(layer "In7.Cu")
		(net "PRSNT_NIC5_FPGA_R_N")
	)
	(segment
		(start 358.098852 -168.1988)
		(end 364.95863 -175.058578)
		(width 0.15494)
		(layer "In13.Cu")
		(net "PRSNT_NIC5_FPGA_R_N")
	)
	(segment
		(start 355.378766 -166.935912)
		(end 356.641654 -168.1988)
		(width 0.15494)
		(layer "In13.Cu")
		(net "PRSNT_NIC5_FPGA_R_N")
	)
	(segment
		(start 364.95863 -175.058578)
		(end 369.42776 -175.058578)
		(width 0.15494)
		(layer "In13.Cu")
		(net "PRSNT_NIC5_FPGA_R_N")
	)
	(segment
		(start 356.641654 -168.1988)
		(end 358.098852 -168.1988)
		(width 0.15494)
		(layer "In13.Cu")
		(net "PRSNT_NIC5_FPGA_R_N")
	)
	(segment
		(start 369.42776 -175.058578)
		(end 370.868194 -173.618144)
		(width 0.15494)
		(layer "In13.Cu")
		(net "PRSNT_NIC5_FPGA_R_N")
	)
	(segment
		(start 355.378766 -166.148766)
		(end 355.378766 -166.935912)
		(width 0.15494)
		(layer "In13.Cu")
		(net "PRSNT_NIC5_FPGA_R_N")
	)
	(segment
		(start 354.838 -165.608)
		(end 355.378766 -166.148766)
		(width 0.15494)
		(layer "In13.Cu")
		(net "PRSNT_NIC5_FPGA_R_N")
	)
	(segment
		(start 279.226772 -45.693838)
		(end 279.645872 -45.693838)
		(width 0.254)
		(layer "F.Cu")
		(net "P12V_SSD9_VIN_N")
	)
	(segment
		(start 278.647398 -45.114464)
		(end 279.226772 -45.693838)
		(width 0.254)
		(layer "F.Cu")
		(net "P12V_SSD9_VIN_N")
	)
	(segment
		(start 277.938484 -44.741592)
		(end 278.274526 -44.741592)
		(width 0.254)
		(layer "F.Cu")
		(net "P12V_SSD9_VIN_N")
	)
	(segment
		(start 278.274526 -44.741592)
		(end 278.647398 -45.114464)
		(width 0.254)
		(layer "F.Cu")
		(net "P12V_SSD9_VIN_N")
	)
	(segment
		(start 276.922484 -44.741592)
		(end 277.938484 -44.741592)
		(width 0.254)
		(layer "F.Cu")
		(net "P12V_SSD9_VIN_N")
	)
	(via
		(at 278.647398 -45.114464)
		(size 0.508)
		(drill 0.254)
		(layers "F.Cu" "B.Cu")
		(net "P12V_SSD9_VIN_N")
	)
	(segment
		(start 338.47405 -178.943)
		(end 339.681312 -178.943)
		(width 0.13208)
		(layer "F.Cu")
		(net "PRSNT_SSD9_FPGA_PCA9555_N")
	)
	(segment
		(start 340.992206 -180.253894)
		(end 343.149936 -180.253894)
		(width 0.13208)
		(layer "F.Cu")
		(net "PRSNT_SSD9_FPGA_PCA9555_N")
	)
	(segment
		(start 339.681312 -178.943)
		(end 340.179406 -179.441094)
		(width 0.13208)
		(layer "F.Cu")
		(net "PRSNT_SSD9_FPGA_PCA9555_N")
	)
	(segment
		(start 340.179406 -179.441094)
		(end 340.992206 -180.253894)
		(width 0.13208)
		(layer "F.Cu")
		(net "PRSNT_SSD9_FPGA_PCA9555_N")
	)
	(via
		(at 340.179406 -179.441094)
		(size 0.508)
		(drill 0.254)
		(layers "F.Cu" "B.Cu")
		(net "PRSNT_SSD9_FPGA_PCA9555_N")
	)
	(segment
		(start 458.3684 -93.986096)
		(end 461.012032 -96.629728)
		(width 0.13208)
		(layer "F.Cu")
		(net "HP_NIC7_EN")
	)
	(segment
		(start 432.16195 -139.13231)
		(end 432.80203 -139.77239)
		(width 0.13208)
		(layer "F.Cu")
		(net "HP_NIC7_EN")
	)
	(segment
		(start 430.41443 -139.734798)
		(end 431.016918 -139.13231)
		(width 0.13208)
		(layer "F.Cu")
		(net "HP_NIC7_EN")
	)
	(segment
		(start 445.32296 -122.04192)
		(end 445.709802 -122.428762)
		(width 0.13208)
		(layer "F.Cu")
		(net "HP_NIC7_EN")
	)
	(segment
		(start 450.330316 -93.986096)
		(end 458.3684 -93.986096)
		(width 0.13208)
		(layer "F.Cu")
		(net "HP_NIC7_EN")
	)
	(segment
		(start 461.012032 -96.629728)
		(end 461.012032 -107.848654)
		(width 0.13208)
		(layer "F.Cu")
		(net "HP_NIC7_EN")
	)
	(segment
		(start 445.0715 -122.04192)
		(end 445.32296 -122.04192)
		(width 0.13208)
		(layer "F.Cu")
		(net "HP_NIC7_EN")
	)
	(segment
		(start 449.452238 -94.864174)
		(end 450.330316 -93.986096)
		(width 0.13208)
		(layer "F.Cu")
		(net "HP_NIC7_EN")
	)
	(segment
		(start 461.722724 -107.848654)
		(end 461.012032 -107.848654)
		(width 0.13208)
		(layer "F.Cu")
		(net "HP_NIC7_EN")
	)
	(segment
		(start 462.2546 -115.709446)
		(end 462.2546 -108.38053)
		(width 0.13208)
		(layer "F.Cu")
		(net "HP_NIC7_EN")
	)
	(segment
		(start 436.55234 -115.400836)
		(end 435.94274 -115.400836)
		(width 0.13208)
		(layer "F.Cu")
		(net "HP_NIC7_EN")
	)
	(segment
		(start 449.974208 -124.079)
		(end 456.650598 -121.313448)
		(width 0.13208)
		(layer "F.Cu")
		(net "HP_NIC7_EN")
	)
	(segment
		(start 431.016918 -139.13231)
		(end 432.16195 -139.13231)
		(width 0.13208)
		(layer "F.Cu")
		(net "HP_NIC7_EN")
	)
	(segment
		(start 462.2546 -108.38053)
		(end 461.722724 -107.848654)
		(width 0.13208)
		(layer "F.Cu")
		(net "HP_NIC7_EN")
	)
	(segment
		(start 447.021712 -124.408946)
		(end 448.919854 -124.408946)
		(width 0.13208)
		(layer "F.Cu")
		(net "HP_NIC7_EN")
	)
	(segment
		(start 456.650598 -121.313448)
		(end 462.2546 -115.709446)
		(width 0.13208)
		(layer "F.Cu")
		(net "HP_NIC7_EN")
	)
	(segment
		(start 449.2498 -124.079)
		(end 449.974208 -124.079)
		(width 0.13208)
		(layer "F.Cu")
		(net "HP_NIC7_EN")
	)
	(segment
		(start 429.775112 -139.734798)
		(end 430.41443 -139.734798)
		(width 0.13208)
		(layer "F.Cu")
		(net "HP_NIC7_EN")
	)
	(segment
		(start 448.919854 -124.408946)
		(end 449.2498 -124.079)
		(width 0.13208)
		(layer "F.Cu")
		(net "HP_NIC7_EN")
	)
	(segment
		(start 446.875662 -123.795028)
		(end 446.875662 -124.262896)
		(width 0.13208)
		(layer "F.Cu")
		(net "HP_NIC7_EN")
	)
	(segment
		(start 446.875662 -123.795028)
		(end 446.123314 -123.795028)
		(width 0.13208)
		(layer "F.Cu")
		(net "HP_NIC7_EN")
	)
	(segment
		(start 445.709802 -122.428762)
		(end 445.709802 -123.381516)
		(width 0.13208)
		(layer "F.Cu")
		(net "HP_NIC7_EN")
	)
	(segment
		(start 432.80203 -139.77239)
		(end 432.80203 -140.050774)
		(width 0.13208)
		(layer "F.Cu")
		(net "HP_NIC7_EN")
	)
	(segment
		(start 445.709802 -123.381516)
		(end 446.123314 -123.795028)
		(width 0.13208)
		(layer "F.Cu")
		(net "HP_NIC7_EN")
	)
	(segment
		(start 446.875662 -124.262896)
		(end 447.021712 -124.408946)
		(width 0.13208)
		(layer "F.Cu")
		(net "HP_NIC7_EN")
	)
	(via
		(at 446.123314 -123.795028)
		(size 0.508)
		(drill 0.254)
		(layers "F.Cu" "B.Cu")
		(net "HP_NIC7_EN")
	)
	(via
		(at 435.94274 -115.400836)
		(size 0.508)
		(drill 0.254)
		(layers "F.Cu" "B.Cu")
		(net "HP_NIC7_EN")
	)
	(via
		(at 429.775112 -139.734798)
		(size 0.508)
		(drill 0.254)
		(layers "F.Cu" "B.Cu")
		(net "HP_NIC7_EN")
	)
	(segment
		(start 440.972702 -120.374918)
		(end 439.312304 -120.374918)
		(width 0.15494)
		(layer "In5.Cu")
		(net "HP_NIC7_EN")
	)
	(segment
		(start 436.757064 -116.21516)
		(end 435.94274 -115.400836)
		(width 0.15494)
		(layer "In5.Cu")
		(net "HP_NIC7_EN")
	)
	(segment
		(start 436.757064 -117.819678)
		(end 436.757064 -116.21516)
		(width 0.15494)
		(layer "In5.Cu")
		(net "HP_NIC7_EN")
	)
	(segment
		(start 439.312304 -120.374918)
		(end 436.757064 -117.819678)
		(width 0.15494)
		(layer "In5.Cu")
		(net "HP_NIC7_EN")
	)
	(segment
		(start 446.123314 -123.795028)
		(end 442.873892 -120.545606)
		(width 0.15494)
		(layer "In5.Cu")
		(net "HP_NIC7_EN")
	)
	(segment
		(start 442.873892 -120.545606)
		(end 441.14339 -120.545606)
		(width 0.15494)
		(layer "In5.Cu")
		(net "HP_NIC7_EN")
	)
	(segment
		(start 441.14339 -120.545606)
		(end 440.972702 -120.374918)
		(width 0.15494)
		(layer "In5.Cu")
		(net "HP_NIC7_EN")
	)
	(segment
		(start 434.06695 -136.391396)
		(end 434.06695 -117.276626)
		(width 0.15494)
		(layer "In7.Cu")
		(net "HP_NIC7_EN")
	)
	(segment
		(start 429.775112 -139.734798)
		(end 430.723548 -139.734798)
		(width 0.15494)
		(layer "In7.Cu")
		(net "HP_NIC7_EN")
	)
	(segment
		(start 430.723548 -139.734798)
		(end 434.06695 -136.391396)
		(width 0.15494)
		(layer "In7.Cu")
		(net "HP_NIC7_EN")
	)
	(segment
		(start 434.06695 -117.276626)
		(end 435.94274 -115.400836)
		(width 0.15494)
		(layer "In7.Cu")
		(net "HP_NIC7_EN")
	)
	(segment
		(start 215.5444 -257.4544)
		(end 214.3506 -258.6482)
		(width 0.13462)
		(layer "F.Cu")
		(net "USB2_BIC_DP")
	)
	(segment
		(start 219.4052 -238.3028)
		(end 218.059 -239.649)
		(width 0.13462)
		(layer "F.Cu")
		(net "USB2_BIC_DP")
	)
	(segment
		(start 123.38431 -365.71682)
		(end 123.29541 -365.62792)
		(width 0.13462)
		(layer "F.Cu")
		(net "USB2_BIC_DP")
	)
	(segment
		(start 220.2434 -236.1438)
		(end 219.4052 -236.982)
		(width 0.13462)
		(layer "F.Cu")
		(net "USB2_BIC_DP")
	)
	(segment
		(start 225.0694 -236.6518)
		(end 224.5614 -236.1438)
		(width 0.13462)
		(layer "F.Cu")
		(net "USB2_BIC_DP")
	)
	(segment
		(start 241.7318 -231.394)
		(end 241.7318 -233.9594)
		(width 0.13462)
		(layer "F.Cu")
		(net "USB2_BIC_DP")
	)
	(segment
		(start 187.154312 -360.545888)
		(end 174.88535 -365.62792)
		(width 0.13462)
		(layer "F.Cu")
		(net "USB2_BIC_DP")
	)
	(segment
		(start 117.96395 -365.62792)
		(end 117.87505 -365.71682)
		(width 0.13462)
		(layer "F.Cu")
		(net "USB2_BIC_DP")
	)
	(segment
		(start 206.293212 -341.406988)
		(end 187.154312 -360.545888)
		(width 0.13462)
		(layer "F.Cu")
		(net "USB2_BIC_DP")
	)
	(segment
		(start 233.067606 -215.904064)
		(end 233.467402 -215.504268)
		(width 0.13462)
		(layer "F.Cu")
		(net "USB2_BIC_DP")
	)
	(segment
		(start 119.35333 -365.62792)
		(end 118.94947 -365.62792)
		(width 0.13462)
		(layer "F.Cu")
		(net "USB2_BIC_DP")
	)
	(segment
		(start 212.1916 -282.557474)
		(end 212.1916 -310.441086)
		(width 0.13462)
		(layer "F.Cu")
		(net "USB2_BIC_DP")
	)
	(segment
		(start 105.946194 -380.498858)
		(end 105.461308 -380.013972)
		(width 0.13462)
		(layer "F.Cu")
		(net "USB2_BIC_DP")
	)
	(segment
		(start 215.1634 -256.1336)
		(end 215.5444 -256.5146)
		(width 0.13462)
		(layer "F.Cu")
		(net "USB2_BIC_DP")
	)
	(segment
		(start 214.5284 -321.524884)
		(end 206.293212 -341.406988)
		(width 0.13462)
		(layer "F.Cu")
		(net "USB2_BIC_DP")
	)
	(segment
		(start 215.1634 -246.253)
		(end 215.1634 -256.1336)
		(width 0.13462)
		(layer "F.Cu")
		(net "USB2_BIC_DP")
	)
	(segment
		(start 122.39879 -365.71682)
		(end 122.30989 -365.62792)
		(width 0.13462)
		(layer "F.Cu")
		(net "USB2_BIC_DP")
	)
	(segment
		(start 241.434366 -228.20122)
		(end 241.434366 -227.489766)
		(width 0.13462)
		(layer "F.Cu")
		(net "USB2_BIC_DP")
	)
	(segment
		(start 123.87707 -365.62792)
		(end 123.78817 -365.71682)
		(width 0.13462)
		(layer "F.Cu")
		(net "USB2_BIC_DP")
	)
	(segment
		(start 118.94947 -365.62792)
		(end 118.86057 -365.71682)
		(width 0.13462)
		(layer "F.Cu")
		(net "USB2_BIC_DP")
	)
	(segment
		(start 119.44223 -365.71682)
		(end 119.35333 -365.62792)
		(width 0.13462)
		(layer "F.Cu")
		(net "USB2_BIC_DP")
	)
	(segment
		(start 240.848388 -225.525838)
		(end 241.143028 -225.231198)
		(width 0.13462)
		(layer "F.Cu")
		(net "USB2_BIC_DP")
	)
	(segment
		(start 218.059 -243.3574)
		(end 215.1634 -246.253)
		(width 0.13462)
		(layer "F.Cu")
		(net "USB2_BIC_DP")
	)
	(segment
		(start 212.1916 -310.441086)
		(end 214.5284 -316.08268)
		(width 0.13462)
		(layer "F.Cu")
		(net "USB2_BIC_DP")
	)
	(segment
		(start 119.84609 -365.71682)
		(end 119.44223 -365.71682)
		(width 0.13462)
		(layer "F.Cu")
		(net "USB2_BIC_DP")
	)
	(segment
		(start 122.30989 -365.62792)
		(end 121.90603 -365.62792)
		(width 0.13462)
		(layer "F.Cu")
		(net "USB2_BIC_DP")
	)
	(segment
		(start 113.993676 -365.62792)
		(end 106.778552 -372.843044)
		(width 0.13462)
		(layer "F.Cu")
		(net "USB2_BIC_DP")
	)
	(segment
		(start 116.88953 -365.71682)
		(end 116.48567 -365.71682)
		(width 0.13462)
		(layer "F.Cu")
		(net "USB2_BIC_DP")
	)
	(segment
		(start 240.919 -236.0168)
		(end 240.284 -236.6518)
		(width 0.13462)
		(layer "F.Cu")
		(net "USB2_BIC_DP")
	)
	(segment
		(start 121.32437 -365.62792)
		(end 120.92051 -365.62792)
		(width 0.13462)
		(layer "F.Cu")
		(net "USB2_BIC_DP")
	)
	(segment
		(start 122.80265 -365.71682)
		(end 122.39879 -365.71682)
		(width 0.13462)
		(layer "F.Cu")
		(net "USB2_BIC_DP")
	)
	(segment
		(start 240.919 -234.7722)
		(end 240.919 -236.0168)
		(width 0.13462)
		(layer "F.Cu")
		(net "USB2_BIC_DP")
	)
	(segment
		(start 219.4052 -236.982)
		(end 219.4052 -238.3028)
		(width 0.13462)
		(layer "F.Cu")
		(net "USB2_BIC_DP")
	)
	(segment
		(start 120.92051 -365.62792)
		(end 120.83161 -365.71682)
		(width 0.13462)
		(layer "F.Cu")
		(net "USB2_BIC_DP")
	)
	(segment
		(start 241.805206 -228.57206)
		(end 241.434366 -228.9429)
		(width 0.13462)
		(layer "F.Cu")
		(net "USB2_BIC_DP")
	)
	(segment
		(start 120.33885 -365.62792)
		(end 119.93499 -365.62792)
		(width 0.13462)
		(layer "F.Cu")
		(net "USB2_BIC_DP")
	)
	(segment
		(start 240.848388 -226.903788)
		(end 240.848388 -225.525838)
		(width 0.13462)
		(layer "F.Cu")
		(net "USB2_BIC_DP")
	)
	(segment
		(start 116.48567 -365.71682)
		(end 116.39677 -365.62792)
		(width 0.13462)
		(layer "F.Cu")
		(net "USB2_BIC_DP")
	)
	(segment
		(start 117.38229 -365.62792)
		(end 116.97843 -365.62792)
		(width 0.13462)
		(layer "F.Cu")
		(net "USB2_BIC_DP")
	)
	(segment
		(start 214.3506 -258.6482)
		(end 214.3506 -277.34514)
		(width 0.13462)
		(layer "F.Cu")
		(net "USB2_BIC_DP")
	)
	(segment
		(start 121.90603 -365.62792)
		(end 121.81713 -365.71682)
		(width 0.13462)
		(layer "F.Cu")
		(net "USB2_BIC_DP")
	)
	(segment
		(start 121.81713 -365.71682)
		(end 121.41327 -365.71682)
		(width 0.13462)
		(layer "F.Cu")
		(net "USB2_BIC_DP")
	)
	(segment
		(start 106.778552 -372.843044)
		(end 106.12755 -373.494046)
		(width 0.13462)
		(layer "F.Cu")
		(net "USB2_BIC_DP")
	)
	(segment
		(start 214.3506 -277.34514)
		(end 212.1916 -282.557474)
		(width 0.13462)
		(layer "F.Cu")
		(net "USB2_BIC_DP")
	)
	(segment
		(start 241.434366 -227.489766)
		(end 240.848388 -226.903788)
		(width 0.13462)
		(layer "F.Cu")
		(net "USB2_BIC_DP")
	)
	(segment
		(start 123.29541 -365.62792)
		(end 122.89155 -365.62792)
		(width 0.13462)
		(layer "F.Cu")
		(net "USB2_BIC_DP")
	)
	(segment
		(start 218.059 -239.649)
		(end 218.059 -243.3574)
		(width 0.13462)
		(layer "F.Cu")
		(net "USB2_BIC_DP")
	)
	(segment
		(start 224.5614 -236.1438)
		(end 220.2434 -236.1438)
		(width 0.13462)
		(layer "F.Cu")
		(net "USB2_BIC_DP")
	)
	(segment
		(start 118.45671 -365.71682)
		(end 118.36781 -365.62792)
		(width 0.13462)
		(layer "F.Cu")
		(net "USB2_BIC_DP")
	)
	(segment
		(start 241.805206 -228.57206)
		(end 241.434366 -228.20122)
		(width 0.13462)
		(layer "F.Cu")
		(net "USB2_BIC_DP")
	)
	(segment
		(start 120.42775 -365.71682)
		(end 120.33885 -365.62792)
		(width 0.13462)
		(layer "F.Cu")
		(net "USB2_BIC_DP")
	)
	(segment
		(start 121.41327 -365.71682)
		(end 121.32437 -365.62792)
		(width 0.13462)
		(layer "F.Cu")
		(net "USB2_BIC_DP")
	)
	(segment
		(start 241.434366 -231.096566)
		(end 241.7318 -231.394)
		(width 0.13462)
		(layer "F.Cu")
		(net "USB2_BIC_DP")
	)
	(segment
		(start 118.86057 -365.71682)
		(end 118.45671 -365.71682)
		(width 0.13462)
		(layer "F.Cu")
		(net "USB2_BIC_DP")
	)
	(segment
		(start 116.97843 -365.62792)
		(end 116.88953 -365.71682)
		(width 0.13462)
		(layer "F.Cu")
		(net "USB2_BIC_DP")
	)
	(segment
		(start 120.83161 -365.71682)
		(end 120.42775 -365.71682)
		(width 0.13462)
		(layer "F.Cu")
		(net "USB2_BIC_DP")
	)
	(segment
		(start 106.12755 -373.494046)
		(end 105.708196 -374.506744)
		(width 0.13462)
		(layer "F.Cu")
		(net "USB2_BIC_DP")
	)
	(segment
		(start 241.434366 -228.9429)
		(end 241.434366 -231.096566)
		(width 0.13462)
		(layer "F.Cu")
		(net "USB2_BIC_DP")
	)
	(segment
		(start 215.5444 -256.5146)
		(end 215.5444 -257.4544)
		(width 0.13462)
		(layer "F.Cu")
		(net "USB2_BIC_DP")
	)
	(segment
		(start 174.88535 -365.62792)
		(end 123.87707 -365.62792)
		(width 0.13462)
		(layer "F.Cu")
		(net "USB2_BIC_DP")
	)
	(segment
		(start 105.708196 -374.889014)
		(end 106.002836 -375.183654)
		(width 0.13462)
		(layer "F.Cu")
		(net "USB2_BIC_DP")
	)
	(segment
		(start 117.87505 -365.71682)
		(end 117.47119 -365.71682)
		(width 0.13462)
		(layer "F.Cu")
		(net "USB2_BIC_DP")
	)
	(segment
		(start 106.385106 -380.498858)
		(end 105.946194 -380.498858)
		(width 0.13462)
		(layer "F.Cu")
		(net "USB2_BIC_DP")
	)
	(segment
		(start 123.78817 -365.71682)
		(end 123.38431 -365.71682)
		(width 0.13462)
		(layer "F.Cu")
		(net "USB2_BIC_DP")
	)
	(segment
		(start 116.39677 -365.62792)
		(end 113.993676 -365.62792)
		(width 0.13462)
		(layer "F.Cu")
		(net "USB2_BIC_DP")
	)
	(segment
		(start 117.47119 -365.71682)
		(end 117.38229 -365.62792)
		(width 0.13462)
		(layer "F.Cu")
		(net "USB2_BIC_DP")
	)
	(segment
		(start 214.5284 -316.08268)
		(end 214.5284 -321.524884)
		(width 0.13462)
		(layer "F.Cu")
		(net "USB2_BIC_DP")
	)
	(segment
		(start 122.89155 -365.62792)
		(end 122.80265 -365.71682)
		(width 0.13462)
		(layer "F.Cu")
		(net "USB2_BIC_DP")
	)
	(segment
		(start 241.7318 -233.9594)
		(end 240.919 -234.7722)
		(width 0.13462)
		(layer "F.Cu")
		(net "USB2_BIC_DP")
	)
	(segment
		(start 119.93499 -365.62792)
		(end 119.84609 -365.71682)
		(width 0.13462)
		(layer "F.Cu")
		(net "USB2_BIC_DP")
	)
	(segment
		(start 105.708196 -374.506744)
		(end 105.708196 -374.889014)
		(width 0.13462)
		(layer "F.Cu")
		(net "USB2_BIC_DP")
	)
	(segment
		(start 118.36781 -365.62792)
		(end 117.96395 -365.62792)
		(width 0.13462)
		(layer "F.Cu")
		(net "USB2_BIC_DP")
	)
	(segment
		(start 240.284 -236.6518)
		(end 225.0694 -236.6518)
		(width 0.13462)
		(layer "F.Cu")
		(net "USB2_BIC_DP")
	)
	(via
		(at 106.002836 -375.183654)
		(size 0.508)
		(drill 0.254)
		(layers "F.Cu" "B.Cu")
		(net "USB2_BIC_DP")
	)
	(via
		(at 106.778552 -372.843044)
		(size 0.4064)
		(drill 0.2032)
		(layers "F.Cu" "B.Cu")
		(net "USB2_BIC_DP")
	)
	(via
		(at 105.461308 -380.013972)
		(size 0.508)
		(drill 0.254)
		(layers "F.Cu" "B.Cu")
		(net "USB2_BIC_DP")
	)
	(segment
		(start 105.702354 -375.484136)
		(end 105.702354 -375.907046)
		(width 0.13462)
		(layer "B.Cu")
		(net "USB2_BIC_DP")
	)
	(segment
		(start 104.373426 -377.235974)
		(end 104.373426 -379.95352)
		(width 0.13462)
		(layer "B.Cu")
		(net "USB2_BIC_DP")
	)
	(segment
		(start 104.373426 -379.95352)
		(end 104.734868 -380.314962)
		(width 0.13462)
		(layer "B.Cu")
		(net "USB2_BIC_DP")
	)
	(segment
		(start 105.702354 -375.907046)
		(end 104.373426 -377.235974)
		(width 0.13462)
		(layer "B.Cu")
		(net "USB2_BIC_DP")
	)
	(segment
		(start 104.734868 -380.314962)
		(end 105.160318 -380.314962)
		(width 0.13462)
		(layer "B.Cu")
		(net "USB2_BIC_DP")
	)
	(segment
		(start 106.002836 -375.183654)
		(end 105.702354 -375.484136)
		(width 0.13462)
		(layer "B.Cu")
		(net "USB2_BIC_DP")
	)
	(segment
		(start 105.160318 -380.314962)
		(end 105.461308 -380.013972)
		(width 0.13462)
		(layer "B.Cu")
		(net "USB2_BIC_DP")
	)
	(segment
		(start 240.852198 -224.940368)
		(end 240.852198 -224.481898)
		(width 0.1651)
		(layer "In5.Cu")
		(net "USB2_BIC_DP")
	)
	(segment
		(start 233.726482 -215.763348)
		(end 233.467402 -215.504268)
		(width 0.1651)
		(layer "In5.Cu")
		(net "USB2_BIC_DP")
	)
	(segment
		(start 236.8804 -216.5858)
		(end 235.7374 -215.4428)
		(width 0.1651)
		(layer "In5.Cu")
		(net "USB2_BIC_DP")
	)
	(segment
		(start 234.14482 -215.4428)
		(end 233.824272 -215.763348)
		(width 0.1651)
		(layer "In5.Cu")
		(net "USB2_BIC_DP")
	)
	(segment
		(start 235.7374 -215.4428)
		(end 234.14482 -215.4428)
		(width 0.1651)
		(layer "In5.Cu")
		(net "USB2_BIC_DP")
	)
	(segment
		(start 241.143028 -225.231198)
		(end 240.852198 -224.940368)
		(width 0.1651)
		(layer "In5.Cu")
		(net "USB2_BIC_DP")
	)
	(segment
		(start 237.216188 -219.100908)
		(end 236.8804 -218.29014)
		(width 0.1651)
		(layer "In5.Cu")
		(net "USB2_BIC_DP")
	)
	(segment
		(start 239.618774 -221.503494)
		(end 237.216188 -219.100908)
		(width 0.1651)
		(layer "In5.Cu")
		(net "USB2_BIC_DP")
	)
	(segment
		(start 233.824272 -215.763348)
		(end 233.726482 -215.763348)
		(width 0.1651)
		(layer "In5.Cu")
		(net "USB2_BIC_DP")
	)
	(segment
		(start 236.8804 -218.29014)
		(end 236.8804 -216.5858)
		(width 0.1651)
		(layer "In5.Cu")
		(net "USB2_BIC_DP")
	)
	(segment
		(start 240.852198 -224.481898)
		(end 239.618774 -221.503494)
		(width 0.1651)
		(layer "In5.Cu")
		(net "USB2_BIC_DP")
	)
	(segment
		(start 283.478986 -45.88891)
		(end 283.285692 -45.695616)
		(width 0.13208)
		(layer "F.Cu")
		(net "SSD9_ADC_A0")
	)
	(segment
		(start 283.285692 -45.35424)
		(end 283.285692 -45.695616)
		(width 0.13208)
		(layer "F.Cu")
		(net "SSD9_ADC_A0")
	)
	(segment
		(start 283.285692 -45.771816)
		(end 282.863544 -46.193964)
		(width 0.13208)
		(layer "F.Cu")
		(net "SSD9_ADC_A0")
	)
	(segment
		(start 284.043628 -45.88891)
		(end 283.478986 -45.88891)
		(width 0.13208)
		(layer "F.Cu")
		(net "SSD9_ADC_A0")
	)
	(segment
		(start 282.863544 -46.193964)
		(end 282.445968 -46.193964)
		(width 0.13208)
		(layer "F.Cu")
		(net "SSD9_ADC_A0")
	)
	(segment
		(start 284.043628 -44.87291)
		(end 284.043628 -45.88891)
		(width 0.13208)
		(layer "F.Cu")
		(net "SSD9_ADC_A0")
	)
	(segment
		(start 283.285692 -45.695616)
		(end 283.285692 -45.771816)
		(width 0.13208)
		(layer "F.Cu")
		(net "SSD9_ADC_A0")
	)
	(via
		(at 283.285692 -45.35424)
		(size 0.508)
		(drill 0.254)
		(layers "F.Cu" "B.Cu")
		(net "SSD9_ADC_A0")
	)
	(segment
		(start 340.36 -183.007)
		(end 340.512908 -182.854092)
		(width 0.13208)
		(layer "F.Cu")
		(net "PRSNT_SSD8_FPGA_PCA9555_N")
	)
	(segment
		(start 342.019382 -182.854092)
		(end 343.149936 -182.854092)
		(width 0.13208)
		(layer "F.Cu")
		(net "PRSNT_SSD8_FPGA_PCA9555_N")
	)
	(segment
		(start 338.47405 -183.007)
		(end 340.36 -183.007)
		(width 0.13208)
		(layer "F.Cu")
		(net "PRSNT_SSD8_FPGA_PCA9555_N")
	)
	(segment
		(start 340.512908 -182.854092)
		(end 342.019382 -182.854092)
		(width 0.13208)
		(layer "F.Cu")
		(net "PRSNT_SSD8_FPGA_PCA9555_N")
	)
	(via
		(at 342.019382 -182.854092)
		(size 0.508)
		(drill 0.254)
		(layers "F.Cu" "B.Cu")
		(net "PRSNT_SSD8_FPGA_PCA9555_N")
	)
	(segment
		(start 231.3686 -232.032556)
		(end 231.3686 -231.79405)
		(width 0.13208)
		(layer "F.Cu")
		(net "SSD11_PWRDIS_BIC_R")
	)
	(segment
		(start 231.807512 -232.471468)
		(end 231.3686 -232.032556)
		(width 0.13208)
		(layer "F.Cu")
		(net "SSD11_PWRDIS_BIC_R")
	)
	(segment
		(start 335.693766 -212.786976)
		(end 335.29397 -212.38718)
		(width 0.13208)
		(layer "F.Cu")
		(net "SSD11_PWRDIS_BIC_R")
	)
	(segment
		(start 232.279952 -232.943908)
		(end 232.279952 -233.439716)
		(width 0.13208)
		(layer "F.Cu")
		(net "SSD11_PWRDIS_BIC_R")
	)
	(segment
		(start 232.279952 -233.439716)
		(end 231.807512 -233.912156)
		(width 0.13208)
		(layer "F.Cu")
		(net "SSD11_PWRDIS_BIC_R")
	)
	(segment
		(start 231.807512 -232.471468)
		(end 232.279952 -232.943908)
		(width 0.13208)
		(layer "F.Cu")
		(net "SSD11_PWRDIS_BIC_R")
	)
	(segment
		(start 231.807512 -233.912156)
		(end 231.807512 -234.327954)
		(width 0.13208)
		(layer "F.Cu")
		(net "SSD11_PWRDIS_BIC_R")
	)
	(via
		(at 231.807512 -232.471468)
		(size 0.508)
		(drill 0.254)
		(layers "F.Cu" "B.Cu")
		(net "SSD11_PWRDIS_BIC_R")
	)
	(via
		(at 335.29397 -212.38718)
		(size 0.4572)
		(drill 0.254)
		(layers "F.Cu" "B.Cu")
		(net "SSD11_PWRDIS_BIC_R")
	)
	(via
		(at 250.423934 -204.50429)
		(size 0.508)
		(drill 0.254)
		(layers "F.Cu" "B.Cu")
		(net "SSD11_PWRDIS_BIC_R")
	)
	(segment
		(start 249.02033 -208.975706)
		(end 249.174 -209.129376)
		(width 0.15494)
		(layer "In7.Cu")
		(net "SSD11_PWRDIS_BIC_R")
	)
	(segment
		(start 245.8974 -216.305384)
		(end 245.8974 -218.550236)
		(width 0.15494)
		(layer "In7.Cu")
		(net "SSD11_PWRDIS_BIC_R")
	)
	(segment
		(start 241.156236 -227.753164)
		(end 237.676182 -227.753164)
		(width 0.15494)
		(layer "In7.Cu")
		(net "SSD11_PWRDIS_BIC_R")
	)
	(segment
		(start 249.7582 -207.58023)
		(end 249.02033 -208.3181)
		(width 0.15494)
		(layer "In7.Cu")
		(net "SSD11_PWRDIS_BIC_R")
	)
	(segment
		(start 231.807512 -231.056688)
		(end 231.807512 -232.471468)
		(width 0.15494)
		(layer "In7.Cu")
		(net "SSD11_PWRDIS_BIC_R")
	)
	(segment
		(start 234.4674 -228.3968)
		(end 231.807512 -231.056688)
		(width 0.15494)
		(layer "In7.Cu")
		(net "SSD11_PWRDIS_BIC_R")
	)
	(segment
		(start 246.45493 -222.45447)
		(end 241.156236 -227.753164)
		(width 0.15494)
		(layer "In7.Cu")
		(net "SSD11_PWRDIS_BIC_R")
	)
	(segment
		(start 246.45493 -219.107766)
		(end 246.45493 -222.45447)
		(width 0.15494)
		(layer "In7.Cu")
		(net "SSD11_PWRDIS_BIC_R")
	)
	(segment
		(start 250.0884 -210.040982)
		(end 250.0884 -213.366858)
		(width 0.15494)
		(layer "In7.Cu")
		(net "SSD11_PWRDIS_BIC_R")
	)
	(segment
		(start 249.183906 -209.129376)
		(end 249.96394 -209.90941)
		(width 0.15494)
		(layer "In7.Cu")
		(net "SSD11_PWRDIS_BIC_R")
	)
	(segment
		(start 247.541796 -214.660988)
		(end 245.8974 -216.305384)
		(width 0.15494)
		(layer "In7.Cu")
		(net "SSD11_PWRDIS_BIC_R")
	)
	(segment
		(start 249.174 -209.129376)
		(end 249.183906 -209.129376)
		(width 0.15494)
		(layer "In7.Cu")
		(net "SSD11_PWRDIS_BIC_R")
	)
	(segment
		(start 237.676182 -227.753164)
		(end 237.032546 -228.3968)
		(width 0.15494)
		(layer "In7.Cu")
		(net "SSD11_PWRDIS_BIC_R")
	)
	(segment
		(start 249.96394 -209.916522)
		(end 250.0884 -210.040982)
		(width 0.15494)
		(layer "In7.Cu")
		(net "SSD11_PWRDIS_BIC_R")
	)
	(segment
		(start 248.79427 -214.660988)
		(end 247.541796 -214.660988)
		(width 0.15494)
		(layer "In7.Cu")
		(net "SSD11_PWRDIS_BIC_R")
	)
	(segment
		(start 250.0884 -213.366858)
		(end 248.79427 -214.660988)
		(width 0.15494)
		(layer "In7.Cu")
		(net "SSD11_PWRDIS_BIC_R")
	)
	(segment
		(start 250.423934 -204.50429)
		(end 250.423934 -204.929232)
		(width 0.15494)
		(layer "In7.Cu")
		(net "SSD11_PWRDIS_BIC_R")
	)
	(segment
		(start 249.7582 -205.594966)
		(end 249.7582 -207.58023)
		(width 0.15494)
		(layer "In7.Cu")
		(net "SSD11_PWRDIS_BIC_R")
	)
	(segment
		(start 249.02033 -208.3181)
		(end 249.02033 -208.975706)
		(width 0.15494)
		(layer "In7.Cu")
		(net "SSD11_PWRDIS_BIC_R")
	)
	(segment
		(start 249.96394 -209.90941)
		(end 249.96394 -209.916522)
		(width 0.15494)
		(layer "In7.Cu")
		(net "SSD11_PWRDIS_BIC_R")
	)
	(segment
		(start 237.032546 -228.3968)
		(end 234.4674 -228.3968)
		(width 0.15494)
		(layer "In7.Cu")
		(net "SSD11_PWRDIS_BIC_R")
	)
	(segment
		(start 250.423934 -204.929232)
		(end 249.7582 -205.594966)
		(width 0.15494)
		(layer "In7.Cu")
		(net "SSD11_PWRDIS_BIC_R")
	)
	(segment
		(start 245.8974 -218.550236)
		(end 246.45493 -219.107766)
		(width 0.15494)
		(layer "In7.Cu")
		(net "SSD11_PWRDIS_BIC_R")
	)
	(segment
		(start 254.008636 -205.3082)
		(end 251.227844 -205.3082)
		(width 0.15494)
		(layer "In15.Cu")
		(net "SSD11_PWRDIS_BIC_R")
	)
	(segment
		(start 283.810202 -214.511128)
		(end 265.255756 -214.511128)
		(width 0.15494)
		(layer "In15.Cu")
		(net "SSD11_PWRDIS_BIC_R")
	)
	(segment
		(start 331.813408 -212.411564)
		(end 331.813408 -211.907628)
		(width 0.15494)
		(layer "In15.Cu")
		(net "SSD11_PWRDIS_BIC_R")
	)
	(segment
		(start 335.29397 -212.38718)
		(end 334.89646 -212.78469)
		(width 0.0889)
		(layer "In15.Cu")
		(net "SSD11_PWRDIS_BIC_R")
	)
	(segment
		(start 264.866628 -214.900256)
		(end 263.189212 -214.900256)
		(width 0.15494)
		(layer "In15.Cu")
		(net "SSD11_PWRDIS_BIC_R")
	)
	(segment
		(start 261.615428 -213.326472)
		(end 261.615428 -212.914992)
		(width 0.15494)
		(layer "In15.Cu")
		(net "SSD11_PWRDIS_BIC_R")
	)
	(segment
		(start 251.227844 -205.3082)
		(end 250.423934 -204.50429)
		(width 0.15494)
		(layer "In15.Cu")
		(net "SSD11_PWRDIS_BIC_R")
	)
	(segment
		(start 333.061818 -212.78469)
		(end 332.860904 -212.985604)
		(width 0.0889)
		(layer "In15.Cu")
		(net "SSD11_PWRDIS_BIC_R")
	)
	(segment
		(start 261.615428 -212.914992)
		(end 254.008636 -205.3082)
		(width 0.15494)
		(layer "In15.Cu")
		(net "SSD11_PWRDIS_BIC_R")
	)
	(segment
		(start 263.189212 -214.900256)
		(end 261.615428 -213.326472)
		(width 0.15494)
		(layer "In15.Cu")
		(net "SSD11_PWRDIS_BIC_R")
	)
	(segment
		(start 288.648648 -209.672682)
		(end 283.810202 -214.511128)
		(width 0.15494)
		(layer "In15.Cu")
		(net "SSD11_PWRDIS_BIC_R")
	)
	(segment
		(start 334.89646 -212.78469)
		(end 333.061818 -212.78469)
		(width 0.0889)
		(layer "In15.Cu")
		(net "SSD11_PWRDIS_BIC_R")
	)
	(segment
		(start 332.860904 -212.985604)
		(end 332.387448 -212.985604)
		(width 0.15494)
		(layer "In15.Cu")
		(net "SSD11_PWRDIS_BIC_R")
	)
	(segment
		(start 329.578462 -209.672682)
		(end 288.648648 -209.672682)
		(width 0.15494)
		(layer "In15.Cu")
		(net "SSD11_PWRDIS_BIC_R")
	)
	(segment
		(start 331.813408 -211.907628)
		(end 329.578462 -209.672682)
		(width 0.15494)
		(layer "In15.Cu")
		(net "SSD11_PWRDIS_BIC_R")
	)
	(segment
		(start 265.255756 -214.511128)
		(end 264.866628 -214.900256)
		(width 0.15494)
		(layer "In15.Cu")
		(net "SSD11_PWRDIS_BIC_R")
	)
	(segment
		(start 332.387448 -212.985604)
		(end 331.813408 -212.411564)
		(width 0.15494)
		(layer "In15.Cu")
		(net "SSD11_PWRDIS_BIC_R")
	)
	(segment
		(start 213.93912 -270.82623)
		(end 214.07628 -270.68907)
		(width 0.13462)
		(layer "F.Cu")
		(net "USB2_BIC_DN")
	)
	(segment
		(start 186.998864 -360.313224)
		(end 206.060548 -341.25154)
		(width 0.13462)
		(layer "F.Cu")
		(net "USB2_BIC_DN")
	)
	(segment
		(start 214.07628 -277.29053)
		(end 214.07628 -272.44929)
		(width 0.13462)
		(layer "F.Cu")
		(net "USB2_BIC_DN")
	)
	(segment
		(start 228.49967 -236.2708)
		(end 228.90353 -236.2708)
		(width 0.13462)
		(layer "F.Cu")
		(net "USB2_BIC_DN")
	)
	(segment
		(start 213.93912 -269.74419)
		(end 214.07628 -269.60703)
		(width 0.13462)
		(layer "F.Cu")
		(net "USB2_BIC_DN")
	)
	(segment
		(start 240.64468 -234.658408)
		(end 241.45748 -233.845608)
		(width 0.13462)
		(layer "F.Cu")
		(net "USB2_BIC_DN")
	)
	(segment
		(start 224.675192 -235.86948)
		(end 225.183192 -236.37748)
		(width 0.13462)
		(layer "F.Cu")
		(net "USB2_BIC_DN")
	)
	(segment
		(start 241.45748 -231.507792)
		(end 241.160046 -231.210358)
		(width 0.13462)
		(layer "F.Cu")
		(net "USB2_BIC_DN")
	)
	(segment
		(start 174.83074 -365.3536)
		(end 186.998864 -360.313224)
		(width 0.13462)
		(layer "F.Cu")
		(net "USB2_BIC_DN")
	)
	(segment
		(start 105.433876 -374.889014)
		(end 105.433876 -374.452134)
		(width 0.13462)
		(layer "F.Cu")
		(net "USB2_BIC_DN")
	)
	(segment
		(start 229.55123 -236.24032)
		(end 229.95509 -236.24032)
		(width 0.13462)
		(layer "F.Cu")
		(net "USB2_BIC_DN")
	)
	(segment
		(start 241.160046 -228.9429)
		(end 240.789206 -228.57206)
		(width 0.13462)
		(layer "F.Cu")
		(net "USB2_BIC_DN")
	)
	(segment
		(start 105.433876 -374.452134)
		(end 105.894886 -373.338598)
		(width 0.13462)
		(layer "F.Cu")
		(net "USB2_BIC_DN")
	)
	(segment
		(start 240.789206 -228.57206)
		(end 241.160046 -228.20122)
		(width 0.13462)
		(layer "F.Cu")
		(net "USB2_BIC_DN")
	)
	(segment
		(start 227.38207 -236.37748)
		(end 227.48367 -236.27588)
		(width 0.13462)
		(layer "F.Cu")
		(net "USB2_BIC_DN")
	)
	(segment
		(start 219.13088 -236.868208)
		(end 220.129608 -235.86948)
		(width 0.13462)
		(layer "F.Cu")
		(net "USB2_BIC_DN")
	)
	(segment
		(start 229.95509 -236.24032)
		(end 230.09225 -236.37748)
		(width 0.13462)
		(layer "F.Cu")
		(net "USB2_BIC_DN")
	)
	(segment
		(start 241.160046 -227.603558)
		(end 240.574068 -227.01758)
		(width 0.13462)
		(layer "F.Cu")
		(net "USB2_BIC_DN")
	)
	(segment
		(start 241.45748 -233.845608)
		(end 241.45748 -231.507792)
		(width 0.13462)
		(layer "F.Cu")
		(net "USB2_BIC_DN")
	)
	(segment
		(start 240.64468 -235.903008)
		(end 240.64468 -234.658408)
		(width 0.13462)
		(layer "F.Cu")
		(net "USB2_BIC_DN")
	)
	(segment
		(start 104.517698 -380.523496)
		(end 105.107232 -380.523496)
		(width 0.13462)
		(layer "F.Cu")
		(net "USB2_BIC_DN")
	)
	(segment
		(start 240.574068 -225.525838)
		(end 240.279428 -225.231198)
		(width 0.13462)
		(layer "F.Cu")
		(net "USB2_BIC_DN")
	)
	(segment
		(start 214.07628 -271.77111)
		(end 214.07628 -271.36725)
		(width 0.13462)
		(layer "F.Cu")
		(net "USB2_BIC_DN")
	)
	(segment
		(start 227.48367 -236.27588)
		(end 227.88753 -236.27588)
		(width 0.13462)
		(layer "F.Cu")
		(net "USB2_BIC_DN")
	)
	(segment
		(start 214.07628 -271.36725)
		(end 213.93912 -271.23009)
		(width 0.13462)
		(layer "F.Cu")
		(net "USB2_BIC_DN")
	)
	(segment
		(start 206.060548 -341.25154)
		(end 214.25408 -321.470274)
		(width 0.13462)
		(layer "F.Cu")
		(net "USB2_BIC_DN")
	)
	(segment
		(start 219.13088 -238.189008)
		(end 219.13088 -236.868208)
		(width 0.13462)
		(layer "F.Cu")
		(net "USB2_BIC_DN")
	)
	(segment
		(start 227.88753 -236.27588)
		(end 227.98913 -236.37748)
		(width 0.13462)
		(layer "F.Cu")
		(net "USB2_BIC_DN")
	)
	(segment
		(start 240.574068 -227.01758)
		(end 240.574068 -225.525838)
		(width 0.13462)
		(layer "F.Cu")
		(net "USB2_BIC_DN")
	)
	(segment
		(start 214.25408 -316.13729)
		(end 211.91728 -310.495696)
		(width 0.13462)
		(layer "F.Cu")
		(net "USB2_BIC_DN")
	)
	(segment
		(start 240.170208 -236.37748)
		(end 240.64468 -235.903008)
		(width 0.13462)
		(layer "F.Cu")
		(net "USB2_BIC_DN")
	)
	(segment
		(start 214.88908 -256.247392)
		(end 214.88908 -246.139208)
		(width 0.13462)
		(layer "F.Cu")
		(net "USB2_BIC_DN")
	)
	(segment
		(start 228.90353 -236.2708)
		(end 229.01021 -236.37748)
		(width 0.13462)
		(layer "F.Cu")
		(net "USB2_BIC_DN")
	)
	(segment
		(start 214.07628 -258.534408)
		(end 215.27008 -257.340608)
		(width 0.13462)
		(layer "F.Cu")
		(net "USB2_BIC_DN")
	)
	(segment
		(start 211.91728 -282.502864)
		(end 214.07628 -277.29053)
		(width 0.13462)
		(layer "F.Cu")
		(net "USB2_BIC_DN")
	)
	(segment
		(start 214.25408 -321.470274)
		(end 214.25408 -316.13729)
		(width 0.13462)
		(layer "F.Cu")
		(net "USB2_BIC_DN")
	)
	(segment
		(start 241.160046 -231.210358)
		(end 241.160046 -228.9429)
		(width 0.13462)
		(layer "F.Cu")
		(net "USB2_BIC_DN")
	)
	(segment
		(start 217.78468 -243.243608)
		(end 217.78468 -239.535208)
		(width 0.13462)
		(layer "F.Cu")
		(net "USB2_BIC_DN")
	)
	(segment
		(start 213.93912 -271.23009)
		(end 213.93912 -270.82623)
		(width 0.13462)
		(layer "F.Cu")
		(net "USB2_BIC_DN")
	)
	(segment
		(start 225.183192 -236.37748)
		(end 227.38207 -236.37748)
		(width 0.13462)
		(layer "F.Cu")
		(net "USB2_BIC_DN")
	)
	(segment
		(start 113.879884 -365.3536)
		(end 174.83074 -365.3536)
		(width 0.13462)
		(layer "F.Cu")
		(net "USB2_BIC_DN")
	)
	(segment
		(start 213.93912 -272.31213)
		(end 213.93912 -271.90827)
		(width 0.13462)
		(layer "F.Cu")
		(net "USB2_BIC_DN")
	)
	(segment
		(start 109.15142 -370.082064)
		(end 113.879884 -365.3536)
		(width 0.13462)
		(layer "F.Cu")
		(net "USB2_BIC_DN")
	)
	(segment
		(start 213.93912 -270.14805)
		(end 213.93912 -269.74419)
		(width 0.13462)
		(layer "F.Cu")
		(net "USB2_BIC_DN")
	)
	(segment
		(start 105.107232 -380.523496)
		(end 105.461308 -380.877572)
		(width 0.13462)
		(layer "F.Cu")
		(net "USB2_BIC_DN")
	)
	(segment
		(start 230.09225 -236.37748)
		(end 240.170208 -236.37748)
		(width 0.13462)
		(layer "F.Cu")
		(net "USB2_BIC_DN")
	)
	(segment
		(start 214.88908 -246.139208)
		(end 217.78468 -243.243608)
		(width 0.13462)
		(layer "F.Cu")
		(net "USB2_BIC_DN")
	)
	(segment
		(start 229.41407 -236.37748)
		(end 229.55123 -236.24032)
		(width 0.13462)
		(layer "F.Cu")
		(net "USB2_BIC_DN")
	)
	(segment
		(start 227.98913 -236.37748)
		(end 228.39299 -236.37748)
		(width 0.13462)
		(layer "F.Cu")
		(net "USB2_BIC_DN")
	)
	(segment
		(start 215.27008 -256.628392)
		(end 214.88908 -256.247392)
		(width 0.13462)
		(layer "F.Cu")
		(net "USB2_BIC_DN")
	)
	(segment
		(start 105.139236 -375.183654)
		(end 105.433876 -374.889014)
		(width 0.13462)
		(layer "F.Cu")
		(net "USB2_BIC_DN")
	)
	(segment
		(start 228.39299 -236.37748)
		(end 228.49967 -236.2708)
		(width 0.13462)
		(layer "F.Cu")
		(net "USB2_BIC_DN")
	)
	(segment
		(start 213.93912 -271.90827)
		(end 214.07628 -271.77111)
		(width 0.13462)
		(layer "F.Cu")
		(net "USB2_BIC_DN")
	)
	(segment
		(start 214.07628 -272.44929)
		(end 213.93912 -272.31213)
		(width 0.13462)
		(layer "F.Cu")
		(net "USB2_BIC_DN")
	)
	(segment
		(start 214.07628 -269.60703)
		(end 214.07628 -258.534408)
		(width 0.13462)
		(layer "F.Cu")
		(net "USB2_BIC_DN")
	)
	(segment
		(start 214.07628 -270.28521)
		(end 213.93912 -270.14805)
		(width 0.13462)
		(layer "F.Cu")
		(net "USB2_BIC_DN")
	)
	(segment
		(start 220.129608 -235.86948)
		(end 224.675192 -235.86948)
		(width 0.13462)
		(layer "F.Cu")
		(net "USB2_BIC_DN")
	)
	(segment
		(start 229.01021 -236.37748)
		(end 229.41407 -236.37748)
		(width 0.13462)
		(layer "F.Cu")
		(net "USB2_BIC_DN")
	)
	(segment
		(start 215.27008 -257.340608)
		(end 215.27008 -256.628392)
		(width 0.13462)
		(layer "F.Cu")
		(net "USB2_BIC_DN")
	)
	(segment
		(start 214.07628 -270.68907)
		(end 214.07628 -270.28521)
		(width 0.13462)
		(layer "F.Cu")
		(net "USB2_BIC_DN")
	)
	(segment
		(start 217.78468 -239.535208)
		(end 219.13088 -238.189008)
		(width 0.13462)
		(layer "F.Cu")
		(net "USB2_BIC_DN")
	)
	(segment
		(start 241.160046 -228.20122)
		(end 241.160046 -227.603558)
		(width 0.13462)
		(layer "F.Cu")
		(net "USB2_BIC_DN")
	)
	(segment
		(start 211.91728 -310.495696)
		(end 211.91728 -282.502864)
		(width 0.13462)
		(layer "F.Cu")
		(net "USB2_BIC_DN")
	)
	(segment
		(start 233.067606 -216.704164)
		(end 233.467402 -216.304368)
		(width 0.13462)
		(layer "F.Cu")
		(net "USB2_BIC_DN")
	)
	(segment
		(start 105.894886 -373.338598)
		(end 109.15142 -370.082064)
		(width 0.13462)
		(layer "F.Cu")
		(net "USB2_BIC_DN")
	)
	(via
		(at 105.139236 -375.183654)
		(size 0.508)
		(drill 0.254)
		(layers "F.Cu" "B.Cu")
		(net "USB2_BIC_DN")
	)
	(via
		(at 105.461308 -380.877572)
		(size 0.508)
		(drill 0.254)
		(layers "F.Cu" "B.Cu")
		(net "USB2_BIC_DN")
	)
	(via
		(at 109.15142 -370.082064)
		(size 0.4064)
		(drill 0.2032)
		(layers "F.Cu" "B.Cu")
		(net "USB2_BIC_DN")
	)
	(segment
		(start 105.160318 -380.576582)
		(end 105.461308 -380.877572)
		(width 0.13462)
		(layer "B.Cu")
		(net "USB2_BIC_DN")
	)
	(segment
		(start 104.099106 -377.122182)
		(end 104.099106 -380.067312)
		(width 0.13462)
		(layer "B.Cu")
		(net "USB2_BIC_DN")
	)
	(segment
		(start 105.139236 -375.183654)
		(end 105.428034 -375.472452)
		(width 0.13462)
		(layer "B.Cu")
		(net "USB2_BIC_DN")
	)
	(segment
		(start 105.428034 -375.472452)
		(end 105.428034 -375.793254)
		(width 0.13462)
		(layer "B.Cu")
		(net "USB2_BIC_DN")
	)
	(segment
		(start 104.099106 -380.067312)
		(end 104.608376 -380.576582)
		(width 0.13462)
		(layer "B.Cu")
		(net "USB2_BIC_DN")
	)
	(segment
		(start 104.608376 -380.576582)
		(end 105.160318 -380.576582)
		(width 0.13462)
		(layer "B.Cu")
		(net "USB2_BIC_DN")
	)
	(segment
		(start 105.428034 -375.793254)
		(end 104.099106 -377.122182)
		(width 0.13462)
		(layer "B.Cu")
		(net "USB2_BIC_DN")
	)
	(segment
		(start 240.570258 -224.538032)
		(end 239.37976 -221.66326)
		(width 0.1651)
		(layer "In5.Cu")
		(net "USB2_BIC_DN")
	)
	(segment
		(start 240.570258 -224.940368)
		(end 240.570258 -224.538032)
		(width 0.1651)
		(layer "In5.Cu")
		(net "USB2_BIC_DN")
	)
	(segment
		(start 239.37976 -221.66326)
		(end 236.977174 -219.260674)
		(width 0.1651)
		(layer "In5.Cu")
		(net "USB2_BIC_DN")
	)
	(segment
		(start 236.977174 -219.260674)
		(end 236.59846 -218.346274)
		(width 0.1651)
		(layer "In5.Cu")
		(net "USB2_BIC_DN")
	)
	(segment
		(start 233.726482 -216.045288)
		(end 233.467402 -216.304368)
		(width 0.1651)
		(layer "In5.Cu")
		(net "USB2_BIC_DN")
	)
	(segment
		(start 240.279428 -225.231198)
		(end 240.570258 -224.940368)
		(width 0.1651)
		(layer "In5.Cu")
		(net "USB2_BIC_DN")
	)
	(segment
		(start 236.59846 -216.70264)
		(end 235.62056 -215.72474)
		(width 0.1651)
		(layer "In5.Cu")
		(net "USB2_BIC_DN")
	)
	(segment
		(start 235.62056 -215.72474)
		(end 234.26166 -215.72474)
		(width 0.1651)
		(layer "In5.Cu")
		(net "USB2_BIC_DN")
	)
	(segment
		(start 234.26166 -215.72474)
		(end 233.941112 -216.045288)
		(width 0.1651)
		(layer "In5.Cu")
		(net "USB2_BIC_DN")
	)
	(segment
		(start 233.941112 -216.045288)
		(end 233.726482 -216.045288)
		(width 0.1651)
		(layer "In5.Cu")
		(net "USB2_BIC_DN")
	)
	(segment
		(start 236.59846 -218.346274)
		(end 236.59846 -216.70264)
		(width 0.1651)
		(layer "In5.Cu")
		(net "USB2_BIC_DN")
	)
	(segment
		(start 225.88347 -204.84211)
		(end 225.530664 -204.84211)
		(width 0.13208)
		(layer "F.Cu")
		(net "JTAG_BIC_NTRST_R_N")
	)
	(segment
		(start 225.39071 -204.84211)
		(end 225.005392 -204.456792)
		(width 0.13208)
		(layer "F.Cu")
		(net "JTAG_BIC_NTRST_R_N")
	)
	(segment
		(start 224.790508 -201.638662)
		(end 224.268284 -201.638662)
		(width 0.13208)
		(layer "F.Cu")
		(net "JTAG_BIC_NTRST_R_N")
	)
	(segment
		(start 222.580962 -202.518264)
		(end 222.580962 -201.733658)
		(width 0.13208)
		(layer "F.Cu")
		(net "JTAG_BIC_NTRST_R_N")
	)
	(segment
		(start 226.01047 -204.96911)
		(end 225.88347 -204.84211)
		(width 0.13208)
		(layer "F.Cu")
		(net "JTAG_BIC_NTRST_R_N")
	)
	(segment
		(start 225.005392 -202.84821)
		(end 225.184462 -202.66914)
		(width 0.13208)
		(layer "F.Cu")
		(net "JTAG_BIC_NTRST_R_N")
	)
	(segment
		(start 226.01047 -205.75778)
		(end 226.01047 -204.96911)
		(width 0.13208)
		(layer "F.Cu")
		(net "JTAG_BIC_NTRST_R_N")
	)
	(segment
		(start 225.184462 -202.032616)
		(end 224.790508 -201.638662)
		(width 0.13208)
		(layer "F.Cu")
		(net "JTAG_BIC_NTRST_R_N")
	)
	(segment
		(start 223.363536 -202.54341)
		(end 222.606108 -202.54341)
		(width 0.13208)
		(layer "F.Cu")
		(net "JTAG_BIC_NTRST_R_N")
	)
	(segment
		(start 225.005392 -204.456792)
		(end 225.005392 -202.84821)
		(width 0.13208)
		(layer "F.Cu")
		(net "JTAG_BIC_NTRST_R_N")
	)
	(segment
		(start 225.530664 -206.62011)
		(end 225.530664 -206.237586)
		(width 0.13208)
		(layer "F.Cu")
		(net "JTAG_BIC_NTRST_R_N")
	)
	(segment
		(start 225.184462 -202.66914)
		(end 225.184462 -202.032616)
		(width 0.13208)
		(layer "F.Cu")
		(net "JTAG_BIC_NTRST_R_N")
	)
	(segment
		(start 224.268284 -201.638662)
		(end 223.363536 -202.54341)
		(width 0.13208)
		(layer "F.Cu")
		(net "JTAG_BIC_NTRST_R_N")
	)
	(segment
		(start 222.606108 -202.54341)
		(end 222.580962 -202.518264)
		(width 0.13208)
		(layer "F.Cu")
		(net "JTAG_BIC_NTRST_R_N")
	)
	(segment
		(start 225.530664 -206.237586)
		(end 226.01047 -205.75778)
		(width 0.13208)
		(layer "F.Cu")
		(net "JTAG_BIC_NTRST_R_N")
	)
	(segment
		(start 225.530664 -204.84211)
		(end 225.39071 -204.84211)
		(width 0.13208)
		(layer "F.Cu")
		(net "JTAG_BIC_NTRST_R_N")
	)
	(via
		(at 222.606108 -202.54341)
		(size 0.508)
		(drill 0.254)
		(layers "F.Cu" "B.Cu")
		(net "JTAG_BIC_NTRST_R_N")
	)
	(segment
		(start 281.915362 -42.853102)
		(end 281.915362 -43.566842)
		(width 0.13208)
		(layer "F.Cu")
		(net "SMB_SSD9_ADC_SDA")
	)
	(segment
		(start 283.135832 -48.30699)
		(end 283.135832 -48.69942)
		(width 0.13208)
		(layer "F.Cu")
		(net "SMB_SSD9_ADC_SDA")
	)
	(segment
		(start 283.373322 -48.93691)
		(end 284.043628 -48.93691)
		(width 0.13208)
		(layer "F.Cu")
		(net "SMB_SSD9_ADC_SDA")
	)
	(segment
		(start 282.445968 -48.076612)
		(end 282.676346 -48.30699)
		(width 0.13208)
		(layer "F.Cu")
		(net "SMB_SSD9_ADC_SDA")
	)
	(segment
		(start 283.135832 -48.69942)
		(end 283.373322 -48.93691)
		(width 0.13208)
		(layer "F.Cu")
		(net "SMB_SSD9_ADC_SDA")
	)
	(segment
		(start 282.676346 -48.30699)
		(end 283.135832 -48.30699)
		(width 0.13208)
		(layer "F.Cu")
		(net "SMB_SSD9_ADC_SDA")
	)
	(segment
		(start 282.445968 -47.193962)
		(end 282.445968 -48.076612)
		(width 0.13208)
		(layer "F.Cu")
		(net "SMB_SSD9_ADC_SDA")
	)
	(via
		(at 283.135832 -48.30699)
		(size 0.508)
		(drill 0.254)
		(layers "F.Cu" "B.Cu")
		(net "SMB_SSD9_ADC_SDA")
	)
	(via
		(at 281.915362 -43.566842)
		(size 0.508)
		(drill 0.254)
		(layers "F.Cu" "B.Cu")
		(net "SMB_SSD9_ADC_SDA")
	)
	(segment
		(start 283.135832 -48.30699)
		(end 282.589224 -47.760382)
		(width 0.15494)
		(layer "In5.Cu")
		(net "SMB_SSD9_ADC_SDA")
	)
	(segment
		(start 282.589224 -47.760382)
		(end 282.589224 -44.240704)
		(width 0.15494)
		(layer "In5.Cu")
		(net "SMB_SSD9_ADC_SDA")
	)
	(segment
		(start 282.589224 -44.240704)
		(end 281.915362 -43.566842)
		(width 0.15494)
		(layer "In5.Cu")
		(net "SMB_SSD9_ADC_SDA")
	)
	(segment
		(start 374.05691 -173.617128)
		(end 374.717056 -172.956982)
		(width 0.13208)
		(layer "F.Cu")
		(net "PRSNT_NIC3_FPGA_PCA9555_N")
	)
	(segment
		(start 372.114064 -173.617128)
		(end 374.05691 -173.617128)
		(width 0.13208)
		(layer "F.Cu")
		(net "PRSNT_NIC3_FPGA_PCA9555_N")
	)
	(segment
		(start 375.556018 -172.11802)
		(end 376.40895 -172.11802)
		(width 0.13208)
		(layer "F.Cu")
		(net "PRSNT_NIC3_FPGA_PCA9555_N")
	)
	(segment
		(start 374.717056 -172.956982)
		(end 375.556018 -172.11802)
		(width 0.13208)
		(layer "F.Cu")
		(net "PRSNT_NIC3_FPGA_PCA9555_N")
	)
	(via
		(at 374.717056 -172.956982)
		(size 0.508)
		(drill 0.254)
		(layers "F.Cu" "B.Cu")
		(net "PRSNT_NIC3_FPGA_PCA9555_N")
	)
	(segment
		(start 354.22205 -177.546)
		(end 354.838 -177.546)
		(width 0.13208)
		(layer "F.Cu")
		(net "PRSNT_NIC4_FPGA_R_N")
	)
	(segment
		(start 358.41305 -211.328)
		(end 359.029 -211.328)
		(width 0.13208)
		(layer "F.Cu")
		(net "PRSNT_NIC4_FPGA_R_N")
	)
	(via
		(at 373.155464 -182.63997)
		(size 0.508)
		(drill 0.254)
		(layers "F.Cu" "B.Cu")
		(net "PRSNT_NIC4_FPGA_R_N")
	)
	(via
		(at 354.838 -177.546)
		(size 0.508)
		(drill 0.254)
		(layers "F.Cu" "B.Cu")
		(net "PRSNT_NIC4_FPGA_R_N")
	)
	(via
		(at 359.029 -211.328)
		(size 0.508)
		(drill 0.254)
		(layers "F.Cu" "B.Cu")
		(net "PRSNT_NIC4_FPGA_R_N")
	)
	(segment
		(start 374.41886 -188.987938)
		(end 374.41886 -183.903366)
		(width 0.15494)
		(layer "In7.Cu")
		(net "PRSNT_NIC4_FPGA_R_N")
	)
	(segment
		(start 361.359196 -211.328)
		(end 361.486196 -211.455)
		(width 0.15494)
		(layer "In7.Cu")
		(net "PRSNT_NIC4_FPGA_R_N")
	)
	(segment
		(start 369.445032 -206.993998)
		(end 369.45951 -206.993998)
		(width 0.15494)
		(layer "In7.Cu")
		(net "PRSNT_NIC4_FPGA_R_N")
	)
	(segment
		(start 361.486196 -211.455)
		(end 364.98403 -211.455)
		(width 0.15494)
		(layer "In7.Cu")
		(net "PRSNT_NIC4_FPGA_R_N")
	)
	(segment
		(start 374.22328 -189.183518)
		(end 374.41886 -188.987938)
		(width 0.15494)
		(layer "In7.Cu")
		(net "PRSNT_NIC4_FPGA_R_N")
	)
	(segment
		(start 373.628412 -202.810618)
		(end 373.628412 -191.173862)
		(width 0.15494)
		(layer "In7.Cu")
		(net "PRSNT_NIC4_FPGA_R_N")
	)
	(segment
		(start 374.41886 -183.903366)
		(end 373.155464 -182.63997)
		(width 0.15494)
		(layer "In7.Cu")
		(net "PRSNT_NIC4_FPGA_R_N")
	)
	(segment
		(start 369.74272 -206.710788)
		(end 369.74272 -206.69631)
		(width 0.15494)
		(layer "In7.Cu")
		(net "PRSNT_NIC4_FPGA_R_N")
	)
	(segment
		(start 374.22328 -190.578994)
		(end 374.22328 -189.183518)
		(width 0.15494)
		(layer "In7.Cu")
		(net "PRSNT_NIC4_FPGA_R_N")
	)
	(segment
		(start 364.98403 -211.455)
		(end 369.445032 -206.993998)
		(width 0.15494)
		(layer "In7.Cu")
		(net "PRSNT_NIC4_FPGA_R_N")
	)
	(segment
		(start 369.74272 -206.69631)
		(end 373.628412 -202.810618)
		(width 0.15494)
		(layer "In7.Cu")
		(net "PRSNT_NIC4_FPGA_R_N")
	)
	(segment
		(start 359.029 -211.328)
		(end 361.359196 -211.328)
		(width 0.15494)
		(layer "In7.Cu")
		(net "PRSNT_NIC4_FPGA_R_N")
	)
	(segment
		(start 373.628412 -191.173862)
		(end 374.22328 -190.578994)
		(width 0.15494)
		(layer "In7.Cu")
		(net "PRSNT_NIC4_FPGA_R_N")
	)
	(segment
		(start 369.45951 -206.993998)
		(end 369.74272 -206.710788)
		(width 0.15494)
		(layer "In7.Cu")
		(net "PRSNT_NIC4_FPGA_R_N")
	)
	(segment
		(start 364.408212 -178.929538)
		(end 364.957106 -179.478432)
		(width 0.15494)
		(layer "In13.Cu")
		(net "PRSNT_NIC4_FPGA_R_N")
	)
	(segment
		(start 357.650034 -178.540918)
		(end 360.724196 -178.540918)
		(width 0.15494)
		(layer "In13.Cu")
		(net "PRSNT_NIC4_FPGA_R_N")
	)
	(segment
		(start 367.065306 -179.478432)
		(end 370.226844 -182.63997)
		(width 0.15494)
		(layer "In13.Cu")
		(net "PRSNT_NIC4_FPGA_R_N")
	)
	(segment
		(start 355.346 -178.054)
		(end 357.163116 -178.054)
		(width 0.15494)
		(layer "In13.Cu")
		(net "PRSNT_NIC4_FPGA_R_N")
	)
	(segment
		(start 364.957106 -179.478432)
		(end 367.065306 -179.478432)
		(width 0.15494)
		(layer "In13.Cu")
		(net "PRSNT_NIC4_FPGA_R_N")
	)
	(segment
		(start 360.724196 -178.540918)
		(end 361.112816 -178.929538)
		(width 0.15494)
		(layer "In13.Cu")
		(net "PRSNT_NIC4_FPGA_R_N")
	)
	(segment
		(start 370.226844 -182.63997)
		(end 373.155464 -182.63997)
		(width 0.15494)
		(layer "In13.Cu")
		(net "PRSNT_NIC4_FPGA_R_N")
	)
	(segment
		(start 354.838 -177.546)
		(end 355.346 -178.054)
		(width 0.15494)
		(layer "In13.Cu")
		(net "PRSNT_NIC4_FPGA_R_N")
	)
	(segment
		(start 361.112816 -178.929538)
		(end 364.408212 -178.929538)
		(width 0.15494)
		(layer "In13.Cu")
		(net "PRSNT_NIC4_FPGA_R_N")
	)
	(segment
		(start 357.163116 -178.054)
		(end 357.650034 -178.540918)
		(width 0.15494)
		(layer "In13.Cu")
		(net "PRSNT_NIC4_FPGA_R_N")
	)
	(segment
		(start 240.950496 -223.673924)
		(end 241.610642 -223.673924)
		(width 0.13208)
		(layer "F.Cu")
		(net "SSD12_PWRDIS_BIC_R")
	)
	(segment
		(start 242.324382 -224.295716)
		(end 242.347496 -224.31883)
		(width 0.13208)
		(layer "F.Cu")
		(net "SSD12_PWRDIS_BIC_R")
	)
	(segment
		(start 240.700306 -223.924114)
		(end 240.950496 -223.673924)
		(width 0.13208)
		(layer "F.Cu")
		(net "SSD12_PWRDIS_BIC_R")
	)
	(segment
		(start 241.90198 -224.304352)
		(end 241.910616 -224.295716)
		(width 0.13208)
		(layer "F.Cu")
		(net "SSD12_PWRDIS_BIC_R")
	)
	(segment
		(start 241.610642 -223.673924)
		(end 241.886994 -223.397572)
		(width 0.13208)
		(layer "F.Cu")
		(net "SSD12_PWRDIS_BIC_R")
	)
	(segment
		(start 337.293966 -215.187022)
		(end 336.89417 -214.787226)
		(width 0.13208)
		(layer "F.Cu")
		(net "SSD12_PWRDIS_BIC_R")
	)
	(segment
		(start 241.130836 -224.304352)
		(end 241.90198 -224.304352)
		(width 0.13208)
		(layer "F.Cu")
		(net "SSD12_PWRDIS_BIC_R")
	)
	(segment
		(start 241.886994 -222.951802)
		(end 242.12296 -222.715836)
		(width 0.13208)
		(layer "F.Cu")
		(net "SSD12_PWRDIS_BIC_R")
	)
	(segment
		(start 241.116104 -224.319084)
		(end 241.130836 -224.304352)
		(width 0.13208)
		(layer "F.Cu")
		(net "SSD12_PWRDIS_BIC_R")
	)
	(segment
		(start 241.910616 -224.295716)
		(end 242.324382 -224.295716)
		(width 0.13208)
		(layer "F.Cu")
		(net "SSD12_PWRDIS_BIC_R")
	)
	(segment
		(start 241.886994 -223.397572)
		(end 241.886994 -222.951802)
		(width 0.13208)
		(layer "F.Cu")
		(net "SSD12_PWRDIS_BIC_R")
	)
	(segment
		(start 240.700306 -224.319084)
		(end 241.116104 -224.319084)
		(width 0.13208)
		(layer "F.Cu")
		(net "SSD12_PWRDIS_BIC_R")
	)
	(segment
		(start 240.700306 -224.319084)
		(end 240.700306 -223.924114)
		(width 0.13208)
		(layer "F.Cu")
		(net "SSD12_PWRDIS_BIC_R")
	)
	(via
		(at 242.12296 -222.715836)
		(size 0.508)
		(drill 0.254)
		(layers "F.Cu" "B.Cu")
		(net "SSD12_PWRDIS_BIC_R")
	)
	(via
		(at 336.89417 -214.787226)
		(size 0.4572)
		(drill 0.254)
		(layers "F.Cu" "B.Cu")
		(net "SSD12_PWRDIS_BIC_R")
	)
	(via
		(at 242.657122 -220.1799)
		(size 0.508)
		(drill 0.254)
		(layers "F.Cu" "B.Cu")
		(net "SSD12_PWRDIS_BIC_R")
	)
	(segment
		(start 242.12296 -222.715836)
		(end 242.385088 -222.715836)
		(width 0.15494)
		(layer "In7.Cu")
		(net "SSD12_PWRDIS_BIC_R")
	)
	(segment
		(start 242.385088 -222.715836)
		(end 242.657122 -222.443802)
		(width 0.15494)
		(layer "In7.Cu")
		(net "SSD12_PWRDIS_BIC_R")
	)
	(segment
		(start 242.657122 -222.443802)
		(end 242.657122 -220.1799)
		(width 0.15494)
		(layer "In7.Cu")
		(net "SSD12_PWRDIS_BIC_R")
	)
	(segment
		(start 326.847708 -211.12734)
		(end 321.895724 -211.12734)
		(width 0.15494)
		(layer "In15.Cu")
		(net "SSD12_PWRDIS_BIC_R")
	)
	(segment
		(start 336.89417 -214.787226)
		(end 336.51952 -214.412576)
		(width 0.0889)
		(layer "In15.Cu")
		(net "SSD12_PWRDIS_BIC_R")
	)
	(segment
		(start 250.306586 -210.491578)
		(end 250.306586 -211.733892)
		(width 0.15494)
		(layer "In15.Cu")
		(net "SSD12_PWRDIS_BIC_R")
	)
	(segment
		(start 327.787 -212.13953)
		(end 327.787 -212.066632)
		(width 0.15494)
		(layer "In15.Cu")
		(net "SSD12_PWRDIS_BIC_R")
	)
	(segment
		(start 289.58794 -210.43646)
		(end 284.796992 -215.227408)
		(width 0.15494)
		(layer "In15.Cu")
		(net "SSD12_PWRDIS_BIC_R")
	)
	(segment
		(start 321.204844 -210.43646)
		(end 289.58794 -210.43646)
		(width 0.15494)
		(layer "In15.Cu")
		(net "SSD12_PWRDIS_BIC_R")
	)
	(segment
		(start 250.716034 -210.08213)
		(end 250.306586 -210.491578)
		(width 0.15494)
		(layer "In15.Cu")
		(net "SSD12_PWRDIS_BIC_R")
	)
	(segment
		(start 284.796992 -215.227408)
		(end 265.55319 -215.227408)
		(width 0.15494)
		(layer "In15.Cu")
		(net "SSD12_PWRDIS_BIC_R")
	)
	(segment
		(start 248.235216 -213.805262)
		(end 248.059702 -213.805262)
		(width 0.15494)
		(layer "In15.Cu")
		(net "SSD12_PWRDIS_BIC_R")
	)
	(segment
		(start 328.351896 -212.704426)
		(end 327.787 -212.13953)
		(width 0.15494)
		(layer "In15.Cu")
		(net "SSD12_PWRDIS_BIC_R")
	)
	(segment
		(start 250.306586 -211.733892)
		(end 248.235216 -213.805262)
		(width 0.15494)
		(layer "In15.Cu")
		(net "SSD12_PWRDIS_BIC_R")
	)
	(segment
		(start 333.236824 -214.412576)
		(end 333.121 -214.5284)
		(width 0.0889)
		(layer "In15.Cu")
		(net "SSD12_PWRDIS_BIC_R")
	)
	(segment
		(start 330.14285 -213.200996)
		(end 329.64628 -212.704426)
		(width 0.15494)
		(layer "In15.Cu")
		(net "SSD12_PWRDIS_BIC_R")
	)
	(segment
		(start 258.089908 -212.233256)
		(end 255.938782 -210.08213)
		(width 0.15494)
		(layer "In15.Cu")
		(net "SSD12_PWRDIS_BIC_R")
	)
	(segment
		(start 336.51952 -214.412576)
		(end 333.236824 -214.412576)
		(width 0.0889)
		(layer "In15.Cu")
		(net "SSD12_PWRDIS_BIC_R")
	)
	(segment
		(start 327.787 -212.066632)
		(end 326.847708 -211.12734)
		(width 0.15494)
		(layer "In15.Cu")
		(net "SSD12_PWRDIS_BIC_R")
	)
	(segment
		(start 265.55319 -215.227408)
		(end 265.164062 -215.616536)
		(width 0.15494)
		(layer "In15.Cu")
		(net "SSD12_PWRDIS_BIC_R")
	)
	(segment
		(start 265.164062 -215.616536)
		(end 262.892032 -215.616536)
		(width 0.15494)
		(layer "In15.Cu")
		(net "SSD12_PWRDIS_BIC_R")
	)
	(segment
		(start 332.579472 -214.5284)
		(end 331.252068 -213.200996)
		(width 0.15494)
		(layer "In15.Cu")
		(net "SSD12_PWRDIS_BIC_R")
	)
	(segment
		(start 255.938782 -210.08213)
		(end 250.716034 -210.08213)
		(width 0.15494)
		(layer "In15.Cu")
		(net "SSD12_PWRDIS_BIC_R")
	)
	(segment
		(start 329.64628 -212.704426)
		(end 328.351896 -212.704426)
		(width 0.15494)
		(layer "In15.Cu")
		(net "SSD12_PWRDIS_BIC_R")
	)
	(segment
		(start 248.059702 -213.805262)
		(end 245.491 -216.373964)
		(width 0.15494)
		(layer "In15.Cu")
		(net "SSD12_PWRDIS_BIC_R")
	)
	(segment
		(start 333.121 -214.5284)
		(end 332.579472 -214.5284)
		(width 0.15494)
		(layer "In15.Cu")
		(net "SSD12_PWRDIS_BIC_R")
	)
	(segment
		(start 245.491 -217.747342)
		(end 243.058442 -220.1799)
		(width 0.15494)
		(layer "In15.Cu")
		(net "SSD12_PWRDIS_BIC_R")
	)
	(segment
		(start 243.058442 -220.1799)
		(end 242.657122 -220.1799)
		(width 0.15494)
		(layer "In15.Cu")
		(net "SSD12_PWRDIS_BIC_R")
	)
	(segment
		(start 245.491 -216.373964)
		(end 245.491 -217.747342)
		(width 0.15494)
		(layer "In15.Cu")
		(net "SSD12_PWRDIS_BIC_R")
	)
	(segment
		(start 259.508752 -212.233256)
		(end 258.089908 -212.233256)
		(width 0.15494)
		(layer "In15.Cu")
		(net "SSD12_PWRDIS_BIC_R")
	)
	(segment
		(start 321.895724 -211.12734)
		(end 321.204844 -210.43646)
		(width 0.15494)
		(layer "In15.Cu")
		(net "SSD12_PWRDIS_BIC_R")
	)
	(segment
		(start 331.252068 -213.200996)
		(end 330.14285 -213.200996)
		(width 0.15494)
		(layer "In15.Cu")
		(net "SSD12_PWRDIS_BIC_R")
	)
	(segment
		(start 262.892032 -215.616536)
		(end 259.508752 -212.233256)
		(width 0.15494)
		(layer "In15.Cu")
		(net "SSD12_PWRDIS_BIC_R")
	)
	(segment
		(start 279.497028 -43.73626)
		(end 280.295858 -44.53509)
		(width 0.254)
		(layer "F.Cu")
		(net "P12V_SSD9_VIN_P")
	)
	(segment
		(start 280.295858 -44.53509)
		(end 280.295858 -45.043852)
		(width 0.254)
		(layer "F.Cu")
		(net "P12V_SSD9_VIN_P")
	)
	(segment
		(start 277.925276 -42.849038)
		(end 277.925276 -43.928284)
		(width 0.254)
		(layer "F.Cu")
		(net "P12V_SSD9_VIN_P")
	)
	(segment
		(start 278.794972 -43.73626)
		(end 279.497028 -43.73626)
		(width 0.254)
		(layer "F.Cu")
		(net "P12V_SSD9_VIN_P")
	)
	(segment
		(start 277.925276 -43.928284)
		(end 277.938484 -43.941492)
		(width 0.254)
		(layer "F.Cu")
		(net "P12V_SSD9_VIN_P")
	)
	(segment
		(start 278.58974 -43.941492)
		(end 278.794972 -43.73626)
		(width 0.254)
		(layer "F.Cu")
		(net "P12V_SSD9_VIN_P")
	)
	(segment
		(start 277.938484 -43.941492)
		(end 278.58974 -43.941492)
		(width 0.254)
		(layer "F.Cu")
		(net "P12V_SSD9_VIN_P")
	)
	(via
		(at 278.794972 -43.73626)
		(size 0.508)
		(drill 0.254)
		(layers "F.Cu" "B.Cu")
		(net "P12V_SSD9_VIN_P")
	)
	(segment
		(start 327.611994 -172.113448)
		(end 331.272642 -168.4528)
		(width 0.13208)
		(layer "F.Cu")
		(net "RST_PEX_SSD10_PERST_R_N")
	)
	(segment
		(start 338.093812 -218.387168)
		(end 337.694016 -217.987372)
		(width 0.13208)
		(layer "F.Cu")
		(net "RST_PEX_SSD10_PERST_R_N")
	)
	(segment
		(start 331.272642 -168.4528)
		(end 336.28965 -168.4528)
		(width 0.13208)
		(layer "F.Cu")
		(net "RST_PEX_SSD10_PERST_R_N")
	)
	(segment
		(start 336.44205 -168.6052)
		(end 336.44205 -169.037)
		(width 0.13208)
		(layer "F.Cu")
		(net "RST_PEX_SSD10_PERST_R_N")
	)
	(segment
		(start 336.28965 -168.4528)
		(end 336.44205 -168.6052)
		(width 0.13208)
		(layer "F.Cu")
		(net "RST_PEX_SSD10_PERST_R_N")
	)
	(segment
		(start 337.67395 -169.037)
		(end 336.44205 -169.037)
		(width 0.13208)
		(layer "F.Cu")
		(net "RST_PEX_SSD10_PERST_R_N")
	)
	(via
		(at 327.611994 -172.113448)
		(size 0.508)
		(drill 0.254)
		(layers "F.Cu" "B.Cu")
		(net "RST_PEX_SSD10_PERST_R_N")
	)
	(via
		(at 337.694016 -217.987372)
		(size 0.4572)
		(drill 0.254)
		(layers "F.Cu" "B.Cu")
		(net "RST_PEX_SSD10_PERST_R_N")
	)
	(segment
		(start 337.278726 -219.02547)
		(end 337.278726 -218.927934)
		(width 0.15494)
		(layer "In5.Cu")
		(net "RST_PEX_SSD10_PERST_R_N")
	)
	(segment
		(start 333.729838 -219.227908)
		(end 337.076288 -219.227908)
		(width 0.15494)
		(layer "In5.Cu")
		(net "RST_PEX_SSD10_PERST_R_N")
	)
	(segment
		(start 333.297022 -218.795092)
		(end 333.729838 -219.227908)
		(width 0.15494)
		(layer "In5.Cu")
		(net "RST_PEX_SSD10_PERST_R_N")
	)
	(segment
		(start 326.864472 -216.792556)
		(end 328.283316 -218.2114)
		(width 0.15494)
		(layer "In5.Cu")
		(net "RST_PEX_SSD10_PERST_R_N")
	)
	(segment
		(start 328.283316 -218.2114)
		(end 329.04049 -218.2114)
		(width 0.15494)
		(layer "In5.Cu")
		(net "RST_PEX_SSD10_PERST_R_N")
	)
	(segment
		(start 337.278726 -218.402662)
		(end 337.694016 -217.987372)
		(width 0.0889)
		(layer "In5.Cu")
		(net "RST_PEX_SSD10_PERST_R_N")
	)
	(segment
		(start 337.076288 -219.227908)
		(end 337.278726 -219.02547)
		(width 0.15494)
		(layer "In5.Cu")
		(net "RST_PEX_SSD10_PERST_R_N")
	)
	(segment
		(start 324.115938 -199.705468)
		(end 323.572886 -200.24852)
		(width 0.15494)
		(layer "In5.Cu")
		(net "RST_PEX_SSD10_PERST_R_N")
	)
	(segment
		(start 323.572886 -214.046562)
		(end 326.31888 -216.792556)
		(width 0.15494)
		(layer "In5.Cu")
		(net "RST_PEX_SSD10_PERST_R_N")
	)
	(segment
		(start 324.115938 -189.25032)
		(end 324.115938 -199.705468)
		(width 0.15494)
		(layer "In5.Cu")
		(net "RST_PEX_SSD10_PERST_R_N")
	)
	(segment
		(start 327.611994 -173.460156)
		(end 326.9996 -174.07255)
		(width 0.15494)
		(layer "In5.Cu")
		(net "RST_PEX_SSD10_PERST_R_N")
	)
	(segment
		(start 327.611994 -172.113448)
		(end 327.611994 -173.460156)
		(width 0.15494)
		(layer "In5.Cu")
		(net "RST_PEX_SSD10_PERST_R_N")
	)
	(segment
		(start 326.31888 -216.792556)
		(end 326.864472 -216.792556)
		(width 0.15494)
		(layer "In5.Cu")
		(net "RST_PEX_SSD10_PERST_R_N")
	)
	(segment
		(start 329.624182 -218.795092)
		(end 333.297022 -218.795092)
		(width 0.15494)
		(layer "In5.Cu")
		(net "RST_PEX_SSD10_PERST_R_N")
	)
	(segment
		(start 323.572886 -200.24852)
		(end 323.572886 -214.046562)
		(width 0.15494)
		(layer "In5.Cu")
		(net "RST_PEX_SSD10_PERST_R_N")
	)
	(segment
		(start 326.9996 -186.366658)
		(end 324.115938 -189.25032)
		(width 0.15494)
		(layer "In5.Cu")
		(net "RST_PEX_SSD10_PERST_R_N")
	)
	(segment
		(start 337.278726 -218.927934)
		(end 337.278726 -218.402662)
		(width 0.0889)
		(layer "In5.Cu")
		(net "RST_PEX_SSD10_PERST_R_N")
	)
	(segment
		(start 326.9996 -174.07255)
		(end 326.9996 -186.366658)
		(width 0.15494)
		(layer "In5.Cu")
		(net "RST_PEX_SSD10_PERST_R_N")
	)
	(segment
		(start 329.04049 -218.2114)
		(end 329.624182 -218.795092)
		(width 0.15494)
		(layer "In5.Cu")
		(net "RST_PEX_SSD10_PERST_R_N")
	)
	(segment
		(start 366.263936 -176.316894)
		(end 364.481618 -176.316894)
		(width 0.13208)
		(layer "F.Cu")
		(net "PRSNT_SSD7_FPGA_PCA9555_N")
	)
	(segment
		(start 363.724444 -175.935132)
		(end 362.795312 -175.006)
		(width 0.13208)
		(layer "F.Cu")
		(net "PRSNT_SSD7_FPGA_PCA9555_N")
	)
	(segment
		(start 364.099856 -175.935132)
		(end 363.724444 -175.935132)
		(width 0.13208)
		(layer "F.Cu")
		(net "PRSNT_SSD7_FPGA_PCA9555_N")
	)
	(segment
		(start 362.795312 -175.006)
		(end 361.58805 -175.006)
		(width 0.13208)
		(layer "F.Cu")
		(net "PRSNT_SSD7_FPGA_PCA9555_N")
	)
	(segment
		(start 364.481618 -176.316894)
		(end 364.099856 -175.935132)
		(width 0.13208)
		(layer "F.Cu")
		(net "PRSNT_SSD7_FPGA_PCA9555_N")
	)
	(via
		(at 364.099856 -175.935132)
		(size 0.508)
		(drill 0.254)
		(layers "F.Cu" "B.Cu")
		(net "PRSNT_SSD7_FPGA_PCA9555_N")
	)
	(segment
		(start 335.693766 -215.187022)
		(end 335.29397 -214.787226)
		(width 0.13208)
		(layer "F.Cu")
		(net "SSD13_PWRDIS_BIC_R")
	)
	(via
		(at 335.29397 -214.787226)
		(size 0.4572)
		(drill 0.254)
		(layers "F.Cu" "B.Cu")
		(net "SSD13_PWRDIS_BIC_R")
	)
	(via
		(at 262.080502 -215.969342)
		(size 0.508)
		(drill 0.254)
		(layers "F.Cu" "B.Cu")
		(net "SSD13_PWRDIS_BIC_R")
	)
	(via
		(at 237.903512 -233.182668)
		(size 0.508)
		(drill 0.254)
		(layers "F.Cu" "B.Cu")
		(net "SSD13_PWRDIS_BIC_R")
	)
	(segment
		(start 237.903512 -233.182668)
		(end 237.429548 -232.708704)
		(width 0.13208)
		(layer "B.Cu")
		(net "SSD13_PWRDIS_BIC_R")
	)
	(segment
		(start 237.429548 -231.758744)
		(end 237.562644 -231.625648)
		(width 0.13208)
		(layer "B.Cu")
		(net "SSD13_PWRDIS_BIC_R")
	)
	(segment
		(start 237.429548 -232.708704)
		(end 237.429548 -231.758744)
		(width 0.13208)
		(layer "B.Cu")
		(net "SSD13_PWRDIS_BIC_R")
	)
	(segment
		(start 237.903512 -234.327954)
		(end 237.903512 -233.182668)
		(width 0.13208)
		(layer "B.Cu")
		(net "SSD13_PWRDIS_BIC_R")
	)
	(segment
		(start 237.903512 -233.182668)
		(end 241.97945 -233.182668)
		(width 0.15494)
		(layer "In7.Cu")
		(net "SSD13_PWRDIS_BIC_R")
	)
	(segment
		(start 251.489972 -224.6884)
		(end 252.73889 -223.439482)
		(width 0.15494)
		(layer "In7.Cu")
		(net "SSD13_PWRDIS_BIC_R")
	)
	(segment
		(start 250.7488 -224.6884)
		(end 251.489972 -224.6884)
		(width 0.15494)
		(layer "In7.Cu")
		(net "SSD13_PWRDIS_BIC_R")
	)
	(segment
		(start 252.73889 -222.84944)
		(end 253.5936 -221.99473)
		(width 0.15494)
		(layer "In7.Cu")
		(net "SSD13_PWRDIS_BIC_R")
	)
	(segment
		(start 256.9972 -216.8398)
		(end 261.210044 -216.8398)
		(width 0.15494)
		(layer "In7.Cu")
		(net "SSD13_PWRDIS_BIC_R")
	)
	(segment
		(start 244.8306 -229.209346)
		(end 246.684546 -227.3554)
		(width 0.15494)
		(layer "In7.Cu")
		(net "SSD13_PWRDIS_BIC_R")
	)
	(segment
		(start 241.97945 -233.182668)
		(end 244.8306 -230.331518)
		(width 0.15494)
		(layer "In7.Cu")
		(net "SSD13_PWRDIS_BIC_R")
	)
	(segment
		(start 252.73889 -223.439482)
		(end 252.73889 -222.84944)
		(width 0.15494)
		(layer "In7.Cu")
		(net "SSD13_PWRDIS_BIC_R")
	)
	(segment
		(start 253.5936 -221.99473)
		(end 253.5936 -220.599254)
		(width 0.15494)
		(layer "In7.Cu")
		(net "SSD13_PWRDIS_BIC_R")
	)
	(segment
		(start 248.0818 -227.3554)
		(end 250.7488 -224.6884)
		(width 0.15494)
		(layer "In7.Cu")
		(net "SSD13_PWRDIS_BIC_R")
	)
	(segment
		(start 255.1938 -215.0364)
		(end 256.9972 -216.8398)
		(width 0.15494)
		(layer "In7.Cu")
		(net "SSD13_PWRDIS_BIC_R")
	)
	(segment
		(start 261.210044 -216.8398)
		(end 262.080502 -215.969342)
		(width 0.15494)
		(layer "In7.Cu")
		(net "SSD13_PWRDIS_BIC_R")
	)
	(segment
		(start 253.7079 -220.484954)
		(end 253.7079 -215.4809)
		(width 0.15494)
		(layer "In7.Cu")
		(net "SSD13_PWRDIS_BIC_R")
	)
	(segment
		(start 246.684546 -227.3554)
		(end 248.0818 -227.3554)
		(width 0.15494)
		(layer "In7.Cu")
		(net "SSD13_PWRDIS_BIC_R")
	)
	(segment
		(start 244.8306 -230.331518)
		(end 244.8306 -229.209346)
		(width 0.15494)
		(layer "In7.Cu")
		(net "SSD13_PWRDIS_BIC_R")
	)
	(segment
		(start 253.5936 -220.599254)
		(end 253.7079 -220.484954)
		(width 0.15494)
		(layer "In7.Cu")
		(net "SSD13_PWRDIS_BIC_R")
	)
	(segment
		(start 254.1524 -215.0364)
		(end 255.1938 -215.0364)
		(width 0.15494)
		(layer "In7.Cu")
		(net "SSD13_PWRDIS_BIC_R")
	)
	(segment
		(start 253.7079 -215.4809)
		(end 254.1524 -215.0364)
		(width 0.15494)
		(layer "In7.Cu")
		(net "SSD13_PWRDIS_BIC_R")
	)
	(segment
		(start 265.980418 -215.6714)
		(end 265.248136 -215.974676)
		(width 0.15494)
		(layer "In15.Cu")
		(net "SSD13_PWRDIS_BIC_R")
	)
	(segment
		(start 327.42886 -212.215222)
		(end 326.699118 -211.48548)
		(width 0.15494)
		(layer "In15.Cu")
		(net "SSD13_PWRDIS_BIC_R")
	)
	(segment
		(start 331.24521 -213.851236)
		(end 329.2094 -213.851236)
		(width 0.15494)
		(layer "In15.Cu")
		(net "SSD13_PWRDIS_BIC_R")
	)
	(segment
		(start 334.01762 -215.011)
		(end 332.404974 -215.011)
		(width 0.15494)
		(layer "In15.Cu")
		(net "SSD13_PWRDIS_BIC_R")
	)
	(segment
		(start 262.085836 -215.974676)
		(end 262.080502 -215.969342)
		(width 0.15494)
		(layer "In15.Cu")
		(net "SSD13_PWRDIS_BIC_R")
	)
	(segment
		(start 332.404974 -215.011)
		(end 331.24521 -213.851236)
		(width 0.15494)
		(layer "In15.Cu")
		(net "SSD13_PWRDIS_BIC_R")
	)
	(segment
		(start 265.248136 -215.974676)
		(end 262.085836 -215.974676)
		(width 0.15494)
		(layer "In15.Cu")
		(net "SSD13_PWRDIS_BIC_R")
	)
	(segment
		(start 327.42886 -212.49386)
		(end 327.42886 -212.215222)
		(width 0.15494)
		(layer "In15.Cu")
		(net "SSD13_PWRDIS_BIC_R")
	)
	(segment
		(start 328.743564 -213.3854)
		(end 328.3204 -213.3854)
		(width 0.15494)
		(layer "In15.Cu")
		(net "SSD13_PWRDIS_BIC_R")
	)
	(segment
		(start 321.747134 -211.48548)
		(end 321.056254 -210.7946)
		(width 0.15494)
		(layer "In15.Cu")
		(net "SSD13_PWRDIS_BIC_R")
	)
	(segment
		(start 335.29397 -214.787226)
		(end 334.241394 -214.787226)
		(width 0.15494)
		(layer "In15.Cu")
		(net "SSD13_PWRDIS_BIC_R")
	)
	(segment
		(start 290.0299 -210.7946)
		(end 285.1531 -215.6714)
		(width 0.15494)
		(layer "In15.Cu")
		(net "SSD13_PWRDIS_BIC_R")
	)
	(segment
		(start 285.1531 -215.6714)
		(end 265.980418 -215.6714)
		(width 0.15494)
		(layer "In15.Cu")
		(net "SSD13_PWRDIS_BIC_R")
	)
	(segment
		(start 326.699118 -211.48548)
		(end 321.747134 -211.48548)
		(width 0.15494)
		(layer "In15.Cu")
		(net "SSD13_PWRDIS_BIC_R")
	)
	(segment
		(start 321.056254 -210.7946)
		(end 290.0299 -210.7946)
		(width 0.15494)
		(layer "In15.Cu")
		(net "SSD13_PWRDIS_BIC_R")
	)
	(segment
		(start 328.3204 -213.3854)
		(end 327.42886 -212.49386)
		(width 0.15494)
		(layer "In15.Cu")
		(net "SSD13_PWRDIS_BIC_R")
	)
	(segment
		(start 334.241394 -214.787226)
		(end 334.01762 -215.011)
		(width 0.15494)
		(layer "In15.Cu")
		(net "SSD13_PWRDIS_BIC_R")
	)
	(segment
		(start 329.2094 -213.851236)
		(end 328.743564 -213.3854)
		(width 0.15494)
		(layer "In15.Cu")
		(net "SSD13_PWRDIS_BIC_R")
	)
	(segment
		(start 355.2444 -59.012582)
		(end 355.403404 -59.171586)
		(width 0.13208)
		(layer "F.Cu")
		(net "P3V3_SSD12_OCP")
	)
	(segment
		(start 355.440996 -58.364628)
		(end 355.2444 -58.561224)
		(width 0.13208)
		(layer "F.Cu")
		(net "P3V3_SSD12_OCP")
	)
	(segment
		(start 355.440996 -57.16397)
		(end 355.440996 -58.364628)
		(width 0.13208)
		(layer "F.Cu")
		(net "P3V3_SSD12_OCP")
	)
	(segment
		(start 355.2444 -58.561224)
		(end 355.2444 -59.012582)
		(width 0.13208)
		(layer "F.Cu")
		(net "P3V3_SSD12_OCP")
	)
	(via
		(at 355.2444 -58.561224)
		(size 0.508)
		(drill 0.254)
		(layers "F.Cu" "B.Cu")
		(net "P3V3_SSD12_OCP")
	)
	(segment
		(start 220.608144 -181.14518)
		(end 221.061534 -181.14518)
		(width 0.13208)
		(layer "F.Cu")
		(net "RST_FW_BIC_PLTRST_C")
	)
	(segment
		(start 219.414344 -180.12918)
		(end 219.414344 -181.14518)
		(width 0.13208)
		(layer "F.Cu")
		(net "RST_FW_BIC_PLTRST_C")
	)
	(segment
		(start 220.205808 -181.547516)
		(end 220.608144 -181.14518)
		(width 0.13208)
		(layer "F.Cu")
		(net "RST_FW_BIC_PLTRST_C")
	)
	(segment
		(start 220.205808 -181.939692)
		(end 220.205808 -181.547516)
		(width 0.13208)
		(layer "F.Cu")
		(net "RST_FW_BIC_PLTRST_C")
	)
	(segment
		(start 219.414344 -181.14518)
		(end 219.414344 -181.971696)
		(width 0.13208)
		(layer "F.Cu")
		(net "RST_FW_BIC_PLTRST_C")
	)
	(segment
		(start 219.794074 -182.351426)
		(end 220.205808 -181.939692)
		(width 0.13208)
		(layer "F.Cu")
		(net "RST_FW_BIC_PLTRST_C")
	)
	(segment
		(start 219.414344 -181.971696)
		(end 219.794074 -182.351426)
		(width 0.13208)
		(layer "F.Cu")
		(net "RST_FW_BIC_PLTRST_C")
	)
	(via
		(at 219.794074 -182.351426)
		(size 0.762)
		(drill 0.381)
		(layers "F.Cu" "B.Cu")
		(net "RST_FW_BIC_PLTRST_C")
	)
	(segment
		(start 284.043628 -46.90491)
		(end 283.832554 -46.693836)
		(width 0.13208)
		(layer "F.Cu")
		(net "SSD9_ADC_ALERT_N")
	)
	(segment
		(start 283.832554 -46.693836)
		(end 283.257752 -46.693836)
		(width 0.13208)
		(layer "F.Cu")
		(net "SSD9_ADC_ALERT_N")
	)
	(segment
		(start 283.257752 -46.693836)
		(end 282.445968 -46.693836)
		(width 0.13208)
		(layer "F.Cu")
		(net "SSD9_ADC_ALERT_N")
	)
	(via
		(at 283.257752 -46.693836)
		(size 0.508)
		(drill 0.254)
		(layers "F.Cu" "B.Cu")
		(net "SSD9_ADC_ALERT_N")
	)
	(segment
		(start 363.626908 -178.917092)
		(end 365.133382 -178.917092)
		(width 0.13208)
		(layer "F.Cu")
		(net "PRSNT_SSD6_FPGA_PCA9555_N")
	)
	(segment
		(start 363.474 -179.07)
		(end 363.626908 -178.917092)
		(width 0.13208)
		(layer "F.Cu")
		(net "PRSNT_SSD6_FPGA_PCA9555_N")
	)
	(segment
		(start 361.58805 -179.07)
		(end 363.474 -179.07)
		(width 0.13208)
		(layer "F.Cu")
		(net "PRSNT_SSD6_FPGA_PCA9555_N")
	)
	(segment
		(start 365.133382 -178.917092)
		(end 366.263936 -178.917092)
		(width 0.13208)
		(layer "F.Cu")
		(net "PRSNT_SSD6_FPGA_PCA9555_N")
	)
	(via
		(at 365.133382 -178.917092)
		(size 0.508)
		(drill 0.254)
		(layers "F.Cu" "B.Cu")
		(net "PRSNT_SSD6_FPGA_PCA9555_N")
	)
	(segment
		(start 233.221784 -126.092966)
		(end 235.53293 -126.092966)
		(width 0.13208)
		(layer "F.Cu")
		(net "PEX_USB2_SEL_CONN")
	)
	(segment
		(start 240.706656 -80.451706)
		(end 241.23523 -80.451706)
		(width 0.13208)
		(layer "F.Cu")
		(net "PEX_USB2_SEL_CONN")
	)
	(segment
		(start 241.23523 -80.451706)
		(end 241.542062 -80.758538)
		(width 0.13208)
		(layer "F.Cu")
		(net "PEX_USB2_SEL_CONN")
	)
	(segment
		(start 232.89895 -124.116338)
		(end 232.89895 -125.770132)
		(width 0.13208)
		(layer "F.Cu")
		(net "PEX_USB2_SEL_CONN")
	)
	(segment
		(start 244.987826 -96.193864)
		(end 240.218468 -100.963222)
		(width 0.13208)
		(layer "F.Cu")
		(net "PEX_USB2_SEL_CONN")
	)
	(segment
		(start 233.756454 -123.258834)
		(end 232.89895 -124.116338)
		(width 0.13208)
		(layer "F.Cu")
		(net "PEX_USB2_SEL_CONN")
	)
	(segment
		(start 240.218468 -100.963222)
		(end 240.218468 -120.686068)
		(width 0.13208)
		(layer "F.Cu")
		(net "PEX_USB2_SEL_CONN")
	)
	(segment
		(start 241.542062 -80.758538)
		(end 244.987826 -84.204302)
		(width 0.13208)
		(layer "F.Cu")
		(net "PEX_USB2_SEL_CONN")
	)
	(segment
		(start 232.89895 -125.770132)
		(end 233.221784 -126.092966)
		(width 0.13208)
		(layer "F.Cu")
		(net "PEX_USB2_SEL_CONN")
	)
	(segment
		(start 240.218468 -120.686068)
		(end 237.645702 -123.258834)
		(width 0.13208)
		(layer "F.Cu")
		(net "PEX_USB2_SEL_CONN")
	)
	(segment
		(start 244.987826 -84.204302)
		(end 244.987826 -96.193864)
		(width 0.13208)
		(layer "F.Cu")
		(net "PEX_USB2_SEL_CONN")
	)
	(segment
		(start 237.645702 -123.258834)
		(end 233.756454 -123.258834)
		(width 0.13208)
		(layer "F.Cu")
		(net "PEX_USB2_SEL_CONN")
	)
	(via
		(at 241.542062 -80.758538)
		(size 0.508)
		(drill 0.254)
		(layers "F.Cu" "B.Cu")
		(net "PEX_USB2_SEL_CONN")
	)
	(segment
		(start 218.091004 -179.11318)
		(end 218.614244 -179.11318)
		(width 0.13208)
		(layer "F.Cu")
		(net "RST_FW_BIC_PLTRST_R")
	)
	(segment
		(start 218.091512 -180.12918)
		(end 217.932508 -179.970176)
		(width 0.13208)
		(layer "F.Cu")
		(net "RST_FW_BIC_PLTRST_R")
	)
	(segment
		(start 217.932508 -179.639976)
		(end 217.932508 -179.271676)
		(width 0.13208)
		(layer "F.Cu")
		(net "RST_FW_BIC_PLTRST_R")
	)
	(segment
		(start 218.614244 -180.12918)
		(end 218.091512 -180.12918)
		(width 0.13208)
		(layer "F.Cu")
		(net "RST_FW_BIC_PLTRST_R")
	)
	(segment
		(start 217.932508 -179.970176)
		(end 217.932508 -179.639976)
		(width 0.13208)
		(layer "F.Cu")
		(net "RST_FW_BIC_PLTRST_R")
	)
	(segment
		(start 217.932508 -179.271676)
		(end 218.091004 -179.11318)
		(width 0.13208)
		(layer "F.Cu")
		(net "RST_FW_BIC_PLTRST_R")
	)
	(via
		(at 217.932508 -179.639976)
		(size 0.508)
		(drill 0.254)
		(layers "F.Cu" "B.Cu")
		(net "RST_FW_BIC_PLTRST_R")
	)
	(segment
		(start 282.856432 -49.95291)
		(end 284.043628 -49.95291)
		(width 0.13208)
		(layer "F.Cu")
		(net "SMB_SSD9_ADC_SCL")
	)
	(segment
		(start 281.795982 -47.843948)
		(end 281.795982 -48.89246)
		(width 0.13208)
		(layer "F.Cu")
		(net "SMB_SSD9_ADC_SCL")
	)
	(segment
		(start 281.795982 -48.89246)
		(end 282.856432 -49.95291)
		(width 0.13208)
		(layer "F.Cu")
		(net "SMB_SSD9_ADC_SCL")
	)
	(via
		(at 281.795982 -48.89246)
		(size 0.508)
		(drill 0.254)
		(layers "F.Cu" "B.Cu")
		(net "SMB_SSD9_ADC_SCL")
	)
	(segment
		(start 378.206 -195.326)
		(end 376.440192 -195.326)
		(width 0.13208)
		(layer "F.Cu")
		(net "PRSNT_NIC2_FPGA_PCA9555_N")
	)
	(segment
		(start 380.143766 -194.31)
		(end 379.222 -194.31)
		(width 0.13208)
		(layer "F.Cu")
		(net "PRSNT_NIC2_FPGA_PCA9555_N")
	)
	(segment
		(start 376.440192 -195.326)
		(end 376.432064 -195.334128)
		(width 0.13208)
		(layer "F.Cu")
		(net "PRSNT_NIC2_FPGA_PCA9555_N")
	)
	(segment
		(start 379.222 -194.31)
		(end 378.206 -195.326)
		(width 0.13208)
		(layer "F.Cu")
		(net "PRSNT_NIC2_FPGA_PCA9555_N")
	)
	(segment
		(start 380.85395 -194.31)
		(end 380.143766 -194.31)
		(width 0.13208)
		(layer "F.Cu")
		(net "PRSNT_NIC2_FPGA_PCA9555_N")
	)
	(via
		(at 380.143766 -194.31)
		(size 0.508)
		(drill 0.254)
		(layers "F.Cu" "B.Cu")
		(net "PRSNT_NIC2_FPGA_PCA9555_N")
	)
	(segment
		(start 377.20905 -171.572936)
		(end 377.20905 -172.11802)
		(width 0.13208)
		(layer "F.Cu")
		(net "PRSNT_NIC3_FPGA_R_N")
	)
	(segment
		(start 372.966488 -171.148248)
		(end 376.784362 -171.148248)
		(width 0.13208)
		(layer "F.Cu")
		(net "PRSNT_NIC3_FPGA_R_N")
	)
	(segment
		(start 376.784362 -171.148248)
		(end 377.20905 -171.572936)
		(width 0.13208)
		(layer "F.Cu")
		(net "PRSNT_NIC3_FPGA_R_N")
	)
	(segment
		(start 358.41305 -212.344)
		(end 359.029 -212.344)
		(width 0.13208)
		(layer "F.Cu")
		(net "PRSNT_NIC3_FPGA_R_N")
	)
	(via
		(at 372.966488 -171.148248)
		(size 0.508)
		(drill 0.254)
		(layers "F.Cu" "B.Cu")
		(net "PRSNT_NIC3_FPGA_R_N")
	)
	(via
		(at 359.029 -212.344)
		(size 0.508)
		(drill 0.254)
		(layers "F.Cu" "B.Cu")
		(net "PRSNT_NIC3_FPGA_R_N")
	)
	(segment
		(start 364.69066 -212.44687)
		(end 368.604038 -208.533492)
		(width 0.15494)
		(layer "In7.Cu")
		(net "PRSNT_NIC3_FPGA_R_N")
	)
	(segment
		(start 368.896646 -208.076038)
		(end 375.158 -201.814684)
		(width 0.15494)
		(layer "In7.Cu")
		(net "PRSNT_NIC3_FPGA_R_N")
	)
	(segment
		(start 375.158 -191.770254)
		(end 375.1834 -191.744854)
		(width 0.15494)
		(layer "In7.Cu")
		(net "PRSNT_NIC3_FPGA_R_N")
	)
	(segment
		(start 373.341646 -182.1561)
		(end 372.7704 -181.584854)
		(width 0.15494)
		(layer "In7.Cu")
		(net "PRSNT_NIC3_FPGA_R_N")
	)
	(segment
		(start 361.286298 -212.344)
		(end 361.437428 -212.49513)
		(width 0.15494)
		(layer "In7.Cu")
		(net "PRSNT_NIC3_FPGA_R_N")
	)
	(segment
		(start 374.777 -189.136528)
		(end 374.777 -183.591454)
		(width 0.15494)
		(layer "In7.Cu")
		(net "PRSNT_NIC3_FPGA_R_N")
	)
	(segment
		(start 372.7704 -171.929298)
		(end 372.966488 -171.73321)
		(width 0.15494)
		(layer "In7.Cu")
		(net "PRSNT_NIC3_FPGA_R_N")
	)
	(segment
		(start 373.356124 -182.1561)
		(end 373.341646 -182.1561)
		(width 0.15494)
		(layer "In7.Cu")
		(net "PRSNT_NIC3_FPGA_R_N")
	)
	(segment
		(start 364.690406 -212.44687)
		(end 364.69066 -212.44687)
		(width 0.15494)
		(layer "In7.Cu")
		(net "PRSNT_NIC3_FPGA_R_N")
	)
	(segment
		(start 375.1834 -190.906654)
		(end 374.601994 -190.325248)
		(width 0.15494)
		(layer "In7.Cu")
		(net "PRSNT_NIC3_FPGA_R_N")
	)
	(segment
		(start 368.604038 -208.359248)
		(end 368.887248 -208.076038)
		(width 0.15494)
		(layer "In7.Cu")
		(net "PRSNT_NIC3_FPGA_R_N")
	)
	(segment
		(start 359.029 -212.344)
		(end 361.286298 -212.344)
		(width 0.15494)
		(layer "In7.Cu")
		(net "PRSNT_NIC3_FPGA_R_N")
	)
	(segment
		(start 364.615476 -212.5218)
		(end 364.690406 -212.44687)
		(width 0.15494)
		(layer "In7.Cu")
		(net "PRSNT_NIC3_FPGA_R_N")
	)
	(segment
		(start 374.601994 -189.311534)
		(end 374.777 -189.136528)
		(width 0.15494)
		(layer "In7.Cu")
		(net "PRSNT_NIC3_FPGA_R_N")
	)
	(segment
		(start 375.1834 -191.744854)
		(end 375.1834 -190.906654)
		(width 0.15494)
		(layer "In7.Cu")
		(net "PRSNT_NIC3_FPGA_R_N")
	)
	(segment
		(start 375.158 -201.814684)
		(end 375.158 -191.770254)
		(width 0.15494)
		(layer "In7.Cu")
		(net "PRSNT_NIC3_FPGA_R_N")
	)
	(segment
		(start 368.604038 -208.533492)
		(end 368.604038 -208.359248)
		(width 0.15494)
		(layer "In7.Cu")
		(net "PRSNT_NIC3_FPGA_R_N")
	)
	(segment
		(start 362.65866 -212.49513)
		(end 362.68533 -212.5218)
		(width 0.15494)
		(layer "In7.Cu")
		(net "PRSNT_NIC3_FPGA_R_N")
	)
	(segment
		(start 361.437428 -212.49513)
		(end 362.65866 -212.49513)
		(width 0.15494)
		(layer "In7.Cu")
		(net "PRSNT_NIC3_FPGA_R_N")
	)
	(segment
		(start 373.639334 -182.453788)
		(end 373.639334 -182.43931)
		(width 0.15494)
		(layer "In7.Cu")
		(net "PRSNT_NIC3_FPGA_R_N")
	)
	(segment
		(start 374.777 -183.591454)
		(end 373.639334 -182.453788)
		(width 0.15494)
		(layer "In7.Cu")
		(net "PRSNT_NIC3_FPGA_R_N")
	)
	(segment
		(start 372.966488 -171.73321)
		(end 372.966488 -171.148248)
		(width 0.15494)
		(layer "In7.Cu")
		(net "PRSNT_NIC3_FPGA_R_N")
	)
	(segment
		(start 373.639334 -182.43931)
		(end 373.356124 -182.1561)
		(width 0.15494)
		(layer "In7.Cu")
		(net "PRSNT_NIC3_FPGA_R_N")
	)
	(segment
		(start 374.601994 -190.325248)
		(end 374.601994 -189.311534)
		(width 0.15494)
		(layer "In7.Cu")
		(net "PRSNT_NIC3_FPGA_R_N")
	)
	(segment
		(start 368.887248 -208.076038)
		(end 368.896646 -208.076038)
		(width 0.15494)
		(layer "In7.Cu")
		(net "PRSNT_NIC3_FPGA_R_N")
	)
	(segment
		(start 362.68533 -212.5218)
		(end 364.615476 -212.5218)
		(width 0.15494)
		(layer "In7.Cu")
		(net "PRSNT_NIC3_FPGA_R_N")
	)
	(segment
		(start 372.7704 -181.584854)
		(end 372.7704 -171.929298)
		(width 0.15494)
		(layer "In7.Cu")
		(net "PRSNT_NIC3_FPGA_R_N")
	)
	(segment
		(start 367.113312 -196.723)
		(end 367.611406 -197.221094)
		(width 0.13208)
		(layer "F.Cu")
		(net "PRSNT_SSD5_FPGA_PCA9555_N")
	)
	(segment
		(start 367.611406 -197.221094)
		(end 368.424206 -198.033894)
		(width 0.13208)
		(layer "F.Cu")
		(net "PRSNT_SSD5_FPGA_PCA9555_N")
	)
	(segment
		(start 368.424206 -198.033894)
		(end 370.581936 -198.033894)
		(width 0.13208)
		(layer "F.Cu")
		(net "PRSNT_SSD5_FPGA_PCA9555_N")
	)
	(segment
		(start 365.90605 -196.723)
		(end 367.113312 -196.723)
		(width 0.13208)
		(layer "F.Cu")
		(net "PRSNT_SSD5_FPGA_PCA9555_N")
	)
	(via
		(at 367.611406 -197.221094)
		(size 0.508)
		(drill 0.254)
		(layers "F.Cu" "B.Cu")
		(net "PRSNT_SSD5_FPGA_PCA9555_N")
	)
	(segment
		(start 220.33357 -180.495194)
		(end 221.061534 -180.495194)
		(width 0.13208)
		(layer "F.Cu")
		(net "RST_FW_BIC_PLTRST")
	)
	(segment
		(start 219.414344 -179.157376)
		(end 219.414344 -179.11318)
		(width 0.13208)
		(layer "F.Cu")
		(net "RST_FW_BIC_PLTRST")
	)
	(segment
		(start 219.414344 -178.09718)
		(end 219.414344 -179.11318)
		(width 0.13208)
		(layer "F.Cu")
		(net "RST_FW_BIC_PLTRST")
	)
	(segment
		(start 220.33357 -180.495194)
		(end 220.33357 -180.076602)
		(width 0.13208)
		(layer "F.Cu")
		(net "RST_FW_BIC_PLTRST")
	)
	(segment
		(start 220.33357 -180.076602)
		(end 219.414344 -179.157376)
		(width 0.13208)
		(layer "F.Cu")
		(net "RST_FW_BIC_PLTRST")
	)
	(via
		(at 220.33357 -180.495194)
		(size 0.508)
		(drill 0.254)
		(layers "F.Cu" "B.Cu")
		(net "RST_FW_BIC_PLTRST")
	)
	(segment
		(start 367.944908 -200.634092)
		(end 369.451382 -200.634092)
		(width 0.13208)
		(layer "F.Cu")
		(net "PRSNT_SSD4_FPGA_PCA9555_N")
	)
	(segment
		(start 367.792 -200.787)
		(end 367.944908 -200.634092)
		(width 0.13208)
		(layer "F.Cu")
		(net "PRSNT_SSD4_FPGA_PCA9555_N")
	)
	(segment
		(start 365.90605 -200.787)
		(end 367.792 -200.787)
		(width 0.13208)
		(layer "F.Cu")
		(net "PRSNT_SSD4_FPGA_PCA9555_N")
	)
	(segment
		(start 369.451382 -200.634092)
		(end 370.581936 -200.634092)
		(width 0.13208)
		(layer "F.Cu")
		(net "PRSNT_SSD4_FPGA_PCA9555_N")
	)
	(via
		(at 369.451382 -200.634092)
		(size 0.508)
		(drill 0.254)
		(layers "F.Cu" "B.Cu")
		(net "PRSNT_SSD4_FPGA_PCA9555_N")
	)
	(segment
		(start 335.693766 -224.786952)
		(end 335.29397 -225.186748)
		(width 0.13208)
		(layer "F.Cu")
		(net "PWR_EN_P1V2_AUX")
	)
	(via
		(at 335.29397 -225.186748)
		(size 0.4572)
		(drill 0.254)
		(layers "F.Cu" "B.Cu")
		(net "PWR_EN_P1V2_AUX")
	)
	(via
		(at 331.5335 -225.8695)
		(size 0.508)
		(drill 0.254)
		(layers "F.Cu" "B.Cu")
		(net "PWR_EN_P1V2_AUX")
	)
	(segment
		(start 331.5335 -225.8695)
		(end 331.1652 -225.5012)
		(width 0.13208)
		(layer "B.Cu")
		(net "PWR_EN_P1V2_AUX")
	)
	(segment
		(start 331.1652 -225.5012)
		(end 330.09205 -225.5012)
		(width 0.13208)
		(layer "B.Cu")
		(net "PWR_EN_P1V2_AUX")
	)
	(segment
		(start 332.216252 -225.186748)
		(end 335.29397 -225.186748)
		(width 0.15494)
		(layer "In5.Cu")
		(net "PWR_EN_P1V2_AUX")
	)
	(segment
		(start 331.5335 -225.8695)
		(end 332.216252 -225.186748)
		(width 0.15494)
		(layer "In5.Cu")
		(net "PWR_EN_P1V2_AUX")
	)
	(segment
		(start 226.667568 -221.504256)
		(end 226.267772 -221.904052)
		(width 0.13208)
		(layer "F.Cu")
		(net "BIC_FORCE_THROTTLE_N")
	)
	(via
		(at 226.267772 -221.904052)
		(size 0.4572)
		(drill 0.254)
		(layers "F.Cu" "B.Cu")
		(net "BIC_FORCE_THROTTLE_N")
	)
	(via
		(at 225.370644 -227.64369)
		(size 0.6604)
		(drill 0.3302)
		(layers "F.Cu" "B.Cu")
		(net "BIC_FORCE_THROTTLE_N")
	)
	(segment
		(start 225.880422 -224.0788)
		(end 225.880422 -227.133912)
		(width 0.13208)
		(layer "B.Cu")
		(net "BIC_FORCE_THROTTLE_N")
	)
	(segment
		(start 225.370644 -227.64369)
		(end 225.370644 -230.825548)
		(width 0.13208)
		(layer "B.Cu")
		(net "BIC_FORCE_THROTTLE_N")
	)
	(segment
		(start 225.871532 -222.300292)
		(end 225.871532 -223.668336)
		(width 0.0889)
		(layer "B.Cu")
		(net "BIC_FORCE_THROTTLE_N")
	)
	(segment
		(start 226.267772 -221.904052)
		(end 225.871532 -222.300292)
		(width 0.0889)
		(layer "B.Cu")
		(net "BIC_FORCE_THROTTLE_N")
	)
	(segment
		(start 225.880422 -227.133912)
		(end 225.370644 -227.64369)
		(width 0.13208)
		(layer "B.Cu")
		(net "BIC_FORCE_THROTTLE_N")
	)
	(segment
		(start 225.880422 -223.677226)
		(end 225.880422 -224.0788)
		(width 0.0889)
		(layer "B.Cu")
		(net "BIC_FORCE_THROTTLE_N")
	)
	(segment
		(start 225.871532 -223.668336)
		(end 225.880422 -223.677226)
		(width 0.0889)
		(layer "B.Cu")
		(net "BIC_FORCE_THROTTLE_N")
	)
	(segment
		(start 375.83491 -191.65697)
		(end 379.504448 -191.65697)
		(width 0.13208)
		(layer "F.Cu")
		(net "PRSNT_NIC2_FPGA_R_N")
	)
	(segment
		(start 381.65405 -193.806572)
		(end 381.65405 -194.31)
		(width 0.13208)
		(layer "F.Cu")
		(net "PRSNT_NIC2_FPGA_R_N")
	)
	(segment
		(start 379.504448 -191.65697)
		(end 381.65405 -193.806572)
		(width 0.13208)
		(layer "F.Cu")
		(net "PRSNT_NIC2_FPGA_R_N")
	)
	(segment
		(start 358.41305 -213.36)
		(end 359.029 -213.36)
		(width 0.13208)
		(layer "F.Cu")
		(net "PRSNT_NIC2_FPGA_R_N")
	)
	(via
		(at 375.83491 -191.65697)
		(size 0.508)
		(drill 0.254)
		(layers "F.Cu" "B.Cu")
		(net "PRSNT_NIC2_FPGA_R_N")
	)
	(via
		(at 359.029 -213.36)
		(size 0.508)
		(drill 0.254)
		(layers "F.Cu" "B.Cu")
		(net "PRSNT_NIC2_FPGA_R_N")
	)
	(segment
		(start 360.894122 -213.36)
		(end 361.021122 -213.487)
		(width 0.15494)
		(layer "In7.Cu")
		(net "PRSNT_NIC2_FPGA_R_N")
	)
	(segment
		(start 359.029 -213.36)
		(end 360.894122 -213.36)
		(width 0.15494)
		(layer "In7.Cu")
		(net "PRSNT_NIC2_FPGA_R_N")
	)
	(segment
		(start 370.028216 -207.64373)
		(end 375.83491 -201.837036)
		(width 0.15494)
		(layer "In7.Cu")
		(net "PRSNT_NIC2_FPGA_R_N")
	)
	(segment
		(start 368.431064 -209.321654)
		(end 369.36934 -209.321654)
		(width 0.15494)
		(layer "In7.Cu")
		(net "PRSNT_NIC2_FPGA_R_N")
	)
	(segment
		(start 370.028216 -208.662778)
		(end 370.028216 -207.64373)
		(width 0.15494)
		(layer "In7.Cu")
		(net "PRSNT_NIC2_FPGA_R_N")
	)
	(segment
		(start 361.021122 -213.487)
		(end 364.265718 -213.487)
		(width 0.15494)
		(layer "In7.Cu")
		(net "PRSNT_NIC2_FPGA_R_N")
	)
	(segment
		(start 364.265718 -213.487)
		(end 368.431064 -209.321654)
		(width 0.15494)
		(layer "In7.Cu")
		(net "PRSNT_NIC2_FPGA_R_N")
	)
	(segment
		(start 369.36934 -209.321654)
		(end 370.028216 -208.662778)
		(width 0.15494)
		(layer "In7.Cu")
		(net "PRSNT_NIC2_FPGA_R_N")
	)
	(segment
		(start 375.83491 -201.837036)
		(end 375.83491 -191.65697)
		(width 0.15494)
		(layer "In7.Cu")
		(net "PRSNT_NIC2_FPGA_R_N")
	)
	(segment
		(start 15.804896 -119.541036)
		(end 15.804896 -120.15343)
		(width 0.13208)
		(layer "F.Cu")
		(net "HP_NIC0_EN")
	)
	(segment
		(start 7.213346 -134.042404)
		(end 6.558026 -134.042404)
		(width 0.13208)
		(layer "F.Cu")
		(net "HP_NIC0_EN")
	)
	(segment
		(start 35.55365 -116.690648)
		(end 34.75609 -116.690648)
		(width 0.13208)
		(layer "F.Cu")
		(net "HP_NIC0_EN")
	)
	(segment
		(start 37.83076 -115.803934)
		(end 37.324284 -115.803934)
		(width 0.13208)
		(layer "F.Cu")
		(net "HP_NIC0_EN")
	)
	(segment
		(start 11.319002 -122.46991)
		(end 10.51052 -121.661428)
		(width 0.13208)
		(layer "F.Cu")
		(net "HP_NIC0_EN")
	)
	(segment
		(start 16.431768 -162.404044)
		(end 16.431768 -163.114736)
		(width 0.13208)
		(layer "F.Cu")
		(net "HP_NIC0_EN")
	)
	(segment
		(start 37.324284 -115.803934)
		(end 37.1856 -115.66525)
		(width 0.13208)
		(layer "F.Cu")
		(net "HP_NIC0_EN")
	)
	(segment
		(start 11.4808 -123.869196)
		(end 11.4808 -122.631708)
		(width 0.13208)
		(layer "F.Cu")
		(net "HP_NIC0_EN")
	)
	(segment
		(start 11.4808 -122.631708)
		(end 11.319002 -122.46991)
		(width 0.13208)
		(layer "F.Cu")
		(net "HP_NIC0_EN")
	)
	(segment
		(start 37.1856 -115.66525)
		(end 36.579048 -115.66525)
		(width 0.13208)
		(layer "F.Cu")
		(net "HP_NIC0_EN")
	)
	(segment
		(start 12.006326 -124.394722)
		(end 11.4808 -123.869196)
		(width 0.13208)
		(layer "F.Cu")
		(net "HP_NIC0_EN")
	)
	(segment
		(start 36.579048 -115.66525)
		(end 35.55365 -116.690648)
		(width 0.13208)
		(layer "F.Cu")
		(net "HP_NIC0_EN")
	)
	(segment
		(start 12.231116 -124.394722)
		(end 12.006326 -124.394722)
		(width 0.13208)
		(layer "F.Cu")
		(net "HP_NIC0_EN")
	)
	(via
		(at 6.558026 -134.042404)
		(size 0.508)
		(drill 0.254)
		(layers "F.Cu" "B.Cu")
		(net "HP_NIC0_EN")
	)
	(via
		(at 16.431768 -163.114736)
		(size 0.508)
		(drill 0.254)
		(layers "F.Cu" "B.Cu")
		(net "HP_NIC0_EN")
	)
	(via
		(at 11.319002 -122.46991)
		(size 0.508)
		(drill 0.254)
		(layers "F.Cu" "B.Cu")
		(net "HP_NIC0_EN")
	)
	(via
		(at 15.804896 -120.15343)
		(size 0.508)
		(drill 0.254)
		(layers "F.Cu" "B.Cu")
		(net "HP_NIC0_EN")
	)
	(via
		(at 37.83076 -115.803934)
		(size 0.508)
		(drill 0.254)
		(layers "F.Cu" "B.Cu")
		(net "HP_NIC0_EN")
	)
	(segment
		(start 15.804896 -120.15343)
		(end 15.804896 -118.544594)
		(width 0.13208)
		(layer "B.Cu")
		(net "HP_NIC0_EN")
	)
	(segment
		(start 37.02177 -114.994944)
		(end 37.83076 -115.803934)
		(width 0.13208)
		(layer "B.Cu")
		(net "HP_NIC0_EN")
	)
	(segment
		(start 18.186146 -114.994944)
		(end 37.02177 -114.994944)
		(width 0.13208)
		(layer "B.Cu")
		(net "HP_NIC0_EN")
	)
	(segment
		(start 15.804896 -118.544594)
		(end 16.99895 -117.35054)
		(width 0.13208)
		(layer "B.Cu")
		(net "HP_NIC0_EN")
	)
	(segment
		(start 16.99895 -117.35054)
		(end 16.99895 -116.18214)
		(width 0.13208)
		(layer "B.Cu")
		(net "HP_NIC0_EN")
	)
	(segment
		(start 16.99895 -116.18214)
		(end 18.186146 -114.994944)
		(width 0.13208)
		(layer "B.Cu")
		(net "HP_NIC0_EN")
	)
	(segment
		(start 10.188448 -125.200918)
		(end 10.188448 -123.600464)
		(width 0.15494)
		(layer "In5.Cu")
		(net "HP_NIC0_EN")
	)
	(segment
		(start 10.188448 -123.600464)
		(end 11.319002 -122.46991)
		(width 0.15494)
		(layer "In5.Cu")
		(net "HP_NIC0_EN")
	)
	(segment
		(start 7.243572 -125.47854)
		(end 9.910826 -125.47854)
		(width 0.15494)
		(layer "In5.Cu")
		(net "HP_NIC0_EN")
	)
	(segment
		(start 15.079726 -119.42826)
		(end 15.804896 -120.15343)
		(width 0.15494)
		(layer "In5.Cu")
		(net "HP_NIC0_EN")
	)
	(segment
		(start 11.0998 -119.588788)
		(end 11.260328 -119.42826)
		(width 0.15494)
		(layer "In5.Cu")
		(net "HP_NIC0_EN")
	)
	(segment
		(start 6.558026 -126.164086)
		(end 7.243572 -125.47854)
		(width 0.15494)
		(layer "In5.Cu")
		(net "HP_NIC0_EN")
	)
	(segment
		(start 9.910826 -125.47854)
		(end 10.188448 -125.200918)
		(width 0.15494)
		(layer "In5.Cu")
		(net "HP_NIC0_EN")
	)
	(segment
		(start 6.558026 -134.042404)
		(end 6.558026 -126.164086)
		(width 0.15494)
		(layer "In5.Cu")
		(net "HP_NIC0_EN")
	)
	(segment
		(start 11.260328 -119.42826)
		(end 15.079726 -119.42826)
		(width 0.15494)
		(layer "In5.Cu")
		(net "HP_NIC0_EN")
	)
	(segment
		(start 11.319002 -122.46991)
		(end 11.0998 -122.250708)
		(width 0.15494)
		(layer "In5.Cu")
		(net "HP_NIC0_EN")
	)
	(segment
		(start 11.0998 -122.250708)
		(end 11.0998 -119.588788)
		(width 0.15494)
		(layer "In5.Cu")
		(net "HP_NIC0_EN")
	)
	(segment
		(start 9.069324 -161.684716)
		(end 15.001748 -161.684716)
		(width 0.15494)
		(layer "In7.Cu")
		(net "HP_NIC0_EN")
	)
	(segment
		(start 7.104126 -144.867884)
		(end 6.152642 -145.819368)
		(width 0.15494)
		(layer "In7.Cu")
		(net "HP_NIC0_EN")
	)
	(segment
		(start 6.558026 -134.10311)
		(end 7.104126 -134.64921)
		(width 0.15494)
		(layer "In7.Cu")
		(net "HP_NIC0_EN")
	)
	(segment
		(start 8.179816 -157.278832)
		(end 8.179816 -160.795208)
		(width 0.15494)
		(layer "In7.Cu")
		(net "HP_NIC0_EN")
	)
	(segment
		(start 7.104126 -134.64921)
		(end 7.104126 -144.867884)
		(width 0.15494)
		(layer "In7.Cu")
		(net "HP_NIC0_EN")
	)
	(segment
		(start 6.558026 -134.042404)
		(end 6.558026 -134.10311)
		(width 0.15494)
		(layer "In7.Cu")
		(net "HP_NIC0_EN")
	)
	(segment
		(start 8.179816 -160.795208)
		(end 9.069324 -161.684716)
		(width 0.15494)
		(layer "In7.Cu")
		(net "HP_NIC0_EN")
	)
	(segment
		(start 15.001748 -161.684716)
		(end 16.431768 -163.114736)
		(width 0.15494)
		(layer "In7.Cu")
		(net "HP_NIC0_EN")
	)
	(segment
		(start 6.152642 -155.251658)
		(end 8.179816 -157.278832)
		(width 0.15494)
		(layer "In7.Cu")
		(net "HP_NIC0_EN")
	)
	(segment
		(start 6.152642 -145.819368)
		(end 6.152642 -155.251658)
		(width 0.15494)
		(layer "In7.Cu")
		(net "HP_NIC0_EN")
	)
	(segment
		(start 441.366148 -305.046126)
		(end 441.366148 -304.437034)
		(width 0.13208)
		(layer "F.Cu")
		(net "PEX3_EXT_GPIO_LATCH_N")
	)
	(segment
		(start 419.824916 -308.724808)
		(end 419.349936 -309.199788)
		(width 0.13208)
		(layer "F.Cu")
		(net "PEX3_EXT_GPIO_LATCH_N")
	)
	(segment
		(start 441.366148 -304.437034)
		(end 441.36564 -304.436526)
		(width 0.13208)
		(layer "F.Cu")
		(net "PEX3_EXT_GPIO_LATCH_N")
	)
	(segment
		(start 441.366148 -305.674522)
		(end 441.366148 -305.046126)
		(width 0.13208)
		(layer "F.Cu")
		(net "PEX3_EXT_GPIO_LATCH_N")
	)
	(via
		(at 419.824916 -308.724808)
		(size 0.4064)
		(drill 0.2032)
		(layers "F.Cu" "B.Cu")
		(net "PEX3_EXT_GPIO_LATCH_N")
	)
	(via
		(at 439.536078 -304.197004)
		(size 0.6604)
		(drill 0.3302)
		(layers "F.Cu" "B.Cu")
		(net "PEX3_EXT_GPIO_LATCH_N")
	)
	(via
		(at 441.366148 -305.046126)
		(size 0.508)
		(drill 0.254)
		(layers "F.Cu" "B.Cu")
		(net "PEX3_EXT_GPIO_LATCH_N")
	)
	(segment
		(start 441.366148 -304.696368)
		(end 441.366148 -305.046126)
		(width 0.13208)
		(layer "B.Cu")
		(net "PEX3_EXT_GPIO_LATCH_N")
	)
	(segment
		(start 437.777128 -305.338734)
		(end 437.777128 -304.687478)
		(width 0.13208)
		(layer "B.Cu")
		(net "PEX3_EXT_GPIO_LATCH_N")
	)
	(segment
		(start 420.299896 -309.199788)
		(end 422.423082 -309.199788)
		(width 0.13208)
		(layer "B.Cu")
		(net "PEX3_EXT_GPIO_LATCH_N")
	)
	(segment
		(start 434.378862 -308.737)
		(end 437.777128 -305.338734)
		(width 0.13208)
		(layer "B.Cu")
		(net "PEX3_EXT_GPIO_LATCH_N")
	)
	(segment
		(start 422.88587 -308.737)
		(end 434.378862 -308.737)
		(width 0.13208)
		(layer "B.Cu")
		(net "PEX3_EXT_GPIO_LATCH_N")
	)
	(segment
		(start 439.536078 -304.197004)
		(end 440.866784 -304.197004)
		(width 0.13208)
		(layer "B.Cu")
		(net "PEX3_EXT_GPIO_LATCH_N")
	)
	(segment
		(start 440.866784 -304.197004)
		(end 441.366148 -304.696368)
		(width 0.13208)
		(layer "B.Cu")
		(net "PEX3_EXT_GPIO_LATCH_N")
	)
	(segment
		(start 438.267602 -304.197004)
		(end 439.536078 -304.197004)
		(width 0.13208)
		(layer "B.Cu")
		(net "PEX3_EXT_GPIO_LATCH_N")
	)
	(segment
		(start 437.777128 -304.687478)
		(end 438.267602 -304.197004)
		(width 0.13208)
		(layer "B.Cu")
		(net "PEX3_EXT_GPIO_LATCH_N")
	)
	(segment
		(start 422.423082 -309.199788)
		(end 422.88587 -308.737)
		(width 0.13208)
		(layer "B.Cu")
		(net "PEX3_EXT_GPIO_LATCH_N")
	)
	(segment
		(start 419.824916 -308.724808)
		(end 420.299896 -309.199788)
		(width 0.13208)
		(layer "B.Cu")
		(net "PEX3_EXT_GPIO_LATCH_N")
	)
	(segment
		(start 378.444252 -93.618304)
		(end 377.67006 -93.618304)
		(width 0.13208)
		(layer "F.Cu")
		(net "SMB_BIC_I2C6_R_SDA")
	)
	(segment
		(start 224.422208 -87.716868)
		(end 224.422208 -90.748104)
		(width 0.13208)
		(layer "F.Cu")
		(net "SMB_BIC_I2C6_R_SDA")
	)
	(via
		(at 216.913206 -160.770062)
		(size 0.508)
		(drill 0.254)
		(layers "F.Cu" "B.Cu")
		(net "SMB_BIC_I2C6_R_SDA")
	)
	(via
		(at 215.489536 -223.382586)
		(size 0.508)
		(drill 0.254)
		(layers "F.Cu" "B.Cu")
		(net "SMB_BIC_I2C6_R_SDA")
	)
	(via
		(at 224.422208 -90.748104)
		(size 0.508)
		(drill 0.254)
		(layers "F.Cu" "B.Cu")
		(net "SMB_BIC_I2C6_R_SDA")
	)
	(via
		(at 377.67006 -93.618304)
		(size 0.508)
		(drill 0.254)
		(layers "F.Cu" "B.Cu")
		(net "SMB_BIC_I2C6_R_SDA")
	)
	(via
		(at 277.121874 -95.20174)
		(size 0.508)
		(drill 0.254)
		(layers "F.Cu" "B.Cu")
		(net "SMB_BIC_I2C6_R_SDA")
	)
	(segment
		(start 215.98255 -223.8756)
		(end 215.489536 -223.382586)
		(width 0.13208)
		(layer "B.Cu")
		(net "SMB_BIC_I2C6_R_SDA")
	)
	(segment
		(start 216.835736 -223.42983)
		(end 216.389966 -223.8756)
		(width 0.13208)
		(layer "B.Cu")
		(net "SMB_BIC_I2C6_R_SDA")
	)
	(segment
		(start 216.389966 -223.8756)
		(end 215.98255 -223.8756)
		(width 0.13208)
		(layer "B.Cu")
		(net "SMB_BIC_I2C6_R_SDA")
	)
	(segment
		(start 216.835736 -223.382586)
		(end 216.835736 -223.42983)
		(width 0.13208)
		(layer "B.Cu")
		(net "SMB_BIC_I2C6_R_SDA")
	)
	(segment
		(start 254.652272 -149.8219)
		(end 255.050544 -149.8219)
		(width 0.15494)
		(layer "In5.Cu")
		(net "SMB_BIC_I2C6_R_SDA")
	)
	(segment
		(start 255.050544 -150.46452)
		(end 254.652272 -150.46452)
		(width 0.15494)
		(layer "In5.Cu")
		(net "SMB_BIC_I2C6_R_SDA")
	)
	(segment
		(start 220.122496 -163.706556)
		(end 219.20454 -162.7886)
		(width 0.15494)
		(layer "In5.Cu")
		(net "SMB_BIC_I2C6_R_SDA")
	)
	(segment
		(start 236.694218 -97.812098)
		(end 255.185164 -116.303044)
		(width 0.15494)
		(layer "In5.Cu")
		(net "SMB_BIC_I2C6_R_SDA")
	)
	(segment
		(start 255.050544 -151.10714)
		(end 255.185164 -151.24176)
		(width 0.15494)
		(layer "In5.Cu")
		(net "SMB_BIC_I2C6_R_SDA")
	)
	(segment
		(start 218.184222 -162.7886)
		(end 216.913206 -161.517584)
		(width 0.15494)
		(layer "In5.Cu")
		(net "SMB_BIC_I2C6_R_SDA")
	)
	(segment
		(start 226.503738 -97.501456)
		(end 226.81438 -97.812098)
		(width 0.15494)
		(layer "In5.Cu")
		(net "SMB_BIC_I2C6_R_SDA")
	)
	(segment
		(start 253.8984 -162.763454)
		(end 252.955298 -163.706556)
		(width 0.15494)
		(layer "In5.Cu")
		(net "SMB_BIC_I2C6_R_SDA")
	)
	(segment
		(start 255.050544 -149.17928)
		(end 254.652272 -149.17928)
		(width 0.15494)
		(layer "In5.Cu")
		(net "SMB_BIC_I2C6_R_SDA")
	)
	(segment
		(start 252.955298 -163.706556)
		(end 220.122496 -163.706556)
		(width 0.15494)
		(layer "In5.Cu")
		(net "SMB_BIC_I2C6_R_SDA")
	)
	(segment
		(start 253.8984 -158.121604)
		(end 253.8984 -162.763454)
		(width 0.15494)
		(layer "In5.Cu")
		(net "SMB_BIC_I2C6_R_SDA")
	)
	(segment
		(start 255.185164 -151.24176)
		(end 255.185164 -156.83484)
		(width 0.15494)
		(layer "In5.Cu")
		(net "SMB_BIC_I2C6_R_SDA")
	)
	(segment
		(start 255.185164 -156.83484)
		(end 253.8984 -158.121604)
		(width 0.15494)
		(layer "In5.Cu")
		(net "SMB_BIC_I2C6_R_SDA")
	)
	(segment
		(start 255.050544 -149.8219)
		(end 255.185164 -149.95652)
		(width 0.15494)
		(layer "In5.Cu")
		(net "SMB_BIC_I2C6_R_SDA")
	)
	(segment
		(start 254.652272 -151.10714)
		(end 255.050544 -151.10714)
		(width 0.15494)
		(layer "In5.Cu")
		(net "SMB_BIC_I2C6_R_SDA")
	)
	(segment
		(start 216.913206 -161.517584)
		(end 216.913206 -160.770062)
		(width 0.15494)
		(layer "In5.Cu")
		(net "SMB_BIC_I2C6_R_SDA")
	)
	(segment
		(start 226.503738 -97.060766)
		(end 226.503738 -97.501456)
		(width 0.15494)
		(layer "In5.Cu")
		(net "SMB_BIC_I2C6_R_SDA")
	)
	(segment
		(start 254.517652 -149.68728)
		(end 254.652272 -149.8219)
		(width 0.15494)
		(layer "In5.Cu")
		(net "SMB_BIC_I2C6_R_SDA")
	)
	(segment
		(start 224.422208 -94.979236)
		(end 226.503738 -97.060766)
		(width 0.15494)
		(layer "In5.Cu")
		(net "SMB_BIC_I2C6_R_SDA")
	)
	(segment
		(start 254.517652 -150.59914)
		(end 254.517652 -150.97252)
		(width 0.15494)
		(layer "In5.Cu")
		(net "SMB_BIC_I2C6_R_SDA")
	)
	(segment
		(start 255.185164 -149.95652)
		(end 255.185164 -150.3299)
		(width 0.15494)
		(layer "In5.Cu")
		(net "SMB_BIC_I2C6_R_SDA")
	)
	(segment
		(start 219.20454 -162.7886)
		(end 218.184222 -162.7886)
		(width 0.15494)
		(layer "In5.Cu")
		(net "SMB_BIC_I2C6_R_SDA")
	)
	(segment
		(start 255.185164 -150.3299)
		(end 255.050544 -150.46452)
		(width 0.15494)
		(layer "In5.Cu")
		(net "SMB_BIC_I2C6_R_SDA")
	)
	(segment
		(start 255.185164 -116.303044)
		(end 255.185164 -149.04466)
		(width 0.15494)
		(layer "In5.Cu")
		(net "SMB_BIC_I2C6_R_SDA")
	)
	(segment
		(start 254.652272 -149.17928)
		(end 254.517652 -149.3139)
		(width 0.15494)
		(layer "In5.Cu")
		(net "SMB_BIC_I2C6_R_SDA")
	)
	(segment
		(start 255.185164 -149.04466)
		(end 255.050544 -149.17928)
		(width 0.15494)
		(layer "In5.Cu")
		(net "SMB_BIC_I2C6_R_SDA")
	)
	(segment
		(start 254.652272 -150.46452)
		(end 254.517652 -150.59914)
		(width 0.15494)
		(layer "In5.Cu")
		(net "SMB_BIC_I2C6_R_SDA")
	)
	(segment
		(start 226.81438 -97.812098)
		(end 236.694218 -97.812098)
		(width 0.15494)
		(layer "In5.Cu")
		(net "SMB_BIC_I2C6_R_SDA")
	)
	(segment
		(start 224.422208 -90.748104)
		(end 224.422208 -94.979236)
		(width 0.15494)
		(layer "In5.Cu")
		(net "SMB_BIC_I2C6_R_SDA")
	)
	(segment
		(start 254.517652 -149.3139)
		(end 254.517652 -149.68728)
		(width 0.15494)
		(layer "In5.Cu")
		(net "SMB_BIC_I2C6_R_SDA")
	)
	(segment
		(start 254.517652 -150.97252)
		(end 254.652272 -151.10714)
		(width 0.15494)
		(layer "In5.Cu")
		(net "SMB_BIC_I2C6_R_SDA")
	)
	(segment
		(start 208.493614 -221.8944)
		(end 206.837534 -220.23832)
		(width 0.15494)
		(layer "In7.Cu")
		(net "SMB_BIC_I2C6_R_SDA")
	)
	(segment
		(start 212.971888 -165.386512)
		(end 212.971888 -162.75431)
		(width 0.15494)
		(layer "In7.Cu")
		(net "SMB_BIC_I2C6_R_SDA")
	)
	(segment
		(start 212.971888 -162.75431)
		(end 214.956136 -160.770062)
		(width 0.15494)
		(layer "In7.Cu")
		(net "SMB_BIC_I2C6_R_SDA")
	)
	(segment
		(start 214.097616 -221.8436)
		(end 212.382354 -221.8436)
		(width 0.15494)
		(layer "In7.Cu")
		(net "SMB_BIC_I2C6_R_SDA")
	)
	(segment
		(start 204.0382 -217.85072)
		(end 204.0382 -194.966844)
		(width 0.15494)
		(layer "In7.Cu")
		(net "SMB_BIC_I2C6_R_SDA")
	)
	(segment
		(start 209.778854 -221.5134)
		(end 209.397854 -221.8944)
		(width 0.15494)
		(layer "In7.Cu")
		(net "SMB_BIC_I2C6_R_SDA")
	)
	(segment
		(start 211.798154 -222.4278)
		(end 211.454746 -222.4278)
		(width 0.15494)
		(layer "In7.Cu")
		(net "SMB_BIC_I2C6_R_SDA")
	)
	(segment
		(start 209.397854 -221.8944)
		(end 208.493614 -221.8944)
		(width 0.15494)
		(layer "In7.Cu")
		(net "SMB_BIC_I2C6_R_SDA")
	)
	(segment
		(start 210.540346 -221.5134)
		(end 209.778854 -221.5134)
		(width 0.15494)
		(layer "In7.Cu")
		(net "SMB_BIC_I2C6_R_SDA")
	)
	(segment
		(start 211.454746 -222.4278)
		(end 210.540346 -221.5134)
		(width 0.15494)
		(layer "In7.Cu")
		(net "SMB_BIC_I2C6_R_SDA")
	)
	(segment
		(start 212.382354 -221.8436)
		(end 211.798154 -222.4278)
		(width 0.15494)
		(layer "In7.Cu")
		(net "SMB_BIC_I2C6_R_SDA")
	)
	(segment
		(start 210.36534 -186.484514)
		(end 210.36534 -184.102502)
		(width 0.15494)
		(layer "In7.Cu")
		(net "SMB_BIC_I2C6_R_SDA")
	)
	(segment
		(start 204.0382 -194.966844)
		(end 209.103214 -189.90183)
		(width 0.15494)
		(layer "In7.Cu")
		(net "SMB_BIC_I2C6_R_SDA")
	)
	(segment
		(start 209.7786 -187.071254)
		(end 210.36534 -186.484514)
		(width 0.15494)
		(layer "In7.Cu")
		(net "SMB_BIC_I2C6_R_SDA")
	)
	(segment
		(start 215.489536 -223.382586)
		(end 215.489536 -223.23552)
		(width 0.15494)
		(layer "In7.Cu")
		(net "SMB_BIC_I2C6_R_SDA")
	)
	(segment
		(start 206.4258 -220.23832)
		(end 204.0382 -217.85072)
		(width 0.15494)
		(layer "In7.Cu")
		(net "SMB_BIC_I2C6_R_SDA")
	)
	(segment
		(start 210.36534 -184.102502)
		(end 208.209388 -181.94655)
		(width 0.15494)
		(layer "In7.Cu")
		(net "SMB_BIC_I2C6_R_SDA")
	)
	(segment
		(start 215.489536 -223.23552)
		(end 214.097616 -221.8436)
		(width 0.15494)
		(layer "In7.Cu")
		(net "SMB_BIC_I2C6_R_SDA")
	)
	(segment
		(start 209.103214 -189.021974)
		(end 209.7786 -188.346588)
		(width 0.15494)
		(layer "In7.Cu")
		(net "SMB_BIC_I2C6_R_SDA")
	)
	(segment
		(start 208.209388 -170.149012)
		(end 212.971888 -165.386512)
		(width 0.15494)
		(layer "In7.Cu")
		(net "SMB_BIC_I2C6_R_SDA")
	)
	(segment
		(start 208.209388 -181.94655)
		(end 208.209388 -170.149012)
		(width 0.15494)
		(layer "In7.Cu")
		(net "SMB_BIC_I2C6_R_SDA")
	)
	(segment
		(start 209.7786 -188.346588)
		(end 209.7786 -187.071254)
		(width 0.15494)
		(layer "In7.Cu")
		(net "SMB_BIC_I2C6_R_SDA")
	)
	(segment
		(start 206.837534 -220.23832)
		(end 206.4258 -220.23832)
		(width 0.15494)
		(layer "In7.Cu")
		(net "SMB_BIC_I2C6_R_SDA")
	)
	(segment
		(start 209.103214 -189.90183)
		(end 209.103214 -189.021974)
		(width 0.15494)
		(layer "In7.Cu")
		(net "SMB_BIC_I2C6_R_SDA")
	)
	(segment
		(start 214.956136 -160.770062)
		(end 216.913206 -160.770062)
		(width 0.15494)
		(layer "In7.Cu")
		(net "SMB_BIC_I2C6_R_SDA")
	)
	(segment
		(start 228.797866 -94.59722)
		(end 231.367584 -97.166938)
		(width 0.15494)
		(layer "In9.Cu")
		(net "SMB_BIC_I2C6_R_SDA")
	)
	(segment
		(start 271.886934 -89.9668)
		(end 277.121874 -95.20174)
		(width 0.15494)
		(layer "In9.Cu")
		(net "SMB_BIC_I2C6_R_SDA")
	)
	(segment
		(start 225.234754 -92.981018)
		(end 226.850956 -94.59722)
		(width 0.15494)
		(layer "In9.Cu")
		(net "SMB_BIC_I2C6_R_SDA")
	)
	(segment
		(start 231.367584 -97.166938)
		(end 251.700538 -97.166938)
		(width 0.15494)
		(layer "In9.Cu")
		(net "SMB_BIC_I2C6_R_SDA")
	)
	(segment
		(start 225.234754 -91.56065)
		(end 225.234754 -92.981018)
		(width 0.15494)
		(layer "In9.Cu")
		(net "SMB_BIC_I2C6_R_SDA")
	)
	(segment
		(start 224.422208 -90.748104)
		(end 225.234754 -91.56065)
		(width 0.15494)
		(layer "In9.Cu")
		(net "SMB_BIC_I2C6_R_SDA")
	)
	(segment
		(start 267.266674 -89.9668)
		(end 271.886934 -89.9668)
		(width 0.15494)
		(layer "In9.Cu")
		(net "SMB_BIC_I2C6_R_SDA")
	)
	(segment
		(start 226.850956 -94.59722)
		(end 228.797866 -94.59722)
		(width 0.15494)
		(layer "In9.Cu")
		(net "SMB_BIC_I2C6_R_SDA")
	)
	(segment
		(start 265.361674 -91.8718)
		(end 267.266674 -89.9668)
		(width 0.15494)
		(layer "In9.Cu")
		(net "SMB_BIC_I2C6_R_SDA")
	)
	(segment
		(start 256.995676 -91.8718)
		(end 265.361674 -91.8718)
		(width 0.15494)
		(layer "In9.Cu")
		(net "SMB_BIC_I2C6_R_SDA")
	)
	(segment
		(start 251.700538 -97.166938)
		(end 256.995676 -91.8718)
		(width 0.15494)
		(layer "In9.Cu")
		(net "SMB_BIC_I2C6_R_SDA")
	)
	(segment
		(start 332.1812 -99.4156)
		(end 334.8228 -102.0572)
		(width 0.15494)
		(layer "In13.Cu")
		(net "SMB_BIC_I2C6_R_SDA")
	)
	(segment
		(start 277.474934 -95.5548)
		(end 278.078946 -95.5548)
		(width 0.15494)
		(layer "In13.Cu")
		(net "SMB_BIC_I2C6_R_SDA")
	)
	(segment
		(start 278.413718 -93.335856)
		(end 279.473152 -92.276422)
		(width 0.15494)
		(layer "In13.Cu")
		(net "SMB_BIC_I2C6_R_SDA")
	)
	(segment
		(start 334.8228 -103.352346)
		(end 335.661254 -104.1908)
		(width 0.15494)
		(layer "In13.Cu")
		(net "SMB_BIC_I2C6_R_SDA")
	)
	(segment
		(start 362.73105 -102.108)
		(end 369.084352 -95.754698)
		(width 0.15494)
		(layer "In13.Cu")
		(net "SMB_BIC_I2C6_R_SDA")
	)
	(segment
		(start 312.089292 -92.861638)
		(end 316.964568 -97.736914)
		(width 0.15494)
		(layer "In13.Cu")
		(net "SMB_BIC_I2C6_R_SDA")
	)
	(segment
		(start 278.413718 -95.220028)
		(end 278.413718 -93.335856)
		(width 0.15494)
		(layer "In13.Cu")
		(net "SMB_BIC_I2C6_R_SDA")
	)
	(segment
		(start 327.4314 -98.7806)
		(end 328.0664 -99.4156)
		(width 0.15494)
		(layer "In13.Cu")
		(net "SMB_BIC_I2C6_R_SDA")
	)
	(segment
		(start 339.0646 -104.1908)
		(end 341.1474 -102.108)
		(width 0.15494)
		(layer "In13.Cu")
		(net "SMB_BIC_I2C6_R_SDA")
	)
	(segment
		(start 334.8228 -102.0572)
		(end 334.8228 -103.352346)
		(width 0.15494)
		(layer "In13.Cu")
		(net "SMB_BIC_I2C6_R_SDA")
	)
	(segment
		(start 377.135136 -94.153228)
		(end 377.67006 -93.618304)
		(width 0.15494)
		(layer "In13.Cu")
		(net "SMB_BIC_I2C6_R_SDA")
	)
	(segment
		(start 341.1474 -102.108)
		(end 362.73105 -102.108)
		(width 0.15494)
		(layer "In13.Cu")
		(net "SMB_BIC_I2C6_R_SDA")
	)
	(segment
		(start 322.212208 -98.7806)
		(end 327.4314 -98.7806)
		(width 0.15494)
		(layer "In13.Cu")
		(net "SMB_BIC_I2C6_R_SDA")
	)
	(segment
		(start 277.121874 -95.20174)
		(end 277.474934 -95.5548)
		(width 0.15494)
		(layer "In13.Cu")
		(net "SMB_BIC_I2C6_R_SDA")
	)
	(segment
		(start 316.964568 -97.736914)
		(end 322.212208 -98.7806)
		(width 0.15494)
		(layer "In13.Cu")
		(net "SMB_BIC_I2C6_R_SDA")
	)
	(segment
		(start 279.473152 -92.276422)
		(end 309.146194 -92.276422)
		(width 0.15494)
		(layer "In13.Cu")
		(net "SMB_BIC_I2C6_R_SDA")
	)
	(segment
		(start 369.084352 -95.754698)
		(end 377.135136 -94.153228)
		(width 0.15494)
		(layer "In13.Cu")
		(net "SMB_BIC_I2C6_R_SDA")
	)
	(segment
		(start 328.0664 -99.4156)
		(end 332.1812 -99.4156)
		(width 0.15494)
		(layer "In13.Cu")
		(net "SMB_BIC_I2C6_R_SDA")
	)
	(segment
		(start 335.661254 -104.1908)
		(end 339.0646 -104.1908)
		(width 0.15494)
		(layer "In13.Cu")
		(net "SMB_BIC_I2C6_R_SDA")
	)
	(segment
		(start 309.146194 -92.276422)
		(end 312.089292 -92.861638)
		(width 0.15494)
		(layer "In13.Cu")
		(net "SMB_BIC_I2C6_R_SDA")
	)
	(segment
		(start 278.078946 -95.5548)
		(end 278.413718 -95.220028)
		(width 0.15494)
		(layer "In13.Cu")
		(net "SMB_BIC_I2C6_R_SDA")
	)
	(segment
		(start 337.312 -176.911)
		(end 337.058 -176.657)
		(width 0.13208)
		(layer "F.Cu")
		(net "RST_PEX_SSD9_PERST_R_N")
	)
	(segment
		(start 336.804 -176.911)
		(end 336.44205 -176.911)
		(width 0.13208)
		(layer "F.Cu")
		(net "RST_PEX_SSD9_PERST_R_N")
	)
	(segment
		(start 338.093812 -217.587068)
		(end 337.694016 -217.187272)
		(width 0.13208)
		(layer "F.Cu")
		(net "RST_PEX_SSD9_PERST_R_N")
	)
	(segment
		(start 337.67395 -176.911)
		(end 337.312 -176.911)
		(width 0.13208)
		(layer "F.Cu")
		(net "RST_PEX_SSD9_PERST_R_N")
	)
	(segment
		(start 337.058 -176.657)
		(end 336.804 -176.911)
		(width 0.13208)
		(layer "F.Cu")
		(net "RST_PEX_SSD9_PERST_R_N")
	)
	(via
		(at 337.058 -176.657)
		(size 0.508)
		(drill 0.254)
		(layers "F.Cu" "B.Cu")
		(net "RST_PEX_SSD9_PERST_R_N")
	)
	(via
		(at 337.694016 -217.187272)
		(size 0.4572)
		(drill 0.254)
		(layers "F.Cu" "B.Cu")
		(net "RST_PEX_SSD9_PERST_R_N")
	)
	(segment
		(start 329.953112 -212.686392)
		(end 327.99274 -210.72602)
		(width 0.15494)
		(layer "In7.Cu")
		(net "RST_PEX_SSD9_PERST_R_N")
	)
	(segment
		(start 333.157322 -217.587322)
		(end 330.84008 -215.27008)
		(width 0.15494)
		(layer "In7.Cu")
		(net "RST_PEX_SSD9_PERST_R_N")
	)
	(segment
		(start 330.84008 -214.895176)
		(end 329.953112 -214.008208)
		(width 0.15494)
		(layer "In7.Cu")
		(net "RST_PEX_SSD9_PERST_R_N")
	)
	(segment
		(start 332.067154 -179.869846)
		(end 334.495648 -177.441352)
		(width 0.15494)
		(layer "In7.Cu")
		(net "RST_PEX_SSD9_PERST_R_N")
	)
	(segment
		(start 337.293966 -217.587322)
		(end 333.4512 -217.587322)
		(width 0.0889)
		(layer "In7.Cu")
		(net "RST_PEX_SSD9_PERST_R_N")
	)
	(segment
		(start 327.10755 -205.644496)
		(end 327.10755 -203.432664)
		(width 0.15494)
		(layer "In7.Cu")
		(net "RST_PEX_SSD9_PERST_R_N")
	)
	(segment
		(start 333.4512 -217.587322)
		(end 333.157322 -217.587322)
		(width 0.15494)
		(layer "In7.Cu")
		(net "RST_PEX_SSD9_PERST_R_N")
	)
	(segment
		(start 332.067154 -198.47306)
		(end 332.067154 -179.869846)
		(width 0.15494)
		(layer "In7.Cu")
		(net "RST_PEX_SSD9_PERST_R_N")
	)
	(segment
		(start 330.84008 -215.27008)
		(end 330.84008 -214.895176)
		(width 0.15494)
		(layer "In7.Cu")
		(net "RST_PEX_SSD9_PERST_R_N")
	)
	(segment
		(start 336.273648 -177.441352)
		(end 337.058 -176.657)
		(width 0.15494)
		(layer "In7.Cu")
		(net "RST_PEX_SSD9_PERST_R_N")
	)
	(segment
		(start 327.99274 -206.529686)
		(end 327.10755 -205.644496)
		(width 0.15494)
		(layer "In7.Cu")
		(net "RST_PEX_SSD9_PERST_R_N")
	)
	(segment
		(start 329.953112 -214.008208)
		(end 329.953112 -212.686392)
		(width 0.15494)
		(layer "In7.Cu")
		(net "RST_PEX_SSD9_PERST_R_N")
	)
	(segment
		(start 337.694016 -217.187272)
		(end 337.293966 -217.587322)
		(width 0.0889)
		(layer "In7.Cu")
		(net "RST_PEX_SSD9_PERST_R_N")
	)
	(segment
		(start 327.10755 -203.432664)
		(end 332.067154 -198.47306)
		(width 0.15494)
		(layer "In7.Cu")
		(net "RST_PEX_SSD9_PERST_R_N")
	)
	(segment
		(start 327.99274 -210.72602)
		(end 327.99274 -206.529686)
		(width 0.15494)
		(layer "In7.Cu")
		(net "RST_PEX_SSD9_PERST_R_N")
	)
	(segment
		(start 334.495648 -177.441352)
		(end 336.273648 -177.441352)
		(width 0.15494)
		(layer "In7.Cu")
		(net "RST_PEX_SSD9_PERST_R_N")
	)
	(via
		(at 228.144578 -152.372314)
		(size 0.508)
		(drill 0.254)
		(layers "F.Cu" "B.Cu")
		(net "P3V3_CLK_GEN_VDDMXCK_CK440_PEX")
	)
	(via
		(at 225.183446 -140.706602)
		(size 0.508)
		(drill 0.254)
		(layers "F.Cu" "B.Cu")
		(net "P3V3_CLK_GEN_VDDMXCK_CK440_PEX")
	)
	(via
		(at 223.807274 -146.646646)
		(size 0.508)
		(drill 0.254)
		(layers "F.Cu" "B.Cu")
		(net "P3V3_CLK_GEN_VDDMXCK_CK440_PEX")
	)
	(via
		(at 226.484942 -152.412446)
		(size 0.508)
		(drill 0.254)
		(layers "F.Cu" "B.Cu")
		(net "P3V3_CLK_GEN_VDDMXCK_CK440_PEX")
	)
	(via
		(at 222.8596 -148.368004)
		(size 0.6604)
		(drill 0.3302)
		(layers "F.Cu" "B.Cu")
		(net "P3V3_CLK_GEN_VDDMXCK_CK440_PEX")
	)
	(via
		(at 223.894904 -149.403308)
		(size 0.508)
		(drill 0.254)
		(layers "F.Cu" "B.Cu")
		(net "P3V3_CLK_GEN_VDDMXCK_CK440_PEX")
	)
	(segment
		(start 226.047046 -140.706602)
		(end 225.183446 -140.706602)
		(width 0.508)
		(layer "B.Cu")
		(net "P3V3_CLK_GEN_VDDMXCK_CK440_PEX")
	)
	(segment
		(start 225.036888 -86.700868)
		(end 225.086418 -86.750398)
		(width 0.13208)
		(layer "F.Cu")
		(net "SMB_BIC_I2C6_R_SCL")
	)
	(segment
		(start 225.086418 -86.750398)
		(end 225.631248 -86.750398)
		(width 0.13208)
		(layer "F.Cu")
		(net "SMB_BIC_I2C6_R_SCL")
	)
	(segment
		(start 224.422208 -86.700868)
		(end 225.036888 -86.700868)
		(width 0.13208)
		(layer "F.Cu")
		(net "SMB_BIC_I2C6_R_SCL")
	)
	(segment
		(start 225.758248 -90.772488)
		(end 225.758248 -86.877398)
		(width 0.13208)
		(layer "F.Cu")
		(net "SMB_BIC_I2C6_R_SCL")
	)
	(segment
		(start 225.758248 -86.877398)
		(end 225.631248 -86.750398)
		(width 0.13208)
		(layer "F.Cu")
		(net "SMB_BIC_I2C6_R_SCL")
	)
	(via
		(at 215.4428 -224.3836)
		(size 0.508)
		(drill 0.254)
		(layers "F.Cu" "B.Cu")
		(net "SMB_BIC_I2C6_R_SCL")
	)
	(via
		(at 225.758248 -90.772488)
		(size 0.508)
		(drill 0.254)
		(layers "F.Cu" "B.Cu")
		(net "SMB_BIC_I2C6_R_SCL")
	)
	(via
		(at 216.913206 -160.135062)
		(size 0.508)
		(drill 0.254)
		(layers "F.Cu" "B.Cu")
		(net "SMB_BIC_I2C6_R_SCL")
	)
	(segment
		(start 215.4428 -224.4344)
		(end 215.891364 -224.882964)
		(width 0.13208)
		(layer "B.Cu")
		(net "SMB_BIC_I2C6_R_SCL")
	)
	(segment
		(start 215.4428 -224.3836)
		(end 215.4428 -224.4344)
		(width 0.13208)
		(layer "B.Cu")
		(net "SMB_BIC_I2C6_R_SCL")
	)
	(segment
		(start 216.835736 -224.56521)
		(end 216.835736 -224.398586)
		(width 0.13208)
		(layer "B.Cu")
		(net "SMB_BIC_I2C6_R_SCL")
	)
	(segment
		(start 216.517982 -224.882964)
		(end 216.835736 -224.56521)
		(width 0.13208)
		(layer "B.Cu")
		(net "SMB_BIC_I2C6_R_SCL")
	)
	(segment
		(start 215.891364 -224.882964)
		(end 216.517982 -224.882964)
		(width 0.13208)
		(layer "B.Cu")
		(net "SMB_BIC_I2C6_R_SCL")
	)
	(segment
		(start 230.429054 -97.352358)
		(end 229.89032 -96.813624)
		(width 0.15494)
		(layer "In5.Cu")
		(net "SMB_BIC_I2C6_R_SCL")
	)
	(segment
		(start 219.912946 -164.338)
		(end 253.3396 -164.338)
		(width 0.15494)
		(layer "In5.Cu")
		(net "SMB_BIC_I2C6_R_SCL")
	)
	(segment
		(start 229.89032 -96.813624)
		(end 227.258118 -96.813624)
		(width 0.15494)
		(layer "In5.Cu")
		(net "SMB_BIC_I2C6_R_SCL")
	)
	(segment
		(start 253.3396 -164.338)
		(end 254.6604 -163.0172)
		(width 0.15494)
		(layer "In5.Cu")
		(net "SMB_BIC_I2C6_R_SCL")
	)
	(segment
		(start 236.884718 -97.352358)
		(end 230.429054 -97.352358)
		(width 0.15494)
		(layer "In5.Cu")
		(net "SMB_BIC_I2C6_R_SCL")
	)
	(segment
		(start 216.750138 -160.135062)
		(end 216.3826 -160.5026)
		(width 0.15494)
		(layer "In5.Cu")
		(net "SMB_BIC_I2C6_R_SCL")
	)
	(segment
		(start 216.3826 -160.5026)
		(end 216.3826 -161.9504)
		(width 0.15494)
		(layer "In5.Cu")
		(net "SMB_BIC_I2C6_R_SCL")
	)
	(segment
		(start 219.074746 -163.4998)
		(end 219.912946 -164.338)
		(width 0.15494)
		(layer "In5.Cu")
		(net "SMB_BIC_I2C6_R_SCL")
	)
	(segment
		(start 216.913206 -160.135062)
		(end 216.750138 -160.135062)
		(width 0.15494)
		(layer "In5.Cu")
		(net "SMB_BIC_I2C6_R_SCL")
	)
	(segment
		(start 217.932 -163.4998)
		(end 219.074746 -163.4998)
		(width 0.15494)
		(layer "In5.Cu")
		(net "SMB_BIC_I2C6_R_SCL")
	)
	(segment
		(start 254.6604 -163.0172)
		(end 254.6604 -160.852612)
		(width 0.15494)
		(layer "In5.Cu")
		(net "SMB_BIC_I2C6_R_SCL")
	)
	(segment
		(start 227.258118 -96.813624)
		(end 225.163888 -94.719394)
		(width 0.15494)
		(layer "In5.Cu")
		(net "SMB_BIC_I2C6_R_SCL")
	)
	(segment
		(start 255.757426 -116.225066)
		(end 236.884718 -97.352358)
		(width 0.15494)
		(layer "In5.Cu")
		(net "SMB_BIC_I2C6_R_SCL")
	)
	(segment
		(start 254.6604 -160.852612)
		(end 255.757426 -159.755586)
		(width 0.15494)
		(layer "In5.Cu")
		(net "SMB_BIC_I2C6_R_SCL")
	)
	(segment
		(start 225.163888 -91.366848)
		(end 225.758248 -90.772488)
		(width 0.15494)
		(layer "In5.Cu")
		(net "SMB_BIC_I2C6_R_SCL")
	)
	(segment
		(start 225.163888 -94.719394)
		(end 225.163888 -91.366848)
		(width 0.15494)
		(layer "In5.Cu")
		(net "SMB_BIC_I2C6_R_SCL")
	)
	(segment
		(start 216.3826 -161.9504)
		(end 217.932 -163.4998)
		(width 0.15494)
		(layer "In5.Cu")
		(net "SMB_BIC_I2C6_R_SCL")
	)
	(segment
		(start 255.757426 -159.755586)
		(end 255.757426 -116.225066)
		(width 0.15494)
		(layer "In5.Cu")
		(net "SMB_BIC_I2C6_R_SCL")
	)
	(segment
		(start 208.643474 -189.711076)
		(end 208.643474 -188.83122)
		(width 0.15494)
		(layer "In7.Cu")
		(net "SMB_BIC_I2C6_R_SCL")
	)
	(segment
		(start 215.4428 -224.256346)
		(end 215.069928 -223.883474)
		(width 0.15494)
		(layer "In7.Cu")
		(net "SMB_BIC_I2C6_R_SCL")
	)
	(segment
		(start 214.240872 -223.883474)
		(end 213.249002 -222.891604)
		(width 0.15494)
		(layer "In7.Cu")
		(net "SMB_BIC_I2C6_R_SCL")
	)
	(segment
		(start 203.57846 -218.04122)
		(end 203.57846 -194.77609)
		(width 0.15494)
		(layer "In7.Cu")
		(net "SMB_BIC_I2C6_R_SCL")
	)
	(segment
		(start 212.43544 -165.18636)
		(end 212.43544 -162.53206)
		(width 0.15494)
		(layer "In7.Cu")
		(net "SMB_BIC_I2C6_R_SCL")
	)
	(segment
		(start 209.296 -188.178694)
		(end 209.296 -186.903614)
		(width 0.15494)
		(layer "In7.Cu")
		(net "SMB_BIC_I2C6_R_SCL")
	)
	(segment
		(start 208.594706 -222.645732)
		(end 206.647034 -220.69806)
		(width 0.15494)
		(layer "In7.Cu")
		(net "SMB_BIC_I2C6_R_SCL")
	)
	(segment
		(start 203.57846 -194.77609)
		(end 208.643474 -189.711076)
		(width 0.15494)
		(layer "In7.Cu")
		(net "SMB_BIC_I2C6_R_SCL")
	)
	(segment
		(start 214.832438 -160.135062)
		(end 216.913206 -160.135062)
		(width 0.15494)
		(layer "In7.Cu")
		(net "SMB_BIC_I2C6_R_SCL")
	)
	(segment
		(start 209.9056 -186.294014)
		(end 209.9056 -184.293002)
		(width 0.15494)
		(layer "In7.Cu")
		(net "SMB_BIC_I2C6_R_SCL")
	)
	(segment
		(start 212.43544 -162.53206)
		(end 214.832438 -160.135062)
		(width 0.15494)
		(layer "In7.Cu")
		(net "SMB_BIC_I2C6_R_SCL")
	)
	(segment
		(start 213.249002 -222.891604)
		(end 210.92922 -222.891604)
		(width 0.15494)
		(layer "In7.Cu")
		(net "SMB_BIC_I2C6_R_SCL")
	)
	(segment
		(start 209.9056 -184.293002)
		(end 207.749648 -182.13705)
		(width 0.15494)
		(layer "In7.Cu")
		(net "SMB_BIC_I2C6_R_SCL")
	)
	(segment
		(start 206.647034 -220.69806)
		(end 206.2353 -220.69806)
		(width 0.15494)
		(layer "In7.Cu")
		(net "SMB_BIC_I2C6_R_SCL")
	)
	(segment
		(start 210.683348 -222.645732)
		(end 208.594706 -222.645732)
		(width 0.15494)
		(layer "In7.Cu")
		(net "SMB_BIC_I2C6_R_SCL")
	)
	(segment
		(start 215.4428 -224.3836)
		(end 215.4428 -224.256346)
		(width 0.15494)
		(layer "In7.Cu")
		(net "SMB_BIC_I2C6_R_SCL")
	)
	(segment
		(start 209.296 -186.903614)
		(end 209.9056 -186.294014)
		(width 0.15494)
		(layer "In7.Cu")
		(net "SMB_BIC_I2C6_R_SCL")
	)
	(segment
		(start 207.749648 -169.872152)
		(end 212.43544 -165.18636)
		(width 0.15494)
		(layer "In7.Cu")
		(net "SMB_BIC_I2C6_R_SCL")
	)
	(segment
		(start 206.2353 -220.69806)
		(end 203.57846 -218.04122)
		(width 0.15494)
		(layer "In7.Cu")
		(net "SMB_BIC_I2C6_R_SCL")
	)
	(segment
		(start 210.92922 -222.891604)
		(end 210.683348 -222.645732)
		(width 0.15494)
		(layer "In7.Cu")
		(net "SMB_BIC_I2C6_R_SCL")
	)
	(segment
		(start 207.749648 -182.13705)
		(end 207.749648 -169.872152)
		(width 0.15494)
		(layer "In7.Cu")
		(net "SMB_BIC_I2C6_R_SCL")
	)
	(segment
		(start 215.069928 -223.883474)
		(end 214.240872 -223.883474)
		(width 0.15494)
		(layer "In7.Cu")
		(net "SMB_BIC_I2C6_R_SCL")
	)
	(segment
		(start 208.643474 -188.83122)
		(end 209.296 -188.178694)
		(width 0.15494)
		(layer "In7.Cu")
		(net "SMB_BIC_I2C6_R_SCL")
	)
	(segment
		(start 337.312 -180.975)
		(end 337.058 -180.721)
		(width 0.13208)
		(layer "F.Cu")
		(net "RST_PEX_SSD8_PERST_R_N")
	)
	(segment
		(start 334.89392 -215.987122)
		(end 334.494124 -215.587326)
		(width 0.13208)
		(layer "F.Cu")
		(net "RST_PEX_SSD8_PERST_R_N")
	)
	(segment
		(start 336.804 -180.975)
		(end 336.44205 -180.975)
		(width 0.13208)
		(layer "F.Cu")
		(net "RST_PEX_SSD8_PERST_R_N")
	)
	(segment
		(start 337.67395 -180.975)
		(end 337.312 -180.975)
		(width 0.13208)
		(layer "F.Cu")
		(net "RST_PEX_SSD8_PERST_R_N")
	)
	(segment
		(start 337.058 -180.721)
		(end 336.804 -180.975)
		(width 0.13208)
		(layer "F.Cu")
		(net "RST_PEX_SSD8_PERST_R_N")
	)
	(via
		(at 334.494124 -215.587326)
		(size 0.4572)
		(drill 0.254)
		(layers "F.Cu" "B.Cu")
		(net "RST_PEX_SSD8_PERST_R_N")
	)
	(via
		(at 337.058 -180.721)
		(size 0.508)
		(drill 0.254)
		(layers "F.Cu" "B.Cu")
		(net "RST_PEX_SSD8_PERST_R_N")
	)
	(segment
		(start 329.672696 -212.391498)
		(end 327.756774 -210.475576)
		(width 0.15494)
		(layer "In11.Cu")
		(net "RST_PEX_SSD8_PERST_R_N")
	)
	(segment
		(start 332.259686 -216.054178)
		(end 329.992736 -213.787228)
		(width 0.15494)
		(layer "In11.Cu")
		(net "RST_PEX_SSD8_PERST_R_N")
	)
	(segment
		(start 334.494124 -215.587326)
		(end 334.027272 -216.054178)
		(width 0.15494)
		(layer "In11.Cu")
		(net "RST_PEX_SSD8_PERST_R_N")
	)
	(segment
		(start 334.027272 -216.054178)
		(end 332.259686 -216.054178)
		(width 0.15494)
		(layer "In11.Cu")
		(net "RST_PEX_SSD8_PERST_R_N")
	)
	(segment
		(start 327.756774 -207.716882)
		(end 326.437244 -206.397352)
		(width 0.15494)
		(layer "In11.Cu")
		(net "RST_PEX_SSD8_PERST_R_N")
	)
	(segment
		(start 326.437244 -202.375516)
		(end 336.042 -192.77076)
		(width 0.15494)
		(layer "In11.Cu")
		(net "RST_PEX_SSD8_PERST_R_N")
	)
	(segment
		(start 329.992736 -213.787228)
		(end 329.992736 -213.197186)
		(width 0.15494)
		(layer "In11.Cu")
		(net "RST_PEX_SSD8_PERST_R_N")
	)
	(segment
		(start 336.042 -181.737)
		(end 337.058 -180.721)
		(width 0.15494)
		(layer "In11.Cu")
		(net "RST_PEX_SSD8_PERST_R_N")
	)
	(segment
		(start 327.756774 -210.475576)
		(end 327.756774 -207.716882)
		(width 0.15494)
		(layer "In11.Cu")
		(net "RST_PEX_SSD8_PERST_R_N")
	)
	(segment
		(start 329.992736 -213.197186)
		(end 329.672696 -212.424518)
		(width 0.15494)
		(layer "In11.Cu")
		(net "RST_PEX_SSD8_PERST_R_N")
	)
	(segment
		(start 329.672696 -212.424518)
		(end 329.672696 -212.391498)
		(width 0.15494)
		(layer "In11.Cu")
		(net "RST_PEX_SSD8_PERST_R_N")
	)
	(segment
		(start 336.042 -192.77076)
		(end 336.042 -181.737)
		(width 0.15494)
		(layer "In11.Cu")
		(net "RST_PEX_SSD8_PERST_R_N")
	)
	(segment
		(start 326.437244 -206.397352)
		(end 326.437244 -202.375516)
		(width 0.15494)
		(layer "In11.Cu")
		(net "RST_PEX_SSD8_PERST_R_N")
	)
	(segment
		(start 372.114064 -184.793128)
		(end 372.122192 -184.785)
		(width 0.13208)
		(layer "F.Cu")
		(net "PRSNT_NIC1_FPGA_PCA9555_N")
	)
	(segment
		(start 372.122192 -184.785)
		(end 373.888 -184.785)
		(width 0.13208)
		(layer "F.Cu")
		(net "PRSNT_NIC1_FPGA_PCA9555_N")
	)
	(segment
		(start 373.888 -184.785)
		(end 374.904 -183.769)
		(width 0.13208)
		(layer "F.Cu")
		(net "PRSNT_NIC1_FPGA_PCA9555_N")
	)
	(segment
		(start 374.904 -183.769)
		(end 376.53595 -183.769)
		(width 0.13208)
		(layer "F.Cu")
		(net "PRSNT_NIC1_FPGA_PCA9555_N")
	)
	(via
		(at 373.888 -184.785)
		(size 0.508)
		(drill 0.254)
		(layers "F.Cu" "B.Cu")
		(net "PRSNT_NIC1_FPGA_PCA9555_N")
	)
	(via
		(at 234.062778 -147.012914)
		(size 0.508)
		(drill 0.254)
		(layers "F.Cu" "B.Cu")
		(net "P3V3_CLK_GEN_VDDA100M_CK440_PEX")
	)
	(via
		(at 235.531152 -144.047718)
		(size 0.6604)
		(drill 0.3302)
		(layers "F.Cu" "B.Cu")
		(net "P3V3_CLK_GEN_VDDA100M_CK440_PEX")
	)
	(via
		(at 233.435652 -147.162012)
		(size 0.508)
		(drill 0.254)
		(layers "F.Cu" "B.Cu")
		(net "P3V3_CLK_GEN_VDDA100M_CK440_PEX")
	)
	(via
		(at 234.011724 -144.09293)
		(size 0.6604)
		(drill 0.3302)
		(layers "F.Cu" "B.Cu")
		(net "P3V3_CLK_GEN_VDDA100M_CK440_PEX")
	)
	(segment
		(start 364.106206 -187.492894)
		(end 363.293406 -186.680094)
		(width 0.13208)
		(layer "F.Cu")
		(net "PRSNT_SSD3_FPGA_PCA9555_N")
	)
	(segment
		(start 362.795312 -186.182)
		(end 361.58805 -186.182)
		(width 0.13208)
		(layer "F.Cu")
		(net "PRSNT_SSD3_FPGA_PCA9555_N")
	)
	(segment
		(start 363.293406 -186.680094)
		(end 362.795312 -186.182)
		(width 0.13208)
		(layer "F.Cu")
		(net "PRSNT_SSD3_FPGA_PCA9555_N")
	)
	(segment
		(start 366.263936 -187.492894)
		(end 364.106206 -187.492894)
		(width 0.13208)
		(layer "F.Cu")
		(net "PRSNT_SSD3_FPGA_PCA9555_N")
	)
	(via
		(at 363.293406 -186.680094)
		(size 0.508)
		(drill 0.254)
		(layers "F.Cu" "B.Cu")
		(net "PRSNT_SSD3_FPGA_PCA9555_N")
	)
	(segment
		(start 358.41305 -215.392)
		(end 359.029 -215.392)
		(width 0.13208)
		(layer "F.Cu")
		(net "PRSNT_NIC1_FPGA_R_N")
	)
	(segment
		(start 377.20905 -183.10479)
		(end 377.33605 -183.23179)
		(width 0.13208)
		(layer "F.Cu")
		(net "PRSNT_NIC1_FPGA_R_N")
	)
	(segment
		(start 375.858786 -183.10479)
		(end 377.20905 -183.10479)
		(width 0.13208)
		(layer "F.Cu")
		(net "PRSNT_NIC1_FPGA_R_N")
	)
	(segment
		(start 377.33605 -183.23179)
		(end 377.33605 -183.769)
		(width 0.13208)
		(layer "F.Cu")
		(net "PRSNT_NIC1_FPGA_R_N")
	)
	(via
		(at 359.029 -215.392)
		(size 0.508)
		(drill 0.254)
		(layers "F.Cu" "B.Cu")
		(net "PRSNT_NIC1_FPGA_R_N")
	)
	(via
		(at 375.858786 -183.10479)
		(size 0.508)
		(drill 0.254)
		(layers "F.Cu" "B.Cu")
		(net "PRSNT_NIC1_FPGA_R_N")
	)
	(segment
		(start 359.029 -215.392)
		(end 359.93959 -214.48141)
		(width 0.15494)
		(layer "In7.Cu")
		(net "PRSNT_NIC1_FPGA_R_N")
	)
	(segment
		(start 369.797584 -210.672172)
		(end 370.680234 -209.789522)
		(width 0.15494)
		(layer "In7.Cu")
		(net "PRSNT_NIC1_FPGA_R_N")
	)
	(segment
		(start 375.359168 -187.02782)
		(end 375.349008 -187.01766)
		(width 0.15494)
		(layer "In7.Cu")
		(net "PRSNT_NIC1_FPGA_R_N")
	)
	(segment
		(start 367.635028 -210.672172)
		(end 369.797584 -210.672172)
		(width 0.15494)
		(layer "In7.Cu")
		(net "PRSNT_NIC1_FPGA_R_N")
	)
	(segment
		(start 375.359168 -183.604408)
		(end 375.858786 -183.10479)
		(width 0.15494)
		(layer "In7.Cu")
		(net "PRSNT_NIC1_FPGA_R_N")
	)
	(segment
		(start 376.31878 -191.45631)
		(end 376.30862 -191.44615)
		(width 0.15494)
		(layer "In7.Cu")
		(net "PRSNT_NIC1_FPGA_R_N")
	)
	(segment
		(start 370.680234 -209.789522)
		(end 370.680234 -207.677766)
		(width 0.15494)
		(layer "In7.Cu")
		(net "PRSNT_NIC1_FPGA_R_N")
	)
	(segment
		(start 375.349008 -186.61634)
		(end 375.359168 -186.60618)
		(width 0.15494)
		(layer "In7.Cu")
		(net "PRSNT_NIC1_FPGA_R_N")
	)
	(segment
		(start 375.359168 -186.60618)
		(end 375.359168 -183.604408)
		(width 0.15494)
		(layer "In7.Cu")
		(net "PRSNT_NIC1_FPGA_R_N")
	)
	(segment
		(start 376.30862 -191.86779)
		(end 376.31878 -191.85763)
		(width 0.15494)
		(layer "In7.Cu")
		(net "PRSNT_NIC1_FPGA_R_N")
	)
	(segment
		(start 376.30862 -190.100966)
		(end 375.359168 -189.151514)
		(width 0.15494)
		(layer "In7.Cu")
		(net "PRSNT_NIC1_FPGA_R_N")
	)
	(segment
		(start 376.30862 -191.44615)
		(end 376.30862 -190.100966)
		(width 0.15494)
		(layer "In7.Cu")
		(net "PRSNT_NIC1_FPGA_R_N")
	)
	(segment
		(start 376.31878 -191.85763)
		(end 376.31878 -191.45631)
		(width 0.15494)
		(layer "In7.Cu")
		(net "PRSNT_NIC1_FPGA_R_N")
	)
	(segment
		(start 363.82579 -214.48141)
		(end 367.635028 -210.672172)
		(width 0.15494)
		(layer "In7.Cu")
		(net "PRSNT_NIC1_FPGA_R_N")
	)
	(segment
		(start 375.359168 -189.151514)
		(end 375.359168 -187.02782)
		(width 0.15494)
		(layer "In7.Cu")
		(net "PRSNT_NIC1_FPGA_R_N")
	)
	(segment
		(start 370.680234 -207.677766)
		(end 376.30862 -202.04938)
		(width 0.15494)
		(layer "In7.Cu")
		(net "PRSNT_NIC1_FPGA_R_N")
	)
	(segment
		(start 375.349008 -187.01766)
		(end 375.349008 -186.61634)
		(width 0.15494)
		(layer "In7.Cu")
		(net "PRSNT_NIC1_FPGA_R_N")
	)
	(segment
		(start 376.30862 -202.04938)
		(end 376.30862 -191.86779)
		(width 0.15494)
		(layer "In7.Cu")
		(net "PRSNT_NIC1_FPGA_R_N")
	)
	(segment
		(start 359.93959 -214.48141)
		(end 363.82579 -214.48141)
		(width 0.15494)
		(layer "In7.Cu")
		(net "PRSNT_NIC1_FPGA_R_N")
	)
	(segment
		(start 233.153712 -149.139402)
		(end 233.44632 -149.26056)
		(width 0.1143)
		(layer "F.Cu")
		(net "P3V3_CLK_GEN_VDD_CK440_PEX")
	)
	(segment
		(start 231.1019 -151.837898)
		(end 231.340406 -152.076404)
		(width 0.2032)
		(layer "F.Cu")
		(net "P3V3_CLK_GEN_VDD_CK440_PEX")
	)
	(segment
		(start 231.09936 -151.533606)
		(end 231.1019 -151.536146)
		(width 0.0889)
		(layer "F.Cu")
		(net "P3V3_CLK_GEN_VDD_CK440_PEX")
	)
	(segment
		(start 231.1019 -150.282402)
		(end 231.09936 -150.284942)
		(width 0.0889)
		(layer "F.Cu")
		(net "P3V3_CLK_GEN_VDD_CK440_PEX")
	)
	(segment
		(start 231.09936 -150.284942)
		(end 231.09936 -151.533606)
		(width 0.0889)
		(layer "F.Cu")
		(net "P3V3_CLK_GEN_VDD_CK440_PEX")
	)
	(segment
		(start 232.54335 -149.139402)
		(end 233.153712 -149.139402)
		(width 0.0889)
		(layer "F.Cu")
		(net "P3V3_CLK_GEN_VDD_CK440_PEX")
	)
	(segment
		(start 231.1019 -151.536146)
		(end 231.1019 -151.837898)
		(width 0.2032)
		(layer "F.Cu")
		(net "P3V3_CLK_GEN_VDD_CK440_PEX")
	)
	(via
		(at 233.44632 -149.26056)
		(size 0.508)
		(drill 0.254)
		(layers "F.Cu" "B.Cu")
		(net "P3V3_CLK_GEN_VDD_CK440_PEX")
	)
	(via
		(at 233.72191 -151.108156)
		(size 0.6604)
		(drill 0.3302)
		(layers "F.Cu" "B.Cu")
		(net "P3V3_CLK_GEN_VDD_CK440_PEX")
	)
	(via
		(at 231.340406 -152.076404)
		(size 0.508)
		(drill 0.254)
		(layers "F.Cu" "B.Cu")
		(net "P3V3_CLK_GEN_VDD_CK440_PEX")
	)
	(via
		(at 236.3343 -153.243026)
		(size 0.6604)
		(drill 0.3302)
		(layers "F.Cu" "B.Cu")
		(net "P3V3_CLK_GEN_VDD_CK440_PEX")
	)
	(segment
		(start 36.849812 -287.349946)
		(end 36.374832 -286.874966)
		(width 0.13208)
		(layer "F.Cu")
		(net "Net_2710")
	)
	(via
		(at 36.374832 -286.874966)
		(size 0.4064)
		(drill 0.2032)
		(layers "F.Cu" "B.Cu")
		(net "Net_2710")
	)
	(segment
		(start 38.749986 -286.399732)
		(end 38.275006 -285.924752)
		(width 0.13208)
		(layer "F.Cu")
		(net "Net_2711")
	)
	(via
		(at 38.275006 -285.924752)
		(size 0.4064)
		(drill 0.2032)
		(layers "F.Cu" "B.Cu")
		(net "Net_2711")
	)
	(segment
		(start 36.849812 -285.449772)
		(end 36.374832 -284.974792)
		(width 0.13208)
		(layer "F.Cu")
		(net "Net_2712")
	)
	(via
		(at 36.374832 -284.974792)
		(size 0.4064)
		(drill 0.2032)
		(layers "F.Cu" "B.Cu")
		(net "Net_2712")
	)
	(segment
		(start 38.749986 -284.499812)
		(end 38.275006 -284.024832)
		(width 0.13208)
		(layer "F.Cu")
		(net "Net_2713")
	)
	(via
		(at 38.275006 -284.024832)
		(size 0.4064)
		(drill 0.2032)
		(layers "F.Cu" "B.Cu")
		(net "Net_2713")
	)
	(segment
		(start 36.849812 -283.549852)
		(end 36.374832 -283.074872)
		(width 0.13208)
		(layer "F.Cu")
		(net "Net_2714")
	)
	(via
		(at 36.374832 -283.074872)
		(size 0.4064)
		(drill 0.2032)
		(layers "F.Cu" "B.Cu")
		(net "Net_2714")
	)
	(segment
		(start 38.749986 -282.599892)
		(end 38.275006 -282.124912)
		(width 0.13208)
		(layer "F.Cu")
		(net "Net_2715")
	)
	(via
		(at 38.275006 -282.124912)
		(size 0.4064)
		(drill 0.2032)
		(layers "F.Cu" "B.Cu")
		(net "Net_2715")
	)
	(segment
		(start 36.849812 -281.649932)
		(end 36.374832 -281.174952)
		(width 0.13208)
		(layer "F.Cu")
		(net "Net_2716")
	)
	(via
		(at 36.374832 -281.174952)
		(size 0.4064)
		(drill 0.2032)
		(layers "F.Cu" "B.Cu")
		(net "Net_2716")
	)
	(segment
		(start 38.749986 -273.099784)
		(end 38.275006 -272.624804)
		(width 0.13208)
		(layer "F.Cu")
		(net "Net_2718")
	)
	(via
		(at 38.275006 -272.624804)
		(size 0.4064)
		(drill 0.2032)
		(layers "F.Cu" "B.Cu")
		(net "Net_2718")
	)
	(segment
		(start 39.699946 -274.999958)
		(end 39.224966 -274.524978)
		(width 0.13208)
		(layer "F.Cu")
		(net "Net_2719")
	)
	(via
		(at 39.224966 -274.524978)
		(size 0.4064)
		(drill 0.2032)
		(layers "F.Cu" "B.Cu")
		(net "Net_2719")
	)
	(segment
		(start 40.649906 -273.099784)
		(end 40.174926 -272.624804)
		(width 0.13208)
		(layer "F.Cu")
		(net "Net_2720")
	)
	(via
		(at 40.174926 -272.624804)
		(size 0.4064)
		(drill 0.2032)
		(layers "F.Cu" "B.Cu")
		(net "Net_2720")
	)
	(segment
		(start 41.599866 -274.999958)
		(end 41.124886 -274.524978)
		(width 0.13208)
		(layer "F.Cu")
		(net "Net_2721")
	)
	(via
		(at 41.124886 -274.524978)
		(size 0.4064)
		(drill 0.2032)
		(layers "F.Cu" "B.Cu")
		(net "Net_2721")
	)
	(segment
		(start 42.549826 -273.099784)
		(end 42.074846 -272.624804)
		(width 0.13208)
		(layer "F.Cu")
		(net "Net_2722")
	)
	(via
		(at 42.074846 -272.624804)
		(size 0.4064)
		(drill 0.2032)
		(layers "F.Cu" "B.Cu")
		(net "Net_2722")
	)
	(segment
		(start 43.499786 -274.999958)
		(end 43.024806 -274.524978)
		(width 0.13208)
		(layer "F.Cu")
		(net "Net_2723")
	)
	(via
		(at 43.024806 -274.524978)
		(size 0.4064)
		(drill 0.2032)
		(layers "F.Cu" "B.Cu")
		(net "Net_2723")
	)
	(segment
		(start 37.799772 -287.349946)
		(end 37.324792 -286.874966)
		(width 0.13208)
		(layer "F.Cu")
		(net "Net_2724")
	)
	(via
		(at 37.324792 -286.874966)
		(size 0.4064)
		(drill 0.2032)
		(layers "F.Cu" "B.Cu")
		(net "Net_2724")
	)
	(segment
		(start 39.699946 -286.399732)
		(end 39.224966 -285.924752)
		(width 0.13208)
		(layer "F.Cu")
		(net "Net_2725")
	)
	(via
		(at 39.224966 -285.924752)
		(size 0.4064)
		(drill 0.2032)
		(layers "F.Cu" "B.Cu")
		(net "Net_2725")
	)
	(segment
		(start 37.799772 -285.449772)
		(end 37.324792 -284.974792)
		(width 0.13208)
		(layer "F.Cu")
		(net "Net_2726")
	)
	(via
		(at 37.324792 -284.974792)
		(size 0.4064)
		(drill 0.2032)
		(layers "F.Cu" "B.Cu")
		(net "Net_2726")
	)
	(segment
		(start 39.699946 -284.499812)
		(end 39.224966 -284.024832)
		(width 0.13208)
		(layer "F.Cu")
		(net "Net_2727")
	)
	(via
		(at 39.224966 -284.024832)
		(size 0.4064)
		(drill 0.2032)
		(layers "F.Cu" "B.Cu")
		(net "Net_2727")
	)
	(segment
		(start 37.799772 -283.549852)
		(end 37.324792 -283.074872)
		(width 0.13208)
		(layer "F.Cu")
		(net "Net_2728")
	)
	(via
		(at 37.324792 -283.074872)
		(size 0.4064)
		(drill 0.2032)
		(layers "F.Cu" "B.Cu")
		(net "Net_2728")
	)
	(segment
		(start 39.699946 -282.599892)
		(end 39.224966 -282.124912)
		(width 0.13208)
		(layer "F.Cu")
		(net "Net_2729")
	)
	(via
		(at 39.224966 -282.124912)
		(size 0.4064)
		(drill 0.2032)
		(layers "F.Cu" "B.Cu")
		(net "Net_2729")
	)
	(segment
		(start 37.799772 -281.649932)
		(end 37.324792 -281.174952)
		(width 0.13208)
		(layer "F.Cu")
		(net "Net_2730")
	)
	(via
		(at 37.324792 -281.174952)
		(size 0.4064)
		(drill 0.2032)
		(layers "F.Cu" "B.Cu")
		(net "Net_2730")
	)
	(segment
		(start 39.699946 -275.949918)
		(end 39.224966 -275.474938)
		(width 0.13208)
		(layer "F.Cu")
		(net "Net_2733")
	)
	(via
		(at 39.224966 -275.474938)
		(size 0.4064)
		(drill 0.2032)
		(layers "F.Cu" "B.Cu")
		(net "Net_2733")
	)
	(segment
		(start 40.649906 -274.049744)
		(end 40.174926 -273.574764)
		(width 0.13208)
		(layer "F.Cu")
		(net "Net_2734")
	)
	(via
		(at 40.174926 -273.574764)
		(size 0.4064)
		(drill 0.2032)
		(layers "F.Cu" "B.Cu")
		(net "Net_2734")
	)
	(segment
		(start 41.599866 -275.949918)
		(end 41.124886 -275.474938)
		(width 0.13208)
		(layer "F.Cu")
		(net "Net_2735")
	)
	(via
		(at 41.124886 -275.474938)
		(size 0.4064)
		(drill 0.2032)
		(layers "F.Cu" "B.Cu")
		(net "Net_2735")
	)
	(segment
		(start 42.549826 -274.049744)
		(end 42.074846 -273.574764)
		(width 0.13208)
		(layer "F.Cu")
		(net "Net_2736")
	)
	(via
		(at 42.074846 -273.574764)
		(size 0.4064)
		(drill 0.2032)
		(layers "F.Cu" "B.Cu")
		(net "Net_2736")
	)
	(segment
		(start 43.499786 -275.949918)
		(end 43.024806 -275.474938)
		(width 0.13208)
		(layer "F.Cu")
		(net "Net_2737")
	)
	(via
		(at 43.024806 -275.474938)
		(size 0.4064)
		(drill 0.2032)
		(layers "F.Cu" "B.Cu")
		(net "Net_2737")
	)
	(segment
		(start 41.599866 -282.599892)
		(end 41.124886 -282.124912)
		(width 0.13208)
		(layer "F.Cu")
		(net "Net_2743")
	)
	(via
		(at 41.124886 -282.124912)
		(size 0.4064)
		(drill 0.2032)
		(layers "F.Cu" "B.Cu")
		(net "Net_2743")
	)
	(segment
		(start 36.849812 -279.749758)
		(end 36.374832 -279.274778)
		(width 0.13208)
		(layer "F.Cu")
		(net "Net_2744")
	)
	(via
		(at 36.374832 -279.274778)
		(size 0.4064)
		(drill 0.2032)
		(layers "F.Cu" "B.Cu")
		(net "Net_2744")
	)
	(segment
		(start 36.849812 -276.899878)
		(end 36.374832 -276.424898)
		(width 0.13208)
		(layer "F.Cu")
		(net "Net_2745")
	)
	(via
		(at 36.374832 -276.424898)
		(size 0.4064)
		(drill 0.2032)
		(layers "F.Cu" "B.Cu")
		(net "Net_2745")
	)
	(segment
		(start 38.749986 -277.849838)
		(end 38.275006 -277.374858)
		(width 0.13208)
		(layer "F.Cu")
		(net "Net_2746")
	)
	(via
		(at 38.275006 -277.374858)
		(size 0.4064)
		(drill 0.2032)
		(layers "F.Cu" "B.Cu")
		(net "Net_2746")
	)
	(segment
		(start 39.699946 -279.749758)
		(end 39.224966 -279.274778)
		(width 0.13208)
		(layer "F.Cu")
		(net "Net_2747")
	)
	(via
		(at 39.224966 -279.274778)
		(size 0.4064)
		(drill 0.2032)
		(layers "F.Cu" "B.Cu")
		(net "Net_2747")
	)
	(segment
		(start 40.649906 -277.849838)
		(end 40.174926 -277.374858)
		(width 0.13208)
		(layer "F.Cu")
		(net "Net_2748")
	)
	(via
		(at 40.174926 -277.374858)
		(size 0.4064)
		(drill 0.2032)
		(layers "F.Cu" "B.Cu")
		(net "Net_2748")
	)
	(segment
		(start 41.599866 -279.749758)
		(end 41.124886 -279.274778)
		(width 0.13208)
		(layer "F.Cu")
		(net "Net_2749")
	)
	(via
		(at 41.124886 -279.274778)
		(size 0.4064)
		(drill 0.2032)
		(layers "F.Cu" "B.Cu")
		(net "Net_2749")
	)
	(segment
		(start 42.549826 -277.849838)
		(end 42.074846 -277.374858)
		(width 0.13208)
		(layer "F.Cu")
		(net "Net_2750")
	)
	(via
		(at 42.074846 -277.374858)
		(size 0.4064)
		(drill 0.2032)
		(layers "F.Cu" "B.Cu")
		(net "Net_2750")
	)
	(segment
		(start 42.549826 -282.599892)
		(end 42.074846 -282.124912)
		(width 0.13208)
		(layer "F.Cu")
		(net "Net_2757")
	)
	(via
		(at 42.074846 -282.124912)
		(size 0.4064)
		(drill 0.2032)
		(layers "F.Cu" "B.Cu")
		(net "Net_2757")
	)
	(segment
		(start 37.799772 -279.749758)
		(end 37.324792 -279.274778)
		(width 0.13208)
		(layer "F.Cu")
		(net "Net_2758")
	)
	(via
		(at 37.324792 -279.274778)
		(size 0.4064)
		(drill 0.2032)
		(layers "F.Cu" "B.Cu")
		(net "Net_2758")
	)
	(segment
		(start 37.799772 -276.899878)
		(end 37.324792 -276.424898)
		(width 0.13208)
		(layer "F.Cu")
		(net "Net_2759")
	)
	(via
		(at 37.324792 -276.424898)
		(size 0.4064)
		(drill 0.2032)
		(layers "F.Cu" "B.Cu")
		(net "Net_2759")
	)
	(segment
		(start 38.749986 -278.799798)
		(end 38.275006 -278.324818)
		(width 0.13208)
		(layer "F.Cu")
		(net "Net_2760")
	)
	(via
		(at 38.275006 -278.324818)
		(size 0.4064)
		(drill 0.2032)
		(layers "F.Cu" "B.Cu")
		(net "Net_2760")
	)
	(segment
		(start 39.699946 -280.699718)
		(end 39.224966 -280.224738)
		(width 0.13208)
		(layer "F.Cu")
		(net "Net_2761")
	)
	(via
		(at 39.224966 -280.224738)
		(size 0.4064)
		(drill 0.2032)
		(layers "F.Cu" "B.Cu")
		(net "Net_2761")
	)
	(segment
		(start 40.649906 -278.799798)
		(end 40.174926 -278.324818)
		(width 0.13208)
		(layer "F.Cu")
		(net "Net_2762")
	)
	(via
		(at 40.174926 -278.324818)
		(size 0.4064)
		(drill 0.2032)
		(layers "F.Cu" "B.Cu")
		(net "Net_2762")
	)
	(segment
		(start 41.599866 -280.699718)
		(end 41.124886 -280.224738)
		(width 0.13208)
		(layer "F.Cu")
		(net "Net_2763")
	)
	(via
		(at 41.124886 -280.224738)
		(size 0.4064)
		(drill 0.2032)
		(layers "F.Cu" "B.Cu")
		(net "Net_2763")
	)
	(segment
		(start 42.549826 -278.799798)
		(end 42.074846 -278.324818)
		(width 0.13208)
		(layer "F.Cu")
		(net "Net_2764")
	)
	(via
		(at 42.074846 -278.324818)
		(size 0.4064)
		(drill 0.2032)
		(layers "F.Cu" "B.Cu")
		(net "Net_2764")
	)
	(segment
		(start 43.499786 -280.699718)
		(end 43.024806 -280.224738)
		(width 0.13208)
		(layer "F.Cu")
		(net "Net_2765")
	)
	(via
		(at 43.024806 -280.224738)
		(size 0.4064)
		(drill 0.2032)
		(layers "F.Cu" "B.Cu")
		(net "Net_2765")
	)
	(segment
		(start 80.54975 -303.499774)
		(end 80.07477 -303.024794)
		(width 0.127)
		(layer "F.Cu")
		(net "Net_2766")
	)
	(via
		(at 80.07477 -303.024794)
		(size 0.4064)
		(drill 0.2032)
		(layers "F.Cu" "B.Cu")
		(net "Net_2766")
	)
	(segment
		(start 82.449924 -302.549814)
		(end 82.924904 -302.074834)
		(width 0.13208)
		(layer "F.Cu")
		(net "Net_2767")
	)
	(via
		(at 82.924904 -302.074834)
		(size 0.4064)
		(drill 0.2032)
		(layers "F.Cu" "B.Cu")
		(net "Net_2767")
	)
	(segment
		(start 80.54975 -301.599854)
		(end 80.07477 -301.124874)
		(width 0.127)
		(layer "F.Cu")
		(net "Net_2768")
	)
	(via
		(at 80.07477 -301.124874)
		(size 0.4064)
		(drill 0.2032)
		(layers "F.Cu" "B.Cu")
		(net "Net_2768")
	)
	(segment
		(start 82.449924 -300.649894)
		(end 82.924904 -300.174914)
		(width 0.13208)
		(layer "F.Cu")
		(net "Net_2769")
	)
	(via
		(at 82.924904 -300.174914)
		(size 0.4064)
		(drill 0.2032)
		(layers "F.Cu" "B.Cu")
		(net "Net_2769")
	)
	(segment
		(start 80.54975 -299.699934)
		(end 80.07477 -299.224954)
		(width 0.127)
		(layer "F.Cu")
		(net "Net_2770")
	)
	(via
		(at 80.07477 -299.224954)
		(size 0.4064)
		(drill 0.2032)
		(layers "F.Cu" "B.Cu")
		(net "Net_2770")
	)
	(segment
		(start 82.449924 -298.74972)
		(end 82.924904 -298.27474)
		(width 0.13208)
		(layer "F.Cu")
		(net "Net_2771")
	)
	(via
		(at 82.924904 -298.27474)
		(size 0.4064)
		(drill 0.2032)
		(layers "F.Cu" "B.Cu")
		(net "Net_2771")
	)
	(segment
		(start 80.54975 -297.79976)
		(end 80.07477 -297.32478)
		(width 0.127)
		(layer "F.Cu")
		(net "Net_2772")
	)
	(via
		(at 80.07477 -297.32478)
		(size 0.4064)
		(drill 0.2032)
		(layers "F.Cu" "B.Cu")
		(net "Net_2772")
	)
	(segment
		(start 82.449924 -294.94988)
		(end 82.924904 -294.4749)
		(width 0.13208)
		(layer "F.Cu")
		(net "Net_2775")
	)
	(via
		(at 82.924904 -294.4749)
		(size 0.4064)
		(drill 0.2032)
		(layers "F.Cu" "B.Cu")
		(net "Net_2775")
	)
	(segment
		(start 80.54975 -293.99992)
		(end 80.07477 -293.52494)
		(width 0.13208)
		(layer "F.Cu")
		(net "Net_2776")
	)
	(via
		(at 80.07477 -293.52494)
		(size 0.4064)
		(drill 0.2032)
		(layers "F.Cu" "B.Cu")
		(net "Net_2776")
	)
	(segment
		(start 82.449924 -293.04996)
		(end 82.924904 -292.57498)
		(width 0.13208)
		(layer "F.Cu")
		(net "Net_2777")
	)
	(via
		(at 82.924904 -292.57498)
		(size 0.4064)
		(drill 0.2032)
		(layers "F.Cu" "B.Cu")
		(net "Net_2777")
	)
	(segment
		(start 80.54975 -292.099746)
		(end 80.07477 -291.624766)
		(width 0.13208)
		(layer "F.Cu")
		(net "Net_2778")
	)
	(via
		(at 80.07477 -291.624766)
		(size 0.4064)
		(drill 0.2032)
		(layers "F.Cu" "B.Cu")
		(net "Net_2778")
	)
	(segment
		(start 82.449924 -291.149786)
		(end 82.924904 -290.674806)
		(width 0.13208)
		(layer "F.Cu")
		(net "Net_2779")
	)
	(via
		(at 82.924904 -290.674806)
		(size 0.4064)
		(drill 0.2032)
		(layers "F.Cu" "B.Cu")
		(net "Net_2779")
	)
	(segment
		(start 80.54975 -290.199826)
		(end 80.07477 -289.724846)
		(width 0.13208)
		(layer "F.Cu")
		(net "Net_2780")
	)
	(via
		(at 80.07477 -289.724846)
		(size 0.4064)
		(drill 0.2032)
		(layers "F.Cu" "B.Cu")
		(net "Net_2780")
	)
	(segment
		(start 82.449924 -289.249866)
		(end 82.924904 -288.774886)
		(width 0.13208)
		(layer "F.Cu")
		(net "Net_2781")
	)
	(via
		(at 82.924904 -288.774886)
		(size 0.4064)
		(drill 0.2032)
		(layers "F.Cu" "B.Cu")
		(net "Net_2781")
	)
	(segment
		(start 79.59979 -303.499774)
		(end 79.12481 -303.024794)
		(width 0.127)
		(layer "F.Cu")
		(net "Net_2782")
	)
	(via
		(at 79.12481 -303.024794)
		(size 0.4064)
		(drill 0.2032)
		(layers "F.Cu" "B.Cu")
		(net "Net_2782")
	)
	(segment
		(start 81.499964 -302.549814)
		(end 81.974944 -302.074834)
		(width 0.13208)
		(layer "F.Cu")
		(net "Net_2783")
	)
	(via
		(at 81.974944 -302.074834)
		(size 0.4064)
		(drill 0.2032)
		(layers "F.Cu" "B.Cu")
		(net "Net_2783")
	)
	(segment
		(start 79.59979 -301.599854)
		(end 79.12481 -301.124874)
		(width 0.127)
		(layer "F.Cu")
		(net "Net_2784")
	)
	(via
		(at 79.12481 -301.124874)
		(size 0.4064)
		(drill 0.2032)
		(layers "F.Cu" "B.Cu")
		(net "Net_2784")
	)
	(segment
		(start 81.499964 -300.649894)
		(end 81.974944 -300.174914)
		(width 0.13208)
		(layer "F.Cu")
		(net "Net_2785")
	)
	(via
		(at 81.974944 -300.174914)
		(size 0.4064)
		(drill 0.2032)
		(layers "F.Cu" "B.Cu")
		(net "Net_2785")
	)
	(segment
		(start 79.59979 -299.699934)
		(end 79.12481 -299.224954)
		(width 0.127)
		(layer "F.Cu")
		(net "Net_2786")
	)
	(via
		(at 79.12481 -299.224954)
		(size 0.4064)
		(drill 0.2032)
		(layers "F.Cu" "B.Cu")
		(net "Net_2786")
	)
	(segment
		(start 81.499964 -298.74972)
		(end 81.974944 -298.27474)
		(width 0.13208)
		(layer "F.Cu")
		(net "Net_2787")
	)
	(via
		(at 81.974944 -298.27474)
		(size 0.4064)
		(drill 0.2032)
		(layers "F.Cu" "B.Cu")
		(net "Net_2787")
	)
	(segment
		(start 79.59979 -297.79976)
		(end 79.12481 -297.32478)
		(width 0.127)
		(layer "F.Cu")
		(net "Net_2788")
	)
	(via
		(at 79.12481 -297.32478)
		(size 0.4064)
		(drill 0.2032)
		(layers "F.Cu" "B.Cu")
		(net "Net_2788")
	)
	(segment
		(start 81.499964 -294.94988)
		(end 81.974944 -294.4749)
		(width 0.13208)
		(layer "F.Cu")
		(net "Net_2791")
	)
	(via
		(at 81.974944 -294.4749)
		(size 0.4064)
		(drill 0.2032)
		(layers "F.Cu" "B.Cu")
		(net "Net_2791")
	)
	(segment
		(start 79.59979 -293.99992)
		(end 79.12481 -293.52494)
		(width 0.13208)
		(layer "F.Cu")
		(net "Net_2792")
	)
	(via
		(at 79.12481 -293.52494)
		(size 0.4064)
		(drill 0.2032)
		(layers "F.Cu" "B.Cu")
		(net "Net_2792")
	)
	(segment
		(start 81.499964 -293.04996)
		(end 81.974944 -292.57498)
		(width 0.13208)
		(layer "F.Cu")
		(net "Net_2793")
	)
	(via
		(at 81.974944 -292.57498)
		(size 0.4064)
		(drill 0.2032)
		(layers "F.Cu" "B.Cu")
		(net "Net_2793")
	)
	(segment
		(start 79.59979 -292.099746)
		(end 79.12481 -291.624766)
		(width 0.13208)
		(layer "F.Cu")
		(net "Net_2794")
	)
	(via
		(at 79.12481 -291.624766)
		(size 0.4064)
		(drill 0.2032)
		(layers "F.Cu" "B.Cu")
		(net "Net_2794")
	)
	(segment
		(start 81.499964 -291.149786)
		(end 81.974944 -290.674806)
		(width 0.13208)
		(layer "F.Cu")
		(net "Net_2795")
	)
	(via
		(at 81.974944 -290.674806)
		(size 0.4064)
		(drill 0.2032)
		(layers "F.Cu" "B.Cu")
		(net "Net_2795")
	)
	(segment
		(start 79.59979 -290.199826)
		(end 79.12481 -289.724846)
		(width 0.13208)
		(layer "F.Cu")
		(net "Net_2796")
	)
	(via
		(at 79.12481 -289.724846)
		(size 0.4064)
		(drill 0.2032)
		(layers "F.Cu" "B.Cu")
		(net "Net_2796")
	)
	(segment
		(start 81.499964 -289.249866)
		(end 81.974944 -288.774886)
		(width 0.13208)
		(layer "F.Cu")
		(net "Net_2797")
	)
	(via
		(at 81.974944 -288.774886)
		(size 0.4064)
		(drill 0.2032)
		(layers "F.Cu" "B.Cu")
		(net "Net_2797")
	)
	(segment
		(start 77.69987 -301.599854)
		(end 78.17485 -302.074834)
		(width 0.127)
		(layer "F.Cu")
		(net "Net_2800")
	)
	(via
		(at 78.17485 -302.074834)
		(size 0.4064)
		(drill 0.2032)
		(layers "F.Cu" "B.Cu")
		(net "Net_2800")
	)
	(segment
		(start 77.69987 -299.699934)
		(end 78.17485 -300.174914)
		(width 0.127)
		(layer "F.Cu")
		(net "Net_2802")
	)
	(via
		(at 78.17485 -300.174914)
		(size 0.4064)
		(drill 0.2032)
		(layers "F.Cu" "B.Cu")
		(net "Net_2802")
	)
	(segment
		(start 77.69987 -297.79976)
		(end 78.17485 -298.27474)
		(width 0.127)
		(layer "F.Cu")
		(net "Net_2804")
	)
	(via
		(at 78.17485 -298.27474)
		(size 0.4064)
		(drill 0.2032)
		(layers "F.Cu" "B.Cu")
		(net "Net_2804")
	)
	(segment
		(start 75.79995 -296.8498)
		(end 75.32497 -297.32478)
		(width 0.127)
		(layer "F.Cu")
		(net "Net_2805")
	)
	(via
		(at 75.32497 -297.32478)
		(size 0.4064)
		(drill 0.2032)
		(layers "F.Cu" "B.Cu")
		(net "Net_2805")
	)
	(segment
		(start 75.79995 -293.04996)
		(end 75.32497 -293.52494)
		(width 0.13208)
		(layer "F.Cu")
		(net "Net_2809")
	)
	(via
		(at 75.32497 -293.52494)
		(size 0.4064)
		(drill 0.2032)
		(layers "F.Cu" "B.Cu")
		(net "Net_2809")
	)
	(segment
		(start 77.69987 -292.099746)
		(end 78.17485 -292.574726)
		(width 0.13208)
		(layer "F.Cu")
		(net "Net_2810")
	)
	(via
		(at 78.17485 -292.574726)
		(size 0.4064)
		(drill 0.2032)
		(layers "F.Cu" "B.Cu")
		(net "Net_2810")
	)
	(segment
		(start 77.69987 -290.199826)
		(end 78.17485 -290.674806)
		(width 0.13208)
		(layer "F.Cu")
		(net "Net_2812")
	)
	(via
		(at 78.17485 -290.674806)
		(size 0.4064)
		(drill 0.2032)
		(layers "F.Cu" "B.Cu")
		(net "Net_2812")
	)
	(segment
		(start 76.74991 -301.599854)
		(end 77.22489 -302.074834)
		(width 0.127)
		(layer "F.Cu")
		(net "Net_2816")
	)
	(via
		(at 77.22489 -302.074834)
		(size 0.4064)
		(drill 0.2032)
		(layers "F.Cu" "B.Cu")
		(net "Net_2816")
	)
	(segment
		(start 76.74991 -299.699934)
		(end 77.22489 -300.174914)
		(width 0.127)
		(layer "F.Cu")
		(net "Net_2818")
	)
	(via
		(at 77.22489 -300.174914)
		(size 0.4064)
		(drill 0.2032)
		(layers "F.Cu" "B.Cu")
		(net "Net_2818")
	)
	(segment
		(start 76.74991 -297.79976)
		(end 77.22489 -298.27474)
		(width 0.127)
		(layer "F.Cu")
		(net "Net_2820")
	)
	(via
		(at 77.22489 -298.27474)
		(size 0.4064)
		(drill 0.2032)
		(layers "F.Cu" "B.Cu")
		(net "Net_2820")
	)
	(segment
		(start 74.84999 -296.8498)
		(end 74.37501 -297.32478)
		(width 0.127)
		(layer "F.Cu")
		(net "Net_2821")
	)
	(via
		(at 74.37501 -297.32478)
		(size 0.4064)
		(drill 0.2032)
		(layers "F.Cu" "B.Cu")
		(net "Net_2821")
	)
	(segment
		(start 74.84999 -293.04996)
		(end 74.37501 -293.52494)
		(width 0.13208)
		(layer "F.Cu")
		(net "Net_2825")
	)
	(via
		(at 74.37501 -293.52494)
		(size 0.4064)
		(drill 0.2032)
		(layers "F.Cu" "B.Cu")
		(net "Net_2825")
	)
	(segment
		(start 76.74991 -292.099746)
		(end 77.22489 -292.574726)
		(width 0.13208)
		(layer "F.Cu")
		(net "Net_2826")
	)
	(via
		(at 77.22489 -292.574726)
		(size 0.4064)
		(drill 0.2032)
		(layers "F.Cu" "B.Cu")
		(net "Net_2826")
	)
	(segment
		(start 74.84999 -291.149786)
		(end 74.37501 -291.624766)
		(width 0.13208)
		(layer "F.Cu")
		(net "Net_2827")
	)
	(via
		(at 74.37501 -291.624766)
		(size 0.4064)
		(drill 0.2032)
		(layers "F.Cu" "B.Cu")
		(net "Net_2827")
	)
	(segment
		(start 76.74991 -290.199826)
		(end 77.22489 -290.674806)
		(width 0.13208)
		(layer "F.Cu")
		(net "Net_2828")
	)
	(via
		(at 77.22489 -290.674806)
		(size 0.4064)
		(drill 0.2032)
		(layers "F.Cu" "B.Cu")
		(net "Net_2828")
	)
	(segment
		(start 74.84999 -289.249866)
		(end 74.37501 -289.724846)
		(width 0.13208)
		(layer "F.Cu")
		(net "Net_2829")
	)
	(via
		(at 74.37501 -289.724846)
		(size 0.4064)
		(drill 0.2032)
		(layers "F.Cu" "B.Cu")
		(net "Net_2829")
	)
	(segment
		(start 71.999856 -303.499774)
		(end 72.474836 -303.974754)
		(width 0.249936)
		(layer "F.Cu")
		(net "Net_2839")
	)
	(via
		(at 72.474836 -303.974754)
		(size 0.4064)
		(drill 0.2032)
		(layers "F.Cu" "B.Cu")
		(net "Net_2839")
	)
	(segment
		(start 36.849812 -292.099746)
		(end 36.374832 -291.624766)
		(width 0.13208)
		(layer "F.Cu")
		(net "Net_2840")
	)
	(via
		(at 36.374832 -291.624766)
		(size 0.4064)
		(drill 0.2032)
		(layers "F.Cu" "B.Cu")
		(net "Net_2840")
	)
	(segment
		(start 37.799772 -292.099746)
		(end 37.324792 -291.624766)
		(width 0.13208)
		(layer "F.Cu")
		(net "Net_2841")
	)
	(via
		(at 37.324792 -291.624766)
		(size 0.4064)
		(drill 0.2032)
		(layers "F.Cu" "B.Cu")
		(net "Net_2841")
	)
	(segment
		(start 71.999856 -289.249866)
		(end 72.474836 -288.774886)
		(width 0.13208)
		(layer "F.Cu")
		(net "Net_2844")
	)
	(via
		(at 72.474836 -288.774886)
		(size 0.4064)
		(drill 0.2032)
		(layers "F.Cu" "B.Cu")
		(net "Net_2844")
	)
	(segment
		(start 72.949816 -292.099746)
		(end 73.424796 -291.624766)
		(width 0.13208)
		(layer "F.Cu")
		(net "Net_2846")
	)
	(via
		(at 73.424796 -291.624766)
		(size 0.4064)
		(drill 0.2032)
		(layers "F.Cu" "B.Cu")
		(net "Net_2846")
	)
	(segment
		(start 50.14976 -283.549852)
		(end 49.67478 -283.074872)
		(width 0.13208)
		(layer "F.Cu")
		(net "Net_2852")
	)
	(via
		(at 49.67478 -283.074872)
		(size 0.4064)
		(drill 0.2032)
		(layers "F.Cu" "B.Cu")
		(net "Net_2852")
	)
	(segment
		(start 53.949854 -283.549852)
		(end 53.474874 -283.074872)
		(width 0.13208)
		(layer "F.Cu")
		(net "Net_2853")
	)
	(via
		(at 53.474874 -283.074872)
		(size 0.4064)
		(drill 0.2032)
		(layers "F.Cu" "B.Cu")
		(net "Net_2853")
	)
	(segment
		(start 52.999894 -283.549852)
		(end 52.524914 -283.074872)
		(width 0.13208)
		(layer "F.Cu")
		(net "Net_2857")
	)
	(via
		(at 52.524914 -283.074872)
		(size 0.4064)
		(drill 0.2032)
		(layers "F.Cu" "B.Cu")
		(net "Net_2857")
	)
	(segment
		(start 49.1998 -283.549852)
		(end 48.72482 -283.074872)
		(width 0.13208)
		(layer "F.Cu")
		(net "Net_2858")
	)
	(via
		(at 48.72482 -283.074872)
		(size 0.4064)
		(drill 0.2032)
		(layers "F.Cu" "B.Cu")
		(net "Net_2858")
	)
	(segment
		(start 51.099974 -283.549852)
		(end 50.624994 -283.074872)
		(width 0.13208)
		(layer "F.Cu")
		(net "Net_2861")
	)
	(via
		(at 50.624994 -283.074872)
		(size 0.4064)
		(drill 0.2032)
		(layers "F.Cu" "B.Cu")
		(net "Net_2861")
	)
	(segment
		(start 52.049934 -283.549852)
		(end 51.574954 -283.074872)
		(width 0.13208)
		(layer "F.Cu")
		(net "Net_2862")
	)
	(via
		(at 51.574954 -283.074872)
		(size 0.4064)
		(drill 0.2032)
		(layers "F.Cu" "B.Cu")
		(net "Net_2862")
	)
	(segment
		(start 47.29988 -283.549852)
		(end 46.8249 -283.074872)
		(width 0.13208)
		(layer "F.Cu")
		(net "Net_2866")
	)
	(via
		(at 46.8249 -283.074872)
		(size 0.4064)
		(drill 0.2032)
		(layers "F.Cu" "B.Cu")
		(net "Net_2866")
	)
	(segment
		(start 48.24984 -283.549852)
		(end 47.77486 -283.074872)
		(width 0.13208)
		(layer "F.Cu")
		(net "Net_2867")
	)
	(via
		(at 47.77486 -283.074872)
		(size 0.4064)
		(drill 0.2032)
		(layers "F.Cu" "B.Cu")
		(net "Net_2867")
	)
	(segment
		(start 70.099936 -282.599892)
		(end 70.574916 -283.074872)
		(width 0.13208)
		(layer "F.Cu")
		(net "Net_2871")
	)
	(via
		(at 70.574916 -283.074872)
		(size 0.4064)
		(drill 0.2032)
		(layers "F.Cu" "B.Cu")
		(net "Net_2871")
	)
	(segment
		(start 69.149976 -283.549852)
		(end 69.624956 -283.074872)
		(width 0.13208)
		(layer "F.Cu")
		(net "Net_2872")
	)
	(via
		(at 69.624956 -283.074872)
		(size 0.4064)
		(drill 0.2032)
		(layers "F.Cu" "B.Cu")
		(net "Net_2872")
	)
	(segment
		(start 71.049896 -282.599892)
		(end 71.524876 -283.074872)
		(width 0.13208)
		(layer "F.Cu")
		(net "Net_2875")
	)
	(via
		(at 71.524876 -283.074872)
		(size 0.4064)
		(drill 0.2032)
		(layers "F.Cu" "B.Cu")
		(net "Net_2875")
	)
	(segment
		(start 71.999856 -290.199826)
		(end 72.474836 -289.724846)
		(width 0.13208)
		(layer "F.Cu")
		(net "Net_2877")
	)
	(via
		(at 72.474836 -289.724846)
		(size 0.4064)
		(drill 0.2032)
		(layers "F.Cu" "B.Cu")
		(net "Net_2877")
	)
	(segment
		(start 64.399922 -308.249828)
		(end 63.924942 -308.724808)
		(width 0.127)
		(layer "F.Cu")
		(net "Net_2880")
	)
	(via
		(at 63.924942 -308.724808)
		(size 0.4064)
		(drill 0.2032)
		(layers "F.Cu" "B.Cu")
		(net "Net_2880")
	)
	(segment
		(start 68.199762 -308.249828)
		(end 67.724782 -308.724808)
		(width 0.127)
		(layer "F.Cu")
		(net "Net_2889")
	)
	(via
		(at 67.724782 -308.724808)
		(size 0.4064)
		(drill 0.2032)
		(layers "F.Cu" "B.Cu")
		(net "Net_2889")
	)
	(segment
		(start 66.299842 -308.249828)
		(end 65.824862 -308.724808)
		(width 0.127)
		(layer "F.Cu")
		(net "Net_2891")
	)
	(via
		(at 65.824862 -308.724808)
		(size 0.4064)
		(drill 0.2032)
		(layers "F.Cu" "B.Cu")
		(net "Net_2891")
	)
	(segment
		(start 55.849774 -283.549852)
		(end 55.374794 -283.074872)
		(width 0.13208)
		(layer "F.Cu")
		(net "Net_2892")
	)
	(via
		(at 55.374794 -283.074872)
		(size 0.4064)
		(drill 0.2032)
		(layers "F.Cu" "B.Cu")
		(net "Net_2892")
	)
	(segment
		(start 56.799988 -283.549852)
		(end 56.325008 -283.074872)
		(width 0.13208)
		(layer "F.Cu")
		(net "Net_2893")
	)
	(via
		(at 56.325008 -283.074872)
		(size 0.4064)
		(drill 0.2032)
		(layers "F.Cu" "B.Cu")
		(net "Net_2893")
	)
	(segment
		(start 57.749948 -283.549852)
		(end 57.274968 -283.074872)
		(width 0.13208)
		(layer "F.Cu")
		(net "Net_2895")
	)
	(via
		(at 57.274968 -283.074872)
		(size 0.4064)
		(drill 0.2032)
		(layers "F.Cu" "B.Cu")
		(net "Net_2895")
	)
	(segment
		(start 56.799988 -309.199788)
		(end 56.325008 -308.724808)
		(width 0.127)
		(layer "F.Cu")
		(net "Net_2897")
	)
	(via
		(at 56.325008 -308.724808)
		(size 0.4064)
		(drill 0.2032)
		(layers "F.Cu" "B.Cu")
		(net "Net_2897")
	)
	(segment
		(start 56.799988 -308.249828)
		(end 56.325008 -307.774848)
		(width 0.127)
		(layer "F.Cu")
		(net "Net_2899")
	)
	(via
		(at 56.325008 -307.774848)
		(size 0.4064)
		(drill 0.2032)
		(layers "F.Cu" "B.Cu")
		(net "Net_2899")
	)
	(segment
		(start 57.749948 -308.249828)
		(end 57.274968 -307.774848)
		(width 0.127)
		(layer "F.Cu")
		(net "Net_2900")
	)
	(via
		(at 57.274968 -307.774848)
		(size 0.4064)
		(drill 0.2032)
		(layers "F.Cu" "B.Cu")
		(net "Net_2900")
	)
	(segment
		(start 57.749948 -309.199788)
		(end 58.224928 -308.724808)
		(width 0.13208)
		(layer "F.Cu")
		(net "Net_2901")
	)
	(via
		(at 58.224928 -308.724808)
		(size 0.4064)
		(drill 0.2032)
		(layers "F.Cu" "B.Cu")
		(net "Net_2901")
	)
	(segment
		(start 58.699908 -308.249828)
		(end 58.224928 -307.774848)
		(width 0.127)
		(layer "F.Cu")
		(net "Net_2902")
	)
	(via
		(at 58.224928 -307.774848)
		(size 0.4064)
		(drill 0.2032)
		(layers "F.Cu" "B.Cu")
		(net "Net_2902")
	)
	(segment
		(start 71.049896 -308.249828)
		(end 70.574916 -308.724808)
		(width 0.127)
		(layer "F.Cu")
		(net "Net_2907")
	)
	(via
		(at 70.574916 -308.724808)
		(size 0.4064)
		(drill 0.2032)
		(layers "F.Cu" "B.Cu")
		(net "Net_2907")
	)
	(segment
		(start 70.099936 -308.249828)
		(end 69.624956 -308.724808)
		(width 0.127)
		(layer "F.Cu")
		(net "Net_2908")
	)
	(via
		(at 69.624956 -308.724808)
		(size 0.4064)
		(drill 0.2032)
		(layers "F.Cu" "B.Cu")
		(net "Net_2908")
	)
	(segment
		(start 42.549826 -291.149786)
		(end 42.074846 -290.674806)
		(width 0.13208)
		(layer "F.Cu")
		(net "Net_2910")
	)
	(via
		(at 42.074846 -290.674806)
		(size 0.4064)
		(drill 0.2032)
		(layers "F.Cu" "B.Cu")
		(net "Net_2910")
	)
	(segment
		(start 43.499786 -292.099746)
		(end 43.024806 -291.624766)
		(width 0.13208)
		(layer "F.Cu")
		(net "Net_2911")
	)
	(via
		(at 43.024806 -291.624766)
		(size 0.4064)
		(drill 0.2032)
		(layers "F.Cu" "B.Cu")
		(net "Net_2911")
	)
	(segment
		(start 292.378892 -59.177936)
		(end 292.378892 -58.71972)
		(width 0.13208)
		(layer "F.Cu")
		(net "PWRGD_P3V3_SSD10")
	)
	(segment
		(start 291.975032 -59.177936)
		(end 292.378892 -59.177936)
		(width 0.13208)
		(layer "F.Cu")
		(net "PWRGD_P3V3_SSD10")
	)
	(segment
		(start 292.224968 -57.841896)
		(end 291.84092 -57.457848)
		(width 0.13208)
		(layer "F.Cu")
		(net "PWRGD_P3V3_SSD10")
	)
	(segment
		(start 291.848032 -61.22416)
		(end 291.848032 -59.304936)
		(width 0.13208)
		(layer "F.Cu")
		(net "PWRGD_P3V3_SSD10")
	)
	(segment
		(start 291.84092 -57.457848)
		(end 291.84092 -57.16397)
		(width 0.13208)
		(layer "F.Cu")
		(net "PWRGD_P3V3_SSD10")
	)
	(segment
		(start 292.224968 -58.565796)
		(end 292.224968 -57.867296)
		(width 0.13208)
		(layer "F.Cu")
		(net "PWRGD_P3V3_SSD10")
	)
	(segment
		(start 291.848032 -59.304936)
		(end 291.975032 -59.177936)
		(width 0.13208)
		(layer "F.Cu")
		(net "PWRGD_P3V3_SSD10")
	)
	(segment
		(start 292.224968 -57.867296)
		(end 292.224968 -57.841896)
		(width 0.13208)
		(layer "F.Cu")
		(net "PWRGD_P3V3_SSD10")
	)
	(segment
		(start 292.010846 -61.386974)
		(end 291.848032 -61.22416)
		(width 0.13208)
		(layer "F.Cu")
		(net "PWRGD_P3V3_SSD10")
	)
	(segment
		(start 292.378892 -58.71972)
		(end 292.224968 -58.565796)
		(width 0.13208)
		(layer "F.Cu")
		(net "PWRGD_P3V3_SSD10")
	)
	(via
		(at 292.224968 -57.867296)
		(size 0.508)
		(drill 0.254)
		(layers "F.Cu" "B.Cu")
		(net "PWRGD_P3V3_SSD10")
	)
	(segment
		(start 233.130344 -95.565468)
		(end 233.297222 -95.565468)
		(width 0.13208)
		(layer "F.Cu")
		(net "PEX_USB_HUB_OVCUR4")
	)
	(segment
		(start 233.297222 -95.565468)
		(end 233.52125 -95.34144)
		(width 0.13208)
		(layer "F.Cu")
		(net "PEX_USB_HUB_OVCUR4")
	)
	(segment
		(start 232.428288 -96.267524)
		(end 232.74782 -95.947992)
		(width 0.13208)
		(layer "F.Cu")
		(net "PEX_USB_HUB_OVCUR4")
	)
	(segment
		(start 232.74782 -95.947992)
		(end 233.130344 -95.565468)
		(width 0.13208)
		(layer "F.Cu")
		(net "PEX_USB_HUB_OVCUR4")
	)
	(segment
		(start 232.428288 -96.858328)
		(end 232.428288 -96.267524)
		(width 0.13208)
		(layer "F.Cu")
		(net "PEX_USB_HUB_OVCUR4")
	)
	(segment
		(start 233.52125 -95.34144)
		(end 233.52125 -94.679008)
		(width 0.13208)
		(layer "F.Cu")
		(net "PEX_USB_HUB_OVCUR4")
	)
	(via
		(at 232.74782 -95.947992)
		(size 0.508)
		(drill 0.254)
		(layers "F.Cu" "B.Cu")
		(net "PEX_USB_HUB_OVCUR4")
	)
	(segment
		(start 126.951486 -174.321724)
		(end 126.621286 -173.991524)
		(width 0.1143)
		(layer "F.Cu")
		(net "CLK_100M_DB2000QL_PEX1_S1_DN")
	)
	(segment
		(start 128.1684 -174.9552)
		(end 127.534924 -174.321724)
		(width 0.1143)
		(layer "F.Cu")
		(net "CLK_100M_DB2000QL_PEX1_S1_DN")
	)
	(segment
		(start 129.971038 -174.900336)
		(end 129.83845 -174.9552)
		(width 0.1143)
		(layer "F.Cu")
		(net "CLK_100M_DB2000QL_PEX1_S1_DN")
	)
	(segment
		(start 127.534924 -174.321724)
		(end 126.951486 -174.321724)
		(width 0.1143)
		(layer "F.Cu")
		(net "CLK_100M_DB2000QL_PEX1_S1_DN")
	)
	(segment
		(start 129.83845 -174.9552)
		(end 128.1684 -174.9552)
		(width 0.1143)
		(layer "F.Cu")
		(net "CLK_100M_DB2000QL_PEX1_S1_DN")
	)
	(segment
		(start 62.500002 -283.549852)
		(end 62.974982 -284.024832)
		(width 0.13208)
		(layer "F.Cu")
		(net "PEX0_MODE_SEL9")
	)
	(segment
		(start 24.342344 -250.470924)
		(end 24.342344 -251.158502)
		(width 0.13208)
		(layer "F.Cu")
		(net "PEX0_MODE_SEL9")
	)
	(segment
		(start 62.499748 -283.549852)
		(end 62.500002 -283.549852)
		(width 0.13208)
		(layer "F.Cu")
		(net "PEX0_MODE_SEL9")
	)
	(segment
		(start 24.342344 -251.158502)
		(end 24.342344 -251.956824)
		(width 0.13208)
		(layer "F.Cu")
		(net "PEX0_MODE_SEL9")
	)
	(via
		(at 24.342344 -251.158502)
		(size 0.508)
		(drill 0.254)
		(layers "F.Cu" "B.Cu")
		(net "PEX0_MODE_SEL9")
	)
	(via
		(at 62.974982 -284.024832)
		(size 0.4064)
		(drill 0.2032)
		(layers "F.Cu" "B.Cu")
		(net "PEX0_MODE_SEL9")
	)
	(segment
		(start 24.819864 -249.94743)
		(end 24.342344 -250.42495)
		(width 0.13208)
		(layer "B.Cu")
		(net "PEX0_MODE_SEL9")
	)
	(segment
		(start 70.7136 -285.3944)
		(end 70.986904 -285.121096)
		(width 0.13208)
		(layer "B.Cu")
		(net "PEX0_MODE_SEL9")
	)
	(segment
		(start 71.297292 -282.672536)
		(end 71.716646 -282.672536)
		(width 0.13208)
		(layer "B.Cu")
		(net "PEX0_MODE_SEL9")
	)
	(segment
		(start 52.81041 -252.054614)
		(end 39.645336 -252.054614)
		(width 0.13208)
		(layer "B.Cu")
		(net "PEX0_MODE_SEL9")
	)
	(segment
		(start 24.342344 -250.42495)
		(end 24.342344 -251.158502)
		(width 0.13208)
		(layer "B.Cu")
		(net "PEX0_MODE_SEL9")
	)
	(segment
		(start 62.974982 -284.024832)
		(end 63.433198 -284.483048)
		(width 0.13208)
		(layer "B.Cu")
		(net "PEX0_MODE_SEL9")
	)
	(segment
		(start 39.116254 -250.806712)
		(end 38.256972 -249.94743)
		(width 0.13208)
		(layer "B.Cu")
		(net "PEX0_MODE_SEL9")
	)
	(segment
		(start 39.645336 -252.054614)
		(end 39.116254 -251.525532)
		(width 0.13208)
		(layer "B.Cu")
		(net "PEX0_MODE_SEL9")
	)
	(segment
		(start 63.433198 -284.483048)
		(end 63.433198 -285.211012)
		(width 0.13208)
		(layer "B.Cu")
		(net "PEX0_MODE_SEL9")
	)
	(segment
		(start 63.616586 -285.3944)
		(end 70.7136 -285.3944)
		(width 0.13208)
		(layer "B.Cu")
		(net "PEX0_MODE_SEL9")
	)
	(segment
		(start 70.986904 -282.982924)
		(end 71.297292 -282.672536)
		(width 0.13208)
		(layer "B.Cu")
		(net "PEX0_MODE_SEL9")
	)
	(segment
		(start 70.986904 -285.121096)
		(end 70.986904 -282.982924)
		(width 0.13208)
		(layer "B.Cu")
		(net "PEX0_MODE_SEL9")
	)
	(segment
		(start 72.505316 -281.883866)
		(end 72.505316 -271.74952)
		(width 0.13208)
		(layer "B.Cu")
		(net "PEX0_MODE_SEL9")
	)
	(segment
		(start 39.116254 -251.525532)
		(end 39.116254 -250.806712)
		(width 0.13208)
		(layer "B.Cu")
		(net "PEX0_MODE_SEL9")
	)
	(segment
		(start 71.716646 -282.672536)
		(end 72.505316 -281.883866)
		(width 0.13208)
		(layer "B.Cu")
		(net "PEX0_MODE_SEL9")
	)
	(segment
		(start 63.433198 -285.211012)
		(end 63.616586 -285.3944)
		(width 0.13208)
		(layer "B.Cu")
		(net "PEX0_MODE_SEL9")
	)
	(segment
		(start 72.505316 -271.74952)
		(end 52.81041 -252.054614)
		(width 0.13208)
		(layer "B.Cu")
		(net "PEX0_MODE_SEL9")
	)
	(segment
		(start 38.256972 -249.94743)
		(end 24.819864 -249.94743)
		(width 0.13208)
		(layer "B.Cu")
		(net "PEX0_MODE_SEL9")
	)
	(segment
		(start 142.922752 -311.556654)
		(end 143.93672 -312.570622)
		(width 0.13208)
		(layer "F.Cu")
		(net "PU_PEX1_TR_TCK")
	)
	(segment
		(start 143.93672 -312.570622)
		(end 147.093432 -312.570622)
		(width 0.13208)
		(layer "F.Cu")
		(net "PU_PEX1_TR_TCK")
	)
	(segment
		(start 170.999912 -309.199788)
		(end 171.474892 -308.724808)
		(width 0.13208)
		(layer "F.Cu")
		(net "PU_PEX1_TR_TCK")
	)
	(segment
		(start 149.747732 -313.669934)
		(end 150.529036 -313.669934)
		(width 0.13208)
		(layer "F.Cu")
		(net "PU_PEX1_TR_TCK")
	)
	(segment
		(start 147.093432 -312.570622)
		(end 149.747732 -313.669934)
		(width 0.13208)
		(layer "F.Cu")
		(net "PU_PEX1_TR_TCK")
	)
	(via
		(at 171.474892 -308.724808)
		(size 0.4064)
		(drill 0.2032)
		(layers "F.Cu" "B.Cu")
		(net "PU_PEX1_TR_TCK")
	)
	(via
		(at 150.529036 -313.669934)
		(size 0.508)
		(drill 0.254)
		(layers "F.Cu" "B.Cu")
		(net "PU_PEX1_TR_TCK")
	)
	(segment
		(start 151.507698 -315.341)
		(end 171.141644 -315.341)
		(width 0.13208)
		(layer "B.Cu")
		(net "PU_PEX1_TR_TCK")
	)
	(segment
		(start 171.141644 -315.341)
		(end 171.474892 -315.007752)
		(width 0.13208)
		(layer "B.Cu")
		(net "PU_PEX1_TR_TCK")
	)
	(segment
		(start 150.529036 -314.362338)
		(end 151.507698 -315.341)
		(width 0.13208)
		(layer "B.Cu")
		(net "PU_PEX1_TR_TCK")
	)
	(segment
		(start 150.529036 -313.669934)
		(end 150.529036 -314.362338)
		(width 0.13208)
		(layer "B.Cu")
		(net "PU_PEX1_TR_TCK")
	)
	(segment
		(start 171.474892 -315.007752)
		(end 171.474892 -308.724808)
		(width 0.13208)
		(layer "B.Cu")
		(net "PU_PEX1_TR_TCK")
	)
	(segment
		(start 214.63 -197.866)
		(end 214.63 -196.977)
		(width 0.13208)
		(layer "F.Cu")
		(net "RST_BIC_I2C6_MUX_R_N")
	)
	(segment
		(start 214.25281 -207.81899)
		(end 214.25281 -198.24319)
		(width 0.13208)
		(layer "F.Cu")
		(net "RST_BIC_I2C6_MUX_R_N")
	)
	(segment
		(start 380.672086 -89.39276)
		(end 373.331232 -89.39276)
		(width 0.13208)
		(layer "F.Cu")
		(net "RST_BIC_I2C6_MUX_R_N")
	)
	(segment
		(start 212.229954 -209.754724)
		(end 211.951316 -209.476086)
		(width 0.13208)
		(layer "F.Cu")
		(net "RST_BIC_I2C6_MUX_R_N")
	)
	(segment
		(start 371.084602 -91.63939)
		(end 367.665508 -91.63939)
		(width 0.13208)
		(layer "F.Cu")
		(net "RST_BIC_I2C6_MUX_R_N")
	)
	(segment
		(start 373.331232 -89.39276)
		(end 371.084602 -91.63939)
		(width 0.13208)
		(layer "F.Cu")
		(net "RST_BIC_I2C6_MUX_R_N")
	)
	(segment
		(start 381.978154 -88.086692)
		(end 380.672086 -89.39276)
		(width 0.13208)
		(layer "F.Cu")
		(net "RST_BIC_I2C6_MUX_R_N")
	)
	(segment
		(start 210.439 -190.754)
		(end 210.185 -190.5)
		(width 0.13208)
		(layer "F.Cu")
		(net "RST_BIC_I2C6_MUX_R_N")
	)
	(segment
		(start 212.0646 -210.7184)
		(end 212.229954 -210.553046)
		(width 0.13208)
		(layer "F.Cu")
		(net "RST_BIC_I2C6_MUX_R_N")
	)
	(segment
		(start 214.503 -191.643)
		(end 213.614 -190.754)
		(width 0.13208)
		(layer "F.Cu")
		(net "RST_BIC_I2C6_MUX_R_N")
	)
	(segment
		(start 382.640078 -88.086692)
		(end 381.978154 -88.086692)
		(width 0.13208)
		(layer "F.Cu")
		(net "RST_BIC_I2C6_MUX_R_N")
	)
	(segment
		(start 211.951316 -209.128868)
		(end 212.211666 -208.868518)
		(width 0.13208)
		(layer "F.Cu")
		(net "RST_BIC_I2C6_MUX_R_N")
	)
	(segment
		(start 213.614 -190.754)
		(end 210.439 -190.754)
		(width 0.13208)
		(layer "F.Cu")
		(net "RST_BIC_I2C6_MUX_R_N")
	)
	(segment
		(start 212.229954 -210.553046)
		(end 212.229954 -209.754724)
		(width 0.13208)
		(layer "F.Cu")
		(net "RST_BIC_I2C6_MUX_R_N")
	)
	(segment
		(start 213.203282 -208.868518)
		(end 214.25281 -207.81899)
		(width 0.13208)
		(layer "F.Cu")
		(net "RST_BIC_I2C6_MUX_R_N")
	)
	(segment
		(start 214.63 -196.977)
		(end 213.499192 -195.846192)
		(width 0.13208)
		(layer "F.Cu")
		(net "RST_BIC_I2C6_MUX_R_N")
	)
	(segment
		(start 212.211666 -208.868518)
		(end 213.203282 -208.868518)
		(width 0.13208)
		(layer "F.Cu")
		(net "RST_BIC_I2C6_MUX_R_N")
	)
	(segment
		(start 212.230462 -212.120226)
		(end 212.0646 -211.954364)
		(width 0.13208)
		(layer "F.Cu")
		(net "RST_BIC_I2C6_MUX_R_N")
	)
	(segment
		(start 211.951316 -209.476086)
		(end 211.951316 -209.128868)
		(width 0.13208)
		(layer "F.Cu")
		(net "RST_BIC_I2C6_MUX_R_N")
	)
	(segment
		(start 214.25281 -198.24319)
		(end 214.63 -197.866)
		(width 0.13208)
		(layer "F.Cu")
		(net "RST_BIC_I2C6_MUX_R_N")
	)
	(segment
		(start 213.499192 -194.424808)
		(end 214.503 -193.421)
		(width 0.13208)
		(layer "F.Cu")
		(net "RST_BIC_I2C6_MUX_R_N")
	)
	(segment
		(start 213.499192 -195.846192)
		(end 213.499192 -194.424808)
		(width 0.13208)
		(layer "F.Cu")
		(net "RST_BIC_I2C6_MUX_R_N")
	)
	(segment
		(start 212.0646 -211.954364)
		(end 212.0646 -210.7184)
		(width 0.13208)
		(layer "F.Cu")
		(net "RST_BIC_I2C6_MUX_R_N")
	)
	(segment
		(start 214.503 -193.421)
		(end 214.503 -191.643)
		(width 0.13208)
		(layer "F.Cu")
		(net "RST_BIC_I2C6_MUX_R_N")
	)
	(via
		(at 367.665508 -91.63939)
		(size 0.508)
		(drill 0.254)
		(layers "F.Cu" "B.Cu")
		(net "RST_BIC_I2C6_MUX_R_N")
	)
	(via
		(at 210.185 -190.5)
		(size 0.508)
		(drill 0.254)
		(layers "F.Cu" "B.Cu")
		(net "RST_BIC_I2C6_MUX_R_N")
	)
	(via
		(at 212.708236 -216.270586)
		(size 0.508)
		(drill 0.254)
		(layers "F.Cu" "B.Cu")
		(net "RST_BIC_I2C6_MUX_R_N")
	)
	(via
		(at 225.169984 -68.317872)
		(size 0.508)
		(drill 0.254)
		(layers "F.Cu" "B.Cu")
		(net "RST_BIC_I2C6_MUX_R_N")
	)
	(via
		(at 212.230462 -212.120226)
		(size 0.508)
		(drill 0.254)
		(layers "F.Cu" "B.Cu")
		(net "RST_BIC_I2C6_MUX_R_N")
	)
	(segment
		(start 214.054436 -216.270586)
		(end 214.054436 -216.063322)
		(width 0.13208)
		(layer "B.Cu")
		(net "RST_BIC_I2C6_MUX_R_N")
	)
	(segment
		(start 213.188296 -215.790526)
		(end 212.708236 -216.270586)
		(width 0.13208)
		(layer "B.Cu")
		(net "RST_BIC_I2C6_MUX_R_N")
	)
	(segment
		(start 214.054436 -216.063322)
		(end 213.78164 -215.790526)
		(width 0.13208)
		(layer "B.Cu")
		(net "RST_BIC_I2C6_MUX_R_N")
	)
	(segment
		(start 213.78164 -215.790526)
		(end 213.188296 -215.790526)
		(width 0.13208)
		(layer "B.Cu")
		(net "RST_BIC_I2C6_MUX_R_N")
	)
	(segment
		(start 211.525866 -215.398604)
		(end 211.525866 -212.824822)
		(width 0.15494)
		(layer "In5.Cu")
		(net "RST_BIC_I2C6_MUX_R_N")
	)
	(segment
		(start 211.525866 -212.824822)
		(end 212.230462 -212.120226)
		(width 0.15494)
		(layer "In5.Cu")
		(net "RST_BIC_I2C6_MUX_R_N")
	)
	(segment
		(start 212.708236 -216.270586)
		(end 212.397848 -216.270586)
		(width 0.15494)
		(layer "In5.Cu")
		(net "RST_BIC_I2C6_MUX_R_N")
	)
	(segment
		(start 212.397848 -216.270586)
		(end 211.525866 -215.398604)
		(width 0.15494)
		(layer "In5.Cu")
		(net "RST_BIC_I2C6_MUX_R_N")
	)
	(segment
		(start 217.397076 -157.683708)
		(end 213.403688 -153.69032)
		(width 0.15494)
		(layer "In7.Cu")
		(net "RST_BIC_I2C6_MUX_R_N")
	)
	(segment
		(start 225.724212 -71.533512)
		(end 225.169984 -70.979284)
		(width 0.15494)
		(layer "In7.Cu")
		(net "RST_BIC_I2C6_MUX_R_N")
	)
	(segment
		(start 214.02548 -88.996774)
		(end 221.903036 -88.996774)
		(width 0.15494)
		(layer "In7.Cu")
		(net "RST_BIC_I2C6_MUX_R_N")
	)
	(segment
		(start 225.169984 -70.979284)
		(end 225.169984 -68.317872)
		(width 0.15494)
		(layer "In7.Cu")
		(net "RST_BIC_I2C6_MUX_R_N")
	)
	(segment
		(start 208.669128 -170.587162)
		(end 217.397076 -161.859214)
		(width 0.15494)
		(layer "In7.Cu")
		(net "RST_BIC_I2C6_MUX_R_N")
	)
	(segment
		(start 208.669128 -181.75605)
		(end 208.669128 -170.587162)
		(width 0.15494)
		(layer "In7.Cu")
		(net "RST_BIC_I2C6_MUX_R_N")
	)
	(segment
		(start 205.2828 -103.8098)
		(end 202.78598 -101.31298)
		(width 0.15494)
		(layer "In7.Cu")
		(net "RST_BIC_I2C6_MUX_R_N")
	)
	(segment
		(start 203.714858 -95.700088)
		(end 209.521044 -89.893902)
		(width 0.15494)
		(layer "In7.Cu")
		(net "RST_BIC_I2C6_MUX_R_N")
	)
	(segment
		(start 217.397076 -161.859214)
		(end 217.397076 -157.683708)
		(width 0.15494)
		(layer "In7.Cu")
		(net "RST_BIC_I2C6_MUX_R_N")
	)
	(segment
		(start 210.410806 -187.089288)
		(end 210.82508 -186.675014)
		(width 0.15494)
		(layer "In7.Cu")
		(net "RST_BIC_I2C6_MUX_R_N")
	)
	(segment
		(start 210.82508 -186.675014)
		(end 210.82508 -183.912002)
		(width 0.15494)
		(layer "In7.Cu")
		(net "RST_BIC_I2C6_MUX_R_N")
	)
	(segment
		(start 210.82508 -183.912002)
		(end 208.669128 -181.75605)
		(width 0.15494)
		(layer "In7.Cu")
		(net "RST_BIC_I2C6_MUX_R_N")
	)
	(segment
		(start 225.724212 -85.175598)
		(end 225.724212 -71.533512)
		(width 0.15494)
		(layer "In7.Cu")
		(net "RST_BIC_I2C6_MUX_R_N")
	)
	(segment
		(start 210.410806 -190.274194)
		(end 210.410806 -187.089288)
		(width 0.15494)
		(layer "In7.Cu")
		(net "RST_BIC_I2C6_MUX_R_N")
	)
	(segment
		(start 210.185 -190.5)
		(end 210.410806 -190.274194)
		(width 0.15494)
		(layer "In7.Cu")
		(net "RST_BIC_I2C6_MUX_R_N")
	)
	(segment
		(start 205.2828 -125.120146)
		(end 205.2828 -103.8098)
		(width 0.15494)
		(layer "In7.Cu")
		(net "RST_BIC_I2C6_MUX_R_N")
	)
	(segment
		(start 202.78598 -101.31298)
		(end 202.78598 -97.942654)
		(width 0.15494)
		(layer "In7.Cu")
		(net "RST_BIC_I2C6_MUX_R_N")
	)
	(segment
		(start 202.78598 -97.942654)
		(end 203.714858 -95.700088)
		(width 0.15494)
		(layer "In7.Cu")
		(net "RST_BIC_I2C6_MUX_R_N")
	)
	(segment
		(start 213.128352 -89.893902)
		(end 214.02548 -88.996774)
		(width 0.15494)
		(layer "In7.Cu")
		(net "RST_BIC_I2C6_MUX_R_N")
	)
	(segment
		(start 209.521044 -89.893902)
		(end 213.128352 -89.893902)
		(width 0.15494)
		(layer "In7.Cu")
		(net "RST_BIC_I2C6_MUX_R_N")
	)
	(segment
		(start 213.403688 -153.69032)
		(end 213.403688 -133.241034)
		(width 0.15494)
		(layer "In7.Cu")
		(net "RST_BIC_I2C6_MUX_R_N")
	)
	(segment
		(start 221.903036 -88.996774)
		(end 225.724212 -85.175598)
		(width 0.15494)
		(layer "In7.Cu")
		(net "RST_BIC_I2C6_MUX_R_N")
	)
	(segment
		(start 213.403688 -133.241034)
		(end 205.2828 -125.120146)
		(width 0.15494)
		(layer "In7.Cu")
		(net "RST_BIC_I2C6_MUX_R_N")
	)
	(segment
		(start 356.031546 -78.3082)
		(end 347.624146 -78.3082)
		(width 0.15494)
		(layer "In15.Cu")
		(net "RST_BIC_I2C6_MUX_R_N")
	)
	(segment
		(start 253.462536 -71.0692)
		(end 247.904254 -71.0692)
		(width 0.15494)
		(layer "In15.Cu")
		(net "RST_BIC_I2C6_MUX_R_N")
	)
	(segment
		(start 321.919854 -74.041)
		(end 310.791352 -74.041)
		(width 0.15494)
		(layer "In15.Cu")
		(net "RST_BIC_I2C6_MUX_R_N")
	)
	(segment
		(start 367.665508 -91.63939)
		(end 367.22939 -91.63939)
		(width 0.15494)
		(layer "In15.Cu")
		(net "RST_BIC_I2C6_MUX_R_N")
	)
	(segment
		(start 344.550746 -75.2348)
		(end 335.737454 -75.2348)
		(width 0.15494)
		(layer "In15.Cu")
		(net "RST_BIC_I2C6_MUX_R_N")
	)
	(segment
		(start 235.3818 -70.4342)
		(end 235.3818 -67.259454)
		(width 0.15494)
		(layer "In15.Cu")
		(net "RST_BIC_I2C6_MUX_R_N")
	)
	(segment
		(start 310.791352 -74.041)
		(end 309.648352 -75.184)
		(width 0.15494)
		(layer "In15.Cu")
		(net "RST_BIC_I2C6_MUX_R_N")
	)
	(segment
		(start 323.799454 -75.9206)
		(end 321.919854 -74.041)
		(width 0.15494)
		(layer "In15.Cu")
		(net "RST_BIC_I2C6_MUX_R_N")
	)
	(segment
		(start 235.3818 -67.259454)
		(end 234.746546 -66.6242)
		(width 0.15494)
		(layer "In15.Cu")
		(net "RST_BIC_I2C6_MUX_R_N")
	)
	(segment
		(start 226.635056 -66.8528)
		(end 225.169984 -68.317872)
		(width 0.15494)
		(layer "In15.Cu")
		(net "RST_BIC_I2C6_MUX_R_N")
	)
	(segment
		(start 276.504146 -75.4126)
		(end 273.029426 -71.93788)
		(width 0.15494)
		(layer "In15.Cu")
		(net "RST_BIC_I2C6_MUX_R_N")
	)
	(segment
		(start 238.379 -71.0692)
		(end 236.0168 -71.0692)
		(width 0.15494)
		(layer "In15.Cu")
		(net "RST_BIC_I2C6_MUX_R_N")
	)
	(segment
		(start 273.029426 -71.93788)
		(end 254.331216 -71.93788)
		(width 0.15494)
		(layer "In15.Cu")
		(net "RST_BIC_I2C6_MUX_R_N")
	)
	(segment
		(start 335.737454 -75.2348)
		(end 335.051654 -75.9206)
		(width 0.15494)
		(layer "In15.Cu")
		(net "RST_BIC_I2C6_MUX_R_N")
	)
	(segment
		(start 363.788452 -89.722198)
		(end 363.788452 -86.065106)
		(width 0.15494)
		(layer "In15.Cu")
		(net "RST_BIC_I2C6_MUX_R_N")
	)
	(segment
		(start 364.718854 -90.6526)
		(end 363.788452 -89.722198)
		(width 0.15494)
		(layer "In15.Cu")
		(net "RST_BIC_I2C6_MUX_R_N")
	)
	(segment
		(start 232.9688 -66.6242)
		(end 232.3084 -67.2846)
		(width 0.15494)
		(layer "In15.Cu")
		(net "RST_BIC_I2C6_MUX_R_N")
	)
	(segment
		(start 229.108 -66.8528)
		(end 226.635056 -66.8528)
		(width 0.15494)
		(layer "In15.Cu")
		(net "RST_BIC_I2C6_MUX_R_N")
	)
	(segment
		(start 254.331216 -71.93788)
		(end 253.462536 -71.0692)
		(width 0.15494)
		(layer "In15.Cu")
		(net "RST_BIC_I2C6_MUX_R_N")
	)
	(segment
		(start 347.624146 -78.3082)
		(end 344.550746 -75.2348)
		(width 0.15494)
		(layer "In15.Cu")
		(net "RST_BIC_I2C6_MUX_R_N")
	)
	(segment
		(start 246.862854 -72.1106)
		(end 239.4204 -72.1106)
		(width 0.15494)
		(layer "In15.Cu")
		(net "RST_BIC_I2C6_MUX_R_N")
	)
	(segment
		(start 239.4204 -72.1106)
		(end 238.379 -71.0692)
		(width 0.15494)
		(layer "In15.Cu")
		(net "RST_BIC_I2C6_MUX_R_N")
	)
	(segment
		(start 335.051654 -75.9206)
		(end 323.799454 -75.9206)
		(width 0.15494)
		(layer "In15.Cu")
		(net "RST_BIC_I2C6_MUX_R_N")
	)
	(segment
		(start 367.22939 -91.63939)
		(end 366.2426 -90.6526)
		(width 0.15494)
		(layer "In15.Cu")
		(net "RST_BIC_I2C6_MUX_R_N")
	)
	(segment
		(start 232.3084 -67.2846)
		(end 229.5398 -67.2846)
		(width 0.15494)
		(layer "In15.Cu")
		(net "RST_BIC_I2C6_MUX_R_N")
	)
	(segment
		(start 247.904254 -71.0692)
		(end 246.862854 -72.1106)
		(width 0.15494)
		(layer "In15.Cu")
		(net "RST_BIC_I2C6_MUX_R_N")
	)
	(segment
		(start 296.357294 -75.184)
		(end 296.128694 -75.4126)
		(width 0.15494)
		(layer "In15.Cu")
		(net "RST_BIC_I2C6_MUX_R_N")
	)
	(segment
		(start 363.788452 -86.065106)
		(end 356.031546 -78.3082)
		(width 0.15494)
		(layer "In15.Cu")
		(net "RST_BIC_I2C6_MUX_R_N")
	)
	(segment
		(start 296.128694 -75.4126)
		(end 276.504146 -75.4126)
		(width 0.15494)
		(layer "In15.Cu")
		(net "RST_BIC_I2C6_MUX_R_N")
	)
	(segment
		(start 229.5398 -67.2846)
		(end 229.108 -66.8528)
		(width 0.15494)
		(layer "In15.Cu")
		(net "RST_BIC_I2C6_MUX_R_N")
	)
	(segment
		(start 309.648352 -75.184)
		(end 296.357294 -75.184)
		(width 0.15494)
		(layer "In15.Cu")
		(net "RST_BIC_I2C6_MUX_R_N")
	)
	(segment
		(start 234.746546 -66.6242)
		(end 232.9688 -66.6242)
		(width 0.15494)
		(layer "In15.Cu")
		(net "RST_BIC_I2C6_MUX_R_N")
	)
	(segment
		(start 236.0168 -71.0692)
		(end 235.3818 -70.4342)
		(width 0.15494)
		(layer "In15.Cu")
		(net "RST_BIC_I2C6_MUX_R_N")
	)
	(segment
		(start 366.2426 -90.6526)
		(end 364.718854 -90.6526)
		(width 0.15494)
		(layer "In15.Cu")
		(net "RST_BIC_I2C6_MUX_R_N")
	)
	(segment
		(start 89.921588 -302.116236)
		(end 88.75395 -302.116236)
		(width 0.13208)
		(layer "F.Cu")
		(net "SMB_PEX0_SDA")
	)
	(segment
		(start 212.574886 -231.550972)
		(end 212.574886 -232.160572)
		(width 0.13208)
		(layer "F.Cu")
		(net "SMB_PEX0_SDA")
	)
	(segment
		(start 90.271092 -301.766732)
		(end 89.921588 -302.116236)
		(width 0.13208)
		(layer "F.Cu")
		(net "SMB_PEX0_SDA")
	)
	(segment
		(start 90.880184 -301.766732)
		(end 90.271092 -301.766732)
		(width 0.13208)
		(layer "F.Cu")
		(net "SMB_PEX0_SDA")
	)
	(segment
		(start 88.339168 -302.531018)
		(end 87.941658 -302.531018)
		(width 0.13208)
		(layer "F.Cu")
		(net "SMB_PEX0_SDA")
	)
	(segment
		(start 88.75395 -302.116236)
		(end 88.339168 -302.531018)
		(width 0.13208)
		(layer "F.Cu")
		(net "SMB_PEX0_SDA")
	)
	(segment
		(start 87.941658 -302.531018)
		(end 87.918544 -302.507904)
		(width 0.13208)
		(layer "F.Cu")
		(net "SMB_PEX0_SDA")
	)
	(via
		(at 96.604074 -198.787258)
		(size 0.508)
		(drill 0.254)
		(layers "F.Cu" "B.Cu")
		(net "SMB_PEX0_SDA")
	)
	(via
		(at 90.880184 -301.766732)
		(size 0.508)
		(drill 0.254)
		(layers "F.Cu" "B.Cu")
		(net "SMB_PEX0_SDA")
	)
	(via
		(at 94.705932 -237.524544)
		(size 0.508)
		(drill 0.254)
		(layers "F.Cu" "B.Cu")
		(net "SMB_PEX0_SDA")
	)
	(via
		(at 212.574886 -232.160572)
		(size 0.508)
		(drill 0.254)
		(layers "F.Cu" "B.Cu")
		(net "SMB_PEX0_SDA")
	)
	(via
		(at 214.884 -196.108066)
		(size 0.508)
		(drill 0.254)
		(layers "F.Cu" "B.Cu")
		(net "SMB_PEX0_SDA")
	)
	(segment
		(start 92.38107 -300.265846)
		(end 90.880184 -301.766732)
		(width 0.13208)
		(layer "B.Cu")
		(net "SMB_PEX0_SDA")
	)
	(segment
		(start 92.870274 -294.53205)
		(end 92.38107 -295.021254)
		(width 0.13208)
		(layer "B.Cu")
		(net "SMB_PEX0_SDA")
	)
	(segment
		(start 95.016574 -238.56696)
		(end 94.64294 -238.940594)
		(width 0.13208)
		(layer "B.Cu")
		(net "SMB_PEX0_SDA")
	)
	(segment
		(start 99.285806 -264.544048)
		(end 99.285806 -277.318724)
		(width 0.13208)
		(layer "B.Cu")
		(net "SMB_PEX0_SDA")
	)
	(segment
		(start 92.961714 -238.940594)
		(end 91.78925 -240.113058)
		(width 0.13208)
		(layer "B.Cu")
		(net "SMB_PEX0_SDA")
	)
	(segment
		(start 100.0252 -263.804654)
		(end 99.285806 -264.544048)
		(width 0.13208)
		(layer "B.Cu")
		(net "SMB_PEX0_SDA")
	)
	(segment
		(start 91.78925 -240.113058)
		(end 91.78925 -247.059704)
		(width 0.13208)
		(layer "B.Cu")
		(net "SMB_PEX0_SDA")
	)
	(segment
		(start 91.78925 -247.059704)
		(end 96.418146 -251.6886)
		(width 0.13208)
		(layer "B.Cu")
		(net "SMB_PEX0_SDA")
	)
	(segment
		(start 93.93301 -289.99815)
		(end 92.870274 -291.060886)
		(width 0.13208)
		(layer "B.Cu")
		(net "SMB_PEX0_SDA")
	)
	(segment
		(start 99.285806 -277.318724)
		(end 93.93301 -282.67152)
		(width 0.13208)
		(layer "B.Cu")
		(net "SMB_PEX0_SDA")
	)
	(segment
		(start 93.93301 -282.67152)
		(end 93.93301 -289.99815)
		(width 0.13208)
		(layer "B.Cu")
		(net "SMB_PEX0_SDA")
	)
	(segment
		(start 94.705932 -237.524544)
		(end 94.733618 -237.524544)
		(width 0.13208)
		(layer "B.Cu")
		(net "SMB_PEX0_SDA")
	)
	(segment
		(start 94.733618 -237.524544)
		(end 95.016574 -237.8075)
		(width 0.13208)
		(layer "B.Cu")
		(net "SMB_PEX0_SDA")
	)
	(segment
		(start 96.418146 -251.6886)
		(end 97.8916 -251.6886)
		(width 0.13208)
		(layer "B.Cu")
		(net "SMB_PEX0_SDA")
	)
	(segment
		(start 100.0252 -253.8222)
		(end 100.0252 -263.804654)
		(width 0.13208)
		(layer "B.Cu")
		(net "SMB_PEX0_SDA")
	)
	(segment
		(start 212.574886 -232.160572)
		(end 212.409532 -231.995218)
		(width 0.13208)
		(layer "B.Cu")
		(net "SMB_PEX0_SDA")
	)
	(segment
		(start 212.409532 -231.995218)
		(end 212.409532 -231.05364)
		(width 0.13208)
		(layer "B.Cu")
		(net "SMB_PEX0_SDA")
	)
	(segment
		(start 92.870274 -291.060886)
		(end 92.870274 -294.53205)
		(width 0.13208)
		(layer "B.Cu")
		(net "SMB_PEX0_SDA")
	)
	(segment
		(start 92.38107 -295.021254)
		(end 92.38107 -300.265846)
		(width 0.13208)
		(layer "B.Cu")
		(net "SMB_PEX0_SDA")
	)
	(segment
		(start 97.8916 -251.6886)
		(end 100.0252 -253.8222)
		(width 0.13208)
		(layer "B.Cu")
		(net "SMB_PEX0_SDA")
	)
	(segment
		(start 95.016574 -237.8075)
		(end 95.016574 -238.56696)
		(width 0.13208)
		(layer "B.Cu")
		(net "SMB_PEX0_SDA")
	)
	(segment
		(start 94.64294 -238.940594)
		(end 92.961714 -238.940594)
		(width 0.13208)
		(layer "B.Cu")
		(net "SMB_PEX0_SDA")
	)
	(segment
		(start 94.705932 -211.899246)
		(end 95.4786 -211.126578)
		(width 0.15494)
		(layer "In5.Cu")
		(net "SMB_PEX0_SDA")
	)
	(segment
		(start 212.574886 -228.374702)
		(end 211.619846 -227.419662)
		(width 0.15494)
		(layer "In5.Cu")
		(net "SMB_PEX0_SDA")
	)
	(segment
		(start 212.496654 -224.912682)
		(end 212.960966 -224.912682)
		(width 0.15494)
		(layer "In5.Cu")
		(net "SMB_PEX0_SDA")
	)
	(segment
		(start 211.619846 -225.78949)
		(end 212.496654 -224.912682)
		(width 0.15494)
		(layer "In5.Cu")
		(net "SMB_PEX0_SDA")
	)
	(segment
		(start 95.4786 -199.912732)
		(end 96.604074 -198.787258)
		(width 0.15494)
		(layer "In5.Cu")
		(net "SMB_PEX0_SDA")
	)
	(segment
		(start 214.421974 -196.318378)
		(end 214.632286 -196.108066)
		(width 0.15494)
		(layer "In5.Cu")
		(net "SMB_PEX0_SDA")
	)
	(segment
		(start 214.421974 -217.193114)
		(end 214.421974 -196.318378)
		(width 0.15494)
		(layer "In5.Cu")
		(net "SMB_PEX0_SDA")
	)
	(segment
		(start 212.960966 -224.912682)
		(end 214.195406 -223.678242)
		(width 0.15494)
		(layer "In5.Cu")
		(net "SMB_PEX0_SDA")
	)
	(segment
		(start 214.195406 -223.678242)
		(end 214.195406 -220.199712)
		(width 0.15494)
		(layer "In5.Cu")
		(net "SMB_PEX0_SDA")
	)
	(segment
		(start 212.574886 -232.160572)
		(end 212.574886 -228.374702)
		(width 0.15494)
		(layer "In5.Cu")
		(net "SMB_PEX0_SDA")
	)
	(segment
		(start 94.705932 -237.524544)
		(end 94.705932 -211.899246)
		(width 0.15494)
		(layer "In5.Cu")
		(net "SMB_PEX0_SDA")
	)
	(segment
		(start 214.195406 -220.199712)
		(end 213.741 -219.745306)
		(width 0.15494)
		(layer "In5.Cu")
		(net "SMB_PEX0_SDA")
	)
	(segment
		(start 213.741 -217.874088)
		(end 214.421974 -217.193114)
		(width 0.15494)
		(layer "In5.Cu")
		(net "SMB_PEX0_SDA")
	)
	(segment
		(start 213.741 -219.745306)
		(end 213.741 -217.874088)
		(width 0.15494)
		(layer "In5.Cu")
		(net "SMB_PEX0_SDA")
	)
	(segment
		(start 95.4786 -211.126578)
		(end 95.4786 -199.912732)
		(width 0.15494)
		(layer "In5.Cu")
		(net "SMB_PEX0_SDA")
	)
	(segment
		(start 211.619846 -227.419662)
		(end 211.619846 -225.78949)
		(width 0.15494)
		(layer "In5.Cu")
		(net "SMB_PEX0_SDA")
	)
	(segment
		(start 214.632286 -196.108066)
		(end 214.884 -196.108066)
		(width 0.15494)
		(layer "In5.Cu")
		(net "SMB_PEX0_SDA")
	)
	(segment
		(start 114.62004 -202.404726)
		(end 117.822726 -202.404726)
		(width 0.15494)
		(layer "In15.Cu")
		(net "SMB_PEX0_SDA")
	)
	(segment
		(start 183.319166 -211.4296)
		(end 184.486296 -212.59673)
		(width 0.15494)
		(layer "In15.Cu")
		(net "SMB_PEX0_SDA")
	)
	(segment
		(start 96.604074 -198.787258)
		(end 99.150932 -196.2404)
		(width 0.15494)
		(layer "In15.Cu")
		(net "SMB_PEX0_SDA")
	)
	(segment
		(start 204.513688 -200.492106)
		(end 209.797142 -200.492106)
		(width 0.15494)
		(layer "In15.Cu")
		(net "SMB_PEX0_SDA")
	)
	(segment
		(start 134.323074 -208.38922)
		(end 135.212074 -208.38922)
		(width 0.15494)
		(layer "In15.Cu")
		(net "SMB_PEX0_SDA")
	)
	(segment
		(start 143.2052 -210.2866)
		(end 144.3482 -211.4296)
		(width 0.15494)
		(layer "In15.Cu")
		(net "SMB_PEX0_SDA")
	)
	(segment
		(start 209.797142 -200.492106)
		(end 210.140042 -200.835006)
		(width 0.15494)
		(layer "In15.Cu")
		(net "SMB_PEX0_SDA")
	)
	(segment
		(start 108.455714 -196.2404)
		(end 114.62004 -202.404726)
		(width 0.15494)
		(layer "In15.Cu")
		(net "SMB_PEX0_SDA")
	)
	(segment
		(start 135.212074 -208.38922)
		(end 136.72693 -209.904076)
		(width 0.15494)
		(layer "In15.Cu")
		(net "SMB_PEX0_SDA")
	)
	(segment
		(start 144.3482 -211.4296)
		(end 183.319166 -211.4296)
		(width 0.15494)
		(layer "In15.Cu")
		(net "SMB_PEX0_SDA")
	)
	(segment
		(start 192.409064 -212.59673)
		(end 204.513688 -200.492106)
		(width 0.15494)
		(layer "In15.Cu")
		(net "SMB_PEX0_SDA")
	)
	(segment
		(start 184.486296 -212.59673)
		(end 192.409064 -212.59673)
		(width 0.15494)
		(layer "In15.Cu")
		(net "SMB_PEX0_SDA")
	)
	(segment
		(start 137.844276 -209.904076)
		(end 138.2268 -210.2866)
		(width 0.15494)
		(layer "In15.Cu")
		(net "SMB_PEX0_SDA")
	)
	(segment
		(start 214.884 -197.917308)
		(end 214.884 -196.108066)
		(width 0.15494)
		(layer "In15.Cu")
		(net "SMB_PEX0_SDA")
	)
	(segment
		(start 122.9868 -207.5688)
		(end 133.502654 -207.5688)
		(width 0.15494)
		(layer "In15.Cu")
		(net "SMB_PEX0_SDA")
	)
	(segment
		(start 99.150932 -196.2404)
		(end 108.455714 -196.2404)
		(width 0.15494)
		(layer "In15.Cu")
		(net "SMB_PEX0_SDA")
	)
	(segment
		(start 133.502654 -207.5688)
		(end 134.323074 -208.38922)
		(width 0.15494)
		(layer "In15.Cu")
		(net "SMB_PEX0_SDA")
	)
	(segment
		(start 211.966302 -200.835006)
		(end 214.884 -197.917308)
		(width 0.15494)
		(layer "In15.Cu")
		(net "SMB_PEX0_SDA")
	)
	(segment
		(start 117.822726 -202.404726)
		(end 122.9868 -207.5688)
		(width 0.15494)
		(layer "In15.Cu")
		(net "SMB_PEX0_SDA")
	)
	(segment
		(start 210.140042 -200.835006)
		(end 211.966302 -200.835006)
		(width 0.15494)
		(layer "In15.Cu")
		(net "SMB_PEX0_SDA")
	)
	(segment
		(start 138.2268 -210.2866)
		(end 143.2052 -210.2866)
		(width 0.15494)
		(layer "In15.Cu")
		(net "SMB_PEX0_SDA")
	)
	(segment
		(start 136.72693 -209.904076)
		(end 137.844276 -209.904076)
		(width 0.15494)
		(layer "In15.Cu")
		(net "SMB_PEX0_SDA")
	)
	(segment
		(start 225.067622 -219.904056)
		(end 224.667826 -220.303852)
		(width 0.13208)
		(layer "F.Cu")
		(net "SMB_PEX_SCL")
	)
	(via
		(at 222.694754 -219.719652)
		(size 0.6604)
		(drill 0.3302)
		(layers "F.Cu" "B.Cu")
		(net "SMB_PEX_SCL")
	)
	(via
		(at 224.667826 -220.303852)
		(size 0.4572)
		(drill 0.254)
		(layers "F.Cu" "B.Cu")
		(net "SMB_PEX_SCL")
	)
	(segment
		(start 217.86088 -218.823286)
		(end 217.635836 -219.04833)
		(width 0.13208)
		(layer "B.Cu")
		(net "SMB_PEX_SCL")
	)
	(segment
		(start 224.667826 -220.303852)
		(end 224.083626 -219.719652)
		(width 0.13208)
		(layer "B.Cu")
		(net "SMB_PEX_SCL")
	)
	(segment
		(start 222.694754 -219.719652)
		(end 220.514926 -219.719652)
		(width 0.13208)
		(layer "B.Cu")
		(net "SMB_PEX_SCL")
	)
	(segment
		(start 220.514926 -219.719652)
		(end 219.61856 -218.823286)
		(width 0.13208)
		(layer "B.Cu")
		(net "SMB_PEX_SCL")
	)
	(segment
		(start 219.61856 -218.823286)
		(end 217.86088 -218.823286)
		(width 0.13208)
		(layer "B.Cu")
		(net "SMB_PEX_SCL")
	)
	(segment
		(start 224.083626 -219.719652)
		(end 222.694754 -219.719652)
		(width 0.13208)
		(layer "B.Cu")
		(net "SMB_PEX_SCL")
	)
	(segment
		(start 217.635836 -219.04833)
		(end 217.635836 -219.318586)
		(width 0.13208)
		(layer "B.Cu")
		(net "SMB_PEX_SCL")
	)
	(segment
		(start 427.304454 -62.119764)
		(end 427.304454 -64.886332)
		(width 0.13208)
		(layer "F.Cu")
		(net "PWRGD_P12V_SSD15_R")
	)
	(segment
		(start 342.392 -210.185)
		(end 342.9 -209.677)
		(width 0.13208)
		(layer "F.Cu")
		(net "PWRGD_P12V_SSD15_R")
	)
	(segment
		(start 342.392 -210.693)
		(end 342.392 -210.185)
		(width 0.13208)
		(layer "F.Cu")
		(net "PWRGD_P12V_SSD15_R")
	)
	(segment
		(start 452.967852 -53.051456)
		(end 453.623172 -53.051456)
		(width 0.13208)
		(layer "F.Cu")
		(net "PWRGD_P12V_SSD15_R")
	)
	(segment
		(start 428.173642 -65.75552)
		(end 441.028582 -65.75552)
		(width 0.13208)
		(layer "F.Cu")
		(net "PWRGD_P12V_SSD15_R")
	)
	(segment
		(start 427.304454 -64.886332)
		(end 428.173642 -65.75552)
		(width 0.13208)
		(layer "F.Cu")
		(net "PWRGD_P12V_SSD15_R")
	)
	(segment
		(start 342.497664 -210.798664)
		(end 342.392 -210.693)
		(width 0.13208)
		(layer "F.Cu")
		(net "PWRGD_P12V_SSD15_R")
	)
	(segment
		(start 342.497664 -211.59089)
		(end 342.497664 -210.798664)
		(width 0.13208)
		(layer "F.Cu")
		(net "PWRGD_P12V_SSD15_R")
	)
	(segment
		(start 342.893904 -211.98713)
		(end 342.497664 -211.59089)
		(width 0.13208)
		(layer "F.Cu")
		(net "PWRGD_P12V_SSD15_R")
	)
	(segment
		(start 427.936406 -61.487812)
		(end 427.304454 -62.119764)
		(width 0.13208)
		(layer "F.Cu")
		(net "PWRGD_P12V_SSD15_R")
	)
	(segment
		(start 429.783494 -61.487812)
		(end 427.936406 -61.487812)
		(width 0.13208)
		(layer "F.Cu")
		(net "PWRGD_P12V_SSD15_R")
	)
	(via
		(at 423.38244 -89.829894)
		(size 0.508)
		(drill 0.254)
		(layers "F.Cu" "B.Cu")
		(net "PWRGD_P12V_SSD15_R")
	)
	(via
		(at 342.9 -209.677)
		(size 0.508)
		(drill 0.254)
		(layers "F.Cu" "B.Cu")
		(net "PWRGD_P12V_SSD15_R")
	)
	(via
		(at 353.200462 -100.948744)
		(size 0.508)
		(drill 0.254)
		(layers "F.Cu" "B.Cu")
		(net "PWRGD_P12V_SSD15_R")
	)
	(via
		(at 453.623172 -53.051456)
		(size 0.508)
		(drill 0.254)
		(layers "F.Cu" "B.Cu")
		(net "PWRGD_P12V_SSD15_R")
	)
	(via
		(at 441.028582 -65.75552)
		(size 0.508)
		(drill 0.254)
		(layers "F.Cu" "B.Cu")
		(net "PWRGD_P12V_SSD15_R")
	)
	(segment
		(start 428.322486 -86.49335)
		(end 429.000666 -86.49335)
		(width 0.15494)
		(layer "In5.Cu")
		(net "PWRGD_P12V_SSD15_R")
	)
	(segment
		(start 451.768464 -64.516)
		(end 452.0438 -64.240664)
		(width 0.15494)
		(layer "In5.Cu")
		(net "PWRGD_P12V_SSD15_R")
	)
	(segment
		(start 452.0438 -57.983628)
		(end 451.5612 -57.501028)
		(width 0.15494)
		(layer "In5.Cu")
		(net "PWRGD_P12V_SSD15_R")
	)
	(segment
		(start 424.899582 -88.312752)
		(end 426.503084 -88.312752)
		(width 0.15494)
		(layer "In5.Cu")
		(net "PWRGD_P12V_SSD15_R")
	)
	(segment
		(start 453.02551 -77.28839)
		(end 454.66381 -75.65009)
		(width 0.15494)
		(layer "In5.Cu")
		(net "PWRGD_P12V_SSD15_R")
	)
	(segment
		(start 454.66381 -75.65009)
		(end 454.66381 -54.092094)
		(width 0.15494)
		(layer "In5.Cu")
		(net "PWRGD_P12V_SSD15_R")
	)
	(segment
		(start 452.0438 -64.240664)
		(end 452.0438 -57.983628)
		(width 0.15494)
		(layer "In5.Cu")
		(net "PWRGD_P12V_SSD15_R")
	)
	(segment
		(start 451.5612 -55.113428)
		(end 453.623172 -53.051456)
		(width 0.15494)
		(layer "In5.Cu")
		(net "PWRGD_P12V_SSD15_R")
	)
	(segment
		(start 438.205626 -77.28839)
		(end 453.02551 -77.28839)
		(width 0.15494)
		(layer "In5.Cu")
		(net "PWRGD_P12V_SSD15_R")
	)
	(segment
		(start 454.66381 -54.092094)
		(end 453.623172 -53.051456)
		(width 0.15494)
		(layer "In5.Cu")
		(net "PWRGD_P12V_SSD15_R")
	)
	(segment
		(start 423.38244 -89.829894)
		(end 424.899582 -88.312752)
		(width 0.15494)
		(layer "In5.Cu")
		(net "PWRGD_P12V_SSD15_R")
	)
	(segment
		(start 429.000666 -86.49335)
		(end 438.205626 -77.28839)
		(width 0.15494)
		(layer "In5.Cu")
		(net "PWRGD_P12V_SSD15_R")
	)
	(segment
		(start 451.5612 -57.501028)
		(end 451.5612 -55.113428)
		(width 0.15494)
		(layer "In5.Cu")
		(net "PWRGD_P12V_SSD15_R")
	)
	(segment
		(start 441.028582 -65.75552)
		(end 444.429134 -65.75552)
		(width 0.15494)
		(layer "In5.Cu")
		(net "PWRGD_P12V_SSD15_R")
	)
	(segment
		(start 444.429134 -65.75552)
		(end 445.668654 -64.516)
		(width 0.15494)
		(layer "In5.Cu")
		(net "PWRGD_P12V_SSD15_R")
	)
	(segment
		(start 445.668654 -64.516)
		(end 451.768464 -64.516)
		(width 0.15494)
		(layer "In5.Cu")
		(net "PWRGD_P12V_SSD15_R")
	)
	(segment
		(start 426.503084 -88.312752)
		(end 428.322486 -86.49335)
		(width 0.15494)
		(layer "In5.Cu")
		(net "PWRGD_P12V_SSD15_R")
	)
	(segment
		(start 346.577666 -127.235458)
		(end 354.490782 -119.322342)
		(width 0.15494)
		(layer "In7.Cu")
		(net "PWRGD_P12V_SSD15_R")
	)
	(segment
		(start 346.111576 -207.125824)
		(end 346.71 -206.5274)
		(width 0.15494)
		(layer "In7.Cu")
		(net "PWRGD_P12V_SSD15_R")
	)
	(segment
		(start 347.218 -202.510644)
		(end 344.473276 -195.885054)
		(width 0.15494)
		(layer "In7.Cu")
		(net "PWRGD_P12V_SSD15_R")
	)
	(segment
		(start 346.577666 -166.440866)
		(end 346.577666 -127.235458)
		(width 0.15494)
		(layer "In7.Cu")
		(net "PWRGD_P12V_SSD15_R")
	)
	(segment
		(start 344.473276 -190.060072)
		(end 348.882716 -185.650632)
		(width 0.15494)
		(layer "In7.Cu")
		(net "PWRGD_P12V_SSD15_R")
	)
	(segment
		(start 345.451176 -207.125824)
		(end 346.111576 -207.125824)
		(width 0.15494)
		(layer "In7.Cu")
		(net "PWRGD_P12V_SSD15_R")
	)
	(segment
		(start 346.71 -205.454758)
		(end 347.218 -204.946758)
		(width 0.15494)
		(layer "In7.Cu")
		(net "PWRGD_P12V_SSD15_R")
	)
	(segment
		(start 342.9 -209.677)
		(end 345.451176 -207.125824)
		(width 0.15494)
		(layer "In7.Cu")
		(net "PWRGD_P12V_SSD15_R")
	)
	(segment
		(start 344.473276 -195.885054)
		(end 344.473276 -190.060072)
		(width 0.15494)
		(layer "In7.Cu")
		(net "PWRGD_P12V_SSD15_R")
	)
	(segment
		(start 348.882716 -168.745916)
		(end 346.577666 -166.440866)
		(width 0.15494)
		(layer "In7.Cu")
		(net "PWRGD_P12V_SSD15_R")
	)
	(segment
		(start 347.218 -204.946758)
		(end 347.218 -202.510644)
		(width 0.15494)
		(layer "In7.Cu")
		(net "PWRGD_P12V_SSD15_R")
	)
	(segment
		(start 353.200462 -102.27564)
		(end 353.200462 -100.948744)
		(width 0.15494)
		(layer "In7.Cu")
		(net "PWRGD_P12V_SSD15_R")
	)
	(segment
		(start 348.882716 -185.650632)
		(end 348.882716 -168.745916)
		(width 0.15494)
		(layer "In7.Cu")
		(net "PWRGD_P12V_SSD15_R")
	)
	(segment
		(start 354.490782 -103.56596)
		(end 353.200462 -102.27564)
		(width 0.15494)
		(layer "In7.Cu")
		(net "PWRGD_P12V_SSD15_R")
	)
	(segment
		(start 346.71 -206.5274)
		(end 346.71 -205.454758)
		(width 0.15494)
		(layer "In7.Cu")
		(net "PWRGD_P12V_SSD15_R")
	)
	(segment
		(start 354.490782 -119.322342)
		(end 354.490782 -103.56596)
		(width 0.15494)
		(layer "In7.Cu")
		(net "PWRGD_P12V_SSD15_R")
	)
	(segment
		(start 357.380032 -101.724968)
		(end 356.5652 -102.5398)
		(width 0.15494)
		(layer "In15.Cu")
		(net "PWRGD_P12V_SSD15_R")
	)
	(segment
		(start 423.38244 -89.829894)
		(end 422.737534 -90.4748)
		(width 0.15494)
		(layer "In15.Cu")
		(net "PWRGD_P12V_SSD15_R")
	)
	(segment
		(start 397.720566 -97.282)
		(end 395.527022 -97.282)
		(width 0.15494)
		(layer "In15.Cu")
		(net "PWRGD_P12V_SSD15_R")
	)
	(segment
		(start 386.376672 -96.6724)
		(end 384.962654 -96.6724)
		(width 0.15494)
		(layer "In15.Cu")
		(net "PWRGD_P12V_SSD15_R")
	)
	(segment
		(start 408.54376 -90.4748)
		(end 407.470864 -91.547696)
		(width 0.15494)
		(layer "In15.Cu")
		(net "PWRGD_P12V_SSD15_R")
	)
	(segment
		(start 407.470864 -91.547696)
		(end 403.45487 -91.547696)
		(width 0.15494)
		(layer "In15.Cu")
		(net "PWRGD_P12V_SSD15_R")
	)
	(segment
		(start 356.5652 -102.5398)
		(end 354.791518 -102.5398)
		(width 0.15494)
		(layer "In15.Cu")
		(net "PWRGD_P12V_SSD15_R")
	)
	(segment
		(start 395.527022 -97.282)
		(end 394.36421 -96.119188)
		(width 0.15494)
		(layer "In15.Cu")
		(net "PWRGD_P12V_SSD15_R")
	)
	(segment
		(start 422.737534 -90.4748)
		(end 408.54376 -90.4748)
		(width 0.15494)
		(layer "In15.Cu")
		(net "PWRGD_P12V_SSD15_R")
	)
	(segment
		(start 369.789202 -101.13772)
		(end 369.201954 -101.724968)
		(width 0.15494)
		(layer "In15.Cu")
		(net "PWRGD_P12V_SSD15_R")
	)
	(segment
		(start 403.45487 -91.547696)
		(end 397.720566 -97.282)
		(width 0.15494)
		(layer "In15.Cu")
		(net "PWRGD_P12V_SSD15_R")
	)
	(segment
		(start 384.962654 -96.6724)
		(end 380.497334 -101.13772)
		(width 0.15494)
		(layer "In15.Cu")
		(net "PWRGD_P12V_SSD15_R")
	)
	(segment
		(start 380.497334 -101.13772)
		(end 369.789202 -101.13772)
		(width 0.15494)
		(layer "In15.Cu")
		(net "PWRGD_P12V_SSD15_R")
	)
	(segment
		(start 386.929884 -96.119188)
		(end 386.376672 -96.6724)
		(width 0.15494)
		(layer "In15.Cu")
		(net "PWRGD_P12V_SSD15_R")
	)
	(segment
		(start 394.36421 -96.119188)
		(end 386.929884 -96.119188)
		(width 0.15494)
		(layer "In15.Cu")
		(net "PWRGD_P12V_SSD15_R")
	)
	(segment
		(start 354.791518 -102.5398)
		(end 353.200462 -100.948744)
		(width 0.15494)
		(layer "In15.Cu")
		(net "PWRGD_P12V_SSD15_R")
	)
	(segment
		(start 369.201954 -101.724968)
		(end 357.380032 -101.724968)
		(width 0.15494)
		(layer "In15.Cu")
		(net "PWRGD_P12V_SSD15_R")
	)
	(segment
		(start 239.510062 -53.397404)
		(end 239.510062 -54.598062)
		(width 0.13208)
		(layer "F.Cu")
		(net "P3V3_SSD8_OCP")
	)
	(segment
		(start 239.47247 -55.40502)
		(end 239.313466 -55.246016)
		(width 0.13208)
		(layer "F.Cu")
		(net "P3V3_SSD8_OCP")
	)
	(segment
		(start 239.313466 -55.246016)
		(end 239.313466 -54.794658)
		(width 0.13208)
		(layer "F.Cu")
		(net "P3V3_SSD8_OCP")
	)
	(segment
		(start 239.510062 -54.598062)
		(end 239.313466 -54.794658)
		(width 0.13208)
		(layer "F.Cu")
		(net "P3V3_SSD8_OCP")
	)
	(via
		(at 239.313466 -54.794658)
		(size 0.508)
		(drill 0.254)
		(layers "F.Cu" "B.Cu")
		(net "P3V3_SSD8_OCP")
	)
	(segment
		(start 231.304084 -95.525336)
		(end 231.565704 -95.263716)
		(width 0.13208)
		(layer "F.Cu")
		(net "PEX_USB_HUB_OVCUR3")
	)
	(segment
		(start 231.565704 -95.263716)
		(end 232.877106 -95.263716)
		(width 0.13208)
		(layer "F.Cu")
		(net "PEX_USB_HUB_OVCUR3")
	)
	(segment
		(start 233.021124 -95.119698)
		(end 233.021124 -94.679008)
		(width 0.13208)
		(layer "F.Cu")
		(net "PEX_USB_HUB_OVCUR3")
	)
	(segment
		(start 232.877106 -95.263716)
		(end 233.021124 -95.119698)
		(width 0.13208)
		(layer "F.Cu")
		(net "PEX_USB_HUB_OVCUR3")
	)
	(segment
		(start 231.304084 -96.750124)
		(end 231.304084 -95.525336)
		(width 0.13208)
		(layer "F.Cu")
		(net "PEX_USB_HUB_OVCUR3")
	)
	(segment
		(start 231.412288 -96.858328)
		(end 231.304084 -96.750124)
		(width 0.13208)
		(layer "F.Cu")
		(net "PEX_USB_HUB_OVCUR3")
	)
	(via
		(at 231.304084 -95.525336)
		(size 0.508)
		(drill 0.254)
		(layers "F.Cu" "B.Cu")
		(net "PEX_USB_HUB_OVCUR3")
	)
	(segment
		(start 208.150206 -305.063906)
		(end 208.150206 -305.674522)
		(width 0.13208)
		(layer "F.Cu")
		(net "PEX1_SPARE6")
	)
	(segment
		(start 208.150206 -305.008026)
		(end 208.150206 -305.063906)
		(width 0.13208)
		(layer "F.Cu")
		(net "PEX1_SPARE6")
	)
	(segment
		(start 208.149698 -304.436526)
		(end 208.149698 -305.007518)
		(width 0.13208)
		(layer "F.Cu")
		(net "PEX1_SPARE6")
	)
	(segment
		(start 208.149698 -305.007518)
		(end 208.150206 -305.008026)
		(width 0.13208)
		(layer "F.Cu")
		(net "PEX1_SPARE6")
	)
	(segment
		(start 179.074826 -308.724554)
		(end 178.599846 -309.199788)
		(width 0.13208)
		(layer "F.Cu")
		(net "PEX1_SPARE6")
	)
	(via
		(at 200.177908 -312.999882)
		(size 0.6604)
		(drill 0.3302)
		(layers "F.Cu" "B.Cu")
		(net "PEX1_SPARE6")
	)
	(via
		(at 208.150206 -305.063906)
		(size 0.508)
		(drill 0.254)
		(layers "F.Cu" "B.Cu")
		(net "PEX1_SPARE6")
	)
	(via
		(at 179.074826 -308.724554)
		(size 0.4064)
		(drill 0.2032)
		(layers "F.Cu" "B.Cu")
		(net "PEX1_SPARE6")
	)
	(segment
		(start 180.960268 -309.760366)
		(end 180.960268 -312.28157)
		(width 0.13208)
		(layer "B.Cu")
		(net "PEX1_SPARE6")
	)
	(segment
		(start 207.582262 -305.63185)
		(end 207.54594 -305.63185)
		(width 0.13208)
		(layer "B.Cu")
		(net "PEX1_SPARE6")
	)
	(segment
		(start 199.715628 -312.537602)
		(end 200.177908 -312.999882)
		(width 0.13208)
		(layer "B.Cu")
		(net "PEX1_SPARE6")
	)
	(segment
		(start 208.150206 -305.063906)
		(end 207.582262 -305.63185)
		(width 0.13208)
		(layer "B.Cu")
		(net "PEX1_SPARE6")
	)
	(segment
		(start 179.537868 -309.187596)
		(end 180.387498 -309.187596)
		(width 0.13208)
		(layer "B.Cu")
		(net "PEX1_SPARE6")
	)
	(segment
		(start 180.960268 -312.28157)
		(end 181.2163 -312.537602)
		(width 0.13208)
		(layer "B.Cu")
		(net "PEX1_SPARE6")
	)
	(segment
		(start 180.387498 -309.187596)
		(end 180.960268 -309.760366)
		(width 0.13208)
		(layer "B.Cu")
		(net "PEX1_SPARE6")
	)
	(segment
		(start 181.2163 -312.537602)
		(end 199.715628 -312.537602)
		(width 0.13208)
		(layer "B.Cu")
		(net "PEX1_SPARE6")
	)
	(segment
		(start 207.54594 -305.63185)
		(end 200.177908 -312.999882)
		(width 0.13208)
		(layer "B.Cu")
		(net "PEX1_SPARE6")
	)
	(segment
		(start 179.074826 -308.724554)
		(end 179.537868 -309.187596)
		(width 0.13208)
		(layer "B.Cu")
		(net "PEX1_SPARE6")
	)
	(segment
		(start 390.660128 -88.855042)
		(end 391.895076 -88.855042)
		(width 0.13208)
		(layer "F.Cu")
		(net "BIC_I2C6_MUX_A2")
	)
	(segment
		(start 393.269216 -89.04605)
		(end 393.446254 -88.869012)
		(width 0.13208)
		(layer "F.Cu")
		(net "BIC_I2C6_MUX_A2")
	)
	(segment
		(start 393.446254 -88.869012)
		(end 395.528038 -88.869012)
		(width 0.13208)
		(layer "F.Cu")
		(net "BIC_I2C6_MUX_A2")
	)
	(segment
		(start 389.241792 -87.436706)
		(end 390.660128 -88.855042)
		(width 0.13208)
		(layer "F.Cu")
		(net "BIC_I2C6_MUX_A2")
	)
	(segment
		(start 395.809216 -89.15019)
		(end 395.809216 -89.500202)
		(width 0.13208)
		(layer "F.Cu")
		(net "BIC_I2C6_MUX_A2")
	)
	(segment
		(start 395.528038 -88.869012)
		(end 395.809216 -89.15019)
		(width 0.13208)
		(layer "F.Cu")
		(net "BIC_I2C6_MUX_A2")
	)
	(segment
		(start 388.24027 -87.436706)
		(end 389.241792 -87.436706)
		(width 0.13208)
		(layer "F.Cu")
		(net "BIC_I2C6_MUX_A2")
	)
	(segment
		(start 391.895076 -88.855042)
		(end 392.540236 -89.500202)
		(width 0.13208)
		(layer "F.Cu")
		(net "BIC_I2C6_MUX_A2")
	)
	(segment
		(start 393.269216 -89.500202)
		(end 393.269216 -89.04605)
		(width 0.13208)
		(layer "F.Cu")
		(net "BIC_I2C6_MUX_A2")
	)
	(segment
		(start 392.540236 -89.500202)
		(end 393.269216 -89.500202)
		(width 0.13208)
		(layer "F.Cu")
		(net "BIC_I2C6_MUX_A2")
	)
	(via
		(at 392.540236 -89.500202)
		(size 0.508)
		(drill 0.254)
		(layers "F.Cu" "B.Cu")
		(net "BIC_I2C6_MUX_A2")
	)
	(via
		(at 178.282346 -414.999932)
		(size 0.6604)
		(drill 0.3302)
		(layers "F.Cu" "B.Cu")
		(net "GPU_RSVD_PARTNER2")
	)
	(segment
		(start 178.282346 -408.962606)
		(end 177.509932 -408.190192)
		(width 0.13208)
		(layer "B.Cu")
		(net "GPU_RSVD_PARTNER2")
	)
	(segment
		(start 178.282346 -414.999932)
		(end 178.282346 -408.962606)
		(width 0.13208)
		(layer "B.Cu")
		(net "GPU_RSVD_PARTNER2")
	)
	(segment
		(start 359.55605 -189.23)
		(end 360.172 -189.23)
		(width 0.13208)
		(layer "F.Cu")
		(net "SSD2_PEX_PWR_EN_R")
	)
	(segment
		(start 360.172 -189.23)
		(end 360.78795 -189.23)
		(width 0.13208)
		(layer "F.Cu")
		(net "SSD2_PEX_PWR_EN_R")
	)
	(segment
		(start 345.29395 -212.786976)
		(end 345.693746 -212.38718)
		(width 0.13208)
		(layer "F.Cu")
		(net "SSD2_PEX_PWR_EN_R")
	)
	(segment
		(start 359.55605 -190.246)
		(end 359.55605 -189.23)
		(width 0.13208)
		(layer "F.Cu")
		(net "SSD2_PEX_PWR_EN_R")
	)
	(via
		(at 345.693746 -212.38718)
		(size 0.4572)
		(drill 0.254)
		(layers "F.Cu" "B.Cu")
		(net "SSD2_PEX_PWR_EN_R")
	)
	(via
		(at 360.172 -189.23)
		(size 0.508)
		(drill 0.254)
		(layers "F.Cu" "B.Cu")
		(net "SSD2_PEX_PWR_EN_R")
	)
	(segment
		(start 354.734622 -203.277978)
		(end 356.9716 -201.041)
		(width 0.15494)
		(layer "In5.Cu")
		(net "SSD2_PEX_PWR_EN_R")
	)
	(segment
		(start 354.734622 -204.336142)
		(end 354.734622 -203.277978)
		(width 0.15494)
		(layer "In5.Cu")
		(net "SSD2_PEX_PWR_EN_R")
	)
	(segment
		(start 356.9716 -201.041)
		(end 357.945944 -201.041)
		(width 0.15494)
		(layer "In5.Cu")
		(net "SSD2_PEX_PWR_EN_R")
	)
	(segment
		(start 346.0496 -210.439)
		(end 351.759266 -204.729334)
		(width 0.15494)
		(layer "In5.Cu")
		(net "SSD2_PEX_PWR_EN_R")
	)
	(segment
		(start 346.0496 -212.031326)
		(end 346.0496 -210.439)
		(width 0.15494)
		(layer "In5.Cu")
		(net "SSD2_PEX_PWR_EN_R")
	)
	(segment
		(start 360.661712 -198.325232)
		(end 360.661712 -189.719712)
		(width 0.15494)
		(layer "In5.Cu")
		(net "SSD2_PEX_PWR_EN_R")
	)
	(segment
		(start 360.661712 -189.719712)
		(end 360.172 -189.23)
		(width 0.15494)
		(layer "In5.Cu")
		(net "SSD2_PEX_PWR_EN_R")
	)
	(segment
		(start 357.945944 -201.041)
		(end 360.661712 -198.325232)
		(width 0.15494)
		(layer "In5.Cu")
		(net "SSD2_PEX_PWR_EN_R")
	)
	(segment
		(start 345.693746 -212.38718)
		(end 346.0496 -212.031326)
		(width 0.15494)
		(layer "In5.Cu")
		(net "SSD2_PEX_PWR_EN_R")
	)
	(segment
		(start 351.759266 -204.729334)
		(end 354.34143 -204.729334)
		(width 0.15494)
		(layer "In5.Cu")
		(net "SSD2_PEX_PWR_EN_R")
	)
	(segment
		(start 354.34143 -204.729334)
		(end 354.734622 -204.336142)
		(width 0.15494)
		(layer "In5.Cu")
		(net "SSD2_PEX_PWR_EN_R")
	)
	(segment
		(start 230.648256 -92.766388)
		(end 229.87 -91.988132)
		(width 0.13208)
		(layer "F.Cu")
		(net "PEX_USB_HUB_OVCUR2")
	)
	(segment
		(start 231.60863 -92.766388)
		(end 230.648256 -92.766388)
		(width 0.13208)
		(layer "F.Cu")
		(net "PEX_USB_HUB_OVCUR2")
	)
	(segment
		(start 229.87 -91.988132)
		(end 229.87 -91.702636)
		(width 0.13208)
		(layer "F.Cu")
		(net "PEX_USB_HUB_OVCUR2")
	)
	(segment
		(start 229.87 -91.702636)
		(end 229.19309 -91.025726)
		(width 0.13208)
		(layer "F.Cu")
		(net "PEX_USB_HUB_OVCUR2")
	)
	(via
		(at 229.87 -91.988132)
		(size 0.508)
		(drill 0.254)
		(layers "F.Cu" "B.Cu")
		(net "PEX_USB_HUB_OVCUR2")
	)
	(segment
		(start 32.470344 -251.956824)
		(end 32.470344 -251.158502)
		(width 0.13208)
		(layer "F.Cu")
		(net "PEX0_MODE_SEL8")
	)
	(segment
		(start 63.449962 -282.599892)
		(end 63.924942 -283.074872)
		(width 0.1651)
		(layer "F.Cu")
		(net "PEX0_MODE_SEL8")
	)
	(segment
		(start 32.470344 -251.158502)
		(end 32.470344 -250.470924)
		(width 0.13208)
		(layer "F.Cu")
		(net "PEX0_MODE_SEL8")
	)
	(via
		(at 63.924942 -283.074872)
		(size 0.4064)
		(drill 0.2032)
		(layers "F.Cu" "B.Cu")
		(net "PEX0_MODE_SEL8")
	)
	(via
		(at 32.470344 -251.158502)
		(size 0.508)
		(drill 0.254)
		(layers "F.Cu" "B.Cu")
		(net "PEX0_MODE_SEL8")
	)
	(segment
		(start 64.835024 -272.034762)
		(end 61.411104 -268.610842)
		(width 0.13208)
		(layer "B.Cu")
		(net "PEX0_MODE_SEL8")
	)
	(segment
		(start 33.1216 -255.6002)
		(end 31.996888 -254.475488)
		(width 0.13208)
		(layer "B.Cu")
		(net "PEX0_MODE_SEL8")
	)
	(segment
		(start 31.996888 -251.631958)
		(end 32.470344 -251.158502)
		(width 0.13208)
		(layer "B.Cu")
		(net "PEX0_MODE_SEL8")
	)
	(segment
		(start 61.321696 -268.610842)
		(end 60.141104 -267.43025)
		(width 0.13208)
		(layer "B.Cu")
		(net "PEX0_MODE_SEL8")
	)
	(segment
		(start 60.141104 -267.340842)
		(end 49.314862 -256.5146)
		(width 0.13208)
		(layer "B.Cu")
		(net "PEX0_MODE_SEL8")
	)
	(segment
		(start 60.141104 -267.43025)
		(end 60.141104 -267.340842)
		(width 0.13208)
		(layer "B.Cu")
		(net "PEX0_MODE_SEL8")
	)
	(segment
		(start 61.411104 -268.610842)
		(end 61.321696 -268.610842)
		(width 0.13208)
		(layer "B.Cu")
		(net "PEX0_MODE_SEL8")
	)
	(segment
		(start 49.314862 -256.5146)
		(end 35.611054 -256.5146)
		(width 0.13208)
		(layer "B.Cu")
		(net "PEX0_MODE_SEL8")
	)
	(segment
		(start 64.835024 -282.16479)
		(end 64.835024 -272.034762)
		(width 0.13208)
		(layer "B.Cu")
		(net "PEX0_MODE_SEL8")
	)
	(segment
		(start 34.696654 -255.6002)
		(end 33.1216 -255.6002)
		(width 0.13208)
		(layer "B.Cu")
		(net "PEX0_MODE_SEL8")
	)
	(segment
		(start 31.996888 -254.475488)
		(end 31.996888 -251.631958)
		(width 0.13208)
		(layer "B.Cu")
		(net "PEX0_MODE_SEL8")
	)
	(segment
		(start 35.611054 -256.5146)
		(end 34.696654 -255.6002)
		(width 0.13208)
		(layer "B.Cu")
		(net "PEX0_MODE_SEL8")
	)
	(segment
		(start 63.924942 -283.074872)
		(end 64.835024 -282.16479)
		(width 0.13208)
		(layer "B.Cu")
		(net "PEX0_MODE_SEL8")
	)
	(segment
		(start 170.049952 -309.199788)
		(end 170.524932 -308.724808)
		(width 0.127)
		(layer "F.Cu")
		(net "TP_PEX1_TDO")
	)
	(via
		(at 170.049952 -309.199788)
		(size 0.6604)
		(drill 0.3302)
		(layers "F.Cu" "B.Cu")
		(net "TP_PEX1_TDO")
	)
	(via
		(at 170.524932 -308.724808)
		(size 0.4064)
		(drill 0.2032)
		(layers "F.Cu" "B.Cu")
		(net "TP_PEX1_TDO")
	)
	(segment
		(start 170.049952 -309.199788)
		(end 170.524932 -308.724808)
		(width 0.13208)
		(layer "B.Cu")
		(net "TP_PEX1_TDO")
	)
	(segment
		(start 369.89512 -259.94487)
		(end 369.671854 -259.721604)
		(width 0.13208)
		(layer "F.Cu")
		(net "PEX3_SYS_ERR_N")
	)
	(segment
		(start 369.671854 -259.721604)
		(end 369.671854 -259.346192)
		(width 0.13208)
		(layer "F.Cu")
		(net "PEX3_SYS_ERR_N")
	)
	(segment
		(start 412.699962 -283.549852)
		(end 413.174942 -284.024832)
		(width 0.13208)
		(layer "F.Cu")
		(net "PEX3_SYS_ERR_N")
	)
	(via
		(at 369.89512 -259.94487)
		(size 0.508)
		(drill 0.254)
		(layers "F.Cu" "B.Cu")
		(net "PEX3_SYS_ERR_N")
	)
	(via
		(at 413.174942 -284.024832)
		(size 0.4064)
		(drill 0.2032)
		(layers "F.Cu" "B.Cu")
		(net "PEX3_SYS_ERR_N")
	)
	(segment
		(start 379.116082 -260.947662)
		(end 380.12878 -261.96036)
		(width 0.13208)
		(layer "B.Cu")
		(net "PEX3_SYS_ERR_N")
	)
	(segment
		(start 408.272742 -285.369)
		(end 410.566362 -285.369)
		(width 0.13208)
		(layer "B.Cu")
		(net "PEX3_SYS_ERR_N")
	)
	(segment
		(start 396.406624 -261.96036)
		(end 405.575262 -271.128998)
		(width 0.13208)
		(layer "B.Cu")
		(net "PEX3_SYS_ERR_N")
	)
	(segment
		(start 405.100028 -282.477972)
		(end 405.100028 -284.092904)
		(width 0.13208)
		(layer "B.Cu")
		(net "PEX3_SYS_ERR_N")
	)
	(segment
		(start 410.83992 -285.095442)
		(end 410.83992 -283.827474)
		(width 0.13208)
		(layer "B.Cu")
		(net "PEX3_SYS_ERR_N")
	)
	(segment
		(start 370.690902 -259.94487)
		(end 371.693694 -260.947662)
		(width 0.13208)
		(layer "B.Cu")
		(net "PEX3_SYS_ERR_N")
	)
	(segment
		(start 408.027378 -284.913578)
		(end 408.027378 -285.123636)
		(width 0.13208)
		(layer "B.Cu")
		(net "PEX3_SYS_ERR_N")
	)
	(segment
		(start 412.7627 -283.61259)
		(end 413.174942 -284.024832)
		(width 0.13208)
		(layer "B.Cu")
		(net "PEX3_SYS_ERR_N")
	)
	(segment
		(start 410.83992 -283.827474)
		(end 411.054804 -283.61259)
		(width 0.13208)
		(layer "B.Cu")
		(net "PEX3_SYS_ERR_N")
	)
	(segment
		(start 408.027378 -285.123636)
		(end 408.272742 -285.369)
		(width 0.13208)
		(layer "B.Cu")
		(net "PEX3_SYS_ERR_N")
	)
	(segment
		(start 411.054804 -283.61259)
		(end 412.7627 -283.61259)
		(width 0.13208)
		(layer "B.Cu")
		(net "PEX3_SYS_ERR_N")
	)
	(segment
		(start 410.566362 -285.369)
		(end 410.83992 -285.095442)
		(width 0.13208)
		(layer "B.Cu")
		(net "PEX3_SYS_ERR_N")
	)
	(segment
		(start 380.12878 -261.96036)
		(end 396.406624 -261.96036)
		(width 0.13208)
		(layer "B.Cu")
		(net "PEX3_SYS_ERR_N")
	)
	(segment
		(start 405.575262 -282.002738)
		(end 405.100028 -282.477972)
		(width 0.13208)
		(layer "B.Cu")
		(net "PEX3_SYS_ERR_N")
	)
	(segment
		(start 369.89512 -259.94487)
		(end 370.690902 -259.94487)
		(width 0.13208)
		(layer "B.Cu")
		(net "PEX3_SYS_ERR_N")
	)
	(segment
		(start 371.693694 -260.947662)
		(end 379.116082 -260.947662)
		(width 0.13208)
		(layer "B.Cu")
		(net "PEX3_SYS_ERR_N")
	)
	(segment
		(start 405.537924 -284.5308)
		(end 407.6446 -284.5308)
		(width 0.13208)
		(layer "B.Cu")
		(net "PEX3_SYS_ERR_N")
	)
	(segment
		(start 405.575262 -271.128998)
		(end 405.575262 -282.002738)
		(width 0.13208)
		(layer "B.Cu")
		(net "PEX3_SYS_ERR_N")
	)
	(segment
		(start 407.6446 -284.5308)
		(end 408.027378 -284.913578)
		(width 0.13208)
		(layer "B.Cu")
		(net "PEX3_SYS_ERR_N")
	)
	(segment
		(start 405.100028 -284.092904)
		(end 405.537924 -284.5308)
		(width 0.13208)
		(layer "B.Cu")
		(net "PEX3_SYS_ERR_N")
	)
	(segment
		(start 379.252734 -89.9668)
		(end 380.90856 -89.9668)
		(width 0.13208)
		(layer "F.Cu")
		(net "BIC_I2C6_MUX_A1")
	)
	(segment
		(start 381.349758 -89.525602)
		(end 381.349758 -89.323418)
		(width 0.13208)
		(layer "F.Cu")
		(net "BIC_I2C6_MUX_A1")
	)
	(segment
		(start 376.712734 -89.9668)
		(end 377.213114 -90.46718)
		(width 0.13208)
		(layer "F.Cu")
		(net "BIC_I2C6_MUX_A1")
	)
	(segment
		(start 381.936498 -88.736678)
		(end 382.640078 -88.736678)
		(width 0.13208)
		(layer "F.Cu")
		(net "BIC_I2C6_MUX_A1")
	)
	(segment
		(start 379.159008 -90.46718)
		(end 379.252734 -90.373454)
		(width 0.13208)
		(layer "F.Cu")
		(net "BIC_I2C6_MUX_A1")
	)
	(segment
		(start 379.252734 -90.373454)
		(end 379.252734 -89.9668)
		(width 0.13208)
		(layer "F.Cu")
		(net "BIC_I2C6_MUX_A1")
	)
	(segment
		(start 381.349758 -89.323418)
		(end 381.936498 -88.736678)
		(width 0.13208)
		(layer "F.Cu")
		(net "BIC_I2C6_MUX_A1")
	)
	(segment
		(start 380.959106 -89.916254)
		(end 381.349758 -89.525602)
		(width 0.13208)
		(layer "F.Cu")
		(net "BIC_I2C6_MUX_A1")
	)
	(segment
		(start 380.90856 -89.9668)
		(end 380.959106 -89.916254)
		(width 0.13208)
		(layer "F.Cu")
		(net "BIC_I2C6_MUX_A1")
	)
	(segment
		(start 377.213114 -90.46718)
		(end 379.159008 -90.46718)
		(width 0.13208)
		(layer "F.Cu")
		(net "BIC_I2C6_MUX_A1")
	)
	(via
		(at 380.959106 -89.916254)
		(size 0.508)
		(drill 0.254)
		(layers "F.Cu" "B.Cu")
		(net "BIC_I2C6_MUX_A1")
	)
	(segment
		(start 86.943692 -302.06569)
		(end 87.152734 -301.856648)
		(width 0.13208)
		(layer "F.Cu")
		(net "SMB_PEX0_SCL")
	)
	(segment
		(start 212.65769 -233.430572)
		(end 212.574886 -233.347768)
		(width 0.13208)
		(layer "F.Cu")
		(net "SMB_PEX0_SCL")
	)
	(segment
		(start 86.943692 -302.473614)
		(end 86.943692 -302.06569)
		(width 0.13208)
		(layer "F.Cu")
		(net "SMB_PEX0_SCL")
	)
	(segment
		(start 212.574886 -233.347768)
		(end 212.574886 -232.820972)
		(width 0.13208)
		(layer "F.Cu")
		(net "SMB_PEX0_SCL")
	)
	(via
		(at 93.716856 -238.185452)
		(size 0.508)
		(drill 0.254)
		(layers "F.Cu" "B.Cu")
		(net "SMB_PEX0_SCL")
	)
	(via
		(at 87.152734 -301.856648)
		(size 0.508)
		(drill 0.254)
		(layers "F.Cu" "B.Cu")
		(net "SMB_PEX0_SCL")
	)
	(via
		(at 212.574886 -232.820972)
		(size 0.508)
		(drill 0.254)
		(layers "F.Cu" "B.Cu")
		(net "SMB_PEX0_SCL")
	)
	(via
		(at 94.920562 -198.76897)
		(size 0.508)
		(drill 0.254)
		(layers "F.Cu" "B.Cu")
		(net "SMB_PEX0_SCL")
	)
	(via
		(at 214.035894 -195.458334)
		(size 0.508)
		(drill 0.254)
		(layers "F.Cu" "B.Cu")
		(net "SMB_PEX0_SCL")
	)
	(segment
		(start 211.393532 -231.044496)
		(end 211.393532 -231.704642)
		(width 0.13208)
		(layer "B.Cu")
		(net "SMB_PEX0_SCL")
	)
	(segment
		(start 87.152734 -301.042324)
		(end 87.152734 -301.856648)
		(width 0.13208)
		(layer "B.Cu")
		(net "SMB_PEX0_SCL")
	)
	(segment
		(start 91.31427 -239.804448)
		(end 91.31427 -247.447816)
		(width 0.13208)
		(layer "B.Cu")
		(net "SMB_PEX0_SCL")
	)
	(segment
		(start 91.225624 -300.410372)
		(end 87.784686 -300.410372)
		(width 0.13208)
		(layer "B.Cu")
		(net "SMB_PEX0_SCL")
	)
	(segment
		(start 93.472 -289.83178)
		(end 92.380816 -290.922964)
		(width 0.13208)
		(layer "B.Cu")
		(net "SMB_PEX0_SCL")
	)
	(segment
		(start 93.472 -282.219654)
		(end 93.472 -289.83178)
		(width 0.13208)
		(layer "B.Cu")
		(net "SMB_PEX0_SCL")
	)
	(segment
		(start 91.900756 -294.818308)
		(end 91.900756 -299.73524)
		(width 0.13208)
		(layer "B.Cu")
		(net "SMB_PEX0_SCL")
	)
	(segment
		(start 92.380816 -290.922964)
		(end 92.380816 -294.338248)
		(width 0.13208)
		(layer "B.Cu")
		(net "SMB_PEX0_SCL")
	)
	(segment
		(start 92.380816 -294.338248)
		(end 91.900756 -294.818308)
		(width 0.13208)
		(layer "B.Cu")
		(net "SMB_PEX0_SCL")
	)
	(segment
		(start 87.784686 -300.410372)
		(end 87.152734 -301.042324)
		(width 0.13208)
		(layer "B.Cu")
		(net "SMB_PEX0_SCL")
	)
	(segment
		(start 99.5172 -254.3302)
		(end 99.5172 -263.651746)
		(width 0.13208)
		(layer "B.Cu")
		(net "SMB_PEX0_SCL")
	)
	(segment
		(start 92.933266 -238.185452)
		(end 91.31427 -239.804448)
		(width 0.13208)
		(layer "B.Cu")
		(net "SMB_PEX0_SCL")
	)
	(segment
		(start 91.31427 -247.447816)
		(end 96.088454 -252.222)
		(width 0.13208)
		(layer "B.Cu")
		(net "SMB_PEX0_SCL")
	)
	(segment
		(start 212.509862 -232.820972)
		(end 212.574886 -232.820972)
		(width 0.13208)
		(layer "B.Cu")
		(net "SMB_PEX0_SCL")
	)
	(segment
		(start 97.409 -252.222)
		(end 99.5172 -254.3302)
		(width 0.13208)
		(layer "B.Cu")
		(net "SMB_PEX0_SCL")
	)
	(segment
		(start 96.088454 -252.222)
		(end 97.409 -252.222)
		(width 0.13208)
		(layer "B.Cu")
		(net "SMB_PEX0_SCL")
	)
	(segment
		(start 98.760026 -276.931628)
		(end 93.472 -282.219654)
		(width 0.13208)
		(layer "B.Cu")
		(net "SMB_PEX0_SCL")
	)
	(segment
		(start 211.393532 -231.704642)
		(end 212.509862 -232.820972)
		(width 0.13208)
		(layer "B.Cu")
		(net "SMB_PEX0_SCL")
	)
	(segment
		(start 91.900756 -299.73524)
		(end 91.225624 -300.410372)
		(width 0.13208)
		(layer "B.Cu")
		(net "SMB_PEX0_SCL")
	)
	(segment
		(start 99.5172 -263.651746)
		(end 98.760026 -264.40892)
		(width 0.13208)
		(layer "B.Cu")
		(net "SMB_PEX0_SCL")
	)
	(segment
		(start 93.716856 -238.185452)
		(end 92.933266 -238.185452)
		(width 0.13208)
		(layer "B.Cu")
		(net "SMB_PEX0_SCL")
	)
	(segment
		(start 98.760026 -264.40892)
		(end 98.760026 -276.931628)
		(width 0.13208)
		(layer "B.Cu")
		(net "SMB_PEX0_SCL")
	)
	(segment
		(start 210.950048 -223.276922)
		(end 212.338666 -221.888304)
		(width 0.15494)
		(layer "In5.Cu")
		(net "SMB_PEX0_SCL")
	)
	(segment
		(start 212.885782 -221.888304)
		(end 213.249764 -221.524322)
		(width 0.15494)
		(layer "In5.Cu")
		(net "SMB_PEX0_SCL")
	)
	(segment
		(start 212.598 -208.407254)
		(end 212.598 -196.407024)
		(width 0.15494)
		(layer "In5.Cu")
		(net "SMB_PEX0_SCL")
	)
	(segment
		(start 93.716856 -238.185452)
		(end 93.716856 -237.473744)
		(width 0.15494)
		(layer "In5.Cu")
		(net "SMB_PEX0_SCL")
	)
	(segment
		(start 212.598 -219.280232)
		(end 212.598 -218.22664)
		(width 0.15494)
		(layer "In5.Cu")
		(net "SMB_PEX0_SCL")
	)
	(segment
		(start 94.1578 -237.0328)
		(end 94.1578 -211.6455)
		(width 0.15494)
		(layer "In5.Cu")
		(net "SMB_PEX0_SCL")
	)
	(segment
		(start 212.338666 -221.888304)
		(end 212.885782 -221.888304)
		(width 0.15494)
		(layer "In5.Cu")
		(net "SMB_PEX0_SCL")
	)
	(segment
		(start 212.598 -196.407024)
		(end 213.54669 -195.458334)
		(width 0.15494)
		(layer "In5.Cu")
		(net "SMB_PEX0_SCL")
	)
	(segment
		(start 212.374226 -232.820972)
		(end 212.0646 -232.511346)
		(width 0.15494)
		(layer "In5.Cu")
		(net "SMB_PEX0_SCL")
	)
	(segment
		(start 213.9188 -209.728054)
		(end 212.598 -208.407254)
		(width 0.15494)
		(layer "In5.Cu")
		(net "SMB_PEX0_SCL")
	)
	(segment
		(start 212.0646 -232.511346)
		(end 212.0646 -228.558598)
		(width 0.15494)
		(layer "In5.Cu")
		(net "SMB_PEX0_SCL")
	)
	(segment
		(start 213.54669 -195.458334)
		(end 214.035894 -195.458334)
		(width 0.15494)
		(layer "In5.Cu")
		(net "SMB_PEX0_SCL")
	)
	(segment
		(start 94.1578 -211.6455)
		(end 94.920562 -210.882738)
		(width 0.15494)
		(layer "In5.Cu")
		(net "SMB_PEX0_SCL")
	)
	(segment
		(start 213.249764 -221.524322)
		(end 213.249764 -219.931996)
		(width 0.15494)
		(layer "In5.Cu")
		(net "SMB_PEX0_SCL")
	)
	(segment
		(start 213.9188 -216.90584)
		(end 213.9188 -209.728054)
		(width 0.15494)
		(layer "In5.Cu")
		(net "SMB_PEX0_SCL")
	)
	(segment
		(start 212.574886 -232.820972)
		(end 212.374226 -232.820972)
		(width 0.15494)
		(layer "In5.Cu")
		(net "SMB_PEX0_SCL")
	)
	(segment
		(start 213.249764 -219.931996)
		(end 212.598 -219.280232)
		(width 0.15494)
		(layer "In5.Cu")
		(net "SMB_PEX0_SCL")
	)
	(segment
		(start 212.598 -218.22664)
		(end 213.9188 -216.90584)
		(width 0.15494)
		(layer "In5.Cu")
		(net "SMB_PEX0_SCL")
	)
	(segment
		(start 210.950048 -227.444046)
		(end 210.950048 -223.276922)
		(width 0.15494)
		(layer "In5.Cu")
		(net "SMB_PEX0_SCL")
	)
	(segment
		(start 93.716856 -237.473744)
		(end 94.1578 -237.0328)
		(width 0.15494)
		(layer "In5.Cu")
		(net "SMB_PEX0_SCL")
	)
	(segment
		(start 94.920562 -210.882738)
		(end 94.920562 -198.76897)
		(width 0.15494)
		(layer "In5.Cu")
		(net "SMB_PEX0_SCL")
	)
	(segment
		(start 212.0646 -228.558598)
		(end 210.950048 -227.444046)
		(width 0.15494)
		(layer "In5.Cu")
		(net "SMB_PEX0_SCL")
	)
	(segment
		(start 119.640096 -201.910696)
		(end 114.849402 -201.910696)
		(width 0.15494)
		(layer "In15.Cu")
		(net "SMB_PEX0_SCL")
	)
	(segment
		(start 139.5984 -208.5848)
		(end 136.1186 -208.5848)
		(width 0.15494)
		(layer "In15.Cu")
		(net "SMB_PEX0_SCL")
	)
	(segment
		(start 93.9292 -196.7484)
		(end 93.9292 -198.5518)
		(width 0.15494)
		(layer "In15.Cu")
		(net "SMB_PEX0_SCL")
	)
	(segment
		(start 136.1186 -208.5848)
		(end 135.4328 -207.899)
		(width 0.15494)
		(layer "In15.Cu")
		(net "SMB_PEX0_SCL")
	)
	(segment
		(start 144.0688 -208.788)
		(end 143.0528 -209.804)
		(width 0.15494)
		(layer "In15.Cu")
		(net "SMB_PEX0_SCL")
	)
	(segment
		(start 143.0528 -209.804)
		(end 140.8176 -209.804)
		(width 0.15494)
		(layer "In15.Cu")
		(net "SMB_PEX0_SCL")
	)
	(segment
		(start 150.495 -207.772)
		(end 148.336 -209.931)
		(width 0.15494)
		(layer "In15.Cu")
		(net "SMB_PEX0_SCL")
	)
	(segment
		(start 94.615 -196.0626)
		(end 93.9292 -196.7484)
		(width 0.15494)
		(layer "In15.Cu")
		(net "SMB_PEX0_SCL")
	)
	(segment
		(start 135.4328 -207.899)
		(end 134.5184 -207.899)
		(width 0.15494)
		(layer "In15.Cu")
		(net "SMB_PEX0_SCL")
	)
	(segment
		(start 212.261196 -199.366124)
		(end 209.673698 -199.366124)
		(width 0.15494)
		(layer "In15.Cu")
		(net "SMB_PEX0_SCL")
	)
	(segment
		(start 203.868274 -199.73798)
		(end 191.72682 -211.879434)
		(width 0.15494)
		(layer "In15.Cu")
		(net "SMB_PEX0_SCL")
	)
	(segment
		(start 98.933 -194.8688)
		(end 97.7392 -196.0626)
		(width 0.15494)
		(layer "In15.Cu")
		(net "SMB_PEX0_SCL")
	)
	(segment
		(start 209.301842 -199.73798)
		(end 203.868274 -199.73798)
		(width 0.15494)
		(layer "In15.Cu")
		(net "SMB_PEX0_SCL")
	)
	(segment
		(start 214.035894 -195.458334)
		(end 214.035894 -195.928742)
		(width 0.15494)
		(layer "In15.Cu")
		(net "SMB_PEX0_SCL")
	)
	(segment
		(start 94.14637 -198.76897)
		(end 94.920562 -198.76897)
		(width 0.15494)
		(layer "In15.Cu")
		(net "SMB_PEX0_SCL")
	)
	(segment
		(start 114.849402 -201.910696)
		(end 107.807506 -194.8688)
		(width 0.15494)
		(layer "In15.Cu")
		(net "SMB_PEX0_SCL")
	)
	(segment
		(start 214.395812 -197.231508)
		(end 212.261196 -199.366124)
		(width 0.15494)
		(layer "In15.Cu")
		(net "SMB_PEX0_SCL")
	)
	(segment
		(start 134.5184 -207.899)
		(end 132.20065 -205.58125)
		(width 0.15494)
		(layer "In15.Cu")
		(net "SMB_PEX0_SCL")
	)
	(segment
		(start 185.486548 -211.879434)
		(end 181.379114 -207.772)
		(width 0.15494)
		(layer "In15.Cu")
		(net "SMB_PEX0_SCL")
	)
	(segment
		(start 145.6436 -208.788)
		(end 144.0688 -208.788)
		(width 0.15494)
		(layer "In15.Cu")
		(net "SMB_PEX0_SCL")
	)
	(segment
		(start 209.673698 -199.366124)
		(end 209.301842 -199.73798)
		(width 0.15494)
		(layer "In15.Cu")
		(net "SMB_PEX0_SCL")
	)
	(segment
		(start 123.31065 -205.58125)
		(end 119.640096 -201.910696)
		(width 0.15494)
		(layer "In15.Cu")
		(net "SMB_PEX0_SCL")
	)
	(segment
		(start 214.035894 -195.928742)
		(end 214.395812 -196.28866)
		(width 0.15494)
		(layer "In15.Cu")
		(net "SMB_PEX0_SCL")
	)
	(segment
		(start 148.336 -209.931)
		(end 146.7866 -209.931)
		(width 0.15494)
		(layer "In15.Cu")
		(net "SMB_PEX0_SCL")
	)
	(segment
		(start 146.7866 -209.931)
		(end 145.6436 -208.788)
		(width 0.15494)
		(layer "In15.Cu")
		(net "SMB_PEX0_SCL")
	)
	(segment
		(start 191.72682 -211.879434)
		(end 185.486548 -211.879434)
		(width 0.15494)
		(layer "In15.Cu")
		(net "SMB_PEX0_SCL")
	)
	(segment
		(start 107.807506 -194.8688)
		(end 98.933 -194.8688)
		(width 0.15494)
		(layer "In15.Cu")
		(net "SMB_PEX0_SCL")
	)
	(segment
		(start 214.395812 -196.28866)
		(end 214.395812 -197.231508)
		(width 0.15494)
		(layer "In15.Cu")
		(net "SMB_PEX0_SCL")
	)
	(segment
		(start 181.379114 -207.772)
		(end 150.495 -207.772)
		(width 0.15494)
		(layer "In15.Cu")
		(net "SMB_PEX0_SCL")
	)
	(segment
		(start 140.8176 -209.804)
		(end 139.5984 -208.5848)
		(width 0.15494)
		(layer "In15.Cu")
		(net "SMB_PEX0_SCL")
	)
	(segment
		(start 97.7392 -196.0626)
		(end 94.615 -196.0626)
		(width 0.15494)
		(layer "In15.Cu")
		(net "SMB_PEX0_SCL")
	)
	(segment
		(start 93.9292 -198.5518)
		(end 94.14637 -198.76897)
		(width 0.15494)
		(layer "In15.Cu")
		(net "SMB_PEX0_SCL")
	)
	(segment
		(start 132.20065 -205.58125)
		(end 123.31065 -205.58125)
		(width 0.15494)
		(layer "In15.Cu")
		(net "SMB_PEX0_SCL")
	)
	(segment
		(start 343.69375 -213.587076)
		(end 344.093546 -213.18728)
		(width 0.13208)
		(layer "F.Cu")
		(net "PRSNT_SSD0_FPGA_N")
	)
	(via
		(at 344.17 -210.693)
		(size 0.6604)
		(drill 0.3302)
		(layers "F.Cu" "B.Cu")
		(net "PRSNT_SSD0_FPGA_N")
	)
	(via
		(at 344.093546 -213.18728)
		(size 0.4572)
		(drill 0.254)
		(layers "F.Cu" "B.Cu")
		(net "PRSNT_SSD0_FPGA_N")
	)
	(segment
		(start 343.696798 -212.790532)
		(end 344.093546 -213.18728)
		(width 0.0889)
		(layer "B.Cu")
		(net "PRSNT_SSD0_FPGA_N")
	)
	(segment
		(start 343.696798 -211.9376)
		(end 343.696798 -212.790532)
		(width 0.0889)
		(layer "B.Cu")
		(net "PRSNT_SSD0_FPGA_N")
	)
	(segment
		(start 344.17 -209.962496)
		(end 344.297 -209.835496)
		(width 0.13208)
		(layer "B.Cu")
		(net "PRSNT_SSD0_FPGA_N")
	)
	(segment
		(start 344.297 -209.835496)
		(end 344.297 -208.17205)
		(width 0.13208)
		(layer "B.Cu")
		(net "PRSNT_SSD0_FPGA_N")
	)
	(segment
		(start 343.696798 -211.166202)
		(end 343.696798 -211.9376)
		(width 0.13208)
		(layer "B.Cu")
		(net "PRSNT_SSD0_FPGA_N")
	)
	(segment
		(start 344.17 -210.693)
		(end 343.696798 -211.166202)
		(width 0.13208)
		(layer "B.Cu")
		(net "PRSNT_SSD0_FPGA_N")
	)
	(segment
		(start 344.17 -210.693)
		(end 344.17 -209.962496)
		(width 0.13208)
		(layer "B.Cu")
		(net "PRSNT_SSD0_FPGA_N")
	)
	(segment
		(start 356.084886 -59.177936)
		(end 356.479094 -59.177936)
		(width 0.13208)
		(layer "F.Cu")
		(net "PWRGD_P3V3_SSD12")
	)
	(segment
		(start 356.32517 -57.841896)
		(end 356.32517 -57.867296)
		(width 0.13208)
		(layer "F.Cu")
		(net "PWRGD_P3V3_SSD12")
	)
	(segment
		(start 355.941122 -57.457848)
		(end 356.32517 -57.841896)
		(width 0.13208)
		(layer "F.Cu")
		(net "PWRGD_P3V3_SSD12")
	)
	(segment
		(start 356.111048 -61.386974)
		(end 355.948234 -61.22416)
		(width 0.13208)
		(layer "F.Cu")
		(net "PWRGD_P3V3_SSD12")
	)
	(segment
		(start 355.941122 -57.16397)
		(end 355.941122 -57.457848)
		(width 0.13208)
		(layer "F.Cu")
		(net "PWRGD_P3V3_SSD12")
	)
	(segment
		(start 356.479094 -58.71972)
		(end 356.479094 -59.177936)
		(width 0.13208)
		(layer "F.Cu")
		(net "PWRGD_P3V3_SSD12")
	)
	(segment
		(start 356.32517 -57.867296)
		(end 356.32517 -58.565796)
		(width 0.13208)
		(layer "F.Cu")
		(net "PWRGD_P3V3_SSD12")
	)
	(segment
		(start 355.948234 -61.22416)
		(end 355.948234 -59.314588)
		(width 0.13208)
		(layer "F.Cu")
		(net "PWRGD_P3V3_SSD12")
	)
	(segment
		(start 356.32517 -58.565796)
		(end 356.479094 -58.71972)
		(width 0.13208)
		(layer "F.Cu")
		(net "PWRGD_P3V3_SSD12")
	)
	(segment
		(start 355.948234 -59.314588)
		(end 356.084886 -59.177936)
		(width 0.13208)
		(layer "F.Cu")
		(net "PWRGD_P3V3_SSD12")
	)
	(via
		(at 356.32517 -57.867296)
		(size 0.508)
		(drill 0.254)
		(layers "F.Cu" "B.Cu")
		(net "PWRGD_P3V3_SSD12")
	)
	(segment
		(start 230.013002 -90.256868)
		(end 229.992682 -90.236548)
		(width 0.13208)
		(layer "F.Cu")
		(net "PEX_USB_HUB_OVCUR1")
	)
	(segment
		(start 231.60863 -92.266516)
		(end 231.035606 -92.266516)
		(width 0.13208)
		(layer "F.Cu")
		(net "PEX_USB_HUB_OVCUR1")
	)
	(segment
		(start 229.76586 -90.009726)
		(end 229.19309 -90.009726)
		(width 0.13208)
		(layer "F.Cu")
		(net "PEX_USB_HUB_OVCUR1")
	)
	(segment
		(start 231.035606 -92.266516)
		(end 230.013002 -91.243912)
		(width 0.13208)
		(layer "F.Cu")
		(net "PEX_USB_HUB_OVCUR1")
	)
	(segment
		(start 230.013002 -91.243912)
		(end 230.013002 -90.256868)
		(width 0.13208)
		(layer "F.Cu")
		(net "PEX_USB_HUB_OVCUR1")
	)
	(segment
		(start 229.992682 -90.236548)
		(end 229.76586 -90.009726)
		(width 0.13208)
		(layer "F.Cu")
		(net "PEX_USB_HUB_OVCUR1")
	)
	(via
		(at 229.992682 -90.236548)
		(size 0.508)
		(drill 0.254)
		(layers "F.Cu" "B.Cu")
		(net "PEX_USB_HUB_OVCUR1")
	)
	(segment
		(start 262.895334 -77.993494)
		(end 262.895334 -79.260954)
		(width 0.13462)
		(layer "F.Cu")
		(net "CLK_100M_CK440Q_2_DB800ZL_DN")
	)
	(segment
		(start 262.426958 -80.156304)
		(end 262.426958 -80.431386)
		(width 0.13462)
		(layer "F.Cu")
		(net "CLK_100M_CK440Q_2_DB800ZL_DN")
	)
	(segment
		(start 262.533384 -80.049878)
		(end 262.426958 -80.156304)
		(width 0.13462)
		(layer "F.Cu")
		(net "CLK_100M_CK440Q_2_DB800ZL_DN")
	)
	(segment
		(start 262.895334 -79.260954)
		(end 262.533384 -79.622904)
		(width 0.13462)
		(layer "F.Cu")
		(net "CLK_100M_CK440Q_2_DB800ZL_DN")
	)
	(segment
		(start 262.533384 -79.622904)
		(end 262.533384 -80.049878)
		(width 0.13462)
		(layer "F.Cu")
		(net "CLK_100M_CK440Q_2_DB800ZL_DN")
	)
	(segment
		(start 262.581644 -77.679804)
		(end 262.895334 -77.993494)
		(width 0.13462)
		(layer "F.Cu")
		(net "CLK_100M_CK440Q_2_DB800ZL_DN")
	)
	(segment
		(start 205.296008 -309.033672)
		(end 205.296008 -308.606444)
		(width 0.13208)
		(layer "F.Cu")
		(net "PEX1_SPARE7")
	)
	(segment
		(start 204.98308 -309.3466)
		(end 205.296008 -309.033672)
		(width 0.13208)
		(layer "F.Cu")
		(net "PEX1_SPARE7")
	)
	(segment
		(start 178.124866 -308.724808)
		(end 177.649886 -308.249828)
		(width 0.13208)
		(layer "F.Cu")
		(net "PEX1_SPARE7")
	)
	(segment
		(start 204.821282 -309.508398)
		(end 204.98308 -309.3466)
		(width 0.13208)
		(layer "F.Cu")
		(net "PEX1_SPARE7")
	)
	(segment
		(start 204.160374 -309.508398)
		(end 204.821282 -309.508398)
		(width 0.13208)
		(layer "F.Cu")
		(net "PEX1_SPARE7")
	)
	(via
		(at 204.98308 -309.3466)
		(size 0.508)
		(drill 0.254)
		(layers "F.Cu" "B.Cu")
		(net "PEX1_SPARE7")
	)
	(via
		(at 203.808076 -310.184038)
		(size 0.6604)
		(drill 0.3302)
		(layers "F.Cu" "B.Cu")
		(net "PEX1_SPARE7")
	)
	(via
		(at 178.124866 -308.724808)
		(size 0.4064)
		(drill 0.2032)
		(layers "F.Cu" "B.Cu")
		(net "PEX1_SPARE7")
	)
	(segment
		(start 204.98308 -309.3466)
		(end 204.645514 -309.3466)
		(width 0.13208)
		(layer "B.Cu")
		(net "PEX1_SPARE7")
	)
	(segment
		(start 180.139848 -313.54522)
		(end 200.446894 -313.54522)
		(width 0.13208)
		(layer "B.Cu")
		(net "PEX1_SPARE7")
	)
	(segment
		(start 178.124866 -308.724808)
		(end 178.42103 -308.724808)
		(width 0.13208)
		(layer "B.Cu")
		(net "PEX1_SPARE7")
	)
	(segment
		(start 180.012848 -309.90032)
		(end 180.012848 -313.41822)
		(width 0.13208)
		(layer "B.Cu")
		(net "PEX1_SPARE7")
	)
	(segment
		(start 180.012848 -313.41822)
		(end 180.139848 -313.54522)
		(width 0.13208)
		(layer "B.Cu")
		(net "PEX1_SPARE7")
	)
	(segment
		(start 179.275994 -309.579772)
		(end 179.6923 -309.579772)
		(width 0.13208)
		(layer "B.Cu")
		(net "PEX1_SPARE7")
	)
	(segment
		(start 179.6923 -309.579772)
		(end 180.012848 -309.90032)
		(width 0.13208)
		(layer "B.Cu")
		(net "PEX1_SPARE7")
	)
	(segment
		(start 200.446894 -313.54522)
		(end 203.808076 -310.184038)
		(width 0.13208)
		(layer "B.Cu")
		(net "PEX1_SPARE7")
	)
	(segment
		(start 204.645514 -309.3466)
		(end 203.808076 -310.184038)
		(width 0.13208)
		(layer "B.Cu")
		(net "PEX1_SPARE7")
	)
	(segment
		(start 178.42103 -308.724808)
		(end 179.275994 -309.579772)
		(width 0.13208)
		(layer "B.Cu")
		(net "PEX1_SPARE7")
	)
	(segment
		(start 400.824954 -307.774848)
		(end 401.299934 -308.249828)
		(width 0.13208)
		(layer "F.Cu")
		(net "TP_PEX3_TRST_L")
	)
	(via
		(at 400.824954 -307.774848)
		(size 0.4064)
		(drill 0.2032)
		(layers "F.Cu" "B.Cu")
		(net "TP_PEX3_TRST_L")
	)
	(via
		(at 403.199854 -308.249828)
		(size 0.6604)
		(drill 0.3302)
		(layers "F.Cu" "B.Cu")
		(net "TP_PEX3_TRST_L")
	)
	(segment
		(start 401.299934 -308.249828)
		(end 403.199854 -308.249828)
		(width 0.13208)
		(layer "B.Cu")
		(net "TP_PEX3_TRST_L")
	)
	(segment
		(start 400.824954 -307.774848)
		(end 401.299934 -308.249828)
		(width 0.13208)
		(layer "B.Cu")
		(net "TP_PEX3_TRST_L")
	)
	(segment
		(start 404.904702 -308.324758)
		(end 405.183848 -308.324758)
		(width 0.13208)
		(layer "B.Cu")
		(net "TP_PEX3_TRST_L")
	)
	(segment
		(start 403.199854 -308.249828)
		(end 404.829772 -308.249828)
		(width 0.13208)
		(layer "B.Cu")
		(net "TP_PEX3_TRST_L")
	)
	(segment
		(start 404.829772 -308.249828)
		(end 404.904702 -308.324758)
		(width 0.13208)
		(layer "B.Cu")
		(net "TP_PEX3_TRST_L")
	)
	(segment
		(start 381.908812 -89.386664)
		(end 381.741426 -89.55405)
		(width 0.13208)
		(layer "F.Cu")
		(net "BIC_I2C6_MUX_A0")
	)
	(segment
		(start 381.741426 -90.227404)
		(end 380.85903 -91.1098)
		(width 0.13208)
		(layer "F.Cu")
		(net "BIC_I2C6_MUX_A0")
	)
	(segment
		(start 379.252734 -91.575128)
		(end 379.252734 -91.1098)
		(width 0.13208)
		(layer "F.Cu")
		(net "BIC_I2C6_MUX_A0")
	)
	(segment
		(start 382.640078 -89.386664)
		(end 381.908812 -89.386664)
		(width 0.13208)
		(layer "F.Cu")
		(net "BIC_I2C6_MUX_A0")
	)
	(segment
		(start 379.076712 -91.75115)
		(end 379.252734 -91.575128)
		(width 0.13208)
		(layer "F.Cu")
		(net "BIC_I2C6_MUX_A0")
	)
	(segment
		(start 381.741426 -89.55405)
		(end 381.741426 -90.227404)
		(width 0.13208)
		(layer "F.Cu")
		(net "BIC_I2C6_MUX_A0")
	)
	(segment
		(start 379.96495 -91.1098)
		(end 379.252734 -91.1098)
		(width 0.13208)
		(layer "F.Cu")
		(net "BIC_I2C6_MUX_A0")
	)
	(segment
		(start 376.712734 -91.1098)
		(end 377.354084 -91.75115)
		(width 0.13208)
		(layer "F.Cu")
		(net "BIC_I2C6_MUX_A0")
	)
	(segment
		(start 380.85903 -91.1098)
		(end 379.96495 -91.1098)
		(width 0.13208)
		(layer "F.Cu")
		(net "BIC_I2C6_MUX_A0")
	)
	(segment
		(start 377.354084 -91.75115)
		(end 379.076712 -91.75115)
		(width 0.13208)
		(layer "F.Cu")
		(net "BIC_I2C6_MUX_A0")
	)
	(via
		(at 379.96495 -91.1098)
		(size 0.508)
		(drill 0.254)
		(layers "F.Cu" "B.Cu")
		(net "BIC_I2C6_MUX_A0")
	)
	(via
		(at 115.41379 -330.66863)
		(size 0.508)
		(drill 0.254)
		(layers "F.Cu" "B.Cu")
		(net "CLK_100M_MB_0_DN")
	)
	(segment
		(start 115.41379 -330.66863)
		(end 115.11534 -330.96708)
		(width 0.13462)
		(layer "B.Cu")
		(net "CLK_100M_MB_0_DN")
	)
	(segment
		(start 114.288824 -330.96708)
		(end 113.914174 -330.59243)
		(width 0.13462)
		(layer "B.Cu")
		(net "CLK_100M_MB_0_DN")
	)
	(segment
		(start 115.11534 -330.96708)
		(end 114.288824 -330.96708)
		(width 0.13462)
		(layer "B.Cu")
		(net "CLK_100M_MB_0_DN")
	)
	(segment
		(start 116.04625 -330.95946)
		(end 116.34216 -331.25537)
		(width 0.1651)
		(layer "In5.Cu")
		(net "CLK_100M_MB_0_DN")
	)
	(segment
		(start 90.12301 -382.97739)
		(end 89.636854 -382.97739)
		(width 0.1651)
		(layer "In5.Cu")
		(net "CLK_100M_MB_0_DN")
	)
	(segment
		(start 96.6724 -360.1212)
		(end 90.667586 -368.862864)
		(width 0.1651)
		(layer "In5.Cu")
		(net "CLK_100M_MB_0_DN")
	)
	(segment
		(start 116.34216 -332.443328)
		(end 115.798092 -333.756762)
		(width 0.1651)
		(layer "In5.Cu")
		(net "CLK_100M_MB_0_DN")
	)
	(segment
		(start 90.667586 -368.862864)
		(end 90.667586 -382.432814)
		(width 0.1651)
		(layer "In5.Cu")
		(net "CLK_100M_MB_0_DN")
	)
	(segment
		(start 116.34216 -331.25537)
		(end 116.34216 -332.443328)
		(width 0.1651)
		(layer "In5.Cu")
		(net "CLK_100M_MB_0_DN")
	)
	(segment
		(start 89.509854 -383.10439)
		(end 89.509854 -383.490216)
		(width 0.1651)
		(layer "In5.Cu")
		(net "CLK_100M_MB_0_DN")
	)
	(segment
		(start 112.645952 -336.908902)
		(end 106.95686 -339.94979)
		(width 0.1651)
		(layer "In5.Cu")
		(net "CLK_100M_MB_0_DN")
	)
	(segment
		(start 96.6724 -346.00134)
		(end 96.6724 -360.1212)
		(width 0.1651)
		(layer "In5.Cu")
		(net "CLK_100M_MB_0_DN")
	)
	(segment
		(start 115.41379 -330.66863)
		(end 115.70462 -330.95946)
		(width 0.1651)
		(layer "In5.Cu")
		(net "CLK_100M_MB_0_DN")
	)
	(segment
		(start 115.798092 -333.756762)
		(end 112.645952 -336.908902)
		(width 0.1651)
		(layer "In5.Cu")
		(net "CLK_100M_MB_0_DN")
	)
	(segment
		(start 89.636854 -382.97739)
		(end 89.509854 -383.10439)
		(width 0.1651)
		(layer "In5.Cu")
		(net "CLK_100M_MB_0_DN")
	)
	(segment
		(start 106.95686 -339.94979)
		(end 101.673152 -341.000588)
		(width 0.1651)
		(layer "In5.Cu")
		(net "CLK_100M_MB_0_DN")
	)
	(segment
		(start 101.673152 -341.000588)
		(end 96.6724 -346.00134)
		(width 0.1651)
		(layer "In5.Cu")
		(net "CLK_100M_MB_0_DN")
	)
	(segment
		(start 115.70462 -330.95946)
		(end 116.04625 -330.95946)
		(width 0.1651)
		(layer "In5.Cu")
		(net "CLK_100M_MB_0_DN")
	)
	(segment
		(start 90.667586 -382.432814)
		(end 90.12301 -382.97739)
		(width 0.1651)
		(layer "In5.Cu")
		(net "CLK_100M_MB_0_DN")
	)
	(segment
		(start 147.271486 -389.998204)
		(end 147.271486 -388.153402)
		(width 0.13208)
		(layer "F.Cu")
		(net "SMB_GPU2_ALERT_N")
	)
	(segment
		(start 147.258532 -388.140448)
		(end 147.271486 -388.153402)
		(width 0.13208)
		(layer "F.Cu")
		(net "SMB_GPU2_ALERT_N")
	)
	(segment
		(start 147.258532 -387.04266)
		(end 147.258532 -388.140448)
		(width 0.13208)
		(layer "F.Cu")
		(net "SMB_GPU2_ALERT_N")
	)
	(via
		(at 147.271486 -388.153402)
		(size 0.508)
		(drill 0.254)
		(layers "F.Cu" "B.Cu")
		(net "SMB_GPU2_ALERT_N")
	)
	(segment
		(start 149.199346 -390.3218)
		(end 152.019 -390.3218)
		(width 0.15494)
		(layer "In9.Cu")
		(net "SMB_GPU2_ALERT_N")
	)
	(segment
		(start 148.792946 -389.9154)
		(end 149.199346 -390.3218)
		(width 0.15494)
		(layer "In9.Cu")
		(net "SMB_GPU2_ALERT_N")
	)
	(segment
		(start 147.929346 -389.9154)
		(end 148.792946 -389.9154)
		(width 0.15494)
		(layer "In9.Cu")
		(net "SMB_GPU2_ALERT_N")
	)
	(segment
		(start 178.360578 -410.34081)
		(end 177.509932 -409.490164)
		(width 0.15494)
		(layer "In9.Cu")
		(net "SMB_GPU2_ALERT_N")
	)
	(segment
		(start 178.360578 -412.350966)
		(end 178.360578 -410.34081)
		(width 0.15494)
		(layer "In9.Cu")
		(net "SMB_GPU2_ALERT_N")
	)
	(segment
		(start 147.271486 -389.25754)
		(end 147.929346 -389.9154)
		(width 0.15494)
		(layer "In9.Cu")
		(net "SMB_GPU2_ALERT_N")
	)
	(segment
		(start 152.019 -390.3218)
		(end 155.702 -394.0048)
		(width 0.15494)
		(layer "In9.Cu")
		(net "SMB_GPU2_ALERT_N")
	)
	(segment
		(start 158.838138 -414.062418)
		(end 176.649126 -414.062418)
		(width 0.15494)
		(layer "In9.Cu")
		(net "SMB_GPU2_ALERT_N")
	)
	(segment
		(start 147.271486 -388.153402)
		(end 147.271486 -389.25754)
		(width 0.15494)
		(layer "In9.Cu")
		(net "SMB_GPU2_ALERT_N")
	)
	(segment
		(start 176.649126 -414.062418)
		(end 178.360578 -412.350966)
		(width 0.15494)
		(layer "In9.Cu")
		(net "SMB_GPU2_ALERT_N")
	)
	(segment
		(start 155.702 -394.0048)
		(end 155.702 -410.92628)
		(width 0.15494)
		(layer "In9.Cu")
		(net "SMB_GPU2_ALERT_N")
	)
	(segment
		(start 155.702 -410.92628)
		(end 158.838138 -414.062418)
		(width 0.15494)
		(layer "In9.Cu")
		(net "SMB_GPU2_ALERT_N")
	)
	(segment
		(start 323.247258 -231.274112)
		(end 323.819012 -230.702358)
		(width 0.13208)
		(layer "F.Cu")
		(net "FPGA_DEBUG_LED_N")
	)
	(segment
		(start 320.451988 -230.395018)
		(end 321.331082 -231.274112)
		(width 0.13208)
		(layer "F.Cu")
		(net "FPGA_DEBUG_LED_N")
	)
	(segment
		(start 320.451988 -229.004368)
		(end 320.451988 -230.395018)
		(width 0.13208)
		(layer "F.Cu")
		(net "FPGA_DEBUG_LED_N")
	)
	(segment
		(start 321.331082 -231.274112)
		(end 323.247258 -231.274112)
		(width 0.13208)
		(layer "F.Cu")
		(net "FPGA_DEBUG_LED_N")
	)
	(via
		(at 320.451988 -230.395018)
		(size 0.762)
		(drill 0.381)
		(layers "F.Cu" "B.Cu")
		(net "FPGA_DEBUG_LED_N")
	)
	(segment
		(start 346.893896 -211.98713)
		(end 347.293692 -211.587334)
		(width 0.13208)
		(layer "F.Cu")
		(net "SSD3_PWRDIS_BIC_R")
	)
	(via
		(at 234.855512 -233.182668)
		(size 0.508)
		(drill 0.254)
		(layers "F.Cu" "B.Cu")
		(net "SSD3_PWRDIS_BIC_R")
	)
	(via
		(at 347.293692 -211.587334)
		(size 0.4572)
		(drill 0.254)
		(layers "F.Cu" "B.Cu")
		(net "SSD3_PWRDIS_BIC_R")
	)
	(via
		(at 263.531858 -212.467444)
		(size 0.508)
		(drill 0.254)
		(layers "F.Cu" "B.Cu")
		(net "SSD3_PWRDIS_BIC_R")
	)
	(segment
		(start 234.855512 -234.327954)
		(end 234.855512 -233.182668)
		(width 0.13208)
		(layer "B.Cu")
		(net "SSD3_PWRDIS_BIC_R")
	)
	(segment
		(start 234.381548 -232.708704)
		(end 234.381548 -231.758744)
		(width 0.13208)
		(layer "B.Cu")
		(net "SSD3_PWRDIS_BIC_R")
	)
	(segment
		(start 234.855512 -233.182668)
		(end 234.381548 -232.708704)
		(width 0.13208)
		(layer "B.Cu")
		(net "SSD3_PWRDIS_BIC_R")
	)
	(segment
		(start 234.381548 -231.758744)
		(end 234.514644 -231.625648)
		(width 0.13208)
		(layer "B.Cu")
		(net "SSD3_PWRDIS_BIC_R")
	)
	(segment
		(start 256.0828 -220.622368)
		(end 256.0828 -223.393254)
		(width 0.15494)
		(layer "In7.Cu")
		(net "SSD3_PWRDIS_BIC_R")
	)
	(segment
		(start 245.4148 -233.9086)
		(end 244.940582 -234.382818)
		(width 0.15494)
		(layer "In7.Cu")
		(net "SSD3_PWRDIS_BIC_R")
	)
	(segment
		(start 262.09879 -216.621106)
		(end 260.100064 -218.619832)
		(width 0.15494)
		(layer "In7.Cu")
		(net "SSD3_PWRDIS_BIC_R")
	)
	(segment
		(start 258.085336 -218.619832)
		(end 256.0828 -220.622368)
		(width 0.15494)
		(layer "In7.Cu")
		(net "SSD3_PWRDIS_BIC_R")
	)
	(segment
		(start 236.055662 -234.382818)
		(end 234.855512 -233.182668)
		(width 0.15494)
		(layer "In7.Cu")
		(net "SSD3_PWRDIS_BIC_R")
	)
	(segment
		(start 254.381 -226.384104)
		(end 250.77674 -229.988364)
		(width 0.15494)
		(layer "In7.Cu")
		(net "SSD3_PWRDIS_BIC_R")
	)
	(segment
		(start 248.1072 -230.378)
		(end 248.1072 -231.495854)
		(width 0.15494)
		(layer "In7.Cu")
		(net "SSD3_PWRDIS_BIC_R")
	)
	(segment
		(start 262.706612 -216.210388)
		(end 262.295894 -216.621106)
		(width 0.15494)
		(layer "In7.Cu")
		(net "SSD3_PWRDIS_BIC_R")
	)
	(segment
		(start 248.1072 -231.495854)
		(end 245.694454 -233.9086)
		(width 0.15494)
		(layer "In7.Cu")
		(net "SSD3_PWRDIS_BIC_R")
	)
	(segment
		(start 254.381 -225.095054)
		(end 254.381 -226.384104)
		(width 0.15494)
		(layer "In7.Cu")
		(net "SSD3_PWRDIS_BIC_R")
	)
	(segment
		(start 263.531858 -212.467444)
		(end 262.706612 -213.29269)
		(width 0.15494)
		(layer "In7.Cu")
		(net "SSD3_PWRDIS_BIC_R")
	)
	(segment
		(start 262.706612 -213.29269)
		(end 262.706612 -216.210388)
		(width 0.15494)
		(layer "In7.Cu")
		(net "SSD3_PWRDIS_BIC_R")
	)
	(segment
		(start 244.940582 -234.382818)
		(end 236.055662 -234.382818)
		(width 0.15494)
		(layer "In7.Cu")
		(net "SSD3_PWRDIS_BIC_R")
	)
	(segment
		(start 245.694454 -233.9086)
		(end 245.4148 -233.9086)
		(width 0.15494)
		(layer "In7.Cu")
		(net "SSD3_PWRDIS_BIC_R")
	)
	(segment
		(start 256.0828 -223.393254)
		(end 254.381 -225.095054)
		(width 0.15494)
		(layer "In7.Cu")
		(net "SSD3_PWRDIS_BIC_R")
	)
	(segment
		(start 260.100064 -218.619832)
		(end 258.085336 -218.619832)
		(width 0.15494)
		(layer "In7.Cu")
		(net "SSD3_PWRDIS_BIC_R")
	)
	(segment
		(start 262.295894 -216.621106)
		(end 262.09879 -216.621106)
		(width 0.15494)
		(layer "In7.Cu")
		(net "SSD3_PWRDIS_BIC_R")
	)
	(segment
		(start 250.77674 -229.988364)
		(end 248.496836 -229.988364)
		(width 0.15494)
		(layer "In7.Cu")
		(net "SSD3_PWRDIS_BIC_R")
	)
	(segment
		(start 248.496836 -229.988364)
		(end 248.1072 -230.378)
		(width 0.15494)
		(layer "In7.Cu")
		(net "SSD3_PWRDIS_BIC_R")
	)
	(segment
		(start 338.22767 -205.62062)
		(end 338.60613 -205.99908)
		(width 0.15494)
		(layer "In15.Cu")
		(net "SSD3_PWRDIS_BIC_R")
	)
	(segment
		(start 336.036412 -204.386942)
		(end 337.27009 -205.62062)
		(width 0.15494)
		(layer "In15.Cu")
		(net "SSD3_PWRDIS_BIC_R")
	)
	(segment
		(start 324.70725 -203.516484)
		(end 326.756014 -201.46772)
		(width 0.15494)
		(layer "In15.Cu")
		(net "SSD3_PWRDIS_BIC_R")
	)
	(segment
		(start 299.522642 -203.516484)
		(end 324.70725 -203.516484)
		(width 0.15494)
		(layer "In15.Cu")
		(net "SSD3_PWRDIS_BIC_R")
	)
	(segment
		(start 334.32496 -202.06843)
		(end 336.036412 -203.779882)
		(width 0.15494)
		(layer "In15.Cu")
		(net "SSD3_PWRDIS_BIC_R")
	)
	(segment
		(start 326.756014 -201.46772)
		(end 333.680816 -201.46772)
		(width 0.15494)
		(layer "In15.Cu")
		(net "SSD3_PWRDIS_BIC_R")
	)
	(segment
		(start 263.531858 -212.467444)
		(end 263.531858 -211.117942)
		(width 0.15494)
		(layer "In15.Cu")
		(net "SSD3_PWRDIS_BIC_R")
	)
	(segment
		(start 336.036412 -203.779882)
		(end 336.036412 -204.386942)
		(width 0.15494)
		(layer "In15.Cu")
		(net "SSD3_PWRDIS_BIC_R")
	)
	(segment
		(start 338.60613 -205.99908)
		(end 338.60613 -206.35214)
		(width 0.15494)
		(layer "In15.Cu")
		(net "SSD3_PWRDIS_BIC_R")
	)
	(segment
		(start 334.281526 -202.06843)
		(end 334.32496 -202.06843)
		(width 0.15494)
		(layer "In15.Cu")
		(net "SSD3_PWRDIS_BIC_R")
	)
	(segment
		(start 333.680816 -201.46772)
		(end 334.281526 -202.06843)
		(width 0.15494)
		(layer "In15.Cu")
		(net "SSD3_PWRDIS_BIC_R")
	)
	(segment
		(start 339.31479 -207.0608)
		(end 343.671398 -207.0608)
		(width 0.15494)
		(layer "In15.Cu")
		(net "SSD3_PWRDIS_BIC_R")
	)
	(segment
		(start 346.891102 -211.184744)
		(end 347.293692 -211.587334)
		(width 0.0889)
		(layer "In15.Cu")
		(net "SSD3_PWRDIS_BIC_R")
	)
	(segment
		(start 263.531858 -211.117942)
		(end 269.940786 -204.709014)
		(width 0.15494)
		(layer "In15.Cu")
		(net "SSD3_PWRDIS_BIC_R")
	)
	(segment
		(start 343.671398 -207.0608)
		(end 346.891102 -210.280504)
		(width 0.15494)
		(layer "In15.Cu")
		(net "SSD3_PWRDIS_BIC_R")
	)
	(segment
		(start 269.940786 -204.709014)
		(end 298.330112 -204.709014)
		(width 0.15494)
		(layer "In15.Cu")
		(net "SSD3_PWRDIS_BIC_R")
	)
	(segment
		(start 338.60613 -206.35214)
		(end 339.31479 -207.0608)
		(width 0.15494)
		(layer "In15.Cu")
		(net "SSD3_PWRDIS_BIC_R")
	)
	(segment
		(start 346.891102 -210.56219)
		(end 346.891102 -211.184744)
		(width 0.0889)
		(layer "In15.Cu")
		(net "SSD3_PWRDIS_BIC_R")
	)
	(segment
		(start 346.891102 -210.280504)
		(end 346.891102 -210.56219)
		(width 0.15494)
		(layer "In15.Cu")
		(net "SSD3_PWRDIS_BIC_R")
	)
	(segment
		(start 298.330112 -204.709014)
		(end 299.522642 -203.516484)
		(width 0.15494)
		(layer "In15.Cu")
		(net "SSD3_PWRDIS_BIC_R")
	)
	(segment
		(start 337.27009 -205.62062)
		(end 338.22767 -205.62062)
		(width 0.15494)
		(layer "In15.Cu")
		(net "SSD3_PWRDIS_BIC_R")
	)
	(segment
		(start 262.92683 -80.155288)
		(end 262.92683 -80.431386)
		(width 0.13462)
		(layer "F.Cu")
		(net "CLK_100M_CK440Q_2_DB800ZL_DP")
	)
	(segment
		(start 263.496044 -77.679804)
		(end 263.169654 -78.006194)
		(width 0.13462)
		(layer "F.Cu")
		(net "CLK_100M_CK440Q_2_DB800ZL_DP")
	)
	(segment
		(start 263.169654 -79.374746)
		(end 262.807704 -79.736696)
		(width 0.13462)
		(layer "F.Cu")
		(net "CLK_100M_CK440Q_2_DB800ZL_DP")
	)
	(segment
		(start 262.807704 -80.036162)
		(end 262.92683 -80.155288)
		(width 0.13462)
		(layer "F.Cu")
		(net "CLK_100M_CK440Q_2_DB800ZL_DP")
	)
	(segment
		(start 263.169654 -78.006194)
		(end 263.169654 -79.374746)
		(width 0.13462)
		(layer "F.Cu")
		(net "CLK_100M_CK440Q_2_DB800ZL_DP")
	)
	(segment
		(start 262.807704 -79.736696)
		(end 262.807704 -80.036162)
		(width 0.13462)
		(layer "F.Cu")
		(net "CLK_100M_CK440Q_2_DB800ZL_DP")
	)
	(segment
		(start 60.599828 -283.549852)
		(end 61.074808 -284.024832)
		(width 0.1651)
		(layer "F.Cu")
		(net "PEX0_MODE_SEL7")
	)
	(segment
		(start 25.358344 -250.470924)
		(end 25.358344 -251.062744)
		(width 0.13208)
		(layer "F.Cu")
		(net "PEX0_MODE_SEL7")
	)
	(segment
		(start 25.358344 -251.247656)
		(end 25.358344 -251.956824)
		(width 0.13208)
		(layer "F.Cu")
		(net "PEX0_MODE_SEL7")
	)
	(segment
		(start 25.4508 -251.1552)
		(end 25.358344 -251.247656)
		(width 0.13208)
		(layer "F.Cu")
		(net "PEX0_MODE_SEL7")
	)
	(segment
		(start 25.358344 -251.062744)
		(end 25.4508 -251.1552)
		(width 0.13208)
		(layer "F.Cu")
		(net "PEX0_MODE_SEL7")
	)
	(via
		(at 57.150254 -269.963138)
		(size 0.6604)
		(drill 0.3302)
		(layers "F.Cu" "B.Cu")
		(net "PEX0_MODE_SEL7")
	)
	(via
		(at 25.4508 -251.1552)
		(size 0.508)
		(drill 0.254)
		(layers "F.Cu" "B.Cu")
		(net "PEX0_MODE_SEL7")
	)
	(via
		(at 61.074808 -284.024832)
		(size 0.4064)
		(drill 0.2032)
		(layers "F.Cu" "B.Cu")
		(net "PEX0_MODE_SEL7")
	)
	(segment
		(start 61.074808 -284.024832)
		(end 60.605924 -284.493716)
		(width 0.13208)
		(layer "B.Cu")
		(net "PEX0_MODE_SEL7")
	)
	(segment
		(start 32.3088 -259.537454)
		(end 32.3088 -260.655054)
		(width 0.13208)
		(layer "B.Cu")
		(net "PEX0_MODE_SEL7")
	)
	(segment
		(start 57.749948 -282.330652)
		(end 58.177684 -281.902916)
		(width 0.13208)
		(layer "B.Cu")
		(net "PEX0_MODE_SEL7")
	)
	(segment
		(start 25.4508 -251.1552)
		(end 25.358344 -251.247656)
		(width 0.13208)
		(layer "B.Cu")
		(net "PEX0_MODE_SEL7")
	)
	(segment
		(start 27.382724 -258.856734)
		(end 31.62808 -258.856734)
		(width 0.13208)
		(layer "B.Cu")
		(net "PEX0_MODE_SEL7")
	)
	(segment
		(start 33.934146 -262.2804)
		(end 49.467516 -262.2804)
		(width 0.13208)
		(layer "B.Cu")
		(net "PEX0_MODE_SEL7")
	)
	(segment
		(start 60.605924 -284.493716)
		(end 59.92114 -284.493716)
		(width 0.13208)
		(layer "B.Cu")
		(net "PEX0_MODE_SEL7")
	)
	(segment
		(start 25.358344 -252.28423)
		(end 24.8412 -252.801374)
		(width 0.13208)
		(layer "B.Cu")
		(net "PEX0_MODE_SEL7")
	)
	(segment
		(start 58.177684 -270.990568)
		(end 57.150254 -269.963138)
		(width 0.13208)
		(layer "B.Cu")
		(net "PEX0_MODE_SEL7")
	)
	(segment
		(start 58.127392 -283.577792)
		(end 57.749948 -283.200348)
		(width 0.13208)
		(layer "B.Cu")
		(net "PEX0_MODE_SEL7")
	)
	(segment
		(start 49.467516 -262.2804)
		(end 57.150254 -269.963138)
		(width 0.13208)
		(layer "B.Cu")
		(net "PEX0_MODE_SEL7")
	)
	(segment
		(start 59.005216 -283.577792)
		(end 58.127392 -283.577792)
		(width 0.13208)
		(layer "B.Cu")
		(net "PEX0_MODE_SEL7")
	)
	(segment
		(start 24.8412 -252.801374)
		(end 24.8412 -256.31521)
		(width 0.13208)
		(layer "B.Cu")
		(net "PEX0_MODE_SEL7")
	)
	(segment
		(start 25.358344 -251.247656)
		(end 25.358344 -252.28423)
		(width 0.13208)
		(layer "B.Cu")
		(net "PEX0_MODE_SEL7")
	)
	(segment
		(start 31.62808 -258.856734)
		(end 32.3088 -259.537454)
		(width 0.13208)
		(layer "B.Cu")
		(net "PEX0_MODE_SEL7")
	)
	(segment
		(start 24.8412 -256.31521)
		(end 27.382724 -258.856734)
		(width 0.13208)
		(layer "B.Cu")
		(net "PEX0_MODE_SEL7")
	)
	(segment
		(start 59.92114 -284.493716)
		(end 59.005216 -283.577792)
		(width 0.13208)
		(layer "B.Cu")
		(net "PEX0_MODE_SEL7")
	)
	(segment
		(start 32.3088 -260.655054)
		(end 33.934146 -262.2804)
		(width 0.13208)
		(layer "B.Cu")
		(net "PEX0_MODE_SEL7")
	)
	(segment
		(start 58.177684 -281.902916)
		(end 58.177684 -270.990568)
		(width 0.13208)
		(layer "B.Cu")
		(net "PEX0_MODE_SEL7")
	)
	(segment
		(start 57.749948 -283.200348)
		(end 57.749948 -282.330652)
		(width 0.13208)
		(layer "B.Cu")
		(net "PEX0_MODE_SEL7")
	)
	(segment
		(start 137.634218 -260.027674)
		(end 138.573764 -260.027674)
		(width 0.13208)
		(layer "F.Cu")
		(net "PEX1_SYS_ERR_N")
	)
	(segment
		(start 137.471912 -259.346192)
		(end 137.471912 -259.865368)
		(width 0.13208)
		(layer "F.Cu")
		(net "PEX1_SYS_ERR_N")
	)
	(segment
		(start 180.50002 -283.549852)
		(end 180.975 -284.024832)
		(width 0.13208)
		(layer "F.Cu")
		(net "PEX1_SYS_ERR_N")
	)
	(segment
		(start 137.471912 -259.865368)
		(end 137.634218 -260.027674)
		(width 0.13208)
		(layer "F.Cu")
		(net "PEX1_SYS_ERR_N")
	)
	(via
		(at 180.975 -284.024832)
		(size 0.4064)
		(drill 0.2032)
		(layers "F.Cu" "B.Cu")
		(net "PEX1_SYS_ERR_N")
	)
	(via
		(at 138.573764 -260.027674)
		(size 0.508)
		(drill 0.254)
		(layers "F.Cu" "B.Cu")
		(net "PEX1_SYS_ERR_N")
	)
	(segment
		(start 162.991546 -261.2136)
		(end 157.0736 -261.2136)
		(width 0.13208)
		(layer "B.Cu")
		(net "PEX1_SYS_ERR_N")
	)
	(segment
		(start 148.6154 -262.2804)
		(end 147.2184 -260.8834)
		(width 0.13208)
		(layer "B.Cu")
		(net "PEX1_SYS_ERR_N")
	)
	(segment
		(start 178.854862 -283.61259)
		(end 178.639978 -283.827474)
		(width 0.13208)
		(layer "B.Cu")
		(net "PEX1_SYS_ERR_N")
	)
	(segment
		(start 175.8188 -284.810454)
		(end 175.539146 -284.5308)
		(width 0.13208)
		(layer "B.Cu")
		(net "PEX1_SYS_ERR_N")
	)
	(segment
		(start 176.1236 -285.4198)
		(end 175.8188 -285.115)
		(width 0.13208)
		(layer "B.Cu")
		(net "PEX1_SYS_ERR_N")
	)
	(segment
		(start 175.539146 -284.5308)
		(end 173.337982 -284.5308)
		(width 0.13208)
		(layer "B.Cu")
		(net "PEX1_SYS_ERR_N")
	)
	(segment
		(start 180.562758 -283.61259)
		(end 178.854862 -283.61259)
		(width 0.13208)
		(layer "B.Cu")
		(net "PEX1_SYS_ERR_N")
	)
	(segment
		(start 178.31562 -285.4198)
		(end 176.1236 -285.4198)
		(width 0.13208)
		(layer "B.Cu")
		(net "PEX1_SYS_ERR_N")
	)
	(segment
		(start 156.0068 -262.2804)
		(end 148.6154 -262.2804)
		(width 0.13208)
		(layer "B.Cu")
		(net "PEX1_SYS_ERR_N")
	)
	(segment
		(start 172.900086 -282.547568)
		(end 173.37532 -282.072334)
		(width 0.13208)
		(layer "B.Cu")
		(net "PEX1_SYS_ERR_N")
	)
	(segment
		(start 178.639978 -283.827474)
		(end 178.639978 -285.095442)
		(width 0.13208)
		(layer "B.Cu")
		(net "PEX1_SYS_ERR_N")
	)
	(segment
		(start 139.42949 -260.8834)
		(end 138.573764 -260.027674)
		(width 0.13208)
		(layer "B.Cu")
		(net "PEX1_SYS_ERR_N")
	)
	(segment
		(start 173.337982 -284.5308)
		(end 172.900086 -284.092904)
		(width 0.13208)
		(layer "B.Cu")
		(net "PEX1_SYS_ERR_N")
	)
	(segment
		(start 175.8188 -285.115)
		(end 175.8188 -284.810454)
		(width 0.13208)
		(layer "B.Cu")
		(net "PEX1_SYS_ERR_N")
	)
	(segment
		(start 172.900086 -284.092904)
		(end 172.900086 -282.547568)
		(width 0.13208)
		(layer "B.Cu")
		(net "PEX1_SYS_ERR_N")
	)
	(segment
		(start 173.37532 -282.072334)
		(end 173.37532 -271.597374)
		(width 0.13208)
		(layer "B.Cu")
		(net "PEX1_SYS_ERR_N")
	)
	(segment
		(start 147.2184 -260.8834)
		(end 139.42949 -260.8834)
		(width 0.13208)
		(layer "B.Cu")
		(net "PEX1_SYS_ERR_N")
	)
	(segment
		(start 157.0736 -261.2136)
		(end 156.0068 -262.2804)
		(width 0.13208)
		(layer "B.Cu")
		(net "PEX1_SYS_ERR_N")
	)
	(segment
		(start 178.639978 -285.095442)
		(end 178.31562 -285.4198)
		(width 0.13208)
		(layer "B.Cu")
		(net "PEX1_SYS_ERR_N")
	)
	(segment
		(start 180.975 -284.024832)
		(end 180.562758 -283.61259)
		(width 0.13208)
		(layer "B.Cu")
		(net "PEX1_SYS_ERR_N")
	)
	(segment
		(start 173.37532 -271.597374)
		(end 162.991546 -261.2136)
		(width 0.13208)
		(layer "B.Cu")
		(net "PEX1_SYS_ERR_N")
	)
	(segment
		(start 382.792732 -312.268108)
		(end 380.946152 -312.268108)
		(width 0.13208)
		(layer "F.Cu")
		(net "PU_PEX3_PAD_TRI_L")
	)
	(segment
		(start 380.946152 -312.268108)
		(end 380.29134 -311.613296)
		(width 0.13208)
		(layer "F.Cu")
		(net "PU_PEX3_PAD_TRI_L")
	)
	(segment
		(start 399.400014 -309.199788)
		(end 398.925034 -308.724808)
		(width 0.13208)
		(layer "F.Cu")
		(net "PU_PEX3_PAD_TRI_L")
	)
	(segment
		(start 380.29134 -311.613296)
		(end 379.167898 -311.613296)
		(width 0.13208)
		(layer "F.Cu")
		(net "PU_PEX3_PAD_TRI_L")
	)
	(segment
		(start 379.167898 -311.613296)
		(end 378.84481 -311.290208)
		(width 0.13208)
		(layer "F.Cu")
		(net "PU_PEX3_PAD_TRI_L")
	)
	(via
		(at 398.925034 -308.724808)
		(size 0.4064)
		(drill 0.2032)
		(layers "F.Cu" "B.Cu")
		(net "PU_PEX3_PAD_TRI_L")
	)
	(via
		(at 382.792732 -312.268108)
		(size 0.508)
		(drill 0.254)
		(layers "F.Cu" "B.Cu")
		(net "PU_PEX3_PAD_TRI_L")
	)
	(segment
		(start 383.147062 -312.268108)
		(end 383.88544 -311.52973)
		(width 0.13208)
		(layer "B.Cu")
		(net "PU_PEX3_PAD_TRI_L")
	)
	(segment
		(start 383.88544 -311.52973)
		(end 398.671034 -311.52973)
		(width 0.13208)
		(layer "B.Cu")
		(net "PU_PEX3_PAD_TRI_L")
	)
	(segment
		(start 398.925034 -311.27573)
		(end 398.925034 -308.724808)
		(width 0.13208)
		(layer "B.Cu")
		(net "PU_PEX3_PAD_TRI_L")
	)
	(segment
		(start 382.792732 -312.268108)
		(end 383.147062 -312.268108)
		(width 0.13208)
		(layer "B.Cu")
		(net "PU_PEX3_PAD_TRI_L")
	)
	(segment
		(start 398.671034 -311.52973)
		(end 398.925034 -311.27573)
		(width 0.13208)
		(layer "B.Cu")
		(net "PU_PEX3_PAD_TRI_L")
	)
	(segment
		(start 336.931 -234.46105)
		(end 336.931 -235.077)
		(width 0.13208)
		(layer "F.Cu")
		(net "SYS_PWR_READY_R_N")
	)
	(segment
		(start 335.915 -233.66095)
		(end 336.1309 -233.66095)
		(width 0.13208)
		(layer "F.Cu")
		(net "SYS_PWR_READY_R_N")
	)
	(segment
		(start 229.067614 -212.704172)
		(end 228.667818 -213.103968)
		(width 0.13208)
		(layer "F.Cu")
		(net "SYS_PWR_READY_R_N")
	)
	(segment
		(start 336.1309 -233.66095)
		(end 336.931 -234.46105)
		(width 0.13208)
		(layer "F.Cu")
		(net "SYS_PWR_READY_R_N")
	)
	(via
		(at 336.931 -235.077)
		(size 0.508)
		(drill 0.254)
		(layers "F.Cu" "B.Cu")
		(net "SYS_PWR_READY_R_N")
	)
	(via
		(at 224.221802 -237.101888)
		(size 0.508)
		(drill 0.254)
		(layers "F.Cu" "B.Cu")
		(net "SYS_PWR_READY_R_N")
	)
	(via
		(at 228.667818 -213.103968)
		(size 0.4572)
		(drill 0.254)
		(layers "F.Cu" "B.Cu")
		(net "SYS_PWR_READY_R_N")
	)
	(segment
		(start 221.53626 -225.194622)
		(end 221.996 -225.654362)
		(width 0.15494)
		(layer "In5.Cu")
		(net "SYS_PWR_READY_R_N")
	)
	(segment
		(start 228.667818 -213.103968)
		(end 228.267514 -213.504272)
		(width 0.1143)
		(layer "In5.Cu")
		(net "SYS_PWR_READY_R_N")
	)
	(segment
		(start 221.996 -226.793552)
		(end 224.211642 -229.009194)
		(width 0.15494)
		(layer "In5.Cu")
		(net "SYS_PWR_READY_R_N")
	)
	(segment
		(start 221.996 -225.654362)
		(end 221.996 -226.793552)
		(width 0.15494)
		(layer "In5.Cu")
		(net "SYS_PWR_READY_R_N")
	)
	(segment
		(start 226.763072 -213.504272)
		(end 226.6188 -213.36)
		(width 0.15494)
		(layer "In5.Cu")
		(net "SYS_PWR_READY_R_N")
	)
	(segment
		(start 221.3102 -214.56904)
		(end 221.3102 -215.641174)
		(width 0.15494)
		(layer "In5.Cu")
		(net "SYS_PWR_READY_R_N")
	)
	(segment
		(start 224.211642 -229.009194)
		(end 224.211642 -237.091728)
		(width 0.15494)
		(layer "In5.Cu")
		(net "SYS_PWR_READY_R_N")
	)
	(segment
		(start 224.211642 -237.091728)
		(end 224.221802 -237.101888)
		(width 0.15494)
		(layer "In5.Cu")
		(net "SYS_PWR_READY_R_N")
	)
	(segment
		(start 222.171006 -220.033596)
		(end 221.53626 -220.668342)
		(width 0.15494)
		(layer "In5.Cu")
		(net "SYS_PWR_READY_R_N")
	)
	(segment
		(start 228.267514 -213.504272)
		(end 226.763072 -213.504272)
		(width 0.1143)
		(layer "In5.Cu")
		(net "SYS_PWR_READY_R_N")
	)
	(segment
		(start 222.171006 -216.50198)
		(end 222.171006 -220.033596)
		(width 0.15494)
		(layer "In5.Cu")
		(net "SYS_PWR_READY_R_N")
	)
	(segment
		(start 222.51924 -213.36)
		(end 221.3102 -214.56904)
		(width 0.15494)
		(layer "In5.Cu")
		(net "SYS_PWR_READY_R_N")
	)
	(segment
		(start 226.6188 -213.36)
		(end 222.51924 -213.36)
		(width 0.15494)
		(layer "In5.Cu")
		(net "SYS_PWR_READY_R_N")
	)
	(segment
		(start 221.53626 -220.668342)
		(end 221.53626 -225.194622)
		(width 0.15494)
		(layer "In5.Cu")
		(net "SYS_PWR_READY_R_N")
	)
	(segment
		(start 221.3102 -215.641174)
		(end 222.171006 -216.50198)
		(width 0.15494)
		(layer "In5.Cu")
		(net "SYS_PWR_READY_R_N")
	)
	(segment
		(start 247.427496 -235.607352)
		(end 250.691142 -232.343706)
		(width 0.15494)
		(layer "In15.Cu")
		(net "SYS_PWR_READY_R_N")
	)
	(segment
		(start 250.691142 -232.343706)
		(end 252.339094 -232.343706)
		(width 0.15494)
		(layer "In15.Cu")
		(net "SYS_PWR_READY_R_N")
	)
	(segment
		(start 336.163412 -235.077)
		(end 336.931 -235.077)
		(width 0.15494)
		(layer "In15.Cu")
		(net "SYS_PWR_READY_R_N")
	)
	(segment
		(start 268.268704 -235.817156)
		(end 268.268704 -236.476286)
		(width 0.15494)
		(layer "In15.Cu")
		(net "SYS_PWR_READY_R_N")
	)
	(segment
		(start 257.928618 -230.78948)
		(end 262.418576 -230.78948)
		(width 0.15494)
		(layer "In15.Cu")
		(net "SYS_PWR_READY_R_N")
	)
	(segment
		(start 276.236176 -238.500158)
		(end 277.16226 -239.426242)
		(width 0.15494)
		(layer "In15.Cu")
		(net "SYS_PWR_READY_R_N")
	)
	(segment
		(start 330.726288 -236.506258)
		(end 334.734154 -236.506258)
		(width 0.15494)
		(layer "In15.Cu")
		(net "SYS_PWR_READY_R_N")
	)
	(segment
		(start 326.625204 -238.962692)
		(end 326.625204 -238.742474)
		(width 0.15494)
		(layer "In15.Cu")
		(net "SYS_PWR_READY_R_N")
	)
	(segment
		(start 327.679558 -237.68812)
		(end 329.544426 -237.68812)
		(width 0.15494)
		(layer "In15.Cu")
		(net "SYS_PWR_READY_R_N")
	)
	(segment
		(start 277.16226 -239.426242)
		(end 326.161654 -239.426242)
		(width 0.15494)
		(layer "In15.Cu")
		(net "SYS_PWR_READY_R_N")
	)
	(segment
		(start 334.734154 -236.506258)
		(end 336.163412 -235.077)
		(width 0.15494)
		(layer "In15.Cu")
		(net "SYS_PWR_READY_R_N")
	)
	(segment
		(start 256.912618 -230.47198)
		(end 257.611118 -230.47198)
		(width 0.15494)
		(layer "In15.Cu")
		(net "SYS_PWR_READY_R_N")
	)
	(segment
		(start 326.625204 -238.742474)
		(end 327.679558 -237.68812)
		(width 0.15494)
		(layer "In15.Cu")
		(net "SYS_PWR_READY_R_N")
	)
	(segment
		(start 269.830296 -238.500158)
		(end 276.236176 -238.500158)
		(width 0.15494)
		(layer "In15.Cu")
		(net "SYS_PWR_READY_R_N")
	)
	(segment
		(start 262.418576 -230.78948)
		(end 263.559036 -231.92994)
		(width 0.15494)
		(layer "In15.Cu")
		(net "SYS_PWR_READY_R_N")
	)
	(segment
		(start 268.238224 -236.908086)
		(end 269.830296 -238.500158)
		(width 0.15494)
		(layer "In15.Cu")
		(net "SYS_PWR_READY_R_N")
	)
	(segment
		(start 263.559036 -231.92994)
		(end 264.963402 -232.511854)
		(width 0.15494)
		(layer "In15.Cu")
		(net "SYS_PWR_READY_R_N")
	)
	(segment
		(start 256.117598 -231.267)
		(end 256.912618 -230.47198)
		(width 0.15494)
		(layer "In15.Cu")
		(net "SYS_PWR_READY_R_N")
	)
	(segment
		(start 230.888794 -236.8042)
		(end 231.326944 -237.24235)
		(width 0.15494)
		(layer "In15.Cu")
		(net "SYS_PWR_READY_R_N")
	)
	(segment
		(start 329.544426 -237.68812)
		(end 330.726288 -236.506258)
		(width 0.15494)
		(layer "In15.Cu")
		(net "SYS_PWR_READY_R_N")
	)
	(segment
		(start 231.326944 -237.24235)
		(end 240.715546 -237.24235)
		(width 0.15494)
		(layer "In15.Cu")
		(net "SYS_PWR_READY_R_N")
	)
	(segment
		(start 252.339094 -232.343706)
		(end 253.4158 -231.267)
		(width 0.15494)
		(layer "In15.Cu")
		(net "SYS_PWR_READY_R_N")
	)
	(segment
		(start 245.4656 -236.8296)
		(end 246.687848 -235.607352)
		(width 0.15494)
		(layer "In15.Cu")
		(net "SYS_PWR_READY_R_N")
	)
	(segment
		(start 268.268704 -236.476286)
		(end 268.238224 -236.506766)
		(width 0.15494)
		(layer "In15.Cu")
		(net "SYS_PWR_READY_R_N")
	)
	(segment
		(start 257.611118 -230.47198)
		(end 257.928618 -230.78948)
		(width 0.15494)
		(layer "In15.Cu")
		(net "SYS_PWR_READY_R_N")
	)
	(segment
		(start 268.238224 -236.506766)
		(end 268.238224 -236.908086)
		(width 0.15494)
		(layer "In15.Cu")
		(net "SYS_PWR_READY_R_N")
	)
	(segment
		(start 253.4158 -231.267)
		(end 256.117598 -231.267)
		(width 0.15494)
		(layer "In15.Cu")
		(net "SYS_PWR_READY_R_N")
	)
	(segment
		(start 246.687848 -235.607352)
		(end 247.427496 -235.607352)
		(width 0.15494)
		(layer "In15.Cu")
		(net "SYS_PWR_READY_R_N")
	)
	(segment
		(start 240.715546 -237.24235)
		(end 241.128296 -236.8296)
		(width 0.15494)
		(layer "In15.Cu")
		(net "SYS_PWR_READY_R_N")
	)
	(segment
		(start 264.963402 -232.511854)
		(end 268.268704 -235.817156)
		(width 0.15494)
		(layer "In15.Cu")
		(net "SYS_PWR_READY_R_N")
	)
	(segment
		(start 224.51949 -236.8042)
		(end 230.888794 -236.8042)
		(width 0.15494)
		(layer "In15.Cu")
		(net "SYS_PWR_READY_R_N")
	)
	(segment
		(start 241.128296 -236.8296)
		(end 245.4656 -236.8296)
		(width 0.15494)
		(layer "In15.Cu")
		(net "SYS_PWR_READY_R_N")
	)
	(segment
		(start 326.161654 -239.426242)
		(end 326.625204 -238.962692)
		(width 0.15494)
		(layer "In15.Cu")
		(net "SYS_PWR_READY_R_N")
	)
	(segment
		(start 224.221802 -237.101888)
		(end 224.51949 -236.8042)
		(width 0.15494)
		(layer "In15.Cu")
		(net "SYS_PWR_READY_R_N")
	)
	(segment
		(start 348.387416 -207.619092)
		(end 348.742 -207.973676)
		(width 0.13208)
		(layer "F.Cu")
		(net "PRSNT_SSD5_FPGA_N")
	)
	(segment
		(start 348.742 -205.63205)
		(end 348.742 -207.264508)
		(width 0.13208)
		(layer "F.Cu")
		(net "PRSNT_SSD5_FPGA_N")
	)
	(segment
		(start 348.742 -210.938872)
		(end 348.493842 -211.18703)
		(width 0.13208)
		(layer "F.Cu")
		(net "PRSNT_SSD5_FPGA_N")
	)
	(segment
		(start 348.742 -207.264508)
		(end 348.387416 -207.619092)
		(width 0.13208)
		(layer "F.Cu")
		(net "PRSNT_SSD5_FPGA_N")
	)
	(segment
		(start 348.742 -207.973676)
		(end 348.742 -210.938872)
		(width 0.13208)
		(layer "F.Cu")
		(net "PRSNT_SSD5_FPGA_N")
	)
	(via
		(at 348.387416 -207.619092)
		(size 0.762)
		(drill 0.381)
		(layers "F.Cu" "B.Cu")
		(net "PRSNT_SSD5_FPGA_N")
	)
	(segment
		(start 317.84798 -59.304936)
		(end 317.97498 -59.177936)
		(width 0.13208)
		(layer "F.Cu")
		(net "PWRGD_P3V3_SSD11")
	)
	(segment
		(start 317.84798 -61.22416)
		(end 317.84798 -59.304936)
		(width 0.13208)
		(layer "F.Cu")
		(net "PWRGD_P3V3_SSD11")
	)
	(segment
		(start 317.97498 -59.177936)
		(end 318.37884 -59.177936)
		(width 0.13208)
		(layer "F.Cu")
		(net "PWRGD_P3V3_SSD11")
	)
	(segment
		(start 317.840868 -57.457848)
		(end 318.224916 -57.841896)
		(width 0.13208)
		(layer "F.Cu")
		(net "PWRGD_P3V3_SSD11")
	)
	(segment
		(start 318.224916 -58.565796)
		(end 318.37884 -58.71972)
		(width 0.13208)
		(layer "F.Cu")
		(net "PWRGD_P3V3_SSD11")
	)
	(segment
		(start 318.224916 -57.841896)
		(end 318.224916 -57.867296)
		(width 0.13208)
		(layer "F.Cu")
		(net "PWRGD_P3V3_SSD11")
	)
	(segment
		(start 318.010794 -61.386974)
		(end 317.84798 -61.22416)
		(width 0.13208)
		(layer "F.Cu")
		(net "PWRGD_P3V3_SSD11")
	)
	(segment
		(start 318.224916 -57.867296)
		(end 318.224916 -58.565796)
		(width 0.13208)
		(layer "F.Cu")
		(net "PWRGD_P3V3_SSD11")
	)
	(segment
		(start 318.37884 -58.71972)
		(end 318.37884 -59.177936)
		(width 0.13208)
		(layer "F.Cu")
		(net "PWRGD_P3V3_SSD11")
	)
	(segment
		(start 317.840868 -57.16397)
		(end 317.840868 -57.457848)
		(width 0.13208)
		(layer "F.Cu")
		(net "PWRGD_P3V3_SSD11")
	)
	(via
		(at 318.224916 -57.867296)
		(size 0.508)
		(drill 0.254)
		(layers "F.Cu" "B.Cu")
		(net "PWRGD_P3V3_SSD11")
	)
	(segment
		(start 266.266422 -81.401412)
		(end 265.50493 -82.162904)
		(width 0.13462)
		(layer "F.Cu")
		(net "CLK_100M_CK440Q_1_DB800ZL_DN")
	)
	(segment
		(start 265.50493 -82.162904)
		(end 263.933432 -82.162904)
		(width 0.13462)
		(layer "F.Cu")
		(net "CLK_100M_CK440Q_1_DB800ZL_DN")
	)
	(segment
		(start 267.82141 -81.401412)
		(end 266.266422 -81.401412)
		(width 0.13462)
		(layer "F.Cu")
		(net "CLK_100M_CK440Q_1_DB800ZL_DN")
	)
	(segment
		(start 268.1351 -81.087722)
		(end 267.82141 -81.401412)
		(width 0.13462)
		(layer "F.Cu")
		(net "CLK_100M_CK440Q_1_DB800ZL_DN")
	)
	(segment
		(start 263.827006 -82.056478)
		(end 263.551924 -82.056478)
		(width 0.13462)
		(layer "F.Cu")
		(net "CLK_100M_CK440Q_1_DB800ZL_DN")
	)
	(segment
		(start 263.933432 -82.162904)
		(end 263.827006 -82.056478)
		(width 0.13462)
		(layer "F.Cu")
		(net "CLK_100M_CK440Q_1_DB800ZL_DN")
	)
	(segment
		(start 145.522442 -251.956824)
		(end 145.522442 -251.158502)
		(width 0.13208)
		(layer "F.Cu")
		(net "PEX1_MODE_SEL3")
	)
	(segment
		(start 145.522442 -251.158502)
		(end 145.522442 -250.470924)
		(width 0.13208)
		(layer "F.Cu")
		(net "PEX1_MODE_SEL3")
	)
	(segment
		(start 177.649886 -283.549852)
		(end 178.124866 -284.024832)
		(width 0.1651)
		(layer "F.Cu")
		(net "PEX1_MODE_SEL3")
	)
	(via
		(at 178.124866 -284.024832)
		(size 0.4064)
		(drill 0.2032)
		(layers "F.Cu" "B.Cu")
		(net "PEX1_MODE_SEL3")
	)
	(via
		(at 145.522442 -251.158502)
		(size 0.508)
		(drill 0.254)
		(layers "F.Cu" "B.Cu")
		(net "PEX1_MODE_SEL3")
	)
	(via
		(at 175.28159 -268.925802)
		(size 0.6604)
		(drill 0.3302)
		(layers "F.Cu" "B.Cu")
		(net "PEX1_MODE_SEL3")
	)
	(segment
		(start 146.227546 -255.8542)
		(end 145.01241 -254.639064)
		(width 0.13208)
		(layer "B.Cu")
		(net "PEX1_MODE_SEL3")
	)
	(segment
		(start 145.01241 -254.639064)
		(end 145.01241 -251.668534)
		(width 0.13208)
		(layer "B.Cu")
		(net "PEX1_MODE_SEL3")
	)
	(segment
		(start 147.771612 -255.8542)
		(end 146.227546 -255.8542)
		(width 0.13208)
		(layer "B.Cu")
		(net "PEX1_MODE_SEL3")
	)
	(segment
		(start 177.649886 -282.82646)
		(end 178.157886 -282.31846)
		(width 0.13208)
		(layer "B.Cu")
		(net "PEX1_MODE_SEL3")
	)
	(segment
		(start 175.28159 -268.925802)
		(end 164.978588 -258.6228)
		(width 0.13208)
		(layer "B.Cu")
		(net "PEX1_MODE_SEL3")
	)
	(segment
		(start 178.124866 -284.024832)
		(end 177.649886 -283.549852)
		(width 0.13208)
		(layer "B.Cu")
		(net "PEX1_MODE_SEL3")
	)
	(segment
		(start 178.157886 -271.802098)
		(end 175.28159 -268.925802)
		(width 0.13208)
		(layer "B.Cu")
		(net "PEX1_MODE_SEL3")
	)
	(segment
		(start 178.157886 -282.31846)
		(end 178.157886 -271.802098)
		(width 0.13208)
		(layer "B.Cu")
		(net "PEX1_MODE_SEL3")
	)
	(segment
		(start 177.649886 -283.549852)
		(end 177.649886 -282.82646)
		(width 0.13208)
		(layer "B.Cu")
		(net "PEX1_MODE_SEL3")
	)
	(segment
		(start 145.01241 -251.668534)
		(end 145.522442 -251.158502)
		(width 0.13208)
		(layer "B.Cu")
		(net "PEX1_MODE_SEL3")
	)
	(segment
		(start 150.540212 -258.6228)
		(end 147.771612 -255.8542)
		(width 0.13208)
		(layer "B.Cu")
		(net "PEX1_MODE_SEL3")
	)
	(segment
		(start 164.978588 -258.6228)
		(end 150.540212 -258.6228)
		(width 0.13208)
		(layer "B.Cu")
		(net "PEX1_MODE_SEL3")
	)
	(segment
		(start 437.319674 -310.226456)
		(end 437.6928 -309.85333)
		(width 0.13208)
		(layer "F.Cu")
		(net "PEX3_SPARE2")
	)
	(segment
		(start 438.214262 -309.324756)
		(end 438.214262 -309.331868)
		(width 0.13208)
		(layer "F.Cu")
		(net "PEX3_SPARE2")
	)
	(segment
		(start 437.078882 -310.226456)
		(end 437.319674 -310.226456)
		(width 0.13208)
		(layer "F.Cu")
		(net "PEX3_SPARE2")
	)
	(segment
		(start 438.214262 -309.331868)
		(end 437.6928 -309.85333)
		(width 0.13208)
		(layer "F.Cu")
		(net "PEX3_SPARE2")
	)
	(via
		(at 434.122576 -313.423554)
		(size 0.6604)
		(drill 0.3302)
		(layers "F.Cu" "B.Cu")
		(net "PEX3_SPARE2")
	)
	(via
		(at 437.6928 -309.85333)
		(size 0.508)
		(drill 0.254)
		(layers "F.Cu" "B.Cu")
		(net "PEX3_SPARE2")
	)
	(via
		(at 409.849828 -309.199788)
		(size 0.4064)
		(drill 0.2032)
		(layers "F.Cu" "B.Cu")
		(net "PEX3_SPARE2")
	)
	(segment
		(start 433.088796 -314.457334)
		(end 434.122576 -313.423554)
		(width 0.13208)
		(layer "B.Cu")
		(net "PEX3_SPARE2")
	)
	(segment
		(start 411.270196 -314.330334)
		(end 411.397196 -314.457334)
		(width 0.13208)
		(layer "B.Cu")
		(net "PEX3_SPARE2")
	)
	(segment
		(start 437.6928 -311.06491)
		(end 437.6928 -309.85333)
		(width 0.13208)
		(layer "B.Cu")
		(net "PEX3_SPARE2")
	)
	(segment
		(start 434.122576 -313.423554)
		(end 435.334156 -313.423554)
		(width 0.13208)
		(layer "B.Cu")
		(net "PEX3_SPARE2")
	)
	(segment
		(start 435.334156 -313.423554)
		(end 437.6928 -311.06491)
		(width 0.13208)
		(layer "B.Cu")
		(net "PEX3_SPARE2")
	)
	(segment
		(start 410.604208 -309.199788)
		(end 411.270196 -309.865776)
		(width 0.13208)
		(layer "B.Cu")
		(net "PEX3_SPARE2")
	)
	(segment
		(start 411.397196 -314.457334)
		(end 433.088796 -314.457334)
		(width 0.13208)
		(layer "B.Cu")
		(net "PEX3_SPARE2")
	)
	(segment
		(start 411.270196 -309.865776)
		(end 411.270196 -314.330334)
		(width 0.13208)
		(layer "B.Cu")
		(net "PEX3_SPARE2")
	)
	(segment
		(start 409.849828 -309.199788)
		(end 410.604208 -309.199788)
		(width 0.13208)
		(layer "B.Cu")
		(net "PEX3_SPARE2")
	)
	(segment
		(start 263.828022 -82.55635)
		(end 263.551924 -82.55635)
		(width 0.13462)
		(layer "F.Cu")
		(net "CLK_100M_CK440Q_1_DB800ZL_DP")
	)
	(segment
		(start 265.618722 -82.437224)
		(end 263.947148 -82.437224)
		(width 0.13462)
		(layer "F.Cu")
		(net "CLK_100M_CK440Q_1_DB800ZL_DP")
	)
	(segment
		(start 267.80871 -81.675732)
		(end 266.380214 -81.675732)
		(width 0.13462)
		(layer "F.Cu")
		(net "CLK_100M_CK440Q_1_DB800ZL_DP")
	)
	(segment
		(start 263.947148 -82.437224)
		(end 263.828022 -82.55635)
		(width 0.13462)
		(layer "F.Cu")
		(net "CLK_100M_CK440Q_1_DB800ZL_DP")
	)
	(segment
		(start 268.1351 -82.002122)
		(end 267.80871 -81.675732)
		(width 0.13462)
		(layer "F.Cu")
		(net "CLK_100M_CK440Q_1_DB800ZL_DP")
	)
	(segment
		(start 266.380214 -81.675732)
		(end 265.618722 -82.437224)
		(width 0.13462)
		(layer "F.Cu")
		(net "CLK_100M_CK440Q_1_DB800ZL_DP")
	)
	(segment
		(start 36.534344 -251.956824)
		(end 36.534344 -251.158502)
		(width 0.13208)
		(layer "F.Cu")
		(net "PEX0_MODE_SEL6")
	)
	(segment
		(start 36.534344 -251.158502)
		(end 36.534344 -250.470924)
		(width 0.13208)
		(layer "F.Cu")
		(net "PEX0_MODE_SEL6")
	)
	(segment
		(start 65.349882 -283.549852)
		(end 65.824862 -284.024832)
		(width 0.13208)
		(layer "F.Cu")
		(net "PEX0_MODE_SEL6")
	)
	(via
		(at 65.824862 -284.024832)
		(size 0.4064)
		(drill 0.2032)
		(layers "F.Cu" "B.Cu")
		(net "PEX0_MODE_SEL6")
	)
	(via
		(at 36.534344 -251.158502)
		(size 0.508)
		(drill 0.254)
		(layers "F.Cu" "B.Cu")
		(net "PEX0_MODE_SEL6")
	)
	(segment
		(start 67.002914 -283.497528)
		(end 67.267836 -283.232606)
		(width 0.13208)
		(layer "B.Cu")
		(net "PEX0_MODE_SEL6")
	)
	(segment
		(start 66.548508 -270.434054)
		(end 66.548508 -270.229838)
		(width 0.13208)
		(layer "B.Cu")
		(net "PEX0_MODE_SEL6")
	)
	(segment
		(start 67.267836 -282.850336)
		(end 67.482974 -282.635198)
		(width 0.13208)
		(layer "B.Cu")
		(net "PEX0_MODE_SEL6")
	)
	(segment
		(start 67.234054 -271.1196)
		(end 66.548508 -270.434054)
		(width 0.13208)
		(layer "B.Cu")
		(net "PEX0_MODE_SEL6")
	)
	(segment
		(start 67.267836 -283.232606)
		(end 67.267836 -282.850336)
		(width 0.13208)
		(layer "B.Cu")
		(net "PEX0_MODE_SEL6")
	)
	(segment
		(start 66.352166 -283.497528)
		(end 67.002914 -283.497528)
		(width 0.13208)
		(layer "B.Cu")
		(net "PEX0_MODE_SEL6")
	)
	(segment
		(start 68.635118 -272.316448)
		(end 67.43827 -271.1196)
		(width 0.13208)
		(layer "B.Cu")
		(net "PEX0_MODE_SEL6")
	)
	(segment
		(start 51.41087 -255.0922)
		(end 37.137086 -255.0922)
		(width 0.13208)
		(layer "B.Cu")
		(net "PEX0_MODE_SEL6")
	)
	(segment
		(start 68.635118 -281.865324)
		(end 68.635118 -272.316448)
		(width 0.13208)
		(layer "B.Cu")
		(net "PEX0_MODE_SEL6")
	)
	(segment
		(start 67.482974 -282.635198)
		(end 67.865244 -282.635198)
		(width 0.13208)
		(layer "B.Cu")
		(net "PEX0_MODE_SEL6")
	)
	(segment
		(start 65.824862 -284.024832)
		(end 66.352166 -283.497528)
		(width 0.13208)
		(layer "B.Cu")
		(net "PEX0_MODE_SEL6")
	)
	(segment
		(start 67.865244 -282.635198)
		(end 68.635118 -281.865324)
		(width 0.13208)
		(layer "B.Cu")
		(net "PEX0_MODE_SEL6")
	)
	(segment
		(start 66.548508 -270.229838)
		(end 51.41087 -255.0922)
		(width 0.13208)
		(layer "B.Cu")
		(net "PEX0_MODE_SEL6")
	)
	(segment
		(start 37.137086 -255.0922)
		(end 36.047172 -254.002286)
		(width 0.13208)
		(layer "B.Cu")
		(net "PEX0_MODE_SEL6")
	)
	(segment
		(start 36.047172 -251.645674)
		(end 36.534344 -251.158502)
		(width 0.13208)
		(layer "B.Cu")
		(net "PEX0_MODE_SEL6")
	)
	(segment
		(start 36.047172 -254.002286)
		(end 36.047172 -251.645674)
		(width 0.13208)
		(layer "B.Cu")
		(net "PEX0_MODE_SEL6")
	)
	(segment
		(start 67.43827 -271.1196)
		(end 67.234054 -271.1196)
		(width 0.13208)
		(layer "B.Cu")
		(net "PEX0_MODE_SEL6")
	)
	(segment
		(start 182.39994 -282.599892)
		(end 182.87492 -283.074872)
		(width 0.13208)
		(layer "F.Cu")
		(net "PEX1_MODE_SEL12")
	)
	(segment
		(start 151.618442 -251.158502)
		(end 151.618442 -251.956824)
		(width 0.13208)
		(layer "F.Cu")
		(net "PEX1_MODE_SEL12")
	)
	(segment
		(start 151.618442 -250.470924)
		(end 151.618442 -251.158502)
		(width 0.13208)
		(layer "F.Cu")
		(net "PEX1_MODE_SEL12")
	)
	(via
		(at 151.618442 -251.158502)
		(size 0.508)
		(drill 0.254)
		(layers "F.Cu" "B.Cu")
		(net "PEX1_MODE_SEL12")
	)
	(via
		(at 182.87492 -283.074872)
		(size 0.4064)
		(drill 0.2032)
		(layers "F.Cu" "B.Cu")
		(net "PEX1_MODE_SEL12")
	)
	(via
		(at 179.642008 -268.169898)
		(size 0.6604)
		(drill 0.3302)
		(layers "F.Cu" "B.Cu")
		(net "PEX1_MODE_SEL12")
	)
	(segment
		(start 179.642008 -268.169898)
		(end 166.99611 -255.524)
		(width 0.13208)
		(layer "B.Cu")
		(net "PEX1_MODE_SEL12")
	)
	(segment
		(start 183.792622 -281.875738)
		(end 182.87492 -282.79344)
		(width 0.13208)
		(layer "B.Cu")
		(net "PEX1_MODE_SEL12")
	)
	(segment
		(start 179.642008 -268.169898)
		(end 183.17591 -271.7038)
		(width 0.13208)
		(layer "B.Cu")
		(net "PEX1_MODE_SEL12")
	)
	(segment
		(start 152.3492 -255.524)
		(end 151.108664 -254.283464)
		(width 0.13208)
		(layer "B.Cu")
		(net "PEX1_MODE_SEL12")
	)
	(segment
		(start 183.460898 -271.7038)
		(end 183.792622 -272.035524)
		(width 0.13208)
		(layer "B.Cu")
		(net "PEX1_MODE_SEL12")
	)
	(segment
		(start 183.17591 -271.7038)
		(end 183.460898 -271.7038)
		(width 0.13208)
		(layer "B.Cu")
		(net "PEX1_MODE_SEL12")
	)
	(segment
		(start 151.108664 -251.66828)
		(end 151.618442 -251.158502)
		(width 0.13208)
		(layer "B.Cu")
		(net "PEX1_MODE_SEL12")
	)
	(segment
		(start 183.792622 -272.035524)
		(end 183.792622 -281.875738)
		(width 0.13208)
		(layer "B.Cu")
		(net "PEX1_MODE_SEL12")
	)
	(segment
		(start 151.108664 -254.283464)
		(end 151.108664 -251.66828)
		(width 0.13208)
		(layer "B.Cu")
		(net "PEX1_MODE_SEL12")
	)
	(segment
		(start 182.87492 -282.79344)
		(end 182.87492 -283.074872)
		(width 0.13208)
		(layer "B.Cu")
		(net "PEX1_MODE_SEL12")
	)
	(segment
		(start 166.99611 -255.524)
		(end 152.3492 -255.524)
		(width 0.13208)
		(layer "B.Cu")
		(net "PEX1_MODE_SEL12")
	)
	(segment
		(start 438.31764 -304.436526)
		(end 438.31764 -305.064414)
		(width 0.13208)
		(layer "F.Cu")
		(net "PEX3_SPARE3")
	)
	(segment
		(start 438.317132 -305.064922)
		(end 438.318148 -305.065938)
		(width 0.13208)
		(layer "F.Cu")
		(net "PEX3_SPARE3")
	)
	(segment
		(start 438.318148 -305.065938)
		(end 438.318148 -305.674522)
		(width 0.13208)
		(layer "F.Cu")
		(net "PEX3_SPARE3")
	)
	(segment
		(start 438.31764 -305.064414)
		(end 438.317132 -305.064922)
		(width 0.13208)
		(layer "F.Cu")
		(net "PEX3_SPARE3")
	)
	(segment
		(start 414.599882 -309.199788)
		(end 415.074862 -308.724808)
		(width 0.13208)
		(layer "F.Cu")
		(net "PEX3_SPARE3")
	)
	(via
		(at 415.074862 -308.724808)
		(size 0.4064)
		(drill 0.2032)
		(layers "F.Cu" "B.Cu")
		(net "PEX3_SPARE3")
	)
	(via
		(at 438.317132 -305.064922)
		(size 0.508)
		(drill 0.254)
		(layers "F.Cu" "B.Cu")
		(net "PEX3_SPARE3")
	)
	(via
		(at 432.435 -310.149748)
		(size 0.6604)
		(drill 0.3302)
		(layers "F.Cu" "B.Cu")
		(net "PEX3_SPARE3")
	)
	(segment
		(start 431.97018 -309.684928)
		(end 432.435 -310.149748)
		(width 0.13208)
		(layer "B.Cu")
		(net "PEX3_SPARE3")
	)
	(segment
		(start 426.700442 -309.684928)
		(end 431.97018 -309.684928)
		(width 0.13208)
		(layer "B.Cu")
		(net "PEX3_SPARE3")
	)
	(segment
		(start 416.184588 -310.657494)
		(end 426.274484 -310.657494)
		(width 0.13208)
		(layer "B.Cu")
		(net "PEX3_SPARE3")
	)
	(segment
		(start 415.074862 -308.724808)
		(end 416.037776 -309.687722)
		(width 0.13208)
		(layer "B.Cu")
		(net "PEX3_SPARE3")
	)
	(segment
		(start 426.494956 -310.437022)
		(end 426.494956 -309.890414)
		(width 0.13208)
		(layer "B.Cu")
		(net "PEX3_SPARE3")
	)
	(segment
		(start 416.037776 -309.687722)
		(end 416.037776 -310.510682)
		(width 0.13208)
		(layer "B.Cu")
		(net "PEX3_SPARE3")
	)
	(segment
		(start 438.317132 -305.534822)
		(end 438.317132 -305.064922)
		(width 0.13208)
		(layer "B.Cu")
		(net "PEX3_SPARE3")
	)
	(segment
		(start 432.435 -310.149748)
		(end 433.702206 -310.149748)
		(width 0.13208)
		(layer "B.Cu")
		(net "PEX3_SPARE3")
	)
	(segment
		(start 433.702206 -310.149748)
		(end 438.317132 -305.534822)
		(width 0.13208)
		(layer "B.Cu")
		(net "PEX3_SPARE3")
	)
	(segment
		(start 426.494956 -309.890414)
		(end 426.700442 -309.684928)
		(width 0.13208)
		(layer "B.Cu")
		(net "PEX3_SPARE3")
	)
	(segment
		(start 426.274484 -310.657494)
		(end 426.494956 -310.437022)
		(width 0.13208)
		(layer "B.Cu")
		(net "PEX3_SPARE3")
	)
	(segment
		(start 416.037776 -310.510682)
		(end 416.184588 -310.657494)
		(width 0.13208)
		(layer "B.Cu")
		(net "PEX3_SPARE3")
	)
	(segment
		(start 347.693742 -212.786976)
		(end 348.093538 -212.38718)
		(width 0.13208)
		(layer "F.Cu")
		(net "SSD4_PWRDIS_BIC_R")
	)
	(via
		(at 348.093538 -212.38718)
		(size 0.4572)
		(drill 0.254)
		(layers "F.Cu" "B.Cu")
		(net "SSD4_PWRDIS_BIC_R")
	)
	(via
		(at 264.4394 -212.979)
		(size 0.508)
		(drill 0.254)
		(layers "F.Cu" "B.Cu")
		(net "SSD4_PWRDIS_BIC_R")
	)
	(via
		(at 232.823512 -233.182668)
		(size 0.508)
		(drill 0.254)
		(layers "F.Cu" "B.Cu")
		(net "SSD4_PWRDIS_BIC_R")
	)
	(segment
		(start 232.349548 -232.708704)
		(end 232.349548 -231.758744)
		(width 0.13208)
		(layer "B.Cu")
		(net "SSD4_PWRDIS_BIC_R")
	)
	(segment
		(start 232.823512 -233.182668)
		(end 232.349548 -232.708704)
		(width 0.13208)
		(layer "B.Cu")
		(net "SSD4_PWRDIS_BIC_R")
	)
	(segment
		(start 232.349548 -231.758744)
		(end 232.482644 -231.625648)
		(width 0.13208)
		(layer "B.Cu")
		(net "SSD4_PWRDIS_BIC_R")
	)
	(segment
		(start 232.823512 -234.327954)
		(end 232.823512 -233.182668)
		(width 0.13208)
		(layer "B.Cu")
		(net "SSD4_PWRDIS_BIC_R")
	)
	(segment
		(start 249.33275 -231.641904)
		(end 246.304054 -234.6706)
		(width 0.15494)
		(layer "In7.Cu")
		(net "SSD4_PWRDIS_BIC_R")
	)
	(segment
		(start 245.8974 -234.6706)
		(end 245.468902 -235.099098)
		(width 0.15494)
		(layer "In7.Cu")
		(net "SSD4_PWRDIS_BIC_R")
	)
	(segment
		(start 250.509278 -231.269286)
		(end 250.20016 -231.269286)
		(width 0.15494)
		(layer "In7.Cu")
		(net "SSD4_PWRDIS_BIC_R")
	)
	(segment
		(start 250.20016 -231.269286)
		(end 249.898916 -231.57053)
		(width 0.15494)
		(layer "In7.Cu")
		(net "SSD4_PWRDIS_BIC_R")
	)
	(segment
		(start 256.87274 -223.616774)
		(end 255.373124 -225.11639)
		(width 0.15494)
		(layer "In7.Cu")
		(net "SSD4_PWRDIS_BIC_R")
	)
	(segment
		(start 255.373124 -226.40544)
		(end 250.509278 -231.269286)
		(width 0.15494)
		(layer "In7.Cu")
		(net "SSD4_PWRDIS_BIC_R")
	)
	(segment
		(start 264.4394 -212.979)
		(end 264.2362 -212.979)
		(width 0.15494)
		(layer "In7.Cu")
		(net "SSD4_PWRDIS_BIC_R")
	)
	(segment
		(start 234.739942 -235.099098)
		(end 232.823512 -233.182668)
		(width 0.15494)
		(layer "In7.Cu")
		(net "SSD4_PWRDIS_BIC_R")
	)
	(segment
		(start 263.824212 -216.135204)
		(end 262.62203 -217.337386)
		(width 0.15494)
		(layer "In7.Cu")
		(net "SSD4_PWRDIS_BIC_R")
	)
	(segment
		(start 260.397244 -219.336112)
		(end 258.382516 -219.336112)
		(width 0.15494)
		(layer "In7.Cu")
		(net "SSD4_PWRDIS_BIC_R")
	)
	(segment
		(start 249.72645 -231.641904)
		(end 249.33275 -231.641904)
		(width 0.15494)
		(layer "In7.Cu")
		(net "SSD4_PWRDIS_BIC_R")
	)
	(segment
		(start 262.39597 -217.337386)
		(end 260.397244 -219.336112)
		(width 0.15494)
		(layer "In7.Cu")
		(net "SSD4_PWRDIS_BIC_R")
	)
	(segment
		(start 258.382516 -219.336112)
		(end 256.87274 -220.845888)
		(width 0.15494)
		(layer "In7.Cu")
		(net "SSD4_PWRDIS_BIC_R")
	)
	(segment
		(start 255.373124 -225.11639)
		(end 255.373124 -226.40544)
		(width 0.15494)
		(layer "In7.Cu")
		(net "SSD4_PWRDIS_BIC_R")
	)
	(segment
		(start 264.2362 -212.979)
		(end 263.824212 -213.390988)
		(width 0.15494)
		(layer "In7.Cu")
		(net "SSD4_PWRDIS_BIC_R")
	)
	(segment
		(start 263.824212 -213.390988)
		(end 263.824212 -216.135204)
		(width 0.15494)
		(layer "In7.Cu")
		(net "SSD4_PWRDIS_BIC_R")
	)
	(segment
		(start 245.468902 -235.099098)
		(end 234.739942 -235.099098)
		(width 0.15494)
		(layer "In7.Cu")
		(net "SSD4_PWRDIS_BIC_R")
	)
	(segment
		(start 256.87274 -220.845888)
		(end 256.87274 -223.616774)
		(width 0.15494)
		(layer "In7.Cu")
		(net "SSD4_PWRDIS_BIC_R")
	)
	(segment
		(start 246.304054 -234.6706)
		(end 245.8974 -234.6706)
		(width 0.15494)
		(layer "In7.Cu")
		(net "SSD4_PWRDIS_BIC_R")
	)
	(segment
		(start 249.898916 -231.57053)
		(end 249.72645 -231.641904)
		(width 0.15494)
		(layer "In7.Cu")
		(net "SSD4_PWRDIS_BIC_R")
	)
	(segment
		(start 262.62203 -217.337386)
		(end 262.39597 -217.337386)
		(width 0.15494)
		(layer "In7.Cu")
		(net "SSD4_PWRDIS_BIC_R")
	)
	(segment
		(start 326.607424 -201.10958)
		(end 324.797928 -202.919076)
		(width 0.15494)
		(layer "In15.Cu")
		(net "SSD4_PWRDIS_BIC_R")
	)
	(segment
		(start 336.428334 -203.508864)
		(end 336.01787 -203.0984)
		(width 0.15494)
		(layer "In15.Cu")
		(net "SSD4_PWRDIS_BIC_R")
	)
	(segment
		(start 337.071462 -204.052932)
		(end 336.527394 -203.508864)
		(width 0.15494)
		(layer "In15.Cu")
		(net "SSD4_PWRDIS_BIC_R")
	)
	(segment
		(start 263.047988 -211.095082)
		(end 263.047988 -212.668104)
		(width 0.15494)
		(layer "In15.Cu")
		(net "SSD4_PWRDIS_BIC_R")
	)
	(segment
		(start 334.271366 -201.55154)
		(end 333.829406 -201.10958)
		(width 0.15494)
		(layer "In15.Cu")
		(net "SSD4_PWRDIS_BIC_R")
	)
	(segment
		(start 347.696028 -211.98967)
		(end 347.696028 -210.383374)
		(width 0.0889)
		(layer "In15.Cu")
		(net "SSD4_PWRDIS_BIC_R")
	)
	(segment
		(start 333.829406 -201.10958)
		(end 326.607424 -201.10958)
		(width 0.15494)
		(layer "In15.Cu")
		(net "SSD4_PWRDIS_BIC_R")
	)
	(segment
		(start 348.093538 -212.38718)
		(end 347.696028 -211.98967)
		(width 0.0889)
		(layer "In15.Cu")
		(net "SSD4_PWRDIS_BIC_R")
	)
	(segment
		(start 336.527394 -203.508864)
		(end 336.428334 -203.508864)
		(width 0.15494)
		(layer "In15.Cu")
		(net "SSD4_PWRDIS_BIC_R")
	)
	(segment
		(start 347.696028 -210.383374)
		(end 347.5863 -210.273646)
		(width 0.0889)
		(layer "In15.Cu")
		(net "SSD4_PWRDIS_BIC_R")
	)
	(segment
		(start 337.071462 -204.405992)
		(end 337.071462 -204.052932)
		(width 0.15494)
		(layer "In15.Cu")
		(net "SSD4_PWRDIS_BIC_R")
	)
	(segment
		(start 347.5863 -210.273646)
		(end 343.98839 -206.675736)
		(width 0.15494)
		(layer "In15.Cu")
		(net "SSD4_PWRDIS_BIC_R")
	)
	(segment
		(start 335.58607 -201.55154)
		(end 334.271366 -201.55154)
		(width 0.15494)
		(layer "In15.Cu")
		(net "SSD4_PWRDIS_BIC_R")
	)
	(segment
		(start 340.405974 -206.675736)
		(end 338.992718 -205.26248)
		(width 0.15494)
		(layer "In15.Cu")
		(net "SSD4_PWRDIS_BIC_R")
	)
	(segment
		(start 271.223994 -202.919076)
		(end 263.047988 -211.095082)
		(width 0.15494)
		(layer "In15.Cu")
		(net "SSD4_PWRDIS_BIC_R")
	)
	(segment
		(start 263.047988 -212.668104)
		(end 263.358884 -212.979)
		(width 0.15494)
		(layer "In15.Cu")
		(net "SSD4_PWRDIS_BIC_R")
	)
	(segment
		(start 338.992718 -205.26248)
		(end 337.92795 -205.26248)
		(width 0.15494)
		(layer "In15.Cu")
		(net "SSD4_PWRDIS_BIC_R")
	)
	(segment
		(start 343.98839 -206.675736)
		(end 340.405974 -206.675736)
		(width 0.15494)
		(layer "In15.Cu")
		(net "SSD4_PWRDIS_BIC_R")
	)
	(segment
		(start 263.358884 -212.979)
		(end 264.4394 -212.979)
		(width 0.15494)
		(layer "In15.Cu")
		(net "SSD4_PWRDIS_BIC_R")
	)
	(segment
		(start 337.92795 -205.26248)
		(end 337.071462 -204.405992)
		(width 0.15494)
		(layer "In15.Cu")
		(net "SSD4_PWRDIS_BIC_R")
	)
	(segment
		(start 324.797928 -202.919076)
		(end 271.223994 -202.919076)
		(width 0.15494)
		(layer "In15.Cu")
		(net "SSD4_PWRDIS_BIC_R")
	)
	(segment
		(start 336.01787 -203.0984)
		(end 336.01787 -201.98334)
		(width 0.15494)
		(layer "In15.Cu")
		(net "SSD4_PWRDIS_BIC_R")
	)
	(segment
		(start 336.01787 -201.98334)
		(end 335.58607 -201.55154)
		(width 0.15494)
		(layer "In15.Cu")
		(net "SSD4_PWRDIS_BIC_R")
	)
	(segment
		(start 128.705356 -171.317412)
		(end 128.387856 -170.999912)
		(width 0.1143)
		(layer "F.Cu")
		(net "CLK_100M_DB2000QL_PEX2_S1_DP")
	)
	(segment
		(start 130.53695 -174.741332)
		(end 130.5306 -174.726092)
		(width 0.1143)
		(layer "F.Cu")
		(net "CLK_100M_DB2000QL_PEX2_S1_DP")
	)
	(segment
		(start 130.5306 -173.546008)
		(end 128.705356 -171.720764)
		(width 0.1143)
		(layer "F.Cu")
		(net "CLK_100M_DB2000QL_PEX2_S1_DP")
	)
	(segment
		(start 130.471164 -174.900336)
		(end 130.53695 -174.741332)
		(width 0.1143)
		(layer "F.Cu")
		(net "CLK_100M_DB2000QL_PEX2_S1_DP")
	)
	(segment
		(start 128.705356 -171.720764)
		(end 128.705356 -171.317412)
		(width 0.1143)
		(layer "F.Cu")
		(net "CLK_100M_DB2000QL_PEX2_S1_DP")
	)
	(segment
		(start 130.5306 -174.726092)
		(end 130.5306 -173.546008)
		(width 0.1143)
		(layer "F.Cu")
		(net "CLK_100M_DB2000QL_PEX2_S1_DP")
	)
	(segment
		(start 106.639106 -88.928956)
		(end 106.639106 -89.982802)
		(width 0.13208)
		(layer "F.Cu")
		(net "PU_9ZXL0851_0_7_HBW")
	)
	(segment
		(start 105.809796 -90.812112)
		(end 105.809796 -91.349068)
		(width 0.13208)
		(layer "F.Cu")
		(net "PU_9ZXL0851_0_7_HBW")
	)
	(segment
		(start 106.639106 -89.982802)
		(end 105.809796 -90.812112)
		(width 0.13208)
		(layer "F.Cu")
		(net "PU_9ZXL0851_0_7_HBW")
	)
	(segment
		(start 104.728772 -91.966796)
		(end 105.744772 -91.966796)
		(width 0.13208)
		(layer "F.Cu")
		(net "PU_9ZXL0851_0_7_HBW")
	)
	(segment
		(start 105.809796 -91.349068)
		(end 105.744772 -91.414092)
		(width 0.13208)
		(layer "F.Cu")
		(net "PU_9ZXL0851_0_7_HBW")
	)
	(segment
		(start 105.744772 -91.414092)
		(end 105.744772 -91.966796)
		(width 0.13208)
		(layer "F.Cu")
		(net "PU_9ZXL0851_0_7_HBW")
	)
	(via
		(at 105.809796 -90.812112)
		(size 0.508)
		(drill 0.254)
		(layers "F.Cu" "B.Cu")
		(net "PU_9ZXL0851_0_7_HBW")
	)
	(segment
		(start 153.650442 -251.158502)
		(end 153.650442 -250.470924)
		(width 0.13208)
		(layer "F.Cu")
		(net "PEX1_MODE_SEL10")
	)
	(segment
		(start 153.650442 -251.956824)
		(end 153.650442 -251.158502)
		(width 0.13208)
		(layer "F.Cu")
		(net "PEX1_MODE_SEL10")
	)
	(segment
		(start 182.39994 -283.549852)
		(end 182.87492 -284.024832)
		(width 0.13208)
		(layer "F.Cu")
		(net "PEX1_MODE_SEL10")
	)
	(via
		(at 153.650442 -251.158502)
		(size 0.508)
		(drill 0.254)
		(layers "F.Cu" "B.Cu")
		(net "PEX1_MODE_SEL10")
	)
	(via
		(at 183.59628 -270.410432)
		(size 0.6604)
		(drill 0.3302)
		(layers "F.Cu" "B.Cu")
		(net "PEX1_MODE_SEL10")
	)
	(via
		(at 182.87492 -284.024832)
		(size 0.4064)
		(drill 0.2032)
		(layers "F.Cu" "B.Cu")
		(net "PEX1_MODE_SEL10")
	)
	(segment
		(start 184.911238 -282.601416)
		(end 184.531508 -282.601416)
		(width 0.13208)
		(layer "B.Cu")
		(net "PEX1_MODE_SEL10")
	)
	(segment
		(start 168.024048 -254.8382)
		(end 153.990548 -254.8382)
		(width 0.13208)
		(layer "B.Cu")
		(net "PEX1_MODE_SEL10")
	)
	(segment
		(start 183.649112 -283.553408)
		(end 183.177688 -284.024832)
		(width 0.13208)
		(layer "B.Cu")
		(net "PEX1_MODE_SEL10")
	)
	(segment
		(start 183.59628 -270.410432)
		(end 168.024048 -254.8382)
		(width 0.13208)
		(layer "B.Cu")
		(net "PEX1_MODE_SEL10")
	)
	(segment
		(start 183.59628 -270.410432)
		(end 184.737248 -271.5514)
		(width 0.13208)
		(layer "B.Cu")
		(net "PEX1_MODE_SEL10")
	)
	(segment
		(start 153.990548 -254.8382)
		(end 153.133806 -253.981458)
		(width 0.13208)
		(layer "B.Cu")
		(net "PEX1_MODE_SEL10")
	)
	(segment
		(start 184.158382 -283.553408)
		(end 183.649112 -283.553408)
		(width 0.13208)
		(layer "B.Cu")
		(net "PEX1_MODE_SEL10")
	)
	(segment
		(start 184.304686 -282.828238)
		(end 184.304686 -283.407104)
		(width 0.13208)
		(layer "B.Cu")
		(net "PEX1_MODE_SEL10")
	)
	(segment
		(start 153.133806 -251.675138)
		(end 153.650442 -251.158502)
		(width 0.13208)
		(layer "B.Cu")
		(net "PEX1_MODE_SEL10")
	)
	(segment
		(start 153.133806 -253.981458)
		(end 153.133806 -251.675138)
		(width 0.13208)
		(layer "B.Cu")
		(net "PEX1_MODE_SEL10")
	)
	(segment
		(start 183.177688 -284.024832)
		(end 182.87492 -284.024832)
		(width 0.13208)
		(layer "B.Cu")
		(net "PEX1_MODE_SEL10")
	)
	(segment
		(start 185.742834 -281.76982)
		(end 184.911238 -282.601416)
		(width 0.13208)
		(layer "B.Cu")
		(net "PEX1_MODE_SEL10")
	)
	(segment
		(start 184.737248 -271.5514)
		(end 185.467752 -271.5514)
		(width 0.13208)
		(layer "B.Cu")
		(net "PEX1_MODE_SEL10")
	)
	(segment
		(start 185.467752 -271.5514)
		(end 185.742834 -271.826482)
		(width 0.13208)
		(layer "B.Cu")
		(net "PEX1_MODE_SEL10")
	)
	(segment
		(start 184.304686 -283.407104)
		(end 184.158382 -283.553408)
		(width 0.13208)
		(layer "B.Cu")
		(net "PEX1_MODE_SEL10")
	)
	(segment
		(start 185.742834 -271.826482)
		(end 185.742834 -281.76982)
		(width 0.13208)
		(layer "B.Cu")
		(net "PEX1_MODE_SEL10")
	)
	(segment
		(start 184.531508 -282.601416)
		(end 184.304686 -282.828238)
		(width 0.13208)
		(layer "B.Cu")
		(net "PEX1_MODE_SEL10")
	)
	(segment
		(start 403.199854 -308.249828)
		(end 402.724874 -307.774848)
		(width 0.13208)
		(layer "F.Cu")
		(net "TP_PEX3_TMS")
	)
	(via
		(at 402.249894 -307.299868)
		(size 0.6604)
		(drill 0.3302)
		(layers "F.Cu" "B.Cu")
		(net "TP_PEX3_TMS")
	)
	(via
		(at 402.724874 -307.774848)
		(size 0.4064)
		(drill 0.2032)
		(layers "F.Cu" "B.Cu")
		(net "TP_PEX3_TMS")
	)
	(segment
		(start 402.724874 -307.774848)
		(end 402.249894 -307.299868)
		(width 0.13208)
		(layer "B.Cu")
		(net "TP_PEX3_TMS")
	)
	(segment
		(start 360.280204 -200.290684)
		(end 363.337094 -200.290684)
		(width 0.13208)
		(layer "F.Cu")
		(net "SSD4_PEX_PWR_EN_R")
	)
	(segment
		(start 347.693742 -211.18703)
		(end 348.093538 -210.787234)
		(width 0.13208)
		(layer "F.Cu")
		(net "SSD4_PEX_PWR_EN_R")
	)
	(segment
		(start 365.10595 -199.771)
		(end 363.87405 -199.771)
		(width 0.13208)
		(layer "F.Cu")
		(net "SSD4_PEX_PWR_EN_R")
	)
	(segment
		(start 359.307638 -201.26325)
		(end 360.280204 -200.290684)
		(width 0.13208)
		(layer "F.Cu")
		(net "SSD4_PEX_PWR_EN_R")
	)
	(segment
		(start 363.87405 -199.771)
		(end 363.87405 -200.787)
		(width 0.13208)
		(layer "F.Cu")
		(net "SSD4_PEX_PWR_EN_R")
	)
	(segment
		(start 363.337094 -200.290684)
		(end 363.83341 -200.787)
		(width 0.13208)
		(layer "F.Cu")
		(net "SSD4_PEX_PWR_EN_R")
	)
	(segment
		(start 363.83341 -200.787)
		(end 363.87405 -200.787)
		(width 0.13208)
		(layer "F.Cu")
		(net "SSD4_PEX_PWR_EN_R")
	)
	(via
		(at 348.093538 -210.787234)
		(size 0.4572)
		(drill 0.254)
		(layers "F.Cu" "B.Cu")
		(net "SSD4_PEX_PWR_EN_R")
	)
	(via
		(at 359.307638 -201.26325)
		(size 0.508)
		(drill 0.254)
		(layers "F.Cu" "B.Cu")
		(net "SSD4_PEX_PWR_EN_R")
	)
	(segment
		(start 355.449632 -205.687168)
		(end 353.193604 -205.687168)
		(width 0.15494)
		(layer "In5.Cu")
		(net "SSD4_PEX_PWR_EN_R")
	)
	(segment
		(start 359.307638 -201.26325)
		(end 359.307638 -204.419962)
		(width 0.15494)
		(layer "In5.Cu")
		(net "SSD4_PEX_PWR_EN_R")
	)
	(segment
		(start 359.307638 -204.419962)
		(end 358.6988 -205.0288)
		(width 0.15494)
		(layer "In5.Cu")
		(net "SSD4_PEX_PWR_EN_R")
	)
	(segment
		(start 353.193604 -205.687168)
		(end 348.093538 -210.787234)
		(width 0.15494)
		(layer "In5.Cu")
		(net "SSD4_PEX_PWR_EN_R")
	)
	(segment
		(start 356.108 -205.0288)
		(end 355.449632 -205.687168)
		(width 0.15494)
		(layer "In5.Cu")
		(net "SSD4_PEX_PWR_EN_R")
	)
	(segment
		(start 358.6988 -205.0288)
		(end 356.108 -205.0288)
		(width 0.15494)
		(layer "In5.Cu")
		(net "SSD4_PEX_PWR_EN_R")
	)
	(segment
		(start 59.649868 -282.599892)
		(end 60.124848 -283.074872)
		(width 0.1651)
		(layer "F.Cu")
		(net "PEX0_MODE_SEL5")
	)
	(segment
		(start 27.390344 -251.956824)
		(end 27.390344 -251.158502)
		(width 0.13208)
		(layer "F.Cu")
		(net "PEX0_MODE_SEL5")
	)
	(segment
		(start 27.390344 -251.158502)
		(end 27.390344 -250.470924)
		(width 0.13208)
		(layer "F.Cu")
		(net "PEX0_MODE_SEL5")
	)
	(via
		(at 56.938926 -268.21765)
		(size 0.6604)
		(drill 0.3302)
		(layers "F.Cu" "B.Cu")
		(net "PEX0_MODE_SEL5")
	)
	(via
		(at 27.390344 -251.158502)
		(size 0.508)
		(drill 0.254)
		(layers "F.Cu" "B.Cu")
		(net "PEX0_MODE_SEL5")
	)
	(via
		(at 60.124848 -283.074872)
		(size 0.4064)
		(drill 0.2032)
		(layers "F.Cu" "B.Cu")
		(net "PEX0_MODE_SEL5")
	)
	(segment
		(start 27.4828 -256.967482)
		(end 28.019756 -257.504438)
		(width 0.13208)
		(layer "B.Cu")
		(net "PEX0_MODE_SEL5")
	)
	(segment
		(start 31.1658 -257.4036)
		(end 33.1343 -259.3721)
		(width 0.13208)
		(layer "B.Cu")
		(net "PEX0_MODE_SEL5")
	)
	(segment
		(start 27.4828 -255.922018)
		(end 27.4828 -256.967482)
		(width 0.13208)
		(layer "B.Cu")
		(net "PEX0_MODE_SEL5")
	)
	(segment
		(start 26.897584 -251.651262)
		(end 26.897584 -255.336802)
		(width 0.13208)
		(layer "B.Cu")
		(net "PEX0_MODE_SEL5")
	)
	(segment
		(start 33.1343 -260.5913)
		(end 34.1376 -261.5946)
		(width 0.13208)
		(layer "B.Cu")
		(net "PEX0_MODE_SEL5")
	)
	(segment
		(start 34.1376 -261.5946)
		(end 50.315876 -261.5946)
		(width 0.13208)
		(layer "B.Cu")
		(net "PEX0_MODE_SEL5")
	)
	(segment
		(start 33.1343 -259.3721)
		(end 33.1343 -260.5913)
		(width 0.13208)
		(layer "B.Cu")
		(net "PEX0_MODE_SEL5")
	)
	(segment
		(start 60.124848 -283.074872)
		(end 60.124848 -271.403572)
		(width 0.13208)
		(layer "B.Cu")
		(net "PEX0_MODE_SEL5")
	)
	(segment
		(start 28.019756 -257.504438)
		(end 28.829 -257.504438)
		(width 0.13208)
		(layer "B.Cu")
		(net "PEX0_MODE_SEL5")
	)
	(segment
		(start 28.929838 -257.4036)
		(end 31.1658 -257.4036)
		(width 0.13208)
		(layer "B.Cu")
		(net "PEX0_MODE_SEL5")
	)
	(segment
		(start 60.124848 -271.403572)
		(end 56.938926 -268.21765)
		(width 0.13208)
		(layer "B.Cu")
		(net "PEX0_MODE_SEL5")
	)
	(segment
		(start 50.315876 -261.5946)
		(end 56.938926 -268.21765)
		(width 0.13208)
		(layer "B.Cu")
		(net "PEX0_MODE_SEL5")
	)
	(segment
		(start 28.829 -257.504438)
		(end 28.929838 -257.4036)
		(width 0.13208)
		(layer "B.Cu")
		(net "PEX0_MODE_SEL5")
	)
	(segment
		(start 26.897584 -255.336802)
		(end 27.4828 -255.922018)
		(width 0.13208)
		(layer "B.Cu")
		(net "PEX0_MODE_SEL5")
	)
	(segment
		(start 27.390344 -251.158502)
		(end 26.897584 -251.651262)
		(width 0.13208)
		(layer "B.Cu")
		(net "PEX0_MODE_SEL5")
	)
	(segment
		(start 164.349938 -309.199788)
		(end 164.824918 -308.724808)
		(width 0.13208)
		(layer "F.Cu")
		(net "PEX1_DBG_MODE1")
	)
	(segment
		(start 150.922482 -309.820564)
		(end 149.518624 -308.416706)
		(width 0.13208)
		(layer "F.Cu")
		(net "PEX1_DBG_MODE1")
	)
	(segment
		(start 150.236936 -307.698394)
		(end 150.23719 -307.698394)
		(width 0.13208)
		(layer "F.Cu")
		(net "PEX1_DBG_MODE1")
	)
	(segment
		(start 150.922482 -309.897272)
		(end 150.922482 -309.820564)
		(width 0.13208)
		(layer "F.Cu")
		(net "PEX1_DBG_MODE1")
	)
	(segment
		(start 149.518624 -308.416706)
		(end 150.236936 -307.698394)
		(width 0.13208)
		(layer "F.Cu")
		(net "PEX1_DBG_MODE1")
	)
	(via
		(at 164.824918 -308.724808)
		(size 0.4064)
		(drill 0.2032)
		(layers "F.Cu" "B.Cu")
		(net "PEX1_DBG_MODE1")
	)
	(via
		(at 150.922482 -309.897272)
		(size 0.508)
		(drill 0.254)
		(layers "F.Cu" "B.Cu")
		(net "PEX1_DBG_MODE1")
	)
	(segment
		(start 161.8234 -309.7022)
		(end 151.117554 -309.7022)
		(width 0.13208)
		(layer "B.Cu")
		(net "PEX1_DBG_MODE1")
	)
	(segment
		(start 164.824918 -308.724808)
		(end 164.333428 -309.216298)
		(width 0.13208)
		(layer "B.Cu")
		(net "PEX1_DBG_MODE1")
	)
	(segment
		(start 151.117554 -309.7022)
		(end 150.922482 -309.897272)
		(width 0.13208)
		(layer "B.Cu")
		(net "PEX1_DBG_MODE1")
	)
	(segment
		(start 162.309302 -309.216298)
		(end 161.8234 -309.7022)
		(width 0.13208)
		(layer "B.Cu")
		(net "PEX1_DBG_MODE1")
	)
	(segment
		(start 164.333428 -309.216298)
		(end 162.309302 -309.216298)
		(width 0.13208)
		(layer "B.Cu")
		(net "PEX1_DBG_MODE1")
	)
	(segment
		(start 437.30164 -305.091846)
		(end 437.30164 -304.436526)
		(width 0.13208)
		(layer "F.Cu")
		(net "PEX3_SPARE4")
	)
	(segment
		(start 437.302148 -305.092354)
		(end 437.30164 -305.091846)
		(width 0.13208)
		(layer "F.Cu")
		(net "PEX3_SPARE4")
	)
	(segment
		(start 437.302148 -305.064922)
		(end 437.302148 -305.092354)
		(width 0.13208)
		(layer "F.Cu")
		(net "PEX3_SPARE4")
	)
	(segment
		(start 437.302148 -305.092354)
		(end 437.302148 -305.674522)
		(width 0.13208)
		(layer "F.Cu")
		(net "PEX3_SPARE4")
	)
	(segment
		(start 408.424888 -307.774848)
		(end 407.949908 -308.249828)
		(width 0.13462)
		(layer "F.Cu")
		(net "PEX3_SPARE4")
	)
	(via
		(at 436.221124 -303.683162)
		(size 0.6604)
		(drill 0.3302)
		(layers "F.Cu" "B.Cu")
		(net "PEX3_SPARE4")
	)
	(via
		(at 408.424888 -307.774848)
		(size 0.4064)
		(drill 0.2032)
		(layers "F.Cu" "B.Cu")
		(net "PEX3_SPARE4")
	)
	(via
		(at 437.302148 -305.064922)
		(size 0.508)
		(drill 0.254)
		(layers "F.Cu" "B.Cu")
		(net "PEX3_SPARE4")
	)
	(segment
		(start 436.755032 -303.544986)
		(end 436.3593 -303.544986)
		(width 0.13208)
		(layer "B.Cu")
		(net "PEX3_SPARE4")
	)
	(segment
		(start 421.947848 -307.2892)
		(end 420.53764 -307.2892)
		(width 0.13208)
		(layer "B.Cu")
		(net "PEX3_SPARE4")
	)
	(segment
		(start 420.299134 -307.967126)
		(end 420.02964 -308.23662)
		(width 0.13208)
		(layer "B.Cu")
		(net "PEX3_SPARE4")
	)
	(segment
		(start 437.302148 -305.064922)
		(end 437.302148 -304.092102)
		(width 0.13208)
		(layer "B.Cu")
		(net "PEX3_SPARE4")
	)
	(segment
		(start 435.842918 -304.061368)
		(end 435.842918 -304.125122)
		(width 0.13208)
		(layer "B.Cu")
		(net "PEX3_SPARE4")
	)
	(segment
		(start 435.842918 -304.125122)
		(end 433.490116 -306.477924)
		(width 0.13208)
		(layer "B.Cu")
		(net "PEX3_SPARE4")
	)
	(segment
		(start 408.88666 -308.23662)
		(end 408.424888 -307.774848)
		(width 0.13208)
		(layer "B.Cu")
		(net "PEX3_SPARE4")
	)
	(segment
		(start 436.3593 -303.544986)
		(end 436.221124 -303.683162)
		(width 0.13208)
		(layer "B.Cu")
		(net "PEX3_SPARE4")
	)
	(segment
		(start 420.299134 -307.527706)
		(end 420.299134 -307.967126)
		(width 0.13208)
		(layer "B.Cu")
		(net "PEX3_SPARE4")
	)
	(segment
		(start 433.490116 -306.477924)
		(end 432.694842 -306.807362)
		(width 0.13208)
		(layer "B.Cu")
		(net "PEX3_SPARE4")
	)
	(segment
		(start 437.302148 -304.092102)
		(end 436.755032 -303.544986)
		(width 0.13208)
		(layer "B.Cu")
		(net "PEX3_SPARE4")
	)
	(segment
		(start 420.02964 -308.23662)
		(end 408.88666 -308.23662)
		(width 0.13208)
		(layer "B.Cu")
		(net "PEX3_SPARE4")
	)
	(segment
		(start 436.221124 -303.683162)
		(end 435.842918 -304.061368)
		(width 0.13208)
		(layer "B.Cu")
		(net "PEX3_SPARE4")
	)
	(segment
		(start 420.53764 -307.2892)
		(end 420.299134 -307.527706)
		(width 0.13208)
		(layer "B.Cu")
		(net "PEX3_SPARE4")
	)
	(segment
		(start 422.429686 -306.807362)
		(end 421.947848 -307.2892)
		(width 0.13208)
		(layer "B.Cu")
		(net "PEX3_SPARE4")
	)
	(segment
		(start 432.694842 -306.807362)
		(end 422.429686 -306.807362)
		(width 0.13208)
		(layer "B.Cu")
		(net "PEX3_SPARE4")
	)
	(segment
		(start 335.896458 -250.381008)
		(end 342.886792 -243.390674)
		(width 0.13208)
		(layer "F.Cu")
		(net "RST_SSD0_PERST_R_N")
	)
	(segment
		(start 14.203934 -24.189944)
		(end 15.264892 -24.189944)
		(width 0.13208)
		(layer "F.Cu")
		(net "RST_SSD0_PERST_R_N")
	)
	(segment
		(start 342.886792 -243.390674)
		(end 342.886792 -241.091212)
		(width 0.13208)
		(layer "F.Cu")
		(net "RST_SSD0_PERST_R_N")
	)
	(segment
		(start 335.896458 -251.008134)
		(end 335.896458 -250.381008)
		(width 0.13208)
		(layer "F.Cu")
		(net "RST_SSD0_PERST_R_N")
	)
	(via
		(at 34.762948 -217.739976)
		(size 0.508)
		(drill 0.254)
		(layers "F.Cu" "B.Cu")
		(net "RST_SSD0_PERST_R_N")
	)
	(via
		(at 335.896458 -251.008134)
		(size 0.508)
		(drill 0.254)
		(layers "F.Cu" "B.Cu")
		(net "RST_SSD0_PERST_R_N")
	)
	(via
		(at 14.203934 -24.189944)
		(size 0.508)
		(drill 0.254)
		(layers "F.Cu" "B.Cu")
		(net "RST_SSD0_PERST_R_N")
	)
	(segment
		(start 25.718516 -28.293822)
		(end 25.718516 -33.913572)
		(width 0.15494)
		(layer "In5.Cu")
		(net "RST_SSD0_PERST_R_N")
	)
	(segment
		(start 27.375104 -166.626032)
		(end 27.375104 -191.73825)
		(width 0.15494)
		(layer "In5.Cu")
		(net "RST_SSD0_PERST_R_N")
	)
	(segment
		(start 30.353 -96.976946)
		(end 30.353 -97.790254)
		(width 0.15494)
		(layer "In5.Cu")
		(net "RST_SSD0_PERST_R_N")
	)
	(segment
		(start 26.939748 -165.57498)
		(end 27.375104 -166.626032)
		(width 0.15494)
		(layer "In5.Cu")
		(net "RST_SSD0_PERST_R_N")
	)
	(segment
		(start 32.57804 -204.143102)
		(end 32.57804 -215.555068)
		(width 0.15494)
		(layer "In5.Cu")
		(net "RST_SSD0_PERST_R_N")
	)
	(segment
		(start 14.203934 -24.189944)
		(end 15.287752 -23.106126)
		(width 0.15494)
		(layer "In5.Cu")
		(net "RST_SSD0_PERST_R_N")
	)
	(segment
		(start 30.353 -97.790254)
		(end 26.939748 -101.203506)
		(width 0.15494)
		(layer "In5.Cu")
		(net "RST_SSD0_PERST_R_N")
	)
	(segment
		(start 15.287752 -23.106126)
		(end 20.53082 -23.106126)
		(width 0.15494)
		(layer "In5.Cu")
		(net "RST_SSD0_PERST_R_N")
	)
	(segment
		(start 26.939748 -101.203506)
		(end 26.939748 -165.57498)
		(width 0.15494)
		(layer "In5.Cu")
		(net "RST_SSD0_PERST_R_N")
	)
	(segment
		(start 20.53082 -23.106126)
		(end 25.718516 -28.293822)
		(width 0.15494)
		(layer "In5.Cu")
		(net "RST_SSD0_PERST_R_N")
	)
	(segment
		(start 37.9603 -46.155356)
		(end 37.9603 -89.369646)
		(width 0.15494)
		(layer "In5.Cu")
		(net "RST_SSD0_PERST_R_N")
	)
	(segment
		(start 27.375104 -191.73825)
		(end 31.750508 -196.113654)
		(width 0.15494)
		(layer "In5.Cu")
		(net "RST_SSD0_PERST_R_N")
	)
	(segment
		(start 25.718516 -33.913572)
		(end 37.9603 -46.155356)
		(width 0.15494)
		(layer "In5.Cu")
		(net "RST_SSD0_PERST_R_N")
	)
	(segment
		(start 31.750508 -196.113654)
		(end 31.750508 -203.31557)
		(width 0.15494)
		(layer "In5.Cu")
		(net "RST_SSD0_PERST_R_N")
	)
	(segment
		(start 37.9603 -89.369646)
		(end 30.353 -96.976946)
		(width 0.15494)
		(layer "In5.Cu")
		(net "RST_SSD0_PERST_R_N")
	)
	(segment
		(start 32.57804 -215.555068)
		(end 34.762948 -217.739976)
		(width 0.15494)
		(layer "In5.Cu")
		(net "RST_SSD0_PERST_R_N")
	)
	(segment
		(start 31.750508 -203.31557)
		(end 32.57804 -204.143102)
		(width 0.15494)
		(layer "In5.Cu")
		(net "RST_SSD0_PERST_R_N")
	)
	(segment
		(start 246.763032 -250.674632)
		(end 257.758946 -250.674632)
		(width 0.15494)
		(layer "In15.Cu")
		(net "RST_SSD0_PERST_R_N")
	)
	(segment
		(start 257.758946 -250.674632)
		(end 258.042156 -250.957842)
		(width 0.15494)
		(layer "In15.Cu")
		(net "RST_SSD0_PERST_R_N")
	)
	(segment
		(start 130.404108 -237.53699)
		(end 139.247626 -237.53699)
		(width 0.15494)
		(layer "In15.Cu")
		(net "RST_SSD0_PERST_R_N")
	)
	(segment
		(start 335.896458 -251.678186)
		(end 335.896458 -251.008134)
		(width 0.15494)
		(layer "In15.Cu")
		(net "RST_SSD0_PERST_R_N")
	)
	(segment
		(start 258.042156 -251.310902)
		(end 258.394454 -251.6632)
		(width 0.15494)
		(layer "In15.Cu")
		(net "RST_SSD0_PERST_R_N")
	)
	(segment
		(start 246.487696 -250.402344)
		(end 246.761508 -250.676156)
		(width 0.15494)
		(layer "In15.Cu")
		(net "RST_SSD0_PERST_R_N")
	)
	(segment
		(start 304.579782 -252.476254)
		(end 325.817738 -252.476254)
		(width 0.15494)
		(layer "In15.Cu")
		(net "RST_SSD0_PERST_R_N")
	)
	(segment
		(start 112.56264 -233.11231)
		(end 119.461788 -240.011458)
		(width 0.15494)
		(layer "In15.Cu")
		(net "RST_SSD0_PERST_R_N")
	)
	(segment
		(start 258.042156 -250.957842)
		(end 258.042156 -251.310902)
		(width 0.15494)
		(layer "In15.Cu")
		(net "RST_SSD0_PERST_R_N")
	)
	(segment
		(start 37.626798 -214.876126)
		(end 70.291706 -214.876126)
		(width 0.15494)
		(layer "In15.Cu")
		(net "RST_SSD0_PERST_R_N")
	)
	(segment
		(start 152.410414 -235.0389)
		(end 153.587958 -235.52658)
		(width 0.15494)
		(layer "In15.Cu")
		(net "RST_SSD0_PERST_R_N")
	)
	(segment
		(start 326.89927 -253.557786)
		(end 334.016858 -253.557786)
		(width 0.15494)
		(layer "In15.Cu")
		(net "RST_SSD0_PERST_R_N")
	)
	(segment
		(start 34.762948 -217.739976)
		(end 37.626798 -214.876126)
		(width 0.15494)
		(layer "In15.Cu")
		(net "RST_SSD0_PERST_R_N")
	)
	(segment
		(start 149.598634 -234.3277)
		(end 151.316436 -235.0389)
		(width 0.15494)
		(layer "In15.Cu")
		(net "RST_SSD0_PERST_R_N")
	)
	(segment
		(start 258.394454 -251.6632)
		(end 273.337274 -251.6632)
		(width 0.15494)
		(layer "In15.Cu")
		(net "RST_SSD0_PERST_R_N")
	)
	(segment
		(start 304.410872 -252.645164)
		(end 304.579782 -252.476254)
		(width 0.15494)
		(layer "In15.Cu")
		(net "RST_SSD0_PERST_R_N")
	)
	(segment
		(start 75.49642 -209.671412)
		(end 109.034834 -209.671412)
		(width 0.15494)
		(layer "In15.Cu")
		(net "RST_SSD0_PERST_R_N")
	)
	(segment
		(start 239.351058 -250.762262)
		(end 239.710976 -250.402344)
		(width 0.15494)
		(layer "In15.Cu")
		(net "RST_SSD0_PERST_R_N")
	)
	(segment
		(start 224.026476 -249.95124)
		(end 224.457006 -249.52071)
		(width 0.15494)
		(layer "In15.Cu")
		(net "RST_SSD0_PERST_R_N")
	)
	(segment
		(start 274.319238 -252.645164)
		(end 304.410872 -252.645164)
		(width 0.15494)
		(layer "In15.Cu")
		(net "RST_SSD0_PERST_R_N")
	)
	(segment
		(start 189.239144 -249.06224)
		(end 190.128144 -249.95124)
		(width 0.15494)
		(layer "In15.Cu")
		(net "RST_SSD0_PERST_R_N")
	)
	(segment
		(start 112.56264 -213.199218)
		(end 112.56264 -233.11231)
		(width 0.15494)
		(layer "In15.Cu")
		(net "RST_SSD0_PERST_R_N")
	)
	(segment
		(start 239.710976 -250.402344)
		(end 246.487696 -250.402344)
		(width 0.15494)
		(layer "In15.Cu")
		(net "RST_SSD0_PERST_R_N")
	)
	(segment
		(start 224.457006 -249.52071)
		(end 229.30993 -249.52071)
		(width 0.15494)
		(layer "In15.Cu")
		(net "RST_SSD0_PERST_R_N")
	)
	(segment
		(start 154.684984 -235.52658)
		(end 160.160208 -241.001804)
		(width 0.15494)
		(layer "In15.Cu")
		(net "RST_SSD0_PERST_R_N")
	)
	(segment
		(start 119.461788 -240.011458)
		(end 127.92964 -240.011458)
		(width 0.15494)
		(layer "In15.Cu")
		(net "RST_SSD0_PERST_R_N")
	)
	(segment
		(start 109.034834 -209.671412)
		(end 112.56264 -213.199218)
		(width 0.15494)
		(layer "In15.Cu")
		(net "RST_SSD0_PERST_R_N")
	)
	(segment
		(start 179.431696 -241.001804)
		(end 187.492132 -249.06224)
		(width 0.15494)
		(layer "In15.Cu")
		(net "RST_SSD0_PERST_R_N")
	)
	(segment
		(start 334.016858 -253.557786)
		(end 335.896458 -251.678186)
		(width 0.15494)
		(layer "In15.Cu")
		(net "RST_SSD0_PERST_R_N")
	)
	(segment
		(start 160.160208 -241.001804)
		(end 179.431696 -241.001804)
		(width 0.15494)
		(layer "In15.Cu")
		(net "RST_SSD0_PERST_R_N")
	)
	(segment
		(start 229.30993 -249.52071)
		(end 230.551482 -250.762262)
		(width 0.15494)
		(layer "In15.Cu")
		(net "RST_SSD0_PERST_R_N")
	)
	(segment
		(start 127.92964 -240.011458)
		(end 130.404108 -237.53699)
		(width 0.15494)
		(layer "In15.Cu")
		(net "RST_SSD0_PERST_R_N")
	)
	(segment
		(start 153.587958 -235.52658)
		(end 154.684984 -235.52658)
		(width 0.15494)
		(layer "In15.Cu")
		(net "RST_SSD0_PERST_R_N")
	)
	(segment
		(start 273.337274 -251.6632)
		(end 274.319238 -252.645164)
		(width 0.15494)
		(layer "In15.Cu")
		(net "RST_SSD0_PERST_R_N")
	)
	(segment
		(start 151.316436 -235.0389)
		(end 152.410414 -235.0389)
		(width 0.15494)
		(layer "In15.Cu")
		(net "RST_SSD0_PERST_R_N")
	)
	(segment
		(start 190.128144 -249.95124)
		(end 224.026476 -249.95124)
		(width 0.15494)
		(layer "In15.Cu")
		(net "RST_SSD0_PERST_R_N")
	)
	(segment
		(start 187.492132 -249.06224)
		(end 189.239144 -249.06224)
		(width 0.15494)
		(layer "In15.Cu")
		(net "RST_SSD0_PERST_R_N")
	)
	(segment
		(start 325.817738 -252.476254)
		(end 326.89927 -253.557786)
		(width 0.15494)
		(layer "In15.Cu")
		(net "RST_SSD0_PERST_R_N")
	)
	(segment
		(start 139.247626 -237.53699)
		(end 142.456916 -234.3277)
		(width 0.15494)
		(layer "In15.Cu")
		(net "RST_SSD0_PERST_R_N")
	)
	(segment
		(start 230.551482 -250.762262)
		(end 239.351058 -250.762262)
		(width 0.15494)
		(layer "In15.Cu")
		(net "RST_SSD0_PERST_R_N")
	)
	(segment
		(start 70.291706 -214.876126)
		(end 75.49642 -209.671412)
		(width 0.15494)
		(layer "In15.Cu")
		(net "RST_SSD0_PERST_R_N")
	)
	(segment
		(start 246.761508 -250.676156)
		(end 246.763032 -250.674632)
		(width 0.15494)
		(layer "In15.Cu")
		(net "RST_SSD0_PERST_R_N")
	)
	(segment
		(start 142.456916 -234.3277)
		(end 149.598634 -234.3277)
		(width 0.15494)
		(layer "In15.Cu")
		(net "RST_SSD0_PERST_R_N")
	)
	(segment
		(start 359.55605 -185.166)
		(end 360.172 -185.166)
		(width 0.13208)
		(layer "F.Cu")
		(net "SSD3_PEX_PWR_EN_R")
	)
	(segment
		(start 360.172 -185.166)
		(end 360.78795 -185.166)
		(width 0.13208)
		(layer "F.Cu")
		(net "SSD3_PEX_PWR_EN_R")
	)
	(segment
		(start 345.29395 -215.187022)
		(end 345.693746 -214.787226)
		(width 0.13208)
		(layer "F.Cu")
		(net "SSD3_PEX_PWR_EN_R")
	)
	(segment
		(start 359.55605 -186.182)
		(end 359.55605 -185.166)
		(width 0.13208)
		(layer "F.Cu")
		(net "SSD3_PEX_PWR_EN_R")
	)
	(via
		(at 345.693746 -214.787226)
		(size 0.4572)
		(drill 0.254)
		(layers "F.Cu" "B.Cu")
		(net "SSD3_PEX_PWR_EN_R")
	)
	(via
		(at 360.172 -185.166)
		(size 0.508)
		(drill 0.254)
		(layers "F.Cu" "B.Cu")
		(net "SSD3_PEX_PWR_EN_R")
	)
	(segment
		(start 346.6846 -209.0166)
		(end 345.743276 -209.957924)
		(width 0.15494)
		(layer "In7.Cu")
		(net "SSD3_PEX_PWR_EN_R")
	)
	(segment
		(start 350.952054 -203.581)
		(end 350.689926 -203.581)
		(width 0.15494)
		(layer "In7.Cu")
		(net "SSD3_PEX_PWR_EN_R")
	)
	(segment
		(start 359.351072 -185.986928)
		(end 359.351072 -193.598292)
		(width 0.15494)
		(layer "In7.Cu")
		(net "SSD3_PEX_PWR_EN_R")
	)
	(segment
		(start 360.172 -185.166)
		(end 359.351072 -185.986928)
		(width 0.15494)
		(layer "In7.Cu")
		(net "SSD3_PEX_PWR_EN_R")
	)
	(segment
		(start 345.293696 -214.387176)
		(end 345.693746 -214.787226)
		(width 0.0889)
		(layer "In7.Cu")
		(net "SSD3_PEX_PWR_EN_R")
	)
	(segment
		(start 350.689926 -203.581)
		(end 350.141032 -204.129894)
		(width 0.15494)
		(layer "In7.Cu")
		(net "SSD3_PEX_PWR_EN_R")
	)
	(segment
		(start 359.351072 -193.598292)
		(end 357.378 -195.571364)
		(width 0.15494)
		(layer "In7.Cu")
		(net "SSD3_PEX_PWR_EN_R")
	)
	(segment
		(start 350.141032 -206.55407)
		(end 347.678502 -209.0166)
		(width 0.15494)
		(layer "In7.Cu")
		(net "SSD3_PEX_PWR_EN_R")
	)
	(segment
		(start 350.141032 -204.129894)
		(end 350.141032 -206.55407)
		(width 0.15494)
		(layer "In7.Cu")
		(net "SSD3_PEX_PWR_EN_R")
	)
	(segment
		(start 347.678502 -209.0166)
		(end 346.6846 -209.0166)
		(width 0.15494)
		(layer "In7.Cu")
		(net "SSD3_PEX_PWR_EN_R")
	)
	(segment
		(start 345.293696 -212.1154)
		(end 345.293696 -214.387176)
		(width 0.0889)
		(layer "In7.Cu")
		(net "SSD3_PEX_PWR_EN_R")
	)
	(segment
		(start 357.378 -197.155054)
		(end 350.952054 -203.581)
		(width 0.15494)
		(layer "In7.Cu")
		(net "SSD3_PEX_PWR_EN_R")
	)
	(segment
		(start 345.743276 -211.456524)
		(end 345.293696 -211.906104)
		(width 0.15494)
		(layer "In7.Cu")
		(net "SSD3_PEX_PWR_EN_R")
	)
	(segment
		(start 357.378 -195.571364)
		(end 357.378 -197.155054)
		(width 0.15494)
		(layer "In7.Cu")
		(net "SSD3_PEX_PWR_EN_R")
	)
	(segment
		(start 345.293696 -211.906104)
		(end 345.293696 -212.1154)
		(width 0.15494)
		(layer "In7.Cu")
		(net "SSD3_PEX_PWR_EN_R")
	)
	(segment
		(start 345.743276 -209.957924)
		(end 345.743276 -211.456524)
		(width 0.15494)
		(layer "In7.Cu")
		(net "SSD3_PEX_PWR_EN_R")
	)
	(segment
		(start 319.39484 -58.453782)
		(end 319.39484 -59.177936)
		(width 0.2032)
		(layer "F.Cu")
		(net "P3V3_SSD11_SS")
	)
	(segment
		(start 319.273174 -58.166)
		(end 319.390776 -58.449718)
		(width 0.2032)
		(layer "F.Cu")
		(net "P3V3_SSD11_SS")
	)
	(segment
		(start 318.34074 -57.16397)
		(end 318.34074 -57.233566)
		(width 0.2032)
		(layer "F.Cu")
		(net "P3V3_SSD11_SS")
	)
	(segment
		(start 319.390776 -58.449718)
		(end 319.39484 -58.453782)
		(width 0.2032)
		(layer "F.Cu")
		(net "P3V3_SSD11_SS")
	)
	(segment
		(start 318.34074 -57.233566)
		(end 319.273174 -58.166)
		(width 0.2032)
		(layer "F.Cu")
		(net "P3V3_SSD11_SS")
	)
	(via
		(at 319.390776 -58.449718)
		(size 0.508)
		(drill 0.254)
		(layers "F.Cu" "B.Cu")
		(net "P3V3_SSD11_SS")
	)
	(segment
		(start 144.506442 -251.158502)
		(end 144.506442 -250.470924)
		(width 0.13208)
		(layer "F.Cu")
		(net "PEX1_DBG_MODE3")
	)
	(segment
		(start 144.506442 -251.956824)
		(end 144.506442 -251.158502)
		(width 0.13208)
		(layer "F.Cu")
		(net "PEX1_DBG_MODE3")
	)
	(segment
		(start 176.699926 -282.599892)
		(end 177.174906 -283.074872)
		(width 0.1651)
		(layer "F.Cu")
		(net "PEX1_DBG_MODE3")
	)
	(via
		(at 144.506442 -251.158502)
		(size 0.508)
		(drill 0.254)
		(layers "F.Cu" "B.Cu")
		(net "PEX1_DBG_MODE3")
	)
	(via
		(at 177.174906 -283.074872)
		(size 0.4064)
		(drill 0.2032)
		(layers "F.Cu" "B.Cu")
		(net "PEX1_DBG_MODE3")
	)
	(segment
		(start 173.761654 -268.300454)
		(end 177.174906 -271.713706)
		(width 0.13208)
		(layer "B.Cu")
		(net "PEX1_DBG_MODE3")
	)
	(segment
		(start 143.9672 -251.697744)
		(end 143.9672 -254.381254)
		(width 0.13208)
		(layer "B.Cu")
		(net "PEX1_DBG_MODE3")
	)
	(segment
		(start 151.0284 -258.953)
		(end 151.6126 -259.5372)
		(width 0.13208)
		(layer "B.Cu")
		(net "PEX1_DBG_MODE3")
	)
	(segment
		(start 172.986954 -267.398246)
		(end 173.062646 -267.398246)
		(width 0.13208)
		(layer "B.Cu")
		(net "PEX1_DBG_MODE3")
	)
	(segment
		(start 144.506442 -251.158502)
		(end 143.9672 -251.697744)
		(width 0.13208)
		(layer "B.Cu")
		(net "PEX1_DBG_MODE3")
	)
	(segment
		(start 173.761654 -268.097254)
		(end 173.761654 -268.300454)
		(width 0.13208)
		(layer "B.Cu")
		(net "PEX1_DBG_MODE3")
	)
	(segment
		(start 177.174906 -271.713706)
		(end 177.174906 -283.074872)
		(width 0.13208)
		(layer "B.Cu")
		(net "PEX1_DBG_MODE3")
	)
	(segment
		(start 165.125908 -259.5372)
		(end 172.986954 -267.398246)
		(width 0.13208)
		(layer "B.Cu")
		(net "PEX1_DBG_MODE3")
	)
	(segment
		(start 173.062646 -267.398246)
		(end 173.761654 -268.097254)
		(width 0.13208)
		(layer "B.Cu")
		(net "PEX1_DBG_MODE3")
	)
	(segment
		(start 151.6126 -259.5372)
		(end 165.125908 -259.5372)
		(width 0.13208)
		(layer "B.Cu")
		(net "PEX1_DBG_MODE3")
	)
	(segment
		(start 148.538946 -258.953)
		(end 151.0284 -258.953)
		(width 0.13208)
		(layer "B.Cu")
		(net "PEX1_DBG_MODE3")
	)
	(segment
		(start 143.9672 -254.381254)
		(end 148.538946 -258.953)
		(width 0.13208)
		(layer "B.Cu")
		(net "PEX1_DBG_MODE3")
	)
	(segment
		(start 437.49595 -308.606444)
		(end 437.49595 -308.696106)
		(width 0.13208)
		(layer "F.Cu")
		(net "PEX3_SPARE7")
	)
	(segment
		(start 437.49595 -308.696106)
		(end 437.016144 -309.175912)
		(width 0.13208)
		(layer "F.Cu")
		(net "PEX3_SPARE7")
	)
	(segment
		(start 410.324808 -308.724808)
		(end 409.849828 -308.249828)
		(width 0.13208)
		(layer "F.Cu")
		(net "PEX3_SPARE7")
	)
	(segment
		(start 436.683658 -309.508398)
		(end 436.360316 -309.508398)
		(width 0.13208)
		(layer "F.Cu")
		(net "PEX3_SPARE7")
	)
	(segment
		(start 437.016144 -309.175912)
		(end 436.683658 -309.508398)
		(width 0.13208)
		(layer "F.Cu")
		(net "PEX3_SPARE7")
	)
	(via
		(at 436.008018 -310.184038)
		(size 0.6604)
		(drill 0.3302)
		(layers "F.Cu" "B.Cu")
		(net "PEX3_SPARE7")
	)
	(via
		(at 437.016144 -309.175912)
		(size 0.508)
		(drill 0.254)
		(layers "F.Cu" "B.Cu")
		(net "PEX3_SPARE7")
	)
	(via
		(at 410.324808 -308.724808)
		(size 0.4064)
		(drill 0.2032)
		(layers "F.Cu" "B.Cu")
		(net "PEX3_SPARE7")
	)
	(segment
		(start 412.33979 -313.54522)
		(end 432.646836 -313.54522)
		(width 0.13208)
		(layer "B.Cu")
		(net "PEX3_SPARE7")
	)
	(segment
		(start 410.324808 -308.724808)
		(end 410.620972 -308.724808)
		(width 0.13208)
		(layer "B.Cu")
		(net "PEX3_SPARE7")
	)
	(segment
		(start 412.21279 -309.90032)
		(end 412.21279 -313.41822)
		(width 0.13208)
		(layer "B.Cu")
		(net "PEX3_SPARE7")
	)
	(segment
		(start 411.475936 -309.579772)
		(end 411.892242 -309.579772)
		(width 0.13208)
		(layer "B.Cu")
		(net "PEX3_SPARE7")
	)
	(segment
		(start 411.892242 -309.579772)
		(end 412.21279 -309.90032)
		(width 0.13208)
		(layer "B.Cu")
		(net "PEX3_SPARE7")
	)
	(segment
		(start 410.620972 -308.724808)
		(end 411.475936 -309.579772)
		(width 0.13208)
		(layer "B.Cu")
		(net "PEX3_SPARE7")
	)
	(segment
		(start 436.008018 -310.184038)
		(end 437.016144 -309.175912)
		(width 0.13208)
		(layer "B.Cu")
		(net "PEX3_SPARE7")
	)
	(segment
		(start 432.646836 -313.54522)
		(end 436.008018 -310.184038)
		(width 0.13208)
		(layer "B.Cu")
		(net "PEX3_SPARE7")
	)
	(segment
		(start 412.21279 -313.41822)
		(end 412.33979 -313.54522)
		(width 0.13208)
		(layer "B.Cu")
		(net "PEX3_SPARE7")
	)
	(via
		(at 99.174046 -378.805948)
		(size 0.6604)
		(drill 0.3302)
		(layers "F.Cu" "B.Cu")
		(net "SMB_GPU_2_SCL")
	)
	(segment
		(start 99.174046 -378.805948)
		(end 90.672412 -378.805948)
		(width 0.13208)
		(layer "B.Cu")
		(net "SMB_GPU_2_SCL")
	)
	(segment
		(start 99.174046 -377.90628)
		(end 99.174046 -378.805948)
		(width 0.13208)
		(layer "B.Cu")
		(net "SMB_GPU_2_SCL")
	)
	(segment
		(start 98.655378 -377.387612)
		(end 99.174046 -377.90628)
		(width 0.13208)
		(layer "B.Cu")
		(net "SMB_GPU_2_SCL")
	)
	(segment
		(start 89.888314 -379.590046)
		(end 89.509854 -379.590046)
		(width 0.13208)
		(layer "B.Cu")
		(net "SMB_GPU_2_SCL")
	)
	(segment
		(start 90.672412 -378.805948)
		(end 89.888314 -379.590046)
		(width 0.13208)
		(layer "B.Cu")
		(net "SMB_GPU_2_SCL")
	)
	(segment
		(start 148.287486 -389.998204)
		(end 148.287486 -389.38835)
		(width 0.13208)
		(layer "F.Cu")
		(net "GPU_BASE_STBY_EN_R")
	)
	(via
		(at 148.287486 -389.38835)
		(size 0.508)
		(drill 0.254)
		(layers "F.Cu" "B.Cu")
		(net "GPU_BASE_STBY_EN_R")
	)
	(segment
		(start 152.196546 -389.89)
		(end 156.1084 -393.801854)
		(width 0.15494)
		(layer "In9.Cu")
		(net "GPU_BASE_STBY_EN_R")
	)
	(segment
		(start 171.6024 -413.597598)
		(end 173.10989 -412.090108)
		(width 0.15494)
		(layer "In9.Cu")
		(net "GPU_BASE_STBY_EN_R")
	)
	(segment
		(start 148.287486 -389.38835)
		(end 148.89734 -389.38835)
		(width 0.15494)
		(layer "In9.Cu")
		(net "GPU_BASE_STBY_EN_R")
	)
	(segment
		(start 148.89734 -389.38835)
		(end 149.39899 -389.89)
		(width 0.15494)
		(layer "In9.Cu")
		(net "GPU_BASE_STBY_EN_R")
	)
	(segment
		(start 156.1084 -410.660342)
		(end 159.045656 -413.597598)
		(width 0.15494)
		(layer "In9.Cu")
		(net "GPU_BASE_STBY_EN_R")
	)
	(segment
		(start 159.045656 -413.597598)
		(end 171.6024 -413.597598)
		(width 0.15494)
		(layer "In9.Cu")
		(net "GPU_BASE_STBY_EN_R")
	)
	(segment
		(start 149.39899 -389.89)
		(end 152.196546 -389.89)
		(width 0.15494)
		(layer "In9.Cu")
		(net "GPU_BASE_STBY_EN_R")
	)
	(segment
		(start 156.1084 -393.801854)
		(end 156.1084 -410.660342)
		(width 0.15494)
		(layer "In9.Cu")
		(net "GPU_BASE_STBY_EN_R")
	)
	(segment
		(start 364.49 -194.437)
		(end 364.744 -194.691)
		(width 0.13208)
		(layer "F.Cu")
		(net "RST_PEX_SSD5_PERST_R_N")
	)
	(segment
		(start 363.87405 -194.691)
		(end 364.236 -194.691)
		(width 0.13208)
		(layer "F.Cu")
		(net "RST_PEX_SSD5_PERST_R_N")
	)
	(segment
		(start 364.744 -194.691)
		(end 365.10595 -194.691)
		(width 0.13208)
		(layer "F.Cu")
		(net "RST_PEX_SSD5_PERST_R_N")
	)
	(segment
		(start 364.236 -194.691)
		(end 364.49 -194.437)
		(width 0.13208)
		(layer "F.Cu")
		(net "RST_PEX_SSD5_PERST_R_N")
	)
	(segment
		(start 345.29395 -215.987122)
		(end 345.693746 -215.587326)
		(width 0.13208)
		(layer "F.Cu")
		(net "RST_PEX_SSD5_PERST_R_N")
	)
	(via
		(at 345.693746 -215.587326)
		(size 0.4572)
		(drill 0.254)
		(layers "F.Cu" "B.Cu")
		(net "RST_PEX_SSD5_PERST_R_N")
	)
	(via
		(at 364.49 -194.437)
		(size 0.508)
		(drill 0.254)
		(layers "F.Cu" "B.Cu")
		(net "RST_PEX_SSD5_PERST_R_N")
	)
	(segment
		(start 346.0242 -210.363054)
		(end 346.662248 -209.725006)
		(width 0.15494)
		(layer "In7.Cu")
		(net "RST_PEX_SSD5_PERST_R_N")
	)
	(segment
		(start 351.3836 -204.216254)
		(end 351.64522 -203.954634)
		(width 0.15494)
		(layer "In7.Cu")
		(net "RST_PEX_SSD5_PERST_R_N")
	)
	(segment
		(start 351.64522 -203.940156)
		(end 351.92843 -203.656946)
		(width 0.15494)
		(layer "In7.Cu")
		(net "RST_PEX_SSD5_PERST_R_N")
	)
	(segment
		(start 350.3676 -207.6196)
		(end 351.3836 -206.6036)
		(width 0.15494)
		(layer "In7.Cu")
		(net "RST_PEX_SSD5_PERST_R_N")
	)
	(segment
		(start 346.093542 -211.9884)
		(end 346.0242 -211.919058)
		(width 0.15494)
		(layer "In7.Cu")
		(net "RST_PEX_SSD5_PERST_R_N")
	)
	(segment
		(start 361.442254 -194.1576)
		(end 364.2106 -194.1576)
		(width 0.15494)
		(layer "In7.Cu")
		(net "RST_PEX_SSD5_PERST_R_N")
	)
	(segment
		(start 346.0242 -211.919058)
		(end 346.0242 -210.363054)
		(width 0.15494)
		(layer "In7.Cu")
		(net "RST_PEX_SSD5_PERST_R_N")
	)
	(segment
		(start 364.2106 -194.1576)
		(end 364.49 -194.437)
		(width 0.15494)
		(layer "In7.Cu")
		(net "RST_PEX_SSD5_PERST_R_N")
	)
	(segment
		(start 351.942908 -203.656946)
		(end 361.442254 -194.1576)
		(width 0.15494)
		(layer "In7.Cu")
		(net "RST_PEX_SSD5_PERST_R_N")
	)
	(segment
		(start 350.050862 -207.6196)
		(end 350.3676 -207.6196)
		(width 0.15494)
		(layer "In7.Cu")
		(net "RST_PEX_SSD5_PERST_R_N")
	)
	(segment
		(start 351.64522 -203.954634)
		(end 351.64522 -203.940156)
		(width 0.15494)
		(layer "In7.Cu")
		(net "RST_PEX_SSD5_PERST_R_N")
	)
	(segment
		(start 347.945456 -209.725006)
		(end 350.050862 -207.6196)
		(width 0.15494)
		(layer "In7.Cu")
		(net "RST_PEX_SSD5_PERST_R_N")
	)
	(segment
		(start 351.92843 -203.656946)
		(end 351.942908 -203.656946)
		(width 0.15494)
		(layer "In7.Cu")
		(net "RST_PEX_SSD5_PERST_R_N")
	)
	(segment
		(start 346.093542 -215.18753)
		(end 346.093542 -211.9884)
		(width 0.0889)
		(layer "In7.Cu")
		(net "RST_PEX_SSD5_PERST_R_N")
	)
	(segment
		(start 345.693746 -215.587326)
		(end 346.093542 -215.18753)
		(width 0.0889)
		(layer "In7.Cu")
		(net "RST_PEX_SSD5_PERST_R_N")
	)
	(segment
		(start 351.3836 -206.6036)
		(end 351.3836 -204.216254)
		(width 0.15494)
		(layer "In7.Cu")
		(net "RST_PEX_SSD5_PERST_R_N")
	)
	(segment
		(start 346.662248 -209.725006)
		(end 347.945456 -209.725006)
		(width 0.15494)
		(layer "In7.Cu")
		(net "RST_PEX_SSD5_PERST_R_N")
	)
	(segment
		(start 31.454344 -251.956824)
		(end 31.454344 -251.158502)
		(width 0.13208)
		(layer "F.Cu")
		(net "PEX0_MODE_SEL4")
	)
	(segment
		(start 62.500002 -282.599892)
		(end 62.974982 -283.074872)
		(width 0.13208)
		(layer "F.Cu")
		(net "PEX0_MODE_SEL4")
	)
	(segment
		(start 31.454344 -251.158502)
		(end 31.454344 -250.470924)
		(width 0.13208)
		(layer "F.Cu")
		(net "PEX0_MODE_SEL4")
	)
	(segment
		(start 62.499748 -282.599892)
		(end 62.500002 -282.599892)
		(width 0.13208)
		(layer "F.Cu")
		(net "PEX0_MODE_SEL4")
	)
	(via
		(at 58.501534 -266.71143)
		(size 0.6604)
		(drill 0.3302)
		(layers "F.Cu" "B.Cu")
		(net "PEX0_MODE_SEL4")
	)
	(via
		(at 31.454344 -251.158502)
		(size 0.508)
		(drill 0.254)
		(layers "F.Cu" "B.Cu")
		(net "PEX0_MODE_SEL4")
	)
	(via
		(at 62.974982 -283.074872)
		(size 0.4064)
		(drill 0.2032)
		(layers "F.Cu" "B.Cu")
		(net "PEX0_MODE_SEL4")
	)
	(segment
		(start 63.922656 -271.872456)
		(end 63.274448 -271.224248)
		(width 0.13208)
		(layer "B.Cu")
		(net "PEX0_MODE_SEL4")
	)
	(segment
		(start 30.97911 -254.169164)
		(end 35.864546 -259.0546)
		(width 0.13208)
		(layer "B.Cu")
		(net "PEX0_MODE_SEL4")
	)
	(segment
		(start 63.274448 -271.224248)
		(end 63.014352 -271.224248)
		(width 0.13208)
		(layer "B.Cu")
		(net "PEX0_MODE_SEL4")
	)
	(segment
		(start 30.97911 -251.633736)
		(end 30.97911 -254.169164)
		(width 0.13208)
		(layer "B.Cu")
		(net "PEX0_MODE_SEL4")
	)
	(segment
		(start 35.864546 -259.0546)
		(end 50.844704 -259.0546)
		(width 0.13208)
		(layer "B.Cu")
		(net "PEX0_MODE_SEL4")
	)
	(segment
		(start 50.844704 -259.0546)
		(end 58.501534 -266.71143)
		(width 0.13208)
		(layer "B.Cu")
		(net "PEX0_MODE_SEL4")
	)
	(segment
		(start 31.454344 -251.158502)
		(end 30.97911 -251.633736)
		(width 0.13208)
		(layer "B.Cu")
		(net "PEX0_MODE_SEL4")
	)
	(segment
		(start 63.922656 -282.127198)
		(end 63.922656 -271.872456)
		(width 0.13208)
		(layer "B.Cu")
		(net "PEX0_MODE_SEL4")
	)
	(segment
		(start 62.974982 -283.074872)
		(end 63.922656 -282.127198)
		(width 0.13208)
		(layer "B.Cu")
		(net "PEX0_MODE_SEL4")
	)
	(segment
		(start 63.014352 -271.224248)
		(end 58.501534 -266.71143)
		(width 0.13208)
		(layer "B.Cu")
		(net "PEX0_MODE_SEL4")
	)
	(segment
		(start 141.458442 -251.956824)
		(end 141.458442 -251.158502)
		(width 0.13208)
		(layer "F.Cu")
		(net "PEX1_MODE_SEL7")
	)
	(segment
		(start 141.458442 -251.158502)
		(end 141.458442 -250.470924)
		(width 0.13208)
		(layer "F.Cu")
		(net "PEX1_MODE_SEL7")
	)
	(segment
		(start 176.699926 -283.549852)
		(end 177.174906 -284.024832)
		(width 0.1651)
		(layer "F.Cu")
		(net "PEX1_MODE_SEL7")
	)
	(via
		(at 177.174906 -284.024832)
		(size 0.4064)
		(drill 0.2032)
		(layers "F.Cu" "B.Cu")
		(net "PEX1_MODE_SEL7")
	)
	(via
		(at 141.458442 -251.158502)
		(size 0.508)
		(drill 0.254)
		(layers "F.Cu" "B.Cu")
		(net "PEX1_MODE_SEL7")
	)
	(via
		(at 173.250352 -269.963138)
		(size 0.6604)
		(drill 0.3302)
		(layers "F.Cu" "B.Cu")
		(net "PEX1_MODE_SEL7")
	)
	(segment
		(start 176.706022 -284.493716)
		(end 176.021238 -284.493716)
		(width 0.13208)
		(layer "B.Cu")
		(net "PEX1_MODE_SEL7")
	)
	(segment
		(start 155.5242 -261.9248)
		(end 148.869146 -261.9248)
		(width 0.13208)
		(layer "B.Cu")
		(net "PEX1_MODE_SEL7")
	)
	(segment
		(start 156.5402 -260.9088)
		(end 155.5242 -261.9248)
		(width 0.13208)
		(layer "B.Cu")
		(net "PEX1_MODE_SEL7")
	)
	(segment
		(start 141.458442 -252.149102)
		(end 141.458442 -251.158502)
		(width 0.13208)
		(layer "B.Cu")
		(net "PEX1_MODE_SEL7")
	)
	(segment
		(start 176.021238 -284.493716)
		(end 175.105314 -283.577792)
		(width 0.13208)
		(layer "B.Cu")
		(net "PEX1_MODE_SEL7")
	)
	(segment
		(start 140.9192 -257.012948)
		(end 140.9192 -252.688344)
		(width 0.13208)
		(layer "B.Cu")
		(net "PEX1_MODE_SEL7")
	)
	(segment
		(start 177.174906 -284.024832)
		(end 176.706022 -284.493716)
		(width 0.13208)
		(layer "B.Cu")
		(net "PEX1_MODE_SEL7")
	)
	(segment
		(start 140.9192 -252.688344)
		(end 141.458442 -252.149102)
		(width 0.13208)
		(layer "B.Cu")
		(net "PEX1_MODE_SEL7")
	)
	(segment
		(start 144.754346 -259.4864)
		(end 143.392652 -259.4864)
		(width 0.13208)
		(layer "B.Cu")
		(net "PEX1_MODE_SEL7")
	)
	(segment
		(start 174.231046 -283.577792)
		(end 173.850046 -283.196792)
		(width 0.13208)
		(layer "B.Cu")
		(net "PEX1_MODE_SEL7")
	)
	(segment
		(start 147.497546 -260.5532)
		(end 145.821146 -260.5532)
		(width 0.13208)
		(layer "B.Cu")
		(net "PEX1_MODE_SEL7")
	)
	(segment
		(start 174.277782 -270.990568)
		(end 173.250352 -269.963138)
		(width 0.13208)
		(layer "B.Cu")
		(net "PEX1_MODE_SEL7")
	)
	(segment
		(start 172.986192 -269.963138)
		(end 163.931854 -260.9088)
		(width 0.13208)
		(layer "B.Cu")
		(net "PEX1_MODE_SEL7")
	)
	(segment
		(start 148.869146 -261.9248)
		(end 147.497546 -260.5532)
		(width 0.13208)
		(layer "B.Cu")
		(net "PEX1_MODE_SEL7")
	)
	(segment
		(start 145.821146 -260.5532)
		(end 144.754346 -259.4864)
		(width 0.13208)
		(layer "B.Cu")
		(net "PEX1_MODE_SEL7")
	)
	(segment
		(start 143.392652 -259.4864)
		(end 140.9192 -257.012948)
		(width 0.13208)
		(layer "B.Cu")
		(net "PEX1_MODE_SEL7")
	)
	(segment
		(start 163.931854 -260.9088)
		(end 156.5402 -260.9088)
		(width 0.13208)
		(layer "B.Cu")
		(net "PEX1_MODE_SEL7")
	)
	(segment
		(start 175.105314 -283.577792)
		(end 174.231046 -283.577792)
		(width 0.13208)
		(layer "B.Cu")
		(net "PEX1_MODE_SEL7")
	)
	(segment
		(start 174.277782 -282.032964)
		(end 174.277782 -270.990568)
		(width 0.13208)
		(layer "B.Cu")
		(net "PEX1_MODE_SEL7")
	)
	(segment
		(start 173.850046 -283.196792)
		(end 173.850046 -282.4607)
		(width 0.13208)
		(layer "B.Cu")
		(net "PEX1_MODE_SEL7")
	)
	(segment
		(start 173.250352 -269.963138)
		(end 172.986192 -269.963138)
		(width 0.13208)
		(layer "B.Cu")
		(net "PEX1_MODE_SEL7")
	)
	(segment
		(start 173.850046 -282.4607)
		(end 174.277782 -282.032964)
		(width 0.13208)
		(layer "B.Cu")
		(net "PEX1_MODE_SEL7")
	)
	(segment
		(start 408.424888 -308.724808)
		(end 407.949908 -309.199788)
		(width 0.13462)
		(layer "F.Cu")
		(net "PEX3_SPARE5")
	)
	(segment
		(start 439.880502 -311.969404)
		(end 439.809382 -311.969404)
		(width 0.13208)
		(layer "F.Cu")
		(net "PEX3_SPARE5")
	)
	(segment
		(start 438.516014 -311.887616)
		(end 439.24855 -312.620152)
		(width 0.13208)
		(layer "F.Cu")
		(net "PEX3_SPARE5")
	)
	(segment
		(start 439.306462 -312.620152)
		(end 439.545222 -312.620152)
		(width 0.13208)
		(layer "F.Cu")
		(net "PEX3_SPARE5")
	)
	(segment
		(start 439.809382 -312.355992)
		(end 439.809382 -311.969404)
		(width 0.13208)
		(layer "F.Cu")
		(net "PEX3_SPARE5")
	)
	(segment
		(start 440.369706 -311.4802)
		(end 439.880502 -311.969404)
		(width 0.13208)
		(layer "F.Cu")
		(net "PEX3_SPARE5")
	)
	(segment
		(start 439.24855 -312.620152)
		(end 439.306462 -312.620152)
		(width 0.13208)
		(layer "F.Cu")
		(net "PEX3_SPARE5")
	)
	(segment
		(start 439.545222 -312.620152)
		(end 439.809382 -312.355992)
		(width 0.13208)
		(layer "F.Cu")
		(net "PEX3_SPARE5")
	)
	(segment
		(start 438.516014 -311.663588)
		(end 438.516014 -311.887616)
		(width 0.13208)
		(layer "F.Cu")
		(net "PEX3_SPARE5")
	)
	(via
		(at 439.809382 -311.969404)
		(size 0.508)
		(drill 0.254)
		(layers "F.Cu" "B.Cu")
		(net "PEX3_SPARE5")
	)
	(via
		(at 408.424888 -308.724808)
		(size 0.4064)
		(drill 0.2032)
		(layers "F.Cu" "B.Cu")
		(net "PEX3_SPARE5")
	)
	(via
		(at 439.306462 -312.620152)
		(size 0.762)
		(drill 0.381)
		(layers "F.Cu" "B.Cu")
		(net "PEX3_SPARE5")
	)
	(segment
		(start 408.424888 -319.76314)
		(end 408.424888 -308.724808)
		(width 0.13208)
		(layer "B.Cu")
		(net "PEX3_SPARE5")
	)
	(segment
		(start 409.552394 -320.890646)
		(end 408.424888 -319.76314)
		(width 0.13208)
		(layer "B.Cu")
		(net "PEX3_SPARE5")
	)
	(segment
		(start 430.235106 -320.890646)
		(end 409.552394 -320.890646)
		(width 0.13208)
		(layer "B.Cu")
		(net "PEX3_SPARE5")
	)
	(segment
		(start 439.809382 -311.969404)
		(end 438.500266 -313.27852)
		(width 0.13208)
		(layer "B.Cu")
		(net "PEX3_SPARE5")
	)
	(segment
		(start 438.500266 -313.27852)
		(end 437.847232 -313.27852)
		(width 0.13208)
		(layer "B.Cu")
		(net "PEX3_SPARE5")
	)
	(segment
		(start 437.847232 -313.27852)
		(end 430.235106 -320.890646)
		(width 0.13208)
		(layer "B.Cu")
		(net "PEX3_SPARE5")
	)
	(segment
		(start 330.60005 -84.582)
		(end 332.881986 -84.582)
		(width 0.13208)
		(layer "F.Cu")
		(net "SMB_BMC_9ZXL0851_8_15_SCL")
	)
	(segment
		(start 329.83805 -83.82)
		(end 330.60005 -84.582)
		(width 0.13208)
		(layer "F.Cu")
		(net "SMB_BMC_9ZXL0851_8_15_SCL")
	)
	(segment
		(start 332.881986 -84.582)
		(end 333.30896 -85.008974)
		(width 0.13208)
		(layer "F.Cu")
		(net "SMB_BMC_9ZXL0851_8_15_SCL")
	)
	(segment
		(start 333.730092 -85.826092)
		(end 334.114394 -86.083394)
		(width 0.13208)
		(layer "F.Cu")
		(net "SMB_BMC_9ZXL0851_8_15_SCL")
	)
	(segment
		(start 333.30896 -85.008974)
		(end 333.30896 -85.40496)
		(width 0.13208)
		(layer "F.Cu")
		(net "SMB_BMC_9ZXL0851_8_15_SCL")
	)
	(segment
		(start 333.30896 -85.40496)
		(end 333.730092 -85.826092)
		(width 0.13208)
		(layer "F.Cu")
		(net "SMB_BMC_9ZXL0851_8_15_SCL")
	)
	(segment
		(start 334.114394 -86.083394)
		(end 334.59547 -86.56447)
		(width 0.13208)
		(layer "F.Cu")
		(net "SMB_BMC_9ZXL0851_8_15_SCL")
	)
	(segment
		(start 334.59547 -86.56447)
		(end 335.145634 -86.56447)
		(width 0.13208)
		(layer "F.Cu")
		(net "SMB_BMC_9ZXL0851_8_15_SCL")
	)
	(via
		(at 333.30896 -85.008974)
		(size 0.508)
		(drill 0.254)
		(layers "F.Cu" "B.Cu")
		(net "SMB_BMC_9ZXL0851_8_15_SCL")
	)
	(segment
		(start 236.887512 -232.471468)
		(end 236.887512 -231.816656)
		(width 0.13208)
		(layer "F.Cu")
		(net "SSD6_PWRDIS_BIC_R")
	)
	(segment
		(start 237.359952 -233.439716)
		(end 237.359952 -232.943908)
		(width 0.13208)
		(layer "F.Cu")
		(net "SSD6_PWRDIS_BIC_R")
	)
	(segment
		(start 237.359952 -232.943908)
		(end 236.887512 -232.471468)
		(width 0.13208)
		(layer "F.Cu")
		(net "SSD6_PWRDIS_BIC_R")
	)
	(segment
		(start 236.887512 -234.327954)
		(end 236.887512 -233.912156)
		(width 0.13208)
		(layer "F.Cu")
		(net "SSD6_PWRDIS_BIC_R")
	)
	(segment
		(start 236.887512 -233.912156)
		(end 237.359952 -233.439716)
		(width 0.13208)
		(layer "F.Cu")
		(net "SSD6_PWRDIS_BIC_R")
	)
	(segment
		(start 346.893896 -214.387176)
		(end 347.293692 -213.98738)
		(width 0.13208)
		(layer "F.Cu")
		(net "SSD6_PWRDIS_BIC_R")
	)
	(via
		(at 347.293692 -213.98738)
		(size 0.4572)
		(drill 0.254)
		(layers "F.Cu" "B.Cu")
		(net "SSD6_PWRDIS_BIC_R")
	)
	(via
		(at 236.887512 -232.471468)
		(size 0.508)
		(drill 0.254)
		(layers "F.Cu" "B.Cu")
		(net "SSD6_PWRDIS_BIC_R")
	)
	(via
		(at 267.0937 -209.079084)
		(size 0.508)
		(drill 0.254)
		(layers "F.Cu" "B.Cu")
		(net "SSD6_PWRDIS_BIC_R")
	)
	(segment
		(start 252.27534 -214.62746)
		(end 253.6444 -213.2584)
		(width 0.15494)
		(layer "In7.Cu")
		(net "SSD6_PWRDIS_BIC_R")
	)
	(segment
		(start 249.745246 -221.805754)
		(end 252.27534 -219.27566)
		(width 0.15494)
		(layer "In7.Cu")
		(net "SSD6_PWRDIS_BIC_R")
	)
	(segment
		(start 249.745246 -223.406462)
		(end 249.745246 -221.805754)
		(width 0.15494)
		(layer "In7.Cu")
		(net "SSD6_PWRDIS_BIC_R")
	)
	(segment
		(start 247.27535 -225.87712)
		(end 249.745246 -223.406462)
		(width 0.15494)
		(layer "In7.Cu")
		(net "SSD6_PWRDIS_BIC_R")
	)
	(segment
		(start 243.2304 -229.666546)
		(end 243.2304 -228.717094)
		(width 0.15494)
		(layer "In7.Cu")
		(net "SSD6_PWRDIS_BIC_R")
	)
	(segment
		(start 253.6444 -213.2584)
		(end 255.7272 -213.2584)
		(width 0.15494)
		(layer "In7.Cu")
		(net "SSD6_PWRDIS_BIC_R")
	)
	(segment
		(start 255.7272 -213.2584)
		(end 256.7178 -212.2678)
		(width 0.15494)
		(layer "In7.Cu")
		(net "SSD6_PWRDIS_BIC_R")
	)
	(segment
		(start 256.7178 -212.2678)
		(end 260.6802 -212.2678)
		(width 0.15494)
		(layer "In7.Cu")
		(net "SSD6_PWRDIS_BIC_R")
	)
	(segment
		(start 246.070374 -225.87712)
		(end 247.27535 -225.87712)
		(width 0.15494)
		(layer "In7.Cu")
		(net "SSD6_PWRDIS_BIC_R")
	)
	(segment
		(start 241.858546 -231.0384)
		(end 243.2304 -229.666546)
		(width 0.15494)
		(layer "In7.Cu")
		(net "SSD6_PWRDIS_BIC_R")
	)
	(segment
		(start 263.868916 -209.079084)
		(end 267.0937 -209.079084)
		(width 0.15494)
		(layer "In7.Cu")
		(net "SSD6_PWRDIS_BIC_R")
	)
	(segment
		(start 236.887512 -231.691688)
		(end 237.5408 -231.0384)
		(width 0.15494)
		(layer "In7.Cu")
		(net "SSD6_PWRDIS_BIC_R")
	)
	(segment
		(start 237.5408 -231.0384)
		(end 241.858546 -231.0384)
		(width 0.15494)
		(layer "In7.Cu")
		(net "SSD6_PWRDIS_BIC_R")
	)
	(segment
		(start 236.887512 -232.471468)
		(end 236.887512 -231.691688)
		(width 0.15494)
		(layer "In7.Cu")
		(net "SSD6_PWRDIS_BIC_R")
	)
	(segment
		(start 243.2304 -228.717094)
		(end 246.070374 -225.87712)
		(width 0.15494)
		(layer "In7.Cu")
		(net "SSD6_PWRDIS_BIC_R")
	)
	(segment
		(start 260.6802 -212.2678)
		(end 263.868916 -209.079084)
		(width 0.15494)
		(layer "In7.Cu")
		(net "SSD6_PWRDIS_BIC_R")
	)
	(segment
		(start 252.27534 -219.27566)
		(end 252.27534 -214.62746)
		(width 0.15494)
		(layer "In7.Cu")
		(net "SSD6_PWRDIS_BIC_R")
	)
	(segment
		(start 345.9988 -210.672426)
		(end 345.9988 -211.652612)
		(width 0.15494)
		(layer "In15.Cu")
		(net "SSD6_PWRDIS_BIC_R")
	)
	(segment
		(start 333.70266 -203.73213)
		(end 333.98587 -204.01534)
		(width 0.15494)
		(layer "In15.Cu")
		(net "SSD6_PWRDIS_BIC_R")
	)
	(segment
		(start 345.9988 -211.652612)
		(end 346.091256 -211.745068)
		(width 0.15494)
		(layer "In15.Cu")
		(net "SSD6_PWRDIS_BIC_R")
	)
	(segment
		(start 335.546954 -205.905354)
		(end 335.546954 -206.326486)
		(width 0.15494)
		(layer "In15.Cu")
		(net "SSD6_PWRDIS_BIC_R")
	)
	(segment
		(start 334.34147 -204.69987)
		(end 335.546954 -205.905354)
		(width 0.15494)
		(layer "In15.Cu")
		(net "SSD6_PWRDIS_BIC_R")
	)
	(segment
		(start 324.208648 -205.228952)
		(end 327.2536 -202.184)
		(width 0.15494)
		(layer "In15.Cu")
		(net "SSD6_PWRDIS_BIC_R")
	)
	(segment
		(start 346.328746 -213.58479)
		(end 346.891102 -213.58479)
		(width 0.0889)
		(layer "In15.Cu")
		(net "SSD6_PWRDIS_BIC_R")
	)
	(segment
		(start 270.610584 -205.5622)
		(end 298.704 -205.5622)
		(width 0.15494)
		(layer "In15.Cu")
		(net "SSD6_PWRDIS_BIC_R")
	)
	(segment
		(start 333.98587 -204.34427)
		(end 334.03413 -204.39253)
		(width 0.15494)
		(layer "In15.Cu")
		(net "SSD6_PWRDIS_BIC_R")
	)
	(segment
		(start 334.03413 -204.39253)
		(end 334.03413 -204.41666)
		(width 0.15494)
		(layer "In15.Cu")
		(net "SSD6_PWRDIS_BIC_R")
	)
	(segment
		(start 335.55813 -206.337662)
		(end 335.55813 -206.35214)
		(width 0.15494)
		(layer "In15.Cu")
		(net "SSD6_PWRDIS_BIC_R")
	)
	(segment
		(start 298.704 -205.5622)
		(end 299.037248 -205.228952)
		(width 0.15494)
		(layer "In15.Cu")
		(net "SSD6_PWRDIS_BIC_R")
	)
	(segment
		(start 299.037248 -205.228952)
		(end 324.208648 -205.228952)
		(width 0.15494)
		(layer "In15.Cu")
		(net "SSD6_PWRDIS_BIC_R")
	)
	(segment
		(start 327.2536 -202.184)
		(end 332.140052 -202.184)
		(width 0.15494)
		(layer "In15.Cu")
		(net "SSD6_PWRDIS_BIC_R")
	)
	(segment
		(start 346.091256 -213.3473)
		(end 346.328746 -213.58479)
		(width 0.0889)
		(layer "In15.Cu")
		(net "SSD6_PWRDIS_BIC_R")
	)
	(segment
		(start 333.688182 -203.73213)
		(end 333.70266 -203.73213)
		(width 0.15494)
		(layer "In15.Cu")
		(net "SSD6_PWRDIS_BIC_R")
	)
	(segment
		(start 346.091256 -211.745068)
		(end 346.091256 -213.3473)
		(width 0.0889)
		(layer "In15.Cu")
		(net "SSD6_PWRDIS_BIC_R")
	)
	(segment
		(start 332.140052 -202.184)
		(end 333.688182 -203.73213)
		(width 0.15494)
		(layer "In15.Cu")
		(net "SSD6_PWRDIS_BIC_R")
	)
	(segment
		(start 335.84134 -206.63535)
		(end 335.855818 -206.63535)
		(width 0.15494)
		(layer "In15.Cu")
		(net "SSD6_PWRDIS_BIC_R")
	)
	(segment
		(start 334.03413 -204.41666)
		(end 334.31734 -204.69987)
		(width 0.15494)
		(layer "In15.Cu")
		(net "SSD6_PWRDIS_BIC_R")
	)
	(segment
		(start 335.546954 -206.326486)
		(end 335.55813 -206.337662)
		(width 0.15494)
		(layer "In15.Cu")
		(net "SSD6_PWRDIS_BIC_R")
	)
	(segment
		(start 345.567 -209.969862)
		(end 345.567 -210.240626)
		(width 0.15494)
		(layer "In15.Cu")
		(net "SSD6_PWRDIS_BIC_R")
	)
	(segment
		(start 346.891102 -213.58479)
		(end 347.293692 -213.98738)
		(width 0.0889)
		(layer "In15.Cu")
		(net "SSD6_PWRDIS_BIC_R")
	)
	(segment
		(start 337.094068 -207.8736)
		(end 343.470738 -207.8736)
		(width 0.15494)
		(layer "In15.Cu")
		(net "SSD6_PWRDIS_BIC_R")
	)
	(segment
		(start 343.470738 -207.8736)
		(end 345.567 -209.969862)
		(width 0.15494)
		(layer "In15.Cu")
		(net "SSD6_PWRDIS_BIC_R")
	)
	(segment
		(start 335.855818 -206.63535)
		(end 337.094068 -207.8736)
		(width 0.15494)
		(layer "In15.Cu")
		(net "SSD6_PWRDIS_BIC_R")
	)
	(segment
		(start 267.0937 -209.079084)
		(end 270.610584 -205.5622)
		(width 0.15494)
		(layer "In15.Cu")
		(net "SSD6_PWRDIS_BIC_R")
	)
	(segment
		(start 345.567 -210.240626)
		(end 345.9988 -210.672426)
		(width 0.15494)
		(layer "In15.Cu")
		(net "SSD6_PWRDIS_BIC_R")
	)
	(segment
		(start 334.31734 -204.69987)
		(end 334.34147 -204.69987)
		(width 0.15494)
		(layer "In15.Cu")
		(net "SSD6_PWRDIS_BIC_R")
	)
	(segment
		(start 333.98587 -204.01534)
		(end 333.98587 -204.34427)
		(width 0.15494)
		(layer "In15.Cu")
		(net "SSD6_PWRDIS_BIC_R")
	)
	(segment
		(start 335.55813 -206.35214)
		(end 335.84134 -206.63535)
		(width 0.15494)
		(layer "In15.Cu")
		(net "SSD6_PWRDIS_BIC_R")
	)
	(segment
		(start 409.49499 -58.453782)
		(end 409.49499 -59.177936)
		(width 0.2032)
		(layer "F.Cu")
		(net "P3V3_SSD14_SS")
	)
	(segment
		(start 409.373324 -58.166)
		(end 409.490926 -58.449718)
		(width 0.2032)
		(layer "F.Cu")
		(net "P3V3_SSD14_SS")
	)
	(segment
		(start 408.44089 -57.16397)
		(end 408.44089 -57.233566)
		(width 0.2032)
		(layer "F.Cu")
		(net "P3V3_SSD14_SS")
	)
	(segment
		(start 409.490926 -58.449718)
		(end 409.49499 -58.453782)
		(width 0.2032)
		(layer "F.Cu")
		(net "P3V3_SSD14_SS")
	)
	(segment
		(start 408.44089 -57.233566)
		(end 409.373324 -58.166)
		(width 0.2032)
		(layer "F.Cu")
		(net "P3V3_SSD14_SS")
	)
	(via
		(at 409.490926 -58.449718)
		(size 0.508)
		(drill 0.254)
		(layers "F.Cu" "B.Cu")
		(net "P3V3_SSD14_SS")
	)
	(segment
		(start 130.737356 -171.317412)
		(end 130.419856 -170.999912)
		(width 0.1143)
		(layer "F.Cu")
		(net "CLK_100M_DB2000QL_PEX3_S1_DP")
	)
	(segment
		(start 130.737356 -171.669456)
		(end 130.737356 -171.317412)
		(width 0.1143)
		(layer "F.Cu")
		(net "CLK_100M_DB2000QL_PEX3_S1_DP")
	)
	(segment
		(start 131.539742 -174.734728)
		(end 131.539742 -172.471842)
		(width 0.1143)
		(layer "F.Cu")
		(net "CLK_100M_DB2000QL_PEX3_S1_DP")
	)
	(segment
		(start 131.471162 -174.900336)
		(end 131.539742 -174.734728)
		(width 0.1143)
		(layer "F.Cu")
		(net "CLK_100M_DB2000QL_PEX3_S1_DP")
	)
	(segment
		(start 131.539742 -172.471842)
		(end 130.737356 -171.669456)
		(width 0.1143)
		(layer "F.Cu")
		(net "CLK_100M_DB2000QL_PEX3_S1_DP")
	)
	(segment
		(start 144.608042 -311.556654)
		(end 143.938752 -311.556654)
		(width 0.13208)
		(layer "F.Cu")
		(net "PEX1_DBG_SEL1")
	)
	(segment
		(start 147.699222 -312.00852)
		(end 148.21408 -312.523378)
		(width 0.13208)
		(layer "F.Cu")
		(net "PEX1_DBG_SEL1")
	)
	(segment
		(start 145.92681 -312.00852)
		(end 145.059908 -312.00852)
		(width 0.13208)
		(layer "F.Cu")
		(net "PEX1_DBG_SEL1")
	)
	(segment
		(start 145.059908 -312.00852)
		(end 144.608042 -311.556654)
		(width 0.13208)
		(layer "F.Cu")
		(net "PEX1_DBG_SEL1")
	)
	(segment
		(start 170.049952 -308.249828)
		(end 169.574972 -308.724808)
		(width 0.13208)
		(layer "F.Cu")
		(net "PEX1_DBG_SEL1")
	)
	(segment
		(start 145.92681 -312.00852)
		(end 147.699222 -312.00852)
		(width 0.13208)
		(layer "F.Cu")
		(net "PEX1_DBG_SEL1")
	)
	(via
		(at 148.21408 -312.523378)
		(size 0.508)
		(drill 0.254)
		(layers "F.Cu" "B.Cu")
		(net "PEX1_DBG_SEL1")
	)
	(via
		(at 169.574972 -308.724808)
		(size 0.4064)
		(drill 0.2032)
		(layers "F.Cu" "B.Cu")
		(net "PEX1_DBG_SEL1")
	)
	(segment
		(start 151.202898 -312.999882)
		(end 148.690584 -312.999882)
		(width 0.13208)
		(layer "B.Cu")
		(net "PEX1_DBG_SEL1")
	)
	(segment
		(start 169.574972 -308.724808)
		(end 169.3164 -308.98338)
		(width 0.13208)
		(layer "B.Cu")
		(net "PEX1_DBG_SEL1")
	)
	(segment
		(start 169.643298 -314.099702)
		(end 169.291 -314.452)
		(width 0.13208)
		(layer "B.Cu")
		(net "PEX1_DBG_SEL1")
	)
	(segment
		(start 169.3164 -308.98338)
		(end 169.3164 -309.524146)
		(width 0.13208)
		(layer "B.Cu")
		(net "PEX1_DBG_SEL1")
	)
	(segment
		(start 169.3164 -309.524146)
		(end 169.643298 -309.851044)
		(width 0.13208)
		(layer "B.Cu")
		(net "PEX1_DBG_SEL1")
	)
	(segment
		(start 169.643298 -309.851044)
		(end 169.643298 -314.099702)
		(width 0.13208)
		(layer "B.Cu")
		(net "PEX1_DBG_SEL1")
	)
	(segment
		(start 152.655016 -314.452)
		(end 151.202898 -312.999882)
		(width 0.13208)
		(layer "B.Cu")
		(net "PEX1_DBG_SEL1")
	)
	(segment
		(start 169.291 -314.452)
		(end 152.655016 -314.452)
		(width 0.13208)
		(layer "B.Cu")
		(net "PEX1_DBG_SEL1")
	)
	(segment
		(start 148.690584 -312.999882)
		(end 148.21408 -312.523378)
		(width 0.13208)
		(layer "B.Cu")
		(net "PEX1_DBG_SEL1")
	)
	(segment
		(start 438.52465 -310.68518)
		(end 438.932828 -310.277002)
		(width 0.13208)
		(layer "F.Cu")
		(net "PEX3_SPARE0")
	)
	(segment
		(start 438.52465 -310.68518)
		(end 438.264808 -310.945022)
		(width 0.13208)
		(layer "F.Cu")
		(net "PEX3_SPARE0")
	)
	(segment
		(start 438.264808 -310.945022)
		(end 437.797448 -310.945022)
		(width 0.13208)
		(layer "F.Cu")
		(net "PEX3_SPARE0")
	)
	(segment
		(start 409.374848 -308.724808)
		(end 408.899868 -308.249828)
		(width 0.13208)
		(layer "F.Cu")
		(net "PEX3_SPARE0")
	)
	(segment
		(start 438.932828 -310.277002)
		(end 438.932828 -310.043322)
		(width 0.13208)
		(layer "F.Cu")
		(net "PEX3_SPARE0")
	)
	(via
		(at 435.46649 -314.33389)
		(size 0.6604)
		(drill 0.3302)
		(layers "F.Cu" "B.Cu")
		(net "PEX3_SPARE0")
	)
	(via
		(at 409.374848 -308.724808)
		(size 0.4064)
		(drill 0.2032)
		(layers "F.Cu" "B.Cu")
		(net "PEX3_SPARE0")
	)
	(via
		(at 438.52465 -310.68518)
		(size 0.508)
		(drill 0.254)
		(layers "F.Cu" "B.Cu")
		(net "PEX3_SPARE0")
	)
	(segment
		(start 410.464762 -315.379862)
		(end 410.337762 -315.252862)
		(width 0.13208)
		(layer "B.Cu")
		(net "PEX3_SPARE0")
	)
	(segment
		(start 409.826714 -309.740046)
		(end 409.374848 -309.28818)
		(width 0.13208)
		(layer "B.Cu")
		(net "PEX3_SPARE0")
	)
	(segment
		(start 434.420518 -315.379862)
		(end 410.464762 -315.379862)
		(width 0.13208)
		(layer "B.Cu")
		(net "PEX3_SPARE0")
	)
	(segment
		(start 410.097224 -309.740046)
		(end 409.826714 -309.740046)
		(width 0.13208)
		(layer "B.Cu")
		(net "PEX3_SPARE0")
	)
	(segment
		(start 435.46649 -314.33389)
		(end 438.52465 -311.27573)
		(width 0.13208)
		(layer "B.Cu")
		(net "PEX3_SPARE0")
	)
	(segment
		(start 409.374848 -309.28818)
		(end 409.374848 -308.724808)
		(width 0.13208)
		(layer "B.Cu")
		(net "PEX3_SPARE0")
	)
	(segment
		(start 410.337762 -315.252862)
		(end 410.337762 -309.980584)
		(width 0.13208)
		(layer "B.Cu")
		(net "PEX3_SPARE0")
	)
	(segment
		(start 435.46649 -314.33389)
		(end 434.420518 -315.379862)
		(width 0.13208)
		(layer "B.Cu")
		(net "PEX3_SPARE0")
	)
	(segment
		(start 410.337762 -309.980584)
		(end 410.097224 -309.740046)
		(width 0.13208)
		(layer "B.Cu")
		(net "PEX3_SPARE0")
	)
	(segment
		(start 438.52465 -311.27573)
		(end 438.52465 -310.68518)
		(width 0.13208)
		(layer "B.Cu")
		(net "PEX3_SPARE0")
	)
	(segment
		(start 330.517246 -85.134196)
		(end 332.402434 -85.134196)
		(width 0.13208)
		(layer "F.Cu")
		(net "SMB_BMC_9ZXL0851_8_15_SDA")
	)
	(segment
		(start 334.232504 -86.964266)
		(end 333.528162 -86.259924)
		(width 0.13208)
		(layer "F.Cu")
		(net "SMB_BMC_9ZXL0851_8_15_SDA")
	)
	(segment
		(start 330.09205 -84.709)
		(end 330.517246 -85.134196)
		(width 0.13208)
		(layer "F.Cu")
		(net "SMB_BMC_9ZXL0851_8_15_SDA")
	)
	(segment
		(start 335.145634 -86.964266)
		(end 334.232504 -86.964266)
		(width 0.13208)
		(layer "F.Cu")
		(net "SMB_BMC_9ZXL0851_8_15_SDA")
	)
	(segment
		(start 329.83805 -84.709)
		(end 330.09205 -84.709)
		(width 0.13208)
		(layer "F.Cu")
		(net "SMB_BMC_9ZXL0851_8_15_SDA")
	)
	(segment
		(start 332.402434 -85.134196)
		(end 333.528162 -86.259924)
		(width 0.13208)
		(layer "F.Cu")
		(net "SMB_BMC_9ZXL0851_8_15_SDA")
	)
	(via
		(at 333.528162 -86.259924)
		(size 0.508)
		(drill 0.254)
		(layers "F.Cu" "B.Cu")
		(net "SMB_BMC_9ZXL0851_8_15_SDA")
	)
	(segment
		(start 151.074374 -381.428498)
		(end 150.237698 -381.428498)
		(width 0.13208)
		(layer "F.Cu")
		(net "GPU_3V3IO_RSVD1_FFU")
	)
	(segment
		(start 149.480778 -381.428498)
		(end 150.237698 -381.428498)
		(width 0.13208)
		(layer "F.Cu")
		(net "GPU_3V3IO_RSVD1_FFU")
	)
	(segment
		(start 151.13254 -381.370332)
		(end 151.074374 -381.428498)
		(width 0.13208)
		(layer "F.Cu")
		(net "GPU_3V3IO_RSVD1_FFU")
	)
	(via
		(at 150.237698 -381.428498)
		(size 0.508)
		(drill 0.254)
		(layers "F.Cu" "B.Cu")
		(net "GPU_3V3IO_RSVD1_FFU")
	)
	(segment
		(start 148.728176 -375.397522)
		(end 157.085792 -367.039906)
		(width 0.15494)
		(layer "In15.Cu")
		(net "GPU_3V3IO_RSVD1_FFU")
	)
	(segment
		(start 148.728176 -379.918976)
		(end 148.728176 -375.397522)
		(width 0.15494)
		(layer "In15.Cu")
		(net "GPU_3V3IO_RSVD1_FFU")
	)
	(segment
		(start 157.085792 -367.039906)
		(end 168.959784 -367.039906)
		(width 0.15494)
		(layer "In15.Cu")
		(net "GPU_3V3IO_RSVD1_FFU")
	)
	(segment
		(start 150.237698 -381.428498)
		(end 148.728176 -379.918976)
		(width 0.15494)
		(layer "In15.Cu")
		(net "GPU_3V3IO_RSVD1_FFU")
	)
	(segment
		(start 168.959784 -367.039906)
		(end 170.909996 -368.990118)
		(width 0.15494)
		(layer "In15.Cu")
		(net "GPU_3V3IO_RSVD1_FFU")
	)
	(segment
		(start 345.694 -206.8068)
		(end 345.694 -205.63205)
		(width 0.13208)
		(layer "F.Cu")
		(net "SSD15_PWRDIS")
	)
	(segment
		(start 343.69375 -210.661504)
		(end 345.694 -208.661254)
		(width 0.13208)
		(layer "F.Cu")
		(net "SSD15_PWRDIS")
	)
	(segment
		(start 345.694 -208.661254)
		(end 345.694 -206.8068)
		(width 0.13208)
		(layer "F.Cu")
		(net "SSD15_PWRDIS")
	)
	(segment
		(start 343.69375 -211.18703)
		(end 343.69375 -210.661504)
		(width 0.13208)
		(layer "F.Cu")
		(net "SSD15_PWRDIS")
	)
	(via
		(at 345.694 -206.8068)
		(size 0.762)
		(drill 0.381)
		(layers "F.Cu" "B.Cu")
		(net "SSD15_PWRDIS")
	)
	(segment
		(start 266.22502 -57.841896)
		(end 265.840972 -57.457848)
		(width 0.13208)
		(layer "F.Cu")
		(net "PWRGD_P3V3_SSD9")
	)
	(segment
		(start 266.010898 -61.386974)
		(end 265.848084 -61.22416)
		(width 0.13208)
		(layer "F.Cu")
		(net "PWRGD_P3V3_SSD9")
	)
	(segment
		(start 265.975084 -59.177936)
		(end 266.378944 -59.177936)
		(width 0.13208)
		(layer "F.Cu")
		(net "PWRGD_P3V3_SSD9")
	)
	(segment
		(start 266.378944 -58.71972)
		(end 266.22502 -58.565796)
		(width 0.13208)
		(layer "F.Cu")
		(net "PWRGD_P3V3_SSD9")
	)
	(segment
		(start 265.848084 -59.304936)
		(end 265.975084 -59.177936)
		(width 0.13208)
		(layer "F.Cu")
		(net "PWRGD_P3V3_SSD9")
	)
	(segment
		(start 265.848084 -61.22416)
		(end 265.848084 -59.304936)
		(width 0.13208)
		(layer "F.Cu")
		(net "PWRGD_P3V3_SSD9")
	)
	(segment
		(start 265.840972 -57.457848)
		(end 265.840972 -57.16397)
		(width 0.13208)
		(layer "F.Cu")
		(net "PWRGD_P3V3_SSD9")
	)
	(segment
		(start 266.22502 -58.565796)
		(end 266.22502 -57.867296)
		(width 0.13208)
		(layer "F.Cu")
		(net "PWRGD_P3V3_SSD9")
	)
	(segment
		(start 266.22502 -57.867296)
		(end 266.22502 -57.841896)
		(width 0.13208)
		(layer "F.Cu")
		(net "PWRGD_P3V3_SSD9")
	)
	(segment
		(start 266.378944 -59.177936)
		(end 266.378944 -58.71972)
		(width 0.13208)
		(layer "F.Cu")
		(net "PWRGD_P3V3_SSD9")
	)
	(via
		(at 266.22502 -57.867296)
		(size 0.508)
		(drill 0.254)
		(layers "F.Cu" "B.Cu")
		(net "PWRGD_P3V3_SSD9")
	)
	(segment
		(start 29.422344 -251.158502)
		(end 29.422344 -250.470924)
		(width 0.13208)
		(layer "F.Cu")
		(net "PEX0_MODE_SEL3")
	)
	(segment
		(start 29.422344 -251.956824)
		(end 29.422344 -251.158502)
		(width 0.13208)
		(layer "F.Cu")
		(net "PEX0_MODE_SEL3")
	)
	(segment
		(start 61.549788 -283.549852)
		(end 62.024768 -284.024832)
		(width 0.1651)
		(layer "F.Cu")
		(net "PEX0_MODE_SEL3")
	)
	(via
		(at 62.024768 -284.024832)
		(size 0.4064)
		(drill 0.2032)
		(layers "F.Cu" "B.Cu")
		(net "PEX0_MODE_SEL3")
	)
	(via
		(at 29.422344 -251.158502)
		(size 0.508)
		(drill 0.254)
		(layers "F.Cu" "B.Cu")
		(net "PEX0_MODE_SEL3")
	)
	(via
		(at 59.181492 -268.925802)
		(size 0.6604)
		(drill 0.3302)
		(layers "F.Cu" "B.Cu")
		(net "PEX0_MODE_SEL3")
	)
	(segment
		(start 29.422344 -251.158502)
		(end 28.9052 -251.675646)
		(width 0.13208)
		(layer "B.Cu")
		(net "PEX0_MODE_SEL3")
	)
	(segment
		(start 62.057788 -282.163012)
		(end 62.057788 -271.802098)
		(width 0.13208)
		(layer "B.Cu")
		(net "PEX0_MODE_SEL3")
	)
	(segment
		(start 61.549788 -282.671012)
		(end 62.057788 -282.163012)
		(width 0.13208)
		(layer "B.Cu")
		(net "PEX0_MODE_SEL3")
	)
	(segment
		(start 28.9052 -251.675646)
		(end 28.9052 -253.9492)
		(width 0.13208)
		(layer "B.Cu")
		(net "PEX0_MODE_SEL3")
	)
	(segment
		(start 49.97069 -259.715)
		(end 59.181492 -268.925802)
		(width 0.13208)
		(layer "B.Cu")
		(net "PEX0_MODE_SEL3")
	)
	(segment
		(start 62.024768 -284.024832)
		(end 61.549788 -283.549852)
		(width 0.13208)
		(layer "B.Cu")
		(net "PEX0_MODE_SEL3")
	)
	(segment
		(start 28.9052 -253.9492)
		(end 30.8102 -255.8542)
		(width 0.13208)
		(layer "B.Cu")
		(net "PEX0_MODE_SEL3")
	)
	(segment
		(start 62.057788 -271.802098)
		(end 59.181492 -268.925802)
		(width 0.13208)
		(layer "B.Cu")
		(net "PEX0_MODE_SEL3")
	)
	(segment
		(start 35.610546 -259.715)
		(end 49.97069 -259.715)
		(width 0.13208)
		(layer "B.Cu")
		(net "PEX0_MODE_SEL3")
	)
	(segment
		(start 30.8102 -255.8542)
		(end 31.749746 -255.8542)
		(width 0.13208)
		(layer "B.Cu")
		(net "PEX0_MODE_SEL3")
	)
	(segment
		(start 31.749746 -255.8542)
		(end 35.610546 -259.715)
		(width 0.13208)
		(layer "B.Cu")
		(net "PEX0_MODE_SEL3")
	)
	(segment
		(start 61.549788 -283.549852)
		(end 61.549788 -282.671012)
		(width 0.13208)
		(layer "B.Cu")
		(net "PEX0_MODE_SEL3")
	)
	(segment
		(start 178.599846 -283.549852)
		(end 178.6001 -283.549852)
		(width 0.13208)
		(layer "F.Cu")
		(net "PEX1_MODE_SEL9")
	)
	(segment
		(start 140.442442 -251.956824)
		(end 140.442442 -251.158502)
		(width 0.13208)
		(layer "F.Cu")
		(net "PEX1_MODE_SEL9")
	)
	(segment
		(start 140.442442 -251.158502)
		(end 140.442442 -250.470924)
		(width 0.13208)
		(layer "F.Cu")
		(net "PEX1_MODE_SEL9")
	)
	(segment
		(start 178.6001 -283.549852)
		(end 179.07508 -284.024832)
		(width 0.13208)
		(layer "F.Cu")
		(net "PEX1_MODE_SEL9")
	)
	(via
		(at 140.442442 -251.158502)
		(size 0.508)
		(drill 0.254)
		(layers "F.Cu" "B.Cu")
		(net "PEX1_MODE_SEL9")
	)
	(via
		(at 179.07508 -284.024832)
		(size 0.4064)
		(drill 0.2032)
		(layers "F.Cu" "B.Cu")
		(net "PEX1_MODE_SEL9")
	)
	(segment
		(start 155.216352 -250.806712)
		(end 154.595068 -250.185428)
		(width 0.13208)
		(layer "B.Cu")
		(net "PEX1_MODE_SEL9")
	)
	(segment
		(start 188.605414 -281.883866)
		(end 188.605414 -271.74952)
		(width 0.13208)
		(layer "B.Cu")
		(net "PEX1_MODE_SEL9")
	)
	(segment
		(start 140.929868 -250.185428)
		(end 140.442442 -250.672854)
		(width 0.13208)
		(layer "B.Cu")
		(net "PEX1_MODE_SEL9")
	)
	(segment
		(start 186.867546 -285.3944)
		(end 187.087002 -285.174944)
		(width 0.13208)
		(layer "B.Cu")
		(net "PEX1_MODE_SEL9")
	)
	(segment
		(start 154.595068 -250.185428)
		(end 140.929868 -250.185428)
		(width 0.13208)
		(layer "B.Cu")
		(net "PEX1_MODE_SEL9")
	)
	(segment
		(start 187.087002 -282.982924)
		(end 187.39739 -282.672536)
		(width 0.13208)
		(layer "B.Cu")
		(net "PEX1_MODE_SEL9")
	)
	(segment
		(start 187.087002 -285.174944)
		(end 187.087002 -282.982924)
		(width 0.13208)
		(layer "B.Cu")
		(net "PEX1_MODE_SEL9")
	)
	(segment
		(start 188.605414 -271.74952)
		(end 168.910508 -252.054614)
		(width 0.13208)
		(layer "B.Cu")
		(net "PEX1_MODE_SEL9")
	)
	(segment
		(start 179.533296 -284.483048)
		(end 179.533296 -285.211012)
		(width 0.13208)
		(layer "B.Cu")
		(net "PEX1_MODE_SEL9")
	)
	(segment
		(start 187.39739 -282.672536)
		(end 187.816744 -282.672536)
		(width 0.13208)
		(layer "B.Cu")
		(net "PEX1_MODE_SEL9")
	)
	(segment
		(start 140.442442 -250.672854)
		(end 140.442442 -251.158502)
		(width 0.13208)
		(layer "B.Cu")
		(net "PEX1_MODE_SEL9")
	)
	(segment
		(start 155.216352 -251.525532)
		(end 155.216352 -250.806712)
		(width 0.13208)
		(layer "B.Cu")
		(net "PEX1_MODE_SEL9")
	)
	(segment
		(start 179.533296 -285.211012)
		(end 179.716684 -285.3944)
		(width 0.13208)
		(layer "B.Cu")
		(net "PEX1_MODE_SEL9")
	)
	(segment
		(start 168.910508 -252.054614)
		(end 155.745434 -252.054614)
		(width 0.13208)
		(layer "B.Cu")
		(net "PEX1_MODE_SEL9")
	)
	(segment
		(start 187.816744 -282.672536)
		(end 188.605414 -281.883866)
		(width 0.13208)
		(layer "B.Cu")
		(net "PEX1_MODE_SEL9")
	)
	(segment
		(start 155.745434 -252.054614)
		(end 155.216352 -251.525532)
		(width 0.13208)
		(layer "B.Cu")
		(net "PEX1_MODE_SEL9")
	)
	(segment
		(start 179.716684 -285.3944)
		(end 186.867546 -285.3944)
		(width 0.13208)
		(layer "B.Cu")
		(net "PEX1_MODE_SEL9")
	)
	(segment
		(start 179.07508 -284.024832)
		(end 179.533296 -284.483048)
		(width 0.13208)
		(layer "B.Cu")
		(net "PEX1_MODE_SEL9")
	)
	(segment
		(start 439.33364 -305.056794)
		(end 439.325512 -305.064922)
		(width 0.13208)
		(layer "F.Cu")
		(net "PEX3_SPARE1")
	)
	(segment
		(start 439.334148 -305.073558)
		(end 439.334148 -305.674522)
		(width 0.13208)
		(layer "F.Cu")
		(net "PEX3_SPARE1")
	)
	(segment
		(start 439.325512 -305.064922)
		(end 439.334148 -305.073558)
		(width 0.13208)
		(layer "F.Cu")
		(net "PEX3_SPARE1")
	)
	(segment
		(start 439.33364 -304.436526)
		(end 439.33364 -305.056794)
		(width 0.13208)
		(layer "F.Cu")
		(net "PEX3_SPARE1")
	)
	(segment
		(start 412.699962 -309.199788)
		(end 413.174942 -308.724808)
		(width 0.13208)
		(layer "F.Cu")
		(net "PEX3_SPARE1")
	)
	(via
		(at 433.364386 -311.026048)
		(size 0.6604)
		(drill 0.3302)
		(layers "F.Cu" "B.Cu")
		(net "PEX3_SPARE1")
	)
	(via
		(at 439.325512 -305.064922)
		(size 0.508)
		(drill 0.254)
		(layers "F.Cu" "B.Cu")
		(net "PEX3_SPARE1")
	)
	(via
		(at 413.174942 -308.724808)
		(size 0.4064)
		(drill 0.2032)
		(layers "F.Cu" "B.Cu")
		(net "PEX3_SPARE1")
	)
	(segment
		(start 414.127696 -311.412636)
		(end 414.254696 -311.539636)
		(width 0.13208)
		(layer "B.Cu")
		(net "PEX3_SPARE1")
	)
	(segment
		(start 432.850798 -311.539636)
		(end 433.364386 -311.026048)
		(width 0.13208)
		(layer "B.Cu")
		(net "PEX3_SPARE1")
	)
	(segment
		(start 414.127696 -309.677562)
		(end 414.127696 -311.412636)
		(width 0.13208)
		(layer "B.Cu")
		(net "PEX3_SPARE1")
	)
	(segment
		(start 433.364386 -311.026048)
		(end 439.325512 -305.064922)
		(width 0.13208)
		(layer "B.Cu")
		(net "PEX3_SPARE1")
	)
	(segment
		(start 414.254696 -311.539636)
		(end 432.850798 -311.539636)
		(width 0.13208)
		(layer "B.Cu")
		(net "PEX3_SPARE1")
	)
	(segment
		(start 413.174942 -308.724808)
		(end 414.127696 -309.677562)
		(width 0.13208)
		(layer "B.Cu")
		(net "PEX3_SPARE1")
	)
	(segment
		(start 51.137312 -53.023008)
		(end 51.137312 -52.587398)
		(width 0.13208)
		(layer "F.Cu")
		(net "PWRGD_P12V_SSD1")
	)
	(segment
		(start 51.60137 -53.051456)
		(end 51.867816 -53.051456)
		(width 0.13208)
		(layer "F.Cu")
		(net "PWRGD_P12V_SSD1")
	)
	(segment
		(start 51.867816 -52.035456)
		(end 51.867816 -53.051456)
		(width 0.13208)
		(layer "F.Cu")
		(net "PWRGD_P12V_SSD1")
	)
	(segment
		(start 50.14722 -53.644038)
		(end 50.516282 -53.644038)
		(width 0.13208)
		(layer "F.Cu")
		(net "PWRGD_P12V_SSD1")
	)
	(segment
		(start 50.516282 -53.644038)
		(end 51.137312 -53.023008)
		(width 0.13208)
		(layer "F.Cu")
		(net "PWRGD_P12V_SSD1")
	)
	(segment
		(start 51.137312 -52.587398)
		(end 51.60137 -53.051456)
		(width 0.13208)
		(layer "F.Cu")
		(net "PWRGD_P12V_SSD1")
	)
	(via
		(at 51.137312 -52.587398)
		(size 0.508)
		(drill 0.254)
		(layers "F.Cu" "B.Cu")
		(net "PWRGD_P12V_SSD1")
	)
	(segment
		(start 359.918 -184.15)
		(end 360.172 -183.896)
		(width 0.13208)
		(layer "F.Cu")
		(net "RST_PEX_SSD3_PERST_R_N")
	)
	(segment
		(start 360.172 -183.896)
		(end 360.426 -184.15)
		(width 0.13208)
		(layer "F.Cu")
		(net "RST_PEX_SSD3_PERST_R_N")
	)
	(segment
		(start 360.426 -184.15)
		(end 360.78795 -184.15)
		(width 0.13208)
		(layer "F.Cu")
		(net "RST_PEX_SSD3_PERST_R_N")
	)
	(segment
		(start 359.55605 -184.15)
		(end 359.918 -184.15)
		(width 0.13208)
		(layer "F.Cu")
		(net "RST_PEX_SSD3_PERST_R_N")
	)
	(segment
		(start 346.893896 -211.18703)
		(end 347.293692 -210.787234)
		(width 0.13208)
		(layer "F.Cu")
		(net "RST_PEX_SSD3_PERST_R_N")
	)
	(via
		(at 360.172 -183.896)
		(size 0.508)
		(drill 0.254)
		(layers "F.Cu" "B.Cu")
		(net "RST_PEX_SSD3_PERST_R_N")
	)
	(via
		(at 347.293692 -210.787234)
		(size 0.4572)
		(drill 0.254)
		(layers "F.Cu" "B.Cu")
		(net "RST_PEX_SSD3_PERST_R_N")
	)
	(segment
		(start 355.9302 -204.47)
		(end 358.5464 -204.47)
		(width 0.15494)
		(layer "In5.Cu")
		(net "RST_PEX_SSD3_PERST_R_N")
	)
	(segment
		(start 355.1936 -205.2066)
		(end 355.9302 -204.47)
		(width 0.15494)
		(layer "In5.Cu")
		(net "RST_PEX_SSD3_PERST_R_N")
	)
	(segment
		(start 352.1202 -205.2066)
		(end 355.1936 -205.2066)
		(width 0.15494)
		(layer "In5.Cu")
		(net "RST_PEX_SSD3_PERST_R_N")
	)
	(segment
		(start 358.72547 -204.29093)
		(end 358.72547 -200.911714)
		(width 0.15494)
		(layer "In5.Cu")
		(net "RST_PEX_SSD3_PERST_R_N")
	)
	(segment
		(start 358.72547 -200.911714)
		(end 361.121452 -198.515732)
		(width 0.15494)
		(layer "In5.Cu")
		(net "RST_PEX_SSD3_PERST_R_N")
	)
	(segment
		(start 347.293692 -210.787234)
		(end 351.3836 -206.697326)
		(width 0.15494)
		(layer "In5.Cu")
		(net "RST_PEX_SSD3_PERST_R_N")
	)
	(segment
		(start 351.3836 -205.9432)
		(end 352.1202 -205.2066)
		(width 0.15494)
		(layer "In5.Cu")
		(net "RST_PEX_SSD3_PERST_R_N")
	)
	(segment
		(start 361.121452 -198.515732)
		(end 361.121452 -184.845452)
		(width 0.15494)
		(layer "In5.Cu")
		(net "RST_PEX_SSD3_PERST_R_N")
	)
	(segment
		(start 358.5464 -204.47)
		(end 358.72547 -204.29093)
		(width 0.15494)
		(layer "In5.Cu")
		(net "RST_PEX_SSD3_PERST_R_N")
	)
	(segment
		(start 361.121452 -184.845452)
		(end 360.172 -183.896)
		(width 0.15494)
		(layer "In5.Cu")
		(net "RST_PEX_SSD3_PERST_R_N")
	)
	(segment
		(start 351.3836 -206.697326)
		(end 351.3836 -205.9432)
		(width 0.15494)
		(layer "In5.Cu")
		(net "RST_PEX_SSD3_PERST_R_N")
	)
	(segment
		(start 435.494938 -58.453782)
		(end 435.490874 -58.449718)
		(width 0.2032)
		(layer "F.Cu")
		(net "P3V3_SSD15_SS")
	)
	(segment
		(start 434.440838 -57.233566)
		(end 435.373272 -58.166)
		(width 0.2032)
		(layer "F.Cu")
		(net "P3V3_SSD15_SS")
	)
	(segment
		(start 435.373272 -58.166)
		(end 435.490874 -58.449718)
		(width 0.2032)
		(layer "F.Cu")
		(net "P3V3_SSD15_SS")
	)
	(segment
		(start 434.440838 -57.16397)
		(end 434.440838 -57.233566)
		(width 0.2032)
		(layer "F.Cu")
		(net "P3V3_SSD15_SS")
	)
	(segment
		(start 435.494938 -59.177936)
		(end 435.494938 -58.453782)
		(width 0.2032)
		(layer "F.Cu")
		(net "P3V3_SSD15_SS")
	)
	(via
		(at 435.490874 -58.449718)
		(size 0.508)
		(drill 0.254)
		(layers "F.Cu" "B.Cu")
		(net "P3V3_SSD15_SS")
	)
	(segment
		(start 150.602442 -251.158502)
		(end 150.602442 -250.470924)
		(width 0.13208)
		(layer "F.Cu")
		(net "PEX1_MODE_SEL11")
	)
	(segment
		(start 150.602442 -251.956824)
		(end 150.602442 -251.158502)
		(width 0.13208)
		(layer "F.Cu")
		(net "PEX1_MODE_SEL11")
	)
	(segment
		(start 181.44998 -282.599892)
		(end 181.92496 -283.074872)
		(width 0.13208)
		(layer "F.Cu")
		(net "PEX1_MODE_SEL11")
	)
	(via
		(at 181.92496 -283.074872)
		(size 0.4064)
		(drill 0.2032)
		(layers "F.Cu" "B.Cu")
		(net "PEX1_MODE_SEL11")
	)
	(via
		(at 150.602442 -251.158502)
		(size 0.508)
		(drill 0.254)
		(layers "F.Cu" "B.Cu")
		(net "PEX1_MODE_SEL11")
	)
	(segment
		(start 181.92496 -283.074872)
		(end 182.875174 -282.124658)
		(width 0.13208)
		(layer "B.Cu")
		(net "PEX1_MODE_SEL11")
	)
	(segment
		(start 150.53056 -254.746506)
		(end 150.05939 -254.275336)
		(width 0.13208)
		(layer "B.Cu")
		(net "PEX1_MODE_SEL11")
	)
	(segment
		(start 150.962106 -254.746506)
		(end 150.53056 -254.746506)
		(width 0.13208)
		(layer "B.Cu")
		(net "PEX1_MODE_SEL11")
	)
	(segment
		(start 182.875174 -272.170144)
		(end 179.850288 -269.145258)
		(width 0.13208)
		(layer "B.Cu")
		(net "PEX1_MODE_SEL11")
	)
	(segment
		(start 178.656488 -267.951458)
		(end 166.53383 -255.8288)
		(width 0.13208)
		(layer "B.Cu")
		(net "PEX1_MODE_SEL11")
	)
	(segment
		(start 179.850288 -269.145258)
		(end 179.635912 -269.145258)
		(width 0.13208)
		(layer "B.Cu")
		(net "PEX1_MODE_SEL11")
	)
	(segment
		(start 178.656488 -268.165834)
		(end 178.656488 -267.951458)
		(width 0.13208)
		(layer "B.Cu")
		(net "PEX1_MODE_SEL11")
	)
	(segment
		(start 166.53383 -255.8288)
		(end 152.0444 -255.8288)
		(width 0.13208)
		(layer "B.Cu")
		(net "PEX1_MODE_SEL11")
	)
	(segment
		(start 150.05939 -254.275336)
		(end 150.05939 -251.701554)
		(width 0.13208)
		(layer "B.Cu")
		(net "PEX1_MODE_SEL11")
	)
	(segment
		(start 150.05939 -251.701554)
		(end 150.602442 -251.158502)
		(width 0.13208)
		(layer "B.Cu")
		(net "PEX1_MODE_SEL11")
	)
	(segment
		(start 179.635912 -269.145258)
		(end 178.656488 -268.165834)
		(width 0.13208)
		(layer "B.Cu")
		(net "PEX1_MODE_SEL11")
	)
	(segment
		(start 152.0444 -255.8288)
		(end 150.962106 -254.746506)
		(width 0.13208)
		(layer "B.Cu")
		(net "PEX1_MODE_SEL11")
	)
	(segment
		(start 182.875174 -282.124658)
		(end 182.875174 -272.170144)
		(width 0.13208)
		(layer "B.Cu")
		(net "PEX1_MODE_SEL11")
	)
	(segment
		(start 400.349974 -309.199788)
		(end 399.874994 -308.724808)
		(width 0.127)
		(layer "F.Cu")
		(net "TP_PEX3_TDI")
	)
	(via
		(at 399.874994 -308.724808)
		(size 0.4064)
		(drill 0.2032)
		(layers "F.Cu" "B.Cu")
		(net "TP_PEX3_TDI")
	)
	(via
		(at 400.349974 -309.199788)
		(size 0.6604)
		(drill 0.3302)
		(layers "F.Cu" "B.Cu")
		(net "TP_PEX3_TDI")
	)
	(segment
		(start 400.349974 -309.199788)
		(end 399.874994 -308.724808)
		(width 0.13208)
		(layer "B.Cu")
		(net "TP_PEX3_TDI")
	)
	(segment
		(start 150.63216 -379.904752)
		(end 150.069804 -379.904752)
		(width 0.13208)
		(layer "F.Cu")
		(net "GPU_3V3IO_RSVD0_FFU")
	)
	(segment
		(start 151.074374 -380.412498)
		(end 151.10714 -380.379732)
		(width 0.13208)
		(layer "F.Cu")
		(net "GPU_3V3IO_RSVD0_FFU")
	)
	(segment
		(start 151.10714 -380.379732)
		(end 150.63216 -379.904752)
		(width 0.13208)
		(layer "F.Cu")
		(net "GPU_3V3IO_RSVD0_FFU")
	)
	(segment
		(start 149.480778 -380.412498)
		(end 151.074374 -380.412498)
		(width 0.13208)
		(layer "F.Cu")
		(net "GPU_3V3IO_RSVD0_FFU")
	)
	(via
		(at 150.069804 -379.904752)
		(size 0.508)
		(drill 0.254)
		(layers "F.Cu" "B.Cu")
		(net "GPU_3V3IO_RSVD0_FFU")
	)
	(segment
		(start 166.509954 -368.990118)
		(end 164.917882 -367.398046)
		(width 0.15494)
		(layer "In15.Cu")
		(net "GPU_3V3IO_RSVD0_FFU")
	)
	(segment
		(start 164.917882 -367.398046)
		(end 157.234382 -367.398046)
		(width 0.15494)
		(layer "In15.Cu")
		(net "GPU_3V3IO_RSVD0_FFU")
	)
	(segment
		(start 157.234382 -367.398046)
		(end 149.086316 -375.546112)
		(width 0.15494)
		(layer "In15.Cu")
		(net "GPU_3V3IO_RSVD0_FFU")
	)
	(segment
		(start 149.086316 -375.546112)
		(end 149.086316 -379.452632)
		(width 0.15494)
		(layer "In15.Cu")
		(net "GPU_3V3IO_RSVD0_FFU")
	)
	(segment
		(start 149.086316 -379.452632)
		(end 149.538436 -379.904752)
		(width 0.15494)
		(layer "In15.Cu")
		(net "GPU_3V3IO_RSVD0_FFU")
	)
	(segment
		(start 149.538436 -379.904752)
		(end 150.069804 -379.904752)
		(width 0.15494)
		(layer "In15.Cu")
		(net "GPU_3V3IO_RSVD0_FFU")
	)
	(segment
		(start 344.678 -208.915)
		(end 344.678 -207.645)
		(width 0.13208)
		(layer "F.Cu")
		(net "RST_SSD15_PERST_N")
	)
	(segment
		(start 343.29751 -211.59089)
		(end 343.29751 -210.998562)
		(width 0.13208)
		(layer "F.Cu")
		(net "RST_SSD15_PERST_N")
	)
	(segment
		(start 343.29751 -210.998562)
		(end 343.431622 -210.86445)
		(width 0.13208)
		(layer "F.Cu")
		(net "RST_SSD15_PERST_N")
	)
	(segment
		(start 343.431622 -210.161378)
		(end 344.678 -208.915)
		(width 0.13208)
		(layer "F.Cu")
		(net "RST_SSD15_PERST_N")
	)
	(segment
		(start 344.678 -207.645)
		(end 344.678 -205.63205)
		(width 0.13208)
		(layer "F.Cu")
		(net "RST_SSD15_PERST_N")
	)
	(segment
		(start 343.69375 -211.98713)
		(end 343.29751 -211.59089)
		(width 0.13208)
		(layer "F.Cu")
		(net "RST_SSD15_PERST_N")
	)
	(segment
		(start 343.431622 -210.86445)
		(end 343.431622 -210.161378)
		(width 0.13208)
		(layer "F.Cu")
		(net "RST_SSD15_PERST_N")
	)
	(via
		(at 344.678 -207.645)
		(size 0.762)
		(drill 0.381)
		(layers "F.Cu" "B.Cu")
		(net "RST_SSD15_PERST_N")
	)
	(segment
		(start 241.725958 -189.347602)
		(end 241.725958 -190.722758)
		(width 0.13208)
		(layer "F.Cu")
		(net "PEX0_MODE_SEL2")
	)
	(segment
		(start 293.228522 -179.63007)
		(end 294.055292 -178.8033)
		(width 0.13208)
		(layer "F.Cu")
		(net "PEX0_MODE_SEL2")
	)
	(segment
		(start 281.723846 -187.058554)
		(end 289.15233 -179.63007)
		(width 0.13208)
		(layer "F.Cu")
		(net "PEX0_MODE_SEL2")
	)
	(segment
		(start 26.374344 -250.470924)
		(end 26.374344 -251.158502)
		(width 0.13208)
		(layer "F.Cu")
		(net "PEX0_MODE_SEL2")
	)
	(segment
		(start 228.47046 -185.547)
		(end 235.813346 -185.547)
		(width 0.13208)
		(layer "F.Cu")
		(net "PEX0_MODE_SEL2")
	)
	(segment
		(start 59.649868 -283.549852)
		(end 60.124848 -284.024832)
		(width 0.1651)
		(layer "F.Cu")
		(net "PEX0_MODE_SEL2")
	)
	(segment
		(start 242.280186 -191.276986)
		(end 243.387118 -191.276986)
		(width 0.13208)
		(layer "F.Cu")
		(net "PEX0_MODE_SEL2")
	)
	(segment
		(start 239.195356 -186.817)
		(end 241.725958 -189.347602)
		(width 0.13208)
		(layer "F.Cu")
		(net "PEX0_MODE_SEL2")
	)
	(segment
		(start 294.677084 -178.213258)
		(end 294.677084 -177.670714)
		(width 0.13208)
		(layer "F.Cu")
		(net "PEX0_MODE_SEL2")
	)
	(segment
		(start 223.935798 -189.015116)
		(end 224.11944 -189.015116)
		(width 0.13208)
		(layer "F.Cu")
		(net "PEX0_MODE_SEL2")
	)
	(segment
		(start 224.441512 -188.693044)
		(end 225.324924 -188.693044)
		(width 0.13208)
		(layer "F.Cu")
		(net "PEX0_MODE_SEL2")
	)
	(segment
		(start 243.387118 -191.276986)
		(end 247.60555 -187.058554)
		(width 0.13208)
		(layer "F.Cu")
		(net "PEX0_MODE_SEL2")
	)
	(segment
		(start 294.055292 -178.8033)
		(end 294.055292 -178.83505)
		(width 0.13208)
		(layer "F.Cu")
		(net "PEX0_MODE_SEL2")
	)
	(segment
		(start 224.11944 -189.015116)
		(end 224.441512 -188.693044)
		(width 0.13208)
		(layer "F.Cu")
		(net "PEX0_MODE_SEL2")
	)
	(segment
		(start 26.374344 -251.158502)
		(end 26.374344 -251.956824)
		(width 0.13208)
		(layer "F.Cu")
		(net "PEX0_MODE_SEL2")
	)
	(segment
		(start 409.277058 -186.033918)
		(end 409.277058 -186.937142)
		(width 0.13208)
		(layer "F.Cu")
		(net "PEX0_MODE_SEL2")
	)
	(segment
		(start 241.725958 -190.722758)
		(end 242.280186 -191.276986)
		(width 0.13208)
		(layer "F.Cu")
		(net "PEX0_MODE_SEL2")
	)
	(segment
		(start 289.15233 -179.63007)
		(end 293.228522 -179.63007)
		(width 0.13208)
		(layer "F.Cu")
		(net "PEX0_MODE_SEL2")
	)
	(segment
		(start 235.813346 -185.547)
		(end 237.083346 -186.817)
		(width 0.13208)
		(layer "F.Cu")
		(net "PEX0_MODE_SEL2")
	)
	(segment
		(start 294.055292 -178.83505)
		(end 294.677084 -178.213258)
		(width 0.13208)
		(layer "F.Cu")
		(net "PEX0_MODE_SEL2")
	)
	(segment
		(start 247.60555 -187.058554)
		(end 281.723846 -187.058554)
		(width 0.13208)
		(layer "F.Cu")
		(net "PEX0_MODE_SEL2")
	)
	(segment
		(start 226.224338 -187.79363)
		(end 226.224338 -187.793122)
		(width 0.13208)
		(layer "F.Cu")
		(net "PEX0_MODE_SEL2")
	)
	(segment
		(start 226.224338 -187.793122)
		(end 228.47046 -185.547)
		(width 0.13208)
		(layer "F.Cu")
		(net "PEX0_MODE_SEL2")
	)
	(segment
		(start 237.083346 -186.817)
		(end 239.195356 -186.817)
		(width 0.13208)
		(layer "F.Cu")
		(net "PEX0_MODE_SEL2")
	)
	(segment
		(start 225.324924 -188.693044)
		(end 226.224338 -187.79363)
		(width 0.13208)
		(layer "F.Cu")
		(net "PEX0_MODE_SEL2")
	)
	(via
		(at 60.124848 -284.024832)
		(size 0.4064)
		(drill 0.2032)
		(layers "F.Cu" "B.Cu")
		(net "PEX0_MODE_SEL2")
	)
	(via
		(at 26.374344 -251.158502)
		(size 0.508)
		(drill 0.254)
		(layers "F.Cu" "B.Cu")
		(net "PEX0_MODE_SEL2")
	)
	(via
		(at 181.158388 -200.866248)
		(size 0.508)
		(drill 0.254)
		(layers "F.Cu" "B.Cu")
		(net "PEX0_MODE_SEL2")
	)
	(via
		(at 223.935798 -189.015116)
		(size 0.508)
		(drill 0.254)
		(layers "F.Cu" "B.Cu")
		(net "PEX0_MODE_SEL2")
	)
	(via
		(at 409.277058 -186.937142)
		(size 0.508)
		(drill 0.254)
		(layers "F.Cu" "B.Cu")
		(net "PEX0_MODE_SEL2")
	)
	(via
		(at 294.677084 -177.670714)
		(size 0.508)
		(drill 0.254)
		(layers "F.Cu" "B.Cu")
		(net "PEX0_MODE_SEL2")
	)
	(segment
		(start 124.968 -217.008456)
		(end 169.868088 -217.008456)
		(width 0.13208)
		(layer "B.Cu")
		(net "PEX0_MODE_SEL2")
	)
	(segment
		(start 24.904954 -251.634244)
		(end 24.652732 -251.886466)
		(width 0.13208)
		(layer "B.Cu")
		(net "PEX0_MODE_SEL2")
	)
	(segment
		(start 26.374344 -251.158502)
		(end 26.374344 -250.613418)
		(width 0.13208)
		(layer "B.Cu")
		(net "PEX0_MODE_SEL2")
	)
	(segment
		(start 34.338514 -241.1476)
		(end 68.575936 -241.1476)
		(width 0.13208)
		(layer "B.Cu")
		(net "PEX0_MODE_SEL2")
	)
	(segment
		(start 178.962812 -207.913732)
		(end 178.962812 -202.159616)
		(width 0.13208)
		(layer "B.Cu")
		(net "PEX0_MODE_SEL2")
	)
	(segment
		(start 56.670702 -268.887702)
		(end 55.863998 -268.080998)
		(width 0.13208)
		(layer "B.Cu")
		(net "PEX0_MODE_SEL2")
	)
	(segment
		(start 57.381902 -269.268702)
		(end 57.222898 -269.268702)
		(width 0.13208)
		(layer "B.Cu")
		(net "PEX0_MODE_SEL2")
	)
	(segment
		(start 100.715826 -209.00771)
		(end 113.617756 -209.00771)
		(width 0.13208)
		(layer "B.Cu")
		(net "PEX0_MODE_SEL2")
	)
	(segment
		(start 25.190704 -250.478798)
		(end 24.904954 -250.764548)
		(width 0.13208)
		(layer "B.Cu")
		(net "PEX0_MODE_SEL2")
	)
	(segment
		(start 49.853596 -261.8994)
		(end 33.9852 -261.8994)
		(width 0.13208)
		(layer "B.Cu")
		(net "PEX0_MODE_SEL2")
	)
	(segment
		(start 55.863998 -268.080998)
		(end 55.863998 -267.909802)
		(width 0.13208)
		(layer "B.Cu")
		(net "PEX0_MODE_SEL2")
	)
	(segment
		(start 32.7152 -260.6294)
		(end 32.7152 -259.461)
		(width 0.13208)
		(layer "B.Cu")
		(net "PEX0_MODE_SEL2")
	)
	(segment
		(start 59.180222 -283.080206)
		(end 59.180222 -271.226026)
		(width 0.13208)
		(layer "B.Cu")
		(net "PEX0_MODE_SEL2")
	)
	(segment
		(start 33.9852 -261.8994)
		(end 32.7152 -260.6294)
		(width 0.13208)
		(layer "B.Cu")
		(net "PEX0_MODE_SEL2")
	)
	(segment
		(start 58.061098 -270.106902)
		(end 58.061098 -269.947898)
		(width 0.13208)
		(layer "B.Cu")
		(net "PEX0_MODE_SEL2")
	)
	(segment
		(start 55.863998 -267.909802)
		(end 49.853596 -261.8994)
		(width 0.13208)
		(layer "B.Cu")
		(net "PEX0_MODE_SEL2")
	)
	(segment
		(start 26.374344 -252.170438)
		(end 26.374344 -251.158502)
		(width 0.13208)
		(layer "B.Cu")
		(net "PEX0_MODE_SEL2")
	)
	(segment
		(start 25.858724 -255.028954)
		(end 25.858724 -252.686058)
		(width 0.13208)
		(layer "B.Cu")
		(net "PEX0_MODE_SEL2")
	)
	(segment
		(start 56.841898 -268.887702)
		(end 56.670702 -268.887702)
		(width 0.13208)
		(layer "B.Cu")
		(net "PEX0_MODE_SEL2")
	)
	(segment
		(start 180.25618 -200.866248)
		(end 181.158388 -200.866248)
		(width 0.13208)
		(layer "B.Cu")
		(net "PEX0_MODE_SEL2")
	)
	(segment
		(start 27.890216 -257.868166)
		(end 26.9748 -256.95275)
		(width 0.13208)
		(layer "B.Cu")
		(net "PEX0_MODE_SEL2")
	)
	(segment
		(start 29.007054 -257.7592)
		(end 28.898088 -257.868166)
		(width 0.13208)
		(layer "B.Cu")
		(net "PEX0_MODE_SEL2")
	)
	(segment
		(start 58.061098 -269.947898)
		(end 57.381902 -269.268702)
		(width 0.13208)
		(layer "B.Cu")
		(net "PEX0_MODE_SEL2")
	)
	(segment
		(start 23.565612 -251.592842)
		(end 23.565612 -250.609354)
		(width 0.13208)
		(layer "B.Cu")
		(net "PEX0_MODE_SEL2")
	)
	(segment
		(start 27.10942 -249.511312)
		(end 27.642058 -248.978674)
		(width 0.13208)
		(layer "B.Cu")
		(net "PEX0_MODE_SEL2")
	)
	(segment
		(start 32.7152 -259.461)
		(end 31.0134 -257.7592)
		(width 0.13208)
		(layer "B.Cu")
		(net "PEX0_MODE_SEL2")
	)
	(segment
		(start 121.037096 -216.42705)
		(end 124.386594 -216.42705)
		(width 0.13208)
		(layer "B.Cu")
		(net "PEX0_MODE_SEL2")
	)
	(segment
		(start 57.222898 -269.268702)
		(end 56.841898 -268.887702)
		(width 0.13208)
		(layer "B.Cu")
		(net "PEX0_MODE_SEL2")
	)
	(segment
		(start 60.124848 -284.024832)
		(end 59.180222 -283.080206)
		(width 0.13208)
		(layer "B.Cu")
		(net "PEX0_MODE_SEL2")
	)
	(segment
		(start 59.180222 -271.226026)
		(end 58.061098 -270.106902)
		(width 0.13208)
		(layer "B.Cu")
		(net "PEX0_MODE_SEL2")
	)
	(segment
		(start 24.904954 -250.764548)
		(end 24.904954 -251.634244)
		(width 0.13208)
		(layer "B.Cu")
		(net "PEX0_MODE_SEL2")
	)
	(segment
		(start 113.617756 -209.00771)
		(end 121.037096 -216.42705)
		(width 0.13208)
		(layer "B.Cu")
		(net "PEX0_MODE_SEL2")
	)
	(segment
		(start 24.663654 -249.511312)
		(end 27.10942 -249.511312)
		(width 0.13208)
		(layer "B.Cu")
		(net "PEX0_MODE_SEL2")
	)
	(segment
		(start 23.565612 -250.609354)
		(end 24.663654 -249.511312)
		(width 0.13208)
		(layer "B.Cu")
		(net "PEX0_MODE_SEL2")
	)
	(segment
		(start 178.962812 -202.159616)
		(end 180.25618 -200.866248)
		(width 0.13208)
		(layer "B.Cu")
		(net "PEX0_MODE_SEL2")
	)
	(segment
		(start 169.868088 -217.008456)
		(end 178.962812 -207.913732)
		(width 0.13208)
		(layer "B.Cu")
		(net "PEX0_MODE_SEL2")
	)
	(segment
		(start 26.239724 -250.478798)
		(end 25.190704 -250.478798)
		(width 0.13208)
		(layer "B.Cu")
		(net "PEX0_MODE_SEL2")
	)
	(segment
		(start 26.374344 -250.613418)
		(end 26.239724 -250.478798)
		(width 0.13208)
		(layer "B.Cu")
		(net "PEX0_MODE_SEL2")
	)
	(segment
		(start 27.642058 -247.844056)
		(end 34.338514 -241.1476)
		(width 0.13208)
		(layer "B.Cu")
		(net "PEX0_MODE_SEL2")
	)
	(segment
		(start 27.642058 -248.978674)
		(end 27.642058 -247.844056)
		(width 0.13208)
		(layer "B.Cu")
		(net "PEX0_MODE_SEL2")
	)
	(segment
		(start 28.898088 -257.868166)
		(end 27.890216 -257.868166)
		(width 0.13208)
		(layer "B.Cu")
		(net "PEX0_MODE_SEL2")
	)
	(segment
		(start 26.9748 -256.95275)
		(end 26.9748 -256.14503)
		(width 0.13208)
		(layer "B.Cu")
		(net "PEX0_MODE_SEL2")
	)
	(segment
		(start 124.386594 -216.42705)
		(end 124.968 -217.008456)
		(width 0.13208)
		(layer "B.Cu")
		(net "PEX0_MODE_SEL2")
	)
	(segment
		(start 68.575936 -241.1476)
		(end 100.715826 -209.00771)
		(width 0.13208)
		(layer "B.Cu")
		(net "PEX0_MODE_SEL2")
	)
	(segment
		(start 26.9748 -256.14503)
		(end 25.858724 -255.028954)
		(width 0.13208)
		(layer "B.Cu")
		(net "PEX0_MODE_SEL2")
	)
	(segment
		(start 25.858724 -252.686058)
		(end 26.374344 -252.170438)
		(width 0.13208)
		(layer "B.Cu")
		(net "PEX0_MODE_SEL2")
	)
	(segment
		(start 23.859236 -251.886466)
		(end 23.565612 -251.592842)
		(width 0.13208)
		(layer "B.Cu")
		(net "PEX0_MODE_SEL2")
	)
	(segment
		(start 24.652732 -251.886466)
		(end 23.859236 -251.886466)
		(width 0.13208)
		(layer "B.Cu")
		(net "PEX0_MODE_SEL2")
	)
	(segment
		(start 31.0134 -257.7592)
		(end 29.007054 -257.7592)
		(width 0.13208)
		(layer "B.Cu")
		(net "PEX0_MODE_SEL2")
	)
	(segment
		(start 341.879174 -179.827936)
		(end 345.298014 -179.827936)
		(width 0.15494)
		(layer "In13.Cu")
		(net "PEX0_MODE_SEL2")
	)
	(segment
		(start 364.607856 -177.389028)
		(end 364.872778 -177.124106)
		(width 0.15494)
		(layer "In13.Cu")
		(net "PEX0_MODE_SEL2")
	)
	(segment
		(start 322.523866 -184.953402)
		(end 328.126598 -184.953402)
		(width 0.15494)
		(layer "In13.Cu")
		(net "PEX0_MODE_SEL2")
	)
	(segment
		(start 337.937602 -179.764944)
		(end 338.62137 -180.448712)
		(width 0.15494)
		(layer "In13.Cu")
		(net "PEX0_MODE_SEL2")
	)
	(segment
		(start 295.371012 -179.293774)
		(end 316.864238 -179.293774)
		(width 0.15494)
		(layer "In13.Cu")
		(net "PEX0_MODE_SEL2")
	)
	(segment
		(start 333.169006 -179.910994)
		(end 336.25282 -179.910994)
		(width 0.15494)
		(layer "In13.Cu")
		(net "PEX0_MODE_SEL2")
	)
	(segment
		(start 357.46309 -176.4665)
		(end 359.291636 -176.4665)
		(width 0.15494)
		(layer "In13.Cu")
		(net "PEX0_MODE_SEL2")
	)
	(segment
		(start 409.277058 -185.544206)
		(end 409.277058 -186.937142)
		(width 0.15494)
		(layer "In13.Cu")
		(net "PEX0_MODE_SEL2")
	)
	(segment
		(start 336.25282 -179.910994)
		(end 336.39887 -179.764944)
		(width 0.15494)
		(layer "In13.Cu")
		(net "PEX0_MODE_SEL2")
	)
	(segment
		(start 360.39806 -176.296066)
		(end 361.491022 -177.389028)
		(width 0.15494)
		(layer "In13.Cu")
		(net "PEX0_MODE_SEL2")
	)
	(segment
		(start 367.720626 -178.238404)
		(end 374.749568 -178.238404)
		(width 0.15494)
		(layer "In13.Cu")
		(net "PEX0_MODE_SEL2")
	)
	(segment
		(start 316.864238 -179.293774)
		(end 322.523866 -184.953402)
		(width 0.15494)
		(layer "In13.Cu")
		(net "PEX0_MODE_SEL2")
	)
	(segment
		(start 294.677084 -178.599846)
		(end 295.371012 -179.293774)
		(width 0.15494)
		(layer "In13.Cu")
		(net "PEX0_MODE_SEL2")
	)
	(segment
		(start 336.39887 -179.764944)
		(end 337.937602 -179.764944)
		(width 0.15494)
		(layer "In13.Cu")
		(net "PEX0_MODE_SEL2")
	)
	(segment
		(start 348.860364 -176.265586)
		(end 357.262176 -176.265586)
		(width 0.15494)
		(layer "In13.Cu")
		(net "PEX0_MODE_SEL2")
	)
	(segment
		(start 338.62137 -180.448712)
		(end 341.258398 -180.448712)
		(width 0.15494)
		(layer "In13.Cu")
		(net "PEX0_MODE_SEL2")
	)
	(segment
		(start 374.749568 -178.238404)
		(end 375.708418 -178.63566)
		(width 0.15494)
		(layer "In13.Cu")
		(net "PEX0_MODE_SEL2")
	)
	(segment
		(start 328.126598 -184.953402)
		(end 333.169006 -179.910994)
		(width 0.15494)
		(layer "In13.Cu")
		(net "PEX0_MODE_SEL2")
	)
	(segment
		(start 366.606328 -177.124106)
		(end 367.720626 -178.238404)
		(width 0.15494)
		(layer "In13.Cu")
		(net "PEX0_MODE_SEL2")
	)
	(segment
		(start 364.872778 -177.124106)
		(end 366.606328 -177.124106)
		(width 0.15494)
		(layer "In13.Cu")
		(net "PEX0_MODE_SEL2")
	)
	(segment
		(start 407.551128 -183.818276)
		(end 409.277058 -185.544206)
		(width 0.15494)
		(layer "In13.Cu")
		(net "PEX0_MODE_SEL2")
	)
	(segment
		(start 359.291636 -176.4665)
		(end 359.46207 -176.296066)
		(width 0.15494)
		(layer "In13.Cu")
		(net "PEX0_MODE_SEL2")
	)
	(segment
		(start 357.262176 -176.265586)
		(end 357.46309 -176.4665)
		(width 0.15494)
		(layer "In13.Cu")
		(net "PEX0_MODE_SEL2")
	)
	(segment
		(start 375.708418 -178.63566)
		(end 380.891034 -183.818276)
		(width 0.15494)
		(layer "In13.Cu")
		(net "PEX0_MODE_SEL2")
	)
	(segment
		(start 294.677084 -177.670714)
		(end 294.677084 -178.599846)
		(width 0.15494)
		(layer "In13.Cu")
		(net "PEX0_MODE_SEL2")
	)
	(segment
		(start 380.891034 -183.818276)
		(end 407.551128 -183.818276)
		(width 0.15494)
		(layer "In13.Cu")
		(net "PEX0_MODE_SEL2")
	)
	(segment
		(start 345.298014 -179.827936)
		(end 348.860364 -176.265586)
		(width 0.15494)
		(layer "In13.Cu")
		(net "PEX0_MODE_SEL2")
	)
	(segment
		(start 361.491022 -177.389028)
		(end 364.607856 -177.389028)
		(width 0.15494)
		(layer "In13.Cu")
		(net "PEX0_MODE_SEL2")
	)
	(segment
		(start 341.258398 -180.448712)
		(end 341.879174 -179.827936)
		(width 0.15494)
		(layer "In13.Cu")
		(net "PEX0_MODE_SEL2")
	)
	(segment
		(start 359.46207 -176.296066)
		(end 360.39806 -176.296066)
		(width 0.15494)
		(layer "In13.Cu")
		(net "PEX0_MODE_SEL2")
	)
	(segment
		(start 210.131406 -194.431158)
		(end 209.4865 -194.431158)
		(width 0.15494)
		(layer "In15.Cu")
		(net "PEX0_MODE_SEL2")
	)
	(segment
		(start 220.548962 -190.842646)
		(end 213.719918 -190.842646)
		(width 0.15494)
		(layer "In15.Cu")
		(net "PEX0_MODE_SEL2")
	)
	(segment
		(start 223.835976 -192.256918)
		(end 221.963234 -192.256918)
		(width 0.15494)
		(layer "In15.Cu")
		(net "PEX0_MODE_SEL2")
	)
	(segment
		(start 221.963234 -192.256918)
		(end 220.548962 -190.842646)
		(width 0.15494)
		(layer "In15.Cu")
		(net "PEX0_MODE_SEL2")
	)
	(segment
		(start 213.719918 -190.842646)
		(end 210.131406 -194.431158)
		(width 0.15494)
		(layer "In15.Cu")
		(net "PEX0_MODE_SEL2")
	)
	(segment
		(start 209.193638 -194.72402)
		(end 200.427336 -194.72402)
		(width 0.15494)
		(layer "In15.Cu")
		(net "PEX0_MODE_SEL2")
	)
	(segment
		(start 223.935798 -189.015116)
		(end 223.935798 -189.531244)
		(width 0.15494)
		(layer "In15.Cu")
		(net "PEX0_MODE_SEL2")
	)
	(segment
		(start 209.4865 -194.431158)
		(end 209.193638 -194.72402)
		(width 0.15494)
		(layer "In15.Cu")
		(net "PEX0_MODE_SEL2")
	)
	(segment
		(start 200.427336 -194.72402)
		(end 194.285108 -200.866248)
		(width 0.15494)
		(layer "In15.Cu")
		(net "PEX0_MODE_SEL2")
	)
	(segment
		(start 224.32772 -189.923166)
		(end 224.32772 -191.765174)
		(width 0.15494)
		(layer "In15.Cu")
		(net "PEX0_MODE_SEL2")
	)
	(segment
		(start 194.285108 -200.866248)
		(end 181.158388 -200.866248)
		(width 0.15494)
		(layer "In15.Cu")
		(net "PEX0_MODE_SEL2")
	)
	(segment
		(start 223.935798 -189.531244)
		(end 224.32772 -189.923166)
		(width 0.15494)
		(layer "In15.Cu")
		(net "PEX0_MODE_SEL2")
	)
	(segment
		(start 224.32772 -191.765174)
		(end 223.835976 -192.256918)
		(width 0.15494)
		(layer "In15.Cu")
		(net "PEX0_MODE_SEL2")
	)
	(segment
		(start 163.399978 -309.199788)
		(end 162.924998 -308.724808)
		(width 0.13208)
		(layer "F.Cu")
		(net "PEX1_DBG_MODE0")
	)
	(segment
		(start 147.362926 -310.571896)
		(end 147.363434 -310.571896)
		(width 0.13208)
		(layer "F.Cu")
		(net "PEX1_DBG_MODE0")
	)
	(segment
		(start 148.130006 -310.892698)
		(end 147.684236 -310.892698)
		(width 0.13208)
		(layer "F.Cu")
		(net "PEX1_DBG_MODE0")
	)
	(segment
		(start 148.971508 -311.7342)
		(end 148.130006 -310.892698)
		(width 0.13208)
		(layer "F.Cu")
		(net "PEX1_DBG_MODE0")
	)
	(segment
		(start 147.363434 -310.571896)
		(end 148.081746 -309.853584)
		(width 0.13208)
		(layer "F.Cu")
		(net "PEX1_DBG_MODE0")
	)
	(segment
		(start 147.684236 -310.892698)
		(end 147.363434 -310.571896)
		(width 0.13208)
		(layer "F.Cu")
		(net "PEX1_DBG_MODE0")
	)
	(via
		(at 162.924998 -308.724808)
		(size 0.4064)
		(drill 0.2032)
		(layers "F.Cu" "B.Cu")
		(net "PEX1_DBG_MODE0")
	)
	(via
		(at 148.971508 -311.7342)
		(size 0.508)
		(drill 0.254)
		(layers "F.Cu" "B.Cu")
		(net "PEX1_DBG_MODE0")
	)
	(via
		(at 150.619714 -308.61889)
		(size 0.6604)
		(drill 0.3302)
		(layers "F.Cu" "B.Cu")
		(net "PEX1_DBG_MODE0")
	)
	(segment
		(start 162.924998 -308.724808)
		(end 162.887406 -308.7624)
		(width 0.13208)
		(layer "B.Cu")
		(net "PEX1_DBG_MODE0")
	)
	(segment
		(start 151.389588 -308.56809)
		(end 150.670514 -308.56809)
		(width 0.13208)
		(layer "B.Cu")
		(net "PEX1_DBG_MODE0")
	)
	(segment
		(start 148.971508 -310.267096)
		(end 150.619714 -308.61889)
		(width 0.13208)
		(layer "B.Cu")
		(net "PEX1_DBG_MODE0")
	)
	(segment
		(start 151.583898 -308.7624)
		(end 151.389588 -308.56809)
		(width 0.13208)
		(layer "B.Cu")
		(net "PEX1_DBG_MODE0")
	)
	(segment
		(start 148.971508 -311.7342)
		(end 148.971508 -310.267096)
		(width 0.13208)
		(layer "B.Cu")
		(net "PEX1_DBG_MODE0")
	)
	(segment
		(start 162.887406 -308.7624)
		(end 151.583898 -308.7624)
		(width 0.13208)
		(layer "B.Cu")
		(net "PEX1_DBG_MODE0")
	)
	(segment
		(start 150.670514 -308.56809)
		(end 150.619714 -308.61889)
		(width 0.13208)
		(layer "B.Cu")
		(net "PEX1_DBG_MODE0")
	)
	(segment
		(start 440.350148 -305.063906)
		(end 440.350148 -305.674522)
		(width 0.13208)
		(layer "F.Cu")
		(net "PEX3_SPARE6")
	)
	(segment
		(start 411.274768 -308.724554)
		(end 410.799788 -309.199788)
		(width 0.13208)
		(layer "F.Cu")
		(net "PEX3_SPARE6")
	)
	(segment
		(start 440.34964 -304.436526)
		(end 440.34964 -305.007518)
		(width 0.13208)
		(layer "F.Cu")
		(net "PEX3_SPARE6")
	)
	(segment
		(start 440.350148 -305.008026)
		(end 440.350148 -305.063906)
		(width 0.13208)
		(layer "F.Cu")
		(net "PEX3_SPARE6")
	)
	(segment
		(start 440.34964 -305.007518)
		(end 440.350148 -305.008026)
		(width 0.13208)
		(layer "F.Cu")
		(net "PEX3_SPARE6")
	)
	(via
		(at 440.350148 -305.063906)
		(size 0.508)
		(drill 0.254)
		(layers "F.Cu" "B.Cu")
		(net "PEX3_SPARE6")
	)
	(via
		(at 411.274768 -308.724554)
		(size 0.4064)
		(drill 0.2032)
		(layers "F.Cu" "B.Cu")
		(net "PEX3_SPARE6")
	)
	(via
		(at 432.37785 -312.999882)
		(size 0.6604)
		(drill 0.3302)
		(layers "F.Cu" "B.Cu")
		(net "PEX3_SPARE6")
	)
	(segment
		(start 432.37785 -312.999882)
		(end 439.745882 -305.63185)
		(width 0.13208)
		(layer "B.Cu")
		(net "PEX3_SPARE6")
	)
	(segment
		(start 412.627572 -309.187596)
		(end 413.16021 -309.720234)
		(width 0.13208)
		(layer "B.Cu")
		(net "PEX3_SPARE6")
	)
	(segment
		(start 411.274768 -308.724554)
		(end 411.73781 -309.187596)
		(width 0.13208)
		(layer "B.Cu")
		(net "PEX3_SPARE6")
	)
	(segment
		(start 431.91557 -312.537602)
		(end 432.37785 -312.999882)
		(width 0.13208)
		(layer "B.Cu")
		(net "PEX3_SPARE6")
	)
	(segment
		(start 413.16021 -309.720234)
		(end 413.16021 -312.410602)
		(width 0.13208)
		(layer "B.Cu")
		(net "PEX3_SPARE6")
	)
	(segment
		(start 411.73781 -309.187596)
		(end 412.627572 -309.187596)
		(width 0.13208)
		(layer "B.Cu")
		(net "PEX3_SPARE6")
	)
	(segment
		(start 413.16021 -312.410602)
		(end 413.28721 -312.537602)
		(width 0.13208)
		(layer "B.Cu")
		(net "PEX3_SPARE6")
	)
	(segment
		(start 439.745882 -305.63185)
		(end 439.782204 -305.63185)
		(width 0.13208)
		(layer "B.Cu")
		(net "PEX3_SPARE6")
	)
	(segment
		(start 439.782204 -305.63185)
		(end 440.350148 -305.063906)
		(width 0.13208)
		(layer "B.Cu")
		(net "PEX3_SPARE6")
	)
	(segment
		(start 413.28721 -312.537602)
		(end 431.91557 -312.537602)
		(width 0.13208)
		(layer "B.Cu")
		(net "PEX3_SPARE6")
	)
	(segment
		(start 142.621 -386.9944)
		(end 143.164052 -386.451348)
		(width 0.13208)
		(layer "F.Cu")
		(net "SMB_MB_BMC_R_SCL")
	)
	(segment
		(start 142.621 -389.444992)
		(end 142.621 -386.9944)
		(width 0.13208)
		(layer "F.Cu")
		(net "SMB_MB_BMC_R_SCL")
	)
	(segment
		(start 142.947644 -389.771636)
		(end 142.621 -389.444992)
		(width 0.13208)
		(layer "F.Cu")
		(net "SMB_MB_BMC_R_SCL")
	)
	(segment
		(start 143.164052 -386.451348)
		(end 145.397728 -386.451348)
		(width 0.13208)
		(layer "F.Cu")
		(net "SMB_MB_BMC_R_SCL")
	)
	(via
		(at 229.338632 -330.156312)
		(size 0.508)
		(drill 0.254)
		(layers "F.Cu" "B.Cu")
		(net "SMB_MB_BMC_R_SCL")
	)
	(via
		(at 305.315112 -253.580646)
		(size 0.508)
		(drill 0.254)
		(layers "F.Cu" "B.Cu")
		(net "SMB_MB_BMC_R_SCL")
	)
	(via
		(at 231.90327 -246.27967)
		(size 0.508)
		(drill 0.254)
		(layers "F.Cu" "B.Cu")
		(net "SMB_MB_BMC_R_SCL")
	)
	(via
		(at 201.383392 -359.338372)
		(size 0.508)
		(drill 0.254)
		(layers "F.Cu" "B.Cu")
		(net "SMB_MB_BMC_R_SCL")
	)
	(via
		(at 145.397728 -386.451348)
		(size 0.508)
		(drill 0.254)
		(layers "F.Cu" "B.Cu")
		(net "SMB_MB_BMC_R_SCL")
	)
	(via
		(at 303.144682 -249.695462)
		(size 0.6604)
		(drill 0.3302)
		(layers "F.Cu" "B.Cu")
		(net "SMB_MB_BMC_R_SCL")
	)
	(segment
		(start 229.338632 -330.156312)
		(end 229.322122 -330.139802)
		(width 0.13208)
		(layer "B.Cu")
		(net "SMB_MB_BMC_R_SCL")
	)
	(segment
		(start 303.11471 -247.305322)
		(end 303.11471 -248.087388)
		(width 0.13208)
		(layer "B.Cu")
		(net "SMB_MB_BMC_R_SCL")
	)
	(segment
		(start 244.974618 -326.536304)
		(end 248.532142 -322.97878)
		(width 0.13208)
		(layer "B.Cu")
		(net "SMB_MB_BMC_R_SCL")
	)
	(segment
		(start 305.763676 -247.469406)
		(end 304.855626 -247.469406)
		(width 0.13208)
		(layer "B.Cu")
		(net "SMB_MB_BMC_R_SCL")
	)
	(segment
		(start 235.333794 -326.536304)
		(end 244.974618 -326.536304)
		(width 0.13208)
		(layer "B.Cu")
		(net "SMB_MB_BMC_R_SCL")
	)
	(segment
		(start 305.315112 -253.580646)
		(end 304.808636 -253.07417)
		(width 0.13208)
		(layer "B.Cu")
		(net "SMB_MB_BMC_R_SCL")
	)
	(segment
		(start 239.816894 -254.373634)
		(end 231.90327 -246.46001)
		(width 0.13208)
		(layer "B.Cu")
		(net "SMB_MB_BMC_R_SCL")
	)
	(segment
		(start 303.077626 -252.187456)
		(end 304.195988 -252.187456)
		(width 0.13208)
		(layer "B.Cu")
		(net "SMB_MB_BMC_R_SCL")
	)
	(segment
		(start 304.347626 -246.961406)
		(end 303.458626 -246.961406)
		(width 0.13208)
		(layer "B.Cu")
		(net "SMB_MB_BMC_R_SCL")
	)
	(segment
		(start 304.195988 -252.187456)
		(end 304.38471 -251.998734)
		(width 0.13208)
		(layer "B.Cu")
		(net "SMB_MB_BMC_R_SCL")
	)
	(segment
		(start 248.532142 -322.97878)
		(end 255.794256 -305.444144)
		(width 0.13208)
		(layer "B.Cu")
		(net "SMB_MB_BMC_R_SCL")
	)
	(segment
		(start 247.251474 -264.992612)
		(end 247.251474 -256.625852)
		(width 0.13208)
		(layer "B.Cu")
		(net "SMB_MB_BMC_R_SCL")
	)
	(segment
		(start 306.633626 -246.599456)
		(end 305.763676 -247.469406)
		(width 0.13208)
		(layer "B.Cu")
		(net "SMB_MB_BMC_R_SCL")
	)
	(segment
		(start 232.852468 -329.01763)
		(end 235.333794 -326.536304)
		(width 0.13208)
		(layer "B.Cu")
		(net "SMB_MB_BMC_R_SCL")
	)
	(segment
		(start 304.808636 -253.07417)
		(end 303.523396 -253.07417)
		(width 0.13208)
		(layer "B.Cu")
		(net "SMB_MB_BMC_R_SCL")
	)
	(segment
		(start 247.251474 -256.625852)
		(end 244.999256 -254.373634)
		(width 0.13208)
		(layer "B.Cu")
		(net "SMB_MB_BMC_R_SCL")
	)
	(segment
		(start 231.90327 -246.46001)
		(end 231.90327 -246.27967)
		(width 0.13208)
		(layer "B.Cu")
		(net "SMB_MB_BMC_R_SCL")
	)
	(segment
		(start 229.598728 -329.066652)
		(end 229.598982 -329.066652)
		(width 0.13208)
		(layer "B.Cu")
		(net "SMB_MB_BMC_R_SCL")
	)
	(segment
		(start 303.144682 -249.695462)
		(end 303.11471 -249.66549)
		(width 0.13208)
		(layer "B.Cu")
		(net "SMB_MB_BMC_R_SCL")
	)
	(segment
		(start 255.794256 -285.619698)
		(end 247.251474 -264.992612)
		(width 0.13208)
		(layer "B.Cu")
		(net "SMB_MB_BMC_R_SCL")
	)
	(segment
		(start 303.523396 -253.07417)
		(end 303.077626 -252.6284)
		(width 0.13208)
		(layer "B.Cu")
		(net "SMB_MB_BMC_R_SCL")
	)
	(segment
		(start 229.598982 -329.066652)
		(end 229.648004 -329.01763)
		(width 0.13208)
		(layer "B.Cu")
		(net "SMB_MB_BMC_R_SCL")
	)
	(segment
		(start 229.322122 -329.343258)
		(end 229.598728 -329.066652)
		(width 0.13208)
		(layer "B.Cu")
		(net "SMB_MB_BMC_R_SCL")
	)
	(segment
		(start 304.38471 -251.998734)
		(end 304.38471 -250.93549)
		(width 0.13208)
		(layer "B.Cu")
		(net "SMB_MB_BMC_R_SCL")
	)
	(segment
		(start 229.322122 -330.139802)
		(end 229.322122 -329.343258)
		(width 0.13208)
		(layer "B.Cu")
		(net "SMB_MB_BMC_R_SCL")
	)
	(segment
		(start 229.648004 -329.01763)
		(end 232.852468 -329.01763)
		(width 0.13208)
		(layer "B.Cu")
		(net "SMB_MB_BMC_R_SCL")
	)
	(segment
		(start 244.999256 -254.373634)
		(end 239.816894 -254.373634)
		(width 0.13208)
		(layer "B.Cu")
		(net "SMB_MB_BMC_R_SCL")
	)
	(segment
		(start 303.077626 -252.6284)
		(end 303.077626 -252.187456)
		(width 0.13208)
		(layer "B.Cu")
		(net "SMB_MB_BMC_R_SCL")
	)
	(segment
		(start 303.458626 -246.961406)
		(end 303.11471 -247.305322)
		(width 0.13208)
		(layer "B.Cu")
		(net "SMB_MB_BMC_R_SCL")
	)
	(segment
		(start 255.794256 -305.444144)
		(end 255.794256 -285.619698)
		(width 0.13208)
		(layer "B.Cu")
		(net "SMB_MB_BMC_R_SCL")
	)
	(segment
		(start 304.38471 -250.93549)
		(end 303.144682 -249.695462)
		(width 0.13208)
		(layer "B.Cu")
		(net "SMB_MB_BMC_R_SCL")
	)
	(segment
		(start 303.11471 -249.66549)
		(end 303.11471 -248.087388)
		(width 0.13208)
		(layer "B.Cu")
		(net "SMB_MB_BMC_R_SCL")
	)
	(segment
		(start 304.855626 -247.469406)
		(end 304.347626 -246.961406)
		(width 0.13208)
		(layer "B.Cu")
		(net "SMB_MB_BMC_R_SCL")
	)
	(segment
		(start 201.383392 -359.338372)
		(end 201.933048 -359.338372)
		(width 0.15494)
		(layer "In5.Cu")
		(net "SMB_MB_BMC_R_SCL")
	)
	(segment
		(start 204.874622 -354.61702)
		(end 219.018104 -354.61702)
		(width 0.15494)
		(layer "In5.Cu")
		(net "SMB_MB_BMC_R_SCL")
	)
	(segment
		(start 227.338128 -346.296996)
		(end 227.338128 -332.156816)
		(width 0.15494)
		(layer "In5.Cu")
		(net "SMB_MB_BMC_R_SCL")
	)
	(segment
		(start 219.018104 -354.61702)
		(end 227.338128 -346.296996)
		(width 0.15494)
		(layer "In5.Cu")
		(net "SMB_MB_BMC_R_SCL")
	)
	(segment
		(start 202.288394 -357.203248)
		(end 204.874622 -354.61702)
		(width 0.15494)
		(layer "In5.Cu")
		(net "SMB_MB_BMC_R_SCL")
	)
	(segment
		(start 202.288394 -358.983026)
		(end 202.288394 -357.203248)
		(width 0.15494)
		(layer "In5.Cu")
		(net "SMB_MB_BMC_R_SCL")
	)
	(segment
		(start 227.338128 -332.156816)
		(end 229.338632 -330.156312)
		(width 0.15494)
		(layer "In5.Cu")
		(net "SMB_MB_BMC_R_SCL")
	)
	(segment
		(start 201.933048 -359.338372)
		(end 202.288394 -358.983026)
		(width 0.15494)
		(layer "In5.Cu")
		(net "SMB_MB_BMC_R_SCL")
	)
	(segment
		(start 231.90327 -246.22379)
		(end 232.2957 -245.83136)
		(width 0.15494)
		(layer "In13.Cu")
		(net "SMB_MB_BMC_R_SCL")
	)
	(segment
		(start 304.854102 -253.119636)
		(end 305.315112 -253.580646)
		(width 0.15494)
		(layer "In13.Cu")
		(net "SMB_MB_BMC_R_SCL")
	)
	(segment
		(start 247.606312 -247.995948)
		(end 272.610834 -247.995948)
		(width 0.15494)
		(layer "In13.Cu")
		(net "SMB_MB_BMC_R_SCL")
	)
	(segment
		(start 298.8691 -250.08586)
		(end 298.92244 -250.1392)
		(width 0.15494)
		(layer "In13.Cu")
		(net "SMB_MB_BMC_R_SCL")
	)
	(segment
		(start 232.2957 -245.83136)
		(end 233.43997 -245.83136)
		(width 0.15494)
		(layer "In13.Cu")
		(net "SMB_MB_BMC_R_SCL")
	)
	(segment
		(start 238.57712 -248.031)
		(end 239.6236 -246.98452)
		(width 0.15494)
		(layer "In13.Cu")
		(net "SMB_MB_BMC_R_SCL")
	)
	(segment
		(start 233.43997 -245.83136)
		(end 235.63961 -248.031)
		(width 0.15494)
		(layer "In13.Cu")
		(net "SMB_MB_BMC_R_SCL")
	)
	(segment
		(start 246.594884 -246.98452)
		(end 247.606312 -247.995948)
		(width 0.15494)
		(layer "In13.Cu")
		(net "SMB_MB_BMC_R_SCL")
	)
	(segment
		(start 235.63961 -248.031)
		(end 238.57712 -248.031)
		(width 0.15494)
		(layer "In13.Cu")
		(net "SMB_MB_BMC_R_SCL")
	)
	(segment
		(start 298.92244 -250.1392)
		(end 298.932346 -250.1392)
		(width 0.15494)
		(layer "In13.Cu")
		(net "SMB_MB_BMC_R_SCL")
	)
	(segment
		(start 301.912782 -253.119636)
		(end 304.854102 -253.119636)
		(width 0.15494)
		(layer "In13.Cu")
		(net "SMB_MB_BMC_R_SCL")
	)
	(segment
		(start 274.700746 -250.08586)
		(end 298.8691 -250.08586)
		(width 0.15494)
		(layer "In13.Cu")
		(net "SMB_MB_BMC_R_SCL")
	)
	(segment
		(start 231.90327 -246.27967)
		(end 231.90327 -246.22379)
		(width 0.15494)
		(layer "In13.Cu")
		(net "SMB_MB_BMC_R_SCL")
	)
	(segment
		(start 239.6236 -246.98452)
		(end 246.594884 -246.98452)
		(width 0.15494)
		(layer "In13.Cu")
		(net "SMB_MB_BMC_R_SCL")
	)
	(segment
		(start 298.932346 -250.1392)
		(end 301.912782 -253.119636)
		(width 0.15494)
		(layer "In13.Cu")
		(net "SMB_MB_BMC_R_SCL")
	)
	(segment
		(start 272.610834 -247.995948)
		(end 274.700746 -250.08586)
		(width 0.15494)
		(layer "In13.Cu")
		(net "SMB_MB_BMC_R_SCL")
	)
	(segment
		(start 199.053196 -360.265218)
		(end 190.104014 -360.265218)
		(width 0.15494)
		(layer "In15.Cu")
		(net "SMB_MB_BMC_R_SCL")
	)
	(segment
		(start 201.383392 -359.338372)
		(end 199.980042 -359.338372)
		(width 0.15494)
		(layer "In15.Cu")
		(net "SMB_MB_BMC_R_SCL")
	)
	(segment
		(start 143.61414 -384.66776)
		(end 145.397728 -386.451348)
		(width 0.15494)
		(layer "In15.Cu")
		(net "SMB_MB_BMC_R_SCL")
	)
	(segment
		(start 186.071002 -364.29823)
		(end 156.087064 -364.29823)
		(width 0.15494)
		(layer "In15.Cu")
		(net "SMB_MB_BMC_R_SCL")
	)
	(segment
		(start 156.087064 -364.29823)
		(end 143.61414 -376.771154)
		(width 0.15494)
		(layer "In15.Cu")
		(net "SMB_MB_BMC_R_SCL")
	)
	(segment
		(start 199.980042 -359.338372)
		(end 199.053196 -360.265218)
		(width 0.15494)
		(layer "In15.Cu")
		(net "SMB_MB_BMC_R_SCL")
	)
	(segment
		(start 190.104014 -360.265218)
		(end 186.071002 -364.29823)
		(width 0.15494)
		(layer "In15.Cu")
		(net "SMB_MB_BMC_R_SCL")
	)
	(segment
		(start 143.61414 -376.771154)
		(end 143.61414 -384.66776)
		(width 0.15494)
		(layer "In15.Cu")
		(net "SMB_MB_BMC_R_SCL")
	)
	(segment
		(start 345.29395 -213.587076)
		(end 345.693746 -213.18728)
		(width 0.13208)
		(layer "F.Cu")
		(net "RST_PEX_SSD2_PERST_R_N")
	)
	(segment
		(start 360.426 -188.214)
		(end 360.78795 -188.214)
		(width 0.13208)
		(layer "F.Cu")
		(net "RST_PEX_SSD2_PERST_R_N")
	)
	(segment
		(start 359.918 -188.214)
		(end 360.172 -187.96)
		(width 0.13208)
		(layer "F.Cu")
		(net "RST_PEX_SSD2_PERST_R_N")
	)
	(segment
		(start 360.172 -187.96)
		(end 360.426 -188.214)
		(width 0.13208)
		(layer "F.Cu")
		(net "RST_PEX_SSD2_PERST_R_N")
	)
	(segment
		(start 359.55605 -188.214)
		(end 359.918 -188.214)
		(width 0.13208)
		(layer "F.Cu")
		(net "RST_PEX_SSD2_PERST_R_N")
	)
	(via
		(at 345.693746 -213.18728)
		(size 0.4572)
		(drill 0.254)
		(layers "F.Cu" "B.Cu")
		(net "RST_PEX_SSD2_PERST_R_N")
	)
	(via
		(at 360.172 -187.96)
		(size 0.508)
		(drill 0.254)
		(layers "F.Cu" "B.Cu")
		(net "RST_PEX_SSD2_PERST_R_N")
	)
	(segment
		(start 358.704388 -190.585852)
		(end 359.638346 -189.651894)
		(width 0.15494)
		(layer "In9.Cu")
		(net "RST_PEX_SSD2_PERST_R_N")
	)
	(segment
		(start 357.378 -195.012056)
		(end 358.704388 -193.685668)
		(width 0.15494)
		(layer "In9.Cu")
		(net "RST_PEX_SSD2_PERST_R_N")
	)
	(segment
		(start 358.704388 -193.685668)
		(end 358.704388 -190.585852)
		(width 0.15494)
		(layer "In9.Cu")
		(net "RST_PEX_SSD2_PERST_R_N")
	)
	(segment
		(start 359.638346 -188.493654)
		(end 360.172 -187.96)
		(width 0.15494)
		(layer "In9.Cu")
		(net "RST_PEX_SSD2_PERST_R_N")
	)
	(segment
		(start 352.35388 -208.122774)
		(end 353.92868 -206.547974)
		(width 0.15494)
		(layer "In9.Cu")
		(net "RST_PEX_SSD2_PERST_R_N")
	)
	(segment
		(start 345.7448 -210.2104)
		(end 347.832426 -208.122774)
		(width 0.15494)
		(layer "In9.Cu")
		(net "RST_PEX_SSD2_PERST_R_N")
	)
	(segment
		(start 357.378 -198.2216)
		(end 357.378 -195.012056)
		(width 0.15494)
		(layer "In9.Cu")
		(net "RST_PEX_SSD2_PERST_R_N")
	)
	(segment
		(start 345.7448 -211.313014)
		(end 345.7448 -210.2104)
		(width 0.15494)
		(layer "In9.Cu")
		(net "RST_PEX_SSD2_PERST_R_N")
	)
	(segment
		(start 353.92868 -206.547974)
		(end 353.92868 -205.754986)
		(width 0.15494)
		(layer "In9.Cu")
		(net "RST_PEX_SSD2_PERST_R_N")
	)
	(segment
		(start 353.703636 -201.895964)
		(end 357.378 -198.2216)
		(width 0.15494)
		(layer "In9.Cu")
		(net "RST_PEX_SSD2_PERST_R_N")
	)
	(segment
		(start 345.296236 -211.761578)
		(end 345.7448 -211.313014)
		(width 0.15494)
		(layer "In9.Cu")
		(net "RST_PEX_SSD2_PERST_R_N")
	)
	(segment
		(start 353.92868 -205.754986)
		(end 353.703636 -205.529942)
		(width 0.15494)
		(layer "In9.Cu")
		(net "RST_PEX_SSD2_PERST_R_N")
	)
	(segment
		(start 347.832426 -208.122774)
		(end 352.35388 -208.122774)
		(width 0.15494)
		(layer "In9.Cu")
		(net "RST_PEX_SSD2_PERST_R_N")
	)
	(segment
		(start 345.296236 -212.78977)
		(end 345.296236 -211.761578)
		(width 0.0889)
		(layer "In9.Cu")
		(net "RST_PEX_SSD2_PERST_R_N")
	)
	(segment
		(start 359.638346 -189.651894)
		(end 359.638346 -188.493654)
		(width 0.15494)
		(layer "In9.Cu")
		(net "RST_PEX_SSD2_PERST_R_N")
	)
	(segment
		(start 353.703636 -205.529942)
		(end 353.703636 -201.895964)
		(width 0.15494)
		(layer "In9.Cu")
		(net "RST_PEX_SSD2_PERST_R_N")
	)
	(segment
		(start 345.693746 -213.18728)
		(end 345.296236 -212.78977)
		(width 0.0889)
		(layer "In9.Cu")
		(net "RST_PEX_SSD2_PERST_R_N")
	)
	(segment
		(start 154.666442 -250.470924)
		(end 154.666442 -251.158502)
		(width 0.13208)
		(layer "F.Cu")
		(net "PEX1_DBG_MODE4")
	)
	(segment
		(start 184.29986 -282.599892)
		(end 184.77484 -283.074872)
		(width 0.13208)
		(layer "F.Cu")
		(net "PEX1_DBG_MODE4")
	)
	(segment
		(start 154.666442 -251.158502)
		(end 154.666442 -251.956824)
		(width 0.13208)
		(layer "F.Cu")
		(net "PEX1_DBG_MODE4")
	)
	(via
		(at 154.666442 -251.158502)
		(size 0.508)
		(drill 0.254)
		(layers "F.Cu" "B.Cu")
		(net "PEX1_DBG_MODE4")
	)
	(via
		(at 184.77484 -283.074872)
		(size 0.4064)
		(drill 0.2032)
		(layers "F.Cu" "B.Cu")
		(net "PEX1_DBG_MODE4")
	)
	(segment
		(start 185.836052 -282.591002)
		(end 186.680094 -281.74696)
		(width 0.13208)
		(layer "B.Cu")
		(net "PEX1_DBG_MODE4")
	)
	(segment
		(start 185.071512 -283.074872)
		(end 185.555382 -282.591002)
		(width 0.13208)
		(layer "B.Cu")
		(net "PEX1_DBG_MODE4")
	)
	(segment
		(start 154.193494 -251.63145)
		(end 154.666442 -251.158502)
		(width 0.13208)
		(layer "B.Cu")
		(net "PEX1_DBG_MODE4")
	)
	(segment
		(start 184.77484 -283.074872)
		(end 185.071512 -283.074872)
		(width 0.13208)
		(layer "B.Cu")
		(net "PEX1_DBG_MODE4")
	)
	(segment
		(start 186.680094 -281.74696)
		(end 186.680094 -272.169636)
		(width 0.13208)
		(layer "B.Cu")
		(net "PEX1_DBG_MODE4")
	)
	(segment
		(start 168.740328 -254.22987)
		(end 154.35199 -254.22987)
		(width 0.13208)
		(layer "B.Cu")
		(net "PEX1_DBG_MODE4")
	)
	(segment
		(start 186.680094 -272.169636)
		(end 168.740328 -254.22987)
		(width 0.13208)
		(layer "B.Cu")
		(net "PEX1_DBG_MODE4")
	)
	(segment
		(start 185.555382 -282.591002)
		(end 185.836052 -282.591002)
		(width 0.13208)
		(layer "B.Cu")
		(net "PEX1_DBG_MODE4")
	)
	(segment
		(start 154.35199 -254.22987)
		(end 154.193494 -254.071374)
		(width 0.13208)
		(layer "B.Cu")
		(net "PEX1_DBG_MODE4")
	)
	(segment
		(start 154.193494 -254.071374)
		(end 154.193494 -251.63145)
		(width 0.13208)
		(layer "B.Cu")
		(net "PEX1_DBG_MODE4")
	)
	(segment
		(start 382.953768 -311.015888)
		(end 382.88087 -311.015888)
		(width 0.13208)
		(layer "F.Cu")
		(net "PU_PEX3_ATPG_MODE_L")
	)
	(segment
		(start 382.88087 -311.015888)
		(end 381 -309.135018)
		(width 0.13208)
		(layer "F.Cu")
		(net "PU_PEX3_ATPG_MODE_L")
	)
	(segment
		(start 398.4498 -309.199788)
		(end 397.97482 -309.674768)
		(width 0.13208)
		(layer "F.Cu")
		(net "PU_PEX3_ATPG_MODE_L")
	)
	(via
		(at 383.9337 -310.96204)
		(size 0.6604)
		(drill 0.3302)
		(layers "F.Cu" "B.Cu")
		(net "PU_PEX3_ATPG_MODE_L")
	)
	(via
		(at 382.953768 -311.015888)
		(size 0.508)
		(drill 0.254)
		(layers "F.Cu" "B.Cu")
		(net "PU_PEX3_ATPG_MODE_L")
	)
	(via
		(at 397.97482 -309.674768)
		(size 0.4064)
		(drill 0.2032)
		(layers "F.Cu" "B.Cu")
		(net "PU_PEX3_ATPG_MODE_L")
	)
	(segment
		(start 397.97482 -310.272176)
		(end 397.97482 -309.674768)
		(width 0.13208)
		(layer "B.Cu")
		(net "PU_PEX3_ATPG_MODE_L")
	)
	(segment
		(start 384.30454 -310.5912)
		(end 397.655796 -310.5912)
		(width 0.13208)
		(layer "B.Cu")
		(net "PU_PEX3_ATPG_MODE_L")
	)
	(segment
		(start 382.953768 -311.015888)
		(end 383.879852 -311.015888)
		(width 0.13208)
		(layer "B.Cu")
		(net "PU_PEX3_ATPG_MODE_L")
	)
	(segment
		(start 397.655796 -310.5912)
		(end 397.97482 -310.272176)
		(width 0.13208)
		(layer "B.Cu")
		(net "PU_PEX3_ATPG_MODE_L")
	)
	(segment
		(start 383.879852 -311.015888)
		(end 383.9337 -310.96204)
		(width 0.13208)
		(layer "B.Cu")
		(net "PU_PEX3_ATPG_MODE_L")
	)
	(segment
		(start 383.9337 -310.96204)
		(end 384.30454 -310.5912)
		(width 0.13208)
		(layer "B.Cu")
		(net "PU_PEX3_ATPG_MODE_L")
	)
	(segment
		(start 149.315932 -387.06806)
		(end 149.315932 -388.19836)
		(width 0.13208)
		(layer "F.Cu")
		(net "GPU_BASE_HMC_READY")
	)
	(segment
		(start 149.303486 -389.998204)
		(end 149.303486 -388.210806)
		(width 0.13208)
		(layer "F.Cu")
		(net "GPU_BASE_HMC_READY")
	)
	(segment
		(start 149.315932 -388.19836)
		(end 149.303486 -388.210806)
		(width 0.13208)
		(layer "F.Cu")
		(net "GPU_BASE_HMC_READY")
	)
	(via
		(at 149.303486 -388.210806)
		(size 0.508)
		(drill 0.254)
		(layers "F.Cu" "B.Cu")
		(net "GPU_BASE_HMC_READY")
	)
	(segment
		(start 154.9654 -389.7884)
		(end 150.88108 -389.7884)
		(width 0.13208)
		(layer "B.Cu")
		(net "GPU_BASE_HMC_READY")
	)
	(segment
		(start 150.88108 -389.7884)
		(end 149.303486 -388.210806)
		(width 0.13208)
		(layer "B.Cu")
		(net "GPU_BASE_HMC_READY")
	)
	(segment
		(start 168.710102 -412.090108)
		(end 167.82161 -412.9786)
		(width 0.13208)
		(layer "B.Cu")
		(net "GPU_BASE_HMC_READY")
	)
	(segment
		(start 156.9974 -391.8204)
		(end 154.9654 -389.7884)
		(width 0.13208)
		(layer "B.Cu")
		(net "GPU_BASE_HMC_READY")
	)
	(segment
		(start 167.82161 -412.9786)
		(end 159.258 -412.9786)
		(width 0.13208)
		(layer "B.Cu")
		(net "GPU_BASE_HMC_READY")
	)
	(segment
		(start 156.9974 -410.718)
		(end 156.9974 -391.8204)
		(width 0.13208)
		(layer "B.Cu")
		(net "GPU_BASE_HMC_READY")
	)
	(segment
		(start 159.258 -412.9786)
		(end 156.9974 -410.718)
		(width 0.13208)
		(layer "B.Cu")
		(net "GPU_BASE_HMC_READY")
	)
	(segment
		(start 381.948182 -59.309)
		(end 382.079246 -59.177936)
		(width 0.13208)
		(layer "F.Cu")
		(net "PWRGD_P3V3_SSD13")
	)
	(segment
		(start 381.94107 -57.457848)
		(end 382.325118 -57.841896)
		(width 0.13208)
		(layer "F.Cu")
		(net "PWRGD_P3V3_SSD13")
	)
	(segment
		(start 381.94107 -57.16397)
		(end 381.94107 -57.457848)
		(width 0.13208)
		(layer "F.Cu")
		(net "PWRGD_P3V3_SSD13")
	)
	(segment
		(start 382.079246 -59.177936)
		(end 382.479042 -59.177936)
		(width 0.13208)
		(layer "F.Cu")
		(net "PWRGD_P3V3_SSD13")
	)
	(segment
		(start 381.948182 -61.22416)
		(end 381.948182 -59.309)
		(width 0.13208)
		(layer "F.Cu")
		(net "PWRGD_P3V3_SSD13")
	)
	(segment
		(start 382.325118 -58.565796)
		(end 382.479042 -58.71972)
		(width 0.13208)
		(layer "F.Cu")
		(net "PWRGD_P3V3_SSD13")
	)
	(segment
		(start 382.325118 -57.841896)
		(end 382.325118 -57.867296)
		(width 0.13208)
		(layer "F.Cu")
		(net "PWRGD_P3V3_SSD13")
	)
	(segment
		(start 382.479042 -58.71972)
		(end 382.479042 -59.177936)
		(width 0.13208)
		(layer "F.Cu")
		(net "PWRGD_P3V3_SSD13")
	)
	(segment
		(start 382.110996 -61.386974)
		(end 381.948182 -61.22416)
		(width 0.13208)
		(layer "F.Cu")
		(net "PWRGD_P3V3_SSD13")
	)
	(segment
		(start 382.325118 -57.867296)
		(end 382.325118 -58.565796)
		(width 0.13208)
		(layer "F.Cu")
		(net "PWRGD_P3V3_SSD13")
	)
	(via
		(at 382.325118 -57.867296)
		(size 0.508)
		(drill 0.254)
		(layers "F.Cu" "B.Cu")
		(net "PWRGD_P3V3_SSD13")
	)
	(segment
		(start 71.999856 -282.599892)
		(end 72.474836 -283.074872)
		(width 0.13208)
		(layer "F.Cu")
		(net "PEX0_MODE_SEL1")
	)
	(segment
		(start 224.653602 -189.168278)
		(end 225.257106 -189.168278)
		(width 0.13208)
		(layer "F.Cu")
		(net "PEX0_MODE_SEL1")
	)
	(segment
		(start 242.1382 -191.5668)
		(end 243.50472 -191.5668)
		(width 0.13208)
		(layer "F.Cu")
		(net "PEX0_MODE_SEL1")
	)
	(segment
		(start 225.257106 -189.168278)
		(end 226.51593 -187.909454)
		(width 0.13208)
		(layer "F.Cu")
		(net "PEX0_MODE_SEL1")
	)
	(segment
		(start 289.2298 -179.959)
		(end 293.566342 -179.959)
		(width 0.13208)
		(layer "F.Cu")
		(net "PEX0_MODE_SEL1")
	)
	(segment
		(start 281.7876 -187.4012)
		(end 289.2298 -179.959)
		(width 0.13208)
		(layer "F.Cu")
		(net "PEX0_MODE_SEL1")
	)
	(segment
		(start 243.50472 -191.5668)
		(end 247.67032 -187.4012)
		(width 0.13208)
		(layer "F.Cu")
		(net "PEX0_MODE_SEL1")
	)
	(segment
		(start 293.566342 -179.959)
		(end 295.388284 -178.137058)
		(width 0.13208)
		(layer "F.Cu")
		(net "PEX0_MODE_SEL1")
	)
	(segment
		(start 226.51593 -187.908946)
		(end 228.547676 -185.8772)
		(width 0.13208)
		(layer "F.Cu")
		(net "PEX0_MODE_SEL1")
	)
	(segment
		(start 247.67032 -187.4012)
		(end 281.7876 -187.4012)
		(width 0.13208)
		(layer "F.Cu")
		(net "PEX0_MODE_SEL1")
	)
	(segment
		(start 228.547676 -185.8772)
		(end 235.711746 -185.8772)
		(width 0.13208)
		(layer "F.Cu")
		(net "PEX0_MODE_SEL1")
	)
	(segment
		(start 239.0394 -187.1218)
		(end 241.427 -189.5094)
		(width 0.13208)
		(layer "F.Cu")
		(net "PEX0_MODE_SEL1")
	)
	(segment
		(start 295.388284 -177.746914)
		(end 295.312084 -177.670714)
		(width 0.13208)
		(layer "F.Cu")
		(net "PEX0_MODE_SEL1")
	)
	(segment
		(start 40.598344 -251.956824)
		(end 40.598344 -251.158502)
		(width 0.13208)
		(layer "F.Cu")
		(net "PEX0_MODE_SEL1")
	)
	(segment
		(start 226.51593 -187.909454)
		(end 226.51593 -187.908946)
		(width 0.13208)
		(layer "F.Cu")
		(net "PEX0_MODE_SEL1")
	)
	(segment
		(start 410.612082 -193.402458)
		(end 409.593542 -193.402458)
		(width 0.13208)
		(layer "F.Cu")
		(net "PEX0_MODE_SEL1")
	)
	(segment
		(start 241.427 -189.5094)
		(end 241.427 -190.8556)
		(width 0.13208)
		(layer "F.Cu")
		(net "PEX0_MODE_SEL1")
	)
	(segment
		(start 295.388284 -178.137058)
		(end 295.388284 -177.746914)
		(width 0.13208)
		(layer "F.Cu")
		(net "PEX0_MODE_SEL1")
	)
	(segment
		(start 40.598344 -251.158502)
		(end 40.598344 -250.470924)
		(width 0.13208)
		(layer "F.Cu")
		(net "PEX0_MODE_SEL1")
	)
	(segment
		(start 241.427 -190.8556)
		(end 242.1382 -191.5668)
		(width 0.13208)
		(layer "F.Cu")
		(net "PEX0_MODE_SEL1")
	)
	(segment
		(start 236.956346 -187.1218)
		(end 239.0394 -187.1218)
		(width 0.13208)
		(layer "F.Cu")
		(net "PEX0_MODE_SEL1")
	)
	(segment
		(start 235.711746 -185.8772)
		(end 236.956346 -187.1218)
		(width 0.13208)
		(layer "F.Cu")
		(net "PEX0_MODE_SEL1")
	)
	(via
		(at 224.653602 -189.168278)
		(size 0.508)
		(drill 0.254)
		(layers "F.Cu" "B.Cu")
		(net "PEX0_MODE_SEL1")
	)
	(via
		(at 40.598344 -251.158502)
		(size 0.508)
		(drill 0.254)
		(layers "F.Cu" "B.Cu")
		(net "PEX0_MODE_SEL1")
	)
	(via
		(at 181.158388 -201.501248)
		(size 0.508)
		(drill 0.254)
		(layers "F.Cu" "B.Cu")
		(net "PEX0_MODE_SEL1")
	)
	(via
		(at 72.474836 -283.074872)
		(size 0.4064)
		(drill 0.2032)
		(layers "F.Cu" "B.Cu")
		(net "PEX0_MODE_SEL1")
	)
	(via
		(at 295.312084 -177.670714)
		(size 0.508)
		(drill 0.254)
		(layers "F.Cu" "B.Cu")
		(net "PEX0_MODE_SEL1")
	)
	(via
		(at 409.593542 -193.402458)
		(size 0.508)
		(drill 0.254)
		(layers "F.Cu" "B.Cu")
		(net "PEX0_MODE_SEL1")
	)
	(segment
		(start 73.42759 -271.937226)
		(end 52.648866 -251.158502)
		(width 0.13208)
		(layer "B.Cu")
		(net "PEX0_MODE_SEL1")
	)
	(segment
		(start 73.42759 -282.122118)
		(end 73.42759 -271.937226)
		(width 0.13208)
		(layer "B.Cu")
		(net "PEX0_MODE_SEL1")
	)
	(segment
		(start 40.598344 -251.158502)
		(end 40.598344 -248.158)
		(width 0.13208)
		(layer "B.Cu")
		(net "PEX0_MODE_SEL1")
	)
	(segment
		(start 124.836936 -217.292936)
		(end 169.985944 -217.292936)
		(width 0.13208)
		(layer "B.Cu")
		(net "PEX0_MODE_SEL1")
	)
	(segment
		(start 124.2568 -216.7128)
		(end 124.836936 -217.292936)
		(width 0.13208)
		(layer "B.Cu")
		(net "PEX0_MODE_SEL1")
	)
	(segment
		(start 47.253144 -241.5032)
		(end 68.652136 -241.5032)
		(width 0.13208)
		(layer "B.Cu")
		(net "PEX0_MODE_SEL1")
	)
	(segment
		(start 179.247292 -208.031588)
		(end 179.247292 -202.277472)
		(width 0.13208)
		(layer "B.Cu")
		(net "PEX0_MODE_SEL1")
	)
	(segment
		(start 120.92051 -216.7128)
		(end 124.2568 -216.7128)
		(width 0.13208)
		(layer "B.Cu")
		(net "PEX0_MODE_SEL1")
	)
	(segment
		(start 100.863146 -209.29219)
		(end 113.4999 -209.29219)
		(width 0.13208)
		(layer "B.Cu")
		(net "PEX0_MODE_SEL1")
	)
	(segment
		(start 180.023516 -201.501248)
		(end 181.158388 -201.501248)
		(width 0.13208)
		(layer "B.Cu")
		(net "PEX0_MODE_SEL1")
	)
	(segment
		(start 40.598344 -248.158)
		(end 47.253144 -241.5032)
		(width 0.13208)
		(layer "B.Cu")
		(net "PEX0_MODE_SEL1")
	)
	(segment
		(start 72.474836 -283.074872)
		(end 73.42759 -282.122118)
		(width 0.13208)
		(layer "B.Cu")
		(net "PEX0_MODE_SEL1")
	)
	(segment
		(start 68.652136 -241.5032)
		(end 100.863146 -209.29219)
		(width 0.13208)
		(layer "B.Cu")
		(net "PEX0_MODE_SEL1")
	)
	(segment
		(start 52.648866 -251.158502)
		(end 40.598344 -251.158502)
		(width 0.13208)
		(layer "B.Cu")
		(net "PEX0_MODE_SEL1")
	)
	(segment
		(start 113.4999 -209.29219)
		(end 120.92051 -216.7128)
		(width 0.13208)
		(layer "B.Cu")
		(net "PEX0_MODE_SEL1")
	)
	(segment
		(start 169.985944 -217.292936)
		(end 179.247292 -208.031588)
		(width 0.13208)
		(layer "B.Cu")
		(net "PEX0_MODE_SEL1")
	)
	(segment
		(start 179.247292 -202.277472)
		(end 180.023516 -201.501248)
		(width 0.13208)
		(layer "B.Cu")
		(net "PEX0_MODE_SEL1")
	)
	(segment
		(start 296.109136 -177.670714)
		(end 297.283378 -178.844956)
		(width 0.15494)
		(layer "In13.Cu")
		(net "PEX0_MODE_SEL1")
	)
	(segment
		(start 366.792256 -176.675288)
		(end 367.906554 -177.789586)
		(width 0.15494)
		(layer "In13.Cu")
		(net "PEX0_MODE_SEL1")
	)
	(segment
		(start 338.12353 -179.316126)
		(end 338.807298 -179.999894)
		(width 0.15494)
		(layer "In13.Cu")
		(net "PEX0_MODE_SEL1")
	)
	(segment
		(start 345.112086 -179.379118)
		(end 348.674436 -175.816768)
		(width 0.15494)
		(layer "In13.Cu")
		(net "PEX0_MODE_SEL1")
	)
	(segment
		(start 336.066892 -179.462176)
		(end 336.212942 -179.316126)
		(width 0.15494)
		(layer "In13.Cu")
		(net "PEX0_MODE_SEL1")
	)
	(segment
		(start 322.709794 -184.504584)
		(end 327.94067 -184.504584)
		(width 0.15494)
		(layer "In13.Cu")
		(net "PEX0_MODE_SEL1")
	)
	(segment
		(start 338.807298 -179.999894)
		(end 341.07247 -179.999894)
		(width 0.15494)
		(layer "In13.Cu")
		(net "PEX0_MODE_SEL1")
	)
	(segment
		(start 297.283378 -178.844956)
		(end 317.050166 -178.844956)
		(width 0.15494)
		(layer "In13.Cu")
		(net "PEX0_MODE_SEL1")
	)
	(segment
		(start 295.312084 -177.670714)
		(end 296.109136 -177.670714)
		(width 0.15494)
		(layer "In13.Cu")
		(net "PEX0_MODE_SEL1")
	)
	(segment
		(start 364.421928 -176.94021)
		(end 364.68685 -176.675288)
		(width 0.15494)
		(layer "In13.Cu")
		(net "PEX0_MODE_SEL1")
	)
	(segment
		(start 317.050166 -178.844956)
		(end 322.709794 -184.504584)
		(width 0.15494)
		(layer "In13.Cu")
		(net "PEX0_MODE_SEL1")
	)
	(segment
		(start 367.906554 -177.789586)
		(end 374.762522 -177.789586)
		(width 0.15494)
		(layer "In13.Cu")
		(net "PEX0_MODE_SEL1")
	)
	(segment
		(start 348.674436 -175.816768)
		(end 357.448104 -175.816768)
		(width 0.15494)
		(layer "In13.Cu")
		(net "PEX0_MODE_SEL1")
	)
	(segment
		(start 357.448104 -175.816768)
		(end 357.649018 -176.017682)
		(width 0.15494)
		(layer "In13.Cu")
		(net "PEX0_MODE_SEL1")
	)
	(segment
		(start 376.01652 -178.309016)
		(end 381.017526 -183.310022)
		(width 0.15494)
		(layer "In13.Cu")
		(net "PEX0_MODE_SEL1")
	)
	(segment
		(start 359.24109 -175.8823)
		(end 360.5403 -175.8823)
		(width 0.15494)
		(layer "In13.Cu")
		(net "PEX0_MODE_SEL1")
	)
	(segment
		(start 374.762522 -177.789586)
		(end 376.01652 -178.309016)
		(width 0.15494)
		(layer "In13.Cu")
		(net "PEX0_MODE_SEL1")
	)
	(segment
		(start 381.017526 -183.310022)
		(end 407.866088 -183.310022)
		(width 0.15494)
		(layer "In13.Cu")
		(net "PEX0_MODE_SEL1")
	)
	(segment
		(start 359.105708 -176.017682)
		(end 359.24109 -175.8823)
		(width 0.15494)
		(layer "In13.Cu")
		(net "PEX0_MODE_SEL1")
	)
	(segment
		(start 360.5403 -175.8823)
		(end 361.59821 -176.94021)
		(width 0.15494)
		(layer "In13.Cu")
		(net "PEX0_MODE_SEL1")
	)
	(segment
		(start 410.003498 -185.447432)
		(end 410.003498 -187.456826)
		(width 0.15494)
		(layer "In13.Cu")
		(net "PEX0_MODE_SEL1")
	)
	(segment
		(start 341.693246 -179.379118)
		(end 345.112086 -179.379118)
		(width 0.15494)
		(layer "In13.Cu")
		(net "PEX0_MODE_SEL1")
	)
	(segment
		(start 364.68685 -176.675288)
		(end 366.792256 -176.675288)
		(width 0.15494)
		(layer "In13.Cu")
		(net "PEX0_MODE_SEL1")
	)
	(segment
		(start 410.003498 -187.456826)
		(end 409.593542 -187.866782)
		(width 0.15494)
		(layer "In13.Cu")
		(net "PEX0_MODE_SEL1")
	)
	(segment
		(start 336.212942 -179.316126)
		(end 338.12353 -179.316126)
		(width 0.15494)
		(layer "In13.Cu")
		(net "PEX0_MODE_SEL1")
	)
	(segment
		(start 357.649018 -176.017682)
		(end 359.105708 -176.017682)
		(width 0.15494)
		(layer "In13.Cu")
		(net "PEX0_MODE_SEL1")
	)
	(segment
		(start 341.07247 -179.999894)
		(end 341.693246 -179.379118)
		(width 0.15494)
		(layer "In13.Cu")
		(net "PEX0_MODE_SEL1")
	)
	(segment
		(start 327.94067 -184.504584)
		(end 332.983078 -179.462176)
		(width 0.15494)
		(layer "In13.Cu")
		(net "PEX0_MODE_SEL1")
	)
	(segment
		(start 407.866088 -183.310022)
		(end 410.003498 -185.447432)
		(width 0.15494)
		(layer "In13.Cu")
		(net "PEX0_MODE_SEL1")
	)
	(segment
		(start 409.593542 -187.866782)
		(end 409.593542 -193.402458)
		(width 0.15494)
		(layer "In13.Cu")
		(net "PEX0_MODE_SEL1")
	)
	(segment
		(start 361.59821 -176.94021)
		(end 364.421928 -176.94021)
		(width 0.15494)
		(layer "In13.Cu")
		(net "PEX0_MODE_SEL1")
	)
	(segment
		(start 332.983078 -179.462176)
		(end 336.066892 -179.462176)
		(width 0.15494)
		(layer "In13.Cu")
		(net "PEX0_MODE_SEL1")
	)
	(segment
		(start 218.38666 -191.54013)
		(end 213.689438 -191.54013)
		(width 0.15494)
		(layer "In15.Cu")
		(net "PEX0_MODE_SEL1")
	)
	(segment
		(start 213.689438 -191.54013)
		(end 210.43519 -194.794378)
		(width 0.15494)
		(layer "In15.Cu")
		(net "PEX0_MODE_SEL1")
	)
	(segment
		(start 224.734628 -193.84264)
		(end 221.464632 -193.84264)
		(width 0.15494)
		(layer "In15.Cu")
		(net "PEX0_MODE_SEL1")
	)
	(segment
		(start 200.96226 -195.08724)
		(end 194.548252 -201.501248)
		(width 0.15494)
		(layer "In15.Cu")
		(net "PEX0_MODE_SEL1")
	)
	(segment
		(start 209.637122 -194.794378)
		(end 209.34426 -195.08724)
		(width 0.15494)
		(layer "In15.Cu")
		(net "PEX0_MODE_SEL1")
	)
	(segment
		(start 225.226372 -193.350896)
		(end 224.734628 -193.84264)
		(width 0.15494)
		(layer "In15.Cu")
		(net "PEX0_MODE_SEL1")
	)
	(segment
		(start 194.548252 -201.501248)
		(end 181.158388 -201.501248)
		(width 0.15494)
		(layer "In15.Cu")
		(net "PEX0_MODE_SEL1")
	)
	(segment
		(start 210.43519 -194.794378)
		(end 209.637122 -194.794378)
		(width 0.15494)
		(layer "In15.Cu")
		(net "PEX0_MODE_SEL1")
	)
	(segment
		(start 221.464632 -193.84264)
		(end 221.235016 -194.072256)
		(width 0.15494)
		(layer "In15.Cu")
		(net "PEX0_MODE_SEL1")
	)
	(segment
		(start 221.235016 -194.072256)
		(end 220.513402 -194.072256)
		(width 0.15494)
		(layer "In15.Cu")
		(net "PEX0_MODE_SEL1")
	)
	(segment
		(start 224.653602 -189.168278)
		(end 225.226372 -189.741048)
		(width 0.15494)
		(layer "In15.Cu")
		(net "PEX0_MODE_SEL1")
	)
	(segment
		(start 219.349574 -192.503044)
		(end 218.38666 -191.54013)
		(width 0.15494)
		(layer "In15.Cu")
		(net "PEX0_MODE_SEL1")
	)
	(segment
		(start 219.349574 -192.908428)
		(end 219.349574 -192.503044)
		(width 0.15494)
		(layer "In15.Cu")
		(net "PEX0_MODE_SEL1")
	)
	(segment
		(start 209.34426 -195.08724)
		(end 200.96226 -195.08724)
		(width 0.15494)
		(layer "In15.Cu")
		(net "PEX0_MODE_SEL1")
	)
	(segment
		(start 220.513402 -194.072256)
		(end 219.349574 -192.908428)
		(width 0.15494)
		(layer "In15.Cu")
		(net "PEX0_MODE_SEL1")
	)
	(segment
		(start 225.226372 -189.741048)
		(end 225.226372 -193.350896)
		(width 0.15494)
		(layer "In15.Cu")
		(net "PEX0_MODE_SEL1")
	)
	(segment
		(start 144.488154 -307.36794)
		(end 143.769842 -308.086252)
		(width 0.13208)
		(layer "F.Cu")
		(net "PEX1_DBG_SEL0")
	)
	(segment
		(start 143.769842 -308.086252)
		(end 144.134078 -308.450488)
		(width 0.13208)
		(layer "F.Cu")
		(net "PEX1_DBG_SEL0")
	)
	(segment
		(start 144.134078 -308.450488)
		(end 144.56029 -308.450488)
		(width 0.13208)
		(layer "F.Cu")
		(net "PEX1_DBG_SEL0")
	)
	(segment
		(start 169.099992 -309.199788)
		(end 168.625012 -308.724808)
		(width 0.13208)
		(layer "F.Cu")
		(net "PEX1_DBG_SEL0")
	)
	(via
		(at 168.625012 -308.724808)
		(size 0.4064)
		(drill 0.2032)
		(layers "F.Cu" "B.Cu")
		(net "PEX1_DBG_SEL0")
	)
	(via
		(at 144.56029 -308.450488)
		(size 0.508)
		(drill 0.254)
		(layers "F.Cu" "B.Cu")
		(net "PEX1_DBG_SEL0")
	)
	(segment
		(start 162.026854 -306.7558)
		(end 162.536632 -307.265578)
		(width 0.13208)
		(layer "B.Cu")
		(net "PEX1_DBG_SEL0")
	)
	(segment
		(start 146.294094 -308.450488)
		(end 147.988782 -306.7558)
		(width 0.13208)
		(layer "B.Cu")
		(net "PEX1_DBG_SEL0")
	)
	(segment
		(start 164.3126 -307.972968)
		(end 164.505894 -308.166262)
		(width 0.13208)
		(layer "B.Cu")
		(net "PEX1_DBG_SEL0")
	)
	(segment
		(start 164.3126 -307.548026)
		(end 164.3126 -307.972968)
		(width 0.13208)
		(layer "B.Cu")
		(net "PEX1_DBG_SEL0")
	)
	(segment
		(start 147.988782 -306.7558)
		(end 162.026854 -306.7558)
		(width 0.13208)
		(layer "B.Cu")
		(net "PEX1_DBG_SEL0")
	)
	(segment
		(start 164.505894 -308.166262)
		(end 168.066466 -308.166262)
		(width 0.13208)
		(layer "B.Cu")
		(net "PEX1_DBG_SEL0")
	)
	(segment
		(start 168.066466 -308.166262)
		(end 168.625012 -308.724808)
		(width 0.13208)
		(layer "B.Cu")
		(net "PEX1_DBG_SEL0")
	)
	(segment
		(start 162.536632 -307.265578)
		(end 164.030152 -307.265578)
		(width 0.13208)
		(layer "B.Cu")
		(net "PEX1_DBG_SEL0")
	)
	(segment
		(start 164.030152 -307.265578)
		(end 164.3126 -307.548026)
		(width 0.13208)
		(layer "B.Cu")
		(net "PEX1_DBG_SEL0")
	)
	(segment
		(start 144.56029 -308.450488)
		(end 146.294094 -308.450488)
		(width 0.13208)
		(layer "B.Cu")
		(net "PEX1_DBG_SEL0")
	)
	(segment
		(start 402.249894 -309.199788)
		(end 402.724874 -308.724808)
		(width 0.127)
		(layer "F.Cu")
		(net "TP_PEX3_TDO")
	)
	(via
		(at 402.724874 -308.724808)
		(size 0.4064)
		(drill 0.2032)
		(layers "F.Cu" "B.Cu")
		(net "TP_PEX3_TDO")
	)
	(via
		(at 402.249894 -309.199788)
		(size 0.6604)
		(drill 0.3302)
		(layers "F.Cu" "B.Cu")
		(net "TP_PEX3_TDO")
	)
	(segment
		(start 402.249894 -309.199788)
		(end 402.724874 -308.724808)
		(width 0.13208)
		(layer "B.Cu")
		(net "TP_PEX3_TDO")
	)
	(segment
		(start 61.445394 -387.93674)
		(end 61.173868 -387.93674)
		(width 0.13208)
		(layer "F.Cu")
		(net "GPU_PWR_BRAKE_N")
	)
	(segment
		(start 64.239394 -389.519922)
		(end 63.860426 -389.89889)
		(width 0.13208)
		(layer "F.Cu")
		(net "GPU_PWR_BRAKE_N")
	)
	(segment
		(start 59.086242 -387.750812)
		(end 59.25693 -387.580124)
		(width 0.13208)
		(layer "F.Cu")
		(net "GPU_PWR_BRAKE_N")
	)
	(segment
		(start 59.25693 -387.580124)
		(end 60.817252 -387.580124)
		(width 0.13208)
		(layer "F.Cu")
		(net "GPU_PWR_BRAKE_N")
	)
	(segment
		(start 61.655452 -388.146798)
		(end 61.445394 -387.93674)
		(width 0.13208)
		(layer "F.Cu")
		(net "GPU_PWR_BRAKE_N")
	)
	(segment
		(start 61.95949 -389.89889)
		(end 61.655452 -389.594852)
		(width 0.13208)
		(layer "F.Cu")
		(net "GPU_PWR_BRAKE_N")
	)
	(segment
		(start 60.817252 -387.580124)
		(end 61.173868 -387.93674)
		(width 0.13208)
		(layer "F.Cu")
		(net "GPU_PWR_BRAKE_N")
	)
	(segment
		(start 61.655452 -389.594852)
		(end 61.655452 -388.146798)
		(width 0.13208)
		(layer "F.Cu")
		(net "GPU_PWR_BRAKE_N")
	)
	(segment
		(start 62.467998 -387.156198)
		(end 63.737998 -387.156198)
		(width 0.13208)
		(layer "F.Cu")
		(net "GPU_PWR_BRAKE_N")
	)
	(segment
		(start 63.737998 -387.156198)
		(end 64.239394 -387.657594)
		(width 0.13208)
		(layer "F.Cu")
		(net "GPU_PWR_BRAKE_N")
	)
	(segment
		(start 64.239394 -387.657594)
		(end 64.239394 -389.519922)
		(width 0.13208)
		(layer "F.Cu")
		(net "GPU_PWR_BRAKE_N")
	)
	(segment
		(start 63.860426 -389.89889)
		(end 61.95949 -389.89889)
		(width 0.13208)
		(layer "F.Cu")
		(net "GPU_PWR_BRAKE_N")
	)
	(via
		(at 62.467998 -387.156198)
		(size 0.508)
		(drill 0.254)
		(layers "F.Cu" "B.Cu")
		(net "GPU_PWR_BRAKE_N")
	)
	(segment
		(start 89.509854 -405.589994)
		(end 88.643206 -405.589994)
		(width 0.15494)
		(layer "In9.Cu")
		(net "GPU_PWR_BRAKE_N")
	)
	(segment
		(start 86.268306 -414.582864)
		(end 70.616318 -414.582864)
		(width 0.15494)
		(layer "In9.Cu")
		(net "GPU_PWR_BRAKE_N")
	)
	(segment
		(start 70.616318 -414.582864)
		(end 68.463414 -412.42996)
		(width 0.15494)
		(layer "In9.Cu")
		(net "GPU_PWR_BRAKE_N")
	)
	(segment
		(start 64.756284 -387.471666)
		(end 64.440816 -387.156198)
		(width 0.15494)
		(layer "In9.Cu")
		(net "GPU_PWR_BRAKE_N")
	)
	(segment
		(start 64.76492 -387.471666)
		(end 64.756284 -387.471666)
		(width 0.15494)
		(layer "In9.Cu")
		(net "GPU_PWR_BRAKE_N")
	)
	(segment
		(start 64.440816 -387.156198)
		(end 62.467998 -387.156198)
		(width 0.15494)
		(layer "In9.Cu")
		(net "GPU_PWR_BRAKE_N")
	)
	(segment
		(start 88.643206 -405.589994)
		(end 88.4174 -405.8158)
		(width 0.15494)
		(layer "In9.Cu")
		(net "GPU_PWR_BRAKE_N")
	)
	(segment
		(start 68.463414 -391.17016)
		(end 64.76492 -387.471666)
		(width 0.15494)
		(layer "In9.Cu")
		(net "GPU_PWR_BRAKE_N")
	)
	(segment
		(start 88.4174 -412.43377)
		(end 86.268306 -414.582864)
		(width 0.15494)
		(layer "In9.Cu")
		(net "GPU_PWR_BRAKE_N")
	)
	(segment
		(start 88.4174 -405.8158)
		(end 88.4174 -412.43377)
		(width 0.15494)
		(layer "In9.Cu")
		(net "GPU_PWR_BRAKE_N")
	)
	(segment
		(start 68.463414 -412.42996)
		(end 68.463414 -391.17016)
		(width 0.15494)
		(layer "In9.Cu")
		(net "GPU_PWR_BRAKE_N")
	)
	(segment
		(start 345.694 -210.947)
		(end 345.694 -211.58708)
		(width 0.13208)
		(layer "F.Cu")
		(net "PRSNT_SSD2_FPGA_N")
	)
	(segment
		(start 347.726 -208.915)
		(end 345.694 -210.947)
		(width 0.13208)
		(layer "F.Cu")
		(net "PRSNT_SSD2_FPGA_N")
	)
	(segment
		(start 347.726 -206.678022)
		(end 347.568774 -206.835248)
		(width 0.13208)
		(layer "F.Cu")
		(net "PRSNT_SSD2_FPGA_N")
	)
	(segment
		(start 347.568774 -206.835248)
		(end 347.726 -206.992474)
		(width 0.13208)
		(layer "F.Cu")
		(net "PRSNT_SSD2_FPGA_N")
	)
	(segment
		(start 345.694 -211.58708)
		(end 345.29395 -211.98713)
		(width 0.13208)
		(layer "F.Cu")
		(net "PRSNT_SSD2_FPGA_N")
	)
	(segment
		(start 347.726 -206.992474)
		(end 347.726 -208.915)
		(width 0.13208)
		(layer "F.Cu")
		(net "PRSNT_SSD2_FPGA_N")
	)
	(segment
		(start 347.726 -205.63205)
		(end 347.726 -206.678022)
		(width 0.13208)
		(layer "F.Cu")
		(net "PRSNT_SSD2_FPGA_N")
	)
	(via
		(at 347.568774 -206.835248)
		(size 0.762)
		(drill 0.381)
		(layers "F.Cu" "B.Cu")
		(net "PRSNT_SSD2_FPGA_N")
	)
	(segment
		(start 240.54816 -55.41137)
		(end 240.54816 -54.953154)
		(width 0.13208)
		(layer "F.Cu")
		(net "PWRGD_P3V3_SSD8")
	)
	(segment
		(start 240.343436 -54.20106)
		(end 240.343436 -54.00802)
		(width 0.13208)
		(layer "F.Cu")
		(net "PWRGD_P3V3_SSD8")
	)
	(segment
		(start 240.010188 -53.674772)
		(end 240.010188 -53.397404)
		(width 0.13208)
		(layer "F.Cu")
		(net "PWRGD_P3V3_SSD8")
	)
	(segment
		(start 240.343436 -54.74843)
		(end 240.343436 -54.20106)
		(width 0.13208)
		(layer "F.Cu")
		(net "PWRGD_P3V3_SSD8")
	)
	(segment
		(start 240.0173 -57.457594)
		(end 240.0173 -55.591202)
		(width 0.13208)
		(layer "F.Cu")
		(net "PWRGD_P3V3_SSD8")
	)
	(segment
		(start 240.54816 -54.953154)
		(end 240.343436 -54.74843)
		(width 0.13208)
		(layer "F.Cu")
		(net "PWRGD_P3V3_SSD8")
	)
	(segment
		(start 240.343436 -54.00802)
		(end 240.010188 -53.674772)
		(width 0.13208)
		(layer "F.Cu")
		(net "PWRGD_P3V3_SSD8")
	)
	(segment
		(start 240.180114 -57.620408)
		(end 240.0173 -57.457594)
		(width 0.13208)
		(layer "F.Cu")
		(net "PWRGD_P3V3_SSD8")
	)
	(segment
		(start 240.197132 -55.41137)
		(end 240.54816 -55.41137)
		(width 0.13208)
		(layer "F.Cu")
		(net "PWRGD_P3V3_SSD8")
	)
	(segment
		(start 240.0173 -55.591202)
		(end 240.197132 -55.41137)
		(width 0.13208)
		(layer "F.Cu")
		(net "PWRGD_P3V3_SSD8")
	)
	(via
		(at 240.343436 -54.20106)
		(size 0.508)
		(drill 0.254)
		(layers "F.Cu" "B.Cu")
		(net "PWRGD_P3V3_SSD8")
	)
	(segment
		(start 149.586442 -251.956824)
		(end 149.586442 -251.158502)
		(width 0.13208)
		(layer "F.Cu")
		(net "PEX1_DBG_MODE2")
	)
	(segment
		(start 149.586442 -251.158502)
		(end 149.586442 -250.470924)
		(width 0.13208)
		(layer "F.Cu")
		(net "PEX1_DBG_MODE2")
	)
	(segment
		(start 180.50002 -282.599892)
		(end 180.975 -283.074872)
		(width 0.13208)
		(layer "F.Cu")
		(net "PEX1_DBG_MODE2")
	)
	(via
		(at 177.211736 -267.544296)
		(size 0.6604)
		(drill 0.3302)
		(layers "F.Cu" "B.Cu")
		(net "PEX1_DBG_MODE2")
	)
	(via
		(at 149.586442 -251.158502)
		(size 0.508)
		(drill 0.254)
		(layers "F.Cu" "B.Cu")
		(net "PEX1_DBG_MODE2")
	)
	(via
		(at 180.975 -283.074872)
		(size 0.4064)
		(drill 0.2032)
		(layers "F.Cu" "B.Cu")
		(net "PEX1_DBG_MODE2")
	)
	(segment
		(start 150.9522 -255.2954)
		(end 149.873462 -255.2954)
		(width 0.13208)
		(layer "B.Cu")
		(net "PEX1_DBG_MODE2")
	)
	(segment
		(start 181.606952 -271.526)
		(end 181.937914 -271.856962)
		(width 0.13208)
		(layer "B.Cu")
		(net "PEX1_DBG_MODE2")
	)
	(segment
		(start 151.8158 -256.159)
		(end 150.9522 -255.2954)
		(width 0.13208)
		(layer "B.Cu")
		(net "PEX1_DBG_MODE2")
	)
	(segment
		(start 149.093936 -251.651008)
		(end 149.586442 -251.158502)
		(width 0.13208)
		(layer "B.Cu")
		(net "PEX1_DBG_MODE2")
	)
	(segment
		(start 149.093936 -254.515874)
		(end 149.093936 -251.651008)
		(width 0.13208)
		(layer "B.Cu")
		(net "PEX1_DBG_MODE2")
	)
	(segment
		(start 149.873462 -255.2954)
		(end 149.093936 -254.515874)
		(width 0.13208)
		(layer "B.Cu")
		(net "PEX1_DBG_MODE2")
	)
	(segment
		(start 165.82644 -256.159)
		(end 151.8158 -256.159)
		(width 0.13208)
		(layer "B.Cu")
		(net "PEX1_DBG_MODE2")
	)
	(segment
		(start 177.211736 -267.544296)
		(end 165.82644 -256.159)
		(width 0.13208)
		(layer "B.Cu")
		(net "PEX1_DBG_MODE2")
	)
	(segment
		(start 181.937914 -271.856962)
		(end 181.937914 -282.111958)
		(width 0.13208)
		(layer "B.Cu")
		(net "PEX1_DBG_MODE2")
	)
	(segment
		(start 181.19344 -271.526)
		(end 181.606952 -271.526)
		(width 0.13208)
		(layer "B.Cu")
		(net "PEX1_DBG_MODE2")
	)
	(segment
		(start 177.211736 -267.544296)
		(end 181.19344 -271.526)
		(width 0.13208)
		(layer "B.Cu")
		(net "PEX1_DBG_MODE2")
	)
	(segment
		(start 181.937914 -282.111958)
		(end 180.975 -283.074872)
		(width 0.13208)
		(layer "B.Cu")
		(net "PEX1_DBG_MODE2")
	)
	(segment
		(start 377.875038 -307.11775)
		(end 378.05487 -307.11775)
		(width 0.13208)
		(layer "F.Cu")
		(net "PEX3_DFT_IDDT")
	)
	(segment
		(start 378.05487 -307.11775)
		(end 378.407422 -306.765198)
		(width 0.13208)
		(layer "F.Cu")
		(net "PEX3_DFT_IDDT")
	)
	(segment
		(start 378.124974 -305.931062)
		(end 377.406662 -306.649374)
		(width 0.13208)
		(layer "F.Cu")
		(net "PEX3_DFT_IDDT")
	)
	(segment
		(start 377.406662 -306.649374)
		(end 377.875038 -307.11775)
		(width 0.13208)
		(layer "F.Cu")
		(net "PEX3_DFT_IDDT")
	)
	(segment
		(start 399.400014 -308.249828)
		(end 398.925034 -307.774848)
		(width 0.13208)
		(layer "F.Cu")
		(net "PEX3_DFT_IDDT")
	)
	(via
		(at 378.407422 -306.765198)
		(size 0.508)
		(drill 0.254)
		(layers "F.Cu" "B.Cu")
		(net "PEX3_DFT_IDDT")
	)
	(via
		(at 398.925034 -307.774848)
		(size 0.4064)
		(drill 0.2032)
		(layers "F.Cu" "B.Cu")
		(net "PEX3_DFT_IDDT")
	)
	(segment
		(start 380.285244 -304.887376)
		(end 378.407422 -306.765198)
		(width 0.13208)
		(layer "B.Cu")
		(net "PEX3_DFT_IDDT")
	)
	(segment
		(start 396.296642 -305.383692)
		(end 394.334492 -305.383692)
		(width 0.13208)
		(layer "B.Cu")
		(net "PEX3_DFT_IDDT")
	)
	(segment
		(start 393.838176 -304.887376)
		(end 380.285244 -304.887376)
		(width 0.13208)
		(layer "B.Cu")
		(net "PEX3_DFT_IDDT")
	)
	(segment
		(start 396.55623 -305.64328)
		(end 396.296642 -305.383692)
		(width 0.13208)
		(layer "B.Cu")
		(net "PEX3_DFT_IDDT")
	)
	(segment
		(start 394.334492 -305.383692)
		(end 393.838176 -304.887376)
		(width 0.13208)
		(layer "B.Cu")
		(net "PEX3_DFT_IDDT")
	)
	(segment
		(start 398.416018 -307.265832)
		(end 396.851378 -307.265832)
		(width 0.13208)
		(layer "B.Cu")
		(net "PEX3_DFT_IDDT")
	)
	(segment
		(start 396.55623 -306.970684)
		(end 396.55623 -305.64328)
		(width 0.13208)
		(layer "B.Cu")
		(net "PEX3_DFT_IDDT")
	)
	(segment
		(start 398.925034 -307.774848)
		(end 398.416018 -307.265832)
		(width 0.13208)
		(layer "B.Cu")
		(net "PEX3_DFT_IDDT")
	)
	(segment
		(start 396.851378 -307.265832)
		(end 396.55623 -306.970684)
		(width 0.13208)
		(layer "B.Cu")
		(net "PEX3_DFT_IDDT")
	)
	(segment
		(start 212.522054 -193.87312)
		(end 211.398866 -193.87312)
		(width 0.13208)
		(layer "F.Cu")
		(net "SMB_NIC7_R_SDA")
	)
	(segment
		(start 210.83905 -193.910204)
		(end 210.83905 -193.675)
		(width 0.13208)
		(layer "F.Cu")
		(net "SMB_NIC7_R_SDA")
	)
	(segment
		(start 210.631278 -194.117976)
		(end 210.83905 -193.910204)
		(width 0.13208)
		(layer "F.Cu")
		(net "SMB_NIC7_R_SDA")
	)
	(segment
		(start 216.214706 -215.254586)
		(end 216.835736 -215.254586)
		(width 0.13208)
		(layer "F.Cu")
		(net "SMB_NIC7_R_SDA")
	)
	(segment
		(start 211.200746 -193.675)
		(end 210.83905 -193.675)
		(width 0.13208)
		(layer "F.Cu")
		(net "SMB_NIC7_R_SDA")
	)
	(segment
		(start 207.672686 -194.117976)
		(end 210.631278 -194.117976)
		(width 0.13208)
		(layer "F.Cu")
		(net "SMB_NIC7_R_SDA")
	)
	(segment
		(start 211.398866 -193.87312)
		(end 211.200746 -193.675)
		(width 0.13208)
		(layer "F.Cu")
		(net "SMB_NIC7_R_SDA")
	)
	(segment
		(start 207.666336 -194.111626)
		(end 207.672686 -194.117976)
		(width 0.13208)
		(layer "F.Cu")
		(net "SMB_NIC7_R_SDA")
	)
	(via
		(at 207.666336 -194.111626)
		(size 0.508)
		(drill 0.254)
		(layers "F.Cu" "B.Cu")
		(net "SMB_NIC7_R_SDA")
	)
	(via
		(at 216.214706 -215.254586)
		(size 0.508)
		(drill 0.254)
		(layers "F.Cu" "B.Cu")
		(net "SMB_NIC7_R_SDA")
	)
	(segment
		(start 207.666336 -194.111626)
		(end 209.494374 -194.111626)
		(width 0.13208)
		(layer "B.Cu")
		(net "SMB_NIC7_R_SDA")
	)
	(segment
		(start 209.494374 -194.111626)
		(end 209.82305 -193.78295)
		(width 0.13208)
		(layer "B.Cu")
		(net "SMB_NIC7_R_SDA")
	)
	(segment
		(start 209.82305 -193.78295)
		(end 212.09 -193.78295)
		(width 0.13208)
		(layer "B.Cu")
		(net "SMB_NIC7_R_SDA")
	)
	(segment
		(start 208.8642 -211.6074)
		(end 208.7372 -211.7344)
		(width 0.15494)
		(layer "In7.Cu")
		(net "SMB_NIC7_R_SDA")
	)
	(segment
		(start 208.8642 -206.0194)
		(end 208.8642 -211.6074)
		(width 0.15494)
		(layer "In7.Cu")
		(net "SMB_NIC7_R_SDA")
	)
	(segment
		(start 216.377774 -218.7956)
		(end 217.113866 -218.059508)
		(width 0.15494)
		(layer "In7.Cu")
		(net "SMB_NIC7_R_SDA")
	)
	(segment
		(start 206.375 -203.5302)
		(end 208.8642 -206.0194)
		(width 0.15494)
		(layer "In7.Cu")
		(net "SMB_NIC7_R_SDA")
	)
	(segment
		(start 213.04885 -218.7956)
		(end 216.377774 -218.7956)
		(width 0.15494)
		(layer "In7.Cu")
		(net "SMB_NIC7_R_SDA")
	)
	(segment
		(start 217.113866 -216.167716)
		(end 216.214706 -215.268556)
		(width 0.15494)
		(layer "In7.Cu")
		(net "SMB_NIC7_R_SDA")
	)
	(segment
		(start 216.214706 -215.268556)
		(end 216.214706 -215.254586)
		(width 0.15494)
		(layer "In7.Cu")
		(net "SMB_NIC7_R_SDA")
	)
	(segment
		(start 207.555084 -194.111626)
		(end 206.375 -195.29171)
		(width 0.15494)
		(layer "In7.Cu")
		(net "SMB_NIC7_R_SDA")
	)
	(segment
		(start 207.666336 -194.111626)
		(end 207.555084 -194.111626)
		(width 0.15494)
		(layer "In7.Cu")
		(net "SMB_NIC7_R_SDA")
	)
	(segment
		(start 211.060792 -218.313)
		(end 212.56625 -218.313)
		(width 0.15494)
		(layer "In7.Cu")
		(net "SMB_NIC7_R_SDA")
	)
	(segment
		(start 206.375 -195.29171)
		(end 206.375 -203.5302)
		(width 0.15494)
		(layer "In7.Cu")
		(net "SMB_NIC7_R_SDA")
	)
	(segment
		(start 208.7372 -214.4522)
		(end 209.55 -215.265)
		(width 0.15494)
		(layer "In7.Cu")
		(net "SMB_NIC7_R_SDA")
	)
	(segment
		(start 208.7372 -211.7344)
		(end 208.7372 -214.4522)
		(width 0.15494)
		(layer "In7.Cu")
		(net "SMB_NIC7_R_SDA")
	)
	(segment
		(start 217.113866 -218.059508)
		(end 217.113866 -216.167716)
		(width 0.15494)
		(layer "In7.Cu")
		(net "SMB_NIC7_R_SDA")
	)
	(segment
		(start 209.55 -215.265)
		(end 209.55 -216.802208)
		(width 0.15494)
		(layer "In7.Cu")
		(net "SMB_NIC7_R_SDA")
	)
	(segment
		(start 212.56625 -218.313)
		(end 213.04885 -218.7956)
		(width 0.15494)
		(layer "In7.Cu")
		(net "SMB_NIC7_R_SDA")
	)
	(segment
		(start 209.55 -216.802208)
		(end 211.060792 -218.313)
		(width 0.15494)
		(layer "In7.Cu")
		(net "SMB_NIC7_R_SDA")
	)
	(via
		(at 89.723468 -415.087308)
		(size 0.6604)
		(drill 0.3302)
		(layers "F.Cu" "B.Cu")
		(net "TP_CLK_100M_MB_2_DN")
	)
	(segment
		(start 89.723468 -415.087308)
		(end 90.22588 -414.584896)
		(width 0.13208)
		(layer "B.Cu")
		(net "TP_CLK_100M_MB_2_DN")
	)
	(segment
		(start 90.22588 -402.406104)
		(end 89.509854 -401.690078)
		(width 0.13208)
		(layer "B.Cu")
		(net "TP_CLK_100M_MB_2_DN")
	)
	(segment
		(start 90.22588 -414.584896)
		(end 90.22588 -402.406104)
		(width 0.13208)
		(layer "B.Cu")
		(net "TP_CLK_100M_MB_2_DN")
	)
	(segment
		(start 344.49385 -215.187022)
		(end 344.893646 -214.787226)
		(width 0.13208)
		(layer "F.Cu")
		(net "SSD0_PWRDIS_BIC_R")
	)
	(segment
		(start 238.919512 -232.471468)
		(end 238.919512 -231.816656)
		(width 0.13208)
		(layer "F.Cu")
		(net "SSD0_PWRDIS_BIC_R")
	)
	(segment
		(start 238.919512 -234.327954)
		(end 238.919512 -232.471468)
		(width 0.13208)
		(layer "F.Cu")
		(net "SSD0_PWRDIS_BIC_R")
	)
	(via
		(at 267.561568 -211.528152)
		(size 0.508)
		(drill 0.254)
		(layers "F.Cu" "B.Cu")
		(net "SSD0_PWRDIS_BIC_R")
	)
	(via
		(at 344.893646 -214.787226)
		(size 0.4572)
		(drill 0.254)
		(layers "F.Cu" "B.Cu")
		(net "SSD0_PWRDIS_BIC_R")
	)
	(via
		(at 238.919512 -232.471468)
		(size 0.508)
		(drill 0.254)
		(layers "F.Cu" "B.Cu")
		(net "SSD0_PWRDIS_BIC_R")
	)
	(segment
		(start 238.919512 -232.471468)
		(end 239.41278 -231.9782)
		(width 0.15494)
		(layer "In7.Cu")
		(net "SSD0_PWRDIS_BIC_R")
	)
	(segment
		(start 252.87732 -220.302074)
		(end 252.99162 -220.187774)
		(width 0.15494)
		(layer "In7.Cu")
		(net "SSD0_PWRDIS_BIC_R")
	)
	(segment
		(start 239.41278 -231.9782)
		(end 242.036854 -231.9782)
		(width 0.15494)
		(layer "In7.Cu")
		(net "SSD0_PWRDIS_BIC_R")
	)
	(segment
		(start 246.367554 -226.5934)
		(end 247.7008 -226.5934)
		(width 0.15494)
		(layer "In7.Cu")
		(net "SSD0_PWRDIS_BIC_R")
	)
	(segment
		(start 244.0178 -229.997254)
		(end 244.0178 -228.943154)
		(width 0.15494)
		(layer "In7.Cu")
		(net "SSD0_PWRDIS_BIC_R")
	)
	(segment
		(start 247.7008 -226.5934)
		(end 250.4694 -223.8248)
		(width 0.15494)
		(layer "In7.Cu")
		(net "SSD0_PWRDIS_BIC_R")
	)
	(segment
		(start 252.02261 -223.142302)
		(end 252.02261 -222.55226)
		(width 0.15494)
		(layer "In7.Cu")
		(net "SSD0_PWRDIS_BIC_R")
	)
	(segment
		(start 265.451844 -211.585302)
		(end 265.963146 -211.074)
		(width 0.15494)
		(layer "In7.Cu")
		(net "SSD0_PWRDIS_BIC_R")
	)
	(segment
		(start 261.5946 -215.2142)
		(end 261.5946 -212.6234)
		(width 0.15494)
		(layer "In7.Cu")
		(net "SSD0_PWRDIS_BIC_R")
	)
	(segment
		(start 265.963146 -211.074)
		(end 266.8778 -211.074)
		(width 0.15494)
		(layer "In7.Cu")
		(net "SSD0_PWRDIS_BIC_R")
	)
	(segment
		(start 259.6134 -214.9602)
		(end 260.096 -215.4428)
		(width 0.15494)
		(layer "In7.Cu")
		(net "SSD0_PWRDIS_BIC_R")
	)
	(segment
		(start 261.5946 -212.6234)
		(end 262.632698 -211.585302)
		(width 0.15494)
		(layer "In7.Cu")
		(net "SSD0_PWRDIS_BIC_R")
	)
	(segment
		(start 261.366 -215.4428)
		(end 261.5946 -215.2142)
		(width 0.15494)
		(layer "In7.Cu")
		(net "SSD0_PWRDIS_BIC_R")
	)
	(segment
		(start 251.340112 -223.8248)
		(end 252.02261 -223.142302)
		(width 0.15494)
		(layer "In7.Cu")
		(net "SSD0_PWRDIS_BIC_R")
	)
	(segment
		(start 256.2606 -214.9602)
		(end 259.6134 -214.9602)
		(width 0.15494)
		(layer "In7.Cu")
		(net "SSD0_PWRDIS_BIC_R")
	)
	(segment
		(start 244.0178 -228.943154)
		(end 246.367554 -226.5934)
		(width 0.15494)
		(layer "In7.Cu")
		(net "SSD0_PWRDIS_BIC_R")
	)
	(segment
		(start 252.02261 -222.55226)
		(end 252.87732 -221.69755)
		(width 0.15494)
		(layer "In7.Cu")
		(net "SSD0_PWRDIS_BIC_R")
	)
	(segment
		(start 262.632698 -211.585302)
		(end 265.451844 -211.585302)
		(width 0.15494)
		(layer "In7.Cu")
		(net "SSD0_PWRDIS_BIC_R")
	)
	(segment
		(start 253.74346 -214.1728)
		(end 255.4732 -214.1728)
		(width 0.15494)
		(layer "In7.Cu")
		(net "SSD0_PWRDIS_BIC_R")
	)
	(segment
		(start 252.99162 -220.187774)
		(end 252.99162 -214.92464)
		(width 0.15494)
		(layer "In7.Cu")
		(net "SSD0_PWRDIS_BIC_R")
	)
	(segment
		(start 252.87732 -221.69755)
		(end 252.87732 -220.302074)
		(width 0.15494)
		(layer "In7.Cu")
		(net "SSD0_PWRDIS_BIC_R")
	)
	(segment
		(start 260.096 -215.4428)
		(end 261.366 -215.4428)
		(width 0.15494)
		(layer "In7.Cu")
		(net "SSD0_PWRDIS_BIC_R")
	)
	(segment
		(start 242.036854 -231.9782)
		(end 244.0178 -229.997254)
		(width 0.15494)
		(layer "In7.Cu")
		(net "SSD0_PWRDIS_BIC_R")
	)
	(segment
		(start 267.331952 -211.528152)
		(end 267.561568 -211.528152)
		(width 0.15494)
		(layer "In7.Cu")
		(net "SSD0_PWRDIS_BIC_R")
	)
	(segment
		(start 266.8778 -211.074)
		(end 267.331952 -211.528152)
		(width 0.15494)
		(layer "In7.Cu")
		(net "SSD0_PWRDIS_BIC_R")
	)
	(segment
		(start 255.4732 -214.1728)
		(end 256.2606 -214.9602)
		(width 0.15494)
		(layer "In7.Cu")
		(net "SSD0_PWRDIS_BIC_R")
	)
	(segment
		(start 250.4694 -223.8248)
		(end 251.340112 -223.8248)
		(width 0.15494)
		(layer "In7.Cu")
		(net "SSD0_PWRDIS_BIC_R")
	)
	(segment
		(start 252.99162 -214.92464)
		(end 253.74346 -214.1728)
		(width 0.15494)
		(layer "In7.Cu")
		(net "SSD0_PWRDIS_BIC_R")
	)
	(segment
		(start 333.27086 -206.927704)
		(end 333.30134 -206.958184)
		(width 0.15494)
		(layer "In15.Cu")
		(net "SSD0_PWRDIS_BIC_R")
	)
	(segment
		(start 298.540424 -207.966818)
		(end 300.158404 -206.348838)
		(width 0.15494)
		(layer "In15.Cu")
		(net "SSD0_PWRDIS_BIC_R")
	)
	(segment
		(start 325.119238 -206.0194)
		(end 327.049638 -206.0194)
		(width 0.15494)
		(layer "In15.Cu")
		(net "SSD0_PWRDIS_BIC_R")
	)
	(segment
		(start 267.817346 -211.272374)
		(end 284.021784 -211.272374)
		(width 0.15494)
		(layer "In15.Cu")
		(net "SSD0_PWRDIS_BIC_R")
	)
	(segment
		(start 287.32734 -207.966818)
		(end 298.540424 -207.966818)
		(width 0.15494)
		(layer "In15.Cu")
		(net "SSD0_PWRDIS_BIC_R")
	)
	(segment
		(start 300.158404 -206.348838)
		(end 324.7898 -206.348838)
		(width 0.15494)
		(layer "In15.Cu")
		(net "SSD0_PWRDIS_BIC_R")
	)
	(segment
		(start 331.670914 -207.82026)
		(end 332.470506 -207.020668)
		(width 0.15494)
		(layer "In15.Cu")
		(net "SSD0_PWRDIS_BIC_R")
	)
	(segment
		(start 335.701894 -208.9912)
		(end 342.855296 -208.9912)
		(width 0.15494)
		(layer "In15.Cu")
		(net "SSD0_PWRDIS_BIC_R")
	)
	(segment
		(start 344.49131 -214.38489)
		(end 344.893646 -214.787226)
		(width 0.0889)
		(layer "In15.Cu")
		(net "SSD0_PWRDIS_BIC_R")
	)
	(segment
		(start 333.668878 -206.958184)
		(end 335.701894 -208.9912)
		(width 0.15494)
		(layer "In15.Cu")
		(net "SSD0_PWRDIS_BIC_R")
	)
	(segment
		(start 332.470506 -207.020668)
		(end 332.485746 -207.014318)
		(width 0.15494)
		(layer "In15.Cu")
		(net "SSD0_PWRDIS_BIC_R")
	)
	(segment
		(start 343.696036 -209.619088)
		(end 343.696036 -212.030564)
		(width 0.15494)
		(layer "In15.Cu")
		(net "SSD0_PWRDIS_BIC_R")
	)
	(segment
		(start 343.696036 -212.030564)
		(end 343.696036 -214.15248)
		(width 0.0889)
		(layer "In15.Cu")
		(net "SSD0_PWRDIS_BIC_R")
	)
	(segment
		(start 343.928446 -214.38489)
		(end 344.49131 -214.38489)
		(width 0.0889)
		(layer "In15.Cu")
		(net "SSD0_PWRDIS_BIC_R")
	)
	(segment
		(start 332.485746 -207.014318)
		(end 332.57236 -206.927704)
		(width 0.15494)
		(layer "In15.Cu")
		(net "SSD0_PWRDIS_BIC_R")
	)
	(segment
		(start 342.855296 -208.9912)
		(end 342.86952 -209.005424)
		(width 0.15494)
		(layer "In15.Cu")
		(net "SSD0_PWRDIS_BIC_R")
	)
	(segment
		(start 327.049638 -206.0194)
		(end 328.850498 -207.82026)
		(width 0.15494)
		(layer "In15.Cu")
		(net "SSD0_PWRDIS_BIC_R")
	)
	(segment
		(start 342.86952 -209.005424)
		(end 343.082372 -209.005424)
		(width 0.15494)
		(layer "In15.Cu")
		(net "SSD0_PWRDIS_BIC_R")
	)
	(segment
		(start 328.850498 -207.82026)
		(end 331.670914 -207.82026)
		(width 0.15494)
		(layer "In15.Cu")
		(net "SSD0_PWRDIS_BIC_R")
	)
	(segment
		(start 333.30134 -206.958184)
		(end 333.668878 -206.958184)
		(width 0.15494)
		(layer "In15.Cu")
		(net "SSD0_PWRDIS_BIC_R")
	)
	(segment
		(start 267.561568 -211.528152)
		(end 267.817346 -211.272374)
		(width 0.15494)
		(layer "In15.Cu")
		(net "SSD0_PWRDIS_BIC_R")
	)
	(segment
		(start 284.021784 -211.272374)
		(end 287.32734 -207.966818)
		(width 0.15494)
		(layer "In15.Cu")
		(net "SSD0_PWRDIS_BIC_R")
	)
	(segment
		(start 324.7898 -206.348838)
		(end 325.119238 -206.0194)
		(width 0.15494)
		(layer "In15.Cu")
		(net "SSD0_PWRDIS_BIC_R")
	)
	(segment
		(start 332.57236 -206.927704)
		(end 333.27086 -206.927704)
		(width 0.15494)
		(layer "In15.Cu")
		(net "SSD0_PWRDIS_BIC_R")
	)
	(segment
		(start 343.696036 -214.15248)
		(end 343.928446 -214.38489)
		(width 0.0889)
		(layer "In15.Cu")
		(net "SSD0_PWRDIS_BIC_R")
	)
	(segment
		(start 343.082372 -209.005424)
		(end 343.696036 -209.619088)
		(width 0.15494)
		(layer "In15.Cu")
		(net "SSD0_PWRDIS_BIC_R")
	)
	(segment
		(start 408.154886 -59.177936)
		(end 408.47899 -59.177936)
		(width 0.13208)
		(layer "F.Cu")
		(net "PWRGD_P3V3_SSD14")
	)
	(segment
		(start 408.325066 -57.841896)
		(end 408.325066 -57.867296)
		(width 0.13208)
		(layer "F.Cu")
		(net "PWRGD_P3V3_SSD14")
	)
	(segment
		(start 408.110944 -61.386974)
		(end 407.94813 -61.22416)
		(width 0.13208)
		(layer "F.Cu")
		(net "PWRGD_P3V3_SSD14")
	)
	(segment
		(start 408.325066 -57.867296)
		(end 408.325066 -58.565796)
		(width 0.13208)
		(layer "F.Cu")
		(net "PWRGD_P3V3_SSD14")
	)
	(segment
		(start 408.47899 -58.71972)
		(end 408.47899 -59.177936)
		(width 0.13208)
		(layer "F.Cu")
		(net "PWRGD_P3V3_SSD14")
	)
	(segment
		(start 407.94813 -59.384692)
		(end 408.154886 -59.177936)
		(width 0.13208)
		(layer "F.Cu")
		(net "PWRGD_P3V3_SSD14")
	)
	(segment
		(start 407.941018 -57.457848)
		(end 408.325066 -57.841896)
		(width 0.13208)
		(layer "F.Cu")
		(net "PWRGD_P3V3_SSD14")
	)
	(segment
		(start 407.941018 -57.16397)
		(end 407.941018 -57.457848)
		(width 0.13208)
		(layer "F.Cu")
		(net "PWRGD_P3V3_SSD14")
	)
	(segment
		(start 408.325066 -58.565796)
		(end 408.47899 -58.71972)
		(width 0.13208)
		(layer "F.Cu")
		(net "PWRGD_P3V3_SSD14")
	)
	(segment
		(start 407.94813 -61.22416)
		(end 407.94813 -59.384692)
		(width 0.13208)
		(layer "F.Cu")
		(net "PWRGD_P3V3_SSD14")
	)
	(via
		(at 408.325066 -57.867296)
		(size 0.508)
		(drill 0.254)
		(layers "F.Cu" "B.Cu")
		(net "PWRGD_P3V3_SSD14")
	)
	(segment
		(start 187.94603 -405.857964)
		(end 187.64885 -405.857964)
		(width 0.13208)
		(layer "F.Cu")
		(net "FM_UV_ADR_TRIGGER_N")
	)
	(segment
		(start 188.524896 -405.279098)
		(end 187.94603 -405.857964)
		(width 0.13208)
		(layer "F.Cu")
		(net "FM_UV_ADR_TRIGGER_N")
	)
	(segment
		(start 188.524896 -404.981918)
		(end 188.524896 -405.279098)
		(width 0.13208)
		(layer "F.Cu")
		(net "FM_UV_ADR_TRIGGER_N")
	)
	(segment
		(start 187.64885 -405.857964)
		(end 187.312554 -406.19426)
		(width 0.13208)
		(layer "F.Cu")
		(net "FM_UV_ADR_TRIGGER_N")
	)
	(segment
		(start 187.312554 -406.19426)
		(end 186.789568 -406.19426)
		(width 0.13208)
		(layer "F.Cu")
		(net "FM_UV_ADR_TRIGGER_N")
	)
	(via
		(at 187.64885 -405.857964)
		(size 0.508)
		(drill 0.254)
		(layers "F.Cu" "B.Cu")
		(net "FM_UV_ADR_TRIGGER_N")
	)
	(segment
		(start 30.438344 -251.956824)
		(end 30.438344 -251.158502)
		(width 0.13208)
		(layer "F.Cu")
		(net "PEX0_MODE_SEL0")
	)
	(segment
		(start 61.549788 -282.599892)
		(end 62.024768 -283.074872)
		(width 0.1651)
		(layer "F.Cu")
		(net "PEX0_MODE_SEL0")
	)
	(segment
		(start 30.438344 -251.158502)
		(end 30.438344 -250.470924)
		(width 0.13208)
		(layer "F.Cu")
		(net "PEX0_MODE_SEL0")
	)
	(via
		(at 62.024768 -283.074872)
		(size 0.4064)
		(drill 0.2032)
		(layers "F.Cu" "B.Cu")
		(net "PEX0_MODE_SEL0")
	)
	(via
		(at 30.438344 -251.158502)
		(size 0.508)
		(drill 0.254)
		(layers "F.Cu" "B.Cu")
		(net "PEX0_MODE_SEL0")
	)
	(segment
		(start 62.97041 -271.947386)
		(end 60.001912 -268.978888)
		(width 0.13208)
		(layer "B.Cu")
		(net "PEX0_MODE_SEL0")
	)
	(segment
		(start 60.001912 -268.840712)
		(end 59.428888 -268.267688)
		(width 0.13208)
		(layer "B.Cu")
		(net "PEX0_MODE_SEL0")
	)
	(segment
		(start 58.592212 -267.569188)
		(end 58.425588 -267.569188)
		(width 0.13208)
		(layer "B.Cu")
		(net "PEX0_MODE_SEL0")
	)
	(segment
		(start 35.687 -259.3848)
		(end 29.898594 -253.596394)
		(width 0.13208)
		(layer "B.Cu")
		(net "PEX0_MODE_SEL0")
	)
	(segment
		(start 57.728612 -266.705588)
		(end 50.407824 -259.3848)
		(width 0.13208)
		(layer "B.Cu")
		(net "PEX0_MODE_SEL0")
	)
	(segment
		(start 62.024768 -283.074872)
		(end 62.97041 -282.12923)
		(width 0.13208)
		(layer "B.Cu")
		(net "PEX0_MODE_SEL0")
	)
	(segment
		(start 62.97041 -282.12923)
		(end 62.97041 -271.947386)
		(width 0.13208)
		(layer "B.Cu")
		(net "PEX0_MODE_SEL0")
	)
	(segment
		(start 29.898594 -253.596394)
		(end 29.898594 -251.698252)
		(width 0.13208)
		(layer "B.Cu")
		(net "PEX0_MODE_SEL0")
	)
	(segment
		(start 57.728612 -266.872212)
		(end 57.728612 -266.705588)
		(width 0.13208)
		(layer "B.Cu")
		(net "PEX0_MODE_SEL0")
	)
	(segment
		(start 50.407824 -259.3848)
		(end 35.687 -259.3848)
		(width 0.13208)
		(layer "B.Cu")
		(net "PEX0_MODE_SEL0")
	)
	(segment
		(start 60.001912 -268.978888)
		(end 60.001912 -268.840712)
		(width 0.13208)
		(layer "B.Cu")
		(net "PEX0_MODE_SEL0")
	)
	(segment
		(start 29.898594 -251.698252)
		(end 30.438344 -251.158502)
		(width 0.13208)
		(layer "B.Cu")
		(net "PEX0_MODE_SEL0")
	)
	(segment
		(start 59.290712 -268.267688)
		(end 58.592212 -267.569188)
		(width 0.13208)
		(layer "B.Cu")
		(net "PEX0_MODE_SEL0")
	)
	(segment
		(start 59.428888 -268.267688)
		(end 59.290712 -268.267688)
		(width 0.13208)
		(layer "B.Cu")
		(net "PEX0_MODE_SEL0")
	)
	(segment
		(start 58.425588 -267.569188)
		(end 57.728612 -266.872212)
		(width 0.13208)
		(layer "B.Cu")
		(net "PEX0_MODE_SEL0")
	)
	(segment
		(start 147.554442 -251.158502)
		(end 147.554442 -250.470924)
		(width 0.13208)
		(layer "F.Cu")
		(net "PEX1_MODE_SEL4")
	)
	(segment
		(start 147.554442 -251.956824)
		(end 147.554442 -251.158502)
		(width 0.13208)
		(layer "F.Cu")
		(net "PEX1_MODE_SEL4")
	)
	(segment
		(start 178.6001 -282.599892)
		(end 179.07508 -283.074872)
		(width 0.13208)
		(layer "F.Cu")
		(net "PEX1_MODE_SEL4")
	)
	(segment
		(start 178.599846 -282.599892)
		(end 178.6001 -282.599892)
		(width 0.13208)
		(layer "F.Cu")
		(net "PEX1_MODE_SEL4")
	)
	(via
		(at 147.554442 -251.158502)
		(size 0.508)
		(drill 0.254)
		(layers "F.Cu" "B.Cu")
		(net "PEX1_MODE_SEL4")
	)
	(via
		(at 179.07508 -283.074872)
		(size 0.4064)
		(drill 0.2032)
		(layers "F.Cu" "B.Cu")
		(net "PEX1_MODE_SEL4")
	)
	(via
		(at 174.601632 -266.71143)
		(size 0.6604)
		(drill 0.3302)
		(layers "F.Cu" "B.Cu")
		(net "PEX1_MODE_SEL4")
	)
	(segment
		(start 179.810156 -271.659858)
		(end 179.55006 -271.659858)
		(width 0.13208)
		(layer "B.Cu")
		(net "PEX1_MODE_SEL4")
	)
	(segment
		(start 147.079208 -254.317754)
		(end 147.079208 -251.633736)
		(width 0.13208)
		(layer "B.Cu")
		(net "PEX1_MODE_SEL4")
	)
	(segment
		(start 180.022754 -282.127198)
		(end 180.022754 -271.872456)
		(width 0.13208)
		(layer "B.Cu")
		(net "PEX1_MODE_SEL4")
	)
	(segment
		(start 179.55006 -271.659858)
		(end 174.601632 -266.71143)
		(width 0.13208)
		(layer "B.Cu")
		(net "PEX1_MODE_SEL4")
	)
	(segment
		(start 179.07508 -283.074872)
		(end 180.022754 -282.127198)
		(width 0.13208)
		(layer "B.Cu")
		(net "PEX1_MODE_SEL4")
	)
	(segment
		(start 180.022754 -271.872456)
		(end 179.810156 -271.659858)
		(width 0.13208)
		(layer "B.Cu")
		(net "PEX1_MODE_SEL4")
	)
	(segment
		(start 147.079208 -251.633736)
		(end 147.554442 -251.158502)
		(width 0.13208)
		(layer "B.Cu")
		(net "PEX1_MODE_SEL4")
	)
	(segment
		(start 165.852602 -257.9624)
		(end 150.723854 -257.9624)
		(width 0.13208)
		(layer "B.Cu")
		(net "PEX1_MODE_SEL4")
	)
	(segment
		(start 174.601632 -266.71143)
		(end 165.852602 -257.9624)
		(width 0.13208)
		(layer "B.Cu")
		(net "PEX1_MODE_SEL4")
	)
	(segment
		(start 150.723854 -257.9624)
		(end 147.079208 -254.317754)
		(width 0.13208)
		(layer "B.Cu")
		(net "PEX1_MODE_SEL4")
	)
	(segment
		(start 403.199854 -309.199788)
		(end 403.674834 -308.724808)
		(width 0.13208)
		(layer "F.Cu")
		(net "PU_PEX3_TR_TCK")
	)
	(segment
		(start 376.123962 -312.557922)
		(end 375.122694 -311.556654)
		(width 0.13208)
		(layer "F.Cu")
		(net "PU_PEX3_TR_TCK")
	)
	(segment
		(start 379.146562 -312.557922)
		(end 376.123962 -312.557922)
		(width 0.13208)
		(layer "F.Cu")
		(net "PU_PEX3_TR_TCK")
	)
	(segment
		(start 382.728978 -313.669934)
		(end 381.831596 -313.669934)
		(width 0.13208)
		(layer "F.Cu")
		(net "PU_PEX3_TR_TCK")
	)
	(segment
		(start 381.831596 -313.669934)
		(end 379.146562 -312.557922)
		(width 0.13208)
		(layer "F.Cu")
		(net "PU_PEX3_TR_TCK")
	)
	(via
		(at 403.674834 -308.724808)
		(size 0.4064)
		(drill 0.2032)
		(layers "F.Cu" "B.Cu")
		(net "PU_PEX3_TR_TCK")
	)
	(via
		(at 382.728978 -313.669934)
		(size 0.508)
		(drill 0.254)
		(layers "F.Cu" "B.Cu")
		(net "PU_PEX3_TR_TCK")
	)
	(segment
		(start 403.364446 -313.454796)
		(end 403.674834 -313.144408)
		(width 0.13208)
		(layer "B.Cu")
		(net "PU_PEX3_TR_TCK")
	)
	(segment
		(start 382.944116 -313.454796)
		(end 403.364446 -313.454796)
		(width 0.13208)
		(layer "B.Cu")
		(net "PU_PEX3_TR_TCK")
	)
	(segment
		(start 382.728978 -313.669934)
		(end 382.944116 -313.454796)
		(width 0.13208)
		(layer "B.Cu")
		(net "PU_PEX3_TR_TCK")
	)
	(segment
		(start 403.674834 -313.144408)
		(end 403.674834 -308.724808)
		(width 0.13208)
		(layer "B.Cu")
		(net "PU_PEX3_TR_TCK")
	)
	(segment
		(start 212.668104 -224.658682)
		(end 212.194648 -225.132138)
		(width 0.13208)
		(layer "F.Cu")
		(net "SMB_NIC3_R_SDA")
	)
	(segment
		(start 212.194648 -225.132138)
		(end 212.194648 -225.622612)
		(width 0.13208)
		(layer "F.Cu")
		(net "SMB_NIC3_R_SDA")
	)
	(segment
		(start 212.194648 -225.622612)
		(end 212.470238 -225.898202)
		(width 0.13208)
		(layer "F.Cu")
		(net "SMB_NIC3_R_SDA")
	)
	(segment
		(start 184.757314 -113.43513)
		(end 183.412638 -113.43513)
		(width 0.13208)
		(layer "F.Cu")
		(net "SMB_NIC3_R_SDA")
	)
	(segment
		(start 212.470238 -225.898202)
		(end 213.07679 -225.898202)
		(width 0.13208)
		(layer "F.Cu")
		(net "SMB_NIC3_R_SDA")
	)
	(segment
		(start 213.07679 -225.898202)
		(end 213.30666 -225.668332)
		(width 0.13208)
		(layer "F.Cu")
		(net "SMB_NIC3_R_SDA")
	)
	(segment
		(start 212.668104 -224.398586)
		(end 212.668104 -224.658682)
		(width 0.13208)
		(layer "F.Cu")
		(net "SMB_NIC3_R_SDA")
	)
	(segment
		(start 213.30666 -225.668332)
		(end 213.30666 -225.42246)
		(width 0.13208)
		(layer "F.Cu")
		(net "SMB_NIC3_R_SDA")
	)
	(via
		(at 183.412638 -113.43513)
		(size 0.508)
		(drill 0.254)
		(layers "F.Cu" "B.Cu")
		(net "SMB_NIC3_R_SDA")
	)
	(via
		(at 212.668104 -224.398586)
		(size 0.508)
		(drill 0.254)
		(layers "F.Cu" "B.Cu")
		(net "SMB_NIC3_R_SDA")
	)
	(via
		(at 211.907628 -136.16559)
		(size 0.762)
		(drill 0.254)
		(layers "F.Cu" "B.Cu")
		(net "SMB_NIC3_R_SDA")
	)
	(segment
		(start 183.415432 -113.437924)
		(end 183.412638 -113.43513)
		(width 0.13208)
		(layer "B.Cu")
		(net "SMB_NIC3_R_SDA")
	)
	(segment
		(start 184.371996 -113.437924)
		(end 183.415432 -113.437924)
		(width 0.13208)
		(layer "B.Cu")
		(net "SMB_NIC3_R_SDA")
	)
	(segment
		(start 210.168744 -223.565212)
		(end 208.213198 -223.565212)
		(width 0.15494)
		(layer "In7.Cu")
		(net "SMB_NIC3_R_SDA")
	)
	(segment
		(start 212.205316 -225.161094)
		(end 211.403946 -225.161094)
		(width 0.15494)
		(layer "In7.Cu")
		(net "SMB_NIC3_R_SDA")
	)
	(segment
		(start 212.668104 -224.698306)
		(end 212.205316 -225.161094)
		(width 0.15494)
		(layer "In7.Cu")
		(net "SMB_NIC3_R_SDA")
	)
	(segment
		(start 202.65898 -194.394836)
		(end 207.723994 -189.329822)
		(width 0.15494)
		(layer "In7.Cu")
		(net "SMB_NIC3_R_SDA")
	)
	(segment
		(start 206.830168 -169.490644)
		(end 211.3026 -165.018212)
		(width 0.15494)
		(layer "In7.Cu")
		(net "SMB_NIC3_R_SDA")
	)
	(segment
		(start 212.668104 -224.398586)
		(end 212.668104 -224.698306)
		(width 0.15494)
		(layer "In7.Cu")
		(net "SMB_NIC3_R_SDA")
	)
	(segment
		(start 211.074762 -224.47123)
		(end 210.168744 -223.565212)
		(width 0.15494)
		(layer "In7.Cu")
		(net "SMB_NIC3_R_SDA")
	)
	(segment
		(start 206.830168 -184.320434)
		(end 206.830168 -169.490644)
		(width 0.15494)
		(layer "In7.Cu")
		(net "SMB_NIC3_R_SDA")
	)
	(segment
		(start 208.1784 -185.693304)
		(end 207.550258 -185.040524)
		(width 0.15494)
		(layer "In7.Cu")
		(net "SMB_NIC3_R_SDA")
	)
	(segment
		(start 207.723994 -189.329822)
		(end 207.723994 -186.958986)
		(width 0.15494)
		(layer "In7.Cu")
		(net "SMB_NIC3_R_SDA")
	)
	(segment
		(start 202.65898 -218.42222)
		(end 202.65898 -194.394836)
		(width 0.15494)
		(layer "In7.Cu")
		(net "SMB_NIC3_R_SDA")
	)
	(segment
		(start 211.403946 -225.161094)
		(end 211.074762 -224.83191)
		(width 0.15494)
		(layer "In7.Cu")
		(net "SMB_NIC3_R_SDA")
	)
	(segment
		(start 208.213198 -223.565212)
		(end 206.265526 -221.61754)
		(width 0.15494)
		(layer "In7.Cu")
		(net "SMB_NIC3_R_SDA")
	)
	(segment
		(start 211.3026 -165.018212)
		(end 211.3026 -161.7472)
		(width 0.15494)
		(layer "In7.Cu")
		(net "SMB_NIC3_R_SDA")
	)
	(segment
		(start 211.074762 -224.83191)
		(end 211.074762 -224.47123)
		(width 0.15494)
		(layer "In7.Cu")
		(net "SMB_NIC3_R_SDA")
	)
	(segment
		(start 212.09 -136.347962)
		(end 211.907628 -136.16559)
		(width 0.15494)
		(layer "In7.Cu")
		(net "SMB_NIC3_R_SDA")
	)
	(segment
		(start 208.1784 -186.50458)
		(end 208.1784 -185.693304)
		(width 0.15494)
		(layer "In7.Cu")
		(net "SMB_NIC3_R_SDA")
	)
	(segment
		(start 211.3026 -161.7472)
		(end 212.09 -160.9598)
		(width 0.15494)
		(layer "In7.Cu")
		(net "SMB_NIC3_R_SDA")
	)
	(segment
		(start 207.723994 -186.958986)
		(end 208.1784 -186.50458)
		(width 0.15494)
		(layer "In7.Cu")
		(net "SMB_NIC3_R_SDA")
	)
	(segment
		(start 212.09 -160.9598)
		(end 212.09 -136.347962)
		(width 0.15494)
		(layer "In7.Cu")
		(net "SMB_NIC3_R_SDA")
	)
	(segment
		(start 206.265526 -221.61754)
		(end 205.8543 -221.61754)
		(width 0.15494)
		(layer "In7.Cu")
		(net "SMB_NIC3_R_SDA")
	)
	(segment
		(start 205.8543 -221.61754)
		(end 202.65898 -218.42222)
		(width 0.15494)
		(layer "In7.Cu")
		(net "SMB_NIC3_R_SDA")
	)
	(segment
		(start 207.550258 -185.040524)
		(end 206.830168 -184.320434)
		(width 0.15494)
		(layer "In7.Cu")
		(net "SMB_NIC3_R_SDA")
	)
	(segment
		(start 184.760108 -114.7826)
		(end 183.412638 -113.43513)
		(width 0.15494)
		(layer "In15.Cu")
		(net "SMB_NIC3_R_SDA")
	)
	(segment
		(start 202.667362 -115.687602)
		(end 192.954402 -115.687602)
		(width 0.15494)
		(layer "In15.Cu")
		(net "SMB_NIC3_R_SDA")
	)
	(segment
		(start 191.435482 -114.168682)
		(end 188.040518 -114.168682)
		(width 0.15494)
		(layer "In15.Cu")
		(net "SMB_NIC3_R_SDA")
	)
	(segment
		(start 211.5312 -135.789162)
		(end 211.5312 -135.347964)
		(width 0.15494)
		(layer "In15.Cu")
		(net "SMB_NIC3_R_SDA")
	)
	(segment
		(start 211.907628 -136.16559)
		(end 211.5312 -135.789162)
		(width 0.15494)
		(layer "In15.Cu")
		(net "SMB_NIC3_R_SDA")
	)
	(segment
		(start 192.954402 -115.687602)
		(end 191.435482 -114.168682)
		(width 0.15494)
		(layer "In15.Cu")
		(net "SMB_NIC3_R_SDA")
	)
	(segment
		(start 203.21143 -127.028194)
		(end 203.21143 -116.23167)
		(width 0.15494)
		(layer "In15.Cu")
		(net "SMB_NIC3_R_SDA")
	)
	(segment
		(start 203.21143 -116.23167)
		(end 202.667362 -115.687602)
		(width 0.15494)
		(layer "In15.Cu")
		(net "SMB_NIC3_R_SDA")
	)
	(segment
		(start 187.4266 -114.7826)
		(end 184.760108 -114.7826)
		(width 0.15494)
		(layer "In15.Cu")
		(net "SMB_NIC3_R_SDA")
	)
	(segment
		(start 211.5312 -135.347964)
		(end 203.21143 -127.028194)
		(width 0.15494)
		(layer "In15.Cu")
		(net "SMB_NIC3_R_SDA")
	)
	(segment
		(start 188.040518 -114.168682)
		(end 187.4266 -114.7826)
		(width 0.15494)
		(layer "In15.Cu")
		(net "SMB_NIC3_R_SDA")
	)
	(segment
		(start 346.093796 -211.18703)
		(end 346.493592 -210.787234)
		(width 0.13208)
		(layer "F.Cu")
		(net "SSD2_PWRDIS_BIC_R")
	)
	(via
		(at 265.081004 -212.487002)
		(size 0.508)
		(drill 0.254)
		(layers "F.Cu" "B.Cu")
		(net "SSD2_PWRDIS_BIC_R")
	)
	(via
		(at 233.839512 -233.182668)
		(size 0.508)
		(drill 0.254)
		(layers "F.Cu" "B.Cu")
		(net "SSD2_PWRDIS_BIC_R")
	)
	(via
		(at 346.493592 -210.787234)
		(size 0.4572)
		(drill 0.254)
		(layers "F.Cu" "B.Cu")
		(net "SSD2_PWRDIS_BIC_R")
	)
	(segment
		(start 233.839512 -234.327954)
		(end 233.839512 -233.182668)
		(width 0.13208)
		(layer "B.Cu")
		(net "SSD2_PWRDIS_BIC_R")
	)
	(segment
		(start 233.839512 -233.182668)
		(end 233.365548 -232.708704)
		(width 0.13208)
		(layer "B.Cu")
		(net "SSD2_PWRDIS_BIC_R")
	)
	(segment
		(start 233.365548 -231.758744)
		(end 233.498644 -231.625648)
		(width 0.13208)
		(layer "B.Cu")
		(net "SSD2_PWRDIS_BIC_R")
	)
	(segment
		(start 233.365548 -232.708704)
		(end 233.365548 -231.758744)
		(width 0.13208)
		(layer "B.Cu")
		(net "SSD2_PWRDIS_BIC_R")
	)
	(segment
		(start 263.064752 -216.387934)
		(end 263.064752 -213.642448)
		(width 0.15494)
		(layer "In7.Cu")
		(net "SSD2_PWRDIS_BIC_R")
	)
	(segment
		(start 264.220198 -212.487002)
		(end 265.081004 -212.487002)
		(width 0.15494)
		(layer "In7.Cu")
		(net "SSD2_PWRDIS_BIC_R")
	)
	(segment
		(start 233.839512 -233.182668)
		(end 235.397802 -234.740958)
		(width 0.15494)
		(layer "In7.Cu")
		(net "SSD2_PWRDIS_BIC_R")
	)
	(segment
		(start 249.529346 -230.4796)
		(end 250.792234 -230.4796)
		(width 0.15494)
		(layer "In7.Cu")
		(net "SSD2_PWRDIS_BIC_R")
	)
	(segment
		(start 246.0244 -234.2896)
		(end 249.127772 -231.186228)
		(width 0.15494)
		(layer "In7.Cu")
		(net "SSD2_PWRDIS_BIC_R")
	)
	(segment
		(start 262.24738 -216.979246)
		(end 262.47344 -216.979246)
		(width 0.15494)
		(layer "In7.Cu")
		(net "SSD2_PWRDIS_BIC_R")
	)
	(segment
		(start 263.064752 -213.642448)
		(end 264.220198 -212.487002)
		(width 0.15494)
		(layer "In7.Cu")
		(net "SSD2_PWRDIS_BIC_R")
	)
	(segment
		(start 262.47344 -216.979246)
		(end 263.064752 -216.387934)
		(width 0.15494)
		(layer "In7.Cu")
		(net "SSD2_PWRDIS_BIC_R")
	)
	(segment
		(start 254.73914 -226.532694)
		(end 254.73914 -225.243644)
		(width 0.15494)
		(layer "In7.Cu")
		(net "SSD2_PWRDIS_BIC_R")
	)
	(segment
		(start 258.233926 -218.977972)
		(end 260.248654 -218.977972)
		(width 0.15494)
		(layer "In7.Cu")
		(net "SSD2_PWRDIS_BIC_R")
	)
	(segment
		(start 254.73914 -225.243644)
		(end 256.5146 -223.468184)
		(width 0.15494)
		(layer "In7.Cu")
		(net "SSD2_PWRDIS_BIC_R")
	)
	(segment
		(start 245.243096 -234.740958)
		(end 245.694454 -234.2896)
		(width 0.15494)
		(layer "In7.Cu")
		(net "SSD2_PWRDIS_BIC_R")
	)
	(segment
		(start 245.694454 -234.2896)
		(end 246.0244 -234.2896)
		(width 0.15494)
		(layer "In7.Cu")
		(net "SSD2_PWRDIS_BIC_R")
	)
	(segment
		(start 235.397802 -234.740958)
		(end 245.243096 -234.740958)
		(width 0.15494)
		(layer "In7.Cu")
		(net "SSD2_PWRDIS_BIC_R")
	)
	(segment
		(start 249.127772 -231.186228)
		(end 249.127772 -230.881174)
		(width 0.15494)
		(layer "In7.Cu")
		(net "SSD2_PWRDIS_BIC_R")
	)
	(segment
		(start 256.5146 -223.468184)
		(end 256.5146 -220.697298)
		(width 0.15494)
		(layer "In7.Cu")
		(net "SSD2_PWRDIS_BIC_R")
	)
	(segment
		(start 260.248654 -218.977972)
		(end 262.24738 -216.979246)
		(width 0.15494)
		(layer "In7.Cu")
		(net "SSD2_PWRDIS_BIC_R")
	)
	(segment
		(start 249.127772 -230.881174)
		(end 249.529346 -230.4796)
		(width 0.15494)
		(layer "In7.Cu")
		(net "SSD2_PWRDIS_BIC_R")
	)
	(segment
		(start 250.792234 -230.4796)
		(end 254.73914 -226.532694)
		(width 0.15494)
		(layer "In7.Cu")
		(net "SSD2_PWRDIS_BIC_R")
	)
	(segment
		(start 256.5146 -220.697298)
		(end 258.233926 -218.977972)
		(width 0.15494)
		(layer "In7.Cu")
		(net "SSD2_PWRDIS_BIC_R")
	)
	(segment
		(start 343.571068 -207.4672)
		(end 337.68919 -207.4672)
		(width 0.15494)
		(layer "In15.Cu")
		(net "SSD2_PWRDIS_BIC_R")
	)
	(segment
		(start 345.92514 -209.821272)
		(end 343.571068 -207.4672)
		(width 0.15494)
		(layer "In15.Cu")
		(net "SSD2_PWRDIS_BIC_R")
	)
	(segment
		(start 335.029556 -204.043026)
		(end 334.4164 -203.42987)
		(width 0.15494)
		(layer "In15.Cu")
		(net "SSD2_PWRDIS_BIC_R")
	)
	(segment
		(start 335.029556 -204.448156)
		(end 335.029556 -204.043026)
		(width 0.15494)
		(layer "In15.Cu")
		(net "SSD2_PWRDIS_BIC_R")
	)
	(segment
		(start 337.68919 -207.4672)
		(end 336.52587 -206.30388)
		(width 0.15494)
		(layer "In15.Cu")
		(net "SSD2_PWRDIS_BIC_R")
	)
	(segment
		(start 336.52587 -205.94447)
		(end 335.029556 -204.448156)
		(width 0.15494)
		(layer "In15.Cu")
		(net "SSD2_PWRDIS_BIC_R")
	)
	(segment
		(start 326.962516 -201.82586)
		(end 324.913752 -203.874624)
		(width 0.15494)
		(layer "In15.Cu")
		(net "SSD2_PWRDIS_BIC_R")
	)
	(segment
		(start 264.54608 -210.61045)
		(end 264.54608 -211.952078)
		(width 0.15494)
		(layer "In15.Cu")
		(net "SSD2_PWRDIS_BIC_R")
	)
	(segment
		(start 264.54608 -211.952078)
		(end 265.081004 -212.487002)
		(width 0.15494)
		(layer "In15.Cu")
		(net "SSD2_PWRDIS_BIC_R")
	)
	(segment
		(start 334.4164 -203.42987)
		(end 334.06334 -203.42987)
		(width 0.15494)
		(layer "In15.Cu")
		(net "SSD2_PWRDIS_BIC_R")
	)
	(segment
		(start 346.493592 -210.787234)
		(end 345.92514 -210.218782)
		(width 0.15494)
		(layer "In15.Cu")
		(net "SSD2_PWRDIS_BIC_R")
	)
	(segment
		(start 299.671232 -203.874624)
		(end 298.478702 -205.067154)
		(width 0.15494)
		(layer "In15.Cu")
		(net "SSD2_PWRDIS_BIC_R")
	)
	(segment
		(start 334.06334 -203.42987)
		(end 332.45933 -201.82586)
		(width 0.15494)
		(layer "In15.Cu")
		(net "SSD2_PWRDIS_BIC_R")
	)
	(segment
		(start 324.913752 -203.874624)
		(end 299.671232 -203.874624)
		(width 0.15494)
		(layer "In15.Cu")
		(net "SSD2_PWRDIS_BIC_R")
	)
	(segment
		(start 345.92514 -210.218782)
		(end 345.92514 -209.821272)
		(width 0.15494)
		(layer "In15.Cu")
		(net "SSD2_PWRDIS_BIC_R")
	)
	(segment
		(start 298.478702 -205.067154)
		(end 270.089376 -205.067154)
		(width 0.15494)
		(layer "In15.Cu")
		(net "SSD2_PWRDIS_BIC_R")
	)
	(segment
		(start 336.52587 -206.30388)
		(end 336.52587 -205.94447)
		(width 0.15494)
		(layer "In15.Cu")
		(net "SSD2_PWRDIS_BIC_R")
	)
	(segment
		(start 270.089376 -205.067154)
		(end 264.54608 -210.61045)
		(width 0.15494)
		(layer "In15.Cu")
		(net "SSD2_PWRDIS_BIC_R")
	)
	(segment
		(start 332.45933 -201.82586)
		(end 326.962516 -201.82586)
		(width 0.15494)
		(layer "In15.Cu")
		(net "SSD2_PWRDIS_BIC_R")
	)
	(segment
		(start 433.948078 -59.34964)
		(end 434.119782 -59.177936)
		(width 0.13208)
		(layer "F.Cu")
		(net "PWRGD_P3V3_SSD15")
	)
	(segment
		(start 434.110892 -61.386974)
		(end 433.948078 -61.22416)
		(width 0.13208)
		(layer "F.Cu")
		(net "PWRGD_P3V3_SSD15")
	)
	(segment
		(start 434.325014 -58.565796)
		(end 434.325014 -58.101738)
		(width 0.13208)
		(layer "F.Cu")
		(net "PWRGD_P3V3_SSD15")
	)
	(segment
		(start 433.940966 -57.457848)
		(end 433.940966 -57.16397)
		(width 0.13208)
		(layer "F.Cu")
		(net "PWRGD_P3V3_SSD15")
	)
	(segment
		(start 433.948078 -61.22416)
		(end 433.948078 -59.34964)
		(width 0.13208)
		(layer "F.Cu")
		(net "PWRGD_P3V3_SSD15")
	)
	(segment
		(start 434.325014 -57.841896)
		(end 433.940966 -57.457848)
		(width 0.13208)
		(layer "F.Cu")
		(net "PWRGD_P3V3_SSD15")
	)
	(segment
		(start 434.478938 -59.177936)
		(end 434.478938 -58.71972)
		(width 0.13208)
		(layer "F.Cu")
		(net "PWRGD_P3V3_SSD15")
	)
	(segment
		(start 434.325014 -58.101738)
		(end 434.325014 -57.841896)
		(width 0.13208)
		(layer "F.Cu")
		(net "PWRGD_P3V3_SSD15")
	)
	(segment
		(start 434.478938 -58.71972)
		(end 434.325014 -58.565796)
		(width 0.13208)
		(layer "F.Cu")
		(net "PWRGD_P3V3_SSD15")
	)
	(segment
		(start 434.119782 -59.177936)
		(end 434.478938 -59.177936)
		(width 0.13208)
		(layer "F.Cu")
		(net "PWRGD_P3V3_SSD15")
	)
	(via
		(at 434.325014 -58.101738)
		(size 0.508)
		(drill 0.254)
		(layers "F.Cu" "B.Cu")
		(net "PWRGD_P3V3_SSD15")
	)
	(segment
		(start 398.4498 -308.249828)
		(end 397.97482 -308.724808)
		(width 0.13208)
		(layer "F.Cu")
		(net "TP_PEX3_TCK")
	)
	(via
		(at 397.97482 -308.724808)
		(size 0.4064)
		(drill 0.2032)
		(layers "F.Cu" "B.Cu")
		(net "TP_PEX3_TCK")
	)
	(via
		(at 397.49984 -309.199788)
		(size 0.6604)
		(drill 0.3302)
		(layers "F.Cu" "B.Cu")
		(net "TP_PEX3_TCK")
	)
	(segment
		(start 397.49984 -309.199788)
		(end 397.97482 -308.724808)
		(width 0.13208)
		(layer "B.Cu")
		(net "TP_PEX3_TCK")
	)
	(segment
		(start 50.64252 -142.56512)
		(end 51.63312 -142.56512)
		(width 0.13208)
		(layer "F.Cu")
		(net "SMB_NIC0_R_SCL")
	)
	(segment
		(start 51.66868 -142.60068)
		(end 51.987196 -142.60068)
		(width 0.13208)
		(layer "F.Cu")
		(net "SMB_NIC0_R_SCL")
	)
	(segment
		(start 53.039264 -142.9512)
		(end 55.47995 -142.9512)
		(width 0.13208)
		(layer "F.Cu")
		(net "SMB_NIC0_R_SCL")
	)
	(segment
		(start 52.688744 -142.60068)
		(end 53.039264 -142.9512)
		(width 0.13208)
		(layer "F.Cu")
		(net "SMB_NIC0_R_SCL")
	)
	(segment
		(start 51.987196 -142.60068)
		(end 52.688744 -142.60068)
		(width 0.13208)
		(layer "F.Cu")
		(net "SMB_NIC0_R_SCL")
	)
	(segment
		(start 51.63312 -142.56512)
		(end 51.66868 -142.60068)
		(width 0.13208)
		(layer "F.Cu")
		(net "SMB_NIC0_R_SCL")
	)
	(via
		(at 51.987196 -142.60068)
		(size 0.508)
		(drill 0.254)
		(layers "F.Cu" "B.Cu")
		(net "SMB_NIC0_R_SCL")
	)
	(via
		(at 64.843406 -209.38236)
		(size 0.508)
		(drill 0.254)
		(layers "F.Cu" "B.Cu")
		(net "SMB_NIC0_R_SCL")
	)
	(via
		(at 222.663512 -233.182668)
		(size 0.508)
		(drill 0.254)
		(layers "F.Cu" "B.Cu")
		(net "SMB_NIC0_R_SCL")
	)
	(segment
		(start 222.158306 -231.789986)
		(end 222.322644 -231.625648)
		(width 0.13208)
		(layer "B.Cu")
		(net "SMB_NIC0_R_SCL")
	)
	(segment
		(start 222.158306 -232.677462)
		(end 222.158306 -231.789986)
		(width 0.13208)
		(layer "B.Cu")
		(net "SMB_NIC0_R_SCL")
	)
	(segment
		(start 222.663512 -233.182668)
		(end 222.158306 -232.677462)
		(width 0.13208)
		(layer "B.Cu")
		(net "SMB_NIC0_R_SCL")
	)
	(segment
		(start 62.989968 -210.070954)
		(end 61.797946 -208.878932)
		(width 0.15494)
		(layer "In9.Cu")
		(net "SMB_NIC0_R_SCL")
	)
	(segment
		(start 52.37988 -142.60068)
		(end 51.987196 -142.60068)
		(width 0.15494)
		(layer "In9.Cu")
		(net "SMB_NIC0_R_SCL")
	)
	(segment
		(start 53.332634 -143.553434)
		(end 52.37988 -142.60068)
		(width 0.15494)
		(layer "In9.Cu")
		(net "SMB_NIC0_R_SCL")
	)
	(segment
		(start 64.154812 -210.070954)
		(end 62.989968 -210.070954)
		(width 0.15494)
		(layer "In9.Cu")
		(net "SMB_NIC0_R_SCL")
	)
	(segment
		(start 54.680104 -147.564094)
		(end 53.332634 -146.216624)
		(width 0.15494)
		(layer "In9.Cu")
		(net "SMB_NIC0_R_SCL")
	)
	(segment
		(start 61.797946 -185.83148)
		(end 54.680104 -178.713638)
		(width 0.15494)
		(layer "In9.Cu")
		(net "SMB_NIC0_R_SCL")
	)
	(segment
		(start 53.332634 -146.216624)
		(end 53.332634 -143.553434)
		(width 0.15494)
		(layer "In9.Cu")
		(net "SMB_NIC0_R_SCL")
	)
	(segment
		(start 64.843406 -209.38236)
		(end 64.154812 -210.070954)
		(width 0.15494)
		(layer "In9.Cu")
		(net "SMB_NIC0_R_SCL")
	)
	(segment
		(start 61.797946 -208.878932)
		(end 61.797946 -185.83148)
		(width 0.15494)
		(layer "In9.Cu")
		(net "SMB_NIC0_R_SCL")
	)
	(segment
		(start 54.680104 -178.713638)
		(end 54.680104 -147.564094)
		(width 0.15494)
		(layer "In9.Cu")
		(net "SMB_NIC0_R_SCL")
	)
	(segment
		(start 141.101064 -221.562168)
		(end 146.375374 -221.562168)
		(width 0.15494)
		(layer "In13.Cu")
		(net "SMB_NIC0_R_SCL")
	)
	(segment
		(start 133.146546 -220.9292)
		(end 133.730746 -220.345)
		(width 0.15494)
		(layer "In13.Cu")
		(net "SMB_NIC0_R_SCL")
	)
	(segment
		(start 75.75931 -211.09432)
		(end 100.728526 -211.09432)
		(width 0.15494)
		(layer "In13.Cu")
		(net "SMB_NIC0_R_SCL")
	)
	(segment
		(start 208.207356 -231.844342)
		(end 208.932272 -231.119426)
		(width 0.15494)
		(layer "In13.Cu")
		(net "SMB_NIC0_R_SCL")
	)
	(segment
		(start 222.169228 -231.7623)
		(end 222.169228 -232.688384)
		(width 0.15494)
		(layer "In13.Cu")
		(net "SMB_NIC0_R_SCL")
	)
	(segment
		(start 65.950846 -210.4898)
		(end 75.15479 -210.4898)
		(width 0.15494)
		(layer "In13.Cu")
		(net "SMB_NIC0_R_SCL")
	)
	(segment
		(start 208.932272 -231.119426)
		(end 221.526354 -231.119426)
		(width 0.15494)
		(layer "In13.Cu")
		(net "SMB_NIC0_R_SCL")
	)
	(segment
		(start 109.643926 -211.7344)
		(end 115.468654 -211.7344)
		(width 0.15494)
		(layer "In13.Cu")
		(net "SMB_NIC0_R_SCL")
	)
	(segment
		(start 101.368606 -211.7344)
		(end 105.9434 -211.7344)
		(width 0.15494)
		(layer "In13.Cu")
		(net "SMB_NIC0_R_SCL")
	)
	(segment
		(start 221.526354 -231.119426)
		(end 222.169228 -231.7623)
		(width 0.15494)
		(layer "In13.Cu")
		(net "SMB_NIC0_R_SCL")
	)
	(segment
		(start 158.364682 -233.551476)
		(end 205.803246 -233.551476)
		(width 0.15494)
		(layer "In13.Cu")
		(net "SMB_NIC0_R_SCL")
	)
	(segment
		(start 108.932726 -211.0232)
		(end 109.643926 -211.7344)
		(width 0.15494)
		(layer "In13.Cu")
		(net "SMB_NIC0_R_SCL")
	)
	(segment
		(start 205.803246 -233.551476)
		(end 207.51038 -231.844342)
		(width 0.15494)
		(layer "In13.Cu")
		(net "SMB_NIC0_R_SCL")
	)
	(segment
		(start 64.843406 -209.38236)
		(end 65.950846 -210.4898)
		(width 0.15494)
		(layer "In13.Cu")
		(net "SMB_NIC0_R_SCL")
	)
	(segment
		(start 146.375374 -221.562168)
		(end 158.364682 -233.551476)
		(width 0.15494)
		(layer "In13.Cu")
		(net "SMB_NIC0_R_SCL")
	)
	(segment
		(start 139.883896 -220.345)
		(end 141.101064 -221.562168)
		(width 0.15494)
		(layer "In13.Cu")
		(net "SMB_NIC0_R_SCL")
	)
	(segment
		(start 222.169228 -232.688384)
		(end 222.663512 -233.182668)
		(width 0.15494)
		(layer "In13.Cu")
		(net "SMB_NIC0_R_SCL")
	)
	(segment
		(start 124.663454 -220.9292)
		(end 133.146546 -220.9292)
		(width 0.15494)
		(layer "In13.Cu")
		(net "SMB_NIC0_R_SCL")
	)
	(segment
		(start 133.730746 -220.345)
		(end 139.883896 -220.345)
		(width 0.15494)
		(layer "In13.Cu")
		(net "SMB_NIC0_R_SCL")
	)
	(segment
		(start 75.15479 -210.4898)
		(end 75.75931 -211.09432)
		(width 0.15494)
		(layer "In13.Cu")
		(net "SMB_NIC0_R_SCL")
	)
	(segment
		(start 105.9434 -211.7344)
		(end 106.6546 -211.0232)
		(width 0.15494)
		(layer "In13.Cu")
		(net "SMB_NIC0_R_SCL")
	)
	(segment
		(start 115.468654 -211.7344)
		(end 124.663454 -220.9292)
		(width 0.15494)
		(layer "In13.Cu")
		(net "SMB_NIC0_R_SCL")
	)
	(segment
		(start 106.6546 -211.0232)
		(end 108.932726 -211.0232)
		(width 0.15494)
		(layer "In13.Cu")
		(net "SMB_NIC0_R_SCL")
	)
	(segment
		(start 207.51038 -231.844342)
		(end 208.207356 -231.844342)
		(width 0.15494)
		(layer "In13.Cu")
		(net "SMB_NIC0_R_SCL")
	)
	(segment
		(start 100.728526 -211.09432)
		(end 101.368606 -211.7344)
		(width 0.15494)
		(layer "In13.Cu")
		(net "SMB_NIC0_R_SCL")
	)
	(segment
		(start 150.331932 -389.985758)
		(end 150.319486 -389.998204)
		(width 0.13208)
		(layer "F.Cu")
		(net "PRSNT_GPU_HMC_N")
	)
	(segment
		(start 150.481792 -388.4676)
		(end 150.331932 -388.61746)
		(width 0.13208)
		(layer "F.Cu")
		(net "PRSNT_GPU_HMC_N")
	)
	(segment
		(start 151.764746 -388.4676)
		(end 150.481792 -388.4676)
		(width 0.13208)
		(layer "F.Cu")
		(net "PRSNT_GPU_HMC_N")
	)
	(segment
		(start 155.889452 -392.812778)
		(end 155.889452 -392.592306)
		(width 0.13208)
		(layer "F.Cu")
		(net "PRSNT_GPU_HMC_N")
	)
	(segment
		(start 155.889452 -392.592306)
		(end 151.764746 -388.4676)
		(width 0.13208)
		(layer "F.Cu")
		(net "PRSNT_GPU_HMC_N")
	)
	(segment
		(start 150.331932 -388.61746)
		(end 150.331932 -389.985758)
		(width 0.13208)
		(layer "F.Cu")
		(net "PRSNT_GPU_HMC_N")
	)
	(via
		(at 155.889452 -392.812778)
		(size 0.508)
		(drill 0.254)
		(layers "F.Cu" "B.Cu")
		(net "PRSNT_GPU_HMC_N")
	)
	(segment
		(start 163.68141 -412.718758)
		(end 164.31006 -412.090108)
		(width 0.15494)
		(layer "In9.Cu")
		(net "PRSNT_GPU_HMC_N")
	)
	(segment
		(start 156.9212 -394.055854)
		(end 156.9212 -410.161994)
		(width 0.15494)
		(layer "In9.Cu")
		(net "PRSNT_GPU_HMC_N")
	)
	(segment
		(start 155.889452 -392.812778)
		(end 155.889452 -393.024106)
		(width 0.15494)
		(layer "In9.Cu")
		(net "PRSNT_GPU_HMC_N")
	)
	(segment
		(start 156.9212 -410.161994)
		(end 159.477964 -412.718758)
		(width 0.15494)
		(layer "In9.Cu")
		(net "PRSNT_GPU_HMC_N")
	)
	(segment
		(start 155.889452 -393.024106)
		(end 156.9212 -394.055854)
		(width 0.15494)
		(layer "In9.Cu")
		(net "PRSNT_GPU_HMC_N")
	)
	(segment
		(start 159.477964 -412.718758)
		(end 163.68141 -412.718758)
		(width 0.15494)
		(layer "In9.Cu")
		(net "PRSNT_GPU_HMC_N")
	)
	(segment
		(start 349.690182 -211.59089)
		(end 349.690182 -210.96859)
		(width 0.13208)
		(layer "F.Cu")
		(net "PRSNT_SSD6_FPGA_N")
	)
	(segment
		(start 349.758 -207.4926)
		(end 350.177608 -207.072992)
		(width 0.13208)
		(layer "F.Cu")
		(net "PRSNT_SSD6_FPGA_N")
	)
	(segment
		(start 349.293942 -211.98713)
		(end 349.690182 -211.59089)
		(width 0.13208)
		(layer "F.Cu")
		(net "PRSNT_SSD6_FPGA_N")
	)
	(segment
		(start 350.393 -206.01305)
		(end 350.393 -206.807816)
		(width 0.13208)
		(layer "F.Cu")
		(net "PRSNT_SSD6_FPGA_N")
	)
	(segment
		(start 350.774 -205.63205)
		(end 350.393 -206.01305)
		(width 0.13208)
		(layer "F.Cu")
		(net "PRSNT_SSD6_FPGA_N")
	)
	(segment
		(start 350.393 -206.807816)
		(end 350.658176 -207.072992)
		(width 0.13208)
		(layer "F.Cu")
		(net "PRSNT_SSD6_FPGA_N")
	)
	(segment
		(start 350.177608 -207.072992)
		(end 350.658176 -207.072992)
		(width 0.13208)
		(layer "F.Cu")
		(net "PRSNT_SSD6_FPGA_N")
	)
	(segment
		(start 349.690182 -210.96859)
		(end 349.758 -210.900772)
		(width 0.13208)
		(layer "F.Cu")
		(net "PRSNT_SSD6_FPGA_N")
	)
	(segment
		(start 349.758 -210.900772)
		(end 349.758 -207.4926)
		(width 0.13208)
		(layer "F.Cu")
		(net "PRSNT_SSD6_FPGA_N")
	)
	(via
		(at 350.658176 -207.072992)
		(size 0.762)
		(drill 0.381)
		(layers "F.Cu" "B.Cu")
		(net "PRSNT_SSD6_FPGA_N")
	)
	(segment
		(start 384.834384 -251.158502)
		(end 384.834384 -250.470924)
		(width 0.13208)
		(layer "F.Cu")
		(net "PEX3_MODE_SEL6")
	)
	(segment
		(start 384.834384 -251.956824)
		(end 384.834384 -251.158502)
		(width 0.13208)
		(layer "F.Cu")
		(net "PEX3_MODE_SEL6")
	)
	(segment
		(start 413.649922 -283.549852)
		(end 414.124902 -284.024832)
		(width 0.13208)
		(layer "F.Cu")
		(net "PEX3_MODE_SEL6")
	)
	(via
		(at 384.834384 -251.158502)
		(size 0.508)
		(drill 0.254)
		(layers "F.Cu" "B.Cu")
		(net "PEX3_MODE_SEL6")
	)
	(via
		(at 414.124902 -284.024832)
		(size 0.4064)
		(drill 0.2032)
		(layers "F.Cu" "B.Cu")
		(net "PEX3_MODE_SEL6")
	)
	(segment
		(start 399.204688 -254.585978)
		(end 414.943798 -270.325088)
		(width 0.13208)
		(layer "B.Cu")
		(net "PEX3_MODE_SEL6")
	)
	(segment
		(start 415.620962 -271.183862)
		(end 415.802572 -271.183862)
		(width 0.13208)
		(layer "B.Cu")
		(net "PEX3_MODE_SEL6")
	)
	(segment
		(start 416.935158 -272.316448)
		(end 416.935158 -281.865324)
		(width 0.13208)
		(layer "B.Cu")
		(net "PEX3_MODE_SEL6")
	)
	(segment
		(start 415.302954 -283.497528)
		(end 414.652206 -283.497528)
		(width 0.13208)
		(layer "B.Cu")
		(net "PEX3_MODE_SEL6")
	)
	(segment
		(start 384.347212 -251.645674)
		(end 384.347212 -254.002286)
		(width 0.13208)
		(layer "B.Cu")
		(net "PEX3_MODE_SEL6")
	)
	(segment
		(start 416.165284 -282.635198)
		(end 415.783014 -282.635198)
		(width 0.13208)
		(layer "B.Cu")
		(net "PEX3_MODE_SEL6")
	)
	(segment
		(start 414.943798 -270.325088)
		(end 414.943798 -270.506698)
		(width 0.13208)
		(layer "B.Cu")
		(net "PEX3_MODE_SEL6")
	)
	(segment
		(start 415.802572 -271.183862)
		(end 416.935158 -272.316448)
		(width 0.13208)
		(layer "B.Cu")
		(net "PEX3_MODE_SEL6")
	)
	(segment
		(start 415.567876 -282.850336)
		(end 415.567876 -283.232606)
		(width 0.13208)
		(layer "B.Cu")
		(net "PEX3_MODE_SEL6")
	)
	(segment
		(start 415.567876 -283.232606)
		(end 415.302954 -283.497528)
		(width 0.13208)
		(layer "B.Cu")
		(net "PEX3_MODE_SEL6")
	)
	(segment
		(start 384.347212 -254.002286)
		(end 384.930904 -254.585978)
		(width 0.13208)
		(layer "B.Cu")
		(net "PEX3_MODE_SEL6")
	)
	(segment
		(start 384.834384 -251.158502)
		(end 384.347212 -251.645674)
		(width 0.13208)
		(layer "B.Cu")
		(net "PEX3_MODE_SEL6")
	)
	(segment
		(start 415.783014 -282.635198)
		(end 415.567876 -282.850336)
		(width 0.13208)
		(layer "B.Cu")
		(net "PEX3_MODE_SEL6")
	)
	(segment
		(start 414.652206 -283.497528)
		(end 414.124902 -284.024832)
		(width 0.13208)
		(layer "B.Cu")
		(net "PEX3_MODE_SEL6")
	)
	(segment
		(start 384.930904 -254.585978)
		(end 399.204688 -254.585978)
		(width 0.13208)
		(layer "B.Cu")
		(net "PEX3_MODE_SEL6")
	)
	(segment
		(start 416.935158 -281.865324)
		(end 416.165284 -282.635198)
		(width 0.13208)
		(layer "B.Cu")
		(net "PEX3_MODE_SEL6")
	)
	(segment
		(start 414.943798 -270.506698)
		(end 415.620962 -271.183862)
		(width 0.13208)
		(layer "B.Cu")
		(net "PEX3_MODE_SEL6")
	)
	(segment
		(start 224.667572 -218.70416)
		(end 225.067622 -219.10421)
		(width 0.13208)
		(layer "F.Cu")
		(net "SMB_NIC5_SCL")
	)
	(segment
		(start 218.871546 -217.734134)
		(end 218.303094 -218.302586)
		(width 0.13208)
		(layer "F.Cu")
		(net "SMB_NIC5_SCL")
	)
	(segment
		(start 220.503242 -218.515692)
		(end 219.721684 -217.734134)
		(width 0.13208)
		(layer "F.Cu")
		(net "SMB_NIC5_SCL")
	)
	(segment
		(start 214.267796 -218.293442)
		(end 213.781386 -218.779852)
		(width 0.13208)
		(layer "F.Cu")
		(net "SMB_NIC5_SCL")
	)
	(segment
		(start 213.013798 -218.779852)
		(end 212.802978 -218.569032)
		(width 0.13208)
		(layer "F.Cu")
		(net "SMB_NIC5_SCL")
	)
	(segment
		(start 220.503242 -218.515692)
		(end 220.69171 -218.70416)
		(width 0.13208)
		(layer "F.Cu")
		(net "SMB_NIC5_SCL")
	)
	(segment
		(start 219.721684 -217.734134)
		(end 218.871546 -217.734134)
		(width 0.13208)
		(layer "F.Cu")
		(net "SMB_NIC5_SCL")
	)
	(segment
		(start 218.303094 -218.302586)
		(end 217.635836 -218.302586)
		(width 0.13208)
		(layer "F.Cu")
		(net "SMB_NIC5_SCL")
	)
	(segment
		(start 212.469984 -218.569032)
		(end 212.44687 -218.545918)
		(width 0.13208)
		(layer "F.Cu")
		(net "SMB_NIC5_SCL")
	)
	(segment
		(start 220.69171 -218.70416)
		(end 224.667572 -218.70416)
		(width 0.13208)
		(layer "F.Cu")
		(net "SMB_NIC5_SCL")
	)
	(segment
		(start 213.781386 -218.779852)
		(end 213.013798 -218.779852)
		(width 0.13208)
		(layer "F.Cu")
		(net "SMB_NIC5_SCL")
	)
	(segment
		(start 212.802978 -218.569032)
		(end 212.469984 -218.569032)
		(width 0.13208)
		(layer "F.Cu")
		(net "SMB_NIC5_SCL")
	)
	(via
		(at 220.503242 -218.515692)
		(size 0.762)
		(drill 0.381)
		(layers "F.Cu" "B.Cu")
		(net "SMB_NIC5_SCL")
	)
	(via
		(at 218.303094 -218.302586)
		(size 0.508)
		(drill 0.254)
		(layers "F.Cu" "B.Cu")
		(net "SMB_NIC5_SCL")
	)
	(via
		(at 214.267796 -218.293442)
		(size 0.508)
		(drill 0.254)
		(layers "F.Cu" "B.Cu")
		(net "SMB_NIC5_SCL")
	)
	(segment
		(start 217.641678 -218.302586)
		(end 218.303094 -218.302586)
		(width 0.15494)
		(layer "In5.Cu")
		(net "SMB_NIC5_SCL")
	)
	(segment
		(start 214.267796 -218.293442)
		(end 214.762334 -217.798904)
		(width 0.15494)
		(layer "In5.Cu")
		(net "SMB_NIC5_SCL")
	)
	(segment
		(start 217.137996 -217.798904)
		(end 217.641678 -218.302586)
		(width 0.15494)
		(layer "In5.Cu")
		(net "SMB_NIC5_SCL")
	)
	(segment
		(start 214.762334 -217.798904)
		(end 217.137996 -217.798904)
		(width 0.15494)
		(layer "In5.Cu")
		(net "SMB_NIC5_SCL")
	)
	(segment
		(start 338.963 -234.46105)
		(end 338.963 -235.077)
		(width 0.13208)
		(layer "F.Cu")
		(net "SSD0_CLK_EN_R_N")
	)
	(segment
		(start 105.056432 -84.178902)
		(end 104.854248 -83.976718)
		(width 0.1778)
		(layer "F.Cu")
		(net "SSD0_CLK_EN_R_N")
	)
	(segment
		(start 105.889044 -84.178902)
		(end 105.056432 -84.178902)
		(width 0.1778)
		(layer "F.Cu")
		(net "SSD0_CLK_EN_R_N")
	)
	(via
		(at 338.963 -235.077)
		(size 0.508)
		(drill 0.254)
		(layers "F.Cu" "B.Cu")
		(net "SSD0_CLK_EN_R_N")
	)
	(via
		(at 97.381314 -204.216)
		(size 0.508)
		(drill 0.254)
		(layers "F.Cu" "B.Cu")
		(net "SSD0_CLK_EN_R_N")
	)
	(via
		(at 104.854248 -83.976718)
		(size 0.508)
		(drill 0.254)
		(layers "F.Cu" "B.Cu")
		(net "SSD0_CLK_EN_R_N")
	)
	(via
		(at 80.901032 -82.377788)
		(size 0.508)
		(drill 0.254)
		(layers "F.Cu" "B.Cu")
		(net "SSD0_CLK_EN_R_N")
	)
	(segment
		(start 77.763116 -108.143294)
		(end 77.763116 -115.443508)
		(width 0.15494)
		(layer "In5.Cu")
		(net "SSD0_CLK_EN_R_N")
	)
	(segment
		(start 77.763116 -115.443508)
		(end 80.33385 -118.014242)
		(width 0.15494)
		(layer "In5.Cu")
		(net "SSD0_CLK_EN_R_N")
	)
	(segment
		(start 80.33385 -118.014242)
		(end 83.203034 -118.014242)
		(width 0.15494)
		(layer "In5.Cu")
		(net "SSD0_CLK_EN_R_N")
	)
	(segment
		(start 77.954378 -91.821508)
		(end 79.035402 -92.902532)
		(width 0.15494)
		(layer "In5.Cu")
		(net "SSD0_CLK_EN_R_N")
	)
	(segment
		(start 77.954378 -87.941912)
		(end 77.954378 -91.821508)
		(width 0.15494)
		(layer "In5.Cu")
		(net "SSD0_CLK_EN_R_N")
	)
	(segment
		(start 96.901 -190.245746)
		(end 96.901 -195.0212)
		(width 0.15494)
		(layer "In5.Cu")
		(net "SSD0_CLK_EN_R_N")
	)
	(segment
		(start 79.035402 -106.871008)
		(end 77.763116 -108.143294)
		(width 0.15494)
		(layer "In5.Cu")
		(net "SSD0_CLK_EN_R_N")
	)
	(segment
		(start 85.39226 -120.203468)
		(end 85.39226 -128.21031)
		(width 0.15494)
		(layer "In5.Cu")
		(net "SSD0_CLK_EN_R_N")
	)
	(segment
		(start 97.381314 -195.501514)
		(end 97.381314 -204.216)
		(width 0.15494)
		(layer "In5.Cu")
		(net "SSD0_CLK_EN_R_N")
	)
	(segment
		(start 79.54772 -86.34857)
		(end 77.954378 -87.941912)
		(width 0.15494)
		(layer "In5.Cu")
		(net "SSD0_CLK_EN_R_N")
	)
	(segment
		(start 88.56726 -131.38531)
		(end 88.56726 -134.49173)
		(width 0.15494)
		(layer "In5.Cu")
		(net "SSD0_CLK_EN_R_N")
	)
	(segment
		(start 96.901 -195.0212)
		(end 97.381314 -195.501514)
		(width 0.15494)
		(layer "In5.Cu")
		(net "SSD0_CLK_EN_R_N")
	)
	(segment
		(start 91.92514 -142.598394)
		(end 91.92514 -178.68519)
		(width 0.15494)
		(layer "In5.Cu")
		(net "SSD0_CLK_EN_R_N")
	)
	(segment
		(start 91.92514 -178.68519)
		(end 93.419168 -180.179218)
		(width 0.15494)
		(layer "In5.Cu")
		(net "SSD0_CLK_EN_R_N")
	)
	(segment
		(start 85.39226 -128.21031)
		(end 88.56726 -131.38531)
		(width 0.15494)
		(layer "In5.Cu")
		(net "SSD0_CLK_EN_R_N")
	)
	(segment
		(start 79.54772 -83.7311)
		(end 79.54772 -86.34857)
		(width 0.15494)
		(layer "In5.Cu")
		(net "SSD0_CLK_EN_R_N")
	)
	(segment
		(start 83.203034 -118.014242)
		(end 85.39226 -120.203468)
		(width 0.15494)
		(layer "In5.Cu")
		(net "SSD0_CLK_EN_R_N")
	)
	(segment
		(start 79.035402 -92.902532)
		(end 79.035402 -106.871008)
		(width 0.15494)
		(layer "In5.Cu")
		(net "SSD0_CLK_EN_R_N")
	)
	(segment
		(start 93.419168 -180.179218)
		(end 93.419168 -186.763914)
		(width 0.15494)
		(layer "In5.Cu")
		(net "SSD0_CLK_EN_R_N")
	)
	(segment
		(start 93.419168 -186.763914)
		(end 96.901 -190.245746)
		(width 0.15494)
		(layer "In5.Cu")
		(net "SSD0_CLK_EN_R_N")
	)
	(segment
		(start 88.56726 -134.49173)
		(end 91.92514 -142.598394)
		(width 0.15494)
		(layer "In5.Cu")
		(net "SSD0_CLK_EN_R_N")
	)
	(segment
		(start 80.901032 -82.377788)
		(end 79.54772 -83.7311)
		(width 0.15494)
		(layer "In5.Cu")
		(net "SSD0_CLK_EN_R_N")
	)
	(segment
		(start 327.828148 -238.04626)
		(end 329.71994 -238.04626)
		(width 0.15494)
		(layer "In15.Cu")
		(net "SSD0_CLK_EN_R_N")
	)
	(segment
		(start 337.448144 -235.244386)
		(end 337.448144 -234.891326)
		(width 0.15494)
		(layer "In15.Cu")
		(net "SSD0_CLK_EN_R_N")
	)
	(segment
		(start 138.09599 -227.664264)
		(end 141.314424 -227.664264)
		(width 0.15494)
		(layer "In15.Cu")
		(net "SSD0_CLK_EN_R_N")
	)
	(segment
		(start 267.880084 -237.056676)
		(end 269.681706 -238.858298)
		(width 0.15494)
		(layer "In15.Cu")
		(net "SSD0_CLK_EN_R_N")
	)
	(segment
		(start 326.983344 -238.891064)
		(end 327.828148 -238.04626)
		(width 0.15494)
		(layer "In15.Cu")
		(net "SSD0_CLK_EN_R_N")
	)
	(segment
		(start 219.964 -236.6518)
		(end 222.9358 -236.6518)
		(width 0.15494)
		(layer "In15.Cu")
		(net "SSD0_CLK_EN_R_N")
	)
	(segment
		(start 215.253316 -237.066074)
		(end 216.298272 -238.11103)
		(width 0.15494)
		(layer "In15.Cu")
		(net "SSD0_CLK_EN_R_N")
	)
	(segment
		(start 264.760456 -232.815638)
		(end 267.910564 -235.965746)
		(width 0.15494)
		(layer "In15.Cu")
		(net "SSD0_CLK_EN_R_N")
	)
	(segment
		(start 246.714264 -236.16539)
		(end 247.376188 -236.16539)
		(width 0.15494)
		(layer "In15.Cu")
		(net "SSD0_CLK_EN_R_N")
	)
	(segment
		(start 257.780028 -231.14762)
		(end 262.269986 -231.14762)
		(width 0.15494)
		(layer "In15.Cu")
		(net "SSD0_CLK_EN_R_N")
	)
	(segment
		(start 337.448144 -234.891326)
		(end 337.74634 -234.59313)
		(width 0.15494)
		(layer "In15.Cu")
		(net "SSD0_CLK_EN_R_N")
	)
	(segment
		(start 257.061208 -230.83012)
		(end 257.462528 -230.83012)
		(width 0.15494)
		(layer "In15.Cu")
		(net "SSD0_CLK_EN_R_N")
	)
	(segment
		(start 130.91033 -228.082094)
		(end 131.285488 -228.457252)
		(width 0.15494)
		(layer "In15.Cu")
		(net "SSD0_CLK_EN_R_N")
	)
	(segment
		(start 136.843262 -228.916992)
		(end 138.09599 -227.664264)
		(width 0.15494)
		(layer "In15.Cu")
		(net "SSD0_CLK_EN_R_N")
	)
	(segment
		(start 147.884134 -227.468684)
		(end 148.712936 -226.643184)
		(width 0.15494)
		(layer "In15.Cu")
		(net "SSD0_CLK_EN_R_N")
	)
	(segment
		(start 218.50477 -238.11103)
		(end 219.964 -236.6518)
		(width 0.15494)
		(layer "In15.Cu")
		(net "SSD0_CLK_EN_R_N")
	)
	(segment
		(start 250.839732 -232.701846)
		(end 252.521212 -232.701846)
		(width 0.15494)
		(layer "In15.Cu")
		(net "SSD0_CLK_EN_R_N")
	)
	(segment
		(start 224.775776 -237.682024)
		(end 225.29546 -237.16234)
		(width 0.15494)
		(layer "In15.Cu")
		(net "SSD0_CLK_EN_R_N")
	)
	(segment
		(start 131.285488 -228.457252)
		(end 133.6294 -228.457252)
		(width 0.15494)
		(layer "In15.Cu")
		(net "SSD0_CLK_EN_R_N")
	)
	(segment
		(start 336.832702 -235.859828)
		(end 337.448144 -235.244386)
		(width 0.15494)
		(layer "In15.Cu")
		(net "SSD0_CLK_EN_R_N")
	)
	(segment
		(start 80.901032 -82.377788)
		(end 80.916018 -82.362802)
		(width 0.15494)
		(layer "In15.Cu")
		(net "SSD0_CLK_EN_R_N")
	)
	(segment
		(start 80.916018 -82.362802)
		(end 103.240332 -82.362802)
		(width 0.15494)
		(layer "In15.Cu")
		(net "SSD0_CLK_EN_R_N")
	)
	(segment
		(start 116.334286 -215.66251)
		(end 128.75387 -228.082094)
		(width 0.15494)
		(layer "In15.Cu")
		(net "SSD0_CLK_EN_R_N")
	)
	(segment
		(start 240.942876 -237.60049)
		(end 241.281966 -237.2614)
		(width 0.15494)
		(layer "In15.Cu")
		(net "SSD0_CLK_EN_R_N")
	)
	(segment
		(start 329.71994 -238.04626)
		(end 330.901802 -236.864398)
		(width 0.15494)
		(layer "In15.Cu")
		(net "SSD0_CLK_EN_R_N")
	)
	(segment
		(start 326.310244 -239.784382)
		(end 326.983344 -239.111282)
		(width 0.15494)
		(layer "In15.Cu")
		(net "SSD0_CLK_EN_R_N")
	)
	(segment
		(start 128.75387 -228.082094)
		(end 130.91033 -228.082094)
		(width 0.15494)
		(layer "In15.Cu")
		(net "SSD0_CLK_EN_R_N")
	)
	(segment
		(start 276.087586 -238.858298)
		(end 277.01367 -239.784382)
		(width 0.15494)
		(layer "In15.Cu")
		(net "SSD0_CLK_EN_R_N")
	)
	(segment
		(start 134.08914 -228.916992)
		(end 136.843262 -228.916992)
		(width 0.15494)
		(layer "In15.Cu")
		(net "SSD0_CLK_EN_R_N")
	)
	(segment
		(start 337.74634 -234.59313)
		(end 338.47913 -234.59313)
		(width 0.15494)
		(layer "In15.Cu")
		(net "SSD0_CLK_EN_R_N")
	)
	(segment
		(start 116.334286 -211.979764)
		(end 116.334286 -215.66251)
		(width 0.15494)
		(layer "In15.Cu")
		(net "SSD0_CLK_EN_R_N")
	)
	(segment
		(start 180.921152 -231.88803)
		(end 187.870084 -231.88803)
		(width 0.15494)
		(layer "In15.Cu")
		(net "SSD0_CLK_EN_R_N")
	)
	(segment
		(start 267.910564 -236.327696)
		(end 267.880084 -236.358176)
		(width 0.15494)
		(layer "In15.Cu")
		(net "SSD0_CLK_EN_R_N")
	)
	(segment
		(start 241.281966 -237.2614)
		(end 245.618254 -237.2614)
		(width 0.15494)
		(layer "In15.Cu")
		(net "SSD0_CLK_EN_R_N")
	)
	(segment
		(start 338.47913 -234.59313)
		(end 338.963 -235.077)
		(width 0.15494)
		(layer "In15.Cu")
		(net "SSD0_CLK_EN_R_N")
	)
	(segment
		(start 225.29546 -237.16234)
		(end 230.740204 -237.16234)
		(width 0.15494)
		(layer "In15.Cu")
		(net "SSD0_CLK_EN_R_N")
	)
	(segment
		(start 141.745208 -227.23348)
		(end 142.335504 -227.23348)
		(width 0.15494)
		(layer "In15.Cu")
		(net "SSD0_CLK_EN_R_N")
	)
	(segment
		(start 222.9358 -236.6518)
		(end 223.966024 -237.682024)
		(width 0.15494)
		(layer "In15.Cu")
		(net "SSD0_CLK_EN_R_N")
	)
	(segment
		(start 231.178354 -237.60049)
		(end 240.942876 -237.60049)
		(width 0.15494)
		(layer "In15.Cu")
		(net "SSD0_CLK_EN_R_N")
	)
	(segment
		(start 142.335504 -227.23348)
		(end 142.766288 -227.664264)
		(width 0.15494)
		(layer "In15.Cu")
		(net "SSD0_CLK_EN_R_N")
	)
	(segment
		(start 157.434534 -226.643184)
		(end 161.46018 -230.66883)
		(width 0.15494)
		(layer "In15.Cu")
		(net "SSD0_CLK_EN_R_N")
	)
	(segment
		(start 263.35609 -232.233724)
		(end 264.760456 -232.815638)
		(width 0.15494)
		(layer "In15.Cu")
		(net "SSD0_CLK_EN_R_N")
	)
	(segment
		(start 257.462528 -230.83012)
		(end 257.780028 -231.14762)
		(width 0.15494)
		(layer "In15.Cu")
		(net "SSD0_CLK_EN_R_N")
	)
	(segment
		(start 97.381314 -204.216)
		(end 98.319336 -204.40269)
		(width 0.15494)
		(layer "In15.Cu")
		(net "SSD0_CLK_EN_R_N")
	)
	(segment
		(start 326.983344 -239.111282)
		(end 326.983344 -238.891064)
		(width 0.15494)
		(layer "In15.Cu")
		(net "SSD0_CLK_EN_R_N")
	)
	(segment
		(start 256.250948 -231.64038)
		(end 257.061208 -230.83012)
		(width 0.15494)
		(layer "In15.Cu")
		(net "SSD0_CLK_EN_R_N")
	)
	(segment
		(start 330.901802 -236.864398)
		(end 334.882744 -236.864398)
		(width 0.15494)
		(layer "In15.Cu")
		(net "SSD0_CLK_EN_R_N")
	)
	(segment
		(start 252.521212 -232.701846)
		(end 253.582678 -231.64038)
		(width 0.15494)
		(layer "In15.Cu")
		(net "SSD0_CLK_EN_R_N")
	)
	(segment
		(start 335.887314 -235.859828)
		(end 336.832702 -235.859828)
		(width 0.15494)
		(layer "In15.Cu")
		(net "SSD0_CLK_EN_R_N")
	)
	(segment
		(start 216.298272 -238.11103)
		(end 218.50477 -238.11103)
		(width 0.15494)
		(layer "In15.Cu")
		(net "SSD0_CLK_EN_R_N")
	)
	(segment
		(start 98.319336 -204.40269)
		(end 102.277672 -206.04226)
		(width 0.15494)
		(layer "In15.Cu")
		(net "SSD0_CLK_EN_R_N")
	)
	(segment
		(start 179.701952 -230.66883)
		(end 180.921152 -231.88803)
		(width 0.15494)
		(layer "In15.Cu")
		(net "SSD0_CLK_EN_R_N")
	)
	(segment
		(start 102.277672 -206.04226)
		(end 110.396782 -206.04226)
		(width 0.15494)
		(layer "In15.Cu")
		(net "SSD0_CLK_EN_R_N")
	)
	(segment
		(start 230.740204 -237.16234)
		(end 231.178354 -237.60049)
		(width 0.15494)
		(layer "In15.Cu")
		(net "SSD0_CLK_EN_R_N")
	)
	(segment
		(start 148.712936 -226.643184)
		(end 157.434534 -226.643184)
		(width 0.15494)
		(layer "In15.Cu")
		(net "SSD0_CLK_EN_R_N")
	)
	(segment
		(start 144.87398 -227.664264)
		(end 145.06956 -227.468684)
		(width 0.15494)
		(layer "In15.Cu")
		(net "SSD0_CLK_EN_R_N")
	)
	(segment
		(start 133.6294 -228.457252)
		(end 134.08914 -228.916992)
		(width 0.15494)
		(layer "In15.Cu")
		(net "SSD0_CLK_EN_R_N")
	)
	(segment
		(start 187.870084 -231.88803)
		(end 193.048128 -237.066074)
		(width 0.15494)
		(layer "In15.Cu")
		(net "SSD0_CLK_EN_R_N")
	)
	(segment
		(start 277.01367 -239.784382)
		(end 326.310244 -239.784382)
		(width 0.15494)
		(layer "In15.Cu")
		(net "SSD0_CLK_EN_R_N")
	)
	(segment
		(start 334.882744 -236.864398)
		(end 335.887314 -235.859828)
		(width 0.15494)
		(layer "In15.Cu")
		(net "SSD0_CLK_EN_R_N")
	)
	(segment
		(start 262.269986 -231.14762)
		(end 263.35609 -232.233724)
		(width 0.15494)
		(layer "In15.Cu")
		(net "SSD0_CLK_EN_R_N")
	)
	(segment
		(start 193.048128 -237.066074)
		(end 215.253316 -237.066074)
		(width 0.15494)
		(layer "In15.Cu")
		(net "SSD0_CLK_EN_R_N")
	)
	(segment
		(start 223.966024 -237.682024)
		(end 224.775776 -237.682024)
		(width 0.15494)
		(layer "In15.Cu")
		(net "SSD0_CLK_EN_R_N")
	)
	(segment
		(start 142.766288 -227.664264)
		(end 144.87398 -227.664264)
		(width 0.15494)
		(layer "In15.Cu")
		(net "SSD0_CLK_EN_R_N")
	)
	(segment
		(start 145.06956 -227.468684)
		(end 147.884134 -227.468684)
		(width 0.15494)
		(layer "In15.Cu")
		(net "SSD0_CLK_EN_R_N")
	)
	(segment
		(start 247.376188 -236.16539)
		(end 250.839732 -232.701846)
		(width 0.15494)
		(layer "In15.Cu")
		(net "SSD0_CLK_EN_R_N")
	)
	(segment
		(start 267.910564 -235.965746)
		(end 267.910564 -236.327696)
		(width 0.15494)
		(layer "In15.Cu")
		(net "SSD0_CLK_EN_R_N")
	)
	(segment
		(start 267.880084 -236.358176)
		(end 267.880084 -237.056676)
		(width 0.15494)
		(layer "In15.Cu")
		(net "SSD0_CLK_EN_R_N")
	)
	(segment
		(start 245.618254 -237.2614)
		(end 246.714264 -236.16539)
		(width 0.15494)
		(layer "In15.Cu")
		(net "SSD0_CLK_EN_R_N")
	)
	(segment
		(start 103.240332 -82.362802)
		(end 104.854248 -83.976718)
		(width 0.15494)
		(layer "In15.Cu")
		(net "SSD0_CLK_EN_R_N")
	)
	(segment
		(start 253.582678 -231.64038)
		(end 256.250948 -231.64038)
		(width 0.15494)
		(layer "In15.Cu")
		(net "SSD0_CLK_EN_R_N")
	)
	(segment
		(start 141.314424 -227.664264)
		(end 141.745208 -227.23348)
		(width 0.15494)
		(layer "In15.Cu")
		(net "SSD0_CLK_EN_R_N")
	)
	(segment
		(start 161.46018 -230.66883)
		(end 179.701952 -230.66883)
		(width 0.15494)
		(layer "In15.Cu")
		(net "SSD0_CLK_EN_R_N")
	)
	(segment
		(start 110.396782 -206.04226)
		(end 116.334286 -211.979764)
		(width 0.15494)
		(layer "In15.Cu")
		(net "SSD0_CLK_EN_R_N")
	)
	(segment
		(start 269.681706 -238.858298)
		(end 276.087586 -238.858298)
		(width 0.15494)
		(layer "In15.Cu")
		(net "SSD0_CLK_EN_R_N")
	)
	(segment
		(start 434.403754 -27.04973)
		(end 434.420518 -27.066494)
		(width 0.13208)
		(layer "F.Cu")
		(net "PRSNT_SSD15_R_N")
	)
	(segment
		(start 434.420518 -27.066494)
		(end 435.242462 -27.066494)
		(width 0.13208)
		(layer "F.Cu")
		(net "PRSNT_SSD15_R_N")
	)
	(segment
		(start 235.867448 -222.703898)
		(end 235.467652 -222.304102)
		(width 0.13208)
		(layer "F.Cu")
		(net "PRSNT_SSD15_R_N")
	)
	(segment
		(start 342.893904 -211.18703)
		(end 342.893904 -210.566)
		(width 0.13208)
		(layer "F.Cu")
		(net "PRSNT_SSD15_R_N")
	)
	(segment
		(start 433.40909 -27.04973)
		(end 434.403754 -27.04973)
		(width 0.13208)
		(layer "F.Cu")
		(net "PRSNT_SSD15_R_N")
	)
	(segment
		(start 432.87569 -36.515548)
		(end 433.69611 -36.515548)
		(width 0.13208)
		(layer "F.Cu")
		(net "PRSNT_SSD15_R_N")
	)
	(segment
		(start 433.40909 -26.03373)
		(end 433.40909 -27.04973)
		(width 0.13208)
		(layer "F.Cu")
		(net "PRSNT_SSD15_R_N")
	)
	(via
		(at 245.703598 -210.540854)
		(size 0.508)
		(drill 0.254)
		(layers "F.Cu" "B.Cu")
		(net "PRSNT_SSD15_R_N")
	)
	(via
		(at 435.242462 -27.066494)
		(size 0.508)
		(drill 0.254)
		(layers "F.Cu" "B.Cu")
		(net "PRSNT_SSD15_R_N")
	)
	(via
		(at 235.867448 -222.703898)
		(size 0.4572)
		(drill 0.254)
		(layers "F.Cu" "B.Cu")
		(net "PRSNT_SSD15_R_N")
	)
	(via
		(at 433.69611 -36.515548)
		(size 0.508)
		(drill 0.254)
		(layers "F.Cu" "B.Cu")
		(net "PRSNT_SSD15_R_N")
	)
	(via
		(at 353.96805 -100.91674)
		(size 0.508)
		(drill 0.254)
		(layers "F.Cu" "B.Cu")
		(net "PRSNT_SSD15_R_N")
	)
	(via
		(at 267.693902 -212.780372)
		(size 0.508)
		(drill 0.254)
		(layers "F.Cu" "B.Cu")
		(net "PRSNT_SSD15_R_N")
	)
	(via
		(at 420.311834 -89.430352)
		(size 0.508)
		(drill 0.254)
		(layers "F.Cu" "B.Cu")
		(net "PRSNT_SSD15_R_N")
	)
	(via
		(at 342.893904 -210.566)
		(size 0.508)
		(drill 0.254)
		(layers "F.Cu" "B.Cu")
		(net "PRSNT_SSD15_R_N")
	)
	(segment
		(start 433.69611 -39.613332)
		(end 438.787286 -44.704508)
		(width 0.15494)
		(layer "In5.Cu")
		(net "PRSNT_SSD15_R_N")
	)
	(segment
		(start 432.063398 -29.737304)
		(end 434.734208 -27.066494)
		(width 0.15494)
		(layer "In5.Cu")
		(net "PRSNT_SSD15_R_N")
	)
	(segment
		(start 429.657002 -76.519532)
		(end 420.311834 -85.8647)
		(width 0.15494)
		(layer "In5.Cu")
		(net "PRSNT_SSD15_R_N")
	)
	(segment
		(start 431.17643 -76.519532)
		(end 429.657002 -76.519532)
		(width 0.15494)
		(layer "In5.Cu")
		(net "PRSNT_SSD15_R_N")
	)
	(segment
		(start 433.69611 -36.515548)
		(end 433.69611 -39.613332)
		(width 0.15494)
		(layer "In5.Cu")
		(net "PRSNT_SSD15_R_N")
	)
	(segment
		(start 438.787286 -44.704508)
		(end 438.787286 -68.908676)
		(width 0.15494)
		(layer "In5.Cu")
		(net "PRSNT_SSD15_R_N")
	)
	(segment
		(start 434.734208 -27.066494)
		(end 435.242462 -27.066494)
		(width 0.15494)
		(layer "In5.Cu")
		(net "PRSNT_SSD15_R_N")
	)
	(segment
		(start 438.787286 -68.908676)
		(end 431.17643 -76.519532)
		(width 0.15494)
		(layer "In5.Cu")
		(net "PRSNT_SSD15_R_N")
	)
	(segment
		(start 420.311834 -85.8647)
		(end 420.311834 -89.430352)
		(width 0.15494)
		(layer "In5.Cu")
		(net "PRSNT_SSD15_R_N")
	)
	(segment
		(start 433.69611 -36.515548)
		(end 432.063398 -34.882836)
		(width 0.15494)
		(layer "In5.Cu")
		(net "PRSNT_SSD15_R_N")
	)
	(segment
		(start 432.063398 -34.882836)
		(end 432.063398 -29.737304)
		(width 0.15494)
		(layer "In5.Cu")
		(net "PRSNT_SSD15_R_N")
	)
	(segment
		(start 244.27053 -213.5378)
		(end 243.713 -213.5378)
		(width 0.15494)
		(layer "In7.Cu")
		(net "PRSNT_SSD15_R_N")
	)
	(segment
		(start 347.118686 -166.397686)
		(end 347.118686 -127.315976)
		(width 0.15494)
		(layer "In7.Cu")
		(net "PRSNT_SSD15_R_N")
	)
	(segment
		(start 345.889326 -207.570578)
		(end 346.632022 -207.570578)
		(width 0.15494)
		(layer "In7.Cu")
		(net "PRSNT_SSD15_R_N")
	)
	(segment
		(start 348.234 -205.41107)
		(end 348.234 -203.792582)
		(width 0.15494)
		(layer "In7.Cu")
		(net "PRSNT_SSD15_R_N")
	)
	(segment
		(start 342.893904 -210.566)
		(end 345.889326 -207.570578)
		(width 0.15494)
		(layer "In7.Cu")
		(net "PRSNT_SSD15_R_N")
	)
	(segment
		(start 245.703598 -210.93684)
		(end 244.62232 -212.018118)
		(width 0.15494)
		(layer "In7.Cu")
		(net "PRSNT_SSD15_R_N")
	)
	(segment
		(start 355.44633 -196.580252)
		(end 355.44633 -190.67653)
		(width 0.15494)
		(layer "In7.Cu")
		(net "PRSNT_SSD15_R_N")
	)
	(segment
		(start 243.713 -213.5378)
		(end 241.1476 -216.1032)
		(width 0.15494)
		(layer "In7.Cu")
		(net "PRSNT_SSD15_R_N")
	)
	(segment
		(start 240.8428 -216.1032)
		(end 239.9284 -217.0176)
		(width 0.15494)
		(layer "In7.Cu")
		(net "PRSNT_SSD15_R_N")
	)
	(segment
		(start 347.727016 -205.918054)
		(end 348.234 -205.41107)
		(width 0.15494)
		(layer "In7.Cu")
		(net "PRSNT_SSD15_R_N")
	)
	(segment
		(start 244.62232 -212.018118)
		(end 244.62232 -213.18601)
		(width 0.15494)
		(layer "In7.Cu")
		(net "PRSNT_SSD15_R_N")
	)
	(segment
		(start 347.727016 -206.475584)
		(end 347.727016 -205.918054)
		(width 0.15494)
		(layer "In7.Cu")
		(net "PRSNT_SSD15_R_N")
	)
	(segment
		(start 354.965 -103.280464)
		(end 353.96805 -102.283514)
		(width 0.15494)
		(layer "In7.Cu")
		(net "PRSNT_SSD15_R_N")
	)
	(segment
		(start 239.9284 -217.0176)
		(end 239.9284 -222.095568)
		(width 0.15494)
		(layer "In7.Cu")
		(net "PRSNT_SSD15_R_N")
	)
	(segment
		(start 236.78515 -223.6216)
		(end 235.867448 -222.703898)
		(width 0.15494)
		(layer "In7.Cu")
		(net "PRSNT_SSD15_R_N")
	)
	(segment
		(start 241.1476 -216.1032)
		(end 240.8428 -216.1032)
		(width 0.15494)
		(layer "In7.Cu")
		(net "PRSNT_SSD15_R_N")
	)
	(segment
		(start 347.118686 -127.315976)
		(end 354.965 -119.469662)
		(width 0.15494)
		(layer "In7.Cu")
		(net "PRSNT_SSD15_R_N")
	)
	(segment
		(start 238.402368 -223.6216)
		(end 236.78515 -223.6216)
		(width 0.15494)
		(layer "In7.Cu")
		(net "PRSNT_SSD15_R_N")
	)
	(segment
		(start 349.32874 -184.55894)
		(end 349.32874 -168.60774)
		(width 0.15494)
		(layer "In7.Cu")
		(net "PRSNT_SSD15_R_N")
	)
	(segment
		(start 244.62232 -213.18601)
		(end 244.27053 -213.5378)
		(width 0.15494)
		(layer "In7.Cu")
		(net "PRSNT_SSD15_R_N")
	)
	(segment
		(start 353.96805 -102.283514)
		(end 353.96805 -100.91674)
		(width 0.15494)
		(layer "In7.Cu")
		(net "PRSNT_SSD15_R_N")
	)
	(segment
		(start 239.9284 -222.095568)
		(end 238.402368 -223.6216)
		(width 0.15494)
		(layer "In7.Cu")
		(net "PRSNT_SSD15_R_N")
	)
	(segment
		(start 348.234 -203.792582)
		(end 355.44633 -196.580252)
		(width 0.15494)
		(layer "In7.Cu")
		(net "PRSNT_SSD15_R_N")
	)
	(segment
		(start 355.44633 -190.67653)
		(end 349.32874 -184.55894)
		(width 0.15494)
		(layer "In7.Cu")
		(net "PRSNT_SSD15_R_N")
	)
	(segment
		(start 245.703598 -210.540854)
		(end 245.703598 -210.93684)
		(width 0.15494)
		(layer "In7.Cu")
		(net "PRSNT_SSD15_R_N")
	)
	(segment
		(start 349.32874 -168.60774)
		(end 347.118686 -166.397686)
		(width 0.15494)
		(layer "In7.Cu")
		(net "PRSNT_SSD15_R_N")
	)
	(segment
		(start 346.632022 -207.570578)
		(end 347.727016 -206.475584)
		(width 0.15494)
		(layer "In7.Cu")
		(net "PRSNT_SSD15_R_N")
	)
	(segment
		(start 354.965 -119.469662)
		(end 354.965 -103.280464)
		(width 0.15494)
		(layer "In7.Cu")
		(net "PRSNT_SSD15_R_N")
	)
	(segment
		(start 266.984226 -213.32952)
		(end 267.533374 -212.780372)
		(width 0.15494)
		(layer "In13.Cu")
		(net "PRSNT_SSD15_R_N")
	)
	(segment
		(start 265.455654 -214.6046)
		(end 266.730734 -213.32952)
		(width 0.15494)
		(layer "In13.Cu")
		(net "PRSNT_SSD15_R_N")
	)
	(segment
		(start 266.730734 -213.32952)
		(end 266.984226 -213.32952)
		(width 0.15494)
		(layer "In13.Cu")
		(net "PRSNT_SSD15_R_N")
	)
	(segment
		(start 253.678436 -209.90179)
		(end 257.187446 -213.4108)
		(width 0.15494)
		(layer "In13.Cu")
		(net "PRSNT_SSD15_R_N")
	)
	(segment
		(start 261.638288 -213.4108)
		(end 262.832088 -214.6046)
		(width 0.15494)
		(layer "In13.Cu")
		(net "PRSNT_SSD15_R_N")
	)
	(segment
		(start 246.874538 -210.540854)
		(end 247.513602 -209.90179)
		(width 0.15494)
		(layer "In13.Cu")
		(net "PRSNT_SSD15_R_N")
	)
	(segment
		(start 262.832088 -214.6046)
		(end 265.455654 -214.6046)
		(width 0.15494)
		(layer "In13.Cu")
		(net "PRSNT_SSD15_R_N")
	)
	(segment
		(start 257.187446 -213.4108)
		(end 261.638288 -213.4108)
		(width 0.15494)
		(layer "In13.Cu")
		(net "PRSNT_SSD15_R_N")
	)
	(segment
		(start 267.533374 -212.780372)
		(end 267.693902 -212.780372)
		(width 0.15494)
		(layer "In13.Cu")
		(net "PRSNT_SSD15_R_N")
	)
	(segment
		(start 247.513602 -209.90179)
		(end 253.678436 -209.90179)
		(width 0.15494)
		(layer "In13.Cu")
		(net "PRSNT_SSD15_R_N")
	)
	(segment
		(start 245.703598 -210.540854)
		(end 246.874538 -210.540854)
		(width 0.15494)
		(layer "In13.Cu")
		(net "PRSNT_SSD15_R_N")
	)
	(segment
		(start 369.634008 -100.2792)
		(end 369.303808 -100.6094)
		(width 0.15494)
		(layer "In15.Cu")
		(net "PRSNT_SSD15_R_N")
	)
	(segment
		(start 332.72095 -207.285844)
		(end 332.688946 -207.317848)
		(width 0.15494)
		(layer "In15.Cu")
		(net "PRSNT_SSD15_R_N")
	)
	(segment
		(start 300.156372 -206.8576)
		(end 298.689014 -208.324958)
		(width 0.15494)
		(layer "In15.Cu")
		(net "PRSNT_SSD15_R_N")
	)
	(segment
		(start 332.673706 -207.324198)
		(end 331.819504 -208.1784)
		(width 0.15494)
		(layer "In15.Cu")
		(net "PRSNT_SSD15_R_N")
	)
	(segment
		(start 335.547716 -209.3976)
		(end 333.46644 -207.316324)
		(width 0.15494)
		(layer "In15.Cu")
		(net "PRSNT_SSD15_R_N")
	)
	(segment
		(start 342.893904 -210.566)
		(end 341.725504 -209.3976)
		(width 0.15494)
		(layer "In15.Cu")
		(net "PRSNT_SSD15_R_N")
	)
	(segment
		(start 407.900378 -89.714324)
		(end 407.030428 -90.584274)
		(width 0.15494)
		(layer "In15.Cu")
		(net "PRSNT_SSD15_R_N")
	)
	(segment
		(start 420.311834 -89.430352)
		(end 420.027862 -89.714324)
		(width 0.15494)
		(layer "In15.Cu")
		(net "PRSNT_SSD15_R_N")
	)
	(segment
		(start 331.819504 -208.1784)
		(end 328.650346 -208.1784)
		(width 0.15494)
		(layer "In15.Cu")
		(net "PRSNT_SSD15_R_N")
	)
	(segment
		(start 324.8406 -206.8576)
		(end 300.156372 -206.8576)
		(width 0.15494)
		(layer "In15.Cu")
		(net "PRSNT_SSD15_R_N")
	)
	(segment
		(start 332.688946 -207.317848)
		(end 332.673706 -207.324198)
		(width 0.15494)
		(layer "In15.Cu")
		(net "PRSNT_SSD15_R_N")
	)
	(segment
		(start 333.12227 -207.285844)
		(end 332.72095 -207.285844)
		(width 0.15494)
		(layer "In15.Cu")
		(net "PRSNT_SSD15_R_N")
	)
	(segment
		(start 283.078428 -212.780372)
		(end 267.693902 -212.780372)
		(width 0.15494)
		(layer "In15.Cu")
		(net "PRSNT_SSD15_R_N")
	)
	(segment
		(start 395.846046 -96.52)
		(end 394.398246 -95.0722)
		(width 0.15494)
		(layer "In15.Cu")
		(net "PRSNT_SSD15_R_N")
	)
	(segment
		(start 397.253714 -96.52)
		(end 395.846046 -96.52)
		(width 0.15494)
		(layer "In15.Cu")
		(net "PRSNT_SSD15_R_N")
	)
	(segment
		(start 341.725504 -209.3976)
		(end 335.547716 -209.3976)
		(width 0.15494)
		(layer "In15.Cu")
		(net "PRSNT_SSD15_R_N")
	)
	(segment
		(start 333.15275 -207.316324)
		(end 333.12227 -207.285844)
		(width 0.15494)
		(layer "In15.Cu")
		(net "PRSNT_SSD15_R_N")
	)
	(segment
		(start 333.46644 -207.316324)
		(end 333.15275 -207.316324)
		(width 0.15494)
		(layer "In15.Cu")
		(net "PRSNT_SSD15_R_N")
	)
	(segment
		(start 325.2724 -206.4258)
		(end 324.8406 -206.8576)
		(width 0.15494)
		(layer "In15.Cu")
		(net "PRSNT_SSD15_R_N")
	)
	(segment
		(start 369.303808 -100.6094)
		(end 357.479346 -100.6094)
		(width 0.15494)
		(layer "In15.Cu")
		(net "PRSNT_SSD15_R_N")
	)
	(segment
		(start 328.650346 -208.1784)
		(end 326.897746 -206.4258)
		(width 0.15494)
		(layer "In15.Cu")
		(net "PRSNT_SSD15_R_N")
	)
	(segment
		(start 287.533842 -208.324958)
		(end 283.078428 -212.780372)
		(width 0.15494)
		(layer "In15.Cu")
		(net "PRSNT_SSD15_R_N")
	)
	(segment
		(start 380.0348 -100.2792)
		(end 369.634008 -100.2792)
		(width 0.15494)
		(layer "In15.Cu")
		(net "PRSNT_SSD15_R_N")
	)
	(segment
		(start 385.2418 -95.0722)
		(end 380.0348 -100.2792)
		(width 0.15494)
		(layer "In15.Cu")
		(net "PRSNT_SSD15_R_N")
	)
	(segment
		(start 403.18944 -90.584274)
		(end 397.253714 -96.52)
		(width 0.15494)
		(layer "In15.Cu")
		(net "PRSNT_SSD15_R_N")
	)
	(segment
		(start 420.027862 -89.714324)
		(end 407.900378 -89.714324)
		(width 0.15494)
		(layer "In15.Cu")
		(net "PRSNT_SSD15_R_N")
	)
	(segment
		(start 357.479346 -100.6094)
		(end 356.183946 -101.9048)
		(width 0.15494)
		(layer "In15.Cu")
		(net "PRSNT_SSD15_R_N")
	)
	(segment
		(start 394.398246 -95.0722)
		(end 385.2418 -95.0722)
		(width 0.15494)
		(layer "In15.Cu")
		(net "PRSNT_SSD15_R_N")
	)
	(segment
		(start 354.95611 -101.9048)
		(end 353.96805 -100.91674)
		(width 0.15494)
		(layer "In15.Cu")
		(net "PRSNT_SSD15_R_N")
	)
	(segment
		(start 407.030428 -90.584274)
		(end 403.18944 -90.584274)
		(width 0.15494)
		(layer "In15.Cu")
		(net "PRSNT_SSD15_R_N")
	)
	(segment
		(start 298.689014 -208.324958)
		(end 287.533842 -208.324958)
		(width 0.15494)
		(layer "In15.Cu")
		(net "PRSNT_SSD15_R_N")
	)
	(segment
		(start 356.183946 -101.9048)
		(end 354.95611 -101.9048)
		(width 0.15494)
		(layer "In15.Cu")
		(net "PRSNT_SSD15_R_N")
	)
	(segment
		(start 326.897746 -206.4258)
		(end 325.2724 -206.4258)
		(width 0.15494)
		(layer "In15.Cu")
		(net "PRSNT_SSD15_R_N")
	)
	(segment
		(start 146.538442 -251.158502)
		(end 146.538442 -250.470924)
		(width 0.13208)
		(layer "F.Cu")
		(net "PEX1_MODE_SEL0")
	)
	(segment
		(start 146.538442 -251.956824)
		(end 146.538442 -251.158502)
		(width 0.13208)
		(layer "F.Cu")
		(net "PEX1_MODE_SEL0")
	)
	(segment
		(start 177.649886 -282.599892)
		(end 178.124866 -283.074872)
		(width 0.1651)
		(layer "F.Cu")
		(net "PEX1_MODE_SEL0")
	)
	(via
		(at 178.124866 -283.074872)
		(size 0.4064)
		(drill 0.2032)
		(layers "F.Cu" "B.Cu")
		(net "PEX1_MODE_SEL0")
	)
	(via
		(at 146.538442 -251.158502)
		(size 0.508)
		(drill 0.254)
		(layers "F.Cu" "B.Cu")
		(net "PEX1_MODE_SEL0")
	)
	(segment
		(start 165.3032 -258.2926)
		(end 150.642066 -258.2926)
		(width 0.13208)
		(layer "B.Cu")
		(net "PEX1_MODE_SEL0")
	)
	(segment
		(start 179.070508 -282.12923)
		(end 179.070508 -271.947386)
		(width 0.13208)
		(layer "B.Cu")
		(net "PEX1_MODE_SEL0")
	)
	(segment
		(start 176.014888 -268.725142)
		(end 175.279812 -267.990066)
		(width 0.13208)
		(layer "B.Cu")
		(net "PEX1_MODE_SEL0")
	)
	(segment
		(start 176.014888 -268.891766)
		(end 176.014888 -268.725142)
		(width 0.13208)
		(layer "B.Cu")
		(net "PEX1_MODE_SEL0")
	)
	(segment
		(start 179.070508 -271.947386)
		(end 176.014888 -268.891766)
		(width 0.13208)
		(layer "B.Cu")
		(net "PEX1_MODE_SEL0")
	)
	(segment
		(start 145.998692 -251.698252)
		(end 146.538442 -251.158502)
		(width 0.13208)
		(layer "B.Cu")
		(net "PEX1_MODE_SEL0")
	)
	(segment
		(start 175.279812 -267.990066)
		(end 175.000666 -267.990066)
		(width 0.13208)
		(layer "B.Cu")
		(net "PEX1_MODE_SEL0")
	)
	(segment
		(start 150.642066 -258.2926)
		(end 145.998692 -253.649226)
		(width 0.13208)
		(layer "B.Cu")
		(net "PEX1_MODE_SEL0")
	)
	(segment
		(start 178.124866 -283.074872)
		(end 179.070508 -282.12923)
		(width 0.13208)
		(layer "B.Cu")
		(net "PEX1_MODE_SEL0")
	)
	(segment
		(start 145.998692 -253.649226)
		(end 145.998692 -251.698252)
		(width 0.13208)
		(layer "B.Cu")
		(net "PEX1_MODE_SEL0")
	)
	(segment
		(start 175.000666 -267.990066)
		(end 165.3032 -258.2926)
		(width 0.13208)
		(layer "B.Cu")
		(net "PEX1_MODE_SEL0")
	)
	(segment
		(start 385.850384 -251.158502)
		(end 385.850384 -250.470924)
		(width 0.13208)
		(layer "F.Cu")
		(net "PEX3_MODE_SEL10")
	)
	(segment
		(start 414.599882 -283.549852)
		(end 415.074862 -284.024832)
		(width 0.13208)
		(layer "F.Cu")
		(net "PEX3_MODE_SEL10")
	)
	(segment
		(start 385.850384 -251.956824)
		(end 385.850384 -251.158502)
		(width 0.13208)
		(layer "F.Cu")
		(net "PEX3_MODE_SEL10")
	)
	(via
		(at 415.074862 -284.024832)
		(size 0.4064)
		(drill 0.2032)
		(layers "F.Cu" "B.Cu")
		(net "PEX3_MODE_SEL10")
	)
	(via
		(at 385.850384 -251.158502)
		(size 0.508)
		(drill 0.254)
		(layers "F.Cu" "B.Cu")
		(net "PEX3_MODE_SEL10")
	)
	(via
		(at 415.796222 -270.410432)
		(size 0.6604)
		(drill 0.3302)
		(layers "F.Cu" "B.Cu")
		(net "PEX3_MODE_SEL10")
	)
	(segment
		(start 416.504628 -283.407104)
		(end 416.358324 -283.553408)
		(width 0.13208)
		(layer "B.Cu")
		(net "PEX3_MODE_SEL10")
	)
	(segment
		(start 415.849054 -283.553408)
		(end 415.37763 -284.024832)
		(width 0.13208)
		(layer "B.Cu")
		(net "PEX3_MODE_SEL10")
	)
	(segment
		(start 385.333748 -253.981458)
		(end 385.652518 -254.300228)
		(width 0.13208)
		(layer "B.Cu")
		(net "PEX3_MODE_SEL10")
	)
	(segment
		(start 415.37763 -284.024832)
		(end 415.074862 -284.024832)
		(width 0.13208)
		(layer "B.Cu")
		(net "PEX3_MODE_SEL10")
	)
	(segment
		(start 417.092384 -282.601416)
		(end 416.73145 -282.601416)
		(width 0.13208)
		(layer "B.Cu")
		(net "PEX3_MODE_SEL10")
	)
	(segment
		(start 385.850384 -251.158502)
		(end 385.333748 -251.675138)
		(width 0.13208)
		(layer "B.Cu")
		(net "PEX3_MODE_SEL10")
	)
	(segment
		(start 415.796222 -270.410432)
		(end 416.308286 -270.410432)
		(width 0.13208)
		(layer "B.Cu")
		(net "PEX3_MODE_SEL10")
	)
	(segment
		(start 416.73145 -282.601416)
		(end 416.504628 -282.828238)
		(width 0.13208)
		(layer "B.Cu")
		(net "PEX3_MODE_SEL10")
	)
	(segment
		(start 416.358324 -283.553408)
		(end 415.849054 -283.553408)
		(width 0.13208)
		(layer "B.Cu")
		(net "PEX3_MODE_SEL10")
	)
	(segment
		(start 385.652518 -254.300228)
		(end 399.686018 -254.300228)
		(width 0.13208)
		(layer "B.Cu")
		(net "PEX3_MODE_SEL10")
	)
	(segment
		(start 399.686018 -254.300228)
		(end 415.796222 -270.410432)
		(width 0.13208)
		(layer "B.Cu")
		(net "PEX3_MODE_SEL10")
	)
	(segment
		(start 416.308286 -270.410432)
		(end 417.942776 -272.044922)
		(width 0.13208)
		(layer "B.Cu")
		(net "PEX3_MODE_SEL10")
	)
	(segment
		(start 417.942776 -272.044922)
		(end 417.942776 -281.751024)
		(width 0.13208)
		(layer "B.Cu")
		(net "PEX3_MODE_SEL10")
	)
	(segment
		(start 416.504628 -282.828238)
		(end 416.504628 -283.407104)
		(width 0.13208)
		(layer "B.Cu")
		(net "PEX3_MODE_SEL10")
	)
	(segment
		(start 417.942776 -281.751024)
		(end 417.092384 -282.601416)
		(width 0.13208)
		(layer "B.Cu")
		(net "PEX3_MODE_SEL10")
	)
	(segment
		(start 385.333748 -251.675138)
		(end 385.333748 -253.981458)
		(width 0.13208)
		(layer "B.Cu")
		(net "PEX3_MODE_SEL10")
	)
	(segment
		(start 34.025078 -57.867296)
		(end 34.025078 -57.841896)
		(width 0.13208)
		(layer "F.Cu")
		(net "PWRGD_P3V3_SSD1")
	)
	(segment
		(start 34.179002 -59.177936)
		(end 34.179002 -58.71972)
		(width 0.13208)
		(layer "F.Cu")
		(net "PWRGD_P3V3_SSD1")
	)
	(segment
		(start 34.179002 -58.71972)
		(end 34.025078 -58.565796)
		(width 0.13208)
		(layer "F.Cu")
		(net "PWRGD_P3V3_SSD1")
	)
	(segment
		(start 33.64103 -57.457848)
		(end 33.64103 -57.16397)
		(width 0.13208)
		(layer "F.Cu")
		(net "PWRGD_P3V3_SSD1")
	)
	(segment
		(start 34.025078 -57.841896)
		(end 33.64103 -57.457848)
		(width 0.13208)
		(layer "F.Cu")
		(net "PWRGD_P3V3_SSD1")
	)
	(segment
		(start 33.81375 -59.177936)
		(end 34.179002 -59.177936)
		(width 0.13208)
		(layer "F.Cu")
		(net "PWRGD_P3V3_SSD1")
	)
	(segment
		(start 33.648142 -61.22416)
		(end 33.648142 -59.343544)
		(width 0.13208)
		(layer "F.Cu")
		(net "PWRGD_P3V3_SSD1")
	)
	(segment
		(start 33.648142 -59.343544)
		(end 33.81375 -59.177936)
		(width 0.13208)
		(layer "F.Cu")
		(net "PWRGD_P3V3_SSD1")
	)
	(segment
		(start 33.810956 -61.386974)
		(end 33.648142 -61.22416)
		(width 0.13208)
		(layer "F.Cu")
		(net "PWRGD_P3V3_SSD1")
	)
	(segment
		(start 34.025078 -58.565796)
		(end 34.025078 -57.867296)
		(width 0.13208)
		(layer "F.Cu")
		(net "PWRGD_P3V3_SSD1")
	)
	(via
		(at 34.025078 -57.867296)
		(size 0.508)
		(drill 0.254)
		(layers "F.Cu" "B.Cu")
		(net "PWRGD_P3V3_SSD1")
	)
	(segment
		(start 343.69375 -215.187022)
		(end 344.093546 -214.787226)
		(width 0.13208)
		(layer "F.Cu")
		(net "SSD15_PWR_EN")
	)
	(segment
		(start 341.63 -201.56805)
		(end 341.63 -202.184)
		(width 0.13208)
		(layer "F.Cu")
		(net "SSD15_PWR_EN")
	)
	(via
		(at 344.093546 -214.787226)
		(size 0.4572)
		(drill 0.254)
		(layers "F.Cu" "B.Cu")
		(net "SSD15_PWR_EN")
	)
	(via
		(at 341.63 -202.184)
		(size 0.508)
		(drill 0.254)
		(layers "F.Cu" "B.Cu")
		(net "SSD15_PWR_EN")
	)
	(segment
		(start 342.649302 -205.844902)
		(end 342.649302 -206.454502)
		(width 0.15494)
		(layer "In5.Cu")
		(net "SSD15_PWR_EN")
	)
	(segment
		(start 342.8492 -214.96782)
		(end 343.06764 -215.18626)
		(width 0.15494)
		(layer "In5.Cu")
		(net "SSD15_PWR_EN")
	)
	(segment
		(start 343.17178 -215.18626)
		(end 343.694512 -215.18626)
		(width 0.0889)
		(layer "In5.Cu")
		(net "SSD15_PWR_EN")
	)
	(segment
		(start 343.694512 -215.18626)
		(end 344.093546 -214.787226)
		(width 0.0889)
		(layer "In5.Cu")
		(net "SSD15_PWR_EN")
	)
	(segment
		(start 341.63 -203.01712)
		(end 342.116918 -203.504038)
		(width 0.15494)
		(layer "In5.Cu")
		(net "SSD15_PWR_EN")
	)
	(segment
		(start 342.116918 -205.312518)
		(end 342.649302 -205.844902)
		(width 0.15494)
		(layer "In5.Cu")
		(net "SSD15_PWR_EN")
	)
	(segment
		(start 342.8492 -211.5312)
		(end 342.8492 -214.96782)
		(width 0.15494)
		(layer "In5.Cu")
		(net "SSD15_PWR_EN")
	)
	(segment
		(start 343.696036 -210.684364)
		(end 342.8492 -211.5312)
		(width 0.15494)
		(layer "In5.Cu")
		(net "SSD15_PWR_EN")
	)
	(segment
		(start 343.696036 -209.0928)
		(end 343.696036 -210.684364)
		(width 0.15494)
		(layer "In5.Cu")
		(net "SSD15_PWR_EN")
	)
	(segment
		(start 342.116918 -203.504038)
		(end 342.116918 -205.312518)
		(width 0.15494)
		(layer "In5.Cu")
		(net "SSD15_PWR_EN")
	)
	(segment
		(start 343.2302 -207.0354)
		(end 343.2302 -208.626964)
		(width 0.15494)
		(layer "In5.Cu")
		(net "SSD15_PWR_EN")
	)
	(segment
		(start 343.2302 -208.626964)
		(end 343.696036 -209.0928)
		(width 0.15494)
		(layer "In5.Cu")
		(net "SSD15_PWR_EN")
	)
	(segment
		(start 341.63 -202.184)
		(end 341.63 -203.01712)
		(width 0.15494)
		(layer "In5.Cu")
		(net "SSD15_PWR_EN")
	)
	(segment
		(start 343.06764 -215.18626)
		(end 343.17178 -215.18626)
		(width 0.15494)
		(layer "In5.Cu")
		(net "SSD15_PWR_EN")
	)
	(segment
		(start 342.649302 -206.454502)
		(end 343.2302 -207.0354)
		(width 0.15494)
		(layer "In5.Cu")
		(net "SSD15_PWR_EN")
	)
	(segment
		(start 111.788956 -87.379048)
		(end 112.643412 -87.379048)
		(width 0.2032)
		(layer "F.Cu")
		(net "P3V3_VDD_9ZXL0851_0_7")
	)
	(segment
		(start 101.784912 -88.884506)
		(end 101.784912 -89.700608)
		(width 0.381)
		(layer "F.Cu")
		(net "P3V3_VDD_9ZXL0851_0_7")
	)
	(segment
		(start 105.150666 -84.688172)
		(end 104.818434 -84.688172)
		(width 0.1778)
		(layer "F.Cu")
		(net "P3V3_VDD_9ZXL0851_0_7")
	)
	(segment
		(start 109.038898 -82.42935)
		(end 109.038898 -83.029044)
		(width 0.1778)
		(layer "F.Cu")
		(net "P3V3_VDD_9ZXL0851_0_7")
	)
	(segment
		(start 105.889044 -84.578952)
		(end 105.259886 -84.578952)
		(width 0.1778)
		(layer "F.Cu")
		(net "P3V3_VDD_9ZXL0851_0_7")
	)
	(segment
		(start 109.311694 -82.089498)
		(end 109.311694 -82.156554)
		(width 0.1778)
		(layer "F.Cu")
		(net "P3V3_VDD_9ZXL0851_0_7")
	)
	(segment
		(start 112.643412 -87.379048)
		(end 112.64392 -87.379556)
		(width 0.2032)
		(layer "F.Cu")
		(net "P3V3_VDD_9ZXL0851_0_7")
	)
	(segment
		(start 110.639098 -89.806272)
		(end 110.715044 -89.882218)
		(width 0.1778)
		(layer "F.Cu")
		(net "P3V3_VDD_9ZXL0851_0_7")
	)
	(segment
		(start 105.259886 -84.578952)
		(end 105.150666 -84.688172)
		(width 0.1778)
		(layer "F.Cu")
		(net "P3V3_VDD_9ZXL0851_0_7")
	)
	(segment
		(start 109.038898 -88.928956)
		(end 109.038898 -89.588594)
		(width 0.1778)
		(layer "F.Cu")
		(net "P3V3_VDD_9ZXL0851_0_7")
	)
	(segment
		(start 107.438952 -83.029044)
		(end 107.438952 -82.201258)
		(width 0.1778)
		(layer "F.Cu")
		(net "P3V3_VDD_9ZXL0851_0_7")
	)
	(segment
		(start 111.788956 -84.578952)
		(end 112.629696 -84.578952)
		(width 0.1778)
		(layer "F.Cu")
		(net "P3V3_VDD_9ZXL0851_0_7")
	)
	(segment
		(start 109.311694 -82.156554)
		(end 109.038898 -82.42935)
		(width 0.1778)
		(layer "F.Cu")
		(net "P3V3_VDD_9ZXL0851_0_7")
	)
	(segment
		(start 109.038898 -89.588594)
		(end 108.81868 -89.808812)
		(width 0.1778)
		(layer "F.Cu")
		(net "P3V3_VDD_9ZXL0851_0_7")
	)
	(segment
		(start 110.639098 -88.928956)
		(end 110.639098 -89.806272)
		(width 0.1778)
		(layer "F.Cu")
		(net "P3V3_VDD_9ZXL0851_0_7")
	)
	(via
		(at 104.818434 -84.688172)
		(size 0.508)
		(drill 0.254)
		(layers "F.Cu" "B.Cu")
		(net "P3V3_VDD_9ZXL0851_0_7")
	)
	(via
		(at 105.442766 -82.595974)
		(size 0.508)
		(drill 0.254)
		(layers "F.Cu" "B.Cu")
		(net "P3V3_VDD_9ZXL0851_0_7")
	)
	(via
		(at 107.438952 -82.201258)
		(size 0.508)
		(drill 0.254)
		(layers "F.Cu" "B.Cu")
		(net "P3V3_VDD_9ZXL0851_0_7")
	)
	(via
		(at 112.64392 -87.379556)
		(size 0.508)
		(drill 0.254)
		(layers "F.Cu" "B.Cu")
		(net "P3V3_VDD_9ZXL0851_0_7")
	)
	(via
		(at 101.784912 -89.700608)
		(size 0.508)
		(drill 0.254)
		(layers "F.Cu" "B.Cu")
		(net "P3V3_VDD_9ZXL0851_0_7")
	)
	(via
		(at 112.629696 -84.578952)
		(size 0.508)
		(drill 0.254)
		(layers "F.Cu" "B.Cu")
		(net "P3V3_VDD_9ZXL0851_0_7")
	)
	(via
		(at 108.81868 -89.808812)
		(size 0.508)
		(drill 0.254)
		(layers "F.Cu" "B.Cu")
		(net "P3V3_VDD_9ZXL0851_0_7")
	)
	(via
		(at 108.320078 -80.54721)
		(size 0.6604)
		(drill 0.3302)
		(layers "F.Cu" "B.Cu")
		(net "P3V3_VDD_9ZXL0851_0_7")
	)
	(via
		(at 109.311694 -82.089498)
		(size 0.508)
		(drill 0.254)
		(layers "F.Cu" "B.Cu")
		(net "P3V3_VDD_9ZXL0851_0_7")
	)
	(via
		(at 110.715044 -89.882218)
		(size 0.508)
		(drill 0.254)
		(layers "F.Cu" "B.Cu")
		(net "P3V3_VDD_9ZXL0851_0_7")
	)
	(via
		(at 110.471458 -80.575912)
		(size 0.6604)
		(drill 0.3302)
		(layers "F.Cu" "B.Cu")
		(net "P3V3_VDD_9ZXL0851_0_7")
	)
	(segment
		(start 112.35436 -87.089996)
		(end 112.64392 -87.379556)
		(width 0.254)
		(layer "B.Cu")
		(net "P3V3_VDD_9ZXL0851_0_7")
	)
	(segment
		(start 110.715044 -89.844372)
		(end 110.715044 -89.882218)
		(width 0.254)
		(layer "B.Cu")
		(net "P3V3_VDD_9ZXL0851_0_7")
	)
	(segment
		(start 111.284258 -88.81745)
		(end 111.289084 -88.822276)
		(width 0.254)
		(layer "B.Cu")
		(net "P3V3_VDD_9ZXL0851_0_7")
	)
	(segment
		(start 108.741972 -89.732104)
		(end 108.81868 -89.808812)
		(width 0.254)
		(layer "B.Cu")
		(net "P3V3_VDD_9ZXL0851_0_7")
	)
	(segment
		(start 108.741972 -88.822784)
		(end 108.741972 -89.732104)
		(width 0.254)
		(layer "B.Cu")
		(net "P3V3_VDD_9ZXL0851_0_7")
	)
	(segment
		(start 111.289084 -89.270332)
		(end 110.715044 -89.844372)
		(width 0.254)
		(layer "B.Cu")
		(net "P3V3_VDD_9ZXL0851_0_7")
	)
	(segment
		(start 111.566706 -87.089996)
		(end 112.35436 -87.089996)
		(width 0.254)
		(layer "B.Cu")
		(net "P3V3_VDD_9ZXL0851_0_7")
	)
	(segment
		(start 111.289084 -88.822276)
		(end 111.289084 -89.270332)
		(width 0.254)
		(layer "B.Cu")
		(net "P3V3_VDD_9ZXL0851_0_7")
	)
	(segment
		(start 247.48363 -186.770518)
		(end 281.478482 -186.770518)
		(width 0.13208)
		(layer "F.Cu")
		(net "PEX1_MODE_SEL2")
	)
	(segment
		(start 242.414806 -190.979806)
		(end 243.274342 -190.979806)
		(width 0.13208)
		(layer "F.Cu")
		(net "PEX1_MODE_SEL2")
	)
	(segment
		(start 281.478482 -186.770518)
		(end 288.925 -179.324)
		(width 0.13208)
		(layer "F.Cu")
		(net "PEX1_MODE_SEL2")
	)
	(segment
		(start 142.474442 -251.158502)
		(end 142.474442 -251.956824)
		(width 0.13208)
		(layer "F.Cu")
		(net "PEX1_MODE_SEL2")
	)
	(segment
		(start 142.474442 -250.470924)
		(end 142.474442 -251.158502)
		(width 0.13208)
		(layer "F.Cu")
		(net "PEX1_MODE_SEL2")
	)
	(segment
		(start 239.28705 -186.473338)
		(end 242.023138 -189.209426)
		(width 0.13208)
		(layer "F.Cu")
		(net "PEX1_MODE_SEL2")
	)
	(segment
		(start 243.274342 -190.979806)
		(end 247.48363 -186.770518)
		(width 0.13208)
		(layer "F.Cu")
		(net "PEX1_MODE_SEL2")
	)
	(segment
		(start 225.39579 -188.186314)
		(end 228.329744 -185.25236)
		(width 0.13208)
		(layer "F.Cu")
		(net "PEX1_MODE_SEL2")
	)
	(segment
		(start 288.925 -179.324)
		(end 293.127176 -179.324)
		(width 0.13208)
		(layer "F.Cu")
		(net "PEX1_MODE_SEL2")
	)
	(segment
		(start 228.329744 -185.25236)
		(end 236.001814 -185.25236)
		(width 0.13208)
		(layer "F.Cu")
		(net "PEX1_MODE_SEL2")
	)
	(segment
		(start 294.042084 -178.409092)
		(end 294.042084 -177.670714)
		(width 0.13208)
		(layer "F.Cu")
		(net "PEX1_MODE_SEL2")
	)
	(segment
		(start 224.783904 -188.186314)
		(end 225.39579 -188.186314)
		(width 0.13208)
		(layer "F.Cu")
		(net "PEX1_MODE_SEL2")
	)
	(segment
		(start 236.001814 -185.25236)
		(end 237.222792 -186.473338)
		(width 0.13208)
		(layer "F.Cu")
		(net "PEX1_MODE_SEL2")
	)
	(segment
		(start 293.127176 -179.324)
		(end 294.042084 -178.409092)
		(width 0.13208)
		(layer "F.Cu")
		(net "PEX1_MODE_SEL2")
	)
	(segment
		(start 237.222792 -186.473338)
		(end 239.28705 -186.473338)
		(width 0.13208)
		(layer "F.Cu")
		(net "PEX1_MODE_SEL2")
	)
	(segment
		(start 175.749966 -283.549852)
		(end 176.224946 -284.024832)
		(width 0.1651)
		(layer "F.Cu")
		(net "PEX1_MODE_SEL2")
	)
	(segment
		(start 242.023138 -189.209426)
		(end 242.023138 -190.588138)
		(width 0.13208)
		(layer "F.Cu")
		(net "PEX1_MODE_SEL2")
	)
	(segment
		(start 242.023138 -190.588138)
		(end 242.414806 -190.979806)
		(width 0.13208)
		(layer "F.Cu")
		(net "PEX1_MODE_SEL2")
	)
	(segment
		(start 408.554682 -198.203058)
		(end 409.353258 -198.203058)
		(width 0.13208)
		(layer "F.Cu")
		(net "PEX1_MODE_SEL2")
	)
	(via
		(at 142.474442 -251.158502)
		(size 0.508)
		(drill 0.254)
		(layers "F.Cu" "B.Cu")
		(net "PEX1_MODE_SEL2")
	)
	(via
		(at 176.224946 -284.024832)
		(size 0.4064)
		(drill 0.2032)
		(layers "F.Cu" "B.Cu")
		(net "PEX1_MODE_SEL2")
	)
	(via
		(at 409.353258 -198.203058)
		(size 0.508)
		(drill 0.254)
		(layers "F.Cu" "B.Cu")
		(net "PEX1_MODE_SEL2")
	)
	(via
		(at 224.783904 -188.186314)
		(size 0.508)
		(drill 0.254)
		(layers "F.Cu" "B.Cu")
		(net "PEX1_MODE_SEL2")
	)
	(via
		(at 186.35472 -210.560158)
		(size 0.508)
		(drill 0.254)
		(layers "F.Cu" "B.Cu")
		(net "PEX1_MODE_SEL2")
	)
	(via
		(at 154.67711 -245.469156)
		(size 0.508)
		(drill 0.254)
		(layers "F.Cu" "B.Cu")
		(net "PEX1_MODE_SEL2")
	)
	(via
		(at 294.042084 -177.670714)
		(size 0.508)
		(drill 0.254)
		(layers "F.Cu" "B.Cu")
		(net "PEX1_MODE_SEL2")
	)
	(segment
		(start 164.287454 -260.5786)
		(end 156.057346 -260.5786)
		(width 0.13208)
		(layer "B.Cu")
		(net "PEX1_MODE_SEL2")
	)
	(segment
		(start 155.066746 -261.5692)
		(end 149.072346 -261.5692)
		(width 0.13208)
		(layer "B.Cu")
		(net "PEX1_MODE_SEL2")
	)
	(segment
		(start 173.37278 -269.232126)
		(end 172.94098 -269.232126)
		(width 0.13208)
		(layer "B.Cu")
		(net "PEX1_MODE_SEL2")
	)
	(segment
		(start 154.67711 -245.469156)
		(end 154.67711 -244.691408)
		(width 0.13208)
		(layer "B.Cu")
		(net "PEX1_MODE_SEL2")
	)
	(segment
		(start 176.224946 -284.024832)
		(end 175.28032 -283.080206)
		(width 0.13208)
		(layer "B.Cu")
		(net "PEX1_MODE_SEL2")
	)
	(segment
		(start 154.67711 -244.691408)
		(end 186.20867 -213.159848)
		(width 0.13208)
		(layer "B.Cu")
		(net "PEX1_MODE_SEL2")
	)
	(segment
		(start 141.958822 -254.83185)
		(end 141.958822 -252.58903)
		(width 0.13208)
		(layer "B.Cu")
		(net "PEX1_MODE_SEL2")
	)
	(segment
		(start 149.072346 -261.5692)
		(end 147.675346 -260.1722)
		(width 0.13208)
		(layer "B.Cu")
		(net "PEX1_MODE_SEL2")
	)
	(segment
		(start 143.079216 -255.952244)
		(end 141.958822 -254.83185)
		(width 0.13208)
		(layer "B.Cu")
		(net "PEX1_MODE_SEL2")
	)
	(segment
		(start 156.057346 -260.5786)
		(end 155.066746 -261.5692)
		(width 0.13208)
		(layer "B.Cu")
		(net "PEX1_MODE_SEL2")
	)
	(segment
		(start 141.958822 -252.58903)
		(end 142.474442 -252.07341)
		(width 0.13208)
		(layer "B.Cu")
		(net "PEX1_MODE_SEL2")
	)
	(segment
		(start 175.28032 -283.080206)
		(end 175.28032 -271.226026)
		(width 0.13208)
		(layer "B.Cu")
		(net "PEX1_MODE_SEL2")
	)
	(segment
		(start 175.28032 -271.226026)
		(end 174.23892 -270.184626)
		(width 0.13208)
		(layer "B.Cu")
		(net "PEX1_MODE_SEL2")
	)
	(segment
		(start 142.474442 -252.07341)
		(end 142.474442 -251.158502)
		(width 0.13208)
		(layer "B.Cu")
		(net "PEX1_MODE_SEL2")
	)
	(segment
		(start 172.94098 -269.232126)
		(end 164.287454 -260.5786)
		(width 0.13208)
		(layer "B.Cu")
		(net "PEX1_MODE_SEL2")
	)
	(segment
		(start 145.9738 -260.1722)
		(end 143.079216 -257.277616)
		(width 0.13208)
		(layer "B.Cu")
		(net "PEX1_MODE_SEL2")
	)
	(segment
		(start 143.079216 -257.277616)
		(end 143.079216 -255.952244)
		(width 0.13208)
		(layer "B.Cu")
		(net "PEX1_MODE_SEL2")
	)
	(segment
		(start 186.20867 -213.159848)
		(end 186.20867 -211.324698)
		(width 0.13208)
		(layer "B.Cu")
		(net "PEX1_MODE_SEL2")
	)
	(segment
		(start 174.23892 -270.184626)
		(end 174.23892 -270.098266)
		(width 0.13208)
		(layer "B.Cu")
		(net "PEX1_MODE_SEL2")
	)
	(segment
		(start 147.675346 -260.1722)
		(end 145.9738 -260.1722)
		(width 0.13208)
		(layer "B.Cu")
		(net "PEX1_MODE_SEL2")
	)
	(segment
		(start 186.35472 -211.178648)
		(end 186.35472 -210.560158)
		(width 0.13208)
		(layer "B.Cu")
		(net "PEX1_MODE_SEL2")
	)
	(segment
		(start 174.23892 -270.098266)
		(end 173.37278 -269.232126)
		(width 0.13208)
		(layer "B.Cu")
		(net "PEX1_MODE_SEL2")
	)
	(segment
		(start 186.20867 -211.324698)
		(end 186.35472 -211.178648)
		(width 0.13208)
		(layer "B.Cu")
		(net "PEX1_MODE_SEL2")
	)
	(segment
		(start 143.508984 -248.128282)
		(end 143.508984 -248.845578)
		(width 0.15494)
		(layer "In5.Cu")
		(net "PEX1_MODE_SEL2")
	)
	(segment
		(start 143.508984 -248.845578)
		(end 142.474442 -249.88012)
		(width 0.15494)
		(layer "In5.Cu")
		(net "PEX1_MODE_SEL2")
	)
	(segment
		(start 154.67711 -245.469156)
		(end 152.735534 -247.410732)
		(width 0.15494)
		(layer "In5.Cu")
		(net "PEX1_MODE_SEL2")
	)
	(segment
		(start 144.226534 -247.410732)
		(end 143.508984 -248.128282)
		(width 0.15494)
		(layer "In5.Cu")
		(net "PEX1_MODE_SEL2")
	)
	(segment
		(start 142.474442 -249.88012)
		(end 142.474442 -251.158502)
		(width 0.15494)
		(layer "In5.Cu")
		(net "PEX1_MODE_SEL2")
	)
	(segment
		(start 152.735534 -247.410732)
		(end 144.226534 -247.410732)
		(width 0.15494)
		(layer "In5.Cu")
		(net "PEX1_MODE_SEL2")
	)
	(segment
		(start 336.438748 -180.359812)
		(end 336.584798 -180.213762)
		(width 0.15494)
		(layer "In13.Cu")
		(net "PEX1_MODE_SEL2")
	)
	(segment
		(start 345.483942 -180.276754)
		(end 348.172278 -177.588418)
		(width 0.15494)
		(layer "In13.Cu")
		(net "PEX1_MODE_SEL2")
	)
	(segment
		(start 375.106692 -182.776876)
		(end 375.50852 -182.375048)
		(width 0.15494)
		(layer "In13.Cu")
		(net "PEX1_MODE_SEL2")
	)
	(segment
		(start 367.634774 -178.684682)
		(end 370.368322 -178.684682)
		(width 0.15494)
		(layer "In13.Cu")
		(net "PEX1_MODE_SEL2")
	)
	(segment
		(start 328.312526 -185.40222)
		(end 333.354934 -180.359812)
		(width 0.15494)
		(layer "In13.Cu")
		(net "PEX1_MODE_SEL2")
	)
	(segment
		(start 402.2725 -184.274968)
		(end 408.866594 -190.869062)
		(width 0.15494)
		(layer "In13.Cu")
		(net "PEX1_MODE_SEL2")
	)
	(segment
		(start 364.848902 -178.282854)
		(end 367.232946 -178.282854)
		(width 0.15494)
		(layer "In13.Cu")
		(net "PEX1_MODE_SEL2")
	)
	(segment
		(start 333.354934 -180.359812)
		(end 336.438748 -180.359812)
		(width 0.15494)
		(layer "In13.Cu")
		(net "PEX1_MODE_SEL2")
	)
	(segment
		(start 370.502942 -178.922172)
		(end 374.357646 -182.776876)
		(width 0.15494)
		(layer "In13.Cu")
		(net "PEX1_MODE_SEL2")
	)
	(segment
		(start 409.353258 -194.261232)
		(end 409.353258 -198.203058)
		(width 0.15494)
		(layer "In13.Cu")
		(net "PEX1_MODE_SEL2")
	)
	(segment
		(start 342.065102 -180.276754)
		(end 345.483942 -180.276754)
		(width 0.15494)
		(layer "In13.Cu")
		(net "PEX1_MODE_SEL2")
	)
	(segment
		(start 352.636582 -176.714404)
		(end 356.98684 -176.714404)
		(width 0.15494)
		(layer "In13.Cu")
		(net "PEX1_MODE_SEL2")
	)
	(segment
		(start 294.042084 -177.670714)
		(end 294.042084 -178.677062)
		(width 0.15494)
		(layer "In13.Cu")
		(net "PEX1_MODE_SEL2")
	)
	(segment
		(start 341.444326 -180.89753)
		(end 342.065102 -180.276754)
		(width 0.15494)
		(layer "In13.Cu")
		(net "PEX1_MODE_SEL2")
	)
	(segment
		(start 336.584798 -180.213762)
		(end 337.751674 -180.213762)
		(width 0.15494)
		(layer "In13.Cu")
		(net "PEX1_MODE_SEL2")
	)
	(segment
		(start 295.107614 -179.742592)
		(end 316.67831 -179.742592)
		(width 0.15494)
		(layer "In13.Cu")
		(net "PEX1_MODE_SEL2")
	)
	(segment
		(start 337.751674 -180.213762)
		(end 338.435442 -180.89753)
		(width 0.15494)
		(layer "In13.Cu")
		(net "PEX1_MODE_SEL2")
	)
	(segment
		(start 364.337346 -177.771298)
		(end 364.848902 -178.282854)
		(width 0.15494)
		(layer "In13.Cu")
		(net "PEX1_MODE_SEL2")
	)
	(segment
		(start 322.337938 -185.40222)
		(end 328.312526 -185.40222)
		(width 0.15494)
		(layer "In13.Cu")
		(net "PEX1_MODE_SEL2")
	)
	(segment
		(start 379.63729 -184.274968)
		(end 402.2725 -184.274968)
		(width 0.15494)
		(layer "In13.Cu")
		(net "PEX1_MODE_SEL2")
	)
	(segment
		(start 370.368322 -178.684682)
		(end 370.502942 -178.819302)
		(width 0.15494)
		(layer "In13.Cu")
		(net "PEX1_MODE_SEL2")
	)
	(segment
		(start 351.762568 -177.588418)
		(end 352.636582 -176.714404)
		(width 0.15494)
		(layer "In13.Cu")
		(net "PEX1_MODE_SEL2")
	)
	(segment
		(start 370.502942 -178.819302)
		(end 370.502942 -178.922172)
		(width 0.15494)
		(layer "In13.Cu")
		(net "PEX1_MODE_SEL2")
	)
	(segment
		(start 408.866594 -193.774568)
		(end 409.353258 -194.261232)
		(width 0.15494)
		(layer "In13.Cu")
		(net "PEX1_MODE_SEL2")
	)
	(segment
		(start 316.67831 -179.742592)
		(end 322.337938 -185.40222)
		(width 0.15494)
		(layer "In13.Cu")
		(net "PEX1_MODE_SEL2")
	)
	(segment
		(start 294.042084 -178.677062)
		(end 295.107614 -179.742592)
		(width 0.15494)
		(layer "In13.Cu")
		(net "PEX1_MODE_SEL2")
	)
	(segment
		(start 375.50852 -182.375048)
		(end 377.73737 -182.375048)
		(width 0.15494)
		(layer "In13.Cu")
		(net "PEX1_MODE_SEL2")
	)
	(segment
		(start 360.820462 -177.771298)
		(end 364.337346 -177.771298)
		(width 0.15494)
		(layer "In13.Cu")
		(net "PEX1_MODE_SEL2")
	)
	(segment
		(start 356.98684 -176.714404)
		(end 357.806244 -177.533808)
		(width 0.15494)
		(layer "In13.Cu")
		(net "PEX1_MODE_SEL2")
	)
	(segment
		(start 377.73737 -182.375048)
		(end 379.63729 -184.274968)
		(width 0.15494)
		(layer "In13.Cu")
		(net "PEX1_MODE_SEL2")
	)
	(segment
		(start 408.866594 -190.869062)
		(end 408.866594 -193.774568)
		(width 0.15494)
		(layer "In13.Cu")
		(net "PEX1_MODE_SEL2")
	)
	(segment
		(start 338.435442 -180.89753)
		(end 341.444326 -180.89753)
		(width 0.15494)
		(layer "In13.Cu")
		(net "PEX1_MODE_SEL2")
	)
	(segment
		(start 348.172278 -177.588418)
		(end 351.762568 -177.588418)
		(width 0.15494)
		(layer "In13.Cu")
		(net "PEX1_MODE_SEL2")
	)
	(segment
		(start 367.232946 -178.282854)
		(end 367.634774 -178.684682)
		(width 0.15494)
		(layer "In13.Cu")
		(net "PEX1_MODE_SEL2")
	)
	(segment
		(start 357.806244 -177.533808)
		(end 360.582972 -177.533808)
		(width 0.15494)
		(layer "In13.Cu")
		(net "PEX1_MODE_SEL2")
	)
	(segment
		(start 374.357646 -182.776876)
		(end 375.106692 -182.776876)
		(width 0.15494)
		(layer "In13.Cu")
		(net "PEX1_MODE_SEL2")
	)
	(segment
		(start 360.582972 -177.533808)
		(end 360.820462 -177.771298)
		(width 0.15494)
		(layer "In13.Cu")
		(net "PEX1_MODE_SEL2")
	)
	(segment
		(start 213.835488 -194.974464)
		(end 213.45398 -195.355718)
		(width 0.15494)
		(layer "In15.Cu")
		(net "PEX1_MODE_SEL2")
	)
	(segment
		(start 225.942652 -194.671696)
		(end 221.398338 -199.21601)
		(width 0.15494)
		(layer "In15.Cu")
		(net "PEX1_MODE_SEL2")
	)
	(segment
		(start 209.22234 -198.27113)
		(end 208.662016 -198.831454)
		(width 0.15494)
		(layer "In15.Cu")
		(net "PEX1_MODE_SEL2")
	)
	(segment
		(start 210.538568 -198.27113)
		(end 209.22234 -198.27113)
		(width 0.15494)
		(layer "In15.Cu")
		(net "PEX1_MODE_SEL2")
	)
	(segment
		(start 224.783904 -188.186314)
		(end 225.242374 -188.186314)
		(width 0.15494)
		(layer "In15.Cu")
		(net "PEX1_MODE_SEL2")
	)
	(segment
		(start 216.8652 -198.24446)
		(end 216.8652 -197.404736)
		(width 0.15494)
		(layer "In15.Cu")
		(net "PEX1_MODE_SEL2")
	)
	(segment
		(start 190.044832 -210.560158)
		(end 186.35472 -210.560158)
		(width 0.15494)
		(layer "In15.Cu")
		(net "PEX1_MODE_SEL2")
	)
	(segment
		(start 214.434928 -194.974464)
		(end 213.835488 -194.974464)
		(width 0.15494)
		(layer "In15.Cu")
		(net "PEX1_MODE_SEL2")
	)
	(segment
		(start 225.942652 -188.886592)
		(end 225.942652 -194.671696)
		(width 0.15494)
		(layer "In15.Cu")
		(net "PEX1_MODE_SEL2")
	)
	(segment
		(start 216.8652 -197.404736)
		(end 214.434928 -194.974464)
		(width 0.15494)
		(layer "In15.Cu")
		(net "PEX1_MODE_SEL2")
	)
	(segment
		(start 201.773536 -198.831454)
		(end 190.044832 -210.560158)
		(width 0.15494)
		(layer "In15.Cu")
		(net "PEX1_MODE_SEL2")
	)
	(segment
		(start 221.398338 -199.21601)
		(end 217.83675 -199.21601)
		(width 0.15494)
		(layer "In15.Cu")
		(net "PEX1_MODE_SEL2")
	)
	(segment
		(start 217.83675 -199.21601)
		(end 216.8652 -198.24446)
		(width 0.15494)
		(layer "In15.Cu")
		(net "PEX1_MODE_SEL2")
	)
	(segment
		(start 225.242374 -188.186314)
		(end 225.942652 -188.886592)
		(width 0.15494)
		(layer "In15.Cu")
		(net "PEX1_MODE_SEL2")
	)
	(segment
		(start 213.45398 -195.355718)
		(end 210.538568 -198.27113)
		(width 0.15494)
		(layer "In15.Cu")
		(net "PEX1_MODE_SEL2")
	)
	(segment
		(start 208.662016 -198.831454)
		(end 201.773536 -198.831454)
		(width 0.15494)
		(layer "In15.Cu")
		(net "PEX1_MODE_SEL2")
	)
	(segment
		(start 376.706384 -251.956824)
		(end 376.706384 -251.158502)
		(width 0.13208)
		(layer "F.Cu")
		(net "PEX3_DBG_MODE3")
	)
	(segment
		(start 408.899868 -282.599892)
		(end 409.374848 -283.074872)
		(width 0.1651)
		(layer "F.Cu")
		(net "PEX3_DBG_MODE3")
	)
	(segment
		(start 376.706384 -251.158502)
		(end 376.706384 -250.470924)
		(width 0.13208)
		(layer "F.Cu")
		(net "PEX3_DBG_MODE3")
	)
	(via
		(at 376.706384 -251.158502)
		(size 0.508)
		(drill 0.254)
		(layers "F.Cu" "B.Cu")
		(net "PEX3_DBG_MODE3")
	)
	(via
		(at 409.374848 -283.074872)
		(size 0.4064)
		(drill 0.2032)
		(layers "F.Cu" "B.Cu")
		(net "PEX3_DBG_MODE3")
	)
	(segment
		(start 376.173746 -254.354076)
		(end 376.05335 -254.474472)
		(width 0.13208)
		(layer "B.Cu")
		(net "PEX3_DBG_MODE3")
	)
	(segment
		(start 407.465784 -269.886684)
		(end 407.675334 -269.886684)
		(width 0.13208)
		(layer "B.Cu")
		(net "PEX3_DBG_MODE3")
	)
	(segment
		(start 376.05335 -254.474472)
		(end 376.05335 -255.303528)
		(width 0.13208)
		(layer "B.Cu")
		(net "PEX3_DBG_MODE3")
	)
	(segment
		(start 376.333512 -255.58369)
		(end 377.39193 -255.58369)
		(width 0.13208)
		(layer "B.Cu")
		(net "PEX3_DBG_MODE3")
	)
	(segment
		(start 406.49017 -268.560296)
		(end 406.49017 -268.91107)
		(width 0.13208)
		(layer "B.Cu")
		(net "PEX3_DBG_MODE3")
	)
	(segment
		(start 378.51969 -257.239516)
		(end 378.519944 -257.23977)
		(width 0.13208)
		(layer "B.Cu")
		(net "PEX3_DBG_MODE3")
	)
	(segment
		(start 381.817626 -257.239516)
		(end 382.593088 -258.014978)
		(width 0.13208)
		(layer "B.Cu")
		(net "PEX3_DBG_MODE3")
	)
	(segment
		(start 407.675334 -269.886684)
		(end 409.374848 -271.586198)
		(width 0.13208)
		(layer "B.Cu")
		(net "PEX3_DBG_MODE3")
	)
	(segment
		(start 377.39193 -255.58369)
		(end 378.083572 -256.275332)
		(width 0.13208)
		(layer "B.Cu")
		(net "PEX3_DBG_MODE3")
	)
	(segment
		(start 395.944852 -258.014978)
		(end 406.49017 -268.560296)
		(width 0.13208)
		(layer "B.Cu")
		(net "PEX3_DBG_MODE3")
	)
	(segment
		(start 378.083572 -257.012186)
		(end 378.310902 -257.239516)
		(width 0.13208)
		(layer "B.Cu")
		(net "PEX3_DBG_MODE3")
	)
	(segment
		(start 409.374848 -271.586198)
		(end 409.374848 -283.074872)
		(width 0.13208)
		(layer "B.Cu")
		(net "PEX3_DBG_MODE3")
	)
	(segment
		(start 376.706384 -251.158502)
		(end 376.173746 -251.69114)
		(width 0.13208)
		(layer "B.Cu")
		(net "PEX3_DBG_MODE3")
	)
	(segment
		(start 382.593088 -258.014978)
		(end 395.944852 -258.014978)
		(width 0.13208)
		(layer "B.Cu")
		(net "PEX3_DBG_MODE3")
	)
	(segment
		(start 376.173746 -251.69114)
		(end 376.173746 -254.354076)
		(width 0.13208)
		(layer "B.Cu")
		(net "PEX3_DBG_MODE3")
	)
	(segment
		(start 376.05335 -255.303528)
		(end 376.333512 -255.58369)
		(width 0.13208)
		(layer "B.Cu")
		(net "PEX3_DBG_MODE3")
	)
	(segment
		(start 378.083572 -256.275332)
		(end 378.083572 -257.012186)
		(width 0.13208)
		(layer "B.Cu")
		(net "PEX3_DBG_MODE3")
	)
	(segment
		(start 378.519944 -257.23977)
		(end 378.689616 -257.23977)
		(width 0.13208)
		(layer "B.Cu")
		(net "PEX3_DBG_MODE3")
	)
	(segment
		(start 378.310902 -257.239516)
		(end 378.51969 -257.239516)
		(width 0.13208)
		(layer "B.Cu")
		(net "PEX3_DBG_MODE3")
	)
	(segment
		(start 406.49017 -268.91107)
		(end 407.465784 -269.886684)
		(width 0.13208)
		(layer "B.Cu")
		(net "PEX3_DBG_MODE3")
	)
	(segment
		(start 378.689616 -257.23977)
		(end 378.68987 -257.239516)
		(width 0.13208)
		(layer "B.Cu")
		(net "PEX3_DBG_MODE3")
	)
	(segment
		(start 378.68987 -257.239516)
		(end 381.817626 -257.239516)
		(width 0.13208)
		(layer "B.Cu")
		(net "PEX3_DBG_MODE3")
	)
	(segment
		(start 359.55605 -179.07)
		(end 359.55605 -178.054)
		(width 0.13208)
		(layer "F.Cu")
		(net "SSD6_PEX_PWR_EN_R")
	)
	(segment
		(start 348.493842 -212.786976)
		(end 348.893638 -212.38718)
		(width 0.13208)
		(layer "F.Cu")
		(net "SSD6_PEX_PWR_EN_R")
	)
	(segment
		(start 359.55605 -178.054)
		(end 360.172 -178.054)
		(width 0.13208)
		(layer "F.Cu")
		(net "SSD6_PEX_PWR_EN_R")
	)
	(segment
		(start 360.172 -178.054)
		(end 360.78795 -178.054)
		(width 0.13208)
		(layer "F.Cu")
		(net "SSD6_PEX_PWR_EN_R")
	)
	(via
		(at 360.172 -178.054)
		(size 0.508)
		(drill 0.254)
		(layers "F.Cu" "B.Cu")
		(net "SSD6_PEX_PWR_EN_R")
	)
	(via
		(at 348.893638 -212.38718)
		(size 0.4572)
		(drill 0.254)
		(layers "F.Cu" "B.Cu")
		(net "SSD6_PEX_PWR_EN_R")
	)
	(segment
		(start 354.7364 -204.368654)
		(end 353.81692 -205.288134)
		(width 0.15494)
		(layer "In7.Cu")
		(net "SSD6_PEX_PWR_EN_R")
	)
	(segment
		(start 365.125 -191.075818)
		(end 365.125 -196.022214)
		(width 0.15494)
		(layer "In7.Cu")
		(net "SSD6_PEX_PWR_EN_R")
	)
	(segment
		(start 365.125 -196.022214)
		(end 363.673136 -197.474078)
		(width 0.15494)
		(layer "In7.Cu")
		(net "SSD6_PEX_PWR_EN_R")
	)
	(segment
		(start 353.81692 -205.288134)
		(end 353.81692 -206.50708)
		(width 0.15494)
		(layer "In7.Cu")
		(net "SSD6_PEX_PWR_EN_R")
	)
	(segment
		(start 364.57636 -185.631836)
		(end 364.57636 -190.527178)
		(width 0.15494)
		(layer "In7.Cu")
		(net "SSD6_PEX_PWR_EN_R")
	)
	(segment
		(start 354.7364 -203.4032)
		(end 354.7364 -204.368654)
		(width 0.15494)
		(layer "In7.Cu")
		(net "SSD6_PEX_PWR_EN_R")
	)
	(segment
		(start 360.9086 -178.054)
		(end 363.600238 -180.745638)
		(width 0.15494)
		(layer "In7.Cu")
		(net "SSD6_PEX_PWR_EN_R")
	)
	(segment
		(start 349.79356 -211.487258)
		(end 348.893638 -212.38718)
		(width 0.15494)
		(layer "In7.Cu")
		(net "SSD6_PEX_PWR_EN_R")
	)
	(segment
		(start 360.665522 -197.474078)
		(end 354.7364 -203.4032)
		(width 0.15494)
		(layer "In7.Cu")
		(net "SSD6_PEX_PWR_EN_R")
	)
	(segment
		(start 349.79356 -210.53044)
		(end 349.79356 -211.487258)
		(width 0.15494)
		(layer "In7.Cu")
		(net "SSD6_PEX_PWR_EN_R")
	)
	(segment
		(start 363.673136 -197.474078)
		(end 360.665522 -197.474078)
		(width 0.15494)
		(layer "In7.Cu")
		(net "SSD6_PEX_PWR_EN_R")
	)
	(segment
		(start 364.57636 -190.527178)
		(end 365.125 -191.075818)
		(width 0.15494)
		(layer "In7.Cu")
		(net "SSD6_PEX_PWR_EN_R")
	)
	(segment
		(start 363.600238 -180.745638)
		(end 363.600238 -184.655714)
		(width 0.15494)
		(layer "In7.Cu")
		(net "SSD6_PEX_PWR_EN_R")
	)
	(segment
		(start 363.600238 -184.655714)
		(end 364.57636 -185.631836)
		(width 0.15494)
		(layer "In7.Cu")
		(net "SSD6_PEX_PWR_EN_R")
	)
	(segment
		(start 360.172 -178.054)
		(end 360.9086 -178.054)
		(width 0.15494)
		(layer "In7.Cu")
		(net "SSD6_PEX_PWR_EN_R")
	)
	(segment
		(start 353.81692 -206.50708)
		(end 349.79356 -210.53044)
		(width 0.15494)
		(layer "In7.Cu")
		(net "SSD6_PEX_PWR_EN_R")
	)
	(segment
		(start 103.7717 -87.487506)
		(end 103.847138 -87.562944)
		(width 0.254)
		(layer "F.Cu")
		(net "P3V3_VDDAR_9ZXL0851_0_7")
	)
	(segment
		(start 103.258112 -88.884506)
		(end 103.258112 -87.487506)
		(width 0.254)
		(layer "F.Cu")
		(net "P3V3_VDDAR_9ZXL0851_0_7")
	)
	(segment
		(start 108.239052 -88.928956)
		(end 108.239052 -90.190066)
		(width 0.1778)
		(layer "F.Cu")
		(net "P3V3_VDDAR_9ZXL0851_0_7")
	)
	(segment
		(start 103.258112 -87.487506)
		(end 103.7717 -87.487506)
		(width 0.254)
		(layer "F.Cu")
		(net "P3V3_VDDAR_9ZXL0851_0_7")
	)
	(segment
		(start 105.081578 -87.379048)
		(end 105.889044 -87.379048)
		(width 0.1778)
		(layer "F.Cu")
		(net "P3V3_VDDAR_9ZXL0851_0_7")
	)
	(segment
		(start 104.314752 -87.562944)
		(end 104.897682 -87.562944)
		(width 0.1778)
		(layer "F.Cu")
		(net "P3V3_VDDAR_9ZXL0851_0_7")
	)
	(segment
		(start 104.897682 -87.562944)
		(end 105.081578 -87.379048)
		(width 0.1778)
		(layer "F.Cu")
		(net "P3V3_VDDAR_9ZXL0851_0_7")
	)
	(segment
		(start 103.847138 -87.562944)
		(end 104.314752 -87.562944)
		(width 0.254)
		(layer "F.Cu")
		(net "P3V3_VDDAR_9ZXL0851_0_7")
	)
	(via
		(at 104.138476 -89.16543)
		(size 0.6604)
		(drill 0.3302)
		(layers "F.Cu" "B.Cu")
		(net "P3V3_VDDAR_9ZXL0851_0_7")
	)
	(via
		(at 106.28249 -89.294208)
		(size 0.6604)
		(drill 0.3302)
		(layers "F.Cu" "B.Cu")
		(net "P3V3_VDDAR_9ZXL0851_0_7")
	)
	(via
		(at 104.314752 -87.562944)
		(size 0.508)
		(drill 0.254)
		(layers "F.Cu" "B.Cu")
		(net "P3V3_VDDAR_9ZXL0851_0_7")
	)
	(via
		(at 108.239052 -90.190066)
		(size 0.508)
		(drill 0.254)
		(layers "F.Cu" "B.Cu")
		(net "P3V3_VDDAR_9ZXL0851_0_7")
	)
	(segment
		(start 106.063796 -87.12327)
		(end 105.31983 -87.12327)
		(width 0.254)
		(layer "B.Cu")
		(net "P3V3_VDDAR_9ZXL0851_0_7")
	)
	(segment
		(start 107.671616 -89.041986)
		(end 107.671616 -89.62263)
		(width 0.254)
		(layer "B.Cu")
		(net "P3V3_VDDAR_9ZXL0851_0_7")
	)
	(segment
		(start 107.671616 -89.62263)
		(end 108.239052 -90.190066)
		(width 0.254)
		(layer "B.Cu")
		(net "P3V3_VDDAR_9ZXL0851_0_7")
	)
	(segment
		(start 104.880156 -87.562944)
		(end 104.314752 -87.562944)
		(width 0.254)
		(layer "B.Cu")
		(net "P3V3_VDDAR_9ZXL0851_0_7")
	)
	(segment
		(start 105.31983 -87.12327)
		(end 104.880156 -87.562944)
		(width 0.254)
		(layer "B.Cu")
		(net "P3V3_VDDAR_9ZXL0851_0_7")
	)
	(segment
		(start 108.239052 -90.190066)
		(end 106.181144 -90.190066)
		(width 0.15494)
		(layer "In7.Cu")
		(net "P3V3_VDDAR_9ZXL0851_0_7")
	)
	(segment
		(start 104.314752 -88.323674)
		(end 104.314752 -87.562944)
		(width 0.15494)
		(layer "In7.Cu")
		(net "P3V3_VDDAR_9ZXL0851_0_7")
	)
	(segment
		(start 106.181144 -90.190066)
		(end 104.314752 -88.323674)
		(width 0.15494)
		(layer "In7.Cu")
		(net "P3V3_VDDAR_9ZXL0851_0_7")
	)
	(segment
		(start 383.122424 -309.897272)
		(end 383.122424 -309.820564)
		(width 0.13208)
		(layer "F.Cu")
		(net "PEX3_DBG_MODE1")
	)
	(segment
		(start 382.436878 -307.698394)
		(end 382.437132 -307.698394)
		(width 0.13208)
		(layer "F.Cu")
		(net "PEX3_DBG_MODE1")
	)
	(segment
		(start 396.54988 -309.199788)
		(end 397.02486 -308.724808)
		(width 0.13208)
		(layer "F.Cu")
		(net "PEX3_DBG_MODE1")
	)
	(segment
		(start 383.122424 -309.820564)
		(end 381.718566 -308.416706)
		(width 0.13208)
		(layer "F.Cu")
		(net "PEX3_DBG_MODE1")
	)
	(segment
		(start 381.718566 -308.416706)
		(end 382.436878 -307.698394)
		(width 0.13208)
		(layer "F.Cu")
		(net "PEX3_DBG_MODE1")
	)
	(via
		(at 397.02486 -308.724808)
		(size 0.4064)
		(drill 0.2032)
		(layers "F.Cu" "B.Cu")
		(net "PEX3_DBG_MODE1")
	)
	(via
		(at 383.122424 -309.897272)
		(size 0.508)
		(drill 0.254)
		(layers "F.Cu" "B.Cu")
		(net "PEX3_DBG_MODE1")
	)
	(segment
		(start 383.122424 -309.897272)
		(end 383.368296 -309.6514)
		(width 0.13208)
		(layer "B.Cu")
		(net "PEX3_DBG_MODE1")
	)
	(segment
		(start 383.368296 -309.6514)
		(end 396.098268 -309.6514)
		(width 0.13208)
		(layer "B.Cu")
		(net "PEX3_DBG_MODE1")
	)
	(segment
		(start 396.098268 -309.6514)
		(end 397.02486 -308.724808)
		(width 0.13208)
		(layer "B.Cu")
		(net "PEX3_DBG_MODE1")
	)
	(segment
		(start 225.867722 -223.104202)
		(end 225.467926 -223.503998)
		(width 0.13208)
		(layer "F.Cu")
		(net "SMB_NIC1_SCL")
	)
	(via
		(at 225.467926 -223.503998)
		(size 0.4572)
		(drill 0.254)
		(layers "F.Cu" "B.Cu")
		(net "SMB_NIC1_SCL")
	)
	(via
		(at 224.354644 -229.091998)
		(size 0.6604)
		(drill 0.3302)
		(layers "F.Cu" "B.Cu")
		(net "SMB_NIC1_SCL")
	)
	(segment
		(start 224.354644 -229.091998)
		(end 224.354644 -230.825548)
		(width 0.13208)
		(layer "B.Cu")
		(net "SMB_NIC1_SCL")
	)
	(segment
		(start 224.354644 -227.278184)
		(end 225.443542 -226.189286)
		(width 0.13208)
		(layer "B.Cu")
		(net "SMB_NIC1_SCL")
	)
	(segment
		(start 225.467926 -225.04908)
		(end 225.467926 -223.503998)
		(width 0.13208)
		(layer "B.Cu")
		(net "SMB_NIC1_SCL")
	)
	(segment
		(start 224.354644 -229.091998)
		(end 224.354644 -227.278184)
		(width 0.13208)
		(layer "B.Cu")
		(net "SMB_NIC1_SCL")
	)
	(segment
		(start 225.443542 -225.073464)
		(end 225.467926 -225.04908)
		(width 0.13208)
		(layer "B.Cu")
		(net "SMB_NIC1_SCL")
	)
	(segment
		(start 225.443542 -226.189286)
		(end 225.443542 -225.073464)
		(width 0.13208)
		(layer "B.Cu")
		(net "SMB_NIC1_SCL")
	)
	(segment
		(start 149.480778 -379.396498)
		(end 149.488144 -379.389132)
		(width 0.13208)
		(layer "F.Cu")
		(net "GPU_FPGA_EROT_FATALERR_N")
	)
	(segment
		(start 149.488144 -379.389132)
		(end 151.10714 -379.389132)
		(width 0.13208)
		(layer "F.Cu")
		(net "GPU_FPGA_EROT_FATALERR_N")
	)
	(segment
		(start 149.570186 -379.30709)
		(end 149.488144 -379.389132)
		(width 0.13208)
		(layer "F.Cu")
		(net "GPU_FPGA_EROT_FATALERR_N")
	)
	(segment
		(start 149.570186 -378.68733)
		(end 149.570186 -379.30709)
		(width 0.13208)
		(layer "F.Cu")
		(net "GPU_FPGA_EROT_FATALERR_N")
	)
	(via
		(at 149.570186 -378.68733)
		(size 0.508)
		(drill 0.254)
		(layers "F.Cu" "B.Cu")
		(net "GPU_FPGA_EROT_FATALERR_N")
	)
	(segment
		(start 160.87598 -367.756186)
		(end 157.382972 -367.756186)
		(width 0.15494)
		(layer "In15.Cu")
		(net "GPU_FPGA_EROT_FATALERR_N")
	)
	(segment
		(start 162.109912 -368.990118)
		(end 160.87598 -367.756186)
		(width 0.15494)
		(layer "In15.Cu")
		(net "GPU_FPGA_EROT_FATALERR_N")
	)
	(segment
		(start 149.570186 -375.568972)
		(end 149.570186 -378.68733)
		(width 0.15494)
		(layer "In15.Cu")
		(net "GPU_FPGA_EROT_FATALERR_N")
	)
	(segment
		(start 157.382972 -367.756186)
		(end 149.570186 -375.568972)
		(width 0.15494)
		(layer "In15.Cu")
		(net "GPU_FPGA_EROT_FATALERR_N")
	)
	(segment
		(start 345.29395 -214.387176)
		(end 345.693746 -213.98738)
		(width 0.13208)
		(layer "F.Cu")
		(net "PRSNT_SSD3_FPGA_N")
	)
	(via
		(at 345.821 -211.201)
		(size 0.6604)
		(drill 0.3302)
		(layers "F.Cu" "B.Cu")
		(net "PRSNT_SSD3_FPGA_N")
	)
	(via
		(at 345.693746 -213.98738)
		(size 0.4572)
		(drill 0.254)
		(layers "F.Cu" "B.Cu")
		(net "PRSNT_SSD3_FPGA_N")
	)
	(segment
		(start 345.821 -211.201)
		(end 345.821 -210.693)
		(width 0.13208)
		(layer "B.Cu")
		(net "PRSNT_SSD3_FPGA_N")
	)
	(segment
		(start 345.294204 -211.727796)
		(end 345.821 -211.201)
		(width 0.13208)
		(layer "B.Cu")
		(net "PRSNT_SSD3_FPGA_N")
	)
	(segment
		(start 346.583 -209.931)
		(end 346.583 -208.17205)
		(width 0.13208)
		(layer "B.Cu")
		(net "PRSNT_SSD3_FPGA_N")
	)
	(segment
		(start 345.693746 -213.98738)
		(end 345.294204 -213.587838)
		(width 0.0889)
		(layer "B.Cu")
		(net "PRSNT_SSD3_FPGA_N")
	)
	(segment
		(start 345.821 -210.693)
		(end 346.583 -209.931)
		(width 0.13208)
		(layer "B.Cu")
		(net "PRSNT_SSD3_FPGA_N")
	)
	(segment
		(start 345.294204 -213.587838)
		(end 345.294204 -211.727796)
		(width 0.0889)
		(layer "B.Cu")
		(net "PRSNT_SSD3_FPGA_N")
	)
	(segment
		(start 110.169706 -93.060012)
		(end 110.169706 -93.757496)
		(width 0.13462)
		(layer "F.Cu")
		(net "CLK_100M_DB800ZL_SSD7_R_DP")
	)
	(segment
		(start 110.169706 -93.757496)
		(end 110.470696 -94.058486)
		(width 0.13462)
		(layer "F.Cu")
		(net "CLK_100M_DB800ZL_SSD7_R_DP")
	)
	(segment
		(start 210.012534 -27.04592)
		(end 209.868516 -27.189938)
		(width 0.13462)
		(layer "F.Cu")
		(net "CLK_100M_DB800ZL_SSD7_R_DP")
	)
	(segment
		(start 110.496096 -92.733622)
		(end 110.169706 -93.060012)
		(width 0.13462)
		(layer "F.Cu")
		(net "CLK_100M_DB800ZL_SSD7_R_DP")
	)
	(segment
		(start 209.868516 -27.189938)
		(end 209.364834 -27.189938)
		(width 0.13462)
		(layer "F.Cu")
		(net "CLK_100M_DB800ZL_SSD7_R_DP")
	)
	(segment
		(start 210.78444 -27.04592)
		(end 210.012534 -27.04592)
		(width 0.13462)
		(layer "F.Cu")
		(net "CLK_100M_DB800ZL_SSD7_R_DP")
	)
	(segment
		(start 211.081366 -27.342846)
		(end 210.78444 -27.04592)
		(width 0.13462)
		(layer "F.Cu")
		(net "CLK_100M_DB800ZL_SSD7_R_DP")
	)
	(via
		(at 211.081366 -27.342846)
		(size 0.508)
		(drill 0.254)
		(layers "F.Cu" "B.Cu")
		(net "CLK_100M_DB800ZL_SSD7_R_DP")
	)
	(via
		(at 110.470696 -94.058486)
		(size 0.508)
		(drill 0.254)
		(layers "F.Cu" "B.Cu")
		(net "CLK_100M_DB800ZL_SSD7_R_DP")
	)
	(segment
		(start 205.507336 -50.472848)
		(end 206.071724 -59.87923)
		(width 0.1651)
		(layer "In13.Cu")
		(net "CLK_100M_DB800ZL_SSD7_R_DP")
	)
	(segment
		(start 181.699916 -79.627222)
		(end 181.585616 -79.512922)
		(width 0.1651)
		(layer "In13.Cu")
		(net "CLK_100M_DB800ZL_SSD7_R_DP")
	)
	(segment
		(start 210.544918 -38.026848)
		(end 210.38312 -38.026848)
		(width 0.1651)
		(layer "In13.Cu")
		(net "CLK_100M_DB800ZL_SSD7_R_DP")
	)
	(segment
		(start 176.823116 -79.627222)
		(end 176.708816 -79.512922)
		(width 0.1651)
		(layer "In13.Cu")
		(net "CLK_100M_DB800ZL_SSD7_R_DP")
	)
	(segment
		(start 182.195216 -79.627222)
		(end 181.699916 -79.627222)
		(width 0.1651)
		(layer "In13.Cu")
		(net "CLK_100M_DB800ZL_SSD7_R_DP")
	)
	(segment
		(start 211.64296 -35.663886)
		(end 211.75726 -35.778186)
		(width 0.1651)
		(layer "In13.Cu")
		(net "CLK_100M_DB800ZL_SSD7_R_DP")
	)
	(segment
		(start 179.756816 -79.627222)
		(end 179.261516 -79.627222)
		(width 0.1651)
		(layer "In13.Cu")
		(net "CLK_100M_DB800ZL_SSD7_R_DP")
	)
	(segment
		(start 211.64296 -27.853386)
		(end 211.64296 -28.348686)
		(width 0.1651)
		(layer "In13.Cu")
		(net "CLK_100M_DB800ZL_SSD7_R_DP")
	)
	(segment
		(start 211.370672 -27.05354)
		(end 211.567014 -27.05354)
		(width 0.1651)
		(layer "In13.Cu")
		(net "CLK_100M_DB800ZL_SSD7_R_DP")
	)
	(segment
		(start 176.099216 -79.627222)
		(end 135.810244 -79.627222)
		(width 0.1651)
		(layer "In13.Cu")
		(net "CLK_100M_DB800ZL_SSD7_R_DP")
	)
	(segment
		(start 180.976016 -79.627222)
		(end 180.480716 -79.627222)
		(width 0.1651)
		(layer "In13.Cu")
		(net "CLK_100M_DB800ZL_SSD7_R_DP")
	)
	(segment
		(start 210.0326 -38.377368)
		(end 210.0326 -38.539166)
		(width 0.1651)
		(layer "In13.Cu")
		(net "CLK_100M_DB800ZL_SSD7_R_DP")
	)
	(segment
		(start 179.147216 -79.512922)
		(end 178.651916 -79.512922)
		(width 0.1651)
		(layer "In13.Cu")
		(net "CLK_100M_DB800ZL_SSD7_R_DP")
	)
	(segment
		(start 177.432716 -79.512922)
		(end 177.318416 -79.627222)
		(width 0.1651)
		(layer "In13.Cu")
		(net "CLK_100M_DB800ZL_SSD7_R_DP")
	)
	(segment
		(start 211.081366 -27.342846)
		(end 211.370672 -27.05354)
		(width 0.1651)
		(layer "In13.Cu")
		(net "CLK_100M_DB800ZL_SSD7_R_DP")
	)
	(segment
		(start 111.851186 -95.06585)
		(end 110.42523 -95.06585)
		(width 0.1651)
		(layer "In13.Cu")
		(net "CLK_100M_DB800ZL_SSD7_R_DP")
	)
	(segment
		(start 110.42523 -95.06585)
		(end 110.179866 -94.820486)
		(width 0.1651)
		(layer "In13.Cu")
		(net "CLK_100M_DB800ZL_SSD7_R_DP")
	)
	(segment
		(start 211.64296 -30.787086)
		(end 211.75726 -30.901386)
		(width 0.1651)
		(layer "In13.Cu")
		(net "CLK_100M_DB800ZL_SSD7_R_DP")
	)
	(segment
		(start 211.64296 -33.225486)
		(end 211.75726 -33.339786)
		(width 0.1651)
		(layer "In13.Cu")
		(net "CLK_100M_DB800ZL_SSD7_R_DP")
	)
	(segment
		(start 211.75726 -33.835086)
		(end 211.64296 -33.949386)
		(width 0.1651)
		(layer "In13.Cu")
		(net "CLK_100M_DB800ZL_SSD7_R_DP")
	)
	(segment
		(start 211.75726 -28.462986)
		(end 211.75726 -28.958286)
		(width 0.1651)
		(layer "In13.Cu")
		(net "CLK_100M_DB800ZL_SSD7_R_DP")
	)
	(segment
		(start 211.75726 -35.778186)
		(end 211.75726 -36.814506)
		(width 0.1651)
		(layer "In13.Cu")
		(net "CLK_100M_DB800ZL_SSD7_R_DP")
	)
	(segment
		(start 211.75726 -35.054286)
		(end 211.64296 -35.168586)
		(width 0.1651)
		(layer "In13.Cu")
		(net "CLK_100M_DB800ZL_SSD7_R_DP")
	)
	(segment
		(start 211.64296 -29.567886)
		(end 211.75726 -29.682186)
		(width 0.1651)
		(layer "In13.Cu")
		(net "CLK_100M_DB800ZL_SSD7_R_DP")
	)
	(segment
		(start 211.64296 -30.291786)
		(end 211.64296 -30.787086)
		(width 0.1651)
		(layer "In13.Cu")
		(net "CLK_100M_DB800ZL_SSD7_R_DP")
	)
	(segment
		(start 211.64296 -32.006286)
		(end 211.75726 -32.120586)
		(width 0.1651)
		(layer "In13.Cu")
		(net "CLK_100M_DB800ZL_SSD7_R_DP")
	)
	(segment
		(start 181.090316 -79.512922)
		(end 180.976016 -79.627222)
		(width 0.1651)
		(layer "In13.Cu")
		(net "CLK_100M_DB800ZL_SSD7_R_DP")
	)
	(segment
		(start 176.708816 -79.512922)
		(end 176.213516 -79.512922)
		(width 0.1651)
		(layer "In13.Cu")
		(net "CLK_100M_DB800ZL_SSD7_R_DP")
	)
	(segment
		(start 211.64296 -32.730186)
		(end 211.64296 -33.225486)
		(width 0.1651)
		(layer "In13.Cu")
		(net "CLK_100M_DB800ZL_SSD7_R_DP")
	)
	(segment
		(start 211.75726 -32.120586)
		(end 211.75726 -32.615886)
		(width 0.1651)
		(layer "In13.Cu")
		(net "CLK_100M_DB800ZL_SSD7_R_DP")
	)
	(segment
		(start 179.261516 -79.627222)
		(end 179.147216 -79.512922)
		(width 0.1651)
		(layer "In13.Cu")
		(net "CLK_100M_DB800ZL_SSD7_R_DP")
	)
	(segment
		(start 211.75726 -30.901386)
		(end 211.75726 -31.396686)
		(width 0.1651)
		(layer "In13.Cu")
		(net "CLK_100M_DB800ZL_SSD7_R_DP")
	)
	(segment
		(start 211.64296 -33.949386)
		(end 211.64296 -34.444686)
		(width 0.1651)
		(layer "In13.Cu")
		(net "CLK_100M_DB800ZL_SSD7_R_DP")
	)
	(segment
		(start 210.38312 -38.026848)
		(end 210.0326 -38.377368)
		(width 0.1651)
		(layer "In13.Cu")
		(net "CLK_100M_DB800ZL_SSD7_R_DP")
	)
	(segment
		(start 178.651916 -79.512922)
		(end 178.537616 -79.627222)
		(width 0.1651)
		(layer "In13.Cu")
		(net "CLK_100M_DB800ZL_SSD7_R_DP")
	)
	(segment
		(start 211.75726 -29.682186)
		(end 211.75726 -30.177486)
		(width 0.1651)
		(layer "In13.Cu")
		(net "CLK_100M_DB800ZL_SSD7_R_DP")
	)
	(segment
		(start 211.75726 -27.739086)
		(end 211.64296 -27.853386)
		(width 0.1651)
		(layer "In13.Cu")
		(net "CLK_100M_DB800ZL_SSD7_R_DP")
	)
	(segment
		(start 211.64296 -35.168586)
		(end 211.64296 -35.663886)
		(width 0.1651)
		(layer "In13.Cu")
		(net "CLK_100M_DB800ZL_SSD7_R_DP")
	)
	(segment
		(start 128.852168 -81.990692)
		(end 120.3706 -90.47226)
		(width 0.1651)
		(layer "In13.Cu")
		(net "CLK_100M_DB800ZL_SSD7_R_DP")
	)
	(segment
		(start 116.444776 -90.47226)
		(end 111.851186 -95.06585)
		(width 0.1651)
		(layer "In13.Cu")
		(net "CLK_100M_DB800ZL_SSD7_R_DP")
	)
	(segment
		(start 211.75726 -30.177486)
		(end 211.64296 -30.291786)
		(width 0.1651)
		(layer "In13.Cu")
		(net "CLK_100M_DB800ZL_SSD7_R_DP")
	)
	(segment
		(start 180.366416 -79.512922)
		(end 179.871116 -79.512922)
		(width 0.1651)
		(layer "In13.Cu")
		(net "CLK_100M_DB800ZL_SSD7_R_DP")
	)
	(segment
		(start 211.75726 -31.396686)
		(end 211.64296 -31.510986)
		(width 0.1651)
		(layer "In13.Cu")
		(net "CLK_100M_DB800ZL_SSD7_R_DP")
	)
	(segment
		(start 179.871116 -79.512922)
		(end 179.756816 -79.627222)
		(width 0.1651)
		(layer "In13.Cu")
		(net "CLK_100M_DB800ZL_SSD7_R_DP")
	)
	(segment
		(start 178.537616 -79.627222)
		(end 178.042316 -79.627222)
		(width 0.1651)
		(layer "In13.Cu")
		(net "CLK_100M_DB800ZL_SSD7_R_DP")
	)
	(segment
		(start 178.042316 -79.627222)
		(end 177.928016 -79.512922)
		(width 0.1651)
		(layer "In13.Cu")
		(net "CLK_100M_DB800ZL_SSD7_R_DP")
	)
	(segment
		(start 211.64296 -29.072586)
		(end 211.64296 -29.567886)
		(width 0.1651)
		(layer "In13.Cu")
		(net "CLK_100M_DB800ZL_SSD7_R_DP")
	)
	(segment
		(start 211.64296 -31.510986)
		(end 211.64296 -32.006286)
		(width 0.1651)
		(layer "In13.Cu")
		(net "CLK_100M_DB800ZL_SSD7_R_DP")
	)
	(segment
		(start 211.75726 -27.243786)
		(end 211.75726 -27.739086)
		(width 0.1651)
		(layer "In13.Cu")
		(net "CLK_100M_DB800ZL_SSD7_R_DP")
	)
	(segment
		(start 181.585616 -79.512922)
		(end 181.090316 -79.512922)
		(width 0.1651)
		(layer "In13.Cu")
		(net "CLK_100M_DB800ZL_SSD7_R_DP")
	)
	(segment
		(start 177.318416 -79.627222)
		(end 176.823116 -79.627222)
		(width 0.1651)
		(layer "In13.Cu")
		(net "CLK_100M_DB800ZL_SSD7_R_DP")
	)
	(segment
		(start 205.781402 -42.790364)
		(end 205.507336 -50.472848)
		(width 0.1651)
		(layer "In13.Cu")
		(net "CLK_100M_DB800ZL_SSD7_R_DP")
	)
	(segment
		(start 211.75726 -33.339786)
		(end 211.75726 -33.835086)
		(width 0.1651)
		(layer "In13.Cu")
		(net "CLK_100M_DB800ZL_SSD7_R_DP")
	)
	(segment
		(start 211.567014 -27.05354)
		(end 211.75726 -27.243786)
		(width 0.1651)
		(layer "In13.Cu")
		(net "CLK_100M_DB800ZL_SSD7_R_DP")
	)
	(segment
		(start 211.75726 -28.958286)
		(end 211.64296 -29.072586)
		(width 0.1651)
		(layer "In13.Cu")
		(net "CLK_100M_DB800ZL_SSD7_R_DP")
	)
	(segment
		(start 133.446774 -81.990692)
		(end 128.852168 -81.990692)
		(width 0.1651)
		(layer "In13.Cu")
		(net "CLK_100M_DB800ZL_SSD7_R_DP")
	)
	(segment
		(start 211.64296 -28.348686)
		(end 211.75726 -28.462986)
		(width 0.1651)
		(layer "In13.Cu")
		(net "CLK_100M_DB800ZL_SSD7_R_DP")
	)
	(segment
		(start 180.480716 -79.627222)
		(end 180.366416 -79.512922)
		(width 0.1651)
		(layer "In13.Cu")
		(net "CLK_100M_DB800ZL_SSD7_R_DP")
	)
	(segment
		(start 211.64296 -34.444686)
		(end 211.75726 -34.558986)
		(width 0.1651)
		(layer "In13.Cu")
		(net "CLK_100M_DB800ZL_SSD7_R_DP")
	)
	(segment
		(start 210.89493 -37.515038)
		(end 210.89493 -37.676836)
		(width 0.1651)
		(layer "In13.Cu")
		(net "CLK_100M_DB800ZL_SSD7_R_DP")
	)
	(segment
		(start 211.75726 -32.615886)
		(end 211.64296 -32.730186)
		(width 0.1651)
		(layer "In13.Cu")
		(net "CLK_100M_DB800ZL_SSD7_R_DP")
	)
	(segment
		(start 205.885034 -61.686186)
		(end 192.00876 -75.56246)
		(width 0.1651)
		(layer "In13.Cu")
		(net "CLK_100M_DB800ZL_SSD7_R_DP")
	)
	(segment
		(start 176.213516 -79.512922)
		(end 176.099216 -79.627222)
		(width 0.1651)
		(layer "In13.Cu")
		(net "CLK_100M_DB800ZL_SSD7_R_DP")
	)
	(segment
		(start 177.928016 -79.512922)
		(end 177.432716 -79.512922)
		(width 0.1651)
		(layer "In13.Cu")
		(net "CLK_100M_DB800ZL_SSD7_R_DP")
	)
	(segment
		(start 210.0326 -38.539166)
		(end 205.781402 -42.790364)
		(width 0.1651)
		(layer "In13.Cu")
		(net "CLK_100M_DB800ZL_SSD7_R_DP")
	)
	(segment
		(start 192.00876 -75.56246)
		(end 182.195216 -79.627222)
		(width 0.1651)
		(layer "In13.Cu")
		(net "CLK_100M_DB800ZL_SSD7_R_DP")
	)
	(segment
		(start 211.75726 -34.558986)
		(end 211.75726 -35.054286)
		(width 0.1651)
		(layer "In13.Cu")
		(net "CLK_100M_DB800ZL_SSD7_R_DP")
	)
	(segment
		(start 120.3706 -90.47226)
		(end 116.444776 -90.47226)
		(width 0.1651)
		(layer "In13.Cu")
		(net "CLK_100M_DB800ZL_SSD7_R_DP")
	)
	(segment
		(start 110.179866 -94.820486)
		(end 110.179866 -94.349316)
		(width 0.1651)
		(layer "In13.Cu")
		(net "CLK_100M_DB800ZL_SSD7_R_DP")
	)
	(segment
		(start 206.071724 -59.87923)
		(end 205.885034 -61.686186)
		(width 0.1651)
		(layer "In13.Cu")
		(net "CLK_100M_DB800ZL_SSD7_R_DP")
	)
	(segment
		(start 211.24545 -37.164518)
		(end 210.89493 -37.515038)
		(width 0.1651)
		(layer "In13.Cu")
		(net "CLK_100M_DB800ZL_SSD7_R_DP")
	)
	(segment
		(start 211.75726 -36.814506)
		(end 211.407248 -37.164518)
		(width 0.1651)
		(layer "In13.Cu")
		(net "CLK_100M_DB800ZL_SSD7_R_DP")
	)
	(segment
		(start 210.89493 -37.676836)
		(end 210.544918 -38.026848)
		(width 0.1651)
		(layer "In13.Cu")
		(net "CLK_100M_DB800ZL_SSD7_R_DP")
	)
	(segment
		(start 211.407248 -37.164518)
		(end 211.24545 -37.164518)
		(width 0.1651)
		(layer "In13.Cu")
		(net "CLK_100M_DB800ZL_SSD7_R_DP")
	)
	(segment
		(start 135.810244 -79.627222)
		(end 133.446774 -81.990692)
		(width 0.1651)
		(layer "In13.Cu")
		(net "CLK_100M_DB800ZL_SSD7_R_DP")
	)
	(segment
		(start 110.179866 -94.349316)
		(end 110.470696 -94.058486)
		(width 0.1651)
		(layer "In13.Cu")
		(net "CLK_100M_DB800ZL_SSD7_R_DP")
	)
	(segment
		(start 138.272012 -258.53136)
		(end 138.453876 -258.349496)
		(width 0.13208)
		(layer "F.Cu")
		(net "PEX1_SYS_ERR_R_N")
	)
	(segment
		(start 138.453876 -257.474212)
		(end 138.081766 -257.102102)
		(width 0.13208)
		(layer "F.Cu")
		(net "PEX1_SYS_ERR_R_N")
	)
	(segment
		(start 136.346946 -256.386584)
		(end 136.32561 -256.386584)
		(width 0.13208)
		(layer "F.Cu")
		(net "PEX1_SYS_ERR_R_N")
	)
	(segment
		(start 138.453876 -258.349496)
		(end 138.453876 -257.474212)
		(width 0.13208)
		(layer "F.Cu")
		(net "PEX1_SYS_ERR_R_N")
	)
	(segment
		(start 138.272012 -259.346192)
		(end 138.272012 -258.53136)
		(width 0.13208)
		(layer "F.Cu")
		(net "PEX1_SYS_ERR_R_N")
	)
	(segment
		(start 137.062464 -257.102102)
		(end 136.346946 -256.386584)
		(width 0.13208)
		(layer "F.Cu")
		(net "PEX1_SYS_ERR_R_N")
	)
	(segment
		(start 138.081766 -257.102102)
		(end 137.608564 -257.102102)
		(width 0.13208)
		(layer "F.Cu")
		(net "PEX1_SYS_ERR_R_N")
	)
	(segment
		(start 137.608564 -257.102102)
		(end 137.062464 -257.102102)
		(width 0.13208)
		(layer "F.Cu")
		(net "PEX1_SYS_ERR_R_N")
	)
	(via
		(at 138.453876 -257.474212)
		(size 0.508)
		(drill 0.254)
		(layers "F.Cu" "B.Cu")
		(net "PEX1_SYS_ERR_R_N")
	)
	(segment
		(start 381.786384 -251.158502)
		(end 381.786384 -250.470924)
		(width 0.13208)
		(layer "F.Cu")
		(net "PEX3_DBG_MODE2")
	)
	(segment
		(start 412.699962 -282.599892)
		(end 413.174942 -283.074872)
		(width 0.13208)
		(layer "F.Cu")
		(net "PEX3_DBG_MODE2")
	)
	(segment
		(start 381.786384 -251.956824)
		(end 381.786384 -251.158502)
		(width 0.13208)
		(layer "F.Cu")
		(net "PEX3_DBG_MODE2")
	)
	(via
		(at 413.174942 -283.074872)
		(size 0.4064)
		(drill 0.2032)
		(layers "F.Cu" "B.Cu")
		(net "PEX3_DBG_MODE2")
	)
	(via
		(at 409.411678 -267.544296)
		(size 0.6604)
		(drill 0.3302)
		(layers "F.Cu" "B.Cu")
		(net "PEX3_DBG_MODE2")
	)
	(via
		(at 381.786384 -251.158502)
		(size 0.508)
		(drill 0.254)
		(layers "F.Cu" "B.Cu")
		(net "PEX3_DBG_MODE2")
	)
	(segment
		(start 384.159252 -255.439418)
		(end 397.3068 -255.439418)
		(width 0.13208)
		(layer "B.Cu")
		(net "PEX3_DBG_MODE2")
	)
	(segment
		(start 383.54381 -254.823976)
		(end 384.159252 -255.439418)
		(width 0.13208)
		(layer "B.Cu")
		(net "PEX3_DBG_MODE2")
	)
	(segment
		(start 397.3068 -255.439418)
		(end 409.411678 -267.544296)
		(width 0.13208)
		(layer "B.Cu")
		(net "PEX3_DBG_MODE2")
	)
	(segment
		(start 414.137856 -282.111958)
		(end 413.174942 -283.074872)
		(width 0.13208)
		(layer "B.Cu")
		(net "PEX3_DBG_MODE2")
	)
	(segment
		(start 414.137856 -272.028666)
		(end 414.137856 -282.111958)
		(width 0.13208)
		(layer "B.Cu")
		(net "PEX3_DBG_MODE2")
	)
	(segment
		(start 381.685292 -254.823976)
		(end 383.54381 -254.823976)
		(width 0.13208)
		(layer "B.Cu")
		(net "PEX3_DBG_MODE2")
	)
	(segment
		(start 381.293878 -251.651008)
		(end 381.293878 -254.432562)
		(width 0.13208)
		(layer "B.Cu")
		(net "PEX3_DBG_MODE2")
	)
	(segment
		(start 381.786384 -251.158502)
		(end 381.293878 -251.651008)
		(width 0.13208)
		(layer "B.Cu")
		(net "PEX3_DBG_MODE2")
	)
	(segment
		(start 409.411678 -267.544296)
		(end 409.653486 -267.544296)
		(width 0.13208)
		(layer "B.Cu")
		(net "PEX3_DBG_MODE2")
	)
	(segment
		(start 409.653486 -267.544296)
		(end 414.137856 -272.028666)
		(width 0.13208)
		(layer "B.Cu")
		(net "PEX3_DBG_MODE2")
	)
	(segment
		(start 381.293878 -254.432562)
		(end 381.685292 -254.823976)
		(width 0.13208)
		(layer "B.Cu")
		(net "PEX3_DBG_MODE2")
	)
	(segment
		(start 211.398866 -203.01712)
		(end 211.200746 -202.819)
		(width 0.13208)
		(layer "F.Cu")
		(net "SMB_NIC5_R_SDA")
	)
	(segment
		(start 216.835736 -217.00109)
		(end 216.835736 -217.286586)
		(width 0.13208)
		(layer "F.Cu")
		(net "SMB_NIC5_R_SDA")
	)
	(segment
		(start 215.489536 -216.583514)
		(end 215.655652 -216.74963)
		(width 0.13208)
		(layer "F.Cu")
		(net "SMB_NIC5_R_SDA")
	)
	(segment
		(start 209.423 -203.327)
		(end 210.566254 -203.327)
		(width 0.13208)
		(layer "F.Cu")
		(net "SMB_NIC5_R_SDA")
	)
	(segment
		(start 215.655652 -216.74963)
		(end 216.584276 -216.74963)
		(width 0.13208)
		(layer "F.Cu")
		(net "SMB_NIC5_R_SDA")
	)
	(segment
		(start 212.522054 -203.01712)
		(end 211.398866 -203.01712)
		(width 0.13208)
		(layer "F.Cu")
		(net "SMB_NIC5_R_SDA")
	)
	(segment
		(start 210.566254 -203.327)
		(end 210.83905 -203.054204)
		(width 0.13208)
		(layer "F.Cu")
		(net "SMB_NIC5_R_SDA")
	)
	(segment
		(start 216.584276 -216.74963)
		(end 216.835736 -217.00109)
		(width 0.13208)
		(layer "F.Cu")
		(net "SMB_NIC5_R_SDA")
	)
	(segment
		(start 215.489536 -216.270586)
		(end 215.489536 -216.583514)
		(width 0.13208)
		(layer "F.Cu")
		(net "SMB_NIC5_R_SDA")
	)
	(segment
		(start 211.200746 -202.819)
		(end 210.83905 -202.819)
		(width 0.13208)
		(layer "F.Cu")
		(net "SMB_NIC5_R_SDA")
	)
	(segment
		(start 210.83905 -203.054204)
		(end 210.83905 -202.819)
		(width 0.13208)
		(layer "F.Cu")
		(net "SMB_NIC5_R_SDA")
	)
	(via
		(at 215.489536 -216.270586)
		(size 0.508)
		(drill 0.254)
		(layers "F.Cu" "B.Cu")
		(net "SMB_NIC5_R_SDA")
	)
	(via
		(at 209.423 -203.327)
		(size 0.508)
		(drill 0.254)
		(layers "F.Cu" "B.Cu")
		(net "SMB_NIC5_R_SDA")
	)
	(segment
		(start 209.423 -203.327)
		(end 209.82305 -202.92695)
		(width 0.13208)
		(layer "B.Cu")
		(net "SMB_NIC5_R_SDA")
	)
	(segment
		(start 209.82305 -202.92695)
		(end 212.09 -202.92695)
		(width 0.13208)
		(layer "B.Cu")
		(net "SMB_NIC5_R_SDA")
	)
	(segment
		(start 212.344 -215.8492)
		(end 211.911946 -215.8492)
		(width 0.15494)
		(layer "In7.Cu")
		(net "SMB_NIC5_R_SDA")
	)
	(segment
		(start 211.06003 -205.95463)
		(end 211.06003 -205.774798)
		(width 0.15494)
		(layer "In7.Cu")
		(net "SMB_NIC5_R_SDA")
	)
	(segment
		(start 211.85378 -209.62366)
		(end 211.85378 -206.74838)
		(width 0.15494)
		(layer "In7.Cu")
		(net "SMB_NIC5_R_SDA")
	)
	(segment
		(start 215.489536 -216.270586)
		(end 214.568532 -216.270586)
		(width 0.15494)
		(layer "In7.Cu")
		(net "SMB_NIC5_R_SDA")
	)
	(segment
		(start 211.392008 -215.329262)
		(end 211.392008 -210.085432)
		(width 0.15494)
		(layer "In7.Cu")
		(net "SMB_NIC5_R_SDA")
	)
	(segment
		(start 211.911946 -215.8492)
		(end 211.392008 -215.329262)
		(width 0.15494)
		(layer "In7.Cu")
		(net "SMB_NIC5_R_SDA")
	)
	(segment
		(start 210.975194 -205.130146)
		(end 210.555586 -205.549754)
		(width 0.15494)
		(layer "In7.Cu")
		(net "SMB_NIC5_R_SDA")
	)
	(segment
		(start 212.4456 -215.7476)
		(end 212.344 -215.8492)
		(width 0.15494)
		(layer "In7.Cu")
		(net "SMB_NIC5_R_SDA")
	)
	(segment
		(start 210.375754 -205.549754)
		(end 209.423 -204.597)
		(width 0.15494)
		(layer "In7.Cu")
		(net "SMB_NIC5_R_SDA")
	)
	(segment
		(start 211.165694 -205.130146)
		(end 210.975194 -205.130146)
		(width 0.15494)
		(layer "In7.Cu")
		(net "SMB_NIC5_R_SDA")
	)
	(segment
		(start 211.06003 -205.774798)
		(end 211.339938 -205.49489)
		(width 0.15494)
		(layer "In7.Cu")
		(net "SMB_NIC5_R_SDA")
	)
	(segment
		(start 211.339938 -205.30439)
		(end 211.165694 -205.130146)
		(width 0.15494)
		(layer "In7.Cu")
		(net "SMB_NIC5_R_SDA")
	)
	(segment
		(start 209.423 -204.597)
		(end 209.423 -203.327)
		(width 0.15494)
		(layer "In7.Cu")
		(net "SMB_NIC5_R_SDA")
	)
	(segment
		(start 210.555586 -205.549754)
		(end 210.375754 -205.549754)
		(width 0.15494)
		(layer "In7.Cu")
		(net "SMB_NIC5_R_SDA")
	)
	(segment
		(start 211.392008 -210.085432)
		(end 211.85378 -209.62366)
		(width 0.15494)
		(layer "In7.Cu")
		(net "SMB_NIC5_R_SDA")
	)
	(segment
		(start 214.045546 -215.7476)
		(end 212.4456 -215.7476)
		(width 0.15494)
		(layer "In7.Cu")
		(net "SMB_NIC5_R_SDA")
	)
	(segment
		(start 211.339938 -205.49489)
		(end 211.339938 -205.30439)
		(width 0.15494)
		(layer "In7.Cu")
		(net "SMB_NIC5_R_SDA")
	)
	(segment
		(start 211.85378 -206.74838)
		(end 211.06003 -205.95463)
		(width 0.15494)
		(layer "In7.Cu")
		(net "SMB_NIC5_R_SDA")
	)
	(segment
		(start 214.568532 -216.270586)
		(end 214.045546 -215.7476)
		(width 0.15494)
		(layer "In7.Cu")
		(net "SMB_NIC5_R_SDA")
	)
	(segment
		(start 15.264892 -25.390094)
		(end 14.191234 -25.390094)
		(width 0.13208)
		(layer "F.Cu")
		(net "SSD0_PWRDIS_R")
	)
	(segment
		(start 337.125818 -250.50242)
		(end 344.019378 -243.60886)
		(width 0.13208)
		(layer "F.Cu")
		(net "SSD0_PWRDIS_R")
	)
	(segment
		(start 19.762216 -24.353266)
		(end 20.746212 -24.353266)
		(width 0.13208)
		(layer "F.Cu")
		(net "SSD0_PWRDIS_R")
	)
	(segment
		(start 21.067268 -25.041098)
		(end 21.541232 -25.515062)
		(width 0.13208)
		(layer "F.Cu")
		(net "SSD0_PWRDIS_R")
	)
	(segment
		(start 344.019378 -241.990626)
		(end 344.918792 -241.091212)
		(width 0.13208)
		(layer "F.Cu")
		(net "SSD0_PWRDIS_R")
	)
	(segment
		(start 20.746212 -24.353266)
		(end 21.067268 -24.674322)
		(width 0.13208)
		(layer "F.Cu")
		(net "SSD0_PWRDIS_R")
	)
	(segment
		(start 21.067268 -24.674322)
		(end 21.067268 -25.041098)
		(width 0.13208)
		(layer "F.Cu")
		(net "SSD0_PWRDIS_R")
	)
	(segment
		(start 337.125818 -251.020834)
		(end 337.125818 -250.50242)
		(width 0.13208)
		(layer "F.Cu")
		(net "SSD0_PWRDIS_R")
	)
	(segment
		(start 344.019378 -243.60886)
		(end 344.019378 -241.990626)
		(width 0.13208)
		(layer "F.Cu")
		(net "SSD0_PWRDIS_R")
	)
	(via
		(at 14.191234 -25.390094)
		(size 0.508)
		(drill 0.254)
		(layers "F.Cu" "B.Cu")
		(net "SSD0_PWRDIS_R")
	)
	(via
		(at 337.125818 -251.020834)
		(size 0.508)
		(drill 0.254)
		(layers "F.Cu" "B.Cu")
		(net "SSD0_PWRDIS_R")
	)
	(via
		(at 19.762216 -24.353266)
		(size 0.508)
		(drill 0.254)
		(layers "F.Cu" "B.Cu")
		(net "SSD0_PWRDIS_R")
	)
	(via
		(at 33.889696 -217.754962)
		(size 0.508)
		(drill 0.254)
		(layers "F.Cu" "B.Cu")
		(net "SSD0_PWRDIS_R")
	)
	(segment
		(start 33.889696 -217.754962)
		(end 32.1183 -215.983566)
		(width 0.15494)
		(layer "In5.Cu")
		(net "SSD0_PWRDIS_R")
	)
	(segment
		(start 17.937734 -24.886412)
		(end 18.459958 -24.364188)
		(width 0.15494)
		(layer "In5.Cu")
		(net "SSD0_PWRDIS_R")
	)
	(segment
		(start 25.152096 -33.997392)
		(end 25.152096 -28.377642)
		(width 0.15494)
		(layer "In5.Cu")
		(net "SSD0_PWRDIS_R")
	)
	(segment
		(start 14.191234 -25.390094)
		(end 14.694916 -24.886412)
		(width 0.15494)
		(layer "In5.Cu")
		(net "SSD0_PWRDIS_R")
	)
	(segment
		(start 37.50056 -46.345856)
		(end 25.152096 -33.997392)
		(width 0.15494)
		(layer "In5.Cu")
		(net "SSD0_PWRDIS_R")
	)
	(segment
		(start 32.1183 -215.983566)
		(end 32.1183 -204.333856)
		(width 0.15494)
		(layer "In5.Cu")
		(net "SSD0_PWRDIS_R")
	)
	(segment
		(start 26.915364 -166.71798)
		(end 26.480008 -165.666928)
		(width 0.15494)
		(layer "In5.Cu")
		(net "SSD0_PWRDIS_R")
	)
	(segment
		(start 25.152096 -28.377642)
		(end 21.12772 -24.353266)
		(width 0.15494)
		(layer "In5.Cu")
		(net "SSD0_PWRDIS_R")
	)
	(segment
		(start 26.915364 -191.964564)
		(end 26.915364 -166.71798)
		(width 0.15494)
		(layer "In5.Cu")
		(net "SSD0_PWRDIS_R")
	)
	(segment
		(start 14.694916 -24.886412)
		(end 17.937734 -24.886412)
		(width 0.15494)
		(layer "In5.Cu")
		(net "SSD0_PWRDIS_R")
	)
	(segment
		(start 29.701236 -97.705164)
		(end 29.701236 -96.689164)
		(width 0.15494)
		(layer "In5.Cu")
		(net "SSD0_PWRDIS_R")
	)
	(segment
		(start 21.12772 -24.353266)
		(end 19.762216 -24.353266)
		(width 0.15494)
		(layer "In5.Cu")
		(net "SSD0_PWRDIS_R")
	)
	(segment
		(start 37.50056 -88.88984)
		(end 37.50056 -46.345856)
		(width 0.15494)
		(layer "In5.Cu")
		(net "SSD0_PWRDIS_R")
	)
	(segment
		(start 31.290768 -203.506324)
		(end 31.290768 -196.339968)
		(width 0.15494)
		(layer "In5.Cu")
		(net "SSD0_PWRDIS_R")
	)
	(segment
		(start 19.751294 -24.364188)
		(end 19.762216 -24.353266)
		(width 0.15494)
		(layer "In5.Cu")
		(net "SSD0_PWRDIS_R")
	)
	(segment
		(start 29.701236 -96.689164)
		(end 37.50056 -88.88984)
		(width 0.15494)
		(layer "In5.Cu")
		(net "SSD0_PWRDIS_R")
	)
	(segment
		(start 31.290768 -196.339968)
		(end 26.915364 -191.964564)
		(width 0.15494)
		(layer "In5.Cu")
		(net "SSD0_PWRDIS_R")
	)
	(segment
		(start 26.480008 -165.666928)
		(end 26.480008 -100.926392)
		(width 0.15494)
		(layer "In5.Cu")
		(net "SSD0_PWRDIS_R")
	)
	(segment
		(start 18.459958 -24.364188)
		(end 19.751294 -24.364188)
		(width 0.15494)
		(layer "In5.Cu")
		(net "SSD0_PWRDIS_R")
	)
	(segment
		(start 26.480008 -100.926392)
		(end 29.701236 -97.705164)
		(width 0.15494)
		(layer "In5.Cu")
		(net "SSD0_PWRDIS_R")
	)
	(segment
		(start 32.1183 -204.333856)
		(end 31.290768 -203.506324)
		(width 0.15494)
		(layer "In5.Cu")
		(net "SSD0_PWRDIS_R")
	)
	(segment
		(start 275.052028 -253.589282)
		(end 275.591016 -254.12827)
		(width 0.15494)
		(layer "In15.Cu")
		(net "SSD0_PWRDIS_R")
	)
	(segment
		(start 272.956274 -252.58268)
		(end 273.962876 -253.589282)
		(width 0.15494)
		(layer "In15.Cu")
		(net "SSD0_PWRDIS_R")
	)
	(segment
		(start 119.080788 -240.930938)
		(end 137.154158 -240.930938)
		(width 0.15494)
		(layer "In15.Cu")
		(net "SSD0_PWRDIS_R")
	)
	(segment
		(start 151.133556 -235.95838)
		(end 152.226772 -235.95838)
		(width 0.15494)
		(layer "In15.Cu")
		(net "SSD0_PWRDIS_R")
	)
	(segment
		(start 111.64316 -213.580218)
		(end 111.64316 -233.49331)
		(width 0.15494)
		(layer "In15.Cu")
		(net "SSD0_PWRDIS_R")
	)
	(segment
		(start 89.592658 -218.4146)
		(end 95.815658 -212.1916)
		(width 0.15494)
		(layer "In15.Cu")
		(net "SSD0_PWRDIS_R")
	)
	(segment
		(start 106.50347 -211.55533)
		(end 109.618272 -211.55533)
		(width 0.15494)
		(layer "In15.Cu")
		(net "SSD0_PWRDIS_R")
	)
	(segment
		(start 149.415754 -235.24718)
		(end 151.133556 -235.95838)
		(width 0.15494)
		(layer "In15.Cu")
		(net "SSD0_PWRDIS_R")
	)
	(segment
		(start 137.154158 -240.930938)
		(end 142.837916 -235.24718)
		(width 0.15494)
		(layer "In15.Cu")
		(net "SSD0_PWRDIS_R")
	)
	(segment
		(start 33.889696 -217.754962)
		(end 34.549334 -218.4146)
		(width 0.15494)
		(layer "In15.Cu")
		(net "SSD0_PWRDIS_R")
	)
	(segment
		(start 142.837916 -235.24718)
		(end 149.415754 -235.24718)
		(width 0.15494)
		(layer "In15.Cu")
		(net "SSD0_PWRDIS_R")
	)
	(segment
		(start 239.732058 -251.681742)
		(end 240.091976 -251.321824)
		(width 0.15494)
		(layer "In15.Cu")
		(net "SSD0_PWRDIS_R")
	)
	(segment
		(start 188.858144 -249.98172)
		(end 189.747144 -250.87072)
		(width 0.15494)
		(layer "In15.Cu")
		(net "SSD0_PWRDIS_R")
	)
	(segment
		(start 240.091976 -251.321824)
		(end 246.106696 -251.321824)
		(width 0.15494)
		(layer "In15.Cu")
		(net "SSD0_PWRDIS_R")
	)
	(segment
		(start 257.861308 -252.58268)
		(end 272.956274 -252.58268)
		(width 0.15494)
		(layer "In15.Cu")
		(net "SSD0_PWRDIS_R")
	)
	(segment
		(start 326.51827 -254.477266)
		(end 334.565498 -254.477266)
		(width 0.15494)
		(layer "In15.Cu")
		(net "SSD0_PWRDIS_R")
	)
	(segment
		(start 95.815658 -212.1916)
		(end 105.8672 -212.1916)
		(width 0.15494)
		(layer "In15.Cu")
		(net "SSD0_PWRDIS_R")
	)
	(segment
		(start 334.565498 -254.477266)
		(end 337.125818 -251.916946)
		(width 0.15494)
		(layer "In15.Cu")
		(net "SSD0_PWRDIS_R")
	)
	(segment
		(start 178.26863 -242.50269)
		(end 185.74766 -249.98172)
		(width 0.15494)
		(layer "In15.Cu")
		(net "SSD0_PWRDIS_R")
	)
	(segment
		(start 337.125818 -251.916946)
		(end 337.125818 -251.020834)
		(width 0.15494)
		(layer "In15.Cu")
		(net "SSD0_PWRDIS_R")
	)
	(segment
		(start 185.74766 -249.98172)
		(end 188.858144 -249.98172)
		(width 0.15494)
		(layer "In15.Cu")
		(net "SSD0_PWRDIS_R")
	)
	(segment
		(start 307.03012 -253.395734)
		(end 325.436738 -253.395734)
		(width 0.15494)
		(layer "In15.Cu")
		(net "SSD0_PWRDIS_R")
	)
	(segment
		(start 34.549334 -218.4146)
		(end 89.592658 -218.4146)
		(width 0.15494)
		(layer "In15.Cu")
		(net "SSD0_PWRDIS_R")
	)
	(segment
		(start 189.747144 -250.87072)
		(end 224.407476 -250.87072)
		(width 0.15494)
		(layer "In15.Cu")
		(net "SSD0_PWRDIS_R")
	)
	(segment
		(start 306.297584 -254.12827)
		(end 307.03012 -253.395734)
		(width 0.15494)
		(layer "In15.Cu")
		(net "SSD0_PWRDIS_R")
	)
	(segment
		(start 153.404316 -236.44606)
		(end 154.26182 -236.44606)
		(width 0.15494)
		(layer "In15.Cu")
		(net "SSD0_PWRDIS_R")
	)
	(segment
		(start 224.407476 -250.87072)
		(end 224.838006 -250.44019)
		(width 0.15494)
		(layer "In15.Cu")
		(net "SSD0_PWRDIS_R")
	)
	(segment
		(start 109.618272 -211.55533)
		(end 111.64316 -213.580218)
		(width 0.15494)
		(layer "In15.Cu")
		(net "SSD0_PWRDIS_R")
	)
	(segment
		(start 224.838006 -250.44019)
		(end 228.92893 -250.44019)
		(width 0.15494)
		(layer "In15.Cu")
		(net "SSD0_PWRDIS_R")
	)
	(segment
		(start 275.591016 -254.12827)
		(end 306.297584 -254.12827)
		(width 0.15494)
		(layer "In15.Cu")
		(net "SSD0_PWRDIS_R")
	)
	(segment
		(start 111.64316 -233.49331)
		(end 119.080788 -240.930938)
		(width 0.15494)
		(layer "In15.Cu")
		(net "SSD0_PWRDIS_R")
	)
	(segment
		(start 246.970042 -252.18517)
		(end 257.463798 -252.18517)
		(width 0.15494)
		(layer "In15.Cu")
		(net "SSD0_PWRDIS_R")
	)
	(segment
		(start 160.31845 -242.50269)
		(end 178.26863 -242.50269)
		(width 0.15494)
		(layer "In15.Cu")
		(net "SSD0_PWRDIS_R")
	)
	(segment
		(start 273.962876 -253.589282)
		(end 275.052028 -253.589282)
		(width 0.15494)
		(layer "In15.Cu")
		(net "SSD0_PWRDIS_R")
	)
	(segment
		(start 154.26182 -236.44606)
		(end 160.31845 -242.50269)
		(width 0.15494)
		(layer "In15.Cu")
		(net "SSD0_PWRDIS_R")
	)
	(segment
		(start 246.106696 -251.321824)
		(end 246.970042 -252.18517)
		(width 0.15494)
		(layer "In15.Cu")
		(net "SSD0_PWRDIS_R")
	)
	(segment
		(start 230.170482 -251.681742)
		(end 239.732058 -251.681742)
		(width 0.15494)
		(layer "In15.Cu")
		(net "SSD0_PWRDIS_R")
	)
	(segment
		(start 152.226772 -235.95838)
		(end 153.404316 -236.44606)
		(width 0.15494)
		(layer "In15.Cu")
		(net "SSD0_PWRDIS_R")
	)
	(segment
		(start 257.463798 -252.18517)
		(end 257.861308 -252.58268)
		(width 0.15494)
		(layer "In15.Cu")
		(net "SSD0_PWRDIS_R")
	)
	(segment
		(start 325.436738 -253.395734)
		(end 326.51827 -254.477266)
		(width 0.15494)
		(layer "In15.Cu")
		(net "SSD0_PWRDIS_R")
	)
	(segment
		(start 105.8672 -212.1916)
		(end 106.50347 -211.55533)
		(width 0.15494)
		(layer "In15.Cu")
		(net "SSD0_PWRDIS_R")
	)
	(segment
		(start 228.92893 -250.44019)
		(end 230.170482 -251.681742)
		(width 0.15494)
		(layer "In15.Cu")
		(net "SSD0_PWRDIS_R")
	)
	(segment
		(start 130.8989 -174.726092)
		(end 130.971036 -174.900336)
		(width 0.1143)
		(layer "F.Cu")
		(net "CLK_100M_DB2000QL_PEX2_S1_DN")
	)
	(segment
		(start 129.073656 -171.56811)
		(end 130.8989 -173.393354)
		(width 0.1143)
		(layer "F.Cu")
		(net "CLK_100M_DB2000QL_PEX2_S1_DN")
	)
	(segment
		(start 130.8989 -173.393354)
		(end 130.8989 -174.726092)
		(width 0.1143)
		(layer "F.Cu")
		(net "CLK_100M_DB2000QL_PEX2_S1_DN")
	)
	(segment
		(start 129.073656 -171.330112)
		(end 129.073656 -171.56811)
		(width 0.1143)
		(layer "F.Cu")
		(net "CLK_100M_DB2000QL_PEX2_S1_DN")
	)
	(segment
		(start 129.403856 -170.999912)
		(end 129.073656 -171.330112)
		(width 0.1143)
		(layer "F.Cu")
		(net "CLK_100M_DB2000QL_PEX2_S1_DN")
	)
	(segment
		(start 117.560598 -88.77808)
		(end 117.8433 -88.495378)
		(width 0.13462)
		(layer "F.Cu")
		(net "CLK_100M_DB800ZL_SSD6_R_DP")
	)
	(segment
		(start 185.081418 -27.342846)
		(end 184.784492 -27.04592)
		(width 0.13462)
		(layer "F.Cu")
		(net "CLK_100M_DB800ZL_SSD6_R_DP")
	)
	(segment
		(start 184.012586 -27.04592)
		(end 183.868568 -27.189938)
		(width 0.13462)
		(layer "F.Cu")
		(net "CLK_100M_DB800ZL_SSD6_R_DP")
	)
	(segment
		(start 184.784492 -27.04592)
		(end 184.012586 -27.04592)
		(width 0.13462)
		(layer "F.Cu")
		(net "CLK_100M_DB800ZL_SSD6_R_DP")
	)
	(segment
		(start 116.064538 -88.77808)
		(end 117.560598 -88.77808)
		(width 0.13462)
		(layer "F.Cu")
		(net "CLK_100M_DB800ZL_SSD6_R_DP")
	)
	(segment
		(start 115.756436 -88.469978)
		(end 116.064538 -88.77808)
		(width 0.13462)
		(layer "F.Cu")
		(net "CLK_100M_DB800ZL_SSD6_R_DP")
	)
	(segment
		(start 183.868568 -27.189938)
		(end 183.364886 -27.189938)
		(width 0.13462)
		(layer "F.Cu")
		(net "CLK_100M_DB800ZL_SSD6_R_DP")
	)
	(via
		(at 117.8433 -88.495378)
		(size 0.508)
		(drill 0.254)
		(layers "F.Cu" "B.Cu")
		(net "CLK_100M_DB800ZL_SSD6_R_DP")
	)
	(via
		(at 185.081418 -27.342846)
		(size 0.508)
		(drill 0.254)
		(layers "F.Cu" "B.Cu")
		(net "CLK_100M_DB800ZL_SSD6_R_DP")
	)
	(segment
		(start 148.449538 -78.586076)
		(end 134.240524 -78.586076)
		(width 0.1651)
		(layer "In13.Cu")
		(net "CLK_100M_DB800ZL_SSD6_R_DP")
	)
	(segment
		(start 179.395374 -48.572674)
		(end 179.395882 -48.579278)
		(width 0.1651)
		(layer "In13.Cu")
		(net "CLK_100M_DB800ZL_SSD6_R_DP")
	)
	(segment
		(start 185.617612 -30.749494)
		(end 185.731912 -30.863794)
		(width 0.1651)
		(layer "In13.Cu")
		(net "CLK_100M_DB800ZL_SSD6_R_DP")
	)
	(segment
		(start 179.38877 -48.586136)
		(end 180.057044 -59.731402)
		(width 0.1651)
		(layer "In13.Cu")
		(net "CLK_100M_DB800ZL_SSD6_R_DP")
	)
	(segment
		(start 118.130066 -88.782144)
		(end 117.8433 -88.495378)
		(width 0.1651)
		(layer "In13.Cu")
		(net "CLK_100M_DB800ZL_SSD6_R_DP")
	)
	(segment
		(start 185.617612 -31.473394)
		(end 185.617612 -31.968694)
		(width 0.1651)
		(layer "In13.Cu")
		(net "CLK_100M_DB800ZL_SSD6_R_DP")
	)
	(segment
		(start 183.770016 -39.194486)
		(end 183.608218 -39.194486)
		(width 0.1651)
		(layer "In13.Cu")
		(net "CLK_100M_DB800ZL_SSD6_R_DP")
	)
	(segment
		(start 185.368438 -27.055826)
		(end 185.581544 -27.055826)
		(width 0.1651)
		(layer "In13.Cu")
		(net "CLK_100M_DB800ZL_SSD6_R_DP")
	)
	(segment
		(start 184.120028 -38.682676)
		(end 184.120028 -38.844474)
		(width 0.1651)
		(layer "In13.Cu")
		(net "CLK_100M_DB800ZL_SSD6_R_DP")
	)
	(segment
		(start 185.731912 -35.763962)
		(end 184.982358 -36.513516)
		(width 0.1651)
		(layer "In13.Cu")
		(net "CLK_100M_DB800ZL_SSD6_R_DP")
	)
	(segment
		(start 185.731912 -33.302194)
		(end 185.731912 -33.797494)
		(width 0.1651)
		(layer "In13.Cu")
		(net "CLK_100M_DB800ZL_SSD6_R_DP")
	)
	(segment
		(start 163.946332 -77.742288)
		(end 149.293326 -77.742288)
		(width 0.1651)
		(layer "In13.Cu")
		(net "CLK_100M_DB800ZL_SSD6_R_DP")
	)
	(segment
		(start 183.608218 -39.194486)
		(end 183.257698 -39.545006)
		(width 0.1651)
		(layer "In13.Cu")
		(net "CLK_100M_DB800ZL_SSD6_R_DP")
	)
	(segment
		(start 185.731912 -27.701494)
		(end 185.617612 -27.815794)
		(width 0.1651)
		(layer "In13.Cu")
		(net "CLK_100M_DB800ZL_SSD6_R_DP")
	)
	(segment
		(start 185.617612 -33.187894)
		(end 185.731912 -33.302194)
		(width 0.1651)
		(layer "In13.Cu")
		(net "CLK_100M_DB800ZL_SSD6_R_DP")
	)
	(segment
		(start 181.533038 -41.431464)
		(end 179.954174 -43.010328)
		(width 0.1651)
		(layer "In13.Cu")
		(net "CLK_100M_DB800ZL_SSD6_R_DP")
	)
	(segment
		(start 179.703984 -61.984636)
		(end 163.946332 -77.742288)
		(width 0.1651)
		(layer "In13.Cu")
		(net "CLK_100M_DB800ZL_SSD6_R_DP")
	)
	(segment
		(start 185.617612 -33.911794)
		(end 185.617612 -34.407094)
		(width 0.1651)
		(layer "In13.Cu")
		(net "CLK_100M_DB800ZL_SSD6_R_DP")
	)
	(segment
		(start 118.413022 -88.782144)
		(end 118.130066 -88.782144)
		(width 0.1651)
		(layer "In13.Cu")
		(net "CLK_100M_DB800ZL_SSD6_R_DP")
	)
	(segment
		(start 184.982358 -37.982144)
		(end 184.632346 -38.332156)
		(width 0.1651)
		(layer "In13.Cu")
		(net "CLK_100M_DB800ZL_SSD6_R_DP")
	)
	(segment
		(start 182.907686 -40.056816)
		(end 182.745888 -40.056816)
		(width 0.1651)
		(layer "In13.Cu")
		(net "CLK_100M_DB800ZL_SSD6_R_DP")
	)
	(segment
		(start 185.731912 -30.863794)
		(end 185.731912 -31.359094)
		(width 0.1651)
		(layer "In13.Cu")
		(net "CLK_100M_DB800ZL_SSD6_R_DP")
	)
	(segment
		(start 132.02285 -80.80375)
		(end 127.524002 -80.80375)
		(width 0.1651)
		(layer "In13.Cu")
		(net "CLK_100M_DB800ZL_SSD6_R_DP")
	)
	(segment
		(start 118.637558 -88.557608)
		(end 118.413022 -88.782144)
		(width 0.1651)
		(layer "In13.Cu")
		(net "CLK_100M_DB800ZL_SSD6_R_DP")
	)
	(segment
		(start 185.731912 -29.644594)
		(end 185.731912 -30.139894)
		(width 0.1651)
		(layer "In13.Cu")
		(net "CLK_100M_DB800ZL_SSD6_R_DP")
	)
	(segment
		(start 121.171208 -87.156544)
		(end 119.70131 -87.156544)
		(width 0.1651)
		(layer "In13.Cu")
		(net "CLK_100M_DB800ZL_SSD6_R_DP")
	)
	(segment
		(start 185.581544 -27.055826)
		(end 185.731912 -27.206194)
		(width 0.1651)
		(layer "In13.Cu")
		(net "CLK_100M_DB800ZL_SSD6_R_DP")
	)
	(segment
		(start 185.731912 -33.797494)
		(end 185.617612 -33.911794)
		(width 0.1651)
		(layer "In13.Cu")
		(net "CLK_100M_DB800ZL_SSD6_R_DP")
	)
	(segment
		(start 184.632346 -38.332156)
		(end 184.470548 -38.332156)
		(width 0.1651)
		(layer "In13.Cu")
		(net "CLK_100M_DB800ZL_SSD6_R_DP")
	)
	(segment
		(start 185.617612 -32.692594)
		(end 185.617612 -33.187894)
		(width 0.1651)
		(layer "In13.Cu")
		(net "CLK_100M_DB800ZL_SSD6_R_DP")
	)
	(segment
		(start 185.617612 -31.968694)
		(end 185.731912 -32.082994)
		(width 0.1651)
		(layer "In13.Cu")
		(net "CLK_100M_DB800ZL_SSD6_R_DP")
	)
	(segment
		(start 185.731912 -27.206194)
		(end 185.731912 -27.701494)
		(width 0.1651)
		(layer "In13.Cu")
		(net "CLK_100M_DB800ZL_SSD6_R_DP")
	)
	(segment
		(start 179.954174 -43.010328)
		(end 179.554124 -43.931078)
		(width 0.1651)
		(layer "In13.Cu")
		(net "CLK_100M_DB800ZL_SSD6_R_DP")
	)
	(segment
		(start 185.617612 -29.530294)
		(end 185.731912 -29.644594)
		(width 0.1651)
		(layer "In13.Cu")
		(net "CLK_100M_DB800ZL_SSD6_R_DP")
	)
	(segment
		(start 182.745888 -40.056816)
		(end 182.395368 -40.407336)
		(width 0.1651)
		(layer "In13.Cu")
		(net "CLK_100M_DB800ZL_SSD6_R_DP")
	)
	(segment
		(start 181.533038 -41.269666)
		(end 181.533038 -41.431464)
		(width 0.1651)
		(layer "In13.Cu")
		(net "CLK_100M_DB800ZL_SSD6_R_DP")
	)
	(segment
		(start 184.982358 -36.513516)
		(end 184.982358 -37.982144)
		(width 0.1651)
		(layer "In13.Cu")
		(net "CLK_100M_DB800ZL_SSD6_R_DP")
	)
	(segment
		(start 185.731912 -32.082994)
		(end 185.731912 -32.578294)
		(width 0.1651)
		(layer "In13.Cu")
		(net "CLK_100M_DB800ZL_SSD6_R_DP")
	)
	(segment
		(start 185.731912 -32.578294)
		(end 185.617612 -32.692594)
		(width 0.1651)
		(layer "In13.Cu")
		(net "CLK_100M_DB800ZL_SSD6_R_DP")
	)
	(segment
		(start 185.731912 -30.139894)
		(end 185.617612 -30.254194)
		(width 0.1651)
		(layer "In13.Cu")
		(net "CLK_100M_DB800ZL_SSD6_R_DP")
	)
	(segment
		(start 179.554124 -43.931078)
		(end 179.395374 -48.572674)
		(width 0.1651)
		(layer "In13.Cu")
		(net "CLK_100M_DB800ZL_SSD6_R_DP")
	)
	(segment
		(start 184.470548 -38.332156)
		(end 184.120028 -38.682676)
		(width 0.1651)
		(layer "In13.Cu")
		(net "CLK_100M_DB800ZL_SSD6_R_DP")
	)
	(segment
		(start 185.617612 -30.254194)
		(end 185.617612 -30.749494)
		(width 0.1651)
		(layer "In13.Cu")
		(net "CLK_100M_DB800ZL_SSD6_R_DP")
	)
	(segment
		(start 183.257698 -39.545006)
		(end 183.257698 -39.706804)
		(width 0.1651)
		(layer "In13.Cu")
		(net "CLK_100M_DB800ZL_SSD6_R_DP")
	)
	(segment
		(start 118.637558 -88.220296)
		(end 118.637558 -88.557608)
		(width 0.1651)
		(layer "In13.Cu")
		(net "CLK_100M_DB800ZL_SSD6_R_DP")
	)
	(segment
		(start 127.524002 -80.80375)
		(end 121.171208 -87.156544)
		(width 0.1651)
		(layer "In13.Cu")
		(net "CLK_100M_DB800ZL_SSD6_R_DP")
	)
	(segment
		(start 185.731912 -34.521394)
		(end 185.731912 -35.763962)
		(width 0.1651)
		(layer "In13.Cu")
		(net "CLK_100M_DB800ZL_SSD6_R_DP")
	)
	(segment
		(start 183.257698 -39.706804)
		(end 182.907686 -40.056816)
		(width 0.1651)
		(layer "In13.Cu")
		(net "CLK_100M_DB800ZL_SSD6_R_DP")
	)
	(segment
		(start 134.240524 -78.586076)
		(end 132.02285 -80.80375)
		(width 0.1651)
		(layer "In13.Cu")
		(net "CLK_100M_DB800ZL_SSD6_R_DP")
	)
	(segment
		(start 182.395368 -40.407336)
		(end 182.395368 -40.569134)
		(width 0.1651)
		(layer "In13.Cu")
		(net "CLK_100M_DB800ZL_SSD6_R_DP")
	)
	(segment
		(start 184.120028 -38.844474)
		(end 183.770016 -39.194486)
		(width 0.1651)
		(layer "In13.Cu")
		(net "CLK_100M_DB800ZL_SSD6_R_DP")
	)
	(segment
		(start 185.617612 -27.815794)
		(end 185.617612 -28.311094)
		(width 0.1651)
		(layer "In13.Cu")
		(net "CLK_100M_DB800ZL_SSD6_R_DP")
	)
	(segment
		(start 179.389786 -48.585882)
		(end 179.38877 -48.586136)
		(width 0.1651)
		(layer "In13.Cu")
		(net "CLK_100M_DB800ZL_SSD6_R_DP")
	)
	(segment
		(start 185.731912 -28.425394)
		(end 185.731912 -28.920694)
		(width 0.1651)
		(layer "In13.Cu")
		(net "CLK_100M_DB800ZL_SSD6_R_DP")
	)
	(segment
		(start 185.617612 -28.311094)
		(end 185.731912 -28.425394)
		(width 0.1651)
		(layer "In13.Cu")
		(net "CLK_100M_DB800ZL_SSD6_R_DP")
	)
	(segment
		(start 185.081418 -27.342846)
		(end 185.368438 -27.055826)
		(width 0.1651)
		(layer "In13.Cu")
		(net "CLK_100M_DB800ZL_SSD6_R_DP")
	)
	(segment
		(start 149.293326 -77.742288)
		(end 148.449538 -78.586076)
		(width 0.1651)
		(layer "In13.Cu")
		(net "CLK_100M_DB800ZL_SSD6_R_DP")
	)
	(segment
		(start 182.045356 -40.919146)
		(end 181.883558 -40.919146)
		(width 0.1651)
		(layer "In13.Cu")
		(net "CLK_100M_DB800ZL_SSD6_R_DP")
	)
	(segment
		(start 185.731912 -28.920694)
		(end 185.617612 -29.034994)
		(width 0.1651)
		(layer "In13.Cu")
		(net "CLK_100M_DB800ZL_SSD6_R_DP")
	)
	(segment
		(start 185.617612 -34.407094)
		(end 185.731912 -34.521394)
		(width 0.1651)
		(layer "In13.Cu")
		(net "CLK_100M_DB800ZL_SSD6_R_DP")
	)
	(segment
		(start 182.395368 -40.569134)
		(end 182.045356 -40.919146)
		(width 0.1651)
		(layer "In13.Cu")
		(net "CLK_100M_DB800ZL_SSD6_R_DP")
	)
	(segment
		(start 119.70131 -87.156544)
		(end 118.637558 -88.220296)
		(width 0.1651)
		(layer "In13.Cu")
		(net "CLK_100M_DB800ZL_SSD6_R_DP")
	)
	(segment
		(start 180.057044 -59.731402)
		(end 179.703984 -61.984636)
		(width 0.1651)
		(layer "In13.Cu")
		(net "CLK_100M_DB800ZL_SSD6_R_DP")
	)
	(segment
		(start 185.617612 -29.034994)
		(end 185.617612 -29.530294)
		(width 0.1651)
		(layer "In13.Cu")
		(net "CLK_100M_DB800ZL_SSD6_R_DP")
	)
	(segment
		(start 185.731912 -31.359094)
		(end 185.617612 -31.473394)
		(width 0.1651)
		(layer "In13.Cu")
		(net "CLK_100M_DB800ZL_SSD6_R_DP")
	)
	(segment
		(start 181.883558 -40.919146)
		(end 181.533038 -41.269666)
		(width 0.1651)
		(layer "In13.Cu")
		(net "CLK_100M_DB800ZL_SSD6_R_DP")
	)
	(segment
		(start 179.395882 -48.579278)
		(end 179.389786 -48.585882)
		(width 0.1651)
		(layer "In13.Cu")
		(net "CLK_100M_DB800ZL_SSD6_R_DP")
	)
	(segment
		(start 247.3706 -186.4614)
		(end 281.3812 -186.4614)
		(width 0.13208)
		(layer "F.Cu")
		(net "PEX1_MODE_SEL1")
	)
	(segment
		(start 242.33251 -190.41491)
		(end 242.5446 -190.627)
		(width 0.13208)
		(layer "F.Cu")
		(net "PEX1_MODE_SEL1")
	)
	(segment
		(start 293.407084 -177.712116)
		(end 293.407084 -177.670714)
		(width 0.13208)
		(layer "F.Cu")
		(net "PEX1_MODE_SEL1")
	)
	(segment
		(start 242.33251 -189.04331)
		(end 242.33251 -190.41491)
		(width 0.13208)
		(layer "F.Cu")
		(net "PEX1_MODE_SEL1")
	)
	(segment
		(start 288.8234 -179.0192)
		(end 292.1 -179.0192)
		(width 0.13208)
		(layer "F.Cu")
		(net "PEX1_MODE_SEL1")
	)
	(segment
		(start 409.200858 -178.848258)
		(end 409.6512 -179.2986)
		(width 0.13208)
		(layer "F.Cu")
		(net "PEX1_MODE_SEL1")
	)
	(segment
		(start 224.052892 -188.030358)
		(end 224.42805 -187.6552)
		(width 0.13208)
		(layer "F.Cu")
		(net "PEX1_MODE_SEL1")
	)
	(segment
		(start 409.200858 -177.778918)
		(end 409.200858 -178.848258)
		(width 0.13208)
		(layer "F.Cu")
		(net "PEX1_MODE_SEL1")
	)
	(segment
		(start 237.45952 -186.163966)
		(end 239.453166 -186.163966)
		(width 0.13208)
		(layer "F.Cu")
		(net "PEX1_MODE_SEL1")
	)
	(segment
		(start 239.453166 -186.163966)
		(end 242.33251 -189.04331)
		(width 0.13208)
		(layer "F.Cu")
		(net "PEX1_MODE_SEL1")
	)
	(segment
		(start 224.42805 -187.6552)
		(end 225.4758 -187.6552)
		(width 0.13208)
		(layer "F.Cu")
		(net "PEX1_MODE_SEL1")
	)
	(segment
		(start 228.1936 -184.9374)
		(end 236.232954 -184.9374)
		(width 0.13208)
		(layer "F.Cu")
		(net "PEX1_MODE_SEL1")
	)
	(segment
		(start 224.052892 -188.35751)
		(end 224.052892 -188.030358)
		(width 0.13208)
		(layer "F.Cu")
		(net "PEX1_MODE_SEL1")
	)
	(segment
		(start 188.099954 -282.599892)
		(end 188.574934 -283.074872)
		(width 0.13208)
		(layer "F.Cu")
		(net "PEX1_MODE_SEL1")
	)
	(segment
		(start 281.3812 -186.4614)
		(end 288.8234 -179.0192)
		(width 0.13208)
		(layer "F.Cu")
		(net "PEX1_MODE_SEL1")
	)
	(segment
		(start 236.232954 -184.9374)
		(end 237.45952 -186.163966)
		(width 0.13208)
		(layer "F.Cu")
		(net "PEX1_MODE_SEL1")
	)
	(segment
		(start 292.1 -179.0192)
		(end 293.407084 -177.712116)
		(width 0.13208)
		(layer "F.Cu")
		(net "PEX1_MODE_SEL1")
	)
	(segment
		(start 225.4758 -187.6552)
		(end 228.1936 -184.9374)
		(width 0.13208)
		(layer "F.Cu")
		(net "PEX1_MODE_SEL1")
	)
	(segment
		(start 156.698442 -251.158502)
		(end 156.698442 -250.470924)
		(width 0.13208)
		(layer "F.Cu")
		(net "PEX1_MODE_SEL1")
	)
	(segment
		(start 243.205 -190.627)
		(end 247.3706 -186.4614)
		(width 0.13208)
		(layer "F.Cu")
		(net "PEX1_MODE_SEL1")
	)
	(segment
		(start 242.5446 -190.627)
		(end 243.205 -190.627)
		(width 0.13208)
		(layer "F.Cu")
		(net "PEX1_MODE_SEL1")
	)
	(segment
		(start 156.698442 -251.956824)
		(end 156.698442 -251.158502)
		(width 0.13208)
		(layer "F.Cu")
		(net "PEX1_MODE_SEL1")
	)
	(via
		(at 409.6512 -179.2986)
		(size 0.508)
		(drill 0.254)
		(layers "F.Cu" "B.Cu")
		(net "PEX1_MODE_SEL1")
	)
	(via
		(at 188.574934 -283.074872)
		(size 0.4064)
		(drill 0.2032)
		(layers "F.Cu" "B.Cu")
		(net "PEX1_MODE_SEL1")
	)
	(via
		(at 185.64352 -210.546696)
		(size 0.508)
		(drill 0.254)
		(layers "F.Cu" "B.Cu")
		(net "PEX1_MODE_SEL1")
	)
	(via
		(at 224.052892 -188.35751)
		(size 0.508)
		(drill 0.254)
		(layers "F.Cu" "B.Cu")
		(net "PEX1_MODE_SEL1")
	)
	(via
		(at 156.698442 -251.158502)
		(size 0.508)
		(drill 0.254)
		(layers "F.Cu" "B.Cu")
		(net "PEX1_MODE_SEL1")
	)
	(via
		(at 293.407084 -177.670714)
		(size 0.508)
		(drill 0.254)
		(layers "F.Cu" "B.Cu")
		(net "PEX1_MODE_SEL1")
	)
	(segment
		(start 154.232864 -249.058938)
		(end 151.071072 -245.897146)
		(width 0.13208)
		(layer "B.Cu")
		(net "PEX1_MODE_SEL1")
	)
	(segment
		(start 168.748964 -251.158502)
		(end 156.698442 -251.158502)
		(width 0.13208)
		(layer "B.Cu")
		(net "PEX1_MODE_SEL1")
	)
	(segment
		(start 156.698442 -251.158502)
		(end 156.698442 -250.91263)
		(width 0.13208)
		(layer "B.Cu")
		(net "PEX1_MODE_SEL1")
	)
	(segment
		(start 151.071072 -245.897146)
		(end 151.071072 -245.244874)
		(width 0.13208)
		(layer "B.Cu")
		(net "PEX1_MODE_SEL1")
	)
	(segment
		(start 189.527688 -271.937226)
		(end 168.748964 -251.158502)
		(width 0.13208)
		(layer "B.Cu")
		(net "PEX1_MODE_SEL1")
	)
	(segment
		(start 156.698442 -250.91263)
		(end 154.84475 -249.058938)
		(width 0.13208)
		(layer "B.Cu")
		(net "PEX1_MODE_SEL1")
	)
	(segment
		(start 155.407106 -243.523516)
		(end 185.64352 -213.287102)
		(width 0.13208)
		(layer "B.Cu")
		(net "PEX1_MODE_SEL1")
	)
	(segment
		(start 185.64352 -213.287102)
		(end 185.64352 -210.546696)
		(width 0.13208)
		(layer "B.Cu")
		(net "PEX1_MODE_SEL1")
	)
	(segment
		(start 188.574934 -283.074872)
		(end 189.527688 -282.122118)
		(width 0.13208)
		(layer "B.Cu")
		(net "PEX1_MODE_SEL1")
	)
	(segment
		(start 152.79243 -243.523516)
		(end 155.407106 -243.523516)
		(width 0.13208)
		(layer "B.Cu")
		(net "PEX1_MODE_SEL1")
	)
	(segment
		(start 151.071072 -245.244874)
		(end 152.79243 -243.523516)
		(width 0.13208)
		(layer "B.Cu")
		(net "PEX1_MODE_SEL1")
	)
	(segment
		(start 189.527688 -282.122118)
		(end 189.527688 -271.937226)
		(width 0.13208)
		(layer "B.Cu")
		(net "PEX1_MODE_SEL1")
	)
	(segment
		(start 154.84475 -249.058938)
		(end 154.232864 -249.058938)
		(width 0.13208)
		(layer "B.Cu")
		(net "PEX1_MODE_SEL1")
	)
	(segment
		(start 374.83923 -177.387504)
		(end 376.246898 -177.970688)
		(width 0.15494)
		(layer "In13.Cu")
		(net "PEX1_MODE_SEL1")
	)
	(segment
		(start 358.939084 -175.6156)
		(end 359.040684 -175.514)
		(width 0.15494)
		(layer "In13.Cu")
		(net "PEX1_MODE_SEL1")
	)
	(segment
		(start 381.020066 -182.743856)
		(end 408.761184 -182.743856)
		(width 0.15494)
		(layer "In13.Cu")
		(net "PEX1_MODE_SEL1")
	)
	(segment
		(start 359.040684 -175.514)
		(end 360.756454 -175.514)
		(width 0.15494)
		(layer "In13.Cu")
		(net "PEX1_MODE_SEL1")
	)
	(segment
		(start 376.246898 -177.970688)
		(end 381.020066 -182.743856)
		(width 0.15494)
		(layer "In13.Cu")
		(net "PEX1_MODE_SEL1")
	)
	(segment
		(start 327.754742 -184.055766)
		(end 333.381604 -178.428904)
		(width 0.15494)
		(layer "In13.Cu")
		(net "PEX1_MODE_SEL1")
	)
	(segment
		(start 357.614728 -175.414686)
		(end 357.815642 -175.6156)
		(width 0.15494)
		(layer "In13.Cu")
		(net "PEX1_MODE_SEL1")
	)
	(segment
		(start 364.255304 -176.538128)
		(end 364.520226 -176.273206)
		(width 0.15494)
		(layer "In13.Cu")
		(net "PEX1_MODE_SEL1")
	)
	(segment
		(start 336.194654 -178.428904)
		(end 336.56016 -178.79441)
		(width 0.15494)
		(layer "In13.Cu")
		(net "PEX1_MODE_SEL1")
	)
	(segment
		(start 341.711788 -178.79441)
		(end 341.894414 -178.977036)
		(width 0.15494)
		(layer "In13.Cu")
		(net "PEX1_MODE_SEL1")
	)
	(segment
		(start 317.236094 -178.396138)
		(end 322.895722 -184.055766)
		(width 0.15494)
		(layer "In13.Cu")
		(net "PEX1_MODE_SEL1")
	)
	(segment
		(start 322.895722 -184.055766)
		(end 327.754742 -184.055766)
		(width 0.15494)
		(layer "In13.Cu")
		(net "PEX1_MODE_SEL1")
	)
	(segment
		(start 360.756454 -175.514)
		(end 361.780582 -176.538128)
		(width 0.15494)
		(layer "In13.Cu")
		(net "PEX1_MODE_SEL1")
	)
	(segment
		(start 357.815642 -175.6156)
		(end 358.939084 -175.6156)
		(width 0.15494)
		(layer "In13.Cu")
		(net "PEX1_MODE_SEL1")
	)
	(segment
		(start 333.381604 -178.428904)
		(end 336.194654 -178.428904)
		(width 0.15494)
		(layer "In13.Cu")
		(net "PEX1_MODE_SEL1")
	)
	(segment
		(start 297.871642 -178.396138)
		(end 317.236094 -178.396138)
		(width 0.15494)
		(layer "In13.Cu")
		(net "PEX1_MODE_SEL1")
	)
	(segment
		(start 348.507812 -175.414686)
		(end 357.614728 -175.414686)
		(width 0.15494)
		(layer "In13.Cu")
		(net "PEX1_MODE_SEL1")
	)
	(segment
		(start 366.95888 -176.273206)
		(end 368.073178 -177.387504)
		(width 0.15494)
		(layer "In13.Cu")
		(net "PEX1_MODE_SEL1")
	)
	(segment
		(start 409.6512 -181.85384)
		(end 409.6512 -179.2986)
		(width 0.15494)
		(layer "In13.Cu")
		(net "PEX1_MODE_SEL1")
	)
	(segment
		(start 364.520226 -176.273206)
		(end 366.95888 -176.273206)
		(width 0.15494)
		(layer "In13.Cu")
		(net "PEX1_MODE_SEL1")
	)
	(segment
		(start 293.407084 -177.670714)
		(end 293.407084 -177.435002)
		(width 0.15494)
		(layer "In13.Cu")
		(net "PEX1_MODE_SEL1")
	)
	(segment
		(start 408.761184 -182.743856)
		(end 409.6512 -181.85384)
		(width 0.15494)
		(layer "In13.Cu")
		(net "PEX1_MODE_SEL1")
	)
	(segment
		(start 293.94404 -176.898046)
		(end 296.37355 -176.898046)
		(width 0.15494)
		(layer "In13.Cu")
		(net "PEX1_MODE_SEL1")
	)
	(segment
		(start 368.073178 -177.387504)
		(end 374.83923 -177.387504)
		(width 0.15494)
		(layer "In13.Cu")
		(net "PEX1_MODE_SEL1")
	)
	(segment
		(start 296.37355 -176.898046)
		(end 297.871642 -178.396138)
		(width 0.15494)
		(layer "In13.Cu")
		(net "PEX1_MODE_SEL1")
	)
	(segment
		(start 341.894414 -178.977036)
		(end 344.945462 -178.977036)
		(width 0.15494)
		(layer "In13.Cu")
		(net "PEX1_MODE_SEL1")
	)
	(segment
		(start 336.56016 -178.79441)
		(end 341.711788 -178.79441)
		(width 0.15494)
		(layer "In13.Cu")
		(net "PEX1_MODE_SEL1")
	)
	(segment
		(start 293.407084 -177.435002)
		(end 293.94404 -176.898046)
		(width 0.15494)
		(layer "In13.Cu")
		(net "PEX1_MODE_SEL1")
	)
	(segment
		(start 361.780582 -176.538128)
		(end 364.255304 -176.538128)
		(width 0.15494)
		(layer "In13.Cu")
		(net "PEX1_MODE_SEL1")
	)
	(segment
		(start 344.945462 -178.977036)
		(end 348.507812 -175.414686)
		(width 0.15494)
		(layer "In13.Cu")
		(net "PEX1_MODE_SEL1")
	)
	(segment
		(start 209.22234 -197.07987)
		(end 209.1436 -197.00113)
		(width 0.15494)
		(layer "In15.Cu")
		(net "PEX1_MODE_SEL1")
	)
	(segment
		(start 213.686644 -194.616324)
		(end 211.223098 -197.07987)
		(width 0.15494)
		(layer "In15.Cu")
		(net "PEX1_MODE_SEL1")
	)
	(segment
		(start 211.223098 -197.07987)
		(end 209.22234 -197.07987)
		(width 0.15494)
		(layer "In15.Cu")
		(net "PEX1_MODE_SEL1")
	)
	(segment
		(start 187.040774 -209.149442)
		(end 185.64352 -210.546696)
		(width 0.15494)
		(layer "In15.Cu")
		(net "PEX1_MODE_SEL1")
	)
	(segment
		(start 224.840038 -188.670184)
		(end 225.584512 -189.414658)
		(width 0.15494)
		(layer "In15.Cu")
		(net "PEX1_MODE_SEL1")
	)
	(segment
		(start 214.583518 -194.616324)
		(end 213.686644 -194.616324)
		(width 0.15494)
		(layer "In15.Cu")
		(net "PEX1_MODE_SEL1")
	)
	(segment
		(start 225.584512 -189.414658)
		(end 225.584512 -194.523106)
		(width 0.15494)
		(layer "In15.Cu")
		(net "PEX1_MODE_SEL1")
	)
	(segment
		(start 217.98534 -198.85787)
		(end 217.226134 -198.098664)
		(width 0.15494)
		(layer "In15.Cu")
		(net "PEX1_MODE_SEL1")
	)
	(segment
		(start 221.249748 -198.85787)
		(end 217.98534 -198.85787)
		(width 0.15494)
		(layer "In15.Cu")
		(net "PEX1_MODE_SEL1")
	)
	(segment
		(start 217.226134 -198.098664)
		(end 217.226134 -197.25894)
		(width 0.15494)
		(layer "In15.Cu")
		(net "PEX1_MODE_SEL1")
	)
	(segment
		(start 202.879198 -197.00113)
		(end 190.730886 -209.149442)
		(width 0.15494)
		(layer "In15.Cu")
		(net "PEX1_MODE_SEL1")
	)
	(segment
		(start 224.052892 -188.35751)
		(end 224.365566 -188.670184)
		(width 0.15494)
		(layer "In15.Cu")
		(net "PEX1_MODE_SEL1")
	)
	(segment
		(start 217.226134 -197.25894)
		(end 214.583518 -194.616324)
		(width 0.15494)
		(layer "In15.Cu")
		(net "PEX1_MODE_SEL1")
	)
	(segment
		(start 190.730886 -209.149442)
		(end 187.040774 -209.149442)
		(width 0.15494)
		(layer "In15.Cu")
		(net "PEX1_MODE_SEL1")
	)
	(segment
		(start 209.1436 -197.00113)
		(end 202.879198 -197.00113)
		(width 0.15494)
		(layer "In15.Cu")
		(net "PEX1_MODE_SEL1")
	)
	(segment
		(start 225.584512 -194.523106)
		(end 221.249748 -198.85787)
		(width 0.15494)
		(layer "In15.Cu")
		(net "PEX1_MODE_SEL1")
	)
	(segment
		(start 224.365566 -188.670184)
		(end 224.840038 -188.670184)
		(width 0.15494)
		(layer "In15.Cu")
		(net "PEX1_MODE_SEL1")
	)
	(segment
		(start 416.499802 -282.599892)
		(end 416.974782 -283.074872)
		(width 0.13208)
		(layer "F.Cu")
		(net "PEX3_DBG_MODE4")
	)
	(segment
		(start 386.866384 -251.158502)
		(end 386.866384 -250.470924)
		(width 0.13208)
		(layer "F.Cu")
		(net "PEX3_DBG_MODE4")
	)
	(segment
		(start 386.866384 -251.956824)
		(end 386.866384 -251.158502)
		(width 0.13208)
		(layer "F.Cu")
		(net "PEX3_DBG_MODE4")
	)
	(via
		(at 416.974782 -283.074872)
		(size 0.4064)
		(drill 0.2032)
		(layers "F.Cu" "B.Cu")
		(net "PEX3_DBG_MODE4")
	)
	(via
		(at 386.866384 -251.158502)
		(size 0.508)
		(drill 0.254)
		(layers "F.Cu" "B.Cu")
		(net "PEX3_DBG_MODE4")
	)
	(segment
		(start 386.393436 -253.696978)
		(end 386.706364 -254.009906)
		(width 0.13208)
		(layer "B.Cu")
		(net "PEX3_DBG_MODE4")
	)
	(segment
		(start 400.720306 -254.009906)
		(end 418.880036 -272.169636)
		(width 0.13208)
		(layer "B.Cu")
		(net "PEX3_DBG_MODE4")
	)
	(segment
		(start 418.017198 -282.591002)
		(end 417.755324 -282.591002)
		(width 0.13208)
		(layer "B.Cu")
		(net "PEX3_DBG_MODE4")
	)
	(segment
		(start 386.706364 -254.009906)
		(end 400.720306 -254.009906)
		(width 0.13208)
		(layer "B.Cu")
		(net "PEX3_DBG_MODE4")
	)
	(segment
		(start 386.866384 -251.158502)
		(end 386.393436 -251.63145)
		(width 0.13208)
		(layer "B.Cu")
		(net "PEX3_DBG_MODE4")
	)
	(segment
		(start 386.393436 -251.63145)
		(end 386.393436 -253.696978)
		(width 0.13208)
		(layer "B.Cu")
		(net "PEX3_DBG_MODE4")
	)
	(segment
		(start 417.271454 -283.074872)
		(end 416.974782 -283.074872)
		(width 0.13208)
		(layer "B.Cu")
		(net "PEX3_DBG_MODE4")
	)
	(segment
		(start 418.880036 -272.169636)
		(end 418.880036 -281.728164)
		(width 0.13208)
		(layer "B.Cu")
		(net "PEX3_DBG_MODE4")
	)
	(segment
		(start 417.755324 -282.591002)
		(end 417.271454 -283.074872)
		(width 0.13208)
		(layer "B.Cu")
		(net "PEX3_DBG_MODE4")
	)
	(segment
		(start 418.880036 -281.728164)
		(end 418.017198 -282.591002)
		(width 0.13208)
		(layer "B.Cu")
		(net "PEX3_DBG_MODE4")
	)
	(segment
		(start 151.335486 -389.998204)
		(end 151.335486 -389.161782)
		(width 0.13208)
		(layer "F.Cu")
		(net "GPU_FPGA_EROT_RECOV_R_N")
	)
	(via
		(at 157.918658 -395.4272)
		(size 0.508)
		(drill 0.254)
		(layers "F.Cu" "B.Cu")
		(net "GPU_FPGA_EROT_RECOV_R_N")
	)
	(via
		(at 151.335486 -389.161782)
		(size 0.508)
		(drill 0.254)
		(layers "F.Cu" "B.Cu")
		(net "GPU_FPGA_EROT_RECOV_R_N")
	)
	(segment
		(start 157.381194 -391.677906)
		(end 154.86507 -389.161782)
		(width 0.13208)
		(layer "B.Cu")
		(net "GPU_FPGA_EROT_RECOV_R_N")
	)
	(segment
		(start 157.918658 -395.4272)
		(end 157.381194 -394.889736)
		(width 0.13208)
		(layer "B.Cu")
		(net "GPU_FPGA_EROT_RECOV_R_N")
	)
	(segment
		(start 154.86507 -389.161782)
		(end 151.335486 -389.161782)
		(width 0.13208)
		(layer "B.Cu")
		(net "GPU_FPGA_EROT_RECOV_R_N")
	)
	(segment
		(start 157.381194 -394.889736)
		(end 157.381194 -391.677906)
		(width 0.13208)
		(layer "B.Cu")
		(net "GPU_FPGA_EROT_RECOV_R_N")
	)
	(segment
		(start 157.918658 -395.4272)
		(end 157.918658 -410.098748)
		(width 0.15494)
		(layer "In9.Cu")
		(net "GPU_FPGA_EROT_RECOV_R_N")
	)
	(segment
		(start 157.918658 -410.098748)
		(end 159.910018 -412.090108)
		(width 0.15494)
		(layer "In9.Cu")
		(net "GPU_FPGA_EROT_RECOV_R_N")
	)
	(segment
		(start 201.240898 -57.16397)
		(end 201.240898 -58.364628)
		(width 0.13208)
		(layer "F.Cu")
		(net "P3V3_SSD7_OCP")
	)
	(segment
		(start 201.203306 -59.171586)
		(end 201.044302 -59.012582)
		(width 0.13208)
		(layer "F.Cu")
		(net "P3V3_SSD7_OCP")
	)
	(segment
		(start 201.044302 -59.012582)
		(end 201.044302 -58.561224)
		(width 0.13208)
		(layer "F.Cu")
		(net "P3V3_SSD7_OCP")
	)
	(segment
		(start 201.240898 -58.364628)
		(end 201.044302 -58.561224)
		(width 0.13208)
		(layer "F.Cu")
		(net "P3V3_SSD7_OCP")
	)
	(via
		(at 201.044302 -58.561224)
		(size 0.508)
		(drill 0.254)
		(layers "F.Cu" "B.Cu")
		(net "P3V3_SSD7_OCP")
	)
	(segment
		(start 127.879348 -176.3522)
		(end 127.522224 -176.709324)
		(width 0.1143)
		(layer "F.Cu")
		(net "CLK_100M_DB2000QL_PEX0_S1_DP")
	)
	(segment
		(start 129.971038 -176.40046)
		(end 129.854452 -176.3522)
		(width 0.1143)
		(layer "F.Cu")
		(net "CLK_100M_DB2000QL_PEX0_S1_DP")
	)
	(segment
		(start 129.854452 -176.3522)
		(end 127.879348 -176.3522)
		(width 0.1143)
		(layer "F.Cu")
		(net "CLK_100M_DB2000QL_PEX0_S1_DP")
	)
	(segment
		(start 126.951486 -176.709324)
		(end 126.621286 -177.039524)
		(width 0.1143)
		(layer "F.Cu")
		(net "CLK_100M_DB2000QL_PEX0_S1_DP")
	)
	(segment
		(start 127.522224 -176.709324)
		(end 126.951486 -176.709324)
		(width 0.1143)
		(layer "F.Cu")
		(net "CLK_100M_DB2000QL_PEX0_S1_DP")
	)
	(segment
		(start 93.768418 -27.189938)
		(end 93.264736 -27.189938)
		(width 0.13462)
		(layer "F.Cu")
		(net "CLK_100M_DB800ZL_SSD3_R_DP")
	)
	(segment
		(start 116.070126 -82.78368)
		(end 116.79301 -82.78368)
		(width 0.13462)
		(layer "F.Cu")
		(net "CLK_100M_DB800ZL_SSD3_R_DP")
	)
	(segment
		(start 116.79301 -82.78368)
		(end 117.0813 -82.49539)
		(width 0.13462)
		(layer "F.Cu")
		(net "CLK_100M_DB800ZL_SSD3_R_DP")
	)
	(segment
		(start 93.907356 -27.051)
		(end 93.768418 -27.189938)
		(width 0.13462)
		(layer "F.Cu")
		(net "CLK_100M_DB800ZL_SSD3_R_DP")
	)
	(segment
		(start 94.689422 -27.051)
		(end 93.907356 -27.051)
		(width 0.13462)
		(layer "F.Cu")
		(net "CLK_100M_DB800ZL_SSD3_R_DP")
	)
	(segment
		(start 115.756436 -82.46999)
		(end 116.070126 -82.78368)
		(width 0.13462)
		(layer "F.Cu")
		(net "CLK_100M_DB800ZL_SSD3_R_DP")
	)
	(segment
		(start 94.981268 -27.342846)
		(end 94.689422 -27.051)
		(width 0.13462)
		(layer "F.Cu")
		(net "CLK_100M_DB800ZL_SSD3_R_DP")
	)
	(via
		(at 94.981268 -27.342846)
		(size 0.508)
		(drill 0.254)
		(layers "F.Cu" "B.Cu")
		(net "CLK_100M_DB800ZL_SSD3_R_DP")
	)
	(via
		(at 117.0813 -82.49539)
		(size 0.508)
		(drill 0.254)
		(layers "F.Cu" "B.Cu")
		(net "CLK_100M_DB800ZL_SSD3_R_DP")
	)
	(segment
		(start 105.463086 -39.63797)
		(end 105.41635 -39.792656)
		(width 0.1651)
		(layer "In13.Cu")
		(net "CLK_100M_DB800ZL_SSD3_R_DP")
	)
	(segment
		(start 113.443512 -58.390536)
		(end 111.09325 -60.740798)
		(width 0.1651)
		(layer "In13.Cu")
		(net "CLK_100M_DB800ZL_SSD3_R_DP")
	)
	(segment
		(start 105.804716 -40.276526)
		(end 106.038142 -40.713152)
		(width 0.1651)
		(layer "In13.Cu")
		(net "CLK_100M_DB800ZL_SSD3_R_DP")
	)
	(segment
		(start 115.122198 -60.069222)
		(end 112.771936 -62.419484)
		(width 0.1651)
		(layer "In13.Cu")
		(net "CLK_100M_DB800ZL_SSD3_R_DP")
	)
	(segment
		(start 104.312974 -37.487606)
		(end 104.266238 -37.642292)
		(width 0.1651)
		(layer "In13.Cu")
		(net "CLK_100M_DB800ZL_SSD3_R_DP")
	)
	(segment
		(start 110.45825 -60.105798)
		(end 112.808512 -57.755536)
		(width 0.1651)
		(layer "In13.Cu")
		(net "CLK_100M_DB800ZL_SSD3_R_DP")
	)
	(segment
		(start 106.800142 -42.380154)
		(end 106.954828 -42.42689)
		(width 0.1651)
		(layer "In13.Cu")
		(net "CLK_100M_DB800ZL_SSD3_R_DP")
	)
	(segment
		(start 106.954828 -42.42689)
		(end 106.954574 -42.42689)
		(width 0.1651)
		(layer "In13.Cu")
		(net "CLK_100M_DB800ZL_SSD3_R_DP")
	)
	(segment
		(start 103.924862 -37.004244)
		(end 104.079548 -37.05098)
		(width 0.1651)
		(layer "In13.Cu")
		(net "CLK_100M_DB800ZL_SSD3_R_DP")
	)
	(segment
		(start 103.390192 -34.146998)
		(end 103.504492 -34.261298)
		(width 0.1651)
		(layer "In13.Cu")
		(net "CLK_100M_DB800ZL_SSD3_R_DP")
	)
	(segment
		(start 110.01629 -60.105798)
		(end 110.45825 -60.105798)
		(width 0.1651)
		(layer "In13.Cu")
		(net "CLK_100M_DB800ZL_SSD3_R_DP")
	)
	(segment
		(start 103.390192 -32.432498)
		(end 103.390192 -32.927798)
		(width 0.1651)
		(layer "In13.Cu")
		(net "CLK_100M_DB800ZL_SSD3_R_DP")
	)
	(segment
		(start 111.129826 -56.07685)
		(end 111.331502 -56.07685)
		(width 0.1651)
		(layer "In13.Cu")
		(net "CLK_100M_DB800ZL_SSD3_R_DP")
	)
	(segment
		(start 103.504492 -35.480498)
		(end 103.504492 -35.975798)
		(width 0.1651)
		(layer "In13.Cu")
		(net "CLK_100M_DB800ZL_SSD3_R_DP")
	)
	(segment
		(start 103.737918 -36.412424)
		(end 103.691182 -36.56711)
		(width 0.1651)
		(layer "In13.Cu")
		(net "CLK_100M_DB800ZL_SSD3_R_DP")
	)
	(segment
		(start 96.971358 -27.299412)
		(end 98.191066 -27.299412)
		(width 0.1651)
		(layer "In13.Cu")
		(net "CLK_100M_DB800ZL_SSD3_R_DP")
	)
	(segment
		(start 112.771936 -62.419484)
		(end 112.771936 -62.850776)
		(width 0.1651)
		(layer "In13.Cu")
		(net "CLK_100M_DB800ZL_SSD3_R_DP")
	)
	(segment
		(start 103.504492 -32.318198)
		(end 103.390192 -32.432498)
		(width 0.1651)
		(layer "In13.Cu")
		(net "CLK_100M_DB800ZL_SSD3_R_DP")
	)
	(segment
		(start 123.521724 -70.46976)
		(end 123.521724 -78.611476)
		(width 0.1651)
		(layer "In13.Cu")
		(net "CLK_100M_DB800ZL_SSD3_R_DP")
	)
	(segment
		(start 112.808512 -57.755536)
		(end 113.010188 -57.755536)
		(width 0.1651)
		(layer "In13.Cu")
		(net "CLK_100M_DB800ZL_SSD3_R_DP")
	)
	(segment
		(start 103.504492 -33.537398)
		(end 103.390192 -33.651698)
		(width 0.1651)
		(layer "In13.Cu")
		(net "CLK_100M_DB800ZL_SSD3_R_DP")
	)
	(segment
		(start 118.025164 -64.9732)
		(end 123.521724 -70.46976)
		(width 0.1651)
		(layer "In13.Cu")
		(net "CLK_100M_DB800ZL_SSD3_R_DP")
	)
	(segment
		(start 112.136936 -61.784484)
		(end 114.487198 -59.434222)
		(width 0.1651)
		(layer "In13.Cu")
		(net "CLK_100M_DB800ZL_SSD3_R_DP")
	)
	(segment
		(start 98.191066 -27.299412)
		(end 99.464876 -28.573222)
		(width 0.1651)
		(layer "In13.Cu")
		(net "CLK_100M_DB800ZL_SSD3_R_DP")
	)
	(segment
		(start 113.443512 -58.18886)
		(end 113.443512 -58.390536)
		(width 0.1651)
		(layer "In13.Cu")
		(net "CLK_100M_DB800ZL_SSD3_R_DP")
	)
	(segment
		(start 103.504492 -34.756598)
		(end 103.390192 -34.870898)
		(width 0.1651)
		(layer "In13.Cu")
		(net "CLK_100M_DB800ZL_SSD3_R_DP")
	)
	(segment
		(start 105.22966 -39.201344)
		(end 105.463086 -39.63797)
		(width 0.1651)
		(layer "In13.Cu")
		(net "CLK_100M_DB800ZL_SSD3_R_DP")
	)
	(segment
		(start 106.225086 -41.304972)
		(end 106.379772 -41.351708)
		(width 0.1651)
		(layer "In13.Cu")
		(net "CLK_100M_DB800ZL_SSD3_R_DP")
	)
	(segment
		(start 104.499918 -38.079426)
		(end 104.654604 -38.126162)
		(width 0.1651)
		(layer "In13.Cu")
		(net "CLK_100M_DB800ZL_SSD3_R_DP")
	)
	(segment
		(start 114.826796 -62.441328)
		(end 115.153694 -62.441328)
		(width 0.1651)
		(layer "In13.Cu")
		(net "CLK_100M_DB800ZL_SSD3_R_DP")
	)
	(segment
		(start 106.613198 -41.788334)
		(end 106.566208 -41.94302)
		(width 0.1651)
		(layer "In13.Cu")
		(net "CLK_100M_DB800ZL_SSD3_R_DP")
	)
	(segment
		(start 103.504492 -31.148782)
		(end 103.504492 -32.318198)
		(width 0.1651)
		(layer "In13.Cu")
		(net "CLK_100M_DB800ZL_SSD3_R_DP")
	)
	(segment
		(start 104.654604 -38.126162)
		(end 104.88803 -38.562788)
		(width 0.1651)
		(layer "In13.Cu")
		(net "CLK_100M_DB800ZL_SSD3_R_DP")
	)
	(segment
		(start 103.691182 -36.56711)
		(end 103.924862 -37.004244)
		(width 0.1651)
		(layer "In13.Cu")
		(net "CLK_100M_DB800ZL_SSD3_R_DP")
	)
	(segment
		(start 107.94746 -52.54244)
		(end 109.97438 -54.56936)
		(width 0.1651)
		(layer "In13.Cu")
		(net "CLK_100M_DB800ZL_SSD3_R_DP")
	)
	(segment
		(start 117.375686 -82.789776)
		(end 117.0813 -82.49539)
		(width 0.1651)
		(layer "In13.Cu")
		(net "CLK_100M_DB800ZL_SSD3_R_DP")
	)
	(segment
		(start 103.390192 -32.927798)
		(end 103.504492 -33.042098)
		(width 0.1651)
		(layer "In13.Cu")
		(net "CLK_100M_DB800ZL_SSD3_R_DP")
	)
	(segment
		(start 106.379772 -41.351708)
		(end 106.613198 -41.788334)
		(width 0.1651)
		(layer "In13.Cu")
		(net "CLK_100M_DB800ZL_SSD3_R_DP")
	)
	(segment
		(start 114.487198 -59.434222)
		(end 114.688874 -59.434222)
		(width 0.1651)
		(layer "In13.Cu")
		(net "CLK_100M_DB800ZL_SSD3_R_DP")
	)
	(segment
		(start 105.41635 -39.792656)
		(end 105.65003 -40.22979)
		(width 0.1651)
		(layer "In13.Cu")
		(net "CLK_100M_DB800ZL_SSD3_R_DP")
	)
	(segment
		(start 111.764826 -56.71185)
		(end 109.414564 -59.062112)
		(width 0.1651)
		(layer "In13.Cu")
		(net "CLK_100M_DB800ZL_SSD3_R_DP")
	)
	(segment
		(start 119.343424 -82.789776)
		(end 117.375686 -82.789776)
		(width 0.1651)
		(layer "In13.Cu")
		(net "CLK_100M_DB800ZL_SSD3_R_DP")
	)
	(segment
		(start 106.954574 -42.42689)
		(end 107.94746 -44.283122)
		(width 0.1651)
		(layer "In13.Cu")
		(net "CLK_100M_DB800ZL_SSD3_R_DP")
	)
	(segment
		(start 95.275908 -27.048206)
		(end 96.720152 -27.048206)
		(width 0.1651)
		(layer "In13.Cu")
		(net "CLK_100M_DB800ZL_SSD3_R_DP")
	)
	(segment
		(start 123.521724 -78.611476)
		(end 119.343424 -82.789776)
		(width 0.1651)
		(layer "In13.Cu")
		(net "CLK_100M_DB800ZL_SSD3_R_DP")
	)
	(segment
		(start 113.010188 -57.755536)
		(end 113.443512 -58.18886)
		(width 0.1651)
		(layer "In13.Cu")
		(net "CLK_100M_DB800ZL_SSD3_R_DP")
	)
	(segment
		(start 115.153694 -62.441328)
		(end 117.685566 -64.9732)
		(width 0.1651)
		(layer "In13.Cu")
		(net "CLK_100M_DB800ZL_SSD3_R_DP")
	)
	(segment
		(start 112.771936 -62.850776)
		(end 113.37671 -63.45555)
		(width 0.1651)
		(layer "In13.Cu")
		(net "CLK_100M_DB800ZL_SSD3_R_DP")
	)
	(segment
		(start 107.743498 -57.375806)
		(end 107.743498 -57.822338)
		(width 0.1651)
		(layer "In13.Cu")
		(net "CLK_100M_DB800ZL_SSD3_R_DP")
	)
	(segment
		(start 113.812574 -63.45555)
		(end 114.826796 -62.441328)
		(width 0.1651)
		(layer "In13.Cu")
		(net "CLK_100M_DB800ZL_SSD3_R_DP")
	)
	(segment
		(start 109.97438 -54.56936)
		(end 109.97438 -55.144924)
		(width 0.1651)
		(layer "In13.Cu")
		(net "CLK_100M_DB800ZL_SSD3_R_DP")
	)
	(segment
		(start 104.88803 -38.562788)
		(end 104.841294 -38.717474)
		(width 0.1651)
		(layer "In13.Cu")
		(net "CLK_100M_DB800ZL_SSD3_R_DP")
	)
	(segment
		(start 115.122198 -59.867546)
		(end 115.122198 -60.069222)
		(width 0.1651)
		(layer "In13.Cu")
		(net "CLK_100M_DB800ZL_SSD3_R_DP")
	)
	(segment
		(start 111.09325 -61.182758)
		(end 111.694976 -61.784484)
		(width 0.1651)
		(layer "In13.Cu")
		(net "CLK_100M_DB800ZL_SSD3_R_DP")
	)
	(segment
		(start 94.981268 -27.342846)
		(end 95.275908 -27.048206)
		(width 0.1651)
		(layer "In13.Cu")
		(net "CLK_100M_DB800ZL_SSD3_R_DP")
	)
	(segment
		(start 105.991406 -40.867838)
		(end 106.225086 -41.304972)
		(width 0.1651)
		(layer "In13.Cu")
		(net "CLK_100M_DB800ZL_SSD3_R_DP")
	)
	(segment
		(start 104.841294 -38.717474)
		(end 105.074974 -39.154608)
		(width 0.1651)
		(layer "In13.Cu")
		(net "CLK_100M_DB800ZL_SSD3_R_DP")
	)
	(segment
		(start 103.504492 -35.975798)
		(end 103.737918 -36.412424)
		(width 0.1651)
		(layer "In13.Cu")
		(net "CLK_100M_DB800ZL_SSD3_R_DP")
	)
	(segment
		(start 103.390192 -34.870898)
		(end 103.390192 -35.366198)
		(width 0.1651)
		(layer "In13.Cu")
		(net "CLK_100M_DB800ZL_SSD3_R_DP")
	)
	(segment
		(start 109.414564 -59.504072)
		(end 110.01629 -60.105798)
		(width 0.1651)
		(layer "In13.Cu")
		(net "CLK_100M_DB800ZL_SSD3_R_DP")
	)
	(segment
		(start 108.787184 -58.419492)
		(end 111.129826 -56.07685)
		(width 0.1651)
		(layer "In13.Cu")
		(net "CLK_100M_DB800ZL_SSD3_R_DP")
	)
	(segment
		(start 103.504492 -33.042098)
		(end 103.504492 -33.537398)
		(width 0.1651)
		(layer "In13.Cu")
		(net "CLK_100M_DB800ZL_SSD3_R_DP")
	)
	(segment
		(start 105.074974 -39.154608)
		(end 105.22966 -39.201344)
		(width 0.1651)
		(layer "In13.Cu")
		(net "CLK_100M_DB800ZL_SSD3_R_DP")
	)
	(segment
		(start 106.038142 -40.713152)
		(end 105.991406 -40.867838)
		(width 0.1651)
		(layer "In13.Cu")
		(net "CLK_100M_DB800ZL_SSD3_R_DP")
	)
	(segment
		(start 113.37671 -63.45555)
		(end 113.812574 -63.45555)
		(width 0.1651)
		(layer "In13.Cu")
		(net "CLK_100M_DB800ZL_SSD3_R_DP")
	)
	(segment
		(start 104.079548 -37.05098)
		(end 104.312974 -37.487606)
		(width 0.1651)
		(layer "In13.Cu")
		(net "CLK_100M_DB800ZL_SSD3_R_DP")
	)
	(segment
		(start 117.685566 -64.9732)
		(end 118.025164 -64.9732)
		(width 0.1651)
		(layer "In13.Cu")
		(net "CLK_100M_DB800ZL_SSD3_R_DP")
	)
	(segment
		(start 111.694976 -61.784484)
		(end 112.136936 -61.784484)
		(width 0.1651)
		(layer "In13.Cu")
		(net "CLK_100M_DB800ZL_SSD3_R_DP")
	)
	(segment
		(start 111.764826 -56.510174)
		(end 111.764826 -56.71185)
		(width 0.1651)
		(layer "In13.Cu")
		(net "CLK_100M_DB800ZL_SSD3_R_DP")
	)
	(segment
		(start 108.340652 -58.419492)
		(end 108.787184 -58.419492)
		(width 0.1651)
		(layer "In13.Cu")
		(net "CLK_100M_DB800ZL_SSD3_R_DP")
	)
	(segment
		(start 109.97438 -55.144924)
		(end 107.743498 -57.375806)
		(width 0.1651)
		(layer "In13.Cu")
		(net "CLK_100M_DB800ZL_SSD3_R_DP")
	)
	(segment
		(start 114.688874 -59.434222)
		(end 115.122198 -59.867546)
		(width 0.1651)
		(layer "In13.Cu")
		(net "CLK_100M_DB800ZL_SSD3_R_DP")
	)
	(segment
		(start 103.390192 -35.366198)
		(end 103.504492 -35.480498)
		(width 0.1651)
		(layer "In13.Cu")
		(net "CLK_100M_DB800ZL_SSD3_R_DP")
	)
	(segment
		(start 103.390192 -33.651698)
		(end 103.390192 -34.146998)
		(width 0.1651)
		(layer "In13.Cu")
		(net "CLK_100M_DB800ZL_SSD3_R_DP")
	)
	(segment
		(start 105.65003 -40.22979)
		(end 105.804716 -40.276526)
		(width 0.1651)
		(layer "In13.Cu")
		(net "CLK_100M_DB800ZL_SSD3_R_DP")
	)
	(segment
		(start 106.566208 -41.94302)
		(end 106.800142 -42.380154)
		(width 0.1651)
		(layer "In13.Cu")
		(net "CLK_100M_DB800ZL_SSD3_R_DP")
	)
	(segment
		(start 96.720152 -27.048206)
		(end 96.971358 -27.299412)
		(width 0.1651)
		(layer "In13.Cu")
		(net "CLK_100M_DB800ZL_SSD3_R_DP")
	)
	(segment
		(start 111.331502 -56.07685)
		(end 111.764826 -56.510174)
		(width 0.1651)
		(layer "In13.Cu")
		(net "CLK_100M_DB800ZL_SSD3_R_DP")
	)
	(segment
		(start 99.464876 -28.573222)
		(end 100.928932 -28.573222)
		(width 0.1651)
		(layer "In13.Cu")
		(net "CLK_100M_DB800ZL_SSD3_R_DP")
	)
	(segment
		(start 111.09325 -60.740798)
		(end 111.09325 -61.182758)
		(width 0.1651)
		(layer "In13.Cu")
		(net "CLK_100M_DB800ZL_SSD3_R_DP")
	)
	(segment
		(start 100.928932 -28.573222)
		(end 103.504492 -31.148782)
		(width 0.1651)
		(layer "In13.Cu")
		(net "CLK_100M_DB800ZL_SSD3_R_DP")
	)
	(segment
		(start 109.414564 -59.062112)
		(end 109.414564 -59.504072)
		(width 0.1651)
		(layer "In13.Cu")
		(net "CLK_100M_DB800ZL_SSD3_R_DP")
	)
	(segment
		(start 103.504492 -34.261298)
		(end 103.504492 -34.756598)
		(width 0.1651)
		(layer "In13.Cu")
		(net "CLK_100M_DB800ZL_SSD3_R_DP")
	)
	(segment
		(start 104.266238 -37.642292)
		(end 104.499918 -38.079426)
		(width 0.1651)
		(layer "In13.Cu")
		(net "CLK_100M_DB800ZL_SSD3_R_DP")
	)
	(segment
		(start 107.94746 -44.283122)
		(end 107.94746 -52.54244)
		(width 0.1651)
		(layer "In13.Cu")
		(net "CLK_100M_DB800ZL_SSD3_R_DP")
	)
	(segment
		(start 107.743498 -57.822338)
		(end 108.340652 -58.419492)
		(width 0.1651)
		(layer "In13.Cu")
		(net "CLK_100M_DB800ZL_SSD3_R_DP")
	)
	(segment
		(start 152.634442 -251.158502)
		(end 152.634442 -250.470924)
		(width 0.13208)
		(layer "F.Cu")
		(net "PEX1_MODE_SEL6")
	)
	(segment
		(start 152.634442 -251.956824)
		(end 152.634442 -251.158502)
		(width 0.13208)
		(layer "F.Cu")
		(net "PEX1_MODE_SEL6")
	)
	(segment
		(start 181.44998 -283.549852)
		(end 181.92496 -284.024832)
		(width 0.13208)
		(layer "F.Cu")
		(net "PEX1_MODE_SEL6")
	)
	(via
		(at 152.634442 -251.158502)
		(size 0.508)
		(drill 0.254)
		(layers "F.Cu" "B.Cu")
		(net "PEX1_MODE_SEL6")
	)
	(via
		(at 181.92496 -284.024832)
		(size 0.4064)
		(drill 0.2032)
		(layers "F.Cu" "B.Cu")
		(net "PEX1_MODE_SEL6")
	)
	(segment
		(start 181.92496 -284.024832)
		(end 182.452264 -283.497528)
		(width 0.13208)
		(layer "B.Cu")
		(net "PEX1_MODE_SEL6")
	)
	(segment
		(start 182.624984 -270.407384)
		(end 182.624984 -270.206216)
		(width 0.13208)
		(layer "B.Cu")
		(net "PEX1_MODE_SEL6")
	)
	(segment
		(start 152.9588 -255.1938)
		(end 152.14727 -254.38227)
		(width 0.13208)
		(layer "B.Cu")
		(net "PEX1_MODE_SEL6")
	)
	(segment
		(start 152.14727 -254.38227)
		(end 152.14727 -251.645674)
		(width 0.13208)
		(layer "B.Cu")
		(net "PEX1_MODE_SEL6")
	)
	(segment
		(start 183.965342 -282.635198)
		(end 184.735216 -281.865324)
		(width 0.13208)
		(layer "B.Cu")
		(net "PEX1_MODE_SEL6")
	)
	(segment
		(start 183.103012 -283.497528)
		(end 183.367934 -283.232606)
		(width 0.13208)
		(layer "B.Cu")
		(net "PEX1_MODE_SEL6")
	)
	(segment
		(start 182.452264 -283.497528)
		(end 183.103012 -283.497528)
		(width 0.13208)
		(layer "B.Cu")
		(net "PEX1_MODE_SEL6")
	)
	(segment
		(start 183.539384 -271.120616)
		(end 183.338216 -271.120616)
		(width 0.13208)
		(layer "B.Cu")
		(net "PEX1_MODE_SEL6")
	)
	(segment
		(start 184.735216 -272.316448)
		(end 183.539384 -271.120616)
		(width 0.13208)
		(layer "B.Cu")
		(net "PEX1_MODE_SEL6")
	)
	(segment
		(start 183.367934 -282.850336)
		(end 183.583072 -282.635198)
		(width 0.13208)
		(layer "B.Cu")
		(net "PEX1_MODE_SEL6")
	)
	(segment
		(start 183.367934 -283.232606)
		(end 183.367934 -282.850336)
		(width 0.13208)
		(layer "B.Cu")
		(net "PEX1_MODE_SEL6")
	)
	(segment
		(start 184.735216 -281.865324)
		(end 184.735216 -272.316448)
		(width 0.13208)
		(layer "B.Cu")
		(net "PEX1_MODE_SEL6")
	)
	(segment
		(start 183.338216 -271.120616)
		(end 182.624984 -270.407384)
		(width 0.13208)
		(layer "B.Cu")
		(net "PEX1_MODE_SEL6")
	)
	(segment
		(start 182.624984 -270.206216)
		(end 167.612568 -255.1938)
		(width 0.13208)
		(layer "B.Cu")
		(net "PEX1_MODE_SEL6")
	)
	(segment
		(start 183.583072 -282.635198)
		(end 183.965342 -282.635198)
		(width 0.13208)
		(layer "B.Cu")
		(net "PEX1_MODE_SEL6")
	)
	(segment
		(start 152.14727 -251.645674)
		(end 152.634442 -251.158502)
		(width 0.13208)
		(layer "B.Cu")
		(net "PEX1_MODE_SEL6")
	)
	(segment
		(start 167.612568 -255.1938)
		(end 152.9588 -255.1938)
		(width 0.13208)
		(layer "B.Cu")
		(net "PEX1_MODE_SEL6")
	)
	(segment
		(start 216.683336 -225.643186)
		(end 216.1286 -225.643186)
		(width 0.13208)
		(layer "F.Cu")
		(net "SMB_NIC3_R_SCL")
	)
	(segment
		(start 216.835736 -225.490786)
		(end 216.683336 -225.643186)
		(width 0.13208)
		(layer "F.Cu")
		(net "SMB_NIC3_R_SCL")
	)
	(segment
		(start 183.132984 -112.485424)
		(end 183.482488 -112.834928)
		(width 0.13208)
		(layer "F.Cu")
		(net "SMB_NIC3_R_SCL")
	)
	(segment
		(start 183.482488 -112.834928)
		(end 184.757314 -112.834928)
		(width 0.13208)
		(layer "F.Cu")
		(net "SMB_NIC3_R_SCL")
	)
	(via
		(at 183.132984 -112.485424)
		(size 0.508)
		(drill 0.254)
		(layers "F.Cu" "B.Cu")
		(net "SMB_NIC3_R_SCL")
	)
	(via
		(at 216.1286 -225.643186)
		(size 0.508)
		(drill 0.254)
		(layers "F.Cu" "B.Cu")
		(net "SMB_NIC3_R_SCL")
	)
	(via
		(at 211.824062 -134.777734)
		(size 0.508)
		(drill 0.254)
		(layers "F.Cu" "B.Cu")
		(net "SMB_NIC3_R_SCL")
	)
	(segment
		(start 184.308496 -112.485424)
		(end 184.371996 -112.421924)
		(width 0.13208)
		(layer "B.Cu")
		(net "SMB_NIC3_R_SCL")
	)
	(segment
		(start 183.132984 -112.485424)
		(end 184.308496 -112.485424)
		(width 0.13208)
		(layer "B.Cu")
		(net "SMB_NIC3_R_SCL")
	)
	(segment
		(start 211.7852 -165.185852)
		(end 211.7852 -162.127946)
		(width 0.15494)
		(layer "In7.Cu")
		(net "SMB_NIC3_R_SCL")
	)
	(segment
		(start 208.788 -188.0362)
		(end 208.788 -186.722512)
		(width 0.15494)
		(layer "In7.Cu")
		(net "SMB_NIC3_R_SCL")
	)
	(segment
		(start 216.1286 -225.643186)
		(end 216.1286 -225.57105)
		(width 0.15494)
		(layer "In7.Cu")
		(net "SMB_NIC3_R_SCL")
	)
	(segment
		(start 208.183734 -189.520576)
		(end 208.183734 -188.640466)
		(width 0.15494)
		(layer "In7.Cu")
		(net "SMB_NIC3_R_SCL")
	)
	(segment
		(start 215.47328 -224.91573)
		(end 213.974934 -224.91573)
		(width 0.15494)
		(layer "In7.Cu")
		(net "SMB_NIC3_R_SCL")
	)
	(segment
		(start 212.965792 -223.906588)
		(end 212.414612 -223.906588)
		(width 0.15494)
		(layer "In7.Cu")
		(net "SMB_NIC3_R_SCL")
	)
	(segment
		(start 212.414612 -223.906588)
		(end 211.881212 -223.373188)
		(width 0.15494)
		(layer "In7.Cu")
		(net "SMB_NIC3_R_SCL")
	)
	(segment
		(start 210.724242 -223.373188)
		(end 210.456526 -223.105472)
		(width 0.15494)
		(layer "In7.Cu")
		(net "SMB_NIC3_R_SCL")
	)
	(segment
		(start 216.1286 -225.57105)
		(end 215.47328 -224.91573)
		(width 0.15494)
		(layer "In7.Cu")
		(net "SMB_NIC3_R_SCL")
	)
	(segment
		(start 208.183734 -188.640466)
		(end 208.788 -188.0362)
		(width 0.15494)
		(layer "In7.Cu")
		(net "SMB_NIC3_R_SCL")
	)
	(segment
		(start 206.456534 -221.1578)
		(end 206.0448 -221.1578)
		(width 0.15494)
		(layer "In7.Cu")
		(net "SMB_NIC3_R_SCL")
	)
	(segment
		(start 212.852 -161.061146)
		(end 212.852 -135.242046)
		(width 0.15494)
		(layer "In7.Cu")
		(net "SMB_NIC3_R_SCL")
	)
	(segment
		(start 212.387688 -134.777734)
		(end 211.824062 -134.777734)
		(width 0.15494)
		(layer "In7.Cu")
		(net "SMB_NIC3_R_SCL")
	)
	(segment
		(start 211.7852 -162.127946)
		(end 212.852 -161.061146)
		(width 0.15494)
		(layer "In7.Cu")
		(net "SMB_NIC3_R_SCL")
	)
	(segment
		(start 208.661 -186.595512)
		(end 208.661 -185.476896)
		(width 0.15494)
		(layer "In7.Cu")
		(net "SMB_NIC3_R_SCL")
	)
	(segment
		(start 210.456526 -223.105472)
		(end 208.404206 -223.105472)
		(width 0.15494)
		(layer "In7.Cu")
		(net "SMB_NIC3_R_SCL")
	)
	(segment
		(start 203.11872 -218.23172)
		(end 203.11872 -194.58559)
		(width 0.15494)
		(layer "In7.Cu")
		(net "SMB_NIC3_R_SCL")
	)
	(segment
		(start 213.974934 -224.91573)
		(end 212.965792 -223.906588)
		(width 0.15494)
		(layer "In7.Cu")
		(net "SMB_NIC3_R_SCL")
	)
	(segment
		(start 208.788 -186.722512)
		(end 208.661 -186.595512)
		(width 0.15494)
		(layer "In7.Cu")
		(net "SMB_NIC3_R_SCL")
	)
	(segment
		(start 206.0448 -221.1578)
		(end 203.11872 -218.23172)
		(width 0.15494)
		(layer "In7.Cu")
		(net "SMB_NIC3_R_SCL")
	)
	(segment
		(start 208.661 -185.476896)
		(end 207.289908 -184.105804)
		(width 0.15494)
		(layer "In7.Cu")
		(net "SMB_NIC3_R_SCL")
	)
	(segment
		(start 203.11872 -194.58559)
		(end 208.183734 -189.520576)
		(width 0.15494)
		(layer "In7.Cu")
		(net "SMB_NIC3_R_SCL")
	)
	(segment
		(start 207.289908 -184.105804)
		(end 207.289908 -169.681144)
		(width 0.15494)
		(layer "In7.Cu")
		(net "SMB_NIC3_R_SCL")
	)
	(segment
		(start 208.404206 -223.105472)
		(end 206.456534 -221.1578)
		(width 0.15494)
		(layer "In7.Cu")
		(net "SMB_NIC3_R_SCL")
	)
	(segment
		(start 207.289908 -169.681144)
		(end 211.7852 -165.185852)
		(width 0.15494)
		(layer "In7.Cu")
		(net "SMB_NIC3_R_SCL")
	)
	(segment
		(start 211.881212 -223.373188)
		(end 210.724242 -223.373188)
		(width 0.15494)
		(layer "In7.Cu")
		(net "SMB_NIC3_R_SCL")
	)
	(segment
		(start 212.852 -135.242046)
		(end 212.387688 -134.777734)
		(width 0.15494)
		(layer "In7.Cu")
		(net "SMB_NIC3_R_SCL")
	)
	(segment
		(start 184.6834 -113.9698)
		(end 183.199024 -112.485424)
		(width 0.15494)
		(layer "In15.Cu")
		(net "SMB_NIC3_R_SCL")
	)
	(segment
		(start 186.715146 -113.6904)
		(end 186.435746 -113.9698)
		(width 0.15494)
		(layer "In15.Cu")
		(net "SMB_NIC3_R_SCL")
	)
	(segment
		(start 193.14033 -115.185952)
		(end 191.644778 -113.6904)
		(width 0.15494)
		(layer "In15.Cu")
		(net "SMB_NIC3_R_SCL")
	)
	(segment
		(start 186.435746 -113.9698)
		(end 184.6834 -113.9698)
		(width 0.15494)
		(layer "In15.Cu")
		(net "SMB_NIC3_R_SCL")
	)
	(segment
		(start 202.90663 -115.185952)
		(end 193.14033 -115.185952)
		(width 0.15494)
		(layer "In15.Cu")
		(net "SMB_NIC3_R_SCL")
	)
	(segment
		(start 203.67117 -115.950492)
		(end 202.90663 -115.185952)
		(width 0.15494)
		(layer "In15.Cu")
		(net "SMB_NIC3_R_SCL")
	)
	(segment
		(start 191.644778 -113.6904)
		(end 186.715146 -113.6904)
		(width 0.15494)
		(layer "In15.Cu")
		(net "SMB_NIC3_R_SCL")
	)
	(segment
		(start 183.199024 -112.485424)
		(end 183.132984 -112.485424)
		(width 0.15494)
		(layer "In15.Cu")
		(net "SMB_NIC3_R_SCL")
	)
	(segment
		(start 211.824062 -134.691628)
		(end 203.67117 -126.538736)
		(width 0.15494)
		(layer "In15.Cu")
		(net "SMB_NIC3_R_SCL")
	)
	(segment
		(start 203.67117 -126.538736)
		(end 203.67117 -115.950492)
		(width 0.15494)
		(layer "In15.Cu")
		(net "SMB_NIC3_R_SCL")
	)
	(segment
		(start 211.824062 -134.777734)
		(end 211.824062 -134.691628)
		(width 0.15494)
		(layer "In15.Cu")
		(net "SMB_NIC3_R_SCL")
	)
	(segment
		(start 340.890098 -227.583238)
		(end 340.493858 -227.186998)
		(width 0.13208)
		(layer "F.Cu")
		(net "PRSNT_SSD0_R_N")
	)
	(segment
		(start 7.109206 -26.03373)
		(end 7.109206 -27.04973)
		(width 0.13208)
		(layer "F.Cu")
		(net "PRSNT_SSD0_R_N")
	)
	(segment
		(start 7.456678 -45.071792)
		(end 6.74751 -45.071792)
		(width 0.13208)
		(layer "F.Cu")
		(net "PRSNT_SSD0_R_N")
	)
	(segment
		(start 7.109206 -27.04973)
		(end 8.10387 -27.04973)
		(width 0.13208)
		(layer "F.Cu")
		(net "PRSNT_SSD0_R_N")
	)
	(segment
		(start 8.10387 -27.04973)
		(end 8.120634 -27.066494)
		(width 0.13208)
		(layer "F.Cu")
		(net "PRSNT_SSD0_R_N")
	)
	(segment
		(start 8.120634 -27.066494)
		(end 8.942578 -27.066494)
		(width 0.13208)
		(layer "F.Cu")
		(net "PRSNT_SSD0_R_N")
	)
	(segment
		(start 235.867448 -225.103944)
		(end 235.467652 -224.704148)
		(width 0.13208)
		(layer "F.Cu")
		(net "PRSNT_SSD0_R_N")
	)
	(segment
		(start 340.890098 -228.831902)
		(end 340.890098 -227.583238)
		(width 0.13208)
		(layer "F.Cu")
		(net "PRSNT_SSD0_R_N")
	)
	(segment
		(start 340.36 -229.362)
		(end 340.890098 -228.831902)
		(width 0.13208)
		(layer "F.Cu")
		(net "PRSNT_SSD0_R_N")
	)
	(via
		(at 340.36 -229.362)
		(size 0.508)
		(drill 0.254)
		(layers "F.Cu" "B.Cu")
		(net "PRSNT_SSD0_R_N")
	)
	(via
		(at 6.74751 -45.071792)
		(size 0.508)
		(drill 0.254)
		(layers "F.Cu" "B.Cu")
		(net "PRSNT_SSD0_R_N")
	)
	(via
		(at 235.867448 -225.103944)
		(size 0.4572)
		(drill 0.254)
		(layers "F.Cu" "B.Cu")
		(net "PRSNT_SSD0_R_N")
	)
	(via
		(at 8.942578 -27.066494)
		(size 0.508)
		(drill 0.254)
		(layers "F.Cu" "B.Cu")
		(net "PRSNT_SSD0_R_N")
	)
	(via
		(at 32.935164 -217.808556)
		(size 0.508)
		(drill 0.254)
		(layers "F.Cu" "B.Cu")
		(net "PRSNT_SSD0_R_N")
	)
	(via
		(at 236.4232 -229.82936)
		(size 0.508)
		(drill 0.254)
		(layers "F.Cu" "B.Cu")
		(net "PRSNT_SSD0_R_N")
	)
	(segment
		(start 30.932628 -203.654914)
		(end 30.932628 -196.697854)
		(width 0.15494)
		(layer "In5.Cu")
		(net "PRSNT_SSD0_R_N")
	)
	(segment
		(start 2.617216 -28.594812)
		(end 6.018022 -28.594812)
		(width 0.15494)
		(layer "In5.Cu")
		(net "PRSNT_SSD0_R_N")
	)
	(segment
		(start 30.932628 -196.697854)
		(end 26.557224 -192.32245)
		(width 0.15494)
		(layer "In5.Cu")
		(net "PRSNT_SSD0_R_N")
	)
	(segment
		(start 26.557224 -166.789608)
		(end 26.121868 -165.738556)
		(width 0.15494)
		(layer "In5.Cu")
		(net "PRSNT_SSD0_R_N")
	)
	(segment
		(start 235.867448 -226.7966)
		(end 235.298488 -227.36556)
		(width 0.15494)
		(layer "In5.Cu")
		(net "PRSNT_SSD0_R_N")
	)
	(segment
		(start 7.54634 -27.066494)
		(end 8.942578 -27.066494)
		(width 0.15494)
		(layer "In5.Cu")
		(net "PRSNT_SSD0_R_N")
	)
	(segment
		(start 31.76016 -216.633552)
		(end 31.76016 -204.482446)
		(width 0.15494)
		(layer "In5.Cu")
		(net "PRSNT_SSD0_R_N")
	)
	(segment
		(start 15.607538 -25.506172)
		(end 14.047216 -27.066494)
		(width 0.15494)
		(layer "In5.Cu")
		(net "PRSNT_SSD0_R_N")
	)
	(segment
		(start 19.233642 -25.877012)
		(end 18.79473 -26.315924)
		(width 0.15494)
		(layer "In5.Cu")
		(net "PRSNT_SSD0_R_N")
	)
	(segment
		(start 2.159 -42.748708)
		(end 2.159 -36.1188)
		(width 0.15494)
		(layer "In5.Cu")
		(net "PRSNT_SSD0_R_N")
	)
	(segment
		(start 14.047216 -27.066494)
		(end 8.942578 -27.066494)
		(width 0.15494)
		(layer "In5.Cu")
		(net "PRSNT_SSD0_R_N")
	)
	(segment
		(start 2.794 -34.29)
		(end 2.0828 -33.5788)
		(width 0.15494)
		(layer "In5.Cu")
		(net "PRSNT_SSD0_R_N")
	)
	(segment
		(start 2.0828 -29.129228)
		(end 2.617216 -28.594812)
		(width 0.15494)
		(layer "In5.Cu")
		(net "PRSNT_SSD0_R_N")
	)
	(segment
		(start 6.74751 -45.071792)
		(end 6.74751 -43.0784)
		(width 0.15494)
		(layer "In5.Cu")
		(net "PRSNT_SSD0_R_N")
	)
	(segment
		(start 18.79473 -26.315924)
		(end 18.36928 -26.315924)
		(width 0.15494)
		(layer "In5.Cu")
		(net "PRSNT_SSD0_R_N")
	)
	(segment
		(start 31.76016 -204.482446)
		(end 30.932628 -203.654914)
		(width 0.15494)
		(layer "In5.Cu")
		(net "PRSNT_SSD0_R_N")
	)
	(segment
		(start 6.018022 -28.594812)
		(end 7.54634 -27.066494)
		(width 0.15494)
		(layer "In5.Cu")
		(net "PRSNT_SSD0_R_N")
	)
	(segment
		(start 26.121868 -165.738556)
		(end 26.121868 -100.544122)
		(width 0.15494)
		(layer "In5.Cu")
		(net "PRSNT_SSD0_R_N")
	)
	(segment
		(start 235.867448 -225.103944)
		(end 235.867448 -226.7966)
		(width 0.15494)
		(layer "In5.Cu")
		(net "PRSNT_SSD0_R_N")
	)
	(segment
		(start 37.14242 -88.536526)
		(end 37.14242 -46.494446)
		(width 0.15494)
		(layer "In5.Cu")
		(net "PRSNT_SSD0_R_N")
	)
	(segment
		(start 32.935164 -217.808556)
		(end 31.76016 -216.633552)
		(width 0.15494)
		(layer "In5.Cu")
		(net "PRSNT_SSD0_R_N")
	)
	(segment
		(start 24.433276 -29.060902)
		(end 21.249386 -25.877012)
		(width 0.15494)
		(layer "In5.Cu")
		(net "PRSNT_SSD0_R_N")
	)
	(segment
		(start 17.559528 -25.506172)
		(end 15.607538 -25.506172)
		(width 0.15494)
		(layer "In5.Cu")
		(net "PRSNT_SSD0_R_N")
	)
	(segment
		(start 235.298488 -228.704648)
		(end 236.4232 -229.82936)
		(width 0.15494)
		(layer "In5.Cu")
		(net "PRSNT_SSD0_R_N")
	)
	(segment
		(start 29.1846 -97.48139)
		(end 29.1846 -96.494346)
		(width 0.15494)
		(layer "In5.Cu")
		(net "PRSNT_SSD0_R_N")
	)
	(segment
		(start 37.14242 -46.494446)
		(end 24.433276 -33.785302)
		(width 0.15494)
		(layer "In5.Cu")
		(net "PRSNT_SSD0_R_N")
	)
	(segment
		(start 18.36928 -26.315924)
		(end 17.559528 -25.506172)
		(width 0.15494)
		(layer "In5.Cu")
		(net "PRSNT_SSD0_R_N")
	)
	(segment
		(start 26.121868 -100.544122)
		(end 29.1846 -97.48139)
		(width 0.15494)
		(layer "In5.Cu")
		(net "PRSNT_SSD0_R_N")
	)
	(segment
		(start 2.0828 -33.5788)
		(end 2.0828 -29.129228)
		(width 0.15494)
		(layer "In5.Cu")
		(net "PRSNT_SSD0_R_N")
	)
	(segment
		(start 235.298488 -227.36556)
		(end 235.298488 -228.704648)
		(width 0.15494)
		(layer "In5.Cu")
		(net "PRSNT_SSD0_R_N")
	)
	(segment
		(start 2.361692 -42.9514)
		(end 2.159 -42.748708)
		(width 0.15494)
		(layer "In5.Cu")
		(net "PRSNT_SSD0_R_N")
	)
	(segment
		(start 2.159 -36.1188)
		(end 2.794 -35.4838)
		(width 0.15494)
		(layer "In5.Cu")
		(net "PRSNT_SSD0_R_N")
	)
	(segment
		(start 2.794 -35.4838)
		(end 2.794 -34.29)
		(width 0.15494)
		(layer "In5.Cu")
		(net "PRSNT_SSD0_R_N")
	)
	(segment
		(start 6.74751 -43.0784)
		(end 6.62051 -42.9514)
		(width 0.15494)
		(layer "In5.Cu")
		(net "PRSNT_SSD0_R_N")
	)
	(segment
		(start 29.1846 -96.494346)
		(end 37.14242 -88.536526)
		(width 0.15494)
		(layer "In5.Cu")
		(net "PRSNT_SSD0_R_N")
	)
	(segment
		(start 6.62051 -42.9514)
		(end 2.361692 -42.9514)
		(width 0.15494)
		(layer "In5.Cu")
		(net "PRSNT_SSD0_R_N")
	)
	(segment
		(start 24.433276 -33.785302)
		(end 24.433276 -29.060902)
		(width 0.15494)
		(layer "In5.Cu")
		(net "PRSNT_SSD0_R_N")
	)
	(segment
		(start 26.557224 -192.32245)
		(end 26.557224 -166.789608)
		(width 0.15494)
		(layer "In5.Cu")
		(net "PRSNT_SSD0_R_N")
	)
	(segment
		(start 21.249386 -25.877012)
		(end 19.233642 -25.877012)
		(width 0.15494)
		(layer "In5.Cu")
		(net "PRSNT_SSD0_R_N")
	)
	(segment
		(start 234.665012 -220.939106)
		(end 234.665012 -221.126558)
		(width 0.0889)
		(layer "In13.Cu")
		(net "PRSNT_SSD0_R_N")
	)
	(segment
		(start 61.595 -207.743044)
		(end 61.972444 -207.3656)
		(width 0.15494)
		(layer "In13.Cu")
		(net "PRSNT_SSD0_R_N")
	)
	(segment
		(start 32.935164 -217.808556)
		(end 33.379918 -217.363802)
		(width 0.15494)
		(layer "In13.Cu")
		(net "PRSNT_SSD0_R_N")
	)
	(segment
		(start 151.300942 -215.603074)
		(end 204.23632 -215.603074)
		(width 0.15494)
		(layer "In13.Cu")
		(net "PRSNT_SSD0_R_N")
	)
	(segment
		(start 218.995498 -221.08922)
		(end 220.978222 -219.106496)
		(width 0.15494)
		(layer "In13.Cu")
		(net "PRSNT_SSD0_R_N")
	)
	(segment
		(start 204.23632 -215.603074)
		(end 207.344772 -218.711526)
		(width 0.15494)
		(layer "In13.Cu")
		(net "PRSNT_SSD0_R_N")
	)
	(segment
		(start 99.997514 -209.14614)
		(end 114.937794 -209.14614)
		(width 0.15494)
		(layer "In13.Cu")
		(net "PRSNT_SSD0_R_N")
	)
	(segment
		(start 56.606186 -207.743044)
		(end 61.595 -207.743044)
		(width 0.15494)
		(layer "In13.Cu")
		(net "PRSNT_SSD0_R_N")
	)
	(segment
		(start 235.232194 -221.506542)
		(end 235.464858 -221.739206)
		(width 0.0889)
		(layer "In13.Cu")
		(net "PRSNT_SSD0_R_N")
	)
	(segment
		(start 212.698076 -219.837)
		(end 216.428574 -219.837)
		(width 0.15494)
		(layer "In13.Cu")
		(net "PRSNT_SSD0_R_N")
	)
	(segment
		(start 120.457468 -214.669878)
		(end 120.461532 -214.669878)
		(width 0.15494)
		(layer "In13.Cu")
		(net "PRSNT_SSD0_R_N")
	)
	(segment
		(start 233.869992 -220.331538)
		(end 233.869992 -220.468698)
		(width 0.0889)
		(layer "In13.Cu")
		(net "PRSNT_SSD0_R_N")
	)
	(segment
		(start 207.344772 -218.711526)
		(end 211.572602 -218.711526)
		(width 0.15494)
		(layer "In13.Cu")
		(net "PRSNT_SSD0_R_N")
	)
	(segment
		(start 236.264958 -222.539052)
		(end 236.264958 -224.706434)
		(width 0.0889)
		(layer "In13.Cu")
		(net "PRSNT_SSD0_R_N")
	)
	(segment
		(start 235.469938 -222.068898)
		(end 235.702602 -222.301562)
		(width 0.0889)
		(layer "In13.Cu")
		(net "PRSNT_SSD0_R_N")
	)
	(segment
		(start 64.131444 -207.743044)
		(end 66.934588 -207.743044)
		(width 0.15494)
		(layer "In13.Cu")
		(net "PRSNT_SSD0_R_N")
	)
	(segment
		(start 235.044996 -221.506542)
		(end 235.232194 -221.506542)
		(width 0.0889)
		(layer "In13.Cu")
		(net "PRSNT_SSD0_R_N")
	)
	(segment
		(start 114.937794 -209.14614)
		(end 120.174258 -214.382604)
		(width 0.15494)
		(layer "In13.Cu")
		(net "PRSNT_SSD0_R_N")
	)
	(segment
		(start 124.355606 -216.50706)
		(end 125.781562 -217.933016)
		(width 0.15494)
		(layer "In13.Cu")
		(net "PRSNT_SSD0_R_N")
	)
	(segment
		(start 233.069892 -219.582746)
		(end 233.069892 -219.668852)
		(width 0.0889)
		(layer "In13.Cu")
		(net "PRSNT_SSD0_R_N")
	)
	(segment
		(start 76.275946 -209.7024)
		(end 99.441254 -209.7024)
		(width 0.15494)
		(layer "In13.Cu")
		(net "PRSNT_SSD0_R_N")
	)
	(segment
		(start 233.444796 -219.906342)
		(end 233.632248 -219.906342)
		(width 0.0889)
		(layer "In13.Cu")
		(net "PRSNT_SSD0_R_N")
	)
	(segment
		(start 236.264958 -224.706434)
		(end 235.867448 -225.103944)
		(width 0.0889)
		(layer "In13.Cu")
		(net "PRSNT_SSD0_R_N")
	)
	(segment
		(start 33.379918 -217.363802)
		(end 56.606186 -207.743044)
		(width 0.15494)
		(layer "In13.Cu")
		(net "PRSNT_SSD0_R_N")
	)
	(segment
		(start 233.065066 -219.57792)
		(end 233.069892 -219.582746)
		(width 0.0889)
		(layer "In13.Cu")
		(net "PRSNT_SSD0_R_N")
	)
	(segment
		(start 220.978222 -219.106496)
		(end 225.1964 -219.106496)
		(width 0.15494)
		(layer "In13.Cu")
		(net "PRSNT_SSD0_R_N")
	)
	(segment
		(start 233.869992 -220.468698)
		(end 234.102656 -220.701362)
		(width 0.0889)
		(layer "In13.Cu")
		(net "PRSNT_SSD0_R_N")
	)
	(segment
		(start 236.032294 -222.306388)
		(end 236.264958 -222.539052)
		(width 0.0889)
		(layer "In13.Cu")
		(net "PRSNT_SSD0_R_N")
	)
	(segment
		(start 120.174258 -214.386668)
		(end 120.457468 -214.669878)
		(width 0.15494)
		(layer "In13.Cu")
		(net "PRSNT_SSD0_R_N")
	)
	(segment
		(start 235.464858 -221.739206)
		(end 235.464858 -221.926404)
		(width 0.0889)
		(layer "In13.Cu")
		(net "PRSNT_SSD0_R_N")
	)
	(segment
		(start 233.065066 -219.33916)
		(end 233.065066 -219.57792)
		(width 0.0889)
		(layer "In13.Cu")
		(net "PRSNT_SSD0_R_N")
	)
	(segment
		(start 235.844842 -222.306388)
		(end 236.032294 -222.306388)
		(width 0.0889)
		(layer "In13.Cu")
		(net "PRSNT_SSD0_R_N")
	)
	(segment
		(start 66.934588 -207.743044)
		(end 68.190872 -208.999328)
		(width 0.15494)
		(layer "In13.Cu")
		(net "PRSNT_SSD0_R_N")
	)
	(segment
		(start 234.669838 -221.268798)
		(end 234.902502 -221.501462)
		(width 0.0889)
		(layer "In13.Cu")
		(net "PRSNT_SSD0_R_N")
	)
	(segment
		(start 122.298714 -216.50706)
		(end 124.355606 -216.50706)
		(width 0.15494)
		(layer "In13.Cu")
		(net "PRSNT_SSD0_R_N")
	)
	(segment
		(start 234.669838 -221.131384)
		(end 234.669838 -221.268798)
		(width 0.0889)
		(layer "In13.Cu")
		(net "PRSNT_SSD0_R_N")
	)
	(segment
		(start 68.190872 -208.999328)
		(end 75.572874 -208.999328)
		(width 0.15494)
		(layer "In13.Cu")
		(net "PRSNT_SSD0_R_N")
	)
	(segment
		(start 75.572874 -208.999328)
		(end 76.275946 -209.7024)
		(width 0.15494)
		(layer "In13.Cu")
		(net "PRSNT_SSD0_R_N")
	)
	(segment
		(start 99.441254 -209.7024)
		(end 99.997514 -209.14614)
		(width 0.15494)
		(layer "In13.Cu")
		(net "PRSNT_SSD0_R_N")
	)
	(segment
		(start 120.174258 -214.382604)
		(end 120.174258 -214.386668)
		(width 0.15494)
		(layer "In13.Cu")
		(net "PRSNT_SSD0_R_N")
	)
	(segment
		(start 211.572602 -218.711526)
		(end 212.698076 -219.837)
		(width 0.15494)
		(layer "In13.Cu")
		(net "PRSNT_SSD0_R_N")
	)
	(segment
		(start 235.840016 -222.301562)
		(end 235.844842 -222.306388)
		(width 0.0889)
		(layer "In13.Cu")
		(net "PRSNT_SSD0_R_N")
	)
	(segment
		(start 125.781562 -217.933016)
		(end 148.971 -217.933016)
		(width 0.15494)
		(layer "In13.Cu")
		(net "PRSNT_SSD0_R_N")
	)
	(segment
		(start 233.864912 -220.139006)
		(end 233.864912 -220.326458)
		(width 0.0889)
		(layer "In13.Cu")
		(net "PRSNT_SSD0_R_N")
	)
	(segment
		(start 234.244896 -220.706442)
		(end 234.432348 -220.706442)
		(width 0.0889)
		(layer "In13.Cu")
		(net "PRSNT_SSD0_R_N")
	)
	(segment
		(start 235.464858 -221.926404)
		(end 235.469938 -221.931484)
		(width 0.0889)
		(layer "In13.Cu")
		(net "PRSNT_SSD0_R_N")
	)
	(segment
		(start 235.702602 -222.301562)
		(end 235.840016 -222.301562)
		(width 0.0889)
		(layer "In13.Cu")
		(net "PRSNT_SSD0_R_N")
	)
	(segment
		(start 217.680794 -221.08922)
		(end 218.995498 -221.08922)
		(width 0.15494)
		(layer "In13.Cu")
		(net "PRSNT_SSD0_R_N")
	)
	(segment
		(start 233.43997 -219.901516)
		(end 233.444796 -219.906342)
		(width 0.0889)
		(layer "In13.Cu")
		(net "PRSNT_SSD0_R_N")
	)
	(segment
		(start 234.102656 -220.701362)
		(end 234.239816 -220.701362)
		(width 0.0889)
		(layer "In13.Cu")
		(net "PRSNT_SSD0_R_N")
	)
	(segment
		(start 233.069892 -219.668852)
		(end 233.302556 -219.901516)
		(width 0.0889)
		(layer "In13.Cu")
		(net "PRSNT_SSD0_R_N")
	)
	(segment
		(start 234.432348 -220.706442)
		(end 234.665012 -220.939106)
		(width 0.0889)
		(layer "In13.Cu")
		(net "PRSNT_SSD0_R_N")
	)
	(segment
		(start 61.972444 -207.3656)
		(end 63.754 -207.3656)
		(width 0.15494)
		(layer "In13.Cu")
		(net "PRSNT_SSD0_R_N")
	)
	(segment
		(start 235.469938 -221.931484)
		(end 235.469938 -222.068898)
		(width 0.0889)
		(layer "In13.Cu")
		(net "PRSNT_SSD0_R_N")
	)
	(segment
		(start 232.832402 -219.106496)
		(end 233.065066 -219.33916)
		(width 0.0889)
		(layer "In13.Cu")
		(net "PRSNT_SSD0_R_N")
	)
	(segment
		(start 234.902502 -221.501462)
		(end 235.039916 -221.501462)
		(width 0.0889)
		(layer "In13.Cu")
		(net "PRSNT_SSD0_R_N")
	)
	(segment
		(start 225.1964 -219.106496)
		(end 232.832402 -219.106496)
		(width 0.0889)
		(layer "In13.Cu")
		(net "PRSNT_SSD0_R_N")
	)
	(segment
		(start 63.754 -207.3656)
		(end 64.131444 -207.743044)
		(width 0.15494)
		(layer "In13.Cu")
		(net "PRSNT_SSD0_R_N")
	)
	(segment
		(start 120.461532 -214.669878)
		(end 122.298714 -216.50706)
		(width 0.15494)
		(layer "In13.Cu")
		(net "PRSNT_SSD0_R_N")
	)
	(segment
		(start 234.665012 -221.126558)
		(end 234.669838 -221.131384)
		(width 0.0889)
		(layer "In13.Cu")
		(net "PRSNT_SSD0_R_N")
	)
	(segment
		(start 235.039916 -221.501462)
		(end 235.044996 -221.506542)
		(width 0.0889)
		(layer "In13.Cu")
		(net "PRSNT_SSD0_R_N")
	)
	(segment
		(start 233.302556 -219.901516)
		(end 233.43997 -219.901516)
		(width 0.0889)
		(layer "In13.Cu")
		(net "PRSNT_SSD0_R_N")
	)
	(segment
		(start 233.864912 -220.326458)
		(end 233.869992 -220.331538)
		(width 0.0889)
		(layer "In13.Cu")
		(net "PRSNT_SSD0_R_N")
	)
	(segment
		(start 148.971 -217.933016)
		(end 151.300942 -215.603074)
		(width 0.15494)
		(layer "In13.Cu")
		(net "PRSNT_SSD0_R_N")
	)
	(segment
		(start 216.428574 -219.837)
		(end 217.680794 -221.08922)
		(width 0.15494)
		(layer "In13.Cu")
		(net "PRSNT_SSD0_R_N")
	)
	(segment
		(start 234.239816 -220.701362)
		(end 234.244896 -220.706442)
		(width 0.0889)
		(layer "In13.Cu")
		(net "PRSNT_SSD0_R_N")
	)
	(segment
		(start 233.632248 -219.906342)
		(end 233.864912 -220.139006)
		(width 0.0889)
		(layer "In13.Cu")
		(net "PRSNT_SSD0_R_N")
	)
	(segment
		(start 240.646458 -230.05161)
		(end 246.080788 -224.61728)
		(width 0.15494)
		(layer "In15.Cu")
		(net "PRSNT_SSD0_R_N")
	)
	(segment
		(start 272.008854 -230.6066)
		(end 290.4236 -230.6066)
		(width 0.15494)
		(layer "In15.Cu")
		(net "PRSNT_SSD0_R_N")
	)
	(segment
		(start 336.62747 -228.42093)
		(end 337.459828 -229.253288)
		(width 0.15494)
		(layer "In15.Cu")
		(net "PRSNT_SSD0_R_N")
	)
	(segment
		(start 291.51834 -229.51186)
		(end 300.842172 -229.51186)
		(width 0.15494)
		(layer "In15.Cu")
		(net "PRSNT_SSD0_R_N")
	)
	(segment
		(start 337.459828 -229.253288)
		(end 339.679534 -229.253288)
		(width 0.15494)
		(layer "In15.Cu")
		(net "PRSNT_SSD0_R_N")
	)
	(segment
		(start 290.4236 -230.6066)
		(end 291.51834 -229.51186)
		(width 0.15494)
		(layer "In15.Cu")
		(net "PRSNT_SSD0_R_N")
	)
	(segment
		(start 260.58495 -224.007934)
		(end 261.129526 -224.55251)
		(width 0.15494)
		(layer "In15.Cu")
		(net "PRSNT_SSD0_R_N")
	)
	(segment
		(start 326.066912 -229.705916)
		(end 326.865996 -230.505)
		(width 0.15494)
		(layer "In15.Cu")
		(net "PRSNT_SSD0_R_N")
	)
	(segment
		(start 236.4232 -229.82936)
		(end 236.64545 -230.05161)
		(width 0.15494)
		(layer "In15.Cu")
		(net "PRSNT_SSD0_R_N")
	)
	(segment
		(start 339.788246 -229.362)
		(end 340.36 -229.362)
		(width 0.15494)
		(layer "In15.Cu")
		(net "PRSNT_SSD0_R_N")
	)
	(segment
		(start 304.381408 -228.347016)
		(end 305.493928 -229.459536)
		(width 0.15494)
		(layer "In15.Cu")
		(net "PRSNT_SSD0_R_N")
	)
	(segment
		(start 323.330316 -229.705916)
		(end 326.066912 -229.705916)
		(width 0.15494)
		(layer "In15.Cu")
		(net "PRSNT_SSD0_R_N")
	)
	(segment
		(start 302.007016 -228.347016)
		(end 304.381408 -228.347016)
		(width 0.15494)
		(layer "In15.Cu")
		(net "PRSNT_SSD0_R_N")
	)
	(segment
		(start 263.597136 -225.80092)
		(end 267.203174 -225.80092)
		(width 0.15494)
		(layer "In15.Cu")
		(net "PRSNT_SSD0_R_N")
	)
	(segment
		(start 333.303626 -229.76078)
		(end 334.643476 -228.42093)
		(width 0.15494)
		(layer "In15.Cu")
		(net "PRSNT_SSD0_R_N")
	)
	(segment
		(start 339.679534 -229.253288)
		(end 339.788246 -229.362)
		(width 0.15494)
		(layer "In15.Cu")
		(net "PRSNT_SSD0_R_N")
	)
	(segment
		(start 329.089766 -230.505)
		(end 329.833986 -229.76078)
		(width 0.15494)
		(layer "In15.Cu")
		(net "PRSNT_SSD0_R_N")
	)
	(segment
		(start 249.62358 -224.61728)
		(end 250.232926 -224.007934)
		(width 0.15494)
		(layer "In15.Cu")
		(net "PRSNT_SSD0_R_N")
	)
	(segment
		(start 267.203174 -225.80092)
		(end 272.008854 -230.6066)
		(width 0.15494)
		(layer "In15.Cu")
		(net "PRSNT_SSD0_R_N")
	)
	(segment
		(start 261.129526 -224.55251)
		(end 262.103108 -224.955862)
		(width 0.15494)
		(layer "In15.Cu")
		(net "PRSNT_SSD0_R_N")
	)
	(segment
		(start 262.103108 -224.955862)
		(end 262.752078 -224.955862)
		(width 0.15494)
		(layer "In15.Cu")
		(net "PRSNT_SSD0_R_N")
	)
	(segment
		(start 305.493928 -229.459536)
		(end 323.083936 -229.459536)
		(width 0.15494)
		(layer "In15.Cu")
		(net "PRSNT_SSD0_R_N")
	)
	(segment
		(start 250.232926 -224.007934)
		(end 260.58495 -224.007934)
		(width 0.15494)
		(layer "In15.Cu")
		(net "PRSNT_SSD0_R_N")
	)
	(segment
		(start 262.752078 -224.955862)
		(end 263.597136 -225.80092)
		(width 0.15494)
		(layer "In15.Cu")
		(net "PRSNT_SSD0_R_N")
	)
	(segment
		(start 334.643476 -228.42093)
		(end 336.62747 -228.42093)
		(width 0.15494)
		(layer "In15.Cu")
		(net "PRSNT_SSD0_R_N")
	)
	(segment
		(start 246.080788 -224.61728)
		(end 249.62358 -224.61728)
		(width 0.15494)
		(layer "In15.Cu")
		(net "PRSNT_SSD0_R_N")
	)
	(segment
		(start 323.083936 -229.459536)
		(end 323.330316 -229.705916)
		(width 0.15494)
		(layer "In15.Cu")
		(net "PRSNT_SSD0_R_N")
	)
	(segment
		(start 300.842172 -229.51186)
		(end 302.007016 -228.347016)
		(width 0.15494)
		(layer "In15.Cu")
		(net "PRSNT_SSD0_R_N")
	)
	(segment
		(start 329.833986 -229.76078)
		(end 333.303626 -229.76078)
		(width 0.15494)
		(layer "In15.Cu")
		(net "PRSNT_SSD0_R_N")
	)
	(segment
		(start 236.64545 -230.05161)
		(end 240.646458 -230.05161)
		(width 0.15494)
		(layer "In15.Cu")
		(net "PRSNT_SSD0_R_N")
	)
	(segment
		(start 326.865996 -230.505)
		(end 329.089766 -230.505)
		(width 0.15494)
		(layer "In15.Cu")
		(net "PRSNT_SSD0_R_N")
	)
	(segment
		(start 363.671866 -197.907656)
		(end 363.87405 -198.10984)
		(width 0.13208)
		(layer "F.Cu")
		(net "RST_PEX_SSD4_PERST_R_N")
	)
	(segment
		(start 363.87405 -198.10984)
		(end 363.87405 -198.755)
		(width 0.13208)
		(layer "F.Cu")
		(net "RST_PEX_SSD4_PERST_R_N")
	)
	(segment
		(start 357.344218 -198.951342)
		(end 360.995722 -198.951342)
		(width 0.13208)
		(layer "F.Cu")
		(net "RST_PEX_SSD4_PERST_R_N")
	)
	(segment
		(start 347.693742 -211.98713)
		(end 348.093538 -211.587334)
		(width 0.13208)
		(layer "F.Cu")
		(net "RST_PEX_SSD4_PERST_R_N")
	)
	(segment
		(start 362.039408 -197.907656)
		(end 363.671866 -197.907656)
		(width 0.13208)
		(layer "F.Cu")
		(net "RST_PEX_SSD4_PERST_R_N")
	)
	(segment
		(start 365.10595 -198.755)
		(end 363.87405 -198.755)
		(width 0.13208)
		(layer "F.Cu")
		(net "RST_PEX_SSD4_PERST_R_N")
	)
	(segment
		(start 360.995722 -198.951342)
		(end 362.039408 -197.907656)
		(width 0.13208)
		(layer "F.Cu")
		(net "RST_PEX_SSD4_PERST_R_N")
	)
	(via
		(at 357.344218 -198.951342)
		(size 0.508)
		(drill 0.254)
		(layers "F.Cu" "B.Cu")
		(net "RST_PEX_SSD4_PERST_R_N")
	)
	(via
		(at 348.093538 -211.587334)
		(size 0.4572)
		(drill 0.254)
		(layers "F.Cu" "B.Cu")
		(net "RST_PEX_SSD4_PERST_R_N")
	)
	(segment
		(start 349.808546 -208.9912)
		(end 349.329502 -208.9912)
		(width 0.15494)
		(layer "In7.Cu")
		(net "RST_PEX_SSD4_PERST_R_N")
	)
	(segment
		(start 352.7044 -204.2668)
		(end 352.36531 -204.60589)
		(width 0.15494)
		(layer "In7.Cu")
		(net "RST_PEX_SSD4_PERST_R_N")
	)
	(segment
		(start 349.329502 -208.9912)
		(end 348.5642 -209.756502)
		(width 0.15494)
		(layer "In7.Cu")
		(net "RST_PEX_SSD4_PERST_R_N")
	)
	(segment
		(start 352.7044 -203.59116)
		(end 352.7044 -204.2668)
		(width 0.15494)
		(layer "In7.Cu")
		(net "RST_PEX_SSD4_PERST_R_N")
	)
	(segment
		(start 348.5642 -209.756502)
		(end 348.5642 -211.116672)
		(width 0.15494)
		(layer "In7.Cu")
		(net "RST_PEX_SSD4_PERST_R_N")
	)
	(segment
		(start 352.36531 -206.434436)
		(end 349.808546 -208.9912)
		(width 0.15494)
		(layer "In7.Cu")
		(net "RST_PEX_SSD4_PERST_R_N")
	)
	(segment
		(start 348.5642 -211.116672)
		(end 348.093538 -211.587334)
		(width 0.15494)
		(layer "In7.Cu")
		(net "RST_PEX_SSD4_PERST_R_N")
	)
	(segment
		(start 357.344218 -198.951342)
		(end 352.7044 -203.59116)
		(width 0.15494)
		(layer "In7.Cu")
		(net "RST_PEX_SSD4_PERST_R_N")
	)
	(segment
		(start 352.36531 -204.60589)
		(end 352.36531 -206.434436)
		(width 0.15494)
		(layer "In7.Cu")
		(net "RST_PEX_SSD4_PERST_R_N")
	)
	(segment
		(start 93.754702 -26.58999)
		(end 93.264736 -26.58999)
		(width 0.13462)
		(layer "F.Cu")
		(net "CLK_100M_DB800ZL_SSD3_R_DN")
	)
	(segment
		(start 116.082826 -83.058)
		(end 116.78031 -83.058)
		(width 0.13462)
		(layer "F.Cu")
		(net "CLK_100M_DB800ZL_SSD3_R_DN")
	)
	(segment
		(start 94.683834 -26.77668)
		(end 93.941392 -26.77668)
		(width 0.13462)
		(layer "F.Cu")
		(net "CLK_100M_DB800ZL_SSD3_R_DN")
	)
	(segment
		(start 93.941392 -26.77668)
		(end 93.754702 -26.58999)
		(width 0.13462)
		(layer "F.Cu")
		(net "CLK_100M_DB800ZL_SSD3_R_DN")
	)
	(segment
		(start 115.756436 -83.38439)
		(end 116.082826 -83.058)
		(width 0.13462)
		(layer "F.Cu")
		(net "CLK_100M_DB800ZL_SSD3_R_DN")
	)
	(segment
		(start 94.981268 -26.479246)
		(end 94.683834 -26.77668)
		(width 0.13462)
		(layer "F.Cu")
		(net "CLK_100M_DB800ZL_SSD3_R_DN")
	)
	(segment
		(start 116.78031 -83.058)
		(end 117.0813 -83.35899)
		(width 0.13462)
		(layer "F.Cu")
		(net "CLK_100M_DB800ZL_SSD3_R_DN")
	)
	(via
		(at 117.0813 -83.35899)
		(size 0.508)
		(drill 0.254)
		(layers "F.Cu" "B.Cu")
		(net "CLK_100M_DB800ZL_SSD3_R_DN")
	)
	(via
		(at 94.981268 -26.479246)
		(size 0.508)
		(drill 0.254)
		(layers "F.Cu" "B.Cu")
		(net "CLK_100M_DB800ZL_SSD3_R_DN")
	)
	(segment
		(start 111.811816 -61.502544)
		(end 112.020096 -61.502544)
		(width 0.1651)
		(layer "In13.Cu")
		(net "CLK_100M_DB800ZL_SSD3_R_DN")
	)
	(segment
		(start 103.786432 -35.904932)
		(end 108.2294 -44.212256)
		(width 0.1651)
		(layer "In13.Cu")
		(net "CLK_100M_DB800ZL_SSD3_R_DN")
	)
	(segment
		(start 98.307906 -27.017472)
		(end 99.581716 -28.291282)
		(width 0.1651)
		(layer "In13.Cu")
		(net "CLK_100M_DB800ZL_SSD3_R_DN")
	)
	(segment
		(start 99.581716 -28.291282)
		(end 101.045772 -28.291282)
		(width 0.1651)
		(layer "In13.Cu")
		(net "CLK_100M_DB800ZL_SSD3_R_DN")
	)
	(segment
		(start 108.457492 -58.137552)
		(end 108.670344 -58.137552)
		(width 0.1651)
		(layer "In13.Cu")
		(net "CLK_100M_DB800ZL_SSD3_R_DN")
	)
	(segment
		(start 109.696504 -59.387232)
		(end 110.13313 -59.823858)
		(width 0.1651)
		(layer "In13.Cu")
		(net "CLK_100M_DB800ZL_SSD3_R_DN")
	)
	(segment
		(start 117.0813 -83.358482)
		(end 117.0813 -83.35899)
		(width 0.1651)
		(layer "In13.Cu")
		(net "CLK_100M_DB800ZL_SSD3_R_DN")
	)
	(segment
		(start 117.368066 -83.071716)
		(end 117.0813 -83.358482)
		(width 0.1651)
		(layer "In13.Cu")
		(net "CLK_100M_DB800ZL_SSD3_R_DN")
	)
	(segment
		(start 101.045772 -28.291282)
		(end 103.786432 -31.031942)
		(width 0.1651)
		(layer "In13.Cu")
		(net "CLK_100M_DB800ZL_SSD3_R_DN")
	)
	(segment
		(start 108.670344 -58.137552)
		(end 111.012986 -55.79491)
		(width 0.1651)
		(layer "In13.Cu")
		(net "CLK_100M_DB800ZL_SSD3_R_DN")
	)
	(segment
		(start 113.49355 -63.17361)
		(end 113.695734 -63.17361)
		(width 0.1651)
		(layer "In13.Cu")
		(net "CLK_100M_DB800ZL_SSD3_R_DN")
	)
	(segment
		(start 95.268288 -26.766266)
		(end 96.836992 -26.766266)
		(width 0.1651)
		(layer "In13.Cu")
		(net "CLK_100M_DB800ZL_SSD3_R_DN")
	)
	(segment
		(start 113.725452 -58.507376)
		(end 111.37519 -60.857638)
		(width 0.1651)
		(layer "In13.Cu")
		(net "CLK_100M_DB800ZL_SSD3_R_DN")
	)
	(segment
		(start 97.088198 -27.017472)
		(end 98.307906 -27.017472)
		(width 0.1651)
		(layer "In13.Cu")
		(net "CLK_100M_DB800ZL_SSD3_R_DN")
	)
	(segment
		(start 110.13313 -59.823858)
		(end 110.34141 -59.823858)
		(width 0.1651)
		(layer "In13.Cu")
		(net "CLK_100M_DB800ZL_SSD3_R_DN")
	)
	(segment
		(start 111.448342 -55.79491)
		(end 112.046766 -56.393334)
		(width 0.1651)
		(layer "In13.Cu")
		(net "CLK_100M_DB800ZL_SSD3_R_DN")
	)
	(segment
		(start 113.053876 -62.536324)
		(end 113.053876 -62.733936)
		(width 0.1651)
		(layer "In13.Cu")
		(net "CLK_100M_DB800ZL_SSD3_R_DN")
	)
	(segment
		(start 111.37519 -60.857638)
		(end 111.37519 -61.065918)
		(width 0.1651)
		(layer "In13.Cu")
		(net "CLK_100M_DB800ZL_SSD3_R_DN")
	)
	(segment
		(start 115.270534 -62.159388)
		(end 117.802406 -64.69126)
		(width 0.1651)
		(layer "In13.Cu")
		(net "CLK_100M_DB800ZL_SSD3_R_DN")
	)
	(segment
		(start 111.012986 -55.79491)
		(end 111.448342 -55.79491)
		(width 0.1651)
		(layer "In13.Cu")
		(net "CLK_100M_DB800ZL_SSD3_R_DN")
	)
	(segment
		(start 113.725452 -58.07202)
		(end 113.725452 -58.507376)
		(width 0.1651)
		(layer "In13.Cu")
		(net "CLK_100M_DB800ZL_SSD3_R_DN")
	)
	(segment
		(start 113.053876 -62.733936)
		(end 113.49355 -63.17361)
		(width 0.1651)
		(layer "In13.Cu")
		(net "CLK_100M_DB800ZL_SSD3_R_DN")
	)
	(segment
		(start 117.802406 -64.69126)
		(end 118.142004 -64.69126)
		(width 0.1651)
		(layer "In13.Cu")
		(net "CLK_100M_DB800ZL_SSD3_R_DN")
	)
	(segment
		(start 115.404138 -59.750706)
		(end 115.404138 -60.186062)
		(width 0.1651)
		(layer "In13.Cu")
		(net "CLK_100M_DB800ZL_SSD3_R_DN")
	)
	(segment
		(start 115.404138 -60.186062)
		(end 113.053876 -62.536324)
		(width 0.1651)
		(layer "In13.Cu")
		(net "CLK_100M_DB800ZL_SSD3_R_DN")
	)
	(segment
		(start 110.25632 -55.261764)
		(end 108.025438 -57.492646)
		(width 0.1651)
		(layer "In13.Cu")
		(net "CLK_100M_DB800ZL_SSD3_R_DN")
	)
	(segment
		(start 110.34141 -59.823858)
		(end 112.691672 -57.473596)
		(width 0.1651)
		(layer "In13.Cu")
		(net "CLK_100M_DB800ZL_SSD3_R_DN")
	)
	(segment
		(start 103.786432 -31.031942)
		(end 103.786432 -35.904932)
		(width 0.1651)
		(layer "In13.Cu")
		(net "CLK_100M_DB800ZL_SSD3_R_DN")
	)
	(segment
		(start 114.709956 -62.159388)
		(end 115.270534 -62.159388)
		(width 0.1651)
		(layer "In13.Cu")
		(net "CLK_100M_DB800ZL_SSD3_R_DN")
	)
	(segment
		(start 94.981268 -26.479246)
		(end 95.268288 -26.766266)
		(width 0.1651)
		(layer "In13.Cu")
		(net "CLK_100M_DB800ZL_SSD3_R_DN")
	)
	(segment
		(start 112.020096 -61.502544)
		(end 114.370358 -59.152282)
		(width 0.1651)
		(layer "In13.Cu")
		(net "CLK_100M_DB800ZL_SSD3_R_DN")
	)
	(segment
		(start 123.803664 -78.728316)
		(end 119.460264 -83.071716)
		(width 0.1651)
		(layer "In13.Cu")
		(net "CLK_100M_DB800ZL_SSD3_R_DN")
	)
	(segment
		(start 119.460264 -83.071716)
		(end 117.368066 -83.071716)
		(width 0.1651)
		(layer "In13.Cu")
		(net "CLK_100M_DB800ZL_SSD3_R_DN")
	)
	(segment
		(start 108.025438 -57.492646)
		(end 108.025438 -57.705498)
		(width 0.1651)
		(layer "In13.Cu")
		(net "CLK_100M_DB800ZL_SSD3_R_DN")
	)
	(segment
		(start 112.046766 -56.82869)
		(end 109.696504 -59.178952)
		(width 0.1651)
		(layer "In13.Cu")
		(net "CLK_100M_DB800ZL_SSD3_R_DN")
	)
	(segment
		(start 114.370358 -59.152282)
		(end 114.805714 -59.152282)
		(width 0.1651)
		(layer "In13.Cu")
		(net "CLK_100M_DB800ZL_SSD3_R_DN")
	)
	(segment
		(start 96.836992 -26.766266)
		(end 97.088198 -27.017472)
		(width 0.1651)
		(layer "In13.Cu")
		(net "CLK_100M_DB800ZL_SSD3_R_DN")
	)
	(segment
		(start 112.691672 -57.473596)
		(end 113.127028 -57.473596)
		(width 0.1651)
		(layer "In13.Cu")
		(net "CLK_100M_DB800ZL_SSD3_R_DN")
	)
	(segment
		(start 112.046766 -56.393334)
		(end 112.046766 -56.82869)
		(width 0.1651)
		(layer "In13.Cu")
		(net "CLK_100M_DB800ZL_SSD3_R_DN")
	)
	(segment
		(start 111.37519 -61.065918)
		(end 111.811816 -61.502544)
		(width 0.1651)
		(layer "In13.Cu")
		(net "CLK_100M_DB800ZL_SSD3_R_DN")
	)
	(segment
		(start 118.142004 -64.69126)
		(end 123.803664 -70.35292)
		(width 0.1651)
		(layer "In13.Cu")
		(net "CLK_100M_DB800ZL_SSD3_R_DN")
	)
	(segment
		(start 123.803664 -70.35292)
		(end 123.803664 -78.728316)
		(width 0.1651)
		(layer "In13.Cu")
		(net "CLK_100M_DB800ZL_SSD3_R_DN")
	)
	(segment
		(start 114.805714 -59.152282)
		(end 115.404138 -59.750706)
		(width 0.1651)
		(layer "In13.Cu")
		(net "CLK_100M_DB800ZL_SSD3_R_DN")
	)
	(segment
		(start 113.127028 -57.473596)
		(end 113.725452 -58.07202)
		(width 0.1651)
		(layer "In13.Cu")
		(net "CLK_100M_DB800ZL_SSD3_R_DN")
	)
	(segment
		(start 113.695734 -63.17361)
		(end 114.709956 -62.159388)
		(width 0.1651)
		(layer "In13.Cu")
		(net "CLK_100M_DB800ZL_SSD3_R_DN")
	)
	(segment
		(start 108.2294 -52.4256)
		(end 110.25632 -54.45252)
		(width 0.1651)
		(layer "In13.Cu")
		(net "CLK_100M_DB800ZL_SSD3_R_DN")
	)
	(segment
		(start 108.025438 -57.705498)
		(end 108.457492 -58.137552)
		(width 0.1651)
		(layer "In13.Cu")
		(net "CLK_100M_DB800ZL_SSD3_R_DN")
	)
	(segment
		(start 108.2294 -44.212256)
		(end 108.2294 -52.4256)
		(width 0.1651)
		(layer "In13.Cu")
		(net "CLK_100M_DB800ZL_SSD3_R_DN")
	)
	(segment
		(start 110.25632 -54.45252)
		(end 110.25632 -55.261764)
		(width 0.1651)
		(layer "In13.Cu")
		(net "CLK_100M_DB800ZL_SSD3_R_DN")
	)
	(segment
		(start 109.696504 -59.178952)
		(end 109.696504 -59.387232)
		(width 0.1651)
		(layer "In13.Cu")
		(net "CLK_100M_DB800ZL_SSD3_R_DN")
	)
	(segment
		(start 143.490442 -251.158502)
		(end 143.490442 -250.470924)
		(width 0.13208)
		(layer "F.Cu")
		(net "PEX1_MODE_SEL5")
	)
	(segment
		(start 175.749966 -282.599892)
		(end 176.224946 -283.074872)
		(width 0.1651)
		(layer "F.Cu")
		(net "PEX1_MODE_SEL5")
	)
	(segment
		(start 143.490442 -251.956824)
		(end 143.490442 -251.158502)
		(width 0.13208)
		(layer "F.Cu")
		(net "PEX1_MODE_SEL5")
	)
	(via
		(at 143.490442 -251.158502)
		(size 0.508)
		(drill 0.254)
		(layers "F.Cu" "B.Cu")
		(net "PEX1_MODE_SEL5")
	)
	(via
		(at 176.224946 -283.074872)
		(size 0.4064)
		(drill 0.2032)
		(layers "F.Cu" "B.Cu")
		(net "PEX1_MODE_SEL5")
	)
	(via
		(at 173.039024 -268.21765)
		(size 0.6604)
		(drill 0.3302)
		(layers "F.Cu" "B.Cu")
		(net "PEX1_MODE_SEL5")
	)
	(segment
		(start 165.069774 -260.2484)
		(end 155.905454 -260.2484)
		(width 0.13208)
		(layer "B.Cu")
		(net "PEX1_MODE_SEL5")
	)
	(segment
		(start 176.263046 -283.036772)
		(end 176.263046 -271.441672)
		(width 0.13208)
		(layer "B.Cu")
		(net "PEX1_MODE_SEL5")
	)
	(segment
		(start 143.717264 -255.927352)
		(end 142.997682 -255.20777)
		(width 0.13208)
		(layer "B.Cu")
		(net "PEX1_MODE_SEL5")
	)
	(segment
		(start 142.997682 -251.651262)
		(end 143.490442 -251.158502)
		(width 0.13208)
		(layer "B.Cu")
		(net "PEX1_MODE_SEL5")
	)
	(segment
		(start 148.1074 -258.9784)
		(end 145.211546 -258.9784)
		(width 0.13208)
		(layer "B.Cu")
		(net "PEX1_MODE_SEL5")
	)
	(segment
		(start 176.263046 -271.441672)
		(end 173.039024 -268.21765)
		(width 0.13208)
		(layer "B.Cu")
		(net "PEX1_MODE_SEL5")
	)
	(segment
		(start 143.717264 -257.484118)
		(end 143.717264 -255.927352)
		(width 0.13208)
		(layer "B.Cu")
		(net "PEX1_MODE_SEL5")
	)
	(segment
		(start 176.224946 -283.074872)
		(end 176.263046 -283.036772)
		(width 0.13208)
		(layer "B.Cu")
		(net "PEX1_MODE_SEL5")
	)
	(segment
		(start 173.039024 -268.21765)
		(end 165.069774 -260.2484)
		(width 0.13208)
		(layer "B.Cu")
		(net "PEX1_MODE_SEL5")
	)
	(segment
		(start 155.905454 -260.2484)
		(end 154.914854 -261.239)
		(width 0.13208)
		(layer "B.Cu")
		(net "PEX1_MODE_SEL5")
	)
	(segment
		(start 154.914854 -261.239)
		(end 150.368 -261.239)
		(width 0.13208)
		(layer "B.Cu")
		(net "PEX1_MODE_SEL5")
	)
	(segment
		(start 150.368 -261.239)
		(end 148.1074 -258.9784)
		(width 0.13208)
		(layer "B.Cu")
		(net "PEX1_MODE_SEL5")
	)
	(segment
		(start 142.997682 -255.20777)
		(end 142.997682 -251.651262)
		(width 0.13208)
		(layer "B.Cu")
		(net "PEX1_MODE_SEL5")
	)
	(segment
		(start 145.211546 -258.9784)
		(end 143.717264 -257.484118)
		(width 0.13208)
		(layer "B.Cu")
		(net "PEX1_MODE_SEL5")
	)
	(segment
		(start 411.750002 -282.599892)
		(end 412.224982 -283.074872)
		(width 0.1651)
		(layer "F.Cu")
		(net "PEX3_MODE_SEL8")
	)
	(segment
		(start 380.770384 -251.158502)
		(end 380.770384 -251.956824)
		(width 0.13208)
		(layer "F.Cu")
		(net "PEX3_MODE_SEL8")
	)
	(segment
		(start 380.770384 -250.470924)
		(end 380.770384 -251.158502)
		(width 0.13208)
		(layer "F.Cu")
		(net "PEX3_MODE_SEL8")
	)
	(via
		(at 380.770384 -251.158502)
		(size 0.508)
		(drill 0.254)
		(layers "F.Cu" "B.Cu")
		(net "PEX3_MODE_SEL8")
	)
	(via
		(at 412.224982 -283.074872)
		(size 0.4064)
		(drill 0.2032)
		(layers "F.Cu" "B.Cu")
		(net "PEX3_MODE_SEL8")
	)
	(segment
		(start 380.770384 -251.158502)
		(end 380.296928 -251.631958)
		(width 0.13208)
		(layer "B.Cu")
		(net "PEX3_MODE_SEL8")
	)
	(segment
		(start 396.823946 -255.723898)
		(end 408.172158 -267.07211)
		(width 0.13208)
		(layer "B.Cu")
		(net "PEX3_MODE_SEL8")
	)
	(segment
		(start 383.425954 -255.108456)
		(end 384.041396 -255.723898)
		(width 0.13208)
		(layer "B.Cu")
		(net "PEX3_MODE_SEL8")
	)
	(segment
		(start 409.525724 -268.677898)
		(end 409.7782 -268.677898)
		(width 0.13208)
		(layer "B.Cu")
		(net "PEX3_MODE_SEL8")
	)
	(segment
		(start 409.7782 -268.677898)
		(end 413.135064 -272.034762)
		(width 0.13208)
		(layer "B.Cu")
		(net "PEX3_MODE_SEL8")
	)
	(segment
		(start 384.041396 -255.723898)
		(end 396.823946 -255.723898)
		(width 0.13208)
		(layer "B.Cu")
		(net "PEX3_MODE_SEL8")
	)
	(segment
		(start 413.135064 -282.16479)
		(end 412.224982 -283.074872)
		(width 0.13208)
		(layer "B.Cu")
		(net "PEX3_MODE_SEL8")
	)
	(segment
		(start 381.501904 -255.108456)
		(end 383.425954 -255.108456)
		(width 0.13208)
		(layer "B.Cu")
		(net "PEX3_MODE_SEL8")
	)
	(segment
		(start 413.135064 -272.034762)
		(end 413.135064 -282.16479)
		(width 0.13208)
		(layer "B.Cu")
		(net "PEX3_MODE_SEL8")
	)
	(segment
		(start 408.172158 -267.324332)
		(end 409.525724 -268.677898)
		(width 0.13208)
		(layer "B.Cu")
		(net "PEX3_MODE_SEL8")
	)
	(segment
		(start 380.296928 -251.631958)
		(end 380.296928 -253.90348)
		(width 0.13208)
		(layer "B.Cu")
		(net "PEX3_MODE_SEL8")
	)
	(segment
		(start 380.296928 -253.90348)
		(end 381.501904 -255.108456)
		(width 0.13208)
		(layer "B.Cu")
		(net "PEX3_MODE_SEL8")
	)
	(segment
		(start 408.172158 -267.07211)
		(end 408.172158 -267.324332)
		(width 0.13208)
		(layer "B.Cu")
		(net "PEX3_MODE_SEL8")
	)
	(segment
		(start 224.267776 -222.304102)
		(end 223.86798 -222.703898)
		(width 0.13208)
		(layer "F.Cu")
		(net "SMB_FIO_SDA")
	)
	(via
		(at 223.86798 -222.703898)
		(size 0.4572)
		(drill 0.254)
		(layers "F.Cu" "B.Cu")
		(net "SMB_FIO_SDA")
	)
	(via
		(at 218.341956 -225.512884)
		(size 0.508)
		(drill 0.254)
		(layers "F.Cu" "B.Cu")
		(net "SMB_FIO_SDA")
	)
	(via
		(at 214.874856 -225.42246)
		(size 0.508)
		(drill 0.254)
		(layers "F.Cu" "B.Cu")
		(net "SMB_FIO_SDA")
	)
	(via
		(at 220.71203 -225.414586)
		(size 0.6604)
		(drill 0.3302)
		(layers "F.Cu" "B.Cu")
		(net "SMB_FIO_SDA")
	)
	(segment
		(start 218.289378 -225.477578)
		(end 218.3257 -225.5139)
		(width 0.13208)
		(layer "B.Cu")
		(net "SMB_FIO_SDA")
	)
	(segment
		(start 218.3257 -225.512884)
		(end 218.341956 -225.512884)
		(width 0.13208)
		(layer "B.Cu")
		(net "SMB_FIO_SDA")
	)
	(segment
		(start 218.341956 -225.512884)
		(end 220.613732 -225.512884)
		(width 0.13208)
		(layer "B.Cu")
		(net "SMB_FIO_SDA")
	)
	(segment
		(start 221.157292 -225.414586)
		(end 223.86798 -222.703898)
		(width 0.13208)
		(layer "B.Cu")
		(net "SMB_FIO_SDA")
	)
	(segment
		(start 217.64371 -225.477578)
		(end 218.289378 -225.477578)
		(width 0.13208)
		(layer "B.Cu")
		(net "SMB_FIO_SDA")
	)
	(segment
		(start 214.10676 -225.42246)
		(end 214.874856 -225.42246)
		(width 0.13208)
		(layer "B.Cu")
		(net "SMB_FIO_SDA")
	)
	(segment
		(start 218.3257 -225.5139)
		(end 218.3257 -225.512884)
		(width 0.13208)
		(layer "B.Cu")
		(net "SMB_FIO_SDA")
	)
	(segment
		(start 220.613732 -225.512884)
		(end 220.71203 -225.414586)
		(width 0.13208)
		(layer "B.Cu")
		(net "SMB_FIO_SDA")
	)
	(segment
		(start 220.71203 -225.414586)
		(end 221.157292 -225.414586)
		(width 0.13208)
		(layer "B.Cu")
		(net "SMB_FIO_SDA")
	)
	(segment
		(start 217.885264 -225.056192)
		(end 215.241124 -225.056192)
		(width 0.15494)
		(layer "In15.Cu")
		(net "SMB_FIO_SDA")
	)
	(segment
		(start 215.241124 -225.056192)
		(end 214.874856 -225.42246)
		(width 0.15494)
		(layer "In15.Cu")
		(net "SMB_FIO_SDA")
	)
	(segment
		(start 218.341956 -225.512884)
		(end 217.885264 -225.056192)
		(width 0.15494)
		(layer "In15.Cu")
		(net "SMB_FIO_SDA")
	)
	(segment
		(start 148.66366 -383.477516)
		(end 148.680678 -383.460498)
		(width 0.13208)
		(layer "F.Cu")
		(net "RST_GPU_FPGA_EROT_N")
	)
	(segment
		(start 148.66366 -384.566668)
		(end 148.66366 -383.477516)
		(width 0.13208)
		(layer "F.Cu")
		(net "RST_GPU_FPGA_EROT_N")
	)
	(segment
		(start 148.680678 -383.460498)
		(end 147.777962 -383.460498)
		(width 0.13208)
		(layer "F.Cu")
		(net "RST_GPU_FPGA_EROT_N")
	)
	(via
		(at 147.777962 -383.460498)
		(size 0.508)
		(drill 0.254)
		(layers "F.Cu" "B.Cu")
		(net "RST_GPU_FPGA_EROT_N")
	)
	(segment
		(start 145.322798 -378.602748)
		(end 145.322798 -381.863854)
		(width 0.15494)
		(layer "In9.Cu")
		(net "RST_GPU_FPGA_EROT_N")
	)
	(segment
		(start 145.322798 -381.863854)
		(end 146.919442 -383.460498)
		(width 0.15494)
		(layer "In9.Cu")
		(net "RST_GPU_FPGA_EROT_N")
	)
	(segment
		(start 146.919442 -383.460498)
		(end 147.777962 -383.460498)
		(width 0.15494)
		(layer "In9.Cu")
		(net "RST_GPU_FPGA_EROT_N")
	)
	(segment
		(start 135.710168 -368.990118)
		(end 145.322798 -378.602748)
		(width 0.15494)
		(layer "In9.Cu")
		(net "RST_GPU_FPGA_EROT_N")
	)
	(segment
		(start 219.701364 -53.051456)
		(end 219.96781 -53.051456)
		(width 0.13208)
		(layer "F.Cu")
		(net "PWRGD_P12V_SSD7")
	)
	(segment
		(start 218.247214 -53.644038)
		(end 218.616276 -53.644038)
		(width 0.13208)
		(layer "F.Cu")
		(net "PWRGD_P12V_SSD7")
	)
	(segment
		(start 219.96781 -52.035456)
		(end 219.96781 -53.051456)
		(width 0.13208)
		(layer "F.Cu")
		(net "PWRGD_P12V_SSD7")
	)
	(segment
		(start 218.616276 -53.644038)
		(end 219.237306 -53.023008)
		(width 0.13208)
		(layer "F.Cu")
		(net "PWRGD_P12V_SSD7")
	)
	(segment
		(start 219.237306 -52.587398)
		(end 219.701364 -53.051456)
		(width 0.13208)
		(layer "F.Cu")
		(net "PWRGD_P12V_SSD7")
	)
	(segment
		(start 219.237306 -53.023008)
		(end 219.237306 -52.587398)
		(width 0.13208)
		(layer "F.Cu")
		(net "PWRGD_P12V_SSD7")
	)
	(via
		(at 219.237306 -52.587398)
		(size 0.508)
		(drill 0.254)
		(layers "F.Cu" "B.Cu")
		(net "PWRGD_P12V_SSD7")
	)
	(segment
		(start 364.236 -205.867)
		(end 364.49 -205.613)
		(width 0.13208)
		(layer "F.Cu")
		(net "RST_PEX_SSD1_PERST_R_N")
	)
	(segment
		(start 364.49 -205.613)
		(end 364.744 -205.867)
		(width 0.13208)
		(layer "F.Cu")
		(net "RST_PEX_SSD1_PERST_R_N")
	)
	(segment
		(start 344.49385 -212.786976)
		(end 344.893646 -212.38718)
		(width 0.13208)
		(layer "F.Cu")
		(net "RST_PEX_SSD1_PERST_R_N")
	)
	(segment
		(start 364.744 -205.867)
		(end 365.10595 -205.867)
		(width 0.13208)
		(layer "F.Cu")
		(net "RST_PEX_SSD1_PERST_R_N")
	)
	(segment
		(start 363.87405 -205.867)
		(end 364.236 -205.867)
		(width 0.13208)
		(layer "F.Cu")
		(net "RST_PEX_SSD1_PERST_R_N")
	)
	(via
		(at 364.49 -205.613)
		(size 0.508)
		(drill 0.254)
		(layers "F.Cu" "B.Cu")
		(net "RST_PEX_SSD1_PERST_R_N")
	)
	(via
		(at 344.893646 -212.38718)
		(size 0.4572)
		(drill 0.254)
		(layers "F.Cu" "B.Cu")
		(net "RST_PEX_SSD1_PERST_R_N")
	)
	(segment
		(start 361.729274 -206.375)
		(end 363.728 -206.375)
		(width 0.15494)
		(layer "In13.Cu")
		(net "RST_PEX_SSD1_PERST_R_N")
	)
	(segment
		(start 357.7844 -208.795366)
		(end 359.308908 -208.795366)
		(width 0.15494)
		(layer "In13.Cu")
		(net "RST_PEX_SSD1_PERST_R_N")
	)
	(segment
		(start 357.512366 -209.0674)
		(end 357.7844 -208.795366)
		(width 0.15494)
		(layer "In13.Cu")
		(net "RST_PEX_SSD1_PERST_R_N")
	)
	(segment
		(start 359.308908 -208.795366)
		(end 361.729274 -206.375)
		(width 0.15494)
		(layer "In13.Cu")
		(net "RST_PEX_SSD1_PERST_R_N")
	)
	(segment
		(start 344.3986 -211.892134)
		(end 344.3986 -210.7438)
		(width 0.15494)
		(layer "In13.Cu")
		(net "RST_PEX_SSD1_PERST_R_N")
	)
	(segment
		(start 346.075 -209.0674)
		(end 357.512366 -209.0674)
		(width 0.15494)
		(layer "In13.Cu")
		(net "RST_PEX_SSD1_PERST_R_N")
	)
	(segment
		(start 344.3986 -210.7438)
		(end 346.075 -209.0674)
		(width 0.15494)
		(layer "In13.Cu")
		(net "RST_PEX_SSD1_PERST_R_N")
	)
	(segment
		(start 363.728 -206.375)
		(end 364.49 -205.613)
		(width 0.15494)
		(layer "In13.Cu")
		(net "RST_PEX_SSD1_PERST_R_N")
	)
	(segment
		(start 344.893646 -212.38718)
		(end 344.3986 -211.892134)
		(width 0.15494)
		(layer "In13.Cu")
		(net "RST_PEX_SSD1_PERST_R_N")
	)
	(segment
		(start 15.907512 -27.051)
		(end 15.768574 -27.189938)
		(width 0.13462)
		(layer "F.Cu")
		(net "CLK_100M_DB800ZL_SSD0_R_DP")
	)
	(segment
		(start 16.689578 -27.051)
		(end 15.907512 -27.051)
		(width 0.13462)
		(layer "F.Cu")
		(net "CLK_100M_DB800ZL_SSD0_R_DP")
	)
	(segment
		(start 15.768574 -27.189938)
		(end 15.264892 -27.189938)
		(width 0.13462)
		(layer "F.Cu")
		(net "CLK_100M_DB800ZL_SSD0_R_DP")
	)
	(segment
		(start 105.89768 -77.625702)
		(end 105.607358 -77.33538)
		(width 0.13462)
		(layer "F.Cu")
		(net "CLK_100M_DB800ZL_SSD0_R_DP")
	)
	(segment
		(start 16.981424 -27.342846)
		(end 16.689578 -27.051)
		(width 0.13462)
		(layer "F.Cu")
		(net "CLK_100M_DB800ZL_SSD0_R_DP")
	)
	(segment
		(start 105.581958 -79.422244)
		(end 105.89768 -79.106522)
		(width 0.13462)
		(layer "F.Cu")
		(net "CLK_100M_DB800ZL_SSD0_R_DP")
	)
	(segment
		(start 105.89768 -79.106522)
		(end 105.89768 -77.625702)
		(width 0.13462)
		(layer "F.Cu")
		(net "CLK_100M_DB800ZL_SSD0_R_DP")
	)
	(via
		(at 16.981424 -27.342846)
		(size 0.508)
		(drill 0.254)
		(layers "F.Cu" "B.Cu")
		(net "CLK_100M_DB800ZL_SSD0_R_DP")
	)
	(via
		(at 105.607358 -77.33538)
		(size 0.508)
		(drill 0.254)
		(layers "F.Cu" "B.Cu")
		(net "CLK_100M_DB800ZL_SSD0_R_DP")
	)
	(segment
		(start 22.100032 -28.196032)
		(end 22.450044 -28.546044)
		(width 0.1651)
		(layer "In13.Cu")
		(net "CLK_100M_DB800ZL_SSD0_R_DP")
	)
	(segment
		(start 105.17378 -76.5556)
		(end 105.642918 -76.5556)
		(width 0.1651)
		(layer "In13.Cu")
		(net "CLK_100M_DB800ZL_SSD0_R_DP")
	)
	(segment
		(start 36.64966 -45.97146)
		(end 37.9476 -59.150504)
		(width 0.1651)
		(layer "In13.Cu")
		(net "CLK_100M_DB800ZL_SSD0_R_DP")
	)
	(segment
		(start 22.962362 -29.058362)
		(end 23.312374 -29.408374)
		(width 0.1651)
		(layer "In13.Cu")
		(net "CLK_100M_DB800ZL_SSD0_R_DP")
	)
	(segment
		(start 24.174704 -30.432502)
		(end 24.525224 -30.783022)
		(width 0.1651)
		(layer "In13.Cu")
		(net "CLK_100M_DB800ZL_SSD0_R_DP")
	)
	(segment
		(start 103.72598 -78.0034)
		(end 105.17378 -76.5556)
		(width 0.1651)
		(layer "In13.Cu")
		(net "CLK_100M_DB800ZL_SSD0_R_DP")
	)
	(segment
		(start 23.312374 -29.570172)
		(end 23.662894 -29.920692)
		(width 0.1651)
		(layer "In13.Cu")
		(net "CLK_100M_DB800ZL_SSD0_R_DP")
	)
	(segment
		(start 105.898188 -77.04455)
		(end 105.607358 -77.33538)
		(width 0.1651)
		(layer "In13.Cu")
		(net "CLK_100M_DB800ZL_SSD0_R_DP")
	)
	(segment
		(start 26.0604 -35.3822)
		(end 36.64966 -45.97146)
		(width 0.1651)
		(layer "In13.Cu")
		(net "CLK_100M_DB800ZL_SSD0_R_DP")
	)
	(segment
		(start 18.3896 -27.305)
		(end 21.209 -27.305)
		(width 0.1651)
		(layer "In13.Cu")
		(net "CLK_100M_DB800ZL_SSD0_R_DP")
	)
	(segment
		(start 23.662894 -29.920692)
		(end 23.824692 -29.920692)
		(width 0.1651)
		(layer "In13.Cu")
		(net "CLK_100M_DB800ZL_SSD0_R_DP")
	)
	(segment
		(start 105.898188 -76.81087)
		(end 105.898188 -77.04455)
		(width 0.1651)
		(layer "In13.Cu")
		(net "CLK_100M_DB800ZL_SSD0_R_DP")
	)
	(segment
		(start 24.525224 -30.783022)
		(end 24.687022 -30.783022)
		(width 0.1651)
		(layer "In13.Cu")
		(net "CLK_100M_DB800ZL_SSD0_R_DP")
	)
	(segment
		(start 105.642918 -76.5556)
		(end 105.898188 -76.81087)
		(width 0.1651)
		(layer "In13.Cu")
		(net "CLK_100M_DB800ZL_SSD0_R_DP")
	)
	(segment
		(start 22.450044 -28.546044)
		(end 22.450044 -28.707842)
		(width 0.1651)
		(layer "In13.Cu")
		(net "CLK_100M_DB800ZL_SSD0_R_DP")
	)
	(segment
		(start 16.981424 -27.342846)
		(end 17.27327 -27.051)
		(width 0.1651)
		(layer "In13.Cu")
		(net "CLK_100M_DB800ZL_SSD0_R_DP")
	)
	(segment
		(start 90.424 -78.0034)
		(end 103.72598 -78.0034)
		(width 0.1651)
		(layer "In13.Cu")
		(net "CLK_100M_DB800ZL_SSD0_R_DP")
	)
	(segment
		(start 24.174704 -30.270704)
		(end 24.174704 -30.432502)
		(width 0.1651)
		(layer "In13.Cu")
		(net "CLK_100M_DB800ZL_SSD0_R_DP")
	)
	(segment
		(start 21.587968 -27.845512)
		(end 21.938488 -28.196032)
		(width 0.1651)
		(layer "In13.Cu")
		(net "CLK_100M_DB800ZL_SSD0_R_DP")
	)
	(segment
		(start 23.312374 -29.408374)
		(end 23.312374 -29.570172)
		(width 0.1651)
		(layer "In13.Cu")
		(net "CLK_100M_DB800ZL_SSD0_R_DP")
	)
	(segment
		(start 37.9476 -73.24598)
		(end 41.07942 -76.3778)
		(width 0.1651)
		(layer "In13.Cu")
		(net "CLK_100M_DB800ZL_SSD0_R_DP")
	)
	(segment
		(start 23.824692 -29.920692)
		(end 24.174704 -30.270704)
		(width 0.1651)
		(layer "In13.Cu")
		(net "CLK_100M_DB800ZL_SSD0_R_DP")
	)
	(segment
		(start 24.687022 -30.783022)
		(end 26.0604 -32.1564)
		(width 0.1651)
		(layer "In13.Cu")
		(net "CLK_100M_DB800ZL_SSD0_R_DP")
	)
	(segment
		(start 22.450044 -28.707842)
		(end 22.800564 -29.058362)
		(width 0.1651)
		(layer "In13.Cu")
		(net "CLK_100M_DB800ZL_SSD0_R_DP")
	)
	(segment
		(start 18.1356 -27.051)
		(end 18.3896 -27.305)
		(width 0.1651)
		(layer "In13.Cu")
		(net "CLK_100M_DB800ZL_SSD0_R_DP")
	)
	(segment
		(start 41.07942 -76.3778)
		(end 88.7984 -76.3778)
		(width 0.1651)
		(layer "In13.Cu")
		(net "CLK_100M_DB800ZL_SSD0_R_DP")
	)
	(segment
		(start 88.7984 -76.3778)
		(end 90.424 -78.0034)
		(width 0.1651)
		(layer "In13.Cu")
		(net "CLK_100M_DB800ZL_SSD0_R_DP")
	)
	(segment
		(start 22.800564 -29.058362)
		(end 22.962362 -29.058362)
		(width 0.1651)
		(layer "In13.Cu")
		(net "CLK_100M_DB800ZL_SSD0_R_DP")
	)
	(segment
		(start 17.27327 -27.051)
		(end 18.1356 -27.051)
		(width 0.1651)
		(layer "In13.Cu")
		(net "CLK_100M_DB800ZL_SSD0_R_DP")
	)
	(segment
		(start 21.209 -27.305)
		(end 21.587968 -27.683968)
		(width 0.1651)
		(layer "In13.Cu")
		(net "CLK_100M_DB800ZL_SSD0_R_DP")
	)
	(segment
		(start 21.938488 -28.196032)
		(end 22.100032 -28.196032)
		(width 0.1651)
		(layer "In13.Cu")
		(net "CLK_100M_DB800ZL_SSD0_R_DP")
	)
	(segment
		(start 21.587968 -27.683968)
		(end 21.587968 -27.845512)
		(width 0.1651)
		(layer "In13.Cu")
		(net "CLK_100M_DB800ZL_SSD0_R_DP")
	)
	(segment
		(start 37.9476 -59.150504)
		(end 37.9476 -73.24598)
		(width 0.1651)
		(layer "In13.Cu")
		(net "CLK_100M_DB800ZL_SSD0_R_DP")
	)
	(segment
		(start 26.0604 -32.1564)
		(end 26.0604 -35.3822)
		(width 0.1651)
		(layer "In13.Cu")
		(net "CLK_100M_DB800ZL_SSD0_R_DP")
	)
	(segment
		(start 401.299934 -309.199788)
		(end 400.824954 -308.724808)
		(width 0.13208)
		(layer "F.Cu")
		(net "PEX3_DBG_SEL0")
	)
	(segment
		(start 376.688096 -307.36794)
		(end 375.969784 -308.086252)
		(width 0.13208)
		(layer "F.Cu")
		(net "PEX3_DBG_SEL0")
	)
	(segment
		(start 375.969784 -308.086252)
		(end 376.33402 -308.450488)
		(width 0.13208)
		(layer "F.Cu")
		(net "PEX3_DBG_SEL0")
	)
	(segment
		(start 376.33402 -308.450488)
		(end 376.760232 -308.450488)
		(width 0.13208)
		(layer "F.Cu")
		(net "PEX3_DBG_SEL0")
	)
	(via
		(at 376.760232 -308.450488)
		(size 0.508)
		(drill 0.254)
		(layers "F.Cu" "B.Cu")
		(net "PEX3_DBG_SEL0")
	)
	(via
		(at 400.824954 -308.724808)
		(size 0.4064)
		(drill 0.2032)
		(layers "F.Cu" "B.Cu")
		(net "PEX3_DBG_SEL0")
	)
	(segment
		(start 396.54988 -307.585364)
		(end 396.230094 -307.265578)
		(width 0.13208)
		(layer "B.Cu")
		(net "PEX3_DBG_SEL0")
	)
	(segment
		(start 400.266408 -308.166262)
		(end 396.705836 -308.166262)
		(width 0.13208)
		(layer "B.Cu")
		(net "PEX3_DBG_SEL0")
	)
	(segment
		(start 393.911074 -305.900074)
		(end 381.044704 -305.900074)
		(width 0.13208)
		(layer "B.Cu")
		(net "PEX3_DBG_SEL0")
	)
	(segment
		(start 394.407136 -306.923694)
		(end 394.407136 -306.396136)
		(width 0.13208)
		(layer "B.Cu")
		(net "PEX3_DBG_SEL0")
	)
	(segment
		(start 396.230094 -307.265578)
		(end 394.74902 -307.265578)
		(width 0.13208)
		(layer "B.Cu")
		(net "PEX3_DBG_SEL0")
	)
	(segment
		(start 394.407136 -306.396136)
		(end 393.911074 -305.900074)
		(width 0.13208)
		(layer "B.Cu")
		(net "PEX3_DBG_SEL0")
	)
	(segment
		(start 396.705836 -308.166262)
		(end 396.54988 -308.010306)
		(width 0.13208)
		(layer "B.Cu")
		(net "PEX3_DBG_SEL0")
	)
	(segment
		(start 396.54988 -308.010306)
		(end 396.54988 -307.585364)
		(width 0.13208)
		(layer "B.Cu")
		(net "PEX3_DBG_SEL0")
	)
	(segment
		(start 381.044704 -305.900074)
		(end 378.49429 -308.450488)
		(width 0.13208)
		(layer "B.Cu")
		(net "PEX3_DBG_SEL0")
	)
	(segment
		(start 400.824954 -308.724808)
		(end 400.266408 -308.166262)
		(width 0.13208)
		(layer "B.Cu")
		(net "PEX3_DBG_SEL0")
	)
	(segment
		(start 394.74902 -307.265578)
		(end 394.407136 -306.923694)
		(width 0.13208)
		(layer "B.Cu")
		(net "PEX3_DBG_SEL0")
	)
	(segment
		(start 378.49429 -308.450488)
		(end 376.760232 -308.450488)
		(width 0.13208)
		(layer "B.Cu")
		(net "PEX3_DBG_SEL0")
	)
	(segment
		(start 214.335106 -214.32266)
		(end 214.688928 -214.32266)
		(width 0.13208)
		(layer "F.Cu")
		(net "SMB_NIC6_SDA")
	)
	(segment
		(start 220.744034 -215.32088)
		(end 222.523558 -217.100404)
		(width 0.13208)
		(layer "F.Cu")
		(net "SMB_NIC6_SDA")
	)
	(segment
		(start 218.905328 -214.934038)
		(end 218.209876 -214.238586)
		(width 0.13208)
		(layer "F.Cu")
		(net "SMB_NIC6_SDA")
	)
	(segment
		(start 223.863916 -217.100404)
		(end 224.267776 -217.504264)
		(width 0.13208)
		(layer "F.Cu")
		(net "SMB_NIC6_SDA")
	)
	(segment
		(start 222.523558 -217.100404)
		(end 223.863916 -217.100404)
		(width 0.13208)
		(layer "F.Cu")
		(net "SMB_NIC6_SDA")
	)
	(segment
		(start 218.209876 -214.238586)
		(end 217.635836 -214.238586)
		(width 0.13208)
		(layer "F.Cu")
		(net "SMB_NIC6_SDA")
	)
	(segment
		(start 220.153738 -215.32088)
		(end 220.744034 -215.32088)
		(width 0.13208)
		(layer "F.Cu")
		(net "SMB_NIC6_SDA")
	)
	(segment
		(start 217.130884 -213.733634)
		(end 217.635836 -214.238586)
		(width 0.13208)
		(layer "F.Cu")
		(net "SMB_NIC6_SDA")
	)
	(segment
		(start 215.277954 -213.733634)
		(end 217.130884 -213.733634)
		(width 0.13208)
		(layer "F.Cu")
		(net "SMB_NIC6_SDA")
	)
	(segment
		(start 219.766896 -214.934038)
		(end 220.153738 -215.32088)
		(width 0.13208)
		(layer "F.Cu")
		(net "SMB_NIC6_SDA")
	)
	(segment
		(start 218.905328 -214.934038)
		(end 219.766896 -214.934038)
		(width 0.13208)
		(layer "F.Cu")
		(net "SMB_NIC6_SDA")
	)
	(segment
		(start 214.688928 -214.32266)
		(end 215.277954 -213.733634)
		(width 0.13208)
		(layer "F.Cu")
		(net "SMB_NIC6_SDA")
	)
	(via
		(at 218.905328 -214.934038)
		(size 0.762)
		(drill 0.381)
		(layers "F.Cu" "B.Cu")
		(net "SMB_NIC6_SDA")
	)
	(segment
		(start 337.043014 -240.808002)
		(end 337.043014 -240.142014)
		(width 0.13208)
		(layer "F.Cu")
		(net "MB_SWB_PWR_EN_ISO")
	)
	(segment
		(start 336.931 -240.03)
		(end 336.931 -239.649)
		(width 0.13208)
		(layer "F.Cu")
		(net "MB_SWB_PWR_EN_ISO")
	)
	(segment
		(start 336.931 -239.649)
		(end 336.931 -239.03305)
		(width 0.13208)
		(layer "F.Cu")
		(net "MB_SWB_PWR_EN_ISO")
	)
	(segment
		(start 337.043014 -240.142014)
		(end 336.931 -240.03)
		(width 0.13208)
		(layer "F.Cu")
		(net "MB_SWB_PWR_EN_ISO")
	)
	(via
		(at 336.931 -239.649)
		(size 0.508)
		(drill 0.254)
		(layers "F.Cu" "B.Cu")
		(net "MB_SWB_PWR_EN_ISO")
	)
	(segment
		(start 350.734376 -235.497624)
		(end 350.734376 -236.897418)
		(width 0.13208)
		(layer "F.Cu")
		(net "SSD7_PWR_EN_R")
	)
	(segment
		(start 219.96781 -57.032144)
		(end 219.96781 -56.353456)
		(width 0.13208)
		(layer "F.Cu")
		(net "SSD7_PWR_EN_R")
	)
	(segment
		(start 350.734376 -236.897418)
		(end 351.135442 -237.298484)
		(width 0.13208)
		(layer "F.Cu")
		(net "SSD7_PWR_EN_R")
	)
	(segment
		(start 351.135442 -237.298484)
		(end 351.17024 -237.298484)
		(width 0.13208)
		(layer "F.Cu")
		(net "SSD7_PWR_EN_R")
	)
	(segment
		(start 351.155 -234.46105)
		(end 351.155 -235.077)
		(width 0.13208)
		(layer "F.Cu")
		(net "SSD7_PWR_EN_R")
	)
	(segment
		(start 214.614506 -65.92189)
		(end 214.614506 -65.100962)
		(width 0.13208)
		(layer "F.Cu")
		(net "SSD7_PWR_EN_R")
	)
	(segment
		(start 351.155 -235.077)
		(end 350.734376 -235.497624)
		(width 0.13208)
		(layer "F.Cu")
		(net "SSD7_PWR_EN_R")
	)
	(segment
		(start 218.758516 -55.144162)
		(end 219.96781 -56.353456)
		(width 0.13208)
		(layer "F.Cu")
		(net "SSD7_PWR_EN_R")
	)
	(segment
		(start 218.247214 -55.144162)
		(end 218.758516 -55.144162)
		(width 0.13208)
		(layer "F.Cu")
		(net "SSD7_PWR_EN_R")
	)
	(via
		(at 222.012764 -248.393712)
		(size 0.508)
		(drill 0.254)
		(layers "F.Cu" "B.Cu")
		(net "SSD7_PWR_EN_R")
	)
	(via
		(at 351.155 -235.077)
		(size 0.508)
		(drill 0.254)
		(layers "F.Cu" "B.Cu")
		(net "SSD7_PWR_EN_R")
	)
	(via
		(at 214.614506 -65.100962)
		(size 0.508)
		(drill 0.254)
		(layers "F.Cu" "B.Cu")
		(net "SSD7_PWR_EN_R")
	)
	(via
		(at 219.96781 -57.032144)
		(size 0.508)
		(drill 0.254)
		(layers "F.Cu" "B.Cu")
		(net "SSD7_PWR_EN_R")
	)
	(segment
		(start 214.40267 -91.936824)
		(end 214.40267 -100.69576)
		(width 0.15494)
		(layer "In5.Cu")
		(net "SSD7_PWR_EN_R")
	)
	(segment
		(start 220.133672 -56.866282)
		(end 220.438218 -56.866282)
		(width 0.15494)
		(layer "In5.Cu")
		(net "SSD7_PWR_EN_R")
	)
	(segment
		(start 220.438218 -56.866282)
		(end 220.951806 -57.37987)
		(width 0.15494)
		(layer "In5.Cu")
		(net "SSD7_PWR_EN_R")
	)
	(segment
		(start 220.951806 -57.37987)
		(end 220.951806 -62.543182)
		(width 0.15494)
		(layer "In5.Cu")
		(net "SSD7_PWR_EN_R")
	)
	(segment
		(start 219.3544 -121.804938)
		(end 219.3544 -131.0132)
		(width 0.15494)
		(layer "In5.Cu")
		(net "SSD7_PWR_EN_R")
	)
	(segment
		(start 220.738446 -219.439236)
		(end 220.103446 -220.074236)
		(width 0.15494)
		(layer "In5.Cu")
		(net "SSD7_PWR_EN_R")
	)
	(segment
		(start 220.103446 -223.83369)
		(end 220.1037 -223.833944)
		(width 0.15494)
		(layer "In5.Cu")
		(net "SSD7_PWR_EN_R")
	)
	(segment
		(start 220.1037 -223.833944)
		(end 220.1037 -225.894646)
		(width 0.15494)
		(layer "In5.Cu")
		(net "SSD7_PWR_EN_R")
	)
	(segment
		(start 222.38208 -239.993424)
		(end 222.38208 -246.00789)
		(width 0.15494)
		(layer "In5.Cu")
		(net "SSD7_PWR_EN_R")
	)
	(segment
		(start 220.04655 -75.177396)
		(end 217.68943 -77.534516)
		(width 0.15494)
		(layer "In5.Cu")
		(net "SSD7_PWR_EN_R")
	)
	(segment
		(start 220.575886 -64.691768)
		(end 220.04655 -65.221104)
		(width 0.15494)
		(layer "In5.Cu")
		(net "SSD7_PWR_EN_R")
	)
	(segment
		(start 219.61602 -216.45499)
		(end 220.738446 -217.577416)
		(width 0.15494)
		(layer "In5.Cu")
		(net "SSD7_PWR_EN_R")
	)
	(segment
		(start 211.776056 -183.700166)
		(end 211.776056 -184.645046)
		(width 0.15494)
		(layer "In5.Cu")
		(net "SSD7_PWR_EN_R")
	)
	(segment
		(start 219.96781 -57.032144)
		(end 220.133672 -56.866282)
		(width 0.15494)
		(layer "In5.Cu")
		(net "SSD7_PWR_EN_R")
	)
	(segment
		(start 218.2114 -113.392966)
		(end 218.2114 -120.661938)
		(width 0.15494)
		(layer "In5.Cu")
		(net "SSD7_PWR_EN_R")
	)
	(segment
		(start 220.283278 -57.912508)
		(end 220.283278 -64.451484)
		(width 0.15494)
		(layer "In5.Cu")
		(net "SSD7_PWR_EN_R")
	)
	(segment
		(start 219.96781 -57.59704)
		(end 220.283278 -57.912508)
		(width 0.15494)
		(layer "In5.Cu")
		(net "SSD7_PWR_EN_R")
	)
	(segment
		(start 212.639402 -107.820968)
		(end 218.2114 -113.392966)
		(width 0.15494)
		(layer "In5.Cu")
		(net "SSD7_PWR_EN_R")
	)
	(segment
		(start 220.951806 -62.543182)
		(end 220.575886 -62.919102)
		(width 0.15494)
		(layer "In5.Cu")
		(net "SSD7_PWR_EN_R")
	)
	(segment
		(start 220.283278 -64.451484)
		(end 219.651072 -65.08369)
		(width 0.15494)
		(layer "In5.Cu")
		(net "SSD7_PWR_EN_R")
	)
	(segment
		(start 214.965026 -209.438494)
		(end 219.61602 -214.089488)
		(width 0.15494)
		(layer "In5.Cu")
		(net "SSD7_PWR_EN_R")
	)
	(segment
		(start 217.68943 -77.534516)
		(end 217.68943 -88.650064)
		(width 0.15494)
		(layer "In5.Cu")
		(net "SSD7_PWR_EN_R")
	)
	(segment
		(start 212.639402 -104.9528)
		(end 212.639402 -107.820968)
		(width 0.15494)
		(layer "In5.Cu")
		(net "SSD7_PWR_EN_R")
	)
	(segment
		(start 215.4936 -167.776398)
		(end 215.4936 -171.899834)
		(width 0.15494)
		(layer "In5.Cu")
		(net "SSD7_PWR_EN_R")
	)
	(segment
		(start 211.776056 -184.645046)
		(end 211.176108 -185.244994)
		(width 0.15494)
		(layer "In5.Cu")
		(net "SSD7_PWR_EN_R")
	)
	(segment
		(start 215.519 -196.342)
		(end 214.965026 -196.895974)
		(width 0.15494)
		(layer "In5.Cu")
		(net "SSD7_PWR_EN_R")
	)
	(segment
		(start 219.651072 -65.08369)
		(end 216.39149 -65.08369)
		(width 0.15494)
		(layer "In5.Cu")
		(net "SSD7_PWR_EN_R")
	)
	(segment
		(start 215.157304 -65.64376)
		(end 214.614506 -65.100962)
		(width 0.15494)
		(layer "In5.Cu")
		(net "SSD7_PWR_EN_R")
	)
	(segment
		(start 222.29826 -238.182404)
		(end 221.784164 -238.6965)
		(width 0.15494)
		(layer "In5.Cu")
		(net "SSD7_PWR_EN_R")
	)
	(segment
		(start 220.1037 -225.894646)
		(end 220.404182 -226.195128)
		(width 0.15494)
		(layer "In5.Cu")
		(net "SSD7_PWR_EN_R")
	)
	(segment
		(start 220.738446 -217.577416)
		(end 220.738446 -219.439236)
		(width 0.15494)
		(layer "In5.Cu")
		(net "SSD7_PWR_EN_R")
	)
	(segment
		(start 211.176108 -185.244994)
		(end 211.175854 -185.244994)
		(width 0.15494)
		(layer "In5.Cu")
		(net "SSD7_PWR_EN_R")
	)
	(segment
		(start 211.175854 -185.244994)
		(end 210.916266 -185.504582)
		(width 0.15494)
		(layer "In5.Cu")
		(net "SSD7_PWR_EN_R")
	)
	(segment
		(start 209.423 -187.411106)
		(end 209.423 -187.95746)
		(width 0.15494)
		(layer "In5.Cu")
		(net "SSD7_PWR_EN_R")
	)
	(segment
		(start 215.519 -195.453)
		(end 215.519 -196.342)
		(width 0.15494)
		(layer "In5.Cu")
		(net "SSD7_PWR_EN_R")
	)
	(segment
		(start 211.6836 -189.5348)
		(end 211.6836 -191.6176)
		(width 0.15494)
		(layer "In5.Cu")
		(net "SSD7_PWR_EN_R")
	)
	(segment
		(start 211.6836 -191.6176)
		(end 215.519 -195.453)
		(width 0.15494)
		(layer "In5.Cu")
		(net "SSD7_PWR_EN_R")
	)
	(segment
		(start 220.404182 -226.195128)
		(end 220.404182 -235.629958)
		(width 0.15494)
		(layer "In5.Cu")
		(net "SSD7_PWR_EN_R")
	)
	(segment
		(start 213.987126 -181.489096)
		(end 211.776056 -183.700166)
		(width 0.15494)
		(layer "In5.Cu")
		(net "SSD7_PWR_EN_R")
	)
	(segment
		(start 216.39149 -65.08369)
		(end 215.83142 -65.64376)
		(width 0.15494)
		(layer "In5.Cu")
		(net "SSD7_PWR_EN_R")
	)
	(segment
		(start 219.61602 -214.089488)
		(end 219.61602 -216.45499)
		(width 0.15494)
		(layer "In5.Cu")
		(net "SSD7_PWR_EN_R")
	)
	(segment
		(start 220.575886 -62.919102)
		(end 220.575886 -64.691768)
		(width 0.15494)
		(layer "In5.Cu")
		(net "SSD7_PWR_EN_R")
	)
	(segment
		(start 213.987126 -173.406308)
		(end 213.987126 -181.489096)
		(width 0.15494)
		(layer "In5.Cu")
		(net "SSD7_PWR_EN_R")
	)
	(segment
		(start 220.103446 -220.074236)
		(end 220.103446 -223.83369)
		(width 0.15494)
		(layer "In5.Cu")
		(net "SSD7_PWR_EN_R")
	)
	(segment
		(start 211.5058 -138.8618)
		(end 211.5058 -163.788598)
		(width 0.15494)
		(layer "In5.Cu")
		(net "SSD7_PWR_EN_R")
	)
	(segment
		(start 210.916266 -185.91784)
		(end 209.423 -187.411106)
		(width 0.15494)
		(layer "In5.Cu")
		(net "SSD7_PWR_EN_R")
	)
	(segment
		(start 222.38208 -246.00789)
		(end 222.012764 -246.377206)
		(width 0.15494)
		(layer "In5.Cu")
		(net "SSD7_PWR_EN_R")
	)
	(segment
		(start 222.29826 -237.524036)
		(end 222.29826 -238.182404)
		(width 0.15494)
		(layer "In5.Cu")
		(net "SSD7_PWR_EN_R")
	)
	(segment
		(start 221.784164 -239.395508)
		(end 222.38208 -239.993424)
		(width 0.15494)
		(layer "In5.Cu")
		(net "SSD7_PWR_EN_R")
	)
	(segment
		(start 215.4936 -171.899834)
		(end 213.987126 -173.406308)
		(width 0.15494)
		(layer "In5.Cu")
		(net "SSD7_PWR_EN_R")
	)
	(segment
		(start 217.68943 -88.650064)
		(end 214.40267 -91.936824)
		(width 0.15494)
		(layer "In5.Cu")
		(net "SSD7_PWR_EN_R")
	)
	(segment
		(start 222.012764 -246.377206)
		(end 222.012764 -248.393712)
		(width 0.15494)
		(layer "In5.Cu")
		(net "SSD7_PWR_EN_R")
	)
	(segment
		(start 220.404182 -235.629958)
		(end 222.29826 -237.524036)
		(width 0.15494)
		(layer "In5.Cu")
		(net "SSD7_PWR_EN_R")
	)
	(segment
		(start 211.5058 -163.788598)
		(end 215.4936 -167.776398)
		(width 0.15494)
		(layer "In5.Cu")
		(net "SSD7_PWR_EN_R")
	)
	(segment
		(start 214.965026 -196.895974)
		(end 214.965026 -209.438494)
		(width 0.15494)
		(layer "In5.Cu")
		(net "SSD7_PWR_EN_R")
	)
	(segment
		(start 219.3544 -131.0132)
		(end 211.5058 -138.8618)
		(width 0.15494)
		(layer "In5.Cu")
		(net "SSD7_PWR_EN_R")
	)
	(segment
		(start 211.195412 -189.046612)
		(end 211.6836 -189.5348)
		(width 0.15494)
		(layer "In5.Cu")
		(net "SSD7_PWR_EN_R")
	)
	(segment
		(start 221.784164 -238.6965)
		(end 221.784164 -239.395508)
		(width 0.15494)
		(layer "In5.Cu")
		(net "SSD7_PWR_EN_R")
	)
	(segment
		(start 209.423 -187.95746)
		(end 210.02879 -188.56325)
		(width 0.15494)
		(layer "In5.Cu")
		(net "SSD7_PWR_EN_R")
	)
	(segment
		(start 220.04655 -65.221104)
		(end 220.04655 -75.177396)
		(width 0.15494)
		(layer "In5.Cu")
		(net "SSD7_PWR_EN_R")
	)
	(segment
		(start 210.916266 -185.504582)
		(end 210.916266 -185.91784)
		(width 0.15494)
		(layer "In5.Cu")
		(net "SSD7_PWR_EN_R")
	)
	(segment
		(start 218.2114 -120.661938)
		(end 219.3544 -121.804938)
		(width 0.15494)
		(layer "In5.Cu")
		(net "SSD7_PWR_EN_R")
	)
	(segment
		(start 214.40267 -100.69576)
		(end 212.639402 -104.9528)
		(width 0.15494)
		(layer "In5.Cu")
		(net "SSD7_PWR_EN_R")
	)
	(segment
		(start 215.83142 -65.64376)
		(end 215.157304 -65.64376)
		(width 0.15494)
		(layer "In5.Cu")
		(net "SSD7_PWR_EN_R")
	)
	(segment
		(start 219.96781 -57.032144)
		(end 219.96781 -57.59704)
		(width 0.15494)
		(layer "In5.Cu")
		(net "SSD7_PWR_EN_R")
	)
	(segment
		(start 210.02879 -188.56325)
		(end 211.195412 -189.046612)
		(width 0.15494)
		(layer "In5.Cu")
		(net "SSD7_PWR_EN_R")
	)
	(segment
		(start 350.74098 -236.492034)
		(end 350.74098 -235.49102)
		(width 0.15494)
		(layer "In15.Cu")
		(net "SSD7_PWR_EN_R")
	)
	(segment
		(start 332.62316 -252.739906)
		(end 333.819246 -251.54382)
		(width 0.15494)
		(layer "In15.Cu")
		(net "SSD7_PWR_EN_R")
	)
	(segment
		(start 229.64902 -248.70283)
		(end 230.890572 -249.944382)
		(width 0.15494)
		(layer "In15.Cu")
		(net "SSD7_PWR_EN_R")
	)
	(segment
		(start 340.508844 -250.4948)
		(end 350.899222 -240.104422)
		(width 0.15494)
		(layer "In15.Cu")
		(net "SSD7_PWR_EN_R")
	)
	(segment
		(start 327.23836 -252.739906)
		(end 332.62316 -252.739906)
		(width 0.15494)
		(layer "In15.Cu")
		(net "SSD7_PWR_EN_R")
	)
	(segment
		(start 298.510198 -250.222258)
		(end 300.115224 -251.827284)
		(width 0.15494)
		(layer "In15.Cu")
		(net "SSD7_PWR_EN_R")
	)
	(segment
		(start 238.533686 -249.944382)
		(end 240.570004 -247.908064)
		(width 0.15494)
		(layer "In15.Cu")
		(net "SSD7_PWR_EN_R")
	)
	(segment
		(start 240.570004 -247.908064)
		(end 247.401588 -247.908064)
		(width 0.15494)
		(layer "In15.Cu")
		(net "SSD7_PWR_EN_R")
	)
	(segment
		(start 350.899222 -236.650276)
		(end 350.74098 -236.492034)
		(width 0.15494)
		(layer "In15.Cu")
		(net "SSD7_PWR_EN_R")
	)
	(segment
		(start 334.332326 -250.4948)
		(end 340.508844 -250.4948)
		(width 0.15494)
		(layer "In15.Cu")
		(net "SSD7_PWR_EN_R")
	)
	(segment
		(start 350.74098 -235.49102)
		(end 351.155 -235.077)
		(width 0.15494)
		(layer "In15.Cu")
		(net "SSD7_PWR_EN_R")
	)
	(segment
		(start 350.899222 -240.104422)
		(end 350.899222 -236.650276)
		(width 0.15494)
		(layer "In15.Cu")
		(net "SSD7_PWR_EN_R")
	)
	(segment
		(start 247.401588 -247.908064)
		(end 249.350276 -249.856752)
		(width 0.15494)
		(layer "In15.Cu")
		(net "SSD7_PWR_EN_R")
	)
	(segment
		(start 300.115224 -251.827284)
		(end 304.071782 -251.827284)
		(width 0.15494)
		(layer "In15.Cu")
		(net "SSD7_PWR_EN_R")
	)
	(segment
		(start 222.012764 -248.393712)
		(end 222.321882 -248.70283)
		(width 0.15494)
		(layer "In15.Cu")
		(net "SSD7_PWR_EN_R")
	)
	(segment
		(start 249.350276 -249.856752)
		(end 258.098036 -249.856752)
		(width 0.15494)
		(layer "In15.Cu")
		(net "SSD7_PWR_EN_R")
	)
	(segment
		(start 304.071782 -251.827284)
		(end 304.240692 -251.658374)
		(width 0.15494)
		(layer "In15.Cu")
		(net "SSD7_PWR_EN_R")
	)
	(segment
		(start 326.156828 -251.658374)
		(end 327.23836 -252.739906)
		(width 0.15494)
		(layer "In15.Cu")
		(net "SSD7_PWR_EN_R")
	)
	(segment
		(start 258.463542 -250.222258)
		(end 298.510198 -250.222258)
		(width 0.15494)
		(layer "In15.Cu")
		(net "SSD7_PWR_EN_R")
	)
	(segment
		(start 222.321882 -248.70283)
		(end 229.64902 -248.70283)
		(width 0.15494)
		(layer "In15.Cu")
		(net "SSD7_PWR_EN_R")
	)
	(segment
		(start 333.819246 -251.54382)
		(end 333.819246 -251.00788)
		(width 0.15494)
		(layer "In15.Cu")
		(net "SSD7_PWR_EN_R")
	)
	(segment
		(start 258.098036 -249.856752)
		(end 258.463542 -250.222258)
		(width 0.15494)
		(layer "In15.Cu")
		(net "SSD7_PWR_EN_R")
	)
	(segment
		(start 230.890572 -249.944382)
		(end 238.533686 -249.944382)
		(width 0.15494)
		(layer "In15.Cu")
		(net "SSD7_PWR_EN_R")
	)
	(segment
		(start 304.240692 -251.658374)
		(end 326.156828 -251.658374)
		(width 0.15494)
		(layer "In15.Cu")
		(net "SSD7_PWR_EN_R")
	)
	(segment
		(start 333.819246 -251.00788)
		(end 334.332326 -250.4948)
		(width 0.15494)
		(layer "In15.Cu")
		(net "SSD7_PWR_EN_R")
	)
	(segment
		(start 239.935512 -231.861614)
		(end 239.935512 -231.816656)
		(width 0.13208)
		(layer "F.Cu")
		(net "SSD1_PWRDIS_BIC_R")
	)
	(segment
		(start 240.545366 -232.471468)
		(end 239.935512 -231.861614)
		(width 0.13208)
		(layer "F.Cu")
		(net "SSD1_PWRDIS_BIC_R")
	)
	(segment
		(start 239.935512 -233.081322)
		(end 240.545366 -232.471468)
		(width 0.13208)
		(layer "F.Cu")
		(net "SSD1_PWRDIS_BIC_R")
	)
	(segment
		(start 239.935512 -234.327954)
		(end 239.935512 -233.081322)
		(width 0.13208)
		(layer "F.Cu")
		(net "SSD1_PWRDIS_BIC_R")
	)
	(segment
		(start 344.49385 -213.587076)
		(end 344.8939 -213.187026)
		(width 0.13208)
		(layer "F.Cu")
		(net "SSD1_PWRDIS_BIC_R")
	)
	(via
		(at 240.545366 -232.471468)
		(size 0.508)
		(drill 0.254)
		(layers "F.Cu" "B.Cu")
		(net "SSD1_PWRDIS_BIC_R")
	)
	(via
		(at 344.8939 -213.187026)
		(size 0.4572)
		(drill 0.254)
		(layers "F.Cu" "B.Cu")
		(net "SSD1_PWRDIS_BIC_R")
	)
	(via
		(at 266.271756 -211.607908)
		(size 0.508)
		(drill 0.254)
		(layers "F.Cu" "B.Cu")
		(net "SSD1_PWRDIS_BIC_R")
	)
	(segment
		(start 256.159 -215.3666)
		(end 257.6322 -215.3666)
		(width 0.15494)
		(layer "In7.Cu")
		(net "SSD1_PWRDIS_BIC_R")
	)
	(segment
		(start 257.6322 -215.3666)
		(end 258.3942 -216.1286)
		(width 0.15494)
		(layer "In7.Cu")
		(net "SSD1_PWRDIS_BIC_R")
	)
	(segment
		(start 253.34976 -220.336364)
		(end 253.34976 -215.07323)
		(width 0.15494)
		(layer "In7.Cu")
		(net "SSD1_PWRDIS_BIC_R")
	)
	(segment
		(start 258.3942 -216.1286)
		(end 261.2136 -216.1286)
		(width 0.15494)
		(layer "In7.Cu")
		(net "SSD1_PWRDIS_BIC_R")
	)
	(segment
		(start 262.0264 -215.3158)
		(end 262.0264 -212.7758)
		(width 0.15494)
		(layer "In7.Cu")
		(net "SSD1_PWRDIS_BIC_R")
	)
	(segment
		(start 253.81839 -214.6046)
		(end 255.397 -214.6046)
		(width 0.15494)
		(layer "In7.Cu")
		(net "SSD1_PWRDIS_BIC_R")
	)
	(segment
		(start 262.0264 -212.7758)
		(end 262.8392 -211.963)
		(width 0.15494)
		(layer "In7.Cu")
		(net "SSD1_PWRDIS_BIC_R")
	)
	(segment
		(start 250.596146 -224.2312)
		(end 251.440442 -224.2312)
		(width 0.15494)
		(layer "In7.Cu")
		(net "SSD1_PWRDIS_BIC_R")
	)
	(segment
		(start 253.23546 -221.84614)
		(end 253.23546 -220.450664)
		(width 0.15494)
		(layer "In7.Cu")
		(net "SSD1_PWRDIS_BIC_R")
	)
	(segment
		(start 261.2136 -216.1286)
		(end 262.0264 -215.3158)
		(width 0.15494)
		(layer "In7.Cu")
		(net "SSD1_PWRDIS_BIC_R")
	)
	(segment
		(start 252.38075 -223.290892)
		(end 252.38075 -222.70085)
		(width 0.15494)
		(layer "In7.Cu")
		(net "SSD1_PWRDIS_BIC_R")
	)
	(segment
		(start 242.127532 -232.471468)
		(end 244.4496 -230.1494)
		(width 0.15494)
		(layer "In7.Cu")
		(net "SSD1_PWRDIS_BIC_R")
	)
	(segment
		(start 244.4496 -229.083616)
		(end 246.535956 -226.99726)
		(width 0.15494)
		(layer "In7.Cu")
		(net "SSD1_PWRDIS_BIC_R")
	)
	(segment
		(start 251.440442 -224.2312)
		(end 252.38075 -223.290892)
		(width 0.15494)
		(layer "In7.Cu")
		(net "SSD1_PWRDIS_BIC_R")
	)
	(segment
		(start 246.535956 -226.99726)
		(end 247.830086 -226.99726)
		(width 0.15494)
		(layer "In7.Cu")
		(net "SSD1_PWRDIS_BIC_R")
	)
	(segment
		(start 253.34976 -215.07323)
		(end 253.81839 -214.6046)
		(width 0.15494)
		(layer "In7.Cu")
		(net "SSD1_PWRDIS_BIC_R")
	)
	(segment
		(start 247.830086 -226.99726)
		(end 250.596146 -224.2312)
		(width 0.15494)
		(layer "In7.Cu")
		(net "SSD1_PWRDIS_BIC_R")
	)
	(segment
		(start 252.38075 -222.70085)
		(end 253.23546 -221.84614)
		(width 0.15494)
		(layer "In7.Cu")
		(net "SSD1_PWRDIS_BIC_R")
	)
	(segment
		(start 253.23546 -220.450664)
		(end 253.34976 -220.336364)
		(width 0.15494)
		(layer "In7.Cu")
		(net "SSD1_PWRDIS_BIC_R")
	)
	(segment
		(start 265.916664 -211.963)
		(end 266.271756 -211.607908)
		(width 0.15494)
		(layer "In7.Cu")
		(net "SSD1_PWRDIS_BIC_R")
	)
	(segment
		(start 255.397 -214.6046)
		(end 256.159 -215.3666)
		(width 0.15494)
		(layer "In7.Cu")
		(net "SSD1_PWRDIS_BIC_R")
	)
	(segment
		(start 240.545366 -232.471468)
		(end 242.127532 -232.471468)
		(width 0.15494)
		(layer "In7.Cu")
		(net "SSD1_PWRDIS_BIC_R")
	)
	(segment
		(start 262.8392 -211.963)
		(end 265.916664 -211.963)
		(width 0.15494)
		(layer "In7.Cu")
		(net "SSD1_PWRDIS_BIC_R")
	)
	(segment
		(start 244.4496 -230.1494)
		(end 244.4496 -229.083616)
		(width 0.15494)
		(layer "In7.Cu")
		(net "SSD1_PWRDIS_BIC_R")
	)
	(segment
		(start 342.99779 -208.626964)
		(end 343.01811 -208.647284)
		(width 0.15494)
		(layer "In15.Cu")
		(net "SSD1_PWRDIS_BIC_R")
	)
	(segment
		(start 332.282546 -206.710788)
		(end 332.424024 -206.569564)
		(width 0.15494)
		(layer "In15.Cu")
		(net "SSD1_PWRDIS_BIC_R")
	)
	(segment
		(start 328.999088 -207.46212)
		(end 331.522324 -207.46212)
		(width 0.15494)
		(layer "In15.Cu")
		(net "SSD1_PWRDIS_BIC_R")
	)
	(segment
		(start 332.511654 -206.569564)
		(end 332.690216 -206.4766)
		(width 0.15494)
		(layer "In15.Cu")
		(net "SSD1_PWRDIS_BIC_R")
	)
	(segment
		(start 344.111834 -211.727034)
		(end 344.373962 -211.989162)
		(width 0.15494)
		(layer "In15.Cu")
		(net "SSD1_PWRDIS_BIC_R")
	)
	(segment
		(start 333.774034 -206.600044)
		(end 333.817468 -206.600044)
		(width 0.15494)
		(layer "In15.Cu")
		(net "SSD1_PWRDIS_BIC_R")
	)
	(segment
		(start 332.267306 -206.717138)
		(end 332.282546 -206.710788)
		(width 0.15494)
		(layer "In15.Cu")
		(net "SSD1_PWRDIS_BIC_R")
	)
	(segment
		(start 344.491056 -212.106256)
		(end 344.491056 -212.784182)
		(width 0.0889)
		(layer "In15.Cu")
		(net "SSD1_PWRDIS_BIC_R")
	)
	(segment
		(start 332.424024 -206.569564)
		(end 332.511654 -206.569564)
		(width 0.15494)
		(layer "In15.Cu")
		(net "SSD1_PWRDIS_BIC_R")
	)
	(segment
		(start 344.091514 -209.720688)
		(end 344.111834 -209.741008)
		(width 0.15494)
		(layer "In15.Cu")
		(net "SSD1_PWRDIS_BIC_R")
	)
	(segment
		(start 287.17875 -207.608678)
		(end 298.391834 -207.608678)
		(width 0.15494)
		(layer "In15.Cu")
		(net "SSD1_PWRDIS_BIC_R")
	)
	(segment
		(start 332.690216 -206.4766)
		(end 333.65059 -206.4766)
		(width 0.15494)
		(layer "In15.Cu")
		(net "SSD1_PWRDIS_BIC_R")
	)
	(segment
		(start 325.0184 -205.613)
		(end 327.149968 -205.613)
		(width 0.15494)
		(layer "In15.Cu")
		(net "SSD1_PWRDIS_BIC_R")
	)
	(segment
		(start 344.111834 -209.741008)
		(end 344.111834 -211.727034)
		(width 0.15494)
		(layer "In15.Cu")
		(net "SSD1_PWRDIS_BIC_R")
	)
	(segment
		(start 324.640702 -205.990698)
		(end 325.0184 -205.613)
		(width 0.15494)
		(layer "In15.Cu")
		(net "SSD1_PWRDIS_BIC_R")
	)
	(segment
		(start 343.01811 -208.647284)
		(end 343.230962 -208.647284)
		(width 0.15494)
		(layer "In15.Cu")
		(net "SSD1_PWRDIS_BIC_R")
	)
	(segment
		(start 298.391834 -207.608678)
		(end 300.009814 -205.990698)
		(width 0.15494)
		(layer "In15.Cu")
		(net "SSD1_PWRDIS_BIC_R")
	)
	(segment
		(start 327.149968 -205.613)
		(end 328.999088 -207.46212)
		(width 0.15494)
		(layer "In15.Cu")
		(net "SSD1_PWRDIS_BIC_R")
	)
	(segment
		(start 266.99845 -210.881214)
		(end 283.906214 -210.881214)
		(width 0.15494)
		(layer "In15.Cu")
		(net "SSD1_PWRDIS_BIC_R")
	)
	(segment
		(start 344.491056 -212.784182)
		(end 344.8939 -213.187026)
		(width 0.0889)
		(layer "In15.Cu")
		(net "SSD1_PWRDIS_BIC_R")
	)
	(segment
		(start 331.522324 -207.46212)
		(end 332.267306 -206.717138)
		(width 0.15494)
		(layer "In15.Cu")
		(net "SSD1_PWRDIS_BIC_R")
	)
	(segment
		(start 344.091514 -209.507836)
		(end 344.091514 -209.720688)
		(width 0.15494)
		(layer "In15.Cu")
		(net "SSD1_PWRDIS_BIC_R")
	)
	(segment
		(start 343.230962 -208.647284)
		(end 344.091514 -209.507836)
		(width 0.15494)
		(layer "In15.Cu")
		(net "SSD1_PWRDIS_BIC_R")
	)
	(segment
		(start 333.65059 -206.4766)
		(end 333.774034 -206.600044)
		(width 0.15494)
		(layer "In15.Cu")
		(net "SSD1_PWRDIS_BIC_R")
	)
	(segment
		(start 335.844388 -208.626964)
		(end 342.99779 -208.626964)
		(width 0.15494)
		(layer "In15.Cu")
		(net "SSD1_PWRDIS_BIC_R")
	)
	(segment
		(start 283.906214 -210.881214)
		(end 287.17875 -207.608678)
		(width 0.15494)
		(layer "In15.Cu")
		(net "SSD1_PWRDIS_BIC_R")
	)
	(segment
		(start 300.009814 -205.990698)
		(end 324.640702 -205.990698)
		(width 0.15494)
		(layer "In15.Cu")
		(net "SSD1_PWRDIS_BIC_R")
	)
	(segment
		(start 266.271756 -211.607908)
		(end 266.99845 -210.881214)
		(width 0.15494)
		(layer "In15.Cu")
		(net "SSD1_PWRDIS_BIC_R")
	)
	(segment
		(start 344.373962 -211.989162)
		(end 344.491056 -212.106256)
		(width 0.0889)
		(layer "In15.Cu")
		(net "SSD1_PWRDIS_BIC_R")
	)
	(segment
		(start 333.817468 -206.600044)
		(end 335.844388 -208.626964)
		(width 0.15494)
		(layer "In15.Cu")
		(net "SSD1_PWRDIS_BIC_R")
	)
	(segment
		(start 210.789012 -26.7716)
		(end 210.03641 -26.7716)
		(width 0.13462)
		(layer "F.Cu")
		(net "CLK_100M_DB800ZL_SSD7_R_DN")
	)
	(segment
		(start 109.607096 -94.058486)
		(end 109.895386 -93.770196)
		(width 0.13462)
		(layer "F.Cu")
		(net "CLK_100M_DB800ZL_SSD7_R_DN")
	)
	(segment
		(start 209.8548 -26.58999)
		(end 209.364834 -26.58999)
		(width 0.13462)
		(layer "F.Cu")
		(net "CLK_100M_DB800ZL_SSD7_R_DN")
	)
	(segment
		(start 211.081366 -26.479246)
		(end 210.789012 -26.7716)
		(width 0.13462)
		(layer "F.Cu")
		(net "CLK_100M_DB800ZL_SSD7_R_DN")
	)
	(segment
		(start 109.895386 -93.770196)
		(end 109.895386 -93.047312)
		(width 0.13462)
		(layer "F.Cu")
		(net "CLK_100M_DB800ZL_SSD7_R_DN")
	)
	(segment
		(start 109.895386 -93.047312)
		(end 109.581696 -92.733622)
		(width 0.13462)
		(layer "F.Cu")
		(net "CLK_100M_DB800ZL_SSD7_R_DN")
	)
	(segment
		(start 210.03641 -26.7716)
		(end 209.8548 -26.58999)
		(width 0.13462)
		(layer "F.Cu")
		(net "CLK_100M_DB800ZL_SSD7_R_DN")
	)
	(via
		(at 211.081366 -26.479246)
		(size 0.508)
		(drill 0.254)
		(layers "F.Cu" "B.Cu")
		(net "CLK_100M_DB800ZL_SSD7_R_DN")
	)
	(via
		(at 109.607096 -94.058486)
		(size 0.508)
		(drill 0.254)
		(layers "F.Cu" "B.Cu")
		(net "CLK_100M_DB800ZL_SSD7_R_DN")
	)
	(segment
		(start 128.969008 -82.272632)
		(end 133.563614 -82.272632)
		(width 0.1651)
		(layer "In13.Cu")
		(net "CLK_100M_DB800ZL_SSD7_R_DN")
	)
	(segment
		(start 109.607096 -94.058486)
		(end 109.897926 -94.349316)
		(width 0.1651)
		(layer "In13.Cu")
		(net "CLK_100M_DB800ZL_SSD7_R_DN")
	)
	(segment
		(start 206.15529 -61.81471)
		(end 206.35468 -59.885326)
		(width 0.1651)
		(layer "In13.Cu")
		(net "CLK_100M_DB800ZL_SSD7_R_DN")
	)
	(segment
		(start 109.897926 -94.349316)
		(end 109.897926 -94.937326)
		(width 0.1651)
		(layer "In13.Cu")
		(net "CLK_100M_DB800ZL_SSD7_R_DN")
	)
	(segment
		(start 135.927084 -79.909162)
		(end 182.25135 -79.909162)
		(width 0.1651)
		(layer "In13.Cu")
		(net "CLK_100M_DB800ZL_SSD7_R_DN")
	)
	(segment
		(start 206.059278 -42.911268)
		(end 212.0392 -36.931346)
		(width 0.1651)
		(layer "In13.Cu")
		(net "CLK_100M_DB800ZL_SSD7_R_DN")
	)
	(segment
		(start 109.897926 -94.937326)
		(end 110.30839 -95.34779)
		(width 0.1651)
		(layer "In13.Cu")
		(net "CLK_100M_DB800ZL_SSD7_R_DN")
	)
	(segment
		(start 192.168526 -75.801474)
		(end 206.15529 -61.81471)
		(width 0.1651)
		(layer "In13.Cu")
		(net "CLK_100M_DB800ZL_SSD7_R_DN")
	)
	(segment
		(start 133.563614 -82.272632)
		(end 135.927084 -79.909162)
		(width 0.1651)
		(layer "In13.Cu")
		(net "CLK_100M_DB800ZL_SSD7_R_DN")
	)
	(segment
		(start 120.48744 -90.7542)
		(end 128.969008 -82.272632)
		(width 0.1651)
		(layer "In13.Cu")
		(net "CLK_100M_DB800ZL_SSD7_R_DN")
	)
	(segment
		(start 206.35468 -59.885326)
		(end 205.789784 -50.469292)
		(width 0.1651)
		(layer "In13.Cu")
		(net "CLK_100M_DB800ZL_SSD7_R_DN")
	)
	(segment
		(start 211.37372 -26.7716)
		(end 211.081366 -26.479246)
		(width 0.1651)
		(layer "In13.Cu")
		(net "CLK_100M_DB800ZL_SSD7_R_DN")
	)
	(segment
		(start 212.0392 -27.126946)
		(end 211.683854 -26.7716)
		(width 0.1651)
		(layer "In13.Cu")
		(net "CLK_100M_DB800ZL_SSD7_R_DN")
	)
	(segment
		(start 182.25135 -79.909162)
		(end 192.168526 -75.801474)
		(width 0.1651)
		(layer "In13.Cu")
		(net "CLK_100M_DB800ZL_SSD7_R_DN")
	)
	(segment
		(start 211.683854 -26.7716)
		(end 211.37372 -26.7716)
		(width 0.1651)
		(layer "In13.Cu")
		(net "CLK_100M_DB800ZL_SSD7_R_DN")
	)
	(segment
		(start 116.561616 -90.7542)
		(end 120.48744 -90.7542)
		(width 0.1651)
		(layer "In13.Cu")
		(net "CLK_100M_DB800ZL_SSD7_R_DN")
	)
	(segment
		(start 111.968026 -95.34779)
		(end 116.561616 -90.7542)
		(width 0.1651)
		(layer "In13.Cu")
		(net "CLK_100M_DB800ZL_SSD7_R_DN")
	)
	(segment
		(start 205.789784 -50.469292)
		(end 206.059278 -42.911268)
		(width 0.1651)
		(layer "In13.Cu")
		(net "CLK_100M_DB800ZL_SSD7_R_DN")
	)
	(segment
		(start 110.30839 -95.34779)
		(end 111.968026 -95.34779)
		(width 0.1651)
		(layer "In13.Cu")
		(net "CLK_100M_DB800ZL_SSD7_R_DN")
	)
	(segment
		(start 212.0392 -36.931346)
		(end 212.0392 -27.126946)
		(width 0.1651)
		(layer "In13.Cu")
		(net "CLK_100M_DB800ZL_SSD7_R_DN")
	)
	(segment
		(start 148.570442 -251.158502)
		(end 148.570442 -250.470924)
		(width 0.13208)
		(layer "F.Cu")
		(net "PEX1_MODE_SEL8")
	)
	(segment
		(start 179.55006 -282.599892)
		(end 180.02504 -283.074872)
		(width 0.1651)
		(layer "F.Cu")
		(net "PEX1_MODE_SEL8")
	)
	(segment
		(start 148.570442 -251.956824)
		(end 148.570442 -251.158502)
		(width 0.13208)
		(layer "F.Cu")
		(net "PEX1_MODE_SEL8")
	)
	(via
		(at 148.570442 -251.158502)
		(size 0.508)
		(drill 0.254)
		(layers "F.Cu" "B.Cu")
		(net "PEX1_MODE_SEL8")
	)
	(via
		(at 180.02504 -283.074872)
		(size 0.4064)
		(drill 0.2032)
		(layers "F.Cu" "B.Cu")
		(net "PEX1_MODE_SEL8")
	)
	(segment
		(start 151.7396 -256.5146)
		(end 151.0284 -255.8034)
		(width 0.13208)
		(layer "B.Cu")
		(net "PEX1_MODE_SEL8")
	)
	(segment
		(start 176.10328 -267.20292)
		(end 165.41496 -256.5146)
		(width 0.13208)
		(layer "B.Cu")
		(net "PEX1_MODE_SEL8")
	)
	(segment
		(start 148.096986 -254.44704)
		(end 148.096986 -251.631958)
		(width 0.13208)
		(layer "B.Cu")
		(net "PEX1_MODE_SEL8")
	)
	(segment
		(start 149.453346 -255.8034)
		(end 148.096986 -254.44704)
		(width 0.13208)
		(layer "B.Cu")
		(net "PEX1_MODE_SEL8")
	)
	(segment
		(start 180.02504 -283.074872)
		(end 180.935122 -282.16479)
		(width 0.13208)
		(layer "B.Cu")
		(net "PEX1_MODE_SEL8")
	)
	(segment
		(start 177.09642 -268.40942)
		(end 176.10328 -267.41628)
		(width 0.13208)
		(layer "B.Cu")
		(net "PEX1_MODE_SEL8")
	)
	(segment
		(start 165.41496 -256.5146)
		(end 151.7396 -256.5146)
		(width 0.13208)
		(layer "B.Cu")
		(net "PEX1_MODE_SEL8")
	)
	(segment
		(start 180.935122 -282.16479)
		(end 180.935122 -272.034762)
		(width 0.13208)
		(layer "B.Cu")
		(net "PEX1_MODE_SEL8")
	)
	(segment
		(start 176.10328 -267.41628)
		(end 176.10328 -267.20292)
		(width 0.13208)
		(layer "B.Cu")
		(net "PEX1_MODE_SEL8")
	)
	(segment
		(start 148.096986 -251.631958)
		(end 148.570442 -251.158502)
		(width 0.13208)
		(layer "B.Cu")
		(net "PEX1_MODE_SEL8")
	)
	(segment
		(start 151.0284 -255.8034)
		(end 149.453346 -255.8034)
		(width 0.13208)
		(layer "B.Cu")
		(net "PEX1_MODE_SEL8")
	)
	(segment
		(start 180.935122 -272.034762)
		(end 177.30978 -268.40942)
		(width 0.13208)
		(layer "B.Cu")
		(net "PEX1_MODE_SEL8")
	)
	(segment
		(start 177.30978 -268.40942)
		(end 177.09642 -268.40942)
		(width 0.13208)
		(layer "B.Cu")
		(net "PEX1_MODE_SEL8")
	)
	(segment
		(start 374.674384 -251.956824)
		(end 374.674384 -251.158502)
		(width 0.13208)
		(layer "F.Cu")
		(net "PEX3_MODE_SEL2")
	)
	(segment
		(start 374.674384 -251.158502)
		(end 374.674384 -250.470924)
		(width 0.13208)
		(layer "F.Cu")
		(net "PEX3_MODE_SEL2")
	)
	(segment
		(start 409.200858 -182.325518)
		(end 409.200858 -183.496458)
		(width 0.13208)
		(layer "F.Cu")
		(net "PEX3_MODE_SEL2")
	)
	(segment
		(start 407.949908 -283.549852)
		(end 408.424888 -284.024832)
		(width 0.1651)
		(layer "F.Cu")
		(net "PEX3_MODE_SEL2")
	)
	(via
		(at 409.200858 -183.496458)
		(size 0.508)
		(drill 0.254)
		(layers "F.Cu" "B.Cu")
		(net "PEX3_MODE_SEL2")
	)
	(via
		(at 408.424888 -284.024832)
		(size 0.4064)
		(drill 0.2032)
		(layers "F.Cu" "B.Cu")
		(net "PEX3_MODE_SEL2")
	)
	(via
		(at 374.674384 -251.158502)
		(size 0.508)
		(drill 0.254)
		(layers "F.Cu" "B.Cu")
		(net "PEX3_MODE_SEL2")
	)
	(segment
		(start 385.518406 -224.352866)
		(end 383.840736 -224.352866)
		(width 0.13208)
		(layer "B.Cu")
		(net "PEX3_MODE_SEL2")
	)
	(segment
		(start 376.830336 -258.847336)
		(end 395.062964 -258.847336)
		(width 0.13208)
		(layer "B.Cu")
		(net "PEX3_MODE_SEL2")
	)
	(segment
		(start 372.813834 -251.898912)
		(end 372.210584 -251.898912)
		(width 0.13208)
		(layer "B.Cu")
		(net "PEX3_MODE_SEL2")
	)
	(segment
		(start 412.030926 -190.0809)
		(end 412.030926 -185.941462)
		(width 0.13208)
		(layer "B.Cu")
		(net "PEX3_MODE_SEL2")
	)
	(segment
		(start 373.19839 -250.774962)
		(end 373.19839 -251.514356)
		(width 0.13208)
		(layer "B.Cu")
		(net "PEX3_MODE_SEL2")
	)
	(segment
		(start 374.158764 -252.825758)
		(end 374.158764 -256.948178)
		(width 0.13208)
		(layer "B.Cu")
		(net "PEX3_MODE_SEL2")
	)
	(segment
		(start 386.0292 -224.86366)
		(end 385.518406 -224.352866)
		(width 0.13208)
		(layer "B.Cu")
		(net "PEX3_MODE_SEL2")
	)
	(segment
		(start 374.158764 -256.948178)
		(end 375.79554 -258.584954)
		(width 0.13208)
		(layer "B.Cu")
		(net "PEX3_MODE_SEL2")
	)
	(segment
		(start 374.542304 -250.616212)
		(end 373.35714 -250.616212)
		(width 0.13208)
		(layer "B.Cu")
		(net "PEX3_MODE_SEL2")
	)
	(segment
		(start 409.89885 -202.697842)
		(end 409.89885 -196.311774)
		(width 0.13208)
		(layer "B.Cu")
		(net "PEX3_MODE_SEL2")
	)
	(segment
		(start 409.585922 -183.496458)
		(end 409.200858 -183.496458)
		(width 0.13208)
		(layer "B.Cu")
		(net "PEX3_MODE_SEL2")
	)
	(segment
		(start 372.210584 -251.898912)
		(end 371.911626 -251.599954)
		(width 0.13208)
		(layer "B.Cu")
		(net "PEX3_MODE_SEL2")
	)
	(segment
		(start 371.911626 -250.213876)
		(end 372.43893 -249.686572)
		(width 0.13208)
		(layer "B.Cu")
		(net "PEX3_MODE_SEL2")
	)
	(segment
		(start 383.453894 -223.966024)
		(end 383.453894 -217.193114)
		(width 0.13208)
		(layer "B.Cu")
		(net "PEX3_MODE_SEL2")
	)
	(segment
		(start 375.79554 -258.584954)
		(end 376.567954 -258.584954)
		(width 0.13208)
		(layer "B.Cu")
		(net "PEX3_MODE_SEL2")
	)
	(segment
		(start 405.234394 -269.018766)
		(end 405.374602 -269.018766)
		(width 0.13208)
		(layer "B.Cu")
		(net "PEX3_MODE_SEL2")
	)
	(segment
		(start 409.89885 -196.311774)
		(end 410.882846 -195.327778)
		(width 0.13208)
		(layer "B.Cu")
		(net "PEX3_MODE_SEL2")
	)
	(segment
		(start 374.674384 -252.310138)
		(end 374.158764 -252.825758)
		(width 0.13208)
		(layer "B.Cu")
		(net "PEX3_MODE_SEL2")
	)
	(segment
		(start 395.062964 -258.847336)
		(end 405.234394 -269.018766)
		(width 0.13208)
		(layer "B.Cu")
		(net "PEX3_MODE_SEL2")
	)
	(segment
		(start 371.911626 -251.599954)
		(end 371.911626 -250.213876)
		(width 0.13208)
		(layer "B.Cu")
		(net "PEX3_MODE_SEL2")
	)
	(segment
		(start 385.697476 -214.949532)
		(end 385.697476 -211.129626)
		(width 0.13208)
		(layer "B.Cu")
		(net "PEX3_MODE_SEL2")
	)
	(segment
		(start 387.1595 -230.44785)
		(end 386.0292 -229.31755)
		(width 0.13208)
		(layer "B.Cu")
		(net "PEX3_MODE_SEL2")
	)
	(segment
		(start 409.469336 -203.127356)
		(end 409.89885 -202.697842)
		(width 0.13208)
		(layer "B.Cu")
		(net "PEX3_MODE_SEL2")
	)
	(segment
		(start 374.674384 -250.748292)
		(end 374.542304 -250.616212)
		(width 0.13208)
		(layer "B.Cu")
		(net "PEX3_MODE_SEL2")
	)
	(segment
		(start 374.674384 -251.158502)
		(end 374.674384 -252.310138)
		(width 0.13208)
		(layer "B.Cu")
		(net "PEX3_MODE_SEL2")
	)
	(segment
		(start 383.453894 -217.193114)
		(end 385.697476 -214.949532)
		(width 0.13208)
		(layer "B.Cu")
		(net "PEX3_MODE_SEL2")
	)
	(segment
		(start 374.674384 -251.158502)
		(end 374.674384 -250.748292)
		(width 0.13208)
		(layer "B.Cu")
		(net "PEX3_MODE_SEL2")
	)
	(segment
		(start 387.59384 -230.44785)
		(end 387.1595 -230.44785)
		(width 0.13208)
		(layer "B.Cu")
		(net "PEX3_MODE_SEL2")
	)
	(segment
		(start 372.43893 -249.686572)
		(end 388.918958 -249.686572)
		(width 0.13208)
		(layer "B.Cu")
		(net "PEX3_MODE_SEL2")
	)
	(segment
		(start 407.480262 -271.124426)
		(end 407.480262 -283.080206)
		(width 0.13208)
		(layer "B.Cu")
		(net "PEX3_MODE_SEL2")
	)
	(segment
		(start 376.567954 -258.584954)
		(end 376.830336 -258.847336)
		(width 0.13208)
		(layer "B.Cu")
		(net "PEX3_MODE_SEL2")
	)
	(segment
		(start 393.699746 -203.127356)
		(end 409.469336 -203.127356)
		(width 0.13208)
		(layer "B.Cu")
		(net "PEX3_MODE_SEL2")
	)
	(segment
		(start 410.882846 -191.22898)
		(end 412.030926 -190.0809)
		(width 0.13208)
		(layer "B.Cu")
		(net "PEX3_MODE_SEL2")
	)
	(segment
		(start 407.480262 -283.080206)
		(end 408.424888 -284.024832)
		(width 0.13208)
		(layer "B.Cu")
		(net "PEX3_MODE_SEL2")
	)
	(segment
		(start 373.35714 -250.616212)
		(end 373.19839 -250.774962)
		(width 0.13208)
		(layer "B.Cu")
		(net "PEX3_MODE_SEL2")
	)
	(segment
		(start 412.030926 -185.941462)
		(end 409.585922 -183.496458)
		(width 0.13208)
		(layer "B.Cu")
		(net "PEX3_MODE_SEL2")
	)
	(segment
		(start 405.374602 -269.018766)
		(end 407.480262 -271.124426)
		(width 0.13208)
		(layer "B.Cu")
		(net "PEX3_MODE_SEL2")
	)
	(segment
		(start 373.19839 -251.514356)
		(end 372.813834 -251.898912)
		(width 0.13208)
		(layer "B.Cu")
		(net "PEX3_MODE_SEL2")
	)
	(segment
		(start 388.918958 -249.686572)
		(end 390.356852 -248.248678)
		(width 0.13208)
		(layer "B.Cu")
		(net "PEX3_MODE_SEL2")
	)
	(segment
		(start 410.882846 -195.327778)
		(end 410.882846 -191.22898)
		(width 0.13208)
		(layer "B.Cu")
		(net "PEX3_MODE_SEL2")
	)
	(segment
		(start 390.356852 -233.210862)
		(end 387.59384 -230.44785)
		(width 0.13208)
		(layer "B.Cu")
		(net "PEX3_MODE_SEL2")
	)
	(segment
		(start 383.840736 -224.352866)
		(end 383.453894 -223.966024)
		(width 0.13208)
		(layer "B.Cu")
		(net "PEX3_MODE_SEL2")
	)
	(segment
		(start 390.356852 -248.248678)
		(end 390.356852 -233.210862)
		(width 0.13208)
		(layer "B.Cu")
		(net "PEX3_MODE_SEL2")
	)
	(segment
		(start 386.0292 -229.31755)
		(end 386.0292 -224.86366)
		(width 0.13208)
		(layer "B.Cu")
		(net "PEX3_MODE_SEL2")
	)
	(segment
		(start 385.697476 -211.129626)
		(end 393.699746 -203.127356)
		(width 0.13208)
		(layer "B.Cu")
		(net "PEX3_MODE_SEL2")
	)
	(segment
		(start 223.288098 -222.304102)
		(end 222.9612 -222.631)
		(width 0.13208)
		(layer "F.Cu")
		(net "SMB_BIC_I2C6_SCL")
	)
	(segment
		(start 223.467676 -222.304102)
		(end 223.288098 -222.304102)
		(width 0.13208)
		(layer "F.Cu")
		(net "SMB_BIC_I2C6_SCL")
	)
	(via
		(at 214.790782 -224.406968)
		(size 0.508)
		(drill 0.254)
		(layers "F.Cu" "B.Cu")
		(net "SMB_BIC_I2C6_SCL")
	)
	(via
		(at 222.9612 -222.631)
		(size 0.4572)
		(drill 0.254)
		(layers "F.Cu" "B.Cu")
		(net "SMB_BIC_I2C6_SCL")
	)
	(via
		(at 218.341956 -224.4852)
		(size 0.508)
		(drill 0.254)
		(layers "F.Cu" "B.Cu")
		(net "SMB_BIC_I2C6_SCL")
	)
	(via
		(at 219.362274 -224.398586)
		(size 0.6604)
		(drill 0.3302)
		(layers "F.Cu" "B.Cu")
		(net "SMB_BIC_I2C6_SCL")
	)
	(segment
		(start 217.72245 -224.4852)
		(end 218.341956 -224.4852)
		(width 0.13208)
		(layer "B.Cu")
		(net "SMB_BIC_I2C6_SCL")
	)
	(segment
		(start 217.635836 -224.398586)
		(end 217.72245 -224.4852)
		(width 0.13208)
		(layer "B.Cu")
		(net "SMB_BIC_I2C6_SCL")
	)
	(segment
		(start 222.9612 -222.675196)
		(end 221.23781 -224.398586)
		(width 0.13208)
		(layer "B.Cu")
		(net "SMB_BIC_I2C6_SCL")
	)
	(segment
		(start 214.130382 -224.398586)
		(end 214.7824 -224.398586)
		(width 0.13208)
		(layer "B.Cu")
		(net "SMB_BIC_I2C6_SCL")
	)
	(segment
		(start 218.341956 -224.4852)
		(end 219.27566 -224.4852)
		(width 0.13208)
		(layer "B.Cu")
		(net "SMB_BIC_I2C6_SCL")
	)
	(segment
		(start 222.9612 -222.631)
		(end 222.9612 -222.675196)
		(width 0.13208)
		(layer "B.Cu")
		(net "SMB_BIC_I2C6_SCL")
	)
	(segment
		(start 214.7824 -224.398586)
		(end 214.7824 -224.406968)
		(width 0.13208)
		(layer "B.Cu")
		(net "SMB_BIC_I2C6_SCL")
	)
	(segment
		(start 219.27566 -224.4852)
		(end 219.362274 -224.398586)
		(width 0.13208)
		(layer "B.Cu")
		(net "SMB_BIC_I2C6_SCL")
	)
	(segment
		(start 214.7824 -224.406968)
		(end 214.790782 -224.406968)
		(width 0.13208)
		(layer "B.Cu")
		(net "SMB_BIC_I2C6_SCL")
	)
	(segment
		(start 221.23781 -224.398586)
		(end 219.362274 -224.398586)
		(width 0.13208)
		(layer "B.Cu")
		(net "SMB_BIC_I2C6_SCL")
	)
	(segment
		(start 217.7034 -223.8756)
		(end 215.213946 -223.8756)
		(width 0.15494)
		(layer "In15.Cu")
		(net "SMB_BIC_I2C6_SCL")
	)
	(segment
		(start 214.790782 -224.298764)
		(end 214.790782 -224.406968)
		(width 0.15494)
		(layer "In15.Cu")
		(net "SMB_BIC_I2C6_SCL")
	)
	(segment
		(start 218.341956 -224.4852)
		(end 218.313 -224.4852)
		(width 0.15494)
		(layer "In15.Cu")
		(net "SMB_BIC_I2C6_SCL")
	)
	(segment
		(start 218.313 -224.4852)
		(end 217.7034 -223.8756)
		(width 0.15494)
		(layer "In15.Cu")
		(net "SMB_BIC_I2C6_SCL")
	)
	(segment
		(start 215.213946 -223.8756)
		(end 214.790782 -224.298764)
		(width 0.15494)
		(layer "In15.Cu")
		(net "SMB_BIC_I2C6_SCL")
	)
	(segment
		(start 338.893912 -223.987106)
		(end 338.494116 -224.386902)
		(width 0.13208)
		(layer "F.Cu")
		(net "MB_SWB_PWR_EN_ISO_R")
	)
	(segment
		(start 336.931 -238.23295)
		(end 336.931 -237.25505)
		(width 0.13208)
		(layer "F.Cu")
		(net "MB_SWB_PWR_EN_ISO_R")
	)
	(segment
		(start 336.931 -237.25505)
		(end 336.042 -237.25505)
		(width 0.13208)
		(layer "F.Cu")
		(net "MB_SWB_PWR_EN_ISO_R")
	)
	(via
		(at 336.042 -237.25505)
		(size 0.508)
		(drill 0.254)
		(layers "F.Cu" "B.Cu")
		(net "MB_SWB_PWR_EN_ISO_R")
	)
	(via
		(at 338.494116 -224.386902)
		(size 0.4572)
		(drill 0.254)
		(layers "F.Cu" "B.Cu")
		(net "MB_SWB_PWR_EN_ISO_R")
	)
	(segment
		(start 338.09432 -224.786698)
		(end 338.494116 -224.386902)
		(width 0.0889)
		(layer "In7.Cu")
		(net "MB_SWB_PWR_EN_ISO_R")
	)
	(segment
		(start 335.69148 -236.90453)
		(end 335.69148 -227.3808)
		(width 0.15494)
		(layer "In7.Cu")
		(net "MB_SWB_PWR_EN_ISO_R")
	)
	(segment
		(start 335.69148 -227.3808)
		(end 335.69148 -225.010218)
		(width 0.0889)
		(layer "In7.Cu")
		(net "MB_SWB_PWR_EN_ISO_R")
	)
	(segment
		(start 335.69148 -225.010218)
		(end 335.915 -224.786698)
		(width 0.0889)
		(layer "In7.Cu")
		(net "MB_SWB_PWR_EN_ISO_R")
	)
	(segment
		(start 335.915 -224.786698)
		(end 338.09432 -224.786698)
		(width 0.0889)
		(layer "In7.Cu")
		(net "MB_SWB_PWR_EN_ISO_R")
	)
	(segment
		(start 336.042 -237.25505)
		(end 335.69148 -236.90453)
		(width 0.15494)
		(layer "In7.Cu")
		(net "MB_SWB_PWR_EN_ISO_R")
	)
	(segment
		(start 103.137208 -52.587398)
		(end 103.601266 -53.051456)
		(width 0.13208)
		(layer "F.Cu")
		(net "PWRGD_P12V_SSD3")
	)
	(segment
		(start 103.601266 -53.051456)
		(end 103.867712 -53.051456)
		(width 0.13208)
		(layer "F.Cu")
		(net "PWRGD_P12V_SSD3")
	)
	(segment
		(start 102.147116 -53.644038)
		(end 102.516178 -53.644038)
		(width 0.13208)
		(layer "F.Cu")
		(net "PWRGD_P12V_SSD3")
	)
	(segment
		(start 103.137208 -53.023008)
		(end 103.137208 -52.587398)
		(width 0.13208)
		(layer "F.Cu")
		(net "PWRGD_P12V_SSD3")
	)
	(segment
		(start 103.867712 -52.035456)
		(end 103.867712 -53.051456)
		(width 0.13208)
		(layer "F.Cu")
		(net "PWRGD_P12V_SSD3")
	)
	(segment
		(start 102.516178 -53.644038)
		(end 103.137208 -53.023008)
		(width 0.13208)
		(layer "F.Cu")
		(net "PWRGD_P12V_SSD3")
	)
	(via
		(at 103.137208 -52.587398)
		(size 0.508)
		(drill 0.254)
		(layers "F.Cu" "B.Cu")
		(net "PWRGD_P12V_SSD3")
	)
	(segment
		(start 346.093796 -214.387176)
		(end 346.493592 -213.98738)
		(width 0.13208)
		(layer "F.Cu")
		(net "PRSNT_SSD4_FPGA_N")
	)
	(via
		(at 347.726 -209.423)
		(size 0.6604)
		(drill 0.3302)
		(layers "F.Cu" "B.Cu")
		(net "PRSNT_SSD4_FPGA_N")
	)
	(via
		(at 346.493592 -213.98738)
		(size 0.4572)
		(drill 0.254)
		(layers "F.Cu" "B.Cu")
		(net "PRSNT_SSD4_FPGA_N")
	)
	(segment
		(start 346.89542 -210.25358)
		(end 347.726 -209.423)
		(width 0.13208)
		(layer "B.Cu")
		(net "PRSNT_SSD4_FPGA_N")
	)
	(segment
		(start 346.493592 -213.98738)
		(end 346.89542 -213.585552)
		(width 0.0889)
		(layer "B.Cu")
		(net "PRSNT_SSD4_FPGA_N")
	)
	(segment
		(start 346.89542 -213.585552)
		(end 346.89542 -210.25358)
		(width 0.0889)
		(layer "B.Cu")
		(net "PRSNT_SSD4_FPGA_N")
	)
	(segment
		(start 347.726 -209.423)
		(end 347.726 -208.17205)
		(width 0.13208)
		(layer "B.Cu")
		(net "PRSNT_SSD4_FPGA_N")
	)
	(segment
		(start 183.854852 -26.58999)
		(end 183.364886 -26.58999)
		(width 0.13462)
		(layer "F.Cu")
		(net "CLK_100M_DB800ZL_SSD6_R_DN")
	)
	(segment
		(start 184.036462 -26.7716)
		(end 183.854852 -26.58999)
		(width 0.13462)
		(layer "F.Cu")
		(net "CLK_100M_DB800ZL_SSD6_R_DN")
	)
	(segment
		(start 116.088414 -89.0524)
		(end 117.536722 -89.0524)
		(width 0.13462)
		(layer "F.Cu")
		(net "CLK_100M_DB800ZL_SSD6_R_DN")
	)
	(segment
		(start 115.756436 -89.384378)
		(end 116.088414 -89.0524)
		(width 0.13462)
		(layer "F.Cu")
		(net "CLK_100M_DB800ZL_SSD6_R_DN")
	)
	(segment
		(start 185.081418 -26.479246)
		(end 184.789064 -26.7716)
		(width 0.13462)
		(layer "F.Cu")
		(net "CLK_100M_DB800ZL_SSD6_R_DN")
	)
	(segment
		(start 184.789064 -26.7716)
		(end 184.036462 -26.7716)
		(width 0.13462)
		(layer "F.Cu")
		(net "CLK_100M_DB800ZL_SSD6_R_DN")
	)
	(segment
		(start 117.536722 -89.0524)
		(end 117.8433 -89.358978)
		(width 0.13462)
		(layer "F.Cu")
		(net "CLK_100M_DB800ZL_SSD6_R_DN")
	)
	(via
		(at 185.081418 -26.479246)
		(size 0.508)
		(drill 0.254)
		(layers "F.Cu" "B.Cu")
		(net "CLK_100M_DB800ZL_SSD6_R_DN")
	)
	(via
		(at 117.8433 -89.358978)
		(size 0.508)
		(drill 0.254)
		(layers "F.Cu" "B.Cu")
		(net "CLK_100M_DB800ZL_SSD6_R_DN")
	)
	(segment
		(start 118.137686 -89.064084)
		(end 117.8433 -89.35847)
		(width 0.1651)
		(layer "In13.Cu")
		(net "CLK_100M_DB800ZL_SSD6_R_DN")
	)
	(segment
		(start 181.814978 -41.548304)
		(end 180.19141 -43.171872)
		(width 0.1651)
		(layer "In13.Cu")
		(net "CLK_100M_DB800ZL_SSD6_R_DN")
	)
	(segment
		(start 127.640842 -81.08569)
		(end 121.288048 -87.438484)
		(width 0.1651)
		(layer "In13.Cu")
		(net "CLK_100M_DB800ZL_SSD6_R_DN")
	)
	(segment
		(start 179.968398 -62.119002)
		(end 164.063172 -78.024228)
		(width 0.1651)
		(layer "In13.Cu")
		(net "CLK_100M_DB800ZL_SSD6_R_DN")
	)
	(segment
		(start 179.834286 -43.994324)
		(end 179.678076 -48.562006)
		(width 0.1651)
		(layer "In13.Cu")
		(net "CLK_100M_DB800ZL_SSD6_R_DN")
	)
	(segment
		(start 181.815232 -41.548304)
		(end 181.814978 -41.548304)
		(width 0.1651)
		(layer "In13.Cu")
		(net "CLK_100M_DB800ZL_SSD6_R_DN")
	)
	(segment
		(start 149.410166 -78.024228)
		(end 148.566378 -78.868016)
		(width 0.1651)
		(layer "In13.Cu")
		(net "CLK_100M_DB800ZL_SSD6_R_DN")
	)
	(segment
		(start 148.566378 -78.868016)
		(end 134.357364 -78.868016)
		(width 0.1651)
		(layer "In13.Cu")
		(net "CLK_100M_DB800ZL_SSD6_R_DN")
	)
	(segment
		(start 132.13969 -81.08569)
		(end 127.640842 -81.08569)
		(width 0.1651)
		(layer "In13.Cu")
		(net "CLK_100M_DB800ZL_SSD6_R_DN")
	)
	(segment
		(start 186.013852 -27.089354)
		(end 186.013852 -35.880802)
		(width 0.1651)
		(layer "In13.Cu")
		(net "CLK_100M_DB800ZL_SSD6_R_DN")
	)
	(segment
		(start 134.357364 -78.868016)
		(end 132.13969 -81.08569)
		(width 0.1651)
		(layer "In13.Cu")
		(net "CLK_100M_DB800ZL_SSD6_R_DN")
	)
	(segment
		(start 185.698384 -26.773886)
		(end 186.013852 -27.089354)
		(width 0.1651)
		(layer "In13.Cu")
		(net "CLK_100M_DB800ZL_SSD6_R_DN")
	)
	(segment
		(start 185.376058 -26.773886)
		(end 185.698384 -26.773886)
		(width 0.1651)
		(layer "In13.Cu")
		(net "CLK_100M_DB800ZL_SSD6_R_DN")
	)
	(segment
		(start 118.529862 -89.064084)
		(end 118.137686 -89.064084)
		(width 0.1651)
		(layer "In13.Cu")
		(net "CLK_100M_DB800ZL_SSD6_R_DN")
	)
	(segment
		(start 118.919498 -88.674448)
		(end 118.529862 -89.064084)
		(width 0.1651)
		(layer "In13.Cu")
		(net "CLK_100M_DB800ZL_SSD6_R_DN")
	)
	(segment
		(start 185.264298 -38.098984)
		(end 181.815232 -41.548304)
		(width 0.1651)
		(layer "In13.Cu")
		(net "CLK_100M_DB800ZL_SSD6_R_DN")
	)
	(segment
		(start 180.19141 -43.171872)
		(end 179.834286 -43.994324)
		(width 0.1651)
		(layer "In13.Cu")
		(net "CLK_100M_DB800ZL_SSD6_R_DN")
	)
	(segment
		(start 185.264298 -36.630356)
		(end 185.264298 -38.098984)
		(width 0.1651)
		(layer "In13.Cu")
		(net "CLK_100M_DB800ZL_SSD6_R_DN")
	)
	(segment
		(start 186.013852 -35.880802)
		(end 185.264298 -36.630356)
		(width 0.1651)
		(layer "In13.Cu")
		(net "CLK_100M_DB800ZL_SSD6_R_DN")
	)
	(segment
		(start 179.670202 -48.569118)
		(end 180.340508 -59.744864)
		(width 0.1651)
		(layer "In13.Cu")
		(net "CLK_100M_DB800ZL_SSD6_R_DN")
	)
	(segment
		(start 119.81815 -87.438484)
		(end 118.919498 -88.337136)
		(width 0.1651)
		(layer "In13.Cu")
		(net "CLK_100M_DB800ZL_SSD6_R_DN")
	)
	(segment
		(start 179.678076 -48.562006)
		(end 179.670202 -48.569118)
		(width 0.1651)
		(layer "In13.Cu")
		(net "CLK_100M_DB800ZL_SSD6_R_DN")
	)
	(segment
		(start 164.063172 -78.024228)
		(end 149.410166 -78.024228)
		(width 0.1651)
		(layer "In13.Cu")
		(net "CLK_100M_DB800ZL_SSD6_R_DN")
	)
	(segment
		(start 121.288048 -87.438484)
		(end 119.81815 -87.438484)
		(width 0.1651)
		(layer "In13.Cu")
		(net "CLK_100M_DB800ZL_SSD6_R_DN")
	)
	(segment
		(start 180.340508 -59.744864)
		(end 179.968398 -62.119002)
		(width 0.1651)
		(layer "In13.Cu")
		(net "CLK_100M_DB800ZL_SSD6_R_DN")
	)
	(segment
		(start 185.081418 -26.479246)
		(end 185.376058 -26.773886)
		(width 0.1651)
		(layer "In13.Cu")
		(net "CLK_100M_DB800ZL_SSD6_R_DN")
	)
	(segment
		(start 118.919498 -88.337136)
		(end 118.919498 -88.674448)
		(width 0.1651)
		(layer "In13.Cu")
		(net "CLK_100M_DB800ZL_SSD6_R_DN")
	)
	(segment
		(start 117.8433 -89.35847)
		(end 117.8433 -89.358978)
		(width 0.1651)
		(layer "In13.Cu")
		(net "CLK_100M_DB800ZL_SSD6_R_DN")
	)
	(segment
		(start 410.800042 -282.599892)
		(end 411.275022 -283.074872)
		(width 0.13208)
		(layer "F.Cu")
		(net "PEX3_MODE_SEL4")
	)
	(segment
		(start 410.799788 -282.599892)
		(end 410.800042 -282.599892)
		(width 0.13208)
		(layer "F.Cu")
		(net "PEX3_MODE_SEL4")
	)
	(segment
		(start 379.754384 -251.158502)
		(end 379.754384 -250.470924)
		(width 0.13208)
		(layer "F.Cu")
		(net "PEX3_MODE_SEL4")
	)
	(segment
		(start 379.754384 -251.956824)
		(end 379.754384 -251.158502)
		(width 0.13208)
		(layer "F.Cu")
		(net "PEX3_MODE_SEL4")
	)
	(via
		(at 411.275022 -283.074872)
		(size 0.4064)
		(drill 0.2032)
		(layers "F.Cu" "B.Cu")
		(net "PEX3_MODE_SEL4")
	)
	(via
		(at 379.754384 -251.158502)
		(size 0.508)
		(drill 0.254)
		(layers "F.Cu" "B.Cu")
		(net "PEX3_MODE_SEL4")
	)
	(via
		(at 406.801574 -266.71143)
		(size 0.6604)
		(drill 0.3302)
		(layers "F.Cu" "B.Cu")
		(net "PEX3_MODE_SEL4")
	)
	(segment
		(start 380.139194 -254.954278)
		(end 380.828042 -254.954278)
		(width 0.13208)
		(layer "B.Cu")
		(net "PEX3_MODE_SEL4")
	)
	(segment
		(start 406.801574 -266.71143)
		(end 407.024078 -266.71143)
		(width 0.13208)
		(layer "B.Cu")
		(net "PEX3_MODE_SEL4")
	)
	(segment
		(start 379.754384 -251.158502)
		(end 379.27915 -251.633736)
		(width 0.13208)
		(layer "B.Cu")
		(net "PEX3_MODE_SEL4")
	)
	(segment
		(start 396.098522 -256.008378)
		(end 406.801574 -266.71143)
		(width 0.13208)
		(layer "B.Cu")
		(net "PEX3_MODE_SEL4")
	)
	(segment
		(start 412.222696 -282.127198)
		(end 411.275022 -283.074872)
		(width 0.13208)
		(layer "B.Cu")
		(net "PEX3_MODE_SEL4")
	)
	(segment
		(start 412.222696 -271.910048)
		(end 412.222696 -282.127198)
		(width 0.13208)
		(layer "B.Cu")
		(net "PEX3_MODE_SEL4")
	)
	(segment
		(start 380.828042 -254.954278)
		(end 381.2667 -255.392936)
		(width 0.13208)
		(layer "B.Cu")
		(net "PEX3_MODE_SEL4")
	)
	(segment
		(start 379.27915 -254.094234)
		(end 380.139194 -254.954278)
		(width 0.13208)
		(layer "B.Cu")
		(net "PEX3_MODE_SEL4")
	)
	(segment
		(start 407.024078 -266.71143)
		(end 412.222696 -271.910048)
		(width 0.13208)
		(layer "B.Cu")
		(net "PEX3_MODE_SEL4")
	)
	(segment
		(start 379.27915 -251.633736)
		(end 379.27915 -254.094234)
		(width 0.13208)
		(layer "B.Cu")
		(net "PEX3_MODE_SEL4")
	)
	(segment
		(start 381.2667 -255.392936)
		(end 383.308098 -255.392936)
		(width 0.13208)
		(layer "B.Cu")
		(net "PEX3_MODE_SEL4")
	)
	(segment
		(start 383.92354 -256.008378)
		(end 396.098522 -256.008378)
		(width 0.13208)
		(layer "B.Cu")
		(net "PEX3_MODE_SEL4")
	)
	(segment
		(start 383.308098 -255.392936)
		(end 383.92354 -256.008378)
		(width 0.13208)
		(layer "B.Cu")
		(net "PEX3_MODE_SEL4")
	)
	(segment
		(start 68.65747 -113.43513)
		(end 67.312794 -113.43513)
		(width 0.13208)
		(layer "F.Cu")
		(net "SMB_NIC1_R_SDA")
	)
	(via
		(at 67.312794 -113.43513)
		(size 0.508)
		(drill 0.254)
		(layers "F.Cu" "B.Cu")
		(net "SMB_NIC1_R_SDA")
	)
	(via
		(at 201.648822 -104.013508)
		(size 0.508)
		(drill 0.254)
		(layers "F.Cu" "B.Cu")
		(net "SMB_NIC1_R_SDA")
	)
	(via
		(at 223.679512 -233.182668)
		(size 0.508)
		(drill 0.254)
		(layers "F.Cu" "B.Cu")
		(net "SMB_NIC1_R_SDA")
	)
	(segment
		(start 67.315588 -113.437924)
		(end 67.312794 -113.43513)
		(width 0.13208)
		(layer "B.Cu")
		(net "SMB_NIC1_R_SDA")
	)
	(segment
		(start 223.205548 -232.708704)
		(end 223.205548 -231.758744)
		(width 0.13208)
		(layer "B.Cu")
		(net "SMB_NIC1_R_SDA")
	)
	(segment
		(start 223.679512 -233.182668)
		(end 223.205548 -232.708704)
		(width 0.13208)
		(layer "B.Cu")
		(net "SMB_NIC1_R_SDA")
	)
	(segment
		(start 68.272152 -113.437924)
		(end 67.315588 -113.437924)
		(width 0.13208)
		(layer "B.Cu")
		(net "SMB_NIC1_R_SDA")
	)
	(segment
		(start 223.205548 -231.758744)
		(end 223.338644 -231.625648)
		(width 0.13208)
		(layer "B.Cu")
		(net "SMB_NIC1_R_SDA")
	)
	(segment
		(start 223.008698 -231.666288)
		(end 221.875858 -231.666288)
		(width 0.15494)
		(layer "In7.Cu")
		(net "SMB_NIC1_R_SDA")
	)
	(segment
		(start 221.27337 -231.0638)
		(end 206.958946 -231.0638)
		(width 0.15494)
		(layer "In7.Cu")
		(net "SMB_NIC1_R_SDA")
	)
	(segment
		(start 208.522316 -164.106606)
		(end 208.522316 -131.118356)
		(width 0.15494)
		(layer "In7.Cu")
		(net "SMB_NIC1_R_SDA")
	)
	(segment
		(start 223.679512 -233.182668)
		(end 223.19107 -232.694226)
		(width 0.15494)
		(layer "In7.Cu")
		(net "SMB_NIC1_R_SDA")
	)
	(segment
		(start 202.7174 -113.4618)
		(end 202.3364 -113.0808)
		(width 0.15494)
		(layer "In7.Cu")
		(net "SMB_NIC1_R_SDA")
	)
	(segment
		(start 202.7174 -115.9256)
		(end 202.7174 -113.4618)
		(width 0.15494)
		(layer "In7.Cu")
		(net "SMB_NIC1_R_SDA")
	)
	(segment
		(start 202.3364 -113.0808)
		(end 202.3364 -104.701086)
		(width 0.15494)
		(layer "In7.Cu")
		(net "SMB_NIC1_R_SDA")
	)
	(segment
		(start 221.875858 -231.666288)
		(end 221.27337 -231.0638)
		(width 0.15494)
		(layer "In7.Cu")
		(net "SMB_NIC1_R_SDA")
	)
	(segment
		(start 223.19107 -232.694226)
		(end 223.19107 -231.84866)
		(width 0.15494)
		(layer "In7.Cu")
		(net "SMB_NIC1_R_SDA")
	)
	(segment
		(start 208.522316 -131.118356)
		(end 203.14666 -125.7427)
		(width 0.15494)
		(layer "In7.Cu")
		(net "SMB_NIC1_R_SDA")
	)
	(segment
		(start 206.1718 -231.1908)
		(end 200.048876 -225.067876)
		(width 0.15494)
		(layer "In7.Cu")
		(net "SMB_NIC1_R_SDA")
	)
	(segment
		(start 204.220064 -187.814966)
		(end 204.220064 -168.408858)
		(width 0.15494)
		(layer "In7.Cu")
		(net "SMB_NIC1_R_SDA")
	)
	(segment
		(start 204.220064 -168.408858)
		(end 208.522316 -164.106606)
		(width 0.15494)
		(layer "In7.Cu")
		(net "SMB_NIC1_R_SDA")
	)
	(segment
		(start 206.958946 -231.0638)
		(end 206.831946 -231.1908)
		(width 0.15494)
		(layer "In7.Cu")
		(net "SMB_NIC1_R_SDA")
	)
	(segment
		(start 223.19107 -231.84866)
		(end 223.008698 -231.666288)
		(width 0.15494)
		(layer "In7.Cu")
		(net "SMB_NIC1_R_SDA")
	)
	(segment
		(start 200.048876 -191.986154)
		(end 204.220064 -187.814966)
		(width 0.15494)
		(layer "In7.Cu")
		(net "SMB_NIC1_R_SDA")
	)
	(segment
		(start 200.048876 -225.067876)
		(end 200.048876 -191.986154)
		(width 0.15494)
		(layer "In7.Cu")
		(net "SMB_NIC1_R_SDA")
	)
	(segment
		(start 203.14666 -116.35486)
		(end 202.7174 -115.9256)
		(width 0.15494)
		(layer "In7.Cu")
		(net "SMB_NIC1_R_SDA")
	)
	(segment
		(start 202.3364 -104.701086)
		(end 201.648822 -104.013508)
		(width 0.15494)
		(layer "In7.Cu")
		(net "SMB_NIC1_R_SDA")
	)
	(segment
		(start 203.14666 -125.7427)
		(end 203.14666 -116.35486)
		(width 0.15494)
		(layer "In7.Cu")
		(net "SMB_NIC1_R_SDA")
	)
	(segment
		(start 206.831946 -231.1908)
		(end 206.1718 -231.1908)
		(width 0.15494)
		(layer "In7.Cu")
		(net "SMB_NIC1_R_SDA")
	)
	(segment
		(start 103.3526 -96.5708)
		(end 107.849924 -96.5708)
		(width 0.15494)
		(layer "In15.Cu")
		(net "SMB_NIC1_R_SDA")
	)
	(segment
		(start 70.560946 -99.2124)
		(end 74.676 -99.2124)
		(width 0.15494)
		(layer "In15.Cu")
		(net "SMB_NIC1_R_SDA")
	)
	(segment
		(start 200.0504 -99.4664)
		(end 200.0504 -103.2002)
		(width 0.15494)
		(layer "In15.Cu")
		(net "SMB_NIC1_R_SDA")
	)
	(segment
		(start 67.362324 -113.3856)
		(end 67.362324 -112.333024)
		(width 0.15494)
		(layer "In15.Cu")
		(net "SMB_NIC1_R_SDA")
	)
	(segment
		(start 179.7558 -91.2876)
		(end 180.1622 -91.694)
		(width 0.15494)
		(layer "In15.Cu")
		(net "SMB_NIC1_R_SDA")
	)
	(segment
		(start 200.863708 -104.013508)
		(end 201.648822 -104.013508)
		(width 0.15494)
		(layer "In15.Cu")
		(net "SMB_NIC1_R_SDA")
	)
	(segment
		(start 182.5498 -90.932)
		(end 191.516 -90.932)
		(width 0.15494)
		(layer "In15.Cu")
		(net "SMB_NIC1_R_SDA")
	)
	(segment
		(start 89.280746 -93.3704)
		(end 100.1522 -93.3704)
		(width 0.15494)
		(layer "In15.Cu")
		(net "SMB_NIC1_R_SDA")
	)
	(segment
		(start 181.7878 -91.694)
		(end 182.5498 -90.932)
		(width 0.15494)
		(layer "In15.Cu")
		(net "SMB_NIC1_R_SDA")
	)
	(segment
		(start 107.849924 -96.5708)
		(end 114.504724 -103.2256)
		(width 0.15494)
		(layer "In15.Cu")
		(net "SMB_NIC1_R_SDA")
	)
	(segment
		(start 76.0222 -99.9744)
		(end 76.430378 -99.566222)
		(width 0.15494)
		(layer "In15.Cu")
		(net "SMB_NIC1_R_SDA")
	)
	(segment
		(start 83.084924 -99.566222)
		(end 89.280746 -93.3704)
		(width 0.15494)
		(layer "In15.Cu")
		(net "SMB_NIC1_R_SDA")
	)
	(segment
		(start 74.676 -99.2124)
		(end 75.438 -99.9744)
		(width 0.15494)
		(layer "In15.Cu")
		(net "SMB_NIC1_R_SDA")
	)
	(segment
		(start 75.438 -99.9744)
		(end 76.0222 -99.9744)
		(width 0.15494)
		(layer "In15.Cu")
		(net "SMB_NIC1_R_SDA")
	)
	(segment
		(start 156.972 -91.2876)
		(end 179.7558 -91.2876)
		(width 0.15494)
		(layer "In15.Cu")
		(net "SMB_NIC1_R_SDA")
	)
	(segment
		(start 67.362324 -112.333024)
		(end 66.7258 -111.6965)
		(width 0.15494)
		(layer "In15.Cu")
		(net "SMB_NIC1_R_SDA")
	)
	(segment
		(start 66.7258 -111.6965)
		(end 66.7258 -101.8794)
		(width 0.15494)
		(layer "In15.Cu")
		(net "SMB_NIC1_R_SDA")
	)
	(segment
		(start 191.516 -90.932)
		(end 200.0504 -99.4664)
		(width 0.15494)
		(layer "In15.Cu")
		(net "SMB_NIC1_R_SDA")
	)
	(segment
		(start 114.504724 -103.2256)
		(end 145.034 -103.2256)
		(width 0.15494)
		(layer "In15.Cu")
		(net "SMB_NIC1_R_SDA")
	)
	(segment
		(start 66.7258 -101.8794)
		(end 68.8848 -99.7204)
		(width 0.15494)
		(layer "In15.Cu")
		(net "SMB_NIC1_R_SDA")
	)
	(segment
		(start 100.1522 -93.3704)
		(end 103.3526 -96.5708)
		(width 0.15494)
		(layer "In15.Cu")
		(net "SMB_NIC1_R_SDA")
	)
	(segment
		(start 68.8848 -99.7204)
		(end 70.052946 -99.7204)
		(width 0.15494)
		(layer "In15.Cu")
		(net "SMB_NIC1_R_SDA")
	)
	(segment
		(start 145.034 -103.2256)
		(end 156.972 -91.2876)
		(width 0.15494)
		(layer "In15.Cu")
		(net "SMB_NIC1_R_SDA")
	)
	(segment
		(start 180.1622 -91.694)
		(end 181.7878 -91.694)
		(width 0.15494)
		(layer "In15.Cu")
		(net "SMB_NIC1_R_SDA")
	)
	(segment
		(start 67.312794 -113.43513)
		(end 67.362324 -113.3856)
		(width 0.15494)
		(layer "In15.Cu")
		(net "SMB_NIC1_R_SDA")
	)
	(segment
		(start 76.430378 -99.566222)
		(end 83.084924 -99.566222)
		(width 0.15494)
		(layer "In15.Cu")
		(net "SMB_NIC1_R_SDA")
	)
	(segment
		(start 70.052946 -99.7204)
		(end 70.560946 -99.2124)
		(width 0.15494)
		(layer "In15.Cu")
		(net "SMB_NIC1_R_SDA")
	)
	(segment
		(start 200.0504 -103.2002)
		(end 200.863708 -104.013508)
		(width 0.15494)
		(layer "In15.Cu")
		(net "SMB_NIC1_R_SDA")
	)
	(segment
		(start 108.639102 -83.029044)
		(end 108.639102 -81.77911)
		(width 0.13208)
		(layer "F.Cu")
		(net "SSD1_CLK_EN_R_N")
	)
	(via
		(at 108.639102 -81.77911)
		(size 0.508)
		(drill 0.254)
		(layers "F.Cu" "B.Cu")
		(net "SSD1_CLK_EN_R_N")
	)
	(via
		(at 116.966492 -221.064836)
		(size 0.508)
		(drill 0.254)
		(layers "F.Cu" "B.Cu")
		(net "SSD1_CLK_EN_R_N")
	)
	(via
		(at 89.187528 -81.839308)
		(size 0.508)
		(drill 0.254)
		(layers "F.Cu" "B.Cu")
		(net "SSD1_CLK_EN_R_N")
	)
	(via
		(at 337.616546 -237.19155)
		(size 0.508)
		(drill 0.254)
		(layers "F.Cu" "B.Cu")
		(net "SSD1_CLK_EN_R_N")
	)
	(segment
		(start 339.270086 -235.816648)
		(end 338.059014 -235.816648)
		(width 0.13208)
		(layer "B.Cu")
		(net "SSD1_CLK_EN_R_N")
	)
	(segment
		(start 339.979 -233.95305)
		(end 339.979 -234.300014)
		(width 0.13208)
		(layer "B.Cu")
		(net "SSD1_CLK_EN_R_N")
	)
	(segment
		(start 339.485478 -235.601256)
		(end 339.270086 -235.816648)
		(width 0.13208)
		(layer "B.Cu")
		(net "SSD1_CLK_EN_R_N")
	)
	(segment
		(start 339.979 -234.300014)
		(end 339.485478 -234.793536)
		(width 0.13208)
		(layer "B.Cu")
		(net "SSD1_CLK_EN_R_N")
	)
	(segment
		(start 339.485478 -234.793536)
		(end 339.485478 -235.601256)
		(width 0.13208)
		(layer "B.Cu")
		(net "SSD1_CLK_EN_R_N")
	)
	(segment
		(start 337.616546 -236.259116)
		(end 337.616546 -237.19155)
		(width 0.13208)
		(layer "B.Cu")
		(net "SSD1_CLK_EN_R_N")
	)
	(segment
		(start 338.059014 -235.816648)
		(end 337.616546 -236.259116)
		(width 0.13208)
		(layer "B.Cu")
		(net "SSD1_CLK_EN_R_N")
	)
	(segment
		(start 101.710998 -192.672462)
		(end 106.00563 -192.672462)
		(width 0.15494)
		(layer "In5.Cu")
		(net "SSD1_CLK_EN_R_N")
	)
	(segment
		(start 81.755234 -114.587782)
		(end 84.624164 -114.587782)
		(width 0.15494)
		(layer "In5.Cu")
		(net "SSD1_CLK_EN_R_N")
	)
	(segment
		(start 115.55349 -219.651834)
		(end 116.966492 -221.064836)
		(width 0.15494)
		(layer "In5.Cu")
		(net "SSD1_CLK_EN_R_N")
	)
	(segment
		(start 100.623878 -191.585342)
		(end 101.710998 -192.672462)
		(width 0.15494)
		(layer "In5.Cu")
		(net "SSD1_CLK_EN_R_N")
	)
	(segment
		(start 95.3516 -177.26406)
		(end 96.845628 -178.758088)
		(width 0.15494)
		(layer "In5.Cu")
		(net "SSD1_CLK_EN_R_N")
	)
	(segment
		(start 100.623878 -186.475878)
		(end 100.623878 -191.585342)
		(width 0.15494)
		(layer "In5.Cu")
		(net "SSD1_CLK_EN_R_N")
	)
	(segment
		(start 84.624164 -114.587782)
		(end 88.81872 -118.782338)
		(width 0.15494)
		(layer "In5.Cu")
		(net "SSD1_CLK_EN_R_N")
	)
	(segment
		(start 82.461862 -92.268548)
		(end 82.461862 -108.2929)
		(width 0.15494)
		(layer "In5.Cu")
		(net "SSD1_CLK_EN_R_N")
	)
	(segment
		(start 107.5436 -200.1266)
		(end 108.4072 -200.9902)
		(width 0.15494)
		(layer "In5.Cu")
		(net "SSD1_CLK_EN_R_N")
	)
	(segment
		(start 115.55349 -207.12049)
		(end 115.55349 -219.651834)
		(width 0.15494)
		(layer "In5.Cu")
		(net "SSD1_CLK_EN_R_N")
	)
	(segment
		(start 108.4072 -200.9902)
		(end 109.4232 -200.9902)
		(width 0.15494)
		(layer "In5.Cu")
		(net "SSD1_CLK_EN_R_N")
	)
	(segment
		(start 106.00563 -192.672462)
		(end 107.5436 -194.210432)
		(width 0.15494)
		(layer "In5.Cu")
		(net "SSD1_CLK_EN_R_N")
	)
	(segment
		(start 81.189576 -114.022124)
		(end 81.755234 -114.587782)
		(width 0.15494)
		(layer "In5.Cu")
		(net "SSD1_CLK_EN_R_N")
	)
	(segment
		(start 89.187528 -81.839308)
		(end 89.187528 -85.542882)
		(width 0.15494)
		(layer "In5.Cu")
		(net "SSD1_CLK_EN_R_N")
	)
	(segment
		(start 88.81872 -126.78918)
		(end 91.99372 -129.96418)
		(width 0.15494)
		(layer "In5.Cu")
		(net "SSD1_CLK_EN_R_N")
	)
	(segment
		(start 109.4232 -200.9902)
		(end 115.55349 -207.12049)
		(width 0.15494)
		(layer "In5.Cu")
		(net "SSD1_CLK_EN_R_N")
	)
	(segment
		(start 91.99372 -133.68655)
		(end 95.3516 -141.793214)
		(width 0.15494)
		(layer "In5.Cu")
		(net "SSD1_CLK_EN_R_N")
	)
	(segment
		(start 81.189576 -109.565186)
		(end 81.189576 -114.022124)
		(width 0.15494)
		(layer "In5.Cu")
		(net "SSD1_CLK_EN_R_N")
	)
	(segment
		(start 96.845628 -178.758088)
		(end 96.845628 -182.697628)
		(width 0.15494)
		(layer "In5.Cu")
		(net "SSD1_CLK_EN_R_N")
	)
	(segment
		(start 107.5436 -194.210432)
		(end 107.5436 -200.1266)
		(width 0.15494)
		(layer "In5.Cu")
		(net "SSD1_CLK_EN_R_N")
	)
	(segment
		(start 91.99372 -129.96418)
		(end 91.99372 -133.68655)
		(width 0.15494)
		(layer "In5.Cu")
		(net "SSD1_CLK_EN_R_N")
	)
	(segment
		(start 82.461862 -108.2929)
		(end 81.189576 -109.565186)
		(width 0.15494)
		(layer "In5.Cu")
		(net "SSD1_CLK_EN_R_N")
	)
	(segment
		(start 95.3516 -141.793214)
		(end 95.3516 -177.26406)
		(width 0.15494)
		(layer "In5.Cu")
		(net "SSD1_CLK_EN_R_N")
	)
	(segment
		(start 89.187528 -85.542882)
		(end 82.461862 -92.268548)
		(width 0.15494)
		(layer "In5.Cu")
		(net "SSD1_CLK_EN_R_N")
	)
	(segment
		(start 96.845628 -182.697628)
		(end 100.623878 -186.475878)
		(width 0.15494)
		(layer "In5.Cu")
		(net "SSD1_CLK_EN_R_N")
	)
	(segment
		(start 88.81872 -118.782338)
		(end 88.81872 -126.78918)
		(width 0.15494)
		(layer "In5.Cu")
		(net "SSD1_CLK_EN_R_N")
	)
	(segment
		(start 118.939056 -221.064836)
		(end 128.53162 -230.6574)
		(width 0.15494)
		(layer "In15.Cu")
		(net "SSD1_CLK_EN_R_N")
	)
	(segment
		(start 138.714226 -230.40848)
		(end 138.963146 -230.6574)
		(width 0.15494)
		(layer "In15.Cu")
		(net "SSD1_CLK_EN_R_N")
	)
	(segment
		(start 145.953226 -228.236526)
		(end 158.014416 -228.236526)
		(width 0.15494)
		(layer "In15.Cu")
		(net "SSD1_CLK_EN_R_N")
	)
	(segment
		(start 230.556308 -238.4044)
		(end 241.1222 -238.4044)
		(width 0.15494)
		(layer "In15.Cu")
		(net "SSD1_CLK_EN_R_N")
	)
	(segment
		(start 221.44609 -238.82731)
		(end 222.25 -238.0234)
		(width 0.15494)
		(layer "In15.Cu")
		(net "SSD1_CLK_EN_R_N")
	)
	(segment
		(start 224.94367 -238.5822)
		(end 225.42881 -238.09706)
		(width 0.15494)
		(layer "In15.Cu")
		(net "SSD1_CLK_EN_R_N")
	)
	(segment
		(start 144.488154 -229.701598)
		(end 145.953226 -228.236526)
		(width 0.15494)
		(layer "In15.Cu")
		(net "SSD1_CLK_EN_R_N")
	)
	(segment
		(start 276.71649 -240.500662)
		(end 327.014078 -240.500662)
		(width 0.15494)
		(layer "In15.Cu")
		(net "SSD1_CLK_EN_R_N")
	)
	(segment
		(start 241.1222 -238.4044)
		(end 241.75466 -239.03686)
		(width 0.15494)
		(layer "In15.Cu")
		(net "SSD1_CLK_EN_R_N")
	)
	(segment
		(start 253.879858 -232.35666)
		(end 257.687826 -232.35666)
		(width 0.15494)
		(layer "In15.Cu")
		(net "SSD1_CLK_EN_R_N")
	)
	(segment
		(start 275.820886 -239.605058)
		(end 276.71649 -240.500662)
		(width 0.15494)
		(layer "In15.Cu")
		(net "SSD1_CLK_EN_R_N")
	)
	(segment
		(start 222.25 -238.0234)
		(end 223.16313 -238.0234)
		(width 0.15494)
		(layer "In15.Cu")
		(net "SSD1_CLK_EN_R_N")
	)
	(segment
		(start 216.001092 -238.82731)
		(end 221.44609 -238.82731)
		(width 0.15494)
		(layer "In15.Cu")
		(net "SSD1_CLK_EN_R_N")
	)
	(segment
		(start 328.72172 -239.78489)
		(end 331.39126 -239.78489)
		(width 0.15494)
		(layer "In15.Cu")
		(net "SSD1_CLK_EN_R_N")
	)
	(segment
		(start 331.39126 -239.78489)
		(end 332.777338 -238.398812)
		(width 0.15494)
		(layer "In15.Cu")
		(net "SSD1_CLK_EN_R_N")
	)
	(segment
		(start 230.248968 -238.09706)
		(end 230.556308 -238.4044)
		(width 0.15494)
		(layer "In15.Cu")
		(net "SSD1_CLK_EN_R_N")
	)
	(segment
		(start 267.163804 -237.353856)
		(end 269.415006 -239.605058)
		(width 0.15494)
		(layer "In15.Cu")
		(net "SSD1_CLK_EN_R_N")
	)
	(segment
		(start 89.572084 -81.454752)
		(end 89.187528 -81.839308)
		(width 0.15494)
		(layer "In15.Cu")
		(net "SSD1_CLK_EN_R_N")
	)
	(segment
		(start 158.014416 -228.236526)
		(end 162.3822 -232.60431)
		(width 0.15494)
		(layer "In15.Cu")
		(net "SSD1_CLK_EN_R_N")
	)
	(segment
		(start 267.163804 -236.232446)
		(end 267.163804 -237.353856)
		(width 0.15494)
		(layer "In15.Cu")
		(net "SSD1_CLK_EN_R_N")
	)
	(segment
		(start 186.103514 -232.60431)
		(end 191.31026 -237.811056)
		(width 0.15494)
		(layer "In15.Cu")
		(net "SSD1_CLK_EN_R_N")
	)
	(segment
		(start 336.409284 -238.398812)
		(end 337.616546 -237.19155)
		(width 0.15494)
		(layer "In15.Cu")
		(net "SSD1_CLK_EN_R_N")
	)
	(segment
		(start 262.950198 -232.841292)
		(end 264.35431 -233.422952)
		(width 0.15494)
		(layer "In15.Cu")
		(net "SSD1_CLK_EN_R_N")
	)
	(segment
		(start 138.963146 -230.6574)
		(end 139.590526 -230.6574)
		(width 0.15494)
		(layer "In15.Cu")
		(net "SSD1_CLK_EN_R_N")
	)
	(segment
		(start 223.72193 -238.5822)
		(end 224.94367 -238.5822)
		(width 0.15494)
		(layer "In15.Cu")
		(net "SSD1_CLK_EN_R_N")
	)
	(segment
		(start 241.75466 -239.03686)
		(end 247.199658 -239.03686)
		(width 0.15494)
		(layer "In15.Cu")
		(net "SSD1_CLK_EN_R_N")
	)
	(segment
		(start 116.966492 -221.064836)
		(end 118.939056 -221.064836)
		(width 0.15494)
		(layer "In15.Cu")
		(net "SSD1_CLK_EN_R_N")
	)
	(segment
		(start 223.16313 -238.0234)
		(end 223.72193 -238.5822)
		(width 0.15494)
		(layer "In15.Cu")
		(net "SSD1_CLK_EN_R_N")
	)
	(segment
		(start 257.687826 -232.35666)
		(end 258.180586 -231.8639)
		(width 0.15494)
		(layer "In15.Cu")
		(net "SSD1_CLK_EN_R_N")
	)
	(segment
		(start 108.314744 -81.454752)
		(end 89.572084 -81.454752)
		(width 0.15494)
		(layer "In15.Cu")
		(net "SSD1_CLK_EN_R_N")
	)
	(segment
		(start 140.546328 -229.701598)
		(end 144.488154 -229.701598)
		(width 0.15494)
		(layer "In15.Cu")
		(net "SSD1_CLK_EN_R_N")
	)
	(segment
		(start 130.049016 -230.6574)
		(end 130.297936 -230.40848)
		(width 0.15494)
		(layer "In15.Cu")
		(net "SSD1_CLK_EN_R_N")
	)
	(segment
		(start 328.175366 -240.33099)
		(end 328.72172 -239.78489)
		(width 0.15494)
		(layer "In15.Cu")
		(net "SSD1_CLK_EN_R_N")
	)
	(segment
		(start 225.42881 -238.09706)
		(end 230.248968 -238.09706)
		(width 0.15494)
		(layer "In15.Cu")
		(net "SSD1_CLK_EN_R_N")
	)
	(segment
		(start 327.18375 -240.33099)
		(end 328.175366 -240.33099)
		(width 0.15494)
		(layer "In15.Cu")
		(net "SSD1_CLK_EN_R_N")
	)
	(segment
		(start 264.35431 -233.422952)
		(end 267.163804 -236.232446)
		(width 0.15494)
		(layer "In15.Cu")
		(net "SSD1_CLK_EN_R_N")
	)
	(segment
		(start 214.984838 -237.811056)
		(end 216.001092 -238.82731)
		(width 0.15494)
		(layer "In15.Cu")
		(net "SSD1_CLK_EN_R_N")
	)
	(segment
		(start 327.014078 -240.500662)
		(end 327.18375 -240.33099)
		(width 0.15494)
		(layer "In15.Cu")
		(net "SSD1_CLK_EN_R_N")
	)
	(segment
		(start 130.297936 -230.40848)
		(end 138.714226 -230.40848)
		(width 0.15494)
		(layer "In15.Cu")
		(net "SSD1_CLK_EN_R_N")
	)
	(segment
		(start 258.180586 -231.8639)
		(end 261.972806 -231.8639)
		(width 0.15494)
		(layer "In15.Cu")
		(net "SSD1_CLK_EN_R_N")
	)
	(segment
		(start 108.639102 -81.77911)
		(end 108.314744 -81.454752)
		(width 0.15494)
		(layer "In15.Cu")
		(net "SSD1_CLK_EN_R_N")
	)
	(segment
		(start 247.199658 -239.03686)
		(end 253.879858 -232.35666)
		(width 0.15494)
		(layer "In15.Cu")
		(net "SSD1_CLK_EN_R_N")
	)
	(segment
		(start 139.590526 -230.6574)
		(end 140.546328 -229.701598)
		(width 0.15494)
		(layer "In15.Cu")
		(net "SSD1_CLK_EN_R_N")
	)
	(segment
		(start 332.777338 -238.398812)
		(end 336.409284 -238.398812)
		(width 0.15494)
		(layer "In15.Cu")
		(net "SSD1_CLK_EN_R_N")
	)
	(segment
		(start 191.31026 -237.811056)
		(end 214.984838 -237.811056)
		(width 0.15494)
		(layer "In15.Cu")
		(net "SSD1_CLK_EN_R_N")
	)
	(segment
		(start 261.972806 -231.8639)
		(end 262.950198 -232.841292)
		(width 0.15494)
		(layer "In15.Cu")
		(net "SSD1_CLK_EN_R_N")
	)
	(segment
		(start 269.415006 -239.605058)
		(end 275.820886 -239.605058)
		(width 0.15494)
		(layer "In15.Cu")
		(net "SSD1_CLK_EN_R_N")
	)
	(segment
		(start 162.3822 -232.60431)
		(end 186.103514 -232.60431)
		(width 0.15494)
		(layer "In15.Cu")
		(net "SSD1_CLK_EN_R_N")
	)
	(segment
		(start 128.53162 -230.6574)
		(end 130.049016 -230.6574)
		(width 0.15494)
		(layer "In15.Cu")
		(net "SSD1_CLK_EN_R_N")
	)
	(segment
		(start 113.427764 -86.12759)
		(end 113.300764 -86.25459)
		(width 0.13208)
		(layer "F.Cu")
		(net "SSD5_CLK_EN_R_N")
	)
	(segment
		(start 112.332008 -86.178898)
		(end 111.788956 -86.178898)
		(width 0.13208)
		(layer "F.Cu")
		(net "SSD5_CLK_EN_R_N")
	)
	(segment
		(start 113.427764 -85.830918)
		(end 113.427764 -86.12759)
		(width 0.13208)
		(layer "F.Cu")
		(net "SSD5_CLK_EN_R_N")
	)
	(segment
		(start 113.300764 -86.25459)
		(end 112.4077 -86.25459)
		(width 0.13208)
		(layer "F.Cu")
		(net "SSD5_CLK_EN_R_N")
	)
	(segment
		(start 112.4077 -86.25459)
		(end 112.332008 -86.178898)
		(width 0.13208)
		(layer "F.Cu")
		(net "SSD5_CLK_EN_R_N")
	)
	(segment
		(start 348.107 -234.46105)
		(end 348.107 -235.077)
		(width 0.13208)
		(layer "F.Cu")
		(net "SSD5_CLK_EN_R_N")
	)
	(via
		(at 348.107 -235.077)
		(size 0.508)
		(drill 0.254)
		(layers "F.Cu" "B.Cu")
		(net "SSD5_CLK_EN_R_N")
	)
	(via
		(at 80.08874 -90.604848)
		(size 0.508)
		(drill 0.254)
		(layers "F.Cu" "B.Cu")
		(net "SSD5_CLK_EN_R_N")
	)
	(via
		(at 119.651272 -236.27969)
		(size 0.508)
		(drill 0.254)
		(layers "F.Cu" "B.Cu")
		(net "SSD5_CLK_EN_R_N")
	)
	(via
		(at 113.427764 -85.830918)
		(size 0.508)
		(drill 0.254)
		(layers "F.Cu" "B.Cu")
		(net "SSD5_CLK_EN_R_N")
	)
	(segment
		(start 113.897918 -211.027518)
		(end 113.897918 -222.122492)
		(width 0.15494)
		(layer "In5.Cu")
		(net "SSD5_CLK_EN_R_N")
	)
	(segment
		(start 94.493588 -179.733448)
		(end 94.493588 -184.688988)
		(width 0.15494)
		(layer "In5.Cu")
		(net "SSD5_CLK_EN_R_N")
	)
	(segment
		(start 78.837536 -108.589064)
		(end 78.837536 -114.997738)
		(width 0.15494)
		(layer "In5.Cu")
		(net "SSD5_CLK_EN_R_N")
	)
	(segment
		(start 92.99956 -142.263876)
		(end 92.99956 -178.23942)
		(width 0.15494)
		(layer "In5.Cu")
		(net "SSD5_CLK_EN_R_N")
	)
	(segment
		(start 119.17807 -234.392724)
		(end 119.5324 -234.747054)
		(width 0.15494)
		(layer "In5.Cu")
		(net "SSD5_CLK_EN_R_N")
	)
	(segment
		(start 92.99956 -178.23942)
		(end 94.493588 -179.733448)
		(width 0.15494)
		(layer "In5.Cu")
		(net "SSD5_CLK_EN_R_N")
	)
	(segment
		(start 119.5324 -236.160818)
		(end 119.651272 -236.27969)
		(width 0.15494)
		(layer "In5.Cu")
		(net "SSD5_CLK_EN_R_N")
	)
	(segment
		(start 104.21747 -201.34707)
		(end 113.897918 -211.027518)
		(width 0.15494)
		(layer "In5.Cu")
		(net "SSD5_CLK_EN_R_N")
	)
	(segment
		(start 83.648804 -116.939822)
		(end 86.46668 -119.757698)
		(width 0.15494)
		(layer "In5.Cu")
		(net "SSD5_CLK_EN_R_N")
	)
	(segment
		(start 80.109822 -92.059252)
		(end 80.109822 -107.316778)
		(width 0.15494)
		(layer "In5.Cu")
		(net "SSD5_CLK_EN_R_N")
	)
	(segment
		(start 89.64168 -130.93954)
		(end 89.64168 -134.157212)
		(width 0.15494)
		(layer "In5.Cu")
		(net "SSD5_CLK_EN_R_N")
	)
	(segment
		(start 78.837536 -114.997738)
		(end 80.77962 -116.939822)
		(width 0.15494)
		(layer "In5.Cu")
		(net "SSD5_CLK_EN_R_N")
	)
	(segment
		(start 80.109822 -107.316778)
		(end 78.837536 -108.589064)
		(width 0.15494)
		(layer "In5.Cu")
		(net "SSD5_CLK_EN_R_N")
	)
	(segment
		(start 80.08874 -90.604848)
		(end 80.08874 -92.03817)
		(width 0.15494)
		(layer "In5.Cu")
		(net "SSD5_CLK_EN_R_N")
	)
	(segment
		(start 98.5266 -188.722)
		(end 98.5266 -193.625216)
		(width 0.15494)
		(layer "In5.Cu")
		(net "SSD5_CLK_EN_R_N")
	)
	(segment
		(start 86.46668 -127.76454)
		(end 89.64168 -130.93954)
		(width 0.15494)
		(layer "In5.Cu")
		(net "SSD5_CLK_EN_R_N")
	)
	(segment
		(start 80.08874 -92.03817)
		(end 80.109822 -92.059252)
		(width 0.15494)
		(layer "In5.Cu")
		(net "SSD5_CLK_EN_R_N")
	)
	(segment
		(start 113.897918 -222.122492)
		(end 119.17807 -227.402644)
		(width 0.15494)
		(layer "In5.Cu")
		(net "SSD5_CLK_EN_R_N")
	)
	(segment
		(start 104.21747 -199.316086)
		(end 104.21747 -201.34707)
		(width 0.15494)
		(layer "In5.Cu")
		(net "SSD5_CLK_EN_R_N")
	)
	(segment
		(start 86.46668 -119.757698)
		(end 86.46668 -127.76454)
		(width 0.15494)
		(layer "In5.Cu")
		(net "SSD5_CLK_EN_R_N")
	)
	(segment
		(start 119.5324 -234.747054)
		(end 119.5324 -236.160818)
		(width 0.15494)
		(layer "In5.Cu")
		(net "SSD5_CLK_EN_R_N")
	)
	(segment
		(start 94.493588 -184.688988)
		(end 98.5266 -188.722)
		(width 0.15494)
		(layer "In5.Cu")
		(net "SSD5_CLK_EN_R_N")
	)
	(segment
		(start 98.5266 -193.625216)
		(end 104.21747 -199.316086)
		(width 0.15494)
		(layer "In5.Cu")
		(net "SSD5_CLK_EN_R_N")
	)
	(segment
		(start 119.17807 -227.402644)
		(end 119.17807 -234.392724)
		(width 0.15494)
		(layer "In5.Cu")
		(net "SSD5_CLK_EN_R_N")
	)
	(segment
		(start 80.77962 -116.939822)
		(end 83.648804 -116.939822)
		(width 0.15494)
		(layer "In5.Cu")
		(net "SSD5_CLK_EN_R_N")
	)
	(segment
		(start 89.64168 -134.157212)
		(end 92.99956 -142.263876)
		(width 0.15494)
		(layer "In5.Cu")
		(net "SSD5_CLK_EN_R_N")
	)
	(segment
		(start 273.841972 -246.791988)
		(end 274.115276 -247.065292)
		(width 0.15494)
		(layer "In15.Cu")
		(net "SSD5_CLK_EN_R_N")
	)
	(segment
		(start 154.074876 -233.0704)
		(end 156.410914 -233.0704)
		(width 0.15494)
		(layer "In15.Cu")
		(net "SSD5_CLK_EN_R_N")
	)
	(segment
		(start 141.439646 -231.87406)
		(end 150.771606 -231.87406)
		(width 0.15494)
		(layer "In15.Cu")
		(net "SSD5_CLK_EN_R_N")
	)
	(segment
		(start 347.34754 -239.564672)
		(end 347.894402 -239.01781)
		(width 0.15494)
		(layer "In15.Cu")
		(net "SSD5_CLK_EN_R_N")
	)
	(segment
		(start 326.32777 -248.501916)
		(end 327.190354 -249.3645)
		(width 0.15494)
		(layer "In15.Cu")
		(net "SSD5_CLK_EN_R_N")
	)
	(segment
		(start 237.558326 -247.592342)
		(end 239.594644 -245.556024)
		(width 0.15494)
		(layer "In15.Cu")
		(net "SSD5_CLK_EN_R_N")
	)
	(segment
		(start 347.62313 -237.901734)
		(end 347.62313 -235.56087)
		(width 0.15494)
		(layer "In15.Cu")
		(net "SSD5_CLK_EN_R_N")
	)
	(segment
		(start 249.714512 -246.791988)
		(end 273.841972 -246.791988)
		(width 0.15494)
		(layer "In15.Cu")
		(net "SSD5_CLK_EN_R_N")
	)
	(segment
		(start 80.523588 -91.039696)
		(end 80.08874 -90.604848)
		(width 0.15494)
		(layer "In15.Cu")
		(net "SSD5_CLK_EN_R_N")
	)
	(segment
		(start 100.518722 -85.266276)
		(end 99.05746 -85.266276)
		(width 0.15494)
		(layer "In15.Cu")
		(net "SSD5_CLK_EN_R_N")
	)
	(segment
		(start 239.594644 -245.556024)
		(end 248.478548 -245.556024)
		(width 0.15494)
		(layer "In15.Cu")
		(net "SSD5_CLK_EN_R_N")
	)
	(segment
		(start 99.05746 -85.266276)
		(end 97.785936 -86.5378)
		(width 0.15494)
		(layer "In15.Cu")
		(net "SSD5_CLK_EN_R_N")
	)
	(segment
		(start 300.208188 -248.592848)
		(end 303.315624 -248.592848)
		(width 0.15494)
		(layer "In15.Cu")
		(net "SSD5_CLK_EN_R_N")
	)
	(segment
		(start 333.356966 -248.14276)
		(end 339.452204 -248.14276)
		(width 0.15494)
		(layer "In15.Cu")
		(net "SSD5_CLK_EN_R_N")
	)
	(segment
		(start 151.76373 -232.565448)
		(end 152.855676 -232.565448)
		(width 0.15494)
		(layer "In15.Cu")
		(net "SSD5_CLK_EN_R_N")
	)
	(segment
		(start 156.410914 -233.0704)
		(end 160.027874 -236.68736)
		(width 0.15494)
		(layer "In15.Cu")
		(net "SSD5_CLK_EN_R_N")
	)
	(segment
		(start 160.027874 -236.68736)
		(end 179.80914 -236.68736)
		(width 0.15494)
		(layer "In15.Cu")
		(net "SSD5_CLK_EN_R_N")
	)
	(segment
		(start 119.651272 -236.27969)
		(end 121.758964 -236.27969)
		(width 0.15494)
		(layer "In15.Cu")
		(net "SSD5_CLK_EN_R_N")
	)
	(segment
		(start 333.138526 -248.3612)
		(end 333.356966 -248.14276)
		(width 0.15494)
		(layer "In15.Cu")
		(net "SSD5_CLK_EN_R_N")
	)
	(segment
		(start 327.190354 -249.3645)
		(end 330.388468 -249.3645)
		(width 0.15494)
		(layer "In15.Cu")
		(net "SSD5_CLK_EN_R_N")
	)
	(segment
		(start 123.676664 -234.36199)
		(end 138.951716 -234.36199)
		(width 0.15494)
		(layer "In15.Cu")
		(net "SSD5_CLK_EN_R_N")
	)
	(segment
		(start 347.894402 -239.01781)
		(end 347.894402 -238.173006)
		(width 0.15494)
		(layer "In15.Cu")
		(net "SSD5_CLK_EN_R_N")
	)
	(segment
		(start 113.427764 -85.830918)
		(end 112.334802 -86.92388)
		(width 0.15494)
		(layer "In15.Cu")
		(net "SSD5_CLK_EN_R_N")
	)
	(segment
		(start 121.758964 -236.27969)
		(end 123.676664 -234.36199)
		(width 0.15494)
		(layer "In15.Cu")
		(net "SSD5_CLK_EN_R_N")
	)
	(segment
		(start 331.391768 -248.3612)
		(end 333.138526 -248.3612)
		(width 0.15494)
		(layer "In15.Cu")
		(net "SSD5_CLK_EN_R_N")
	)
	(segment
		(start 185.029094 -241.907314)
		(end 185.417714 -241.907314)
		(width 0.15494)
		(layer "In15.Cu")
		(net "SSD5_CLK_EN_R_N")
	)
	(segment
		(start 185.417714 -241.907314)
		(end 189.724538 -246.214138)
		(width 0.15494)
		(layer "In15.Cu")
		(net "SSD5_CLK_EN_R_N")
	)
	(segment
		(start 220.687138 -246.214138)
		(end 220.985334 -245.915942)
		(width 0.15494)
		(layer "In15.Cu")
		(net "SSD5_CLK_EN_R_N")
	)
	(segment
		(start 151.25065 -232.353104)
		(end 151.76373 -232.565448)
		(width 0.15494)
		(layer "In15.Cu")
		(net "SSD5_CLK_EN_R_N")
	)
	(segment
		(start 223.040194 -245.915942)
		(end 223.475042 -246.35079)
		(width 0.15494)
		(layer "In15.Cu")
		(net "SSD5_CLK_EN_R_N")
	)
	(segment
		(start 303.53508 -248.501916)
		(end 326.32777 -248.501916)
		(width 0.15494)
		(layer "In15.Cu")
		(net "SSD5_CLK_EN_R_N")
	)
	(segment
		(start 298.680632 -247.065292)
		(end 300.208188 -248.592848)
		(width 0.15494)
		(layer "In15.Cu")
		(net "SSD5_CLK_EN_R_N")
	)
	(segment
		(start 138.951716 -234.36199)
		(end 141.439646 -231.87406)
		(width 0.15494)
		(layer "In15.Cu")
		(net "SSD5_CLK_EN_R_N")
	)
	(segment
		(start 102.176326 -86.92388)
		(end 100.518722 -85.266276)
		(width 0.15494)
		(layer "In15.Cu")
		(net "SSD5_CLK_EN_R_N")
	)
	(segment
		(start 81.807304 -91.039696)
		(end 80.523588 -91.039696)
		(width 0.15494)
		(layer "In15.Cu")
		(net "SSD5_CLK_EN_R_N")
	)
	(segment
		(start 347.894402 -238.173006)
		(end 347.62313 -237.901734)
		(width 0.15494)
		(layer "In15.Cu")
		(net "SSD5_CLK_EN_R_N")
	)
	(segment
		(start 347.62313 -235.56087)
		(end 348.107 -235.077)
		(width 0.15494)
		(layer "In15.Cu")
		(net "SSD5_CLK_EN_R_N")
	)
	(segment
		(start 330.388468 -249.3645)
		(end 331.391768 -248.3612)
		(width 0.15494)
		(layer "In15.Cu")
		(net "SSD5_CLK_EN_R_N")
	)
	(segment
		(start 231.865932 -247.592342)
		(end 237.558326 -247.592342)
		(width 0.15494)
		(layer "In15.Cu")
		(net "SSD5_CLK_EN_R_N")
	)
	(segment
		(start 150.771606 -231.87406)
		(end 151.25065 -232.353104)
		(width 0.15494)
		(layer "In15.Cu")
		(net "SSD5_CLK_EN_R_N")
	)
	(segment
		(start 112.334802 -86.92388)
		(end 102.176326 -86.92388)
		(width 0.15494)
		(layer "In15.Cu")
		(net "SSD5_CLK_EN_R_N")
	)
	(segment
		(start 189.724538 -246.214138)
		(end 220.687138 -246.214138)
		(width 0.15494)
		(layer "In15.Cu")
		(net "SSD5_CLK_EN_R_N")
	)
	(segment
		(start 248.478548 -245.556024)
		(end 249.714512 -246.791988)
		(width 0.15494)
		(layer "In15.Cu")
		(net "SSD5_CLK_EN_R_N")
	)
	(segment
		(start 339.452204 -248.14276)
		(end 347.34754 -240.247424)
		(width 0.15494)
		(layer "In15.Cu")
		(net "SSD5_CLK_EN_R_N")
	)
	(segment
		(start 274.115276 -247.065292)
		(end 298.680632 -247.065292)
		(width 0.15494)
		(layer "In15.Cu")
		(net "SSD5_CLK_EN_R_N")
	)
	(segment
		(start 223.475042 -246.35079)
		(end 230.62438 -246.35079)
		(width 0.15494)
		(layer "In15.Cu")
		(net "SSD5_CLK_EN_R_N")
	)
	(segment
		(start 97.785936 -86.5378)
		(end 86.3092 -86.5378)
		(width 0.15494)
		(layer "In15.Cu")
		(net "SSD5_CLK_EN_R_N")
	)
	(segment
		(start 220.985334 -245.915942)
		(end 223.040194 -245.915942)
		(width 0.15494)
		(layer "In15.Cu")
		(net "SSD5_CLK_EN_R_N")
	)
	(segment
		(start 86.3092 -86.5378)
		(end 81.807304 -91.039696)
		(width 0.15494)
		(layer "In15.Cu")
		(net "SSD5_CLK_EN_R_N")
	)
	(segment
		(start 152.855676 -232.565448)
		(end 154.074876 -233.0704)
		(width 0.15494)
		(layer "In15.Cu")
		(net "SSD5_CLK_EN_R_N")
	)
	(segment
		(start 347.34754 -240.247424)
		(end 347.34754 -239.564672)
		(width 0.15494)
		(layer "In15.Cu")
		(net "SSD5_CLK_EN_R_N")
	)
	(segment
		(start 230.62438 -246.35079)
		(end 231.865932 -247.592342)
		(width 0.15494)
		(layer "In15.Cu")
		(net "SSD5_CLK_EN_R_N")
	)
	(segment
		(start 179.80914 -236.68736)
		(end 185.029094 -241.907314)
		(width 0.15494)
		(layer "In15.Cu")
		(net "SSD5_CLK_EN_R_N")
	)
	(segment
		(start 303.315624 -248.592848)
		(end 303.53508 -248.501916)
		(width 0.15494)
		(layer "In15.Cu")
		(net "SSD5_CLK_EN_R_N")
	)
	(segment
		(start 363.87405 -196.723)
		(end 363.87405 -195.707)
		(width 0.13208)
		(layer "F.Cu")
		(net "SSD5_PEX_PWR_EN_R")
	)
	(segment
		(start 364.49 -195.707)
		(end 365.10595 -195.707)
		(width 0.13208)
		(layer "F.Cu")
		(net "SSD5_PEX_PWR_EN_R")
	)
	(segment
		(start 348.493842 -211.98713)
		(end 348.893638 -211.587334)
		(width 0.13208)
		(layer "F.Cu")
		(net "SSD5_PEX_PWR_EN_R")
	)
	(segment
		(start 363.87405 -195.707)
		(end 364.49 -195.707)
		(width 0.13208)
		(layer "F.Cu")
		(net "SSD5_PEX_PWR_EN_R")
	)
	(via
		(at 364.49 -195.707)
		(size 0.508)
		(drill 0.254)
		(layers "F.Cu" "B.Cu")
		(net "SSD5_PEX_PWR_EN_R")
	)
	(via
		(at 348.893638 -211.587334)
		(size 0.4572)
		(drill 0.254)
		(layers "F.Cu" "B.Cu")
		(net "SSD5_PEX_PWR_EN_R")
	)
	(segment
		(start 362.25734 -195.22313)
		(end 362.65866 -195.22313)
		(width 0.15494)
		(layer "In7.Cu")
		(net "SSD5_PEX_PWR_EN_R")
	)
	(segment
		(start 353.670108 -203.605892)
		(end 362.04271 -195.23329)
		(width 0.15494)
		(layer "In7.Cu")
		(net "SSD5_PEX_PWR_EN_R")
	)
	(segment
		(start 353.670108 -204.4446)
		(end 353.670108 -204.345286)
		(width 0.15494)
		(layer "In7.Cu")
		(net "SSD5_PEX_PWR_EN_R")
	)
	(segment
		(start 348.893638 -210.566508)
		(end 352.82505 -206.635096)
		(width 0.15494)
		(layer "In7.Cu")
		(net "SSD5_PEX_PWR_EN_R")
	)
	(segment
		(start 362.04271 -195.23329)
		(end 362.24718 -195.23329)
		(width 0.15494)
		(layer "In7.Cu")
		(net "SSD5_PEX_PWR_EN_R")
	)
	(segment
		(start 352.82505 -205.289658)
		(end 353.670108 -204.4446)
		(width 0.15494)
		(layer "In7.Cu")
		(net "SSD5_PEX_PWR_EN_R")
	)
	(segment
		(start 348.893638 -211.587334)
		(end 348.893638 -210.566508)
		(width 0.15494)
		(layer "In7.Cu")
		(net "SSD5_PEX_PWR_EN_R")
	)
	(segment
		(start 353.670108 -204.345286)
		(end 353.680268 -204.335126)
		(width 0.15494)
		(layer "In7.Cu")
		(net "SSD5_PEX_PWR_EN_R")
	)
	(segment
		(start 352.82505 -206.635096)
		(end 352.82505 -205.289658)
		(width 0.15494)
		(layer "In7.Cu")
		(net "SSD5_PEX_PWR_EN_R")
	)
	(segment
		(start 362.24718 -195.23329)
		(end 362.25734 -195.22313)
		(width 0.15494)
		(layer "In7.Cu")
		(net "SSD5_PEX_PWR_EN_R")
	)
	(segment
		(start 353.670108 -203.923646)
		(end 353.670108 -203.605892)
		(width 0.15494)
		(layer "In7.Cu")
		(net "SSD5_PEX_PWR_EN_R")
	)
	(segment
		(start 353.680268 -203.933806)
		(end 353.670108 -203.923646)
		(width 0.15494)
		(layer "In7.Cu")
		(net "SSD5_PEX_PWR_EN_R")
	)
	(segment
		(start 362.66882 -195.23329)
		(end 364.01629 -195.23329)
		(width 0.15494)
		(layer "In7.Cu")
		(net "SSD5_PEX_PWR_EN_R")
	)
	(segment
		(start 353.680268 -204.335126)
		(end 353.680268 -203.933806)
		(width 0.15494)
		(layer "In7.Cu")
		(net "SSD5_PEX_PWR_EN_R")
	)
	(segment
		(start 364.01629 -195.23329)
		(end 364.49 -195.707)
		(width 0.15494)
		(layer "In7.Cu")
		(net "SSD5_PEX_PWR_EN_R")
	)
	(segment
		(start 362.65866 -195.22313)
		(end 362.66882 -195.23329)
		(width 0.15494)
		(layer "In7.Cu")
		(net "SSD5_PEX_PWR_EN_R")
	)
	(segment
		(start 317.144146 -59.012582)
		(end 317.144146 -58.561224)
		(width 0.13208)
		(layer "F.Cu")
		(net "P3V3_SSD11_OCP")
	)
	(segment
		(start 317.340742 -58.364628)
		(end 317.144146 -58.561224)
		(width 0.13208)
		(layer "F.Cu")
		(net "P3V3_SSD11_OCP")
	)
	(segment
		(start 317.30315 -59.171586)
		(end 317.144146 -59.012582)
		(width 0.13208)
		(layer "F.Cu")
		(net "P3V3_SSD11_OCP")
	)
	(segment
		(start 317.340742 -57.16397)
		(end 317.340742 -58.364628)
		(width 0.13208)
		(layer "F.Cu")
		(net "P3V3_SSD11_OCP")
	)
	(via
		(at 317.144146 -58.561224)
		(size 0.508)
		(drill 0.254)
		(layers "F.Cu" "B.Cu")
		(net "P3V3_SSD11_OCP")
	)
	(segment
		(start 222.877126 -198.704454)
		(end 222.877126 -197.078092)
		(width 0.13208)
		(layer "F.Cu")
		(net "SPI_BIC1_MISO_R5")
	)
	(segment
		(start 223.491298 -199.318626)
		(end 222.877126 -198.704454)
		(width 0.13208)
		(layer "F.Cu")
		(net "SPI_BIC1_MISO_R5")
	)
	(via
		(at 223.491298 -199.318626)
		(size 0.508)
		(drill 0.254)
		(layers "F.Cu" "B.Cu")
		(net "SPI_BIC1_MISO_R5")
	)
	(segment
		(start 223.491298 -199.318626)
		(end 223.533716 -199.276208)
		(width 0.13208)
		(layer "B.Cu")
		(net "SPI_BIC1_MISO_R5")
	)
	(segment
		(start 223.533716 -199.276208)
		(end 223.533716 -198.189342)
		(width 0.13208)
		(layer "B.Cu")
		(net "SPI_BIC1_MISO_R5")
	)
	(segment
		(start 16.981424 -26.479246)
		(end 16.68399 -26.77668)
		(width 0.13462)
		(layer "F.Cu")
		(net "CLK_100M_DB800ZL_SSD0_R_DN")
	)
	(segment
		(start 106.172 -79.097886)
		(end 106.172 -77.634338)
		(width 0.13462)
		(layer "F.Cu")
		(net "CLK_100M_DB800ZL_SSD0_R_DN")
	)
	(segment
		(start 106.172 -77.634338)
		(end 106.470958 -77.33538)
		(width 0.13462)
		(layer "F.Cu")
		(net "CLK_100M_DB800ZL_SSD0_R_DN")
	)
	(segment
		(start 15.754858 -26.58999)
		(end 15.264892 -26.58999)
		(width 0.13462)
		(layer "F.Cu")
		(net "CLK_100M_DB800ZL_SSD0_R_DN")
	)
	(segment
		(start 15.941548 -26.77668)
		(end 15.754858 -26.58999)
		(width 0.13462)
		(layer "F.Cu")
		(net "CLK_100M_DB800ZL_SSD0_R_DN")
	)
	(segment
		(start 16.68399 -26.77668)
		(end 15.941548 -26.77668)
		(width 0.13462)
		(layer "F.Cu")
		(net "CLK_100M_DB800ZL_SSD0_R_DN")
	)
	(segment
		(start 106.496358 -79.422244)
		(end 106.172 -79.097886)
		(width 0.13462)
		(layer "F.Cu")
		(net "CLK_100M_DB800ZL_SSD0_R_DN")
	)
	(via
		(at 106.470958 -77.33538)
		(size 0.508)
		(drill 0.254)
		(layers "F.Cu" "B.Cu")
		(net "CLK_100M_DB800ZL_SSD0_R_DN")
	)
	(via
		(at 16.981424 -26.479246)
		(size 0.508)
		(drill 0.254)
		(layers "F.Cu" "B.Cu")
		(net "CLK_100M_DB800ZL_SSD0_R_DN")
	)
	(segment
		(start 90.54084 -77.72146)
		(end 103.60914 -77.72146)
		(width 0.1651)
		(layer "In13.Cu")
		(net "CLK_100M_DB800ZL_SSD0_R_DN")
	)
	(segment
		(start 18.25244 -26.76906)
		(end 18.50644 -27.02306)
		(width 0.1651)
		(layer "In13.Cu")
		(net "CLK_100M_DB800ZL_SSD0_R_DN")
	)
	(segment
		(start 106.180128 -76.69403)
		(end 106.180128 -77.04455)
		(width 0.1651)
		(layer "In13.Cu")
		(net "CLK_100M_DB800ZL_SSD0_R_DN")
	)
	(segment
		(start 105.759758 -76.27366)
		(end 106.180128 -76.69403)
		(width 0.1651)
		(layer "In13.Cu")
		(net "CLK_100M_DB800ZL_SSD0_R_DN")
	)
	(segment
		(start 88.91524 -76.09586)
		(end 90.54084 -77.72146)
		(width 0.1651)
		(layer "In13.Cu")
		(net "CLK_100M_DB800ZL_SSD0_R_DN")
	)
	(segment
		(start 16.981424 -26.479246)
		(end 17.271238 -26.76906)
		(width 0.1651)
		(layer "In13.Cu")
		(net "CLK_100M_DB800ZL_SSD0_R_DN")
	)
	(segment
		(start 38.22954 -59.136534)
		(end 38.22954 -73.12914)
		(width 0.1651)
		(layer "In13.Cu")
		(net "CLK_100M_DB800ZL_SSD0_R_DN")
	)
	(segment
		(start 17.271238 -26.76906)
		(end 18.25244 -26.76906)
		(width 0.1651)
		(layer "In13.Cu")
		(net "CLK_100M_DB800ZL_SSD0_R_DN")
	)
	(segment
		(start 36.920424 -45.843444)
		(end 38.22954 -59.136534)
		(width 0.1651)
		(layer "In13.Cu")
		(net "CLK_100M_DB800ZL_SSD0_R_DN")
	)
	(segment
		(start 105.05694 -76.27366)
		(end 105.759758 -76.27366)
		(width 0.1651)
		(layer "In13.Cu")
		(net "CLK_100M_DB800ZL_SSD0_R_DN")
	)
	(segment
		(start 103.60914 -77.72146)
		(end 105.05694 -76.27366)
		(width 0.1651)
		(layer "In13.Cu")
		(net "CLK_100M_DB800ZL_SSD0_R_DN")
	)
	(segment
		(start 106.180128 -77.04455)
		(end 106.470958 -77.33538)
		(width 0.1651)
		(layer "In13.Cu")
		(net "CLK_100M_DB800ZL_SSD0_R_DN")
	)
	(segment
		(start 38.22954 -73.12914)
		(end 41.19626 -76.09586)
		(width 0.1651)
		(layer "In13.Cu")
		(net "CLK_100M_DB800ZL_SSD0_R_DN")
	)
	(segment
		(start 26.34234 -32.03956)
		(end 26.34234 -35.26536)
		(width 0.1651)
		(layer "In13.Cu")
		(net "CLK_100M_DB800ZL_SSD0_R_DN")
	)
	(segment
		(start 41.19626 -76.09586)
		(end 88.91524 -76.09586)
		(width 0.1651)
		(layer "In13.Cu")
		(net "CLK_100M_DB800ZL_SSD0_R_DN")
	)
	(segment
		(start 26.34234 -35.26536)
		(end 36.920424 -45.843444)
		(width 0.1651)
		(layer "In13.Cu")
		(net "CLK_100M_DB800ZL_SSD0_R_DN")
	)
	(segment
		(start 18.50644 -27.02306)
		(end 21.32584 -27.02306)
		(width 0.1651)
		(layer "In13.Cu")
		(net "CLK_100M_DB800ZL_SSD0_R_DN")
	)
	(segment
		(start 21.32584 -27.02306)
		(end 26.34234 -32.03956)
		(width 0.1651)
		(layer "In13.Cu")
		(net "CLK_100M_DB800ZL_SSD0_R_DN")
	)
	(segment
		(start 420.299896 -282.599892)
		(end 420.774876 -283.074872)
		(width 0.13208)
		(layer "F.Cu")
		(net "PEX3_MODE_SEL1")
	)
	(segment
		(start 388.898384 -251.158502)
		(end 388.898384 -250.470924)
		(width 0.13208)
		(layer "F.Cu")
		(net "PEX3_MODE_SEL1")
	)
	(segment
		(start 422.933114 -242.49888)
		(end 415.08807 -250.343924)
		(width 0.13208)
		(layer "F.Cu")
		(net "PEX3_MODE_SEL1")
	)
	(segment
		(start 409.364942 -205.652878)
		(end 410.014928 -206.302864)
		(width 0.13208)
		(layer "F.Cu")
		(net "PEX3_MODE_SEL1")
	)
	(segment
		(start 409.245562 -205.518258)
		(end 409.364942 -205.637638)
		(width 0.13208)
		(layer "F.Cu")
		(net "PEX3_MODE_SEL1")
	)
	(segment
		(start 415.08807 -250.343924)
		(end 389.025384 -250.343924)
		(width 0.13208)
		(layer "F.Cu")
		(net "PEX3_MODE_SEL1")
	)
	(segment
		(start 409.364942 -205.637638)
		(end 409.364942 -205.652878)
		(width 0.13208)
		(layer "F.Cu")
		(net "PEX3_MODE_SEL1")
	)
	(segment
		(start 408.503882 -205.518258)
		(end 409.245562 -205.518258)
		(width 0.13208)
		(layer "F.Cu")
		(net "PEX3_MODE_SEL1")
	)
	(segment
		(start 410.014928 -206.302864)
		(end 412.73095 -206.302864)
		(width 0.13208)
		(layer "F.Cu")
		(net "PEX3_MODE_SEL1")
	)
	(segment
		(start 389.025384 -250.343924)
		(end 388.898384 -250.470924)
		(width 0.13208)
		(layer "F.Cu")
		(net "PEX3_MODE_SEL1")
	)
	(segment
		(start 418.2872 -207.069436)
		(end 422.933114 -211.71535)
		(width 0.13208)
		(layer "F.Cu")
		(net "PEX3_MODE_SEL1")
	)
	(segment
		(start 413.497522 -207.069436)
		(end 418.2872 -207.069436)
		(width 0.13208)
		(layer "F.Cu")
		(net "PEX3_MODE_SEL1")
	)
	(segment
		(start 388.898384 -251.956824)
		(end 388.898384 -251.158502)
		(width 0.13208)
		(layer "F.Cu")
		(net "PEX3_MODE_SEL1")
	)
	(segment
		(start 412.73095 -206.302864)
		(end 413.497522 -207.069436)
		(width 0.13208)
		(layer "F.Cu")
		(net "PEX3_MODE_SEL1")
	)
	(segment
		(start 422.933114 -211.71535)
		(end 422.933114 -242.49888)
		(width 0.13208)
		(layer "F.Cu")
		(net "PEX3_MODE_SEL1")
	)
	(via
		(at 388.898384 -251.158502)
		(size 0.508)
		(drill 0.254)
		(layers "F.Cu" "B.Cu")
		(net "PEX3_MODE_SEL1")
	)
	(via
		(at 420.774876 -283.074872)
		(size 0.4064)
		(drill 0.2032)
		(layers "F.Cu" "B.Cu")
		(net "PEX3_MODE_SEL1")
	)
	(segment
		(start 400.948906 -251.158502)
		(end 421.72763 -271.937226)
		(width 0.13208)
		(layer "B.Cu")
		(net "PEX3_MODE_SEL1")
	)
	(segment
		(start 421.72763 -271.937226)
		(end 421.72763 -282.122118)
		(width 0.13208)
		(layer "B.Cu")
		(net "PEX3_MODE_SEL1")
	)
	(segment
		(start 388.898384 -251.158502)
		(end 400.948906 -251.158502)
		(width 0.13208)
		(layer "B.Cu")
		(net "PEX3_MODE_SEL1")
	)
	(segment
		(start 421.72763 -282.122118)
		(end 420.774876 -283.074872)
		(width 0.13208)
		(layer "B.Cu")
		(net "PEX3_MODE_SEL1")
	)
	(segment
		(start 226.667568 -223.104202)
		(end 226.267772 -223.503998)
		(width 0.13208)
		(layer "F.Cu")
		(net "SMB_NIC0_SDA")
	)
	(via
		(at 226.267772 -223.503998)
		(size 0.4572)
		(drill 0.254)
		(layers "F.Cu" "B.Cu")
		(net "SMB_NIC0_SDA")
	)
	(via
		(at 226.412044 -228.473254)
		(size 0.6604)
		(drill 0.3302)
		(layers "F.Cu" "B.Cu")
		(net "SMB_NIC0_SDA")
	)
	(segment
		(start 226.412044 -224.696274)
		(end 226.267772 -224.552002)
		(width 0.13208)
		(layer "B.Cu")
		(net "SMB_NIC0_SDA")
	)
	(segment
		(start 226.267772 -224.552002)
		(end 226.267772 -223.503998)
		(width 0.13208)
		(layer "B.Cu")
		(net "SMB_NIC0_SDA")
	)
	(segment
		(start 226.412044 -230.825548)
		(end 226.386644 -230.825548)
		(width 0.13208)
		(layer "B.Cu")
		(net "SMB_NIC0_SDA")
	)
	(segment
		(start 226.412044 -228.473254)
		(end 226.412044 -230.825548)
		(width 0.13208)
		(layer "B.Cu")
		(net "SMB_NIC0_SDA")
	)
	(segment
		(start 226.412044 -228.473254)
		(end 226.412044 -224.696274)
		(width 0.13208)
		(layer "B.Cu")
		(net "SMB_NIC0_SDA")
	)
	(segment
		(start 145.669 -392.2522)
		(end 145.917666 -392.003534)
		(width 0.13208)
		(layer "F.Cu")
		(net "GPU_FPGA_BOOT_EN")
	)
	(segment
		(start 145.296128 -392.2522)
		(end 145.669 -392.2522)
		(width 0.13208)
		(layer "F.Cu")
		(net "GPU_FPGA_BOOT_EN")
	)
	(segment
		(start 145.273268 -392.22934)
		(end 145.296128 -392.2522)
		(width 0.13208)
		(layer "F.Cu")
		(net "GPU_FPGA_BOOT_EN")
	)
	(segment
		(start 145.161 -391.765028)
		(end 145.416778 -391.50925)
		(width 0.13208)
		(layer "F.Cu")
		(net "GPU_FPGA_BOOT_EN")
	)
	(segment
		(start 145.273268 -392.22934)
		(end 145.161 -392.117072)
		(width 0.13208)
		(layer "F.Cu")
		(net "GPU_FPGA_BOOT_EN")
	)
	(segment
		(start 145.161 -392.117072)
		(end 145.161 -391.765028)
		(width 0.13208)
		(layer "F.Cu")
		(net "GPU_FPGA_BOOT_EN")
	)
	(segment
		(start 146.255486 -391.188448)
		(end 146.255486 -390.798304)
		(width 0.13208)
		(layer "F.Cu")
		(net "GPU_FPGA_BOOT_EN")
	)
	(segment
		(start 145.917666 -392.003534)
		(end 146.255486 -391.188448)
		(width 0.13208)
		(layer "F.Cu")
		(net "GPU_FPGA_BOOT_EN")
	)
	(via
		(at 145.416778 -391.50925)
		(size 0.508)
		(drill 0.254)
		(layers "F.Cu" "B.Cu")
		(net "GPU_FPGA_BOOT_EN")
	)
	(segment
		(start 136.4742 -392.836146)
		(end 136.4742 -402.02612)
		(width 0.15494)
		(layer "In9.Cu")
		(net "GPU_FPGA_BOOT_EN")
	)
	(segment
		(start 136.4742 -402.02612)
		(end 135.710168 -402.790152)
		(width 0.15494)
		(layer "In9.Cu")
		(net "GPU_FPGA_BOOT_EN")
	)
	(segment
		(start 145.416778 -390.689846)
		(end 144.154906 -389.427974)
		(width 0.15494)
		(layer "In9.Cu")
		(net "GPU_FPGA_BOOT_EN")
	)
	(segment
		(start 145.416778 -391.50925)
		(end 145.416778 -390.689846)
		(width 0.15494)
		(layer "In9.Cu")
		(net "GPU_FPGA_BOOT_EN")
	)
	(segment
		(start 139.882372 -389.427974)
		(end 136.4742 -392.836146)
		(width 0.15494)
		(layer "In9.Cu")
		(net "GPU_FPGA_BOOT_EN")
	)
	(segment
		(start 144.154906 -389.427974)
		(end 139.882372 -389.427974)
		(width 0.15494)
		(layer "In9.Cu")
		(net "GPU_FPGA_BOOT_EN")
	)
	(segment
		(start 336.6897 -243.58854)
		(end 337.043014 -243.235226)
		(width 0.13208)
		(layer "F.Cu")
		(net "MB_SWB_PWR_EN")
	)
	(segment
		(start 336.6897 -243.95303)
		(end 336.6897 -243.58854)
		(width 0.13208)
		(layer "F.Cu")
		(net "MB_SWB_PWR_EN")
	)
	(segment
		(start 337.043014 -243.235226)
		(end 337.043014 -242.807998)
		(width 0.13208)
		(layer "F.Cu")
		(net "MB_SWB_PWR_EN")
	)
	(segment
		(start 363.793532 -358.36606)
		(end 363.793532 -359.3084)
		(width 0.13208)
		(layer "F.Cu")
		(net "MB_SWB_PWR_EN")
	)
	(segment
		(start 362.268262 -358.356408)
		(end 363.78388 -358.356408)
		(width 0.13208)
		(layer "F.Cu")
		(net "MB_SWB_PWR_EN")
	)
	(segment
		(start 337.058 -244.83695)
		(end 336.6897 -244.46865)
		(width 0.13208)
		(layer "F.Cu")
		(net "MB_SWB_PWR_EN")
	)
	(segment
		(start 363.78388 -358.356408)
		(end 363.793532 -358.36606)
		(width 0.13208)
		(layer "F.Cu")
		(net "MB_SWB_PWR_EN")
	)
	(segment
		(start 336.6897 -244.46865)
		(end 336.6897 -243.95303)
		(width 0.13208)
		(layer "F.Cu")
		(net "MB_SWB_PWR_EN")
	)
	(via
		(at 336.6897 -243.95303)
		(size 0.508)
		(drill 0.254)
		(layers "F.Cu" "B.Cu")
		(net "MB_SWB_PWR_EN")
	)
	(via
		(at 363.793532 -359.3084)
		(size 0.508)
		(drill 0.254)
		(layers "F.Cu" "B.Cu")
		(net "MB_SWB_PWR_EN")
	)
	(via
		(at 332.936342 -325.732394)
		(size 0.508)
		(drill 0.254)
		(layers "F.Cu" "B.Cu")
		(net "MB_SWB_PWR_EN")
	)
	(via
		(at 335.984342 -264.312146)
		(size 0.508)
		(drill 0.254)
		(layers "F.Cu" "B.Cu")
		(net "MB_SWB_PWR_EN")
	)
	(segment
		(start 332.752954 -325.915782)
		(end 332.752954 -326.64146)
		(width 0.13208)
		(layer "B.Cu")
		(net "MB_SWB_PWR_EN")
	)
	(segment
		(start 335.984342 -264.587228)
		(end 335.984342 -264.312146)
		(width 0.13208)
		(layer "B.Cu")
		(net "MB_SWB_PWR_EN")
	)
	(segment
		(start 328.177398 -323.226176)
		(end 328.177398 -317.607188)
		(width 0.13208)
		(layer "B.Cu")
		(net "MB_SWB_PWR_EN")
	)
	(segment
		(start 330.846938 -265.596624)
		(end 334.974946 -265.596624)
		(width 0.13208)
		(layer "B.Cu")
		(net "MB_SWB_PWR_EN")
	)
	(segment
		(start 325.104506 -314.534296)
		(end 325.104506 -309.015892)
		(width 0.13208)
		(layer "B.Cu")
		(net "MB_SWB_PWR_EN")
	)
	(segment
		(start 334.974946 -265.596624)
		(end 335.984342 -264.587228)
		(width 0.13208)
		(layer "B.Cu")
		(net "MB_SWB_PWR_EN")
	)
	(segment
		(start 328.597006 -267.846556)
		(end 330.846938 -265.596624)
		(width 0.13208)
		(layer "B.Cu")
		(net "MB_SWB_PWR_EN")
	)
	(segment
		(start 332.55458 -326.839834)
		(end 331.791056 -326.839834)
		(width 0.13208)
		(layer "B.Cu")
		(net "MB_SWB_PWR_EN")
	)
	(segment
		(start 331.791056 -326.839834)
		(end 328.177398 -323.226176)
		(width 0.13208)
		(layer "B.Cu")
		(net "MB_SWB_PWR_EN")
	)
	(segment
		(start 328.597006 -273.274028)
		(end 328.597006 -267.846556)
		(width 0.13208)
		(layer "B.Cu")
		(net "MB_SWB_PWR_EN")
	)
	(segment
		(start 326.56907 -275.301964)
		(end 328.597006 -273.274028)
		(width 0.13208)
		(layer "B.Cu")
		(net "MB_SWB_PWR_EN")
	)
	(segment
		(start 332.936342 -325.732394)
		(end 332.752954 -325.915782)
		(width 0.13208)
		(layer "B.Cu")
		(net "MB_SWB_PWR_EN")
	)
	(segment
		(start 326.56907 -307.551328)
		(end 326.56907 -275.301964)
		(width 0.13208)
		(layer "B.Cu")
		(net "MB_SWB_PWR_EN")
	)
	(segment
		(start 328.177398 -317.607188)
		(end 325.104506 -314.534296)
		(width 0.13208)
		(layer "B.Cu")
		(net "MB_SWB_PWR_EN")
	)
	(segment
		(start 332.752954 -326.64146)
		(end 332.55458 -326.839834)
		(width 0.13208)
		(layer "B.Cu")
		(net "MB_SWB_PWR_EN")
	)
	(segment
		(start 325.104506 -309.015892)
		(end 326.56907 -307.551328)
		(width 0.13208)
		(layer "B.Cu")
		(net "MB_SWB_PWR_EN")
	)
	(segment
		(start 338.383372 -330.512166)
		(end 341.444072 -333.572866)
		(width 0.15494)
		(layer "In9.Cu")
		(net "MB_SWB_PWR_EN")
	)
	(segment
		(start 364.0328 -359.547668)
		(end 364.0328 -360.2228)
		(width 0.15494)
		(layer "In9.Cu")
		(net "MB_SWB_PWR_EN")
	)
	(segment
		(start 336.6897 -244.563646)
		(end 336.6897 -243.95303)
		(width 0.15494)
		(layer "In9.Cu")
		(net "MB_SWB_PWR_EN")
	)
	(segment
		(start 335.984342 -264.312146)
		(end 335.984342 -263.284716)
		(width 0.15494)
		(layer "In9.Cu")
		(net "MB_SWB_PWR_EN")
	)
	(segment
		(start 330.378054 -249.778774)
		(end 333.105252 -247.051576)
		(width 0.15494)
		(layer "In9.Cu")
		(net "MB_SWB_PWR_EN")
	)
	(segment
		(start 334.20177 -247.051576)
		(end 336.6897 -244.563646)
		(width 0.15494)
		(layer "In9.Cu")
		(net "MB_SWB_PWR_EN")
	)
	(segment
		(start 335.984342 -263.284716)
		(end 335.463134 -262.763508)
		(width 0.15494)
		(layer "In9.Cu")
		(net "MB_SWB_PWR_EN")
	)
	(segment
		(start 341.444072 -333.572866)
		(end 355.867208 -339.5472)
		(width 0.15494)
		(layer "In9.Cu")
		(net "MB_SWB_PWR_EN")
	)
	(segment
		(start 335.463134 -259.01777)
		(end 330.378054 -253.93269)
		(width 0.15494)
		(layer "In9.Cu")
		(net "MB_SWB_PWR_EN")
	)
	(segment
		(start 371.728746 -362.8644)
		(end 377.689872 -368.825526)
		(width 0.15494)
		(layer "In9.Cu")
		(net "MB_SWB_PWR_EN")
	)
	(segment
		(start 333.6036 -325.732394)
		(end 336.974688 -329.103482)
		(width 0.15494)
		(layer "In9.Cu")
		(net "MB_SWB_PWR_EN")
	)
	(segment
		(start 364.0328 -360.2228)
		(end 366.6744 -362.8644)
		(width 0.15494)
		(layer "In9.Cu")
		(net "MB_SWB_PWR_EN")
	)
	(segment
		(start 337.726782 -330.512166)
		(end 338.383372 -330.512166)
		(width 0.15494)
		(layer "In9.Cu")
		(net "MB_SWB_PWR_EN")
	)
	(segment
		(start 355.867208 -339.5472)
		(end 361.492546 -339.5472)
		(width 0.15494)
		(layer "In9.Cu")
		(net "MB_SWB_PWR_EN")
	)
	(segment
		(start 363.7026 -359.217468)
		(end 363.793532 -359.3084)
		(width 0.15494)
		(layer "In9.Cu")
		(net "MB_SWB_PWR_EN")
	)
	(segment
		(start 363.793532 -359.3084)
		(end 364.0328 -359.547668)
		(width 0.15494)
		(layer "In9.Cu")
		(net "MB_SWB_PWR_EN")
	)
	(segment
		(start 336.974688 -329.760072)
		(end 337.726782 -330.512166)
		(width 0.15494)
		(layer "In9.Cu")
		(net "MB_SWB_PWR_EN")
	)
	(segment
		(start 377.689872 -368.825526)
		(end 377.689872 -368.990118)
		(width 0.15494)
		(layer "In9.Cu")
		(net "MB_SWB_PWR_EN")
	)
	(segment
		(start 333.105252 -247.051576)
		(end 334.20177 -247.051576)
		(width 0.15494)
		(layer "In9.Cu")
		(net "MB_SWB_PWR_EN")
	)
	(segment
		(start 366.6744 -362.8644)
		(end 371.728746 -362.8644)
		(width 0.15494)
		(layer "In9.Cu")
		(net "MB_SWB_PWR_EN")
	)
	(segment
		(start 330.378054 -253.93269)
		(end 330.378054 -249.778774)
		(width 0.15494)
		(layer "In9.Cu")
		(net "MB_SWB_PWR_EN")
	)
	(segment
		(start 336.974688 -329.103482)
		(end 336.974688 -329.760072)
		(width 0.15494)
		(layer "In9.Cu")
		(net "MB_SWB_PWR_EN")
	)
	(segment
		(start 363.7026 -341.757254)
		(end 363.7026 -359.217468)
		(width 0.15494)
		(layer "In9.Cu")
		(net "MB_SWB_PWR_EN")
	)
	(segment
		(start 332.936342 -325.732394)
		(end 333.6036 -325.732394)
		(width 0.15494)
		(layer "In9.Cu")
		(net "MB_SWB_PWR_EN")
	)
	(segment
		(start 361.492546 -339.5472)
		(end 363.7026 -341.757254)
		(width 0.15494)
		(layer "In9.Cu")
		(net "MB_SWB_PWR_EN")
	)
	(segment
		(start 335.463134 -262.763508)
		(end 335.463134 -259.01777)
		(width 0.15494)
		(layer "In9.Cu")
		(net "MB_SWB_PWR_EN")
	)
	(segment
		(start 145.503646 -385.750308)
		(end 143.077692 -385.750308)
		(width 0.13208)
		(layer "F.Cu")
		(net "SMB_MB_BMC_R_SDA")
	)
	(segment
		(start 143.077692 -385.750308)
		(end 141.931644 -386.896356)
		(width 0.13208)
		(layer "F.Cu")
		(net "SMB_MB_BMC_R_SDA")
	)
	(segment
		(start 141.931644 -386.896356)
		(end 141.931644 -389.771636)
		(width 0.13208)
		(layer "F.Cu")
		(net "SMB_MB_BMC_R_SDA")
	)
	(via
		(at 202.005184 -359.91673)
		(size 0.508)
		(drill 0.254)
		(layers "F.Cu" "B.Cu")
		(net "SMB_MB_BMC_R_SDA")
	)
	(via
		(at 230.252524 -329.993752)
		(size 0.508)
		(drill 0.254)
		(layers "F.Cu" "B.Cu")
		(net "SMB_MB_BMC_R_SDA")
	)
	(via
		(at 301.679356 -250.137676)
		(size 0.6604)
		(drill 0.3302)
		(layers "F.Cu" "B.Cu")
		(net "SMB_MB_BMC_R_SDA")
	)
	(via
		(at 303.8602 -253.6444)
		(size 0.508)
		(drill 0.254)
		(layers "F.Cu" "B.Cu")
		(net "SMB_MB_BMC_R_SDA")
	)
	(via
		(at 233.23931 -246.31523)
		(size 0.508)
		(drill 0.254)
		(layers "F.Cu" "B.Cu")
		(net "SMB_MB_BMC_R_SDA")
	)
	(via
		(at 145.503646 -385.750308)
		(size 0.508)
		(drill 0.254)
		(layers "F.Cu" "B.Cu")
		(net "SMB_MB_BMC_R_SDA")
	)
	(segment
		(start 237.688882 -248.599706)
		(end 237.688882 -248.768362)
		(width 0.13208)
		(layer "B.Cu")
		(net "SMB_MB_BMC_R_SDA")
	)
	(segment
		(start 237.65891 -251.275342)
		(end 237.65891 -251.443998)
		(width 0.13208)
		(layer "B.Cu")
		(net "SMB_MB_BMC_R_SDA")
	)
	(segment
		(start 237.694216 -250.521216)
		(end 237.969298 -250.796298)
		(width 0.13208)
		(layer "B.Cu")
		(net "SMB_MB_BMC_R_SDA")
	)
	(segment
		(start 233.23931 -246.31523)
		(end 233.23931 -247.024398)
		(width 0.13208)
		(layer "B.Cu")
		(net "SMB_MB_BMC_R_SDA")
	)
	(segment
		(start 235.976668 -249.5931)
		(end 237.245144 -248.324624)
		(width 0.13208)
		(layer "B.Cu")
		(net "SMB_MB_BMC_R_SDA")
	)
	(segment
		(start 235.089192 -248.705624)
		(end 236.357668 -247.437148)
		(width 0.13208)
		(layer "B.Cu")
		(net "SMB_MB_BMC_R_SDA")
	)
	(segment
		(start 235.53293 -249.149362)
		(end 235.53293 -249.318018)
		(width 0.13208)
		(layer "B.Cu")
		(net "SMB_MB_BMC_R_SDA")
	)
	(segment
		(start 302.442626 -247.215406)
		(end 302.442626 -248.065544)
		(width 0.13208)
		(layer "B.Cu")
		(net "SMB_MB_BMC_R_SDA")
	)
	(segment
		(start 236.420406 -250.036838)
		(end 236.420406 -250.205494)
		(width 0.13208)
		(layer "B.Cu")
		(net "SMB_MB_BMC_R_SDA")
	)
	(segment
		(start 236.801406 -247.880886)
		(end 235.53293 -249.149362)
		(width 0.13208)
		(layer "B.Cu")
		(net "SMB_MB_BMC_R_SDA")
	)
	(segment
		(start 304.474626 -246.453406)
		(end 303.204626 -246.453406)
		(width 0.13208)
		(layer "B.Cu")
		(net "SMB_MB_BMC_R_SDA")
	)
	(segment
		(start 236.526324 -247.437148)
		(end 236.801406 -247.71223)
		(width 0.13208)
		(layer "B.Cu")
		(net "SMB_MB_BMC_R_SDA")
	)
	(segment
		(start 235.808012 -249.5931)
		(end 235.976668 -249.5931)
		(width 0.13208)
		(layer "B.Cu")
		(net "SMB_MB_BMC_R_SDA")
	)
	(segment
		(start 302.442626 -248.065544)
		(end 302.46447 -248.087388)
		(width 0.13208)
		(layer "B.Cu")
		(net "SMB_MB_BMC_R_SDA")
	)
	(segment
		(start 233.001058 -329.487022)
		(end 230.759254 -329.487022)
		(width 0.13208)
		(layer "B.Cu")
		(net "SMB_MB_BMC_R_SDA")
	)
	(segment
		(start 237.245144 -248.324624)
		(end 237.4138 -248.324624)
		(width 0.13208)
		(layer "B.Cu")
		(net "SMB_MB_BMC_R_SDA")
	)
	(segment
		(start 234.645454 -248.430542)
		(end 234.920536 -248.705624)
		(width 0.13208)
		(layer "B.Cu")
		(net "SMB_MB_BMC_R_SDA")
	)
	(segment
		(start 235.53293 -249.318018)
		(end 235.808012 -249.5931)
		(width 0.13208)
		(layer "B.Cu")
		(net "SMB_MB_BMC_R_SDA")
	)
	(segment
		(start 245.15191 -326.976994)
		(end 235.511086 -326.976994)
		(width 0.13208)
		(layer "B.Cu")
		(net "SMB_MB_BMC_R_SDA")
	)
	(segment
		(start 303.204626 -246.453406)
		(end 302.442626 -247.215406)
		(width 0.13208)
		(layer "B.Cu")
		(net "SMB_MB_BMC_R_SDA")
	)
	(segment
		(start 234.920536 -248.705624)
		(end 235.089192 -248.705624)
		(width 0.13208)
		(layer "B.Cu")
		(net "SMB_MB_BMC_R_SDA")
	)
	(segment
		(start 302.061626 -252.187456)
		(end 302.061626 -252.461776)
		(width 0.13208)
		(layer "B.Cu")
		(net "SMB_MB_BMC_R_SDA")
	)
	(segment
		(start 301.299626 -250.517406)
		(end 301.299626 -252.041406)
		(width 0.13208)
		(layer "B.Cu")
		(net "SMB_MB_BMC_R_SDA")
	)
	(segment
		(start 247.688354 -256.44475)
		(end 247.688354 -264.90549)
		(width 0.13208)
		(layer "B.Cu")
		(net "SMB_MB_BMC_R_SDA")
	)
	(segment
		(start 237.265972 -250.780804)
		(end 237.52556 -250.521216)
		(width 0.13208)
		(layer "B.Cu")
		(net "SMB_MB_BMC_R_SDA")
	)
	(segment
		(start 301.445676 -252.187456)
		(end 302.061626 -252.187456)
		(width 0.13208)
		(layer "B.Cu")
		(net "SMB_MB_BMC_R_SDA")
	)
	(segment
		(start 230.759254 -329.487022)
		(end 230.252524 -329.993752)
		(width 0.13208)
		(layer "B.Cu")
		(net "SMB_MB_BMC_R_SDA")
	)
	(segment
		(start 240.151666 -253.936754)
		(end 245.180358 -253.936754)
		(width 0.13208)
		(layer "B.Cu")
		(net "SMB_MB_BMC_R_SDA")
	)
	(segment
		(start 247.688354 -264.90549)
		(end 256.231136 -285.532322)
		(width 0.13208)
		(layer "B.Cu")
		(net "SMB_MB_BMC_R_SDA")
	)
	(segment
		(start 234.03306 -247.818148)
		(end 234.201716 -247.818148)
		(width 0.13208)
		(layer "B.Cu")
		(net "SMB_MB_BMC_R_SDA")
	)
	(segment
		(start 245.180358 -253.936754)
		(end 247.688354 -256.44475)
		(width 0.13208)
		(layer "B.Cu")
		(net "SMB_MB_BMC_R_SDA")
	)
	(segment
		(start 234.645454 -248.261886)
		(end 234.645454 -248.430542)
		(width 0.13208)
		(layer "B.Cu")
		(net "SMB_MB_BMC_R_SDA")
	)
	(segment
		(start 303.762156 -253.742444)
		(end 303.8602 -253.6444)
		(width 0.13208)
		(layer "B.Cu")
		(net "SMB_MB_BMC_R_SDA")
	)
	(segment
		(start 235.91393 -246.824754)
		(end 235.91393 -246.99341)
		(width 0.13208)
		(layer "B.Cu")
		(net "SMB_MB_BMC_R_SDA")
	)
	(segment
		(start 256.231136 -305.532536)
		(end 248.902474 -323.22643)
		(width 0.13208)
		(layer "B.Cu")
		(net "SMB_MB_BMC_R_SDA")
	)
	(segment
		(start 302.46447 -248.087388)
		(end 302.46447 -249.352562)
		(width 0.13208)
		(layer "B.Cu")
		(net "SMB_MB_BMC_R_SDA")
	)
	(segment
		(start 235.638848 -246.549672)
		(end 235.91393 -246.824754)
		(width 0.13208)
		(layer "B.Cu")
		(net "SMB_MB_BMC_R_SDA")
	)
	(segment
		(start 302.061626 -252.461776)
		(end 303.342294 -253.742444)
		(width 0.13208)
		(layer "B.Cu")
		(net "SMB_MB_BMC_R_SDA")
	)
	(segment
		(start 256.231136 -285.532322)
		(end 256.231136 -305.532536)
		(width 0.13208)
		(layer "B.Cu")
		(net "SMB_MB_BMC_R_SDA")
	)
	(segment
		(start 237.65891 -251.443998)
		(end 240.151666 -253.936754)
		(width 0.13208)
		(layer "B.Cu")
		(net "SMB_MB_BMC_R_SDA")
	)
	(segment
		(start 236.801406 -247.71223)
		(end 236.801406 -247.880886)
		(width 0.13208)
		(layer "B.Cu")
		(net "SMB_MB_BMC_R_SDA")
	)
	(segment
		(start 237.969298 -250.796298)
		(end 237.969298 -250.964954)
		(width 0.13208)
		(layer "B.Cu")
		(net "SMB_MB_BMC_R_SDA")
	)
	(segment
		(start 248.902474 -323.22643)
		(end 245.15191 -326.976994)
		(width 0.13208)
		(layer "B.Cu")
		(net "SMB_MB_BMC_R_SDA")
	)
	(segment
		(start 236.420406 -250.205494)
		(end 236.995716 -250.780804)
		(width 0.13208)
		(layer "B.Cu")
		(net "SMB_MB_BMC_R_SDA")
	)
	(segment
		(start 237.969298 -250.964954)
		(end 237.65891 -251.275342)
		(width 0.13208)
		(layer "B.Cu")
		(net "SMB_MB_BMC_R_SDA")
	)
	(segment
		(start 235.91393 -246.99341)
		(end 234.645454 -248.261886)
		(width 0.13208)
		(layer "B.Cu")
		(net "SMB_MB_BMC_R_SDA")
	)
	(segment
		(start 234.201716 -247.818148)
		(end 235.470192 -246.549672)
		(width 0.13208)
		(layer "B.Cu")
		(net "SMB_MB_BMC_R_SDA")
	)
	(segment
		(start 301.679356 -250.137676)
		(end 301.299626 -250.517406)
		(width 0.13208)
		(layer "B.Cu")
		(net "SMB_MB_BMC_R_SDA")
	)
	(segment
		(start 301.299626 -252.041406)
		(end 301.445676 -252.187456)
		(width 0.13208)
		(layer "B.Cu")
		(net "SMB_MB_BMC_R_SDA")
	)
	(segment
		(start 235.511086 -326.976994)
		(end 233.001058 -329.487022)
		(width 0.13208)
		(layer "B.Cu")
		(net "SMB_MB_BMC_R_SDA")
	)
	(segment
		(start 302.46447 -249.352562)
		(end 301.679356 -250.137676)
		(width 0.13208)
		(layer "B.Cu")
		(net "SMB_MB_BMC_R_SDA")
	)
	(segment
		(start 236.357668 -247.437148)
		(end 236.526324 -247.437148)
		(width 0.13208)
		(layer "B.Cu")
		(net "SMB_MB_BMC_R_SDA")
	)
	(segment
		(start 237.4138 -248.324624)
		(end 237.688882 -248.599706)
		(width 0.13208)
		(layer "B.Cu")
		(net "SMB_MB_BMC_R_SDA")
	)
	(segment
		(start 237.52556 -250.521216)
		(end 237.694216 -250.521216)
		(width 0.13208)
		(layer "B.Cu")
		(net "SMB_MB_BMC_R_SDA")
	)
	(segment
		(start 237.688882 -248.768362)
		(end 236.420406 -250.036838)
		(width 0.13208)
		(layer "B.Cu")
		(net "SMB_MB_BMC_R_SDA")
	)
	(segment
		(start 303.342294 -253.742444)
		(end 303.762156 -253.742444)
		(width 0.13208)
		(layer "B.Cu")
		(net "SMB_MB_BMC_R_SDA")
	)
	(segment
		(start 235.470192 -246.549672)
		(end 235.638848 -246.549672)
		(width 0.13208)
		(layer "B.Cu")
		(net "SMB_MB_BMC_R_SDA")
	)
	(segment
		(start 305.490626 -246.599456)
		(end 304.620676 -246.599456)
		(width 0.13208)
		(layer "B.Cu")
		(net "SMB_MB_BMC_R_SDA")
	)
	(segment
		(start 236.995716 -250.780804)
		(end 237.265972 -250.780804)
		(width 0.13208)
		(layer "B.Cu")
		(net "SMB_MB_BMC_R_SDA")
	)
	(segment
		(start 304.620676 -246.599456)
		(end 304.474626 -246.453406)
		(width 0.13208)
		(layer "B.Cu")
		(net "SMB_MB_BMC_R_SDA")
	)
	(segment
		(start 233.23931 -247.024398)
		(end 234.03306 -247.818148)
		(width 0.13208)
		(layer "B.Cu")
		(net "SMB_MB_BMC_R_SDA")
	)
	(segment
		(start 202.8952 -357.246682)
		(end 205.065122 -355.07676)
		(width 0.15494)
		(layer "In5.Cu")
		(net "SMB_MB_BMC_R_SDA")
	)
	(segment
		(start 219.208604 -355.07676)
		(end 227.797868 -346.487496)
		(width 0.15494)
		(layer "In5.Cu")
		(net "SMB_MB_BMC_R_SDA")
	)
	(segment
		(start 227.797868 -346.487496)
		(end 227.797868 -332.622398)
		(width 0.15494)
		(layer "In5.Cu")
		(net "SMB_MB_BMC_R_SDA")
	)
	(segment
		(start 202.005184 -359.91673)
		(end 202.8952 -359.026714)
		(width 0.15494)
		(layer "In5.Cu")
		(net "SMB_MB_BMC_R_SDA")
	)
	(segment
		(start 230.252524 -330.167742)
		(end 230.252524 -329.993752)
		(width 0.15494)
		(layer "In5.Cu")
		(net "SMB_MB_BMC_R_SDA")
	)
	(segment
		(start 205.065122 -355.07676)
		(end 219.208604 -355.07676)
		(width 0.15494)
		(layer "In5.Cu")
		(net "SMB_MB_BMC_R_SDA")
	)
	(segment
		(start 227.797868 -332.622398)
		(end 230.252524 -330.167742)
		(width 0.15494)
		(layer "In5.Cu")
		(net "SMB_MB_BMC_R_SDA")
	)
	(segment
		(start 202.8952 -359.026714)
		(end 202.8952 -357.246682)
		(width 0.15494)
		(layer "In5.Cu")
		(net "SMB_MB_BMC_R_SDA")
	)
	(segment
		(start 303.8602 -253.6444)
		(end 303.762156 -253.742444)
		(width 0.15494)
		(layer "In13.Cu")
		(net "SMB_MB_BMC_R_SDA")
	)
	(segment
		(start 303.762156 -253.742444)
		(end 301.875444 -253.742444)
		(width 0.15494)
		(layer "In13.Cu")
		(net "SMB_MB_BMC_R_SDA")
	)
	(segment
		(start 272.420334 -248.455688)
		(end 247.415812 -248.455688)
		(width 0.15494)
		(layer "In13.Cu")
		(net "SMB_MB_BMC_R_SDA")
	)
	(segment
		(start 247.415812 -248.455688)
		(end 246.404384 -247.44426)
		(width 0.15494)
		(layer "In13.Cu")
		(net "SMB_MB_BMC_R_SDA")
	)
	(segment
		(start 301.875444 -253.742444)
		(end 298.6786 -250.5456)
		(width 0.15494)
		(layer "In13.Cu")
		(net "SMB_MB_BMC_R_SDA")
	)
	(segment
		(start 238.4933 -248.76506)
		(end 235.68914 -248.76506)
		(width 0.15494)
		(layer "In13.Cu")
		(net "SMB_MB_BMC_R_SDA")
	)
	(segment
		(start 298.6786 -250.5456)
		(end 274.510246 -250.5456)
		(width 0.15494)
		(layer "In13.Cu")
		(net "SMB_MB_BMC_R_SDA")
	)
	(segment
		(start 274.510246 -250.5456)
		(end 272.420334 -248.455688)
		(width 0.15494)
		(layer "In13.Cu")
		(net "SMB_MB_BMC_R_SDA")
	)
	(segment
		(start 235.68914 -248.76506)
		(end 233.23931 -246.31523)
		(width 0.15494)
		(layer "In13.Cu")
		(net "SMB_MB_BMC_R_SDA")
	)
	(segment
		(start 239.8141 -247.44426)
		(end 238.4933 -248.76506)
		(width 0.15494)
		(layer "In13.Cu")
		(net "SMB_MB_BMC_R_SDA")
	)
	(segment
		(start 246.404384 -247.44426)
		(end 239.8141 -247.44426)
		(width 0.15494)
		(layer "In13.Cu")
		(net "SMB_MB_BMC_R_SDA")
	)
	(segment
		(start 156.516578 -364.84687)
		(end 145.01241 -376.351038)
		(width 0.15494)
		(layer "In15.Cu")
		(net "SMB_MB_BMC_R_SDA")
	)
	(segment
		(start 145.01241 -380.759208)
		(end 144.87779 -380.893828)
		(width 0.15494)
		(layer "In15.Cu")
		(net "SMB_MB_BMC_R_SDA")
	)
	(segment
		(start 202.005184 -359.91673)
		(end 200.0885 -359.91673)
		(width 0.15494)
		(layer "In15.Cu")
		(net "SMB_MB_BMC_R_SDA")
	)
	(segment
		(start 145.01241 -382.956308)
		(end 145.01241 -383.329688)
		(width 0.15494)
		(layer "In15.Cu")
		(net "SMB_MB_BMC_R_SDA")
	)
	(segment
		(start 144.212818 -378.457968)
		(end 144.212818 -378.831348)
		(width 0.15494)
		(layer "In15.Cu")
		(net "SMB_MB_BMC_R_SDA")
	)
	(segment
		(start 144.347438 -380.251208)
		(end 144.87779 -380.251208)
		(width 0.15494)
		(layer "In15.Cu")
		(net "SMB_MB_BMC_R_SDA")
	)
	(segment
		(start 144.347438 -380.893828)
		(end 144.212818 -381.028448)
		(width 0.15494)
		(layer "In15.Cu")
		(net "SMB_MB_BMC_R_SDA")
	)
	(segment
		(start 144.212818 -382.687068)
		(end 144.347438 -382.821688)
		(width 0.15494)
		(layer "In15.Cu")
		(net "SMB_MB_BMC_R_SDA")
	)
	(segment
		(start 144.212818 -379.743208)
		(end 144.212818 -380.116588)
		(width 0.15494)
		(layer "In15.Cu")
		(net "SMB_MB_BMC_R_SDA")
	)
	(segment
		(start 145.01241 -385.259072)
		(end 145.503646 -385.750308)
		(width 0.15494)
		(layer "In15.Cu")
		(net "SMB_MB_BMC_R_SDA")
	)
	(segment
		(start 144.87779 -382.821688)
		(end 145.01241 -382.956308)
		(width 0.15494)
		(layer "In15.Cu")
		(net "SMB_MB_BMC_R_SDA")
	)
	(segment
		(start 144.87779 -383.464308)
		(end 144.347438 -383.464308)
		(width 0.15494)
		(layer "In15.Cu")
		(net "SMB_MB_BMC_R_SDA")
	)
	(segment
		(start 144.347438 -379.608588)
		(end 144.212818 -379.743208)
		(width 0.15494)
		(layer "In15.Cu")
		(net "SMB_MB_BMC_R_SDA")
	)
	(segment
		(start 144.347438 -382.179068)
		(end 144.212818 -382.313688)
		(width 0.15494)
		(layer "In15.Cu")
		(net "SMB_MB_BMC_R_SDA")
	)
	(segment
		(start 144.212818 -378.831348)
		(end 144.347438 -378.965968)
		(width 0.15494)
		(layer "In15.Cu")
		(net "SMB_MB_BMC_R_SDA")
	)
	(segment
		(start 144.212818 -380.116588)
		(end 144.347438 -380.251208)
		(width 0.15494)
		(layer "In15.Cu")
		(net "SMB_MB_BMC_R_SDA")
	)
	(segment
		(start 144.87779 -380.251208)
		(end 145.01241 -380.385828)
		(width 0.15494)
		(layer "In15.Cu")
		(net "SMB_MB_BMC_R_SDA")
	)
	(segment
		(start 144.87779 -378.965968)
		(end 145.01241 -379.100588)
		(width 0.15494)
		(layer "In15.Cu")
		(net "SMB_MB_BMC_R_SDA")
	)
	(segment
		(start 144.347438 -381.536448)
		(end 144.87779 -381.536448)
		(width 0.15494)
		(layer "In15.Cu")
		(net "SMB_MB_BMC_R_SDA")
	)
	(segment
		(start 200.0885 -359.91673)
		(end 199.2757 -360.72953)
		(width 0.15494)
		(layer "In15.Cu")
		(net "SMB_MB_BMC_R_SDA")
	)
	(segment
		(start 145.01241 -383.329688)
		(end 144.87779 -383.464308)
		(width 0.15494)
		(layer "In15.Cu")
		(net "SMB_MB_BMC_R_SDA")
	)
	(segment
		(start 145.01241 -382.044448)
		(end 144.87779 -382.179068)
		(width 0.15494)
		(layer "In15.Cu")
		(net "SMB_MB_BMC_R_SDA")
	)
	(segment
		(start 144.347438 -382.821688)
		(end 144.87779 -382.821688)
		(width 0.15494)
		(layer "In15.Cu")
		(net "SMB_MB_BMC_R_SDA")
	)
	(segment
		(start 186.20486 -364.84687)
		(end 156.516578 -364.84687)
		(width 0.15494)
		(layer "In15.Cu")
		(net "SMB_MB_BMC_R_SDA")
	)
	(segment
		(start 144.347438 -384.106928)
		(end 144.87779 -384.106928)
		(width 0.15494)
		(layer "In15.Cu")
		(net "SMB_MB_BMC_R_SDA")
	)
	(segment
		(start 144.212818 -381.401828)
		(end 144.347438 -381.536448)
		(width 0.15494)
		(layer "In15.Cu")
		(net "SMB_MB_BMC_R_SDA")
	)
	(segment
		(start 144.87779 -381.536448)
		(end 145.01241 -381.671068)
		(width 0.15494)
		(layer "In15.Cu")
		(net "SMB_MB_BMC_R_SDA")
	)
	(segment
		(start 144.87779 -384.106928)
		(end 145.01241 -384.241548)
		(width 0.15494)
		(layer "In15.Cu")
		(net "SMB_MB_BMC_R_SDA")
	)
	(segment
		(start 145.01241 -376.351038)
		(end 145.01241 -378.188728)
		(width 0.15494)
		(layer "In15.Cu")
		(net "SMB_MB_BMC_R_SDA")
	)
	(segment
		(start 144.87779 -378.323348)
		(end 144.347438 -378.323348)
		(width 0.15494)
		(layer "In15.Cu")
		(net "SMB_MB_BMC_R_SDA")
	)
	(segment
		(start 144.347438 -383.464308)
		(end 144.212818 -383.598928)
		(width 0.15494)
		(layer "In15.Cu")
		(net "SMB_MB_BMC_R_SDA")
	)
	(segment
		(start 144.87779 -382.179068)
		(end 144.347438 -382.179068)
		(width 0.15494)
		(layer "In15.Cu")
		(net "SMB_MB_BMC_R_SDA")
	)
	(segment
		(start 144.212818 -383.598928)
		(end 144.212818 -383.972308)
		(width 0.15494)
		(layer "In15.Cu")
		(net "SMB_MB_BMC_R_SDA")
	)
	(segment
		(start 145.01241 -384.241548)
		(end 145.01241 -385.259072)
		(width 0.15494)
		(layer "In15.Cu")
		(net "SMB_MB_BMC_R_SDA")
	)
	(segment
		(start 144.347438 -378.323348)
		(end 144.212818 -378.457968)
		(width 0.15494)
		(layer "In15.Cu")
		(net "SMB_MB_BMC_R_SDA")
	)
	(segment
		(start 144.212818 -383.972308)
		(end 144.347438 -384.106928)
		(width 0.15494)
		(layer "In15.Cu")
		(net "SMB_MB_BMC_R_SDA")
	)
	(segment
		(start 144.212818 -381.028448)
		(end 144.212818 -381.401828)
		(width 0.15494)
		(layer "In15.Cu")
		(net "SMB_MB_BMC_R_SDA")
	)
	(segment
		(start 144.347438 -378.965968)
		(end 144.87779 -378.965968)
		(width 0.15494)
		(layer "In15.Cu")
		(net "SMB_MB_BMC_R_SDA")
	)
	(segment
		(start 145.01241 -380.385828)
		(end 145.01241 -380.759208)
		(width 0.15494)
		(layer "In15.Cu")
		(net "SMB_MB_BMC_R_SDA")
	)
	(segment
		(start 144.87779 -380.893828)
		(end 144.347438 -380.893828)
		(width 0.15494)
		(layer "In15.Cu")
		(net "SMB_MB_BMC_R_SDA")
	)
	(segment
		(start 144.87779 -379.608588)
		(end 144.347438 -379.608588)
		(width 0.15494)
		(layer "In15.Cu")
		(net "SMB_MB_BMC_R_SDA")
	)
	(segment
		(start 145.01241 -378.188728)
		(end 144.87779 -378.323348)
		(width 0.15494)
		(layer "In15.Cu")
		(net "SMB_MB_BMC_R_SDA")
	)
	(segment
		(start 145.01241 -381.671068)
		(end 145.01241 -382.044448)
		(width 0.15494)
		(layer "In15.Cu")
		(net "SMB_MB_BMC_R_SDA")
	)
	(segment
		(start 199.2757 -360.72953)
		(end 190.3222 -360.72953)
		(width 0.15494)
		(layer "In15.Cu")
		(net "SMB_MB_BMC_R_SDA")
	)
	(segment
		(start 145.01241 -379.100588)
		(end 145.01241 -379.473968)
		(width 0.15494)
		(layer "In15.Cu")
		(net "SMB_MB_BMC_R_SDA")
	)
	(segment
		(start 190.3222 -360.72953)
		(end 186.20486 -364.84687)
		(width 0.15494)
		(layer "In15.Cu")
		(net "SMB_MB_BMC_R_SDA")
	)
	(segment
		(start 144.212818 -382.313688)
		(end 144.212818 -382.687068)
		(width 0.15494)
		(layer "In15.Cu")
		(net "SMB_MB_BMC_R_SDA")
	)
	(segment
		(start 145.01241 -379.473968)
		(end 144.87779 -379.608588)
		(width 0.15494)
		(layer "In15.Cu")
		(net "SMB_MB_BMC_R_SDA")
	)
	(segment
		(start 349.690182 -228.84765)
		(end 349.690182 -227.583238)
		(width 0.13208)
		(layer "F.Cu")
		(net "PRSNT_SSD7_R_N")
	)
	(segment
		(start 201.209148 -27.04973)
		(end 202.203812 -27.04973)
		(width 0.13208)
		(layer "F.Cu")
		(net "PRSNT_SSD7_R_N")
	)
	(segment
		(start 201.209148 -26.03373)
		(end 201.209148 -27.04973)
		(width 0.13208)
		(layer "F.Cu")
		(net "PRSNT_SSD7_R_N")
	)
	(segment
		(start 233.067606 -223.904048)
		(end 233.467402 -224.303844)
		(width 0.13208)
		(layer "F.Cu")
		(net "PRSNT_SSD7_R_N")
	)
	(segment
		(start 202.203812 -27.04973)
		(end 202.220576 -27.066494)
		(width 0.13208)
		(layer "F.Cu")
		(net "PRSNT_SSD7_R_N")
	)
	(segment
		(start 349.683832 -228.854)
		(end 349.690182 -228.84765)
		(width 0.13208)
		(layer "F.Cu")
		(net "PRSNT_SSD7_R_N")
	)
	(segment
		(start 349.690182 -227.583238)
		(end 349.293942 -227.186998)
		(width 0.13208)
		(layer "F.Cu")
		(net "PRSNT_SSD7_R_N")
	)
	(segment
		(start 200.675748 -36.515548)
		(end 201.496168 -36.515548)
		(width 0.13208)
		(layer "F.Cu")
		(net "PRSNT_SSD7_R_N")
	)
	(segment
		(start 202.220576 -27.066494)
		(end 203.04252 -27.066494)
		(width 0.13208)
		(layer "F.Cu")
		(net "PRSNT_SSD7_R_N")
	)
	(via
		(at 349.683832 -228.854)
		(size 0.508)
		(drill 0.254)
		(layers "F.Cu" "B.Cu")
		(net "PRSNT_SSD7_R_N")
	)
	(via
		(at 209.796634 -87.655654)
		(size 0.508)
		(drill 0.254)
		(layers "F.Cu" "B.Cu")
		(net "PRSNT_SSD7_R_N")
	)
	(via
		(at 232.205022 -240.110772)
		(size 0.508)
		(drill 0.254)
		(layers "F.Cu" "B.Cu")
		(net "PRSNT_SSD7_R_N")
	)
	(via
		(at 203.04252 -27.066494)
		(size 0.508)
		(drill 0.254)
		(layers "F.Cu" "B.Cu")
		(net "PRSNT_SSD7_R_N")
	)
	(via
		(at 233.467402 -224.303844)
		(size 0.4572)
		(drill 0.254)
		(layers "F.Cu" "B.Cu")
		(net "PRSNT_SSD7_R_N")
	)
	(via
		(at 201.496168 -36.515548)
		(size 0.508)
		(drill 0.254)
		(layers "F.Cu" "B.Cu")
		(net "PRSNT_SSD7_R_N")
	)
	(segment
		(start 199.863456 -34.882836)
		(end 199.863456 -29.676344)
		(width 0.15494)
		(layer "In5.Cu")
		(net "PRSNT_SSD7_R_N")
	)
	(segment
		(start 202.473306 -27.066494)
		(end 203.04252 -27.066494)
		(width 0.15494)
		(layer "In5.Cu")
		(net "PRSNT_SSD7_R_N")
	)
	(segment
		(start 232.8418 -227.132896)
		(end 233.467402 -226.507294)
		(width 0.15494)
		(layer "In5.Cu")
		(net "PRSNT_SSD7_R_N")
	)
	(segment
		(start 233.467402 -226.507294)
		(end 233.467402 -224.303844)
		(width 0.15494)
		(layer "In5.Cu")
		(net "PRSNT_SSD7_R_N")
	)
	(segment
		(start 199.863456 -29.676344)
		(end 202.473306 -27.066494)
		(width 0.15494)
		(layer "In5.Cu")
		(net "PRSNT_SSD7_R_N")
	)
	(segment
		(start 206.536544 -77.16012)
		(end 209.796634 -80.42021)
		(width 0.15494)
		(layer "In5.Cu")
		(net "PRSNT_SSD7_R_N")
	)
	(segment
		(start 232.8418 -231.212136)
		(end 232.8418 -227.132896)
		(width 0.15494)
		(layer "In5.Cu")
		(net "PRSNT_SSD7_R_N")
	)
	(segment
		(start 232.205022 -240.110772)
		(end 232.205022 -237.99419)
		(width 0.15494)
		(layer "In5.Cu")
		(net "PRSNT_SSD7_R_N")
	)
	(segment
		(start 209.796634 -80.42021)
		(end 209.796634 -87.655654)
		(width 0.15494)
		(layer "In5.Cu")
		(net "PRSNT_SSD7_R_N")
	)
	(segment
		(start 233.307382 -231.677718)
		(end 232.8418 -231.212136)
		(width 0.15494)
		(layer "In5.Cu")
		(net "PRSNT_SSD7_R_N")
	)
	(segment
		(start 233.307382 -236.89183)
		(end 233.307382 -231.677718)
		(width 0.15494)
		(layer "In5.Cu")
		(net "PRSNT_SSD7_R_N")
	)
	(segment
		(start 206.536544 -44.72686)
		(end 206.536544 -77.16012)
		(width 0.15494)
		(layer "In5.Cu")
		(net "PRSNT_SSD7_R_N")
	)
	(segment
		(start 201.506074 -36.525454)
		(end 201.506074 -39.69639)
		(width 0.15494)
		(layer "In5.Cu")
		(net "PRSNT_SSD7_R_N")
	)
	(segment
		(start 232.205022 -237.99419)
		(end 233.307382 -236.89183)
		(width 0.15494)
		(layer "In5.Cu")
		(net "PRSNT_SSD7_R_N")
	)
	(segment
		(start 201.496168 -36.515548)
		(end 199.863456 -34.882836)
		(width 0.15494)
		(layer "In5.Cu")
		(net "PRSNT_SSD7_R_N")
	)
	(segment
		(start 201.496168 -36.515548)
		(end 201.506074 -36.525454)
		(width 0.15494)
		(layer "In5.Cu")
		(net "PRSNT_SSD7_R_N")
	)
	(segment
		(start 201.506074 -39.69639)
		(end 206.536544 -44.72686)
		(width 0.15494)
		(layer "In5.Cu")
		(net "PRSNT_SSD7_R_N")
	)
	(segment
		(start 204.679804 -168.599358)
		(end 204.679804 -188.005466)
		(width 0.15494)
		(layer "In7.Cu")
		(net "PRSNT_SSD7_R_N")
	)
	(segment
		(start 208.8388 -87.655654)
		(end 203.074524 -93.41993)
		(width 0.15494)
		(layer "In7.Cu")
		(net "PRSNT_SSD7_R_N")
	)
	(segment
		(start 203.2254 -115.6462)
		(end 203.6064 -116.0272)
		(width 0.15494)
		(layer "In7.Cu")
		(net "PRSNT_SSD7_R_N")
	)
	(segment
		(start 203.2254 -113.1316)
		(end 203.2254 -115.6462)
		(width 0.15494)
		(layer "In7.Cu")
		(net "PRSNT_SSD7_R_N")
	)
	(segment
		(start 208.982056 -130.927856)
		(end 208.982056 -164.297106)
		(width 0.15494)
		(layer "In7.Cu")
		(net "PRSNT_SSD7_R_N")
	)
	(segment
		(start 200.508616 -222.682816)
		(end 207.8228 -229.997)
		(width 0.15494)
		(layer "In7.Cu")
		(net "PRSNT_SSD7_R_N")
	)
	(segment
		(start 203.6064 -116.0272)
		(end 203.6064 -125.5522)
		(width 0.15494)
		(layer "In7.Cu")
		(net "PRSNT_SSD7_R_N")
	)
	(segment
		(start 207.8228 -229.997)
		(end 224.790254 -229.997)
		(width 0.15494)
		(layer "In7.Cu")
		(net "PRSNT_SSD7_R_N")
	)
	(segment
		(start 202.86472 -112.77092)
		(end 203.2254 -113.1316)
		(width 0.15494)
		(layer "In7.Cu")
		(net "PRSNT_SSD7_R_N")
	)
	(segment
		(start 224.790254 -229.997)
		(end 225.374454 -230.5812)
		(width 0.15494)
		(layer "In7.Cu")
		(net "PRSNT_SSD7_R_N")
	)
	(segment
		(start 227.190046 -230.5812)
		(end 233.467402 -224.303844)
		(width 0.15494)
		(layer "In7.Cu")
		(net "PRSNT_SSD7_R_N")
	)
	(segment
		(start 202.86472 -103.65232)
		(end 202.86472 -112.77092)
		(width 0.15494)
		(layer "In7.Cu")
		(net "PRSNT_SSD7_R_N")
	)
	(segment
		(start 203.6064 -125.5522)
		(end 208.982056 -130.927856)
		(width 0.15494)
		(layer "In7.Cu")
		(net "PRSNT_SSD7_R_N")
	)
	(segment
		(start 204.679804 -188.005466)
		(end 200.508616 -192.176654)
		(width 0.15494)
		(layer "In7.Cu")
		(net "PRSNT_SSD7_R_N")
	)
	(segment
		(start 203.074524 -93.41993)
		(end 201.2442 -97.838514)
		(width 0.15494)
		(layer "In7.Cu")
		(net "PRSNT_SSD7_R_N")
	)
	(segment
		(start 209.796634 -87.655654)
		(end 208.8388 -87.655654)
		(width 0.15494)
		(layer "In7.Cu")
		(net "PRSNT_SSD7_R_N")
	)
	(segment
		(start 225.374454 -230.5812)
		(end 227.190046 -230.5812)
		(width 0.15494)
		(layer "In7.Cu")
		(net "PRSNT_SSD7_R_N")
	)
	(segment
		(start 200.508616 -192.176654)
		(end 200.508616 -222.682816)
		(width 0.15494)
		(layer "In7.Cu")
		(net "PRSNT_SSD7_R_N")
	)
	(segment
		(start 208.982056 -164.297106)
		(end 204.679804 -168.599358)
		(width 0.15494)
		(layer "In7.Cu")
		(net "PRSNT_SSD7_R_N")
	)
	(segment
		(start 201.2442 -102.0318)
		(end 202.86472 -103.65232)
		(width 0.15494)
		(layer "In7.Cu")
		(net "PRSNT_SSD7_R_N")
	)
	(segment
		(start 201.2442 -97.838514)
		(end 201.2442 -102.0318)
		(width 0.15494)
		(layer "In7.Cu")
		(net "PRSNT_SSD7_R_N")
	)
	(segment
		(start 240.375948 -240.516918)
		(end 239.764062 -239.905032)
		(width 0.15494)
		(layer "In13.Cu")
		(net "PRSNT_SSD7_R_N")
	)
	(segment
		(start 276.759416 -242.84686)
		(end 274.429474 -240.516918)
		(width 0.15494)
		(layer "In13.Cu")
		(net "PRSNT_SSD7_R_N")
	)
	(segment
		(start 340.56574 -242.84686)
		(end 276.759416 -242.84686)
		(width 0.15494)
		(layer "In13.Cu")
		(net "PRSNT_SSD7_R_N")
	)
	(segment
		(start 274.429474 -240.516918)
		(end 240.375948 -240.516918)
		(width 0.15494)
		(layer "In13.Cu")
		(net "PRSNT_SSD7_R_N")
	)
	(segment
		(start 348.591378 -236.599222)
		(end 347.8276 -237.363)
		(width 0.15494)
		(layer "In13.Cu")
		(net "PRSNT_SSD7_R_N")
	)
	(segment
		(start 342.936068 -240.476532)
		(end 340.56574 -242.84686)
		(width 0.15494)
		(layer "In13.Cu")
		(net "PRSNT_SSD7_R_N")
	)
	(segment
		(start 349.683832 -233.586782)
		(end 348.591378 -234.679236)
		(width 0.15494)
		(layer "In13.Cu")
		(net "PRSNT_SSD7_R_N")
	)
	(segment
		(start 348.591378 -234.679236)
		(end 348.591378 -236.599222)
		(width 0.15494)
		(layer "In13.Cu")
		(net "PRSNT_SSD7_R_N")
	)
	(segment
		(start 232.410762 -239.905032)
		(end 232.205022 -240.110772)
		(width 0.15494)
		(layer "In13.Cu")
		(net "PRSNT_SSD7_R_N")
	)
	(segment
		(start 347.8276 -237.363)
		(end 346.8116 -237.363)
		(width 0.15494)
		(layer "In13.Cu")
		(net "PRSNT_SSD7_R_N")
	)
	(segment
		(start 349.683832 -228.854)
		(end 349.683832 -233.586782)
		(width 0.15494)
		(layer "In13.Cu")
		(net "PRSNT_SSD7_R_N")
	)
	(segment
		(start 342.936068 -239.930432)
		(end 342.936068 -240.476532)
		(width 0.15494)
		(layer "In13.Cu")
		(net "PRSNT_SSD7_R_N")
	)
	(segment
		(start 345.001342 -239.173258)
		(end 343.693242 -239.173258)
		(width 0.15494)
		(layer "In13.Cu")
		(net "PRSNT_SSD7_R_N")
	)
	(segment
		(start 346.8116 -237.363)
		(end 345.001342 -239.173258)
		(width 0.15494)
		(layer "In13.Cu")
		(net "PRSNT_SSD7_R_N")
	)
	(segment
		(start 239.764062 -239.905032)
		(end 232.410762 -239.905032)
		(width 0.15494)
		(layer "In13.Cu")
		(net "PRSNT_SSD7_R_N")
	)
	(segment
		(start 343.693242 -239.173258)
		(end 342.936068 -239.930432)
		(width 0.15494)
		(layer "In13.Cu")
		(net "PRSNT_SSD7_R_N")
	)
	(segment
		(start 337.566 -206.8068)
		(end 337.566 -205.63205)
		(width 0.13208)
		(layer "F.Cu")
		(net "SSD10_PWR_EN")
	)
	(segment
		(start 337.82 -210.913218)
		(end 337.82 -207.0608)
		(width 0.13208)
		(layer "F.Cu")
		(net "SSD10_PWR_EN")
	)
	(segment
		(start 338.093812 -211.18703)
		(end 337.82 -210.913218)
		(width 0.13208)
		(layer "F.Cu")
		(net "SSD10_PWR_EN")
	)
	(segment
		(start 337.82 -207.0608)
		(end 337.566 -206.8068)
		(width 0.13208)
		(layer "F.Cu")
		(net "SSD10_PWR_EN")
	)
	(via
		(at 337.566 -206.8068)
		(size 0.762)
		(drill 0.381)
		(layers "F.Cu" "B.Cu")
		(net "SSD10_PWR_EN")
	)
	(segment
		(start 265.303254 -59.171586)
		(end 265.14425 -59.012582)
		(width 0.13208)
		(layer "F.Cu")
		(net "P3V3_SSD9_OCP")
	)
	(segment
		(start 265.340846 -57.16397)
		(end 265.340846 -58.364628)
		(width 0.13208)
		(layer "F.Cu")
		(net "P3V3_SSD9_OCP")
	)
	(segment
		(start 265.14425 -59.012582)
		(end 265.14425 -58.561224)
		(width 0.13208)
		(layer "F.Cu")
		(net "P3V3_SSD9_OCP")
	)
	(segment
		(start 265.340846 -58.364628)
		(end 265.14425 -58.561224)
		(width 0.13208)
		(layer "F.Cu")
		(net "P3V3_SSD9_OCP")
	)
	(via
		(at 265.14425 -58.561224)
		(size 0.508)
		(drill 0.254)
		(layers "F.Cu" "B.Cu")
		(net "P3V3_SSD9_OCP")
	)
	(segment
		(start 116.083334 -86.79688)
		(end 116.779802 -86.79688)
		(width 0.13462)
		(layer "F.Cu")
		(net "CLK_100M_DB800ZL_SSD5_R_DP")
	)
	(segment
		(start 157.86862 -27.189938)
		(end 157.364938 -27.189938)
		(width 0.13462)
		(layer "F.Cu")
		(net "CLK_100M_DB800ZL_SSD5_R_DP")
	)
	(segment
		(start 159.08147 -27.342846)
		(end 158.784544 -27.04592)
		(width 0.13462)
		(layer "F.Cu")
		(net "CLK_100M_DB800ZL_SSD5_R_DP")
	)
	(segment
		(start 158.012638 -27.04592)
		(end 157.86862 -27.189938)
		(width 0.13462)
		(layer "F.Cu")
		(net "CLK_100M_DB800ZL_SSD5_R_DP")
	)
	(segment
		(start 115.756436 -86.469982)
		(end 116.083334 -86.79688)
		(width 0.13462)
		(layer "F.Cu")
		(net "CLK_100M_DB800ZL_SSD5_R_DP")
	)
	(segment
		(start 116.779802 -86.79688)
		(end 117.0813 -86.495382)
		(width 0.13462)
		(layer "F.Cu")
		(net "CLK_100M_DB800ZL_SSD5_R_DP")
	)
	(segment
		(start 158.784544 -27.04592)
		(end 158.012638 -27.04592)
		(width 0.13462)
		(layer "F.Cu")
		(net "CLK_100M_DB800ZL_SSD5_R_DP")
	)
	(via
		(at 159.08147 -27.342846)
		(size 0.508)
		(drill 0.254)
		(layers "F.Cu" "B.Cu")
		(net "CLK_100M_DB800ZL_SSD5_R_DP")
	)
	(via
		(at 117.0813 -86.495382)
		(size 0.508)
		(drill 0.254)
		(layers "F.Cu" "B.Cu")
		(net "CLK_100M_DB800ZL_SSD5_R_DP")
	)
	(segment
		(start 159.741362 -30.19425)
		(end 159.627062 -30.30855)
		(width 0.1651)
		(layer "In13.Cu")
		(net "CLK_100M_DB800ZL_SSD5_R_DP")
	)
	(segment
		(start 158.879032 -37.064188)
		(end 158.879032 -37.225986)
		(width 0.1651)
		(layer "In13.Cu")
		(net "CLK_100M_DB800ZL_SSD5_R_DP")
	)
	(segment
		(start 158.879032 -37.225986)
		(end 157.719776 -38.385242)
		(width 0.1651)
		(layer "In13.Cu")
		(net "CLK_100M_DB800ZL_SSD5_R_DP")
	)
	(segment
		(start 159.627062 -32.74695)
		(end 159.627062 -33.24225)
		(width 0.1651)
		(layer "In13.Cu")
		(net "CLK_100M_DB800ZL_SSD5_R_DP")
	)
	(segment
		(start 159.741362 -33.35655)
		(end 159.741362 -33.85185)
		(width 0.1651)
		(layer "In13.Cu")
		(net "CLK_100M_DB800ZL_SSD5_R_DP")
	)
	(segment
		(start 156.857446 -40.1701)
		(end 153.777188 -43.250358)
		(width 0.1651)
		(layer "In13.Cu")
		(net "CLK_100M_DB800ZL_SSD5_R_DP")
	)
	(segment
		(start 145.549874 -69.448426)
		(end 145.108422 -69.448426)
		(width 0.1651)
		(layer "In13.Cu")
		(net "CLK_100M_DB800ZL_SSD5_R_DP")
	)
	(segment
		(start 143.904208 -73.418192)
		(end 139.748006 -77.574394)
		(width 0.1651)
		(layer "In13.Cu")
		(net "CLK_100M_DB800ZL_SSD5_R_DP")
	)
	(segment
		(start 159.741362 -32.13735)
		(end 159.741362 -32.63265)
		(width 0.1651)
		(layer "In13.Cu")
		(net "CLK_100M_DB800ZL_SSD5_R_DP")
	)
	(segment
		(start 118.112286 -86.789768)
		(end 117.375686 -86.789768)
		(width 0.1651)
		(layer "In13.Cu")
		(net "CLK_100M_DB800ZL_SSD5_R_DP")
	)
	(segment
		(start 148.323808 -68.864988)
		(end 147.229322 -67.770502)
		(width 0.1651)
		(layer "In13.Cu")
		(net "CLK_100M_DB800ZL_SSD5_R_DP")
	)
	(segment
		(start 159.627062 -33.96615)
		(end 159.627062 -34.46145)
		(width 0.1651)
		(layer "In13.Cu")
		(net "CLK_100M_DB800ZL_SSD5_R_DP")
	)
	(segment
		(start 159.627062 -32.02305)
		(end 159.741362 -32.13735)
		(width 0.1651)
		(layer "In13.Cu")
		(net "CLK_100M_DB800ZL_SSD5_R_DP")
	)
	(segment
		(start 145.600674 -71.588122)
		(end 145.600674 -71.790306)
		(width 0.1651)
		(layer "In13.Cu")
		(net "CLK_100M_DB800ZL_SSD5_R_DP")
	)
	(segment
		(start 159.627062 -33.24225)
		(end 159.741362 -33.35655)
		(width 0.1651)
		(layer "In13.Cu")
		(net "CLK_100M_DB800ZL_SSD5_R_DP")
	)
	(segment
		(start 142.83436 -71.733156)
		(end 142.83436 -72.168512)
		(width 0.1651)
		(layer "In13.Cu")
		(net "CLK_100M_DB800ZL_SSD5_R_DP")
	)
	(segment
		(start 157.369764 -39.657782)
		(end 157.207966 -39.657782)
		(width 0.1651)
		(layer "In13.Cu")
		(net "CLK_100M_DB800ZL_SSD5_R_DP")
	)
	(segment
		(start 147.27936 -70.11162)
		(end 146.847306 -70.543674)
		(width 0.1651)
		(layer "In13.Cu")
		(net "CLK_100M_DB800ZL_SSD5_R_DP")
	)
	(segment
		(start 156.857446 -40.008302)
		(end 156.857446 -40.1701)
		(width 0.1651)
		(layer "In13.Cu")
		(net "CLK_100M_DB800ZL_SSD5_R_DP")
	)
	(segment
		(start 119.033544 -85.86851)
		(end 118.112286 -86.789768)
		(width 0.1651)
		(layer "In13.Cu")
		(net "CLK_100M_DB800ZL_SSD5_R_DP")
	)
	(segment
		(start 145.108422 -69.448426)
		(end 144.505426 -70.051422)
		(width 0.1651)
		(layer "In13.Cu")
		(net "CLK_100M_DB800ZL_SSD5_R_DP")
	)
	(segment
		(start 159.741362 -34.57575)
		(end 159.741362 -35.07105)
		(width 0.1651)
		(layer "In13.Cu")
		(net "CLK_100M_DB800ZL_SSD5_R_DP")
	)
	(segment
		(start 159.627062 -35.68065)
		(end 159.741362 -35.79495)
		(width 0.1651)
		(layer "In13.Cu")
		(net "CLK_100M_DB800ZL_SSD5_R_DP")
	)
	(segment
		(start 157.719776 -38.385242)
		(end 157.719776 -39.30777)
		(width 0.1651)
		(layer "In13.Cu")
		(net "CLK_100M_DB800ZL_SSD5_R_DP")
	)
	(segment
		(start 159.741362 -33.85185)
		(end 159.627062 -33.96615)
		(width 0.1651)
		(layer "In13.Cu")
		(net "CLK_100M_DB800ZL_SSD5_R_DP")
	)
	(segment
		(start 159.627062 -29.08935)
		(end 159.627062 -29.58465)
		(width 0.1651)
		(layer "In13.Cu")
		(net "CLK_100M_DB800ZL_SSD5_R_DP")
	)
	(segment
		(start 159.627062 -27.87015)
		(end 159.627062 -28.36545)
		(width 0.1651)
		(layer "In13.Cu")
		(net "CLK_100M_DB800ZL_SSD5_R_DP")
	)
	(segment
		(start 159.36849 -27.055826)
		(end 159.614108 -27.055826)
		(width 0.1651)
		(layer "In13.Cu")
		(net "CLK_100M_DB800ZL_SSD5_R_DP")
	)
	(segment
		(start 159.741362 -31.41345)
		(end 159.627062 -31.52775)
		(width 0.1651)
		(layer "In13.Cu")
		(net "CLK_100M_DB800ZL_SSD5_R_DP")
	)
	(segment
		(start 153.994866 -63.396114)
		(end 148.526246 -68.864988)
		(width 0.1651)
		(layer "In13.Cu")
		(net "CLK_100M_DB800ZL_SSD5_R_DP")
	)
	(segment
		(start 159.627062 -30.80385)
		(end 159.741362 -30.91815)
		(width 0.1651)
		(layer "In13.Cu")
		(net "CLK_100M_DB800ZL_SSD5_R_DP")
	)
	(segment
		(start 159.741362 -29.69895)
		(end 159.741362 -30.19425)
		(width 0.1651)
		(layer "In13.Cu")
		(net "CLK_100M_DB800ZL_SSD5_R_DP")
	)
	(segment
		(start 159.614108 -27.055826)
		(end 159.741362 -27.18308)
		(width 0.1651)
		(layer "In13.Cu")
		(net "CLK_100M_DB800ZL_SSD5_R_DP")
	)
	(segment
		(start 145.16862 -72.22236)
		(end 144.966436 -72.22236)
		(width 0.1651)
		(layer "In13.Cu")
		(net "CLK_100M_DB800ZL_SSD5_R_DP")
	)
	(segment
		(start 159.627062 -35.18535)
		(end 159.627062 -35.68065)
		(width 0.1651)
		(layer "In13.Cu")
		(net "CLK_100M_DB800ZL_SSD5_R_DP")
	)
	(segment
		(start 147.27936 -69.909436)
		(end 147.27936 -70.11162)
		(width 0.1651)
		(layer "In13.Cu")
		(net "CLK_100M_DB800ZL_SSD5_R_DP")
	)
	(segment
		(start 143.904208 -73.23836)
		(end 143.904208 -73.418192)
		(width 0.1651)
		(layer "In13.Cu")
		(net "CLK_100M_DB800ZL_SSD5_R_DP")
	)
	(segment
		(start 139.748006 -77.574394)
		(end 128.994154 -77.574394)
		(width 0.1651)
		(layer "In13.Cu")
		(net "CLK_100M_DB800ZL_SSD5_R_DP")
	)
	(segment
		(start 144.505426 -70.051422)
		(end 144.505426 -70.492874)
		(width 0.1651)
		(layer "In13.Cu")
		(net "CLK_100M_DB800ZL_SSD5_R_DP")
	)
	(segment
		(start 144.505426 -70.492874)
		(end 145.600674 -71.588122)
		(width 0.1651)
		(layer "In13.Cu")
		(net "CLK_100M_DB800ZL_SSD5_R_DP")
	)
	(segment
		(start 159.08147 -27.342846)
		(end 159.36849 -27.055826)
		(width 0.1651)
		(layer "In13.Cu")
		(net "CLK_100M_DB800ZL_SSD5_R_DP")
	)
	(segment
		(start 159.741362 -35.07105)
		(end 159.627062 -35.18535)
		(width 0.1651)
		(layer "In13.Cu")
		(net "CLK_100M_DB800ZL_SSD5_R_DP")
	)
	(segment
		(start 153.777188 -43.250358)
		(end 153.531316 -50.838862)
		(width 0.1651)
		(layer "In13.Cu")
		(net "CLK_100M_DB800ZL_SSD5_R_DP")
	)
	(segment
		(start 159.627062 -31.52775)
		(end 159.627062 -32.02305)
		(width 0.1651)
		(layer "In13.Cu")
		(net "CLK_100M_DB800ZL_SSD5_R_DP")
	)
	(segment
		(start 159.39135 -36.713668)
		(end 159.229552 -36.713668)
		(width 0.1651)
		(layer "In13.Cu")
		(net "CLK_100M_DB800ZL_SSD5_R_DP")
	)
	(segment
		(start 146.847306 -70.543674)
		(end 146.645122 -70.543674)
		(width 0.1651)
		(layer "In13.Cu")
		(net "CLK_100M_DB800ZL_SSD5_R_DP")
	)
	(segment
		(start 159.741362 -27.75585)
		(end 159.627062 -27.87015)
		(width 0.1651)
		(layer "In13.Cu")
		(net "CLK_100M_DB800ZL_SSD5_R_DP")
	)
	(segment
		(start 159.627062 -34.46145)
		(end 159.741362 -34.57575)
		(width 0.1651)
		(layer "In13.Cu")
		(net "CLK_100M_DB800ZL_SSD5_R_DP")
	)
	(segment
		(start 159.741362 -36.363656)
		(end 159.39135 -36.713668)
		(width 0.1651)
		(layer "In13.Cu")
		(net "CLK_100M_DB800ZL_SSD5_R_DP")
	)
	(segment
		(start 159.229552 -36.713668)
		(end 158.879032 -37.064188)
		(width 0.1651)
		(layer "In13.Cu")
		(net "CLK_100M_DB800ZL_SSD5_R_DP")
	)
	(segment
		(start 142.83436 -72.168512)
		(end 143.904208 -73.23836)
		(width 0.1651)
		(layer "In13.Cu")
		(net "CLK_100M_DB800ZL_SSD5_R_DP")
	)
	(segment
		(start 147.229322 -67.770502)
		(end 146.783298 -67.770502)
		(width 0.1651)
		(layer "In13.Cu")
		(net "CLK_100M_DB800ZL_SSD5_R_DP")
	)
	(segment
		(start 128.994154 -77.574394)
		(end 120.700038 -85.86851)
		(width 0.1651)
		(layer "In13.Cu")
		(net "CLK_100M_DB800ZL_SSD5_R_DP")
	)
	(segment
		(start 159.741362 -30.91815)
		(end 159.741362 -31.41345)
		(width 0.1651)
		(layer "In13.Cu")
		(net "CLK_100M_DB800ZL_SSD5_R_DP")
	)
	(segment
		(start 159.741362 -28.97505)
		(end 159.627062 -29.08935)
		(width 0.1651)
		(layer "In13.Cu")
		(net "CLK_100M_DB800ZL_SSD5_R_DP")
	)
	(segment
		(start 159.741362 -35.79495)
		(end 159.741362 -36.363656)
		(width 0.1651)
		(layer "In13.Cu")
		(net "CLK_100M_DB800ZL_SSD5_R_DP")
	)
	(segment
		(start 159.627062 -28.36545)
		(end 159.741362 -28.47975)
		(width 0.1651)
		(layer "In13.Cu")
		(net "CLK_100M_DB800ZL_SSD5_R_DP")
	)
	(segment
		(start 148.526246 -68.864988)
		(end 148.323808 -68.864988)
		(width 0.1651)
		(layer "In13.Cu")
		(net "CLK_100M_DB800ZL_SSD5_R_DP")
	)
	(segment
		(start 157.207966 -39.657782)
		(end 156.857446 -40.008302)
		(width 0.1651)
		(layer "In13.Cu")
		(net "CLK_100M_DB800ZL_SSD5_R_DP")
	)
	(segment
		(start 154.157934 -61.28893)
		(end 153.994866 -63.396114)
		(width 0.1651)
		(layer "In13.Cu")
		(net "CLK_100M_DB800ZL_SSD5_R_DP")
	)
	(segment
		(start 144.966436 -72.22236)
		(end 143.871188 -71.127112)
		(width 0.1651)
		(layer "In13.Cu")
		(net "CLK_100M_DB800ZL_SSD5_R_DP")
	)
	(segment
		(start 146.783298 -67.770502)
		(end 146.184874 -68.368926)
		(width 0.1651)
		(layer "In13.Cu")
		(net "CLK_100M_DB800ZL_SSD5_R_DP")
	)
	(segment
		(start 143.440404 -71.127112)
		(end 142.83436 -71.733156)
		(width 0.1651)
		(layer "In13.Cu")
		(net "CLK_100M_DB800ZL_SSD5_R_DP")
	)
	(segment
		(start 159.627062 -30.30855)
		(end 159.627062 -30.80385)
		(width 0.1651)
		(layer "In13.Cu")
		(net "CLK_100M_DB800ZL_SSD5_R_DP")
	)
	(segment
		(start 159.741362 -32.63265)
		(end 159.627062 -32.74695)
		(width 0.1651)
		(layer "In13.Cu")
		(net "CLK_100M_DB800ZL_SSD5_R_DP")
	)
	(segment
		(start 120.700038 -85.86851)
		(end 119.033544 -85.86851)
		(width 0.1651)
		(layer "In13.Cu")
		(net "CLK_100M_DB800ZL_SSD5_R_DP")
	)
	(segment
		(start 146.184874 -68.81495)
		(end 147.27936 -69.909436)
		(width 0.1651)
		(layer "In13.Cu")
		(net "CLK_100M_DB800ZL_SSD5_R_DP")
	)
	(segment
		(start 153.531316 -50.838862)
		(end 154.157934 -61.28893)
		(width 0.1651)
		(layer "In13.Cu")
		(net "CLK_100M_DB800ZL_SSD5_R_DP")
	)
	(segment
		(start 146.184874 -68.368926)
		(end 146.184874 -68.81495)
		(width 0.1651)
		(layer "In13.Cu")
		(net "CLK_100M_DB800ZL_SSD5_R_DP")
	)
	(segment
		(start 159.741362 -28.47975)
		(end 159.741362 -28.97505)
		(width 0.1651)
		(layer "In13.Cu")
		(net "CLK_100M_DB800ZL_SSD5_R_DP")
	)
	(segment
		(start 145.600674 -71.790306)
		(end 145.16862 -72.22236)
		(width 0.1651)
		(layer "In13.Cu")
		(net "CLK_100M_DB800ZL_SSD5_R_DP")
	)
	(segment
		(start 117.375686 -86.789768)
		(end 117.0813 -86.495382)
		(width 0.1651)
		(layer "In13.Cu")
		(net "CLK_100M_DB800ZL_SSD5_R_DP")
	)
	(segment
		(start 157.719776 -39.30777)
		(end 157.369764 -39.657782)
		(width 0.1651)
		(layer "In13.Cu")
		(net "CLK_100M_DB800ZL_SSD5_R_DP")
	)
	(segment
		(start 159.741362 -27.18308)
		(end 159.741362 -27.75585)
		(width 0.1651)
		(layer "In13.Cu")
		(net "CLK_100M_DB800ZL_SSD5_R_DP")
	)
	(segment
		(start 143.871188 -71.127112)
		(end 143.440404 -71.127112)
		(width 0.1651)
		(layer "In13.Cu")
		(net "CLK_100M_DB800ZL_SSD5_R_DP")
	)
	(segment
		(start 146.645122 -70.543674)
		(end 145.549874 -69.448426)
		(width 0.1651)
		(layer "In13.Cu")
		(net "CLK_100M_DB800ZL_SSD5_R_DP")
	)
	(segment
		(start 159.627062 -29.58465)
		(end 159.741362 -29.69895)
		(width 0.1651)
		(layer "In13.Cu")
		(net "CLK_100M_DB800ZL_SSD5_R_DP")
	)
	(segment
		(start 38.566344 -251.956824)
		(end 38.566344 -251.158502)
		(width 0.13208)
		(layer "F.Cu")
		(net "PEX0_DBG_MODE4")
	)
	(segment
		(start 38.566344 -251.158502)
		(end 38.566344 -250.470924)
		(width 0.13208)
		(layer "F.Cu")
		(net "PEX0_DBG_MODE4")
	)
	(segment
		(start 68.199762 -282.599892)
		(end 68.674742 -283.074872)
		(width 0.13208)
		(layer "F.Cu")
		(net "PEX0_DBG_MODE4")
	)
	(via
		(at 68.674742 -283.074872)
		(size 0.4064)
		(drill 0.2032)
		(layers "F.Cu" "B.Cu")
		(net "PEX0_DBG_MODE4")
	)
	(via
		(at 38.566344 -251.158502)
		(size 0.508)
		(drill 0.254)
		(layers "F.Cu" "B.Cu")
		(net "PEX0_DBG_MODE4")
	)
	(segment
		(start 69.455284 -282.591002)
		(end 69.783198 -282.591002)
		(width 0.13208)
		(layer "B.Cu")
		(net "PEX0_DBG_MODE4")
	)
	(segment
		(start 70.579996 -272.169636)
		(end 52.64023 -254.22987)
		(width 0.13208)
		(layer "B.Cu")
		(net "PEX0_DBG_MODE4")
	)
	(segment
		(start 38.093396 -251.63145)
		(end 38.566344 -251.158502)
		(width 0.13208)
		(layer "B.Cu")
		(net "PEX0_DBG_MODE4")
	)
	(segment
		(start 68.971414 -283.074872)
		(end 69.455284 -282.591002)
		(width 0.13208)
		(layer "B.Cu")
		(net "PEX0_DBG_MODE4")
	)
	(segment
		(start 70.579996 -281.794204)
		(end 70.579996 -272.169636)
		(width 0.13208)
		(layer "B.Cu")
		(net "PEX0_DBG_MODE4")
	)
	(segment
		(start 38.251892 -254.22987)
		(end 38.093396 -254.071374)
		(width 0.13208)
		(layer "B.Cu")
		(net "PEX0_DBG_MODE4")
	)
	(segment
		(start 38.093396 -254.071374)
		(end 38.093396 -251.63145)
		(width 0.13208)
		(layer "B.Cu")
		(net "PEX0_DBG_MODE4")
	)
	(segment
		(start 52.64023 -254.22987)
		(end 38.251892 -254.22987)
		(width 0.13208)
		(layer "B.Cu")
		(net "PEX0_DBG_MODE4")
	)
	(segment
		(start 69.783198 -282.591002)
		(end 70.579996 -281.794204)
		(width 0.13208)
		(layer "B.Cu")
		(net "PEX0_DBG_MODE4")
	)
	(segment
		(start 68.674742 -283.074872)
		(end 68.971414 -283.074872)
		(width 0.13208)
		(layer "B.Cu")
		(net "PEX0_DBG_MODE4")
	)
	(segment
		(start 373.658384 -251.209302)
		(end 373.709184 -251.158502)
		(width 0.13208)
		(layer "F.Cu")
		(net "PEX3_MODE_SEL7")
	)
	(segment
		(start 373.658384 -251.956824)
		(end 373.658384 -251.209302)
		(width 0.13208)
		(layer "F.Cu")
		(net "PEX3_MODE_SEL7")
	)
	(segment
		(start 408.899868 -283.549852)
		(end 409.374848 -284.024832)
		(width 0.1651)
		(layer "F.Cu")
		(net "PEX3_MODE_SEL7")
	)
	(segment
		(start 373.658384 -251.107702)
		(end 373.658384 -250.470924)
		(width 0.13208)
		(layer "F.Cu")
		(net "PEX3_MODE_SEL7")
	)
	(segment
		(start 373.709184 -251.158502)
		(end 373.658384 -251.107702)
		(width 0.13208)
		(layer "F.Cu")
		(net "PEX3_MODE_SEL7")
	)
	(via
		(at 409.374848 -284.024832)
		(size 0.4064)
		(drill 0.2032)
		(layers "F.Cu" "B.Cu")
		(net "PEX3_MODE_SEL7")
	)
	(via
		(at 405.450294 -269.963138)
		(size 0.6604)
		(drill 0.3302)
		(layers "F.Cu" "B.Cu")
		(net "PEX3_MODE_SEL7")
	)
	(via
		(at 373.709184 -251.158502)
		(size 0.508)
		(drill 0.254)
		(layers "F.Cu" "B.Cu")
		(net "PEX3_MODE_SEL7")
	)
	(segment
		(start 405.450294 -269.963138)
		(end 406.477724 -270.990568)
		(width 0.13208)
		(layer "B.Cu")
		(net "PEX3_MODE_SEL7")
	)
	(segment
		(start 375.88063 -259.1054)
		(end 376.301 -259.1054)
		(width 0.13208)
		(layer "B.Cu")
		(net "PEX3_MODE_SEL7")
	)
	(segment
		(start 406.049988 -283.317188)
		(end 406.310592 -283.577792)
		(width 0.13208)
		(layer "B.Cu")
		(net "PEX3_MODE_SEL7")
	)
	(segment
		(start 373.130826 -256.355596)
		(end 375.88063 -259.1054)
		(width 0.13208)
		(layer "B.Cu")
		(net "PEX3_MODE_SEL7")
	)
	(segment
		(start 406.310592 -283.577792)
		(end 407.305256 -283.577792)
		(width 0.13208)
		(layer "B.Cu")
		(net "PEX3_MODE_SEL7")
	)
	(segment
		(start 396.685516 -261.19836)
		(end 405.450294 -269.963138)
		(width 0.13208)
		(layer "B.Cu")
		(net "PEX3_MODE_SEL7")
	)
	(segment
		(start 406.049988 -282.340812)
		(end 406.049988 -283.317188)
		(width 0.13208)
		(layer "B.Cu")
		(net "PEX3_MODE_SEL7")
	)
	(segment
		(start 406.477724 -281.913076)
		(end 406.049988 -282.340812)
		(width 0.13208)
		(layer "B.Cu")
		(net "PEX3_MODE_SEL7")
	)
	(segment
		(start 373.709184 -251.802646)
		(end 373.130826 -252.381004)
		(width 0.13208)
		(layer "B.Cu")
		(net "PEX3_MODE_SEL7")
	)
	(segment
		(start 406.477724 -270.990568)
		(end 406.477724 -281.913076)
		(width 0.13208)
		(layer "B.Cu")
		(net "PEX3_MODE_SEL7")
	)
	(segment
		(start 408.22118 -284.493716)
		(end 408.905964 -284.493716)
		(width 0.13208)
		(layer "B.Cu")
		(net "PEX3_MODE_SEL7")
	)
	(segment
		(start 376.301 -259.1054)
		(end 377.3424 -260.1468)
		(width 0.13208)
		(layer "B.Cu")
		(net "PEX3_MODE_SEL7")
	)
	(segment
		(start 382.695704 -261.19836)
		(end 396.685516 -261.19836)
		(width 0.13208)
		(layer "B.Cu")
		(net "PEX3_MODE_SEL7")
	)
	(segment
		(start 408.905964 -284.493716)
		(end 409.374848 -284.024832)
		(width 0.13208)
		(layer "B.Cu")
		(net "PEX3_MODE_SEL7")
	)
	(segment
		(start 373.130826 -252.381004)
		(end 373.130826 -256.355596)
		(width 0.13208)
		(layer "B.Cu")
		(net "PEX3_MODE_SEL7")
	)
	(segment
		(start 373.709184 -251.158502)
		(end 373.709184 -251.802646)
		(width 0.13208)
		(layer "B.Cu")
		(net "PEX3_MODE_SEL7")
	)
	(segment
		(start 377.3424 -260.1468)
		(end 381.644144 -260.1468)
		(width 0.13208)
		(layer "B.Cu")
		(net "PEX3_MODE_SEL7")
	)
	(segment
		(start 381.644144 -260.1468)
		(end 382.695704 -261.19836)
		(width 0.13208)
		(layer "B.Cu")
		(net "PEX3_MODE_SEL7")
	)
	(segment
		(start 407.305256 -283.577792)
		(end 408.22118 -284.493716)
		(width 0.13208)
		(layer "B.Cu")
		(net "PEX3_MODE_SEL7")
	)
	(segment
		(start 218.791282 -226.10699)
		(end 219.466922 -225.43135)
		(width 0.13208)
		(layer "F.Cu")
		(net "SMB_NIC3_SCL")
	)
	(segment
		(start 223.237044 -223.504252)
		(end 223.867726 -223.504252)
		(width 0.13208)
		(layer "F.Cu")
		(net "SMB_NIC3_SCL")
	)
	(segment
		(start 219.54236 -224.476564)
		(end 219.542868 -224.475548)
		(width 0.13208)
		(layer "F.Cu")
		(net "SMB_NIC3_SCL")
	)
	(segment
		(start 217.635836 -225.490786)
		(end 218.25204 -226.10699)
		(width 0.13208)
		(layer "F.Cu")
		(net "SMB_NIC3_SCL")
	)
	(segment
		(start 219.466922 -225.43135)
		(end 219.466922 -224.65919)
		(width 0.13208)
		(layer "F.Cu")
		(net "SMB_NIC3_SCL")
	)
	(segment
		(start 223.145604 -223.595692)
		(end 223.237044 -223.504252)
		(width 0.13208)
		(layer "F.Cu")
		(net "SMB_NIC3_SCL")
	)
	(segment
		(start 219.466922 -224.65919)
		(end 219.54236 -224.476564)
		(width 0.13208)
		(layer "F.Cu")
		(net "SMB_NIC3_SCL")
	)
	(segment
		(start 223.867726 -223.504252)
		(end 224.267776 -223.104202)
		(width 0.13208)
		(layer "F.Cu")
		(net "SMB_NIC3_SCL")
	)
	(segment
		(start 219.624402 -224.278444)
		(end 220.307154 -223.595692)
		(width 0.13208)
		(layer "F.Cu")
		(net "SMB_NIC3_SCL")
	)
	(segment
		(start 220.503242 -223.595692)
		(end 223.145604 -223.595692)
		(width 0.13208)
		(layer "F.Cu")
		(net "SMB_NIC3_SCL")
	)
	(segment
		(start 218.25204 -226.10699)
		(end 218.791282 -226.10699)
		(width 0.13208)
		(layer "F.Cu")
		(net "SMB_NIC3_SCL")
	)
	(segment
		(start 220.307154 -223.595692)
		(end 220.503242 -223.595692)
		(width 0.13208)
		(layer "F.Cu")
		(net "SMB_NIC3_SCL")
	)
	(segment
		(start 219.542868 -224.475548)
		(end 219.624402 -224.278444)
		(width 0.13208)
		(layer "F.Cu")
		(net "SMB_NIC3_SCL")
	)
	(via
		(at 220.503242 -223.595692)
		(size 0.762)
		(drill 0.381)
		(layers "F.Cu" "B.Cu")
		(net "SMB_NIC3_SCL")
	)
	(segment
		(start 192.616328 -53.644038)
		(end 193.237358 -53.023008)
		(width 0.13208)
		(layer "F.Cu")
		(net "PWRGD_P12V_SSD6")
	)
	(segment
		(start 192.247266 -53.644038)
		(end 192.616328 -53.644038)
		(width 0.13208)
		(layer "F.Cu")
		(net "PWRGD_P12V_SSD6")
	)
	(segment
		(start 193.237358 -52.587398)
		(end 193.701416 -53.051456)
		(width 0.13208)
		(layer "F.Cu")
		(net "PWRGD_P12V_SSD6")
	)
	(segment
		(start 193.967862 -52.035456)
		(end 193.967862 -53.051456)
		(width 0.13208)
		(layer "F.Cu")
		(net "PWRGD_P12V_SSD6")
	)
	(segment
		(start 193.237358 -53.023008)
		(end 193.237358 -52.587398)
		(width 0.13208)
		(layer "F.Cu")
		(net "PWRGD_P12V_SSD6")
	)
	(segment
		(start 193.701416 -53.051456)
		(end 193.967862 -53.051456)
		(width 0.13208)
		(layer "F.Cu")
		(net "PWRGD_P12V_SSD6")
	)
	(via
		(at 193.237358 -52.587398)
		(size 0.508)
		(drill 0.254)
		(layers "F.Cu" "B.Cu")
		(net "PWRGD_P12V_SSD6")
	)
	(segment
		(start 340.493858 -212.786976)
		(end 340.094062 -212.38718)
		(width 0.13208)
		(layer "F.Cu")
		(net "SSD13_PWR_EN")
	)
	(via
		(at 339.715602 -209.305652)
		(size 0.6604)
		(drill 0.3302)
		(layers "F.Cu" "B.Cu")
		(net "SSD13_PWR_EN")
	)
	(via
		(at 340.094062 -212.38718)
		(size 0.4572)
		(drill 0.254)
		(layers "F.Cu" "B.Cu")
		(net "SSD13_PWR_EN")
	)
	(segment
		(start 340.094062 -209.684112)
		(end 340.094062 -212.38718)
		(width 0.13208)
		(layer "B.Cu")
		(net "SSD13_PWR_EN")
	)
	(segment
		(start 338.582 -208.17205)
		(end 339.715602 -209.305652)
		(width 0.13208)
		(layer "B.Cu")
		(net "SSD13_PWR_EN")
	)
	(segment
		(start 339.715602 -209.305652)
		(end 340.094062 -209.684112)
		(width 0.13208)
		(layer "B.Cu")
		(net "SSD13_PWR_EN")
	)
	(segment
		(start 381.244348 -59.012582)
		(end 381.244348 -58.561224)
		(width 0.13208)
		(layer "F.Cu")
		(net "P3V3_SSD13_OCP")
	)
	(segment
		(start 381.440944 -57.16397)
		(end 381.440944 -58.364628)
		(width 0.13208)
		(layer "F.Cu")
		(net "P3V3_SSD13_OCP")
	)
	(segment
		(start 381.403352 -59.171586)
		(end 381.244348 -59.012582)
		(width 0.13208)
		(layer "F.Cu")
		(net "P3V3_SSD13_OCP")
	)
	(segment
		(start 381.440944 -58.364628)
		(end 381.244348 -58.561224)
		(width 0.13208)
		(layer "F.Cu")
		(net "P3V3_SSD13_OCP")
	)
	(via
		(at 381.244348 -58.561224)
		(size 0.508)
		(drill 0.254)
		(layers "F.Cu" "B.Cu")
		(net "P3V3_SSD13_OCP")
	)
	(segment
		(start 222.226886 -197.887082)
		(end 222.226886 -197.078092)
		(width 0.13208)
		(layer "F.Cu")
		(net "SPI_BIC1_MOSI_R5")
	)
	(segment
		(start 221.993968 -198.12)
		(end 222.226886 -197.887082)
		(width 0.13208)
		(layer "F.Cu")
		(net "SPI_BIC1_MOSI_R5")
	)
	(segment
		(start 220.98 -198.12)
		(end 221.993968 -198.12)
		(width 0.13208)
		(layer "F.Cu")
		(net "SPI_BIC1_MOSI_R5")
	)
	(via
		(at 220.98 -198.12)
		(size 0.508)
		(drill 0.254)
		(layers "F.Cu" "B.Cu")
		(net "SPI_BIC1_MOSI_R5")
	)
	(segment
		(start 221.615 -198.191882)
		(end 222.212154 -198.191882)
		(width 0.13208)
		(layer "B.Cu")
		(net "SPI_BIC1_MOSI_R5")
	)
	(segment
		(start 220.98 -198.12)
		(end 221.543118 -198.12)
		(width 0.13208)
		(layer "B.Cu")
		(net "SPI_BIC1_MOSI_R5")
	)
	(segment
		(start 221.543118 -198.12)
		(end 221.615 -198.191882)
		(width 0.13208)
		(layer "B.Cu")
		(net "SPI_BIC1_MOSI_R5")
	)
	(segment
		(start 131.971034 -175.400462)
		(end 132.282946 -175.865536)
		(width 0.13208)
		(layer "F.Cu")
		(net "SMB_BMC_9QXL2001_SCL")
	)
	(via
		(at 132.282946 -175.865536)
		(size 0.4572)
		(drill 0.254)
		(layers "F.Cu" "B.Cu")
		(net "SMB_BMC_9QXL2001_SCL")
	)
	(via
		(at 132.150358 -173.386496)
		(size 0.6604)
		(drill 0.3302)
		(layers "F.Cu" "B.Cu")
		(net "SMB_BMC_9QXL2001_SCL")
	)
	(segment
		(start 131.982464 -174.517558)
		(end 131.982464 -174.024036)
		(width 0.13208)
		(layer "B.Cu")
		(net "SMB_BMC_9QXL2001_SCL")
	)
	(segment
		(start 132.084826 -174.637954)
		(end 132.084826 -174.61992)
		(width 0.13208)
		(layer "B.Cu")
		(net "SMB_BMC_9QXL2001_SCL")
	)
	(segment
		(start 132.150358 -173.386496)
		(end 131.51485 -172.750988)
		(width 0.13208)
		(layer "B.Cu")
		(net "SMB_BMC_9QXL2001_SCL")
	)
	(segment
		(start 131.982464 -174.024036)
		(end 132.150358 -173.856142)
		(width 0.13208)
		(layer "B.Cu")
		(net "SMB_BMC_9QXL2001_SCL")
	)
	(segment
		(start 132.282946 -174.836074)
		(end 132.084826 -174.637954)
		(width 0.13208)
		(layer "B.Cu")
		(net "SMB_BMC_9QXL2001_SCL")
	)
	(segment
		(start 131.51485 -172.750988)
		(end 131.51485 -171.83862)
		(width 0.13208)
		(layer "B.Cu")
		(net "SMB_BMC_9QXL2001_SCL")
	)
	(segment
		(start 132.084826 -174.61992)
		(end 131.982464 -174.517558)
		(width 0.13208)
		(layer "B.Cu")
		(net "SMB_BMC_9QXL2001_SCL")
	)
	(segment
		(start 132.150358 -173.856142)
		(end 132.150358 -173.386496)
		(width 0.13208)
		(layer "B.Cu")
		(net "SMB_BMC_9QXL2001_SCL")
	)
	(segment
		(start 132.282946 -175.865536)
		(end 132.282946 -174.836074)
		(width 0.13208)
		(layer "B.Cu")
		(net "SMB_BMC_9QXL2001_SCL")
	)
	(segment
		(start 159.08147 -26.479246)
		(end 158.789116 -26.7716)
		(width 0.13462)
		(layer "F.Cu")
		(net "CLK_100M_DB800ZL_SSD5_R_DN")
	)
	(segment
		(start 158.036514 -26.7716)
		(end 157.854904 -26.58999)
		(width 0.13462)
		(layer "F.Cu")
		(net "CLK_100M_DB800ZL_SSD5_R_DN")
	)
	(segment
		(start 116.793518 -87.0712)
		(end 117.0813 -87.358982)
		(width 0.13462)
		(layer "F.Cu")
		(net "CLK_100M_DB800ZL_SSD5_R_DN")
	)
	(segment
		(start 158.789116 -26.7716)
		(end 158.036514 -26.7716)
		(width 0.13462)
		(layer "F.Cu")
		(net "CLK_100M_DB800ZL_SSD5_R_DN")
	)
	(segment
		(start 157.854904 -26.58999)
		(end 157.364938 -26.58999)
		(width 0.13462)
		(layer "F.Cu")
		(net "CLK_100M_DB800ZL_SSD5_R_DN")
	)
	(segment
		(start 115.756436 -87.384382)
		(end 116.069618 -87.0712)
		(width 0.13462)
		(layer "F.Cu")
		(net "CLK_100M_DB800ZL_SSD5_R_DN")
	)
	(segment
		(start 116.069618 -87.0712)
		(end 116.793518 -87.0712)
		(width 0.13462)
		(layer "F.Cu")
		(net "CLK_100M_DB800ZL_SSD5_R_DN")
	)
	(via
		(at 117.0813 -87.358982)
		(size 0.508)
		(drill 0.254)
		(layers "F.Cu" "B.Cu")
		(net "CLK_100M_DB800ZL_SSD5_R_DN")
	)
	(via
		(at 159.08147 -26.479246)
		(size 0.508)
		(drill 0.254)
		(layers "F.Cu" "B.Cu")
		(net "CLK_100M_DB800ZL_SSD5_R_DN")
	)
	(segment
		(start 146.528282 -70.825614)
		(end 145.433034 -69.730366)
		(width 0.1651)
		(layer "In13.Cu")
		(net "CLK_100M_DB800ZL_SSD5_R_DN")
	)
	(segment
		(start 139.864846 -77.856334)
		(end 129.110994 -77.856334)
		(width 0.1651)
		(layer "In13.Cu")
		(net "CLK_100M_DB800ZL_SSD5_R_DN")
	)
	(segment
		(start 144.787366 -70.376034)
		(end 145.882614 -71.471282)
		(width 0.1651)
		(layer "In13.Cu")
		(net "CLK_100M_DB800ZL_SSD5_R_DN")
	)
	(segment
		(start 143.1163 -72.051672)
		(end 144.186148 -73.12152)
		(width 0.1651)
		(layer "In13.Cu")
		(net "CLK_100M_DB800ZL_SSD5_R_DN")
	)
	(segment
		(start 143.1163 -71.849996)
		(end 143.1163 -72.051672)
		(width 0.1651)
		(layer "In13.Cu")
		(net "CLK_100M_DB800ZL_SSD5_R_DN")
	)
	(segment
		(start 146.900138 -68.052442)
		(end 146.466814 -68.485766)
		(width 0.1651)
		(layer "In13.Cu")
		(net "CLK_100M_DB800ZL_SSD5_R_DN")
	)
	(segment
		(start 147.5613 -69.792596)
		(end 147.5613 -70.22846)
		(width 0.1651)
		(layer "In13.Cu")
		(net "CLK_100M_DB800ZL_SSD5_R_DN")
	)
	(segment
		(start 145.882614 -71.907146)
		(end 145.28546 -72.5043)
		(width 0.1651)
		(layer "In13.Cu")
		(net "CLK_100M_DB800ZL_SSD5_R_DN")
	)
	(segment
		(start 154.26817 -63.521844)
		(end 148.643086 -69.146928)
		(width 0.1651)
		(layer "In13.Cu")
		(net "CLK_100M_DB800ZL_SSD5_R_DN")
	)
	(segment
		(start 145.433034 -69.730366)
		(end 145.225262 -69.730366)
		(width 0.1651)
		(layer "In13.Cu")
		(net "CLK_100M_DB800ZL_SSD5_R_DN")
	)
	(segment
		(start 148.206968 -69.146928)
		(end 147.112482 -68.052442)
		(width 0.1651)
		(layer "In13.Cu")
		(net "CLK_100M_DB800ZL_SSD5_R_DN")
	)
	(segment
		(start 158.001716 -38.502082)
		(end 158.001716 -39.42461)
		(width 0.1651)
		(layer "In13.Cu")
		(net "CLK_100M_DB800ZL_SSD5_R_DN")
	)
	(segment
		(start 160.023302 -27.06624)
		(end 160.023302 -36.480496)
		(width 0.1651)
		(layer "In13.Cu")
		(net "CLK_100M_DB800ZL_SSD5_R_DN")
	)
	(segment
		(start 145.225262 -69.730366)
		(end 144.787366 -70.168262)
		(width 0.1651)
		(layer "In13.Cu")
		(net "CLK_100M_DB800ZL_SSD5_R_DN")
	)
	(segment
		(start 145.28546 -72.5043)
		(end 144.849596 -72.5043)
		(width 0.1651)
		(layer "In13.Cu")
		(net "CLK_100M_DB800ZL_SSD5_R_DN")
	)
	(segment
		(start 144.849596 -72.5043)
		(end 143.754348 -71.409052)
		(width 0.1651)
		(layer "In13.Cu")
		(net "CLK_100M_DB800ZL_SSD5_R_DN")
	)
	(segment
		(start 154.055572 -43.371008)
		(end 153.813764 -50.835052)
		(width 0.1651)
		(layer "In13.Cu")
		(net "CLK_100M_DB800ZL_SSD5_R_DN")
	)
	(segment
		(start 119.150384 -86.15045)
		(end 118.229126 -87.071708)
		(width 0.1651)
		(layer "In13.Cu")
		(net "CLK_100M_DB800ZL_SSD5_R_DN")
	)
	(segment
		(start 158.001716 -39.42461)
		(end 154.055572 -43.371008)
		(width 0.1651)
		(layer "In13.Cu")
		(net "CLK_100M_DB800ZL_SSD5_R_DN")
	)
	(segment
		(start 144.787366 -70.168262)
		(end 144.787366 -70.376034)
		(width 0.1651)
		(layer "In13.Cu")
		(net "CLK_100M_DB800ZL_SSD5_R_DN")
	)
	(segment
		(start 153.813764 -50.835052)
		(end 154.440636 -61.29147)
		(width 0.1651)
		(layer "In13.Cu")
		(net "CLK_100M_DB800ZL_SSD5_R_DN")
	)
	(segment
		(start 117.368066 -87.071708)
		(end 117.0813 -87.358474)
		(width 0.1651)
		(layer "In13.Cu")
		(net "CLK_100M_DB800ZL_SSD5_R_DN")
	)
	(segment
		(start 159.730948 -26.773886)
		(end 160.023302 -27.06624)
		(width 0.1651)
		(layer "In13.Cu")
		(net "CLK_100M_DB800ZL_SSD5_R_DN")
	)
	(segment
		(start 145.882614 -71.471282)
		(end 145.882614 -71.907146)
		(width 0.1651)
		(layer "In13.Cu")
		(net "CLK_100M_DB800ZL_SSD5_R_DN")
	)
	(segment
		(start 146.466814 -68.485766)
		(end 146.466814 -68.69811)
		(width 0.1651)
		(layer "In13.Cu")
		(net "CLK_100M_DB800ZL_SSD5_R_DN")
	)
	(segment
		(start 160.023302 -36.480496)
		(end 158.001716 -38.502082)
		(width 0.1651)
		(layer "In13.Cu")
		(net "CLK_100M_DB800ZL_SSD5_R_DN")
	)
	(segment
		(start 118.229126 -87.071708)
		(end 117.368066 -87.071708)
		(width 0.1651)
		(layer "In13.Cu")
		(net "CLK_100M_DB800ZL_SSD5_R_DN")
	)
	(segment
		(start 159.08147 -26.479246)
		(end 159.37611 -26.773886)
		(width 0.1651)
		(layer "In13.Cu")
		(net "CLK_100M_DB800ZL_SSD5_R_DN")
	)
	(segment
		(start 148.643086 -69.146928)
		(end 148.206968 -69.146928)
		(width 0.1651)
		(layer "In13.Cu")
		(net "CLK_100M_DB800ZL_SSD5_R_DN")
	)
	(segment
		(start 143.557244 -71.409052)
		(end 143.1163 -71.849996)
		(width 0.1651)
		(layer "In13.Cu")
		(net "CLK_100M_DB800ZL_SSD5_R_DN")
	)
	(segment
		(start 147.5613 -70.22846)
		(end 146.964146 -70.825614)
		(width 0.1651)
		(layer "In13.Cu")
		(net "CLK_100M_DB800ZL_SSD5_R_DN")
	)
	(segment
		(start 144.186148 -73.12152)
		(end 144.186148 -73.535032)
		(width 0.1651)
		(layer "In13.Cu")
		(net "CLK_100M_DB800ZL_SSD5_R_DN")
	)
	(segment
		(start 159.37611 -26.773886)
		(end 159.730948 -26.773886)
		(width 0.1651)
		(layer "In13.Cu")
		(net "CLK_100M_DB800ZL_SSD5_R_DN")
	)
	(segment
		(start 129.110994 -77.856334)
		(end 120.816878 -86.15045)
		(width 0.1651)
		(layer "In13.Cu")
		(net "CLK_100M_DB800ZL_SSD5_R_DN")
	)
	(segment
		(start 143.754348 -71.409052)
		(end 143.557244 -71.409052)
		(width 0.1651)
		(layer "In13.Cu")
		(net "CLK_100M_DB800ZL_SSD5_R_DN")
	)
	(segment
		(start 154.440636 -61.29147)
		(end 154.26817 -63.521844)
		(width 0.1651)
		(layer "In13.Cu")
		(net "CLK_100M_DB800ZL_SSD5_R_DN")
	)
	(segment
		(start 147.112482 -68.052442)
		(end 146.900138 -68.052442)
		(width 0.1651)
		(layer "In13.Cu")
		(net "CLK_100M_DB800ZL_SSD5_R_DN")
	)
	(segment
		(start 117.0813 -87.358474)
		(end 117.0813 -87.358982)
		(width 0.1651)
		(layer "In13.Cu")
		(net "CLK_100M_DB800ZL_SSD5_R_DN")
	)
	(segment
		(start 120.816878 -86.15045)
		(end 119.150384 -86.15045)
		(width 0.1651)
		(layer "In13.Cu")
		(net "CLK_100M_DB800ZL_SSD5_R_DN")
	)
	(segment
		(start 146.466814 -68.69811)
		(end 147.5613 -69.792596)
		(width 0.1651)
		(layer "In13.Cu")
		(net "CLK_100M_DB800ZL_SSD5_R_DN")
	)
	(segment
		(start 144.186148 -73.535032)
		(end 139.864846 -77.856334)
		(width 0.1651)
		(layer "In13.Cu")
		(net "CLK_100M_DB800ZL_SSD5_R_DN")
	)
	(segment
		(start 146.964146 -70.825614)
		(end 146.528282 -70.825614)
		(width 0.1651)
		(layer "In13.Cu")
		(net "CLK_100M_DB800ZL_SSD5_R_DN")
	)
	(segment
		(start 369.808506 -257.102102)
		(end 370.281708 -257.102102)
		(width 0.13208)
		(layer "F.Cu")
		(net "PEX3_SYS_ERR_R_N")
	)
	(segment
		(start 369.152932 -255.399032)
		(end 369.152932 -256.941574)
		(width 0.13208)
		(layer "F.Cu")
		(net "PEX3_SYS_ERR_R_N")
	)
	(segment
		(start 370.653818 -257.474212)
		(end 370.653818 -258.349496)
		(width 0.13208)
		(layer "F.Cu")
		(net "PEX3_SYS_ERR_R_N")
	)
	(segment
		(start 369.39855 -255.153414)
		(end 369.152932 -255.399032)
		(width 0.13208)
		(layer "F.Cu")
		(net "PEX3_SYS_ERR_R_N")
	)
	(segment
		(start 370.471954 -258.53136)
		(end 370.471954 -259.346192)
		(width 0.13208)
		(layer "F.Cu")
		(net "PEX3_SYS_ERR_R_N")
	)
	(segment
		(start 369.152932 -256.941574)
		(end 369.31346 -257.102102)
		(width 0.13208)
		(layer "F.Cu")
		(net "PEX3_SYS_ERR_R_N")
	)
	(segment
		(start 370.281708 -257.102102)
		(end 370.653818 -257.474212)
		(width 0.13208)
		(layer "F.Cu")
		(net "PEX3_SYS_ERR_R_N")
	)
	(segment
		(start 369.31346 -257.102102)
		(end 369.808506 -257.102102)
		(width 0.13208)
		(layer "F.Cu")
		(net "PEX3_SYS_ERR_R_N")
	)
	(segment
		(start 370.653818 -258.349496)
		(end 370.471954 -258.53136)
		(width 0.13208)
		(layer "F.Cu")
		(net "PEX3_SYS_ERR_R_N")
	)
	(segment
		(start 369.813586 -255.153414)
		(end 369.39855 -255.153414)
		(width 0.13208)
		(layer "F.Cu")
		(net "PEX3_SYS_ERR_R_N")
	)
	(via
		(at 370.653818 -257.474212)
		(size 0.508)
		(drill 0.254)
		(layers "F.Cu" "B.Cu")
		(net "PEX3_SYS_ERR_R_N")
	)
	(segment
		(start 218.270836 -215.619838)
		(end 219.603066 -215.619838)
		(width 0.13208)
		(layer "F.Cu")
		(net "SMB_NIC7_SDA")
	)
	(segment
		(start 218.242896 -215.576912)
		(end 218.22791 -215.576912)
		(width 0.13208)
		(layer "F.Cu")
		(net "SMB_NIC7_SDA")
	)
	(segment
		(start 219.603066 -215.619838)
		(end 219.854018 -215.87079)
		(width 0.13208)
		(layer "F.Cu")
		(net "SMB_NIC7_SDA")
	)
	(segment
		(start 220.584268 -215.87079)
		(end 222.217742 -217.504264)
		(width 0.13208)
		(layer "F.Cu")
		(net "SMB_NIC7_SDA")
	)
	(segment
		(start 214.335106 -215.26246)
		(end 214.944706 -215.26246)
		(width 0.13208)
		(layer "F.Cu")
		(net "SMB_NIC7_SDA")
	)
	(segment
		(start 217.635836 -215.254586)
		(end 217.92057 -215.254586)
		(width 0.13208)
		(layer "F.Cu")
		(net "SMB_NIC7_SDA")
	)
	(segment
		(start 218.22791 -215.576912)
		(end 218.270836 -215.619838)
		(width 0.13208)
		(layer "F.Cu")
		(net "SMB_NIC7_SDA")
	)
	(segment
		(start 222.217742 -217.504264)
		(end 223.467676 -217.504264)
		(width 0.13208)
		(layer "F.Cu")
		(net "SMB_NIC7_SDA")
	)
	(segment
		(start 219.854018 -215.87079)
		(end 220.584268 -215.87079)
		(width 0.13208)
		(layer "F.Cu")
		(net "SMB_NIC7_SDA")
	)
	(segment
		(start 217.92057 -215.254586)
		(end 218.242896 -215.576912)
		(width 0.13208)
		(layer "F.Cu")
		(net "SMB_NIC7_SDA")
	)
	(via
		(at 219.854018 -215.87079)
		(size 0.762)
		(drill 0.381)
		(layers "F.Cu" "B.Cu")
		(net "SMB_NIC7_SDA")
	)
	(via
		(at 214.944706 -215.26246)
		(size 0.508)
		(drill 0.254)
		(layers "F.Cu" "B.Cu")
		(net "SMB_NIC7_SDA")
	)
	(via
		(at 218.22791 -215.576912)
		(size 0.508)
		(drill 0.254)
		(layers "F.Cu" "B.Cu")
		(net "SMB_NIC7_SDA")
	)
	(segment
		(start 215.04021 -214.755222)
		(end 214.944706 -214.850726)
		(width 0.15494)
		(layer "In7.Cu")
		(net "SMB_NIC7_SDA")
	)
	(segment
		(start 217.40622 -214.755222)
		(end 215.04021 -214.755222)
		(width 0.15494)
		(layer "In7.Cu")
		(net "SMB_NIC7_SDA")
	)
	(segment
		(start 218.22791 -215.576912)
		(end 217.40622 -214.755222)
		(width 0.15494)
		(layer "In7.Cu")
		(net "SMB_NIC7_SDA")
	)
	(segment
		(start 214.944706 -214.850726)
		(end 214.944706 -215.26246)
		(width 0.15494)
		(layer "In7.Cu")
		(net "SMB_NIC7_SDA")
	)
	(segment
		(start 340.995 -234.46105)
		(end 340.995 -235.077)
		(width 0.13208)
		(layer "F.Cu")
		(net "SSD1_PWR_EN_R")
	)
	(segment
		(start 46.514512 -65.92189)
		(end 46.514512 -65.100962)
		(width 0.13208)
		(layer "F.Cu")
		(net "SSD1_PWR_EN_R")
	)
	(segment
		(start 51.867054 -57.332626)
		(end 51.867054 -57.563766)
		(width 0.13208)
		(layer "F.Cu")
		(net "SSD1_PWR_EN_R")
	)
	(segment
		(start 51.867054 -57.332626)
		(end 51.867054 -56.354218)
		(width 0.13208)
		(layer "F.Cu")
		(net "SSD1_PWR_EN_R")
	)
	(segment
		(start 51.867054 -57.563766)
		(end 52.375562 -58.072274)
		(width 0.13208)
		(layer "F.Cu")
		(net "SSD1_PWR_EN_R")
	)
	(segment
		(start 50.658522 -55.144162)
		(end 51.867816 -56.353456)
		(width 0.13208)
		(layer "F.Cu")
		(net "SSD1_PWR_EN_R")
	)
	(segment
		(start 51.867054 -56.354218)
		(end 51.867816 -56.353456)
		(width 0.13208)
		(layer "F.Cu")
		(net "SSD1_PWR_EN_R")
	)
	(segment
		(start 50.14722 -55.144162)
		(end 50.658522 -55.144162)
		(width 0.13208)
		(layer "F.Cu")
		(net "SSD1_PWR_EN_R")
	)
	(via
		(at 60.348114 -207.077564)
		(size 0.508)
		(drill 0.254)
		(layers "F.Cu" "B.Cu")
		(net "SSD1_PWR_EN_R")
	)
	(via
		(at 46.514512 -65.100962)
		(size 0.508)
		(drill 0.254)
		(layers "F.Cu" "B.Cu")
		(net "SSD1_PWR_EN_R")
	)
	(via
		(at 52.375562 -58.072274)
		(size 0.508)
		(drill 0.254)
		(layers "F.Cu" "B.Cu")
		(net "SSD1_PWR_EN_R")
	)
	(via
		(at 340.995 -235.077)
		(size 0.508)
		(drill 0.254)
		(layers "F.Cu" "B.Cu")
		(net "SSD1_PWR_EN_R")
	)
	(segment
		(start 60.37453 -207.051148)
		(end 60.348114 -207.077564)
		(width 0.15494)
		(layer "In5.Cu")
		(net "SSD1_PWR_EN_R")
	)
	(segment
		(start 52.634134 -64.902334)
		(end 53.928772 -66.196972)
		(width 0.15494)
		(layer "In5.Cu")
		(net "SSD1_PWR_EN_R")
	)
	(segment
		(start 52.634134 -58.330846)
		(end 52.634134 -64.902334)
		(width 0.15494)
		(layer "In5.Cu")
		(net "SSD1_PWR_EN_R")
	)
	(segment
		(start 56.9468 -108.1278)
		(end 57.823608 -109.004608)
		(width 0.15494)
		(layer "In5.Cu")
		(net "SSD1_PWR_EN_R")
	)
	(segment
		(start 56.9468 -96.875346)
		(end 56.9468 -108.1278)
		(width 0.15494)
		(layer "In5.Cu")
		(net "SSD1_PWR_EN_R")
	)
	(segment
		(start 47.731426 -65.64376)
		(end 47.05731 -65.64376)
		(width 0.15494)
		(layer "In5.Cu")
		(net "SSD1_PWR_EN_R")
	)
	(segment
		(start 57.823608 -109.004608)
		(end 57.823608 -153.885392)
		(width 0.15494)
		(layer "In5.Cu")
		(net "SSD1_PWR_EN_R")
	)
	(segment
		(start 53.928772 -66.196972)
		(end 55.522622 -66.196972)
		(width 0.15494)
		(layer "In5.Cu")
		(net "SSD1_PWR_EN_R")
	)
	(segment
		(start 52.183284 -64.451484)
		(end 51.659536 -64.975232)
		(width 0.15494)
		(layer "In5.Cu")
		(net "SSD1_PWR_EN_R")
	)
	(segment
		(start 57.823608 -153.885392)
		(end 56.99506 -154.71394)
		(width 0.15494)
		(layer "In5.Cu")
		(net "SSD1_PWR_EN_R")
	)
	(segment
		(start 56.99506 -181.082188)
		(end 60.37453 -184.461658)
		(width 0.15494)
		(layer "In5.Cu")
		(net "SSD1_PWR_EN_R")
	)
	(segment
		(start 56.5404 -67.21475)
		(end 56.5404 -96.468946)
		(width 0.15494)
		(layer "In5.Cu")
		(net "SSD1_PWR_EN_R")
	)
	(segment
		(start 56.99506 -154.71394)
		(end 56.99506 -181.082188)
		(width 0.15494)
		(layer "In5.Cu")
		(net "SSD1_PWR_EN_R")
	)
	(segment
		(start 55.522622 -66.196972)
		(end 56.5404 -67.21475)
		(width 0.15494)
		(layer "In5.Cu")
		(net "SSD1_PWR_EN_R")
	)
	(segment
		(start 51.659536 -64.975232)
		(end 48.399954 -64.975232)
		(width 0.15494)
		(layer "In5.Cu")
		(net "SSD1_PWR_EN_R")
	)
	(segment
		(start 52.183284 -58.264552)
		(end 52.183284 -64.451484)
		(width 0.15494)
		(layer "In5.Cu")
		(net "SSD1_PWR_EN_R")
	)
	(segment
		(start 60.37453 -184.461658)
		(end 60.37453 -207.051148)
		(width 0.15494)
		(layer "In5.Cu")
		(net "SSD1_PWR_EN_R")
	)
	(segment
		(start 52.375562 -58.072274)
		(end 52.634134 -58.330846)
		(width 0.15494)
		(layer "In5.Cu")
		(net "SSD1_PWR_EN_R")
	)
	(segment
		(start 48.399954 -64.975232)
		(end 47.731426 -65.64376)
		(width 0.15494)
		(layer "In5.Cu")
		(net "SSD1_PWR_EN_R")
	)
	(segment
		(start 56.5404 -96.468946)
		(end 56.9468 -96.875346)
		(width 0.15494)
		(layer "In5.Cu")
		(net "SSD1_PWR_EN_R")
	)
	(segment
		(start 47.05731 -65.64376)
		(end 46.514512 -65.100962)
		(width 0.15494)
		(layer "In5.Cu")
		(net "SSD1_PWR_EN_R")
	)
	(segment
		(start 52.375562 -58.072274)
		(end 52.183284 -58.264552)
		(width 0.15494)
		(layer "In5.Cu")
		(net "SSD1_PWR_EN_R")
	)
	(segment
		(start 144.761712 -230.4415)
		(end 140.819886 -230.4415)
		(width 0.15494)
		(layer "In15.Cu")
		(net "SSD1_PWR_EN_R")
	)
	(segment
		(start 230.192326 -239.582198)
		(end 219.622116 -239.582198)
		(width 0.15494)
		(layer "In15.Cu")
		(net "SSD1_PWR_EN_R")
	)
	(segment
		(start 115.48999 -212.148928)
		(end 110.135162 -206.7941)
		(width 0.15494)
		(layer "In15.Cu")
		(net "SSD1_PWR_EN_R")
	)
	(segment
		(start 219.622116 -239.582198)
		(end 219.253054 -239.95126)
		(width 0.15494)
		(layer "In15.Cu")
		(net "SSD1_PWR_EN_R")
	)
	(segment
		(start 337.870292 -239.140238)
		(end 333.049372 -239.140238)
		(width 0.15494)
		(layer "In15.Cu")
		(net "SSD1_PWR_EN_R")
	)
	(segment
		(start 240.86566 -239.164876)
		(end 230.609648 -239.164876)
		(width 0.15494)
		(layer "In15.Cu")
		(net "SSD1_PWR_EN_R")
	)
	(segment
		(start 146.250406 -228.952806)
		(end 144.761712 -230.4415)
		(width 0.15494)
		(layer "In15.Cu")
		(net "SSD1_PWR_EN_R")
	)
	(segment
		(start 102.220268 -206.7941)
		(end 98.80092 -205.37805)
		(width 0.15494)
		(layer "In15.Cu")
		(net "SSD1_PWR_EN_R")
	)
	(segment
		(start 340.995 -235.077)
		(end 340.46287 -235.60913)
		(width 0.15494)
		(layer "In15.Cu")
		(net "SSD1_PWR_EN_R")
	)
	(segment
		(start 329.0189 -240.50117)
		(end 327.8632 -241.65687)
		(width 0.15494)
		(layer "In15.Cu")
		(net "SSD1_PWR_EN_R")
	)
	(segment
		(start 326.871584 -241.65687)
		(end 326.51954 -242.00866)
		(width 0.15494)
		(layer "In15.Cu")
		(net "SSD1_PWR_EN_R")
	)
	(segment
		(start 98.80092 -205.37805)
		(end 74.129392 -205.37805)
		(width 0.15494)
		(layer "In15.Cu")
		(net "SSD1_PWR_EN_R")
	)
	(segment
		(start 262.544052 -233.44886)
		(end 261.675372 -232.58018)
		(width 0.15494)
		(layer "In15.Cu")
		(net "SSD1_PWR_EN_R")
	)
	(segment
		(start 215.25865 -239.95126)
		(end 214.82177 -239.51438)
		(width 0.15494)
		(layer "In15.Cu")
		(net "SSD1_PWR_EN_R")
	)
	(segment
		(start 127.335534 -232.66273)
		(end 115.48999 -220.817186)
		(width 0.15494)
		(layer "In15.Cu")
		(net "SSD1_PWR_EN_R")
	)
	(segment
		(start 157.502606 -228.952806)
		(end 146.250406 -228.952806)
		(width 0.15494)
		(layer "In15.Cu")
		(net "SSD1_PWR_EN_R")
	)
	(segment
		(start 247.497346 -239.8776)
		(end 241.578384 -239.8776)
		(width 0.15494)
		(layer "In15.Cu")
		(net "SSD1_PWR_EN_R")
	)
	(segment
		(start 331.68844 -240.50117)
		(end 329.0189 -240.50117)
		(width 0.15494)
		(layer "In15.Cu")
		(net "SSD1_PWR_EN_R")
	)
	(segment
		(start 72.053958 -207.453484)
		(end 60.724034 -207.453484)
		(width 0.15494)
		(layer "In15.Cu")
		(net "SSD1_PWR_EN_R")
	)
	(segment
		(start 266.447524 -237.651036)
		(end 266.447524 -236.529626)
		(width 0.15494)
		(layer "In15.Cu")
		(net "SSD1_PWR_EN_R")
	)
	(segment
		(start 340.46287 -236.54766)
		(end 337.870292 -239.140238)
		(width 0.15494)
		(layer "In15.Cu")
		(net "SSD1_PWR_EN_R")
	)
	(segment
		(start 257.962146 -233.0958)
		(end 254.279146 -233.0958)
		(width 0.15494)
		(layer "In15.Cu")
		(net "SSD1_PWR_EN_R")
	)
	(segment
		(start 266.447524 -236.529626)
		(end 263.948418 -234.03052)
		(width 0.15494)
		(layer "In15.Cu")
		(net "SSD1_PWR_EN_R")
	)
	(segment
		(start 60.724034 -207.453484)
		(end 60.348114 -207.077564)
		(width 0.15494)
		(layer "In15.Cu")
		(net "SSD1_PWR_EN_R")
	)
	(segment
		(start 302.684434 -241.318288)
		(end 276.520656 -241.318288)
		(width 0.15494)
		(layer "In15.Cu")
		(net "SSD1_PWR_EN_R")
	)
	(segment
		(start 138.598656 -232.66273)
		(end 127.335534 -232.66273)
		(width 0.15494)
		(layer "In15.Cu")
		(net "SSD1_PWR_EN_R")
	)
	(segment
		(start 115.48999 -220.817186)
		(end 115.48999 -212.148928)
		(width 0.15494)
		(layer "In15.Cu")
		(net "SSD1_PWR_EN_R")
	)
	(segment
		(start 74.129392 -205.37805)
		(end 72.053958 -207.453484)
		(width 0.15494)
		(layer "In15.Cu")
		(net "SSD1_PWR_EN_R")
	)
	(segment
		(start 269.353792 -240.557304)
		(end 266.447524 -237.651036)
		(width 0.15494)
		(layer "In15.Cu")
		(net "SSD1_PWR_EN_R")
	)
	(segment
		(start 327.8632 -241.65687)
		(end 326.871584 -241.65687)
		(width 0.15494)
		(layer "In15.Cu")
		(net "SSD1_PWR_EN_R")
	)
	(segment
		(start 303.412398 -242.046252)
		(end 302.684434 -241.318288)
		(width 0.15494)
		(layer "In15.Cu")
		(net "SSD1_PWR_EN_R")
	)
	(segment
		(start 219.253054 -239.95126)
		(end 215.25865 -239.95126)
		(width 0.15494)
		(layer "In15.Cu")
		(net "SSD1_PWR_EN_R")
	)
	(segment
		(start 161.925 -233.3752)
		(end 157.502606 -228.952806)
		(width 0.15494)
		(layer "In15.Cu")
		(net "SSD1_PWR_EN_R")
	)
	(segment
		(start 333.049372 -239.140238)
		(end 331.68844 -240.50117)
		(width 0.15494)
		(layer "In15.Cu")
		(net "SSD1_PWR_EN_R")
	)
	(segment
		(start 140.819886 -230.4415)
		(end 138.598656 -232.66273)
		(width 0.15494)
		(layer "In15.Cu")
		(net "SSD1_PWR_EN_R")
	)
	(segment
		(start 110.135162 -206.7941)
		(end 102.220268 -206.7941)
		(width 0.15494)
		(layer "In15.Cu")
		(net "SSD1_PWR_EN_R")
	)
	(segment
		(start 185.608214 -233.3752)
		(end 161.925 -233.3752)
		(width 0.15494)
		(layer "In15.Cu")
		(net "SSD1_PWR_EN_R")
	)
	(segment
		(start 191.747394 -239.51438)
		(end 185.608214 -233.3752)
		(width 0.15494)
		(layer "In15.Cu")
		(net "SSD1_PWR_EN_R")
	)
	(segment
		(start 340.46287 -235.60913)
		(end 340.46287 -236.54766)
		(width 0.15494)
		(layer "In15.Cu")
		(net "SSD1_PWR_EN_R")
	)
	(segment
		(start 326.51954 -242.00866)
		(end 326.481948 -242.046252)
		(width 0.15494)
		(layer "In15.Cu")
		(net "SSD1_PWR_EN_R")
	)
	(segment
		(start 261.675372 -232.58018)
		(end 258.477766 -232.58018)
		(width 0.15494)
		(layer "In15.Cu")
		(net "SSD1_PWR_EN_R")
	)
	(segment
		(start 258.477766 -232.58018)
		(end 257.962146 -233.0958)
		(width 0.15494)
		(layer "In15.Cu")
		(net "SSD1_PWR_EN_R")
	)
	(segment
		(start 230.609648 -239.164876)
		(end 230.192326 -239.582198)
		(width 0.15494)
		(layer "In15.Cu")
		(net "SSD1_PWR_EN_R")
	)
	(segment
		(start 263.948418 -234.03052)
		(end 262.544052 -233.44886)
		(width 0.15494)
		(layer "In15.Cu")
		(net "SSD1_PWR_EN_R")
	)
	(segment
		(start 241.578384 -239.8776)
		(end 240.86566 -239.164876)
		(width 0.15494)
		(layer "In15.Cu")
		(net "SSD1_PWR_EN_R")
	)
	(segment
		(start 275.759672 -240.557304)
		(end 269.353792 -240.557304)
		(width 0.15494)
		(layer "In15.Cu")
		(net "SSD1_PWR_EN_R")
	)
	(segment
		(start 254.279146 -233.0958)
		(end 247.497346 -239.8776)
		(width 0.15494)
		(layer "In15.Cu")
		(net "SSD1_PWR_EN_R")
	)
	(segment
		(start 276.520656 -241.318288)
		(end 275.759672 -240.557304)
		(width 0.15494)
		(layer "In15.Cu")
		(net "SSD1_PWR_EN_R")
	)
	(segment
		(start 326.481948 -242.046252)
		(end 303.412398 -242.046252)
		(width 0.15494)
		(layer "In15.Cu")
		(net "SSD1_PWR_EN_R")
	)
	(segment
		(start 214.82177 -239.51438)
		(end 191.747394 -239.51438)
		(width 0.15494)
		(layer "In15.Cu")
		(net "SSD1_PWR_EN_R")
	)
	(segment
		(start 124.279152 -58.71972)
		(end 124.125228 -58.565796)
		(width 0.13208)
		(layer "F.Cu")
		(net "PWRGD_P3V3_SSD4")
	)
	(segment
		(start 124.279152 -59.177936)
		(end 124.279152 -58.71972)
		(width 0.13208)
		(layer "F.Cu")
		(net "PWRGD_P3V3_SSD4")
	)
	(segment
		(start 124.125228 -57.841896)
		(end 123.74118 -57.457848)
		(width 0.13208)
		(layer "F.Cu")
		(net "PWRGD_P3V3_SSD4")
	)
	(segment
		(start 123.74118 -57.457848)
		(end 123.74118 -57.16397)
		(width 0.13208)
		(layer "F.Cu")
		(net "PWRGD_P3V3_SSD4")
	)
	(segment
		(start 123.748292 -61.22416)
		(end 123.748292 -59.343544)
		(width 0.13208)
		(layer "F.Cu")
		(net "PWRGD_P3V3_SSD4")
	)
	(segment
		(start 123.748292 -59.343544)
		(end 123.9139 -59.177936)
		(width 0.13208)
		(layer "F.Cu")
		(net "PWRGD_P3V3_SSD4")
	)
	(segment
		(start 123.911106 -61.386974)
		(end 123.748292 -61.22416)
		(width 0.13208)
		(layer "F.Cu")
		(net "PWRGD_P3V3_SSD4")
	)
	(segment
		(start 123.9139 -59.177936)
		(end 124.279152 -59.177936)
		(width 0.13208)
		(layer "F.Cu")
		(net "PWRGD_P3V3_SSD4")
	)
	(segment
		(start 124.125228 -57.867296)
		(end 124.125228 -57.841896)
		(width 0.13208)
		(layer "F.Cu")
		(net "PWRGD_P3V3_SSD4")
	)
	(segment
		(start 124.125228 -58.565796)
		(end 124.125228 -57.867296)
		(width 0.13208)
		(layer "F.Cu")
		(net "PWRGD_P3V3_SSD4")
	)
	(via
		(at 124.125228 -57.867296)
		(size 0.508)
		(drill 0.254)
		(layers "F.Cu" "B.Cu")
		(net "PWRGD_P3V3_SSD4")
	)
	(segment
		(start 259.20446 -62.119764)
		(end 259.20446 -64.886332)
		(width 0.13208)
		(layer "F.Cu")
		(net "PWRGD_P12V_SSD9_R")
	)
	(segment
		(start 284.867858 -53.051456)
		(end 285.523178 -53.051456)
		(width 0.13208)
		(layer "F.Cu")
		(net "PWRGD_P12V_SSD9_R")
	)
	(segment
		(start 259.20446 -64.886332)
		(end 260.073648 -65.75552)
		(width 0.13208)
		(layer "F.Cu")
		(net "PWRGD_P12V_SSD9_R")
	)
	(segment
		(start 336.493866 -211.98713)
		(end 336.09407 -211.587334)
		(width 0.13208)
		(layer "F.Cu")
		(net "PWRGD_P12V_SSD9_R")
	)
	(segment
		(start 259.836412 -61.487812)
		(end 259.20446 -62.119764)
		(width 0.13208)
		(layer "F.Cu")
		(net "PWRGD_P12V_SSD9_R")
	)
	(segment
		(start 261.6835 -61.487812)
		(end 259.836412 -61.487812)
		(width 0.13208)
		(layer "F.Cu")
		(net "PWRGD_P12V_SSD9_R")
	)
	(segment
		(start 260.073648 -65.75552)
		(end 272.928588 -65.75552)
		(width 0.13208)
		(layer "F.Cu")
		(net "PWRGD_P12V_SSD9_R")
	)
	(via
		(at 272.928588 -65.75552)
		(size 0.508)
		(drill 0.254)
		(layers "F.Cu" "B.Cu")
		(net "PWRGD_P12V_SSD9_R")
	)
	(via
		(at 285.523178 -53.051456)
		(size 0.508)
		(drill 0.254)
		(layers "F.Cu" "B.Cu")
		(net "PWRGD_P12V_SSD9_R")
	)
	(via
		(at 336.09407 -211.587334)
		(size 0.4572)
		(drill 0.254)
		(layers "F.Cu" "B.Cu")
		(net "PWRGD_P12V_SSD9_R")
	)
	(segment
		(start 331.550518 -158.64332)
		(end 330.486258 -159.70758)
		(width 0.15494)
		(layer "In5.Cu")
		(net "PWRGD_P12V_SSD9_R")
	)
	(segment
		(start 328.717656 -208.386934)
		(end 331.528674 -208.386934)
		(width 0.15494)
		(layer "In5.Cu")
		(net "PWRGD_P12V_SSD9_R")
	)
	(segment
		(start 330.486258 -189.14999)
		(end 329.977496 -189.658752)
		(width 0.15494)
		(layer "In5.Cu")
		(net "PWRGD_P12V_SSD9_R")
	)
	(segment
		(start 309.460138 -95.740474)
		(end 309.460138 -105.707942)
		(width 0.15494)
		(layer "In5.Cu")
		(net "PWRGD_P12V_SSD9_R")
	)
	(segment
		(start 277.941278 -64.008254)
		(end 276.194012 -65.75552)
		(width 0.15494)
		(layer "In5.Cu")
		(net "PWRGD_P12V_SSD9_R")
	)
	(segment
		(start 326.223122 -205.8924)
		(end 328.717656 -208.386934)
		(width 0.15494)
		(layer "In5.Cu")
		(net "PWRGD_P12V_SSD9_R")
	)
	(segment
		(start 283.461206 -55.113428)
		(end 283.461206 -57.501028)
		(width 0.15494)
		(layer "In5.Cu")
		(net "PWRGD_P12V_SSD9_R")
	)
	(segment
		(start 293.381684 -76.38034)
		(end 297.331384 -80.33004)
		(width 0.15494)
		(layer "In5.Cu")
		(net "PWRGD_P12V_SSD9_R")
	)
	(segment
		(start 309.913274 -106.161078)
		(end 309.913274 -121.484136)
		(width 0.15494)
		(layer "In5.Cu")
		(net "PWRGD_P12V_SSD9_R")
	)
	(segment
		(start 283.943806 -63.571374)
		(end 283.506926 -64.008254)
		(width 0.15494)
		(layer "In5.Cu")
		(net "PWRGD_P12V_SSD9_R")
	)
	(segment
		(start 298.471336 -80.33004)
		(end 299.444664 -81.303368)
		(width 0.15494)
		(layer "In5.Cu")
		(net "PWRGD_P12V_SSD9_R")
	)
	(segment
		(start 276.194012 -65.75552)
		(end 272.928588 -65.75552)
		(width 0.15494)
		(layer "In5.Cu")
		(net "PWRGD_P12V_SSD9_R")
	)
	(segment
		(start 332.892908 -209.751168)
		(end 334.257904 -209.751168)
		(width 0.15494)
		(layer "In5.Cu")
		(net "PWRGD_P12V_SSD9_R")
	)
	(segment
		(start 285.523178 -53.051456)
		(end 283.461206 -55.113428)
		(width 0.15494)
		(layer "In5.Cu")
		(net "PWRGD_P12V_SSD9_R")
	)
	(segment
		(start 291.65042 -65.0113)
		(end 293.381684 -66.742564)
		(width 0.15494)
		(layer "In5.Cu")
		(net "PWRGD_P12V_SSD9_R")
	)
	(segment
		(start 330.707238 -143.152622)
		(end 331.550518 -143.995902)
		(width 0.15494)
		(layer "In5.Cu")
		(net "PWRGD_P12V_SSD9_R")
	)
	(segment
		(start 286.59201 -55.965852)
		(end 286.59201 -64.354202)
		(width 0.15494)
		(layer "In5.Cu")
		(net "PWRGD_P12V_SSD9_R")
	)
	(segment
		(start 297.331384 -80.33004)
		(end 298.471336 -80.33004)
		(width 0.15494)
		(layer "In5.Cu")
		(net "PWRGD_P12V_SSD9_R")
	)
	(segment
		(start 309.460138 -105.707942)
		(end 309.913274 -106.161078)
		(width 0.15494)
		(layer "In5.Cu")
		(net "PWRGD_P12V_SSD9_R")
	)
	(segment
		(start 285.523178 -53.051456)
		(end 286.283908 -53.812186)
		(width 0.15494)
		(layer "In5.Cu")
		(net "PWRGD_P12V_SSD9_R")
	)
	(segment
		(start 330.486258 -159.70758)
		(end 330.486258 -189.14999)
		(width 0.15494)
		(layer "In5.Cu")
		(net "PWRGD_P12V_SSD9_R")
	)
	(segment
		(start 308.60111 -92.905326)
		(end 308.60111 -94.881446)
		(width 0.15494)
		(layer "In5.Cu")
		(net "PWRGD_P12V_SSD9_R")
	)
	(segment
		(start 326.223122 -201.989182)
		(end 326.223122 -205.8924)
		(width 0.15494)
		(layer "In5.Cu")
		(net "PWRGD_P12V_SSD9_R")
	)
	(segment
		(start 283.943806 -57.983628)
		(end 283.943806 -63.571374)
		(width 0.15494)
		(layer "In5.Cu")
		(net "PWRGD_P12V_SSD9_R")
	)
	(segment
		(start 286.283908 -55.65775)
		(end 286.59201 -55.965852)
		(width 0.15494)
		(layer "In5.Cu")
		(net "PWRGD_P12V_SSD9_R")
	)
	(segment
		(start 329.977496 -198.234808)
		(end 326.223122 -201.989182)
		(width 0.15494)
		(layer "In5.Cu")
		(net "PWRGD_P12V_SSD9_R")
	)
	(segment
		(start 283.506926 -64.008254)
		(end 277.941278 -64.008254)
		(width 0.15494)
		(layer "In5.Cu")
		(net "PWRGD_P12V_SSD9_R")
	)
	(segment
		(start 299.444664 -81.303368)
		(end 299.444664 -83.74888)
		(width 0.15494)
		(layer "In5.Cu")
		(net "PWRGD_P12V_SSD9_R")
	)
	(segment
		(start 329.977496 -189.658752)
		(end 329.977496 -198.234808)
		(width 0.15494)
		(layer "In5.Cu")
		(net "PWRGD_P12V_SSD9_R")
	)
	(segment
		(start 328.878692 -143.152622)
		(end 330.707238 -143.152622)
		(width 0.15494)
		(layer "In5.Cu")
		(net "PWRGD_P12V_SSD9_R")
	)
	(segment
		(start 309.913274 -121.484136)
		(end 320.049398 -131.62026)
		(width 0.15494)
		(layer "In5.Cu")
		(net "PWRGD_P12V_SSD9_R")
	)
	(segment
		(start 299.444664 -83.74888)
		(end 308.60111 -92.905326)
		(width 0.15494)
		(layer "In5.Cu")
		(net "PWRGD_P12V_SSD9_R")
	)
	(segment
		(start 308.60111 -94.881446)
		(end 309.460138 -95.740474)
		(width 0.15494)
		(layer "In5.Cu")
		(net "PWRGD_P12V_SSD9_R")
	)
	(segment
		(start 334.257904 -209.751168)
		(end 336.09407 -211.587334)
		(width 0.15494)
		(layer "In5.Cu")
		(net "PWRGD_P12V_SSD9_R")
	)
	(segment
		(start 286.59201 -64.354202)
		(end 287.249108 -65.0113)
		(width 0.15494)
		(layer "In5.Cu")
		(net "PWRGD_P12V_SSD9_R")
	)
	(segment
		(start 286.283908 -53.812186)
		(end 286.283908 -55.65775)
		(width 0.15494)
		(layer "In5.Cu")
		(net "PWRGD_P12V_SSD9_R")
	)
	(segment
		(start 331.550518 -143.995902)
		(end 331.550518 -158.64332)
		(width 0.15494)
		(layer "In5.Cu")
		(net "PWRGD_P12V_SSD9_R")
	)
	(segment
		(start 287.249108 -65.0113)
		(end 291.65042 -65.0113)
		(width 0.15494)
		(layer "In5.Cu")
		(net "PWRGD_P12V_SSD9_R")
	)
	(segment
		(start 331.528674 -208.386934)
		(end 332.892908 -209.751168)
		(width 0.15494)
		(layer "In5.Cu")
		(net "PWRGD_P12V_SSD9_R")
	)
	(segment
		(start 320.049398 -131.62026)
		(end 320.049398 -134.323328)
		(width 0.15494)
		(layer "In5.Cu")
		(net "PWRGD_P12V_SSD9_R")
	)
	(segment
		(start 283.461206 -57.501028)
		(end 283.943806 -57.983628)
		(width 0.15494)
		(layer "In5.Cu")
		(net "PWRGD_P12V_SSD9_R")
	)
	(segment
		(start 320.049398 -134.323328)
		(end 328.878692 -143.152622)
		(width 0.15494)
		(layer "In5.Cu")
		(net "PWRGD_P12V_SSD9_R")
	)
	(segment
		(start 293.381684 -66.742564)
		(end 293.381684 -76.38034)
		(width 0.15494)
		(layer "In5.Cu")
		(net "PWRGD_P12V_SSD9_R")
	)
	(segment
		(start 41.941496 -26.77668)
		(end 41.754806 -26.58999)
		(width 0.13462)
		(layer "F.Cu")
		(net "CLK_100M_DB800ZL_SSD1_R_DN")
	)
	(segment
		(start 41.754806 -26.58999)
		(end 41.26484 -26.58999)
		(width 0.13462)
		(layer "F.Cu")
		(net "CLK_100M_DB800ZL_SSD1_R_DN")
	)
	(segment
		(start 108.496354 -79.422244)
		(end 108.1786 -79.10449)
		(width 0.13462)
		(layer "F.Cu")
		(net "CLK_100M_DB800ZL_SSD1_R_DN")
	)
	(segment
		(start 42.981372 -26.479246)
		(end 42.683938 -26.77668)
		(width 0.13462)
		(layer "F.Cu")
		(net "CLK_100M_DB800ZL_SSD1_R_DN")
	)
	(segment
		(start 108.1786 -79.10449)
		(end 108.1786 -78.389734)
		(width 0.13462)
		(layer "F.Cu")
		(net "CLK_100M_DB800ZL_SSD1_R_DN")
	)
	(segment
		(start 42.683938 -26.77668)
		(end 41.941496 -26.77668)
		(width 0.13462)
		(layer "F.Cu")
		(net "CLK_100M_DB800ZL_SSD1_R_DN")
	)
	(segment
		(start 108.1786 -78.389734)
		(end 108.470954 -78.09738)
		(width 0.13462)
		(layer "F.Cu")
		(net "CLK_100M_DB800ZL_SSD1_R_DN")
	)
	(via
		(at 42.981372 -26.479246)
		(size 0.508)
		(drill 0.254)
		(layers "F.Cu" "B.Cu")
		(net "CLK_100M_DB800ZL_SSD1_R_DN")
	)
	(via
		(at 108.470954 -78.09738)
		(size 0.508)
		(drill 0.254)
		(layers "F.Cu" "B.Cu")
		(net "CLK_100M_DB800ZL_SSD1_R_DN")
	)
	(segment
		(start 48.74006 -27.99588)
		(end 50.59934 -29.85516)
		(width 0.1651)
		(layer "In13.Cu")
		(net "CLK_100M_DB800ZL_SSD1_R_DN")
	)
	(segment
		(start 43.271186 -26.76906)
		(end 43.863768 -26.76906)
		(width 0.1651)
		(layer "In13.Cu")
		(net "CLK_100M_DB800ZL_SSD1_R_DN")
	)
	(segment
		(start 90.41384 -75.18146)
		(end 91.68384 -76.45146)
		(width 0.1651)
		(layer "In13.Cu")
		(net "CLK_100M_DB800ZL_SSD1_R_DN")
	)
	(segment
		(start 103.26116 -76.45146)
		(end 104.35082 -75.3618)
		(width 0.1651)
		(layer "In13.Cu")
		(net "CLK_100M_DB800ZL_SSD1_R_DN")
	)
	(segment
		(start 42.981372 -26.479246)
		(end 43.271186 -26.76906)
		(width 0.1651)
		(layer "In13.Cu")
		(net "CLK_100M_DB800ZL_SSD1_R_DN")
	)
	(segment
		(start 107.0864 -75.3618)
		(end 108.180124 -76.455524)
		(width 0.1651)
		(layer "In13.Cu")
		(net "CLK_100M_DB800ZL_SSD1_R_DN")
	)
	(segment
		(start 46.949868 -27.639772)
		(end 48.74006 -27.99588)
		(width 0.1651)
		(layer "In13.Cu")
		(net "CLK_100M_DB800ZL_SSD1_R_DN")
	)
	(segment
		(start 91.68384 -76.45146)
		(end 103.26116 -76.45146)
		(width 0.1651)
		(layer "In13.Cu")
		(net "CLK_100M_DB800ZL_SSD1_R_DN")
	)
	(segment
		(start 66.46164 -75.18146)
		(end 90.41384 -75.18146)
		(width 0.1651)
		(layer "In13.Cu")
		(net "CLK_100M_DB800ZL_SSD1_R_DN")
	)
	(segment
		(start 63.93434 -56.795162)
		(end 63.93434 -72.65416)
		(width 0.1651)
		(layer "In13.Cu")
		(net "CLK_100M_DB800ZL_SSD1_R_DN")
	)
	(segment
		(start 50.59934 -29.85516)
		(end 50.59934 -33.51276)
		(width 0.1651)
		(layer "In13.Cu")
		(net "CLK_100M_DB800ZL_SSD1_R_DN")
	)
	(segment
		(start 45.757592 -27.145488)
		(end 46.949868 -27.639772)
		(width 0.1651)
		(layer "In13.Cu")
		(net "CLK_100M_DB800ZL_SSD1_R_DN")
	)
	(segment
		(start 50.59934 -33.51276)
		(end 63.420498 -46.333918)
		(width 0.1651)
		(layer "In13.Cu")
		(net "CLK_100M_DB800ZL_SSD1_R_DN")
	)
	(segment
		(start 108.180124 -77.80655)
		(end 108.470954 -78.09738)
		(width 0.1651)
		(layer "In13.Cu")
		(net "CLK_100M_DB800ZL_SSD1_R_DN")
	)
	(segment
		(start 104.35082 -75.3618)
		(end 107.0864 -75.3618)
		(width 0.1651)
		(layer "In13.Cu")
		(net "CLK_100M_DB800ZL_SSD1_R_DN")
	)
	(segment
		(start 43.863768 -26.76906)
		(end 45.757592 -27.145488)
		(width 0.1651)
		(layer "In13.Cu")
		(net "CLK_100M_DB800ZL_SSD1_R_DN")
	)
	(segment
		(start 63.93434 -72.65416)
		(end 66.46164 -75.18146)
		(width 0.1651)
		(layer "In13.Cu")
		(net "CLK_100M_DB800ZL_SSD1_R_DN")
	)
	(segment
		(start 108.180124 -76.455524)
		(end 108.180124 -77.80655)
		(width 0.1651)
		(layer "In13.Cu")
		(net "CLK_100M_DB800ZL_SSD1_R_DN")
	)
	(segment
		(start 63.420498 -46.333918)
		(end 63.93434 -56.795162)
		(width 0.1651)
		(layer "In13.Cu")
		(net "CLK_100M_DB800ZL_SSD1_R_DN")
	)
	(segment
		(start 60.599828 -282.599892)
		(end 61.074808 -283.074872)
		(width 0.1651)
		(layer "F.Cu")
		(net "PEX0_DBG_MODE3")
	)
	(segment
		(start 28.406344 -251.158502)
		(end 28.406344 -250.470924)
		(width 0.13208)
		(layer "F.Cu")
		(net "PEX0_DBG_MODE3")
	)
	(segment
		(start 28.406344 -251.956824)
		(end 28.406344 -251.158502)
		(width 0.13208)
		(layer "F.Cu")
		(net "PEX0_DBG_MODE3")
	)
	(via
		(at 61.074808 -283.074872)
		(size 0.4064)
		(drill 0.2032)
		(layers "F.Cu" "B.Cu")
		(net "PEX0_DBG_MODE3")
	)
	(via
		(at 28.406344 -251.158502)
		(size 0.508)
		(drill 0.254)
		(layers "F.Cu" "B.Cu")
		(net "PEX0_DBG_MODE3")
	)
	(segment
		(start 33.8709 -260.387846)
		(end 33.8709 -259.219446)
		(width 0.13208)
		(layer "B.Cu")
		(net "PEX0_DBG_MODE3")
	)
	(segment
		(start 33.8709 -259.219446)
		(end 31.521654 -256.8702)
		(width 0.13208)
		(layer "B.Cu")
		(net "PEX0_DBG_MODE3")
	)
	(segment
		(start 31.521654 -256.8702)
		(end 30.3276 -256.8702)
		(width 0.13208)
		(layer "B.Cu")
		(net "PEX0_DBG_MODE3")
	)
	(segment
		(start 27.9146 -251.650246)
		(end 28.406344 -251.158502)
		(width 0.13208)
		(layer "B.Cu")
		(net "PEX0_DBG_MODE3")
	)
	(segment
		(start 30.3276 -256.8702)
		(end 27.9146 -254.4572)
		(width 0.13208)
		(layer "B.Cu")
		(net "PEX0_DBG_MODE3")
	)
	(segment
		(start 50.677064 -261.1882)
		(end 34.671254 -261.1882)
		(width 0.13208)
		(layer "B.Cu")
		(net "PEX0_DBG_MODE3")
	)
	(segment
		(start 61.074808 -283.074872)
		(end 61.074808 -271.585944)
		(width 0.13208)
		(layer "B.Cu")
		(net "PEX0_DBG_MODE3")
	)
	(segment
		(start 58.639202 -269.150338)
		(end 57.647332 -268.158468)
		(width 0.13208)
		(layer "B.Cu")
		(net "PEX0_DBG_MODE3")
	)
	(segment
		(start 56.893968 -267.307568)
		(end 56.796432 -267.307568)
		(width 0.13208)
		(layer "B.Cu")
		(net "PEX0_DBG_MODE3")
	)
	(segment
		(start 27.9146 -254.4572)
		(end 27.9146 -251.650246)
		(width 0.13208)
		(layer "B.Cu")
		(net "PEX0_DBG_MODE3")
	)
	(segment
		(start 58.639202 -269.281656)
		(end 58.639202 -269.150338)
		(width 0.13208)
		(layer "B.Cu")
		(net "PEX0_DBG_MODE3")
	)
	(segment
		(start 57.647332 -268.060932)
		(end 56.893968 -267.307568)
		(width 0.13208)
		(layer "B.Cu")
		(net "PEX0_DBG_MODE3")
	)
	(segment
		(start 56.796432 -267.307568)
		(end 50.677064 -261.1882)
		(width 0.13208)
		(layer "B.Cu")
		(net "PEX0_DBG_MODE3")
	)
	(segment
		(start 61.074808 -271.585944)
		(end 58.956956 -269.468092)
		(width 0.13208)
		(layer "B.Cu")
		(net "PEX0_DBG_MODE3")
	)
	(segment
		(start 57.647332 -268.158468)
		(end 57.647332 -268.060932)
		(width 0.13208)
		(layer "B.Cu")
		(net "PEX0_DBG_MODE3")
	)
	(segment
		(start 58.956956 -269.468092)
		(end 58.825638 -269.468092)
		(width 0.13208)
		(layer "B.Cu")
		(net "PEX0_DBG_MODE3")
	)
	(segment
		(start 58.825638 -269.468092)
		(end 58.639202 -269.281656)
		(width 0.13208)
		(layer "B.Cu")
		(net "PEX0_DBG_MODE3")
	)
	(segment
		(start 34.671254 -261.1882)
		(end 33.8709 -260.387846)
		(width 0.13208)
		(layer "B.Cu")
		(net "PEX0_DBG_MODE3")
	)
	(segment
		(start 409.849828 -282.599892)
		(end 410.324808 -283.074872)
		(width 0.1651)
		(layer "F.Cu")
		(net "PEX3_MODE_SEL0")
	)
	(segment
		(start 378.738384 -251.158502)
		(end 378.738384 -250.470924)
		(width 0.13208)
		(layer "F.Cu")
		(net "PEX3_MODE_SEL0")
	)
	(segment
		(start 378.738384 -251.956824)
		(end 378.738384 -251.158502)
		(width 0.13208)
		(layer "F.Cu")
		(net "PEX3_MODE_SEL0")
	)
	(via
		(at 378.738384 -251.158502)
		(size 0.508)
		(drill 0.254)
		(layers "F.Cu" "B.Cu")
		(net "PEX3_MODE_SEL0")
	)
	(via
		(at 410.324808 -283.074872)
		(size 0.4064)
		(drill 0.2032)
		(layers "F.Cu" "B.Cu")
		(net "PEX3_MODE_SEL0")
	)
	(segment
		(start 411.27045 -271.947386)
		(end 411.27045 -282.12923)
		(width 0.13208)
		(layer "B.Cu")
		(net "PEX3_MODE_SEL0")
	)
	(segment
		(start 378.198634 -253.674626)
		(end 379.803406 -255.279398)
		(width 0.13208)
		(layer "B.Cu")
		(net "PEX3_MODE_SEL0")
	)
	(segment
		(start 411.27045 -282.12923)
		(end 410.324808 -283.074872)
		(width 0.13208)
		(layer "B.Cu")
		(net "PEX3_MODE_SEL0")
	)
	(segment
		(start 406.909016 -267.725652)
		(end 407.319988 -267.725652)
		(width 0.13208)
		(layer "B.Cu")
		(net "PEX3_MODE_SEL0")
	)
	(segment
		(start 381.066548 -255.677416)
		(end 383.190242 -255.677416)
		(width 0.13208)
		(layer "B.Cu")
		(net "PEX3_MODE_SEL0")
	)
	(segment
		(start 408.527758 -268.933422)
		(end 408.527758 -269.204694)
		(width 0.13208)
		(layer "B.Cu")
		(net "PEX3_MODE_SEL0")
	)
	(segment
		(start 378.738384 -251.158502)
		(end 378.198634 -251.698252)
		(width 0.13208)
		(layer "B.Cu")
		(net "PEX3_MODE_SEL0")
	)
	(segment
		(start 408.527758 -269.204694)
		(end 411.27045 -271.947386)
		(width 0.13208)
		(layer "B.Cu")
		(net "PEX3_MODE_SEL0")
	)
	(segment
		(start 407.319988 -267.725652)
		(end 408.527758 -268.933422)
		(width 0.13208)
		(layer "B.Cu")
		(net "PEX3_MODE_SEL0")
	)
	(segment
		(start 395.476222 -256.292858)
		(end 406.909016 -267.725652)
		(width 0.13208)
		(layer "B.Cu")
		(net "PEX3_MODE_SEL0")
	)
	(segment
		(start 383.190242 -255.677416)
		(end 383.805684 -256.292858)
		(width 0.13208)
		(layer "B.Cu")
		(net "PEX3_MODE_SEL0")
	)
	(segment
		(start 383.805684 -256.292858)
		(end 395.476222 -256.292858)
		(width 0.13208)
		(layer "B.Cu")
		(net "PEX3_MODE_SEL0")
	)
	(segment
		(start 379.803406 -255.279398)
		(end 380.66853 -255.279398)
		(width 0.13208)
		(layer "B.Cu")
		(net "PEX3_MODE_SEL0")
	)
	(segment
		(start 380.66853 -255.279398)
		(end 381.066548 -255.677416)
		(width 0.13208)
		(layer "B.Cu")
		(net "PEX3_MODE_SEL0")
	)
	(segment
		(start 378.198634 -251.698252)
		(end 378.198634 -253.674626)
		(width 0.13208)
		(layer "B.Cu")
		(net "PEX3_MODE_SEL0")
	)
	(segment
		(start 224.267776 -223.904048)
		(end 223.86798 -224.303844)
		(width 0.13208)
		(layer "F.Cu")
		(net "SMB_NIC0_SCL")
	)
	(via
		(at 223.86798 -224.303844)
		(size 0.4572)
		(drill 0.254)
		(layers "F.Cu" "B.Cu")
		(net "SMB_NIC0_SCL")
	)
	(via
		(at 222.77832 -225.393504)
		(size 0.6604)
		(drill 0.3302)
		(layers "F.Cu" "B.Cu")
		(net "SMB_NIC0_SCL")
	)
	(segment
		(start 222.322644 -230.825548)
		(end 222.322644 -225.84918)
		(width 0.13208)
		(layer "B.Cu")
		(net "SMB_NIC0_SCL")
	)
	(segment
		(start 222.322644 -225.84918)
		(end 222.77832 -225.393504)
		(width 0.13208)
		(layer "B.Cu")
		(net "SMB_NIC0_SCL")
	)
	(segment
		(start 222.77832 -225.393504)
		(end 223.86798 -224.303844)
		(width 0.13208)
		(layer "B.Cu")
		(net "SMB_NIC0_SCL")
	)
	(segment
		(start 338.455 -239.903)
		(end 339.09 -239.903)
		(width 0.13208)
		(layer "F.Cu")
		(net "RST_MB_PERST_2_ISO_N")
	)
	(segment
		(start 338.342986 -240.808002)
		(end 338.342986 -240.015014)
		(width 0.13208)
		(layer "F.Cu")
		(net "RST_MB_PERST_2_ISO_N")
	)
	(segment
		(start 339.09 -239.903)
		(end 339.344 -239.649)
		(width 0.13208)
		(layer "F.Cu")
		(net "RST_MB_PERST_2_ISO_N")
	)
	(segment
		(start 338.342986 -240.015014)
		(end 338.455 -239.903)
		(width 0.13208)
		(layer "F.Cu")
		(net "RST_MB_PERST_2_ISO_N")
	)
	(segment
		(start 339.344 -239.649)
		(end 339.344 -239.03305)
		(width 0.13208)
		(layer "F.Cu")
		(net "RST_MB_PERST_2_ISO_N")
	)
	(via
		(at 339.344 -239.649)
		(size 0.508)
		(drill 0.254)
		(layers "F.Cu" "B.Cu")
		(net "RST_MB_PERST_2_ISO_N")
	)
	(segment
		(start 41.26484 -25.390094)
		(end 40.191182 -25.390094)
		(width 0.13208)
		(layer "F.Cu")
		(net "SSD1_PWRDIS_R")
	)
	(segment
		(start 50.13452 -28.469082)
		(end 50.13452 -28.550108)
		(width 0.13208)
		(layer "F.Cu")
		(net "SSD1_PWRDIS_R")
	)
	(segment
		(start 50.13452 -28.550108)
		(end 50.664364 -29.079952)
		(width 0.13208)
		(layer "F.Cu")
		(net "SSD1_PWRDIS_R")
	)
	(segment
		(start 339.979 -234.46105)
		(end 339.979 -235.077)
		(width 0.13208)
		(layer "F.Cu")
		(net "SSD1_PWRDIS_R")
	)
	(via
		(at 65.100962 -206.312516)
		(size 0.508)
		(drill 0.254)
		(layers "F.Cu" "B.Cu")
		(net "SSD1_PWRDIS_R")
	)
	(via
		(at 50.13452 -28.469082)
		(size 0.508)
		(drill 0.254)
		(layers "F.Cu" "B.Cu")
		(net "SSD1_PWRDIS_R")
	)
	(via
		(at 40.191182 -25.390094)
		(size 0.508)
		(drill 0.254)
		(layers "F.Cu" "B.Cu")
		(net "SSD1_PWRDIS_R")
	)
	(via
		(at 339.979 -235.077)
		(size 0.508)
		(drill 0.254)
		(layers "F.Cu" "B.Cu")
		(net "SSD1_PWRDIS_R")
	)
	(segment
		(start 44.834556 -27.432)
		(end 46.35881 -27.432)
		(width 0.15494)
		(layer "In5.Cu")
		(net "SSD1_PWRDIS_R")
	)
	(segment
		(start 59.5122 -154.888946)
		(end 58.531506 -155.86964)
		(width 0.15494)
		(layer "In5.Cu")
		(net "SSD1_PWRDIS_R")
	)
	(segment
		(start 40.191182 -25.390094)
		(end 42.79265 -25.390094)
		(width 0.15494)
		(layer "In5.Cu")
		(net "SSD1_PWRDIS_R")
	)
	(segment
		(start 59.5122 -93.76664)
		(end 59.5122 -154.888946)
		(width 0.15494)
		(layer "In5.Cu")
		(net "SSD1_PWRDIS_R")
	)
	(segment
		(start 65.100962 -204.872336)
		(end 65.100962 -206.312516)
		(width 0.15494)
		(layer "In5.Cu")
		(net "SSD1_PWRDIS_R")
	)
	(segment
		(start 50.13452 -28.469082)
		(end 50.41392 -28.748482)
		(width 0.15494)
		(layer "In5.Cu")
		(net "SSD1_PWRDIS_R")
	)
	(segment
		(start 58.531506 -179.303426)
		(end 63.550292 -184.322212)
		(width 0.15494)
		(layer "In5.Cu")
		(net "SSD1_PWRDIS_R")
	)
	(segment
		(start 59.212734 -66.03492)
		(end 59.212734 -84.195412)
		(width 0.15494)
		(layer "In5.Cu")
		(net "SSD1_PWRDIS_R")
	)
	(segment
		(start 46.35881 -27.432)
		(end 46.841664 -27.914854)
		(width 0.15494)
		(layer "In5.Cu")
		(net "SSD1_PWRDIS_R")
	)
	(segment
		(start 59.212734 -84.195412)
		(end 58.303922 -85.104224)
		(width 0.15494)
		(layer "In5.Cu")
		(net "SSD1_PWRDIS_R")
	)
	(segment
		(start 58.531506 -155.86964)
		(end 58.531506 -179.303426)
		(width 0.15494)
		(layer "In5.Cu")
		(net "SSD1_PWRDIS_R")
	)
	(segment
		(start 46.841664 -27.914854)
		(end 49.580292 -27.914854)
		(width 0.15494)
		(layer "In5.Cu")
		(net "SSD1_PWRDIS_R")
	)
	(segment
		(start 62.47384 -45.815758)
		(end 62.47384 -62.773814)
		(width 0.15494)
		(layer "In5.Cu")
		(net "SSD1_PWRDIS_R")
	)
	(segment
		(start 63.550292 -184.322212)
		(end 63.550292 -203.321666)
		(width 0.15494)
		(layer "In5.Cu")
		(net "SSD1_PWRDIS_R")
	)
	(segment
		(start 62.47384 -62.773814)
		(end 59.212734 -66.03492)
		(width 0.15494)
		(layer "In5.Cu")
		(net "SSD1_PWRDIS_R")
	)
	(segment
		(start 50.41392 -28.748482)
		(end 50.41392 -33.755838)
		(width 0.15494)
		(layer "In5.Cu")
		(net "SSD1_PWRDIS_R")
	)
	(segment
		(start 58.303922 -92.558362)
		(end 59.5122 -93.76664)
		(width 0.15494)
		(layer "In5.Cu")
		(net "SSD1_PWRDIS_R")
	)
	(segment
		(start 58.303922 -85.104224)
		(end 58.303922 -92.558362)
		(width 0.15494)
		(layer "In5.Cu")
		(net "SSD1_PWRDIS_R")
	)
	(segment
		(start 50.41392 -33.755838)
		(end 62.47384 -45.815758)
		(width 0.15494)
		(layer "In5.Cu")
		(net "SSD1_PWRDIS_R")
	)
	(segment
		(start 63.550292 -203.321666)
		(end 65.100962 -204.872336)
		(width 0.15494)
		(layer "In5.Cu")
		(net "SSD1_PWRDIS_R")
	)
	(segment
		(start 42.79265 -25.390094)
		(end 44.834556 -27.432)
		(width 0.15494)
		(layer "In5.Cu")
		(net "SSD1_PWRDIS_R")
	)
	(segment
		(start 49.580292 -27.914854)
		(end 50.13452 -28.469082)
		(width 0.15494)
		(layer "In5.Cu")
		(net "SSD1_PWRDIS_R")
	)
	(segment
		(start 241.553492 -238.328962)
		(end 241.27079 -238.04626)
		(width 0.15494)
		(layer "In15.Cu")
		(net "SSD1_PWRDIS_R")
	)
	(segment
		(start 223.3676 -237.6424)
		(end 222.046546 -237.6424)
		(width 0.15494)
		(layer "In15.Cu")
		(net "SSD1_PWRDIS_R")
	)
	(segment
		(start 230.704898 -238.04626)
		(end 230.397558 -237.73892)
		(width 0.15494)
		(layer "In15.Cu")
		(net "SSD1_PWRDIS_R")
	)
	(segment
		(start 137.518394 -229.23246)
		(end 137.285984 -229.46487)
		(width 0.15494)
		(layer "In15.Cu")
		(net "SSD1_PWRDIS_R")
	)
	(segment
		(start 245.083838 -238.328962)
		(end 241.553492 -238.328962)
		(width 0.15494)
		(layer "In15.Cu")
		(net "SSD1_PWRDIS_R")
	)
	(segment
		(start 252.669802 -233.059986)
		(end 250.988322 -233.059986)
		(width 0.15494)
		(layer "In15.Cu")
		(net "SSD1_PWRDIS_R")
	)
	(segment
		(start 115.976146 -212.128354)
		(end 110.248192 -206.4004)
		(width 0.15494)
		(layer "In15.Cu")
		(net "SSD1_PWRDIS_R")
	)
	(segment
		(start 327.03516 -239.97285)
		(end 326.865488 -240.142522)
		(width 0.15494)
		(layer "In15.Cu")
		(net "SSD1_PWRDIS_R")
	)
	(segment
		(start 144.339564 -229.343458)
		(end 142.246096 -229.343458)
		(width 0.15494)
		(layer "In15.Cu")
		(net "SSD1_PWRDIS_R")
	)
	(segment
		(start 267.521944 -237.205266)
		(end 267.521944 -236.083856)
		(width 0.15494)
		(layer "In15.Cu")
		(net "SSD1_PWRDIS_R")
	)
	(segment
		(start 326.865488 -240.142522)
		(end 276.86508 -240.142522)
		(width 0.15494)
		(layer "In15.Cu")
		(net "SSD1_PWRDIS_R")
	)
	(segment
		(start 275.938996 -239.216438)
		(end 269.533116 -239.216438)
		(width 0.15494)
		(layer "In15.Cu")
		(net "SSD1_PWRDIS_R")
	)
	(segment
		(start 331.65034 -237.38713)
		(end 331.36713 -237.67034)
		(width 0.15494)
		(layer "In15.Cu")
		(net "SSD1_PWRDIS_R")
	)
	(segment
		(start 327.270618 -239.97285)
		(end 327.03516 -239.97285)
		(width 0.15494)
		(layer "In15.Cu")
		(net "SSD1_PWRDIS_R")
	)
	(segment
		(start 339.453982 -235.602018)
		(end 338.351622 -235.602018)
		(width 0.15494)
		(layer "In15.Cu")
		(net "SSD1_PWRDIS_R")
	)
	(segment
		(start 137.285984 -229.46487)
		(end 129.817876 -229.46487)
		(width 0.15494)
		(layer "In15.Cu")
		(net "SSD1_PWRDIS_R")
	)
	(segment
		(start 339.979 -235.077)
		(end 339.453982 -235.602018)
		(width 0.15494)
		(layer "In15.Cu")
		(net "SSD1_PWRDIS_R")
	)
	(segment
		(start 66.393568 -205.01991)
		(end 65.100962 -206.312516)
		(width 0.15494)
		(layer "In15.Cu")
		(net "SSD1_PWRDIS_R")
	)
	(segment
		(start 331.03566 -239.11687)
		(end 330.58227 -239.11687)
		(width 0.15494)
		(layer "In15.Cu")
		(net "SSD1_PWRDIS_R")
	)
	(segment
		(start 222.046546 -237.6424)
		(end 221.219776 -238.46917)
		(width 0.15494)
		(layer "In15.Cu")
		(net "SSD1_PWRDIS_R")
	)
	(segment
		(start 336.52587 -237.45571)
		(end 336.24266 -237.73892)
		(width 0.15494)
		(layer "In15.Cu")
		(net "SSD1_PWRDIS_R")
	)
	(segment
		(start 215.104726 -237.424214)
		(end 191.442594 -237.424214)
		(width 0.15494)
		(layer "In15.Cu")
		(net "SSD1_PWRDIS_R")
	)
	(segment
		(start 157.285944 -227.001324)
		(end 148.861018 -227.001324)
		(width 0.15494)
		(layer "In15.Cu")
		(net "SSD1_PWRDIS_R")
	)
	(segment
		(start 148.259038 -227.601018)
		(end 148.032216 -227.826824)
		(width 0.15494)
		(layer "In15.Cu")
		(net "SSD1_PWRDIS_R")
	)
	(segment
		(start 334.677258 -237.38713)
		(end 331.65034 -237.38713)
		(width 0.15494)
		(layer "In15.Cu")
		(net "SSD1_PWRDIS_R")
	)
	(segment
		(start 225.28022 -237.73892)
		(end 224.79508 -238.22406)
		(width 0.15494)
		(layer "In15.Cu")
		(net "SSD1_PWRDIS_R")
	)
	(segment
		(start 230.397558 -237.73892)
		(end 225.28022 -237.73892)
		(width 0.15494)
		(layer "In15.Cu")
		(net "SSD1_PWRDIS_R")
	)
	(segment
		(start 269.533116 -239.216438)
		(end 267.521944 -237.205266)
		(width 0.15494)
		(layer "In15.Cu")
		(net "SSD1_PWRDIS_R")
	)
	(segment
		(start 115.976146 -217.366088)
		(end 115.976146 -212.128354)
		(width 0.15494)
		(layer "In15.Cu")
		(net "SSD1_PWRDIS_R")
	)
	(segment
		(start 191.442594 -237.424214)
		(end 186.26455 -232.24617)
		(width 0.15494)
		(layer "In15.Cu")
		(net "SSD1_PWRDIS_R")
	)
	(segment
		(start 110.248192 -206.4004)
		(end 102.206044 -206.4004)
		(width 0.15494)
		(layer "In15.Cu")
		(net "SSD1_PWRDIS_R")
	)
	(segment
		(start 102.206044 -206.4004)
		(end 98.872548 -205.01991)
		(width 0.15494)
		(layer "In15.Cu")
		(net "SSD1_PWRDIS_R")
	)
	(segment
		(start 127.842518 -229.23246)
		(end 115.976146 -217.366088)
		(width 0.15494)
		(layer "In15.Cu")
		(net "SSD1_PWRDIS_R")
	)
	(segment
		(start 223.94926 -238.22406)
		(end 223.3676 -237.6424)
		(width 0.15494)
		(layer "In15.Cu")
		(net "SSD1_PWRDIS_R")
	)
	(segment
		(start 142.135098 -229.23246)
		(end 137.518394 -229.23246)
		(width 0.15494)
		(layer "In15.Cu")
		(net "SSD1_PWRDIS_R")
	)
	(segment
		(start 276.86508 -240.142522)
		(end 275.938996 -239.216438)
		(width 0.15494)
		(layer "In15.Cu")
		(net "SSD1_PWRDIS_R")
	)
	(segment
		(start 216.149682 -238.46917)
		(end 215.104726 -237.424214)
		(width 0.15494)
		(layer "In15.Cu")
		(net "SSD1_PWRDIS_R")
	)
	(segment
		(start 331.36713 -237.67034)
		(end 331.36713 -238.7854)
		(width 0.15494)
		(layer "In15.Cu")
		(net "SSD1_PWRDIS_R")
	)
	(segment
		(start 250.988322 -233.059986)
		(end 247.524778 -236.52353)
		(width 0.15494)
		(layer "In15.Cu")
		(net "SSD1_PWRDIS_R")
	)
	(segment
		(start 253.731268 -231.99852)
		(end 252.669802 -233.059986)
		(width 0.15494)
		(layer "In15.Cu")
		(net "SSD1_PWRDIS_R")
	)
	(segment
		(start 142.246096 -229.343458)
		(end 142.135098 -229.23246)
		(width 0.15494)
		(layer "In15.Cu")
		(net "SSD1_PWRDIS_R")
	)
	(segment
		(start 258.031996 -231.50576)
		(end 257.539236 -231.99852)
		(width 0.15494)
		(layer "In15.Cu")
		(net "SSD1_PWRDIS_R")
	)
	(segment
		(start 264.557256 -233.119168)
		(end 263.153144 -232.537508)
		(width 0.15494)
		(layer "In15.Cu")
		(net "SSD1_PWRDIS_R")
	)
	(segment
		(start 328.75093 -238.492538)
		(end 327.270618 -239.97285)
		(width 0.15494)
		(layer "In15.Cu")
		(net "SSD1_PWRDIS_R")
	)
	(segment
		(start 186.26455 -232.24617)
		(end 162.53079 -232.24617)
		(width 0.15494)
		(layer "In15.Cu")
		(net "SSD1_PWRDIS_R")
	)
	(segment
		(start 241.27079 -238.04626)
		(end 230.704898 -238.04626)
		(width 0.15494)
		(layer "In15.Cu")
		(net "SSD1_PWRDIS_R")
	)
	(segment
		(start 148.861018 -227.001324)
		(end 148.259038 -227.601018)
		(width 0.15494)
		(layer "In15.Cu")
		(net "SSD1_PWRDIS_R")
	)
	(segment
		(start 145.856198 -227.826824)
		(end 144.339564 -229.343458)
		(width 0.15494)
		(layer "In15.Cu")
		(net "SSD1_PWRDIS_R")
	)
	(segment
		(start 263.153144 -232.537508)
		(end 262.121396 -231.50576)
		(width 0.15494)
		(layer "In15.Cu")
		(net "SSD1_PWRDIS_R")
	)
	(segment
		(start 98.872548 -205.01991)
		(end 66.393568 -205.01991)
		(width 0.15494)
		(layer "In15.Cu")
		(net "SSD1_PWRDIS_R")
	)
	(segment
		(start 336.24266 -237.73892)
		(end 335.037938 -237.73892)
		(width 0.15494)
		(layer "In15.Cu")
		(net "SSD1_PWRDIS_R")
	)
	(segment
		(start 129.817876 -229.46487)
		(end 129.585466 -229.23246)
		(width 0.15494)
		(layer "In15.Cu")
		(net "SSD1_PWRDIS_R")
	)
	(segment
		(start 331.36713 -238.7854)
		(end 331.03566 -239.11687)
		(width 0.15494)
		(layer "In15.Cu")
		(net "SSD1_PWRDIS_R")
	)
	(segment
		(start 335.037938 -237.73892)
		(end 334.677258 -237.38713)
		(width 0.15494)
		(layer "In15.Cu")
		(net "SSD1_PWRDIS_R")
	)
	(segment
		(start 148.032216 -227.826824)
		(end 145.856198 -227.826824)
		(width 0.15494)
		(layer "In15.Cu")
		(net "SSD1_PWRDIS_R")
	)
	(segment
		(start 224.79508 -238.22406)
		(end 223.94926 -238.22406)
		(width 0.15494)
		(layer "In15.Cu")
		(net "SSD1_PWRDIS_R")
	)
	(segment
		(start 246.88927 -236.52353)
		(end 245.083838 -238.328962)
		(width 0.15494)
		(layer "In15.Cu")
		(net "SSD1_PWRDIS_R")
	)
	(segment
		(start 329.957938 -238.492538)
		(end 328.75093 -238.492538)
		(width 0.15494)
		(layer "In15.Cu")
		(net "SSD1_PWRDIS_R")
	)
	(segment
		(start 162.53079 -232.24617)
		(end 157.285944 -227.001324)
		(width 0.15494)
		(layer "In15.Cu")
		(net "SSD1_PWRDIS_R")
	)
	(segment
		(start 129.585466 -229.23246)
		(end 127.842518 -229.23246)
		(width 0.15494)
		(layer "In15.Cu")
		(net "SSD1_PWRDIS_R")
	)
	(segment
		(start 221.219776 -238.46917)
		(end 216.149682 -238.46917)
		(width 0.15494)
		(layer "In15.Cu")
		(net "SSD1_PWRDIS_R")
	)
	(segment
		(start 267.521944 -236.083856)
		(end 264.557256 -233.119168)
		(width 0.15494)
		(layer "In15.Cu")
		(net "SSD1_PWRDIS_R")
	)
	(segment
		(start 257.539236 -231.99852)
		(end 253.731268 -231.99852)
		(width 0.15494)
		(layer "In15.Cu")
		(net "SSD1_PWRDIS_R")
	)
	(segment
		(start 330.58227 -239.11687)
		(end 329.957938 -238.492538)
		(width 0.15494)
		(layer "In15.Cu")
		(net "SSD1_PWRDIS_R")
	)
	(segment
		(start 262.121396 -231.50576)
		(end 258.031996 -231.50576)
		(width 0.15494)
		(layer "In15.Cu")
		(net "SSD1_PWRDIS_R")
	)
	(segment
		(start 247.524778 -236.52353)
		(end 246.88927 -236.52353)
		(width 0.15494)
		(layer "In15.Cu")
		(net "SSD1_PWRDIS_R")
	)
	(segment
		(start 336.52587 -237.42777)
		(end 336.52587 -237.45571)
		(width 0.15494)
		(layer "In15.Cu")
		(net "SSD1_PWRDIS_R")
	)
	(segment
		(start 338.351622 -235.602018)
		(end 336.52587 -237.42777)
		(width 0.15494)
		(layer "In15.Cu")
		(net "SSD1_PWRDIS_R")
	)
	(segment
		(start 175.748188 -59.343544)
		(end 175.913796 -59.177936)
		(width 0.13208)
		(layer "F.Cu")
		(net "PWRGD_P3V3_SSD6")
	)
	(segment
		(start 176.279048 -58.71972)
		(end 176.125124 -58.565796)
		(width 0.13208)
		(layer "F.Cu")
		(net "PWRGD_P3V3_SSD6")
	)
	(segment
		(start 175.911002 -61.386974)
		(end 175.748188 -61.22416)
		(width 0.13208)
		(layer "F.Cu")
		(net "PWRGD_P3V3_SSD6")
	)
	(segment
		(start 176.125124 -57.867296)
		(end 176.125124 -57.841896)
		(width 0.13208)
		(layer "F.Cu")
		(net "PWRGD_P3V3_SSD6")
	)
	(segment
		(start 175.741076 -57.457848)
		(end 175.741076 -57.16397)
		(width 0.13208)
		(layer "F.Cu")
		(net "PWRGD_P3V3_SSD6")
	)
	(segment
		(start 176.125124 -58.565796)
		(end 176.125124 -57.867296)
		(width 0.13208)
		(layer "F.Cu")
		(net "PWRGD_P3V3_SSD6")
	)
	(segment
		(start 175.913796 -59.177936)
		(end 176.279048 -59.177936)
		(width 0.13208)
		(layer "F.Cu")
		(net "PWRGD_P3V3_SSD6")
	)
	(segment
		(start 175.748188 -61.22416)
		(end 175.748188 -59.343544)
		(width 0.13208)
		(layer "F.Cu")
		(net "PWRGD_P3V3_SSD6")
	)
	(segment
		(start 176.279048 -59.177936)
		(end 176.279048 -58.71972)
		(width 0.13208)
		(layer "F.Cu")
		(net "PWRGD_P3V3_SSD6")
	)
	(segment
		(start 176.125124 -57.841896)
		(end 175.741076 -57.457848)
		(width 0.13208)
		(layer "F.Cu")
		(net "PWRGD_P3V3_SSD6")
	)
	(via
		(at 176.125124 -57.867296)
		(size 0.508)
		(drill 0.254)
		(layers "F.Cu" "B.Cu")
		(net "PWRGD_P3V3_SSD6")
	)
	(segment
		(start 407.409142 -27.04973)
		(end 408.403806 -27.04973)
		(width 0.13208)
		(layer "F.Cu")
		(net "PRSNT_SSD14_R_N")
	)
	(segment
		(start 406.875742 -36.515548)
		(end 407.696162 -36.515548)
		(width 0.13208)
		(layer "F.Cu")
		(net "PRSNT_SSD14_R_N")
	)
	(segment
		(start 234.667552 -222.304102)
		(end 235.067348 -222.703898)
		(width 0.13208)
		(layer "F.Cu")
		(net "PRSNT_SSD14_R_N")
	)
	(segment
		(start 342.093804 -215.987122)
		(end 341.694008 -215.587326)
		(width 0.13208)
		(layer "F.Cu")
		(net "PRSNT_SSD14_R_N")
	)
	(segment
		(start 408.42057 -27.066494)
		(end 409.242514 -27.066494)
		(width 0.13208)
		(layer "F.Cu")
		(net "PRSNT_SSD14_R_N")
	)
	(segment
		(start 407.409142 -26.03373)
		(end 407.409142 -27.04973)
		(width 0.13208)
		(layer "F.Cu")
		(net "PRSNT_SSD14_R_N")
	)
	(segment
		(start 408.403806 -27.04973)
		(end 408.42057 -27.066494)
		(width 0.13208)
		(layer "F.Cu")
		(net "PRSNT_SSD14_R_N")
	)
	(via
		(at 235.067348 -222.703898)
		(size 0.4572)
		(drill 0.254)
		(layers "F.Cu" "B.Cu")
		(net "PRSNT_SSD14_R_N")
	)
	(via
		(at 355.491034 -100.944172)
		(size 0.508)
		(drill 0.254)
		(layers "F.Cu" "B.Cu")
		(net "PRSNT_SSD14_R_N")
	)
	(via
		(at 409.242514 -27.066494)
		(size 0.508)
		(drill 0.254)
		(layers "F.Cu" "B.Cu")
		(net "PRSNT_SSD14_R_N")
	)
	(via
		(at 248.501408 -185.614564)
		(size 0.508)
		(drill 0.254)
		(layers "F.Cu" "B.Cu")
		(net "PRSNT_SSD14_R_N")
	)
	(via
		(at 341.694008 -215.587326)
		(size 0.4572)
		(drill 0.254)
		(layers "F.Cu" "B.Cu")
		(net "PRSNT_SSD14_R_N")
	)
	(via
		(at 407.696162 -36.515548)
		(size 0.508)
		(drill 0.254)
		(layers "F.Cu" "B.Cu")
		(net "PRSNT_SSD14_R_N")
	)
	(via
		(at 406.943052 -89.165938)
		(size 0.508)
		(drill 0.254)
		(layers "F.Cu" "B.Cu")
		(net "PRSNT_SSD14_R_N")
	)
	(segment
		(start 407.696162 -36.515548)
		(end 406.06345 -34.882836)
		(width 0.15494)
		(layer "In5.Cu")
		(net "PRSNT_SSD14_R_N")
	)
	(segment
		(start 407.448258 -85.319362)
		(end 407.448258 -69.81063)
		(width 0.15494)
		(layer "In5.Cu")
		(net "PRSNT_SSD14_R_N")
	)
	(segment
		(start 407.706068 -39.526718)
		(end 407.706068 -36.525454)
		(width 0.15494)
		(layer "In5.Cu")
		(net "PRSNT_SSD14_R_N")
	)
	(segment
		(start 406.943052 -89.165938)
		(end 408.54376 -87.56523)
		(width 0.15494)
		(layer "In5.Cu")
		(net "PRSNT_SSD14_R_N")
	)
	(segment
		(start 407.448258 -69.81063)
		(end 412.787338 -64.47155)
		(width 0.15494)
		(layer "In5.Cu")
		(net "PRSNT_SSD14_R_N")
	)
	(segment
		(start 408.70886 -27.066494)
		(end 409.242514 -27.066494)
		(width 0.15494)
		(layer "In5.Cu")
		(net "PRSNT_SSD14_R_N")
	)
	(segment
		(start 408.54376 -86.414864)
		(end 407.448258 -85.319362)
		(width 0.15494)
		(layer "In5.Cu")
		(net "PRSNT_SSD14_R_N")
	)
	(segment
		(start 412.787338 -64.47155)
		(end 412.787338 -44.607988)
		(width 0.15494)
		(layer "In5.Cu")
		(net "PRSNT_SSD14_R_N")
	)
	(segment
		(start 408.54376 -87.56523)
		(end 408.54376 -86.414864)
		(width 0.15494)
		(layer "In5.Cu")
		(net "PRSNT_SSD14_R_N")
	)
	(segment
		(start 406.06345 -29.711904)
		(end 408.70886 -27.066494)
		(width 0.15494)
		(layer "In5.Cu")
		(net "PRSNT_SSD14_R_N")
	)
	(segment
		(start 412.787338 -44.607988)
		(end 407.706068 -39.526718)
		(width 0.15494)
		(layer "In5.Cu")
		(net "PRSNT_SSD14_R_N")
	)
	(segment
		(start 407.706068 -36.525454)
		(end 407.696162 -36.515548)
		(width 0.15494)
		(layer "In5.Cu")
		(net "PRSNT_SSD14_R_N")
	)
	(segment
		(start 406.06345 -34.882836)
		(end 406.06345 -29.711904)
		(width 0.15494)
		(layer "In5.Cu")
		(net "PRSNT_SSD14_R_N")
	)
	(segment
		(start 239.522 -221.712028)
		(end 239.522 -215.9254)
		(width 0.15494)
		(layer "In7.Cu")
		(net "PRSNT_SSD14_R_N")
	)
	(segment
		(start 356.195376 -187.108592)
		(end 356.478586 -187.391802)
		(width 0.15494)
		(layer "In7.Cu")
		(net "PRSNT_SSD14_R_N")
	)
	(segment
		(start 348.353634 -127.209296)
		(end 348.353634 -165.397434)
		(width 0.15494)
		(layer "In7.Cu")
		(net "PRSNT_SSD14_R_N")
	)
	(segment
		(start 247.2182 -201.828654)
		(end 246.598694 -201.209148)
		(width 0.15494)
		(layer "In7.Cu")
		(net "PRSNT_SSD14_R_N")
	)
	(segment
		(start 347.661738 -208.504282)
		(end 346.409518 -208.504282)
		(width 0.15494)
		(layer "In7.Cu")
		(net "PRSNT_SSD14_R_N")
	)
	(segment
		(start 246.54383 -192.03543)
		(end 246.54383 -188.598556)
		(width 0.15494)
		(layer "In7.Cu")
		(net "PRSNT_SSD14_R_N")
	)
	(segment
		(start 356.205536 -186.697112)
		(end 356.195376 -186.707272)
		(width 0.15494)
		(layer "In7.Cu")
		(net "PRSNT_SSD14_R_N")
	)
	(segment
		(start 356.493064 -187.391802)
		(end 356.7684 -187.667138)
		(width 0.15494)
		(layer "In7.Cu")
		(net "PRSNT_SSD14_R_N")
	)
	(segment
		(start 242.697508 -213.4362)
		(end 244.6528 -211.480908)
		(width 0.15494)
		(layer "In7.Cu")
		(net "PRSNT_SSD14_R_N")
	)
	(segment
		(start 349.782892 -206.383128)
		(end 347.661738 -208.504282)
		(width 0.15494)
		(layer "In7.Cu")
		(net "PRSNT_SSD14_R_N")
	)
	(segment
		(start 244.673374 -211.446364)
		(end 244.673374 -209.897726)
		(width 0.15494)
		(layer "In7.Cu")
		(net "PRSNT_SSD14_R_N")
	)
	(segment
		(start 346.409518 -208.504282)
		(end 342.8746 -212.0392)
		(width 0.15494)
		(layer "In7.Cu")
		(net "PRSNT_SSD14_R_N")
	)
	(segment
		(start 355.80828 -119.75465)
		(end 348.353634 -127.209296)
		(width 0.15494)
		(layer "In7.Cu")
		(net "PRSNT_SSD14_R_N")
	)
	(segment
		(start 351.0534 -166.9542)
		(end 356.205536 -172.106336)
		(width 0.15494)
		(layer "In7.Cu")
		(net "PRSNT_SSD14_R_N")
	)
	(segment
		(start 349.782892 -203.810108)
		(end 349.782892 -206.383128)
		(width 0.15494)
		(layer "In7.Cu")
		(net "PRSNT_SSD14_R_N")
	)
	(segment
		(start 235.080302 -222.703898)
		(end 235.458 -222.3262)
		(width 0.0889)
		(layer "In7.Cu")
		(net "PRSNT_SSD14_R_N")
	)
	(segment
		(start 248.501408 -186.640978)
		(end 248.501408 -185.614564)
		(width 0.15494)
		(layer "In7.Cu")
		(net "PRSNT_SSD14_R_N")
	)
	(segment
		(start 247.2182 -204.49413)
		(end 247.2182 -201.828654)
		(width 0.15494)
		(layer "In7.Cu")
		(net "PRSNT_SSD14_R_N")
	)
	(segment
		(start 235.067348 -222.703898)
		(end 235.080302 -222.703898)
		(width 0.0889)
		(layer "In7.Cu")
		(net "PRSNT_SSD14_R_N")
	)
	(segment
		(start 236.2708 -222.3262)
		(end 237.5662 -222.3262)
		(width 0.15494)
		(layer "In7.Cu")
		(net "PRSNT_SSD14_R_N")
	)
	(segment
		(start 244.6528 -211.480908)
		(end 244.6528 -211.466938)
		(width 0.15494)
		(layer "In7.Cu")
		(net "PRSNT_SSD14_R_N")
	)
	(segment
		(start 356.7684 -196.8246)
		(end 349.782892 -203.810108)
		(width 0.15494)
		(layer "In7.Cu")
		(net "PRSNT_SSD14_R_N")
	)
	(segment
		(start 246.598694 -198.962518)
		(end 247.4214 -198.139812)
		(width 0.15494)
		(layer "In7.Cu")
		(net "PRSNT_SSD14_R_N")
	)
	(segment
		(start 247.4214 -198.139812)
		(end 247.4214 -192.913)
		(width 0.15494)
		(layer "In7.Cu")
		(net "PRSNT_SSD14_R_N")
	)
	(segment
		(start 242.0112 -213.4362)
		(end 242.697508 -213.4362)
		(width 0.15494)
		(layer "In7.Cu")
		(net "PRSNT_SSD14_R_N")
	)
	(segment
		(start 238.637064 -222.596964)
		(end 239.522 -221.712028)
		(width 0.15494)
		(layer "In7.Cu")
		(net "PRSNT_SSD14_R_N")
	)
	(segment
		(start 342.8746 -212.0392)
		(end 342.8746 -214.406734)
		(width 0.15494)
		(layer "In7.Cu")
		(net "PRSNT_SSD14_R_N")
	)
	(segment
		(start 342.8746 -214.406734)
		(end 341.694008 -215.587326)
		(width 0.15494)
		(layer "In7.Cu")
		(net "PRSNT_SSD14_R_N")
	)
	(segment
		(start 237.5662 -222.3262)
		(end 237.836964 -222.596964)
		(width 0.15494)
		(layer "In7.Cu")
		(net "PRSNT_SSD14_R_N")
	)
	(segment
		(start 239.522 -215.9254)
		(end 242.0112 -213.4362)
		(width 0.15494)
		(layer "In7.Cu")
		(net "PRSNT_SSD14_R_N")
	)
	(segment
		(start 237.836964 -222.596964)
		(end 238.637064 -222.596964)
		(width 0.15494)
		(layer "In7.Cu")
		(net "PRSNT_SSD14_R_N")
	)
	(segment
		(start 356.195376 -186.707272)
		(end 356.195376 -187.108592)
		(width 0.15494)
		(layer "In7.Cu")
		(net "PRSNT_SSD14_R_N")
	)
	(segment
		(start 355.80828 -101.261418)
		(end 355.80828 -119.75465)
		(width 0.15494)
		(layer "In7.Cu")
		(net "PRSNT_SSD14_R_N")
	)
	(segment
		(start 356.478586 -187.391802)
		(end 356.493064 -187.391802)
		(width 0.15494)
		(layer "In7.Cu")
		(net "PRSNT_SSD14_R_N")
	)
	(segment
		(start 244.6528 -211.466938)
		(end 244.673374 -211.446364)
		(width 0.15494)
		(layer "In7.Cu")
		(net "PRSNT_SSD14_R_N")
	)
	(segment
		(start 247.4214 -192.913)
		(end 246.54383 -192.03543)
		(width 0.15494)
		(layer "In7.Cu")
		(net "PRSNT_SSD14_R_N")
	)
	(segment
		(start 356.7684 -187.667138)
		(end 356.7684 -196.8246)
		(width 0.15494)
		(layer "In7.Cu")
		(net "PRSNT_SSD14_R_N")
	)
	(segment
		(start 355.491034 -100.944172)
		(end 355.80828 -101.261418)
		(width 0.15494)
		(layer "In7.Cu")
		(net "PRSNT_SSD14_R_N")
	)
	(segment
		(start 246.05234 -208.51876)
		(end 246.05234 -207.515206)
		(width 0.15494)
		(layer "In7.Cu")
		(net "PRSNT_SSD14_R_N")
	)
	(segment
		(start 246.30634 -207.261206)
		(end 246.30634 -205.40599)
		(width 0.15494)
		(layer "In7.Cu")
		(net "PRSNT_SSD14_R_N")
	)
	(segment
		(start 244.673374 -209.897726)
		(end 246.05234 -208.51876)
		(width 0.15494)
		(layer "In7.Cu")
		(net "PRSNT_SSD14_R_N")
	)
	(segment
		(start 246.54383 -188.598556)
		(end 248.501408 -186.640978)
		(width 0.15494)
		(layer "In7.Cu")
		(net "PRSNT_SSD14_R_N")
	)
	(segment
		(start 246.598694 -201.209148)
		(end 246.598694 -198.962518)
		(width 0.15494)
		(layer "In7.Cu")
		(net "PRSNT_SSD14_R_N")
	)
	(segment
		(start 356.205536 -172.106336)
		(end 356.205536 -186.697112)
		(width 0.15494)
		(layer "In7.Cu")
		(net "PRSNT_SSD14_R_N")
	)
	(segment
		(start 348.353634 -165.397434)
		(end 349.9104 -166.9542)
		(width 0.15494)
		(layer "In7.Cu")
		(net "PRSNT_SSD14_R_N")
	)
	(segment
		(start 246.05234 -207.515206)
		(end 246.30634 -207.261206)
		(width 0.15494)
		(layer "In7.Cu")
		(net "PRSNT_SSD14_R_N")
	)
	(segment
		(start 235.458 -222.3262)
		(end 236.2708 -222.3262)
		(width 0.0889)
		(layer "In7.Cu")
		(net "PRSNT_SSD14_R_N")
	)
	(segment
		(start 349.9104 -166.9542)
		(end 351.0534 -166.9542)
		(width 0.15494)
		(layer "In7.Cu")
		(net "PRSNT_SSD14_R_N")
	)
	(segment
		(start 246.30634 -205.40599)
		(end 247.2182 -204.49413)
		(width 0.15494)
		(layer "In7.Cu")
		(net "PRSNT_SSD14_R_N")
	)
	(segment
		(start 321.53606 -210.12785)
		(end 322.53301 -211.1248)
		(width 0.15494)
		(layer "In13.Cu")
		(net "PRSNT_SSD14_R_N")
	)
	(segment
		(start 248.501408 -185.614564)
		(end 251.416566 -185.614564)
		(width 0.15494)
		(layer "In13.Cu")
		(net "PRSNT_SSD14_R_N")
	)
	(segment
		(start 255.666748 -191.58585)
		(end 257.386328 -193.30543)
		(width 0.15494)
		(layer "In13.Cu")
		(net "PRSNT_SSD14_R_N")
	)
	(segment
		(start 337.295998 -214.997792)
		(end 337.295998 -214.602568)
		(width 0.0889)
		(layer "In13.Cu")
		(net "PRSNT_SSD14_R_N")
	)
	(segment
		(start 334.414876 -215.00592)
		(end 334.593692 -215.184736)
		(width 0.15494)
		(layer "In13.Cu")
		(net "PRSNT_SSD14_R_N")
	)
	(segment
		(start 328.428096 -211.1248)
		(end 332.309216 -215.00592)
		(width 0.15494)
		(layer "In13.Cu")
		(net "PRSNT_SSD14_R_N")
	)
	(segment
		(start 337.109054 -215.184736)
		(end 337.295998 -214.997792)
		(width 0.0889)
		(layer "In13.Cu")
		(net "PRSNT_SSD14_R_N")
	)
	(segment
		(start 280.613866 -210.12785)
		(end 321.53606 -210.12785)
		(width 0.15494)
		(layer "In13.Cu")
		(net "PRSNT_SSD14_R_N")
	)
	(segment
		(start 258.925822 -195.2752)
		(end 260.793484 -195.2752)
		(width 0.15494)
		(layer "In13.Cu")
		(net "PRSNT_SSD14_R_N")
	)
	(segment
		(start 257.386328 -193.735706)
		(end 258.925822 -195.2752)
		(width 0.15494)
		(layer "In13.Cu")
		(net "PRSNT_SSD14_R_N")
	)
	(segment
		(start 322.53301 -211.1248)
		(end 328.428096 -211.1248)
		(width 0.15494)
		(layer "In13.Cu")
		(net "PRSNT_SSD14_R_N")
	)
	(segment
		(start 340.491572 -214.962994)
		(end 340.713314 -215.184736)
		(width 0.0889)
		(layer "In13.Cu")
		(net "PRSNT_SSD14_R_N")
	)
	(segment
		(start 341.291418 -215.184736)
		(end 341.694008 -215.587326)
		(width 0.0889)
		(layer "In13.Cu")
		(net "PRSNT_SSD14_R_N")
	)
	(segment
		(start 251.416566 -185.614564)
		(end 255.666748 -189.864746)
		(width 0.15494)
		(layer "In13.Cu")
		(net "PRSNT_SSD14_R_N")
	)
	(segment
		(start 340.295738 -214.386922)
		(end 340.491572 -214.582756)
		(width 0.0889)
		(layer "In13.Cu")
		(net "PRSNT_SSD14_R_N")
	)
	(segment
		(start 332.309216 -215.00592)
		(end 334.414876 -215.00592)
		(width 0.15494)
		(layer "In13.Cu")
		(net "PRSNT_SSD14_R_N")
	)
	(segment
		(start 340.713314 -215.184736)
		(end 341.291418 -215.184736)
		(width 0.0889)
		(layer "In13.Cu")
		(net "PRSNT_SSD14_R_N")
	)
	(segment
		(start 266.2174 -195.731384)
		(end 280.613866 -210.12785)
		(width 0.15494)
		(layer "In13.Cu")
		(net "PRSNT_SSD14_R_N")
	)
	(segment
		(start 260.793484 -195.2752)
		(end 261.249668 -195.731384)
		(width 0.15494)
		(layer "In13.Cu")
		(net "PRSNT_SSD14_R_N")
	)
	(segment
		(start 334.593692 -215.184736)
		(end 337.109054 -215.184736)
		(width 0.0889)
		(layer "In13.Cu")
		(net "PRSNT_SSD14_R_N")
	)
	(segment
		(start 340.491572 -214.582756)
		(end 340.491572 -214.962994)
		(width 0.0889)
		(layer "In13.Cu")
		(net "PRSNT_SSD14_R_N")
	)
	(segment
		(start 255.666748 -189.864746)
		(end 255.666748 -191.58585)
		(width 0.15494)
		(layer "In13.Cu")
		(net "PRSNT_SSD14_R_N")
	)
	(segment
		(start 261.249668 -195.731384)
		(end 266.2174 -195.731384)
		(width 0.15494)
		(layer "In13.Cu")
		(net "PRSNT_SSD14_R_N")
	)
	(segment
		(start 337.511644 -214.386922)
		(end 340.295738 -214.386922)
		(width 0.0889)
		(layer "In13.Cu")
		(net "PRSNT_SSD14_R_N")
	)
	(segment
		(start 337.295998 -214.602568)
		(end 337.511644 -214.386922)
		(width 0.0889)
		(layer "In13.Cu")
		(net "PRSNT_SSD14_R_N")
	)
	(segment
		(start 257.386328 -193.30543)
		(end 257.386328 -193.735706)
		(width 0.15494)
		(layer "In13.Cu")
		(net "PRSNT_SSD14_R_N")
	)
	(segment
		(start 400.405346 -92.1766)
		(end 402.893276 -89.68867)
		(width 0.15494)
		(layer "In15.Cu")
		(net "PRSNT_SSD14_R_N")
	)
	(segment
		(start 392.0998 -94.2594)
		(end 394.1826 -92.1766)
		(width 0.15494)
		(layer "In15.Cu")
		(net "PRSNT_SSD14_R_N")
	)
	(segment
		(start 355.491034 -100.944172)
		(end 356.638606 -99.7966)
		(width 0.15494)
		(layer "In15.Cu")
		(net "PRSNT_SSD14_R_N")
	)
	(segment
		(start 394.1826 -92.1766)
		(end 400.405346 -92.1766)
		(width 0.15494)
		(layer "In15.Cu")
		(net "PRSNT_SSD14_R_N")
	)
	(segment
		(start 356.638606 -99.7966)
		(end 368.336576 -99.7966)
		(width 0.15494)
		(layer "In15.Cu")
		(net "PRSNT_SSD14_R_N")
	)
	(segment
		(start 380.2888 -98.5266)
		(end 384.556 -94.2594)
		(width 0.15494)
		(layer "In15.Cu")
		(net "PRSNT_SSD14_R_N")
	)
	(segment
		(start 406.42032 -89.68867)
		(end 406.943052 -89.165938)
		(width 0.15494)
		(layer "In15.Cu")
		(net "PRSNT_SSD14_R_N")
	)
	(segment
		(start 369.606576 -98.5266)
		(end 380.2888 -98.5266)
		(width 0.15494)
		(layer "In15.Cu")
		(net "PRSNT_SSD14_R_N")
	)
	(segment
		(start 368.336576 -99.7966)
		(end 369.606576 -98.5266)
		(width 0.15494)
		(layer "In15.Cu")
		(net "PRSNT_SSD14_R_N")
	)
	(segment
		(start 384.556 -94.2594)
		(end 392.0998 -94.2594)
		(width 0.15494)
		(layer "In15.Cu")
		(net "PRSNT_SSD14_R_N")
	)
	(segment
		(start 402.893276 -89.68867)
		(end 406.42032 -89.68867)
		(width 0.15494)
		(layer "In15.Cu")
		(net "PRSNT_SSD14_R_N")
	)
	(segment
		(start 383.373376 -58.166)
		(end 383.490978 -58.449718)
		(width 0.2032)
		(layer "F.Cu")
		(net "P3V3_SSD13_SS")
	)
	(segment
		(start 383.495042 -58.453782)
		(end 383.495042 -59.177936)
		(width 0.2032)
		(layer "F.Cu")
		(net "P3V3_SSD13_SS")
	)
	(segment
		(start 382.440942 -57.233566)
		(end 383.373376 -58.166)
		(width 0.2032)
		(layer "F.Cu")
		(net "P3V3_SSD13_SS")
	)
	(segment
		(start 383.490978 -58.449718)
		(end 383.495042 -58.453782)
		(width 0.2032)
		(layer "F.Cu")
		(net "P3V3_SSD13_SS")
	)
	(segment
		(start 382.440942 -57.16397)
		(end 382.440942 -57.233566)
		(width 0.2032)
		(layer "F.Cu")
		(net "P3V3_SSD13_SS")
	)
	(via
		(at 383.490978 -58.449718)
		(size 0.508)
		(drill 0.254)
		(layers "F.Cu" "B.Cu")
		(net "P3V3_SSD13_SS")
	)
	(segment
		(start 224.221802 -198.289672)
		(end 223.527112 -197.594982)
		(width 0.13208)
		(layer "F.Cu")
		(net "SPI_BIC1_CLK_R5")
	)
	(segment
		(start 226.57816 -199.265794)
		(end 224.221802 -198.289672)
		(width 0.13208)
		(layer "F.Cu")
		(net "SPI_BIC1_CLK_R5")
	)
	(segment
		(start 223.527112 -197.594982)
		(end 223.527112 -197.078092)
		(width 0.13208)
		(layer "F.Cu")
		(net "SPI_BIC1_CLK_R5")
	)
	(via
		(at 226.57816 -199.265794)
		(size 0.508)
		(drill 0.254)
		(layers "F.Cu" "B.Cu")
		(net "SPI_BIC1_CLK_R5")
	)
	(segment
		(start 225.128836 -198.498968)
		(end 224.81794 -198.188072)
		(width 0.13208)
		(layer "B.Cu")
		(net "SPI_BIC1_CLK_R5")
	)
	(segment
		(start 226.294188 -198.981822)
		(end 225.128836 -198.498968)
		(width 0.13208)
		(layer "B.Cu")
		(net "SPI_BIC1_CLK_R5")
	)
	(segment
		(start 226.57816 -199.265794)
		(end 226.294188 -198.981822)
		(width 0.13208)
		(layer "B.Cu")
		(net "SPI_BIC1_CLK_R5")
	)
	(segment
		(start 133.081522 -26.479246)
		(end 132.789168 -26.7716)
		(width 0.13462)
		(layer "F.Cu")
		(net "CLK_100M_DB800ZL_SSD4_R_DN")
	)
	(segment
		(start 115.756436 -85.384386)
		(end 116.076222 -85.0646)
		(width 0.13462)
		(layer "F.Cu")
		(net "CLK_100M_DB800ZL_SSD4_R_DN")
	)
	(segment
		(start 131.854956 -26.58999)
		(end 131.36499 -26.58999)
		(width 0.13462)
		(layer "F.Cu")
		(net "CLK_100M_DB800ZL_SSD4_R_DN")
	)
	(segment
		(start 117.548914 -85.0646)
		(end 117.8433 -85.358986)
		(width 0.13462)
		(layer "F.Cu")
		(net "CLK_100M_DB800ZL_SSD4_R_DN")
	)
	(segment
		(start 132.789168 -26.7716)
		(end 132.036566 -26.7716)
		(width 0.13462)
		(layer "F.Cu")
		(net "CLK_100M_DB800ZL_SSD4_R_DN")
	)
	(segment
		(start 116.076222 -85.0646)
		(end 117.548914 -85.0646)
		(width 0.13462)
		(layer "F.Cu")
		(net "CLK_100M_DB800ZL_SSD4_R_DN")
	)
	(segment
		(start 132.036566 -26.7716)
		(end 131.854956 -26.58999)
		(width 0.13462)
		(layer "F.Cu")
		(net "CLK_100M_DB800ZL_SSD4_R_DN")
	)
	(via
		(at 117.8433 -85.358986)
		(size 0.508)
		(drill 0.254)
		(layers "F.Cu" "B.Cu")
		(net "CLK_100M_DB800ZL_SSD4_R_DN")
	)
	(via
		(at 133.081522 -26.479246)
		(size 0.508)
		(drill 0.254)
		(layers "F.Cu" "B.Cu")
		(net "CLK_100M_DB800ZL_SSD4_R_DN")
	)
	(segment
		(start 128.739138 -70.273672)
		(end 128.739138 -71.115936)
		(width 0.1651)
		(layer "In13.Cu")
		(net "CLK_100M_DB800ZL_SSD4_R_DN")
	)
	(segment
		(start 128.43383 -72.340724)
		(end 128.739138 -72.646032)
		(width 0.1651)
		(layer "In13.Cu")
		(net "CLK_100M_DB800ZL_SSD4_R_DN")
	)
	(segment
		(start 125.168406 -74.713084)
		(end 128.43383 -74.713084)
		(width 0.1651)
		(layer "In13.Cu")
		(net "CLK_100M_DB800ZL_SSD4_R_DN")
	)
	(segment
		(start 133.702806 -26.76906)
		(end 134.0358 -27.102054)
		(width 0.1651)
		(layer "In13.Cu")
		(net "CLK_100M_DB800ZL_SSD4_R_DN")
	)
	(segment
		(start 125.0188 -79.4131)
		(end 119.363998 -85.067902)
		(width 0.1651)
		(layer "In13.Cu")
		(net "CLK_100M_DB800ZL_SSD4_R_DN")
	)
	(segment
		(start 125.168406 -69.968364)
		(end 128.43383 -69.968364)
		(width 0.1651)
		(layer "In13.Cu")
		(net "CLK_100M_DB800ZL_SSD4_R_DN")
	)
	(segment
		(start 125.033024 -67.458082)
		(end 125.170946 -67.596004)
		(width 0.1651)
		(layer "In13.Cu")
		(net "CLK_100M_DB800ZL_SSD4_R_DN")
	)
	(segment
		(start 125.041406 -74.586084)
		(end 125.168406 -74.713084)
		(width 0.1651)
		(layer "In13.Cu")
		(net "CLK_100M_DB800ZL_SSD4_R_DN")
	)
	(segment
		(start 125.041406 -73.973944)
		(end 125.041406 -74.586084)
		(width 0.1651)
		(layer "In13.Cu")
		(net "CLK_100M_DB800ZL_SSD4_R_DN")
	)
	(segment
		(start 128.739138 -67.901312)
		(end 128.739138 -68.743576)
		(width 0.1651)
		(layer "In13.Cu")
		(net "CLK_100M_DB800ZL_SSD4_R_DN")
	)
	(segment
		(start 128.739138 -71.115936)
		(end 128.43383 -71.421244)
		(width 0.1651)
		(layer "In13.Cu")
		(net "CLK_100M_DB800ZL_SSD4_R_DN")
	)
	(segment
		(start 128.7018 -42.7228)
		(end 128.7018 -66.369946)
		(width 0.1651)
		(layer "In13.Cu")
		(net "CLK_100M_DB800ZL_SSD4_R_DN")
	)
	(segment
		(start 125.041406 -69.229224)
		(end 125.041406 -69.841364)
		(width 0.1651)
		(layer "In13.Cu")
		(net "CLK_100M_DB800ZL_SSD4_R_DN")
	)
	(segment
		(start 118.134384 -85.067902)
		(end 117.8433 -85.358986)
		(width 0.1651)
		(layer "In13.Cu")
		(net "CLK_100M_DB800ZL_SSD4_R_DN")
	)
	(segment
		(start 119.363998 -85.067902)
		(end 118.134384 -85.067902)
		(width 0.1651)
		(layer "In13.Cu")
		(net "CLK_100M_DB800ZL_SSD4_R_DN")
	)
	(segment
		(start 125.041406 -69.841364)
		(end 125.168406 -69.968364)
		(width 0.1651)
		(layer "In13.Cu")
		(net "CLK_100M_DB800ZL_SSD4_R_DN")
	)
	(segment
		(start 125.170946 -67.596004)
		(end 128.43383 -67.596004)
		(width 0.1651)
		(layer "In13.Cu")
		(net "CLK_100M_DB800ZL_SSD4_R_DN")
	)
	(segment
		(start 132.765292 -38.659308)
		(end 128.7018 -42.7228)
		(width 0.1651)
		(layer "In13.Cu")
		(net "CLK_100M_DB800ZL_SSD4_R_DN")
	)
	(segment
		(start 128.379982 -66.691764)
		(end 125.190758 -66.691764)
		(width 0.1651)
		(layer "In13.Cu")
		(net "CLK_100M_DB800ZL_SSD4_R_DN")
	)
	(segment
		(start 125.190758 -66.691764)
		(end 125.033024 -66.849498)
		(width 0.1651)
		(layer "In13.Cu")
		(net "CLK_100M_DB800ZL_SSD4_R_DN")
	)
	(segment
		(start 128.739138 -72.646032)
		(end 128.739138 -73.488296)
		(width 0.1651)
		(layer "In13.Cu")
		(net "CLK_100M_DB800ZL_SSD4_R_DN")
	)
	(segment
		(start 128.43383 -74.713084)
		(end 128.739138 -75.018392)
		(width 0.1651)
		(layer "In13.Cu")
		(net "CLK_100M_DB800ZL_SSD4_R_DN")
	)
	(segment
		(start 128.739138 -76.312522)
		(end 128.403096 -76.648564)
		(width 0.1651)
		(layer "In13.Cu")
		(net "CLK_100M_DB800ZL_SSD4_R_DN")
	)
	(segment
		(start 125.0188 -76.82738)
		(end 125.0188 -79.4131)
		(width 0.1651)
		(layer "In13.Cu")
		(net "CLK_100M_DB800ZL_SSD4_R_DN")
	)
	(segment
		(start 128.403096 -76.648564)
		(end 125.197616 -76.648564)
		(width 0.1651)
		(layer "In13.Cu")
		(net "CLK_100M_DB800ZL_SSD4_R_DN")
	)
	(segment
		(start 125.041406 -71.601584)
		(end 125.041406 -72.213724)
		(width 0.1651)
		(layer "In13.Cu")
		(net "CLK_100M_DB800ZL_SSD4_R_DN")
	)
	(segment
		(start 128.739138 -68.743576)
		(end 128.43383 -69.048884)
		(width 0.1651)
		(layer "In13.Cu")
		(net "CLK_100M_DB800ZL_SSD4_R_DN")
	)
	(segment
		(start 128.739138 -75.018392)
		(end 128.739138 -76.312522)
		(width 0.1651)
		(layer "In13.Cu")
		(net "CLK_100M_DB800ZL_SSD4_R_DN")
	)
	(segment
		(start 133.371336 -26.76906)
		(end 133.702806 -26.76906)
		(width 0.1651)
		(layer "In13.Cu")
		(net "CLK_100M_DB800ZL_SSD4_R_DN")
	)
	(segment
		(start 134.0358 -27.102054)
		(end 134.0358 -35.2806)
		(width 0.1651)
		(layer "In13.Cu")
		(net "CLK_100M_DB800ZL_SSD4_R_DN")
	)
	(segment
		(start 128.739138 -73.488296)
		(end 128.43383 -73.793604)
		(width 0.1651)
		(layer "In13.Cu")
		(net "CLK_100M_DB800ZL_SSD4_R_DN")
	)
	(segment
		(start 134.0358 -35.2806)
		(end 132.765292 -36.551108)
		(width 0.1651)
		(layer "In13.Cu")
		(net "CLK_100M_DB800ZL_SSD4_R_DN")
	)
	(segment
		(start 128.43383 -69.968364)
		(end 128.739138 -70.273672)
		(width 0.1651)
		(layer "In13.Cu")
		(net "CLK_100M_DB800ZL_SSD4_R_DN")
	)
	(segment
		(start 125.041406 -72.213724)
		(end 125.168406 -72.340724)
		(width 0.1651)
		(layer "In13.Cu")
		(net "CLK_100M_DB800ZL_SSD4_R_DN")
	)
	(segment
		(start 125.197616 -76.648564)
		(end 125.0188 -76.82738)
		(width 0.1651)
		(layer "In13.Cu")
		(net "CLK_100M_DB800ZL_SSD4_R_DN")
	)
	(segment
		(start 128.43383 -71.421244)
		(end 125.221746 -71.421244)
		(width 0.1651)
		(layer "In13.Cu")
		(net "CLK_100M_DB800ZL_SSD4_R_DN")
	)
	(segment
		(start 125.221746 -69.048884)
		(end 125.041406 -69.229224)
		(width 0.1651)
		(layer "In13.Cu")
		(net "CLK_100M_DB800ZL_SSD4_R_DN")
	)
	(segment
		(start 125.221746 -73.793604)
		(end 125.041406 -73.973944)
		(width 0.1651)
		(layer "In13.Cu")
		(net "CLK_100M_DB800ZL_SSD4_R_DN")
	)
	(segment
		(start 132.765292 -36.551108)
		(end 132.765292 -38.659308)
		(width 0.1651)
		(layer "In13.Cu")
		(net "CLK_100M_DB800ZL_SSD4_R_DN")
	)
	(segment
		(start 125.221746 -71.421244)
		(end 125.041406 -71.601584)
		(width 0.1651)
		(layer "In13.Cu")
		(net "CLK_100M_DB800ZL_SSD4_R_DN")
	)
	(segment
		(start 128.43383 -73.793604)
		(end 125.221746 -73.793604)
		(width 0.1651)
		(layer "In13.Cu")
		(net "CLK_100M_DB800ZL_SSD4_R_DN")
	)
	(segment
		(start 128.43383 -69.048884)
		(end 125.221746 -69.048884)
		(width 0.1651)
		(layer "In13.Cu")
		(net "CLK_100M_DB800ZL_SSD4_R_DN")
	)
	(segment
		(start 128.7018 -66.369946)
		(end 128.379982 -66.691764)
		(width 0.1651)
		(layer "In13.Cu")
		(net "CLK_100M_DB800ZL_SSD4_R_DN")
	)
	(segment
		(start 125.033024 -66.849498)
		(end 125.033024 -67.458082)
		(width 0.1651)
		(layer "In13.Cu")
		(net "CLK_100M_DB800ZL_SSD4_R_DN")
	)
	(segment
		(start 133.081522 -26.479246)
		(end 133.371336 -26.76906)
		(width 0.1651)
		(layer "In13.Cu")
		(net "CLK_100M_DB800ZL_SSD4_R_DN")
	)
	(segment
		(start 128.43383 -67.596004)
		(end 128.739138 -67.901312)
		(width 0.1651)
		(layer "In13.Cu")
		(net "CLK_100M_DB800ZL_SSD4_R_DN")
	)
	(segment
		(start 125.168406 -72.340724)
		(end 128.43383 -72.340724)
		(width 0.1651)
		(layer "In13.Cu")
		(net "CLK_100M_DB800ZL_SSD4_R_DN")
	)
	(segment
		(start 223.13138 -219.10421)
		(end 223.467676 -219.10421)
		(width 0.13208)
		(layer "F.Cu")
		(net "SMB_NIC4_SCL")
	)
	(segment
		(start 218.339162 -219.34678)
		(end 218.619324 -219.066618)
		(width 0.13208)
		(layer "F.Cu")
		(net "SMB_NIC4_SCL")
	)
	(segment
		(start 220.399864 -219.150692)
		(end 223.084898 -219.150692)
		(width 0.13208)
		(layer "F.Cu")
		(net "SMB_NIC4_SCL")
	)
	(segment
		(start 218.339162 -219.34678)
		(end 218.143074 -219.150692)
		(width 0.13208)
		(layer "F.Cu")
		(net "SMB_NIC4_SCL")
	)
	(segment
		(start 214.201248 -219.306902)
		(end 214.83828 -219.306902)
		(width 0.13208)
		(layer "F.Cu")
		(net "SMB_NIC4_SCL")
	)
	(segment
		(start 223.084898 -219.150692)
		(end 223.13138 -219.10421)
		(width 0.13208)
		(layer "F.Cu")
		(net "SMB_NIC4_SCL")
	)
	(segment
		(start 217.80373 -219.150692)
		(end 217.635836 -219.318586)
		(width 0.13208)
		(layer "F.Cu")
		(net "SMB_NIC4_SCL")
	)
	(segment
		(start 218.143074 -219.150692)
		(end 217.80373 -219.150692)
		(width 0.13208)
		(layer "F.Cu")
		(net "SMB_NIC4_SCL")
	)
	(segment
		(start 220.196664 -219.066618)
		(end 220.399864 -219.150692)
		(width 0.13208)
		(layer "F.Cu")
		(net "SMB_NIC4_SCL")
	)
	(segment
		(start 219.145104 -219.066618)
		(end 220.196664 -219.066618)
		(width 0.13208)
		(layer "F.Cu")
		(net "SMB_NIC4_SCL")
	)
	(segment
		(start 218.619324 -219.066618)
		(end 219.145104 -219.066618)
		(width 0.13208)
		(layer "F.Cu")
		(net "SMB_NIC4_SCL")
	)
	(via
		(at 218.339162 -219.34678)
		(size 0.508)
		(drill 0.254)
		(layers "F.Cu" "B.Cu")
		(net "SMB_NIC4_SCL")
	)
	(via
		(at 219.145104 -219.066618)
		(size 0.762)
		(drill 0.381)
		(layers "F.Cu" "B.Cu")
		(net "SMB_NIC4_SCL")
	)
	(via
		(at 214.83828 -219.306902)
		(size 0.508)
		(drill 0.254)
		(layers "F.Cu" "B.Cu")
		(net "SMB_NIC4_SCL")
	)
	(segment
		(start 214.989156 -218.82227)
		(end 214.83828 -218.973146)
		(width 0.15494)
		(layer "In5.Cu")
		(net "SMB_NIC4_SCL")
	)
	(segment
		(start 217.17381 -218.82227)
		(end 214.989156 -218.82227)
		(width 0.15494)
		(layer "In5.Cu")
		(net "SMB_NIC4_SCL")
	)
	(segment
		(start 218.339162 -219.34678)
		(end 218.143074 -219.150692)
		(width 0.15494)
		(layer "In5.Cu")
		(net "SMB_NIC4_SCL")
	)
	(segment
		(start 217.502232 -219.150692)
		(end 217.17381 -218.82227)
		(width 0.15494)
		(layer "In5.Cu")
		(net "SMB_NIC4_SCL")
	)
	(segment
		(start 218.143074 -219.150692)
		(end 217.502232 -219.150692)
		(width 0.15494)
		(layer "In5.Cu")
		(net "SMB_NIC4_SCL")
	)
	(segment
		(start 214.83828 -218.973146)
		(end 214.83828 -219.306902)
		(width 0.15494)
		(layer "In5.Cu")
		(net "SMB_NIC4_SCL")
	)
	(segment
		(start 105.238804 -85.779102)
		(end 105.889044 -85.779102)
		(width 0.13208)
		(layer "F.Cu")
		(net "SMB_BMC_9ZXL0851_0_7_SCL")
	)
	(segment
		(start 103.411274 -84.223606)
		(end 104.05237 -84.223606)
		(width 0.13208)
		(layer "F.Cu")
		(net "SMB_BMC_9ZXL0851_0_7_SCL")
	)
	(segment
		(start 104.05237 -84.223606)
		(end 104.05237 -84.592668)
		(width 0.13208)
		(layer "F.Cu")
		(net "SMB_BMC_9ZXL0851_0_7_SCL")
	)
	(segment
		(start 104.05237 -84.592668)
		(end 105.238804 -85.779102)
		(width 0.13208)
		(layer "F.Cu")
		(net "SMB_BMC_9ZXL0851_0_7_SCL")
	)
	(via
		(at 104.05237 -84.223606)
		(size 0.508)
		(drill 0.254)
		(layers "F.Cu" "B.Cu")
		(net "SMB_BMC_9ZXL0851_0_7_SCL")
	)
	(segment
		(start 335.604612 -194.644518)
		(end 338.492592 -194.644518)
		(width 0.13208)
		(layer "F.Cu")
		(net "FM_SOL_UART_CH_SEL")
	)
	(segment
		(start 338.492592 -194.644518)
		(end 338.65566 -194.48145)
		(width 0.13208)
		(layer "F.Cu")
		(net "FM_SOL_UART_CH_SEL")
	)
	(segment
		(start 337.947 -234.46105)
		(end 337.947 -235.077)
		(width 0.13208)
		(layer "F.Cu")
		(net "FM_SOL_UART_CH_SEL")
	)
	(segment
		(start 338.65566 -194.48145)
		(end 339.4583 -194.48145)
		(width 0.13208)
		(layer "F.Cu")
		(net "FM_SOL_UART_CH_SEL")
	)
	(segment
		(start 339.4583 -194.48145)
		(end 340.161372 -194.48145)
		(width 0.13208)
		(layer "F.Cu")
		(net "FM_SOL_UART_CH_SEL")
	)
	(via
		(at 371.047264 -184.902856)
		(size 0.508)
		(drill 0.254)
		(layers "F.Cu" "B.Cu")
		(net "FM_SOL_UART_CH_SEL")
	)
	(via
		(at 339.4583 -194.48145)
		(size 0.508)
		(drill 0.254)
		(layers "F.Cu" "B.Cu")
		(net "FM_SOL_UART_CH_SEL")
	)
	(via
		(at 325.764906 -189.503304)
		(size 0.508)
		(drill 0.254)
		(layers "F.Cu" "B.Cu")
		(net "FM_SOL_UART_CH_SEL")
	)
	(via
		(at 337.947 -235.077)
		(size 0.508)
		(drill 0.254)
		(layers "F.Cu" "B.Cu")
		(net "FM_SOL_UART_CH_SEL")
	)
	(segment
		(start 364.684056 -188.070744)
		(end 367.879376 -188.070744)
		(width 0.15494)
		(layer "In9.Cu")
		(net "FM_SOL_UART_CH_SEL")
	)
	(segment
		(start 367.879376 -188.070744)
		(end 371.047264 -184.902856)
		(width 0.15494)
		(layer "In9.Cu")
		(net "FM_SOL_UART_CH_SEL")
	)
	(segment
		(start 345.816174 -231.017826)
		(end 354.50272 -231.017826)
		(width 0.15494)
		(layer "In9.Cu")
		(net "FM_SOL_UART_CH_SEL")
	)
	(segment
		(start 337.947 -235.077)
		(end 341.1982 -231.8258)
		(width 0.15494)
		(layer "In9.Cu")
		(net "FM_SOL_UART_CH_SEL")
	)
	(segment
		(start 355.371146 -230.1494)
		(end 357.2764 -230.1494)
		(width 0.15494)
		(layer "In9.Cu")
		(net "FM_SOL_UART_CH_SEL")
	)
	(segment
		(start 361.283504 -202.85837)
		(end 361.283504 -191.471296)
		(width 0.15494)
		(layer "In9.Cu")
		(net "FM_SOL_UART_CH_SEL")
	)
	(segment
		(start 345.597734 -231.236266)
		(end 345.816174 -231.017826)
		(width 0.15494)
		(layer "In9.Cu")
		(net "FM_SOL_UART_CH_SEL")
	)
	(segment
		(start 342.133682 -231.236266)
		(end 345.597734 -231.236266)
		(width 0.15494)
		(layer "In9.Cu")
		(net "FM_SOL_UART_CH_SEL")
	)
	(segment
		(start 341.544148 -231.8258)
		(end 342.133682 -231.236266)
		(width 0.15494)
		(layer "In9.Cu")
		(net "FM_SOL_UART_CH_SEL")
	)
	(segment
		(start 357.2764 -230.1494)
		(end 358.4702 -228.9556)
		(width 0.15494)
		(layer "In9.Cu")
		(net "FM_SOL_UART_CH_SEL")
	)
	(segment
		(start 341.1982 -231.8258)
		(end 341.544148 -231.8258)
		(width 0.15494)
		(layer "In9.Cu")
		(net "FM_SOL_UART_CH_SEL")
	)
	(segment
		(start 358.4702 -205.671674)
		(end 361.283504 -202.85837)
		(width 0.15494)
		(layer "In9.Cu")
		(net "FM_SOL_UART_CH_SEL")
	)
	(segment
		(start 358.4702 -228.9556)
		(end 358.4702 -205.671674)
		(width 0.15494)
		(layer "In9.Cu")
		(net "FM_SOL_UART_CH_SEL")
	)
	(segment
		(start 361.283504 -191.471296)
		(end 364.684056 -188.070744)
		(width 0.15494)
		(layer "In9.Cu")
		(net "FM_SOL_UART_CH_SEL")
	)
	(segment
		(start 354.50272 -231.017826)
		(end 355.371146 -230.1494)
		(width 0.15494)
		(layer "In9.Cu")
		(net "FM_SOL_UART_CH_SEL")
	)
	(segment
		(start 367.318798 -184.902856)
		(end 371.047264 -184.902856)
		(width 0.15494)
		(layer "In13.Cu")
		(net "FM_SOL_UART_CH_SEL")
	)
	(segment
		(start 361.420156 -193.976244)
		(end 361.420156 -191.018922)
		(width 0.15494)
		(layer "In13.Cu")
		(net "FM_SOL_UART_CH_SEL")
	)
	(segment
		(start 359.242106 -198.039736)
		(end 359.242106 -196.154294)
		(width 0.15494)
		(layer "In13.Cu")
		(net "FM_SOL_UART_CH_SEL")
	)
	(segment
		(start 357.36657 -199.915272)
		(end 359.242106 -198.039736)
		(width 0.15494)
		(layer "In13.Cu")
		(net "FM_SOL_UART_CH_SEL")
	)
	(segment
		(start 365.59236 -187.796678)
		(end 366.387888 -187.00115)
		(width 0.15494)
		(layer "In13.Cu")
		(net "FM_SOL_UART_CH_SEL")
	)
	(segment
		(start 359.242106 -196.154294)
		(end 361.420156 -193.976244)
		(width 0.15494)
		(layer "In13.Cu")
		(net "FM_SOL_UART_CH_SEL")
	)
	(segment
		(start 341.52205 -199.472042)
		(end 344.36558 -199.472042)
		(width 0.15494)
		(layer "In13.Cu")
		(net "FM_SOL_UART_CH_SEL")
	)
	(segment
		(start 364.6424 -187.796678)
		(end 365.59236 -187.796678)
		(width 0.15494)
		(layer "In13.Cu")
		(net "FM_SOL_UART_CH_SEL")
	)
	(segment
		(start 366.387888 -185.833766)
		(end 367.318798 -184.902856)
		(width 0.15494)
		(layer "In13.Cu")
		(net "FM_SOL_UART_CH_SEL")
	)
	(segment
		(start 344.36558 -199.472042)
		(end 344.80881 -199.915272)
		(width 0.15494)
		(layer "In13.Cu")
		(net "FM_SOL_UART_CH_SEL")
	)
	(segment
		(start 339.4583 -197.408292)
		(end 341.52205 -199.472042)
		(width 0.15494)
		(layer "In13.Cu")
		(net "FM_SOL_UART_CH_SEL")
	)
	(segment
		(start 344.80881 -199.915272)
		(end 357.36657 -199.915272)
		(width 0.15494)
		(layer "In13.Cu")
		(net "FM_SOL_UART_CH_SEL")
	)
	(segment
		(start 361.420156 -191.018922)
		(end 364.6424 -187.796678)
		(width 0.15494)
		(layer "In13.Cu")
		(net "FM_SOL_UART_CH_SEL")
	)
	(segment
		(start 366.387888 -187.00115)
		(end 366.387888 -185.833766)
		(width 0.15494)
		(layer "In13.Cu")
		(net "FM_SOL_UART_CH_SEL")
	)
	(segment
		(start 339.4583 -194.48145)
		(end 339.4583 -197.408292)
		(width 0.15494)
		(layer "In13.Cu")
		(net "FM_SOL_UART_CH_SEL")
	)
	(segment
		(start 339.4583 -194.48145)
		(end 330.743052 -194.48145)
		(width 0.15494)
		(layer "In15.Cu")
		(net "FM_SOL_UART_CH_SEL")
	)
	(segment
		(start 330.743052 -194.48145)
		(end 325.764906 -189.503304)
		(width 0.15494)
		(layer "In15.Cu")
		(net "FM_SOL_UART_CH_SEL")
	)
	(segment
		(start 111.788956 -85.779102)
		(end 112.651032 -85.779102)
		(width 0.13208)
		(layer "F.Cu")
		(net "SSD4_CLK_EN_R_N")
	)
	(via
		(at 80.899 -90.555826)
		(size 0.508)
		(drill 0.254)
		(layers "F.Cu" "B.Cu")
		(net "SSD4_CLK_EN_R_N")
	)
	(via
		(at 112.651032 -85.779102)
		(size 0.508)
		(drill 0.254)
		(layers "F.Cu" "B.Cu")
		(net "SSD4_CLK_EN_R_N")
	)
	(via
		(at 119.66194 -234.080558)
		(size 0.508)
		(drill 0.254)
		(layers "F.Cu" "B.Cu")
		(net "SSD4_CLK_EN_R_N")
	)
	(via
		(at 342.011 -236.347)
		(size 0.508)
		(drill 0.254)
		(layers "F.Cu" "B.Cu")
		(net "SSD4_CLK_EN_R_N")
	)
	(segment
		(start 343.027 -233.95305)
		(end 342.55329 -234.42676)
		(width 0.13208)
		(layer "B.Cu")
		(net "SSD4_CLK_EN_R_N")
	)
	(segment
		(start 342.55329 -234.42676)
		(end 342.55329 -235.80471)
		(width 0.13208)
		(layer "B.Cu")
		(net "SSD4_CLK_EN_R_N")
	)
	(segment
		(start 342.55329 -235.80471)
		(end 342.011 -236.347)
		(width 0.13208)
		(layer "B.Cu")
		(net "SSD4_CLK_EN_R_N")
	)
	(segment
		(start 89.99982 -134.085584)
		(end 93.3577 -142.192248)
		(width 0.15494)
		(layer "In5.Cu")
		(net "SSD4_CLK_EN_R_N")
	)
	(segment
		(start 86.82482 -119.609108)
		(end 86.82482 -127.61595)
		(width 0.15494)
		(layer "In5.Cu")
		(net "SSD4_CLK_EN_R_N")
	)
	(segment
		(start 93.3577 -178.09083)
		(end 94.851728 -179.584858)
		(width 0.15494)
		(layer "In5.Cu")
		(net "SSD4_CLK_EN_R_N")
	)
	(segment
		(start 83.797394 -116.581682)
		(end 86.82482 -119.609108)
		(width 0.15494)
		(layer "In5.Cu")
		(net "SSD4_CLK_EN_R_N")
	)
	(segment
		(start 119.66194 -227.37953)
		(end 119.66194 -234.080558)
		(width 0.15494)
		(layer "In5.Cu")
		(net "SSD4_CLK_EN_R_N")
	)
	(segment
		(start 94.851728 -179.584858)
		(end 94.851728 -184.513728)
		(width 0.15494)
		(layer "In5.Cu")
		(net "SSD4_CLK_EN_R_N")
	)
	(segment
		(start 100.6856 -194.945)
		(end 102.181914 -194.945)
		(width 0.15494)
		(layer "In5.Cu")
		(net "SSD4_CLK_EN_R_N")
	)
	(segment
		(start 80.899 -90.555826)
		(end 80.467962 -90.986864)
		(width 0.15494)
		(layer "In5.Cu")
		(net "SSD4_CLK_EN_R_N")
	)
	(segment
		(start 93.3577 -142.192248)
		(end 93.3577 -178.09083)
		(width 0.15494)
		(layer "In5.Cu")
		(net "SSD4_CLK_EN_R_N")
	)
	(segment
		(start 102.181914 -194.945)
		(end 104.57561 -197.338696)
		(width 0.15494)
		(layer "In5.Cu")
		(net "SSD4_CLK_EN_R_N")
	)
	(segment
		(start 99.06 -188.722)
		(end 99.06 -193.3194)
		(width 0.15494)
		(layer "In5.Cu")
		(net "SSD4_CLK_EN_R_N")
	)
	(segment
		(start 94.851728 -184.513728)
		(end 99.06 -188.722)
		(width 0.15494)
		(layer "In5.Cu")
		(net "SSD4_CLK_EN_R_N")
	)
	(segment
		(start 104.57561 -197.338696)
		(end 104.57561 -201.09561)
		(width 0.15494)
		(layer "In5.Cu")
		(net "SSD4_CLK_EN_R_N")
	)
	(segment
		(start 114.3254 -222.04299)
		(end 119.66194 -227.37953)
		(width 0.15494)
		(layer "In5.Cu")
		(net "SSD4_CLK_EN_R_N")
	)
	(segment
		(start 79.195676 -108.737654)
		(end 79.195676 -114.849148)
		(width 0.15494)
		(layer "In5.Cu")
		(net "SSD4_CLK_EN_R_N")
	)
	(segment
		(start 79.195676 -114.849148)
		(end 80.92821 -116.581682)
		(width 0.15494)
		(layer "In5.Cu")
		(net "SSD4_CLK_EN_R_N")
	)
	(segment
		(start 80.467962 -107.465368)
		(end 79.195676 -108.737654)
		(width 0.15494)
		(layer "In5.Cu")
		(net "SSD4_CLK_EN_R_N")
	)
	(segment
		(start 99.06 -193.3194)
		(end 100.6856 -194.945)
		(width 0.15494)
		(layer "In5.Cu")
		(net "SSD4_CLK_EN_R_N")
	)
	(segment
		(start 86.82482 -127.61595)
		(end 89.99982 -130.79095)
		(width 0.15494)
		(layer "In5.Cu")
		(net "SSD4_CLK_EN_R_N")
	)
	(segment
		(start 89.99982 -130.79095)
		(end 89.99982 -134.085584)
		(width 0.15494)
		(layer "In5.Cu")
		(net "SSD4_CLK_EN_R_N")
	)
	(segment
		(start 104.57561 -201.09561)
		(end 114.3254 -210.8454)
		(width 0.15494)
		(layer "In5.Cu")
		(net "SSD4_CLK_EN_R_N")
	)
	(segment
		(start 114.3254 -210.8454)
		(end 114.3254 -222.04299)
		(width 0.15494)
		(layer "In5.Cu")
		(net "SSD4_CLK_EN_R_N")
	)
	(segment
		(start 80.467962 -90.986864)
		(end 80.467962 -107.465368)
		(width 0.15494)
		(layer "In5.Cu")
		(net "SSD4_CLK_EN_R_N")
	)
	(segment
		(start 80.92821 -116.581682)
		(end 83.797394 -116.581682)
		(width 0.15494)
		(layer "In5.Cu")
		(net "SSD4_CLK_EN_R_N")
	)
	(segment
		(start 214.376 -240.5888)
		(end 214.8586 -241.0714)
		(width 0.15494)
		(layer "In15.Cu")
		(net "SSD4_CLK_EN_R_N")
	)
	(segment
		(start 231.16794 -241.07394)
		(end 232.95102 -241.07394)
		(width 0.15494)
		(layer "In15.Cu")
		(net "SSD4_CLK_EN_R_N")
	)
	(segment
		(start 232.95102 -241.07394)
		(end 233.393488 -240.631472)
		(width 0.15494)
		(layer "In15.Cu")
		(net "SSD4_CLK_EN_R_N")
	)
	(segment
		(start 265.373104 -238.096806)
		(end 268.908022 -241.631724)
		(width 0.15494)
		(layer "In15.Cu")
		(net "SSD4_CLK_EN_R_N")
	)
	(segment
		(start 219.653104 -241.0714)
		(end 220.067886 -240.656618)
		(width 0.15494)
		(layer "In15.Cu")
		(net "SSD4_CLK_EN_R_N")
	)
	(segment
		(start 220.067886 -240.656618)
		(end 230.750618 -240.656618)
		(width 0.15494)
		(layer "In15.Cu")
		(net "SSD4_CLK_EN_R_N")
	)
	(segment
		(start 97.61474 -86.0044)
		(end 86.258146 -86.0044)
		(width 0.15494)
		(layer "In15.Cu")
		(net "SSD4_CLK_EN_R_N")
	)
	(segment
		(start 147.02282 -231.15778)
		(end 147.79498 -230.38562)
		(width 0.15494)
		(layer "In15.Cu")
		(net "SSD4_CLK_EN_R_N")
	)
	(segment
		(start 256.467102 -234.21086)
		(end 256.799588 -234.543346)
		(width 0.15494)
		(layer "In15.Cu")
		(net "SSD4_CLK_EN_R_N")
	)
	(segment
		(start 263.523222 -235.125514)
		(end 265.373104 -236.975396)
		(width 0.15494)
		(layer "In15.Cu")
		(net "SSD4_CLK_EN_R_N")
	)
	(segment
		(start 98.711004 -84.908136)
		(end 97.61474 -86.0044)
		(width 0.15494)
		(layer "In15.Cu")
		(net "SSD4_CLK_EN_R_N")
	)
	(segment
		(start 329.325224 -241.715036)
		(end 331.994764 -241.715036)
		(width 0.15494)
		(layer "In15.Cu")
		(net "SSD4_CLK_EN_R_N")
	)
	(segment
		(start 112.651032 -85.779102)
		(end 111.864394 -86.56574)
		(width 0.15494)
		(layer "In15.Cu")
		(net "SSD4_CLK_EN_R_N")
	)
	(segment
		(start 81.70672 -90.555826)
		(end 80.899 -90.555826)
		(width 0.15494)
		(layer "In15.Cu")
		(net "SSD4_CLK_EN_R_N")
	)
	(segment
		(start 339.9028 -239.77473)
		(end 339.9028 -238.700818)
		(width 0.15494)
		(layer "In15.Cu")
		(net "SSD4_CLK_EN_R_N")
	)
	(segment
		(start 102.324916 -86.56574)
		(end 100.667312 -84.908136)
		(width 0.15494)
		(layer "In15.Cu")
		(net "SSD4_CLK_EN_R_N")
	)
	(segment
		(start 119.66194 -234.080558)
		(end 120.096788 -233.64571)
		(width 0.15494)
		(layer "In15.Cu")
		(net "SSD4_CLK_EN_R_N")
	)
	(segment
		(start 214.8586 -241.0714)
		(end 219.653104 -241.0714)
		(width 0.15494)
		(layer "In15.Cu")
		(net "SSD4_CLK_EN_R_N")
	)
	(segment
		(start 302.238664 -242.392708)
		(end 302.966628 -243.120672)
		(width 0.15494)
		(layer "In15.Cu")
		(net "SSD4_CLK_EN_R_N")
	)
	(segment
		(start 191.12738 -240.5888)
		(end 214.376 -240.5888)
		(width 0.15494)
		(layer "In15.Cu")
		(net "SSD4_CLK_EN_R_N")
	)
	(segment
		(start 328.257408 -242.782852)
		(end 329.325224 -241.715036)
		(width 0.15494)
		(layer "In15.Cu")
		(net "SSD4_CLK_EN_R_N")
	)
	(segment
		(start 156.90342 -230.38562)
		(end 161.00806 -234.49026)
		(width 0.15494)
		(layer "In15.Cu")
		(net "SSD4_CLK_EN_R_N")
	)
	(segment
		(start 233.393488 -240.631472)
		(end 240.743232 -240.631472)
		(width 0.15494)
		(layer "In15.Cu")
		(net "SSD4_CLK_EN_R_N")
	)
	(segment
		(start 262.11784 -234.543346)
		(end 263.523222 -235.125514)
		(width 0.15494)
		(layer "In15.Cu")
		(net "SSD4_CLK_EN_R_N")
	)
	(segment
		(start 240.743232 -240.631472)
		(end 241.38636 -241.2746)
		(width 0.15494)
		(layer "In15.Cu")
		(net "SSD4_CLK_EN_R_N")
	)
	(segment
		(start 339.9028 -238.700818)
		(end 342.011 -236.592618)
		(width 0.15494)
		(layer "In15.Cu")
		(net "SSD4_CLK_EN_R_N")
	)
	(segment
		(start 326.941688 -243.120672)
		(end 327.279508 -242.782852)
		(width 0.15494)
		(layer "In15.Cu")
		(net "SSD4_CLK_EN_R_N")
	)
	(segment
		(start 276.074886 -242.392708)
		(end 302.238664 -242.392708)
		(width 0.15494)
		(layer "In15.Cu")
		(net "SSD4_CLK_EN_R_N")
	)
	(segment
		(start 254.91694 -234.21086)
		(end 256.467102 -234.21086)
		(width 0.15494)
		(layer "In15.Cu")
		(net "SSD4_CLK_EN_R_N")
	)
	(segment
		(start 138.629136 -233.64571)
		(end 141.117066 -231.15778)
		(width 0.15494)
		(layer "In15.Cu")
		(net "SSD4_CLK_EN_R_N")
	)
	(segment
		(start 275.313902 -241.631724)
		(end 276.074886 -242.392708)
		(width 0.15494)
		(layer "In15.Cu")
		(net "SSD4_CLK_EN_R_N")
	)
	(segment
		(start 147.79498 -230.38562)
		(end 156.90342 -230.38562)
		(width 0.15494)
		(layer "In15.Cu")
		(net "SSD4_CLK_EN_R_N")
	)
	(segment
		(start 111.864394 -86.56574)
		(end 102.324916 -86.56574)
		(width 0.15494)
		(layer "In15.Cu")
		(net "SSD4_CLK_EN_R_N")
	)
	(segment
		(start 241.38636 -241.2746)
		(end 247.8532 -241.2746)
		(width 0.15494)
		(layer "In15.Cu")
		(net "SSD4_CLK_EN_R_N")
	)
	(segment
		(start 342.011 -236.592618)
		(end 342.011 -236.347)
		(width 0.15494)
		(layer "In15.Cu")
		(net "SSD4_CLK_EN_R_N")
	)
	(segment
		(start 331.994764 -241.715036)
		(end 332.661514 -241.048286)
		(width 0.15494)
		(layer "In15.Cu")
		(net "SSD4_CLK_EN_R_N")
	)
	(segment
		(start 302.966628 -243.120672)
		(end 326.941688 -243.120672)
		(width 0.15494)
		(layer "In15.Cu")
		(net "SSD4_CLK_EN_R_N")
	)
	(segment
		(start 256.799588 -234.543346)
		(end 262.11784 -234.543346)
		(width 0.15494)
		(layer "In15.Cu")
		(net "SSD4_CLK_EN_R_N")
	)
	(segment
		(start 185.02884 -234.49026)
		(end 191.12738 -240.5888)
		(width 0.15494)
		(layer "In15.Cu")
		(net "SSD4_CLK_EN_R_N")
	)
	(segment
		(start 86.258146 -86.0044)
		(end 81.70672 -90.555826)
		(width 0.15494)
		(layer "In15.Cu")
		(net "SSD4_CLK_EN_R_N")
	)
	(segment
		(start 141.117066 -231.15778)
		(end 147.02282 -231.15778)
		(width 0.15494)
		(layer "In15.Cu")
		(net "SSD4_CLK_EN_R_N")
	)
	(segment
		(start 120.096788 -233.64571)
		(end 138.629136 -233.64571)
		(width 0.15494)
		(layer "In15.Cu")
		(net "SSD4_CLK_EN_R_N")
	)
	(segment
		(start 327.279508 -242.782852)
		(end 328.257408 -242.782852)
		(width 0.15494)
		(layer "In15.Cu")
		(net "SSD4_CLK_EN_R_N")
	)
	(segment
		(start 338.629244 -241.048286)
		(end 339.9028 -239.77473)
		(width 0.15494)
		(layer "In15.Cu")
		(net "SSD4_CLK_EN_R_N")
	)
	(segment
		(start 247.8532 -241.2746)
		(end 254.91694 -234.21086)
		(width 0.15494)
		(layer "In15.Cu")
		(net "SSD4_CLK_EN_R_N")
	)
	(segment
		(start 268.908022 -241.631724)
		(end 275.313902 -241.631724)
		(width 0.15494)
		(layer "In15.Cu")
		(net "SSD4_CLK_EN_R_N")
	)
	(segment
		(start 100.667312 -84.908136)
		(end 98.711004 -84.908136)
		(width 0.15494)
		(layer "In15.Cu")
		(net "SSD4_CLK_EN_R_N")
	)
	(segment
		(start 332.661514 -241.048286)
		(end 338.629244 -241.048286)
		(width 0.15494)
		(layer "In15.Cu")
		(net "SSD4_CLK_EN_R_N")
	)
	(segment
		(start 161.00806 -234.49026)
		(end 185.02884 -234.49026)
		(width 0.15494)
		(layer "In15.Cu")
		(net "SSD4_CLK_EN_R_N")
	)
	(segment
		(start 230.750618 -240.656618)
		(end 231.16794 -241.07394)
		(width 0.15494)
		(layer "In15.Cu")
		(net "SSD4_CLK_EN_R_N")
	)
	(segment
		(start 265.373104 -236.975396)
		(end 265.373104 -238.096806)
		(width 0.15494)
		(layer "In15.Cu")
		(net "SSD4_CLK_EN_R_N")
	)
	(segment
		(start 339.693758 -211.98713)
		(end 339.293962 -211.587334)
		(width 0.13208)
		(layer "F.Cu")
		(net "PRSNT_SSD12_R_N")
	)
	(segment
		(start 355.409246 -27.04973)
		(end 356.40391 -27.04973)
		(width 0.13208)
		(layer "F.Cu")
		(net "PRSNT_SSD12_R_N")
	)
	(segment
		(start 355.409246 -26.03373)
		(end 355.409246 -27.04973)
		(width 0.13208)
		(layer "F.Cu")
		(net "PRSNT_SSD12_R_N")
	)
	(segment
		(start 235.867448 -221.904052)
		(end 235.467652 -221.504256)
		(width 0.13208)
		(layer "F.Cu")
		(net "PRSNT_SSD12_R_N")
	)
	(segment
		(start 354.875846 -36.515548)
		(end 355.696266 -36.515548)
		(width 0.13208)
		(layer "F.Cu")
		(net "PRSNT_SSD12_R_N")
	)
	(segment
		(start 356.420674 -27.066494)
		(end 357.242618 -27.066494)
		(width 0.13208)
		(layer "F.Cu")
		(net "PRSNT_SSD12_R_N")
	)
	(segment
		(start 356.40391 -27.04973)
		(end 356.420674 -27.066494)
		(width 0.13208)
		(layer "F.Cu")
		(net "PRSNT_SSD12_R_N")
	)
	(via
		(at 339.293962 -211.587334)
		(size 0.4572)
		(drill 0.254)
		(layers "F.Cu" "B.Cu")
		(net "PRSNT_SSD12_R_N")
	)
	(via
		(at 357.242618 -27.066494)
		(size 0.508)
		(drill 0.254)
		(layers "F.Cu" "B.Cu")
		(net "PRSNT_SSD12_R_N")
	)
	(via
		(at 246.654574 -183.549798)
		(size 0.508)
		(drill 0.254)
		(layers "F.Cu" "B.Cu")
		(net "PRSNT_SSD12_R_N")
	)
	(via
		(at 349.293434 -107.884214)
		(size 0.508)
		(drill 0.254)
		(layers "F.Cu" "B.Cu")
		(net "PRSNT_SSD12_R_N")
	)
	(via
		(at 355.696266 -36.515548)
		(size 0.508)
		(drill 0.254)
		(layers "F.Cu" "B.Cu")
		(net "PRSNT_SSD12_R_N")
	)
	(via
		(at 235.867448 -221.904052)
		(size 0.4572)
		(drill 0.254)
		(layers "F.Cu" "B.Cu")
		(net "PRSNT_SSD12_R_N")
	)
	(segment
		(start 356.663244 -27.066494)
		(end 357.242618 -27.066494)
		(width 0.15494)
		(layer "In5.Cu")
		(net "PRSNT_SSD12_R_N")
	)
	(segment
		(start 350.709484 -95.693484)
		(end 353.015804 -93.387164)
		(width 0.15494)
		(layer "In5.Cu")
		(net "PRSNT_SSD12_R_N")
	)
	(segment
		(start 353.307904 -81.546954)
		(end 360.685842 -74.169016)
		(width 0.15494)
		(layer "In5.Cu")
		(net "PRSNT_SSD12_R_N")
	)
	(segment
		(start 350.709484 -104.391968)
		(end 350.709484 -95.693484)
		(width 0.15494)
		(layer "In5.Cu")
		(net "PRSNT_SSD12_R_N")
	)
	(segment
		(start 360.685842 -44.044616)
		(end 355.706172 -39.064946)
		(width 0.15494)
		(layer "In5.Cu")
		(net "PRSNT_SSD12_R_N")
	)
	(segment
		(start 354.063554 -34.882836)
		(end 354.063554 -29.666184)
		(width 0.15494)
		(layer "In5.Cu")
		(net "PRSNT_SSD12_R_N")
	)
	(segment
		(start 360.685842 -74.169016)
		(end 360.685842 -44.044616)
		(width 0.15494)
		(layer "In5.Cu")
		(net "PRSNT_SSD12_R_N")
	)
	(segment
		(start 348.72803 -107.31881)
		(end 348.72803 -106.373422)
		(width 0.15494)
		(layer "In5.Cu")
		(net "PRSNT_SSD12_R_N")
	)
	(segment
		(start 353.015804 -93.387164)
		(end 353.015804 -92.521024)
		(width 0.15494)
		(layer "In5.Cu")
		(net "PRSNT_SSD12_R_N")
	)
	(segment
		(start 353.015804 -92.521024)
		(end 353.307904 -92.228924)
		(width 0.15494)
		(layer "In5.Cu")
		(net "PRSNT_SSD12_R_N")
	)
	(segment
		(start 355.706172 -39.064946)
		(end 355.706172 -36.525454)
		(width 0.15494)
		(layer "In5.Cu")
		(net "PRSNT_SSD12_R_N")
	)
	(segment
		(start 349.293434 -107.884214)
		(end 348.72803 -107.31881)
		(width 0.15494)
		(layer "In5.Cu")
		(net "PRSNT_SSD12_R_N")
	)
	(segment
		(start 355.706172 -36.525454)
		(end 355.696266 -36.515548)
		(width 0.15494)
		(layer "In5.Cu")
		(net "PRSNT_SSD12_R_N")
	)
	(segment
		(start 355.696266 -36.515548)
		(end 354.063554 -34.882836)
		(width 0.15494)
		(layer "In5.Cu")
		(net "PRSNT_SSD12_R_N")
	)
	(segment
		(start 354.063554 -29.666184)
		(end 356.663244 -27.066494)
		(width 0.15494)
		(layer "In5.Cu")
		(net "PRSNT_SSD12_R_N")
	)
	(segment
		(start 348.72803 -106.373422)
		(end 350.709484 -104.391968)
		(width 0.15494)
		(layer "In5.Cu")
		(net "PRSNT_SSD12_R_N")
	)
	(segment
		(start 353.307904 -92.228924)
		(end 353.307904 -81.546954)
		(width 0.15494)
		(layer "In5.Cu")
		(net "PRSNT_SSD12_R_N")
	)
	(segment
		(start 349.951548 -119.073676)
		(end 349.951548 -108.542328)
		(width 0.15494)
		(layer "In7.Cu")
		(net "PRSNT_SSD12_R_N")
	)
	(segment
		(start 244.315234 -211.297774)
		(end 244.315234 -209.749136)
		(width 0.15494)
		(layer "In7.Cu")
		(net "PRSNT_SSD12_R_N")
	)
	(segment
		(start 242.426236 -212.2678)
		(end 242.68176 -212.3186)
		(width 0.15494)
		(layer "In7.Cu")
		(net "PRSNT_SSD12_R_N")
	)
	(segment
		(start 344.846656 -177.425858)
		(end 344.8812 -177.391314)
		(width 0.15494)
		(layer "In7.Cu")
		(net "PRSNT_SSD12_R_N")
	)
	(segment
		(start 246.888 -192.912746)
		(end 246.1006 -192.125346)
		(width 0.15494)
		(layer "In7.Cu")
		(net "PRSNT_SSD12_R_N")
	)
	(segment
		(start 240.8936 -213.7918)
		(end 240.8936 -213.4362)
		(width 0.15494)
		(layer "In7.Cu")
		(net "PRSNT_SSD12_R_N")
	)
	(segment
		(start 245.6942 -207.366616)
		(end 245.9482 -207.112616)
		(width 0.15494)
		(layer "In7.Cu")
		(net "PRSNT_SSD12_R_N")
	)
	(segment
		(start 342.449658 -170.208956)
		(end 341.628222 -170.208956)
		(width 0.15494)
		(layer "In7.Cu")
		(net "PRSNT_SSD12_R_N")
	)
	(segment
		(start 242.062 -212.2678)
		(end 242.426236 -212.2678)
		(width 0.15494)
		(layer "In7.Cu")
		(net "PRSNT_SSD12_R_N")
	)
	(segment
		(start 338.380832 -210.674204)
		(end 338.380832 -207.536034)
		(width 0.15494)
		(layer "In7.Cu")
		(net "PRSNT_SSD12_R_N")
	)
	(segment
		(start 245.6942 -208.37017)
		(end 245.6942 -207.366616)
		(width 0.15494)
		(layer "In7.Cu")
		(net "PRSNT_SSD12_R_N")
	)
	(segment
		(start 243.294408 -212.3186)
		(end 244.315234 -211.297774)
		(width 0.15494)
		(layer "In7.Cu")
		(net "PRSNT_SSD12_R_N")
	)
	(segment
		(start 339.293962 -211.587334)
		(end 338.380832 -210.674204)
		(width 0.15494)
		(layer "In7.Cu")
		(net "PRSNT_SSD12_R_N")
	)
	(segment
		(start 337.332828 -198.88073)
		(end 337.332828 -188.623448)
		(width 0.15494)
		(layer "In7.Cu")
		(net "PRSNT_SSD12_R_N")
	)
	(segment
		(start 340.487 -163.64712)
		(end 340.487 -161.5948)
		(width 0.15494)
		(layer "In7.Cu")
		(net "PRSNT_SSD12_R_N")
	)
	(segment
		(start 242.68176 -212.3186)
		(end 243.294408 -212.3186)
		(width 0.15494)
		(layer "In7.Cu")
		(net "PRSNT_SSD12_R_N")
	)
	(segment
		(start 246.1006 -188.39434)
		(end 247.4722 -187.02274)
		(width 0.15494)
		(layer "In7.Cu")
		(net "PRSNT_SSD12_R_N")
	)
	(segment
		(start 246.1768 -198.602346)
		(end 246.888 -197.891146)
		(width 0.15494)
		(layer "In7.Cu")
		(net "PRSNT_SSD12_R_N")
	)
	(segment
		(start 338.065872 -199.613774)
		(end 337.332828 -198.88073)
		(width 0.15494)
		(layer "In7.Cu")
		(net "PRSNT_SSD12_R_N")
	)
	(segment
		(start 340.018878 -159.272478)
		(end 340.018878 -157.655768)
		(width 0.15494)
		(layer "In7.Cu")
		(net "PRSNT_SSD12_R_N")
	)
	(segment
		(start 338.582 -205.110334)
		(end 338.065872 -204.594206)
		(width 0.15494)
		(layer "In7.Cu")
		(net "PRSNT_SSD12_R_N")
	)
	(segment
		(start 246.1768 -201.3712)
		(end 246.1768 -198.602346)
		(width 0.15494)
		(layer "In7.Cu")
		(net "PRSNT_SSD12_R_N")
	)
	(segment
		(start 339.073744 -165.060376)
		(end 340.487 -163.64712)
		(width 0.15494)
		(layer "In7.Cu")
		(net "PRSNT_SSD12_R_N")
	)
	(segment
		(start 344.8812 -177.391314)
		(end 344.8812 -172.640498)
		(width 0.15494)
		(layer "In7.Cu")
		(net "PRSNT_SSD12_R_N")
	)
	(segment
		(start 239.141 -220.497654)
		(end 239.141 -215.5444)
		(width 0.15494)
		(layer "In7.Cu")
		(net "PRSNT_SSD12_R_N")
	)
	(segment
		(start 338.3788 -183.92267)
		(end 344.846656 -177.454814)
		(width 0.15494)
		(layer "In7.Cu")
		(net "PRSNT_SSD12_R_N")
	)
	(segment
		(start 344.846656 -177.454814)
		(end 344.846656 -177.425858)
		(width 0.15494)
		(layer "In7.Cu")
		(net "PRSNT_SSD12_R_N")
	)
	(segment
		(start 338.3788 -187.577476)
		(end 338.3788 -183.92267)
		(width 0.15494)
		(layer "In7.Cu")
		(net "PRSNT_SSD12_R_N")
	)
	(segment
		(start 246.86006 -202.05446)
		(end 246.1768 -201.3712)
		(width 0.15494)
		(layer "In7.Cu")
		(net "PRSNT_SSD12_R_N")
	)
	(segment
		(start 342.0364 -154.556968)
		(end 342.0364 -149.0726)
		(width 0.15494)
		(layer "In7.Cu")
		(net "PRSNT_SSD12_R_N")
	)
	(segment
		(start 340.986618 -155.60675)
		(end 342.0364 -154.556968)
		(width 0.15494)
		(layer "In7.Cu")
		(net "PRSNT_SSD12_R_N")
	)
	(segment
		(start 244.315234 -209.749136)
		(end 245.6942 -208.37017)
		(width 0.15494)
		(layer "In7.Cu")
		(net "PRSNT_SSD12_R_N")
	)
	(segment
		(start 235.867448 -221.904052)
		(end 237.734602 -221.904052)
		(width 0.15494)
		(layer "In7.Cu")
		(net "PRSNT_SSD12_R_N")
	)
	(segment
		(start 340.986618 -156.688028)
		(end 340.986618 -155.60675)
		(width 0.15494)
		(layer "In7.Cu")
		(net "PRSNT_SSD12_R_N")
	)
	(segment
		(start 240.8936 -213.4362)
		(end 242.062 -212.2678)
		(width 0.15494)
		(layer "In7.Cu")
		(net "PRSNT_SSD12_R_N")
	)
	(segment
		(start 245.9482 -207.112616)
		(end 245.9482 -205.2574)
		(width 0.15494)
		(layer "In7.Cu")
		(net "PRSNT_SSD12_R_N")
	)
	(segment
		(start 337.332828 -188.623448)
		(end 338.3788 -187.577476)
		(width 0.15494)
		(layer "In7.Cu")
		(net "PRSNT_SSD12_R_N")
	)
	(segment
		(start 343.0778 -125.947424)
		(end 349.951548 -119.073676)
		(width 0.15494)
		(layer "In7.Cu")
		(net "PRSNT_SSD12_R_N")
	)
	(segment
		(start 246.86006 -204.34554)
		(end 246.86006 -202.05446)
		(width 0.15494)
		(layer "In7.Cu")
		(net "PRSNT_SSD12_R_N")
	)
	(segment
		(start 237.734602 -221.904052)
		(end 239.141 -220.497654)
		(width 0.15494)
		(layer "In7.Cu")
		(net "PRSNT_SSD12_R_N")
	)
	(segment
		(start 247.4722 -184.367424)
		(end 246.654574 -183.549798)
		(width 0.15494)
		(layer "In7.Cu")
		(net "PRSNT_SSD12_R_N")
	)
	(segment
		(start 341.460328 -142.104618)
		(end 343.0778 -140.487146)
		(width 0.15494)
		(layer "In7.Cu")
		(net "PRSNT_SSD12_R_N")
	)
	(segment
		(start 339.073744 -167.654478)
		(end 339.073744 -165.060376)
		(width 0.15494)
		(layer "In7.Cu")
		(net "PRSNT_SSD12_R_N")
	)
	(segment
		(start 247.4722 -187.02274)
		(end 247.4722 -184.367424)
		(width 0.15494)
		(layer "In7.Cu")
		(net "PRSNT_SSD12_R_N")
	)
	(segment
		(start 341.628222 -170.208956)
		(end 339.073744 -167.654478)
		(width 0.15494)
		(layer "In7.Cu")
		(net "PRSNT_SSD12_R_N")
	)
	(segment
		(start 246.888 -197.891146)
		(end 246.888 -192.912746)
		(width 0.15494)
		(layer "In7.Cu")
		(net "PRSNT_SSD12_R_N")
	)
	(segment
		(start 246.1006 -192.125346)
		(end 246.1006 -188.39434)
		(width 0.15494)
		(layer "In7.Cu")
		(net "PRSNT_SSD12_R_N")
	)
	(segment
		(start 340.487 -161.5948)
		(end 341.0712 -161.0106)
		(width 0.15494)
		(layer "In7.Cu")
		(net "PRSNT_SSD12_R_N")
	)
	(segment
		(start 341.0712 -161.0106)
		(end 341.0712 -160.3248)
		(width 0.15494)
		(layer "In7.Cu")
		(net "PRSNT_SSD12_R_N")
	)
	(segment
		(start 338.065872 -204.594206)
		(end 338.065872 -199.613774)
		(width 0.15494)
		(layer "In7.Cu")
		(net "PRSNT_SSD12_R_N")
	)
	(segment
		(start 341.460328 -148.496528)
		(end 341.460328 -142.104618)
		(width 0.15494)
		(layer "In7.Cu")
		(net "PRSNT_SSD12_R_N")
	)
	(segment
		(start 342.0364 -149.0726)
		(end 341.460328 -148.496528)
		(width 0.15494)
		(layer "In7.Cu")
		(net "PRSNT_SSD12_R_N")
	)
	(segment
		(start 341.0712 -160.3248)
		(end 340.018878 -159.272478)
		(width 0.15494)
		(layer "In7.Cu")
		(net "PRSNT_SSD12_R_N")
	)
	(segment
		(start 349.951548 -108.542328)
		(end 349.293434 -107.884214)
		(width 0.15494)
		(layer "In7.Cu")
		(net "PRSNT_SSD12_R_N")
	)
	(segment
		(start 245.9482 -205.2574)
		(end 246.86006 -204.34554)
		(width 0.15494)
		(layer "In7.Cu")
		(net "PRSNT_SSD12_R_N")
	)
	(segment
		(start 338.380832 -207.536034)
		(end 338.582 -207.334866)
		(width 0.15494)
		(layer "In7.Cu")
		(net "PRSNT_SSD12_R_N")
	)
	(segment
		(start 344.8812 -172.640498)
		(end 342.449658 -170.208956)
		(width 0.15494)
		(layer "In7.Cu")
		(net "PRSNT_SSD12_R_N")
	)
	(segment
		(start 343.0778 -140.487146)
		(end 343.0778 -125.947424)
		(width 0.15494)
		(layer "In7.Cu")
		(net "PRSNT_SSD12_R_N")
	)
	(segment
		(start 340.018878 -157.655768)
		(end 340.986618 -156.688028)
		(width 0.15494)
		(layer "In7.Cu")
		(net "PRSNT_SSD12_R_N")
	)
	(segment
		(start 338.582 -207.334866)
		(end 338.582 -205.110334)
		(width 0.15494)
		(layer "In7.Cu")
		(net "PRSNT_SSD12_R_N")
	)
	(segment
		(start 239.141 -215.5444)
		(end 240.8936 -213.7918)
		(width 0.15494)
		(layer "In7.Cu")
		(net "PRSNT_SSD12_R_N")
	)
	(segment
		(start 326.6694 -207.5688)
		(end 327.5076 -208.407)
		(width 0.15494)
		(layer "In13.Cu")
		(net "PRSNT_SSD12_R_N")
	)
	(segment
		(start 301.000414 -208.33715)
		(end 301.768764 -207.5688)
		(width 0.15494)
		(layer "In13.Cu")
		(net "PRSNT_SSD12_R_N")
	)
	(segment
		(start 246.654574 -183.549798)
		(end 247.015 -183.910224)
		(width 0.15494)
		(layer "In13.Cu")
		(net "PRSNT_SSD12_R_N")
	)
	(segment
		(start 247.015 -183.910224)
		(end 252.642878 -183.910224)
		(width 0.15494)
		(layer "In13.Cu")
		(net "PRSNT_SSD12_R_N")
	)
	(segment
		(start 337.423252 -209.716624)
		(end 339.293962 -211.587334)
		(width 0.15494)
		(layer "In13.Cu")
		(net "PRSNT_SSD12_R_N")
	)
	(segment
		(start 331.3684 -208.407)
		(end 332.678024 -209.716624)
		(width 0.15494)
		(layer "In13.Cu")
		(net "PRSNT_SSD12_R_N")
	)
	(segment
		(start 281.664156 -208.33715)
		(end 301.000414 -208.33715)
		(width 0.15494)
		(layer "In13.Cu")
		(net "PRSNT_SSD12_R_N")
	)
	(segment
		(start 252.642878 -183.910224)
		(end 258.544314 -189.81166)
		(width 0.15494)
		(layer "In13.Cu")
		(net "PRSNT_SSD12_R_N")
	)
	(segment
		(start 258.544314 -189.81166)
		(end 263.138666 -189.81166)
		(width 0.15494)
		(layer "In13.Cu")
		(net "PRSNT_SSD12_R_N")
	)
	(segment
		(start 332.678024 -209.716624)
		(end 337.423252 -209.716624)
		(width 0.15494)
		(layer "In13.Cu")
		(net "PRSNT_SSD12_R_N")
	)
	(segment
		(start 301.768764 -207.5688)
		(end 326.6694 -207.5688)
		(width 0.15494)
		(layer "In13.Cu")
		(net "PRSNT_SSD12_R_N")
	)
	(segment
		(start 263.138666 -189.81166)
		(end 281.664156 -208.33715)
		(width 0.15494)
		(layer "In13.Cu")
		(net "PRSNT_SSD12_R_N")
	)
	(segment
		(start 327.5076 -208.407)
		(end 331.3684 -208.407)
		(width 0.15494)
		(layer "In13.Cu")
		(net "PRSNT_SSD12_R_N")
	)
	(segment
		(start 433.244244 -59.012582)
		(end 433.244244 -58.561224)
		(width 0.13208)
		(layer "F.Cu")
		(net "P3V3_SSD15_OCP")
	)
	(segment
		(start 433.44084 -57.16397)
		(end 433.44084 -58.364628)
		(width 0.13208)
		(layer "F.Cu")
		(net "P3V3_SSD15_OCP")
	)
	(segment
		(start 433.44084 -58.364628)
		(end 433.244244 -58.561224)
		(width 0.13208)
		(layer "F.Cu")
		(net "P3V3_SSD15_OCP")
	)
	(segment
		(start 433.403248 -59.171586)
		(end 433.244244 -59.012582)
		(width 0.13208)
		(layer "F.Cu")
		(net "P3V3_SSD15_OCP")
	)
	(via
		(at 433.244244 -58.561224)
		(size 0.508)
		(drill 0.254)
		(layers "F.Cu" "B.Cu")
		(net "P3V3_SSD15_OCP")
	)
	(segment
		(start 107.581954 -79.422244)
		(end 107.90428 -79.099918)
		(width 0.13462)
		(layer "F.Cu")
		(net "CLK_100M_DB800ZL_SSD1_R_DP")
	)
	(segment
		(start 42.981372 -27.342846)
		(end 42.689526 -27.051)
		(width 0.13462)
		(layer "F.Cu")
		(net "CLK_100M_DB800ZL_SSD1_R_DP")
	)
	(segment
		(start 107.90428 -79.099918)
		(end 107.90428 -78.394306)
		(width 0.13462)
		(layer "F.Cu")
		(net "CLK_100M_DB800ZL_SSD1_R_DP")
	)
	(segment
		(start 42.689526 -27.051)
		(end 41.90746 -27.051)
		(width 0.13462)
		(layer "F.Cu")
		(net "CLK_100M_DB800ZL_SSD1_R_DP")
	)
	(segment
		(start 41.90746 -27.051)
		(end 41.768522 -27.189938)
		(width 0.13462)
		(layer "F.Cu")
		(net "CLK_100M_DB800ZL_SSD1_R_DP")
	)
	(segment
		(start 107.90428 -78.394306)
		(end 107.607354 -78.09738)
		(width 0.13462)
		(layer "F.Cu")
		(net "CLK_100M_DB800ZL_SSD1_R_DP")
	)
	(segment
		(start 41.768522 -27.189938)
		(end 41.26484 -27.189938)
		(width 0.13462)
		(layer "F.Cu")
		(net "CLK_100M_DB800ZL_SSD1_R_DP")
	)
	(via
		(at 42.981372 -27.342846)
		(size 0.508)
		(drill 0.254)
		(layers "F.Cu" "B.Cu")
		(net "CLK_100M_DB800ZL_SSD1_R_DP")
	)
	(via
		(at 107.607354 -78.09738)
		(size 0.508)
		(drill 0.254)
		(layers "F.Cu" "B.Cu")
		(net "CLK_100M_DB800ZL_SSD1_R_DP")
	)
	(segment
		(start 53.254402 -36.7284)
		(end 53.604922 -37.07892)
		(width 0.1651)
		(layer "In13.Cu")
		(net "CLK_100M_DB800ZL_SSD1_R_DP")
	)
	(segment
		(start 63.6524 -56.802274)
		(end 63.6524 -72.771)
		(width 0.1651)
		(layer "In13.Cu")
		(net "CLK_100M_DB800ZL_SSD1_R_DP")
	)
	(segment
		(start 53.254402 -36.566602)
		(end 53.254402 -36.7284)
		(width 0.1651)
		(layer "In13.Cu")
		(net "CLK_100M_DB800ZL_SSD1_R_DP")
	)
	(segment
		(start 107.898184 -77.80655)
		(end 107.607354 -78.09738)
		(width 0.1651)
		(layer "In13.Cu")
		(net "CLK_100M_DB800ZL_SSD1_R_DP")
	)
	(segment
		(start 43.835828 -27.051)
		(end 45.675296 -27.41676)
		(width 0.1651)
		(layer "In13.Cu")
		(net "CLK_100M_DB800ZL_SSD1_R_DP")
	)
	(segment
		(start 53.76672 -37.07892)
		(end 63.144146 -46.456346)
		(width 0.1651)
		(layer "In13.Cu")
		(net "CLK_100M_DB800ZL_SSD1_R_DP")
	)
	(segment
		(start 50.3174 -33.6296)
		(end 50.667412 -33.979612)
		(width 0.1651)
		(layer "In13.Cu")
		(net "CLK_100M_DB800ZL_SSD1_R_DP")
	)
	(segment
		(start 106.96956 -75.64374)
		(end 107.898184 -76.572364)
		(width 0.1651)
		(layer "In13.Cu")
		(net "CLK_100M_DB800ZL_SSD1_R_DP")
	)
	(segment
		(start 63.144146 -46.456346)
		(end 63.6524 -56.802274)
		(width 0.1651)
		(layer "In13.Cu")
		(net "CLK_100M_DB800ZL_SSD1_R_DP")
	)
	(segment
		(start 103.378 -76.7334)
		(end 104.46766 -75.64374)
		(width 0.1651)
		(layer "In13.Cu")
		(net "CLK_100M_DB800ZL_SSD1_R_DP")
	)
	(segment
		(start 46.867572 -27.911044)
		(end 48.601122 -28.255722)
		(width 0.1651)
		(layer "In13.Cu")
		(net "CLK_100M_DB800ZL_SSD1_R_DP")
	)
	(segment
		(start 51.529742 -34.841942)
		(end 51.529742 -35.00374)
		(width 0.1651)
		(layer "In13.Cu")
		(net "CLK_100M_DB800ZL_SSD1_R_DP")
	)
	(segment
		(start 52.04206 -35.35426)
		(end 52.392072 -35.704272)
		(width 0.1651)
		(layer "In13.Cu")
		(net "CLK_100M_DB800ZL_SSD1_R_DP")
	)
	(segment
		(start 51.17973 -34.49193)
		(end 51.529742 -34.841942)
		(width 0.1651)
		(layer "In13.Cu")
		(net "CLK_100M_DB800ZL_SSD1_R_DP")
	)
	(segment
		(start 48.601122 -28.255722)
		(end 50.3174 -29.972)
		(width 0.1651)
		(layer "In13.Cu")
		(net "CLK_100M_DB800ZL_SSD1_R_DP")
	)
	(segment
		(start 91.567 -76.7334)
		(end 103.378 -76.7334)
		(width 0.1651)
		(layer "In13.Cu")
		(net "CLK_100M_DB800ZL_SSD1_R_DP")
	)
	(segment
		(start 66.3448 -75.4634)
		(end 90.297 -75.4634)
		(width 0.1651)
		(layer "In13.Cu")
		(net "CLK_100M_DB800ZL_SSD1_R_DP")
	)
	(segment
		(start 52.742592 -36.21659)
		(end 52.90439 -36.21659)
		(width 0.1651)
		(layer "In13.Cu")
		(net "CLK_100M_DB800ZL_SSD1_R_DP")
	)
	(segment
		(start 53.604922 -37.07892)
		(end 53.76672 -37.07892)
		(width 0.1651)
		(layer "In13.Cu")
		(net "CLK_100M_DB800ZL_SSD1_R_DP")
	)
	(segment
		(start 107.898184 -76.572364)
		(end 107.898184 -77.80655)
		(width 0.1651)
		(layer "In13.Cu")
		(net "CLK_100M_DB800ZL_SSD1_R_DP")
	)
	(segment
		(start 43.273218 -27.051)
		(end 43.835828 -27.051)
		(width 0.1651)
		(layer "In13.Cu")
		(net "CLK_100M_DB800ZL_SSD1_R_DP")
	)
	(segment
		(start 50.3174 -29.972)
		(end 50.3174 -33.6296)
		(width 0.1651)
		(layer "In13.Cu")
		(net "CLK_100M_DB800ZL_SSD1_R_DP")
	)
	(segment
		(start 104.46766 -75.64374)
		(end 106.96956 -75.64374)
		(width 0.1651)
		(layer "In13.Cu")
		(net "CLK_100M_DB800ZL_SSD1_R_DP")
	)
	(segment
		(start 90.297 -75.4634)
		(end 91.567 -76.7334)
		(width 0.1651)
		(layer "In13.Cu")
		(net "CLK_100M_DB800ZL_SSD1_R_DP")
	)
	(segment
		(start 51.017932 -34.49193)
		(end 51.17973 -34.49193)
		(width 0.1651)
		(layer "In13.Cu")
		(net "CLK_100M_DB800ZL_SSD1_R_DP")
	)
	(segment
		(start 63.6524 -72.771)
		(end 66.3448 -75.4634)
		(width 0.1651)
		(layer "In13.Cu")
		(net "CLK_100M_DB800ZL_SSD1_R_DP")
	)
	(segment
		(start 51.880262 -35.35426)
		(end 52.04206 -35.35426)
		(width 0.1651)
		(layer "In13.Cu")
		(net "CLK_100M_DB800ZL_SSD1_R_DP")
	)
	(segment
		(start 45.675296 -27.41676)
		(end 46.867572 -27.911044)
		(width 0.1651)
		(layer "In13.Cu")
		(net "CLK_100M_DB800ZL_SSD1_R_DP")
	)
	(segment
		(start 50.667412 -34.14141)
		(end 51.017932 -34.49193)
		(width 0.1651)
		(layer "In13.Cu")
		(net "CLK_100M_DB800ZL_SSD1_R_DP")
	)
	(segment
		(start 52.392072 -35.704272)
		(end 52.392072 -35.86607)
		(width 0.1651)
		(layer "In13.Cu")
		(net "CLK_100M_DB800ZL_SSD1_R_DP")
	)
	(segment
		(start 42.981372 -27.342846)
		(end 43.273218 -27.051)
		(width 0.1651)
		(layer "In13.Cu")
		(net "CLK_100M_DB800ZL_SSD1_R_DP")
	)
	(segment
		(start 52.90439 -36.21659)
		(end 53.254402 -36.566602)
		(width 0.1651)
		(layer "In13.Cu")
		(net "CLK_100M_DB800ZL_SSD1_R_DP")
	)
	(segment
		(start 52.392072 -35.86607)
		(end 52.742592 -36.21659)
		(width 0.1651)
		(layer "In13.Cu")
		(net "CLK_100M_DB800ZL_SSD1_R_DP")
	)
	(segment
		(start 50.667412 -33.979612)
		(end 50.667412 -34.14141)
		(width 0.1651)
		(layer "In13.Cu")
		(net "CLK_100M_DB800ZL_SSD1_R_DP")
	)
	(segment
		(start 51.529742 -35.00374)
		(end 51.880262 -35.35426)
		(width 0.1651)
		(layer "In13.Cu")
		(net "CLK_100M_DB800ZL_SSD1_R_DP")
	)
	(segment
		(start 33.486344 -251.158502)
		(end 33.486344 -250.470924)
		(width 0.13208)
		(layer "F.Cu")
		(net "PEX0_DBG_MODE2")
	)
	(segment
		(start 64.399922 -282.599892)
		(end 64.874902 -283.074872)
		(width 0.13208)
		(layer "F.Cu")
		(net "PEX0_DBG_MODE2")
	)
	(segment
		(start 33.486344 -251.956824)
		(end 33.486344 -251.158502)
		(width 0.13208)
		(layer "F.Cu")
		(net "PEX0_DBG_MODE2")
	)
	(via
		(at 64.874902 -283.074872)
		(size 0.4064)
		(drill 0.2032)
		(layers "F.Cu" "B.Cu")
		(net "PEX0_DBG_MODE2")
	)
	(via
		(at 33.486344 -251.158502)
		(size 0.508)
		(drill 0.254)
		(layers "F.Cu" "B.Cu")
		(net "PEX0_DBG_MODE2")
	)
	(via
		(at 61.111638 -267.544296)
		(size 0.6604)
		(drill 0.3302)
		(layers "F.Cu" "B.Cu")
		(net "PEX0_DBG_MODE2")
	)
	(segment
		(start 65.256156 -271.275302)
		(end 64.842644 -271.275302)
		(width 0.13208)
		(layer "B.Cu")
		(net "PEX0_DBG_MODE2")
	)
	(segment
		(start 65.837816 -282.111958)
		(end 65.837816 -271.856962)
		(width 0.13208)
		(layer "B.Cu")
		(net "PEX0_DBG_MODE2")
	)
	(segment
		(start 35.712146 -256.1844)
		(end 49.751742 -256.1844)
		(width 0.13208)
		(layer "B.Cu")
		(net "PEX0_DBG_MODE2")
	)
	(segment
		(start 32.993838 -254.515874)
		(end 33.747964 -255.27)
		(width 0.13208)
		(layer "B.Cu")
		(net "PEX0_DBG_MODE2")
	)
	(segment
		(start 33.747964 -255.27)
		(end 34.797746 -255.27)
		(width 0.13208)
		(layer "B.Cu")
		(net "PEX0_DBG_MODE2")
	)
	(segment
		(start 33.486344 -251.158502)
		(end 32.993838 -251.651008)
		(width 0.13208)
		(layer "B.Cu")
		(net "PEX0_DBG_MODE2")
	)
	(segment
		(start 65.837816 -271.856962)
		(end 65.256156 -271.275302)
		(width 0.13208)
		(layer "B.Cu")
		(net "PEX0_DBG_MODE2")
	)
	(segment
		(start 64.874902 -283.074872)
		(end 65.837816 -282.111958)
		(width 0.13208)
		(layer "B.Cu")
		(net "PEX0_DBG_MODE2")
	)
	(segment
		(start 49.751742 -256.1844)
		(end 61.111638 -267.544296)
		(width 0.13208)
		(layer "B.Cu")
		(net "PEX0_DBG_MODE2")
	)
	(segment
		(start 32.993838 -251.651008)
		(end 32.993838 -254.515874)
		(width 0.13208)
		(layer "B.Cu")
		(net "PEX0_DBG_MODE2")
	)
	(segment
		(start 34.797746 -255.27)
		(end 35.712146 -256.1844)
		(width 0.13208)
		(layer "B.Cu")
		(net "PEX0_DBG_MODE2")
	)
	(segment
		(start 64.842644 -271.275302)
		(end 61.111638 -267.544296)
		(width 0.13208)
		(layer "B.Cu")
		(net "PEX0_DBG_MODE2")
	)
	(segment
		(start 218.862402 -216.697814)
		(end 219.759784 -216.697814)
		(width 0.13208)
		(layer "F.Cu")
		(net "SMB_NIC6_SCL")
	)
	(segment
		(start 215.041226 -215.749632)
		(end 217.114882 -215.749632)
		(width 0.13208)
		(layer "F.Cu")
		(net "SMB_NIC6_SCL")
	)
	(segment
		(start 217.114882 -215.749632)
		(end 217.635836 -216.270586)
		(width 0.13208)
		(layer "F.Cu")
		(net "SMB_NIC6_SCL")
	)
	(segment
		(start 219.940632 -216.516966)
		(end 220.390974 -216.516966)
		(width 0.13208)
		(layer "F.Cu")
		(net "SMB_NIC6_SCL")
	)
	(segment
		(start 217.635836 -216.270586)
		(end 218.063064 -216.697814)
		(width 0.13208)
		(layer "F.Cu")
		(net "SMB_NIC6_SCL")
	)
	(segment
		(start 214.854536 -215.936322)
		(end 215.041226 -215.749632)
		(width 0.13208)
		(layer "F.Cu")
		(net "SMB_NIC6_SCL")
	)
	(segment
		(start 220.390974 -216.516966)
		(end 221.781878 -217.90787)
		(width 0.13208)
		(layer "F.Cu")
		(net "SMB_NIC6_SCL")
	)
	(segment
		(start 219.759784 -216.697814)
		(end 219.940632 -216.516966)
		(width 0.13208)
		(layer "F.Cu")
		(net "SMB_NIC6_SCL")
	)
	(segment
		(start 221.781878 -217.90787)
		(end 223.871536 -217.90787)
		(width 0.13208)
		(layer "F.Cu")
		(net "SMB_NIC6_SCL")
	)
	(segment
		(start 218.063064 -216.697814)
		(end 218.862402 -216.697814)
		(width 0.13208)
		(layer "F.Cu")
		(net "SMB_NIC6_SCL")
	)
	(segment
		(start 214.854536 -216.270586)
		(end 214.854536 -215.936322)
		(width 0.13208)
		(layer "F.Cu")
		(net "SMB_NIC6_SCL")
	)
	(segment
		(start 223.871536 -217.90787)
		(end 224.267776 -218.30411)
		(width 0.13208)
		(layer "F.Cu")
		(net "SMB_NIC6_SCL")
	)
	(via
		(at 218.862402 -216.697814)
		(size 0.762)
		(drill 0.381)
		(layers "F.Cu" "B.Cu")
		(net "SMB_NIC6_SCL")
	)
	(segment
		(start 104.161844 -85.54593)
		(end 104.557322 -85.54593)
		(width 0.13208)
		(layer "F.Cu")
		(net "SMB_BMC_9ZXL0851_0_7_SDA")
	)
	(segment
		(start 104.557322 -85.54593)
		(end 105.19029 -86.178898)
		(width 0.13208)
		(layer "F.Cu")
		(net "SMB_BMC_9ZXL0851_0_7_SDA")
	)
	(segment
		(start 105.19029 -86.178898)
		(end 105.889044 -86.178898)
		(width 0.13208)
		(layer "F.Cu")
		(net "SMB_BMC_9ZXL0851_0_7_SDA")
	)
	(segment
		(start 103.717598 -85.54593)
		(end 103.411274 -85.239606)
		(width 0.13208)
		(layer "F.Cu")
		(net "SMB_BMC_9ZXL0851_0_7_SDA")
	)
	(segment
		(start 104.161844 -85.54593)
		(end 103.717598 -85.54593)
		(width 0.13208)
		(layer "F.Cu")
		(net "SMB_BMC_9ZXL0851_0_7_SDA")
	)
	(via
		(at 104.161844 -85.54593)
		(size 0.508)
		(drill 0.254)
		(layers "F.Cu" "B.Cu")
		(net "SMB_BMC_9ZXL0851_0_7_SDA")
	)
	(segment
		(start 59.810904 -61.386974)
		(end 59.64809 -61.22416)
		(width 0.13208)
		(layer "F.Cu")
		(net "PWRGD_P3V3_SSD2")
	)
	(segment
		(start 60.025026 -57.867296)
		(end 60.025026 -57.841896)
		(width 0.13208)
		(layer "F.Cu")
		(net "PWRGD_P3V3_SSD2")
	)
	(segment
		(start 59.64809 -59.343544)
		(end 59.813698 -59.177936)
		(width 0.13208)
		(layer "F.Cu")
		(net "PWRGD_P3V3_SSD2")
	)
	(segment
		(start 59.813698 -59.177936)
		(end 60.17895 -59.177936)
		(width 0.13208)
		(layer "F.Cu")
		(net "PWRGD_P3V3_SSD2")
	)
	(segment
		(start 60.025026 -57.841896)
		(end 59.640978 -57.457848)
		(width 0.13208)
		(layer "F.Cu")
		(net "PWRGD_P3V3_SSD2")
	)
	(segment
		(start 60.17895 -59.177936)
		(end 60.17895 -58.71972)
		(width 0.13208)
		(layer "F.Cu")
		(net "PWRGD_P3V3_SSD2")
	)
	(segment
		(start 59.640978 -57.457848)
		(end 59.640978 -57.16397)
		(width 0.13208)
		(layer "F.Cu")
		(net "PWRGD_P3V3_SSD2")
	)
	(segment
		(start 59.64809 -61.22416)
		(end 59.64809 -59.343544)
		(width 0.13208)
		(layer "F.Cu")
		(net "PWRGD_P3V3_SSD2")
	)
	(segment
		(start 60.025026 -58.565796)
		(end 60.025026 -57.867296)
		(width 0.13208)
		(layer "F.Cu")
		(net "PWRGD_P3V3_SSD2")
	)
	(segment
		(start 60.17895 -58.71972)
		(end 60.025026 -58.565796)
		(width 0.13208)
		(layer "F.Cu")
		(net "PWRGD_P3V3_SSD2")
	)
	(via
		(at 60.025026 -57.867296)
		(size 0.508)
		(drill 0.254)
		(layers "F.Cu" "B.Cu")
		(net "PWRGD_P3V3_SSD2")
	)
	(segment
		(start 340.493858 -211.98713)
		(end 340.097618 -211.59089)
		(width 0.13208)
		(layer "F.Cu")
		(net "SSD12_PWRDIS")
	)
	(segment
		(start 339.598 -209.425032)
		(end 339.598 -206.8068)
		(width 0.13208)
		(layer "F.Cu")
		(net "SSD12_PWRDIS")
	)
	(segment
		(start 340.097618 -211.59089)
		(end 340.097618 -209.92465)
		(width 0.13208)
		(layer "F.Cu")
		(net "SSD12_PWRDIS")
	)
	(segment
		(start 339.598 -206.8068)
		(end 339.598 -205.63205)
		(width 0.13208)
		(layer "F.Cu")
		(net "SSD12_PWRDIS")
	)
	(segment
		(start 340.097618 -209.92465)
		(end 339.598 -209.425032)
		(width 0.13208)
		(layer "F.Cu")
		(net "SSD12_PWRDIS")
	)
	(via
		(at 339.598 -206.8068)
		(size 0.762)
		(drill 0.381)
		(layers "F.Cu" "B.Cu")
		(net "SSD12_PWRDIS")
	)
	(segment
		(start 407.244296 -59.012582)
		(end 407.244296 -58.561224)
		(width 0.13208)
		(layer "F.Cu")
		(net "P3V3_SSD14_OCP")
	)
	(segment
		(start 407.440892 -58.364628)
		(end 407.244296 -58.561224)
		(width 0.13208)
		(layer "F.Cu")
		(net "P3V3_SSD14_OCP")
	)
	(segment
		(start 407.440892 -57.16397)
		(end 407.440892 -58.364628)
		(width 0.13208)
		(layer "F.Cu")
		(net "P3V3_SSD14_OCP")
	)
	(segment
		(start 407.4033 -59.171586)
		(end 407.244296 -59.012582)
		(width 0.13208)
		(layer "F.Cu")
		(net "P3V3_SSD14_OCP")
	)
	(via
		(at 407.244296 -58.561224)
		(size 0.508)
		(drill 0.254)
		(layers "F.Cu" "B.Cu")
		(net "P3V3_SSD14_OCP")
	)
	(segment
		(start 110.1852 -77.62113)
		(end 110.47095 -77.33538)
		(width 0.13462)
		(layer "F.Cu")
		(net "CLK_100M_DB800ZL_SSD2_R_DN")
	)
	(segment
		(start 67.754754 -26.58999)
		(end 67.264788 -26.58999)
		(width 0.13462)
		(layer "F.Cu")
		(net "CLK_100M_DB800ZL_SSD2_R_DN")
	)
	(segment
		(start 68.683886 -26.77668)
		(end 67.941444 -26.77668)
		(width 0.13462)
		(layer "F.Cu")
		(net "CLK_100M_DB800ZL_SSD2_R_DN")
	)
	(segment
		(start 68.98132 -26.479246)
		(end 68.683886 -26.77668)
		(width 0.13462)
		(layer "F.Cu")
		(net "CLK_100M_DB800ZL_SSD2_R_DN")
	)
	(segment
		(start 110.49635 -79.422244)
		(end 110.1852 -79.111094)
		(width 0.13462)
		(layer "F.Cu")
		(net "CLK_100M_DB800ZL_SSD2_R_DN")
	)
	(segment
		(start 110.1852 -79.111094)
		(end 110.1852 -77.62113)
		(width 0.13462)
		(layer "F.Cu")
		(net "CLK_100M_DB800ZL_SSD2_R_DN")
	)
	(segment
		(start 67.941444 -26.77668)
		(end 67.754754 -26.58999)
		(width 0.13462)
		(layer "F.Cu")
		(net "CLK_100M_DB800ZL_SSD2_R_DN")
	)
	(via
		(at 68.98132 -26.479246)
		(size 0.508)
		(drill 0.254)
		(layers "F.Cu" "B.Cu")
		(net "CLK_100M_DB800ZL_SSD2_R_DN")
	)
	(via
		(at 110.47095 -77.33538)
		(size 0.508)
		(drill 0.254)
		(layers "F.Cu" "B.Cu")
		(net "CLK_100M_DB800ZL_SSD2_R_DN")
	)
	(segment
		(start 105.71988 -74.153268)
		(end 105.71988 -73.523856)
		(width 0.1651)
		(layer "In13.Cu")
		(net "CLK_100M_DB800ZL_SSD2_R_DN")
	)
	(segment
		(start 105.8545 -73.389236)
		(end 108.03382 -73.389236)
		(width 0.1651)
		(layer "In13.Cu")
		(net "CLK_100M_DB800ZL_SSD2_R_DN")
	)
	(segment
		(start 105.70464 -71.166736)
		(end 105.8545 -71.016876)
		(width 0.1651)
		(layer "In13.Cu")
		(net "CLK_100M_DB800ZL_SSD2_R_DN")
	)
	(segment
		(start 108.431076 -74.293476)
		(end 105.860088 -74.293476)
		(width 0.1651)
		(layer "In13.Cu")
		(net "CLK_100M_DB800ZL_SSD2_R_DN")
	)
	(segment
		(start 78.384654 -34.549588)
		(end 78.384654 -31.961328)
		(width 0.1651)
		(layer "In13.Cu")
		(net "CLK_100M_DB800ZL_SSD2_R_DN")
	)
	(segment
		(start 78.384654 -31.961328)
		(end 74.84872 -28.425394)
		(width 0.1651)
		(layer "In13.Cu")
		(net "CLK_100M_DB800ZL_SSD2_R_DN")
	)
	(segment
		(start 108.339128 -69.869304)
		(end 108.03382 -69.563996)
		(width 0.1651)
		(layer "In13.Cu")
		(net "CLK_100M_DB800ZL_SSD2_R_DN")
	)
	(segment
		(start 105.70464 -71.786496)
		(end 105.70464 -71.166736)
		(width 0.1651)
		(layer "In13.Cu")
		(net "CLK_100M_DB800ZL_SSD2_R_DN")
	)
	(segment
		(start 110.47095 -77.33538)
		(end 110.182406 -77.046836)
		(width 0.1651)
		(layer "In13.Cu")
		(net "CLK_100M_DB800ZL_SSD2_R_DN")
	)
	(segment
		(start 70.11924 -26.7716)
		(end 69.273674 -26.7716)
		(width 0.1651)
		(layer "In13.Cu")
		(net "CLK_100M_DB800ZL_SSD2_R_DN")
	)
	(segment
		(start 74.84872 -28.425394)
		(end 71.53402 -27.053032)
		(width 0.1651)
		(layer "In13.Cu")
		(net "CLK_100M_DB800ZL_SSD2_R_DN")
	)
	(segment
		(start 108.03382 -69.563996)
		(end 103.782876 -69.563996)
		(width 0.1651)
		(layer "In13.Cu")
		(net "CLK_100M_DB800ZL_SSD2_R_DN")
	)
	(segment
		(start 69.273674 -26.7716)
		(end 68.98132 -26.479246)
		(width 0.1651)
		(layer "In13.Cu")
		(net "CLK_100M_DB800ZL_SSD2_R_DN")
	)
	(segment
		(start 105.8545 -71.936356)
		(end 105.70464 -71.786496)
		(width 0.1651)
		(layer "In13.Cu")
		(net "CLK_100M_DB800ZL_SSD2_R_DN")
	)
	(segment
		(start 103.45547 -74.35215)
		(end 102.226872 -75.580748)
		(width 0.1651)
		(layer "In13.Cu")
		(net "CLK_100M_DB800ZL_SSD2_R_DN")
	)
	(segment
		(start 108.339128 -72.241664)
		(end 108.03382 -71.936356)
		(width 0.1651)
		(layer "In13.Cu")
		(net "CLK_100M_DB800ZL_SSD2_R_DN")
	)
	(segment
		(start 108.03382 -71.936356)
		(end 105.8545 -71.936356)
		(width 0.1651)
		(layer "In13.Cu")
		(net "CLK_100M_DB800ZL_SSD2_R_DN")
	)
	(segment
		(start 108.03382 -73.389236)
		(end 108.339128 -73.083928)
		(width 0.1651)
		(layer "In13.Cu")
		(net "CLK_100M_DB800ZL_SSD2_R_DN")
	)
	(segment
		(start 103.45547 -69.891402)
		(end 103.45547 -74.35215)
		(width 0.1651)
		(layer "In13.Cu")
		(net "CLK_100M_DB800ZL_SSD2_R_DN")
	)
	(segment
		(start 110.182406 -77.046836)
		(end 110.182406 -76.044806)
		(width 0.1651)
		(layer "In13.Cu")
		(net "CLK_100M_DB800ZL_SSD2_R_DN")
	)
	(segment
		(start 108.03382 -71.016876)
		(end 108.339128 -70.711568)
		(width 0.1651)
		(layer "In13.Cu")
		(net "CLK_100M_DB800ZL_SSD2_R_DN")
	)
	(segment
		(start 89.38514 -45.550074)
		(end 78.384654 -34.549588)
		(width 0.1651)
		(layer "In13.Cu")
		(net "CLK_100M_DB800ZL_SSD2_R_DN")
	)
	(segment
		(start 102.226872 -75.580748)
		(end 92.070428 -75.580748)
		(width 0.1651)
		(layer "In13.Cu")
		(net "CLK_100M_DB800ZL_SSD2_R_DN")
	)
	(segment
		(start 105.71988 -73.523856)
		(end 105.8545 -73.389236)
		(width 0.1651)
		(layer "In13.Cu")
		(net "CLK_100M_DB800ZL_SSD2_R_DN")
	)
	(segment
		(start 105.8545 -71.016876)
		(end 108.03382 -71.016876)
		(width 0.1651)
		(layer "In13.Cu")
		(net "CLK_100M_DB800ZL_SSD2_R_DN")
	)
	(segment
		(start 92.070428 -75.580748)
		(end 90.354404 -73.864724)
		(width 0.1651)
		(layer "In13.Cu")
		(net "CLK_100M_DB800ZL_SSD2_R_DN")
	)
	(segment
		(start 108.339128 -73.083928)
		(end 108.339128 -72.241664)
		(width 0.1651)
		(layer "In13.Cu")
		(net "CLK_100M_DB800ZL_SSD2_R_DN")
	)
	(segment
		(start 108.339128 -70.711568)
		(end 108.339128 -69.869304)
		(width 0.1651)
		(layer "In13.Cu")
		(net "CLK_100M_DB800ZL_SSD2_R_DN")
	)
	(segment
		(start 105.860088 -74.293476)
		(end 105.71988 -74.153268)
		(width 0.1651)
		(layer "In13.Cu")
		(net "CLK_100M_DB800ZL_SSD2_R_DN")
	)
	(segment
		(start 103.782876 -69.563996)
		(end 103.45547 -69.891402)
		(width 0.1651)
		(layer "In13.Cu")
		(net "CLK_100M_DB800ZL_SSD2_R_DN")
	)
	(segment
		(start 110.182406 -76.044806)
		(end 108.431076 -74.293476)
		(width 0.1651)
		(layer "In13.Cu")
		(net "CLK_100M_DB800ZL_SSD2_R_DN")
	)
	(segment
		(start 90.546428 -64.916558)
		(end 89.38514 -45.550074)
		(width 0.1651)
		(layer "In13.Cu")
		(net "CLK_100M_DB800ZL_SSD2_R_DN")
	)
	(segment
		(start 90.354404 -73.864724)
		(end 90.546428 -64.916558)
		(width 0.1651)
		(layer "In13.Cu")
		(net "CLK_100M_DB800ZL_SSD2_R_DN")
	)
	(segment
		(start 71.53402 -27.053032)
		(end 70.11924 -26.7716)
		(width 0.1651)
		(layer "In13.Cu")
		(net "CLK_100M_DB800ZL_SSD2_R_DN")
	)
	(segment
		(start 375.690384 -251.158502)
		(end 375.690384 -250.470924)
		(width 0.13208)
		(layer "F.Cu")
		(net "PEX3_MODE_SEL5")
	)
	(segment
		(start 407.949908 -282.599892)
		(end 408.424888 -283.074872)
		(width 0.1651)
		(layer "F.Cu")
		(net "PEX3_MODE_SEL5")
	)
	(segment
		(start 375.690384 -251.956824)
		(end 375.690384 -251.158502)
		(width 0.13208)
		(layer "F.Cu")
		(net "PEX3_MODE_SEL5")
	)
	(via
		(at 375.690384 -251.158502)
		(size 0.508)
		(drill 0.254)
		(layers "F.Cu" "B.Cu")
		(net "PEX3_MODE_SEL5")
	)
	(via
		(at 405.238966 -268.21765)
		(size 0.6604)
		(drill 0.3302)
		(layers "F.Cu" "B.Cu")
		(net "PEX3_MODE_SEL5")
	)
	(via
		(at 408.424888 -283.074872)
		(size 0.4064)
		(drill 0.2032)
		(layers "F.Cu" "B.Cu")
		(net "PEX3_MODE_SEL5")
	)
	(segment
		(start 405.238966 -268.21765)
		(end 408.424888 -271.403572)
		(width 0.13208)
		(layer "B.Cu")
		(net "PEX3_MODE_SEL5")
	)
	(segment
		(start 408.424888 -271.403572)
		(end 408.424888 -283.074872)
		(width 0.13208)
		(layer "B.Cu")
		(net "PEX3_MODE_SEL5")
	)
	(segment
		(start 376.53976 -257.68427)
		(end 381.544322 -257.68427)
		(width 0.13208)
		(layer "B.Cu")
		(net "PEX3_MODE_SEL5")
	)
	(segment
		(start 375.197624 -251.651262)
		(end 375.197624 -256.342134)
		(width 0.13208)
		(layer "B.Cu")
		(net "PEX3_MODE_SEL5")
	)
	(segment
		(start 382.162812 -258.30276)
		(end 395.324076 -258.30276)
		(width 0.13208)
		(layer "B.Cu")
		(net "PEX3_MODE_SEL5")
	)
	(segment
		(start 395.324076 -258.30276)
		(end 405.238966 -268.21765)
		(width 0.13208)
		(layer "B.Cu")
		(net "PEX3_MODE_SEL5")
	)
	(segment
		(start 381.544322 -257.68427)
		(end 382.162812 -258.30276)
		(width 0.13208)
		(layer "B.Cu")
		(net "PEX3_MODE_SEL5")
	)
	(segment
		(start 375.690384 -251.158502)
		(end 375.197624 -251.651262)
		(width 0.13208)
		(layer "B.Cu")
		(net "PEX3_MODE_SEL5")
	)
	(segment
		(start 375.197624 -256.342134)
		(end 376.53976 -257.68427)
		(width 0.13208)
		(layer "B.Cu")
		(net "PEX3_MODE_SEL5")
	)
	(segment
		(start 225.067622 -222.304102)
		(end 224.667826 -222.703898)
		(width 0.13208)
		(layer "F.Cu")
		(net "SMB_NIC1_SDA")
	)
	(via
		(at 224.667826 -222.703898)
		(size 0.4572)
		(drill 0.254)
		(layers "F.Cu" "B.Cu")
		(net "SMB_NIC1_SDA")
	)
	(via
		(at 223.338644 -227.376482)
		(size 0.6604)
		(drill 0.3302)
		(layers "F.Cu" "B.Cu")
		(net "SMB_NIC1_SDA")
	)
	(segment
		(start 224.26422 -223.346264)
		(end 224.26422 -225.552)
		(width 0.0889)
		(layer "B.Cu")
		(net "SMB_NIC1_SDA")
	)
	(segment
		(start 224.667826 -222.703898)
		(end 224.498916 -223.111568)
		(width 0.0889)
		(layer "B.Cu")
		(net "SMB_NIC1_SDA")
	)
	(segment
		(start 224.26422 -225.552)
		(end 224.26422 -226.450906)
		(width 0.13208)
		(layer "B.Cu")
		(net "SMB_NIC1_SDA")
	)
	(segment
		(start 224.26422 -226.450906)
		(end 223.338644 -227.376482)
		(width 0.13208)
		(layer "B.Cu")
		(net "SMB_NIC1_SDA")
	)
	(segment
		(start 224.498916 -223.111568)
		(end 224.26422 -223.346264)
		(width 0.0889)
		(layer "B.Cu")
		(net "SMB_NIC1_SDA")
	)
	(segment
		(start 223.338644 -230.825548)
		(end 223.338644 -227.376482)
		(width 0.13208)
		(layer "B.Cu")
		(net "SMB_NIC1_SDA")
	)
	(segment
		(start 58.575448 -379.567694)
		(end 58.575448 -378.573792)
		(width 0.13208)
		(layer "F.Cu")
		(net "GPU_BASE_ID1")
	)
	(segment
		(start 58.576972 -378.572268)
		(end 58.967116 -378.572268)
		(width 0.13208)
		(layer "F.Cu")
		(net "GPU_BASE_ID1")
	)
	(segment
		(start 58.575448 -378.573792)
		(end 58.576972 -378.572268)
		(width 0.13208)
		(layer "F.Cu")
		(net "GPU_BASE_ID1")
	)
	(segment
		(start 58.967116 -378.572268)
		(end 59.224164 -378.829316)
		(width 0.13208)
		(layer "F.Cu")
		(net "GPU_BASE_ID1")
	)
	(via
		(at 59.224164 -378.829316)
		(size 0.508)
		(drill 0.254)
		(layers "F.Cu" "B.Cu")
		(net "GPU_BASE_ID1")
	)
	(segment
		(start 57.832752 -374.690132)
		(end 57.832752 -377.437904)
		(width 0.15494)
		(layer "In15.Cu")
		(net "GPU_BASE_ID1")
	)
	(segment
		(start 87.30996 -368.990118)
		(end 86.35492 -368.990118)
		(width 0.15494)
		(layer "In15.Cu")
		(net "GPU_BASE_ID1")
	)
	(segment
		(start 84.623402 -367.2586)
		(end 65.264284 -367.2586)
		(width 0.15494)
		(layer "In15.Cu")
		(net "GPU_BASE_ID1")
	)
	(segment
		(start 57.832752 -377.437904)
		(end 59.224164 -378.829316)
		(width 0.15494)
		(layer "In15.Cu")
		(net "GPU_BASE_ID1")
	)
	(segment
		(start 86.35492 -368.990118)
		(end 84.623402 -367.2586)
		(width 0.15494)
		(layer "In15.Cu")
		(net "GPU_BASE_ID1")
	)
	(segment
		(start 65.264284 -367.2586)
		(end 57.832752 -374.690132)
		(width 0.15494)
		(layer "In15.Cu")
		(net "GPU_BASE_ID1")
	)
	(segment
		(start 146.703034 -392.179302)
		(end 146.730466 -392.179302)
		(width 0.13208)
		(layer "F.Cu")
		(net "SMB_GPU2_ALERT_R_N")
	)
	(segment
		(start 146.730466 -392.179302)
		(end 147.271486 -391.638282)
		(width 0.13208)
		(layer "F.Cu")
		(net "SMB_GPU2_ALERT_R_N")
	)
	(segment
		(start 147.271486 -391.638282)
		(end 147.271486 -390.798304)
		(width 0.13208)
		(layer "F.Cu")
		(net "SMB_GPU2_ALERT_R_N")
	)
	(via
		(at 146.703034 -392.179302)
		(size 0.508)
		(drill 0.254)
		(layers "F.Cu" "B.Cu")
		(net "SMB_GPU2_ALERT_R_N")
	)
	(segment
		(start 136.174988 -409.9306)
		(end 138.4554 -407.650188)
		(width 0.15494)
		(layer "In9.Cu")
		(net "SMB_GPU2_ALERT_R_N")
	)
	(segment
		(start 142.334234 -391.305034)
		(end 143.208502 -392.179302)
		(width 0.15494)
		(layer "In9.Cu")
		(net "SMB_GPU2_ALERT_R_N")
	)
	(segment
		(start 143.208502 -392.179302)
		(end 146.703034 -392.179302)
		(width 0.15494)
		(layer "In9.Cu")
		(net "SMB_GPU2_ALERT_R_N")
	)
	(segment
		(start 134.554214 -409.9306)
		(end 136.174988 -409.9306)
		(width 0.15494)
		(layer "In9.Cu")
		(net "SMB_GPU2_ALERT_R_N")
	)
	(segment
		(start 138.4554 -407.650188)
		(end 138.4554 -393.420854)
		(width 0.15494)
		(layer "In9.Cu")
		(net "SMB_GPU2_ALERT_R_N")
	)
	(segment
		(start 140.57122 -391.305034)
		(end 142.334234 -391.305034)
		(width 0.15494)
		(layer "In9.Cu")
		(net "SMB_GPU2_ALERT_R_N")
	)
	(segment
		(start 133.51002 -409.490164)
		(end 134.113778 -409.490164)
		(width 0.15494)
		(layer "In9.Cu")
		(net "SMB_GPU2_ALERT_R_N")
	)
	(segment
		(start 138.4554 -393.420854)
		(end 140.57122 -391.305034)
		(width 0.15494)
		(layer "In9.Cu")
		(net "SMB_GPU2_ALERT_R_N")
	)
	(segment
		(start 134.113778 -409.490164)
		(end 134.554214 -409.9306)
		(width 0.15494)
		(layer "In9.Cu")
		(net "SMB_GPU2_ALERT_R_N")
	)
	(segment
		(start 339.344 -238.23295)
		(end 339.344 -237.25505)
		(width 0.13208)
		(layer "F.Cu")
		(net "RST_MB_PERST_2_ISO_R_N")
	)
	(segment
		(start 339.269324 -237.180374)
		(end 338.615528 -237.180374)
		(width 0.13208)
		(layer "F.Cu")
		(net "RST_MB_PERST_2_ISO_R_N")
	)
	(segment
		(start 339.344 -237.25505)
		(end 339.269324 -237.180374)
		(width 0.13208)
		(layer "F.Cu")
		(net "RST_MB_PERST_2_ISO_R_N")
	)
	(segment
		(start 338.093812 -224.786952)
		(end 337.694016 -225.186748)
		(width 0.13208)
		(layer "F.Cu")
		(net "RST_MB_PERST_2_ISO_R_N")
	)
	(via
		(at 337.694016 -225.186748)
		(size 0.4572)
		(drill 0.254)
		(layers "F.Cu" "B.Cu")
		(net "RST_MB_PERST_2_ISO_R_N")
	)
	(via
		(at 338.615528 -237.180374)
		(size 0.508)
		(drill 0.254)
		(layers "F.Cu" "B.Cu")
		(net "RST_MB_PERST_2_ISO_R_N")
	)
	(segment
		(start 338.455 -234.085638)
		(end 338.455 -235.676186)
		(width 0.15494)
		(layer "In7.Cu")
		(net "RST_MB_PERST_2_ISO_R_N")
	)
	(segment
		(start 337.694016 -225.186748)
		(end 338.094066 -225.586798)
		(width 0.0889)
		(layer "In7.Cu")
		(net "RST_MB_PERST_2_ISO_R_N")
	)
	(segment
		(start 337.47329 -233.103928)
		(end 338.455 -234.085638)
		(width 0.15494)
		(layer "In7.Cu")
		(net "RST_MB_PERST_2_ISO_R_N")
	)
	(segment
		(start 338.199984 -235.931202)
		(end 338.199984 -236.76483)
		(width 0.15494)
		(layer "In7.Cu")
		(net "RST_MB_PERST_2_ISO_R_N")
	)
	(segment
		(start 337.47329 -229.700836)
		(end 337.47329 -233.103928)
		(width 0.15494)
		(layer "In7.Cu")
		(net "RST_MB_PERST_2_ISO_R_N")
	)
	(segment
		(start 338.455 -235.676186)
		(end 338.199984 -235.931202)
		(width 0.15494)
		(layer "In7.Cu")
		(net "RST_MB_PERST_2_ISO_R_N")
	)
	(segment
		(start 338.094066 -225.586798)
		(end 338.094066 -227.076)
		(width 0.0889)
		(layer "In7.Cu")
		(net "RST_MB_PERST_2_ISO_R_N")
	)
	(segment
		(start 338.094066 -227.680012)
		(end 337.655408 -228.11867)
		(width 0.15494)
		(layer "In7.Cu")
		(net "RST_MB_PERST_2_ISO_R_N")
	)
	(segment
		(start 337.655408 -229.518718)
		(end 337.47329 -229.700836)
		(width 0.15494)
		(layer "In7.Cu")
		(net "RST_MB_PERST_2_ISO_R_N")
	)
	(segment
		(start 338.094066 -227.076)
		(end 338.094066 -227.680012)
		(width 0.15494)
		(layer "In7.Cu")
		(net "RST_MB_PERST_2_ISO_R_N")
	)
	(segment
		(start 337.655408 -228.11867)
		(end 337.655408 -229.518718)
		(width 0.15494)
		(layer "In7.Cu")
		(net "RST_MB_PERST_2_ISO_R_N")
	)
	(segment
		(start 338.199984 -236.76483)
		(end 338.615528 -237.180374)
		(width 0.15494)
		(layer "In7.Cu")
		(net "RST_MB_PERST_2_ISO_R_N")
	)
	(segment
		(start 329.922886 -208.57337)
		(end 330.835254 -209.485738)
		(width 0.13208)
		(layer "F.Cu")
		(net "CLK_25M_FPGA_R")
	)
	(segment
		(start 329.922886 -207.941418)
		(end 329.922886 -208.57337)
		(width 0.13208)
		(layer "F.Cu")
		(net "CLK_25M_FPGA_R")
	)
	(segment
		(start 330.835254 -209.485738)
		(end 331.359764 -210.010248)
		(width 0.13208)
		(layer "F.Cu")
		(net "CLK_25M_FPGA_R")
	)
	(segment
		(start 331.359764 -213.594188)
		(end 332.552802 -214.787226)
		(width 0.13208)
		(layer "F.Cu")
		(net "CLK_25M_FPGA_R")
	)
	(segment
		(start 334.494124 -214.787226)
		(end 334.89392 -215.187022)
		(width 0.13208)
		(layer "F.Cu")
		(net "CLK_25M_FPGA_R")
	)
	(segment
		(start 332.552802 -214.787226)
		(end 334.494124 -214.787226)
		(width 0.13208)
		(layer "F.Cu")
		(net "CLK_25M_FPGA_R")
	)
	(segment
		(start 331.359764 -210.010248)
		(end 331.359764 -213.594188)
		(width 0.13208)
		(layer "F.Cu")
		(net "CLK_25M_FPGA_R")
	)
	(via
		(at 330.835254 -209.485738)
		(size 0.508)
		(drill 0.254)
		(layers "F.Cu" "B.Cu")
		(net "CLK_25M_FPGA_R")
	)
	(segment
		(start 340.614 -210.566)
		(end 340.614 -207.645)
		(width 0.13208)
		(layer "F.Cu")
		(net "RST_SSD12_PERST_N")
	)
	(segment
		(start 340.614 -207.645)
		(end 340.614 -205.63205)
		(width 0.13208)
		(layer "F.Cu")
		(net "RST_SSD12_PERST_N")
	)
	(segment
		(start 340.493858 -210.686142)
		(end 340.614 -210.566)
		(width 0.13208)
		(layer "F.Cu")
		(net "RST_SSD12_PERST_N")
	)
	(segment
		(start 340.493858 -211.18703)
		(end 340.493858 -210.686142)
		(width 0.13208)
		(layer "F.Cu")
		(net "RST_SSD12_PERST_N")
	)
	(via
		(at 340.614 -207.645)
		(size 0.762)
		(drill 0.381)
		(layers "F.Cu" "B.Cu")
		(net "RST_SSD12_PERST_N")
	)
	(segment
		(start 109.91088 -79.093314)
		(end 109.91088 -77.63891)
		(width 0.13462)
		(layer "F.Cu")
		(net "CLK_100M_DB800ZL_SSD2_R_DP")
	)
	(segment
		(start 67.907408 -27.051)
		(end 67.76847 -27.189938)
		(width 0.13462)
		(layer "F.Cu")
		(net "CLK_100M_DB800ZL_SSD2_R_DP")
	)
	(segment
		(start 109.58195 -79.422244)
		(end 109.91088 -79.093314)
		(width 0.13462)
		(layer "F.Cu")
		(net "CLK_100M_DB800ZL_SSD2_R_DP")
	)
	(segment
		(start 109.91088 -77.63891)
		(end 109.60735 -77.33538)
		(width 0.13462)
		(layer "F.Cu")
		(net "CLK_100M_DB800ZL_SSD2_R_DP")
	)
	(segment
		(start 67.76847 -27.189938)
		(end 67.264788 -27.189938)
		(width 0.13462)
		(layer "F.Cu")
		(net "CLK_100M_DB800ZL_SSD2_R_DP")
	)
	(segment
		(start 68.98132 -27.342846)
		(end 68.689474 -27.051)
		(width 0.13462)
		(layer "F.Cu")
		(net "CLK_100M_DB800ZL_SSD2_R_DP")
	)
	(segment
		(start 68.689474 -27.051)
		(end 67.907408 -27.051)
		(width 0.13462)
		(layer "F.Cu")
		(net "CLK_100M_DB800ZL_SSD2_R_DP")
	)
	(via
		(at 109.60735 -77.33538)
		(size 0.508)
		(drill 0.254)
		(layers "F.Cu" "B.Cu")
		(net "CLK_100M_DB800ZL_SSD2_R_DP")
	)
	(via
		(at 68.98132 -27.342846)
		(size 0.508)
		(drill 0.254)
		(layers "F.Cu" "B.Cu")
		(net "CLK_100M_DB800ZL_SSD2_R_DP")
	)
	(segment
		(start 73.385934 -28.248864)
		(end 73.843642 -28.438348)
		(width 0.1651)
		(layer "In13.Cu")
		(net "CLK_100M_DB800ZL_SSD2_R_DP")
	)
	(segment
		(start 103.73741 -70.008242)
		(end 103.899716 -69.845936)
		(width 0.1651)
		(layer "In13.Cu")
		(net "CLK_100M_DB800ZL_SSD2_R_DP")
	)
	(segment
		(start 103.899716 -69.845936)
		(end 107.91698 -69.845936)
		(width 0.1651)
		(layer "In13.Cu")
		(net "CLK_100M_DB800ZL_SSD2_R_DP")
	)
	(segment
		(start 74.688954 -28.664408)
		(end 75.515724 -29.491178)
		(width 0.1651)
		(layer "In13.Cu")
		(net "CLK_100M_DB800ZL_SSD2_R_DP")
	)
	(segment
		(start 69.270626 -27.05354)
		(end 70.0913 -27.05354)
		(width 0.1651)
		(layer "In13.Cu")
		(net "CLK_100M_DB800ZL_SSD2_R_DP")
	)
	(segment
		(start 108.314236 -74.575416)
		(end 109.900466 -76.161646)
		(width 0.1651)
		(layer "In13.Cu")
		(net "CLK_100M_DB800ZL_SSD2_R_DP")
	)
	(segment
		(start 76.378054 -30.515306)
		(end 76.728574 -30.865826)
		(width 0.1651)
		(layer "In13.Cu")
		(net "CLK_100M_DB800ZL_SSD2_R_DP")
	)
	(segment
		(start 105.4227 -71.903336)
		(end 105.73766 -72.218296)
		(width 0.1651)
		(layer "In13.Cu")
		(net "CLK_100M_DB800ZL_SSD2_R_DP")
	)
	(segment
		(start 109.900466 -77.042264)
		(end 109.60735 -77.33538)
		(width 0.1651)
		(layer "In13.Cu")
		(net "CLK_100M_DB800ZL_SSD2_R_DP")
	)
	(segment
		(start 76.028042 -30.003496)
		(end 76.378054 -30.353508)
		(width 0.1651)
		(layer "In13.Cu")
		(net "CLK_100M_DB800ZL_SSD2_R_DP")
	)
	(segment
		(start 77.988414 -33.183068)
		(end 78.102714 -33.297368)
		(width 0.1651)
		(layer "In13.Cu")
		(net "CLK_100M_DB800ZL_SSD2_R_DP")
	)
	(segment
		(start 90.264234 -64.921892)
		(end 90.069924 -73.979024)
		(width 0.1651)
		(layer "In13.Cu")
		(net "CLK_100M_DB800ZL_SSD2_R_DP")
	)
	(segment
		(start 73.323958 -28.099258)
		(end 73.385934 -28.248864)
		(width 0.1651)
		(layer "In13.Cu")
		(net "CLK_100M_DB800ZL_SSD2_R_DP")
	)
	(segment
		(start 105.43794 -73.407016)
		(end 105.43794 -74.270108)
		(width 0.1651)
		(layer "In13.Cu")
		(net "CLK_100M_DB800ZL_SSD2_R_DP")
	)
	(segment
		(start 107.91698 -72.218296)
		(end 108.057188 -72.358504)
		(width 0.1651)
		(layer "In13.Cu")
		(net "CLK_100M_DB800ZL_SSD2_R_DP")
	)
	(segment
		(start 77.752702 -31.728156)
		(end 78.102714 -32.078168)
		(width 0.1651)
		(layer "In13.Cu")
		(net "CLK_100M_DB800ZL_SSD2_R_DP")
	)
	(segment
		(start 77.240384 -31.215838)
		(end 77.240384 -31.377636)
		(width 0.1651)
		(layer "In13.Cu")
		(net "CLK_100M_DB800ZL_SSD2_R_DP")
	)
	(segment
		(start 89.110058 -45.673772)
		(end 90.264234 -64.921892)
		(width 0.1651)
		(layer "In13.Cu")
		(net "CLK_100M_DB800ZL_SSD2_R_DP")
	)
	(segment
		(start 73.992994 -28.376372)
		(end 74.688954 -28.664408)
		(width 0.1651)
		(layer "In13.Cu")
		(net "CLK_100M_DB800ZL_SSD2_R_DP")
	)
	(segment
		(start 70.0913 -27.05354)
		(end 71.451724 -27.324304)
		(width 0.1651)
		(layer "In13.Cu")
		(net "CLK_100M_DB800ZL_SSD2_R_DP")
	)
	(segment
		(start 77.240384 -31.377636)
		(end 77.590904 -31.728156)
		(width 0.1651)
		(layer "In13.Cu")
		(net "CLK_100M_DB800ZL_SSD2_R_DP")
	)
	(segment
		(start 78.102714 -32.573468)
		(end 77.988414 -32.687768)
		(width 0.1651)
		(layer "In13.Cu")
		(net "CLK_100M_DB800ZL_SSD2_R_DP")
	)
	(segment
		(start 109.900466 -76.161646)
		(end 109.900466 -77.042264)
		(width 0.1651)
		(layer "In13.Cu")
		(net "CLK_100M_DB800ZL_SSD2_R_DP")
	)
	(segment
		(start 102.343712 -75.862688)
		(end 103.73741 -74.46899)
		(width 0.1651)
		(layer "In13.Cu")
		(net "CLK_100M_DB800ZL_SSD2_R_DP")
	)
	(segment
		(start 75.515724 -29.652976)
		(end 75.866244 -30.003496)
		(width 0.1651)
		(layer "In13.Cu")
		(net "CLK_100M_DB800ZL_SSD2_R_DP")
	)
	(segment
		(start 75.866244 -30.003496)
		(end 76.028042 -30.003496)
		(width 0.1651)
		(layer "In13.Cu")
		(net "CLK_100M_DB800ZL_SSD2_R_DP")
	)
	(segment
		(start 108.057188 -70.594728)
		(end 107.91698 -70.734936)
		(width 0.1651)
		(layer "In13.Cu")
		(net "CLK_100M_DB800ZL_SSD2_R_DP")
	)
	(segment
		(start 78.102714 -33.297368)
		(end 78.102714 -34.666428)
		(width 0.1651)
		(layer "In13.Cu")
		(net "CLK_100M_DB800ZL_SSD2_R_DP")
	)
	(segment
		(start 73.843642 -28.438348)
		(end 73.992994 -28.376372)
		(width 0.1651)
		(layer "In13.Cu")
		(net "CLK_100M_DB800ZL_SSD2_R_DP")
	)
	(segment
		(start 76.728574 -30.865826)
		(end 76.890372 -30.865826)
		(width 0.1651)
		(layer "In13.Cu")
		(net "CLK_100M_DB800ZL_SSD2_R_DP")
	)
	(segment
		(start 76.890372 -30.865826)
		(end 77.240384 -31.215838)
		(width 0.1651)
		(layer "In13.Cu")
		(net "CLK_100M_DB800ZL_SSD2_R_DP")
	)
	(segment
		(start 107.91698 -70.734936)
		(end 105.73766 -70.734936)
		(width 0.1651)
		(layer "In13.Cu")
		(net "CLK_100M_DB800ZL_SSD2_R_DP")
	)
	(segment
		(start 108.057188 -69.986144)
		(end 108.057188 -70.594728)
		(width 0.1651)
		(layer "In13.Cu")
		(net "CLK_100M_DB800ZL_SSD2_R_DP")
	)
	(segment
		(start 107.91698 -73.107296)
		(end 105.73766 -73.107296)
		(width 0.1651)
		(layer "In13.Cu")
		(net "CLK_100M_DB800ZL_SSD2_R_DP")
	)
	(segment
		(start 105.73766 -70.734936)
		(end 105.4227 -71.049896)
		(width 0.1651)
		(layer "In13.Cu")
		(net "CLK_100M_DB800ZL_SSD2_R_DP")
	)
	(segment
		(start 107.91698 -69.845936)
		(end 108.057188 -69.986144)
		(width 0.1651)
		(layer "In13.Cu")
		(net "CLK_100M_DB800ZL_SSD2_R_DP")
	)
	(segment
		(start 76.378054 -30.353508)
		(end 76.378054 -30.515306)
		(width 0.1651)
		(layer "In13.Cu")
		(net "CLK_100M_DB800ZL_SSD2_R_DP")
	)
	(segment
		(start 105.43794 -74.270108)
		(end 105.743248 -74.575416)
		(width 0.1651)
		(layer "In13.Cu")
		(net "CLK_100M_DB800ZL_SSD2_R_DP")
	)
	(segment
		(start 78.102714 -34.666428)
		(end 89.110058 -45.673772)
		(width 0.1651)
		(layer "In13.Cu")
		(net "CLK_100M_DB800ZL_SSD2_R_DP")
	)
	(segment
		(start 108.057188 -72.967088)
		(end 107.91698 -73.107296)
		(width 0.1651)
		(layer "In13.Cu")
		(net "CLK_100M_DB800ZL_SSD2_R_DP")
	)
	(segment
		(start 105.4227 -71.049896)
		(end 105.4227 -71.903336)
		(width 0.1651)
		(layer "In13.Cu")
		(net "CLK_100M_DB800ZL_SSD2_R_DP")
	)
	(segment
		(start 105.73766 -73.107296)
		(end 105.43794 -73.407016)
		(width 0.1651)
		(layer "In13.Cu")
		(net "CLK_100M_DB800ZL_SSD2_R_DP")
	)
	(segment
		(start 105.73766 -72.218296)
		(end 107.91698 -72.218296)
		(width 0.1651)
		(layer "In13.Cu")
		(net "CLK_100M_DB800ZL_SSD2_R_DP")
	)
	(segment
		(start 68.98132 -27.342846)
		(end 69.270626 -27.05354)
		(width 0.1651)
		(layer "In13.Cu")
		(net "CLK_100M_DB800ZL_SSD2_R_DP")
	)
	(segment
		(start 108.057188 -72.358504)
		(end 108.057188 -72.967088)
		(width 0.1651)
		(layer "In13.Cu")
		(net "CLK_100M_DB800ZL_SSD2_R_DP")
	)
	(segment
		(start 77.590904 -31.728156)
		(end 77.752702 -31.728156)
		(width 0.1651)
		(layer "In13.Cu")
		(net "CLK_100M_DB800ZL_SSD2_R_DP")
	)
	(segment
		(start 78.102714 -32.078168)
		(end 78.102714 -32.573468)
		(width 0.1651)
		(layer "In13.Cu")
		(net "CLK_100M_DB800ZL_SSD2_R_DP")
	)
	(segment
		(start 71.451724 -27.324304)
		(end 73.323958 -28.099258)
		(width 0.1651)
		(layer "In13.Cu")
		(net "CLK_100M_DB800ZL_SSD2_R_DP")
	)
	(segment
		(start 105.743248 -74.575416)
		(end 108.314236 -74.575416)
		(width 0.1651)
		(layer "In13.Cu")
		(net "CLK_100M_DB800ZL_SSD2_R_DP")
	)
	(segment
		(start 77.988414 -32.687768)
		(end 77.988414 -33.183068)
		(width 0.1651)
		(layer "In13.Cu")
		(net "CLK_100M_DB800ZL_SSD2_R_DP")
	)
	(segment
		(start 90.069924 -73.979024)
		(end 91.953588 -75.862688)
		(width 0.1651)
		(layer "In13.Cu")
		(net "CLK_100M_DB800ZL_SSD2_R_DP")
	)
	(segment
		(start 103.73741 -74.46899)
		(end 103.73741 -70.008242)
		(width 0.1651)
		(layer "In13.Cu")
		(net "CLK_100M_DB800ZL_SSD2_R_DP")
	)
	(segment
		(start 75.515724 -29.491178)
		(end 75.515724 -29.652976)
		(width 0.1651)
		(layer "In13.Cu")
		(net "CLK_100M_DB800ZL_SSD2_R_DP")
	)
	(segment
		(start 91.953588 -75.862688)
		(end 102.343712 -75.862688)
		(width 0.1651)
		(layer "In13.Cu")
		(net "CLK_100M_DB800ZL_SSD2_R_DP")
	)
	(segment
		(start 34.482278 -309.480458)
		(end 33.418526 -308.416706)
		(width 0.13208)
		(layer "F.Cu")
		(net "PEX0_DBG_MODE1")
	)
	(segment
		(start 34.482278 -310.237378)
		(end 34.482278 -309.480458)
		(width 0.13208)
		(layer "F.Cu")
		(net "PEX0_DBG_MODE1")
	)
	(segment
		(start 33.418526 -308.416706)
		(end 34.136838 -307.698394)
		(width 0.13208)
		(layer "F.Cu")
		(net "PEX0_DBG_MODE1")
	)
	(segment
		(start 34.136838 -307.698394)
		(end 34.137092 -307.698394)
		(width 0.13208)
		(layer "F.Cu")
		(net "PEX0_DBG_MODE1")
	)
	(via
		(at 48.24984 -309.199788)
		(size 0.4064)
		(drill 0.2032)
		(layers "F.Cu" "B.Cu")
		(net "PEX0_DBG_MODE1")
	)
	(via
		(at 34.482278 -310.237378)
		(size 0.508)
		(drill 0.254)
		(layers "F.Cu" "B.Cu")
		(net "PEX0_DBG_MODE1")
	)
	(segment
		(start 48.24984 -309.199788)
		(end 47.747428 -309.7022)
		(width 0.13208)
		(layer "B.Cu")
		(net "PEX0_DBG_MODE1")
	)
	(segment
		(start 47.747428 -309.7022)
		(end 35.017456 -309.7022)
		(width 0.13208)
		(layer "B.Cu")
		(net "PEX0_DBG_MODE1")
	)
	(segment
		(start 35.017456 -309.7022)
		(end 34.482278 -310.237378)
		(width 0.13208)
		(layer "B.Cu")
		(net "PEX0_DBG_MODE1")
	)
	(segment
		(start 372.642384 -251.158502)
		(end 372.642384 -250.470924)
		(width 0.13208)
		(layer "F.Cu")
		(net "PEX3_MODE_SEL9")
	)
	(segment
		(start 372.642384 -251.956824)
		(end 372.642384 -251.158502)
		(width 0.13208)
		(layer "F.Cu")
		(net "PEX3_MODE_SEL9")
	)
	(segment
		(start 410.799788 -283.549852)
		(end 410.800042 -283.549852)
		(width 0.13208)
		(layer "F.Cu")
		(net "PEX3_MODE_SEL9")
	)
	(segment
		(start 410.800042 -283.549852)
		(end 411.275022 -284.024832)
		(width 0.13208)
		(layer "F.Cu")
		(net "PEX3_MODE_SEL9")
	)
	(via
		(at 372.642384 -251.158502)
		(size 0.508)
		(drill 0.254)
		(layers "F.Cu" "B.Cu")
		(net "PEX3_MODE_SEL9")
	)
	(via
		(at 411.275022 -284.024832)
		(size 0.4064)
		(drill 0.2032)
		(layers "F.Cu" "B.Cu")
		(net "PEX3_MODE_SEL9")
	)
	(segment
		(start 419.597332 -282.672536)
		(end 419.286944 -282.982924)
		(width 0.13208)
		(layer "B.Cu")
		(net "PEX3_MODE_SEL9")
	)
	(segment
		(start 419.286944 -282.982924)
		(end 419.286944 -285.207456)
		(width 0.13208)
		(layer "B.Cu")
		(net "PEX3_MODE_SEL9")
	)
	(segment
		(start 401.11045 -252.054614)
		(end 420.805356 -271.74952)
		(width 0.13208)
		(layer "B.Cu")
		(net "PEX3_MODE_SEL9")
	)
	(segment
		(start 372.642384 -251.158502)
		(end 372.642384 -250.570238)
		(width 0.13208)
		(layer "B.Cu")
		(net "PEX3_MODE_SEL9")
	)
	(segment
		(start 420.805356 -271.74952)
		(end 420.805356 -281.883866)
		(width 0.13208)
		(layer "B.Cu")
		(net "PEX3_MODE_SEL9")
	)
	(segment
		(start 419.1254 -285.369)
		(end 412.013146 -285.369)
		(width 0.13208)
		(layer "B.Cu")
		(net "PEX3_MODE_SEL9")
	)
	(segment
		(start 411.733238 -284.483048)
		(end 411.275022 -284.024832)
		(width 0.13208)
		(layer "B.Cu")
		(net "PEX3_MODE_SEL9")
	)
	(segment
		(start 412.013146 -285.369)
		(end 411.733238 -285.089092)
		(width 0.13208)
		(layer "B.Cu")
		(net "PEX3_MODE_SEL9")
	)
	(segment
		(start 420.805356 -281.883866)
		(end 420.016686 -282.672536)
		(width 0.13208)
		(layer "B.Cu")
		(net "PEX3_MODE_SEL9")
	)
	(segment
		(start 387.416294 -250.806712)
		(end 387.416294 -251.525532)
		(width 0.13208)
		(layer "B.Cu")
		(net "PEX3_MODE_SEL9")
	)
	(segment
		(start 387.945376 -252.054614)
		(end 401.11045 -252.054614)
		(width 0.13208)
		(layer "B.Cu")
		(net "PEX3_MODE_SEL9")
	)
	(segment
		(start 420.016686 -282.672536)
		(end 419.597332 -282.672536)
		(width 0.13208)
		(layer "B.Cu")
		(net "PEX3_MODE_SEL9")
	)
	(segment
		(start 386.878068 -250.268486)
		(end 387.416294 -250.806712)
		(width 0.13208)
		(layer "B.Cu")
		(net "PEX3_MODE_SEL9")
	)
	(segment
		(start 387.416294 -251.525532)
		(end 387.945376 -252.054614)
		(width 0.13208)
		(layer "B.Cu")
		(net "PEX3_MODE_SEL9")
	)
	(segment
		(start 419.286944 -285.207456)
		(end 419.1254 -285.369)
		(width 0.13208)
		(layer "B.Cu")
		(net "PEX3_MODE_SEL9")
	)
	(segment
		(start 411.733238 -285.089092)
		(end 411.733238 -284.483048)
		(width 0.13208)
		(layer "B.Cu")
		(net "PEX3_MODE_SEL9")
	)
	(segment
		(start 372.944136 -250.268486)
		(end 386.878068 -250.268486)
		(width 0.13208)
		(layer "B.Cu")
		(net "PEX3_MODE_SEL9")
	)
	(segment
		(start 372.642384 -250.570238)
		(end 372.944136 -250.268486)
		(width 0.13208)
		(layer "B.Cu")
		(net "PEX3_MODE_SEL9")
	)
	(segment
		(start 219.903802 -225.612452)
		(end 219.903802 -224.746058)
		(width 0.13208)
		(layer "F.Cu")
		(net "SMB_NIC2_SDA")
	)
	(segment
		(start 218.070938 -226.54387)
		(end 218.972384 -226.54387)
		(width 0.13208)
		(layer "F.Cu")
		(net "SMB_NIC2_SDA")
	)
	(segment
		(start 223.141032 -224.230692)
		(end 223.467676 -223.904048)
		(width 0.13208)
		(layer "F.Cu")
		(net "SMB_NIC2_SDA")
	)
	(segment
		(start 217.663268 -226.1362)
		(end 218.070938 -226.54387)
		(width 0.13208)
		(layer "F.Cu")
		(net "SMB_NIC2_SDA")
	)
	(segment
		(start 219.903802 -224.746058)
		(end 219.994734 -224.526348)
		(width 0.13208)
		(layer "F.Cu")
		(net "SMB_NIC2_SDA")
	)
	(segment
		(start 220.29039 -224.230692)
		(end 223.141032 -224.230692)
		(width 0.13208)
		(layer "F.Cu")
		(net "SMB_NIC2_SDA")
	)
	(segment
		(start 219.994734 -224.526348)
		(end 220.29039 -224.230692)
		(width 0.13208)
		(layer "F.Cu")
		(net "SMB_NIC2_SDA")
	)
	(segment
		(start 214.440262 -226.711256)
		(end 214.819738 -226.711256)
		(width 0.13208)
		(layer "F.Cu")
		(net "SMB_NIC2_SDA")
	)
	(segment
		(start 218.972384 -226.54387)
		(end 219.903802 -225.612452)
		(width 0.13208)
		(layer "F.Cu")
		(net "SMB_NIC2_SDA")
	)
	(segment
		(start 215.162892 -226.368102)
		(end 215.394794 -226.1362)
		(width 0.13208)
		(layer "F.Cu")
		(net "SMB_NIC2_SDA")
	)
	(segment
		(start 215.394794 -226.1362)
		(end 217.663268 -226.1362)
		(width 0.13208)
		(layer "F.Cu")
		(net "SMB_NIC2_SDA")
	)
	(segment
		(start 214.819738 -226.711256)
		(end 215.162892 -226.368102)
		(width 0.13208)
		(layer "F.Cu")
		(net "SMB_NIC2_SDA")
	)
	(via
		(at 215.162892 -226.368102)
		(size 0.508)
		(drill 0.254)
		(layers "F.Cu" "B.Cu")
		(net "SMB_NIC2_SDA")
	)
	(segment
		(start 40.203882 -24.189944)
		(end 41.26484 -24.189944)
		(width 0.13208)
		(layer "F.Cu")
		(net "RST_SSD1_PERST_R_N")
	)
	(segment
		(start 343.510616 -243.43106)
		(end 343.510616 -241.483388)
		(width 0.13208)
		(layer "F.Cu")
		(net "RST_SSD1_PERST_R_N")
	)
	(segment
		(start 336.48269 -251.451364)
		(end 336.48269 -250.458986)
		(width 0.13208)
		(layer "F.Cu")
		(net "RST_SSD1_PERST_R_N")
	)
	(segment
		(start 343.510616 -241.483388)
		(end 343.902792 -241.091212)
		(width 0.13208)
		(layer "F.Cu")
		(net "RST_SSD1_PERST_R_N")
	)
	(segment
		(start 336.48269 -250.458986)
		(end 343.510616 -243.43106)
		(width 0.13208)
		(layer "F.Cu")
		(net "RST_SSD1_PERST_R_N")
	)
	(via
		(at 336.48269 -251.451364)
		(size 0.508)
		(drill 0.254)
		(layers "F.Cu" "B.Cu")
		(net "RST_SSD1_PERST_R_N")
	)
	(via
		(at 69.881242 -215.359996)
		(size 0.508)
		(drill 0.254)
		(layers "F.Cu" "B.Cu")
		(net "RST_SSD1_PERST_R_N")
	)
	(via
		(at 40.203882 -24.189944)
		(size 0.508)
		(drill 0.254)
		(layers "F.Cu" "B.Cu")
		(net "RST_SSD1_PERST_R_N")
	)
	(segment
		(start 47.032164 -27.455114)
		(end 46.52645 -26.9494)
		(width 0.15494)
		(layer "In5.Cu")
		(net "RST_SSD1_PERST_R_N")
	)
	(segment
		(start 64.091312 -184.030366)
		(end 58.991246 -178.9303)
		(width 0.15494)
		(layer "In5.Cu")
		(net "RST_SSD1_PERST_R_N")
	)
	(segment
		(start 40.944292 -24.930354)
		(end 40.203882 -24.189944)
		(width 0.15494)
		(layer "In5.Cu")
		(net "RST_SSD1_PERST_R_N")
	)
	(segment
		(start 69.881242 -211.892896)
		(end 67.126612 -209.138266)
		(width 0.15494)
		(layer "In5.Cu")
		(net "RST_SSD1_PERST_R_N")
	)
	(segment
		(start 67.126612 -209.138266)
		(end 67.126612 -205.96987)
		(width 0.15494)
		(layer "In5.Cu")
		(net "RST_SSD1_PERST_R_N")
	)
	(segment
		(start 62.93358 -45.625004)
		(end 50.87366 -33.565084)
		(width 0.15494)
		(layer "In5.Cu")
		(net "RST_SSD1_PERST_R_N")
	)
	(segment
		(start 50.87366 -29.206952)
		(end 51.113436 -28.967176)
		(width 0.15494)
		(layer "In5.Cu")
		(net "RST_SSD1_PERST_R_N")
	)
	(segment
		(start 50.87366 -33.565084)
		(end 50.87366 -29.206952)
		(width 0.15494)
		(layer "In5.Cu")
		(net "RST_SSD1_PERST_R_N")
	)
	(segment
		(start 46.52645 -26.9494)
		(end 45.00245 -26.9494)
		(width 0.15494)
		(layer "In5.Cu")
		(net "RST_SSD1_PERST_R_N")
	)
	(segment
		(start 69.881242 -215.359996)
		(end 69.881242 -211.892896)
		(width 0.15494)
		(layer "In5.Cu")
		(net "RST_SSD1_PERST_R_N")
	)
	(segment
		(start 42.983404 -24.930354)
		(end 40.944292 -24.930354)
		(width 0.15494)
		(layer "In5.Cu")
		(net "RST_SSD1_PERST_R_N")
	)
	(segment
		(start 58.991246 -156.093414)
		(end 59.9948 -155.08986)
		(width 0.15494)
		(layer "In5.Cu")
		(net "RST_SSD1_PERST_R_N")
	)
	(segment
		(start 51.113436 -28.967176)
		(end 51.113436 -28.38069)
		(width 0.15494)
		(layer "In5.Cu")
		(net "RST_SSD1_PERST_R_N")
	)
	(segment
		(start 51.113436 -28.38069)
		(end 50.18786 -27.455114)
		(width 0.15494)
		(layer "In5.Cu")
		(net "RST_SSD1_PERST_R_N")
	)
	(segment
		(start 50.18786 -27.455114)
		(end 47.032164 -27.455114)
		(width 0.15494)
		(layer "In5.Cu")
		(net "RST_SSD1_PERST_R_N")
	)
	(segment
		(start 59.686444 -84.483956)
		(end 59.686444 -66.373756)
		(width 0.15494)
		(layer "In5.Cu")
		(net "RST_SSD1_PERST_R_N")
	)
	(segment
		(start 59.9948 -93.598746)
		(end 58.763662 -92.367608)
		(width 0.15494)
		(layer "In5.Cu")
		(net "RST_SSD1_PERST_R_N")
	)
	(segment
		(start 67.126612 -205.96987)
		(end 64.091312 -202.93457)
		(width 0.15494)
		(layer "In5.Cu")
		(net "RST_SSD1_PERST_R_N")
	)
	(segment
		(start 45.00245 -26.9494)
		(end 42.983404 -24.930354)
		(width 0.15494)
		(layer "In5.Cu")
		(net "RST_SSD1_PERST_R_N")
	)
	(segment
		(start 58.763662 -85.406738)
		(end 59.686444 -84.483956)
		(width 0.15494)
		(layer "In5.Cu")
		(net "RST_SSD1_PERST_R_N")
	)
	(segment
		(start 58.991246 -178.9303)
		(end 58.991246 -156.093414)
		(width 0.15494)
		(layer "In5.Cu")
		(net "RST_SSD1_PERST_R_N")
	)
	(segment
		(start 59.9948 -155.08986)
		(end 59.9948 -93.598746)
		(width 0.15494)
		(layer "In5.Cu")
		(net "RST_SSD1_PERST_R_N")
	)
	(segment
		(start 62.93358 -63.12662)
		(end 62.93358 -45.625004)
		(width 0.15494)
		(layer "In5.Cu")
		(net "RST_SSD1_PERST_R_N")
	)
	(segment
		(start 59.686444 -66.373756)
		(end 62.93358 -63.12662)
		(width 0.15494)
		(layer "In5.Cu")
		(net "RST_SSD1_PERST_R_N")
	)
	(segment
		(start 58.763662 -92.367608)
		(end 58.763662 -85.406738)
		(width 0.15494)
		(layer "In5.Cu")
		(net "RST_SSD1_PERST_R_N")
	)
	(segment
		(start 64.091312 -202.93457)
		(end 64.091312 -184.030366)
		(width 0.15494)
		(layer "In5.Cu")
		(net "RST_SSD1_PERST_R_N")
	)
	(segment
		(start 325.627238 -252.935994)
		(end 326.70877 -254.017526)
		(width 0.15494)
		(layer "In15.Cu")
		(net "RST_SSD1_PERST_R_N")
	)
	(segment
		(start 153.496264 -235.98632)
		(end 154.494484 -235.98632)
		(width 0.15494)
		(layer "In15.Cu")
		(net "RST_SSD1_PERST_R_N")
	)
	(segment
		(start 230.360982 -251.222002)
		(end 239.541558 -251.222002)
		(width 0.15494)
		(layer "In15.Cu")
		(net "RST_SSD1_PERST_R_N")
	)
	(segment
		(start 139.438126 -237.99673)
		(end 142.647416 -234.78744)
		(width 0.15494)
		(layer "In15.Cu")
		(net "RST_SSD1_PERST_R_N")
	)
	(segment
		(start 274.128738 -253.104904)
		(end 304.601372 -253.104904)
		(width 0.15494)
		(layer "In15.Cu")
		(net "RST_SSD1_PERST_R_N")
	)
	(segment
		(start 258.051808 -252.12294)
		(end 273.146774 -252.12294)
		(width 0.15494)
		(layer "In15.Cu")
		(net "RST_SSD1_PERST_R_N")
	)
	(segment
		(start 336.48269 -251.909834)
		(end 336.48269 -251.451364)
		(width 0.15494)
		(layer "In15.Cu")
		(net "RST_SSD1_PERST_R_N")
	)
	(segment
		(start 108.844334 -210.131152)
		(end 112.1029 -213.389718)
		(width 0.15494)
		(layer "In15.Cu")
		(net "RST_SSD1_PERST_R_N")
	)
	(segment
		(start 159.969708 -241.461544)
		(end 177.877724 -241.461544)
		(width 0.15494)
		(layer "In15.Cu")
		(net "RST_SSD1_PERST_R_N")
	)
	(segment
		(start 246.297196 -250.862084)
		(end 247.123712 -251.6886)
		(width 0.15494)
		(layer "In15.Cu")
		(net "RST_SSD1_PERST_R_N")
	)
	(segment
		(start 185.93816 -249.52198)
		(end 189.048644 -249.52198)
		(width 0.15494)
		(layer "In15.Cu")
		(net "RST_SSD1_PERST_R_N")
	)
	(segment
		(start 177.877724 -241.461544)
		(end 185.93816 -249.52198)
		(width 0.15494)
		(layer "In15.Cu")
		(net "RST_SSD1_PERST_R_N")
	)
	(segment
		(start 112.1029 -233.30281)
		(end 119.271288 -240.471198)
		(width 0.15494)
		(layer "In15.Cu")
		(net "RST_SSD1_PERST_R_N")
	)
	(segment
		(start 229.11943 -249.98045)
		(end 230.360982 -251.222002)
		(width 0.15494)
		(layer "In15.Cu")
		(net "RST_SSD1_PERST_R_N")
	)
	(segment
		(start 154.494484 -235.98632)
		(end 159.969708 -241.461544)
		(width 0.15494)
		(layer "In15.Cu")
		(net "RST_SSD1_PERST_R_N")
	)
	(segment
		(start 152.31872 -235.49864)
		(end 153.496264 -235.98632)
		(width 0.15494)
		(layer "In15.Cu")
		(net "RST_SSD1_PERST_R_N")
	)
	(segment
		(start 239.901476 -250.862084)
		(end 246.297196 -250.862084)
		(width 0.15494)
		(layer "In15.Cu")
		(net "RST_SSD1_PERST_R_N")
	)
	(segment
		(start 224.216976 -250.41098)
		(end 224.647506 -249.98045)
		(width 0.15494)
		(layer "In15.Cu")
		(net "RST_SSD1_PERST_R_N")
	)
	(segment
		(start 112.1029 -213.389718)
		(end 112.1029 -233.30281)
		(width 0.15494)
		(layer "In15.Cu")
		(net "RST_SSD1_PERST_R_N")
	)
	(segment
		(start 304.770282 -252.935994)
		(end 325.627238 -252.935994)
		(width 0.15494)
		(layer "In15.Cu")
		(net "RST_SSD1_PERST_R_N")
	)
	(segment
		(start 142.647416 -234.78744)
		(end 149.507194 -234.78744)
		(width 0.15494)
		(layer "In15.Cu")
		(net "RST_SSD1_PERST_R_N")
	)
	(segment
		(start 130.594862 -237.99673)
		(end 139.438126 -237.99673)
		(width 0.15494)
		(layer "In15.Cu")
		(net "RST_SSD1_PERST_R_N")
	)
	(segment
		(start 257.617468 -251.6886)
		(end 258.051808 -252.12294)
		(width 0.15494)
		(layer "In15.Cu")
		(net "RST_SSD1_PERST_R_N")
	)
	(segment
		(start 128.12014 -240.471198)
		(end 129.046478 -239.54486)
		(width 0.15494)
		(layer "In15.Cu")
		(net "RST_SSD1_PERST_R_N")
	)
	(segment
		(start 247.123712 -251.6886)
		(end 257.617468 -251.6886)
		(width 0.15494)
		(layer "In15.Cu")
		(net "RST_SSD1_PERST_R_N")
	)
	(segment
		(start 75.849734 -210.131152)
		(end 108.844334 -210.131152)
		(width 0.15494)
		(layer "In15.Cu")
		(net "RST_SSD1_PERST_R_N")
	)
	(segment
		(start 189.048644 -249.52198)
		(end 189.937644 -250.41098)
		(width 0.15494)
		(layer "In15.Cu")
		(net "RST_SSD1_PERST_R_N")
	)
	(segment
		(start 151.224996 -235.49864)
		(end 152.31872 -235.49864)
		(width 0.15494)
		(layer "In15.Cu")
		(net "RST_SSD1_PERST_R_N")
	)
	(segment
		(start 189.937644 -250.41098)
		(end 224.216976 -250.41098)
		(width 0.15494)
		(layer "In15.Cu")
		(net "RST_SSD1_PERST_R_N")
	)
	(segment
		(start 334.374998 -254.017526)
		(end 336.48269 -251.909834)
		(width 0.15494)
		(layer "In15.Cu")
		(net "RST_SSD1_PERST_R_N")
	)
	(segment
		(start 224.647506 -249.98045)
		(end 229.11943 -249.98045)
		(width 0.15494)
		(layer "In15.Cu")
		(net "RST_SSD1_PERST_R_N")
	)
	(segment
		(start 70.62089 -215.359996)
		(end 75.849734 -210.131152)
		(width 0.15494)
		(layer "In15.Cu")
		(net "RST_SSD1_PERST_R_N")
	)
	(segment
		(start 326.70877 -254.017526)
		(end 334.374998 -254.017526)
		(width 0.15494)
		(layer "In15.Cu")
		(net "RST_SSD1_PERST_R_N")
	)
	(segment
		(start 273.146774 -252.12294)
		(end 274.128738 -253.104904)
		(width 0.15494)
		(layer "In15.Cu")
		(net "RST_SSD1_PERST_R_N")
	)
	(segment
		(start 69.881242 -215.359996)
		(end 70.62089 -215.359996)
		(width 0.15494)
		(layer "In15.Cu")
		(net "RST_SSD1_PERST_R_N")
	)
	(segment
		(start 119.271288 -240.471198)
		(end 128.12014 -240.471198)
		(width 0.15494)
		(layer "In15.Cu")
		(net "RST_SSD1_PERST_R_N")
	)
	(segment
		(start 129.046478 -239.54486)
		(end 130.594862 -237.99673)
		(width 0.15494)
		(layer "In15.Cu")
		(net "RST_SSD1_PERST_R_N")
	)
	(segment
		(start 304.601372 -253.104904)
		(end 304.770282 -252.935994)
		(width 0.15494)
		(layer "In15.Cu")
		(net "RST_SSD1_PERST_R_N")
	)
	(segment
		(start 149.507194 -234.78744)
		(end 151.224996 -235.49864)
		(width 0.15494)
		(layer "In15.Cu")
		(net "RST_SSD1_PERST_R_N")
	)
	(segment
		(start 239.541558 -251.222002)
		(end 239.901476 -250.862084)
		(width 0.15494)
		(layer "In15.Cu")
		(net "RST_SSD1_PERST_R_N")
	)
	(segment
		(start 209.364834 -25.390094)
		(end 208.291176 -25.390094)
		(width 0.13208)
		(layer "F.Cu")
		(net "SSD7_PWRDIS_R")
	)
	(segment
		(start 218.234514 -28.550108)
		(end 218.764358 -29.079952)
		(width 0.13208)
		(layer "F.Cu")
		(net "SSD7_PWRDIS_R")
	)
	(segment
		(start 218.234514 -28.469082)
		(end 218.234514 -28.550108)
		(width 0.13208)
		(layer "F.Cu")
		(net "SSD7_PWRDIS_R")
	)
	(segment
		(start 355.854 -234.46105)
		(end 355.854 -235.150406)
		(width 0.13208)
		(layer "F.Cu")
		(net "SSD7_PWRDIS_R")
	)
	(via
		(at 218.234514 -28.469082)
		(size 0.508)
		(drill 0.254)
		(layers "F.Cu" "B.Cu")
		(net "SSD7_PWRDIS_R")
	)
	(via
		(at 222.661988 -74.605134)
		(size 0.508)
		(drill 0.254)
		(layers "F.Cu" "B.Cu")
		(net "SSD7_PWRDIS_R")
	)
	(via
		(at 208.291176 -25.390094)
		(size 0.508)
		(drill 0.254)
		(layers "F.Cu" "B.Cu")
		(net "SSD7_PWRDIS_R")
	)
	(via
		(at 356.341934 -81.890362)
		(size 0.508)
		(drill 0.254)
		(layers "F.Cu" "B.Cu")
		(net "SSD7_PWRDIS_R")
	)
	(via
		(at 355.854 -235.150406)
		(size 0.508)
		(drill 0.254)
		(layers "F.Cu" "B.Cu")
		(net "SSD7_PWRDIS_R")
	)
	(segment
		(start 217.54084 -36.322)
		(end 222.77324 -41.5544)
		(width 0.15494)
		(layer "In5.Cu")
		(net "SSD7_PWRDIS_R")
	)
	(segment
		(start 214.941658 -27.914854)
		(end 217.680286 -27.914854)
		(width 0.15494)
		(layer "In5.Cu")
		(net "SSD7_PWRDIS_R")
	)
	(segment
		(start 222.77324 -62.697106)
		(end 221.783148 -63.687198)
		(width 0.15494)
		(layer "In5.Cu")
		(net "SSD7_PWRDIS_R")
	)
	(segment
		(start 217.54084 -29.591)
		(end 217.54084 -36.322)
		(width 0.15494)
		(layer "In5.Cu")
		(net "SSD7_PWRDIS_R")
	)
	(segment
		(start 221.5642 -73.507346)
		(end 222.661988 -74.605134)
		(width 0.15494)
		(layer "In5.Cu")
		(net "SSD7_PWRDIS_R")
	)
	(segment
		(start 214.458804 -27.432)
		(end 214.941658 -27.914854)
		(width 0.15494)
		(layer "In5.Cu")
		(net "SSD7_PWRDIS_R")
	)
	(segment
		(start 221.783148 -65.525142)
		(end 221.5642 -65.74409)
		(width 0.15494)
		(layer "In5.Cu")
		(net "SSD7_PWRDIS_R")
	)
	(segment
		(start 218.234514 -28.897326)
		(end 217.54084 -29.591)
		(width 0.15494)
		(layer "In5.Cu")
		(net "SSD7_PWRDIS_R")
	)
	(segment
		(start 221.783148 -63.687198)
		(end 221.783148 -65.525142)
		(width 0.15494)
		(layer "In5.Cu")
		(net "SSD7_PWRDIS_R")
	)
	(segment
		(start 221.5642 -65.74409)
		(end 221.5642 -73.507346)
		(width 0.15494)
		(layer "In5.Cu")
		(net "SSD7_PWRDIS_R")
	)
	(segment
		(start 212.93455 -27.432)
		(end 214.458804 -27.432)
		(width 0.15494)
		(layer "In5.Cu")
		(net "SSD7_PWRDIS_R")
	)
	(segment
		(start 218.234514 -28.469082)
		(end 218.234514 -28.897326)
		(width 0.15494)
		(layer "In5.Cu")
		(net "SSD7_PWRDIS_R")
	)
	(segment
		(start 208.291176 -25.390094)
		(end 210.892644 -25.390094)
		(width 0.15494)
		(layer "In5.Cu")
		(net "SSD7_PWRDIS_R")
	)
	(segment
		(start 217.680286 -27.914854)
		(end 218.234514 -28.469082)
		(width 0.15494)
		(layer "In5.Cu")
		(net "SSD7_PWRDIS_R")
	)
	(segment
		(start 210.892644 -25.390094)
		(end 212.93455 -27.432)
		(width 0.15494)
		(layer "In5.Cu")
		(net "SSD7_PWRDIS_R")
	)
	(segment
		(start 222.77324 -41.5544)
		(end 222.77324 -62.697106)
		(width 0.15494)
		(layer "In5.Cu")
		(net "SSD7_PWRDIS_R")
	)
	(segment
		(start 380.297182 -200.68413)
		(end 378.665994 -199.052942)
		(width 0.15494)
		(layer "In7.Cu")
		(net "SSD7_PWRDIS_R")
	)
	(segment
		(start 356.648258 -129.84099)
		(end 356.648258 -121.642632)
		(width 0.15494)
		(layer "In7.Cu")
		(net "SSD7_PWRDIS_R")
	)
	(segment
		(start 380.27483 -209.75066)
		(end 380.27483 -209.736182)
		(width 0.15494)
		(layer "In7.Cu")
		(net "SSD7_PWRDIS_R")
	)
	(segment
		(start 372.217696 -217.062304)
		(end 377.3678 -211.9122)
		(width 0.15494)
		(layer "In7.Cu")
		(net "SSD7_PWRDIS_R")
	)
	(segment
		(start 378.5616 -187.30468)
		(end 378.5616 -185.72607)
		(width 0.15494)
		(layer "In7.Cu")
		(net "SSD7_PWRDIS_R")
	)
	(segment
		(start 354.901754 -96.524572)
		(end 354.901754 -92.80525)
		(width 0.15494)
		(layer "In7.Cu")
		(net "SSD7_PWRDIS_R")
	)
	(segment
		(start 356.244652 -234.759754)
		(end 367.702846 -234.759754)
		(width 0.15494)
		(layer "In7.Cu")
		(net "SSD7_PWRDIS_R")
	)
	(segment
		(start 359.752138 -102.693978)
		(end 359.752138 -100.91293)
		(width 0.15494)
		(layer "In7.Cu")
		(net "SSD7_PWRDIS_R")
	)
	(segment
		(start 354.00996 -141.489938)
		(end 353.9998 -141.479778)
		(width 0.15494)
		(layer "In7.Cu")
		(net "SSD7_PWRDIS_R")
	)
	(segment
		(start 355.854 -235.150406)
		(end 356.244652 -234.759754)
		(width 0.15494)
		(layer "In7.Cu")
		(net "SSD7_PWRDIS_R")
	)
	(segment
		(start 367.702846 -234.759754)
		(end 372.217696 -230.244904)
		(width 0.15494)
		(layer "In7.Cu")
		(net "SSD7_PWRDIS_R")
	)
	(segment
		(start 359.0798 -116.8908)
		(end 357.8606 -115.6716)
		(width 0.15494)
		(layer "In7.Cu")
		(net "SSD7_PWRDIS_R")
	)
	(segment
		(start 357.8606 -106.070146)
		(end 358.96042 -104.970326)
		(width 0.15494)
		(layer "In7.Cu")
		(net "SSD7_PWRDIS_R")
	)
	(segment
		(start 378.5616 -185.72607)
		(end 377.8504 -185.01487)
		(width 0.15494)
		(layer "In7.Cu")
		(net "SSD7_PWRDIS_R")
	)
	(segment
		(start 358.532938 -163.378134)
		(end 358.532938 -163.181792)
		(width 0.15494)
		(layer "In7.Cu")
		(net "SSD7_PWRDIS_R")
	)
	(segment
		(start 377.3678 -211.9122)
		(end 378.098812 -211.9122)
		(width 0.15494)
		(layer "In7.Cu")
		(net "SSD7_PWRDIS_R")
	)
	(segment
		(start 380.8222 -201.209148)
		(end 380.59487 -200.981818)
		(width 0.15494)
		(layer "In7.Cu")
		(net "SSD7_PWRDIS_R")
	)
	(segment
		(start 358.96042 -104.970326)
		(end 358.96042 -103.485696)
		(width 0.15494)
		(layer "In7.Cu")
		(net "SSD7_PWRDIS_R")
	)
	(segment
		(start 380.8222 -209.188812)
		(end 380.8222 -201.209148)
		(width 0.15494)
		(layer "In7.Cu")
		(net "SSD7_PWRDIS_R")
	)
	(segment
		(start 358.95026 -163.795456)
		(end 358.532938 -163.378134)
		(width 0.15494)
		(layer "In7.Cu")
		(net "SSD7_PWRDIS_R")
	)
	(segment
		(start 375.92508 -173.234096)
		(end 374.547384 -171.8564)
		(width 0.15494)
		(layer "In7.Cu")
		(net "SSD7_PWRDIS_R")
	)
	(segment
		(start 379.977142 -210.03387)
		(end 379.99162 -210.03387)
		(width 0.15494)
		(layer "In7.Cu")
		(net "SSD7_PWRDIS_R")
	)
	(segment
		(start 375.92508 -173.621954)
		(end 375.92508 -173.234096)
		(width 0.15494)
		(layer "In7.Cu")
		(net "SSD7_PWRDIS_R")
	)
	(segment
		(start 373.123714 -169.2656)
		(end 369.978432 -169.2656)
		(width 0.15494)
		(layer "In7.Cu")
		(net "SSD7_PWRDIS_R")
	)
	(segment
		(start 374.547384 -171.8564)
		(end 374.547384 -170.68927)
		(width 0.15494)
		(layer "In7.Cu")
		(net "SSD7_PWRDIS_R")
	)
	(segment
		(start 359.0798 -117.8052)
		(end 359.0798 -116.8908)
		(width 0.15494)
		(layer "In7.Cu")
		(net "SSD7_PWRDIS_R")
	)
	(segment
		(start 354.00996 -141.068298)
		(end 354.00996 -132.479288)
		(width 0.15494)
		(layer "In7.Cu")
		(net "SSD7_PWRDIS_R")
	)
	(segment
		(start 377.8504 -182.182262)
		(end 376.81281 -181.144672)
		(width 0.15494)
		(layer "In7.Cu")
		(net "SSD7_PWRDIS_R")
	)
	(segment
		(start 354.901754 -92.80525)
		(end 356.341934 -91.36507)
		(width 0.15494)
		(layer "In7.Cu")
		(net "SSD7_PWRDIS_R")
	)
	(segment
		(start 364.508542 -163.79571)
		(end 358.951022 -163.79571)
		(width 0.15494)
		(layer "In7.Cu")
		(net "SSD7_PWRDIS_R")
	)
	(segment
		(start 376.3772 -174.074074)
		(end 375.92508 -173.621954)
		(width 0.15494)
		(layer "In7.Cu")
		(net "SSD7_PWRDIS_R")
	)
	(segment
		(start 376.81281 -181.144672)
		(end 376.81281 -176.49063)
		(width 0.15494)
		(layer "In7.Cu")
		(net "SSD7_PWRDIS_R")
	)
	(segment
		(start 377.8504 -185.01487)
		(end 377.8504 -182.182262)
		(width 0.15494)
		(layer "In7.Cu")
		(net "SSD7_PWRDIS_R")
	)
	(segment
		(start 376.4026 -174.208186)
		(end 376.3772 -174.074074)
		(width 0.15494)
		(layer "In7.Cu")
		(net "SSD7_PWRDIS_R")
	)
	(segment
		(start 356.717854 -162.2552)
		(end 354.00996 -159.547306)
		(width 0.15494)
		(layer "In7.Cu")
		(net "SSD7_PWRDIS_R")
	)
	(segment
		(start 376.4026 -176.08042)
		(end 376.4026 -174.208186)
		(width 0.15494)
		(layer "In7.Cu")
		(net "SSD7_PWRDIS_R")
	)
	(segment
		(start 378.098812 -211.9122)
		(end 379.977142 -210.03387)
		(width 0.15494)
		(layer "In7.Cu")
		(net "SSD7_PWRDIS_R")
	)
	(segment
		(start 354.00996 -132.479288)
		(end 356.648258 -129.84099)
		(width 0.15494)
		(layer "In7.Cu")
		(net "SSD7_PWRDIS_R")
	)
	(segment
		(start 358.96042 -103.485696)
		(end 359.752138 -102.693978)
		(width 0.15494)
		(layer "In7.Cu")
		(net "SSD7_PWRDIS_R")
	)
	(segment
		(start 356.648258 -121.642632)
		(end 357.8352 -120.45569)
		(width 0.15494)
		(layer "In7.Cu")
		(net "SSD7_PWRDIS_R")
	)
	(segment
		(start 379.99162 -210.03387)
		(end 380.27483 -209.75066)
		(width 0.15494)
		(layer "In7.Cu")
		(net "SSD7_PWRDIS_R")
	)
	(segment
		(start 369.978432 -169.2656)
		(end 364.508542 -163.79571)
		(width 0.15494)
		(layer "In7.Cu")
		(net "SSD7_PWRDIS_R")
	)
	(segment
		(start 380.27483 -209.736182)
		(end 380.8222 -209.188812)
		(width 0.15494)
		(layer "In7.Cu")
		(net "SSD7_PWRDIS_R")
	)
	(segment
		(start 380.31166 -200.68413)
		(end 380.297182 -200.68413)
		(width 0.15494)
		(layer "In7.Cu")
		(net "SSD7_PWRDIS_R")
	)
	(segment
		(start 357.8352 -120.45569)
		(end 357.8352 -119.0498)
		(width 0.15494)
		(layer "In7.Cu")
		(net "SSD7_PWRDIS_R")
	)
	(segment
		(start 373.398034 -169.53992)
		(end 373.123714 -169.2656)
		(width 0.15494)
		(layer "In7.Cu")
		(net "SSD7_PWRDIS_R")
	)
	(segment
		(start 372.217696 -230.244904)
		(end 372.217696 -217.062304)
		(width 0.15494)
		(layer "In7.Cu")
		(net "SSD7_PWRDIS_R")
	)
	(segment
		(start 356.341934 -91.36507)
		(end 356.341934 -81.890362)
		(width 0.15494)
		(layer "In7.Cu")
		(net "SSD7_PWRDIS_R")
	)
	(segment
		(start 358.532938 -163.181792)
		(end 357.606346 -162.2552)
		(width 0.15494)
		(layer "In7.Cu")
		(net "SSD7_PWRDIS_R")
	)
	(segment
		(start 374.397778 -170.48226)
		(end 373.455438 -169.53992)
		(width 0.15494)
		(layer "In7.Cu")
		(net "SSD7_PWRDIS_R")
	)
	(segment
		(start 374.397778 -170.539664)
		(end 374.397778 -170.48226)
		(width 0.15494)
		(layer "In7.Cu")
		(net "SSD7_PWRDIS_R")
	)
	(segment
		(start 357.8606 -115.6716)
		(end 357.8606 -106.070146)
		(width 0.15494)
		(layer "In7.Cu")
		(net "SSD7_PWRDIS_R")
	)
	(segment
		(start 353.9998 -141.479778)
		(end 353.9998 -141.078458)
		(width 0.15494)
		(layer "In7.Cu")
		(net "SSD7_PWRDIS_R")
	)
	(segment
		(start 374.547384 -170.68927)
		(end 374.397778 -170.539664)
		(width 0.15494)
		(layer "In7.Cu")
		(net "SSD7_PWRDIS_R")
	)
	(segment
		(start 359.752138 -100.91293)
		(end 358.962706 -100.123498)
		(width 0.15494)
		(layer "In7.Cu")
		(net "SSD7_PWRDIS_R")
	)
	(segment
		(start 358.50068 -100.123498)
		(end 354.901754 -96.524572)
		(width 0.15494)
		(layer "In7.Cu")
		(net "SSD7_PWRDIS_R")
	)
	(segment
		(start 357.8352 -119.0498)
		(end 359.0798 -117.8052)
		(width 0.15494)
		(layer "In7.Cu")
		(net "SSD7_PWRDIS_R")
	)
	(segment
		(start 373.455438 -169.53992)
		(end 373.398034 -169.53992)
		(width 0.15494)
		(layer "In7.Cu")
		(net "SSD7_PWRDIS_R")
	)
	(segment
		(start 354.00996 -159.547306)
		(end 354.00996 -141.489938)
		(width 0.15494)
		(layer "In7.Cu")
		(net "SSD7_PWRDIS_R")
	)
	(segment
		(start 380.59487 -200.981818)
		(end 380.59487 -200.96734)
		(width 0.15494)
		(layer "In7.Cu")
		(net "SSD7_PWRDIS_R")
	)
	(segment
		(start 358.962706 -100.123498)
		(end 358.50068 -100.123498)
		(width 0.15494)
		(layer "In7.Cu")
		(net "SSD7_PWRDIS_R")
	)
	(segment
		(start 378.665994 -199.052942)
		(end 378.665994 -187.409074)
		(width 0.15494)
		(layer "In7.Cu")
		(net "SSD7_PWRDIS_R")
	)
	(segment
		(start 378.665994 -187.409074)
		(end 378.5616 -187.30468)
		(width 0.15494)
		(layer "In7.Cu")
		(net "SSD7_PWRDIS_R")
	)
	(segment
		(start 353.9998 -141.078458)
		(end 354.00996 -141.068298)
		(width 0.15494)
		(layer "In7.Cu")
		(net "SSD7_PWRDIS_R")
	)
	(segment
		(start 357.606346 -162.2552)
		(end 356.717854 -162.2552)
		(width 0.15494)
		(layer "In7.Cu")
		(net "SSD7_PWRDIS_R")
	)
	(segment
		(start 358.951022 -163.79571)
		(end 358.95026 -163.795456)
		(width 0.15494)
		(layer "In7.Cu")
		(net "SSD7_PWRDIS_R")
	)
	(segment
		(start 380.59487 -200.96734)
		(end 380.31166 -200.68413)
		(width 0.15494)
		(layer "In7.Cu")
		(net "SSD7_PWRDIS_R")
	)
	(segment
		(start 376.81281 -176.49063)
		(end 376.4026 -176.08042)
		(width 0.15494)
		(layer "In7.Cu")
		(net "SSD7_PWRDIS_R")
	)
	(segment
		(start 238.035846 -72.39)
		(end 239.077246 -73.4314)
		(width 0.15494)
		(layer "In15.Cu")
		(net "SSD7_PWRDIS_R")
	)
	(segment
		(start 254.07874 -75.0697)
		(end 261.0485 -75.0697)
		(width 0.15494)
		(layer "In15.Cu")
		(net "SSD7_PWRDIS_R")
	)
	(segment
		(start 298.130214 -76.722986)
		(end 298.3738 -76.4794)
		(width 0.15494)
		(layer "In15.Cu")
		(net "SSD7_PWRDIS_R")
	)
	(segment
		(start 226.850956 -72.39)
		(end 238.035846 -72.39)
		(width 0.15494)
		(layer "In15.Cu")
		(net "SSD7_PWRDIS_R")
	)
	(segment
		(start 323.1642 -77.1652)
		(end 335.534 -77.1652)
		(width 0.15494)
		(layer "In15.Cu")
		(net "SSD7_PWRDIS_R")
	)
	(segment
		(start 222.661988 -74.605134)
		(end 222.794068 -74.737214)
		(width 0.15494)
		(layer "In15.Cu")
		(net "SSD7_PWRDIS_R")
	)
	(segment
		(start 249.636788 -74.74458)
		(end 253.75362 -74.74458)
		(width 0.15494)
		(layer "In15.Cu")
		(net "SSD7_PWRDIS_R")
	)
	(segment
		(start 261.0485 -75.0697)
		(end 261.9502 -74.168)
		(width 0.15494)
		(layer "In15.Cu")
		(net "SSD7_PWRDIS_R")
	)
	(segment
		(start 265.684 -74.168)
		(end 268.238986 -76.722986)
		(width 0.15494)
		(layer "In15.Cu")
		(net "SSD7_PWRDIS_R")
	)
	(segment
		(start 343.8652 -76.5048)
		(end 347.089476 -79.729076)
		(width 0.15494)
		(layer "In15.Cu")
		(net "SSD7_PWRDIS_R")
	)
	(segment
		(start 248.323608 -73.4314)
		(end 249.636788 -74.74458)
		(width 0.15494)
		(layer "In15.Cu")
		(net "SSD7_PWRDIS_R")
	)
	(segment
		(start 239.077246 -73.4314)
		(end 248.323608 -73.4314)
		(width 0.15494)
		(layer "In15.Cu")
		(net "SSD7_PWRDIS_R")
	)
	(segment
		(start 335.534 -77.1652)
		(end 336.1944 -76.5048)
		(width 0.15494)
		(layer "In15.Cu")
		(net "SSD7_PWRDIS_R")
	)
	(segment
		(start 310.845454 -76.4794)
		(end 312.043318 -75.281536)
		(width 0.15494)
		(layer "In15.Cu")
		(net "SSD7_PWRDIS_R")
	)
	(segment
		(start 354.180648 -79.729076)
		(end 356.341934 -81.890362)
		(width 0.15494)
		(layer "In15.Cu")
		(net "SSD7_PWRDIS_R")
	)
	(segment
		(start 222.794068 -74.737214)
		(end 224.503742 -74.737214)
		(width 0.15494)
		(layer "In15.Cu")
		(net "SSD7_PWRDIS_R")
	)
	(segment
		(start 268.238986 -76.722986)
		(end 298.130214 -76.722986)
		(width 0.15494)
		(layer "In15.Cu")
		(net "SSD7_PWRDIS_R")
	)
	(segment
		(start 321.280536 -75.281536)
		(end 323.1642 -77.1652)
		(width 0.15494)
		(layer "In15.Cu")
		(net "SSD7_PWRDIS_R")
	)
	(segment
		(start 261.9502 -74.168)
		(end 265.684 -74.168)
		(width 0.15494)
		(layer "In15.Cu")
		(net "SSD7_PWRDIS_R")
	)
	(segment
		(start 312.043318 -75.281536)
		(end 321.280536 -75.281536)
		(width 0.15494)
		(layer "In15.Cu")
		(net "SSD7_PWRDIS_R")
	)
	(segment
		(start 336.1944 -76.5048)
		(end 343.8652 -76.5048)
		(width 0.15494)
		(layer "In15.Cu")
		(net "SSD7_PWRDIS_R")
	)
	(segment
		(start 347.089476 -79.729076)
		(end 354.180648 -79.729076)
		(width 0.15494)
		(layer "In15.Cu")
		(net "SSD7_PWRDIS_R")
	)
	(segment
		(start 253.75362 -74.74458)
		(end 254.07874 -75.0697)
		(width 0.15494)
		(layer "In15.Cu")
		(net "SSD7_PWRDIS_R")
	)
	(segment
		(start 224.503742 -74.737214)
		(end 226.850956 -72.39)
		(width 0.15494)
		(layer "In15.Cu")
		(net "SSD7_PWRDIS_R")
	)
	(segment
		(start 298.3738 -76.4794)
		(end 310.845454 -76.4794)
		(width 0.15494)
		(layer "In15.Cu")
		(net "SSD7_PWRDIS_R")
	)
	(segment
		(start 340.493858 -214.387176)
		(end 340.094062 -213.98738)
		(width 0.13208)
		(layer "F.Cu")
		(net "RST_SSD11_PERST_N")
	)
	(via
		(at 340.741 -211.074)
		(size 0.6604)
		(drill 0.3302)
		(layers "F.Cu" "B.Cu")
		(net "RST_SSD11_PERST_N")
	)
	(via
		(at 340.094062 -213.98738)
		(size 0.4572)
		(drill 0.254)
		(layers "F.Cu" "B.Cu")
		(net "RST_SSD11_PERST_N")
	)
	(segment
		(start 340.49589 -212.1408)
		(end 340.49589 -211.70011)
		(width 0.13208)
		(layer "B.Cu")
		(net "RST_SSD11_PERST_N")
	)
	(segment
		(start 340.49589 -211.70011)
		(end 340.741 -211.455)
		(width 0.13208)
		(layer "B.Cu")
		(net "RST_SSD11_PERST_N")
	)
	(segment
		(start 340.741 -211.455)
		(end 340.741 -211.074)
		(width 0.13208)
		(layer "B.Cu")
		(net "RST_SSD11_PERST_N")
	)
	(segment
		(start 340.49589 -213.585552)
		(end 340.49589 -212.1408)
		(width 0.0889)
		(layer "B.Cu")
		(net "RST_SSD11_PERST_N")
	)
	(segment
		(start 339.725 -208.17205)
		(end 340.741 -209.18805)
		(width 0.13208)
		(layer "B.Cu")
		(net "RST_SSD11_PERST_N")
	)
	(segment
		(start 340.094062 -213.98738)
		(end 340.49589 -213.585552)
		(width 0.0889)
		(layer "B.Cu")
		(net "RST_SSD11_PERST_N")
	)
	(segment
		(start 340.741 -209.18805)
		(end 340.741 -211.074)
		(width 0.13208)
		(layer "B.Cu")
		(net "RST_SSD11_PERST_N")
	)
	(segment
		(start 116.07673 -84.79028)
		(end 117.548406 -84.79028)
		(width 0.13462)
		(layer "F.Cu")
		(net "CLK_100M_DB800ZL_SSD4_R_DP")
	)
	(segment
		(start 117.548406 -84.79028)
		(end 117.8433 -84.495386)
		(width 0.13462)
		(layer "F.Cu")
		(net "CLK_100M_DB800ZL_SSD4_R_DP")
	)
	(segment
		(start 132.784596 -27.04592)
		(end 132.01269 -27.04592)
		(width 0.13462)
		(layer "F.Cu")
		(net "CLK_100M_DB800ZL_SSD4_R_DP")
	)
	(segment
		(start 115.756436 -84.469986)
		(end 116.07673 -84.79028)
		(width 0.13462)
		(layer "F.Cu")
		(net "CLK_100M_DB800ZL_SSD4_R_DP")
	)
	(segment
		(start 133.081522 -27.342846)
		(end 132.784596 -27.04592)
		(width 0.13462)
		(layer "F.Cu")
		(net "CLK_100M_DB800ZL_SSD4_R_DP")
	)
	(segment
		(start 131.868672 -27.189938)
		(end 131.36499 -27.189938)
		(width 0.13462)
		(layer "F.Cu")
		(net "CLK_100M_DB800ZL_SSD4_R_DP")
	)
	(segment
		(start 132.01269 -27.04592)
		(end 131.868672 -27.189938)
		(width 0.13462)
		(layer "F.Cu")
		(net "CLK_100M_DB800ZL_SSD4_R_DP")
	)
	(via
		(at 133.081522 -27.342846)
		(size 0.508)
		(drill 0.254)
		(layers "F.Cu" "B.Cu")
		(net "CLK_100M_DB800ZL_SSD4_R_DP")
	)
	(via
		(at 117.8433 -84.495386)
		(size 0.508)
		(drill 0.254)
		(layers "F.Cu" "B.Cu")
		(net "CLK_100M_DB800ZL_SSD4_R_DP")
	)
	(segment
		(start 130.758692 -40.10533)
		(end 131.109212 -39.75481)
		(width 0.1651)
		(layer "In13.Cu")
		(net "CLK_100M_DB800ZL_SSD4_R_DP")
	)
	(segment
		(start 133.63956 -29.047694)
		(end 133.75386 -28.933394)
		(width 0.1651)
		(layer "In13.Cu")
		(net "CLK_100M_DB800ZL_SSD4_R_DP")
	)
	(segment
		(start 133.75386 -32.095694)
		(end 133.63956 -31.981394)
		(width 0.1651)
		(layer "In13.Cu")
		(net "CLK_100M_DB800ZL_SSD4_R_DP")
	)
	(segment
		(start 128.286256 -76.366624)
		(end 128.457198 -76.195682)
		(width 0.1651)
		(layer "In13.Cu")
		(net "CLK_100M_DB800ZL_SSD4_R_DP")
	)
	(segment
		(start 128.31699 -70.250304)
		(end 125.051566 -70.250304)
		(width 0.1651)
		(layer "In13.Cu")
		(net "CLK_100M_DB800ZL_SSD4_R_DP")
	)
	(segment
		(start 128.31699 -67.877944)
		(end 125.054106 -67.877944)
		(width 0.1651)
		(layer "In13.Cu")
		(net "CLK_100M_DB800ZL_SSD4_R_DP")
	)
	(segment
		(start 133.373368 -27.051)
		(end 133.081522 -27.342846)
		(width 0.1651)
		(layer "In13.Cu")
		(net "CLK_100M_DB800ZL_SSD4_R_DP")
	)
	(segment
		(start 133.75386 -33.810194)
		(end 133.75386 -33.314894)
		(width 0.1651)
		(layer "In13.Cu")
		(net "CLK_100M_DB800ZL_SSD4_R_DP")
	)
	(segment
		(start 128.31699 -68.766944)
		(end 128.457198 -68.626736)
		(width 0.1651)
		(layer "In13.Cu")
		(net "CLK_100M_DB800ZL_SSD4_R_DP")
	)
	(segment
		(start 130.758692 -40.267128)
		(end 130.758692 -40.10533)
		(width 0.1651)
		(layer "In13.Cu")
		(net "CLK_100M_DB800ZL_SSD4_R_DP")
	)
	(segment
		(start 133.75386 -28.933394)
		(end 133.75386 -28.438094)
		(width 0.1651)
		(layer "In13.Cu")
		(net "CLK_100M_DB800ZL_SSD4_R_DP")
	)
	(segment
		(start 130.40868 -40.61714)
		(end 130.758692 -40.267128)
		(width 0.1651)
		(layer "In13.Cu")
		(net "CLK_100M_DB800ZL_SSD4_R_DP")
	)
	(segment
		(start 119.247158 -84.785962)
		(end 124.73686 -79.29626)
		(width 0.1651)
		(layer "In13.Cu")
		(net "CLK_100M_DB800ZL_SSD4_R_DP")
	)
	(segment
		(start 128.31699 -74.995024)
		(end 125.051566 -74.995024)
		(width 0.1651)
		(layer "In13.Cu")
		(net "CLK_100M_DB800ZL_SSD4_R_DP")
	)
	(segment
		(start 125.051566 -72.622664)
		(end 124.759466 -72.330564)
		(width 0.1651)
		(layer "In13.Cu")
		(net "CLK_100M_DB800ZL_SSD4_R_DP")
	)
	(segment
		(start 124.759466 -72.330564)
		(end 124.759466 -71.484744)
		(width 0.1651)
		(layer "In13.Cu")
		(net "CLK_100M_DB800ZL_SSD4_R_DP")
	)
	(segment
		(start 133.585966 -27.051)
		(end 133.373368 -27.051)
		(width 0.1651)
		(layer "In13.Cu")
		(net "CLK_100M_DB800ZL_SSD4_R_DP")
	)
	(segment
		(start 125.104906 -73.511664)
		(end 128.31699 -73.511664)
		(width 0.1651)
		(layer "In13.Cu")
		(net "CLK_100M_DB800ZL_SSD4_R_DP")
	)
	(segment
		(start 128.31699 -71.139304)
		(end 128.457198 -70.999096)
		(width 0.1651)
		(layer "In13.Cu")
		(net "CLK_100M_DB800ZL_SSD4_R_DP")
	)
	(segment
		(start 124.759466 -73.857104)
		(end 125.104906 -73.511664)
		(width 0.1651)
		(layer "In13.Cu")
		(net "CLK_100M_DB800ZL_SSD4_R_DP")
	)
	(segment
		(start 124.759466 -74.702924)
		(end 124.759466 -73.857104)
		(width 0.1651)
		(layer "In13.Cu")
		(net "CLK_100M_DB800ZL_SSD4_R_DP")
	)
	(segment
		(start 124.751084 -66.732658)
		(end 125.073918 -66.409824)
		(width 0.1651)
		(layer "In13.Cu")
		(net "CLK_100M_DB800ZL_SSD4_R_DP")
	)
	(segment
		(start 131.621022 -39.404798)
		(end 131.621022 -39.243)
		(width 0.1651)
		(layer "In13.Cu")
		(net "CLK_100M_DB800ZL_SSD4_R_DP")
	)
	(segment
		(start 128.457198 -76.195682)
		(end 128.457198 -75.135232)
		(width 0.1651)
		(layer "In13.Cu")
		(net "CLK_100M_DB800ZL_SSD4_R_DP")
	)
	(segment
		(start 131.621022 -39.243)
		(end 131.971542 -38.89248)
		(width 0.1651)
		(layer "In13.Cu")
		(net "CLK_100M_DB800ZL_SSD4_R_DP")
	)
	(segment
		(start 124.759466 -69.112384)
		(end 125.104906 -68.766944)
		(width 0.1651)
		(layer "In13.Cu")
		(net "CLK_100M_DB800ZL_SSD4_R_DP")
	)
	(segment
		(start 133.75386 -31.371794)
		(end 133.75386 -30.876494)
		(width 0.1651)
		(layer "In13.Cu")
		(net "CLK_100M_DB800ZL_SSD4_R_DP")
	)
	(segment
		(start 125.080776 -76.366624)
		(end 128.286256 -76.366624)
		(width 0.1651)
		(layer "In13.Cu")
		(net "CLK_100M_DB800ZL_SSD4_R_DP")
	)
	(segment
		(start 131.971542 -38.89248)
		(end 132.13334 -38.89248)
		(width 0.1651)
		(layer "In13.Cu")
		(net "CLK_100M_DB800ZL_SSD4_R_DP")
	)
	(segment
		(start 128.31699 -73.511664)
		(end 128.457198 -73.371456)
		(width 0.1651)
		(layer "In13.Cu")
		(net "CLK_100M_DB800ZL_SSD4_R_DP")
	)
	(segment
		(start 125.051566 -70.250304)
		(end 124.759466 -69.958204)
		(width 0.1651)
		(layer "In13.Cu")
		(net "CLK_100M_DB800ZL_SSD4_R_DP")
	)
	(segment
		(start 133.63956 -30.762194)
		(end 133.63956 -30.266894)
		(width 0.1651)
		(layer "In13.Cu")
		(net "CLK_100M_DB800ZL_SSD4_R_DP")
	)
	(segment
		(start 131.27101 -39.75481)
		(end 131.621022 -39.404798)
		(width 0.1651)
		(layer "In13.Cu")
		(net "CLK_100M_DB800ZL_SSD4_R_DP")
	)
	(segment
		(start 131.109212 -39.75481)
		(end 131.27101 -39.75481)
		(width 0.1651)
		(layer "In13.Cu")
		(net "CLK_100M_DB800ZL_SSD4_R_DP")
	)
	(segment
		(start 128.31699 -72.622664)
		(end 125.051566 -72.622664)
		(width 0.1651)
		(layer "In13.Cu")
		(net "CLK_100M_DB800ZL_SSD4_R_DP")
	)
	(segment
		(start 132.483352 -38.542468)
		(end 132.483352 -36.434268)
		(width 0.1651)
		(layer "In13.Cu")
		(net "CLK_100M_DB800ZL_SSD4_R_DP")
	)
	(segment
		(start 128.457198 -73.371456)
		(end 128.457198 -72.762872)
		(width 0.1651)
		(layer "In13.Cu")
		(net "CLK_100M_DB800ZL_SSD4_R_DP")
	)
	(segment
		(start 133.63956 -28.323794)
		(end 133.63956 -27.828494)
		(width 0.1651)
		(layer "In13.Cu")
		(net "CLK_100M_DB800ZL_SSD4_R_DP")
	)
	(segment
		(start 133.75386 -34.534094)
		(end 133.63956 -34.419794)
		(width 0.1651)
		(layer "In13.Cu")
		(net "CLK_100M_DB800ZL_SSD4_R_DP")
	)
	(segment
		(start 133.75386 -33.314894)
		(end 133.63956 -33.200594)
		(width 0.1651)
		(layer "In13.Cu")
		(net "CLK_100M_DB800ZL_SSD4_R_DP")
	)
	(segment
		(start 128.457198 -68.018152)
		(end 128.31699 -67.877944)
		(width 0.1651)
		(layer "In13.Cu")
		(net "CLK_100M_DB800ZL_SSD4_R_DP")
	)
	(segment
		(start 133.75386 -28.438094)
		(end 133.63956 -28.323794)
		(width 0.1651)
		(layer "In13.Cu")
		(net "CLK_100M_DB800ZL_SSD4_R_DP")
	)
	(segment
		(start 125.104906 -68.766944)
		(end 128.31699 -68.766944)
		(width 0.1651)
		(layer "In13.Cu")
		(net "CLK_100M_DB800ZL_SSD4_R_DP")
	)
	(segment
		(start 133.75386 -35.16376)
		(end 133.75386 -34.534094)
		(width 0.1651)
		(layer "In13.Cu")
		(net "CLK_100M_DB800ZL_SSD4_R_DP")
	)
	(segment
		(start 129.896362 -40.96766)
		(end 130.246882 -40.61714)
		(width 0.1651)
		(layer "In13.Cu")
		(net "CLK_100M_DB800ZL_SSD4_R_DP")
	)
	(segment
		(start 117.8433 -84.495386)
		(end 118.133876 -84.785962)
		(width 0.1651)
		(layer "In13.Cu")
		(net "CLK_100M_DB800ZL_SSD4_R_DP")
	)
	(segment
		(start 124.759466 -69.958204)
		(end 124.759466 -69.112384)
		(width 0.1651)
		(layer "In13.Cu")
		(net "CLK_100M_DB800ZL_SSD4_R_DP")
	)
	(segment
		(start 133.63956 -33.924494)
		(end 133.75386 -33.810194)
		(width 0.1651)
		(layer "In13.Cu")
		(net "CLK_100M_DB800ZL_SSD4_R_DP")
	)
	(segment
		(start 133.75386 -30.152594)
		(end 133.75386 -29.657294)
		(width 0.1651)
		(layer "In13.Cu")
		(net "CLK_100M_DB800ZL_SSD4_R_DP")
	)
	(segment
		(start 133.75386 -27.218894)
		(end 133.585966 -27.051)
		(width 0.1651)
		(layer "In13.Cu")
		(net "CLK_100M_DB800ZL_SSD4_R_DP")
	)
	(segment
		(start 128.41986 -66.253106)
		(end 128.41986 -42.60596)
		(width 0.1651)
		(layer "In13.Cu")
		(net "CLK_100M_DB800ZL_SSD4_R_DP")
	)
	(segment
		(start 124.751084 -67.574922)
		(end 124.751084 -66.732658)
		(width 0.1651)
		(layer "In13.Cu")
		(net "CLK_100M_DB800ZL_SSD4_R_DP")
	)
	(segment
		(start 133.75386 -29.657294)
		(end 133.63956 -29.542994)
		(width 0.1651)
		(layer "In13.Cu")
		(net "CLK_100M_DB800ZL_SSD4_R_DP")
	)
	(segment
		(start 133.63956 -33.200594)
		(end 133.63956 -32.705294)
		(width 0.1651)
		(layer "In13.Cu")
		(net "CLK_100M_DB800ZL_SSD4_R_DP")
	)
	(segment
		(start 128.457198 -75.135232)
		(end 128.31699 -74.995024)
		(width 0.1651)
		(layer "In13.Cu")
		(net "CLK_100M_DB800ZL_SSD4_R_DP")
	)
	(segment
		(start 128.457198 -70.999096)
		(end 128.457198 -70.390512)
		(width 0.1651)
		(layer "In13.Cu")
		(net "CLK_100M_DB800ZL_SSD4_R_DP")
	)
	(segment
		(start 128.457198 -70.390512)
		(end 128.31699 -70.250304)
		(width 0.1651)
		(layer "In13.Cu")
		(net "CLK_100M_DB800ZL_SSD4_R_DP")
	)
	(segment
		(start 125.054106 -67.877944)
		(end 124.751084 -67.574922)
		(width 0.1651)
		(layer "In13.Cu")
		(net "CLK_100M_DB800ZL_SSD4_R_DP")
	)
	(segment
		(start 133.75386 -30.876494)
		(end 133.63956 -30.762194)
		(width 0.1651)
		(layer "In13.Cu")
		(net "CLK_100M_DB800ZL_SSD4_R_DP")
	)
	(segment
		(start 133.75386 -32.590994)
		(end 133.75386 -32.095694)
		(width 0.1651)
		(layer "In13.Cu")
		(net "CLK_100M_DB800ZL_SSD4_R_DP")
	)
	(segment
		(start 125.104906 -71.139304)
		(end 128.31699 -71.139304)
		(width 0.1651)
		(layer "In13.Cu")
		(net "CLK_100M_DB800ZL_SSD4_R_DP")
	)
	(segment
		(start 133.63956 -29.542994)
		(end 133.63956 -29.047694)
		(width 0.1651)
		(layer "In13.Cu")
		(net "CLK_100M_DB800ZL_SSD4_R_DP")
	)
	(segment
		(start 124.73686 -76.71054)
		(end 125.080776 -76.366624)
		(width 0.1651)
		(layer "In13.Cu")
		(net "CLK_100M_DB800ZL_SSD4_R_DP")
	)
	(segment
		(start 132.13334 -38.89248)
		(end 132.483352 -38.542468)
		(width 0.1651)
		(layer "In13.Cu")
		(net "CLK_100M_DB800ZL_SSD4_R_DP")
	)
	(segment
		(start 128.41986 -42.60596)
		(end 129.896362 -41.129458)
		(width 0.1651)
		(layer "In13.Cu")
		(net "CLK_100M_DB800ZL_SSD4_R_DP")
	)
	(segment
		(start 133.63956 -27.828494)
		(end 133.75386 -27.714194)
		(width 0.1651)
		(layer "In13.Cu")
		(net "CLK_100M_DB800ZL_SSD4_R_DP")
	)
	(segment
		(start 125.073918 -66.409824)
		(end 128.263142 -66.409824)
		(width 0.1651)
		(layer "In13.Cu")
		(net "CLK_100M_DB800ZL_SSD4_R_DP")
	)
	(segment
		(start 128.457198 -68.626736)
		(end 128.457198 -68.018152)
		(width 0.1651)
		(layer "In13.Cu")
		(net "CLK_100M_DB800ZL_SSD4_R_DP")
	)
	(segment
		(start 125.051566 -74.995024)
		(end 124.759466 -74.702924)
		(width 0.1651)
		(layer "In13.Cu")
		(net "CLK_100M_DB800ZL_SSD4_R_DP")
	)
	(segment
		(start 133.63956 -31.981394)
		(end 133.63956 -31.486094)
		(width 0.1651)
		(layer "In13.Cu")
		(net "CLK_100M_DB800ZL_SSD4_R_DP")
	)
	(segment
		(start 133.63956 -30.266894)
		(end 133.75386 -30.152594)
		(width 0.1651)
		(layer "In13.Cu")
		(net "CLK_100M_DB800ZL_SSD4_R_DP")
	)
	(segment
		(start 128.263142 -66.409824)
		(end 128.41986 -66.253106)
		(width 0.1651)
		(layer "In13.Cu")
		(net "CLK_100M_DB800ZL_SSD4_R_DP")
	)
	(segment
		(start 124.73686 -79.29626)
		(end 124.73686 -76.71054)
		(width 0.1651)
		(layer "In13.Cu")
		(net "CLK_100M_DB800ZL_SSD4_R_DP")
	)
	(segment
		(start 118.133876 -84.785962)
		(end 119.247158 -84.785962)
		(width 0.1651)
		(layer "In13.Cu")
		(net "CLK_100M_DB800ZL_SSD4_R_DP")
	)
	(segment
		(start 124.759466 -71.484744)
		(end 125.104906 -71.139304)
		(width 0.1651)
		(layer "In13.Cu")
		(net "CLK_100M_DB800ZL_SSD4_R_DP")
	)
	(segment
		(start 128.457198 -72.762872)
		(end 128.31699 -72.622664)
		(width 0.1651)
		(layer "In13.Cu")
		(net "CLK_100M_DB800ZL_SSD4_R_DP")
	)
	(segment
		(start 133.63956 -32.705294)
		(end 133.75386 -32.590994)
		(width 0.1651)
		(layer "In13.Cu")
		(net "CLK_100M_DB800ZL_SSD4_R_DP")
	)
	(segment
		(start 133.75386 -27.714194)
		(end 133.75386 -27.218894)
		(width 0.1651)
		(layer "In13.Cu")
		(net "CLK_100M_DB800ZL_SSD4_R_DP")
	)
	(segment
		(start 130.246882 -40.61714)
		(end 130.40868 -40.61714)
		(width 0.1651)
		(layer "In13.Cu")
		(net "CLK_100M_DB800ZL_SSD4_R_DP")
	)
	(segment
		(start 133.63956 -31.486094)
		(end 133.75386 -31.371794)
		(width 0.1651)
		(layer "In13.Cu")
		(net "CLK_100M_DB800ZL_SSD4_R_DP")
	)
	(segment
		(start 129.896362 -41.129458)
		(end 129.896362 -40.96766)
		(width 0.1651)
		(layer "In13.Cu")
		(net "CLK_100M_DB800ZL_SSD4_R_DP")
	)
	(segment
		(start 132.483352 -36.434268)
		(end 133.75386 -35.16376)
		(width 0.1651)
		(layer "In13.Cu")
		(net "CLK_100M_DB800ZL_SSD4_R_DP")
	)
	(segment
		(start 133.63956 -34.419794)
		(end 133.63956 -33.924494)
		(width 0.1651)
		(layer "In13.Cu")
		(net "CLK_100M_DB800ZL_SSD4_R_DP")
	)
	(segment
		(start 382.802384 -251.956824)
		(end 382.802384 -251.158502)
		(width 0.13208)
		(layer "F.Cu")
		(net "PEX3_MODE_SEL11")
	)
	(segment
		(start 413.649922 -282.599892)
		(end 414.124902 -283.074872)
		(width 0.13208)
		(layer "F.Cu")
		(net "PEX3_MODE_SEL11")
	)
	(segment
		(start 382.802384 -251.158502)
		(end 382.802384 -250.470924)
		(width 0.13208)
		(layer "F.Cu")
		(net "PEX3_MODE_SEL11")
	)
	(via
		(at 382.802384 -251.158502)
		(size 0.508)
		(drill 0.254)
		(layers "F.Cu" "B.Cu")
		(net "PEX3_MODE_SEL11")
	)
	(via
		(at 414.124902 -283.074872)
		(size 0.4064)
		(drill 0.2032)
		(layers "F.Cu" "B.Cu")
		(net "PEX3_MODE_SEL11")
	)
	(segment
		(start 384.277108 -255.154938)
		(end 383.653284 -254.531114)
		(width 0.13208)
		(layer "B.Cu")
		(net "PEX3_MODE_SEL11")
	)
	(segment
		(start 398.05991 -255.154938)
		(end 384.277108 -255.154938)
		(width 0.13208)
		(layer "B.Cu")
		(net "PEX3_MODE_SEL11")
	)
	(segment
		(start 382.51511 -254.531114)
		(end 382.259332 -254.275336)
		(width 0.13208)
		(layer "B.Cu")
		(net "PEX3_MODE_SEL11")
	)
	(segment
		(start 415.075116 -272.170144)
		(end 412.043118 -269.138146)
		(width 0.13208)
		(layer "B.Cu")
		(net "PEX3_MODE_SEL11")
	)
	(segment
		(start 415.075116 -282.124658)
		(end 415.075116 -272.170144)
		(width 0.13208)
		(layer "B.Cu")
		(net "PEX3_MODE_SEL11")
	)
	(segment
		(start 414.124902 -283.074872)
		(end 415.075116 -282.124658)
		(width 0.13208)
		(layer "B.Cu")
		(net "PEX3_MODE_SEL11")
	)
	(segment
		(start 411.680406 -269.138146)
		(end 410.97962 -268.43736)
		(width 0.13208)
		(layer "B.Cu")
		(net "PEX3_MODE_SEL11")
	)
	(segment
		(start 410.97962 -268.43736)
		(end 410.97962 -268.074648)
		(width 0.13208)
		(layer "B.Cu")
		(net "PEX3_MODE_SEL11")
	)
	(segment
		(start 410.97962 -268.074648)
		(end 398.05991 -255.154938)
		(width 0.13208)
		(layer "B.Cu")
		(net "PEX3_MODE_SEL11")
	)
	(segment
		(start 412.043118 -269.138146)
		(end 411.680406 -269.138146)
		(width 0.13208)
		(layer "B.Cu")
		(net "PEX3_MODE_SEL11")
	)
	(segment
		(start 382.259332 -254.275336)
		(end 382.259332 -251.701554)
		(width 0.13208)
		(layer "B.Cu")
		(net "PEX3_MODE_SEL11")
	)
	(segment
		(start 383.653284 -254.531114)
		(end 382.51511 -254.531114)
		(width 0.13208)
		(layer "B.Cu")
		(net "PEX3_MODE_SEL11")
	)
	(segment
		(start 382.259332 -251.701554)
		(end 382.802384 -251.158502)
		(width 0.13208)
		(layer "B.Cu")
		(net "PEX3_MODE_SEL11")
	)
	(segment
		(start 215.98128 -214.73033)
		(end 216.5604 -214.73033)
		(width 0.13208)
		(layer "F.Cu")
		(net "SMB_NIC6_R_SDA")
	)
	(segment
		(start 211.200746 -198.247)
		(end 210.83905 -198.247)
		(width 0.13208)
		(layer "F.Cu")
		(net "SMB_NIC6_R_SDA")
	)
	(segment
		(start 216.835736 -214.454994)
		(end 216.835736 -214.238586)
		(width 0.13208)
		(layer "F.Cu")
		(net "SMB_NIC6_R_SDA")
	)
	(segment
		(start 212.522054 -198.44512)
		(end 211.398866 -198.44512)
		(width 0.13208)
		(layer "F.Cu")
		(net "SMB_NIC6_R_SDA")
	)
	(segment
		(start 216.5604 -214.73033)
		(end 216.835736 -214.454994)
		(width 0.13208)
		(layer "F.Cu")
		(net "SMB_NIC6_R_SDA")
	)
	(segment
		(start 215.489536 -214.238586)
		(end 215.98128 -214.73033)
		(width 0.13208)
		(layer "F.Cu")
		(net "SMB_NIC6_R_SDA")
	)
	(segment
		(start 210.83905 -198.247)
		(end 210.83905 -198.482204)
		(width 0.13208)
		(layer "F.Cu")
		(net "SMB_NIC6_R_SDA")
	)
	(segment
		(start 210.83905 -198.482204)
		(end 210.566254 -198.755)
		(width 0.13208)
		(layer "F.Cu")
		(net "SMB_NIC6_R_SDA")
	)
	(segment
		(start 210.566254 -198.755)
		(end 209.423 -198.755)
		(width 0.13208)
		(layer "F.Cu")
		(net "SMB_NIC6_R_SDA")
	)
	(segment
		(start 211.398866 -198.44512)
		(end 211.200746 -198.247)
		(width 0.13208)
		(layer "F.Cu")
		(net "SMB_NIC6_R_SDA")
	)
	(via
		(at 215.489536 -214.238586)
		(size 0.508)
		(drill 0.254)
		(layers "F.Cu" "B.Cu")
		(net "SMB_NIC6_R_SDA")
	)
	(via
		(at 209.423 -198.755)
		(size 0.508)
		(drill 0.254)
		(layers "F.Cu" "B.Cu")
		(net "SMB_NIC6_R_SDA")
	)
	(segment
		(start 209.423 -198.755)
		(end 209.82305 -198.35495)
		(width 0.13208)
		(layer "B.Cu")
		(net "SMB_NIC6_R_SDA")
	)
	(segment
		(start 209.82305 -198.35495)
		(end 212.09 -198.35495)
		(width 0.13208)
		(layer "B.Cu")
		(net "SMB_NIC6_R_SDA")
	)
	(segment
		(start 214.338154 -201.384154)
		(end 214.338154 -213.087204)
		(width 0.15494)
		(layer "In7.Cu")
		(net "SMB_NIC6_R_SDA")
	)
	(segment
		(start 209.423 -198.755)
		(end 211.709 -198.755)
		(width 0.15494)
		(layer "In7.Cu")
		(net "SMB_NIC6_R_SDA")
	)
	(segment
		(start 211.709 -198.755)
		(end 214.338154 -201.384154)
		(width 0.15494)
		(layer "In7.Cu")
		(net "SMB_NIC6_R_SDA")
	)
	(segment
		(start 214.338154 -213.087204)
		(end 215.489536 -214.238586)
		(width 0.15494)
		(layer "In7.Cu")
		(net "SMB_NIC6_R_SDA")
	)
	(via
		(at 360.098594 -330.639166)
		(size 0.508)
		(drill 0.254)
		(layers "F.Cu" "B.Cu")
		(net "UART_MB_BIC_RX")
	)
	(segment
		(start 395.515338 -360.376724)
		(end 394.040106 -360.376724)
		(width 0.13208)
		(layer "B.Cu")
		(net "UART_MB_BIC_RX")
	)
	(segment
		(start 395.29004 -361.647486)
		(end 395.29004 -368.990118)
		(width 0.13208)
		(layer "B.Cu")
		(net "UART_MB_BIC_RX")
	)
	(segment
		(start 394.040106 -360.376724)
		(end 394.029692 -360.387138)
		(width 0.13208)
		(layer "B.Cu")
		(net "UART_MB_BIC_RX")
	)
	(segment
		(start 395.515338 -360.376724)
		(end 395.515338 -361.422188)
		(width 0.13208)
		(layer "B.Cu")
		(net "UART_MB_BIC_RX")
	)
	(segment
		(start 395.515338 -361.422188)
		(end 395.29004 -361.647486)
		(width 0.13208)
		(layer "B.Cu")
		(net "UART_MB_BIC_RX")
	)
	(segment
		(start 395.29004 -368.874294)
		(end 391.232644 -364.816898)
		(width 0.15494)
		(layer "In9.Cu")
		(net "UART_MB_BIC_RX")
	)
	(segment
		(start 368.806984 -339.795866)
		(end 360.098594 -331.087476)
		(width 0.15494)
		(layer "In9.Cu")
		(net "UART_MB_BIC_RX")
	)
	(segment
		(start 360.098594 -331.087476)
		(end 360.098594 -330.639166)
		(width 0.15494)
		(layer "In9.Cu")
		(net "UART_MB_BIC_RX")
	)
	(segment
		(start 391.232644 -364.816898)
		(end 379.561852 -364.816898)
		(width 0.15494)
		(layer "In9.Cu")
		(net "UART_MB_BIC_RX")
	)
	(segment
		(start 379.561852 -364.816898)
		(end 368.806984 -354.06203)
		(width 0.15494)
		(layer "In9.Cu")
		(net "UART_MB_BIC_RX")
	)
	(segment
		(start 395.29004 -368.990118)
		(end 395.29004 -368.874294)
		(width 0.15494)
		(layer "In9.Cu")
		(net "UART_MB_BIC_RX")
	)
	(segment
		(start 368.806984 -354.06203)
		(end 368.806984 -339.795866)
		(width 0.15494)
		(layer "In9.Cu")
		(net "UART_MB_BIC_RX")
	)
	(segment
		(start 60.12053 -27.066494)
		(end 60.942474 -27.066494)
		(width 0.13208)
		(layer "F.Cu")
		(net "PRSNT_SSD2_R_N")
	)
	(segment
		(start 336.493866 -228.656134)
		(end 336.493866 -227.987098)
		(width 0.13208)
		(layer "F.Cu")
		(net "PRSNT_SSD2_R_N")
	)
	(segment
		(start 59.109102 -26.03373)
		(end 59.109102 -27.04973)
		(width 0.13208)
		(layer "F.Cu")
		(net "PRSNT_SSD2_R_N")
	)
	(segment
		(start 59.109102 -27.04973)
		(end 60.103766 -27.04973)
		(width 0.13208)
		(layer "F.Cu")
		(net "PRSNT_SSD2_R_N")
	)
	(segment
		(start 234.667552 -224.704148)
		(end 235.067348 -225.103944)
		(width 0.13208)
		(layer "F.Cu")
		(net "PRSNT_SSD2_R_N")
	)
	(segment
		(start 58.575702 -36.515548)
		(end 59.396122 -36.515548)
		(width 0.13208)
		(layer "F.Cu")
		(net "PRSNT_SSD2_R_N")
	)
	(segment
		(start 60.103766 -27.04973)
		(end 60.12053 -27.066494)
		(width 0.13208)
		(layer "F.Cu")
		(net "PRSNT_SSD2_R_N")
	)
	(segment
		(start 336.296 -228.854)
		(end 336.493866 -228.656134)
		(width 0.13208)
		(layer "F.Cu")
		(net "PRSNT_SSD2_R_N")
	)
	(via
		(at 235.067348 -225.103944)
		(size 0.4572)
		(drill 0.254)
		(layers "F.Cu" "B.Cu")
		(net "PRSNT_SSD2_R_N")
	)
	(via
		(at 109.804962 -199.407018)
		(size 0.508)
		(drill 0.254)
		(layers "F.Cu" "B.Cu")
		(net "PRSNT_SSD2_R_N")
	)
	(via
		(at 113.891314 -97.190814)
		(size 0.508)
		(drill 0.254)
		(layers "F.Cu" "B.Cu")
		(net "PRSNT_SSD2_R_N")
	)
	(via
		(at 60.942474 -27.066494)
		(size 0.508)
		(drill 0.254)
		(layers "F.Cu" "B.Cu")
		(net "PRSNT_SSD2_R_N")
	)
	(via
		(at 59.247532 -91.233244)
		(size 0.508)
		(drill 0.254)
		(layers "F.Cu" "B.Cu")
		(net "PRSNT_SSD2_R_N")
	)
	(via
		(at 247.951244 -200.614026)
		(size 0.508)
		(drill 0.254)
		(layers "F.Cu" "B.Cu")
		(net "PRSNT_SSD2_R_N")
	)
	(via
		(at 333.07655 -235.945172)
		(size 0.508)
		(drill 0.254)
		(layers "F.Cu" "B.Cu")
		(net "PRSNT_SSD2_R_N")
	)
	(via
		(at 59.396122 -36.515548)
		(size 0.508)
		(drill 0.254)
		(layers "F.Cu" "B.Cu")
		(net "PRSNT_SSD2_R_N")
	)
	(via
		(at 336.296 -228.854)
		(size 0.508)
		(drill 0.254)
		(layers "F.Cu" "B.Cu")
		(net "PRSNT_SSD2_R_N")
	)
	(segment
		(start 57.76341 -29.742892)
		(end 57.76341 -34.882836)
		(width 0.15494)
		(layer "In5.Cu")
		(net "PRSNT_SSD2_R_N")
	)
	(segment
		(start 59.406028 -39.638986)
		(end 64.8208 -45.053758)
		(width 0.15494)
		(layer "In5.Cu")
		(net "PRSNT_SSD2_R_N")
	)
	(segment
		(start 60.439808 -27.066494)
		(end 57.76341 -29.742892)
		(width 0.15494)
		(layer "In5.Cu")
		(net "PRSNT_SSD2_R_N")
	)
	(segment
		(start 336.296 -231.269032)
		(end 336.296 -228.854)
		(width 0.15494)
		(layer "In5.Cu")
		(net "PRSNT_SSD2_R_N")
	)
	(segment
		(start 66.04 -76.295758)
		(end 66.04 -79.870808)
		(width 0.15494)
		(layer "In5.Cu")
		(net "PRSNT_SSD2_R_N")
	)
	(segment
		(start 64.8208 -75.076558)
		(end 66.04 -76.295758)
		(width 0.15494)
		(layer "In5.Cu")
		(net "PRSNT_SSD2_R_N")
	)
	(segment
		(start 109.804962 -199.407018)
		(end 114.080544 -203.6826)
		(width 0.15494)
		(layer "In5.Cu")
		(net "PRSNT_SSD2_R_N")
	)
	(segment
		(start 123.444 -197.8152)
		(end 123.444 -186.3344)
		(width 0.15494)
		(layer "In5.Cu")
		(net "PRSNT_SSD2_R_N")
	)
	(segment
		(start 333.07655 -235.945172)
		(end 333.07655 -234.488482)
		(width 0.15494)
		(layer "In5.Cu")
		(net "PRSNT_SSD2_R_N")
	)
	(segment
		(start 117.5766 -203.6826)
		(end 123.444 -197.8152)
		(width 0.15494)
		(layer "In5.Cu")
		(net "PRSNT_SSD2_R_N")
	)
	(segment
		(start 120.17756 -104.04221)
		(end 113.891314 -97.755964)
		(width 0.15494)
		(layer "In5.Cu")
		(net "PRSNT_SSD2_R_N")
	)
	(segment
		(start 114.080544 -203.6826)
		(end 117.5766 -203.6826)
		(width 0.15494)
		(layer "In5.Cu")
		(net "PRSNT_SSD2_R_N")
	)
	(segment
		(start 66.04 -79.870808)
		(end 61.313568 -84.59724)
		(width 0.15494)
		(layer "In5.Cu")
		(net "PRSNT_SSD2_R_N")
	)
	(segment
		(start 59.396122 -36.515548)
		(end 59.406028 -36.525454)
		(width 0.15494)
		(layer "In5.Cu")
		(net "PRSNT_SSD2_R_N")
	)
	(segment
		(start 57.76341 -34.882836)
		(end 59.396122 -36.515548)
		(width 0.15494)
		(layer "In5.Cu")
		(net "PRSNT_SSD2_R_N")
	)
	(segment
		(start 120.793002 -118.46179)
		(end 120.17756 -117.846348)
		(width 0.15494)
		(layer "In5.Cu")
		(net "PRSNT_SSD2_R_N")
	)
	(segment
		(start 120.06326 -126.55169)
		(end 120.793002 -125.821948)
		(width 0.15494)
		(layer "In5.Cu")
		(net "PRSNT_SSD2_R_N")
	)
	(segment
		(start 123.444 -186.3344)
		(end 120.06326 -182.95366)
		(width 0.15494)
		(layer "In5.Cu")
		(net "PRSNT_SSD2_R_N")
	)
	(segment
		(start 64.8208 -45.053758)
		(end 64.8208 -75.076558)
		(width 0.15494)
		(layer "In5.Cu")
		(net "PRSNT_SSD2_R_N")
	)
	(segment
		(start 120.06326 -182.95366)
		(end 120.06326 -126.55169)
		(width 0.15494)
		(layer "In5.Cu")
		(net "PRSNT_SSD2_R_N")
	)
	(segment
		(start 113.891314 -97.755964)
		(end 113.891314 -97.190814)
		(width 0.15494)
		(layer "In5.Cu")
		(net "PRSNT_SSD2_R_N")
	)
	(segment
		(start 120.793002 -125.821948)
		(end 120.793002 -118.46179)
		(width 0.15494)
		(layer "In5.Cu")
		(net "PRSNT_SSD2_R_N")
	)
	(segment
		(start 61.313568 -84.59724)
		(end 61.313568 -86.693248)
		(width 0.15494)
		(layer "In5.Cu")
		(net "PRSNT_SSD2_R_N")
	)
	(segment
		(start 60.942474 -27.066494)
		(end 60.439808 -27.066494)
		(width 0.15494)
		(layer "In5.Cu")
		(net "PRSNT_SSD2_R_N")
	)
	(segment
		(start 333.07655 -234.488482)
		(end 336.296 -231.269032)
		(width 0.15494)
		(layer "In5.Cu")
		(net "PRSNT_SSD2_R_N")
	)
	(segment
		(start 59.247532 -88.759284)
		(end 59.247532 -91.233244)
		(width 0.15494)
		(layer "In5.Cu")
		(net "PRSNT_SSD2_R_N")
	)
	(segment
		(start 61.313568 -86.693248)
		(end 59.247532 -88.759284)
		(width 0.15494)
		(layer "In5.Cu")
		(net "PRSNT_SSD2_R_N")
	)
	(segment
		(start 59.406028 -36.525454)
		(end 59.406028 -39.638986)
		(width 0.15494)
		(layer "In5.Cu")
		(net "PRSNT_SSD2_R_N")
	)
	(segment
		(start 120.17756 -117.846348)
		(end 120.17756 -104.04221)
		(width 0.15494)
		(layer "In5.Cu")
		(net "PRSNT_SSD2_R_N")
	)
	(segment
		(start 236.429804 -225.342196)
		(end 236.429804 -225.103944)
		(width 0.15494)
		(layer "In7.Cu")
		(net "PRSNT_SSD2_R_N")
	)
	(segment
		(start 249.21972 -204.498448)
		(end 249.21972 -201.882502)
		(width 0.15494)
		(layer "In7.Cu")
		(net "PRSNT_SSD2_R_N")
	)
	(segment
		(start 245.720616 -212.515958)
		(end 247.153176 -211.083398)
		(width 0.15494)
		(layer "In7.Cu")
		(net "PRSNT_SSD2_R_N")
	)
	(segment
		(start 245.618 -214.755476)
		(end 245.720616 -214.65286)
		(width 0.15494)
		(layer "In7.Cu")
		(net "PRSNT_SSD2_R_N")
	)
	(segment
		(start 244.3988 -221.920054)
		(end 244.3988 -217.887804)
		(width 0.15494)
		(layer "In7.Cu")
		(net "PRSNT_SSD2_R_N")
	)
	(segment
		(start 244.3988 -217.887804)
		(end 244.406674 -217.87993)
		(width 0.15494)
		(layer "In7.Cu")
		(net "PRSNT_SSD2_R_N")
	)
	(segment
		(start 247.460262 -207.177132)
		(end 247.46712 -207.170274)
		(width 0.15494)
		(layer "In7.Cu")
		(net "PRSNT_SSD2_R_N")
	)
	(segment
		(start 247.12168 -208.96961)
		(end 247.12676 -208.96453)
		(width 0.15494)
		(layer "In7.Cu")
		(net "PRSNT_SSD2_R_N")
	)
	(segment
		(start 247.153176 -211.083398)
		(end 247.153176 -209.354674)
		(width 0.15494)
		(layer "In7.Cu")
		(net "PRSNT_SSD2_R_N")
	)
	(segment
		(start 245.618 -214.7824)
		(end 245.618 -214.755476)
		(width 0.15494)
		(layer "In7.Cu")
		(net "PRSNT_SSD2_R_N")
	)
	(segment
		(start 247.46712 -207.170274)
		(end 247.46712 -206.251048)
		(width 0.15494)
		(layer "In7.Cu")
		(net "PRSNT_SSD2_R_N")
	)
	(segment
		(start 236.1438 -225.6282)
		(end 236.429804 -225.342196)
		(width 0.15494)
		(layer "In7.Cu")
		(net "PRSNT_SSD2_R_N")
	)
	(segment
		(start 235.067348 -225.103944)
		(end 235.591604 -225.6282)
		(width 0.15494)
		(layer "In7.Cu")
		(net "PRSNT_SSD2_R_N")
	)
	(segment
		(start 247.12676 -207.960976)
		(end 247.460262 -207.627474)
		(width 0.15494)
		(layer "In7.Cu")
		(net "PRSNT_SSD2_R_N")
	)
	(segment
		(start 249.21972 -201.882502)
		(end 247.951244 -200.614026)
		(width 0.15494)
		(layer "In7.Cu")
		(net "PRSNT_SSD2_R_N")
	)
	(segment
		(start 242.087654 -224.2312)
		(end 244.3988 -221.920054)
		(width 0.15494)
		(layer "In7.Cu")
		(net "PRSNT_SSD2_R_N")
	)
	(segment
		(start 247.12676 -208.96453)
		(end 247.12676 -207.960976)
		(width 0.15494)
		(layer "In7.Cu")
		(net "PRSNT_SSD2_R_N")
	)
	(segment
		(start 247.12168 -209.323178)
		(end 247.12168 -208.96961)
		(width 0.15494)
		(layer "In7.Cu")
		(net "PRSNT_SSD2_R_N")
	)
	(segment
		(start 238.734346 -224.917)
		(end 239.420146 -224.2312)
		(width 0.15494)
		(layer "In7.Cu")
		(net "PRSNT_SSD2_R_N")
	)
	(segment
		(start 244.406674 -215.993726)
		(end 245.618 -214.7824)
		(width 0.15494)
		(layer "In7.Cu")
		(net "PRSNT_SSD2_R_N")
	)
	(segment
		(start 245.720616 -214.65286)
		(end 245.720616 -212.515958)
		(width 0.15494)
		(layer "In7.Cu")
		(net "PRSNT_SSD2_R_N")
	)
	(segment
		(start 236.429804 -225.103944)
		(end 236.616748 -224.917)
		(width 0.15494)
		(layer "In7.Cu")
		(net "PRSNT_SSD2_R_N")
	)
	(segment
		(start 236.616748 -224.917)
		(end 238.734346 -224.917)
		(width 0.15494)
		(layer "In7.Cu")
		(net "PRSNT_SSD2_R_N")
	)
	(segment
		(start 239.420146 -224.2312)
		(end 242.087654 -224.2312)
		(width 0.15494)
		(layer "In7.Cu")
		(net "PRSNT_SSD2_R_N")
	)
	(segment
		(start 247.460262 -207.627474)
		(end 247.460262 -207.177132)
		(width 0.15494)
		(layer "In7.Cu")
		(net "PRSNT_SSD2_R_N")
	)
	(segment
		(start 235.591604 -225.6282)
		(end 236.1438 -225.6282)
		(width 0.15494)
		(layer "In7.Cu")
		(net "PRSNT_SSD2_R_N")
	)
	(segment
		(start 244.406674 -217.87993)
		(end 244.406674 -215.993726)
		(width 0.15494)
		(layer "In7.Cu")
		(net "PRSNT_SSD2_R_N")
	)
	(segment
		(start 247.153176 -209.354674)
		(end 247.12168 -209.323178)
		(width 0.15494)
		(layer "In7.Cu")
		(net "PRSNT_SSD2_R_N")
	)
	(segment
		(start 247.46712 -206.251048)
		(end 249.21972 -204.498448)
		(width 0.15494)
		(layer "In7.Cu")
		(net "PRSNT_SSD2_R_N")
	)
	(segment
		(start 249.06732 -231.6226)
		(end 255.6256 -231.6226)
		(width 0.15494)
		(layer "In13.Cu")
		(net "PRSNT_SSD2_R_N")
	)
	(segment
		(start 256.892044 -230.356156)
		(end 256.892806 -230.356156)
		(width 0.15494)
		(layer "In13.Cu")
		(net "PRSNT_SSD2_R_N")
	)
	(segment
		(start 272.5039 -230.7717)
		(end 277.276814 -235.544614)
		(width 0.15494)
		(layer "In13.Cu")
		(net "PRSNT_SSD2_R_N")
	)
	(segment
		(start 246.466614 -229.021894)
		(end 249.06732 -231.6226)
		(width 0.15494)
		(layer "In13.Cu")
		(net "PRSNT_SSD2_R_N")
	)
	(segment
		(start 258.844796 -230.7717)
		(end 272.5039 -230.7717)
		(width 0.15494)
		(layer "In13.Cu")
		(net "PRSNT_SSD2_R_N")
	)
	(segment
		(start 317.9572 -236.728)
		(end 328.939652 -236.728)
		(width 0.15494)
		(layer "In13.Cu")
		(net "PRSNT_SSD2_R_N")
	)
	(segment
		(start 243.772182 -229.021894)
		(end 246.466614 -229.021894)
		(width 0.15494)
		(layer "In13.Cu")
		(net "PRSNT_SSD2_R_N")
	)
	(segment
		(start 242.949476 -229.8446)
		(end 243.772182 -229.021894)
		(width 0.15494)
		(layer "In13.Cu")
		(net "PRSNT_SSD2_R_N")
	)
	(segment
		(start 256.892806 -230.356156)
		(end 256.933954 -230.315008)
		(width 0.15494)
		(layer "In13.Cu")
		(net "PRSNT_SSD2_R_N")
	)
	(segment
		(start 328.939652 -236.728)
		(end 330.387452 -235.2802)
		(width 0.15494)
		(layer "In13.Cu")
		(net "PRSNT_SSD2_R_N")
	)
	(segment
		(start 316.773814 -235.544614)
		(end 317.9572 -236.728)
		(width 0.15494)
		(layer "In13.Cu")
		(net "PRSNT_SSD2_R_N")
	)
	(segment
		(start 255.6256 -231.6226)
		(end 256.892044 -230.356156)
		(width 0.15494)
		(layer "In13.Cu")
		(net "PRSNT_SSD2_R_N")
	)
	(segment
		(start 256.933954 -230.315008)
		(end 258.388104 -230.315008)
		(width 0.15494)
		(layer "In13.Cu")
		(net "PRSNT_SSD2_R_N")
	)
	(segment
		(start 235.067348 -225.103944)
		(end 235.067348 -227.729542)
		(width 0.15494)
		(layer "In13.Cu")
		(net "PRSNT_SSD2_R_N")
	)
	(segment
		(start 236.054392 -228.716586)
		(end 237.005622 -228.716586)
		(width 0.15494)
		(layer "In13.Cu")
		(net "PRSNT_SSD2_R_N")
	)
	(segment
		(start 277.276814 -235.544614)
		(end 316.773814 -235.544614)
		(width 0.15494)
		(layer "In13.Cu")
		(net "PRSNT_SSD2_R_N")
	)
	(segment
		(start 235.067348 -227.729542)
		(end 236.054392 -228.716586)
		(width 0.15494)
		(layer "In13.Cu")
		(net "PRSNT_SSD2_R_N")
	)
	(segment
		(start 238.133636 -229.8446)
		(end 242.949476 -229.8446)
		(width 0.15494)
		(layer "In13.Cu")
		(net "PRSNT_SSD2_R_N")
	)
	(segment
		(start 330.387452 -235.2802)
		(end 332.411578 -235.2802)
		(width 0.15494)
		(layer "In13.Cu")
		(net "PRSNT_SSD2_R_N")
	)
	(segment
		(start 258.388104 -230.315008)
		(end 258.844796 -230.7717)
		(width 0.15494)
		(layer "In13.Cu")
		(net "PRSNT_SSD2_R_N")
	)
	(segment
		(start 332.411578 -235.2802)
		(end 333.07655 -235.945172)
		(width 0.15494)
		(layer "In13.Cu")
		(net "PRSNT_SSD2_R_N")
	)
	(segment
		(start 237.005622 -228.716586)
		(end 238.133636 -229.8446)
		(width 0.15494)
		(layer "In13.Cu")
		(net "PRSNT_SSD2_R_N")
	)
	(segment
		(start 111.721138 -97.190814)
		(end 108.680504 -94.15018)
		(width 0.15494)
		(layer "In15.Cu")
		(net "PRSNT_SSD2_R_N")
	)
	(segment
		(start 87.83447 -91.04884)
		(end 84.470494 -94.412816)
		(width 0.15494)
		(layer "In15.Cu")
		(net "PRSNT_SSD2_R_N")
	)
	(segment
		(start 74.79792 -91.233244)
		(end 59.247532 -91.233244)
		(width 0.15494)
		(layer "In15.Cu")
		(net "PRSNT_SSD2_R_N")
	)
	(segment
		(start 137.228326 -213.5378)
		(end 134.480554 -213.5378)
		(width 0.15494)
		(layer "In15.Cu")
		(net "PRSNT_SSD2_R_N")
	)
	(segment
		(start 113.891314 -97.190814)
		(end 111.721138 -97.190814)
		(width 0.15494)
		(layer "In15.Cu")
		(net "PRSNT_SSD2_R_N")
	)
	(segment
		(start 117.24386 -203.502514)
		(end 113.900458 -203.502514)
		(width 0.15494)
		(layer "In15.Cu")
		(net "PRSNT_SSD2_R_N")
	)
	(segment
		(start 113.900458 -203.502514)
		(end 109.804962 -199.407018)
		(width 0.15494)
		(layer "In15.Cu")
		(net "PRSNT_SSD2_R_N")
	)
	(segment
		(start 241.17935 -205.340966)
		(end 240.434622 -206.085694)
		(width 0.15494)
		(layer "In15.Cu")
		(net "PRSNT_SSD2_R_N")
	)
	(segment
		(start 181.144926 -213.012274)
		(end 138.523726 -213.012274)
		(width 0.15494)
		(layer "In15.Cu")
		(net "PRSNT_SSD2_R_N")
	)
	(segment
		(start 128.143 -209.991706)
		(end 123.733052 -209.991706)
		(width 0.15494)
		(layer "In15.Cu")
		(net "PRSNT_SSD2_R_N")
	)
	(segment
		(start 193.66865 -217.37193)
		(end 185.504582 -217.37193)
		(width 0.15494)
		(layer "In15.Cu")
		(net "PRSNT_SSD2_R_N")
	)
	(segment
		(start 243.8654 -199.9234)
		(end 241.7826 -202.0062)
		(width 0.15494)
		(layer "In15.Cu")
		(net "PRSNT_SSD2_R_N")
	)
	(segment
		(start 129.326894 -211.1756)
		(end 128.143 -209.991706)
		(width 0.15494)
		(layer "In15.Cu")
		(net "PRSNT_SSD2_R_N")
	)
	(segment
		(start 132.118354 -211.1756)
		(end 129.326894 -211.1756)
		(width 0.15494)
		(layer "In15.Cu")
		(net "PRSNT_SSD2_R_N")
	)
	(segment
		(start 213.377272 -204.274928)
		(end 212.618574 -205.033626)
		(width 0.15494)
		(layer "In15.Cu")
		(net "PRSNT_SSD2_R_N")
	)
	(segment
		(start 101.351588 -91.04884)
		(end 87.83447 -91.04884)
		(width 0.15494)
		(layer "In15.Cu")
		(net "PRSNT_SSD2_R_N")
	)
	(segment
		(start 206.006954 -205.033626)
		(end 193.66865 -217.37193)
		(width 0.15494)
		(layer "In15.Cu")
		(net "PRSNT_SSD2_R_N")
	)
	(segment
		(start 240.434622 -206.085694)
		(end 237.21822 -206.085694)
		(width 0.15494)
		(layer "In15.Cu")
		(net "PRSNT_SSD2_R_N")
	)
	(segment
		(start 241.17935 -203.42225)
		(end 241.17935 -205.340966)
		(width 0.15494)
		(layer "In15.Cu")
		(net "PRSNT_SSD2_R_N")
	)
	(segment
		(start 212.618574 -205.033626)
		(end 206.006954 -205.033626)
		(width 0.15494)
		(layer "In15.Cu")
		(net "PRSNT_SSD2_R_N")
	)
	(segment
		(start 237.21822 -206.085694)
		(end 235.407454 -204.274928)
		(width 0.15494)
		(layer "In15.Cu")
		(net "PRSNT_SSD2_R_N")
	)
	(segment
		(start 247.260618 -199.9234)
		(end 243.8654 -199.9234)
		(width 0.15494)
		(layer "In15.Cu")
		(net "PRSNT_SSD2_R_N")
	)
	(segment
		(start 241.7826 -202.0062)
		(end 241.7826 -202.819)
		(width 0.15494)
		(layer "In15.Cu")
		(net "PRSNT_SSD2_R_N")
	)
	(segment
		(start 241.7826 -202.819)
		(end 241.17935 -203.42225)
		(width 0.15494)
		(layer "In15.Cu")
		(net "PRSNT_SSD2_R_N")
	)
	(segment
		(start 235.407454 -204.274928)
		(end 213.377272 -204.274928)
		(width 0.15494)
		(layer "In15.Cu")
		(net "PRSNT_SSD2_R_N")
	)
	(segment
		(start 137.406126 -213.7156)
		(end 137.228326 -213.5378)
		(width 0.15494)
		(layer "In15.Cu")
		(net "PRSNT_SSD2_R_N")
	)
	(segment
		(start 138.523726 -213.012274)
		(end 137.8204 -213.7156)
		(width 0.15494)
		(layer "In15.Cu")
		(net "PRSNT_SSD2_R_N")
	)
	(segment
		(start 137.8204 -213.7156)
		(end 137.406126 -213.7156)
		(width 0.15494)
		(layer "In15.Cu")
		(net "PRSNT_SSD2_R_N")
	)
	(segment
		(start 134.480554 -213.5378)
		(end 132.118354 -211.1756)
		(width 0.15494)
		(layer "In15.Cu")
		(net "PRSNT_SSD2_R_N")
	)
	(segment
		(start 104.452928 -94.15018)
		(end 101.351588 -91.04884)
		(width 0.15494)
		(layer "In15.Cu")
		(net "PRSNT_SSD2_R_N")
	)
	(segment
		(start 247.951244 -200.614026)
		(end 247.260618 -199.9234)
		(width 0.15494)
		(layer "In15.Cu")
		(net "PRSNT_SSD2_R_N")
	)
	(segment
		(start 77.977492 -94.412816)
		(end 74.79792 -91.233244)
		(width 0.15494)
		(layer "In15.Cu")
		(net "PRSNT_SSD2_R_N")
	)
	(segment
		(start 108.680504 -94.15018)
		(end 104.452928 -94.15018)
		(width 0.15494)
		(layer "In15.Cu")
		(net "PRSNT_SSD2_R_N")
	)
	(segment
		(start 123.733052 -209.991706)
		(end 117.24386 -203.502514)
		(width 0.15494)
		(layer "In15.Cu")
		(net "PRSNT_SSD2_R_N")
	)
	(segment
		(start 84.470494 -94.412816)
		(end 77.977492 -94.412816)
		(width 0.15494)
		(layer "In15.Cu")
		(net "PRSNT_SSD2_R_N")
	)
	(segment
		(start 185.504582 -217.37193)
		(end 181.144926 -213.012274)
		(width 0.15494)
		(layer "In15.Cu")
		(net "PRSNT_SSD2_R_N")
	)
	(segment
		(start 233.408728 -36.232592)
		(end 232.863136 -35.687)
		(width 0.13208)
		(layer "F.Cu")
		(net "PWRGD_P3V3_SSD8_R")
	)
	(segment
		(start 230.271828 -35.687)
		(end 230.08209 -35.876738)
		(width 0.13208)
		(layer "F.Cu")
		(net "PWRGD_P3V3_SSD8_R")
	)
	(segment
		(start 233.795316 -36.232592)
		(end 233.408728 -36.232592)
		(width 0.13208)
		(layer "F.Cu")
		(net "PWRGD_P3V3_SSD8_R")
	)
	(segment
		(start 232.863136 -35.687)
		(end 230.271828 -35.687)
		(width 0.13208)
		(layer "F.Cu")
		(net "PWRGD_P3V3_SSD8_R")
	)
	(segment
		(start 338.093812 -214.387176)
		(end 337.694016 -213.98738)
		(width 0.13208)
		(layer "F.Cu")
		(net "PWRGD_P3V3_SSD8_R")
	)
	(segment
		(start 228.62794 -35.876738)
		(end 229.37089 -35.876738)
		(width 0.13208)
		(layer "F.Cu")
		(net "PWRGD_P3V3_SSD8_R")
	)
	(segment
		(start 230.08209 -35.876738)
		(end 229.37089 -35.876738)
		(width 0.13208)
		(layer "F.Cu")
		(net "PWRGD_P3V3_SSD8_R")
	)
	(segment
		(start 240.980214 -57.620408)
		(end 240.980214 -58.284872)
		(width 0.13208)
		(layer "F.Cu")
		(net "PWRGD_P3V3_SSD8_R")
	)
	(via
		(at 241.293396 -74.054716)
		(size 0.508)
		(drill 0.254)
		(layers "F.Cu" "B.Cu")
		(net "PWRGD_P3V3_SSD8_R")
	)
	(via
		(at 319.024 -85.852)
		(size 0.508)
		(drill 0.254)
		(layers "F.Cu" "B.Cu")
		(net "PWRGD_P3V3_SSD8_R")
	)
	(via
		(at 229.37089 -35.876738)
		(size 0.508)
		(drill 0.254)
		(layers "F.Cu" "B.Cu")
		(net "PWRGD_P3V3_SSD8_R")
	)
	(via
		(at 240.980214 -58.284872)
		(size 0.508)
		(drill 0.254)
		(layers "F.Cu" "B.Cu")
		(net "PWRGD_P3V3_SSD8_R")
	)
	(via
		(at 337.694016 -213.98738)
		(size 0.4572)
		(drill 0.254)
		(layers "F.Cu" "B.Cu")
		(net "PWRGD_P3V3_SSD8_R")
	)
	(segment
		(start 240.980214 -58.284872)
		(end 242.445286 -59.749944)
		(width 0.15494)
		(layer "In5.Cu")
		(net "PWRGD_P3V3_SSD8_R")
	)
	(segment
		(start 233.18216 -35.876738)
		(end 242.050824 -44.745402)
		(width 0.15494)
		(layer "In5.Cu")
		(net "PWRGD_P3V3_SSD8_R")
	)
	(segment
		(start 242.050824 -44.745402)
		(end 242.050824 -57.214262)
		(width 0.15494)
		(layer "In5.Cu")
		(net "PWRGD_P3V3_SSD8_R")
	)
	(segment
		(start 229.37089 -35.876738)
		(end 233.18216 -35.876738)
		(width 0.15494)
		(layer "In5.Cu")
		(net "PWRGD_P3V3_SSD8_R")
	)
	(segment
		(start 242.445286 -59.749944)
		(end 242.445286 -73.61809)
		(width 0.15494)
		(layer "In5.Cu")
		(net "PWRGD_P3V3_SSD8_R")
	)
	(segment
		(start 242.00866 -74.054716)
		(end 241.293396 -74.054716)
		(width 0.15494)
		(layer "In5.Cu")
		(net "PWRGD_P3V3_SSD8_R")
	)
	(segment
		(start 242.445286 -73.61809)
		(end 242.00866 -74.054716)
		(width 0.15494)
		(layer "In5.Cu")
		(net "PWRGD_P3V3_SSD8_R")
	)
	(segment
		(start 242.050824 -57.214262)
		(end 240.980214 -58.284872)
		(width 0.15494)
		(layer "In5.Cu")
		(net "PWRGD_P3V3_SSD8_R")
	)
	(segment
		(start 338.5566 -148.1836)
		(end 338.963 -147.7772)
		(width 0.15494)
		(layer "In7.Cu")
		(net "PWRGD_P3V3_SSD8_R")
	)
	(segment
		(start 319.28435 -131.637786)
		(end 319.28435 -120.60047)
		(width 0.15494)
		(layer "In7.Cu")
		(net "PWRGD_P3V3_SSD8_R")
	)
	(segment
		(start 335.547462 -206.852012)
		(end 335.547462 -205.182216)
		(width 0.15494)
		(layer "In7.Cu")
		(net "PWRGD_P3V3_SSD8_R")
	)
	(segment
		(start 343.662 -174.96663)
		(end 343.662 -174.342298)
		(width 0.15494)
		(layer "In7.Cu")
		(net "PWRGD_P3V3_SSD8_R")
	)
	(segment
		(start 335.788 -184.656222)
		(end 338.2264 -182.217822)
		(width 0.15494)
		(layer "In7.Cu")
		(net "PWRGD_P3V3_SSD8_R")
	)
	(segment
		(start 337.694016 -213.98738)
		(end 337.293966 -213.58733)
		(width 0.0889)
		(layer "In7.Cu")
		(net "PWRGD_P3V3_SSD8_R")
	)
	(segment
		(start 337.293966 -213.58733)
		(end 337.293966 -212.224366)
		(width 0.0889)
		(layer "In7.Cu")
		(net "PWRGD_P3V3_SSD8_R")
	)
	(segment
		(start 320.6496 -86.3346)
		(end 320.167 -85.852)
		(width 0.15494)
		(layer "In7.Cu")
		(net "PWRGD_P3V3_SSD8_R")
	)
	(segment
		(start 341.260684 -177.353468)
		(end 341.543894 -177.070258)
		(width 0.15494)
		(layer "In7.Cu")
		(net "PWRGD_P3V3_SSD8_R")
	)
	(segment
		(start 338.2264 -182.217822)
		(end 338.2264 -180.40223)
		(width 0.15494)
		(layer "In7.Cu")
		(net "PWRGD_P3V3_SSD8_R")
	)
	(segment
		(start 341.912702 -172.593)
		(end 338.7598 -172.593)
		(width 0.15494)
		(layer "In7.Cu")
		(net "PWRGD_P3V3_SSD8_R")
	)
	(segment
		(start 317.724536 -119.040656)
		(end 317.724536 -96.785176)
		(width 0.15494)
		(layer "In7.Cu")
		(net "PWRGD_P3V3_SSD8_R")
	)
	(segment
		(start 338.963 -147.7772)
		(end 338.963 -141.882114)
		(width 0.15494)
		(layer "In7.Cu")
		(net "PWRGD_P3V3_SSD8_R")
	)
	(segment
		(start 336.9056 -211.836)
		(end 336.9056 -211.6074)
		(width 0.0889)
		(layer "In7.Cu")
		(net "PWRGD_P3V3_SSD8_R")
	)
	(segment
		(start 337.293966 -212.224366)
		(end 336.9056 -211.836)
		(width 0.0889)
		(layer "In7.Cu")
		(net "PWRGD_P3V3_SSD8_R")
	)
	(segment
		(start 338.2264 -180.40223)
		(end 341.260684 -177.367946)
		(width 0.15494)
		(layer "In7.Cu")
		(net "PWRGD_P3V3_SSD8_R")
	)
	(segment
		(start 341.543894 -177.070258)
		(end 341.558372 -177.070258)
		(width 0.15494)
		(layer "In7.Cu")
		(net "PWRGD_P3V3_SSD8_R")
	)
	(segment
		(start 335.026 -204.660754)
		(end 335.026 -187.325)
		(width 0.15494)
		(layer "In7.Cu")
		(net "PWRGD_P3V3_SSD8_R")
	)
	(segment
		(start 338.5566 -148.960586)
		(end 338.5566 -148.1836)
		(width 0.15494)
		(layer "In7.Cu")
		(net "PWRGD_P3V3_SSD8_R")
	)
	(segment
		(start 334.315308 -137.234422)
		(end 324.880986 -137.234422)
		(width 0.15494)
		(layer "In7.Cu")
		(net "PWRGD_P3V3_SSD8_R")
	)
	(segment
		(start 320.6496 -93.860112)
		(end 320.6496 -86.3346)
		(width 0.15494)
		(layer "In7.Cu")
		(net "PWRGD_P3V3_SSD8_R")
	)
	(segment
		(start 335.547462 -205.182216)
		(end 335.026 -204.660754)
		(width 0.15494)
		(layer "In7.Cu")
		(net "PWRGD_P3V3_SSD8_R")
	)
	(segment
		(start 335.788 -186.563)
		(end 335.788 -184.656222)
		(width 0.15494)
		(layer "In7.Cu")
		(net "PWRGD_P3V3_SSD8_R")
	)
	(segment
		(start 336.9056 -211.6074)
		(end 336.9056 -208.21015)
		(width 0.15494)
		(layer "In7.Cu")
		(net "PWRGD_P3V3_SSD8_R")
	)
	(segment
		(start 338.7598 -172.593)
		(end 337.7184 -171.5516)
		(width 0.15494)
		(layer "In7.Cu")
		(net "PWRGD_P3V3_SSD8_R")
	)
	(segment
		(start 343.662 -174.342298)
		(end 341.912702 -172.593)
		(width 0.15494)
		(layer "In7.Cu")
		(net "PWRGD_P3V3_SSD8_R")
	)
	(segment
		(start 341.260684 -177.367946)
		(end 341.260684 -177.353468)
		(width 0.15494)
		(layer "In7.Cu")
		(net "PWRGD_P3V3_SSD8_R")
	)
	(segment
		(start 341.558372 -177.070258)
		(end 343.662 -174.96663)
		(width 0.15494)
		(layer "In7.Cu")
		(net "PWRGD_P3V3_SSD8_R")
	)
	(segment
		(start 320.167 -85.852)
		(end 319.024 -85.852)
		(width 0.15494)
		(layer "In7.Cu")
		(net "PWRGD_P3V3_SSD8_R")
	)
	(segment
		(start 337.7184 -149.798786)
		(end 338.5566 -148.960586)
		(width 0.15494)
		(layer "In7.Cu")
		(net "PWRGD_P3V3_SSD8_R")
	)
	(segment
		(start 324.880986 -137.234422)
		(end 319.28435 -131.637786)
		(width 0.15494)
		(layer "In7.Cu")
		(net "PWRGD_P3V3_SSD8_R")
	)
	(segment
		(start 319.28435 -120.60047)
		(end 317.724536 -119.040656)
		(width 0.15494)
		(layer "In7.Cu")
		(net "PWRGD_P3V3_SSD8_R")
	)
	(segment
		(start 338.963 -141.882114)
		(end 334.315308 -137.234422)
		(width 0.15494)
		(layer "In7.Cu")
		(net "PWRGD_P3V3_SSD8_R")
	)
	(segment
		(start 336.9056 -208.21015)
		(end 335.547462 -206.852012)
		(width 0.15494)
		(layer "In7.Cu")
		(net "PWRGD_P3V3_SSD8_R")
	)
	(segment
		(start 337.7184 -171.5516)
		(end 337.7184 -149.798786)
		(width 0.15494)
		(layer "In7.Cu")
		(net "PWRGD_P3V3_SSD8_R")
	)
	(segment
		(start 317.724536 -96.785176)
		(end 320.6496 -93.860112)
		(width 0.15494)
		(layer "In7.Cu")
		(net "PWRGD_P3V3_SSD8_R")
	)
	(segment
		(start 335.026 -187.325)
		(end 335.788 -186.563)
		(width 0.15494)
		(layer "In7.Cu")
		(net "PWRGD_P3V3_SSD8_R")
	)
	(segment
		(start 278.647906 -78.95336)
		(end 295.150286 -78.95336)
		(width 0.15494)
		(layer "In15.Cu")
		(net "PWRGD_P3V3_SSD8_R")
	)
	(segment
		(start 248.188226 -73.918826)
		(end 249.401076 -75.131676)
		(width 0.15494)
		(layer "In15.Cu")
		(net "PWRGD_P3V3_SSD8_R")
	)
	(segment
		(start 303.542446 -84.950046)
		(end 310.756808 -84.950046)
		(width 0.15494)
		(layer "In15.Cu")
		(net "PWRGD_P3V3_SSD8_R")
	)
	(segment
		(start 301.7266 -83.1342)
		(end 303.542446 -84.950046)
		(width 0.15494)
		(layer "In15.Cu")
		(net "PWRGD_P3V3_SSD8_R")
	)
	(segment
		(start 262.139684 -74.573384)
		(end 265.547094 -74.573384)
		(width 0.15494)
		(layer "In15.Cu")
		(net "PWRGD_P3V3_SSD8_R")
	)
	(segment
		(start 241.40668 -74.168)
		(end 243.77904 -74.168)
		(width 0.15494)
		(layer "In15.Cu")
		(net "PWRGD_P3V3_SSD8_R")
	)
	(segment
		(start 274.860766 -77.1652)
		(end 276.003766 -78.3082)
		(width 0.15494)
		(layer "In15.Cu")
		(net "PWRGD_P3V3_SSD8_R")
	)
	(segment
		(start 241.293396 -74.054716)
		(end 241.40668 -74.168)
		(width 0.15494)
		(layer "In15.Cu")
		(net "PWRGD_P3V3_SSD8_R")
	)
	(segment
		(start 253.541276 -75.131676)
		(end 253.837694 -75.428094)
		(width 0.15494)
		(layer "In15.Cu")
		(net "PWRGD_P3V3_SSD8_R")
	)
	(segment
		(start 278.002746 -78.3082)
		(end 278.647906 -78.95336)
		(width 0.15494)
		(layer "In15.Cu")
		(net "PWRGD_P3V3_SSD8_R")
	)
	(segment
		(start 310.756808 -84.950046)
		(end 311.734454 -83.9724)
		(width 0.15494)
		(layer "In15.Cu")
		(net "PWRGD_P3V3_SSD8_R")
	)
	(segment
		(start 299.331126 -83.1342)
		(end 301.7266 -83.1342)
		(width 0.15494)
		(layer "In15.Cu")
		(net "PWRGD_P3V3_SSD8_R")
	)
	(segment
		(start 249.401076 -75.131676)
		(end 253.541276 -75.131676)
		(width 0.15494)
		(layer "In15.Cu")
		(net "PWRGD_P3V3_SSD8_R")
	)
	(segment
		(start 311.734454 -83.9724)
		(end 317.144908 -83.9724)
		(width 0.15494)
		(layer "In15.Cu")
		(net "PWRGD_P3V3_SSD8_R")
	)
	(segment
		(start 295.150286 -78.95336)
		(end 299.331126 -83.1342)
		(width 0.15494)
		(layer "In15.Cu")
		(net "PWRGD_P3V3_SSD8_R")
	)
	(segment
		(start 317.144908 -83.9724)
		(end 319.024 -85.852)
		(width 0.15494)
		(layer "In15.Cu")
		(net "PWRGD_P3V3_SSD8_R")
	)
	(segment
		(start 244.028214 -73.918826)
		(end 248.188226 -73.918826)
		(width 0.15494)
		(layer "In15.Cu")
		(net "PWRGD_P3V3_SSD8_R")
	)
	(segment
		(start 276.003766 -78.3082)
		(end 278.002746 -78.3082)
		(width 0.15494)
		(layer "In15.Cu")
		(net "PWRGD_P3V3_SSD8_R")
	)
	(segment
		(start 243.77904 -74.168)
		(end 244.028214 -73.918826)
		(width 0.15494)
		(layer "In15.Cu")
		(net "PWRGD_P3V3_SSD8_R")
	)
	(segment
		(start 261.284974 -75.428094)
		(end 262.139684 -74.573384)
		(width 0.15494)
		(layer "In15.Cu")
		(net "PWRGD_P3V3_SSD8_R")
	)
	(segment
		(start 268.13891 -77.1652)
		(end 274.860766 -77.1652)
		(width 0.15494)
		(layer "In15.Cu")
		(net "PWRGD_P3V3_SSD8_R")
	)
	(segment
		(start 253.837694 -75.428094)
		(end 261.284974 -75.428094)
		(width 0.15494)
		(layer "In15.Cu")
		(net "PWRGD_P3V3_SSD8_R")
	)
	(segment
		(start 265.547094 -74.573384)
		(end 268.13891 -77.1652)
		(width 0.15494)
		(layer "In15.Cu")
		(net "PWRGD_P3V3_SSD8_R")
	)
	(segment
		(start 31.899098 -310.892698)
		(end 31.584138 -310.892698)
		(width 0.13208)
		(layer "F.Cu")
		(net "PEX0_DBG_MODE0")
	)
	(segment
		(start 31.263336 -310.571896)
		(end 31.262828 -310.571896)
		(width 0.13208)
		(layer "F.Cu")
		(net "PEX0_DBG_MODE0")
	)
	(segment
		(start 31.584138 -310.892698)
		(end 31.263336 -310.571896)
		(width 0.13208)
		(layer "F.Cu")
		(net "PEX0_DBG_MODE0")
	)
	(segment
		(start 31.263336 -310.571896)
		(end 31.981648 -309.853584)
		(width 0.13208)
		(layer "F.Cu")
		(net "PEX0_DBG_MODE0")
	)
	(segment
		(start 32.8295 -311.8231)
		(end 31.899098 -310.892698)
		(width 0.13208)
		(layer "F.Cu")
		(net "PEX0_DBG_MODE0")
	)
	(via
		(at 32.8295 -311.8231)
		(size 0.508)
		(drill 0.254)
		(layers "F.Cu" "B.Cu")
		(net "PEX0_DBG_MODE0")
	)
	(via
		(at 47.29988 -309.199788)
		(size 0.4064)
		(drill 0.2032)
		(layers "F.Cu" "B.Cu")
		(net "PEX0_DBG_MODE0")
	)
	(via
		(at 34.570416 -308.56809)
		(size 0.6604)
		(drill 0.3302)
		(layers "F.Cu" "B.Cu")
		(net "PEX0_DBG_MODE0")
	)
	(segment
		(start 35.28949 -308.56809)
		(end 34.570416 -308.56809)
		(width 0.13208)
		(layer "B.Cu")
		(net "PEX0_DBG_MODE0")
	)
	(segment
		(start 32.87141 -310.267096)
		(end 34.570416 -308.56809)
		(width 0.13208)
		(layer "B.Cu")
		(net "PEX0_DBG_MODE0")
	)
	(segment
		(start 32.87141 -311.78119)
		(end 32.87141 -310.267096)
		(width 0.13208)
		(layer "B.Cu")
		(net "PEX0_DBG_MODE0")
	)
	(segment
		(start 35.446208 -308.724808)
		(end 35.28949 -308.56809)
		(width 0.13208)
		(layer "B.Cu")
		(net "PEX0_DBG_MODE0")
	)
	(segment
		(start 47.29988 -309.199788)
		(end 46.8249 -308.724808)
		(width 0.13208)
		(layer "B.Cu")
		(net "PEX0_DBG_MODE0")
	)
	(segment
		(start 32.8295 -311.8231)
		(end 32.87141 -311.78119)
		(width 0.13208)
		(layer "B.Cu")
		(net "PEX0_DBG_MODE0")
	)
	(segment
		(start 46.8249 -308.724808)
		(end 35.446208 -308.724808)
		(width 0.13208)
		(layer "B.Cu")
		(net "PEX0_DBG_MODE0")
	)
	(segment
		(start 212.522054 -193.22288)
		(end 211.68868 -193.22288)
		(width 0.13208)
		(layer "F.Cu")
		(net "SMB_NIC7_R_SCL")
	)
	(segment
		(start 211.1248 -192.659)
		(end 210.83905 -192.659)
		(width 0.13208)
		(layer "F.Cu")
		(net "SMB_NIC7_R_SCL")
	)
	(segment
		(start 211.68868 -193.22288)
		(end 211.1248 -192.659)
		(width 0.13208)
		(layer "F.Cu")
		(net "SMB_NIC7_R_SCL")
	)
	(segment
		(start 210.83905 -192.170304)
		(end 210.692746 -192.024)
		(width 0.13208)
		(layer "F.Cu")
		(net "SMB_NIC7_R_SCL")
	)
	(segment
		(start 210.83905 -192.659)
		(end 210.83905 -192.170304)
		(width 0.13208)
		(layer "F.Cu")
		(net "SMB_NIC7_R_SCL")
	)
	(segment
		(start 210.692746 -192.024)
		(end 209.423 -192.024)
		(width 0.13208)
		(layer "F.Cu")
		(net "SMB_NIC7_R_SCL")
	)
	(via
		(at 209.423 -192.024)
		(size 0.508)
		(drill 0.254)
		(layers "F.Cu" "B.Cu")
		(net "SMB_NIC7_R_SCL")
	)
	(via
		(at 214.969344 -217.286586)
		(size 0.508)
		(drill 0.254)
		(layers "F.Cu" "B.Cu")
		(net "SMB_NIC7_R_SCL")
	)
	(segment
		(start 216.835736 -218.302586)
		(end 215.901016 -218.302586)
		(width 0.13208)
		(layer "B.Cu")
		(net "SMB_NIC7_R_SCL")
	)
	(segment
		(start 212.09 -192.80505)
		(end 210.20405 -192.80505)
		(width 0.13208)
		(layer "B.Cu")
		(net "SMB_NIC7_R_SCL")
	)
	(segment
		(start 215.901016 -218.302586)
		(end 214.969344 -217.370914)
		(width 0.13208)
		(layer "B.Cu")
		(net "SMB_NIC7_R_SCL")
	)
	(segment
		(start 214.969344 -217.370914)
		(end 214.969344 -217.286586)
		(width 0.13208)
		(layer "B.Cu")
		(net "SMB_NIC7_R_SCL")
	)
	(segment
		(start 210.20405 -192.80505)
		(end 209.423 -192.024)
		(width 0.13208)
		(layer "B.Cu")
		(net "SMB_NIC7_R_SCL")
	)
	(segment
		(start 210.058 -206.5528)
		(end 210.058 -207.3402)
		(width 0.15494)
		(layer "In7.Cu")
		(net "SMB_NIC7_R_SCL")
	)
	(segment
		(start 214.842344 -217.424)
		(end 214.842344 -217.413586)
		(width 0.15494)
		(layer "In7.Cu")
		(net "SMB_NIC7_R_SCL")
	)
	(segment
		(start 208.3308 -192.550796)
		(end 208.3308 -194.183)
		(width 0.15494)
		(layer "In7.Cu")
		(net "SMB_NIC7_R_SCL")
	)
	(segment
		(start 209.423 -192.024)
		(end 208.857596 -192.024)
		(width 0.15494)
		(layer "In7.Cu")
		(net "SMB_NIC7_R_SCL")
	)
	(segment
		(start 209.2452 -212.217)
		(end 209.2452 -213.919054)
		(width 0.15494)
		(layer "In7.Cu")
		(net "SMB_NIC7_R_SCL")
	)
	(segment
		(start 213.112858 -217.594688)
		(end 214.671656 -217.594688)
		(width 0.15494)
		(layer "In7.Cu")
		(net "SMB_NIC7_R_SCL")
	)
	(segment
		(start 208.3308 -194.183)
		(end 206.83474 -195.67906)
		(width 0.15494)
		(layer "In7.Cu")
		(net "SMB_NIC7_R_SCL")
	)
	(segment
		(start 211.233766 -217.810334)
		(end 212.897212 -217.810334)
		(width 0.15494)
		(layer "In7.Cu")
		(net "SMB_NIC7_R_SCL")
	)
	(segment
		(start 209.2452 -213.919054)
		(end 210.0326 -214.706454)
		(width 0.15494)
		(layer "In7.Cu")
		(net "SMB_NIC7_R_SCL")
	)
	(segment
		(start 210.058 -207.3402)
		(end 209.4484 -207.9498)
		(width 0.15494)
		(layer "In7.Cu")
		(net "SMB_NIC7_R_SCL")
	)
	(segment
		(start 212.897212 -217.810334)
		(end 213.112858 -217.594688)
		(width 0.15494)
		(layer "In7.Cu")
		(net "SMB_NIC7_R_SCL")
	)
	(segment
		(start 208.857596 -192.024)
		(end 208.3308 -192.550796)
		(width 0.15494)
		(layer "In7.Cu")
		(net "SMB_NIC7_R_SCL")
	)
	(segment
		(start 210.0326 -214.706454)
		(end 210.0326 -216.609168)
		(width 0.15494)
		(layer "In7.Cu")
		(net "SMB_NIC7_R_SCL")
	)
	(segment
		(start 214.671656 -217.594688)
		(end 214.842344 -217.424)
		(width 0.15494)
		(layer "In7.Cu")
		(net "SMB_NIC7_R_SCL")
	)
	(segment
		(start 210.0326 -216.609168)
		(end 211.233766 -217.810334)
		(width 0.15494)
		(layer "In7.Cu")
		(net "SMB_NIC7_R_SCL")
	)
	(segment
		(start 209.4484 -207.9498)
		(end 209.4484 -212.0138)
		(width 0.15494)
		(layer "In7.Cu")
		(net "SMB_NIC7_R_SCL")
	)
	(segment
		(start 206.83474 -203.32954)
		(end 210.058 -206.5528)
		(width 0.15494)
		(layer "In7.Cu")
		(net "SMB_NIC7_R_SCL")
	)
	(segment
		(start 214.842344 -217.413586)
		(end 214.969344 -217.286586)
		(width 0.15494)
		(layer "In7.Cu")
		(net "SMB_NIC7_R_SCL")
	)
	(segment
		(start 206.83474 -195.67906)
		(end 206.83474 -203.32954)
		(width 0.15494)
		(layer "In7.Cu")
		(net "SMB_NIC7_R_SCL")
	)
	(segment
		(start 209.4484 -212.0138)
		(end 209.2452 -212.217)
		(width 0.15494)
		(layer "In7.Cu")
		(net "SMB_NIC7_R_SCL")
	)
	(segment
		(start 166.247318 -53.644038)
		(end 166.61638 -53.644038)
		(width 0.13208)
		(layer "F.Cu")
		(net "PWRGD_P12V_SSD5")
	)
	(segment
		(start 167.23741 -52.587398)
		(end 167.701468 -53.051456)
		(width 0.13208)
		(layer "F.Cu")
		(net "PWRGD_P12V_SSD5")
	)
	(segment
		(start 166.61638 -53.644038)
		(end 167.23741 -53.023008)
		(width 0.13208)
		(layer "F.Cu")
		(net "PWRGD_P12V_SSD5")
	)
	(segment
		(start 167.701468 -53.051456)
		(end 167.967914 -53.051456)
		(width 0.13208)
		(layer "F.Cu")
		(net "PWRGD_P12V_SSD5")
	)
	(segment
		(start 167.967914 -52.035456)
		(end 167.967914 -53.051456)
		(width 0.13208)
		(layer "F.Cu")
		(net "PWRGD_P12V_SSD5")
	)
	(segment
		(start 167.23741 -53.023008)
		(end 167.23741 -52.587398)
		(width 0.13208)
		(layer "F.Cu")
		(net "PWRGD_P12V_SSD5")
	)
	(via
		(at 167.23741 -52.587398)
		(size 0.508)
		(drill 0.254)
		(layers "F.Cu" "B.Cu")
		(net "PWRGD_P12V_SSD5")
	)
	(segment
		(start 348.937834 -35.6616)
		(end 349.508826 -36.232592)
		(width 0.13208)
		(layer "F.Cu")
		(net "PWRGD_P3V3_SSD12_R")
	)
	(segment
		(start 345.470988 -35.876738)
		(end 344.728038 -35.876738)
		(width 0.13208)
		(layer "F.Cu")
		(net "PWRGD_P3V3_SSD12_R")
	)
	(segment
		(start 346.397326 -35.6616)
		(end 348.937834 -35.6616)
		(width 0.13208)
		(layer "F.Cu")
		(net "PWRGD_P3V3_SSD12_R")
	)
	(segment
		(start 356.911148 -61.386974)
		(end 356.911148 -62.051438)
		(width 0.13208)
		(layer "F.Cu")
		(net "PWRGD_P3V3_SSD12_R")
	)
	(segment
		(start 346.182188 -35.876738)
		(end 346.397326 -35.6616)
		(width 0.13208)
		(layer "F.Cu")
		(net "PWRGD_P3V3_SSD12_R")
	)
	(segment
		(start 345.470988 -35.876738)
		(end 346.182188 -35.876738)
		(width 0.13208)
		(layer "F.Cu")
		(net "PWRGD_P3V3_SSD12_R")
	)
	(segment
		(start 349.508826 -36.232592)
		(end 349.895414 -36.232592)
		(width 0.13208)
		(layer "F.Cu")
		(net "PWRGD_P3V3_SSD12_R")
	)
	(segment
		(start 339.693758 -212.786976)
		(end 339.293962 -212.38718)
		(width 0.13208)
		(layer "F.Cu")
		(net "PWRGD_P3V3_SSD12_R")
	)
	(via
		(at 345.470988 -35.876738)
		(size 0.508)
		(drill 0.254)
		(layers "F.Cu" "B.Cu")
		(net "PWRGD_P3V3_SSD12_R")
	)
	(via
		(at 356.911148 -62.051438)
		(size 0.508)
		(drill 0.254)
		(layers "F.Cu" "B.Cu")
		(net "PWRGD_P3V3_SSD12_R")
	)
	(via
		(at 339.293962 -212.38718)
		(size 0.4572)
		(drill 0.254)
		(layers "F.Cu" "B.Cu")
		(net "PWRGD_P3V3_SSD12_R")
	)
	(via
		(at 342.498426 -67.366388)
		(size 0.508)
		(drill 0.254)
		(layers "F.Cu" "B.Cu")
		(net "PWRGD_P3V3_SSD12_R")
	)
	(segment
		(start 344.866722 -64.998092)
		(end 351.768156 -64.998092)
		(width 0.15494)
		(layer "In5.Cu")
		(net "PWRGD_P3V3_SSD12_R")
	)
	(segment
		(start 358.157018 -61.30036)
		(end 358.157018 -46.64583)
		(width 0.15494)
		(layer "In5.Cu")
		(net "PWRGD_P3V3_SSD12_R")
	)
	(segment
		(start 354.71481 -62.051438)
		(end 356.911148 -62.051438)
		(width 0.15494)
		(layer "In5.Cu")
		(net "PWRGD_P3V3_SSD12_R")
	)
	(segment
		(start 351.768156 -64.998092)
		(end 354.71481 -62.051438)
		(width 0.15494)
		(layer "In5.Cu")
		(net "PWRGD_P3V3_SSD12_R")
	)
	(segment
		(start 348.162626 -35.876738)
		(end 345.470988 -35.876738)
		(width 0.15494)
		(layer "In5.Cu")
		(net "PWRGD_P3V3_SSD12_R")
	)
	(segment
		(start 342.498426 -67.366388)
		(end 344.866722 -64.998092)
		(width 0.15494)
		(layer "In5.Cu")
		(net "PWRGD_P3V3_SSD12_R")
	)
	(segment
		(start 352.229166 -40.717978)
		(end 352.229166 -39.943278)
		(width 0.15494)
		(layer "In5.Cu")
		(net "PWRGD_P3V3_SSD12_R")
	)
	(segment
		(start 352.229166 -39.943278)
		(end 348.162626 -35.876738)
		(width 0.15494)
		(layer "In5.Cu")
		(net "PWRGD_P3V3_SSD12_R")
	)
	(segment
		(start 358.157018 -46.64583)
		(end 352.229166 -40.717978)
		(width 0.15494)
		(layer "In5.Cu")
		(net "PWRGD_P3V3_SSD12_R")
	)
	(segment
		(start 357.40594 -62.051438)
		(end 358.157018 -61.30036)
		(width 0.15494)
		(layer "In5.Cu")
		(net "PWRGD_P3V3_SSD12_R")
	)
	(segment
		(start 356.911148 -62.051438)
		(end 357.40594 -62.051438)
		(width 0.15494)
		(layer "In5.Cu")
		(net "PWRGD_P3V3_SSD12_R")
	)
	(segment
		(start 343.28608 -142.073884)
		(end 343.28608 -167.197024)
		(width 0.15494)
		(layer "In7.Cu")
		(net "PWRGD_P3V3_SSD12_R")
	)
	(segment
		(start 346.1766 -170.786552)
		(end 346.1766 -183.448452)
		(width 0.15494)
		(layer "In7.Cu")
		(net "PWRGD_P3V3_SSD12_R")
	)
	(segment
		(start 341.122 -199.968358)
		(end 341.122 -205.02753)
		(width 0.15494)
		(layer "In7.Cu")
		(net "PWRGD_P3V3_SSD12_R")
	)
	(segment
		(start 341.122 -205.02753)
		(end 340.597236 -205.552294)
		(width 0.15494)
		(layer "In7.Cu")
		(net "PWRGD_P3V3_SSD12_R")
	)
	(segment
		(start 339.858604 -211.62645)
		(end 339.293962 -212.191092)
		(width 0.15494)
		(layer "In7.Cu")
		(net "PWRGD_P3V3_SSD12_R")
	)
	(segment
		(start 350.380808 -84.506562)
		(end 350.380808 -94.737428)
		(width 0.15494)
		(layer "In7.Cu")
		(net "PWRGD_P3V3_SSD12_R")
	)
	(segment
		(start 344.77452 -168.685464)
		(end 344.77452 -169.384472)
		(width 0.15494)
		(layer "In7.Cu")
		(net "PWRGD_P3V3_SSD12_R")
	)
	(segment
		(start 346.1766 -183.448452)
		(end 341.771732 -187.85332)
		(width 0.15494)
		(layer "In7.Cu")
		(net "PWRGD_P3V3_SSD12_R")
	)
	(segment
		(start 340.597236 -207.74152)
		(end 339.858604 -208.480152)
		(width 0.15494)
		(layer "In7.Cu")
		(net "PWRGD_P3V3_SSD12_R")
	)
	(segment
		(start 341.771732 -187.85332)
		(end 341.228934 -187.85332)
		(width 0.15494)
		(layer "In7.Cu")
		(net "PWRGD_P3V3_SSD12_R")
	)
	(segment
		(start 351.269808 -119.387874)
		(end 344.2462 -126.411482)
		(width 0.15494)
		(layer "In7.Cu")
		(net "PWRGD_P3V3_SSD12_R")
	)
	(segment
		(start 342.498426 -76.62418)
		(end 350.380808 -84.506562)
		(width 0.15494)
		(layer "In7.Cu")
		(net "PWRGD_P3V3_SSD12_R")
	)
	(segment
		(start 342.498426 -67.366388)
		(end 342.498426 -76.62418)
		(width 0.15494)
		(layer "In7.Cu")
		(net "PWRGD_P3V3_SSD12_R")
	)
	(segment
		(start 339.858604 -208.480152)
		(end 339.858604 -211.62645)
		(width 0.15494)
		(layer "In7.Cu")
		(net "PWRGD_P3V3_SSD12_R")
	)
	(segment
		(start 350.380808 -94.737428)
		(end 351.269808 -95.626428)
		(width 0.15494)
		(layer "In7.Cu")
		(net "PWRGD_P3V3_SSD12_R")
	)
	(segment
		(start 344.77452 -169.384472)
		(end 346.1766 -170.786552)
		(width 0.15494)
		(layer "In7.Cu")
		(net "PWRGD_P3V3_SSD12_R")
	)
	(segment
		(start 339.293962 -212.191092)
		(end 339.293962 -212.38718)
		(width 0.15494)
		(layer "In7.Cu")
		(net "PWRGD_P3V3_SSD12_R")
	)
	(segment
		(start 344.2462 -126.411482)
		(end 344.2462 -141.113764)
		(width 0.15494)
		(layer "In7.Cu")
		(net "PWRGD_P3V3_SSD12_R")
	)
	(segment
		(start 351.269808 -95.626428)
		(end 351.269808 -119.387874)
		(width 0.15494)
		(layer "In7.Cu")
		(net "PWRGD_P3V3_SSD12_R")
	)
	(segment
		(start 340.614 -199.460358)
		(end 341.122 -199.968358)
		(width 0.15494)
		(layer "In7.Cu")
		(net "PWRGD_P3V3_SSD12_R")
	)
	(segment
		(start 343.28608 -167.197024)
		(end 344.77452 -168.685464)
		(width 0.15494)
		(layer "In7.Cu")
		(net "PWRGD_P3V3_SSD12_R")
	)
	(segment
		(start 340.597236 -205.552294)
		(end 340.597236 -207.74152)
		(width 0.15494)
		(layer "In7.Cu")
		(net "PWRGD_P3V3_SSD12_R")
	)
	(segment
		(start 340.614 -188.468254)
		(end 340.614 -199.460358)
		(width 0.15494)
		(layer "In7.Cu")
		(net "PWRGD_P3V3_SSD12_R")
	)
	(segment
		(start 344.2462 -141.113764)
		(end 343.28608 -142.073884)
		(width 0.15494)
		(layer "In7.Cu")
		(net "PWRGD_P3V3_SSD12_R")
	)
	(segment
		(start 341.228934 -187.85332)
		(end 340.614 -188.468254)
		(width 0.15494)
		(layer "In7.Cu")
		(net "PWRGD_P3V3_SSD12_R")
	)
	(segment
		(start 409.849828 -283.549852)
		(end 410.324808 -284.024832)
		(width 0.1651)
		(layer "F.Cu")
		(net "PEX3_MODE_SEL3")
	)
	(segment
		(start 377.722384 -251.956824)
		(end 377.722384 -251.158502)
		(width 0.13208)
		(layer "F.Cu")
		(net "PEX3_MODE_SEL3")
	)
	(segment
		(start 377.722384 -251.158502)
		(end 377.722384 -250.470924)
		(width 0.13208)
		(layer "F.Cu")
		(net "PEX3_MODE_SEL3")
	)
	(via
		(at 377.722384 -251.158502)
		(size 0.508)
		(drill 0.254)
		(layers "F.Cu" "B.Cu")
		(net "PEX3_MODE_SEL3")
	)
	(via
		(at 407.481532 -268.925802)
		(size 0.6604)
		(drill 0.3302)
		(layers "F.Cu" "B.Cu")
		(net "PEX3_MODE_SEL3")
	)
	(via
		(at 410.324808 -284.024832)
		(size 0.4064)
		(drill 0.2032)
		(layers "F.Cu" "B.Cu")
		(net "PEX3_MODE_SEL3")
	)
	(segment
		(start 410.357828 -282.071572)
		(end 409.849828 -282.579572)
		(width 0.13208)
		(layer "B.Cu")
		(net "PEX3_MODE_SEL3")
	)
	(segment
		(start 378.610368 -256.892298)
		(end 382.014476 -256.892298)
		(width 0.13208)
		(layer "B.Cu")
		(net "PEX3_MODE_SEL3")
	)
	(segment
		(start 410.357828 -271.802098)
		(end 410.357828 -282.071572)
		(width 0.13208)
		(layer "B.Cu")
		(net "PEX3_MODE_SEL3")
	)
	(segment
		(start 409.849828 -283.549852)
		(end 410.324808 -284.024832)
		(width 0.13208)
		(layer "B.Cu")
		(net "PEX3_MODE_SEL3")
	)
	(segment
		(start 377.212352 -251.668534)
		(end 377.212352 -254.963168)
		(width 0.13208)
		(layer "B.Cu")
		(net "PEX3_MODE_SEL3")
	)
	(segment
		(start 378.394468 -256.676398)
		(end 378.610368 -256.892298)
		(width 0.13208)
		(layer "B.Cu")
		(net "PEX3_MODE_SEL3")
	)
	(segment
		(start 409.849828 -282.579572)
		(end 409.849828 -283.549852)
		(width 0.13208)
		(layer "B.Cu")
		(net "PEX3_MODE_SEL3")
	)
	(segment
		(start 378.394468 -256.145284)
		(end 378.394468 -256.676398)
		(width 0.13208)
		(layer "B.Cu")
		(net "PEX3_MODE_SEL3")
	)
	(segment
		(start 407.481532 -268.925802)
		(end 410.357828 -271.802098)
		(width 0.13208)
		(layer "B.Cu")
		(net "PEX3_MODE_SEL3")
	)
	(segment
		(start 377.722384 -251.158502)
		(end 377.212352 -251.668534)
		(width 0.13208)
		(layer "B.Cu")
		(net "PEX3_MODE_SEL3")
	)
	(segment
		(start 382.8415 -257.719322)
		(end 396.275052 -257.719322)
		(width 0.13208)
		(layer "B.Cu")
		(net "PEX3_MODE_SEL3")
	)
	(segment
		(start 396.275052 -257.719322)
		(end 407.481532 -268.925802)
		(width 0.13208)
		(layer "B.Cu")
		(net "PEX3_MODE_SEL3")
	)
	(segment
		(start 382.014476 -256.892298)
		(end 382.8415 -257.719322)
		(width 0.13208)
		(layer "B.Cu")
		(net "PEX3_MODE_SEL3")
	)
	(segment
		(start 377.212352 -254.963168)
		(end 378.394468 -256.145284)
		(width 0.13208)
		(layer "B.Cu")
		(net "PEX3_MODE_SEL3")
	)
	(segment
		(start 51.987196 -141.964918)
		(end 52.652422 -141.964918)
		(width 0.13208)
		(layer "F.Cu")
		(net "SMB_NIC0_R_SDA")
	)
	(segment
		(start 50.64252 -141.964918)
		(end 51.987196 -141.964918)
		(width 0.13208)
		(layer "F.Cu")
		(net "SMB_NIC0_R_SDA")
	)
	(segment
		(start 52.652422 -141.964918)
		(end 53.01234 -141.605)
		(width 0.13208)
		(layer "F.Cu")
		(net "SMB_NIC0_R_SDA")
	)
	(segment
		(start 53.01234 -141.605)
		(end 55.14975 -141.605)
		(width 0.13208)
		(layer "F.Cu")
		(net "SMB_NIC0_R_SDA")
	)
	(segment
		(start 55.14975 -141.605)
		(end 55.47995 -141.9352)
		(width 0.13208)
		(layer "F.Cu")
		(net "SMB_NIC0_R_SDA")
	)
	(via
		(at 63.133224 -209.296762)
		(size 0.508)
		(drill 0.254)
		(layers "F.Cu" "B.Cu")
		(net "SMB_NIC0_R_SDA")
	)
	(via
		(at 51.987196 -141.964918)
		(size 0.508)
		(drill 0.254)
		(layers "F.Cu" "B.Cu")
		(net "SMB_NIC0_R_SDA")
	)
	(via
		(at 225.851212 -230.027226)
		(size 0.508)
		(drill 0.254)
		(layers "F.Cu" "B.Cu")
		(net "SMB_NIC0_R_SDA")
	)
	(segment
		(start 225.851212 -231.498648)
		(end 225.851212 -230.027226)
		(width 0.13208)
		(layer "B.Cu")
		(net "SMB_NIC0_R_SDA")
	)
	(segment
		(start 226.386644 -231.625648)
		(end 225.978212 -231.625648)
		(width 0.13208)
		(layer "B.Cu")
		(net "SMB_NIC0_R_SDA")
	)
	(segment
		(start 225.978212 -231.625648)
		(end 225.851212 -231.498648)
		(width 0.13208)
		(layer "B.Cu")
		(net "SMB_NIC0_R_SDA")
	)
	(segment
		(start 63.133224 -209.296762)
		(end 63.133224 -207.07477)
		(width 0.15494)
		(layer "In9.Cu")
		(net "SMB_NIC0_R_SDA")
	)
	(segment
		(start 55.1688 -147.3962)
		(end 53.818028 -146.045428)
		(width 0.15494)
		(layer "In9.Cu")
		(net "SMB_NIC0_R_SDA")
	)
	(segment
		(start 52.429918 -141.964918)
		(end 51.987196 -141.964918)
		(width 0.15494)
		(layer "In9.Cu")
		(net "SMB_NIC0_R_SDA")
	)
	(segment
		(start 62.2808 -185.6232)
		(end 55.1688 -178.5112)
		(width 0.15494)
		(layer "In9.Cu")
		(net "SMB_NIC0_R_SDA")
	)
	(segment
		(start 63.133224 -207.07477)
		(end 62.2808 -206.222346)
		(width 0.15494)
		(layer "In9.Cu")
		(net "SMB_NIC0_R_SDA")
	)
	(segment
		(start 53.818028 -146.045428)
		(end 53.818028 -143.353028)
		(width 0.15494)
		(layer "In9.Cu")
		(net "SMB_NIC0_R_SDA")
	)
	(segment
		(start 55.1688 -178.5112)
		(end 55.1688 -147.3962)
		(width 0.15494)
		(layer "In9.Cu")
		(net "SMB_NIC0_R_SDA")
	)
	(segment
		(start 62.2808 -206.222346)
		(end 62.2808 -185.6232)
		(width 0.15494)
		(layer "In9.Cu")
		(net "SMB_NIC0_R_SDA")
	)
	(segment
		(start 53.818028 -143.353028)
		(end 52.429918 -141.964918)
		(width 0.15494)
		(layer "In9.Cu")
		(net "SMB_NIC0_R_SDA")
	)
	(segment
		(start 66.853562 -210.03006)
		(end 65.665858 -208.842356)
		(width 0.15494)
		(layer "In13.Cu")
		(net "SMB_NIC0_R_SDA")
	)
	(segment
		(start 115.694714 -211.27466)
		(end 110.41126 -211.27466)
		(width 0.15494)
		(layer "In13.Cu")
		(net "SMB_NIC0_R_SDA")
	)
	(segment
		(start 75.94981 -210.63458)
		(end 75.34529 -210.03006)
		(width 0.15494)
		(layer "In13.Cu")
		(net "SMB_NIC0_R_SDA")
	)
	(segment
		(start 100.26142 -210.63458)
		(end 75.94981 -210.63458)
		(width 0.15494)
		(layer "In13.Cu")
		(net "SMB_NIC0_R_SDA")
	)
	(segment
		(start 133.366256 -219.822014)
		(end 132.71881 -220.46946)
		(width 0.15494)
		(layer "In13.Cu")
		(net "SMB_NIC0_R_SDA")
	)
	(segment
		(start 100.79609 -210.09991)
		(end 100.26142 -210.63458)
		(width 0.15494)
		(layer "In13.Cu")
		(net "SMB_NIC0_R_SDA")
	)
	(segment
		(start 63.58763 -208.842356)
		(end 63.133224 -209.296762)
		(width 0.15494)
		(layer "In13.Cu")
		(net "SMB_NIC0_R_SDA")
	)
	(segment
		(start 225.851212 -230.027226)
		(end 225.364294 -230.514144)
		(width 0.15494)
		(layer "In13.Cu")
		(net "SMB_NIC0_R_SDA")
	)
	(segment
		(start 75.34529 -210.03006)
		(end 66.853562 -210.03006)
		(width 0.15494)
		(layer "In13.Cu")
		(net "SMB_NIC0_R_SDA")
	)
	(segment
		(start 206.437738 -232.067862)
		(end 157.687772 -232.067862)
		(width 0.15494)
		(layer "In13.Cu")
		(net "SMB_NIC0_R_SDA")
	)
	(segment
		(start 157.687772 -232.067862)
		(end 145.441924 -219.822014)
		(width 0.15494)
		(layer "In13.Cu")
		(net "SMB_NIC0_R_SDA")
	)
	(segment
		(start 124.889514 -220.46946)
		(end 115.694714 -211.27466)
		(width 0.15494)
		(layer "In13.Cu")
		(net "SMB_NIC0_R_SDA")
	)
	(segment
		(start 109.23651 -210.09991)
		(end 100.79609 -210.09991)
		(width 0.15494)
		(layer "In13.Cu")
		(net "SMB_NIC0_R_SDA")
	)
	(segment
		(start 208.745074 -230.514144)
		(end 207.972914 -231.286304)
		(width 0.15494)
		(layer "In13.Cu")
		(net "SMB_NIC0_R_SDA")
	)
	(segment
		(start 65.665858 -208.842356)
		(end 63.58763 -208.842356)
		(width 0.15494)
		(layer "In13.Cu")
		(net "SMB_NIC0_R_SDA")
	)
	(segment
		(start 225.364294 -230.514144)
		(end 208.745074 -230.514144)
		(width 0.15494)
		(layer "In13.Cu")
		(net "SMB_NIC0_R_SDA")
	)
	(segment
		(start 132.71881 -220.46946)
		(end 124.889514 -220.46946)
		(width 0.15494)
		(layer "In13.Cu")
		(net "SMB_NIC0_R_SDA")
	)
	(segment
		(start 110.41126 -211.27466)
		(end 109.23651 -210.09991)
		(width 0.15494)
		(layer "In13.Cu")
		(net "SMB_NIC0_R_SDA")
	)
	(segment
		(start 207.219296 -231.286304)
		(end 206.437738 -232.067862)
		(width 0.15494)
		(layer "In13.Cu")
		(net "SMB_NIC0_R_SDA")
	)
	(segment
		(start 145.441924 -219.822014)
		(end 133.366256 -219.822014)
		(width 0.15494)
		(layer "In13.Cu")
		(net "SMB_NIC0_R_SDA")
	)
	(segment
		(start 207.972914 -231.286304)
		(end 207.219296 -231.286304)
		(width 0.15494)
		(layer "In13.Cu")
		(net "SMB_NIC0_R_SDA")
	)
	(segment
		(start 406.781 -384.06705)
		(end 406.781 -384.683)
		(width 0.13208)
		(layer "F.Cu")
		(net "I3C_MB_BMC_SDA")
	)
	(via
		(at 406.781 -384.683)
		(size 0.508)
		(drill 0.254)
		(layers "F.Cu" "B.Cu")
		(net "I3C_MB_BMC_SDA")
	)
	(segment
		(start 405.311864 -388.084568)
		(end 403.190964 -388.084568)
		(width 0.15494)
		(layer "In9.Cu")
		(net "I3C_MB_BMC_SDA")
	)
	(segment
		(start 406.550114 -384.913886)
		(end 406.550114 -386.846318)
		(width 0.15494)
		(layer "In9.Cu")
		(net "I3C_MB_BMC_SDA")
	)
	(segment
		(start 397.368268 -393.907264)
		(end 397.368268 -400.711924)
		(width 0.15494)
		(layer "In9.Cu")
		(net "I3C_MB_BMC_SDA")
	)
	(segment
		(start 403.190964 -388.084568)
		(end 397.368268 -393.907264)
		(width 0.15494)
		(layer "In9.Cu")
		(net "I3C_MB_BMC_SDA")
	)
	(segment
		(start 406.550114 -386.846318)
		(end 405.311864 -388.084568)
		(width 0.15494)
		(layer "In9.Cu")
		(net "I3C_MB_BMC_SDA")
	)
	(segment
		(start 397.368268 -400.711924)
		(end 395.29004 -402.790152)
		(width 0.15494)
		(layer "In9.Cu")
		(net "I3C_MB_BMC_SDA")
	)
	(segment
		(start 406.781 -384.683)
		(end 406.550114 -384.913886)
		(width 0.15494)
		(layer "In9.Cu")
		(net "I3C_MB_BMC_SDA")
	)
	(segment
		(start 346.075 -234.46105)
		(end 346.075 -235.077)
		(width 0.13208)
		(layer "F.Cu")
		(net "RST_SSD4_PERST_R_N")
	)
	(segment
		(start 130.304032 -24.189944)
		(end 131.36499 -24.189944)
		(width 0.13208)
		(layer "F.Cu")
		(net "RST_SSD4_PERST_R_N")
	)
	(via
		(at 130.304032 -24.189944)
		(size 0.508)
		(drill 0.254)
		(layers "F.Cu" "B.Cu")
		(net "RST_SSD4_PERST_R_N")
	)
	(via
		(at 153.59761 -232.31856)
		(size 0.508)
		(drill 0.254)
		(layers "F.Cu" "B.Cu")
		(net "RST_SSD4_PERST_R_N")
	)
	(via
		(at 346.075 -235.077)
		(size 0.508)
		(drill 0.254)
		(layers "F.Cu" "B.Cu")
		(net "RST_SSD4_PERST_R_N")
	)
	(segment
		(start 140.7922 -28.2956)
		(end 140.7922 -28.873196)
		(width 0.15494)
		(layer "In5.Cu")
		(net "RST_SSD4_PERST_R_N")
	)
	(segment
		(start 136.6266 -26.9494)
		(end 137.132314 -27.455114)
		(width 0.15494)
		(layer "In5.Cu")
		(net "RST_SSD4_PERST_R_N")
	)
	(segment
		(start 139.951714 -27.455114)
		(end 140.7922 -28.2956)
		(width 0.15494)
		(layer "In5.Cu")
		(net "RST_SSD4_PERST_R_N")
	)
	(segment
		(start 140.468858 -29.196538)
		(end 140.468858 -32.932116)
		(width 0.15494)
		(layer "In5.Cu")
		(net "RST_SSD4_PERST_R_N")
	)
	(segment
		(start 150.733506 -191.500506)
		(end 152.101042 -194.802252)
		(width 0.15494)
		(layer "In5.Cu")
		(net "RST_SSD4_PERST_R_N")
	)
	(segment
		(start 142.580106 -112.029494)
		(end 142.580106 -162.74796)
		(width 0.15494)
		(layer "In5.Cu")
		(net "RST_SSD4_PERST_R_N")
	)
	(segment
		(start 143.48714 -111.12246)
		(end 142.580106 -112.029494)
		(width 0.15494)
		(layer "In5.Cu")
		(net "RST_SSD4_PERST_R_N")
	)
	(segment
		(start 143.48714 -82.674206)
		(end 143.48714 -111.12246)
		(width 0.15494)
		(layer "In5.Cu")
		(net "RST_SSD4_PERST_R_N")
	)
	(segment
		(start 142.580106 -162.74796)
		(end 143.9418 -164.109654)
		(width 0.15494)
		(layer "In5.Cu")
		(net "RST_SSD4_PERST_R_N")
	)
	(segment
		(start 152.89022 -73.271126)
		(end 143.48714 -82.674206)
		(width 0.15494)
		(layer "In5.Cu")
		(net "RST_SSD4_PERST_R_N")
	)
	(segment
		(start 152.101042 -230.460296)
		(end 153.59761 -231.956864)
		(width 0.15494)
		(layer "In5.Cu")
		(net "RST_SSD4_PERST_R_N")
	)
	(segment
		(start 145.2118 -172.669454)
		(end 145.2118 -185.9788)
		(width 0.15494)
		(layer "In5.Cu")
		(net "RST_SSD4_PERST_R_N")
	)
	(segment
		(start 135.1026 -26.9494)
		(end 136.6266 -26.9494)
		(width 0.15494)
		(layer "In5.Cu")
		(net "RST_SSD4_PERST_R_N")
	)
	(segment
		(start 131.044442 -24.930354)
		(end 133.083554 -24.930354)
		(width 0.15494)
		(layer "In5.Cu")
		(net "RST_SSD4_PERST_R_N")
	)
	(segment
		(start 152.101042 -194.802252)
		(end 152.101042 -230.460296)
		(width 0.15494)
		(layer "In5.Cu")
		(net "RST_SSD4_PERST_R_N")
	)
	(segment
		(start 143.9418 -171.399454)
		(end 145.2118 -172.669454)
		(width 0.15494)
		(layer "In5.Cu")
		(net "RST_SSD4_PERST_R_N")
	)
	(segment
		(start 140.468858 -32.932116)
		(end 152.89022 -45.353478)
		(width 0.15494)
		(layer "In5.Cu")
		(net "RST_SSD4_PERST_R_N")
	)
	(segment
		(start 133.083554 -24.930354)
		(end 135.1026 -26.9494)
		(width 0.15494)
		(layer "In5.Cu")
		(net "RST_SSD4_PERST_R_N")
	)
	(segment
		(start 140.7922 -28.873196)
		(end 140.468858 -29.196538)
		(width 0.15494)
		(layer "In5.Cu")
		(net "RST_SSD4_PERST_R_N")
	)
	(segment
		(start 130.304032 -24.189944)
		(end 131.044442 -24.930354)
		(width 0.15494)
		(layer "In5.Cu")
		(net "RST_SSD4_PERST_R_N")
	)
	(segment
		(start 145.2118 -185.9788)
		(end 150.733506 -191.500506)
		(width 0.15494)
		(layer "In5.Cu")
		(net "RST_SSD4_PERST_R_N")
	)
	(segment
		(start 137.132314 -27.455114)
		(end 139.951714 -27.455114)
		(width 0.15494)
		(layer "In5.Cu")
		(net "RST_SSD4_PERST_R_N")
	)
	(segment
		(start 153.59761 -231.956864)
		(end 153.59761 -232.31856)
		(width 0.15494)
		(layer "In5.Cu")
		(net "RST_SSD4_PERST_R_N")
	)
	(segment
		(start 152.89022 -45.353478)
		(end 152.89022 -73.271126)
		(width 0.15494)
		(layer "In5.Cu")
		(net "RST_SSD4_PERST_R_N")
	)
	(segment
		(start 143.9418 -164.109654)
		(end 143.9418 -171.399454)
		(width 0.15494)
		(layer "In5.Cu")
		(net "RST_SSD4_PERST_R_N")
	)
	(segment
		(start 186.47918 -240.856008)
		(end 187.008008 -240.856008)
		(width 0.15494)
		(layer "In15.Cu")
		(net "RST_SSD4_PERST_R_N")
	)
	(segment
		(start 332.304136 -245.467886)
		(end 335.806542 -245.467886)
		(width 0.15494)
		(layer "In15.Cu")
		(net "RST_SSD4_PERST_R_N")
	)
	(segment
		(start 232.474008 -244.094508)
		(end 236.083094 -244.094508)
		(width 0.15494)
		(layer "In15.Cu")
		(net "RST_SSD4_PERST_R_N")
	)
	(segment
		(start 329.379072 -245.950994)
		(end 330.118974 -245.950994)
		(width 0.15494)
		(layer "In15.Cu")
		(net "RST_SSD4_PERST_R_N")
	)
	(segment
		(start 339.620352 -245.292372)
		(end 344.92946 -239.983264)
		(width 0.15494)
		(layer "In15.Cu")
		(net "RST_SSD4_PERST_R_N")
	)
	(segment
		(start 224.046542 -244.97157)
		(end 231.596946 -244.97157)
		(width 0.15494)
		(layer "In15.Cu")
		(net "RST_SSD4_PERST_R_N")
	)
	(segment
		(start 274.60448 -244.929914)
		(end 274.900898 -245.226332)
		(width 0.15494)
		(layer "In15.Cu")
		(net "RST_SSD4_PERST_R_N")
	)
	(segment
		(start 335.982056 -245.292372)
		(end 339.620352 -245.292372)
		(width 0.15494)
		(layer "In15.Cu")
		(net "RST_SSD4_PERST_R_N")
	)
	(segment
		(start 300.970188 -246.753888)
		(end 302.86579 -246.753888)
		(width 0.15494)
		(layer "In15.Cu")
		(net "RST_SSD4_PERST_R_N")
	)
	(segment
		(start 181.98719 -237.838234)
		(end 183.461406 -237.838234)
		(width 0.15494)
		(layer "In15.Cu")
		(net "RST_SSD4_PERST_R_N")
	)
	(segment
		(start 187.008008 -240.856008)
		(end 190.234316 -244.082316)
		(width 0.15494)
		(layer "In15.Cu")
		(net "RST_SSD4_PERST_R_N")
	)
	(segment
		(start 254.682498 -244.929914)
		(end 274.60448 -244.929914)
		(width 0.15494)
		(layer "In15.Cu")
		(net "RST_SSD4_PERST_R_N")
	)
	(segment
		(start 253.929134 -244.17655)
		(end 254.682498 -244.929914)
		(width 0.15494)
		(layer "In15.Cu")
		(net "RST_SSD4_PERST_R_N")
	)
	(segment
		(start 345.54287 -238.714534)
		(end 345.54287 -235.60913)
		(width 0.15494)
		(layer "In15.Cu")
		(net "RST_SSD4_PERST_R_N")
	)
	(segment
		(start 330.173838 -245.89613)
		(end 331.875892 -245.89613)
		(width 0.15494)
		(layer "In15.Cu")
		(net "RST_SSD4_PERST_R_N")
	)
	(segment
		(start 183.461406 -237.838234)
		(end 186.47918 -240.856008)
		(width 0.15494)
		(layer "In15.Cu")
		(net "RST_SSD4_PERST_R_N")
	)
	(segment
		(start 153.59761 -232.31856)
		(end 153.60396 -232.31221)
		(width 0.15494)
		(layer "In15.Cu")
		(net "RST_SSD4_PERST_R_N")
	)
	(segment
		(start 331.875892 -245.89613)
		(end 332.304136 -245.467886)
		(width 0.15494)
		(layer "In15.Cu")
		(net "RST_SSD4_PERST_R_N")
	)
	(segment
		(start 274.900898 -245.226332)
		(end 299.442632 -245.226332)
		(width 0.15494)
		(layer "In15.Cu")
		(net "RST_SSD4_PERST_R_N")
	)
	(segment
		(start 239.023398 -244.17655)
		(end 253.929134 -244.17655)
		(width 0.15494)
		(layer "In15.Cu")
		(net "RST_SSD4_PERST_R_N")
	)
	(segment
		(start 330.118974 -245.950994)
		(end 330.173838 -245.89613)
		(width 0.15494)
		(layer "In15.Cu")
		(net "RST_SSD4_PERST_R_N")
	)
	(segment
		(start 153.60396 -232.31221)
		(end 156.302964 -232.31221)
		(width 0.15494)
		(layer "In15.Cu")
		(net "RST_SSD4_PERST_R_N")
	)
	(segment
		(start 213.633304 -244.834918)
		(end 220.115638 -244.834918)
		(width 0.15494)
		(layer "In15.Cu")
		(net "RST_SSD4_PERST_R_N")
	)
	(segment
		(start 220.115638 -244.834918)
		(end 220.413834 -244.536722)
		(width 0.15494)
		(layer "In15.Cu")
		(net "RST_SSD4_PERST_R_N")
	)
	(segment
		(start 223.611694 -244.536722)
		(end 224.046542 -244.97157)
		(width 0.15494)
		(layer "In15.Cu")
		(net "RST_SSD4_PERST_R_N")
	)
	(segment
		(start 345.54287 -235.60913)
		(end 346.075 -235.077)
		(width 0.15494)
		(layer "In15.Cu")
		(net "RST_SSD4_PERST_R_N")
	)
	(segment
		(start 212.880702 -244.082316)
		(end 213.633304 -244.834918)
		(width 0.15494)
		(layer "In15.Cu")
		(net "RST_SSD4_PERST_R_N")
	)
	(segment
		(start 231.596946 -244.97157)
		(end 232.474008 -244.094508)
		(width 0.15494)
		(layer "In15.Cu")
		(net "RST_SSD4_PERST_R_N")
	)
	(segment
		(start 160.218374 -236.22762)
		(end 180.376576 -236.22762)
		(width 0.15494)
		(layer "In15.Cu")
		(net "RST_SSD4_PERST_R_N")
	)
	(segment
		(start 344.92946 -239.327944)
		(end 345.54287 -238.714534)
		(width 0.15494)
		(layer "In15.Cu")
		(net "RST_SSD4_PERST_R_N")
	)
	(segment
		(start 344.92946 -239.983264)
		(end 344.92946 -239.327944)
		(width 0.15494)
		(layer "In15.Cu")
		(net "RST_SSD4_PERST_R_N")
	)
	(segment
		(start 238.072168 -245.12778)
		(end 239.023398 -244.17655)
		(width 0.15494)
		(layer "In15.Cu")
		(net "RST_SSD4_PERST_R_N")
	)
	(segment
		(start 156.302964 -232.31221)
		(end 160.218374 -236.22762)
		(width 0.15494)
		(layer "In15.Cu")
		(net "RST_SSD4_PERST_R_N")
	)
	(segment
		(start 335.806542 -245.467886)
		(end 335.982056 -245.292372)
		(width 0.15494)
		(layer "In15.Cu")
		(net "RST_SSD4_PERST_R_N")
	)
	(segment
		(start 236.083094 -244.094508)
		(end 237.116366 -245.12778)
		(width 0.15494)
		(layer "In15.Cu")
		(net "RST_SSD4_PERST_R_N")
	)
	(segment
		(start 299.442632 -245.226332)
		(end 300.970188 -246.753888)
		(width 0.15494)
		(layer "In15.Cu")
		(net "RST_SSD4_PERST_R_N")
	)
	(segment
		(start 190.234316 -244.082316)
		(end 212.880702 -244.082316)
		(width 0.15494)
		(layer "In15.Cu")
		(net "RST_SSD4_PERST_R_N")
	)
	(segment
		(start 302.86579 -246.753888)
		(end 303.939448 -246.308626)
		(width 0.15494)
		(layer "In15.Cu")
		(net "RST_SSD4_PERST_R_N")
	)
	(segment
		(start 303.939448 -246.308626)
		(end 329.02144 -246.308626)
		(width 0.15494)
		(layer "In15.Cu")
		(net "RST_SSD4_PERST_R_N")
	)
	(segment
		(start 220.413834 -244.536722)
		(end 223.611694 -244.536722)
		(width 0.15494)
		(layer "In15.Cu")
		(net "RST_SSD4_PERST_R_N")
	)
	(segment
		(start 180.376576 -236.22762)
		(end 181.98719 -237.838234)
		(width 0.15494)
		(layer "In15.Cu")
		(net "RST_SSD4_PERST_R_N")
	)
	(segment
		(start 329.02144 -246.308626)
		(end 329.379072 -245.950994)
		(width 0.15494)
		(layer "In15.Cu")
		(net "RST_SSD4_PERST_R_N")
	)
	(segment
		(start 237.116366 -245.12778)
		(end 238.072168 -245.12778)
		(width 0.15494)
		(layer "In15.Cu")
		(net "RST_SSD4_PERST_R_N")
	)
	(segment
		(start 341.293958 -215.987122)
		(end 340.894162 -215.587326)
		(width 0.13208)
		(layer "F.Cu")
		(net "SSD12_CLK_EN_N")
	)
	(segment
		(start 338.582 -201.56805)
		(end 338.582 -202.946)
		(width 0.13208)
		(layer "F.Cu")
		(net "SSD12_CLK_EN_N")
	)
	(via
		(at 340.894162 -215.587326)
		(size 0.4572)
		(drill 0.254)
		(layers "F.Cu" "B.Cu")
		(net "SSD12_CLK_EN_N")
	)
	(via
		(at 338.582 -202.946)
		(size 0.508)
		(drill 0.254)
		(layers "F.Cu" "B.Cu")
		(net "SSD12_CLK_EN_N")
	)
	(segment
		(start 339.599778 -206.264764)
		(end 339.599778 -204.977492)
		(width 0.15494)
		(layer "In5.Cu")
		(net "SSD12_CLK_EN_N")
	)
	(segment
		(start 339.599778 -204.977492)
		(end 339.088222 -204.465936)
		(width 0.15494)
		(layer "In5.Cu")
		(net "SSD12_CLK_EN_N")
	)
	(segment
		(start 341.249 -211.793328)
		(end 341.249 -207.913986)
		(width 0.15494)
		(layer "In5.Cu")
		(net "SSD12_CLK_EN_N")
	)
	(segment
		(start 340.894162 -215.587326)
		(end 341.291672 -215.189816)
		(width 0.0889)
		(layer "In5.Cu")
		(net "SSD12_CLK_EN_N")
	)
	(segment
		(start 339.088222 -203.452222)
		(end 338.582 -202.946)
		(width 0.15494)
		(layer "In5.Cu")
		(net "SSD12_CLK_EN_N")
	)
	(segment
		(start 341.249 -207.913986)
		(end 339.599778 -206.264764)
		(width 0.15494)
		(layer "In5.Cu")
		(net "SSD12_CLK_EN_N")
	)
	(segment
		(start 341.291672 -212.217)
		(end 341.291672 -211.836)
		(width 0.15494)
		(layer "In5.Cu")
		(net "SSD12_CLK_EN_N")
	)
	(segment
		(start 339.088222 -204.465936)
		(end 339.088222 -203.452222)
		(width 0.15494)
		(layer "In5.Cu")
		(net "SSD12_CLK_EN_N")
	)
	(segment
		(start 341.291672 -215.189816)
		(end 341.291672 -212.217)
		(width 0.0889)
		(layer "In5.Cu")
		(net "SSD12_CLK_EN_N")
	)
	(segment
		(start 341.291672 -211.836)
		(end 341.249 -211.793328)
		(width 0.15494)
		(layer "In5.Cu")
		(net "SSD12_CLK_EN_N")
	)
	(segment
		(start 28.95981 -312.00852)
		(end 28.507944 -311.556654)
		(width 0.13208)
		(layer "F.Cu")
		(net "PEX0_DBG_SEL1")
	)
	(segment
		(start 29.826712 -312.00852)
		(end 31.599124 -312.00852)
		(width 0.13208)
		(layer "F.Cu")
		(net "PEX0_DBG_SEL1")
	)
	(segment
		(start 53.949854 -308.249828)
		(end 53.474874 -308.724808)
		(width 0.13208)
		(layer "F.Cu")
		(net "PEX0_DBG_SEL1")
	)
	(segment
		(start 29.826712 -312.00852)
		(end 28.95981 -312.00852)
		(width 0.13208)
		(layer "F.Cu")
		(net "PEX0_DBG_SEL1")
	)
	(segment
		(start 31.599124 -312.00852)
		(end 32.113982 -312.523378)
		(width 0.13208)
		(layer "F.Cu")
		(net "PEX0_DBG_SEL1")
	)
	(segment
		(start 28.507944 -311.556654)
		(end 27.838654 -311.556654)
		(width 0.13208)
		(layer "F.Cu")
		(net "PEX0_DBG_SEL1")
	)
	(via
		(at 53.474874 -308.724808)
		(size 0.4064)
		(drill 0.2032)
		(layers "F.Cu" "B.Cu")
		(net "PEX0_DBG_SEL1")
	)
	(via
		(at 32.113982 -312.523378)
		(size 0.508)
		(drill 0.254)
		(layers "F.Cu" "B.Cu")
		(net "PEX0_DBG_SEL1")
	)
	(segment
		(start 52.578 -314.1726)
		(end 52.2478 -314.5028)
		(width 0.13208)
		(layer "B.Cu")
		(net "PEX0_DBG_SEL1")
	)
	(segment
		(start 32.417004 -312.8264)
		(end 32.113982 -312.523378)
		(width 0.13208)
		(layer "B.Cu")
		(net "PEX0_DBG_SEL1")
	)
	(segment
		(start 53.474874 -308.724808)
		(end 52.869592 -308.724808)
		(width 0.13208)
		(layer "B.Cu")
		(net "PEX0_DBG_SEL1")
	)
	(segment
		(start 52.2478 -314.5028)
		(end 38.5318 -314.5028)
		(width 0.13208)
		(layer "B.Cu")
		(net "PEX0_DBG_SEL1")
	)
	(segment
		(start 35.5854 -313.309)
		(end 35.1028 -312.8264)
		(width 0.13208)
		(layer "B.Cu")
		(net "PEX0_DBG_SEL1")
	)
	(segment
		(start 36.2204 -314.3504)
		(end 35.5854 -313.7154)
		(width 0.13208)
		(layer "B.Cu")
		(net "PEX0_DBG_SEL1")
	)
	(segment
		(start 38.5318 -314.5028)
		(end 38.3794 -314.3504)
		(width 0.13208)
		(layer "B.Cu")
		(net "PEX0_DBG_SEL1")
	)
	(segment
		(start 52.869592 -308.724808)
		(end 52.578 -309.0164)
		(width 0.13208)
		(layer "B.Cu")
		(net "PEX0_DBG_SEL1")
	)
	(segment
		(start 52.578 -309.0164)
		(end 52.578 -314.1726)
		(width 0.13208)
		(layer "B.Cu")
		(net "PEX0_DBG_SEL1")
	)
	(segment
		(start 38.3794 -314.3504)
		(end 36.2204 -314.3504)
		(width 0.13208)
		(layer "B.Cu")
		(net "PEX0_DBG_SEL1")
	)
	(segment
		(start 35.5854 -313.7154)
		(end 35.5854 -313.309)
		(width 0.13208)
		(layer "B.Cu")
		(net "PEX0_DBG_SEL1")
	)
	(segment
		(start 35.1028 -312.8264)
		(end 32.417004 -312.8264)
		(width 0.13208)
		(layer "B.Cu")
		(net "PEX0_DBG_SEL1")
	)
	(segment
		(start 395.59992 -309.199788)
		(end 395.12494 -308.724808)
		(width 0.13208)
		(layer "F.Cu")
		(net "PEX3_DBG_MODE0")
	)
	(segment
		(start 379.884178 -310.892698)
		(end 379.563376 -310.571896)
		(width 0.13208)
		(layer "F.Cu")
		(net "PEX3_DBG_MODE0")
	)
	(segment
		(start 379.563376 -310.571896)
		(end 379.562868 -310.571896)
		(width 0.13208)
		(layer "F.Cu")
		(net "PEX3_DBG_MODE0")
	)
	(segment
		(start 380.329948 -310.892698)
		(end 379.884178 -310.892698)
		(width 0.13208)
		(layer "F.Cu")
		(net "PEX3_DBG_MODE0")
	)
	(segment
		(start 379.563376 -310.571896)
		(end 380.281688 -309.853584)
		(width 0.13208)
		(layer "F.Cu")
		(net "PEX3_DBG_MODE0")
	)
	(segment
		(start 381.17145 -311.7342)
		(end 380.329948 -310.892698)
		(width 0.13208)
		(layer "F.Cu")
		(net "PEX3_DBG_MODE0")
	)
	(via
		(at 381.17145 -311.7342)
		(size 0.508)
		(drill 0.254)
		(layers "F.Cu" "B.Cu")
		(net "PEX3_DBG_MODE0")
	)
	(via
		(at 382.836928 -308.601618)
		(size 0.6604)
		(drill 0.3302)
		(layers "F.Cu" "B.Cu")
		(net "PEX3_DBG_MODE0")
	)
	(via
		(at 395.12494 -308.724808)
		(size 0.4064)
		(drill 0.2032)
		(layers "F.Cu" "B.Cu")
		(net "PEX3_DBG_MODE0")
	)
	(segment
		(start 381.17145 -311.7342)
		(end 381.17145 -310.267096)
		(width 0.13208)
		(layer "B.Cu")
		(net "PEX3_DBG_MODE0")
	)
	(segment
		(start 382.960118 -308.724808)
		(end 382.836928 -308.601618)
		(width 0.13208)
		(layer "B.Cu")
		(net "PEX3_DBG_MODE0")
	)
	(segment
		(start 395.12494 -308.724808)
		(end 382.960118 -308.724808)
		(width 0.13208)
		(layer "B.Cu")
		(net "PEX3_DBG_MODE0")
	)
	(segment
		(start 381.17145 -310.267096)
		(end 382.836928 -308.601618)
		(width 0.13208)
		(layer "B.Cu")
		(net "PEX3_DBG_MODE0")
	)
	(segment
		(start 68.65747 -112.834928)
		(end 66.878454 -112.834928)
		(width 0.13208)
		(layer "F.Cu")
		(net "SMB_NIC1_R_SCL")
	)
	(via
		(at 66.878454 -112.834928)
		(size 0.508)
		(drill 0.254)
		(layers "F.Cu" "B.Cu")
		(net "SMB_NIC1_R_SCL")
	)
	(via
		(at 200.553574 -102.872794)
		(size 0.508)
		(drill 0.254)
		(layers "F.Cu" "B.Cu")
		(net "SMB_NIC1_R_SCL")
	)
	(via
		(at 224.695512 -233.182668)
		(size 0.508)
		(drill 0.254)
		(layers "F.Cu" "B.Cu")
		(net "SMB_NIC1_R_SCL")
	)
	(segment
		(start 224.221548 -231.758744)
		(end 224.354644 -231.625648)
		(width 0.13208)
		(layer "B.Cu")
		(net "SMB_NIC1_R_SCL")
	)
	(segment
		(start 67.321684 -112.391698)
		(end 66.878454 -112.834928)
		(width 0.13208)
		(layer "B.Cu")
		(net "SMB_NIC1_R_SCL")
	)
	(segment
		(start 224.221548 -232.708704)
		(end 224.221548 -231.758744)
		(width 0.13208)
		(layer "B.Cu")
		(net "SMB_NIC1_R_SCL")
	)
	(segment
		(start 68.272152 -112.421924)
		(end 68.241926 -112.391698)
		(width 0.13208)
		(layer "B.Cu")
		(net "SMB_NIC1_R_SCL")
	)
	(segment
		(start 224.695512 -233.182668)
		(end 224.221548 -232.708704)
		(width 0.13208)
		(layer "B.Cu")
		(net "SMB_NIC1_R_SCL")
	)
	(segment
		(start 68.241926 -112.391698)
		(end 67.321684 -112.391698)
		(width 0.13208)
		(layer "B.Cu")
		(net "SMB_NIC1_R_SCL")
	)
	(segment
		(start 224.103438 -233.774742)
		(end 224.695512 -233.182668)
		(width 0.15494)
		(layer "In7.Cu")
		(net "SMB_NIC1_R_SCL")
	)
	(segment
		(start 199.589136 -191.795654)
		(end 199.589136 -225.344736)
		(width 0.15494)
		(layer "In7.Cu")
		(net "SMB_NIC1_R_SCL")
	)
	(segment
		(start 207.137254 -231.5464)
		(end 220.596206 -231.5464)
		(width 0.15494)
		(layer "In7.Cu")
		(net "SMB_NIC1_R_SCL")
	)
	(segment
		(start 221.217236 -233.774742)
		(end 224.103438 -233.774742)
		(width 0.15494)
		(layer "In7.Cu")
		(net "SMB_NIC1_R_SCL")
	)
	(segment
		(start 202.68692 -116.54536)
		(end 202.68692 -125.9332)
		(width 0.15494)
		(layer "In7.Cu")
		(net "SMB_NIC1_R_SCL")
	)
	(segment
		(start 202.68692 -125.9332)
		(end 208.062576 -131.308856)
		(width 0.15494)
		(layer "In7.Cu")
		(net "SMB_NIC1_R_SCL")
	)
	(segment
		(start 203.760324 -168.218358)
		(end 203.760324 -187.624466)
		(width 0.15494)
		(layer "In7.Cu")
		(net "SMB_NIC1_R_SCL")
	)
	(segment
		(start 208.062576 -131.308856)
		(end 208.062576 -163.916106)
		(width 0.15494)
		(layer "In7.Cu")
		(net "SMB_NIC1_R_SCL")
	)
	(segment
		(start 205.9178 -231.6734)
		(end 207.010254 -231.6734)
		(width 0.15494)
		(layer "In7.Cu")
		(net "SMB_NIC1_R_SCL")
	)
	(segment
		(start 203.760324 -187.624466)
		(end 199.589136 -191.795654)
		(width 0.15494)
		(layer "In7.Cu")
		(net "SMB_NIC1_R_SCL")
	)
	(segment
		(start 200.553574 -103.641906)
		(end 201.87666 -104.964992)
		(width 0.15494)
		(layer "In7.Cu")
		(net "SMB_NIC1_R_SCL")
	)
	(segment
		(start 201.87666 -113.2713)
		(end 202.25766 -113.6523)
		(width 0.15494)
		(layer "In7.Cu")
		(net "SMB_NIC1_R_SCL")
	)
	(segment
		(start 221.117922 -233.675428)
		(end 221.217236 -233.774742)
		(width 0.15494)
		(layer "In7.Cu")
		(net "SMB_NIC1_R_SCL")
	)
	(segment
		(start 200.553574 -102.872794)
		(end 200.553574 -103.641906)
		(width 0.15494)
		(layer "In7.Cu")
		(net "SMB_NIC1_R_SCL")
	)
	(segment
		(start 202.25766 -113.6523)
		(end 202.25766 -116.1161)
		(width 0.15494)
		(layer "In7.Cu")
		(net "SMB_NIC1_R_SCL")
	)
	(segment
		(start 208.062576 -163.916106)
		(end 203.760324 -168.218358)
		(width 0.15494)
		(layer "In7.Cu")
		(net "SMB_NIC1_R_SCL")
	)
	(segment
		(start 207.010254 -231.6734)
		(end 207.137254 -231.5464)
		(width 0.15494)
		(layer "In7.Cu")
		(net "SMB_NIC1_R_SCL")
	)
	(segment
		(start 221.117922 -232.068116)
		(end 221.117922 -233.675428)
		(width 0.15494)
		(layer "In7.Cu")
		(net "SMB_NIC1_R_SCL")
	)
	(segment
		(start 220.596206 -231.5464)
		(end 221.117922 -232.068116)
		(width 0.15494)
		(layer "In7.Cu")
		(net "SMB_NIC1_R_SCL")
	)
	(segment
		(start 201.87666 -104.964992)
		(end 201.87666 -113.2713)
		(width 0.15494)
		(layer "In7.Cu")
		(net "SMB_NIC1_R_SCL")
	)
	(segment
		(start 199.589136 -225.344736)
		(end 205.9178 -231.6734)
		(width 0.15494)
		(layer "In7.Cu")
		(net "SMB_NIC1_R_SCL")
	)
	(segment
		(start 202.25766 -116.1161)
		(end 202.68692 -116.54536)
		(width 0.15494)
		(layer "In7.Cu")
		(net "SMB_NIC1_R_SCL")
	)
	(segment
		(start 179.982876 -90.75293)
		(end 156.744924 -90.75293)
		(width 0.15494)
		(layer "In15.Cu")
		(net "SMB_NIC1_R_SCL")
	)
	(segment
		(start 77.2922 -98.5266)
		(end 77.11567 -98.70313)
		(width 0.15494)
		(layer "In15.Cu")
		(net "SMB_NIC1_R_SCL")
	)
	(segment
		(start 89.0778 -92.8878)
		(end 83.439 -98.5266)
		(width 0.15494)
		(layer "In15.Cu")
		(net "SMB_NIC1_R_SCL")
	)
	(segment
		(start 100.456746 -92.8878)
		(end 89.0778 -92.8878)
		(width 0.15494)
		(layer "In15.Cu")
		(net "SMB_NIC1_R_SCL")
	)
	(segment
		(start 108.040424 -96.11106)
		(end 103.680006 -96.11106)
		(width 0.15494)
		(layer "In15.Cu")
		(net "SMB_NIC1_R_SCL")
	)
	(segment
		(start 180.441346 -91.2114)
		(end 179.982876 -90.75293)
		(width 0.15494)
		(layer "In15.Cu")
		(net "SMB_NIC1_R_SCL")
	)
	(segment
		(start 66.2432 -112.199674)
		(end 66.878454 -112.834928)
		(width 0.15494)
		(layer "In15.Cu")
		(net "SMB_NIC1_R_SCL")
	)
	(segment
		(start 200.553574 -99.15652)
		(end 191.744854 -90.3478)
		(width 0.15494)
		(layer "In15.Cu")
		(net "SMB_NIC1_R_SCL")
	)
	(segment
		(start 156.744924 -90.75293)
		(end 144.831054 -102.6668)
		(width 0.15494)
		(layer "In15.Cu")
		(net "SMB_NIC1_R_SCL")
	)
	(segment
		(start 66.2432 -101.421946)
		(end 66.2432 -112.199674)
		(width 0.15494)
		(layer "In15.Cu")
		(net "SMB_NIC1_R_SCL")
	)
	(segment
		(start 200.553574 -102.872794)
		(end 200.553574 -99.15652)
		(width 0.15494)
		(layer "In15.Cu")
		(net "SMB_NIC1_R_SCL")
	)
	(segment
		(start 68.962016 -98.70313)
		(end 66.2432 -101.421946)
		(width 0.15494)
		(layer "In15.Cu")
		(net "SMB_NIC1_R_SCL")
	)
	(segment
		(start 182.346854 -90.3478)
		(end 181.483254 -91.2114)
		(width 0.15494)
		(layer "In15.Cu")
		(net "SMB_NIC1_R_SCL")
	)
	(segment
		(start 181.483254 -91.2114)
		(end 180.441346 -91.2114)
		(width 0.15494)
		(layer "In15.Cu")
		(net "SMB_NIC1_R_SCL")
	)
	(segment
		(start 77.11567 -98.70313)
		(end 68.962016 -98.70313)
		(width 0.15494)
		(layer "In15.Cu")
		(net "SMB_NIC1_R_SCL")
	)
	(segment
		(start 114.596164 -102.6668)
		(end 108.040424 -96.11106)
		(width 0.15494)
		(layer "In15.Cu")
		(net "SMB_NIC1_R_SCL")
	)
	(segment
		(start 191.744854 -90.3478)
		(end 182.346854 -90.3478)
		(width 0.15494)
		(layer "In15.Cu")
		(net "SMB_NIC1_R_SCL")
	)
	(segment
		(start 144.831054 -102.6668)
		(end 114.596164 -102.6668)
		(width 0.15494)
		(layer "In15.Cu")
		(net "SMB_NIC1_R_SCL")
	)
	(segment
		(start 83.439 -98.5266)
		(end 77.2922 -98.5266)
		(width 0.15494)
		(layer "In15.Cu")
		(net "SMB_NIC1_R_SCL")
	)
	(segment
		(start 103.680006 -96.11106)
		(end 100.456746 -92.8878)
		(width 0.15494)
		(layer "In15.Cu")
		(net "SMB_NIC1_R_SCL")
	)
	(segment
		(start 337.752436 -250.960128)
		(end 337.752436 -250.858528)
		(width 0.13208)
		(layer "F.Cu")
		(net "SMB_FPGA_ALERT_R_N")
	)
	(segment
		(start 225.067622 -217.504264)
		(end 224.667826 -217.104468)
		(width 0.13208)
		(layer "F.Cu")
		(net "SMB_FPGA_ALERT_R_N")
	)
	(segment
		(start 337.843876 -250.37923)
		(end 344.501724 -243.721382)
		(width 0.13208)
		(layer "F.Cu")
		(net "SMB_FPGA_ALERT_R_N")
	)
	(segment
		(start 344.501724 -242.58905)
		(end 345.934792 -241.155982)
		(width 0.13208)
		(layer "F.Cu")
		(net "SMB_FPGA_ALERT_R_N")
	)
	(segment
		(start 337.777836 -250.985528)
		(end 337.752436 -250.960128)
		(width 0.13208)
		(layer "F.Cu")
		(net "SMB_FPGA_ALERT_R_N")
	)
	(segment
		(start 337.843876 -250.767088)
		(end 337.843876 -250.37923)
		(width 0.13208)
		(layer "F.Cu")
		(net "SMB_FPGA_ALERT_R_N")
	)
	(segment
		(start 345.934792 -241.155982)
		(end 345.934792 -241.091212)
		(width 0.13208)
		(layer "F.Cu")
		(net "SMB_FPGA_ALERT_R_N")
	)
	(segment
		(start 337.752436 -250.858528)
		(end 337.843876 -250.767088)
		(width 0.13208)
		(layer "F.Cu")
		(net "SMB_FPGA_ALERT_R_N")
	)
	(segment
		(start 344.501724 -243.721382)
		(end 344.501724 -242.58905)
		(width 0.13208)
		(layer "F.Cu")
		(net "SMB_FPGA_ALERT_R_N")
	)
	(via
		(at 335.599024 -239.72901)
		(size 0.508)
		(drill 0.254)
		(layers "F.Cu" "B.Cu")
		(net "SMB_FPGA_ALERT_R_N")
	)
	(via
		(at 230.86568 -230.03002)
		(size 0.508)
		(drill 0.254)
		(layers "F.Cu" "B.Cu")
		(net "SMB_FPGA_ALERT_R_N")
	)
	(via
		(at 337.777836 -250.985528)
		(size 0.508)
		(drill 0.254)
		(layers "F.Cu" "B.Cu")
		(net "SMB_FPGA_ALERT_R_N")
	)
	(via
		(at 224.667826 -217.104468)
		(size 0.4572)
		(drill 0.254)
		(layers "F.Cu" "B.Cu")
		(net "SMB_FPGA_ALERT_R_N")
	)
	(segment
		(start 228.727254 -218.533472)
		(end 229.615238 -219.421456)
		(width 0.15494)
		(layer "In5.Cu")
		(net "SMB_FPGA_ALERT_R_N")
	)
	(segment
		(start 224.667826 -217.104468)
		(end 224.139252 -217.633042)
		(width 0.15494)
		(layer "In5.Cu")
		(net "SMB_FPGA_ALERT_R_N")
	)
	(segment
		(start 224.6249 -218.533472)
		(end 228.727254 -218.533472)
		(width 0.15494)
		(layer "In5.Cu")
		(net "SMB_FPGA_ALERT_R_N")
	)
	(segment
		(start 229.615238 -227.437696)
		(end 230.86568 -228.688138)
		(width 0.15494)
		(layer "In5.Cu")
		(net "SMB_FPGA_ALERT_R_N")
	)
	(segment
		(start 229.615238 -219.421456)
		(end 229.615238 -227.437696)
		(width 0.15494)
		(layer "In5.Cu")
		(net "SMB_FPGA_ALERT_R_N")
	)
	(segment
		(start 224.139252 -217.633042)
		(end 224.139252 -218.047824)
		(width 0.15494)
		(layer "In5.Cu")
		(net "SMB_FPGA_ALERT_R_N")
	)
	(segment
		(start 224.139252 -218.047824)
		(end 224.6249 -218.533472)
		(width 0.15494)
		(layer "In5.Cu")
		(net "SMB_FPGA_ALERT_R_N")
	)
	(segment
		(start 230.86568 -228.688138)
		(end 230.86568 -230.03002)
		(width 0.15494)
		(layer "In5.Cu")
		(net "SMB_FPGA_ALERT_R_N")
	)
	(segment
		(start 335.599024 -243.586254)
		(end 335.599024 -239.72901)
		(width 0.15494)
		(layer "In7.Cu")
		(net "SMB_FPGA_ALERT_R_N")
	)
	(segment
		(start 337.777836 -250.985528)
		(end 337.73872 -250.946412)
		(width 0.15494)
		(layer "In7.Cu")
		(net "SMB_FPGA_ALERT_R_N")
	)
	(segment
		(start 337.73872 -250.946412)
		(end 337.73872 -245.72595)
		(width 0.15494)
		(layer "In7.Cu")
		(net "SMB_FPGA_ALERT_R_N")
	)
	(segment
		(start 337.73872 -245.72595)
		(end 335.599024 -243.586254)
		(width 0.15494)
		(layer "In7.Cu")
		(net "SMB_FPGA_ALERT_R_N")
	)
	(segment
		(start 276.533864 -237.335314)
		(end 305.925982 -237.335314)
		(width 0.15494)
		(layer "In13.Cu")
		(net "SMB_FPGA_ALERT_R_N")
	)
	(segment
		(start 232.76306 -231.9274)
		(end 244.3988 -231.9274)
		(width 0.15494)
		(layer "In13.Cu")
		(net "SMB_FPGA_ALERT_R_N")
	)
	(segment
		(start 252.942852 -233.517948)
		(end 257.539744 -233.517948)
		(width 0.15494)
		(layer "In13.Cu")
		(net "SMB_FPGA_ALERT_R_N")
	)
	(segment
		(start 247.03151 -233.553)
		(end 248.818146 -233.553)
		(width 0.15494)
		(layer "In13.Cu")
		(net "SMB_FPGA_ALERT_R_N")
	)
	(segment
		(start 257.539744 -233.517948)
		(end 258.495292 -232.5624)
		(width 0.15494)
		(layer "In13.Cu")
		(net "SMB_FPGA_ALERT_R_N")
	)
	(segment
		(start 258.495292 -232.5624)
		(end 271.76095 -232.5624)
		(width 0.15494)
		(layer "In13.Cu")
		(net "SMB_FPGA_ALERT_R_N")
	)
	(segment
		(start 335.289906 -239.039908)
		(end 335.599024 -239.349026)
		(width 0.15494)
		(layer "In13.Cu")
		(net "SMB_FPGA_ALERT_R_N")
	)
	(segment
		(start 308.491128 -239.90046)
		(end 331.90942 -239.90046)
		(width 0.15494)
		(layer "In13.Cu")
		(net "SMB_FPGA_ALERT_R_N")
	)
	(segment
		(start 248.818146 -233.553)
		(end 249.910346 -234.6452)
		(width 0.15494)
		(layer "In13.Cu")
		(net "SMB_FPGA_ALERT_R_N")
	)
	(segment
		(start 271.76095 -232.5624)
		(end 276.533864 -237.335314)
		(width 0.15494)
		(layer "In13.Cu")
		(net "SMB_FPGA_ALERT_R_N")
	)
	(segment
		(start 332.769972 -239.039908)
		(end 335.289906 -239.039908)
		(width 0.15494)
		(layer "In13.Cu")
		(net "SMB_FPGA_ALERT_R_N")
	)
	(segment
		(start 331.90942 -239.90046)
		(end 332.769972 -239.039908)
		(width 0.15494)
		(layer "In13.Cu")
		(net "SMB_FPGA_ALERT_R_N")
	)
	(segment
		(start 249.910346 -234.6452)
		(end 251.8156 -234.6452)
		(width 0.15494)
		(layer "In13.Cu")
		(net "SMB_FPGA_ALERT_R_N")
	)
	(segment
		(start 305.925982 -237.335314)
		(end 308.491128 -239.90046)
		(width 0.15494)
		(layer "In13.Cu")
		(net "SMB_FPGA_ALERT_R_N")
	)
	(segment
		(start 245.313454 -232.842054)
		(end 247.03151 -233.553)
		(width 0.15494)
		(layer "In13.Cu")
		(net "SMB_FPGA_ALERT_R_N")
	)
	(segment
		(start 335.599024 -239.349026)
		(end 335.599024 -239.72901)
		(width 0.15494)
		(layer "In13.Cu")
		(net "SMB_FPGA_ALERT_R_N")
	)
	(segment
		(start 251.8156 -234.6452)
		(end 252.942852 -233.517948)
		(width 0.15494)
		(layer "In13.Cu")
		(net "SMB_FPGA_ALERT_R_N")
	)
	(segment
		(start 230.86568 -230.03002)
		(end 232.76306 -231.9274)
		(width 0.15494)
		(layer "In13.Cu")
		(net "SMB_FPGA_ALERT_R_N")
	)
	(segment
		(start 244.3988 -231.9274)
		(end 245.313454 -232.842054)
		(width 0.15494)
		(layer "In13.Cu")
		(net "SMB_FPGA_ALERT_R_N")
	)
	(segment
		(start 102.134416 -28.550108)
		(end 102.66426 -29.079952)
		(width 0.13208)
		(layer "F.Cu")
		(net "SSD3_PWRDIS_R")
	)
	(segment
		(start 102.134416 -28.469082)
		(end 102.134416 -28.550108)
		(width 0.13208)
		(layer "F.Cu")
		(net "SSD3_PWRDIS_R")
	)
	(segment
		(start 93.264736 -25.390094)
		(end 92.191078 -25.390094)
		(width 0.13208)
		(layer "F.Cu")
		(net "SSD3_PWRDIS_R")
	)
	(via
		(at 148.09851 -229.436676)
		(size 0.508)
		(drill 0.254)
		(layers "F.Cu" "B.Cu")
		(net "SSD3_PWRDIS_R")
	)
	(via
		(at 92.191078 -25.390094)
		(size 0.508)
		(drill 0.254)
		(layers "F.Cu" "B.Cu")
		(net "SSD3_PWRDIS_R")
	)
	(via
		(at 340.995 -236.347)
		(size 0.508)
		(drill 0.254)
		(layers "F.Cu" "B.Cu")
		(net "SSD3_PWRDIS_R")
	)
	(via
		(at 102.134416 -28.469082)
		(size 0.508)
		(drill 0.254)
		(layers "F.Cu" "B.Cu")
		(net "SSD3_PWRDIS_R")
	)
	(segment
		(start 341.53729 -235.80471)
		(end 340.995 -236.347)
		(width 0.13208)
		(layer "B.Cu")
		(net "SSD3_PWRDIS_R")
	)
	(segment
		(start 341.53729 -234.42676)
		(end 341.53729 -235.80471)
		(width 0.13208)
		(layer "B.Cu")
		(net "SSD3_PWRDIS_R")
	)
	(segment
		(start 342.011 -233.95305)
		(end 341.53729 -234.42676)
		(width 0.13208)
		(layer "B.Cu")
		(net "SSD3_PWRDIS_R")
	)
	(segment
		(start 140.10386 -169.643806)
		(end 140.10386 -172.517816)
		(width 0.15494)
		(layer "In5.Cu")
		(net "SSD3_PWRDIS_R")
	)
	(segment
		(start 138.292332 -89.764108)
		(end 138.292332 -110.250478)
		(width 0.15494)
		(layer "In5.Cu")
		(net "SSD3_PWRDIS_R")
	)
	(segment
		(start 98.358706 -27.432)
		(end 98.84156 -27.914854)
		(width 0.15494)
		(layer "In5.Cu")
		(net "SSD3_PWRDIS_R")
	)
	(segment
		(start 101.418898 -35.947858)
		(end 107.58424 -42.1132)
		(width 0.15494)
		(layer "In5.Cu")
		(net "SSD3_PWRDIS_R")
	)
	(segment
		(start 138.292332 -110.250478)
		(end 139.285726 -111.243872)
		(width 0.15494)
		(layer "In5.Cu")
		(net "SSD3_PWRDIS_R")
	)
	(segment
		(start 101.418898 -29.1846)
		(end 101.418898 -35.947858)
		(width 0.15494)
		(layer "In5.Cu")
		(net "SSD3_PWRDIS_R")
	)
	(segment
		(start 139.446 -191.35344)
		(end 146.449542 -198.356982)
		(width 0.15494)
		(layer "In5.Cu")
		(net "SSD3_PWRDIS_R")
	)
	(segment
		(start 139.285726 -168.825672)
		(end 140.10386 -169.643806)
		(width 0.15494)
		(layer "In5.Cu")
		(net "SSD3_PWRDIS_R")
	)
	(segment
		(start 117.488462 -66.205608)
		(end 120.154954 -66.205608)
		(width 0.15494)
		(layer "In5.Cu")
		(net "SSD3_PWRDIS_R")
	)
	(segment
		(start 114.828066 -63.545212)
		(end 117.488462 -66.205608)
		(width 0.15494)
		(layer "In5.Cu")
		(net "SSD3_PWRDIS_R")
	)
	(segment
		(start 140.10386 -172.517816)
		(end 139.446 -173.175676)
		(width 0.15494)
		(layer "In5.Cu")
		(net "SSD3_PWRDIS_R")
	)
	(segment
		(start 148.09851 -209.96529)
		(end 148.09851 -229.436676)
		(width 0.15494)
		(layer "In5.Cu")
		(net "SSD3_PWRDIS_R")
	)
	(segment
		(start 123.788932 -75.260708)
		(end 138.292332 -89.764108)
		(width 0.15494)
		(layer "In5.Cu")
		(net "SSD3_PWRDIS_R")
	)
	(segment
		(start 146.449542 -204.059536)
		(end 148.499068 -206.109062)
		(width 0.15494)
		(layer "In5.Cu")
		(net "SSD3_PWRDIS_R")
	)
	(segment
		(start 120.154954 -66.205608)
		(end 123.788932 -69.839586)
		(width 0.15494)
		(layer "In5.Cu")
		(net "SSD3_PWRDIS_R")
	)
	(segment
		(start 96.834452 -27.432)
		(end 98.358706 -27.432)
		(width 0.15494)
		(layer "In5.Cu")
		(net "SSD3_PWRDIS_R")
	)
	(segment
		(start 107.58424 -53.6448)
		(end 114.828066 -60.888626)
		(width 0.15494)
		(layer "In5.Cu")
		(net "SSD3_PWRDIS_R")
	)
	(segment
		(start 148.499068 -209.564732)
		(end 148.09851 -209.96529)
		(width 0.15494)
		(layer "In5.Cu")
		(net "SSD3_PWRDIS_R")
	)
	(segment
		(start 139.446 -173.175676)
		(end 139.446 -191.35344)
		(width 0.15494)
		(layer "In5.Cu")
		(net "SSD3_PWRDIS_R")
	)
	(segment
		(start 146.449542 -198.356982)
		(end 146.449542 -204.059536)
		(width 0.15494)
		(layer "In5.Cu")
		(net "SSD3_PWRDIS_R")
	)
	(segment
		(start 102.134416 -28.469082)
		(end 101.418898 -29.1846)
		(width 0.15494)
		(layer "In5.Cu")
		(net "SSD3_PWRDIS_R")
	)
	(segment
		(start 92.191078 -25.390094)
		(end 94.792546 -25.390094)
		(width 0.15494)
		(layer "In5.Cu")
		(net "SSD3_PWRDIS_R")
	)
	(segment
		(start 98.84156 -27.914854)
		(end 101.580188 -27.914854)
		(width 0.15494)
		(layer "In5.Cu")
		(net "SSD3_PWRDIS_R")
	)
	(segment
		(start 107.58424 -42.1132)
		(end 107.58424 -53.6448)
		(width 0.15494)
		(layer "In5.Cu")
		(net "SSD3_PWRDIS_R")
	)
	(segment
		(start 94.792546 -25.390094)
		(end 96.834452 -27.432)
		(width 0.15494)
		(layer "In5.Cu")
		(net "SSD3_PWRDIS_R")
	)
	(segment
		(start 101.580188 -27.914854)
		(end 102.134416 -28.469082)
		(width 0.15494)
		(layer "In5.Cu")
		(net "SSD3_PWRDIS_R")
	)
	(segment
		(start 123.788932 -69.839586)
		(end 123.788932 -75.260708)
		(width 0.15494)
		(layer "In5.Cu")
		(net "SSD3_PWRDIS_R")
	)
	(segment
		(start 148.499068 -206.109062)
		(end 148.499068 -209.564732)
		(width 0.15494)
		(layer "In5.Cu")
		(net "SSD3_PWRDIS_R")
	)
	(segment
		(start 139.285726 -111.243872)
		(end 139.285726 -168.825672)
		(width 0.15494)
		(layer "In5.Cu")
		(net "SSD3_PWRDIS_R")
	)
	(segment
		(start 114.828066 -60.888626)
		(end 114.828066 -63.545212)
		(width 0.15494)
		(layer "In5.Cu")
		(net "SSD3_PWRDIS_R")
	)
	(segment
		(start 257.953256 -233.487214)
		(end 258.196842 -233.7308)
		(width 0.15494)
		(layer "In15.Cu")
		(net "SSD3_PWRDIS_R")
	)
	(segment
		(start 230.758238 -239.523016)
		(end 240.71707 -239.523016)
		(width 0.15494)
		(layer "In15.Cu")
		(net "SSD3_PWRDIS_R")
	)
	(segment
		(start 247.523 -240.4618)
		(end 254.497586 -233.487214)
		(width 0.15494)
		(layer "In15.Cu")
		(net "SSD3_PWRDIS_R")
	)
	(segment
		(start 276.372066 -241.676428)
		(end 302.535844 -241.676428)
		(width 0.15494)
		(layer "In15.Cu")
		(net "SSD3_PWRDIS_R")
	)
	(segment
		(start 263.877552 -234.466384)
		(end 266.089384 -236.678216)
		(width 0.15494)
		(layer "In15.Cu")
		(net "SSD3_PWRDIS_R")
	)
	(segment
		(start 340.819232 -236.770926)
		(end 340.995 -236.347)
		(width 0.15494)
		(layer "In15.Cu")
		(net "SSD3_PWRDIS_R")
	)
	(segment
		(start 148.09851 -229.436676)
		(end 157.249622 -229.436676)
		(width 0.15494)
		(layer "In15.Cu")
		(net "SSD3_PWRDIS_R")
	)
	(segment
		(start 230.340916 -239.940338)
		(end 230.758238 -239.523016)
		(width 0.15494)
		(layer "In15.Cu")
		(net "SSD3_PWRDIS_R")
	)
	(segment
		(start 240.71707 -239.523016)
		(end 241.655854 -240.4618)
		(width 0.15494)
		(layer "In15.Cu")
		(net "SSD3_PWRDIS_R")
	)
	(segment
		(start 219.401644 -240.3094)
		(end 219.770706 -239.940338)
		(width 0.15494)
		(layer "In15.Cu")
		(net "SSD3_PWRDIS_R")
	)
	(segment
		(start 266.089384 -237.799626)
		(end 269.205202 -240.915444)
		(width 0.15494)
		(layer "In15.Cu")
		(net "SSD3_PWRDIS_R")
	)
	(segment
		(start 275.611082 -240.915444)
		(end 276.372066 -241.676428)
		(width 0.15494)
		(layer "In15.Cu")
		(net "SSD3_PWRDIS_R")
	)
	(segment
		(start 332.364334 -240.332006)
		(end 337.258152 -240.332006)
		(width 0.15494)
		(layer "In15.Cu")
		(net "SSD3_PWRDIS_R")
	)
	(segment
		(start 215.11006 -240.3094)
		(end 219.401644 -240.3094)
		(width 0.15494)
		(layer "In15.Cu")
		(net "SSD3_PWRDIS_R")
	)
	(segment
		(start 327.031604 -242.017296)
		(end 328.009504 -242.017296)
		(width 0.15494)
		(layer "In15.Cu")
		(net "SSD3_PWRDIS_R")
	)
	(segment
		(start 214.67318 -239.87252)
		(end 215.11006 -240.3094)
		(width 0.15494)
		(layer "In15.Cu")
		(net "SSD3_PWRDIS_R")
	)
	(segment
		(start 266.089384 -236.678216)
		(end 266.089384 -237.799626)
		(width 0.15494)
		(layer "In15.Cu")
		(net "SSD3_PWRDIS_R")
	)
	(segment
		(start 157.249622 -229.436676)
		(end 161.586926 -233.77398)
		(width 0.15494)
		(layer "In15.Cu")
		(net "SSD3_PWRDIS_R")
	)
	(segment
		(start 337.258152 -240.332006)
		(end 340.819232 -236.770926)
		(width 0.15494)
		(layer "In15.Cu")
		(net "SSD3_PWRDIS_R")
	)
	(segment
		(start 219.770706 -239.940338)
		(end 230.340916 -239.940338)
		(width 0.15494)
		(layer "In15.Cu")
		(net "SSD3_PWRDIS_R")
	)
	(segment
		(start 326.644508 -242.404392)
		(end 327.031604 -242.017296)
		(width 0.15494)
		(layer "In15.Cu")
		(net "SSD3_PWRDIS_R")
	)
	(segment
		(start 269.205202 -240.915444)
		(end 275.611082 -240.915444)
		(width 0.15494)
		(layer "In15.Cu")
		(net "SSD3_PWRDIS_R")
	)
	(segment
		(start 262.101584 -233.7308)
		(end 263.877552 -234.466384)
		(width 0.15494)
		(layer "In15.Cu")
		(net "SSD3_PWRDIS_R")
	)
	(segment
		(start 254.497586 -233.487214)
		(end 257.953256 -233.487214)
		(width 0.15494)
		(layer "In15.Cu")
		(net "SSD3_PWRDIS_R")
	)
	(segment
		(start 329.08621 -240.94059)
		(end 331.75575 -240.94059)
		(width 0.15494)
		(layer "In15.Cu")
		(net "SSD3_PWRDIS_R")
	)
	(segment
		(start 241.655854 -240.4618)
		(end 247.523 -240.4618)
		(width 0.15494)
		(layer "In15.Cu")
		(net "SSD3_PWRDIS_R")
	)
	(segment
		(start 303.263808 -242.404392)
		(end 326.644508 -242.404392)
		(width 0.15494)
		(layer "In15.Cu")
		(net "SSD3_PWRDIS_R")
	)
	(segment
		(start 258.196842 -233.7308)
		(end 262.101584 -233.7308)
		(width 0.15494)
		(layer "In15.Cu")
		(net "SSD3_PWRDIS_R")
	)
	(segment
		(start 302.535844 -241.676428)
		(end 303.263808 -242.404392)
		(width 0.15494)
		(layer "In15.Cu")
		(net "SSD3_PWRDIS_R")
	)
	(segment
		(start 328.009504 -242.017296)
		(end 329.08621 -240.94059)
		(width 0.15494)
		(layer "In15.Cu")
		(net "SSD3_PWRDIS_R")
	)
	(segment
		(start 191.598804 -239.87252)
		(end 214.67318 -239.87252)
		(width 0.15494)
		(layer "In15.Cu")
		(net "SSD3_PWRDIS_R")
	)
	(segment
		(start 161.586926 -233.77398)
		(end 185.500264 -233.77398)
		(width 0.15494)
		(layer "In15.Cu")
		(net "SSD3_PWRDIS_R")
	)
	(segment
		(start 331.75575 -240.94059)
		(end 332.364334 -240.332006)
		(width 0.15494)
		(layer "In15.Cu")
		(net "SSD3_PWRDIS_R")
	)
	(segment
		(start 185.500264 -233.77398)
		(end 191.598804 -239.87252)
		(width 0.15494)
		(layer "In15.Cu")
		(net "SSD3_PWRDIS_R")
	)
	(segment
		(start 336.493866 -212.786976)
		(end 336.09407 -212.38718)
		(width 0.13208)
		(layer "F.Cu")
		(net "SSD8_CLK_EN_N")
	)
	(via
		(at 334.588104 -210.001104)
		(size 0.6604)
		(drill 0.3302)
		(layers "F.Cu" "B.Cu")
		(net "SSD8_CLK_EN_N")
	)
	(via
		(at 336.09407 -212.38718)
		(size 0.4572)
		(drill 0.254)
		(layers "F.Cu" "B.Cu")
		(net "SSD8_CLK_EN_N")
	)
	(segment
		(start 334.01 -208.17205)
		(end 334.01 -209.423)
		(width 0.13208)
		(layer "B.Cu")
		(net "SSD8_CLK_EN_N")
	)
	(segment
		(start 335.661 -211.074)
		(end 335.661 -211.95411)
		(width 0.13208)
		(layer "B.Cu")
		(net "SSD8_CLK_EN_N")
	)
	(segment
		(start 335.661 -211.95411)
		(end 336.09407 -212.38718)
		(width 0.13208)
		(layer "B.Cu")
		(net "SSD8_CLK_EN_N")
	)
	(segment
		(start 334.01 -209.423)
		(end 334.588104 -210.001104)
		(width 0.13208)
		(layer "B.Cu")
		(net "SSD8_CLK_EN_N")
	)
	(segment
		(start 334.588104 -210.001104)
		(end 335.661 -211.074)
		(width 0.13208)
		(layer "B.Cu")
		(net "SSD8_CLK_EN_N")
	)
	(segment
		(start 129.769108 -175.9839)
		(end 127.726694 -175.9839)
		(width 0.1143)
		(layer "F.Cu")
		(net "CLK_100M_DB2000QL_PEX0_S1_DN")
	)
	(segment
		(start 126.938786 -176.341024)
		(end 126.621286 -176.023524)
		(width 0.1143)
		(layer "F.Cu")
		(net "CLK_100M_DB2000QL_PEX0_S1_DN")
	)
	(segment
		(start 127.36957 -176.341024)
		(end 126.938786 -176.341024)
		(width 0.1143)
		(layer "F.Cu")
		(net "CLK_100M_DB2000QL_PEX0_S1_DN")
	)
	(segment
		(start 127.726694 -175.9839)
		(end 127.36957 -176.341024)
		(width 0.1143)
		(layer "F.Cu")
		(net "CLK_100M_DB2000QL_PEX0_S1_DN")
	)
	(segment
		(start 129.971038 -175.900334)
		(end 129.769108 -175.9839)
		(width 0.1143)
		(layer "F.Cu")
		(net "CLK_100M_DB2000QL_PEX0_S1_DN")
	)
	(segment
		(start 383.818384 -251.956824)
		(end 383.818384 -251.158502)
		(width 0.13208)
		(layer "F.Cu")
		(net "PEX3_MODE_SEL12")
	)
	(segment
		(start 414.599882 -282.599892)
		(end 415.074862 -283.074872)
		(width 0.13208)
		(layer "F.Cu")
		(net "PEX3_MODE_SEL12")
	)
	(segment
		(start 383.818384 -251.158502)
		(end 383.818384 -250.470924)
		(width 0.13208)
		(layer "F.Cu")
		(net "PEX3_MODE_SEL12")
	)
	(via
		(at 383.818384 -251.158502)
		(size 0.508)
		(drill 0.254)
		(layers "F.Cu" "B.Cu")
		(net "PEX3_MODE_SEL12")
	)
	(via
		(at 415.074862 -283.074872)
		(size 0.4064)
		(drill 0.2032)
		(layers "F.Cu" "B.Cu")
		(net "PEX3_MODE_SEL12")
	)
	(via
		(at 411.84195 -268.169898)
		(size 0.6604)
		(drill 0.3302)
		(layers "F.Cu" "B.Cu")
		(net "PEX3_MODE_SEL12")
	)
	(segment
		(start 398.54251 -254.870458)
		(end 384.408426 -254.870458)
		(width 0.13208)
		(layer "B.Cu")
		(net "PEX3_MODE_SEL12")
	)
	(segment
		(start 384.408426 -254.870458)
		(end 383.308606 -253.770638)
		(width 0.13208)
		(layer "B.Cu")
		(net "PEX3_MODE_SEL12")
	)
	(segment
		(start 411.84195 -268.169898)
		(end 398.54251 -254.870458)
		(width 0.13208)
		(layer "B.Cu")
		(net "PEX3_MODE_SEL12")
	)
	(segment
		(start 415.992564 -281.875738)
		(end 415.074862 -282.79344)
		(width 0.13208)
		(layer "B.Cu")
		(net "PEX3_MODE_SEL12")
	)
	(segment
		(start 383.308606 -251.66828)
		(end 383.818384 -251.158502)
		(width 0.13208)
		(layer "B.Cu")
		(net "PEX3_MODE_SEL12")
	)
	(segment
		(start 383.308606 -253.770638)
		(end 383.308606 -251.66828)
		(width 0.13208)
		(layer "B.Cu")
		(net "PEX3_MODE_SEL12")
	)
	(segment
		(start 415.074862 -282.79344)
		(end 415.074862 -283.074872)
		(width 0.13208)
		(layer "B.Cu")
		(net "PEX3_MODE_SEL12")
	)
	(segment
		(start 415.992564 -272.04416)
		(end 415.992564 -281.875738)
		(width 0.13208)
		(layer "B.Cu")
		(net "PEX3_MODE_SEL12")
	)
	(segment
		(start 411.84195 -268.169898)
		(end 412.118302 -268.169898)
		(width 0.13208)
		(layer "B.Cu")
		(net "PEX3_MODE_SEL12")
	)
	(segment
		(start 412.118302 -268.169898)
		(end 415.992564 -272.04416)
		(width 0.13208)
		(layer "B.Cu")
		(net "PEX3_MODE_SEL12")
	)
	(segment
		(start 210.727036 -205.77429)
		(end 210.83905 -205.886304)
		(width 0.13208)
		(layer "F.Cu")
		(net "SMB_NIC4_R_SCL")
	)
	(segment
		(start 211.1248 -206.375)
		(end 211.68868 -206.93888)
		(width 0.13208)
		(layer "F.Cu")
		(net "SMB_NIC4_R_SCL")
	)
	(segment
		(start 216.835736 -219.318586)
		(end 216.835736 -218.994482)
		(width 0.13208)
		(layer "F.Cu")
		(net "SMB_NIC4_R_SCL")
	)
	(segment
		(start 216.835736 -218.994482)
		(end 216.684606 -218.843352)
		(width 0.13208)
		(layer "F.Cu")
		(net "SMB_NIC4_R_SCL")
	)
	(segment
		(start 216.684606 -218.843352)
		(end 215.96477 -218.843352)
		(width 0.13208)
		(layer "F.Cu")
		(net "SMB_NIC4_R_SCL")
	)
	(segment
		(start 211.68868 -206.93888)
		(end 212.522054 -206.93888)
		(width 0.13208)
		(layer "F.Cu")
		(net "SMB_NIC4_R_SCL")
	)
	(segment
		(start 207.899 -205.77429)
		(end 210.727036 -205.77429)
		(width 0.13208)
		(layer "F.Cu")
		(net "SMB_NIC4_R_SCL")
	)
	(segment
		(start 210.83905 -206.375)
		(end 211.1248 -206.375)
		(width 0.13208)
		(layer "F.Cu")
		(net "SMB_NIC4_R_SCL")
	)
	(segment
		(start 215.96477 -218.843352)
		(end 215.489536 -219.318586)
		(width 0.13208)
		(layer "F.Cu")
		(net "SMB_NIC4_R_SCL")
	)
	(segment
		(start 210.83905 -205.886304)
		(end 210.83905 -206.375)
		(width 0.13208)
		(layer "F.Cu")
		(net "SMB_NIC4_R_SCL")
	)
	(via
		(at 207.899 -205.77429)
		(size 0.508)
		(drill 0.254)
		(layers "F.Cu" "B.Cu")
		(net "SMB_NIC4_R_SCL")
	)
	(via
		(at 215.489536 -219.318586)
		(size 0.508)
		(drill 0.254)
		(layers "F.Cu" "B.Cu")
		(net "SMB_NIC4_R_SCL")
	)
	(segment
		(start 211.09305 -206.52105)
		(end 212.09 -206.52105)
		(width 0.13208)
		(layer "B.Cu")
		(net "SMB_NIC4_R_SCL")
	)
	(segment
		(start 207.899 -205.77429)
		(end 210.34629 -205.77429)
		(width 0.13208)
		(layer "B.Cu")
		(net "SMB_NIC4_R_SCL")
	)
	(segment
		(start 210.34629 -205.77429)
		(end 211.09305 -206.52105)
		(width 0.13208)
		(layer "B.Cu")
		(net "SMB_NIC4_R_SCL")
	)
	(segment
		(start 208.38287 -206.25816)
		(end 207.899 -205.77429)
		(width 0.15494)
		(layer "In7.Cu")
		(net "SMB_NIC4_R_SCL")
	)
	(segment
		(start 211.661502 -218.784424)
		(end 210.785202 -218.784424)
		(width 0.15494)
		(layer "In7.Cu")
		(net "SMB_NIC4_R_SCL")
	)
	(segment
		(start 210.785202 -218.784424)
		(end 209.297778 -217.297)
		(width 0.15494)
		(layer "In7.Cu")
		(net "SMB_NIC4_R_SCL")
	)
	(segment
		(start 208.2546 -211.404454)
		(end 208.38287 -211.276184)
		(width 0.15494)
		(layer "In7.Cu")
		(net "SMB_NIC4_R_SCL")
	)
	(segment
		(start 208.38287 -211.276184)
		(end 208.38287 -206.25816)
		(width 0.15494)
		(layer "In7.Cu")
		(net "SMB_NIC4_R_SCL")
	)
	(segment
		(start 215.489536 -219.612718)
		(end 215.309958 -219.792296)
		(width 0.15494)
		(layer "In7.Cu")
		(net "SMB_NIC4_R_SCL")
	)
	(segment
		(start 209.042 -217.297)
		(end 208.2546 -216.5096)
		(width 0.15494)
		(layer "In7.Cu")
		(net "SMB_NIC4_R_SCL")
	)
	(segment
		(start 209.297778 -217.297)
		(end 209.042 -217.297)
		(width 0.15494)
		(layer "In7.Cu")
		(net "SMB_NIC4_R_SCL")
	)
	(segment
		(start 212.669374 -219.792296)
		(end 211.661502 -218.784424)
		(width 0.15494)
		(layer "In7.Cu")
		(net "SMB_NIC4_R_SCL")
	)
	(segment
		(start 215.309958 -219.792296)
		(end 212.669374 -219.792296)
		(width 0.15494)
		(layer "In7.Cu")
		(net "SMB_NIC4_R_SCL")
	)
	(segment
		(start 215.489536 -219.318586)
		(end 215.489536 -219.612718)
		(width 0.15494)
		(layer "In7.Cu")
		(net "SMB_NIC4_R_SCL")
	)
	(segment
		(start 208.2546 -216.5096)
		(end 208.2546 -211.404454)
		(width 0.15494)
		(layer "In7.Cu")
		(net "SMB_NIC4_R_SCL")
	)
	(segment
		(start 148.270468 -392.35634)
		(end 148.270468 -391.585196)
		(width 0.13208)
		(layer "F.Cu")
		(net "GPU_BASE_STBY_EN")
	)
	(segment
		(start 148.287486 -390.798304)
		(end 148.287486 -391.568178)
		(width 0.13208)
		(layer "F.Cu")
		(net "GPU_BASE_STBY_EN")
	)
	(segment
		(start 148.270468 -391.585196)
		(end 148.287486 -391.568178)
		(width 0.13208)
		(layer "F.Cu")
		(net "GPU_BASE_STBY_EN")
	)
	(via
		(at 148.287486 -391.568178)
		(size 0.508)
		(drill 0.254)
		(layers "F.Cu" "B.Cu")
		(net "GPU_BASE_STBY_EN")
	)
	(segment
		(start 129.109978 -412.090108)
		(end 130.17627 -413.1564)
		(width 0.15494)
		(layer "In9.Cu")
		(net "GPU_BASE_STBY_EN")
	)
	(segment
		(start 148.287486 -392.42873)
		(end 148.287486 -391.568178)
		(width 0.15494)
		(layer "In9.Cu")
		(net "GPU_BASE_STBY_EN")
	)
	(segment
		(start 139.517628 -409.823158)
		(end 139.517628 -393.729718)
		(width 0.15494)
		(layer "In9.Cu")
		(net "GPU_BASE_STBY_EN")
	)
	(segment
		(start 130.17627 -413.1564)
		(end 136.184386 -413.1564)
		(width 0.15494)
		(layer "In9.Cu")
		(net "GPU_BASE_STBY_EN")
	)
	(segment
		(start 139.517628 -393.729718)
		(end 140.385546 -392.8618)
		(width 0.15494)
		(layer "In9.Cu")
		(net "GPU_BASE_STBY_EN")
	)
	(segment
		(start 136.184386 -413.1564)
		(end 139.517628 -409.823158)
		(width 0.15494)
		(layer "In9.Cu")
		(net "GPU_BASE_STBY_EN")
	)
	(segment
		(start 147.854416 -392.8618)
		(end 148.287486 -392.42873)
		(width 0.15494)
		(layer "In9.Cu")
		(net "GPU_BASE_STBY_EN")
	)
	(segment
		(start 140.385546 -392.8618)
		(end 147.854416 -392.8618)
		(width 0.15494)
		(layer "In9.Cu")
		(net "GPU_BASE_STBY_EN")
	)
	(segment
		(start 372.277132 -255.992376)
		(end 372.277132 -255.688592)
		(width 0.13208)
		(layer "F.Cu")
		(net "LED_PEX3_SYS_ERR_N")
	)
	(segment
		(start 373.033544 -256.748788)
		(end 372.277132 -255.992376)
		(width 0.13208)
		(layer "F.Cu")
		(net "LED_PEX3_SYS_ERR_N")
	)
	(segment
		(start 373.092726 -256.748788)
		(end 373.033544 -256.748788)
		(width 0.13208)
		(layer "F.Cu")
		(net "LED_PEX3_SYS_ERR_N")
	)
	(segment
		(start 372.277132 -255.688592)
		(end 372.277132 -254.850646)
		(width 0.13208)
		(layer "F.Cu")
		(net "LED_PEX3_SYS_ERR_N")
	)
	(via
		(at 372.277132 -255.688592)
		(size 0.508)
		(drill 0.254)
		(layers "F.Cu" "B.Cu")
		(net "LED_PEX3_SYS_ERR_N")
	)
	(segment
		(start 407.416 -385.826)
		(end 407.035 -385.826)
		(width 0.13208)
		(layer "F.Cu")
		(net "I3C_MB_BMC_SCL")
	)
	(segment
		(start 407.035 -385.826)
		(end 405.892 -384.683)
		(width 0.13208)
		(layer "F.Cu")
		(net "I3C_MB_BMC_SCL")
	)
	(segment
		(start 405.892 -384.683)
		(end 405.892 -384.06705)
		(width 0.13208)
		(layer "F.Cu")
		(net "I3C_MB_BMC_SCL")
	)
	(via
		(at 407.416 -385.826)
		(size 0.508)
		(drill 0.254)
		(layers "F.Cu" "B.Cu")
		(net "I3C_MB_BMC_SCL")
	)
	(segment
		(start 407.416 -386.989828)
		(end 405.60752 -388.798308)
		(width 0.15494)
		(layer "In9.Cu")
		(net "I3C_MB_BMC_SCL")
	)
	(segment
		(start 395.523212 -405.952706)
		(end 393.452604 -405.952706)
		(width 0.15494)
		(layer "In9.Cu")
		(net "I3C_MB_BMC_SCL")
	)
	(segment
		(start 398.082008 -403.39391)
		(end 395.523212 -405.952706)
		(width 0.15494)
		(layer "In9.Cu")
		(net "I3C_MB_BMC_SCL")
	)
	(segment
		(start 403.48662 -388.798308)
		(end 398.082008 -394.20292)
		(width 0.15494)
		(layer "In9.Cu")
		(net "I3C_MB_BMC_SCL")
	)
	(segment
		(start 407.416 -385.826)
		(end 407.416 -386.989828)
		(width 0.15494)
		(layer "In9.Cu")
		(net "I3C_MB_BMC_SCL")
	)
	(segment
		(start 393.452604 -405.952706)
		(end 393.089892 -405.589994)
		(width 0.15494)
		(layer "In9.Cu")
		(net "I3C_MB_BMC_SCL")
	)
	(segment
		(start 405.60752 -388.798308)
		(end 403.48662 -388.798308)
		(width 0.15494)
		(layer "In9.Cu")
		(net "I3C_MB_BMC_SCL")
	)
	(segment
		(start 398.082008 -394.20292)
		(end 398.082008 -403.39391)
		(width 0.15494)
		(layer "In9.Cu")
		(net "I3C_MB_BMC_SCL")
	)
	(segment
		(start 85.10905 -27.04973)
		(end 86.103714 -27.04973)
		(width 0.13208)
		(layer "F.Cu")
		(net "PRSNT_SSD3_R_N")
	)
	(segment
		(start 86.120478 -27.066494)
		(end 86.942422 -27.066494)
		(width 0.13208)
		(layer "F.Cu")
		(net "PRSNT_SSD3_R_N")
	)
	(segment
		(start 86.103714 -27.04973)
		(end 86.120478 -27.066494)
		(width 0.13208)
		(layer "F.Cu")
		(net "PRSNT_SSD3_R_N")
	)
	(segment
		(start 84.57565 -36.515548)
		(end 85.39607 -36.515548)
		(width 0.13208)
		(layer "F.Cu")
		(net "PRSNT_SSD3_R_N")
	)
	(segment
		(start 343.69375 -223.987106)
		(end 344.093546 -224.386902)
		(width 0.13208)
		(layer "F.Cu")
		(net "PRSNT_SSD3_R_N")
	)
	(segment
		(start 85.10905 -26.03373)
		(end 85.10905 -27.04973)
		(width 0.13208)
		(layer "F.Cu")
		(net "PRSNT_SSD3_R_N")
	)
	(segment
		(start 233.867706 -224.704148)
		(end 234.267502 -225.103944)
		(width 0.13208)
		(layer "F.Cu")
		(net "PRSNT_SSD3_R_N")
	)
	(via
		(at 243.935504 -99.772978)
		(size 0.508)
		(drill 0.254)
		(layers "F.Cu" "B.Cu")
		(net "PRSNT_SSD3_R_N")
	)
	(via
		(at 85.39607 -36.515548)
		(size 0.508)
		(drill 0.254)
		(layers "F.Cu" "B.Cu")
		(net "PRSNT_SSD3_R_N")
	)
	(via
		(at 86.942422 -27.066494)
		(size 0.508)
		(drill 0.254)
		(layers "F.Cu" "B.Cu")
		(net "PRSNT_SSD3_R_N")
	)
	(via
		(at 119.582184 -100.226368)
		(size 0.508)
		(drill 0.254)
		(layers "F.Cu" "B.Cu")
		(net "PRSNT_SSD3_R_N")
	)
	(via
		(at 234.267502 -225.103944)
		(size 0.4572)
		(drill 0.254)
		(layers "F.Cu" "B.Cu")
		(net "PRSNT_SSD3_R_N")
	)
	(via
		(at 344.093546 -224.386902)
		(size 0.4572)
		(drill 0.254)
		(layers "F.Cu" "B.Cu")
		(net "PRSNT_SSD3_R_N")
	)
	(segment
		(start 121.621042 -84.38007)
		(end 116.775484 -79.534512)
		(width 0.15494)
		(layer "In5.Cu")
		(net "PRSNT_SSD3_R_N")
	)
	(segment
		(start 121.621042 -99.667822)
		(end 121.621042 -84.38007)
		(width 0.15494)
		(layer "In5.Cu")
		(net "PRSNT_SSD3_R_N")
	)
	(segment
		(start 91.3384 -44.99737)
		(end 85.405976 -39.064946)
		(width 0.15494)
		(layer "In5.Cu")
		(net "PRSNT_SSD3_R_N")
	)
	(segment
		(start 85.405976 -39.064946)
		(end 85.405976 -36.525454)
		(width 0.15494)
		(layer "In5.Cu")
		(net "PRSNT_SSD3_R_N")
	)
	(segment
		(start 91.3384 -73.18248)
		(end 91.3384 -44.99737)
		(width 0.15494)
		(layer "In5.Cu")
		(net "PRSNT_SSD3_R_N")
	)
	(segment
		(start 86.439248 -27.066494)
		(end 83.763358 -29.742384)
		(width 0.15494)
		(layer "In5.Cu")
		(net "PRSNT_SSD3_R_N")
	)
	(segment
		(start 86.942422 -27.066494)
		(end 86.439248 -27.066494)
		(width 0.15494)
		(layer "In5.Cu")
		(net "PRSNT_SSD3_R_N")
	)
	(segment
		(start 91.765374 -73.609454)
		(end 91.3384 -73.18248)
		(width 0.15494)
		(layer "In5.Cu")
		(net "PRSNT_SSD3_R_N")
	)
	(segment
		(start 91.765374 -76.034392)
		(end 91.765374 -73.609454)
		(width 0.15494)
		(layer "In5.Cu")
		(net "PRSNT_SSD3_R_N")
	)
	(segment
		(start 121.062496 -100.226368)
		(end 121.621042 -99.667822)
		(width 0.15494)
		(layer "In5.Cu")
		(net "PRSNT_SSD3_R_N")
	)
	(segment
		(start 94.317566 -78.586584)
		(end 91.765374 -76.034392)
		(width 0.15494)
		(layer "In5.Cu")
		(net "PRSNT_SSD3_R_N")
	)
	(segment
		(start 83.763358 -29.742384)
		(end 83.763358 -34.882836)
		(width 0.15494)
		(layer "In5.Cu")
		(net "PRSNT_SSD3_R_N")
	)
	(segment
		(start 119.582184 -100.226368)
		(end 121.062496 -100.226368)
		(width 0.15494)
		(layer "In5.Cu")
		(net "PRSNT_SSD3_R_N")
	)
	(segment
		(start 85.405976 -36.525454)
		(end 85.39607 -36.515548)
		(width 0.15494)
		(layer "In5.Cu")
		(net "PRSNT_SSD3_R_N")
	)
	(segment
		(start 106.29011 -79.534512)
		(end 105.342182 -78.586584)
		(width 0.15494)
		(layer "In5.Cu")
		(net "PRSNT_SSD3_R_N")
	)
	(segment
		(start 83.763358 -34.882836)
		(end 85.39607 -36.515548)
		(width 0.15494)
		(layer "In5.Cu")
		(net "PRSNT_SSD3_R_N")
	)
	(segment
		(start 116.775484 -79.534512)
		(end 106.29011 -79.534512)
		(width 0.15494)
		(layer "In5.Cu")
		(net "PRSNT_SSD3_R_N")
	)
	(segment
		(start 105.342182 -78.586584)
		(end 94.317566 -78.586584)
		(width 0.15494)
		(layer "In5.Cu")
		(net "PRSNT_SSD3_R_N")
	)
	(segment
		(start 249.5804 -202.920346)
		(end 249.5804 -202.953366)
		(width 0.15494)
		(layer "In7.Cu")
		(net "PRSNT_SSD3_R_N")
	)
	(segment
		(start 235.585 -169.545254)
		(end 236.154976 -170.11523)
		(width 0.15494)
		(layer "In7.Cu")
		(net "PRSNT_SSD3_R_N")
	)
	(segment
		(start 252.5522 -181.113176)
		(end 252.5522 -199.948546)
		(width 0.15494)
		(layer "In7.Cu")
		(net "PRSNT_SSD3_R_N")
	)
	(segment
		(start 249.3264 -213.0298)
		(end 248.41454 -213.94166)
		(width 0.15494)
		(layer "In7.Cu")
		(net "PRSNT_SSD3_R_N")
	)
	(segment
		(start 249.57786 -202.955906)
		(end 249.57786 -204.647038)
		(width 0.15494)
		(layer "In7.Cu")
		(net "PRSNT_SSD3_R_N")
	)
	(segment
		(start 247.227852 -213.9442)
		(end 244.856762 -216.31529)
		(width 0.15494)
		(layer "In7.Cu")
		(net "PRSNT_SSD3_R_N")
	)
	(segment
		(start 249.57786 -204.647038)
		(end 247.82526 -206.399638)
		(width 0.15494)
		(layer "In7.Cu")
		(net "PRSNT_SSD3_R_N")
	)
	(segment
		(start 247.4849 -209.1055)
		(end 248.3104 -209.931)
		(width 0.15494)
		(layer "In7.Cu")
		(net "PRSNT_SSD3_R_N")
	)
	(segment
		(start 235.6866 -168.275)
		(end 235.585 -168.3766)
		(width 0.15494)
		(layer "In7.Cu")
		(net "PRSNT_SSD3_R_N")
	)
	(segment
		(start 247.818402 -207.935068)
		(end 247.4849 -208.26857)
		(width 0.15494)
		(layer "In7.Cu")
		(net "PRSNT_SSD3_R_N")
	)
	(segment
		(start 247.82526 -206.399638)
		(end 247.82526 -207.318864)
		(width 0.15494)
		(layer "In7.Cu")
		(net "PRSNT_SSD3_R_N")
	)
	(segment
		(start 247.358916 -213.9442)
		(end 247.227852 -213.9442)
		(width 0.15494)
		(layer "In7.Cu")
		(net "PRSNT_SSD3_R_N")
	)
	(segment
		(start 236.165898 -226.449382)
		(end 235.61294 -226.449382)
		(width 0.15494)
		(layer "In7.Cu")
		(net "PRSNT_SSD3_R_N")
	)
	(segment
		(start 252.5522 -199.948546)
		(end 249.5804 -202.920346)
		(width 0.15494)
		(layer "In7.Cu")
		(net "PRSNT_SSD3_R_N")
	)
	(segment
		(start 236.154976 -170.11523)
		(end 241.554254 -170.11523)
		(width 0.15494)
		(layer "In7.Cu")
		(net "PRSNT_SSD3_R_N")
	)
	(segment
		(start 243.205 -119.38)
		(end 242.7224 -119.38)
		(width 0.15494)
		(layer "In7.Cu")
		(net "PRSNT_SSD3_R_N")
	)
	(segment
		(start 240.92662 -226.955858)
		(end 236.672374 -226.955858)
		(width 0.15494)
		(layer "In7.Cu")
		(net "PRSNT_SSD3_R_N")
	)
	(segment
		(start 248.41454 -213.94166)
		(end 247.361456 -213.94166)
		(width 0.15494)
		(layer "In7.Cu")
		(net "PRSNT_SSD3_R_N")
	)
	(segment
		(start 247.818402 -207.325722)
		(end 247.818402 -207.935068)
		(width 0.15494)
		(layer "In7.Cu")
		(net "PRSNT_SSD3_R_N")
	)
	(segment
		(start 247.361456 -213.94166)
		(end 247.358916 -213.9442)
		(width 0.15494)
		(layer "In7.Cu")
		(net "PRSNT_SSD3_R_N")
	)
	(segment
		(start 243.935504 -118.649496)
		(end 243.205 -119.38)
		(width 0.15494)
		(layer "In7.Cu")
		(net "PRSNT_SSD3_R_N")
	)
	(segment
		(start 236.672374 -226.955858)
		(end 236.165898 -226.449382)
		(width 0.15494)
		(layer "In7.Cu")
		(net "PRSNT_SSD3_R_N")
	)
	(segment
		(start 241.554254 -170.11523)
		(end 252.5522 -181.113176)
		(width 0.15494)
		(layer "In7.Cu")
		(net "PRSNT_SSD3_R_N")
	)
	(segment
		(start 244.856762 -223.025716)
		(end 240.92662 -226.955858)
		(width 0.15494)
		(layer "In7.Cu")
		(net "PRSNT_SSD3_R_N")
	)
	(segment
		(start 235.6866 -126.4158)
		(end 235.6866 -168.275)
		(width 0.15494)
		(layer "In7.Cu")
		(net "PRSNT_SSD3_R_N")
	)
	(segment
		(start 248.3104 -209.931)
		(end 248.92 -209.931)
		(width 0.15494)
		(layer "In7.Cu")
		(net "PRSNT_SSD3_R_N")
	)
	(segment
		(start 242.7224 -119.38)
		(end 235.6866 -126.4158)
		(width 0.15494)
		(layer "In7.Cu")
		(net "PRSNT_SSD3_R_N")
	)
	(segment
		(start 248.92 -209.931)
		(end 249.3264 -210.3374)
		(width 0.15494)
		(layer "In7.Cu")
		(net "PRSNT_SSD3_R_N")
	)
	(segment
		(start 235.585 -168.3766)
		(end 235.585 -169.545254)
		(width 0.15494)
		(layer "In7.Cu")
		(net "PRSNT_SSD3_R_N")
	)
	(segment
		(start 244.856762 -216.31529)
		(end 244.856762 -223.025716)
		(width 0.15494)
		(layer "In7.Cu")
		(net "PRSNT_SSD3_R_N")
	)
	(segment
		(start 249.5804 -202.953366)
		(end 249.57786 -202.955906)
		(width 0.15494)
		(layer "In7.Cu")
		(net "PRSNT_SSD3_R_N")
	)
	(segment
		(start 247.82526 -207.318864)
		(end 247.818402 -207.325722)
		(width 0.15494)
		(layer "In7.Cu")
		(net "PRSNT_SSD3_R_N")
	)
	(segment
		(start 249.3264 -210.3374)
		(end 249.3264 -213.0298)
		(width 0.15494)
		(layer "In7.Cu")
		(net "PRSNT_SSD3_R_N")
	)
	(segment
		(start 235.61294 -226.449382)
		(end 234.267502 -225.103944)
		(width 0.15494)
		(layer "In7.Cu")
		(net "PRSNT_SSD3_R_N")
	)
	(segment
		(start 243.935504 -99.772978)
		(end 243.935504 -118.649496)
		(width 0.15494)
		(layer "In7.Cu")
		(net "PRSNT_SSD3_R_N")
	)
	(segment
		(start 247.4849 -208.26857)
		(end 247.4849 -209.1055)
		(width 0.15494)
		(layer "In7.Cu")
		(net "PRSNT_SSD3_R_N")
	)
	(segment
		(start 317.83147 -237.109)
		(end 329.216004 -237.109)
		(width 0.15494)
		(layer "In13.Cu")
		(net "PRSNT_SSD3_R_N")
	)
	(segment
		(start 258.280408 -230.714296)
		(end 258.695952 -231.12984)
		(width 0.15494)
		(layer "In13.Cu")
		(net "PRSNT_SSD3_R_N")
	)
	(segment
		(start 236.703616 -229.286054)
		(end 237.620556 -230.202994)
		(width 0.15494)
		(layer "In13.Cu")
		(net "PRSNT_SSD3_R_N")
	)
	(segment
		(start 344.491056 -230.920798)
		(end 344.491056 -227.1522)
		(width 0.15494)
		(layer "In13.Cu")
		(net "PRSNT_SSD3_R_N")
	)
	(segment
		(start 329.216004 -237.109)
		(end 329.894184 -236.43082)
		(width 0.15494)
		(layer "In13.Cu")
		(net "PRSNT_SSD3_R_N")
	)
	(segment
		(start 344.491056 -224.784412)
		(end 344.093546 -224.386902)
		(width 0.0889)
		(layer "In13.Cu")
		(net "PRSNT_SSD3_R_N")
	)
	(segment
		(start 244.884448 -230.202994)
		(end 246.07901 -231.397556)
		(width 0.15494)
		(layer "In13.Cu")
		(net "PRSNT_SSD3_R_N")
	)
	(segment
		(start 335.6864 -234.90301)
		(end 337.31581 -233.2736)
		(width 0.15494)
		(layer "In13.Cu")
		(net "PRSNT_SSD3_R_N")
	)
	(segment
		(start 247.4976 -231.985566)
		(end 255.769364 -231.985566)
		(width 0.15494)
		(layer "In13.Cu")
		(net "PRSNT_SSD3_R_N")
	)
	(segment
		(start 340.106 -233.2736)
		(end 341.3506 -232.029)
		(width 0.15494)
		(layer "In13.Cu")
		(net "PRSNT_SSD3_R_N")
	)
	(segment
		(start 246.07901 -231.397556)
		(end 247.4976 -231.985566)
		(width 0.15494)
		(layer "In13.Cu")
		(net "PRSNT_SSD3_R_N")
	)
	(segment
		(start 272.35531 -231.12984)
		(end 277.128224 -235.902754)
		(width 0.15494)
		(layer "In13.Cu")
		(net "PRSNT_SSD3_R_N")
	)
	(segment
		(start 316.625224 -235.902754)
		(end 317.83147 -237.109)
		(width 0.15494)
		(layer "In13.Cu")
		(net "PRSNT_SSD3_R_N")
	)
	(segment
		(start 343.382854 -232.029)
		(end 344.491056 -230.920798)
		(width 0.15494)
		(layer "In13.Cu")
		(net "PRSNT_SSD3_R_N")
	)
	(segment
		(start 257.040634 -230.714296)
		(end 258.280408 -230.714296)
		(width 0.15494)
		(layer "In13.Cu")
		(net "PRSNT_SSD3_R_N")
	)
	(segment
		(start 237.620556 -230.202994)
		(end 244.884448 -230.202994)
		(width 0.15494)
		(layer "In13.Cu")
		(net "PRSNT_SSD3_R_N")
	)
	(segment
		(start 235.82376 -229.286054)
		(end 236.703616 -229.286054)
		(width 0.15494)
		(layer "In13.Cu")
		(net "PRSNT_SSD3_R_N")
	)
	(segment
		(start 344.491056 -227.1522)
		(end 344.491056 -224.784412)
		(width 0.0889)
		(layer "In13.Cu")
		(net "PRSNT_SSD3_R_N")
	)
	(segment
		(start 255.769364 -231.985566)
		(end 257.040634 -230.714296)
		(width 0.15494)
		(layer "In13.Cu")
		(net "PRSNT_SSD3_R_N")
	)
	(segment
		(start 234.267502 -225.103944)
		(end 234.267502 -227.729796)
		(width 0.15494)
		(layer "In13.Cu")
		(net "PRSNT_SSD3_R_N")
	)
	(segment
		(start 337.31581 -233.2736)
		(end 340.106 -233.2736)
		(width 0.15494)
		(layer "In13.Cu")
		(net "PRSNT_SSD3_R_N")
	)
	(segment
		(start 329.894184 -236.43082)
		(end 334.68818 -236.43082)
		(width 0.15494)
		(layer "In13.Cu")
		(net "PRSNT_SSD3_R_N")
	)
	(segment
		(start 234.267502 -227.729796)
		(end 235.82376 -229.286054)
		(width 0.15494)
		(layer "In13.Cu")
		(net "PRSNT_SSD3_R_N")
	)
	(segment
		(start 334.68818 -236.43082)
		(end 335.6864 -235.4326)
		(width 0.15494)
		(layer "In13.Cu")
		(net "PRSNT_SSD3_R_N")
	)
	(segment
		(start 335.6864 -235.4326)
		(end 335.6864 -234.90301)
		(width 0.15494)
		(layer "In13.Cu")
		(net "PRSNT_SSD3_R_N")
	)
	(segment
		(start 277.128224 -235.902754)
		(end 316.625224 -235.902754)
		(width 0.15494)
		(layer "In13.Cu")
		(net "PRSNT_SSD3_R_N")
	)
	(segment
		(start 258.695952 -231.12984)
		(end 272.35531 -231.12984)
		(width 0.15494)
		(layer "In13.Cu")
		(net "PRSNT_SSD3_R_N")
	)
	(segment
		(start 341.3506 -232.029)
		(end 343.382854 -232.029)
		(width 0.15494)
		(layer "In13.Cu")
		(net "PRSNT_SSD3_R_N")
	)
	(segment
		(start 226.742752 -97.930462)
		(end 227.75164 -98.93935)
		(width 0.15494)
		(layer "In15.Cu")
		(net "PRSNT_SSD3_R_N")
	)
	(segment
		(start 212.242146 -92.4306)
		(end 213.410546 -93.599)
		(width 0.15494)
		(layer "In15.Cu")
		(net "PRSNT_SSD3_R_N")
	)
	(segment
		(start 194.642232 -92.4306)
		(end 212.242146 -92.4306)
		(width 0.15494)
		(layer "In15.Cu")
		(net "PRSNT_SSD3_R_N")
	)
	(segment
		(start 233.219752 -99.09556)
		(end 233.89717 -99.772978)
		(width 0.15494)
		(layer "In15.Cu")
		(net "PRSNT_SSD3_R_N")
	)
	(segment
		(start 221.931484 -94.75343)
		(end 221.931484 -95.606616)
		(width 0.15494)
		(layer "In15.Cu")
		(net "PRSNT_SSD3_R_N")
	)
	(segment
		(start 227.765102 -98.93935)
		(end 227.921312 -99.09556)
		(width 0.15494)
		(layer "In15.Cu")
		(net "PRSNT_SSD3_R_N")
	)
	(segment
		(start 144.35074 -101.648006)
		(end 156.200856 -89.79789)
		(width 0.15494)
		(layer "In15.Cu")
		(net "PRSNT_SSD3_R_N")
	)
	(segment
		(start 223.220026 -96.895158)
		(end 223.220026 -97.540572)
		(width 0.15494)
		(layer "In15.Cu")
		(net "PRSNT_SSD3_R_N")
	)
	(segment
		(start 227.75164 -98.93935)
		(end 227.765102 -98.93935)
		(width 0.15494)
		(layer "In15.Cu")
		(net "PRSNT_SSD3_R_N")
	)
	(segment
		(start 220.777054 -93.599)
		(end 221.931484 -94.75343)
		(width 0.15494)
		(layer "In15.Cu")
		(net "PRSNT_SSD3_R_N")
	)
	(segment
		(start 192.009522 -89.79789)
		(end 194.642232 -92.4306)
		(width 0.15494)
		(layer "In15.Cu")
		(net "PRSNT_SSD3_R_N")
	)
	(segment
		(start 233.89717 -99.772978)
		(end 243.935504 -99.772978)
		(width 0.15494)
		(layer "In15.Cu")
		(net "PRSNT_SSD3_R_N")
	)
	(segment
		(start 213.410546 -93.599)
		(end 220.777054 -93.599)
		(width 0.15494)
		(layer "In15.Cu")
		(net "PRSNT_SSD3_R_N")
	)
	(segment
		(start 156.200856 -89.79789)
		(end 192.009522 -89.79789)
		(width 0.15494)
		(layer "In15.Cu")
		(net "PRSNT_SSD3_R_N")
	)
	(segment
		(start 227.921312 -99.09556)
		(end 233.219752 -99.09556)
		(width 0.15494)
		(layer "In15.Cu")
		(net "PRSNT_SSD3_R_N")
	)
	(segment
		(start 221.931484 -95.606616)
		(end 223.220026 -96.895158)
		(width 0.15494)
		(layer "In15.Cu")
		(net "PRSNT_SSD3_R_N")
	)
	(segment
		(start 223.220026 -97.540572)
		(end 223.609916 -97.930462)
		(width 0.15494)
		(layer "In15.Cu")
		(net "PRSNT_SSD3_R_N")
	)
	(segment
		(start 223.609916 -97.930462)
		(end 226.742752 -97.930462)
		(width 0.15494)
		(layer "In15.Cu")
		(net "PRSNT_SSD3_R_N")
	)
	(segment
		(start 119.582184 -100.226368)
		(end 121.003822 -101.648006)
		(width 0.15494)
		(layer "In15.Cu")
		(net "PRSNT_SSD3_R_N")
	)
	(segment
		(start 121.003822 -101.648006)
		(end 144.35074 -101.648006)
		(width 0.15494)
		(layer "In15.Cu")
		(net "PRSNT_SSD3_R_N")
	)
	(segment
		(start 266.810998 -61.386974)
		(end 266.810998 -62.051438)
		(width 0.13208)
		(layer "F.Cu")
		(net "PWRGD_P3V3_SSD9_R")
	)
	(segment
		(start 259.795264 -36.232592)
		(end 259.447792 -36.232592)
		(width 0.13208)
		(layer "F.Cu")
		(net "PWRGD_P3V3_SSD9_R")
	)
	(segment
		(start 255.370838 -35.876738)
		(end 254.627888 -35.876738)
		(width 0.13208)
		(layer "F.Cu")
		(net "PWRGD_P3V3_SSD9_R")
	)
	(segment
		(start 256.082038 -35.876738)
		(end 255.370838 -35.876738)
		(width 0.13208)
		(layer "F.Cu")
		(net "PWRGD_P3V3_SSD9_R")
	)
	(segment
		(start 336.493866 -211.18703)
		(end 336.09407 -210.787234)
		(width 0.13208)
		(layer "F.Cu")
		(net "PWRGD_P3V3_SSD9_R")
	)
	(segment
		(start 258.8768 -35.6616)
		(end 256.297176 -35.6616)
		(width 0.13208)
		(layer "F.Cu")
		(net "PWRGD_P3V3_SSD9_R")
	)
	(segment
		(start 256.297176 -35.6616)
		(end 256.082038 -35.876738)
		(width 0.13208)
		(layer "F.Cu")
		(net "PWRGD_P3V3_SSD9_R")
	)
	(segment
		(start 259.447792 -36.232592)
		(end 258.8768 -35.6616)
		(width 0.13208)
		(layer "F.Cu")
		(net "PWRGD_P3V3_SSD9_R")
	)
	(via
		(at 255.370838 -35.876738)
		(size 0.508)
		(drill 0.254)
		(layers "F.Cu" "B.Cu")
		(net "PWRGD_P3V3_SSD9_R")
	)
	(via
		(at 274.903438 -86.55558)
		(size 0.508)
		(drill 0.254)
		(layers "F.Cu" "B.Cu")
		(net "PWRGD_P3V3_SSD9_R")
	)
	(via
		(at 309.162958 -93.96095)
		(size 0.508)
		(drill 0.254)
		(layers "F.Cu" "B.Cu")
		(net "PWRGD_P3V3_SSD9_R")
	)
	(via
		(at 336.09407 -210.787234)
		(size 0.4572)
		(drill 0.254)
		(layers "F.Cu" "B.Cu")
		(net "PWRGD_P3V3_SSD9_R")
	)
	(via
		(at 266.810998 -62.051438)
		(size 0.508)
		(drill 0.254)
		(layers "F.Cu" "B.Cu")
		(net "PWRGD_P3V3_SSD9_R")
	)
	(segment
		(start 328.988166 -208.002378)
		(end 326.67321 -205.687422)
		(width 0.15494)
		(layer "In5.Cu")
		(net "PWRGD_P3V3_SSD9_R")
	)
	(segment
		(start 336.09407 -210.217258)
		(end 333.152242 -207.27543)
		(width 0.15494)
		(layer "In5.Cu")
		(net "PWRGD_P3V3_SSD9_R")
	)
	(segment
		(start 331.198474 -159.700722)
		(end 332.079854 -158.819342)
		(width 0.15494)
		(layer "In5.Cu")
		(net "PWRGD_P3V3_SSD9_R")
	)
	(segment
		(start 331.989938 -208.002378)
		(end 328.988166 -208.002378)
		(width 0.15494)
		(layer "In5.Cu")
		(net "PWRGD_P3V3_SSD9_R")
	)
	(segment
		(start 332.079854 -158.819342)
		(end 332.079854 -144.018508)
		(width 0.15494)
		(layer "In5.Cu")
		(net "PWRGD_P3V3_SSD9_R")
	)
	(segment
		(start 309.818278 -105.194608)
		(end 309.818278 -95.18015)
		(width 0.15494)
		(layer "In5.Cu")
		(net "PWRGD_P3V3_SSD9_R")
	)
	(segment
		(start 331.198474 -189.196472)
		(end 331.198474 -159.700722)
		(width 0.15494)
		(layer "In5.Cu")
		(net "PWRGD_P3V3_SSD9_R")
	)
	(segment
		(start 332.716886 -207.27543)
		(end 331.989938 -208.002378)
		(width 0.15494)
		(layer "In5.Cu")
		(net "PWRGD_P3V3_SSD9_R")
	)
	(segment
		(start 310.352694 -121.416826)
		(end 310.352694 -105.729024)
		(width 0.15494)
		(layer "In5.Cu")
		(net "PWRGD_P3V3_SSD9_R")
	)
	(segment
		(start 266.810998 -62.051438)
		(end 268.005052 -63.245492)
		(width 0.15494)
		(layer "In5.Cu")
		(net "PWRGD_P3V3_SSD9_R")
	)
	(segment
		(start 273.322542 -86.55558)
		(end 274.903438 -86.55558)
		(width 0.15494)
		(layer "In5.Cu")
		(net "PWRGD_P3V3_SSD9_R")
	)
	(segment
		(start 268.050772 -61.32068)
		(end 267.320014 -62.051438)
		(width 0.15494)
		(layer "In5.Cu")
		(net "PWRGD_P3V3_SSD9_R")
	)
	(segment
		(start 267.320014 -62.051438)
		(end 266.810998 -62.051438)
		(width 0.15494)
		(layer "In5.Cu")
		(net "PWRGD_P3V3_SSD9_R")
	)
	(segment
		(start 309.818278 -95.18015)
		(end 309.162958 -94.52483)
		(width 0.15494)
		(layer "In5.Cu")
		(net "PWRGD_P3V3_SSD9_R")
	)
	(segment
		(start 263.669018 -70.315582)
		(end 263.669018 -71.535798)
		(width 0.15494)
		(layer "In5.Cu")
		(net "PWRGD_P3V3_SSD9_R")
	)
	(segment
		(start 310.352694 -105.729024)
		(end 309.818278 -105.194608)
		(width 0.15494)
		(layer "In5.Cu")
		(net "PWRGD_P3V3_SSD9_R")
	)
	(segment
		(start 258.062476 -35.876738)
		(end 268.050772 -45.865034)
		(width 0.15494)
		(layer "In5.Cu")
		(net "PWRGD_P3V3_SSD9_R")
	)
	(segment
		(start 255.370838 -35.876738)
		(end 258.062476 -35.876738)
		(width 0.15494)
		(layer "In5.Cu")
		(net "PWRGD_P3V3_SSD9_R")
	)
	(segment
		(start 329.027282 -142.794482)
		(end 320.407538 -134.174738)
		(width 0.15494)
		(layer "In5.Cu")
		(net "PWRGD_P3V3_SSD9_R")
	)
	(segment
		(start 330.855828 -142.794482)
		(end 329.027282 -142.794482)
		(width 0.15494)
		(layer "In5.Cu")
		(net "PWRGD_P3V3_SSD9_R")
	)
	(segment
		(start 268.005052 -65.979548)
		(end 263.669018 -70.315582)
		(width 0.15494)
		(layer "In5.Cu")
		(net "PWRGD_P3V3_SSD9_R")
	)
	(segment
		(start 268.005052 -63.245492)
		(end 268.005052 -65.979548)
		(width 0.15494)
		(layer "In5.Cu")
		(net "PWRGD_P3V3_SSD9_R")
	)
	(segment
		(start 336.09407 -210.787234)
		(end 336.09407 -210.217258)
		(width 0.15494)
		(layer "In5.Cu")
		(net "PWRGD_P3V3_SSD9_R")
	)
	(segment
		(start 263.669018 -71.535798)
		(end 269.676118 -77.542898)
		(width 0.15494)
		(layer "In5.Cu")
		(net "PWRGD_P3V3_SSD9_R")
	)
	(segment
		(start 332.079854 -144.018508)
		(end 330.855828 -142.794482)
		(width 0.15494)
		(layer "In5.Cu")
		(net "PWRGD_P3V3_SSD9_R")
	)
	(segment
		(start 309.162958 -94.52483)
		(end 309.162958 -93.96095)
		(width 0.15494)
		(layer "In5.Cu")
		(net "PWRGD_P3V3_SSD9_R")
	)
	(segment
		(start 269.676118 -82.909156)
		(end 273.322542 -86.55558)
		(width 0.15494)
		(layer "In5.Cu")
		(net "PWRGD_P3V3_SSD9_R")
	)
	(segment
		(start 330.527152 -189.867794)
		(end 331.198474 -189.196472)
		(width 0.15494)
		(layer "In5.Cu")
		(net "PWRGD_P3V3_SSD9_R")
	)
	(segment
		(start 320.407538 -134.174738)
		(end 320.407538 -131.47167)
		(width 0.15494)
		(layer "In5.Cu")
		(net "PWRGD_P3V3_SSD9_R")
	)
	(segment
		(start 268.050772 -45.865034)
		(end 268.050772 -61.32068)
		(width 0.15494)
		(layer "In5.Cu")
		(net "PWRGD_P3V3_SSD9_R")
	)
	(segment
		(start 326.67321 -205.687422)
		(end 326.67321 -202.132184)
		(width 0.15494)
		(layer "In5.Cu")
		(net "PWRGD_P3V3_SSD9_R")
	)
	(segment
		(start 326.67321 -202.132184)
		(end 330.527152 -198.278242)
		(width 0.15494)
		(layer "In5.Cu")
		(net "PWRGD_P3V3_SSD9_R")
	)
	(segment
		(start 320.407538 -131.47167)
		(end 310.352694 -121.416826)
		(width 0.15494)
		(layer "In5.Cu")
		(net "PWRGD_P3V3_SSD9_R")
	)
	(segment
		(start 330.527152 -198.278242)
		(end 330.527152 -189.867794)
		(width 0.15494)
		(layer "In5.Cu")
		(net "PWRGD_P3V3_SSD9_R")
	)
	(segment
		(start 269.676118 -77.542898)
		(end 269.676118 -82.909156)
		(width 0.15494)
		(layer "In5.Cu")
		(net "PWRGD_P3V3_SSD9_R")
	)
	(segment
		(start 333.152242 -207.27543)
		(end 332.716886 -207.27543)
		(width 0.15494)
		(layer "In5.Cu")
		(net "PWRGD_P3V3_SSD9_R")
	)
	(segment
		(start 275.197062 -86.849204)
		(end 274.903438 -86.55558)
		(width 0.15494)
		(layer "In9.Cu")
		(net "PWRGD_P3V3_SSD9_R")
	)
	(segment
		(start 277.853648 -88.184736)
		(end 276.518116 -86.849204)
		(width 0.15494)
		(layer "In9.Cu")
		(net "PWRGD_P3V3_SSD9_R")
	)
	(segment
		(start 309.162958 -93.96095)
		(end 303.386744 -88.184736)
		(width 0.15494)
		(layer "In9.Cu")
		(net "PWRGD_P3V3_SSD9_R")
	)
	(segment
		(start 276.518116 -86.849204)
		(end 275.197062 -86.849204)
		(width 0.15494)
		(layer "In9.Cu")
		(net "PWRGD_P3V3_SSD9_R")
	)
	(segment
		(start 303.386744 -88.184736)
		(end 277.853648 -88.184736)
		(width 0.15494)
		(layer "In9.Cu")
		(net "PWRGD_P3V3_SSD9_R")
	)
	(segment
		(start 27.669744 -308.086252)
		(end 28.03398 -308.450488)
		(width 0.13208)
		(layer "F.Cu")
		(net "PEX0_DBG_SEL0")
	)
	(segment
		(start 28.388056 -307.36794)
		(end 27.669744 -308.086252)
		(width 0.13208)
		(layer "F.Cu")
		(net "PEX0_DBG_SEL0")
	)
	(segment
		(start 28.03398 -308.450488)
		(end 28.460192 -308.450488)
		(width 0.13208)
		(layer "F.Cu")
		(net "PEX0_DBG_SEL0")
	)
	(via
		(at 52.999894 -309.199788)
		(size 0.4064)
		(drill 0.2032)
		(layers "F.Cu" "B.Cu")
		(net "PEX0_DBG_SEL0")
	)
	(via
		(at 28.460192 -308.450488)
		(size 0.508)
		(drill 0.254)
		(layers "F.Cu" "B.Cu")
		(net "PEX0_DBG_SEL0")
	)
	(segment
		(start 54.356 -315.087)
		(end 54.0258 -315.4172)
		(width 0.13208)
		(layer "B.Cu")
		(net "PEX0_DBG_SEL0")
	)
	(segment
		(start 53.126894 -309.7276)
		(end 54.102 -309.7276)
		(width 0.13208)
		(layer "B.Cu")
		(net "PEX0_DBG_SEL0")
	)
	(segment
		(start 31.4452 -311.435496)
		(end 28.460192 -308.450488)
		(width 0.13208)
		(layer "B.Cu")
		(net "PEX0_DBG_SEL0")
	)
	(segment
		(start 35.2044 -314.8076)
		(end 35.2044 -313.69)
		(width 0.13208)
		(layer "B.Cu")
		(net "PEX0_DBG_SEL0")
	)
	(segment
		(start 54.102 -309.7276)
		(end 54.356 -309.9816)
		(width 0.13208)
		(layer "B.Cu")
		(net "PEX0_DBG_SEL0")
	)
	(segment
		(start 54.356 -309.9816)
		(end 54.356 -315.087)
		(width 0.13208)
		(layer "B.Cu")
		(net "PEX0_DBG_SEL0")
	)
	(segment
		(start 31.4452 -312.801)
		(end 31.4452 -311.435496)
		(width 0.13208)
		(layer "B.Cu")
		(net "PEX0_DBG_SEL0")
	)
	(segment
		(start 52.999894 -309.6006)
		(end 53.126894 -309.7276)
		(width 0.13208)
		(layer "B.Cu")
		(net "PEX0_DBG_SEL0")
	)
	(segment
		(start 35.2044 -313.69)
		(end 34.62528 -313.11088)
		(width 0.13208)
		(layer "B.Cu")
		(net "PEX0_DBG_SEL0")
	)
	(segment
		(start 54.0258 -315.4172)
		(end 35.814 -315.4172)
		(width 0.13208)
		(layer "B.Cu")
		(net "PEX0_DBG_SEL0")
	)
	(segment
		(start 34.62528 -313.11088)
		(end 31.75508 -313.11088)
		(width 0.13208)
		(layer "B.Cu")
		(net "PEX0_DBG_SEL0")
	)
	(segment
		(start 52.999894 -309.199788)
		(end 52.999894 -309.6006)
		(width 0.13208)
		(layer "B.Cu")
		(net "PEX0_DBG_SEL0")
	)
	(segment
		(start 31.75508 -313.11088)
		(end 31.4452 -312.801)
		(width 0.13208)
		(layer "B.Cu")
		(net "PEX0_DBG_SEL0")
	)
	(segment
		(start 35.814 -315.4172)
		(end 35.2044 -314.8076)
		(width 0.13208)
		(layer "B.Cu")
		(net "PEX0_DBG_SEL0")
	)
	(segment
		(start 378.126752 -312.00852)
		(end 379.899164 -312.00852)
		(width 0.13208)
		(layer "F.Cu")
		(net "PEX3_DBG_SEL1")
	)
	(segment
		(start 378.126752 -312.00852)
		(end 377.994672 -312.1406)
		(width 0.13208)
		(layer "F.Cu")
		(net "PEX3_DBG_SEL1")
	)
	(segment
		(start 402.249894 -308.249828)
		(end 401.774914 -308.724808)
		(width 0.13208)
		(layer "F.Cu")
		(net "PEX3_DBG_SEL1")
	)
	(segment
		(start 377.994672 -312.1406)
		(end 377.39193 -312.1406)
		(width 0.13208)
		(layer "F.Cu")
		(net "PEX3_DBG_SEL1")
	)
	(segment
		(start 376.807984 -311.556654)
		(end 376.138694 -311.556654)
		(width 0.13208)
		(layer "F.Cu")
		(net "PEX3_DBG_SEL1")
	)
	(segment
		(start 379.899164 -312.00852)
		(end 380.414022 -312.523378)
		(width 0.13208)
		(layer "F.Cu")
		(net "PEX3_DBG_SEL1")
	)
	(segment
		(start 377.39193 -312.1406)
		(end 376.807984 -311.556654)
		(width 0.13208)
		(layer "F.Cu")
		(net "PEX3_DBG_SEL1")
	)
	(via
		(at 401.774914 -308.724808)
		(size 0.4064)
		(drill 0.2032)
		(layers "F.Cu" "B.Cu")
		(net "PEX3_DBG_SEL1")
	)
	(via
		(at 380.414022 -312.523378)
		(size 0.508)
		(drill 0.254)
		(layers "F.Cu" "B.Cu")
		(net "PEX3_DBG_SEL1")
	)
	(segment
		(start 380.748794 -312.85815)
		(end 383.8448 -312.85815)
		(width 0.13208)
		(layer "B.Cu")
		(net "PEX3_DBG_SEL1")
	)
	(segment
		(start 400.813016 -312.396378)
		(end 400.813016 -309.686706)
		(width 0.13208)
		(layer "B.Cu")
		(net "PEX3_DBG_SEL1")
	)
	(segment
		(start 400.813016 -309.686706)
		(end 401.774914 -308.724808)
		(width 0.13208)
		(layer "B.Cu")
		(net "PEX3_DBG_SEL1")
	)
	(segment
		(start 384.179572 -312.523378)
		(end 400.686016 -312.523378)
		(width 0.13208)
		(layer "B.Cu")
		(net "PEX3_DBG_SEL1")
	)
	(segment
		(start 383.8448 -312.85815)
		(end 384.179572 -312.523378)
		(width 0.13208)
		(layer "B.Cu")
		(net "PEX3_DBG_SEL1")
	)
	(segment
		(start 380.414022 -312.523378)
		(end 380.748794 -312.85815)
		(width 0.13208)
		(layer "B.Cu")
		(net "PEX3_DBG_SEL1")
	)
	(segment
		(start 400.686016 -312.523378)
		(end 400.813016 -312.396378)
		(width 0.13208)
		(layer "B.Cu")
		(net "PEX3_DBG_SEL1")
	)
	(segment
		(start 213.640162 -226.711256)
		(end 212.968078 -226.711256)
		(width 0.13208)
		(layer "F.Cu")
		(net "SMB_NIC2_R_SDA")
	)
	(segment
		(start 171.249594 -141.605)
		(end 169.112184 -141.605)
		(width 0.13208)
		(layer "F.Cu")
		(net "SMB_NIC2_R_SDA")
	)
	(segment
		(start 168.08704 -141.964918)
		(end 166.742364 -141.964918)
		(width 0.13208)
		(layer "F.Cu")
		(net "SMB_NIC2_R_SDA")
	)
	(segment
		(start 168.752266 -141.964918)
		(end 168.08704 -141.964918)
		(width 0.13208)
		(layer "F.Cu")
		(net "SMB_NIC2_R_SDA")
	)
	(segment
		(start 171.579794 -141.9352)
		(end 171.249594 -141.605)
		(width 0.13208)
		(layer "F.Cu")
		(net "SMB_NIC2_R_SDA")
	)
	(segment
		(start 169.112184 -141.605)
		(end 168.752266 -141.964918)
		(width 0.13208)
		(layer "F.Cu")
		(net "SMB_NIC2_R_SDA")
	)
	(segment
		(start 212.968078 -226.711256)
		(end 212.360764 -227.31857)
		(width 0.13208)
		(layer "F.Cu")
		(net "SMB_NIC2_R_SDA")
	)
	(via
		(at 212.360764 -227.31857)
		(size 0.508)
		(drill 0.254)
		(layers "F.Cu" "B.Cu")
		(net "SMB_NIC2_R_SDA")
	)
	(via
		(at 185.087768 -225.209862)
		(size 0.508)
		(drill 0.254)
		(layers "F.Cu" "B.Cu")
		(net "SMB_NIC2_R_SDA")
	)
	(via
		(at 168.08704 -141.964918)
		(size 0.508)
		(drill 0.254)
		(layers "F.Cu" "B.Cu")
		(net "SMB_NIC2_R_SDA")
	)
	(segment
		(start 170.9928 -144.493742)
		(end 170.9928 -177.379376)
		(width 0.15494)
		(layer "In9.Cu")
		(net "SMB_NIC2_R_SDA")
	)
	(segment
		(start 184.553352 -190.939928)
		(end 184.553352 -224.675446)
		(width 0.15494)
		(layer "In9.Cu")
		(net "SMB_NIC2_R_SDA")
	)
	(segment
		(start 184.553352 -224.675446)
		(end 185.087768 -225.209862)
		(width 0.15494)
		(layer "In9.Cu")
		(net "SMB_NIC2_R_SDA")
	)
	(segment
		(start 168.463976 -141.964918)
		(end 170.9928 -144.493742)
		(width 0.15494)
		(layer "In9.Cu")
		(net "SMB_NIC2_R_SDA")
	)
	(segment
		(start 170.9928 -177.379376)
		(end 184.553352 -190.939928)
		(width 0.15494)
		(layer "In9.Cu")
		(net "SMB_NIC2_R_SDA")
	)
	(segment
		(start 168.08704 -141.964918)
		(end 168.463976 -141.964918)
		(width 0.15494)
		(layer "In9.Cu")
		(net "SMB_NIC2_R_SDA")
	)
	(segment
		(start 209.723736 -223.4438)
		(end 210.878928 -224.598992)
		(width 0.15494)
		(layer "In13.Cu")
		(net "SMB_NIC2_R_SDA")
	)
	(segment
		(start 211.363306 -226.780344)
		(end 211.901532 -227.31857)
		(width 0.15494)
		(layer "In13.Cu")
		(net "SMB_NIC2_R_SDA")
	)
	(segment
		(start 210.878928 -225.283014)
		(end 211.363306 -225.767392)
		(width 0.15494)
		(layer "In13.Cu")
		(net "SMB_NIC2_R_SDA")
	)
	(segment
		(start 185.087768 -225.209862)
		(end 187.630308 -222.667322)
		(width 0.15494)
		(layer "In13.Cu")
		(net "SMB_NIC2_R_SDA")
	)
	(segment
		(start 207.782922 -222.667322)
		(end 208.5594 -223.4438)
		(width 0.15494)
		(layer "In13.Cu")
		(net "SMB_NIC2_R_SDA")
	)
	(segment
		(start 211.363306 -225.767392)
		(end 211.363306 -226.780344)
		(width 0.15494)
		(layer "In13.Cu")
		(net "SMB_NIC2_R_SDA")
	)
	(segment
		(start 187.630308 -222.667322)
		(end 207.782922 -222.667322)
		(width 0.15494)
		(layer "In13.Cu")
		(net "SMB_NIC2_R_SDA")
	)
	(segment
		(start 210.878928 -224.598992)
		(end 210.878928 -225.283014)
		(width 0.15494)
		(layer "In13.Cu")
		(net "SMB_NIC2_R_SDA")
	)
	(segment
		(start 208.5594 -223.4438)
		(end 209.723736 -223.4438)
		(width 0.15494)
		(layer "In13.Cu")
		(net "SMB_NIC2_R_SDA")
	)
	(segment
		(start 211.901532 -227.31857)
		(end 212.360764 -227.31857)
		(width 0.15494)
		(layer "In13.Cu")
		(net "SMB_NIC2_R_SDA")
	)
	(segment
		(start 58.576972 -377.556268)
		(end 59.22772 -377.556268)
		(width 0.13208)
		(layer "F.Cu")
		(net "GPU_BASE_PWR_GD_R")
	)
	(via
		(at 59.22772 -377.556268)
		(size 0.508)
		(drill 0.254)
		(layers "F.Cu" "B.Cu")
		(net "GPU_BASE_PWR_GD_R")
	)
	(segment
		(start 58.2676 -376.596148)
		(end 58.2676 -374.827546)
		(width 0.15494)
		(layer "In15.Cu")
		(net "GPU_BASE_PWR_GD_R")
	)
	(segment
		(start 58.2676 -374.827546)
		(end 65.456816 -367.63833)
		(width 0.15494)
		(layer "In15.Cu")
		(net "GPU_BASE_PWR_GD_R")
	)
	(segment
		(start 59.22772 -377.556268)
		(end 58.2676 -376.596148)
		(width 0.15494)
		(layer "In15.Cu")
		(net "GPU_BASE_PWR_GD_R")
	)
	(segment
		(start 65.456816 -367.63833)
		(end 81.55813 -367.63833)
		(width 0.15494)
		(layer "In15.Cu")
		(net "GPU_BASE_PWR_GD_R")
	)
	(segment
		(start 81.55813 -367.63833)
		(end 82.909918 -368.990118)
		(width 0.15494)
		(layer "In15.Cu")
		(net "GPU_BASE_PWR_GD_R")
	)
	(segment
		(start 370.431568 -256.35204)
		(end 370.558568 -256.22504)
		(width 0.13208)
		(layer "F.Cu")
		(net "PEX3_SYS_ERR_3V3_N")
	)
	(segment
		(start 369.808506 -256.35204)
		(end 370.431568 -256.35204)
		(width 0.13208)
		(layer "F.Cu")
		(net "PEX3_SYS_ERR_3V3_N")
	)
	(segment
		(start 370.558568 -256.22504)
		(end 370.558568 -255.910588)
		(width 0.13208)
		(layer "F.Cu")
		(net "PEX3_SYS_ERR_3V3_N")
	)
	(segment
		(start 370.558568 -255.08458)
		(end 370.792502 -254.850646)
		(width 0.13208)
		(layer "F.Cu")
		(net "PEX3_SYS_ERR_3V3_N")
	)
	(segment
		(start 370.558568 -255.910588)
		(end 370.558568 -255.08458)
		(width 0.13208)
		(layer "F.Cu")
		(net "PEX3_SYS_ERR_3V3_N")
	)
	(segment
		(start 370.792502 -254.850646)
		(end 371.327172 -254.850646)
		(width 0.13208)
		(layer "F.Cu")
		(net "PEX3_SYS_ERR_3V3_N")
	)
	(via
		(at 370.558568 -255.910588)
		(size 0.508)
		(drill 0.254)
		(layers "F.Cu" "B.Cu")
		(net "PEX3_SYS_ERR_3V3_N")
	)
	(segment
		(start 24.658574 -55.144162)
		(end 25.867868 -56.353456)
		(width 0.13208)
		(layer "F.Cu")
		(net "SSD0_PWR_EN_R")
	)
	(segment
		(start 24.147272 -55.144162)
		(end 24.658574 -55.144162)
		(width 0.13208)
		(layer "F.Cu")
		(net "SSD0_PWR_EN_R")
	)
	(segment
		(start 25.867106 -56.354218)
		(end 25.867868 -56.353456)
		(width 0.13208)
		(layer "F.Cu")
		(net "SSD0_PWR_EN_R")
	)
	(segment
		(start 25.867106 -57.332626)
		(end 25.867106 -56.354218)
		(width 0.13208)
		(layer "F.Cu")
		(net "SSD0_PWR_EN_R")
	)
	(segment
		(start 20.514564 -65.92189)
		(end 20.514564 -65.100962)
		(width 0.13208)
		(layer "F.Cu")
		(net "SSD0_PWR_EN_R")
	)
	(segment
		(start 25.867106 -57.563766)
		(end 26.375614 -58.072274)
		(width 0.13208)
		(layer "F.Cu")
		(net "SSD0_PWR_EN_R")
	)
	(segment
		(start 335.247996 -251.423424)
		(end 335.247996 -250.34875)
		(width 0.13208)
		(layer "F.Cu")
		(net "SSD0_PWR_EN_R")
	)
	(segment
		(start 341.870792 -243.725954)
		(end 341.870792 -241.091212)
		(width 0.13208)
		(layer "F.Cu")
		(net "SSD0_PWR_EN_R")
	)
	(segment
		(start 335.247996 -250.34875)
		(end 341.870792 -243.725954)
		(width 0.13208)
		(layer "F.Cu")
		(net "SSD0_PWR_EN_R")
	)
	(segment
		(start 25.867106 -57.332626)
		(end 25.867106 -57.563766)
		(width 0.13208)
		(layer "F.Cu")
		(net "SSD0_PWR_EN_R")
	)
	(via
		(at 31.097728 -217.81516)
		(size 0.508)
		(drill 0.254)
		(layers "F.Cu" "B.Cu")
		(net "SSD0_PWR_EN_R")
	)
	(via
		(at 26.375614 -58.072274)
		(size 0.508)
		(drill 0.254)
		(layers "F.Cu" "B.Cu")
		(net "SSD0_PWR_EN_R")
	)
	(via
		(at 335.247996 -251.423424)
		(size 0.508)
		(drill 0.254)
		(layers "F.Cu" "B.Cu")
		(net "SSD0_PWR_EN_R")
	)
	(via
		(at 20.514564 -65.100962)
		(size 0.508)
		(drill 0.254)
		(layers "F.Cu" "B.Cu")
		(net "SSD0_PWR_EN_R")
	)
	(segment
		(start 31.029148 -204.764894)
		(end 31.029148 -217.74658)
		(width 0.15494)
		(layer "In5.Cu")
		(net "SSD0_PWR_EN_R")
	)
	(segment
		(start 21.731224 -65.64376)
		(end 21.057362 -65.64376)
		(width 0.15494)
		(layer "In5.Cu")
		(net "SSD0_PWR_EN_R")
	)
	(segment
		(start 26.375614 -58.072274)
		(end 25.867868 -58.58002)
		(width 0.15494)
		(layer "In5.Cu")
		(net "SSD0_PWR_EN_R")
	)
	(segment
		(start 26.407618 -66.47561)
		(end 27.891232 -67.959224)
		(width 0.15494)
		(layer "In5.Cu")
		(net "SSD0_PWR_EN_R")
	)
	(segment
		(start 25.219152 -192.877694)
		(end 29.478478 -197.13702)
		(width 0.15494)
		(layer "In5.Cu")
		(net "SSD0_PWR_EN_R")
	)
	(segment
		(start 31.029148 -217.74658)
		(end 31.097728 -217.81516)
		(width 0.15494)
		(layer "In5.Cu")
		(net "SSD0_PWR_EN_R")
	)
	(segment
		(start 25.219152 -166.36873)
		(end 25.219152 -192.877694)
		(width 0.15494)
		(layer "In5.Cu")
		(net "SSD0_PWR_EN_R")
	)
	(segment
		(start 25.047448 -165.954202)
		(end 25.219152 -166.36873)
		(width 0.15494)
		(layer "In5.Cu")
		(net "SSD0_PWR_EN_R")
	)
	(segment
		(start 29.478478 -203.214224)
		(end 31.029148 -204.764894)
		(width 0.15494)
		(layer "In5.Cu")
		(net "SSD0_PWR_EN_R")
	)
	(segment
		(start 27.891232 -67.959224)
		(end 27.891232 -97.254568)
		(width 0.15494)
		(layer "In5.Cu")
		(net "SSD0_PWR_EN_R")
	)
	(segment
		(start 27.891232 -97.254568)
		(end 25.047448 -100.098352)
		(width 0.15494)
		(layer "In5.Cu")
		(net "SSD0_PWR_EN_R")
	)
	(segment
		(start 29.478478 -197.13702)
		(end 29.478478 -203.214224)
		(width 0.15494)
		(layer "In5.Cu")
		(net "SSD0_PWR_EN_R")
	)
	(segment
		(start 21.057362 -65.64376)
		(end 20.514564 -65.100962)
		(width 0.15494)
		(layer "In5.Cu")
		(net "SSD0_PWR_EN_R")
	)
	(segment
		(start 22.477984 -64.897)
		(end 21.731224 -65.64376)
		(width 0.15494)
		(layer "In5.Cu")
		(net "SSD0_PWR_EN_R")
	)
	(segment
		(start 25.867868 -58.58002)
		(end 25.867868 -64.337184)
		(width 0.15494)
		(layer "In5.Cu")
		(net "SSD0_PWR_EN_R")
	)
	(segment
		(start 26.375614 -58.072274)
		(end 26.407618 -58.104278)
		(width 0.15494)
		(layer "In5.Cu")
		(net "SSD0_PWR_EN_R")
	)
	(segment
		(start 25.308052 -64.897)
		(end 22.477984 -64.897)
		(width 0.15494)
		(layer "In5.Cu")
		(net "SSD0_PWR_EN_R")
	)
	(segment
		(start 25.867868 -64.337184)
		(end 25.308052 -64.897)
		(width 0.15494)
		(layer "In5.Cu")
		(net "SSD0_PWR_EN_R")
	)
	(segment
		(start 25.047448 -100.098352)
		(end 25.047448 -165.954202)
		(width 0.15494)
		(layer "In5.Cu")
		(net "SSD0_PWR_EN_R")
	)
	(segment
		(start 26.407618 -58.104278)
		(end 26.407618 -66.47561)
		(width 0.15494)
		(layer "In5.Cu")
		(net "SSD0_PWR_EN_R")
	)
	(segment
		(start 333.826358 -253.098046)
		(end 335.06918 -251.855224)
		(width 0.15494)
		(layer "In15.Cu")
		(net "SSD0_PWR_EN_R")
	)
	(segment
		(start 160.350454 -240.54181)
		(end 179.621942 -240.54181)
		(width 0.15494)
		(layer "In15.Cu")
		(net "SSD0_PWR_EN_R")
	)
	(segment
		(start 152.50287 -234.57916)
		(end 153.68016 -235.06684)
		(width 0.15494)
		(layer "In15.Cu")
		(net "SSD0_PWR_EN_R")
	)
	(segment
		(start 179.621942 -240.54181)
		(end 187.682632 -248.6025)
		(width 0.15494)
		(layer "In15.Cu")
		(net "SSD0_PWR_EN_R")
	)
	(segment
		(start 223.835976 -249.4915)
		(end 224.266506 -249.06097)
		(width 0.15494)
		(layer "In15.Cu")
		(net "SSD0_PWR_EN_R")
	)
	(segment
		(start 187.682632 -248.6025)
		(end 189.429644 -248.6025)
		(width 0.15494)
		(layer "In15.Cu")
		(net "SSD0_PWR_EN_R")
	)
	(segment
		(start 239.992154 -248.992644)
		(end 247.979438 -248.992644)
		(width 0.15494)
		(layer "In15.Cu")
		(net "SSD0_PWR_EN_R")
	)
	(segment
		(start 130.213608 -237.07725)
		(end 139.057126 -237.07725)
		(width 0.15494)
		(layer "In15.Cu")
		(net "SSD0_PWR_EN_R")
	)
	(segment
		(start 249.201686 -250.214892)
		(end 257.949446 -250.214892)
		(width 0.15494)
		(layer "In15.Cu")
		(net "SSD0_PWR_EN_R")
	)
	(segment
		(start 109.225334 -209.211672)
		(end 113.02238 -213.008718)
		(width 0.15494)
		(layer "In15.Cu")
		(net "SSD0_PWR_EN_R")
	)
	(segment
		(start 151.409146 -234.57916)
		(end 152.50287 -234.57916)
		(width 0.15494)
		(layer "In15.Cu")
		(net "SSD0_PWR_EN_R")
	)
	(segment
		(start 224.266506 -249.06097)
		(end 229.50043 -249.06097)
		(width 0.15494)
		(layer "In15.Cu")
		(net "SSD0_PWR_EN_R")
	)
	(segment
		(start 31.097728 -217.81516)
		(end 34.66211 -214.250778)
		(width 0.15494)
		(layer "In15.Cu")
		(net "SSD0_PWR_EN_R")
	)
	(segment
		(start 335.06918 -251.855224)
		(end 335.247996 -251.423424)
		(width 0.15494)
		(layer "In15.Cu")
		(net "SSD0_PWR_EN_R")
	)
	(segment
		(start 190.318644 -249.4915)
		(end 223.835976 -249.4915)
		(width 0.15494)
		(layer "In15.Cu")
		(net "SSD0_PWR_EN_R")
	)
	(segment
		(start 113.02238 -213.008718)
		(end 113.02238 -232.92181)
		(width 0.15494)
		(layer "In15.Cu")
		(net "SSD0_PWR_EN_R")
	)
	(segment
		(start 70.165468 -214.250778)
		(end 75.204574 -209.211672)
		(width 0.15494)
		(layer "In15.Cu")
		(net "SSD0_PWR_EN_R")
	)
	(segment
		(start 326.008238 -252.016514)
		(end 327.08977 -253.098046)
		(width 0.15494)
		(layer "In15.Cu")
		(net "SSD0_PWR_EN_R")
	)
	(segment
		(start 119.652288 -239.551718)
		(end 127.73914 -239.551718)
		(width 0.15494)
		(layer "In15.Cu")
		(net "SSD0_PWR_EN_R")
	)
	(segment
		(start 247.979438 -248.992644)
		(end 249.201686 -250.214892)
		(width 0.15494)
		(layer "In15.Cu")
		(net "SSD0_PWR_EN_R")
	)
	(segment
		(start 304.389282 -252.016514)
		(end 326.008238 -252.016514)
		(width 0.15494)
		(layer "In15.Cu")
		(net "SSD0_PWR_EN_R")
	)
	(segment
		(start 189.429644 -248.6025)
		(end 190.318644 -249.4915)
		(width 0.15494)
		(layer "In15.Cu")
		(net "SSD0_PWR_EN_R")
	)
	(segment
		(start 229.50043 -249.06097)
		(end 230.741982 -250.302522)
		(width 0.15494)
		(layer "In15.Cu")
		(net "SSD0_PWR_EN_R")
	)
	(segment
		(start 258.314952 -250.580398)
		(end 298.361608 -250.580398)
		(width 0.15494)
		(layer "In15.Cu")
		(net "SSD0_PWR_EN_R")
	)
	(segment
		(start 113.02238 -232.92181)
		(end 119.652288 -239.551718)
		(width 0.15494)
		(layer "In15.Cu")
		(net "SSD0_PWR_EN_R")
	)
	(segment
		(start 327.08977 -253.098046)
		(end 333.826358 -253.098046)
		(width 0.15494)
		(layer "In15.Cu")
		(net "SSD0_PWR_EN_R")
	)
	(segment
		(start 139.057126 -237.07725)
		(end 142.266416 -233.86796)
		(width 0.15494)
		(layer "In15.Cu")
		(net "SSD0_PWR_EN_R")
	)
	(segment
		(start 257.949446 -250.214892)
		(end 258.314952 -250.580398)
		(width 0.15494)
		(layer "In15.Cu")
		(net "SSD0_PWR_EN_R")
	)
	(segment
		(start 230.741982 -250.302522)
		(end 238.682276 -250.302522)
		(width 0.15494)
		(layer "In15.Cu")
		(net "SSD0_PWR_EN_R")
	)
	(segment
		(start 34.66211 -214.250778)
		(end 70.165468 -214.250778)
		(width 0.15494)
		(layer "In15.Cu")
		(net "SSD0_PWR_EN_R")
	)
	(segment
		(start 299.966634 -252.185424)
		(end 304.220372 -252.185424)
		(width 0.15494)
		(layer "In15.Cu")
		(net "SSD0_PWR_EN_R")
	)
	(segment
		(start 149.690328 -233.86796)
		(end 151.409146 -234.57916)
		(width 0.15494)
		(layer "In15.Cu")
		(net "SSD0_PWR_EN_R")
	)
	(segment
		(start 142.266416 -233.86796)
		(end 149.690328 -233.86796)
		(width 0.15494)
		(layer "In15.Cu")
		(net "SSD0_PWR_EN_R")
	)
	(segment
		(start 304.220372 -252.185424)
		(end 304.389282 -252.016514)
		(width 0.15494)
		(layer "In15.Cu")
		(net "SSD0_PWR_EN_R")
	)
	(segment
		(start 153.68016 -235.06684)
		(end 154.875484 -235.06684)
		(width 0.15494)
		(layer "In15.Cu")
		(net "SSD0_PWR_EN_R")
	)
	(segment
		(start 238.682276 -250.302522)
		(end 239.992154 -248.992644)
		(width 0.15494)
		(layer "In15.Cu")
		(net "SSD0_PWR_EN_R")
	)
	(segment
		(start 127.73914 -239.551718)
		(end 130.213608 -237.07725)
		(width 0.15494)
		(layer "In15.Cu")
		(net "SSD0_PWR_EN_R")
	)
	(segment
		(start 298.361608 -250.580398)
		(end 299.966634 -252.185424)
		(width 0.15494)
		(layer "In15.Cu")
		(net "SSD0_PWR_EN_R")
	)
	(segment
		(start 75.204574 -209.211672)
		(end 109.225334 -209.211672)
		(width 0.15494)
		(layer "In15.Cu")
		(net "SSD0_PWR_EN_R")
	)
	(segment
		(start 154.875484 -235.06684)
		(end 160.350454 -240.54181)
		(width 0.15494)
		(layer "In15.Cu")
		(net "SSD0_PWR_EN_R")
	)
	(segment
		(start 343.027 -234.46105)
		(end 343.027 -235.077)
		(width 0.13208)
		(layer "F.Cu")
		(net "RST_SSD3_PERST_R_N")
	)
	(segment
		(start 92.203778 -24.189944)
		(end 93.264736 -24.189944)
		(width 0.13208)
		(layer "F.Cu")
		(net "RST_SSD3_PERST_R_N")
	)
	(via
		(at 92.203778 -24.189944)
		(size 0.508)
		(drill 0.254)
		(layers "F.Cu" "B.Cu")
		(net "RST_SSD3_PERST_R_N")
	)
	(via
		(at 148.878544 -230.86949)
		(size 0.508)
		(drill 0.254)
		(layers "F.Cu" "B.Cu")
		(net "RST_SSD3_PERST_R_N")
	)
	(via
		(at 343.027 -235.077)
		(size 0.508)
		(drill 0.254)
		(layers "F.Cu" "B.Cu")
		(net "RST_SSD3_PERST_R_N")
	)
	(segment
		(start 148.958808 -209.755486)
		(end 148.958808 -205.877922)
		(width 0.15494)
		(layer "In5.Cu")
		(net "RST_SSD3_PERST_R_N")
	)
	(segment
		(start 102.00386 -27.455114)
		(end 99.03206 -27.455114)
		(width 0.15494)
		(layer "In5.Cu")
		(net "RST_SSD3_PERST_R_N")
	)
	(segment
		(start 139.9286 -173.343316)
		(end 140.5636 -172.708316)
		(width 0.15494)
		(layer "In5.Cu")
		(net "RST_SSD3_PERST_R_N")
	)
	(segment
		(start 120.345708 -65.745868)
		(end 117.748304 -65.745868)
		(width 0.15494)
		(layer "In5.Cu")
		(net "RST_SSD3_PERST_R_N")
	)
	(segment
		(start 115.331748 -60.742068)
		(end 108.04398 -53.4543)
		(width 0.15494)
		(layer "In5.Cu")
		(net "RST_SSD3_PERST_R_N")
	)
	(segment
		(start 108.04398 -41.9227)
		(end 101.878638 -35.757358)
		(width 0.15494)
		(layer "In5.Cu")
		(net "RST_SSD3_PERST_R_N")
	)
	(segment
		(start 148.878544 -230.86949)
		(end 148.6154 -230.606346)
		(width 0.15494)
		(layer "In5.Cu")
		(net "RST_SSD3_PERST_R_N")
	)
	(segment
		(start 139.0904 -110.0836)
		(end 139.0904 -89.911682)
		(width 0.15494)
		(layer "In5.Cu")
		(net "RST_SSD3_PERST_R_N")
	)
	(segment
		(start 124.248672 -75.069954)
		(end 124.248672 -69.648832)
		(width 0.15494)
		(layer "In5.Cu")
		(net "RST_SSD3_PERST_R_N")
	)
	(segment
		(start 139.9286 -191.1858)
		(end 139.9286 -173.343316)
		(width 0.15494)
		(layer "In5.Cu")
		(net "RST_SSD3_PERST_R_N")
	)
	(segment
		(start 139.869926 -165.193726)
		(end 139.869926 -110.863126)
		(width 0.15494)
		(layer "In5.Cu")
		(net "RST_SSD3_PERST_R_N")
	)
	(segment
		(start 115.331748 -63.329312)
		(end 115.331748 -60.742068)
		(width 0.15494)
		(layer "In5.Cu")
		(net "RST_SSD3_PERST_R_N")
	)
	(segment
		(start 148.6154 -210.098894)
		(end 148.958808 -209.755486)
		(width 0.15494)
		(layer "In5.Cu")
		(net "RST_SSD3_PERST_R_N")
	)
	(segment
		(start 148.6154 -230.606346)
		(end 148.6154 -210.098894)
		(width 0.15494)
		(layer "In5.Cu")
		(net "RST_SSD3_PERST_R_N")
	)
	(segment
		(start 97.002346 -26.9494)
		(end 94.9833 -24.930354)
		(width 0.15494)
		(layer "In5.Cu")
		(net "RST_SSD3_PERST_R_N")
	)
	(segment
		(start 147.36953 -198.62673)
		(end 139.9286 -191.1858)
		(width 0.15494)
		(layer "In5.Cu")
		(net "RST_SSD3_PERST_R_N")
	)
	(segment
		(start 102.7684 -28.219654)
		(end 102.00386 -27.455114)
		(width 0.15494)
		(layer "In5.Cu")
		(net "RST_SSD3_PERST_R_N")
	)
	(segment
		(start 124.248672 -69.648832)
		(end 120.345708 -65.745868)
		(width 0.15494)
		(layer "In5.Cu")
		(net "RST_SSD3_PERST_R_N")
	)
	(segment
		(start 140.5636 -172.708316)
		(end 140.5636 -165.8874)
		(width 0.15494)
		(layer "In5.Cu")
		(net "RST_SSD3_PERST_R_N")
	)
	(segment
		(start 98.526346 -26.9494)
		(end 97.002346 -26.9494)
		(width 0.15494)
		(layer "In5.Cu")
		(net "RST_SSD3_PERST_R_N")
	)
	(segment
		(start 139.869926 -110.863126)
		(end 139.0904 -110.0836)
		(width 0.15494)
		(layer "In5.Cu")
		(net "RST_SSD3_PERST_R_N")
	)
	(segment
		(start 102.7684 -28.519882)
		(end 102.7684 -28.219654)
		(width 0.15494)
		(layer "In5.Cu")
		(net "RST_SSD3_PERST_R_N")
	)
	(segment
		(start 117.748304 -65.745868)
		(end 115.331748 -63.329312)
		(width 0.15494)
		(layer "In5.Cu")
		(net "RST_SSD3_PERST_R_N")
	)
	(segment
		(start 140.5636 -165.8874)
		(end 139.869926 -165.193726)
		(width 0.15494)
		(layer "In5.Cu")
		(net "RST_SSD3_PERST_R_N")
	)
	(segment
		(start 108.04398 -53.4543)
		(end 108.04398 -41.9227)
		(width 0.15494)
		(layer "In5.Cu")
		(net "RST_SSD3_PERST_R_N")
	)
	(segment
		(start 94.9833 -24.930354)
		(end 92.944188 -24.930354)
		(width 0.15494)
		(layer "In5.Cu")
		(net "RST_SSD3_PERST_R_N")
	)
	(segment
		(start 99.03206 -27.455114)
		(end 98.526346 -26.9494)
		(width 0.15494)
		(layer "In5.Cu")
		(net "RST_SSD3_PERST_R_N")
	)
	(segment
		(start 101.878638 -29.409644)
		(end 102.7684 -28.519882)
		(width 0.15494)
		(layer "In5.Cu")
		(net "RST_SSD3_PERST_R_N")
	)
	(segment
		(start 139.0904 -89.911682)
		(end 124.248672 -75.069954)
		(width 0.15494)
		(layer "In5.Cu")
		(net "RST_SSD3_PERST_R_N")
	)
	(segment
		(start 92.944188 -24.930354)
		(end 92.203778 -24.189944)
		(width 0.15494)
		(layer "In5.Cu")
		(net "RST_SSD3_PERST_R_N")
	)
	(segment
		(start 148.958808 -205.877922)
		(end 147.36953 -204.288644)
		(width 0.15494)
		(layer "In5.Cu")
		(net "RST_SSD3_PERST_R_N")
	)
	(segment
		(start 147.36953 -204.288644)
		(end 147.36953 -198.62673)
		(width 0.15494)
		(layer "In5.Cu")
		(net "RST_SSD3_PERST_R_N")
	)
	(segment
		(start 101.878638 -35.757358)
		(end 101.878638 -29.409644)
		(width 0.15494)
		(layer "In5.Cu")
		(net "RST_SSD3_PERST_R_N")
	)
	(segment
		(start 184.8104 -234.95)
		(end 191.565022 -241.704622)
		(width 0.15494)
		(layer "In15.Cu")
		(net "RST_SSD3_PERST_R_N")
	)
	(segment
		(start 219.17787 -241.627406)
		(end 228.57714 -241.627406)
		(width 0.15494)
		(layer "In15.Cu")
		(net "RST_SSD3_PERST_R_N")
	)
	(segment
		(start 327.132188 -243.580412)
		(end 327.470008 -243.242592)
		(width 0.15494)
		(layer "In15.Cu")
		(net "RST_SSD3_PERST_R_N")
	)
	(segment
		(start 218.322398 -242.482878)
		(end 219.17787 -241.627406)
		(width 0.15494)
		(layer "In15.Cu")
		(net "RST_SSD3_PERST_R_N")
	)
	(segment
		(start 342.49487 -236.758988)
		(end 342.49487 -235.60913)
		(width 0.15494)
		(layer "In15.Cu")
		(net "RST_SSD3_PERST_R_N")
	)
	(segment
		(start 262.007096 -235.003086)
		(end 263.27608 -235.528612)
		(width 0.15494)
		(layer "In15.Cu")
		(net "RST_SSD3_PERST_R_N")
	)
	(segment
		(start 263.27608 -235.528612)
		(end 264.913364 -237.165896)
		(width 0.15494)
		(layer "In15.Cu")
		(net "RST_SSD3_PERST_R_N")
	)
	(segment
		(start 214.608664 -242.482878)
		(end 218.322398 -242.482878)
		(width 0.15494)
		(layer "In15.Cu")
		(net "RST_SSD3_PERST_R_N")
	)
	(segment
		(start 302.776128 -243.580412)
		(end 327.132188 -243.580412)
		(width 0.15494)
		(layer "In15.Cu")
		(net "RST_SSD3_PERST_R_N")
	)
	(segment
		(start 241.28603 -241.82451)
		(end 248.319544 -241.82451)
		(width 0.15494)
		(layer "In15.Cu")
		(net "RST_SSD3_PERST_R_N")
	)
	(segment
		(start 254.577088 -235.566966)
		(end 257.413252 -235.003086)
		(width 0.15494)
		(layer "In15.Cu")
		(net "RST_SSD3_PERST_R_N")
	)
	(segment
		(start 213.830408 -241.704622)
		(end 214.608664 -242.482878)
		(width 0.15494)
		(layer "In15.Cu")
		(net "RST_SSD3_PERST_R_N")
	)
	(segment
		(start 233.0704 -241.6048)
		(end 233.583988 -241.091212)
		(width 0.15494)
		(layer "In15.Cu")
		(net "RST_SSD3_PERST_R_N")
	)
	(segment
		(start 332.852014 -241.508026)
		(end 338.819744 -241.508026)
		(width 0.15494)
		(layer "In15.Cu")
		(net "RST_SSD3_PERST_R_N")
	)
	(segment
		(start 156.667454 -230.86949)
		(end 160.747964 -234.95)
		(width 0.15494)
		(layer "In15.Cu")
		(net "RST_SSD3_PERST_R_N")
	)
	(segment
		(start 340.46541 -239.86236)
		(end 340.46541 -238.788448)
		(width 0.15494)
		(layer "In15.Cu")
		(net "RST_SSD3_PERST_R_N")
	)
	(segment
		(start 230.543862 -241.161062)
		(end 230.9876 -241.6048)
		(width 0.15494)
		(layer "In15.Cu")
		(net "RST_SSD3_PERST_R_N")
	)
	(segment
		(start 275.884386 -242.852448)
		(end 302.048164 -242.852448)
		(width 0.15494)
		(layer "In15.Cu")
		(net "RST_SSD3_PERST_R_N")
	)
	(segment
		(start 327.470008 -243.242592)
		(end 328.447908 -243.242592)
		(width 0.15494)
		(layer "In15.Cu")
		(net "RST_SSD3_PERST_R_N")
	)
	(segment
		(start 228.57714 -241.627406)
		(end 229.043484 -241.161062)
		(width 0.15494)
		(layer "In15.Cu")
		(net "RST_SSD3_PERST_R_N")
	)
	(segment
		(start 240.552732 -241.091212)
		(end 241.28603 -241.82451)
		(width 0.15494)
		(layer "In15.Cu")
		(net "RST_SSD3_PERST_R_N")
	)
	(segment
		(start 342.49487 -235.60913)
		(end 343.027 -235.077)
		(width 0.15494)
		(layer "In15.Cu")
		(net "RST_SSD3_PERST_R_N")
	)
	(segment
		(start 302.048164 -242.852448)
		(end 302.776128 -243.580412)
		(width 0.15494)
		(layer "In15.Cu")
		(net "RST_SSD3_PERST_R_N")
	)
	(segment
		(start 275.123402 -242.091464)
		(end 275.884386 -242.852448)
		(width 0.15494)
		(layer "In15.Cu")
		(net "RST_SSD3_PERST_R_N")
	)
	(segment
		(start 338.819744 -241.508026)
		(end 340.46541 -239.86236)
		(width 0.15494)
		(layer "In15.Cu")
		(net "RST_SSD3_PERST_R_N")
	)
	(segment
		(start 248.319544 -241.82451)
		(end 254.577088 -235.566966)
		(width 0.15494)
		(layer "In15.Cu")
		(net "RST_SSD3_PERST_R_N")
	)
	(segment
		(start 257.413252 -235.003086)
		(end 262.007096 -235.003086)
		(width 0.15494)
		(layer "In15.Cu")
		(net "RST_SSD3_PERST_R_N")
	)
	(segment
		(start 268.717522 -242.091464)
		(end 275.123402 -242.091464)
		(width 0.15494)
		(layer "In15.Cu")
		(net "RST_SSD3_PERST_R_N")
	)
	(segment
		(start 233.583988 -241.091212)
		(end 240.552732 -241.091212)
		(width 0.15494)
		(layer "In15.Cu")
		(net "RST_SSD3_PERST_R_N")
	)
	(segment
		(start 332.185264 -242.174776)
		(end 332.852014 -241.508026)
		(width 0.15494)
		(layer "In15.Cu")
		(net "RST_SSD3_PERST_R_N")
	)
	(segment
		(start 229.043484 -241.161062)
		(end 230.543862 -241.161062)
		(width 0.15494)
		(layer "In15.Cu")
		(net "RST_SSD3_PERST_R_N")
	)
	(segment
		(start 340.46541 -238.788448)
		(end 342.49487 -236.758988)
		(width 0.15494)
		(layer "In15.Cu")
		(net "RST_SSD3_PERST_R_N")
	)
	(segment
		(start 148.878544 -230.86949)
		(end 156.667454 -230.86949)
		(width 0.15494)
		(layer "In15.Cu")
		(net "RST_SSD3_PERST_R_N")
	)
	(segment
		(start 264.913364 -238.287306)
		(end 268.717522 -242.091464)
		(width 0.15494)
		(layer "In15.Cu")
		(net "RST_SSD3_PERST_R_N")
	)
	(segment
		(start 329.515724 -242.174776)
		(end 332.185264 -242.174776)
		(width 0.15494)
		(layer "In15.Cu")
		(net "RST_SSD3_PERST_R_N")
	)
	(segment
		(start 191.565022 -241.704622)
		(end 213.830408 -241.704622)
		(width 0.15494)
		(layer "In15.Cu")
		(net "RST_SSD3_PERST_R_N")
	)
	(segment
		(start 328.447908 -243.242592)
		(end 329.515724 -242.174776)
		(width 0.15494)
		(layer "In15.Cu")
		(net "RST_SSD3_PERST_R_N")
	)
	(segment
		(start 264.913364 -237.165896)
		(end 264.913364 -238.287306)
		(width 0.15494)
		(layer "In15.Cu")
		(net "RST_SSD3_PERST_R_N")
	)
	(segment
		(start 230.9876 -241.6048)
		(end 233.0704 -241.6048)
		(width 0.15494)
		(layer "In15.Cu")
		(net "RST_SSD3_PERST_R_N")
	)
	(segment
		(start 160.747964 -234.95)
		(end 184.8104 -234.95)
		(width 0.15494)
		(layer "In15.Cu")
		(net "RST_SSD3_PERST_R_N")
	)
	(segment
		(start 338.893912 -211.98713)
		(end 338.492846 -211.586064)
		(width 0.13208)
		(layer "F.Cu")
		(net "SSD10_CLK_EN_N")
	)
	(segment
		(start 338.492846 -210.0199)
		(end 338.582 -209.930746)
		(width 0.13208)
		(layer "F.Cu")
		(net "SSD10_CLK_EN_N")
	)
	(segment
		(start 338.582 -207.645)
		(end 338.582 -205.63205)
		(width 0.13208)
		(layer "F.Cu")
		(net "SSD10_CLK_EN_N")
	)
	(segment
		(start 338.492846 -211.586064)
		(end 338.492846 -210.0199)
		(width 0.13208)
		(layer "F.Cu")
		(net "SSD10_CLK_EN_N")
	)
	(segment
		(start 338.582 -209.930746)
		(end 338.582 -207.645)
		(width 0.13208)
		(layer "F.Cu")
		(net "SSD10_CLK_EN_N")
	)
	(via
		(at 338.582 -207.645)
		(size 0.762)
		(drill 0.381)
		(layers "F.Cu" "B.Cu")
		(net "SSD10_CLK_EN_N")
	)
	(segment
		(start 420.254684 -244.436646)
		(end 414.773872 -249.917458)
		(width 0.13208)
		(layer "F.Cu")
		(net "UART_PEX3_SDB_BUF_R_TX")
	)
	(segment
		(start 386.808726 -248.34342)
		(end 386.322824 -248.829322)
		(width 0.13208)
		(layer "F.Cu")
		(net "UART_PEX3_SDB_BUF_R_TX")
	)
	(segment
		(start 417.619942 -232.979214)
		(end 418.016944 -232.979214)
		(width 0.13208)
		(layer "F.Cu")
		(net "UART_PEX3_SDB_BUF_R_TX")
	)
	(segment
		(start 418.016944 -232.979214)
		(end 418.531802 -233.494072)
		(width 0.13208)
		(layer "F.Cu")
		(net "UART_PEX3_SDB_BUF_R_TX")
	)
	(segment
		(start 418.531802 -236.063282)
		(end 420.254684 -237.786164)
		(width 0.13208)
		(layer "F.Cu")
		(net "UART_PEX3_SDB_BUF_R_TX")
	)
	(segment
		(start 444.313818 -232.524554)
		(end 444.313818 -233.276902)
		(width 0.13208)
		(layer "F.Cu")
		(net "UART_PEX3_SDB_BUF_R_TX")
	)
	(segment
		(start 386.322824 -248.829322)
		(end 377.188222 -248.829322)
		(width 0.13208)
		(layer "F.Cu")
		(net "UART_PEX3_SDB_BUF_R_TX")
	)
	(segment
		(start 418.531802 -233.494072)
		(end 418.531802 -236.063282)
		(width 0.13208)
		(layer "F.Cu")
		(net "UART_PEX3_SDB_BUF_R_TX")
	)
	(segment
		(start 420.254684 -237.786164)
		(end 420.254684 -244.436646)
		(width 0.13208)
		(layer "F.Cu")
		(net "UART_PEX3_SDB_BUF_R_TX")
	)
	(segment
		(start 414.773872 -249.917458)
		(end 391.149586 -249.917458)
		(width 0.13208)
		(layer "F.Cu")
		(net "UART_PEX3_SDB_BUF_R_TX")
	)
	(segment
		(start 377.188222 -248.829322)
		(end 376.025156 -247.666256)
		(width 0.13208)
		(layer "F.Cu")
		(net "UART_PEX3_SDB_BUF_R_TX")
	)
	(segment
		(start 391.149586 -249.917458)
		(end 389.575548 -248.34342)
		(width 0.13208)
		(layer "F.Cu")
		(net "UART_PEX3_SDB_BUF_R_TX")
	)
	(segment
		(start 389.575548 -248.34342)
		(end 386.808726 -248.34342)
		(width 0.13208)
		(layer "F.Cu")
		(net "UART_PEX3_SDB_BUF_R_TX")
	)
	(via
		(at 418.531802 -233.494072)
		(size 0.508)
		(drill 0.254)
		(layers "F.Cu" "B.Cu")
		(net "UART_PEX3_SDB_BUF_R_TX")
	)
	(via
		(at 444.313818 -233.276902)
		(size 0.508)
		(drill 0.254)
		(layers "F.Cu" "B.Cu")
		(net "UART_PEX3_SDB_BUF_R_TX")
	)
	(via
		(at 376.025156 -247.666256)
		(size 0.508)
		(drill 0.254)
		(layers "F.Cu" "B.Cu")
		(net "UART_PEX3_SDB_BUF_R_TX")
	)
	(segment
		(start 375.599452 -248.09196)
		(end 374.03532 -248.09196)
		(width 0.13208)
		(layer "B.Cu")
		(net "UART_PEX3_SDB_BUF_R_TX")
	)
	(segment
		(start 376.025156 -247.666256)
		(end 375.599452 -248.09196)
		(width 0.13208)
		(layer "B.Cu")
		(net "UART_PEX3_SDB_BUF_R_TX")
	)
	(segment
		(start 376.562874 -248.203974)
		(end 376.025156 -247.666256)
		(width 0.13208)
		(layer "B.Cu")
		(net "UART_PEX3_SDB_BUF_R_TX")
	)
	(segment
		(start 377.588272 -248.203974)
		(end 376.562874 -248.203974)
		(width 0.13208)
		(layer "B.Cu")
		(net "UART_PEX3_SDB_BUF_R_TX")
	)
	(segment
		(start 441.742576 -231.48544)
		(end 420.540434 -231.48544)
		(width 0.15494)
		(layer "In15.Cu")
		(net "UART_PEX3_SDB_BUF_R_TX")
	)
	(segment
		(start 420.540434 -231.48544)
		(end 418.531802 -233.494072)
		(width 0.15494)
		(layer "In15.Cu")
		(net "UART_PEX3_SDB_BUF_R_TX")
	)
	(segment
		(start 443.534038 -233.276902)
		(end 441.742576 -231.48544)
		(width 0.15494)
		(layer "In15.Cu")
		(net "UART_PEX3_SDB_BUF_R_TX")
	)
	(segment
		(start 444.313818 -233.276902)
		(end 443.534038 -233.276902)
		(width 0.15494)
		(layer "In15.Cu")
		(net "UART_PEX3_SDB_BUF_R_TX")
	)
	(segment
		(start 234.909868 -149.046438)
		(end 234.632246 -149.046438)
		(width 0.1143)
		(layer "F.Cu")
		(net "CLK_100M_PEX3_REF_DN")
	)
	(segment
		(start 232.860088 -148.453348)
		(end 232.797096 -148.390356)
		(width 0.1143)
		(layer "F.Cu")
		(net "CLK_100M_PEX3_REF_DN")
	)
	(segment
		(start 235.219494 -148.736812)
		(end 234.909868 -149.046438)
		(width 0.1143)
		(layer "F.Cu")
		(net "CLK_100M_PEX3_REF_DN")
	)
	(segment
		(start 234.632246 -149.046438)
		(end 234.026456 -148.440648)
		(width 0.1143)
		(layer "F.Cu")
		(net "CLK_100M_PEX3_REF_DN")
	)
	(segment
		(start 232.797096 -148.390356)
		(end 232.471976 -148.390356)
		(width 0.1143)
		(layer "F.Cu")
		(net "CLK_100M_PEX3_REF_DN")
	)
	(segment
		(start 232.867962 -148.453348)
		(end 232.860088 -148.453348)
		(width 0.1143)
		(layer "F.Cu")
		(net "CLK_100M_PEX3_REF_DN")
	)
	(segment
		(start 234.026456 -148.440648)
		(end 232.880662 -148.440648)
		(width 0.1143)
		(layer "F.Cu")
		(net "CLK_100M_PEX3_REF_DN")
	)
	(segment
		(start 232.880662 -148.440648)
		(end 232.867962 -148.453348)
		(width 0.1143)
		(layer "F.Cu")
		(net "CLK_100M_PEX3_REF_DN")
	)
	(segment
		(start 217.635836 -226.811586)
		(end 217.635836 -227.27793)
		(width 0.13208)
		(layer "F.Cu")
		(net "SMB_NIC2_SCL")
	)
	(segment
		(start 220.503242 -226.295712)
		(end 220.503242 -224.865692)
		(width 0.13208)
		(layer "F.Cu")
		(net "SMB_NIC2_SCL")
	)
	(segment
		(start 217.893646 -227.53574)
		(end 219.263214 -227.53574)
		(width 0.13208)
		(layer "F.Cu")
		(net "SMB_NIC2_SCL")
	)
	(segment
		(start 220.503242 -224.865692)
		(end 223.306132 -224.865692)
		(width 0.13208)
		(layer "F.Cu")
		(net "SMB_NIC2_SCL")
	)
	(segment
		(start 223.306132 -224.865692)
		(end 223.467676 -224.704148)
		(width 0.13208)
		(layer "F.Cu")
		(net "SMB_NIC2_SCL")
	)
	(segment
		(start 217.635836 -227.27793)
		(end 217.893646 -227.53574)
		(width 0.13208)
		(layer "F.Cu")
		(net "SMB_NIC2_SCL")
	)
	(segment
		(start 219.263214 -227.53574)
		(end 220.503242 -226.295712)
		(width 0.13208)
		(layer "F.Cu")
		(net "SMB_NIC2_SCL")
	)
	(via
		(at 220.503242 -224.865692)
		(size 0.762)
		(drill 0.381)
		(layers "F.Cu" "B.Cu")
		(net "SMB_NIC2_SCL")
	)
	(segment
		(start 371.428518 -259.475224)
		(end 371.428518 -260.407658)
		(width 0.13208)
		(layer "F.Cu")
		(net "PEX3_SYS_ERR_N_G")
	)
	(segment
		(start 372.175532 -257.22326)
		(end 372.175532 -257.73126)
		(width 0.13208)
		(layer "F.Cu")
		(net "PEX3_SYS_ERR_N_G")
	)
	(segment
		(start 372.054374 -257.102102)
		(end 372.175532 -257.22326)
		(width 0.13208)
		(layer "F.Cu")
		(net "PEX3_SYS_ERR_N_G")
	)
	(segment
		(start 371.60835 -257.852164)
		(end 371.60835 -258.649978)
		(width 0.13208)
		(layer "F.Cu")
		(net "PEX3_SYS_ERR_N_G")
	)
	(segment
		(start 372.054628 -257.852164)
		(end 371.60835 -257.852164)
		(width 0.13208)
		(layer "F.Cu")
		(net "PEX3_SYS_ERR_N_G")
	)
	(segment
		(start 371.60835 -257.102102)
		(end 372.054374 -257.102102)
		(width 0.13208)
		(layer "F.Cu")
		(net "PEX3_SYS_ERR_N_G")
	)
	(segment
		(start 371.60835 -259.295392)
		(end 371.524784 -259.378958)
		(width 0.13208)
		(layer "F.Cu")
		(net "PEX3_SYS_ERR_N_G")
	)
	(segment
		(start 372.175532 -257.73126)
		(end 372.054628 -257.852164)
		(width 0.13208)
		(layer "F.Cu")
		(net "PEX3_SYS_ERR_N_G")
	)
	(segment
		(start 371.60835 -258.649978)
		(end 371.60835 -259.295392)
		(width 0.13208)
		(layer "F.Cu")
		(net "PEX3_SYS_ERR_N_G")
	)
	(segment
		(start 371.524784 -259.378958)
		(end 371.428518 -259.475224)
		(width 0.13208)
		(layer "F.Cu")
		(net "PEX3_SYS_ERR_N_G")
	)
	(via
		(at 371.60835 -258.649978)
		(size 0.508)
		(drill 0.254)
		(layers "F.Cu" "B.Cu")
		(net "PEX3_SYS_ERR_N_G")
	)
	(segment
		(start 211.491322 -228.126036)
		(end 211.398358 -228.219)
		(width 0.13208)
		(layer "F.Cu")
		(net "UART_MB_BIC_TX_BUF_R")
	)
	(segment
		(start 211.398358 -228.219)
		(end 210.836002 -228.219)
		(width 0.13208)
		(layer "F.Cu")
		(net "UART_MB_BIC_TX_BUF_R")
	)
	(segment
		(start 211.491322 -227.625656)
		(end 211.491322 -228.126036)
		(width 0.13208)
		(layer "F.Cu")
		(net "UART_MB_BIC_TX_BUF_R")
	)
	(via
		(at 239.748314 -331.878432)
		(size 0.508)
		(drill 0.254)
		(layers "F.Cu" "B.Cu")
		(net "UART_MB_BIC_TX_BUF_R")
	)
	(via
		(at 360.994452 -330.634848)
		(size 0.508)
		(drill 0.254)
		(layers "F.Cu" "B.Cu")
		(net "UART_MB_BIC_TX_BUF_R")
	)
	(via
		(at 210.836002 -228.219)
		(size 0.508)
		(drill 0.254)
		(layers "F.Cu" "B.Cu")
		(net "UART_MB_BIC_TX_BUF_R")
	)
	(segment
		(start 358.727248 -332.902052)
		(end 360.994452 -330.634848)
		(width 0.13208)
		(layer "B.Cu")
		(net "UART_MB_BIC_TX_BUF_R")
	)
	(segment
		(start 239.748314 -331.878432)
		(end 240.771934 -332.902052)
		(width 0.13208)
		(layer "B.Cu")
		(net "UART_MB_BIC_TX_BUF_R")
	)
	(segment
		(start 240.771934 -332.902052)
		(end 358.727248 -332.902052)
		(width 0.13208)
		(layer "B.Cu")
		(net "UART_MB_BIC_TX_BUF_R")
	)
	(segment
		(start 395.474952 -393.603734)
		(end 393.36472 -393.603734)
		(width 0.15494)
		(layer "In9.Cu")
		(net "UART_MB_BIC_TX_BUF_R")
	)
	(segment
		(start 360.994452 -330.634848)
		(end 360.994452 -331.333094)
		(width 0.15494)
		(layer "In9.Cu")
		(net "UART_MB_BIC_TX_BUF_R")
	)
	(segment
		(start 380.85649 -363.701076)
		(end 391.630916 -363.701076)
		(width 0.15494)
		(layer "In9.Cu")
		(net "UART_MB_BIC_TX_BUF_R")
	)
	(segment
		(start 403.315424 -375.385584)
		(end 403.315424 -385.763262)
		(width 0.15494)
		(layer "In9.Cu")
		(net "UART_MB_BIC_TX_BUF_R")
	)
	(segment
		(start 239.748314 -324.12051)
		(end 238.647224 -323.01942)
		(width 0.15494)
		(layer "In9.Cu")
		(net "UART_MB_BIC_TX_BUF_R")
	)
	(segment
		(start 211.99856 -228.219)
		(end 210.836002 -228.219)
		(width 0.15494)
		(layer "In9.Cu")
		(net "UART_MB_BIC_TX_BUF_R")
	)
	(segment
		(start 371.237764 -353.22129)
		(end 375.736612 -353.22129)
		(width 0.15494)
		(layer "In9.Cu")
		(net "UART_MB_BIC_TX_BUF_R")
	)
	(segment
		(start 369.581938 -351.565464)
		(end 371.237764 -353.22129)
		(width 0.15494)
		(layer "In9.Cu")
		(net "UART_MB_BIC_TX_BUF_R")
	)
	(segment
		(start 239.748314 -331.878432)
		(end 239.748314 -324.12051)
		(width 0.15494)
		(layer "In9.Cu")
		(net "UART_MB_BIC_TX_BUF_R")
	)
	(segment
		(start 218.277186 -236.036866)
		(end 218.277186 -230.062786)
		(width 0.15494)
		(layer "In9.Cu")
		(net "UART_MB_BIC_TX_BUF_R")
	)
	(segment
		(start 229.907846 -272.995136)
		(end 230.8352 -272.067782)
		(width 0.15494)
		(layer "In9.Cu")
		(net "UART_MB_BIC_TX_BUF_R")
	)
	(segment
		(start 234.017566 -323.01942)
		(end 232.990644 -321.992498)
		(width 0.15494)
		(layer "In9.Cu")
		(net "UART_MB_BIC_TX_BUF_R")
	)
	(segment
		(start 224.6884 -253.314454)
		(end 224.6884 -243.789454)
		(width 0.15494)
		(layer "In9.Cu")
		(net "UART_MB_BIC_TX_BUF_R")
	)
	(segment
		(start 217.217498 -229.003098)
		(end 212.782658 -229.003098)
		(width 0.15494)
		(layer "In9.Cu")
		(net "UART_MB_BIC_TX_BUF_R")
	)
	(segment
		(start 218.277186 -230.062786)
		(end 217.217498 -229.003098)
		(width 0.15494)
		(layer "In9.Cu")
		(net "UART_MB_BIC_TX_BUF_R")
	)
	(segment
		(start 392.492484 -409.490164)
		(end 393.089892 -409.490164)
		(width 0.15494)
		(layer "In9.Cu")
		(net "UART_MB_BIC_TX_BUF_R")
	)
	(segment
		(start 391.630916 -363.701076)
		(end 403.315424 -375.385584)
		(width 0.15494)
		(layer "In9.Cu")
		(net "UART_MB_BIC_TX_BUF_R")
	)
	(segment
		(start 375.736612 -353.22129)
		(end 376.282712 -353.76739)
		(width 0.15494)
		(layer "In9.Cu")
		(net "UART_MB_BIC_TX_BUF_R")
	)
	(segment
		(start 224.6884 -243.789454)
		(end 218.968066 -238.06912)
		(width 0.15494)
		(layer "In9.Cu")
		(net "UART_MB_BIC_TX_BUF_R")
	)
	(segment
		(start 360.994452 -331.333094)
		(end 369.581938 -339.92058)
		(width 0.15494)
		(layer "In9.Cu")
		(net "UART_MB_BIC_TX_BUF_R")
	)
	(segment
		(start 369.581938 -339.92058)
		(end 369.581938 -351.565464)
		(width 0.15494)
		(layer "In9.Cu")
		(net "UART_MB_BIC_TX_BUF_R")
	)
	(segment
		(start 232.990644 -282.64866)
		(end 229.907846 -279.565862)
		(width 0.15494)
		(layer "In9.Cu")
		(net "UART_MB_BIC_TX_BUF_R")
	)
	(segment
		(start 232.990644 -321.992498)
		(end 232.990644 -282.64866)
		(width 0.15494)
		(layer "In9.Cu")
		(net "UART_MB_BIC_TX_BUF_R")
	)
	(segment
		(start 218.968066 -236.727746)
		(end 218.277186 -236.036866)
		(width 0.15494)
		(layer "In9.Cu")
		(net "UART_MB_BIC_TX_BUF_R")
	)
	(segment
		(start 229.108 -257.734054)
		(end 224.6884 -253.314454)
		(width 0.15494)
		(layer "In9.Cu")
		(net "UART_MB_BIC_TX_BUF_R")
	)
	(segment
		(start 376.282712 -353.76739)
		(end 376.282712 -359.127298)
		(width 0.15494)
		(layer "In9.Cu")
		(net "UART_MB_BIC_TX_BUF_R")
	)
	(segment
		(start 392.04392 -409.0416)
		(end 392.492484 -409.490164)
		(width 0.15494)
		(layer "In9.Cu")
		(net "UART_MB_BIC_TX_BUF_R")
	)
	(segment
		(start 392.04392 -394.924534)
		(end 392.04392 -409.0416)
		(width 0.15494)
		(layer "In9.Cu")
		(net "UART_MB_BIC_TX_BUF_R")
	)
	(segment
		(start 230.8352 -262.1534)
		(end 229.108 -260.4262)
		(width 0.15494)
		(layer "In9.Cu")
		(net "UART_MB_BIC_TX_BUF_R")
	)
	(segment
		(start 212.782658 -229.003098)
		(end 211.99856 -228.219)
		(width 0.15494)
		(layer "In9.Cu")
		(net "UART_MB_BIC_TX_BUF_R")
	)
	(segment
		(start 229.108 -260.4262)
		(end 229.108 -257.734054)
		(width 0.15494)
		(layer "In9.Cu")
		(net "UART_MB_BIC_TX_BUF_R")
	)
	(segment
		(start 376.282712 -359.127298)
		(end 380.85649 -363.701076)
		(width 0.15494)
		(layer "In9.Cu")
		(net "UART_MB_BIC_TX_BUF_R")
	)
	(segment
		(start 218.968066 -238.06912)
		(end 218.968066 -236.727746)
		(width 0.15494)
		(layer "In9.Cu")
		(net "UART_MB_BIC_TX_BUF_R")
	)
	(segment
		(start 229.907846 -279.565862)
		(end 229.907846 -272.995136)
		(width 0.15494)
		(layer "In9.Cu")
		(net "UART_MB_BIC_TX_BUF_R")
	)
	(segment
		(start 238.647224 -323.01942)
		(end 234.017566 -323.01942)
		(width 0.15494)
		(layer "In9.Cu")
		(net "UART_MB_BIC_TX_BUF_R")
	)
	(segment
		(start 230.8352 -272.067782)
		(end 230.8352 -262.1534)
		(width 0.15494)
		(layer "In9.Cu")
		(net "UART_MB_BIC_TX_BUF_R")
	)
	(segment
		(start 403.315424 -385.763262)
		(end 395.474952 -393.603734)
		(width 0.15494)
		(layer "In9.Cu")
		(net "UART_MB_BIC_TX_BUF_R")
	)
	(segment
		(start 393.36472 -393.603734)
		(end 392.04392 -394.924534)
		(width 0.15494)
		(layer "In9.Cu")
		(net "UART_MB_BIC_TX_BUF_R")
	)
	(segment
		(start 33.109154 -27.04973)
		(end 33.109154 -26.03373)
		(width 0.13208)
		(layer "F.Cu")
		(net "PRSNT_SSD1_R_N")
	)
	(segment
		(start 341.293958 -229.190042)
		(end 340.36 -230.124)
		(width 0.13208)
		(layer "F.Cu")
		(net "PRSNT_SSD1_R_N")
	)
	(segment
		(start 32.575754 -36.515548)
		(end 33.396174 -36.515548)
		(width 0.13208)
		(layer "F.Cu")
		(net "PRSNT_SSD1_R_N")
	)
	(segment
		(start 33.11144 -27.04973)
		(end 33.109154 -27.04973)
		(width 0.13208)
		(layer "F.Cu")
		(net "PRSNT_SSD1_R_N")
	)
	(segment
		(start 34.103818 -27.04973)
		(end 33.11144 -27.04973)
		(width 0.13208)
		(layer "F.Cu")
		(net "PRSNT_SSD1_R_N")
	)
	(segment
		(start 34.120582 -27.066494)
		(end 34.103818 -27.04973)
		(width 0.13208)
		(layer "F.Cu")
		(net "PRSNT_SSD1_R_N")
	)
	(segment
		(start 341.293958 -227.987098)
		(end 341.293958 -229.190042)
		(width 0.13208)
		(layer "F.Cu")
		(net "PRSNT_SSD1_R_N")
	)
	(segment
		(start 34.942526 -27.066494)
		(end 34.120582 -27.066494)
		(width 0.13208)
		(layer "F.Cu")
		(net "PRSNT_SSD1_R_N")
	)
	(segment
		(start 233.867706 -223.904048)
		(end 234.267502 -224.303844)
		(width 0.13208)
		(layer "F.Cu")
		(net "PRSNT_SSD1_R_N")
	)
	(via
		(at 33.396174 -36.515548)
		(size 0.508)
		(drill 0.254)
		(layers "F.Cu" "B.Cu")
		(net "PRSNT_SSD1_R_N")
	)
	(via
		(at 58.633868 -79.727552)
		(size 0.508)
		(drill 0.254)
		(layers "F.Cu" "B.Cu")
		(net "PRSNT_SSD1_R_N")
	)
	(via
		(at 340.36 -230.124)
		(size 0.508)
		(drill 0.254)
		(layers "F.Cu" "B.Cu")
		(net "PRSNT_SSD1_R_N")
	)
	(via
		(at 234.048554 -229.5652)
		(size 0.508)
		(drill 0.254)
		(layers "F.Cu" "B.Cu")
		(net "PRSNT_SSD1_R_N")
	)
	(via
		(at 64.530732 -208.242154)
		(size 0.508)
		(drill 0.254)
		(layers "F.Cu" "B.Cu")
		(net "PRSNT_SSD1_R_N")
	)
	(via
		(at 234.267502 -224.303844)
		(size 0.4572)
		(drill 0.254)
		(layers "F.Cu" "B.Cu")
		(net "PRSNT_SSD1_R_N")
	)
	(via
		(at 43.23461 -79.164434)
		(size 0.508)
		(drill 0.254)
		(layers "F.Cu" "B.Cu")
		(net "PRSNT_SSD1_R_N")
	)
	(via
		(at 34.942526 -27.066494)
		(size 0.508)
		(drill 0.254)
		(layers "F.Cu" "B.Cu")
		(net "PRSNT_SSD1_R_N")
	)
	(segment
		(start 234.665012 -224.701354)
		(end 234.267502 -224.303844)
		(width 0.0889)
		(layer "In5.Cu")
		(net "PRSNT_SSD1_R_N")
	)
	(segment
		(start 31.763462 -34.882836)
		(end 31.763462 -29.742892)
		(width 0.15494)
		(layer "In5.Cu")
		(net "PRSNT_SSD1_R_N")
	)
	(segment
		(start 234.665012 -226.67722)
		(end 234.665012 -225.4758)
		(width 0.15494)
		(layer "In5.Cu")
		(net "PRSNT_SSD1_R_N")
	)
	(segment
		(start 31.763462 -29.742892)
		(end 34.43986 -27.066494)
		(width 0.15494)
		(layer "In5.Cu")
		(net "PRSNT_SSD1_R_N")
	)
	(segment
		(start 234.048554 -229.5652)
		(end 234.048554 -227.293678)
		(width 0.15494)
		(layer "In5.Cu")
		(net "PRSNT_SSD1_R_N")
	)
	(segment
		(start 57.945782 -84.777326)
		(end 58.633868 -84.08924)
		(width 0.15494)
		(layer "In5.Cu")
		(net "PRSNT_SSD1_R_N")
	)
	(segment
		(start 34.43986 -27.066494)
		(end 34.942526 -27.066494)
		(width 0.15494)
		(layer "In5.Cu")
		(net "PRSNT_SSD1_R_N")
	)
	(segment
		(start 38.81374 -74.743564)
		(end 38.81374 -43.893994)
		(width 0.15494)
		(layer "In5.Cu")
		(net "PRSNT_SSD1_R_N")
	)
	(segment
		(start 59.055 -154.6352)
		(end 59.055 -93.81617)
		(width 0.15494)
		(layer "In5.Cu")
		(net "PRSNT_SSD1_R_N")
	)
	(segment
		(start 64.530732 -208.242154)
		(end 64.530732 -205.20787)
		(width 0.15494)
		(layer "In5.Cu")
		(net "PRSNT_SSD1_R_N")
	)
	(segment
		(start 58.173366 -179.837588)
		(end 58.173366 -155.516834)
		(width 0.15494)
		(layer "In5.Cu")
		(net "PRSNT_SSD1_R_N")
	)
	(segment
		(start 58.173366 -155.516834)
		(end 59.055 -154.6352)
		(width 0.15494)
		(layer "In5.Cu")
		(net "PRSNT_SSD1_R_N")
	)
	(segment
		(start 62.92342 -203.600558)
		(end 62.92342 -184.587642)
		(width 0.15494)
		(layer "In5.Cu")
		(net "PRSNT_SSD1_R_N")
	)
	(segment
		(start 62.92342 -184.587642)
		(end 58.173366 -179.837588)
		(width 0.15494)
		(layer "In5.Cu")
		(net "PRSNT_SSD1_R_N")
	)
	(segment
		(start 234.048554 -227.293678)
		(end 234.665012 -226.67722)
		(width 0.15494)
		(layer "In5.Cu")
		(net "PRSNT_SSD1_R_N")
	)
	(segment
		(start 58.633868 -84.08924)
		(end 58.633868 -79.727552)
		(width 0.15494)
		(layer "In5.Cu")
		(net "PRSNT_SSD1_R_N")
	)
	(segment
		(start 33.396174 -36.515548)
		(end 31.763462 -34.882836)
		(width 0.15494)
		(layer "In5.Cu")
		(net "PRSNT_SSD1_R_N")
	)
	(segment
		(start 33.396174 -38.476428)
		(end 33.396174 -36.515548)
		(width 0.15494)
		(layer "In5.Cu")
		(net "PRSNT_SSD1_R_N")
	)
	(segment
		(start 57.945782 -92.706952)
		(end 57.945782 -84.777326)
		(width 0.15494)
		(layer "In5.Cu")
		(net "PRSNT_SSD1_R_N")
	)
	(segment
		(start 43.23461 -79.164434)
		(end 38.81374 -74.743564)
		(width 0.15494)
		(layer "In5.Cu")
		(net "PRSNT_SSD1_R_N")
	)
	(segment
		(start 59.055 -93.81617)
		(end 57.945782 -92.706952)
		(width 0.15494)
		(layer "In5.Cu")
		(net "PRSNT_SSD1_R_N")
	)
	(segment
		(start 38.81374 -43.893994)
		(end 33.396174 -38.476428)
		(width 0.15494)
		(layer "In5.Cu")
		(net "PRSNT_SSD1_R_N")
	)
	(segment
		(start 64.530732 -205.20787)
		(end 62.92342 -203.600558)
		(width 0.15494)
		(layer "In5.Cu")
		(net "PRSNT_SSD1_R_N")
	)
	(segment
		(start 234.665012 -225.4758)
		(end 234.665012 -224.701354)
		(width 0.0889)
		(layer "In5.Cu")
		(net "PRSNT_SSD1_R_N")
	)
	(segment
		(start 233.864912 -221.240858)
		(end 233.869992 -221.245938)
		(width 0.0889)
		(layer "In13.Cu")
		(net "PRSNT_SSD1_R_N")
	)
	(segment
		(start 234.665012 -221.739206)
		(end 234.665012 -223.906334)
		(width 0.0889)
		(layer "In13.Cu")
		(net "PRSNT_SSD1_R_N")
	)
	(segment
		(start 66.108072 -208.242154)
		(end 67.436238 -209.57032)
		(width 0.15494)
		(layer "In13.Cu")
		(net "PRSNT_SSD1_R_N")
	)
	(segment
		(start 125.632972 -218.291156)
		(end 125.657356 -218.291156)
		(width 0.15494)
		(layer "In13.Cu")
		(net "PRSNT_SSD1_R_N")
	)
	(segment
		(start 233.869992 -221.245938)
		(end 233.869992 -221.268798)
		(width 0.0889)
		(layer "In13.Cu")
		(net "PRSNT_SSD1_R_N")
	)
	(segment
		(start 116.06403 -210.81492)
		(end 122.11431 -216.8652)
		(width 0.15494)
		(layer "In13.Cu")
		(net "PRSNT_SSD1_R_N")
	)
	(segment
		(start 233.065066 -220.139006)
		(end 233.065066 -220.441012)
		(width 0.0889)
		(layer "In13.Cu")
		(net "PRSNT_SSD1_R_N")
	)
	(segment
		(start 233.330496 -220.706442)
		(end 233.632248 -220.706442)
		(width 0.0889)
		(layer "In13.Cu")
		(net "PRSNT_SSD1_R_N")
	)
	(segment
		(start 124.207016 -216.8652)
		(end 125.632972 -218.291156)
		(width 0.15494)
		(layer "In13.Cu")
		(net "PRSNT_SSD1_R_N")
	)
	(segment
		(start 234.125516 -221.501462)
		(end 234.130596 -221.506542)
		(width 0.0889)
		(layer "In13.Cu")
		(net "PRSNT_SSD1_R_N")
	)
	(segment
		(start 233.325416 -220.701362)
		(end 233.330496 -220.706442)
		(width 0.0889)
		(layer "In13.Cu")
		(net "PRSNT_SSD1_R_N")
	)
	(segment
		(start 125.685804 -218.319604)
		(end 149.091142 -218.319604)
		(width 0.15494)
		(layer "In13.Cu")
		(net "PRSNT_SSD1_R_N")
	)
	(segment
		(start 125.657356 -218.291156)
		(end 125.685804 -218.319604)
		(width 0.15494)
		(layer "In13.Cu")
		(net "PRSNT_SSD1_R_N")
	)
	(segment
		(start 234.130596 -221.506542)
		(end 234.432348 -221.506542)
		(width 0.0889)
		(layer "In13.Cu")
		(net "PRSNT_SSD1_R_N")
	)
	(segment
		(start 207.265778 -220.093032)
		(end 209.02168 -221.848934)
		(width 0.15494)
		(layer "In13.Cu")
		(net "PRSNT_SSD1_R_N")
	)
	(segment
		(start 221.115128 -219.906342)
		(end 223.52 -219.906342)
		(width 0.15494)
		(layer "In13.Cu")
		(net "PRSNT_SSD1_R_N")
	)
	(segment
		(start 233.069892 -220.445838)
		(end 233.069892 -220.468698)
		(width 0.0889)
		(layer "In13.Cu")
		(net "PRSNT_SSD1_R_N")
	)
	(segment
		(start 210.27644 -221.252034)
		(end 211.807298 -221.252034)
		(width 0.15494)
		(layer "In13.Cu")
		(net "PRSNT_SSD1_R_N")
	)
	(segment
		(start 211.807298 -221.252034)
		(end 212.411818 -221.856554)
		(width 0.15494)
		(layer "In13.Cu")
		(net "PRSNT_SSD1_R_N")
	)
	(segment
		(start 151.449532 -215.961214)
		(end 204.08773 -215.961214)
		(width 0.15494)
		(layer "In13.Cu")
		(net "PRSNT_SSD1_R_N")
	)
	(segment
		(start 233.302556 -220.701362)
		(end 233.325416 -220.701362)
		(width 0.0889)
		(layer "In13.Cu")
		(net "PRSNT_SSD1_R_N")
	)
	(segment
		(start 219.164916 -221.856554)
		(end 221.115128 -219.906342)
		(width 0.15494)
		(layer "In13.Cu")
		(net "PRSNT_SSD1_R_N")
	)
	(segment
		(start 233.065066 -220.441012)
		(end 233.069892 -220.445838)
		(width 0.0889)
		(layer "In13.Cu")
		(net "PRSNT_SSD1_R_N")
	)
	(segment
		(start 234.432348 -221.506542)
		(end 234.665012 -221.739206)
		(width 0.0889)
		(layer "In13.Cu")
		(net "PRSNT_SSD1_R_N")
	)
	(segment
		(start 100.21443 -209.64017)
		(end 109.61497 -209.64017)
		(width 0.15494)
		(layer "In13.Cu")
		(net "PRSNT_SSD1_R_N")
	)
	(segment
		(start 109.61497 -209.64017)
		(end 110.78972 -210.81492)
		(width 0.15494)
		(layer "In13.Cu")
		(net "PRSNT_SSD1_R_N")
	)
	(segment
		(start 99.67976 -210.17484)
		(end 100.21443 -209.64017)
		(width 0.15494)
		(layer "In13.Cu")
		(net "PRSNT_SSD1_R_N")
	)
	(segment
		(start 122.11431 -216.8652)
		(end 124.207016 -216.8652)
		(width 0.15494)
		(layer "In13.Cu")
		(net "PRSNT_SSD1_R_N")
	)
	(segment
		(start 76.14031 -210.17484)
		(end 99.67976 -210.17484)
		(width 0.15494)
		(layer "In13.Cu")
		(net "PRSNT_SSD1_R_N")
	)
	(segment
		(start 149.091142 -218.319604)
		(end 151.449532 -215.961214)
		(width 0.15494)
		(layer "In13.Cu")
		(net "PRSNT_SSD1_R_N")
	)
	(segment
		(start 234.102656 -221.501462)
		(end 234.125516 -221.501462)
		(width 0.0889)
		(layer "In13.Cu")
		(net "PRSNT_SSD1_R_N")
	)
	(segment
		(start 209.67954 -221.848934)
		(end 210.27644 -221.252034)
		(width 0.15494)
		(layer "In13.Cu")
		(net "PRSNT_SSD1_R_N")
	)
	(segment
		(start 67.436238 -209.57032)
		(end 75.53579 -209.57032)
		(width 0.15494)
		(layer "In13.Cu")
		(net "PRSNT_SSD1_R_N")
	)
	(segment
		(start 234.665012 -223.906334)
		(end 234.267502 -224.303844)
		(width 0.0889)
		(layer "In13.Cu")
		(net "PRSNT_SSD1_R_N")
	)
	(segment
		(start 232.832402 -219.906342)
		(end 233.065066 -220.139006)
		(width 0.0889)
		(layer "In13.Cu")
		(net "PRSNT_SSD1_R_N")
	)
	(segment
		(start 207.265778 -219.139262)
		(end 207.265778 -220.093032)
		(width 0.15494)
		(layer "In13.Cu")
		(net "PRSNT_SSD1_R_N")
	)
	(segment
		(start 209.02168 -221.848934)
		(end 209.67954 -221.848934)
		(width 0.15494)
		(layer "In13.Cu")
		(net "PRSNT_SSD1_R_N")
	)
	(segment
		(start 64.530732 -208.242154)
		(end 66.108072 -208.242154)
		(width 0.15494)
		(layer "In13.Cu")
		(net "PRSNT_SSD1_R_N")
	)
	(segment
		(start 233.632248 -220.706442)
		(end 233.864912 -220.939106)
		(width 0.0889)
		(layer "In13.Cu")
		(net "PRSNT_SSD1_R_N")
	)
	(segment
		(start 75.53579 -209.57032)
		(end 76.14031 -210.17484)
		(width 0.15494)
		(layer "In13.Cu")
		(net "PRSNT_SSD1_R_N")
	)
	(segment
		(start 204.08773 -215.961214)
		(end 207.265778 -219.139262)
		(width 0.15494)
		(layer "In13.Cu")
		(net "PRSNT_SSD1_R_N")
	)
	(segment
		(start 212.411818 -221.856554)
		(end 219.164916 -221.856554)
		(width 0.15494)
		(layer "In13.Cu")
		(net "PRSNT_SSD1_R_N")
	)
	(segment
		(start 233.864912 -220.939106)
		(end 233.864912 -221.240858)
		(width 0.0889)
		(layer "In13.Cu")
		(net "PRSNT_SSD1_R_N")
	)
	(segment
		(start 223.52 -219.906342)
		(end 232.832402 -219.906342)
		(width 0.0889)
		(layer "In13.Cu")
		(net "PRSNT_SSD1_R_N")
	)
	(segment
		(start 233.069892 -220.468698)
		(end 233.302556 -220.701362)
		(width 0.0889)
		(layer "In13.Cu")
		(net "PRSNT_SSD1_R_N")
	)
	(segment
		(start 110.78972 -210.81492)
		(end 116.06403 -210.81492)
		(width 0.15494)
		(layer "In13.Cu")
		(net "PRSNT_SSD1_R_N")
	)
	(segment
		(start 233.869992 -221.268798)
		(end 234.102656 -221.501462)
		(width 0.0889)
		(layer "In13.Cu")
		(net "PRSNT_SSD1_R_N")
	)
	(segment
		(start 242.694968 -229.51567)
		(end 241.800888 -230.40975)
		(width 0.15494)
		(layer "In15.Cu")
		(net "PRSNT_SSD1_R_N")
	)
	(segment
		(start 242.694968 -228.50983)
		(end 242.694968 -229.51567)
		(width 0.15494)
		(layer "In15.Cu")
		(net "PRSNT_SSD1_R_N")
	)
	(segment
		(start 325.93788 -231.89692)
		(end 324.55612 -231.89692)
		(width 0.15494)
		(layer "In15.Cu")
		(net "PRSNT_SSD1_R_N")
	)
	(segment
		(start 320.544444 -230.79964)
		(end 291.855906 -230.79964)
		(width 0.15494)
		(layer "In15.Cu")
		(net "PRSNT_SSD1_R_N")
	)
	(segment
		(start 250.381516 -224.366074)
		(end 249.77217 -224.97542)
		(width 0.15494)
		(layer "In15.Cu")
		(net "PRSNT_SSD1_R_N")
	)
	(segment
		(start 291.855906 -230.79964)
		(end 290.753546 -231.902)
		(width 0.15494)
		(layer "In15.Cu")
		(net "PRSNT_SSD1_R_N")
	)
	(segment
		(start 324.55612 -231.89692)
		(end 324.362572 -231.703372)
		(width 0.15494)
		(layer "In15.Cu")
		(net "PRSNT_SSD1_R_N")
	)
	(segment
		(start 326.898 -230.9368)
		(end 325.93788 -231.89692)
		(width 0.15494)
		(layer "In15.Cu")
		(net "PRSNT_SSD1_R_N")
	)
	(segment
		(start 323.353684 -231.846628)
		(end 321.591432 -231.846628)
		(width 0.15494)
		(layer "In15.Cu")
		(net "PRSNT_SSD1_R_N")
	)
	(segment
		(start 290.753546 -231.902)
		(end 271.37868 -231.902)
		(width 0.15494)
		(layer "In15.Cu")
		(net "PRSNT_SSD1_R_N")
	)
	(segment
		(start 265.63574 -226.15906)
		(end 262.215122 -226.15906)
		(width 0.15494)
		(layer "In15.Cu")
		(net "PRSNT_SSD1_R_N")
	)
	(segment
		(start 323.49694 -231.703372)
		(end 323.353684 -231.846628)
		(width 0.15494)
		(layer "In15.Cu")
		(net "PRSNT_SSD1_R_N")
	)
	(segment
		(start 234.893104 -230.40975)
		(end 234.048554 -229.5652)
		(width 0.15494)
		(layer "In15.Cu")
		(net "PRSNT_SSD1_R_N")
	)
	(segment
		(start 260.595364 -225.488246)
		(end 259.473192 -224.366074)
		(width 0.15494)
		(layer "In15.Cu")
		(net "PRSNT_SSD1_R_N")
	)
	(segment
		(start 330.143358 -230.405686)
		(end 329.612244 -230.9368)
		(width 0.15494)
		(layer "In15.Cu")
		(net "PRSNT_SSD1_R_N")
	)
	(segment
		(start 58.07075 -79.164434)
		(end 43.23461 -79.164434)
		(width 0.15494)
		(layer "In15.Cu")
		(net "PRSNT_SSD1_R_N")
	)
	(segment
		(start 262.215122 -226.15906)
		(end 260.595364 -225.488246)
		(width 0.15494)
		(layer "In15.Cu")
		(net "PRSNT_SSD1_R_N")
	)
	(segment
		(start 271.37868 -231.902)
		(end 265.63574 -226.15906)
		(width 0.15494)
		(layer "In15.Cu")
		(net "PRSNT_SSD1_R_N")
	)
	(segment
		(start 340.078314 -230.405686)
		(end 330.143358 -230.405686)
		(width 0.15494)
		(layer "In15.Cu")
		(net "PRSNT_SSD1_R_N")
	)
	(segment
		(start 58.633868 -79.727552)
		(end 58.07075 -79.164434)
		(width 0.15494)
		(layer "In15.Cu")
		(net "PRSNT_SSD1_R_N")
	)
	(segment
		(start 259.473192 -224.366074)
		(end 250.381516 -224.366074)
		(width 0.15494)
		(layer "In15.Cu")
		(net "PRSNT_SSD1_R_N")
	)
	(segment
		(start 321.591432 -231.846628)
		(end 320.544444 -230.79964)
		(width 0.15494)
		(layer "In15.Cu")
		(net "PRSNT_SSD1_R_N")
	)
	(segment
		(start 324.362572 -231.703372)
		(end 323.49694 -231.703372)
		(width 0.15494)
		(layer "In15.Cu")
		(net "PRSNT_SSD1_R_N")
	)
	(segment
		(start 241.800888 -230.40975)
		(end 234.893104 -230.40975)
		(width 0.15494)
		(layer "In15.Cu")
		(net "PRSNT_SSD1_R_N")
	)
	(segment
		(start 329.612244 -230.9368)
		(end 326.898 -230.9368)
		(width 0.15494)
		(layer "In15.Cu")
		(net "PRSNT_SSD1_R_N")
	)
	(segment
		(start 246.229378 -224.97542)
		(end 242.694968 -228.50983)
		(width 0.15494)
		(layer "In15.Cu")
		(net "PRSNT_SSD1_R_N")
	)
	(segment
		(start 249.77217 -224.97542)
		(end 246.229378 -224.97542)
		(width 0.15494)
		(layer "In15.Cu")
		(net "PRSNT_SSD1_R_N")
	)
	(segment
		(start 340.36 -230.124)
		(end 340.078314 -230.405686)
		(width 0.15494)
		(layer "In15.Cu")
		(net "PRSNT_SSD1_R_N")
	)
	(segment
		(start 148.675852 -36.515548)
		(end 149.496272 -36.515548)
		(width 0.13208)
		(layer "F.Cu")
		(net "PRSNT_SSD5_R_N")
	)
	(segment
		(start 345.29395 -225.587052)
		(end 345.693746 -225.986848)
		(width 0.13208)
		(layer "F.Cu")
		(net "PRSNT_SSD5_R_N")
	)
	(segment
		(start 150.22068 -27.066494)
		(end 151.042624 -27.066494)
		(width 0.13208)
		(layer "F.Cu")
		(net "PRSNT_SSD5_R_N")
	)
	(segment
		(start 149.209252 -27.04973)
		(end 150.203916 -27.04973)
		(width 0.13208)
		(layer "F.Cu")
		(net "PRSNT_SSD5_R_N")
	)
	(segment
		(start 150.203916 -27.04973)
		(end 150.22068 -27.066494)
		(width 0.13208)
		(layer "F.Cu")
		(net "PRSNT_SSD5_R_N")
	)
	(segment
		(start 149.209252 -26.03373)
		(end 149.209252 -27.04973)
		(width 0.13208)
		(layer "F.Cu")
		(net "PRSNT_SSD5_R_N")
	)
	(segment
		(start 231.46766 -223.104202)
		(end 231.867456 -223.503998)
		(width 0.13208)
		(layer "F.Cu")
		(net "PRSNT_SSD5_R_N")
	)
	(via
		(at 345.693746 -225.986848)
		(size 0.4572)
		(drill 0.254)
		(layers "F.Cu" "B.Cu")
		(net "PRSNT_SSD5_R_N")
	)
	(via
		(at 151.042624 -27.066494)
		(size 0.508)
		(drill 0.254)
		(layers "F.Cu" "B.Cu")
		(net "PRSNT_SSD5_R_N")
	)
	(via
		(at 207.553306 -226.14382)
		(size 0.508)
		(drill 0.254)
		(layers "F.Cu" "B.Cu")
		(net "PRSNT_SSD5_R_N")
	)
	(via
		(at 187.058808 -226.199192)
		(size 0.508)
		(drill 0.254)
		(layers "F.Cu" "B.Cu")
		(net "PRSNT_SSD5_R_N")
	)
	(via
		(at 149.496272 -36.515548)
		(size 0.508)
		(drill 0.254)
		(layers "F.Cu" "B.Cu")
		(net "PRSNT_SSD5_R_N")
	)
	(via
		(at 183.686958 -184.967626)
		(size 0.508)
		(drill 0.254)
		(layers "F.Cu" "B.Cu")
		(net "PRSNT_SSD5_R_N")
	)
	(via
		(at 146.445224 -184.967626)
		(size 0.508)
		(drill 0.254)
		(layers "F.Cu" "B.Cu")
		(net "PRSNT_SSD5_R_N")
	)
	(via
		(at 231.867456 -223.503998)
		(size 0.4572)
		(drill 0.254)
		(layers "F.Cu" "B.Cu")
		(net "PRSNT_SSD5_R_N")
	)
	(segment
		(start 183.686958 -184.967626)
		(end 183.686958 -196.718174)
		(width 0.15494)
		(layer "In5.Cu")
		(net "PRSNT_SSD5_R_N")
	)
	(segment
		(start 147.86356 -34.882836)
		(end 147.86356 -29.742892)
		(width 0.15494)
		(layer "In5.Cu")
		(net "PRSNT_SSD5_R_N")
	)
	(segment
		(start 183.686958 -196.718174)
		(end 184.715912 -197.747128)
		(width 0.15494)
		(layer "In5.Cu")
		(net "PRSNT_SSD5_R_N")
	)
	(segment
		(start 144.4752 -170.561)
		(end 144.4752 -163.99256)
		(width 0.15494)
		(layer "In5.Cu")
		(net "PRSNT_SSD5_R_N")
	)
	(segment
		(start 146.445224 -172.531024)
		(end 144.4752 -170.561)
		(width 0.15494)
		(layer "In5.Cu")
		(net "PRSNT_SSD5_R_N")
	)
	(segment
		(start 183.707278 -213.97214)
		(end 186.68365 -221.157546)
		(width 0.15494)
		(layer "In5.Cu")
		(net "PRSNT_SSD5_R_N")
	)
	(segment
		(start 147.86356 -29.742892)
		(end 150.539958 -27.066494)
		(width 0.15494)
		(layer "In5.Cu")
		(net "PRSNT_SSD5_R_N")
	)
	(segment
		(start 183.707278 -201.694288)
		(end 183.707278 -213.97214)
		(width 0.15494)
		(layer "In5.Cu")
		(net "PRSNT_SSD5_R_N")
	)
	(segment
		(start 149.496272 -36.515548)
		(end 147.86356 -34.882836)
		(width 0.15494)
		(layer "In5.Cu")
		(net "PRSNT_SSD5_R_N")
	)
	(segment
		(start 186.68365 -225.824034)
		(end 187.058808 -226.199192)
		(width 0.15494)
		(layer "In5.Cu")
		(net "PRSNT_SSD5_R_N")
	)
	(segment
		(start 143.94688 -111.526574)
		(end 143.94688 -92.260674)
		(width 0.15494)
		(layer "In5.Cu")
		(net "PRSNT_SSD5_R_N")
	)
	(segment
		(start 154.62758 -44.632372)
		(end 149.506178 -39.51097)
		(width 0.15494)
		(layer "In5.Cu")
		(net "PRSNT_SSD5_R_N")
	)
	(segment
		(start 150.241508 -85.966046)
		(end 150.241508 -80.09763)
		(width 0.15494)
		(layer "In5.Cu")
		(net "PRSNT_SSD5_R_N")
	)
	(segment
		(start 143.039846 -112.433608)
		(end 143.94688 -111.526574)
		(width 0.15494)
		(layer "In5.Cu")
		(net "PRSNT_SSD5_R_N")
	)
	(segment
		(start 149.506178 -36.525454)
		(end 149.496272 -36.515548)
		(width 0.15494)
		(layer "In5.Cu")
		(net "PRSNT_SSD5_R_N")
	)
	(segment
		(start 149.506178 -39.51097)
		(end 149.506178 -36.525454)
		(width 0.15494)
		(layer "In5.Cu")
		(net "PRSNT_SSD5_R_N")
	)
	(segment
		(start 184.715912 -200.685654)
		(end 183.707278 -201.694288)
		(width 0.15494)
		(layer "In5.Cu")
		(net "PRSNT_SSD5_R_N")
	)
	(segment
		(start 150.241508 -80.09763)
		(end 154.62758 -75.711558)
		(width 0.15494)
		(layer "In5.Cu")
		(net "PRSNT_SSD5_R_N")
	)
	(segment
		(start 184.715912 -197.747128)
		(end 184.715912 -200.685654)
		(width 0.15494)
		(layer "In5.Cu")
		(net "PRSNT_SSD5_R_N")
	)
	(segment
		(start 143.039846 -162.557206)
		(end 143.039846 -112.433608)
		(width 0.15494)
		(layer "In5.Cu")
		(net "PRSNT_SSD5_R_N")
	)
	(segment
		(start 154.62758 -75.711558)
		(end 154.62758 -44.632372)
		(width 0.15494)
		(layer "In5.Cu")
		(net "PRSNT_SSD5_R_N")
	)
	(segment
		(start 143.94688 -92.260674)
		(end 150.241508 -85.966046)
		(width 0.15494)
		(layer "In5.Cu")
		(net "PRSNT_SSD5_R_N")
	)
	(segment
		(start 186.68365 -221.157546)
		(end 186.68365 -225.824034)
		(width 0.15494)
		(layer "In5.Cu")
		(net "PRSNT_SSD5_R_N")
	)
	(segment
		(start 150.539958 -27.066494)
		(end 151.042624 -27.066494)
		(width 0.15494)
		(layer "In5.Cu")
		(net "PRSNT_SSD5_R_N")
	)
	(segment
		(start 144.4752 -163.99256)
		(end 143.039846 -162.557206)
		(width 0.15494)
		(layer "In5.Cu")
		(net "PRSNT_SSD5_R_N")
	)
	(segment
		(start 146.445224 -184.967626)
		(end 146.445224 -172.531024)
		(width 0.15494)
		(layer "In5.Cu")
		(net "PRSNT_SSD5_R_N")
	)
	(segment
		(start 225.17989 -228.7778)
		(end 208.8388 -228.7778)
		(width 0.15494)
		(layer "In7.Cu")
		(net "PRSNT_SSD5_R_N")
	)
	(segment
		(start 231.867456 -223.503998)
		(end 229.28453 -226.086924)
		(width 0.15494)
		(layer "In7.Cu")
		(net "PRSNT_SSD5_R_N")
	)
	(segment
		(start 229.28453 -226.086924)
		(end 227.870766 -226.086924)
		(width 0.15494)
		(layer "In7.Cu")
		(net "PRSNT_SSD5_R_N")
	)
	(segment
		(start 227.870766 -226.086924)
		(end 225.17989 -228.7778)
		(width 0.15494)
		(layer "In7.Cu")
		(net "PRSNT_SSD5_R_N")
	)
	(segment
		(start 208.407 -226.997514)
		(end 207.553306 -226.14382)
		(width 0.15494)
		(layer "In7.Cu")
		(net "PRSNT_SSD5_R_N")
	)
	(segment
		(start 208.407 -228.346)
		(end 208.407 -226.997514)
		(width 0.15494)
		(layer "In7.Cu")
		(net "PRSNT_SSD5_R_N")
	)
	(segment
		(start 208.8388 -228.7778)
		(end 208.407 -228.346)
		(width 0.15494)
		(layer "In7.Cu")
		(net "PRSNT_SSD5_R_N")
	)
	(segment
		(start 245.676928 -232.113328)
		(end 244.75694 -231.19334)
		(width 0.15494)
		(layer "In13.Cu")
		(net "PRSNT_SSD5_R_N")
	)
	(segment
		(start 346.091256 -226.384358)
		(end 346.091256 -227.161344)
		(width 0.0889)
		(layer "In13.Cu")
		(net "PRSNT_SSD5_R_N")
	)
	(segment
		(start 335.568544 -237.8202)
		(end 335.035144 -237.2868)
		(width 0.15494)
		(layer "In13.Cu")
		(net "PRSNT_SSD5_R_N")
	)
	(segment
		(start 234.19054 -231.19334)
		(end 231.867456 -228.870256)
		(width 0.15494)
		(layer "In13.Cu")
		(net "PRSNT_SSD5_R_N")
	)
	(segment
		(start 146.445224 -184.967626)
		(end 183.686958 -184.967626)
		(width 0.15494)
		(layer "In13.Cu")
		(net "PRSNT_SSD5_R_N")
	)
	(segment
		(start 345.694 -227.5586)
		(end 345.694 -231.8258)
		(width 0.15494)
		(layer "In13.Cu")
		(net "PRSNT_SSD5_R_N")
	)
	(segment
		(start 231.867456 -228.870256)
		(end 231.867456 -223.503998)
		(width 0.15494)
		(layer "In13.Cu")
		(net "PRSNT_SSD5_R_N")
	)
	(segment
		(start 346.091256 -227.161344)
		(end 345.694 -227.5586)
		(width 0.15494)
		(layer "In13.Cu")
		(net "PRSNT_SSD5_R_N")
	)
	(segment
		(start 335.035144 -237.2868)
		(end 330.487274 -237.2868)
		(width 0.15494)
		(layer "In13.Cu")
		(net "PRSNT_SSD5_R_N")
	)
	(segment
		(start 207.205326 -226.4918)
		(end 206.364586 -226.4918)
		(width 0.15494)
		(layer "In13.Cu")
		(net "PRSNT_SSD5_R_N")
	)
	(segment
		(start 316.328044 -236.619034)
		(end 276.831044 -236.619034)
		(width 0.15494)
		(layer "In13.Cu")
		(net "PRSNT_SSD5_R_N")
	)
	(segment
		(start 247.096788 -232.701846)
		(end 245.676928 -232.113328)
		(width 0.15494)
		(layer "In13.Cu")
		(net "PRSNT_SSD5_R_N")
	)
	(segment
		(start 343.981278 -233.538522)
		(end 341.619078 -233.538522)
		(width 0.15494)
		(layer "In13.Cu")
		(net "PRSNT_SSD5_R_N")
	)
	(segment
		(start 337.439 -234.7722)
		(end 337.439 -236.601254)
		(width 0.15494)
		(layer "In13.Cu")
		(net "PRSNT_SSD5_R_N")
	)
	(segment
		(start 341.619078 -233.538522)
		(end 340.9188 -234.2388)
		(width 0.15494)
		(layer "In13.Cu")
		(net "PRSNT_SSD5_R_N")
	)
	(segment
		(start 337.439 -236.601254)
		(end 336.220054 -237.8202)
		(width 0.15494)
		(layer "In13.Cu")
		(net "PRSNT_SSD5_R_N")
	)
	(segment
		(start 207.553306 -226.14382)
		(end 207.205326 -226.4918)
		(width 0.15494)
		(layer "In13.Cu")
		(net "PRSNT_SSD5_R_N")
	)
	(segment
		(start 345.693746 -225.986848)
		(end 346.091256 -226.384358)
		(width 0.0889)
		(layer "In13.Cu")
		(net "PRSNT_SSD5_R_N")
	)
	(segment
		(start 206.071978 -226.199192)
		(end 187.058808 -226.199192)
		(width 0.15494)
		(layer "In13.Cu")
		(net "PRSNT_SSD5_R_N")
	)
	(segment
		(start 330.487274 -237.2868)
		(end 329.547474 -238.2266)
		(width 0.15494)
		(layer "In13.Cu")
		(net "PRSNT_SSD5_R_N")
	)
	(segment
		(start 345.694 -231.8258)
		(end 343.981278 -233.538522)
		(width 0.15494)
		(layer "In13.Cu")
		(net "PRSNT_SSD5_R_N")
	)
	(segment
		(start 258.01828 -231.84612)
		(end 257.162554 -232.701846)
		(width 0.15494)
		(layer "In13.Cu")
		(net "PRSNT_SSD5_R_N")
	)
	(segment
		(start 317.93561 -238.2266)
		(end 316.328044 -236.619034)
		(width 0.15494)
		(layer "In13.Cu")
		(net "PRSNT_SSD5_R_N")
	)
	(segment
		(start 336.220054 -237.8202)
		(end 335.568544 -237.8202)
		(width 0.15494)
		(layer "In13.Cu")
		(net "PRSNT_SSD5_R_N")
	)
	(segment
		(start 329.547474 -238.2266)
		(end 317.93561 -238.2266)
		(width 0.15494)
		(layer "In13.Cu")
		(net "PRSNT_SSD5_R_N")
	)
	(segment
		(start 257.162554 -232.701846)
		(end 247.096788 -232.701846)
		(width 0.15494)
		(layer "In13.Cu")
		(net "PRSNT_SSD5_R_N")
	)
	(segment
		(start 244.75694 -231.19334)
		(end 234.19054 -231.19334)
		(width 0.15494)
		(layer "In13.Cu")
		(net "PRSNT_SSD5_R_N")
	)
	(segment
		(start 276.831044 -236.619034)
		(end 272.05813 -231.84612)
		(width 0.15494)
		(layer "In13.Cu")
		(net "PRSNT_SSD5_R_N")
	)
	(segment
		(start 206.364586 -226.4918)
		(end 206.071978 -226.199192)
		(width 0.15494)
		(layer "In13.Cu")
		(net "PRSNT_SSD5_R_N")
	)
	(segment
		(start 272.05813 -231.84612)
		(end 258.01828 -231.84612)
		(width 0.15494)
		(layer "In13.Cu")
		(net "PRSNT_SSD5_R_N")
	)
	(segment
		(start 340.9188 -234.2388)
		(end 337.9724 -234.2388)
		(width 0.15494)
		(layer "In13.Cu")
		(net "PRSNT_SSD5_R_N")
	)
	(segment
		(start 337.9724 -234.2388)
		(end 337.439 -234.7722)
		(width 0.15494)
		(layer "In13.Cu")
		(net "PRSNT_SSD5_R_N")
	)
	(segment
		(start 339.598 -201.56805)
		(end 339.598 -202.184)
		(width 0.13208)
		(layer "F.Cu")
		(net "SSD14_PWRDIS")
	)
	(segment
		(start 342.093804 -214.387176)
		(end 341.694008 -213.98738)
		(width 0.13208)
		(layer "F.Cu")
		(net "SSD14_PWRDIS")
	)
	(via
		(at 339.598 -202.184)
		(size 0.508)
		(drill 0.254)
		(layers "F.Cu" "B.Cu")
		(net "SSD14_PWRDIS")
	)
	(via
		(at 341.694008 -213.98738)
		(size 0.4572)
		(drill 0.254)
		(layers "F.Cu" "B.Cu")
		(net "SSD14_PWRDIS")
	)
	(segment
		(start 340.10473 -206.140304)
		(end 340.10473 -202.69073)
		(width 0.15494)
		(layer "In5.Cu")
		(net "SSD14_PWRDIS")
	)
	(segment
		(start 342.15324 -213.528148)
		(end 342.15324 -211.33308)
		(width 0.15494)
		(layer "In5.Cu")
		(net "SSD14_PWRDIS")
	)
	(segment
		(start 340.10473 -202.69073)
		(end 339.598 -202.184)
		(width 0.15494)
		(layer "In5.Cu")
		(net "SSD14_PWRDIS")
	)
	(segment
		(start 341.81542 -210.99526)
		(end 341.81542 -207.850994)
		(width 0.15494)
		(layer "In5.Cu")
		(net "SSD14_PWRDIS")
	)
	(segment
		(start 342.15324 -211.33308)
		(end 341.81542 -210.99526)
		(width 0.15494)
		(layer "In5.Cu")
		(net "SSD14_PWRDIS")
	)
	(segment
		(start 341.694008 -213.98738)
		(end 342.15324 -213.528148)
		(width 0.15494)
		(layer "In5.Cu")
		(net "SSD14_PWRDIS")
	)
	(segment
		(start 341.81542 -207.850994)
		(end 340.10473 -206.140304)
		(width 0.15494)
		(layer "In5.Cu")
		(net "SSD14_PWRDIS")
	)
	(segment
		(start 417.558474 -241.83975)
		(end 418.45738 -241.83975)
		(width 0.13208)
		(layer "F.Cu")
		(net "UART_PEX2_SDB_BUF_R_TX")
	)
	(segment
		(start 444.508382 -224.700846)
		(end 443.708536 -224.700846)
		(width 0.13208)
		(layer "F.Cu")
		(net "UART_PEX2_SDB_BUF_R_TX")
	)
	(via
		(at 443.708536 -224.700846)
		(size 0.508)
		(drill 0.254)
		(layers "F.Cu" "B.Cu")
		(net "UART_PEX2_SDB_BUF_R_TX")
	)
	(via
		(at 418.45738 -241.83975)
		(size 0.508)
		(drill 0.254)
		(layers "F.Cu" "B.Cu")
		(net "UART_PEX2_SDB_BUF_R_TX")
	)
	(via
		(at 375.715784 -246.38)
		(size 0.508)
		(drill 0.254)
		(layers "F.Cu" "B.Cu")
		(net "UART_PEX2_SDB_BUF_R_TX")
	)
	(segment
		(start 377.67895 -245.872)
		(end 377.288298 -245.872)
		(width 0.13208)
		(layer "B.Cu")
		(net "UART_PEX2_SDB_BUF_R_TX")
	)
	(segment
		(start 374.746012 -246.791988)
		(end 374.03532 -246.791988)
		(width 0.13208)
		(layer "B.Cu")
		(net "UART_PEX2_SDB_BUF_R_TX")
	)
	(segment
		(start 377.288298 -245.872)
		(end 376.780298 -246.38)
		(width 0.13208)
		(layer "B.Cu")
		(net "UART_PEX2_SDB_BUF_R_TX")
	)
	(segment
		(start 376.780298 -246.38)
		(end 375.715784 -246.38)
		(width 0.13208)
		(layer "B.Cu")
		(net "UART_PEX2_SDB_BUF_R_TX")
	)
	(segment
		(start 375.715784 -246.38)
		(end 375.158 -246.38)
		(width 0.13208)
		(layer "B.Cu")
		(net "UART_PEX2_SDB_BUF_R_TX")
	)
	(segment
		(start 375.158 -246.38)
		(end 374.746012 -246.791988)
		(width 0.13208)
		(layer "B.Cu")
		(net "UART_PEX2_SDB_BUF_R_TX")
	)
	(segment
		(start 375.715784 -246.38)
		(end 381.297942 -246.38)
		(width 0.15494)
		(layer "In13.Cu")
		(net "UART_PEX2_SDB_BUF_R_TX")
	)
	(segment
		(start 382.50622 -244.503702)
		(end 384.425952 -244.503702)
		(width 0.15494)
		(layer "In13.Cu")
		(net "UART_PEX2_SDB_BUF_R_TX")
	)
	(segment
		(start 381.907034 -245.770908)
		(end 381.907034 -245.102888)
		(width 0.15494)
		(layer "In13.Cu")
		(net "UART_PEX2_SDB_BUF_R_TX")
	)
	(segment
		(start 417.72713 -242.57)
		(end 418.45738 -241.83975)
		(width 0.15494)
		(layer "In13.Cu")
		(net "UART_PEX2_SDB_BUF_R_TX")
	)
	(segment
		(start 384.425952 -244.503702)
		(end 385.628388 -243.301266)
		(width 0.15494)
		(layer "In13.Cu")
		(net "UART_PEX2_SDB_BUF_R_TX")
	)
	(segment
		(start 385.628388 -242.94465)
		(end 386.003038 -242.57)
		(width 0.15494)
		(layer "In13.Cu")
		(net "UART_PEX2_SDB_BUF_R_TX")
	)
	(segment
		(start 381.297942 -246.38)
		(end 381.907034 -245.770908)
		(width 0.15494)
		(layer "In13.Cu")
		(net "UART_PEX2_SDB_BUF_R_TX")
	)
	(segment
		(start 381.907034 -245.102888)
		(end 382.50622 -244.503702)
		(width 0.15494)
		(layer "In13.Cu")
		(net "UART_PEX2_SDB_BUF_R_TX")
	)
	(segment
		(start 385.628388 -243.301266)
		(end 385.628388 -242.94465)
		(width 0.15494)
		(layer "In13.Cu")
		(net "UART_PEX2_SDB_BUF_R_TX")
	)
	(segment
		(start 386.003038 -242.57)
		(end 417.72713 -242.57)
		(width 0.15494)
		(layer "In13.Cu")
		(net "UART_PEX2_SDB_BUF_R_TX")
	)
	(segment
		(start 418.45738 -241.83975)
		(end 438.092596 -241.83975)
		(width 0.15494)
		(layer "In15.Cu")
		(net "UART_PEX2_SDB_BUF_R_TX")
	)
	(segment
		(start 445.888618 -226.880928)
		(end 443.708536 -224.700846)
		(width 0.15494)
		(layer "In15.Cu")
		(net "UART_PEX2_SDB_BUF_R_TX")
	)
	(segment
		(start 445.888618 -234.043728)
		(end 445.888618 -226.880928)
		(width 0.15494)
		(layer "In15.Cu")
		(net "UART_PEX2_SDB_BUF_R_TX")
	)
	(segment
		(start 438.092596 -241.83975)
		(end 445.888618 -234.043728)
		(width 0.15494)
		(layer "In15.Cu")
		(net "UART_PEX2_SDB_BUF_R_TX")
	)
	(segment
		(start 222.226886 -191.483742)
		(end 222.226886 -193.378328)
		(width 0.13208)
		(layer "F.Cu")
		(net "SPI2_DI_BUF")
	)
	(segment
		(start 221.926912 -191.183768)
		(end 222.226886 -191.483742)
		(width 0.13208)
		(layer "F.Cu")
		(net "SPI2_DI_BUF")
	)
	(via
		(at 221.926912 -191.183768)
		(size 0.508)
		(drill 0.254)
		(layers "F.Cu" "B.Cu")
		(net "SPI2_DI_BUF")
	)
	(segment
		(start 223.30283 -192.559686)
		(end 221.926912 -191.183768)
		(width 0.13208)
		(layer "B.Cu")
		(net "SPI2_DI_BUF")
	)
	(segment
		(start 223.533716 -192.559686)
		(end 223.30283 -192.559686)
		(width 0.13208)
		(layer "B.Cu")
		(net "SPI2_DI_BUF")
	)
	(segment
		(start 131.471162 -175.400462)
		(end 131.647946 -175.865536)
		(width 0.13208)
		(layer "F.Cu")
		(net "SMB_BMC_9QXL2001_SDA")
	)
	(via
		(at 130.70459 -173.05655)
		(size 0.6604)
		(drill 0.3302)
		(layers "F.Cu" "B.Cu")
		(net "SMB_BMC_9QXL2001_SDA")
	)
	(via
		(at 131.647946 -175.865536)
		(size 0.4572)
		(drill 0.254)
		(layers "F.Cu" "B.Cu")
		(net "SMB_BMC_9QXL2001_SDA")
	)
	(segment
		(start 131.647946 -175.865536)
		(end 131.647946 -174.801022)
		(width 0.13208)
		(layer "B.Cu")
		(net "SMB_BMC_9QXL2001_SDA")
	)
	(segment
		(start 131.647946 -174.801022)
		(end 131.463034 -174.61611)
		(width 0.13208)
		(layer "B.Cu")
		(net "SMB_BMC_9QXL2001_SDA")
	)
	(segment
		(start 130.70459 -173.05655)
		(end 130.70459 -172.546264)
		(width 0.13208)
		(layer "B.Cu")
		(net "SMB_BMC_9QXL2001_SDA")
	)
	(segment
		(start 131.463034 -174.61611)
		(end 131.463034 -173.814994)
		(width 0.13208)
		(layer "B.Cu")
		(net "SMB_BMC_9QXL2001_SDA")
	)
	(segment
		(start 130.49885 -172.340524)
		(end 130.49885 -171.83862)
		(width 0.13208)
		(layer "B.Cu")
		(net "SMB_BMC_9QXL2001_SDA")
	)
	(segment
		(start 131.463034 -173.814994)
		(end 130.70459 -173.05655)
		(width 0.13208)
		(layer "B.Cu")
		(net "SMB_BMC_9QXL2001_SDA")
	)
	(segment
		(start 130.70459 -172.546264)
		(end 130.49885 -172.340524)
		(width 0.13208)
		(layer "B.Cu")
		(net "SMB_BMC_9QXL2001_SDA")
	)
	(segment
		(start 232.794302 -148.890482)
		(end 232.471976 -148.890482)
		(width 0.1143)
		(layer "F.Cu")
		(net "CLK_100M_PEX3_REF_DP")
	)
	(segment
		(start 235.219494 -149.752812)
		(end 234.88142 -149.414738)
		(width 0.1143)
		(layer "F.Cu")
		(net "CLK_100M_PEX3_REF_DP")
	)
	(segment
		(start 234.479592 -149.414738)
		(end 233.873802 -148.808948)
		(width 0.1143)
		(layer "F.Cu")
		(net "CLK_100M_PEX3_REF_DP")
	)
	(segment
		(start 233.873802 -148.808948)
		(end 232.875836 -148.808948)
		(width 0.1143)
		(layer "F.Cu")
		(net "CLK_100M_PEX3_REF_DP")
	)
	(segment
		(start 234.88142 -149.414738)
		(end 234.479592 -149.414738)
		(width 0.1143)
		(layer "F.Cu")
		(net "CLK_100M_PEX3_REF_DP")
	)
	(segment
		(start 232.875836 -148.808948)
		(end 232.794302 -148.890482)
		(width 0.1143)
		(layer "F.Cu")
		(net "CLK_100M_PEX3_REF_DP")
	)
	(segment
		(start 225.867722 -221.504256)
		(end 225.467926 -221.904052)
		(width 0.13208)
		(layer "F.Cu")
		(net "SMB_FIO_SCL")
	)
	(via
		(at 219.168472 -226.433634)
		(size 0.6604)
		(drill 0.3302)
		(layers "F.Cu" "B.Cu")
		(net "SMB_FIO_SCL")
	)
	(via
		(at 225.467926 -221.904052)
		(size 0.4572)
		(drill 0.254)
		(layers "F.Cu" "B.Cu")
		(net "SMB_FIO_SCL")
	)
	(segment
		(start 217.644472 -226.755452)
		(end 217.96629 -226.433634)
		(width 0.13208)
		(layer "B.Cu")
		(net "SMB_FIO_SCL")
	)
	(segment
		(start 217.96629 -226.433634)
		(end 219.168472 -226.433634)
		(width 0.13208)
		(layer "B.Cu")
		(net "SMB_FIO_SCL")
	)
	(segment
		(start 215.319102 -227.227892)
		(end 214.999062 -226.907852)
		(width 0.13208)
		(layer "B.Cu")
		(net "SMB_FIO_SCL")
	)
	(segment
		(start 223.93783 -223.25203)
		(end 224.271586 -222.918274)
		(width 0.0889)
		(layer "B.Cu")
		(net "SMB_FIO_SCL")
	)
	(segment
		(start 214.572596 -226.907852)
		(end 214.106506 -226.441762)
		(width 0.13208)
		(layer "B.Cu")
		(net "SMB_FIO_SCL")
	)
	(segment
		(start 220.756226 -226.433634)
		(end 223.93783 -223.25203)
		(width 0.13208)
		(layer "B.Cu")
		(net "SMB_FIO_SCL")
	)
	(segment
		(start 224.271586 -222.53956)
		(end 224.503488 -222.307658)
		(width 0.0889)
		(layer "B.Cu")
		(net "SMB_FIO_SCL")
	)
	(segment
		(start 217.172032 -227.227892)
		(end 215.319102 -227.227892)
		(width 0.13208)
		(layer "B.Cu")
		(net "SMB_FIO_SCL")
	)
	(segment
		(start 219.168472 -226.433634)
		(end 220.756226 -226.433634)
		(width 0.13208)
		(layer "B.Cu")
		(net "SMB_FIO_SCL")
	)
	(segment
		(start 225.06432 -222.307658)
		(end 225.467926 -221.904052)
		(width 0.0889)
		(layer "B.Cu")
		(net "SMB_FIO_SCL")
	)
	(segment
		(start 214.999062 -226.907852)
		(end 214.572596 -226.907852)
		(width 0.13208)
		(layer "B.Cu")
		(net "SMB_FIO_SCL")
	)
	(segment
		(start 217.644472 -226.755452)
		(end 217.172032 -227.227892)
		(width 0.13208)
		(layer "B.Cu")
		(net "SMB_FIO_SCL")
	)
	(segment
		(start 224.271586 -222.918274)
		(end 224.271586 -222.53956)
		(width 0.0889)
		(layer "B.Cu")
		(net "SMB_FIO_SCL")
	)
	(segment
		(start 224.503488 -222.307658)
		(end 225.06432 -222.307658)
		(width 0.0889)
		(layer "B.Cu")
		(net "SMB_FIO_SCL")
	)
	(segment
		(start 4.39801 -24.534114)
		(end 3.630168 -25.301956)
		(width 0.13208)
		(layer "F.Cu")
		(net "SMB_ISO_SSD0_SDA")
	)
	(segment
		(start 3.523996 -27.652726)
		(end 3.523996 -28.37434)
		(width 0.13208)
		(layer "F.Cu")
		(net "SMB_ISO_SSD0_SDA")
	)
	(segment
		(start 3.429 -27.423364)
		(end 3.523996 -27.652726)
		(width 0.13208)
		(layer "F.Cu")
		(net "SMB_ISO_SSD0_SDA")
	)
	(segment
		(start 4.050792 -35.272218)
		(end 4.050792 -35.881818)
		(width 0.13208)
		(layer "F.Cu")
		(net "SMB_ISO_SSD0_SDA")
	)
	(segment
		(start 4.647692 -24.534114)
		(end 4.39801 -24.534114)
		(width 0.13208)
		(layer "F.Cu")
		(net "SMB_ISO_SSD0_SDA")
	)
	(segment
		(start 3.630168 -25.301956)
		(end 3.630168 -25.345644)
		(width 0.13208)
		(layer "F.Cu")
		(net "SMB_ISO_SSD0_SDA")
	)
	(segment
		(start 3.630168 -25.345644)
		(end 3.429 -25.546812)
		(width 0.13208)
		(layer "F.Cu")
		(net "SMB_ISO_SSD0_SDA")
	)
	(segment
		(start 3.523996 -28.37434)
		(end 3.523996 -29.035248)
		(width 0.13208)
		(layer "F.Cu")
		(net "SMB_ISO_SSD0_SDA")
	)
	(segment
		(start 3.523996 -29.035248)
		(end 3.846322 -29.357574)
		(width 0.13208)
		(layer "F.Cu")
		(net "SMB_ISO_SSD0_SDA")
	)
	(segment
		(start 3.429 -25.546812)
		(end 3.429 -27.423364)
		(width 0.13208)
		(layer "F.Cu")
		(net "SMB_ISO_SSD0_SDA")
	)
	(via
		(at 3.846322 -29.357574)
		(size 0.508)
		(drill 0.254)
		(layers "F.Cu" "B.Cu")
		(net "SMB_ISO_SSD0_SDA")
	)
	(via
		(at 4.050792 -35.881818)
		(size 0.508)
		(drill 0.254)
		(layers "F.Cu" "B.Cu")
		(net "SMB_ISO_SSD0_SDA")
	)
	(segment
		(start 3.495294 -32.606742)
		(end 4.339082 -33.45053)
		(width 0.13208)
		(layer "B.Cu")
		(net "SMB_ISO_SSD0_SDA")
	)
	(segment
		(start 3.846322 -29.772102)
		(end 3.495294 -30.12313)
		(width 0.13208)
		(layer "B.Cu")
		(net "SMB_ISO_SSD0_SDA")
	)
	(segment
		(start 3.802126 -34.812478)
		(end 3.802126 -35.633152)
		(width 0.13208)
		(layer "B.Cu")
		(net "SMB_ISO_SSD0_SDA")
	)
	(segment
		(start 3.846322 -29.357574)
		(end 3.846322 -29.772102)
		(width 0.13208)
		(layer "B.Cu")
		(net "SMB_ISO_SSD0_SDA")
	)
	(segment
		(start 3.495294 -30.12313)
		(end 3.495294 -32.606742)
		(width 0.13208)
		(layer "B.Cu")
		(net "SMB_ISO_SSD0_SDA")
	)
	(segment
		(start 4.339082 -34.275522)
		(end 3.802126 -34.812478)
		(width 0.13208)
		(layer "B.Cu")
		(net "SMB_ISO_SSD0_SDA")
	)
	(segment
		(start 4.339082 -33.45053)
		(end 4.339082 -34.275522)
		(width 0.13208)
		(layer "B.Cu")
		(net "SMB_ISO_SSD0_SDA")
	)
	(segment
		(start 3.802126 -35.633152)
		(end 4.050792 -35.881818)
		(width 0.13208)
		(layer "B.Cu")
		(net "SMB_ISO_SSD0_SDA")
	)
	(segment
		(start 148.680678 -381.428498)
		(end 148.11756 -381.428498)
		(width 0.13208)
		(layer "F.Cu")
		(net "GPU_3V3IO_RSVD1_FFU_R")
	)
	(segment
		(start 148.11756 -381.428498)
		(end 147.834858 -381.7112)
		(width 0.13208)
		(layer "F.Cu")
		(net "GPU_3V3IO_RSVD1_FFU_R")
	)
	(via
		(at 147.834858 -381.7112)
		(size 0.508)
		(drill 0.254)
		(layers "F.Cu" "B.Cu")
		(net "GPU_3V3IO_RSVD1_FFU_R")
	)
	(segment
		(start 128.206754 -367.693448)
		(end 136.121648 -367.693448)
		(width 0.15494)
		(layer "In9.Cu")
		(net "GPU_3V3IO_RSVD1_FFU_R")
	)
	(segment
		(start 126.910084 -368.990118)
		(end 128.206754 -367.693448)
		(width 0.15494)
		(layer "In9.Cu")
		(net "GPU_3V3IO_RSVD1_FFU_R")
	)
	(segment
		(start 146.40179 -377.97359)
		(end 146.40179 -380.553214)
		(width 0.15494)
		(layer "In9.Cu")
		(net "GPU_3V3IO_RSVD1_FFU_R")
	)
	(segment
		(start 147.277074 -381.428498)
		(end 147.552156 -381.428498)
		(width 0.15494)
		(layer "In9.Cu")
		(net "GPU_3V3IO_RSVD1_FFU_R")
	)
	(segment
		(start 146.40179 -380.553214)
		(end 147.277074 -381.428498)
		(width 0.15494)
		(layer "In9.Cu")
		(net "GPU_3V3IO_RSVD1_FFU_R")
	)
	(segment
		(start 136.121648 -367.693448)
		(end 146.40179 -377.97359)
		(width 0.15494)
		(layer "In9.Cu")
		(net "GPU_3V3IO_RSVD1_FFU_R")
	)
	(segment
		(start 147.552156 -381.428498)
		(end 147.834858 -381.7112)
		(width 0.15494)
		(layer "In9.Cu")
		(net "GPU_3V3IO_RSVD1_FFU_R")
	)
	(segment
		(start 338.430616 -251.00661)
		(end 338.430616 -250.614434)
		(width 0.13208)
		(layer "F.Cu")
		(net "RST_SSD2_PERST_R_N")
	)
	(segment
		(start 66.20383 -24.189944)
		(end 67.264788 -24.189944)
		(width 0.13208)
		(layer "F.Cu")
		(net "RST_SSD2_PERST_R_N")
	)
	(segment
		(start 346.950792 -241.281712)
		(end 346.950792 -241.091212)
		(width 0.13208)
		(layer "F.Cu")
		(net "RST_SSD2_PERST_R_N")
	)
	(segment
		(start 338.430616 -250.614434)
		(end 345.031314 -244.013736)
		(width 0.13208)
		(layer "F.Cu")
		(net "RST_SSD2_PERST_R_N")
	)
	(segment
		(start 345.031314 -243.20119)
		(end 346.950792 -241.281712)
		(width 0.13208)
		(layer "F.Cu")
		(net "RST_SSD2_PERST_R_N")
	)
	(segment
		(start 345.031314 -244.013736)
		(end 345.031314 -243.20119)
		(width 0.13208)
		(layer "F.Cu")
		(net "RST_SSD2_PERST_R_N")
	)
	(via
		(at 121.821702 -241.856006)
		(size 0.508)
		(drill 0.254)
		(layers "F.Cu" "B.Cu")
		(net "RST_SSD2_PERST_R_N")
	)
	(via
		(at 66.20383 -24.189944)
		(size 0.508)
		(drill 0.254)
		(layers "F.Cu" "B.Cu")
		(net "RST_SSD2_PERST_R_N")
	)
	(via
		(at 338.430616 -251.00661)
		(size 0.508)
		(drill 0.254)
		(layers "F.Cu" "B.Cu")
		(net "RST_SSD2_PERST_R_N")
	)
	(segment
		(start 118.90883 -94.359222)
		(end 118.90883 -100.849684)
		(width 0.15494)
		(layer "In5.Cu")
		(net "RST_SSD2_PERST_R_N")
	)
	(segment
		(start 124.50953 -185.79973)
		(end 124.50953 -199.61987)
		(width 0.15494)
		(layer "In5.Cu")
		(net "RST_SSD2_PERST_R_N")
	)
	(segment
		(start 118.90883 -100.849684)
		(end 120.99544 -102.936294)
		(width 0.15494)
		(layer "In5.Cu")
		(net "RST_SSD2_PERST_R_N")
	)
	(segment
		(start 76.739496 -28.006802)
		(end 76.739496 -33.889696)
		(width 0.15494)
		(layer "In5.Cu")
		(net "RST_SSD2_PERST_R_N")
	)
	(segment
		(start 91.9226 -83.9724)
		(end 99.67468 -91.72448)
		(width 0.15494)
		(layer "In5.Cu")
		(net "RST_SSD2_PERST_R_N")
	)
	(segment
		(start 91.9226 -80.137)
		(end 91.9226 -83.9724)
		(width 0.15494)
		(layer "In5.Cu")
		(net "RST_SSD2_PERST_R_N")
	)
	(segment
		(start 119.242586 -214.263986)
		(end 119.242586 -224.70364)
		(width 0.15494)
		(layer "In5.Cu")
		(net "RST_SSD2_PERST_R_N")
	)
	(segment
		(start 76.739496 -33.889696)
		(end 89.3064 -46.4566)
		(width 0.15494)
		(layer "In5.Cu")
		(net "RST_SSD2_PERST_R_N")
	)
	(segment
		(start 119.700294 -211.261706)
		(end 118.655846 -212.306154)
		(width 0.15494)
		(layer "In5.Cu")
		(net "RST_SSD2_PERST_R_N")
	)
	(segment
		(start 119.242586 -224.70364)
		(end 121.47677 -226.937824)
		(width 0.15494)
		(layer "In5.Cu")
		(net "RST_SSD2_PERST_R_N")
	)
	(segment
		(start 121.47677 -226.937824)
		(end 121.47677 -241.511074)
		(width 0.15494)
		(layer "In5.Cu")
		(net "RST_SSD2_PERST_R_N")
	)
	(segment
		(start 121.610882 -126.161292)
		(end 120.91416 -126.858014)
		(width 0.15494)
		(layer "In5.Cu")
		(net "RST_SSD2_PERST_R_N")
	)
	(segment
		(start 116.274088 -91.72448)
		(end 118.90883 -94.359222)
		(width 0.15494)
		(layer "In5.Cu")
		(net "RST_SSD2_PERST_R_N")
	)
	(segment
		(start 68.983352 -24.930354)
		(end 71.002398 -26.9494)
		(width 0.15494)
		(layer "In5.Cu")
		(net "RST_SSD2_PERST_R_N")
	)
	(segment
		(start 120.99544 -117.507004)
		(end 121.610882 -118.122446)
		(width 0.15494)
		(layer "In5.Cu")
		(net "RST_SSD2_PERST_R_N")
	)
	(segment
		(start 89.3064 -77.5208)
		(end 91.9226 -80.137)
		(width 0.15494)
		(layer "In5.Cu")
		(net "RST_SSD2_PERST_R_N")
	)
	(segment
		(start 124.50953 -199.61987)
		(end 119.700294 -204.429106)
		(width 0.15494)
		(layer "In5.Cu")
		(net "RST_SSD2_PERST_R_N")
	)
	(segment
		(start 119.700294 -204.429106)
		(end 119.700294 -211.261706)
		(width 0.15494)
		(layer "In5.Cu")
		(net "RST_SSD2_PERST_R_N")
	)
	(segment
		(start 118.655846 -212.306154)
		(end 118.655846 -213.677246)
		(width 0.15494)
		(layer "In5.Cu")
		(net "RST_SSD2_PERST_R_N")
	)
	(segment
		(start 76.187808 -27.455114)
		(end 76.739496 -28.006802)
		(width 0.15494)
		(layer "In5.Cu")
		(net "RST_SSD2_PERST_R_N")
	)
	(segment
		(start 89.3064 -46.4566)
		(end 89.3064 -77.5208)
		(width 0.15494)
		(layer "In5.Cu")
		(net "RST_SSD2_PERST_R_N")
	)
	(segment
		(start 120.99544 -102.936294)
		(end 120.99544 -117.507004)
		(width 0.15494)
		(layer "In5.Cu")
		(net "RST_SSD2_PERST_R_N")
	)
	(segment
		(start 66.94424 -24.930354)
		(end 68.983352 -24.930354)
		(width 0.15494)
		(layer "In5.Cu")
		(net "RST_SSD2_PERST_R_N")
	)
	(segment
		(start 118.655846 -213.677246)
		(end 119.242586 -214.263986)
		(width 0.15494)
		(layer "In5.Cu")
		(net "RST_SSD2_PERST_R_N")
	)
	(segment
		(start 72.526398 -26.9494)
		(end 73.032112 -27.455114)
		(width 0.15494)
		(layer "In5.Cu")
		(net "RST_SSD2_PERST_R_N")
	)
	(segment
		(start 121.610882 -118.122446)
		(end 121.610882 -126.161292)
		(width 0.15494)
		(layer "In5.Cu")
		(net "RST_SSD2_PERST_R_N")
	)
	(segment
		(start 120.91416 -182.20436)
		(end 124.50953 -185.79973)
		(width 0.15494)
		(layer "In5.Cu")
		(net "RST_SSD2_PERST_R_N")
	)
	(segment
		(start 73.032112 -27.455114)
		(end 76.187808 -27.455114)
		(width 0.15494)
		(layer "In5.Cu")
		(net "RST_SSD2_PERST_R_N")
	)
	(segment
		(start 66.20383 -24.189944)
		(end 66.94424 -24.930354)
		(width 0.15494)
		(layer "In5.Cu")
		(net "RST_SSD2_PERST_R_N")
	)
	(segment
		(start 120.91416 -126.858014)
		(end 120.91416 -182.20436)
		(width 0.15494)
		(layer "In5.Cu")
		(net "RST_SSD2_PERST_R_N")
	)
	(segment
		(start 71.002398 -26.9494)
		(end 72.526398 -26.9494)
		(width 0.15494)
		(layer "In5.Cu")
		(net "RST_SSD2_PERST_R_N")
	)
	(segment
		(start 99.67468 -91.72448)
		(end 116.274088 -91.72448)
		(width 0.15494)
		(layer "In5.Cu")
		(net "RST_SSD2_PERST_R_N")
	)
	(segment
		(start 121.47677 -241.511074)
		(end 121.821702 -241.856006)
		(width 0.15494)
		(layer "In5.Cu")
		(net "RST_SSD2_PERST_R_N")
	)
	(segment
		(start 257.841496 -254.42418)
		(end 257.0734 -253.656084)
		(width 0.15494)
		(layer "In15.Cu")
		(net "RST_SSD2_PERST_R_N")
	)
	(segment
		(start 319.94221 -255.884934)
		(end 314.06719 -255.884934)
		(width 0.15494)
		(layer "In15.Cu")
		(net "RST_SSD2_PERST_R_N")
	)
	(segment
		(start 186.29757 -251.6886)
		(end 177.92954 -243.32057)
		(width 0.15494)
		(layer "In15.Cu")
		(net "RST_SSD2_PERST_R_N")
	)
	(segment
		(start 136.93267 -242.36553)
		(end 122.331226 -242.36553)
		(width 0.15494)
		(layer "In15.Cu")
		(net "RST_SSD2_PERST_R_N")
	)
	(segment
		(start 313.7154 -255.533144)
		(end 274.78863 -255.533144)
		(width 0.15494)
		(layer "In15.Cu")
		(net "RST_SSD2_PERST_R_N")
	)
	(segment
		(start 143.1163 -236.1819)
		(end 136.93267 -242.36553)
		(width 0.15494)
		(layer "In15.Cu")
		(net "RST_SSD2_PERST_R_N")
	)
	(segment
		(start 320.294 -255.533144)
		(end 319.94221 -255.884934)
		(width 0.15494)
		(layer "In15.Cu")
		(net "RST_SSD2_PERST_R_N")
	)
	(segment
		(start 149.268688 -236.1819)
		(end 143.1163 -236.1819)
		(width 0.15494)
		(layer "In15.Cu")
		(net "RST_SSD2_PERST_R_N")
	)
	(segment
		(start 230.505762 -253.173992)
		(end 228.58984 -251.25807)
		(width 0.15494)
		(layer "In15.Cu")
		(net "RST_SSD2_PERST_R_N")
	)
	(segment
		(start 228.58984 -251.25807)
		(end 225.177096 -251.25807)
		(width 0.15494)
		(layer "In15.Cu")
		(net "RST_SSD2_PERST_R_N")
	)
	(segment
		(start 338.430616 -251.00661)
		(end 338.430616 -252.108208)
		(width 0.15494)
		(layer "In15.Cu")
		(net "RST_SSD2_PERST_R_N")
	)
	(segment
		(start 274.78863 -255.533144)
		(end 273.679666 -254.42418)
		(width 0.15494)
		(layer "In15.Cu")
		(net "RST_SSD2_PERST_R_N")
	)
	(segment
		(start 151.84374 -237.756954)
		(end 150.975822 -236.888782)
		(width 0.15494)
		(layer "In15.Cu")
		(net "RST_SSD2_PERST_R_N")
	)
	(segment
		(start 156.64815 -243.32057)
		(end 151.84374 -238.51616)
		(width 0.15494)
		(layer "In15.Cu")
		(net "RST_SSD2_PERST_R_N")
	)
	(segment
		(start 335.00568 -255.533144)
		(end 320.294 -255.533144)
		(width 0.15494)
		(layer "In15.Cu")
		(net "RST_SSD2_PERST_R_N")
	)
	(segment
		(start 257.0734 -253.363984)
		(end 256.742946 -253.03353)
		(width 0.15494)
		(layer "In15.Cu")
		(net "RST_SSD2_PERST_R_N")
	)
	(segment
		(start 257.0734 -253.656084)
		(end 257.0734 -253.363984)
		(width 0.15494)
		(layer "In15.Cu")
		(net "RST_SSD2_PERST_R_N")
	)
	(segment
		(start 122.331226 -242.36553)
		(end 121.821702 -241.856006)
		(width 0.15494)
		(layer "In15.Cu")
		(net "RST_SSD2_PERST_R_N")
	)
	(segment
		(start 252.221238 -253.173992)
		(end 230.505762 -253.173992)
		(width 0.15494)
		(layer "In15.Cu")
		(net "RST_SSD2_PERST_R_N")
	)
	(segment
		(start 224.746566 -251.6886)
		(end 186.29757 -251.6886)
		(width 0.15494)
		(layer "In15.Cu")
		(net "RST_SSD2_PERST_R_N")
	)
	(segment
		(start 177.92954 -243.32057)
		(end 156.64815 -243.32057)
		(width 0.15494)
		(layer "In15.Cu")
		(net "RST_SSD2_PERST_R_N")
	)
	(segment
		(start 273.679666 -254.42418)
		(end 257.841496 -254.42418)
		(width 0.15494)
		(layer "In15.Cu")
		(net "RST_SSD2_PERST_R_N")
	)
	(segment
		(start 252.3617 -253.03353)
		(end 252.221238 -253.173992)
		(width 0.15494)
		(layer "In15.Cu")
		(net "RST_SSD2_PERST_R_N")
	)
	(segment
		(start 338.430616 -252.108208)
		(end 335.00568 -255.533144)
		(width 0.15494)
		(layer "In15.Cu")
		(net "RST_SSD2_PERST_R_N")
	)
	(segment
		(start 256.742946 -253.03353)
		(end 252.3617 -253.03353)
		(width 0.15494)
		(layer "In15.Cu")
		(net "RST_SSD2_PERST_R_N")
	)
	(segment
		(start 151.84374 -238.51616)
		(end 151.84374 -237.756954)
		(width 0.15494)
		(layer "In15.Cu")
		(net "RST_SSD2_PERST_R_N")
	)
	(segment
		(start 314.06719 -255.884934)
		(end 313.7154 -255.533144)
		(width 0.15494)
		(layer "In15.Cu")
		(net "RST_SSD2_PERST_R_N")
	)
	(segment
		(start 150.975822 -236.888782)
		(end 149.268688 -236.1819)
		(width 0.15494)
		(layer "In15.Cu")
		(net "RST_SSD2_PERST_R_N")
	)
	(segment
		(start 225.177096 -251.25807)
		(end 224.746566 -251.6886)
		(width 0.15494)
		(layer "In15.Cu")
		(net "RST_SSD2_PERST_R_N")
	)
	(segment
		(start 338.093812 -213.587076)
		(end 337.694016 -213.18728)
		(width 0.13208)
		(layer "F.Cu")
		(net "SSD10_PWRDIS")
	)
	(via
		(at 335.780888 -209.560668)
		(size 0.6604)
		(drill 0.3302)
		(layers "F.Cu" "B.Cu")
		(net "SSD10_PWRDIS")
	)
	(via
		(at 337.694016 -213.18728)
		(size 0.4572)
		(drill 0.254)
		(layers "F.Cu" "B.Cu")
		(net "SSD10_PWRDIS")
	)
	(segment
		(start 337.29422 -211.074)
		(end 337.29422 -212.787484)
		(width 0.0889)
		(layer "B.Cu")
		(net "SSD10_PWRDIS")
	)
	(segment
		(start 335.780888 -209.560668)
		(end 335.153 -208.93278)
		(width 0.13208)
		(layer "B.Cu")
		(net "SSD10_PWRDIS")
	)
	(segment
		(start 335.780888 -209.560668)
		(end 337.29422 -211.074)
		(width 0.13208)
		(layer "B.Cu")
		(net "SSD10_PWRDIS")
	)
	(segment
		(start 337.29422 -212.787484)
		(end 337.694016 -213.18728)
		(width 0.0889)
		(layer "B.Cu")
		(net "SSD10_PWRDIS")
	)
	(segment
		(start 335.153 -208.93278)
		(end 335.153 -208.17205)
		(width 0.13208)
		(layer "B.Cu")
		(net "SSD10_PWRDIS")
	)
	(segment
		(start 421.249856 -290.199826)
		(end 421.724836 -289.724846)
		(width 0.13208)
		(layer "F.Cu")
		(net "UART_PEX3_SDB_TX")
	)
	(via
		(at 422.199816 -290.199826)
		(size 0.6604)
		(drill 0.3302)
		(layers "F.Cu" "B.Cu")
		(net "UART_PEX3_SDB_TX")
	)
	(via
		(at 421.724836 -289.724846)
		(size 0.4064)
		(drill 0.2032)
		(layers "F.Cu" "B.Cu")
		(net "UART_PEX3_SDB_TX")
	)
	(segment
		(start 423.47388 -290.199826)
		(end 423.54881 -290.124896)
		(width 0.13208)
		(layer "B.Cu")
		(net "UART_PEX3_SDB_TX")
	)
	(segment
		(start 421.724836 -289.724846)
		(end 422.199816 -290.199826)
		(width 0.13208)
		(layer "B.Cu")
		(net "UART_PEX3_SDB_TX")
	)
	(segment
		(start 422.199816 -290.199826)
		(end 423.47388 -290.199826)
		(width 0.13208)
		(layer "B.Cu")
		(net "UART_PEX3_SDB_TX")
	)
	(segment
		(start 423.54881 -290.124896)
		(end 424.02379 -290.124896)
		(width 0.13208)
		(layer "B.Cu")
		(net "UART_PEX3_SDB_TX")
	)
	(segment
		(start 220.984318 -192.357502)
		(end 221.5769 -192.950084)
		(width 0.13208)
		(layer "F.Cu")
		(net "SPI2_DO_BUF")
	)
	(segment
		(start 221.5769 -192.950084)
		(end 221.5769 -193.378328)
		(width 0.13208)
		(layer "F.Cu")
		(net "SPI2_DO_BUF")
	)
	(via
		(at 220.984318 -192.357502)
		(size 0.508)
		(drill 0.254)
		(layers "F.Cu" "B.Cu")
		(net "SPI2_DO_BUF")
	)
	(segment
		(start 221.237302 -192.104518)
		(end 220.984318 -192.357502)
		(width 0.13208)
		(layer "B.Cu")
		(net "SPI2_DO_BUF")
	)
	(segment
		(start 222.212154 -192.559686)
		(end 221.756986 -192.104518)
		(width 0.13208)
		(layer "B.Cu")
		(net "SPI2_DO_BUF")
	)
	(segment
		(start 221.756986 -192.104518)
		(end 221.237302 -192.104518)
		(width 0.13208)
		(layer "B.Cu")
		(net "SPI2_DO_BUF")
	)
	(segment
		(start 235.223558 -150.959566)
		(end 234.896406 -151.286718)
		(width 0.1143)
		(layer "F.Cu")
		(net "CLK_100M_PEX2_REF_DN")
	)
	(segment
		(start 232.732072 -149.962616)
		(end 232.659936 -149.89048)
		(width 0.1143)
		(layer "F.Cu")
		(net "CLK_100M_PEX2_REF_DN")
	)
	(segment
		(start 234.896406 -151.286718)
		(end 234.700318 -151.286718)
		(width 0.1143)
		(layer "F.Cu")
		(net "CLK_100M_PEX2_REF_DN")
	)
	(segment
		(start 232.659936 -149.89048)
		(end 232.471976 -149.89048)
		(width 0.1143)
		(layer "F.Cu")
		(net "CLK_100M_PEX2_REF_DN")
	)
	(segment
		(start 234.700318 -151.286718)
		(end 233.376216 -149.962616)
		(width 0.1143)
		(layer "F.Cu")
		(net "CLK_100M_PEX2_REF_DN")
	)
	(segment
		(start 233.376216 -149.962616)
		(end 232.732072 -149.962616)
		(width 0.1143)
		(layer "F.Cu")
		(net "CLK_100M_PEX2_REF_DN")
	)
	(segment
		(start 218.513406 -219.785946)
		(end 218.303602 -219.99575)
		(width 0.13208)
		(layer "F.Cu")
		(net "SMB_NIC4_SDA")
	)
	(segment
		(start 220.502988 -219.785946)
		(end 218.513406 -219.785946)
		(width 0.13208)
		(layer "F.Cu")
		(net "SMB_NIC4_SDA")
	)
	(segment
		(start 223.280732 -219.50426)
		(end 223.867726 -219.50426)
		(width 0.13208)
		(layer "F.Cu")
		(net "SMB_NIC4_SDA")
	)
	(segment
		(start 214.201248 -220.322902)
		(end 214.83828 -220.322902)
		(width 0.13208)
		(layer "F.Cu")
		(net "SMB_NIC4_SDA")
	)
	(segment
		(start 220.503242 -219.785692)
		(end 220.680534 -219.6084)
		(width 0.13208)
		(layer "F.Cu")
		(net "SMB_NIC4_SDA")
	)
	(segment
		(start 220.680534 -219.6084)
		(end 223.176592 -219.6084)
		(width 0.13208)
		(layer "F.Cu")
		(net "SMB_NIC4_SDA")
	)
	(segment
		(start 220.503242 -219.785692)
		(end 220.502988 -219.785946)
		(width 0.13208)
		(layer "F.Cu")
		(net "SMB_NIC4_SDA")
	)
	(segment
		(start 218.303602 -219.99575)
		(end 217.974672 -219.99575)
		(width 0.13208)
		(layer "F.Cu")
		(net "SMB_NIC4_SDA")
	)
	(segment
		(start 223.867726 -219.50426)
		(end 224.267776 -219.10421)
		(width 0.13208)
		(layer "F.Cu")
		(net "SMB_NIC4_SDA")
	)
	(segment
		(start 217.974672 -219.99575)
		(end 217.635836 -220.334586)
		(width 0.13208)
		(layer "F.Cu")
		(net "SMB_NIC4_SDA")
	)
	(segment
		(start 223.176592 -219.6084)
		(end 223.280732 -219.50426)
		(width 0.13208)
		(layer "F.Cu")
		(net "SMB_NIC4_SDA")
	)
	(via
		(at 220.503242 -219.785692)
		(size 0.762)
		(drill 0.381)
		(layers "F.Cu" "B.Cu")
		(net "SMB_NIC4_SDA")
	)
	(via
		(at 214.83828 -220.322902)
		(size 0.508)
		(drill 0.254)
		(layers "F.Cu" "B.Cu")
		(net "SMB_NIC4_SDA")
	)
	(via
		(at 218.303602 -219.99575)
		(size 0.508)
		(drill 0.254)
		(layers "F.Cu" "B.Cu")
		(net "SMB_NIC4_SDA")
	)
	(segment
		(start 214.957914 -219.837508)
		(end 214.83828 -219.957142)
		(width 0.15494)
		(layer "In5.Cu")
		(net "SMB_NIC4_SDA")
	)
	(segment
		(start 214.83828 -219.957142)
		(end 214.83828 -220.322902)
		(width 0.15494)
		(layer "In5.Cu")
		(net "SMB_NIC4_SDA")
	)
	(segment
		(start 218.14536 -219.837508)
		(end 214.957914 -219.837508)
		(width 0.15494)
		(layer "In5.Cu")
		(net "SMB_NIC4_SDA")
	)
	(segment
		(start 218.303602 -219.99575)
		(end 218.14536 -219.837508)
		(width 0.15494)
		(layer "In5.Cu")
		(net "SMB_NIC4_SDA")
	)
	(segment
		(start 1.599692 -24.534114)
		(end 1.844294 -24.534114)
		(width 0.13208)
		(layer "F.Cu")
		(net "SMB_ISO_SSD0_SCL")
	)
	(segment
		(start 2.573274 -29.330142)
		(end 2.873756 -29.02966)
		(width 0.13208)
		(layer "F.Cu")
		(net "SMB_ISO_SSD0_SCL")
	)
	(segment
		(start 1.844294 -24.534114)
		(end 2.614168 -25.303988)
		(width 0.13208)
		(layer "F.Cu")
		(net "SMB_ISO_SSD0_SCL")
	)
	(segment
		(start 2.991612 -25.724612)
		(end 2.991612 -27.407362)
		(width 0.13208)
		(layer "F.Cu")
		(net "SMB_ISO_SSD0_SCL")
	)
	(segment
		(start 2.614168 -25.345644)
		(end 2.614168 -25.347168)
		(width 0.13208)
		(layer "F.Cu")
		(net "SMB_ISO_SSD0_SCL")
	)
	(segment
		(start 2.991612 -27.407362)
		(end 2.873756 -27.692096)
		(width 0.13208)
		(layer "F.Cu")
		(net "SMB_ISO_SSD0_SCL")
	)
	(segment
		(start 2.873756 -27.692096)
		(end 2.873756 -28.37434)
		(width 0.13208)
		(layer "F.Cu")
		(net "SMB_ISO_SSD0_SCL")
	)
	(segment
		(start 2.614168 -25.303988)
		(end 2.614168 -25.345644)
		(width 0.13208)
		(layer "F.Cu")
		(net "SMB_ISO_SSD0_SCL")
	)
	(segment
		(start 3.047746 -35.290506)
		(end 3.047746 -35.91941)
		(width 0.13208)
		(layer "F.Cu")
		(net "SMB_ISO_SSD0_SCL")
	)
	(segment
		(start 2.873756 -29.02966)
		(end 2.873756 -28.37434)
		(width 0.13208)
		(layer "F.Cu")
		(net "SMB_ISO_SSD0_SCL")
	)
	(segment
		(start 2.614168 -25.347168)
		(end 2.991612 -25.724612)
		(width 0.13208)
		(layer "F.Cu")
		(net "SMB_ISO_SSD0_SCL")
	)
	(via
		(at 2.573274 -29.330142)
		(size 0.508)
		(drill 0.254)
		(layers "F.Cu" "B.Cu")
		(net "SMB_ISO_SSD0_SCL")
	)
	(via
		(at 3.047746 -35.91941)
		(size 0.508)
		(drill 0.254)
		(layers "F.Cu" "B.Cu")
		(net "SMB_ISO_SSD0_SCL")
	)
	(segment
		(start 2.573274 -29.330142)
		(end 2.573274 -29.758894)
		(width 0.13208)
		(layer "B.Cu")
		(net "SMB_ISO_SSD0_SCL")
	)
	(segment
		(start 2.573274 -29.758894)
		(end 3.011678 -30.197298)
		(width 0.13208)
		(layer "B.Cu")
		(net "SMB_ISO_SSD0_SCL")
	)
	(segment
		(start 2.43078 -33.911794)
		(end 3.33756 -34.818574)
		(width 0.13208)
		(layer "B.Cu")
		(net "SMB_ISO_SSD0_SCL")
	)
	(segment
		(start 3.047746 -35.900106)
		(end 3.047746 -35.91941)
		(width 0.13208)
		(layer "B.Cu")
		(net "SMB_ISO_SSD0_SCL")
	)
	(segment
		(start 3.33756 -34.818574)
		(end 3.33756 -35.610292)
		(width 0.13208)
		(layer "B.Cu")
		(net "SMB_ISO_SSD0_SCL")
	)
	(segment
		(start 3.011678 -32.888174)
		(end 2.43078 -33.469072)
		(width 0.13208)
		(layer "B.Cu")
		(net "SMB_ISO_SSD0_SCL")
	)
	(segment
		(start 3.33756 -35.610292)
		(end 3.047746 -35.900106)
		(width 0.13208)
		(layer "B.Cu")
		(net "SMB_ISO_SSD0_SCL")
	)
	(segment
		(start 3.011678 -30.197298)
		(end 3.011678 -32.888174)
		(width 0.13208)
		(layer "B.Cu")
		(net "SMB_ISO_SSD0_SCL")
	)
	(segment
		(start 2.43078 -33.469072)
		(end 2.43078 -33.911794)
		(width 0.13208)
		(layer "B.Cu")
		(net "SMB_ISO_SSD0_SCL")
	)
	(segment
		(start 330.542392 -243.624608)
		(end 330.327 -243.84)
		(width 0.13208)
		(layer "F.Cu")
		(net "RST_MB_PERST_1_N")
	)
	(segment
		(start 62.59195 -385.561332)
		(end 62.357 -385.326382)
		(width 0.13208)
		(layer "F.Cu")
		(net "RST_MB_PERST_1_N")
	)
	(segment
		(start 63.14694 -385.561332)
		(end 63.14694 -385.137152)
		(width 0.13208)
		(layer "F.Cu")
		(net "RST_MB_PERST_1_N")
	)
	(segment
		(start 63.14694 -385.137152)
		(end 62.608714 -384.598926)
		(width 0.13208)
		(layer "F.Cu")
		(net "RST_MB_PERST_1_N")
	)
	(segment
		(start 330.542392 -242.848892)
		(end 330.542392 -243.624608)
		(width 0.13208)
		(layer "F.Cu")
		(net "RST_MB_PERST_1_N")
	)
	(segment
		(start 63.14694 -385.561332)
		(end 62.59195 -385.561332)
		(width 0.13208)
		(layer "F.Cu")
		(net "RST_MB_PERST_1_N")
	)
	(segment
		(start 330.327 -243.84)
		(end 330.327 -244.83695)
		(width 0.13208)
		(layer "F.Cu")
		(net "RST_MB_PERST_1_N")
	)
	(via
		(at 199.59828 -362.202222)
		(size 0.508)
		(drill 0.254)
		(layers "F.Cu" "B.Cu")
		(net "RST_MB_PERST_1_N")
	)
	(via
		(at 62.357 -385.326382)
		(size 0.508)
		(drill 0.254)
		(layers "F.Cu" "B.Cu")
		(net "RST_MB_PERST_1_N")
	)
	(via
		(at 330.327 -243.84)
		(size 0.508)
		(drill 0.254)
		(layers "F.Cu" "B.Cu")
		(net "RST_MB_PERST_1_N")
	)
	(via
		(at 104.394 -368.554)
		(size 0.508)
		(drill 0.254)
		(layers "F.Cu" "B.Cu")
		(net "RST_MB_PERST_1_N")
	)
	(via
		(at 240.376202 -241.599466)
		(size 0.508)
		(drill 0.254)
		(layers "F.Cu" "B.Cu")
		(net "RST_MB_PERST_1_N")
	)
	(via
		(at 230.05796 -332.553056)
		(size 0.508)
		(drill 0.254)
		(layers "F.Cu" "B.Cu")
		(net "RST_MB_PERST_1_N")
	)
	(segment
		(start 245.227094 -246.450358)
		(end 249.02668 -255.623822)
		(width 0.13208)
		(layer "B.Cu")
		(net "RST_MB_PERST_1_N")
	)
	(segment
		(start 109.060234 -368.168428)
		(end 115.345718 -361.882944)
		(width 0.13208)
		(layer "B.Cu")
		(net "RST_MB_PERST_1_N")
	)
	(segment
		(start 240.376202 -241.599466)
		(end 245.227094 -246.450358)
		(width 0.13208)
		(layer "B.Cu")
		(net "RST_MB_PERST_1_N")
	)
	(segment
		(start 249.02668 -264.86993)
		(end 257.480816 -285.281624)
		(width 0.13208)
		(layer "B.Cu")
		(net "RST_MB_PERST_1_N")
	)
	(segment
		(start 198.340218 -361.882944)
		(end 198.89089 -362.433616)
		(width 0.13208)
		(layer "B.Cu")
		(net "RST_MB_PERST_1_N")
	)
	(segment
		(start 104.394 -368.554)
		(end 104.394 -368.305842)
		(width 0.13208)
		(layer "B.Cu")
		(net "RST_MB_PERST_1_N")
	)
	(segment
		(start 198.89089 -362.433616)
		(end 199.366886 -362.433616)
		(width 0.13208)
		(layer "B.Cu")
		(net "RST_MB_PERST_1_N")
	)
	(segment
		(start 249.02668 -255.623822)
		(end 249.02668 -264.86993)
		(width 0.13208)
		(layer "B.Cu")
		(net "RST_MB_PERST_1_N")
	)
	(segment
		(start 104.394 -368.305842)
		(end 104.531414 -368.168428)
		(width 0.13208)
		(layer "B.Cu")
		(net "RST_MB_PERST_1_N")
	)
	(segment
		(start 245.672356 -328.255122)
		(end 236.255814 -328.255122)
		(width 0.13208)
		(layer "B.Cu")
		(net "RST_MB_PERST_1_N")
	)
	(segment
		(start 257.480816 -305.856894)
		(end 249.992896 -323.93509)
		(width 0.13208)
		(layer "B.Cu")
		(net "RST_MB_PERST_1_N")
	)
	(segment
		(start 104.531414 -368.168428)
		(end 109.060234 -368.168428)
		(width 0.13208)
		(layer "B.Cu")
		(net "RST_MB_PERST_1_N")
	)
	(segment
		(start 231.95788 -332.553056)
		(end 230.05796 -332.553056)
		(width 0.13208)
		(layer "B.Cu")
		(net "RST_MB_PERST_1_N")
	)
	(segment
		(start 199.366886 -362.433616)
		(end 199.59828 -362.202222)
		(width 0.13208)
		(layer "B.Cu")
		(net "RST_MB_PERST_1_N")
	)
	(segment
		(start 249.992896 -323.93509)
		(end 245.672356 -328.255122)
		(width 0.13208)
		(layer "B.Cu")
		(net "RST_MB_PERST_1_N")
	)
	(segment
		(start 257.480816 -285.281624)
		(end 257.480816 -305.856894)
		(width 0.13208)
		(layer "B.Cu")
		(net "RST_MB_PERST_1_N")
	)
	(segment
		(start 236.255814 -328.255122)
		(end 231.95788 -332.553056)
		(width 0.13208)
		(layer "B.Cu")
		(net "RST_MB_PERST_1_N")
	)
	(segment
		(start 115.345718 -361.882944)
		(end 198.340218 -361.882944)
		(width 0.13208)
		(layer "B.Cu")
		(net "RST_MB_PERST_1_N")
	)
	(segment
		(start 202.962256 -361.039664)
		(end 201.746358 -361.5436)
		(width 0.15494)
		(layer "In5.Cu")
		(net "RST_MB_PERST_1_N")
	)
	(segment
		(start 230.05796 -332.553056)
		(end 229.177088 -333.433928)
		(width 0.15494)
		(layer "In5.Cu")
		(net "RST_MB_PERST_1_N")
	)
	(segment
		(start 229.177088 -333.433928)
		(end 229.177088 -347.058996)
		(width 0.15494)
		(layer "In5.Cu")
		(net "RST_MB_PERST_1_N")
	)
	(segment
		(start 200.138538 -362.202222)
		(end 199.59828 -362.202222)
		(width 0.15494)
		(layer "In5.Cu")
		(net "RST_MB_PERST_1_N")
	)
	(segment
		(start 219.030296 -357.205788)
		(end 206.796132 -357.205788)
		(width 0.15494)
		(layer "In5.Cu")
		(net "RST_MB_PERST_1_N")
	)
	(segment
		(start 201.746358 -361.5436)
		(end 200.79716 -361.5436)
		(width 0.15494)
		(layer "In5.Cu")
		(net "RST_MB_PERST_1_N")
	)
	(segment
		(start 206.796132 -357.205788)
		(end 202.962256 -361.039664)
		(width 0.15494)
		(layer "In5.Cu")
		(net "RST_MB_PERST_1_N")
	)
	(segment
		(start 229.177088 -347.058996)
		(end 219.030296 -357.205788)
		(width 0.15494)
		(layer "In5.Cu")
		(net "RST_MB_PERST_1_N")
	)
	(segment
		(start 200.79716 -361.5436)
		(end 200.138538 -362.202222)
		(width 0.15494)
		(layer "In5.Cu")
		(net "RST_MB_PERST_1_N")
	)
	(segment
		(start 62.357 -385.326382)
		(end 64.448182 -385.326382)
		(width 0.15494)
		(layer "In9.Cu")
		(net "RST_MB_PERST_1_N")
	)
	(segment
		(start 69.659754 -390.537954)
		(end 69.659754 -411.6197)
		(width 0.15494)
		(layer "In9.Cu")
		(net "RST_MB_PERST_1_N")
	)
	(segment
		(start 64.448182 -385.326382)
		(end 69.659754 -390.537954)
		(width 0.15494)
		(layer "In9.Cu")
		(net "RST_MB_PERST_1_N")
	)
	(segment
		(start 71.299832 -413.259778)
		(end 79.540354 -413.259778)
		(width 0.15494)
		(layer "In9.Cu")
		(net "RST_MB_PERST_1_N")
	)
	(segment
		(start 69.659754 -411.6197)
		(end 71.299832 -413.259778)
		(width 0.15494)
		(layer "In9.Cu")
		(net "RST_MB_PERST_1_N")
	)
	(segment
		(start 79.540354 -413.259778)
		(end 80.710024 -412.090108)
		(width 0.15494)
		(layer "In9.Cu")
		(net "RST_MB_PERST_1_N")
	)
	(segment
		(start 275.715984 -243.13134)
		(end 262.511794 -243.13134)
		(width 0.15494)
		(layer "In13.Cu")
		(net "RST_MB_PERST_1_N")
	)
	(segment
		(start 254.462534 -241.599466)
		(end 240.376202 -241.599466)
		(width 0.15494)
		(layer "In13.Cu")
		(net "RST_MB_PERST_1_N")
	)
	(segment
		(start 259.941314 -243.13134)
		(end 256.798826 -243.13134)
		(width 0.15494)
		(layer "In13.Cu")
		(net "RST_MB_PERST_1_N")
	)
	(segment
		(start 276.245828 -243.661184)
		(end 275.715984 -243.13134)
		(width 0.15494)
		(layer "In13.Cu")
		(net "RST_MB_PERST_1_N")
	)
	(segment
		(start 330.327 -243.84)
		(end 330.189332 -243.702332)
		(width 0.15494)
		(layer "In13.Cu")
		(net "RST_MB_PERST_1_N")
	)
	(segment
		(start 260.483858 -242.588796)
		(end 259.941314 -243.13134)
		(width 0.15494)
		(layer "In13.Cu")
		(net "RST_MB_PERST_1_N")
	)
	(segment
		(start 254.978408 -242.11534)
		(end 254.462534 -241.599466)
		(width 0.15494)
		(layer "In13.Cu")
		(net "RST_MB_PERST_1_N")
	)
	(segment
		(start 261.96925 -242.588796)
		(end 260.483858 -242.588796)
		(width 0.15494)
		(layer "In13.Cu")
		(net "RST_MB_PERST_1_N")
	)
	(segment
		(start 276.253956 -243.661184)
		(end 276.245828 -243.661184)
		(width 0.15494)
		(layer "In13.Cu")
		(net "RST_MB_PERST_1_N")
	)
	(segment
		(start 256.798826 -243.13134)
		(end 255.782826 -242.11534)
		(width 0.15494)
		(layer "In13.Cu")
		(net "RST_MB_PERST_1_N")
	)
	(segment
		(start 330.189332 -243.702332)
		(end 276.295104 -243.702332)
		(width 0.15494)
		(layer "In13.Cu")
		(net "RST_MB_PERST_1_N")
	)
	(segment
		(start 255.782826 -242.11534)
		(end 254.978408 -242.11534)
		(width 0.15494)
		(layer "In13.Cu")
		(net "RST_MB_PERST_1_N")
	)
	(segment
		(start 276.295104 -243.702332)
		(end 276.253956 -243.661184)
		(width 0.15494)
		(layer "In13.Cu")
		(net "RST_MB_PERST_1_N")
	)
	(segment
		(start 262.511794 -243.13134)
		(end 261.96925 -242.588796)
		(width 0.15494)
		(layer "In13.Cu")
		(net "RST_MB_PERST_1_N")
	)
	(segment
		(start 65.904618 -388.874)
		(end 62.357 -385.326382)
		(width 0.15494)
		(layer "In15.Cu")
		(net "RST_MB_PERST_1_N")
	)
	(segment
		(start 91.313 -388.874)
		(end 65.904618 -388.874)
		(width 0.15494)
		(layer "In15.Cu")
		(net "RST_MB_PERST_1_N")
	)
	(segment
		(start 104.394 -368.554)
		(end 96.28124 -376.66676)
		(width 0.15494)
		(layer "In15.Cu")
		(net "RST_MB_PERST_1_N")
	)
	(segment
		(start 96.28124 -376.66676)
		(end 96.28124 -383.90576)
		(width 0.15494)
		(layer "In15.Cu")
		(net "RST_MB_PERST_1_N")
	)
	(segment
		(start 96.28124 -383.90576)
		(end 91.313 -388.874)
		(width 0.15494)
		(layer "In15.Cu")
		(net "RST_MB_PERST_1_N")
	)
	(segment
		(start 232.26776 -222.304102)
		(end 232.667556 -222.703898)
		(width 0.13208)
		(layer "F.Cu")
		(net "PRSNT_SSD4_R_N")
	)
	(segment
		(start 123.209304 -27.04973)
		(end 124.203968 -27.04973)
		(width 0.13208)
		(layer "F.Cu")
		(net "PRSNT_SSD4_R_N")
	)
	(segment
		(start 124.203968 -27.04973)
		(end 124.220732 -27.066494)
		(width 0.13208)
		(layer "F.Cu")
		(net "PRSNT_SSD4_R_N")
	)
	(segment
		(start 123.209304 -26.03373)
		(end 123.209304 -27.04973)
		(width 0.13208)
		(layer "F.Cu")
		(net "PRSNT_SSD4_R_N")
	)
	(segment
		(start 124.220732 -27.066494)
		(end 125.042676 -27.066494)
		(width 0.13208)
		(layer "F.Cu")
		(net "PRSNT_SSD4_R_N")
	)
	(segment
		(start 344.49385 -226.387152)
		(end 344.893646 -226.786948)
		(width 0.13208)
		(layer "F.Cu")
		(net "PRSNT_SSD4_R_N")
	)
	(segment
		(start 122.675904 -36.515548)
		(end 123.496324 -36.515548)
		(width 0.13208)
		(layer "F.Cu")
		(net "PRSNT_SSD4_R_N")
	)
	(via
		(at 125.042676 -27.066494)
		(size 0.508)
		(drill 0.254)
		(layers "F.Cu" "B.Cu")
		(net "PRSNT_SSD4_R_N")
	)
	(via
		(at 235.801662 -174.330868)
		(size 0.508)
		(drill 0.254)
		(layers "F.Cu" "B.Cu")
		(net "PRSNT_SSD4_R_N")
	)
	(via
		(at 123.496324 -36.515548)
		(size 0.508)
		(drill 0.254)
		(layers "F.Cu" "B.Cu")
		(net "PRSNT_SSD4_R_N")
	)
	(via
		(at 142.748254 -186.139836)
		(size 0.508)
		(drill 0.254)
		(layers "F.Cu" "B.Cu")
		(net "PRSNT_SSD4_R_N")
	)
	(via
		(at 232.667556 -222.703898)
		(size 0.4572)
		(drill 0.254)
		(layers "F.Cu" "B.Cu")
		(net "PRSNT_SSD4_R_N")
	)
	(via
		(at 344.893646 -226.786948)
		(size 0.4572)
		(drill 0.254)
		(layers "F.Cu" "B.Cu")
		(net "PRSNT_SSD4_R_N")
	)
	(segment
		(start 123.50623 -36.525454)
		(end 123.496324 -36.515548)
		(width 0.15494)
		(layer "In5.Cu")
		(net "PRSNT_SSD4_R_N")
	)
	(segment
		(start 123.50623 -39.064946)
		(end 123.50623 -36.525454)
		(width 0.15494)
		(layer "In5.Cu")
		(net "PRSNT_SSD4_R_N")
	)
	(segment
		(start 141.5542 -164.399468)
		(end 140.687806 -163.533074)
		(width 0.15494)
		(layer "In5.Cu")
		(net "PRSNT_SSD4_R_N")
	)
	(segment
		(start 124.469906 -27.066494)
		(end 125.042676 -27.066494)
		(width 0.15494)
		(layer "In5.Cu")
		(net "PRSNT_SSD4_R_N")
	)
	(segment
		(start 121.863612 -29.672788)
		(end 124.469906 -27.066494)
		(width 0.15494)
		(layer "In5.Cu")
		(net "PRSNT_SSD4_R_N")
	)
	(segment
		(start 140.687806 -163.533074)
		(end 140.687806 -110.365794)
		(width 0.15494)
		(layer "In5.Cu")
		(net "PRSNT_SSD4_R_N")
	)
	(segment
		(start 140.814806 -173.614334)
		(end 141.5542 -172.87494)
		(width 0.15494)
		(layer "In5.Cu")
		(net "PRSNT_SSD4_R_N")
	)
	(segment
		(start 142.748254 -186.139836)
		(end 140.814806 -184.206388)
		(width 0.15494)
		(layer "In5.Cu")
		(net "PRSNT_SSD4_R_N")
	)
	(segment
		(start 132.055108 -78.330806)
		(end 132.055108 -77.4827)
		(width 0.15494)
		(layer "In5.Cu")
		(net "PRSNT_SSD4_R_N")
	)
	(segment
		(start 140.814806 -184.206388)
		(end 140.814806 -173.614334)
		(width 0.15494)
		(layer "In5.Cu")
		(net "PRSNT_SSD4_R_N")
	)
	(segment
		(start 140.687806 -110.365794)
		(end 141.1986 -109.855)
		(width 0.15494)
		(layer "In5.Cu")
		(net "PRSNT_SSD4_R_N")
	)
	(segment
		(start 121.863612 -34.882836)
		(end 121.863612 -29.672788)
		(width 0.15494)
		(layer "In5.Cu")
		(net "PRSNT_SSD4_R_N")
	)
	(segment
		(start 141.5542 -172.87494)
		(end 141.5542 -164.399468)
		(width 0.15494)
		(layer "In5.Cu")
		(net "PRSNT_SSD4_R_N")
	)
	(segment
		(start 131.61137 -77.038962)
		(end 130.763264 -77.038962)
		(width 0.15494)
		(layer "In5.Cu")
		(net "PRSNT_SSD4_R_N")
	)
	(segment
		(start 141.1986 -109.855)
		(end 141.1986 -87.474298)
		(width 0.15494)
		(layer "In5.Cu")
		(net "PRSNT_SSD4_R_N")
	)
	(segment
		(start 127.236982 -42.795698)
		(end 123.50623 -39.064946)
		(width 0.15494)
		(layer "In5.Cu")
		(net "PRSNT_SSD4_R_N")
	)
	(segment
		(start 130.763264 -77.038962)
		(end 127.236982 -73.51268)
		(width 0.15494)
		(layer "In5.Cu")
		(net "PRSNT_SSD4_R_N")
	)
	(segment
		(start 141.1986 -87.474298)
		(end 132.055108 -78.330806)
		(width 0.15494)
		(layer "In5.Cu")
		(net "PRSNT_SSD4_R_N")
	)
	(segment
		(start 132.055108 -77.4827)
		(end 131.61137 -77.038962)
		(width 0.15494)
		(layer "In5.Cu")
		(net "PRSNT_SSD4_R_N")
	)
	(segment
		(start 123.496324 -36.515548)
		(end 121.863612 -34.882836)
		(width 0.15494)
		(layer "In5.Cu")
		(net "PRSNT_SSD4_R_N")
	)
	(segment
		(start 127.236982 -73.51268)
		(end 127.236982 -42.795698)
		(width 0.15494)
		(layer "In5.Cu")
		(net "PRSNT_SSD4_R_N")
	)
	(segment
		(start 244.35943 -187.161424)
		(end 244.06352 -187.457334)
		(width 0.15494)
		(layer "In7.Cu")
		(net "PRSNT_SSD4_R_N")
	)
	(segment
		(start 238.872268 -207.913732)
		(end 238.872268 -209.027014)
		(width 0.15494)
		(layer "In7.Cu")
		(net "PRSNT_SSD4_R_N")
	)
	(segment
		(start 241.24666 -207.16494)
		(end 240.886234 -207.525366)
		(width 0.15494)
		(layer "In7.Cu")
		(net "PRSNT_SSD4_R_N")
	)
	(segment
		(start 239.260634 -207.525366)
		(end 238.872268 -207.913732)
		(width 0.15494)
		(layer "In7.Cu")
		(net "PRSNT_SSD4_R_N")
	)
	(segment
		(start 242.007644 -207.16494)
		(end 241.24666 -207.16494)
		(width 0.15494)
		(layer "In7.Cu")
		(net "PRSNT_SSD4_R_N")
	)
	(segment
		(start 242.64874 -204.267816)
		(end 242.64874 -206.523844)
		(width 0.15494)
		(layer "In7.Cu")
		(net "PRSNT_SSD4_R_N")
	)
	(segment
		(start 235.801662 -174.816516)
		(end 244.2464 -183.261254)
		(width 0.15494)
		(layer "In7.Cu")
		(net "PRSNT_SSD4_R_N")
	)
	(segment
		(start 244.2464 -185.4454)
		(end 244.35943 -185.55843)
		(width 0.15494)
		(layer "In7.Cu")
		(net "PRSNT_SSD4_R_N")
	)
	(segment
		(start 244.2464 -183.261254)
		(end 244.2464 -185.4454)
		(width 0.15494)
		(layer "In7.Cu")
		(net "PRSNT_SSD4_R_N")
	)
	(segment
		(start 236.6264 -210.1088)
		(end 236.4232 -209.9056)
		(width 0.15494)
		(layer "In7.Cu")
		(net "PRSNT_SSD4_R_N")
	)
	(segment
		(start 244.06352 -202.851512)
		(end 244.0051 -202.909932)
		(width 0.15494)
		(layer "In7.Cu")
		(net "PRSNT_SSD4_R_N")
	)
	(segment
		(start 234.6706 -218.0844)
		(end 234.442 -218.313)
		(width 0.15494)
		(layer "In7.Cu")
		(net "PRSNT_SSD4_R_N")
	)
	(segment
		(start 234.442 -218.313)
		(end 233.223054 -218.313)
		(width 0.15494)
		(layer "In7.Cu")
		(net "PRSNT_SSD4_R_N")
	)
	(segment
		(start 234.7214 -214.376)
		(end 234.6706 -214.4268)
		(width 0.0889)
		(layer "In7.Cu")
		(net "PRSNT_SSD4_R_N")
	)
	(segment
		(start 232.2703 -222.306642)
		(end 232.667556 -222.703898)
		(width 0.0889)
		(layer "In7.Cu")
		(net "PRSNT_SSD4_R_N")
	)
	(segment
		(start 244.35943 -185.55843)
		(end 244.35943 -187.161424)
		(width 0.15494)
		(layer "In7.Cu")
		(net "PRSNT_SSD4_R_N")
	)
	(segment
		(start 238.872268 -209.027014)
		(end 237.790482 -210.1088)
		(width 0.15494)
		(layer "In7.Cu")
		(net "PRSNT_SSD4_R_N")
	)
	(segment
		(start 234.6706 -214.4268)
		(end 234.6706 -218.0844)
		(width 0.0889)
		(layer "In7.Cu")
		(net "PRSNT_SSD4_R_N")
	)
	(segment
		(start 244.0051 -202.911456)
		(end 242.64874 -204.267816)
		(width 0.15494)
		(layer "In7.Cu")
		(net "PRSNT_SSD4_R_N")
	)
	(segment
		(start 234.7214 -211.1248)
		(end 234.7214 -214.376)
		(width 0.15494)
		(layer "In7.Cu")
		(net "PRSNT_SSD4_R_N")
	)
	(segment
		(start 235.801662 -174.330868)
		(end 235.801662 -174.816516)
		(width 0.15494)
		(layer "In7.Cu")
		(net "PRSNT_SSD4_R_N")
	)
	(segment
		(start 232.2703 -219.265754)
		(end 232.2703 -222.306642)
		(width 0.0889)
		(layer "In7.Cu")
		(net "PRSNT_SSD4_R_N")
	)
	(segment
		(start 244.0051 -202.909932)
		(end 244.0051 -202.911456)
		(width 0.15494)
		(layer "In7.Cu")
		(net "PRSNT_SSD4_R_N")
	)
	(segment
		(start 244.06352 -187.457334)
		(end 244.06352 -202.851512)
		(width 0.15494)
		(layer "In7.Cu")
		(net "PRSNT_SSD4_R_N")
	)
	(segment
		(start 242.64874 -206.523844)
		(end 242.007644 -207.16494)
		(width 0.15494)
		(layer "In7.Cu")
		(net "PRSNT_SSD4_R_N")
	)
	(segment
		(start 236.4232 -209.9056)
		(end 235.9406 -209.9056)
		(width 0.15494)
		(layer "In7.Cu")
		(net "PRSNT_SSD4_R_N")
	)
	(segment
		(start 237.790482 -210.1088)
		(end 236.6264 -210.1088)
		(width 0.15494)
		(layer "In7.Cu")
		(net "PRSNT_SSD4_R_N")
	)
	(segment
		(start 233.223054 -218.313)
		(end 232.2703 -219.265754)
		(width 0.15494)
		(layer "In7.Cu")
		(net "PRSNT_SSD4_R_N")
	)
	(segment
		(start 235.9406 -209.9056)
		(end 234.7214 -211.1248)
		(width 0.15494)
		(layer "In7.Cu")
		(net "PRSNT_SSD4_R_N")
	)
	(segment
		(start 240.886234 -207.525366)
		(end 239.260634 -207.525366)
		(width 0.15494)
		(layer "In7.Cu")
		(net "PRSNT_SSD4_R_N")
	)
	(segment
		(start 143.36649 -185.5216)
		(end 142.748254 -186.139836)
		(width 0.15494)
		(layer "In13.Cu")
		(net "PRSNT_SSD4_R_N")
	)
	(segment
		(start 336.441288 -234.779312)
		(end 337.4136 -233.807)
		(width 0.15494)
		(layer "In13.Cu")
		(net "PRSNT_SSD4_R_N")
	)
	(segment
		(start 217.93835 -175.3616)
		(end 212.039454 -175.3616)
		(width 0.15494)
		(layer "In13.Cu")
		(net "PRSNT_SSD4_R_N")
	)
	(segment
		(start 233.067352 -224.609152)
		(end 233.067352 -227.606606)
		(width 0.15494)
		(layer "In13.Cu")
		(net "PRSNT_SSD4_R_N")
	)
	(segment
		(start 247.376696 -232.343706)
		(end 257.012948 -232.343706)
		(width 0.15494)
		(layer "In13.Cu")
		(net "PRSNT_SSD4_R_N")
	)
	(segment
		(start 229.422198 -173.645322)
		(end 219.654628 -173.645322)
		(width 0.15494)
		(layer "In13.Cu")
		(net "PRSNT_SSD4_R_N")
	)
	(segment
		(start 330.310236 -236.8042)
		(end 334.9244 -236.8042)
		(width 0.15494)
		(layer "In13.Cu")
		(net "PRSNT_SSD4_R_N")
	)
	(segment
		(start 192.249298 -185.169048)
		(end 184.268618 -185.169048)
		(width 0.15494)
		(layer "In13.Cu")
		(net "PRSNT_SSD4_R_N")
	)
	(segment
		(start 245.779036 -231.682036)
		(end 247.376696 -232.343706)
		(width 0.15494)
		(layer "In13.Cu")
		(net "PRSNT_SSD4_R_N")
	)
	(segment
		(start 336.441288 -235.287312)
		(end 336.441288 -234.779312)
		(width 0.15494)
		(layer "In13.Cu")
		(net "PRSNT_SSD4_R_N")
	)
	(segment
		(start 334.9244 -236.8042)
		(end 336.441288 -235.287312)
		(width 0.15494)
		(layer "In13.Cu")
		(net "PRSNT_SSD4_R_N")
	)
	(segment
		(start 329.245976 -237.86846)
		(end 330.310236 -236.8042)
		(width 0.15494)
		(layer "In13.Cu")
		(net "PRSNT_SSD4_R_N")
	)
	(segment
		(start 184.268618 -185.169048)
		(end 183.925718 -185.511948)
		(width 0.15494)
		(layer "In13.Cu")
		(net "PRSNT_SSD4_R_N")
	)
	(segment
		(start 233.067352 -227.606606)
		(end 236.270546 -230.8098)
		(width 0.15494)
		(layer "In13.Cu")
		(net "PRSNT_SSD4_R_N")
	)
	(segment
		(start 212.039454 -175.3616)
		(end 210.515454 -176.8856)
		(width 0.15494)
		(layer "In13.Cu")
		(net "PRSNT_SSD4_R_N")
	)
	(segment
		(start 235.801662 -174.330868)
		(end 235.482638 -174.330868)
		(width 0.15494)
		(layer "In13.Cu")
		(net "PRSNT_SSD4_R_N")
	)
	(segment
		(start 234.280202 -173.128432)
		(end 229.939088 -173.128432)
		(width 0.15494)
		(layer "In13.Cu")
		(net "PRSNT_SSD4_R_N")
	)
	(segment
		(start 236.270546 -230.8098)
		(end 244.9068 -230.8098)
		(width 0.15494)
		(layer "In13.Cu")
		(net "PRSNT_SSD4_R_N")
	)
	(segment
		(start 244.9068 -230.8098)
		(end 245.779036 -231.682036)
		(width 0.15494)
		(layer "In13.Cu")
		(net "PRSNT_SSD4_R_N")
	)
	(segment
		(start 179.9082 -185.511948)
		(end 179.076604 -186.343544)
		(width 0.15494)
		(layer "In13.Cu")
		(net "PRSNT_SSD4_R_N")
	)
	(segment
		(start 183.925718 -185.511948)
		(end 179.9082 -185.511948)
		(width 0.15494)
		(layer "In13.Cu")
		(net "PRSNT_SSD4_R_N")
	)
	(segment
		(start 344.893646 -231.280208)
		(end 344.893646 -226.786948)
		(width 0.15494)
		(layer "In13.Cu")
		(net "PRSNT_SSD4_R_N")
	)
	(segment
		(start 257.868674 -231.48798)
		(end 272.20672 -231.48798)
		(width 0.15494)
		(layer "In13.Cu")
		(net "PRSNT_SSD4_R_N")
	)
	(segment
		(start 146.7358 -185.5216)
		(end 143.36649 -185.5216)
		(width 0.15494)
		(layer "In13.Cu")
		(net "PRSNT_SSD4_R_N")
	)
	(segment
		(start 179.076604 -186.343544)
		(end 147.557744 -186.343544)
		(width 0.15494)
		(layer "In13.Cu")
		(net "PRSNT_SSD4_R_N")
	)
	(segment
		(start 343.586054 -232.5878)
		(end 344.893646 -231.280208)
		(width 0.15494)
		(layer "In13.Cu")
		(net "PRSNT_SSD4_R_N")
	)
	(segment
		(start 229.939088 -173.128432)
		(end 229.422198 -173.645322)
		(width 0.15494)
		(layer "In13.Cu")
		(net "PRSNT_SSD4_R_N")
	)
	(segment
		(start 316.476634 -236.260894)
		(end 318.0842 -237.86846)
		(width 0.15494)
		(layer "In13.Cu")
		(net "PRSNT_SSD4_R_N")
	)
	(segment
		(start 341.502746 -232.5878)
		(end 343.586054 -232.5878)
		(width 0.15494)
		(layer "In13.Cu")
		(net "PRSNT_SSD4_R_N")
	)
	(segment
		(start 233.067352 -223.103694)
		(end 233.067352 -224.609152)
		(width 0.0889)
		(layer "In13.Cu")
		(net "PRSNT_SSD4_R_N")
	)
	(segment
		(start 276.979634 -236.260894)
		(end 316.476634 -236.260894)
		(width 0.15494)
		(layer "In13.Cu")
		(net "PRSNT_SSD4_R_N")
	)
	(segment
		(start 318.0842 -237.86846)
		(end 329.245976 -237.86846)
		(width 0.15494)
		(layer "In13.Cu")
		(net "PRSNT_SSD4_R_N")
	)
	(segment
		(start 340.283546 -233.807)
		(end 341.502746 -232.5878)
		(width 0.15494)
		(layer "In13.Cu")
		(net "PRSNT_SSD4_R_N")
	)
	(segment
		(start 147.557744 -186.343544)
		(end 146.7358 -185.5216)
		(width 0.15494)
		(layer "In13.Cu")
		(net "PRSNT_SSD4_R_N")
	)
	(segment
		(start 232.667556 -222.703898)
		(end 233.067352 -223.103694)
		(width 0.0889)
		(layer "In13.Cu")
		(net "PRSNT_SSD4_R_N")
	)
	(segment
		(start 257.012948 -232.343706)
		(end 257.868674 -231.48798)
		(width 0.15494)
		(layer "In13.Cu")
		(net "PRSNT_SSD4_R_N")
	)
	(segment
		(start 337.4136 -233.807)
		(end 340.283546 -233.807)
		(width 0.15494)
		(layer "In13.Cu")
		(net "PRSNT_SSD4_R_N")
	)
	(segment
		(start 272.20672 -231.48798)
		(end 276.979634 -236.260894)
		(width 0.15494)
		(layer "In13.Cu")
		(net "PRSNT_SSD4_R_N")
	)
	(segment
		(start 219.654628 -173.645322)
		(end 217.93835 -175.3616)
		(width 0.15494)
		(layer "In13.Cu")
		(net "PRSNT_SSD4_R_N")
	)
	(segment
		(start 200.532746 -176.8856)
		(end 192.249298 -185.169048)
		(width 0.15494)
		(layer "In13.Cu")
		(net "PRSNT_SSD4_R_N")
	)
	(segment
		(start 210.515454 -176.8856)
		(end 200.532746 -176.8856)
		(width 0.15494)
		(layer "In13.Cu")
		(net "PRSNT_SSD4_R_N")
	)
	(segment
		(start 235.482638 -174.330868)
		(end 234.280202 -173.128432)
		(width 0.15494)
		(layer "In13.Cu")
		(net "PRSNT_SSD4_R_N")
	)
	(segment
		(start 340.493858 -213.587076)
		(end 340.093808 -213.187026)
		(width 0.13208)
		(layer "F.Cu")
		(net "SSD12_PWR_EN")
	)
	(via
		(at 338.296758 -209.645758)
		(size 0.6604)
		(drill 0.3302)
		(layers "F.Cu" "B.Cu")
		(net "SSD12_PWR_EN")
	)
	(via
		(at 340.093808 -213.187026)
		(size 0.4572)
		(drill 0.254)
		(layers "F.Cu" "B.Cu")
		(net "SSD12_PWR_EN")
	)
	(segment
		(start 338.296758 -209.645758)
		(end 337.439 -208.788)
		(width 0.13208)
		(layer "B.Cu")
		(net "SSD12_PWR_EN")
	)
	(segment
		(start 339.5472 -210.3882)
		(end 339.694012 -210.535012)
		(width 0.0889)
		(layer "B.Cu")
		(net "SSD12_PWR_EN")
	)
	(segment
		(start 338.296758 -209.645758)
		(end 339.0392 -210.3882)
		(width 0.13208)
		(layer "B.Cu")
		(net "SSD12_PWR_EN")
	)
	(segment
		(start 337.439 -208.788)
		(end 337.439 -208.17205)
		(width 0.13208)
		(layer "B.Cu")
		(net "SSD12_PWR_EN")
	)
	(segment
		(start 339.694012 -210.535012)
		(end 339.694012 -212.78723)
		(width 0.0889)
		(layer "B.Cu")
		(net "SSD12_PWR_EN")
	)
	(segment
		(start 339.694012 -212.78723)
		(end 340.093808 -213.187026)
		(width 0.0889)
		(layer "B.Cu")
		(net "SSD12_PWR_EN")
	)
	(segment
		(start 339.0392 -210.3882)
		(end 339.5472 -210.3882)
		(width 0.0889)
		(layer "B.Cu")
		(net "SSD12_PWR_EN")
	)
	(segment
		(start 305.149758 -290.199826)
		(end 305.624738 -289.724846)
		(width 0.13208)
		(layer "F.Cu")
		(net "UART_PEX2_SDB_TX")
	)
	(via
		(at 306.099718 -290.199826)
		(size 0.6604)
		(drill 0.3302)
		(layers "F.Cu" "B.Cu")
		(net "UART_PEX2_SDB_TX")
	)
	(via
		(at 305.624738 -289.724846)
		(size 0.4064)
		(drill 0.2032)
		(layers "F.Cu" "B.Cu")
		(net "UART_PEX2_SDB_TX")
	)
	(segment
		(start 307.448712 -290.124896)
		(end 307.923692 -290.124896)
		(width 0.13208)
		(layer "B.Cu")
		(net "UART_PEX2_SDB_TX")
	)
	(segment
		(start 305.624738 -289.724846)
		(end 306.099718 -290.199826)
		(width 0.13208)
		(layer "B.Cu")
		(net "UART_PEX2_SDB_TX")
	)
	(segment
		(start 307.373782 -290.199826)
		(end 307.448712 -290.124896)
		(width 0.13208)
		(layer "B.Cu")
		(net "UART_PEX2_SDB_TX")
	)
	(segment
		(start 306.099718 -290.199826)
		(end 307.373782 -290.199826)
		(width 0.13208)
		(layer "B.Cu")
		(net "UART_PEX2_SDB_TX")
	)
	(segment
		(start 223.48825 -191.417448)
		(end 222.877126 -192.028572)
		(width 0.13208)
		(layer "F.Cu")
		(net "SPI2_CLK_BUF")
	)
	(segment
		(start 222.877126 -192.028572)
		(end 222.877126 -193.378328)
		(width 0.13208)
		(layer "F.Cu")
		(net "SPI2_CLK_BUF")
	)
	(via
		(at 223.48825 -191.417448)
		(size 0.508)
		(drill 0.254)
		(layers "F.Cu" "B.Cu")
		(net "SPI2_CLK_BUF")
	)
	(segment
		(start 224.443544 -191.804036)
		(end 223.874838 -191.804036)
		(width 0.13208)
		(layer "B.Cu")
		(net "SPI2_CLK_BUF")
	)
	(segment
		(start 223.874838 -191.804036)
		(end 223.48825 -191.417448)
		(width 0.13208)
		(layer "B.Cu")
		(net "SPI2_CLK_BUF")
	)
	(segment
		(start 225.19894 -192.559432)
		(end 224.443544 -191.804036)
		(width 0.13208)
		(layer "B.Cu")
		(net "SPI2_CLK_BUF")
	)
	(segment
		(start 131.908042 -174.74819)
		(end 131.971034 -174.900336)
		(width 0.1143)
		(layer "F.Cu")
		(net "CLK_100M_DB2000QL_PEX3_S1_DN")
	)
	(segment
		(start 131.908042 -172.319188)
		(end 131.908042 -174.74819)
		(width 0.1143)
		(layer "F.Cu")
		(net "CLK_100M_DB2000QL_PEX3_S1_DN")
	)
	(segment
		(start 131.105656 -171.516802)
		(end 131.908042 -172.319188)
		(width 0.1143)
		(layer "F.Cu")
		(net "CLK_100M_DB2000QL_PEX3_S1_DN")
	)
	(segment
		(start 131.105656 -171.330112)
		(end 131.105656 -171.516802)
		(width 0.1143)
		(layer "F.Cu")
		(net "CLK_100M_DB2000QL_PEX3_S1_DN")
	)
	(segment
		(start 131.435856 -170.999912)
		(end 131.105656 -171.330112)
		(width 0.1143)
		(layer "F.Cu")
		(net "CLK_100M_DB2000QL_PEX3_S1_DN")
	)
	(segment
		(start 235.223558 -151.975566)
		(end 234.90301 -151.655018)
		(width 0.1143)
		(layer "F.Cu")
		(net "CLK_100M_PEX2_REF_DP")
	)
	(segment
		(start 232.67924 -150.390352)
		(end 232.471976 -150.390352)
		(width 0.1143)
		(layer "F.Cu")
		(net "CLK_100M_PEX2_REF_DP")
	)
	(segment
		(start 234.90301 -151.655018)
		(end 234.547664 -151.655018)
		(width 0.1143)
		(layer "F.Cu")
		(net "CLK_100M_PEX2_REF_DP")
	)
	(segment
		(start 234.547664 -151.655018)
		(end 233.223562 -150.330916)
		(width 0.1143)
		(layer "F.Cu")
		(net "CLK_100M_PEX2_REF_DP")
	)
	(segment
		(start 233.223562 -150.330916)
		(end 232.738676 -150.330916)
		(width 0.1143)
		(layer "F.Cu")
		(net "CLK_100M_PEX2_REF_DP")
	)
	(segment
		(start 232.738676 -150.330916)
		(end 232.67924 -150.390352)
		(width 0.1143)
		(layer "F.Cu")
		(net "CLK_100M_PEX2_REF_DP")
	)
	(segment
		(start 4.248912 -32.724344)
		(end 4.248912 -32.987742)
		(width 0.13208)
		(layer "F.Cu")
		(net "SMB_SSD0_ISO_EN")
	)
	(segment
		(start 5.04317 -33.782)
		(end 5.04317 -34.496248)
		(width 0.13208)
		(layer "F.Cu")
		(net "SMB_SSD0_ISO_EN")
	)
	(segment
		(start 4.248912 -32.987742)
		(end 5.04317 -33.782)
		(width 0.13208)
		(layer "F.Cu")
		(net "SMB_SSD0_ISO_EN")
	)
	(via
		(at 5.04317 -33.782)
		(size 0.508)
		(drill 0.254)
		(layers "F.Cu" "B.Cu")
		(net "SMB_SSD0_ISO_EN")
	)
	(segment
		(start 149.303486 -392.646916)
		(end 149.303486 -390.798304)
		(width 0.13208)
		(layer "F.Cu")
		(net "GPU_BASE_HMC_READY_R")
	)
	(via
		(at 149.303486 -392.646916)
		(size 0.508)
		(drill 0.254)
		(layers "F.Cu" "B.Cu")
		(net "GPU_BASE_HMC_READY_R")
	)
	(segment
		(start 140.583412 -393.2428)
		(end 139.957048 -393.869164)
		(width 0.15494)
		(layer "In9.Cu")
		(net "GPU_BASE_HMC_READY_R")
	)
	(segment
		(start 149.303486 -392.646916)
		(end 148.707602 -393.2428)
		(width 0.15494)
		(layer "In9.Cu")
		(net "GPU_BASE_HMC_READY_R")
	)
	(segment
		(start 139.957048 -393.869164)
		(end 139.957048 -409.954476)
		(width 0.15494)
		(layer "In9.Cu")
		(net "GPU_BASE_HMC_READY_R")
	)
	(segment
		(start 126.259082 -413.639)
		(end 124.71019 -412.090108)
		(width 0.15494)
		(layer "In9.Cu")
		(net "GPU_BASE_HMC_READY_R")
	)
	(segment
		(start 139.957048 -409.954476)
		(end 136.272524 -413.639)
		(width 0.15494)
		(layer "In9.Cu")
		(net "GPU_BASE_HMC_READY_R")
	)
	(segment
		(start 148.707602 -393.2428)
		(end 140.583412 -393.2428)
		(width 0.15494)
		(layer "In9.Cu")
		(net "GPU_BASE_HMC_READY_R")
	)
	(segment
		(start 136.272524 -413.639)
		(end 126.259082 -413.639)
		(width 0.15494)
		(layer "In9.Cu")
		(net "GPU_BASE_HMC_READY_R")
	)
	(segment
		(start 166.234618 -28.469082)
		(end 166.234618 -28.550108)
		(width 0.13208)
		(layer "F.Cu")
		(net "SSD5_PWRDIS_R")
	)
	(segment
		(start 157.364938 -25.390094)
		(end 156.29128 -25.390094)
		(width 0.13208)
		(layer "F.Cu")
		(net "SSD5_PWRDIS_R")
	)
	(segment
		(start 166.234618 -28.550108)
		(end 166.764462 -29.079952)
		(width 0.13208)
		(layer "F.Cu")
		(net "SSD5_PWRDIS_R")
	)
	(via
		(at 183.588406 -235.48213)
		(size 0.508)
		(drill 0.254)
		(layers "F.Cu" "B.Cu")
		(net "SSD5_PWRDIS_R")
	)
	(via
		(at 343.027 -236.347)
		(size 0.508)
		(drill 0.254)
		(layers "F.Cu" "B.Cu")
		(net "SSD5_PWRDIS_R")
	)
	(via
		(at 156.29128 -25.390094)
		(size 0.508)
		(drill 0.254)
		(layers "F.Cu" "B.Cu")
		(net "SSD5_PWRDIS_R")
	)
	(via
		(at 166.234618 -28.469082)
		(size 0.508)
		(drill 0.254)
		(layers "F.Cu" "B.Cu")
		(net "SSD5_PWRDIS_R")
	)
	(segment
		(start 343.56929 -235.80471)
		(end 343.027 -236.347)
		(width 0.13208)
		(layer "B.Cu")
		(net "SSD5_PWRDIS_R")
	)
	(segment
		(start 343.56929 -234.42676)
		(end 343.56929 -235.80471)
		(width 0.13208)
		(layer "B.Cu")
		(net "SSD5_PWRDIS_R")
	)
	(segment
		(start 344.043 -233.95305)
		(end 343.56929 -234.42676)
		(width 0.13208)
		(layer "B.Cu")
		(net "SSD5_PWRDIS_R")
	)
	(segment
		(start 178.28514 -45.489368)
		(end 178.28514 -78.622652)
		(width 0.15494)
		(layer "In5.Cu")
		(net "SSD5_PWRDIS_R")
	)
	(segment
		(start 172.134276 -87.526368)
		(end 173.595792 -88.987884)
		(width 0.15494)
		(layer "In5.Cu")
		(net "SSD5_PWRDIS_R")
	)
	(segment
		(start 174.559976 -108.073952)
		(end 174.559976 -199.528938)
		(width 0.15494)
		(layer "In5.Cu")
		(net "SSD5_PWRDIS_R")
	)
	(segment
		(start 158.892748 -25.390094)
		(end 160.934654 -27.432)
		(width 0.15494)
		(layer "In5.Cu")
		(net "SSD5_PWRDIS_R")
	)
	(segment
		(start 182.160926 -227.601526)
		(end 183.635904 -229.076504)
		(width 0.15494)
		(layer "In5.Cu")
		(net "SSD5_PWRDIS_R")
	)
	(segment
		(start 178.080416 -210.23072)
		(end 178.121056 -210.329018)
		(width 0.15494)
		(layer "In5.Cu")
		(net "SSD5_PWRDIS_R")
	)
	(segment
		(start 183.635904 -235.434632)
		(end 183.588406 -235.48213)
		(width 0.15494)
		(layer "In5.Cu")
		(net "SSD5_PWRDIS_R")
	)
	(segment
		(start 173.595792 -88.987884)
		(end 173.595792 -107.109768)
		(width 0.15494)
		(layer "In5.Cu")
		(net "SSD5_PWRDIS_R")
	)
	(segment
		(start 165.68039 -27.914854)
		(end 166.234618 -28.469082)
		(width 0.15494)
		(layer "In5.Cu")
		(net "SSD5_PWRDIS_R")
	)
	(segment
		(start 183.635904 -229.076504)
		(end 183.635904 -235.434632)
		(width 0.15494)
		(layer "In5.Cu")
		(net "SSD5_PWRDIS_R")
	)
	(segment
		(start 165.89375 -28.80995)
		(end 165.89375 -33.099756)
		(width 0.15494)
		(layer "In5.Cu")
		(net "SSD5_PWRDIS_R")
	)
	(segment
		(start 166.234618 -28.469082)
		(end 165.89375 -28.80995)
		(width 0.15494)
		(layer "In5.Cu")
		(net "SSD5_PWRDIS_R")
	)
	(segment
		(start 162.458908 -27.432)
		(end 162.941762 -27.914854)
		(width 0.15494)
		(layer "In5.Cu")
		(net "SSD5_PWRDIS_R")
	)
	(segment
		(start 178.121056 -210.329018)
		(end 178.121056 -211.503768)
		(width 0.15494)
		(layer "In5.Cu")
		(net "SSD5_PWRDIS_R")
	)
	(segment
		(start 162.941762 -27.914854)
		(end 165.68039 -27.914854)
		(width 0.15494)
		(layer "In5.Cu")
		(net "SSD5_PWRDIS_R")
	)
	(segment
		(start 178.121056 -211.503768)
		(end 182.160926 -221.256352)
		(width 0.15494)
		(layer "In5.Cu")
		(net "SSD5_PWRDIS_R")
	)
	(segment
		(start 160.934654 -27.432)
		(end 162.458908 -27.432)
		(width 0.15494)
		(layer "In5.Cu")
		(net "SSD5_PWRDIS_R")
	)
	(segment
		(start 178.28514 -78.622652)
		(end 172.134276 -84.773516)
		(width 0.15494)
		(layer "In5.Cu")
		(net "SSD5_PWRDIS_R")
	)
	(segment
		(start 178.080416 -203.049378)
		(end 178.080416 -210.23072)
		(width 0.15494)
		(layer "In5.Cu")
		(net "SSD5_PWRDIS_R")
	)
	(segment
		(start 182.160926 -221.256352)
		(end 182.160926 -227.601526)
		(width 0.15494)
		(layer "In5.Cu")
		(net "SSD5_PWRDIS_R")
	)
	(segment
		(start 156.29128 -25.390094)
		(end 158.892748 -25.390094)
		(width 0.15494)
		(layer "In5.Cu")
		(net "SSD5_PWRDIS_R")
	)
	(segment
		(start 172.134276 -84.773516)
		(end 172.134276 -87.526368)
		(width 0.15494)
		(layer "In5.Cu")
		(net "SSD5_PWRDIS_R")
	)
	(segment
		(start 174.559976 -199.528938)
		(end 178.080416 -203.049378)
		(width 0.15494)
		(layer "In5.Cu")
		(net "SSD5_PWRDIS_R")
	)
	(segment
		(start 173.595792 -107.109768)
		(end 174.559976 -108.073952)
		(width 0.15494)
		(layer "In5.Cu")
		(net "SSD5_PWRDIS_R")
	)
	(segment
		(start 165.89375 -33.099756)
		(end 178.28514 -45.489368)
		(width 0.15494)
		(layer "In5.Cu")
		(net "SSD5_PWRDIS_R")
	)
	(segment
		(start 327.660508 -243.702332)
		(end 328.638408 -243.702332)
		(width 0.15494)
		(layer "In15.Cu")
		(net "SSD5_PWRDIS_R")
	)
	(segment
		(start 328.638408 -243.702332)
		(end 329.706224 -242.634516)
		(width 0.15494)
		(layer "In15.Cu")
		(net "SSD5_PWRDIS_R")
	)
	(segment
		(start 264.453624 -237.356396)
		(end 264.453624 -238.477806)
		(width 0.15494)
		(layer "In15.Cu")
		(net "SSD5_PWRDIS_R")
	)
	(segment
		(start 332.375764 -242.634516)
		(end 333.042514 -241.967766)
		(width 0.15494)
		(layer "In15.Cu")
		(net "SSD5_PWRDIS_R")
	)
	(segment
		(start 184.571386 -235.48213)
		(end 191.253618 -242.164362)
		(width 0.15494)
		(layer "In15.Cu")
		(net "SSD5_PWRDIS_R")
	)
	(segment
		(start 264.453624 -238.477806)
		(end 268.527022 -242.551204)
		(width 0.15494)
		(layer "In15.Cu")
		(net "SSD5_PWRDIS_R")
	)
	(segment
		(start 343.027 -236.956854)
		(end 343.027 -236.347)
		(width 0.15494)
		(layer "In15.Cu")
		(net "SSD5_PWRDIS_R")
	)
	(segment
		(start 254.802894 -235.9914)
		(end 257.449574 -235.464604)
		(width 0.15494)
		(layer "In15.Cu")
		(net "SSD5_PWRDIS_R")
	)
	(segment
		(start 191.253618 -242.164362)
		(end 213.639908 -242.164362)
		(width 0.15494)
		(layer "In15.Cu")
		(net "SSD5_PWRDIS_R")
	)
	(segment
		(start 340.180422 -241.967766)
		(end 341.37219 -240.775998)
		(width 0.15494)
		(layer "In15.Cu")
		(net "SSD5_PWRDIS_R")
	)
	(segment
		(start 183.588406 -235.48213)
		(end 184.571386 -235.48213)
		(width 0.15494)
		(layer "In15.Cu")
		(net "SSD5_PWRDIS_R")
	)
	(segment
		(start 302.585628 -244.040152)
		(end 327.322688 -244.040152)
		(width 0.15494)
		(layer "In15.Cu")
		(net "SSD5_PWRDIS_R")
	)
	(segment
		(start 214.418164 -242.942618)
		(end 218.512898 -242.942618)
		(width 0.15494)
		(layer "In15.Cu")
		(net "SSD5_PWRDIS_R")
	)
	(segment
		(start 301.857664 -243.312188)
		(end 302.585628 -244.040152)
		(width 0.15494)
		(layer "In15.Cu")
		(net "SSD5_PWRDIS_R")
	)
	(segment
		(start 257.449574 -235.464604)
		(end 261.89051 -235.464604)
		(width 0.15494)
		(layer "In15.Cu")
		(net "SSD5_PWRDIS_R")
	)
	(segment
		(start 213.639908 -242.164362)
		(end 214.418164 -242.942618)
		(width 0.15494)
		(layer "In15.Cu")
		(net "SSD5_PWRDIS_R")
	)
	(segment
		(start 248.510044 -242.28425)
		(end 254.802894 -235.9914)
		(width 0.15494)
		(layer "In15.Cu")
		(net "SSD5_PWRDIS_R")
	)
	(segment
		(start 219.2909 -242.164616)
		(end 238.389922 -242.164616)
		(width 0.15494)
		(layer "In15.Cu")
		(net "SSD5_PWRDIS_R")
	)
	(segment
		(start 218.512898 -242.942618)
		(end 219.2909 -242.164616)
		(width 0.15494)
		(layer "In15.Cu")
		(net "SSD5_PWRDIS_R")
	)
	(segment
		(start 274.932902 -242.551204)
		(end 275.693886 -243.312188)
		(width 0.15494)
		(layer "In15.Cu")
		(net "SSD5_PWRDIS_R")
	)
	(segment
		(start 261.89051 -235.464604)
		(end 263.036304 -235.939076)
		(width 0.15494)
		(layer "In15.Cu")
		(net "SSD5_PWRDIS_R")
	)
	(segment
		(start 333.042514 -241.967766)
		(end 340.180422 -241.967766)
		(width 0.15494)
		(layer "In15.Cu")
		(net "SSD5_PWRDIS_R")
	)
	(segment
		(start 341.37219 -238.611664)
		(end 343.027 -236.956854)
		(width 0.15494)
		(layer "In15.Cu")
		(net "SSD5_PWRDIS_R")
	)
	(segment
		(start 341.37219 -240.775998)
		(end 341.37219 -238.611664)
		(width 0.15494)
		(layer "In15.Cu")
		(net "SSD5_PWRDIS_R")
	)
	(segment
		(start 329.706224 -242.634516)
		(end 332.375764 -242.634516)
		(width 0.15494)
		(layer "In15.Cu")
		(net "SSD5_PWRDIS_R")
	)
	(segment
		(start 268.527022 -242.551204)
		(end 274.932902 -242.551204)
		(width 0.15494)
		(layer "In15.Cu")
		(net "SSD5_PWRDIS_R")
	)
	(segment
		(start 238.389922 -242.164616)
		(end 238.509556 -242.28425)
		(width 0.15494)
		(layer "In15.Cu")
		(net "SSD5_PWRDIS_R")
	)
	(segment
		(start 275.693886 -243.312188)
		(end 301.857664 -243.312188)
		(width 0.15494)
		(layer "In15.Cu")
		(net "SSD5_PWRDIS_R")
	)
	(segment
		(start 263.036304 -235.939076)
		(end 264.453624 -237.356396)
		(width 0.15494)
		(layer "In15.Cu")
		(net "SSD5_PWRDIS_R")
	)
	(segment
		(start 238.509556 -242.28425)
		(end 248.510044 -242.28425)
		(width 0.15494)
		(layer "In15.Cu")
		(net "SSD5_PWRDIS_R")
	)
	(segment
		(start 327.322688 -244.040152)
		(end 327.660508 -243.702332)
		(width 0.15494)
		(layer "In15.Cu")
		(net "SSD5_PWRDIS_R")
	)
	(segment
		(start 340.493858 -215.987122)
		(end 340.094062 -215.587326)
		(width 0.13208)
		(layer "F.Cu")
		(net "SSD11_PWR_EN")
	)
	(segment
		(start 340.614 -201.56805)
		(end 340.614 -202.946)
		(width 0.13208)
		(layer "F.Cu")
		(net "SSD11_PWR_EN")
	)
	(via
		(at 340.614 -202.946)
		(size 0.508)
		(drill 0.254)
		(layers "F.Cu" "B.Cu")
		(net "SSD11_PWR_EN")
	)
	(via
		(at 340.094062 -215.587326)
		(size 0.4572)
		(drill 0.254)
		(layers "F.Cu" "B.Cu")
		(net "SSD11_PWR_EN")
	)
	(segment
		(start 341.639398 -205.649322)
		(end 341.114126 -205.12405)
		(width 0.15494)
		(layer "In5.Cu")
		(net "SSD11_PWR_EN")
	)
	(segment
		(start 340.614 -203.495656)
		(end 340.614 -202.946)
		(width 0.15494)
		(layer "In5.Cu")
		(net "SSD11_PWR_EN")
	)
	(segment
		(start 341.8713 -215.98636)
		(end 342.03386 -215.98636)
		(width 0.15494)
		(layer "In5.Cu")
		(net "SSD11_PWR_EN")
	)
	(segment
		(start 342.03386 -215.98636)
		(end 342.50122 -215.519)
		(width 0.15494)
		(layer "In5.Cu")
		(net "SSD11_PWR_EN")
	)
	(segment
		(start 341.639398 -206.443834)
		(end 341.639398 -205.649322)
		(width 0.15494)
		(layer "In5.Cu")
		(net "SSD11_PWR_EN")
	)
	(segment
		(start 341.114126 -203.995782)
		(end 340.614 -203.495656)
		(width 0.15494)
		(layer "In5.Cu")
		(net "SSD11_PWR_EN")
	)
	(segment
		(start 342.348058 -207.152494)
		(end 341.639398 -206.443834)
		(width 0.15494)
		(layer "In5.Cu")
		(net "SSD11_PWR_EN")
	)
	(segment
		(start 342.50122 -215.519)
		(end 342.50122 -211.039202)
		(width 0.15494)
		(layer "In5.Cu")
		(net "SSD11_PWR_EN")
	)
	(segment
		(start 340.094062 -215.587326)
		(end 340.493096 -215.98636)
		(width 0.0889)
		(layer "In5.Cu")
		(net "SSD11_PWR_EN")
	)
	(segment
		(start 342.50122 -211.039202)
		(end 342.348058 -210.88604)
		(width 0.15494)
		(layer "In5.Cu")
		(net "SSD11_PWR_EN")
	)
	(segment
		(start 340.493096 -215.98636)
		(end 341.8713 -215.98636)
		(width 0.0889)
		(layer "In5.Cu")
		(net "SSD11_PWR_EN")
	)
	(segment
		(start 341.114126 -205.12405)
		(end 341.114126 -203.995782)
		(width 0.15494)
		(layer "In5.Cu")
		(net "SSD11_PWR_EN")
	)
	(segment
		(start 342.348058 -210.88604)
		(end 342.348058 -207.152494)
		(width 0.15494)
		(layer "In5.Cu")
		(net "SSD11_PWR_EN")
	)
	(segment
		(start 231.954832 -155.560776)
		(end 231.630982 -155.236926)
		(width 0.1143)
		(layer "F.Cu")
		(net "CLK_100M_PEX1_REF_DN")
	)
	(segment
		(start 230.781098 -151.310848)
		(end 230.846884 -151.245062)
		(width 0.1143)
		(layer "F.Cu")
		(net "CLK_100M_PEX1_REF_DN")
	)
	(segment
		(start 230.781098 -152.574752)
		(end 230.781098 -151.310848)
		(width 0.1143)
		(layer "F.Cu")
		(net "CLK_100M_PEX1_REF_DN")
	)
	(segment
		(start 231.630982 -155.236926)
		(end 231.630982 -153.424636)
		(width 0.1143)
		(layer "F.Cu")
		(net "CLK_100M_PEX1_REF_DN")
	)
	(segment
		(start 231.630982 -153.424636)
		(end 230.781098 -152.574752)
		(width 0.1143)
		(layer "F.Cu")
		(net "CLK_100M_PEX1_REF_DN")
	)
	(segment
		(start 230.846884 -151.245062)
		(end 230.846884 -151.015446)
		(width 0.1143)
		(layer "F.Cu")
		(net "CLK_100M_PEX1_REF_DN")
	)
	(segment
		(start 168.08704 -142.60068)
		(end 167.74668 -142.60068)
		(width 0.13208)
		(layer "F.Cu")
		(net "SMB_NIC2_R_SCL")
	)
	(segment
		(start 167.74668 -142.60068)
		(end 167.71112 -142.56512)
		(width 0.13208)
		(layer "F.Cu")
		(net "SMB_NIC2_R_SCL")
	)
	(segment
		(start 169.139108 -142.9512)
		(end 168.788588 -142.60068)
		(width 0.13208)
		(layer "F.Cu")
		(net "SMB_NIC2_R_SCL")
	)
	(segment
		(start 216.316814 -226.811586)
		(end 216.835736 -226.811586)
		(width 0.13208)
		(layer "F.Cu")
		(net "SMB_NIC2_R_SCL")
	)
	(segment
		(start 171.579794 -142.9512)
		(end 169.139108 -142.9512)
		(width 0.13208)
		(layer "F.Cu")
		(net "SMB_NIC2_R_SCL")
	)
	(segment
		(start 167.71112 -142.56512)
		(end 166.742364 -142.56512)
		(width 0.13208)
		(layer "F.Cu")
		(net "SMB_NIC2_R_SCL")
	)
	(segment
		(start 168.788588 -142.60068)
		(end 168.08704 -142.60068)
		(width 0.13208)
		(layer "F.Cu")
		(net "SMB_NIC2_R_SCL")
	)
	(segment
		(start 215.593168 -227.703888)
		(end 215.593168 -227.535232)
		(width 0.13208)
		(layer "F.Cu")
		(net "SMB_NIC2_R_SCL")
	)
	(segment
		(start 215.593168 -227.535232)
		(end 216.316814 -226.811586)
		(width 0.13208)
		(layer "F.Cu")
		(net "SMB_NIC2_R_SCL")
	)
	(via
		(at 215.593168 -227.703888)
		(size 0.508)
		(drill 0.254)
		(layers "F.Cu" "B.Cu")
		(net "SMB_NIC2_R_SCL")
	)
	(via
		(at 168.08704 -142.60068)
		(size 0.508)
		(drill 0.254)
		(layers "F.Cu" "B.Cu")
		(net "SMB_NIC2_R_SCL")
	)
	(via
		(at 185.039762 -226.489768)
		(size 0.508)
		(drill 0.254)
		(layers "F.Cu" "B.Cu")
		(net "SMB_NIC2_R_SCL")
	)
	(segment
		(start 168.08704 -142.60068)
		(end 168.40708 -142.60068)
		(width 0.15494)
		(layer "In9.Cu")
		(net "SMB_NIC2_R_SCL")
	)
	(segment
		(start 168.40708 -142.60068)
		(end 170.51528 -144.70888)
		(width 0.15494)
		(layer "In9.Cu")
		(net "SMB_NIC2_R_SCL")
	)
	(segment
		(start 170.51528 -177.90668)
		(end 184.035954 -191.427354)
		(width 0.15494)
		(layer "In9.Cu")
		(net "SMB_NIC2_R_SCL")
	)
	(segment
		(start 184.035954 -224.9043)
		(end 185.039762 -225.908108)
		(width 0.15494)
		(layer "In9.Cu")
		(net "SMB_NIC2_R_SCL")
	)
	(segment
		(start 170.51528 -144.70888)
		(end 170.51528 -177.90668)
		(width 0.15494)
		(layer "In9.Cu")
		(net "SMB_NIC2_R_SCL")
	)
	(segment
		(start 184.035954 -191.427354)
		(end 184.035954 -224.9043)
		(width 0.15494)
		(layer "In9.Cu")
		(net "SMB_NIC2_R_SCL")
	)
	(segment
		(start 185.039762 -225.908108)
		(end 185.039762 -226.489768)
		(width 0.15494)
		(layer "In9.Cu")
		(net "SMB_NIC2_R_SCL")
	)
	(segment
		(start 188.361574 -223.167956)
		(end 207.626712 -223.167956)
		(width 0.15494)
		(layer "In13.Cu")
		(net "SMB_NIC2_R_SCL")
	)
	(segment
		(start 207.626712 -223.167956)
		(end 209.128614 -224.669858)
		(width 0.15494)
		(layer "In13.Cu")
		(net "SMB_NIC2_R_SCL")
	)
	(segment
		(start 209.409538 -224.669858)
		(end 210.810094 -226.070414)
		(width 0.15494)
		(layer "In13.Cu")
		(net "SMB_NIC2_R_SCL")
	)
	(segment
		(start 209.128614 -224.669858)
		(end 209.409538 -224.669858)
		(width 0.15494)
		(layer "In13.Cu")
		(net "SMB_NIC2_R_SCL")
	)
	(segment
		(start 210.810094 -226.898962)
		(end 212.270594 -228.359462)
		(width 0.15494)
		(layer "In13.Cu")
		(net "SMB_NIC2_R_SCL")
	)
	(segment
		(start 185.039762 -226.489768)
		(end 188.361574 -223.167956)
		(width 0.15494)
		(layer "In13.Cu")
		(net "SMB_NIC2_R_SCL")
	)
	(segment
		(start 214.937594 -228.359462)
		(end 215.593168 -227.703888)
		(width 0.15494)
		(layer "In13.Cu")
		(net "SMB_NIC2_R_SCL")
	)
	(segment
		(start 212.270594 -228.359462)
		(end 214.937594 -228.359462)
		(width 0.15494)
		(layer "In13.Cu")
		(net "SMB_NIC2_R_SCL")
	)
	(segment
		(start 210.810094 -226.070414)
		(end 210.810094 -226.898962)
		(width 0.15494)
		(layer "In13.Cu")
		(net "SMB_NIC2_R_SCL")
	)
	(segment
		(start 59.11342 -376.540268)
		(end 59.307984 -376.345704)
		(width 0.13208)
		(layer "F.Cu")
		(net "GPU_BASE_PWR_EN")
	)
	(segment
		(start 60.070492 -375.59361)
		(end 60.070492 -375.959116)
		(width 0.13208)
		(layer "F.Cu")
		(net "GPU_BASE_PWR_EN")
	)
	(segment
		(start 58.576972 -376.540268)
		(end 59.11342 -376.540268)
		(width 0.13208)
		(layer "F.Cu")
		(net "GPU_BASE_PWR_EN")
	)
	(segment
		(start 60.070492 -375.959116)
		(end 59.683904 -376.345704)
		(width 0.13208)
		(layer "F.Cu")
		(net "GPU_BASE_PWR_EN")
	)
	(segment
		(start 59.307984 -376.345704)
		(end 59.683904 -376.345704)
		(width 0.13208)
		(layer "F.Cu")
		(net "GPU_BASE_PWR_EN")
	)
	(via
		(at 59.683904 -376.345704)
		(size 0.508)
		(drill 0.254)
		(layers "F.Cu" "B.Cu")
		(net "GPU_BASE_PWR_EN")
	)
	(segment
		(start 59.683904 -376.345704)
		(end 58.6994 -375.3612)
		(width 0.15494)
		(layer "In15.Cu")
		(net "GPU_BASE_PWR_EN")
	)
	(segment
		(start 58.6994 -375.3612)
		(end 58.6994 -374.922796)
		(width 0.15494)
		(layer "In15.Cu")
		(net "GPU_BASE_PWR_EN")
	)
	(segment
		(start 58.6994 -374.922796)
		(end 65.544446 -368.07775)
		(width 0.15494)
		(layer "In15.Cu")
		(net "GPU_BASE_PWR_EN")
	)
	(segment
		(start 65.544446 -368.07775)
		(end 77.597508 -368.07775)
		(width 0.15494)
		(layer "In15.Cu")
		(net "GPU_BASE_PWR_EN")
	)
	(segment
		(start 77.597508 -368.07775)
		(end 78.509876 -368.990118)
		(width 0.15494)
		(layer "In15.Cu")
		(net "GPU_BASE_PWR_EN")
	)
	(segment
		(start 140.23467 -28.469082)
		(end 140.23467 -28.550108)
		(width 0.13208)
		(layer "F.Cu")
		(net "SSD4_PWRDIS_R")
	)
	(segment
		(start 345.059 -234.46105)
		(end 345.059 -235.077)
		(width 0.13208)
		(layer "F.Cu")
		(net "SSD4_PWRDIS_R")
	)
	(segment
		(start 140.23467 -28.550108)
		(end 140.764514 -29.079952)
		(width 0.13208)
		(layer "F.Cu")
		(net "SSD4_PWRDIS_R")
	)
	(segment
		(start 131.36499 -25.390094)
		(end 130.291332 -25.390094)
		(width 0.13208)
		(layer "F.Cu")
		(net "SSD4_PWRDIS_R")
	)
	(via
		(at 140.23467 -28.469082)
		(size 0.508)
		(drill 0.254)
		(layers "F.Cu" "B.Cu")
		(net "SSD4_PWRDIS_R")
	)
	(via
		(at 130.291332 -25.390094)
		(size 0.508)
		(drill 0.254)
		(layers "F.Cu" "B.Cu")
		(net "SSD4_PWRDIS_R")
	)
	(via
		(at 152.675336 -232.040176)
		(size 0.508)
		(drill 0.254)
		(layers "F.Cu" "B.Cu")
		(net "SSD4_PWRDIS_R")
	)
	(via
		(at 345.059 -235.077)
		(size 0.508)
		(drill 0.254)
		(layers "F.Cu" "B.Cu")
		(net "SSD4_PWRDIS_R")
	)
	(segment
		(start 144.741646 -186.3217)
		(end 150.448772 -192.028826)
		(width 0.15494)
		(layer "In5.Cu")
		(net "SSD4_PWRDIS_R")
	)
	(segment
		(start 142.120366 -111.80318)
		(end 142.120366 -162.938714)
		(width 0.15494)
		(layer "In5.Cu")
		(net "SSD4_PWRDIS_R")
	)
	(segment
		(start 151.570182 -194.735958)
		(end 151.570182 -230.614982)
		(width 0.15494)
		(layer "In5.Cu")
		(net "SSD4_PWRDIS_R")
	)
	(segment
		(start 150.448772 -192.028826)
		(end 151.570182 -194.735958)
		(width 0.15494)
		(layer "In5.Cu")
		(net "SSD4_PWRDIS_R")
	)
	(segment
		(start 140.001244 -33.114996)
		(end 152.43048 -45.544232)
		(width 0.15494)
		(layer "In5.Cu")
		(net "SSD4_PWRDIS_R")
	)
	(segment
		(start 143.0274 -110.896146)
		(end 142.120366 -111.80318)
		(width 0.15494)
		(layer "In5.Cu")
		(net "SSD4_PWRDIS_R")
	)
	(segment
		(start 144.741646 -173.037246)
		(end 144.741646 -186.3217)
		(width 0.15494)
		(layer "In5.Cu")
		(net "SSD4_PWRDIS_R")
	)
	(segment
		(start 143.0274 -82.3468)
		(end 143.0274 -110.896146)
		(width 0.15494)
		(layer "In5.Cu")
		(net "SSD4_PWRDIS_R")
	)
	(segment
		(start 140.001244 -28.997148)
		(end 140.001244 -33.114996)
		(width 0.15494)
		(layer "In5.Cu")
		(net "SSD4_PWRDIS_R")
	)
	(segment
		(start 143.41475 -171.71035)
		(end 144.741646 -173.037246)
		(width 0.15494)
		(layer "In5.Cu")
		(net "SSD4_PWRDIS_R")
	)
	(segment
		(start 152.43048 -72.94372)
		(end 143.0274 -82.3468)
		(width 0.15494)
		(layer "In5.Cu")
		(net "SSD4_PWRDIS_R")
	)
	(segment
		(start 140.23467 -28.469082)
		(end 140.23467 -28.763722)
		(width 0.15494)
		(layer "In5.Cu")
		(net "SSD4_PWRDIS_R")
	)
	(segment
		(start 140.23467 -28.763722)
		(end 140.001244 -28.997148)
		(width 0.15494)
		(layer "In5.Cu")
		(net "SSD4_PWRDIS_R")
	)
	(segment
		(start 136.45896 -27.432)
		(end 136.941814 -27.914854)
		(width 0.15494)
		(layer "In5.Cu")
		(net "SSD4_PWRDIS_R")
	)
	(segment
		(start 142.120366 -162.938714)
		(end 143.41475 -164.233098)
		(width 0.15494)
		(layer "In5.Cu")
		(net "SSD4_PWRDIS_R")
	)
	(segment
		(start 143.41475 -164.233098)
		(end 143.41475 -171.71035)
		(width 0.15494)
		(layer "In5.Cu")
		(net "SSD4_PWRDIS_R")
	)
	(segment
		(start 139.680442 -27.914854)
		(end 140.23467 -28.469082)
		(width 0.15494)
		(layer "In5.Cu")
		(net "SSD4_PWRDIS_R")
	)
	(segment
		(start 136.941814 -27.914854)
		(end 139.680442 -27.914854)
		(width 0.15494)
		(layer "In5.Cu")
		(net "SSD4_PWRDIS_R")
	)
	(segment
		(start 134.934706 -27.432)
		(end 136.45896 -27.432)
		(width 0.15494)
		(layer "In5.Cu")
		(net "SSD4_PWRDIS_R")
	)
	(segment
		(start 152.43048 -45.544232)
		(end 152.43048 -72.94372)
		(width 0.15494)
		(layer "In5.Cu")
		(net "SSD4_PWRDIS_R")
	)
	(segment
		(start 152.675336 -231.720136)
		(end 152.675336 -232.040176)
		(width 0.15494)
		(layer "In5.Cu")
		(net "SSD4_PWRDIS_R")
	)
	(segment
		(start 151.570182 -230.614982)
		(end 152.675336 -231.720136)
		(width 0.15494)
		(layer "In5.Cu")
		(net "SSD4_PWRDIS_R")
	)
	(segment
		(start 132.8928 -25.390094)
		(end 134.934706 -27.432)
		(width 0.15494)
		(layer "In5.Cu")
		(net "SSD4_PWRDIS_R")
	)
	(segment
		(start 130.291332 -25.390094)
		(end 132.8928 -25.390094)
		(width 0.15494)
		(layer "In5.Cu")
		(net "SSD4_PWRDIS_R")
	)
	(segment
		(start 332.46187 -244.16766)
		(end 332.210664 -244.418866)
		(width 0.15494)
		(layer "In15.Cu")
		(net "SSD4_PWRDIS_R")
	)
	(segment
		(start 301.924974 -245.54561)
		(end 300.91888 -245.54561)
		(width 0.15494)
		(layer "In15.Cu")
		(net "SSD4_PWRDIS_R")
	)
	(segment
		(start 160.408874 -235.76788)
		(end 156.475684 -231.83469)
		(width 0.15494)
		(layer "In15.Cu")
		(net "SSD4_PWRDIS_R")
	)
	(segment
		(start 344.076782 -238.806228)
		(end 343.360756 -239.522254)
		(width 0.15494)
		(layer "In15.Cu")
		(net "SSD4_PWRDIS_R")
	)
	(segment
		(start 156.475684 -231.83469)
		(end 152.880822 -231.83469)
		(width 0.15494)
		(layer "In15.Cu")
		(net "SSD4_PWRDIS_R")
	)
	(segment
		(start 184.852564 -237.378494)
		(end 182.17769 -237.378494)
		(width 0.15494)
		(layer "In15.Cu")
		(net "SSD4_PWRDIS_R")
	)
	(segment
		(start 331.536802 -245.07825)
		(end 329.834748 -245.07825)
		(width 0.15494)
		(layer "In15.Cu")
		(net "SSD4_PWRDIS_R")
	)
	(segment
		(start 332.46187 -244.0686)
		(end 332.46187 -244.16766)
		(width 0.15494)
		(layer "In15.Cu")
		(net "SSD4_PWRDIS_R")
	)
	(segment
		(start 190.713106 -243.239036)
		(end 184.852564 -237.378494)
		(width 0.15494)
		(layer "In15.Cu")
		(net "SSD4_PWRDIS_R")
	)
	(segment
		(start 344.076782 -238.116618)
		(end 344.076782 -238.806228)
		(width 0.15494)
		(layer "In15.Cu")
		(net "SSD4_PWRDIS_R")
	)
	(segment
		(start 329.779884 -245.133114)
		(end 328.727816 -245.133114)
		(width 0.15494)
		(layer "In15.Cu")
		(net "SSD4_PWRDIS_R")
	)
	(segment
		(start 343.360756 -239.522254)
		(end 343.360756 -240.307622)
		(width 0.15494)
		(layer "In15.Cu")
		(net "SSD4_PWRDIS_R")
	)
	(segment
		(start 328.474578 -245.386352)
		(end 327.050146 -245.386352)
		(width 0.15494)
		(layer "In15.Cu")
		(net "SSD4_PWRDIS_R")
	)
	(segment
		(start 300.91888 -245.54561)
		(end 299.759878 -244.386608)
		(width 0.15494)
		(layer "In15.Cu")
		(net "SSD4_PWRDIS_R")
	)
	(segment
		(start 299.759878 -244.386608)
		(end 275.248116 -244.386608)
		(width 0.15494)
		(layer "In15.Cu")
		(net "SSD4_PWRDIS_R")
	)
	(segment
		(start 255.066546 -244.0686)
		(end 254.356616 -243.35867)
		(width 0.15494)
		(layer "In15.Cu")
		(net "SSD4_PWRDIS_R")
	)
	(segment
		(start 340.613238 -243.05514)
		(end 333.47533 -243.05514)
		(width 0.15494)
		(layer "In15.Cu")
		(net "SSD4_PWRDIS_R")
	)
	(segment
		(start 218.958668 -244.017038)
		(end 213.972394 -244.017038)
		(width 0.15494)
		(layer "In15.Cu")
		(net "SSD4_PWRDIS_R")
	)
	(segment
		(start 274.930108 -244.0686)
		(end 255.066546 -244.0686)
		(width 0.15494)
		(layer "In15.Cu")
		(net "SSD4_PWRDIS_R")
	)
	(segment
		(start 302.144176 -245.326408)
		(end 301.924974 -245.54561)
		(width 0.15494)
		(layer "In15.Cu")
		(net "SSD4_PWRDIS_R")
	)
	(segment
		(start 332.196186 -244.418866)
		(end 331.536802 -245.07825)
		(width 0.15494)
		(layer "In15.Cu")
		(net "SSD4_PWRDIS_R")
	)
	(segment
		(start 180.567076 -235.76788)
		(end 160.408874 -235.76788)
		(width 0.15494)
		(layer "In15.Cu")
		(net "SSD4_PWRDIS_R")
	)
	(segment
		(start 182.17769 -237.378494)
		(end 180.567076 -235.76788)
		(width 0.15494)
		(layer "In15.Cu")
		(net "SSD4_PWRDIS_R")
	)
	(segment
		(start 345.059 -235.077)
		(end 344.552016 -235.583984)
		(width 0.15494)
		(layer "In15.Cu")
		(net "SSD4_PWRDIS_R")
	)
	(segment
		(start 152.880822 -231.83469)
		(end 152.675336 -232.040176)
		(width 0.15494)
		(layer "In15.Cu")
		(net "SSD4_PWRDIS_R")
	)
	(segment
		(start 343.360756 -240.307622)
		(end 340.613238 -243.05514)
		(width 0.15494)
		(layer "In15.Cu")
		(net "SSD4_PWRDIS_R")
	)
	(segment
		(start 326.990202 -245.326408)
		(end 302.144176 -245.326408)
		(width 0.15494)
		(layer "In15.Cu")
		(net "SSD4_PWRDIS_R")
	)
	(segment
		(start 344.552016 -235.583984)
		(end 344.552016 -237.641384)
		(width 0.15494)
		(layer "In15.Cu")
		(net "SSD4_PWRDIS_R")
	)
	(segment
		(start 328.727816 -245.133114)
		(end 328.474578 -245.386352)
		(width 0.15494)
		(layer "In15.Cu")
		(net "SSD4_PWRDIS_R")
	)
	(segment
		(start 213.194392 -243.239036)
		(end 190.713106 -243.239036)
		(width 0.15494)
		(layer "In15.Cu")
		(net "SSD4_PWRDIS_R")
	)
	(segment
		(start 275.248116 -244.386608)
		(end 274.930108 -244.0686)
		(width 0.15494)
		(layer "In15.Cu")
		(net "SSD4_PWRDIS_R")
	)
	(segment
		(start 344.552016 -237.641384)
		(end 344.076782 -238.116618)
		(width 0.15494)
		(layer "In15.Cu")
		(net "SSD4_PWRDIS_R")
	)
	(segment
		(start 332.210664 -244.418866)
		(end 332.196186 -244.418866)
		(width 0.15494)
		(layer "In15.Cu")
		(net "SSD4_PWRDIS_R")
	)
	(segment
		(start 254.356616 -243.35867)
		(end 238.063786 -243.35867)
		(width 0.15494)
		(layer "In15.Cu")
		(net "SSD4_PWRDIS_R")
	)
	(segment
		(start 213.972394 -244.017038)
		(end 213.194392 -243.239036)
		(width 0.15494)
		(layer "In15.Cu")
		(net "SSD4_PWRDIS_R")
	)
	(segment
		(start 327.050146 -245.386352)
		(end 326.990202 -245.326408)
		(width 0.15494)
		(layer "In15.Cu")
		(net "SSD4_PWRDIS_R")
	)
	(segment
		(start 219.73667 -243.239036)
		(end 218.958668 -244.017038)
		(width 0.15494)
		(layer "In15.Cu")
		(net "SSD4_PWRDIS_R")
	)
	(segment
		(start 329.834748 -245.07825)
		(end 329.779884 -245.133114)
		(width 0.15494)
		(layer "In15.Cu")
		(net "SSD4_PWRDIS_R")
	)
	(segment
		(start 238.063786 -243.35867)
		(end 237.944152 -243.239036)
		(width 0.15494)
		(layer "In15.Cu")
		(net "SSD4_PWRDIS_R")
	)
	(segment
		(start 333.47533 -243.05514)
		(end 332.46187 -244.0686)
		(width 0.15494)
		(layer "In15.Cu")
		(net "SSD4_PWRDIS_R")
	)
	(segment
		(start 237.944152 -243.239036)
		(end 219.73667 -243.239036)
		(width 0.15494)
		(layer "In15.Cu")
		(net "SSD4_PWRDIS_R")
	)
	(segment
		(start 333.502 -209.03438)
		(end 333.502 -206.8068)
		(width 0.13208)
		(layer "F.Cu")
		(net "SSD8_PWRDIS")
	)
	(segment
		(start 333.502 -206.8068)
		(end 333.502 -205.63205)
		(width 0.13208)
		(layer "F.Cu")
		(net "SSD8_PWRDIS")
	)
	(segment
		(start 335.297526 -211.59089)
		(end 335.297526 -210.829906)
		(width 0.13208)
		(layer "F.Cu")
		(net "SSD8_PWRDIS")
	)
	(segment
		(start 335.693766 -211.98713)
		(end 335.297526 -211.59089)
		(width 0.13208)
		(layer "F.Cu")
		(net "SSD8_PWRDIS")
	)
	(segment
		(start 335.297526 -210.829906)
		(end 333.502 -209.03438)
		(width 0.13208)
		(layer "F.Cu")
		(net "SSD8_PWRDIS")
	)
	(via
		(at 333.502 -206.8068)
		(size 0.762)
		(drill 0.381)
		(layers "F.Cu" "B.Cu")
		(net "SSD8_PWRDIS")
	)
	(segment
		(start 230.412798 -151.316944)
		(end 230.347012 -151.251158)
		(width 0.1143)
		(layer "F.Cu")
		(net "CLK_100M_PEX1_REF_DP")
	)
	(segment
		(start 230.938832 -155.560776)
		(end 231.262682 -155.236926)
		(width 0.1143)
		(layer "F.Cu")
		(net "CLK_100M_PEX1_REF_DP")
	)
	(segment
		(start 230.347012 -151.251158)
		(end 230.347012 -151.015446)
		(width 0.1143)
		(layer "F.Cu")
		(net "CLK_100M_PEX1_REF_DP")
	)
	(segment
		(start 231.262682 -155.236926)
		(end 231.262682 -153.57729)
		(width 0.1143)
		(layer "F.Cu")
		(net "CLK_100M_PEX1_REF_DP")
	)
	(segment
		(start 230.412798 -152.727406)
		(end 230.412798 -151.316944)
		(width 0.1143)
		(layer "F.Cu")
		(net "CLK_100M_PEX1_REF_DP")
	)
	(segment
		(start 231.262682 -153.57729)
		(end 230.412798 -152.727406)
		(width 0.1143)
		(layer "F.Cu")
		(net "CLK_100M_PEX1_REF_DP")
	)
	(segment
		(start 216.200736 -216.270586)
		(end 216.835736 -216.270586)
		(width 0.13208)
		(layer "F.Cu")
		(net "SMB_NIC6_R_SCL")
	)
	(segment
		(start 210.83905 -197.231)
		(end 210.83905 -196.742304)
		(width 0.13208)
		(layer "F.Cu")
		(net "SMB_NIC6_R_SCL")
	)
	(segment
		(start 210.692746 -196.596)
		(end 209.423 -196.596)
		(width 0.13208)
		(layer "F.Cu")
		(net "SMB_NIC6_R_SCL")
	)
	(segment
		(start 210.83905 -196.742304)
		(end 210.692746 -196.596)
		(width 0.13208)
		(layer "F.Cu")
		(net "SMB_NIC6_R_SCL")
	)
	(segment
		(start 212.522054 -197.79488)
		(end 211.68868 -197.79488)
		(width 0.13208)
		(layer "F.Cu")
		(net "SMB_NIC6_R_SCL")
	)
	(segment
		(start 211.68868 -197.79488)
		(end 211.1248 -197.231)
		(width 0.13208)
		(layer "F.Cu")
		(net "SMB_NIC6_R_SCL")
	)
	(segment
		(start 211.1248 -197.231)
		(end 210.83905 -197.231)
		(width 0.13208)
		(layer "F.Cu")
		(net "SMB_NIC6_R_SCL")
	)
	(via
		(at 216.200736 -216.270586)
		(size 0.508)
		(drill 0.254)
		(layers "F.Cu" "B.Cu")
		(net "SMB_NIC6_R_SCL")
	)
	(via
		(at 209.423 -196.596)
		(size 0.508)
		(drill 0.254)
		(layers "F.Cu" "B.Cu")
		(net "SMB_NIC6_R_SCL")
	)
	(segment
		(start 212.09 -197.37705)
		(end 210.20405 -197.37705)
		(width 0.13208)
		(layer "B.Cu")
		(net "SMB_NIC6_R_SCL")
	)
	(segment
		(start 210.20405 -197.37705)
		(end 209.423 -196.596)
		(width 0.13208)
		(layer "B.Cu")
		(net "SMB_NIC6_R_SCL")
	)
	(segment
		(start 210.874102 -199.263)
		(end 209.270854 -199.263)
		(width 0.15494)
		(layer "In7.Cu")
		(net "SMB_NIC6_R_SCL")
	)
	(segment
		(start 211.025232 -199.41413)
		(end 210.874102 -199.263)
		(width 0.15494)
		(layer "In7.Cu")
		(net "SMB_NIC6_R_SCL")
	)
	(segment
		(start 211.32292 -199.69734)
		(end 211.03971 -199.41413)
		(width 0.15494)
		(layer "In7.Cu")
		(net "SMB_NIC6_R_SCL")
	)
	(segment
		(start 213.233 -201.621898)
		(end 211.32292 -199.711818)
		(width 0.15494)
		(layer "In7.Cu")
		(net "SMB_NIC6_R_SCL")
	)
	(segment
		(start 215.707468 -215.777318)
		(end 214.761064 -215.777318)
		(width 0.15494)
		(layer "In7.Cu")
		(net "SMB_NIC6_R_SCL")
	)
	(segment
		(start 211.32292 -199.711818)
		(end 211.32292 -199.69734)
		(width 0.15494)
		(layer "In7.Cu")
		(net "SMB_NIC6_R_SCL")
	)
	(segment
		(start 213.878414 -214.894668)
		(end 213.878414 -207.37576)
		(width 0.15494)
		(layer "In7.Cu")
		(net "SMB_NIC6_R_SCL")
	)
	(segment
		(start 213.233 -206.730346)
		(end 213.233 -201.621898)
		(width 0.15494)
		(layer "In7.Cu")
		(net "SMB_NIC6_R_SCL")
	)
	(segment
		(start 216.200736 -216.270586)
		(end 215.707468 -215.777318)
		(width 0.15494)
		(layer "In7.Cu")
		(net "SMB_NIC6_R_SCL")
	)
	(segment
		(start 211.03971 -199.41413)
		(end 211.025232 -199.41413)
		(width 0.15494)
		(layer "In7.Cu")
		(net "SMB_NIC6_R_SCL")
	)
	(segment
		(start 214.761064 -215.777318)
		(end 213.878414 -214.894668)
		(width 0.15494)
		(layer "In7.Cu")
		(net "SMB_NIC6_R_SCL")
	)
	(segment
		(start 209.22234 -199.23887)
		(end 208.93913 -198.95566)
		(width 0.15494)
		(layer "In7.Cu")
		(net "SMB_NIC6_R_SCL")
	)
	(segment
		(start 209.270854 -199.263)
		(end 209.246724 -199.23887)
		(width 0.15494)
		(layer "In7.Cu")
		(net "SMB_NIC6_R_SCL")
	)
	(segment
		(start 213.878414 -207.37576)
		(end 213.233 -206.730346)
		(width 0.15494)
		(layer "In7.Cu")
		(net "SMB_NIC6_R_SCL")
	)
	(segment
		(start 208.93913 -197.07987)
		(end 209.423 -196.596)
		(width 0.15494)
		(layer "In7.Cu")
		(net "SMB_NIC6_R_SCL")
	)
	(segment
		(start 208.93913 -198.95566)
		(end 208.93913 -197.07987)
		(width 0.15494)
		(layer "In7.Cu")
		(net "SMB_NIC6_R_SCL")
	)
	(segment
		(start 209.246724 -199.23887)
		(end 209.22234 -199.23887)
		(width 0.15494)
		(layer "In7.Cu")
		(net "SMB_NIC6_R_SCL")
	)
	(segment
		(start 147.030186 -380.430532)
		(end 147.04822 -380.412498)
		(width 0.13208)
		(layer "F.Cu")
		(net "GPU_3V3IO_RSVD0_FFU_R")
	)
	(segment
		(start 147.04822 -380.412498)
		(end 148.680678 -380.412498)
		(width 0.13208)
		(layer "F.Cu")
		(net "GPU_3V3IO_RSVD0_FFU_R")
	)
	(via
		(at 147.030186 -380.430532)
		(size 0.508)
		(drill 0.254)
		(layers "F.Cu" "B.Cu")
		(net "GPU_3V3IO_RSVD0_FFU_R")
	)
	(segment
		(start 147.030186 -377.989084)
		(end 136.26973 -367.228628)
		(width 0.15494)
		(layer "In9.Cu")
		(net "GPU_3V3IO_RSVD0_FFU_R")
	)
	(segment
		(start 124.271532 -367.228628)
		(end 122.510042 -368.990118)
		(width 0.15494)
		(layer "In9.Cu")
		(net "GPU_3V3IO_RSVD0_FFU_R")
	)
	(segment
		(start 147.030186 -380.430532)
		(end 147.030186 -377.989084)
		(width 0.15494)
		(layer "In9.Cu")
		(net "GPU_3V3IO_RSVD0_FFU_R")
	)
	(segment
		(start 136.26973 -367.228628)
		(end 124.271532 -367.228628)
		(width 0.15494)
		(layer "In9.Cu")
		(net "GPU_3V3IO_RSVD0_FFU_R")
	)
	(segment
		(start 192.234566 -28.550108)
		(end 192.76441 -29.079952)
		(width 0.13208)
		(layer "F.Cu")
		(net "SSD6_PWRDIS_R")
	)
	(segment
		(start 183.364886 -25.390094)
		(end 182.291228 -25.390094)
		(width 0.13208)
		(layer "F.Cu")
		(net "SSD6_PWRDIS_R")
	)
	(segment
		(start 192.234566 -28.469082)
		(end 192.234566 -28.550108)
		(width 0.13208)
		(layer "F.Cu")
		(net "SSD6_PWRDIS_R")
	)
	(via
		(at 192.234566 -28.469082)
		(size 0.508)
		(drill 0.254)
		(layers "F.Cu" "B.Cu")
		(net "SSD6_PWRDIS_R")
	)
	(via
		(at 345.059 -236.347)
		(size 0.508)
		(drill 0.254)
		(layers "F.Cu" "B.Cu")
		(net "SSD6_PWRDIS_R")
	)
	(via
		(at 186.005724 -239.441228)
		(size 0.508)
		(drill 0.254)
		(layers "F.Cu" "B.Cu")
		(net "SSD6_PWRDIS_R")
	)
	(via
		(at 182.291228 -25.390094)
		(size 0.508)
		(drill 0.254)
		(layers "F.Cu" "B.Cu")
		(net "SSD6_PWRDIS_R")
	)
	(segment
		(start 345.60129 -234.42676)
		(end 345.60129 -235.80471)
		(width 0.13208)
		(layer "B.Cu")
		(net "SSD6_PWRDIS_R")
	)
	(segment
		(start 345.60129 -235.80471)
		(end 345.059 -236.347)
		(width 0.13208)
		(layer "B.Cu")
		(net "SSD6_PWRDIS_R")
	)
	(segment
		(start 346.075 -233.95305)
		(end 345.60129 -234.42676)
		(width 0.13208)
		(layer "B.Cu")
		(net "SSD6_PWRDIS_R")
	)
	(segment
		(start 192.076578 -28.954476)
		(end 192.076578 -33.375854)
		(width 0.15494)
		(layer "In5.Cu")
		(net "SSD6_PWRDIS_R")
	)
	(segment
		(start 195.01866 -76.50353)
		(end 189.09411 -82.42808)
		(width 0.15494)
		(layer "In5.Cu")
		(net "SSD6_PWRDIS_R")
	)
	(segment
		(start 192.234566 -28.796488)
		(end 192.076578 -28.954476)
		(width 0.15494)
		(layer "In5.Cu")
		(net "SSD6_PWRDIS_R")
	)
	(segment
		(start 178.3334 -165.049962)
		(end 179.750974 -166.467536)
		(width 0.15494)
		(layer "In5.Cu")
		(net "SSD6_PWRDIS_R")
	)
	(segment
		(start 184.892696 -25.390094)
		(end 186.934602 -27.432)
		(width 0.15494)
		(layer "In5.Cu")
		(net "SSD6_PWRDIS_R")
	)
	(segment
		(start 177.483516 -174.812198)
		(end 177.483516 -180.379116)
		(width 0.15494)
		(layer "In5.Cu")
		(net "SSD6_PWRDIS_R")
	)
	(segment
		(start 180.724556 -198.194422)
		(end 182.18658 -199.656446)
		(width 0.15494)
		(layer "In5.Cu")
		(net "SSD6_PWRDIS_R")
	)
	(segment
		(start 186.934602 -27.432)
		(end 188.458856 -27.432)
		(width 0.15494)
		(layer "In5.Cu")
		(net "SSD6_PWRDIS_R")
	)
	(segment
		(start 185.676794 -228.348794)
		(end 186.005724 -228.677724)
		(width 0.15494)
		(layer "In5.Cu")
		(net "SSD6_PWRDIS_R")
	)
	(segment
		(start 204.339444 -45.63872)
		(end 204.339444 -63.561468)
		(width 0.15494)
		(layer "In5.Cu")
		(net "SSD6_PWRDIS_R")
	)
	(segment
		(start 182.291228 -25.390094)
		(end 184.892696 -25.390094)
		(width 0.15494)
		(layer "In5.Cu")
		(net "SSD6_PWRDIS_R")
	)
	(segment
		(start 192.234566 -28.469082)
		(end 192.234566 -28.796488)
		(width 0.15494)
		(layer "In5.Cu")
		(net "SSD6_PWRDIS_R")
	)
	(segment
		(start 182.18658 -199.656446)
		(end 182.18658 -212.870542)
		(width 0.15494)
		(layer "In5.Cu")
		(net "SSD6_PWRDIS_R")
	)
	(segment
		(start 178.3334 -161.564828)
		(end 178.3334 -165.049962)
		(width 0.15494)
		(layer "In5.Cu")
		(net "SSD6_PWRDIS_R")
	)
	(segment
		(start 195.01866 -72.882252)
		(end 195.01866 -76.50353)
		(width 0.15494)
		(layer "In5.Cu")
		(net "SSD6_PWRDIS_R")
	)
	(segment
		(start 204.339444 -63.561468)
		(end 195.01866 -72.882252)
		(width 0.15494)
		(layer "In5.Cu")
		(net "SSD6_PWRDIS_R")
	)
	(segment
		(start 180.724556 -183.620156)
		(end 180.724556 -198.194422)
		(width 0.15494)
		(layer "In5.Cu")
		(net "SSD6_PWRDIS_R")
	)
	(segment
		(start 188.94171 -27.914854)
		(end 191.680338 -27.914854)
		(width 0.15494)
		(layer "In5.Cu")
		(net "SSD6_PWRDIS_R")
	)
	(segment
		(start 182.18658 -212.870542)
		(end 185.676794 -221.296992)
		(width 0.15494)
		(layer "In5.Cu")
		(net "SSD6_PWRDIS_R")
	)
	(segment
		(start 186.005724 -228.677724)
		(end 186.005724 -239.441228)
		(width 0.15494)
		(layer "In5.Cu")
		(net "SSD6_PWRDIS_R")
	)
	(segment
		(start 177.426112 -160.65754)
		(end 178.3334 -161.564828)
		(width 0.15494)
		(layer "In5.Cu")
		(net "SSD6_PWRDIS_R")
	)
	(segment
		(start 184.22112 -82.42808)
		(end 177.426112 -89.223088)
		(width 0.15494)
		(layer "In5.Cu")
		(net "SSD6_PWRDIS_R")
	)
	(segment
		(start 179.750974 -172.54474)
		(end 177.483516 -174.812198)
		(width 0.15494)
		(layer "In5.Cu")
		(net "SSD6_PWRDIS_R")
	)
	(segment
		(start 185.676794 -221.296992)
		(end 185.676794 -228.348794)
		(width 0.15494)
		(layer "In5.Cu")
		(net "SSD6_PWRDIS_R")
	)
	(segment
		(start 191.680338 -27.914854)
		(end 192.234566 -28.469082)
		(width 0.15494)
		(layer "In5.Cu")
		(net "SSD6_PWRDIS_R")
	)
	(segment
		(start 188.458856 -27.432)
		(end 188.94171 -27.914854)
		(width 0.15494)
		(layer "In5.Cu")
		(net "SSD6_PWRDIS_R")
	)
	(segment
		(start 179.750974 -166.467536)
		(end 179.750974 -172.54474)
		(width 0.15494)
		(layer "In5.Cu")
		(net "SSD6_PWRDIS_R")
	)
	(segment
		(start 177.426112 -89.223088)
		(end 177.426112 -160.65754)
		(width 0.15494)
		(layer "In5.Cu")
		(net "SSD6_PWRDIS_R")
	)
	(segment
		(start 189.09411 -82.42808)
		(end 184.22112 -82.42808)
		(width 0.15494)
		(layer "In5.Cu")
		(net "SSD6_PWRDIS_R")
	)
	(segment
		(start 192.076578 -33.375854)
		(end 204.339444 -45.63872)
		(width 0.15494)
		(layer "In5.Cu")
		(net "SSD6_PWRDIS_R")
	)
	(segment
		(start 177.483516 -180.379116)
		(end 180.724556 -183.620156)
		(width 0.15494)
		(layer "In5.Cu")
		(net "SSD6_PWRDIS_R")
	)
	(segment
		(start 190.536576 -243.622576)
		(end 213.071202 -243.622576)
		(width 0.15494)
		(layer "In15.Cu")
		(net "SSD6_PWRDIS_R")
	)
	(segment
		(start 186.355228 -239.441228)
		(end 190.536576 -243.622576)
		(width 0.15494)
		(layer "In15.Cu")
		(net "SSD6_PWRDIS_R")
	)
	(segment
		(start 254.119634 -243.71681)
		(end 254.872998 -244.470174)
		(width 0.15494)
		(layer "In15.Cu")
		(net "SSD6_PWRDIS_R")
	)
	(segment
		(start 220.559376 -243.597176)
		(end 237.795562 -243.597176)
		(width 0.15494)
		(layer "In15.Cu")
		(net "SSD6_PWRDIS_R")
	)
	(segment
		(start 329.983338 -245.43639)
		(end 331.685392 -245.43639)
		(width 0.15494)
		(layer "In15.Cu")
		(net "SSD6_PWRDIS_R")
	)
	(segment
		(start 345.059 -237.64113)
		(end 345.059 -236.347)
		(width 0.15494)
		(layer "In15.Cu")
		(net "SSD6_PWRDIS_R")
	)
	(segment
		(start 213.823804 -244.375178)
		(end 219.107258 -244.375178)
		(width 0.15494)
		(layer "In15.Cu")
		(net "SSD6_PWRDIS_R")
	)
	(segment
		(start 344.434922 -239.827562)
		(end 344.434922 -238.265208)
		(width 0.15494)
		(layer "In15.Cu")
		(net "SSD6_PWRDIS_R")
	)
	(segment
		(start 237.915196 -243.71681)
		(end 254.119634 -243.71681)
		(width 0.15494)
		(layer "In15.Cu")
		(net "SSD6_PWRDIS_R")
	)
	(segment
		(start 303.769522 -245.848886)
		(end 328.518774 -245.848886)
		(width 0.15494)
		(layer "In15.Cu")
		(net "SSD6_PWRDIS_R")
	)
	(segment
		(start 329.928474 -245.491254)
		(end 329.983338 -245.43639)
		(width 0.15494)
		(layer "In15.Cu")
		(net "SSD6_PWRDIS_R")
	)
	(segment
		(start 213.071202 -243.622576)
		(end 213.823804 -244.375178)
		(width 0.15494)
		(layer "In15.Cu")
		(net "SSD6_PWRDIS_R")
	)
	(segment
		(start 254.872998 -244.470174)
		(end 274.79752 -244.470174)
		(width 0.15494)
		(layer "In15.Cu")
		(net "SSD6_PWRDIS_R")
	)
	(segment
		(start 302.694086 -246.294148)
		(end 303.769522 -245.848886)
		(width 0.15494)
		(layer "In15.Cu")
		(net "SSD6_PWRDIS_R")
	)
	(segment
		(start 275.080476 -244.75313)
		(end 299.61967 -244.75313)
		(width 0.15494)
		(layer "In15.Cu")
		(net "SSD6_PWRDIS_R")
	)
	(segment
		(start 340.525354 -243.73713)
		(end 344.434922 -239.827562)
		(width 0.15494)
		(layer "In15.Cu")
		(net "SSD6_PWRDIS_R")
	)
	(segment
		(start 301.160688 -246.294148)
		(end 302.694086 -246.294148)
		(width 0.15494)
		(layer "In15.Cu")
		(net "SSD6_PWRDIS_R")
	)
	(segment
		(start 336.48904 -244.4369)
		(end 337.55457 -244.4369)
		(width 0.15494)
		(layer "In15.Cu")
		(net "SSD6_PWRDIS_R")
	)
	(segment
		(start 220.533976 -243.622576)
		(end 220.559376 -243.597176)
		(width 0.15494)
		(layer "In15.Cu")
		(net "SSD6_PWRDIS_R")
	)
	(segment
		(start 328.518774 -245.848886)
		(end 328.876406 -245.491254)
		(width 0.15494)
		(layer "In15.Cu")
		(net "SSD6_PWRDIS_R")
	)
	(segment
		(start 331.685392 -245.43639)
		(end 332.113636 -245.008146)
		(width 0.15494)
		(layer "In15.Cu")
		(net "SSD6_PWRDIS_R")
	)
	(segment
		(start 219.85986 -243.622576)
		(end 220.533976 -243.622576)
		(width 0.15494)
		(layer "In15.Cu")
		(net "SSD6_PWRDIS_R")
	)
	(segment
		(start 335.237836 -243.800376)
		(end 335.852516 -243.800376)
		(width 0.15494)
		(layer "In15.Cu")
		(net "SSD6_PWRDIS_R")
	)
	(segment
		(start 237.795562 -243.597176)
		(end 237.915196 -243.71681)
		(width 0.15494)
		(layer "In15.Cu")
		(net "SSD6_PWRDIS_R")
	)
	(segment
		(start 299.61967 -244.75313)
		(end 301.160688 -246.294148)
		(width 0.15494)
		(layer "In15.Cu")
		(net "SSD6_PWRDIS_R")
	)
	(segment
		(start 332.113636 -245.008146)
		(end 334.030066 -245.008146)
		(width 0.15494)
		(layer "In15.Cu")
		(net "SSD6_PWRDIS_R")
	)
	(segment
		(start 338.25434 -243.73713)
		(end 340.525354 -243.73713)
		(width 0.15494)
		(layer "In15.Cu")
		(net "SSD6_PWRDIS_R")
	)
	(segment
		(start 337.55457 -244.4369)
		(end 338.25434 -243.73713)
		(width 0.15494)
		(layer "In15.Cu")
		(net "SSD6_PWRDIS_R")
	)
	(segment
		(start 334.030066 -245.008146)
		(end 335.237836 -243.800376)
		(width 0.15494)
		(layer "In15.Cu")
		(net "SSD6_PWRDIS_R")
	)
	(segment
		(start 186.005724 -239.441228)
		(end 186.355228 -239.441228)
		(width 0.15494)
		(layer "In15.Cu")
		(net "SSD6_PWRDIS_R")
	)
	(segment
		(start 219.107258 -244.375178)
		(end 219.85986 -243.622576)
		(width 0.15494)
		(layer "In15.Cu")
		(net "SSD6_PWRDIS_R")
	)
	(segment
		(start 328.876406 -245.491254)
		(end 329.928474 -245.491254)
		(width 0.15494)
		(layer "In15.Cu")
		(net "SSD6_PWRDIS_R")
	)
	(segment
		(start 344.434922 -238.265208)
		(end 345.059 -237.64113)
		(width 0.15494)
		(layer "In15.Cu")
		(net "SSD6_PWRDIS_R")
	)
	(segment
		(start 335.852516 -243.800376)
		(end 336.48904 -244.4369)
		(width 0.15494)
		(layer "In15.Cu")
		(net "SSD6_PWRDIS_R")
	)
	(segment
		(start 274.79752 -244.470174)
		(end 275.080476 -244.75313)
		(width 0.15494)
		(layer "In15.Cu")
		(net "SSD6_PWRDIS_R")
	)
	(segment
		(start 375.508774 -36.232592)
		(end 374.963182 -35.687)
		(width 0.13208)
		(layer "F.Cu")
		(net "PWRGD_P3V3_SSD13_R")
	)
	(segment
		(start 372.371874 -35.687)
		(end 372.182136 -35.876738)
		(width 0.13208)
		(layer "F.Cu")
		(net "PWRGD_P3V3_SSD13_R")
	)
	(segment
		(start 374.963182 -35.687)
		(end 372.371874 -35.687)
		(width 0.13208)
		(layer "F.Cu")
		(net "PWRGD_P3V3_SSD13_R")
	)
	(segment
		(start 375.895362 -36.232592)
		(end 375.508774 -36.232592)
		(width 0.13208)
		(layer "F.Cu")
		(net "PWRGD_P3V3_SSD13_R")
	)
	(segment
		(start 341.293958 -213.587076)
		(end 340.894162 -213.18728)
		(width 0.13208)
		(layer "F.Cu")
		(net "PWRGD_P3V3_SSD13_R")
	)
	(segment
		(start 371.470936 -35.876738)
		(end 370.727986 -35.876738)
		(width 0.13208)
		(layer "F.Cu")
		(net "PWRGD_P3V3_SSD13_R")
	)
	(segment
		(start 382.911096 -61.386974)
		(end 382.911096 -62.051438)
		(width 0.13208)
		(layer "F.Cu")
		(net "PWRGD_P3V3_SSD13_R")
	)
	(segment
		(start 372.182136 -35.876738)
		(end 371.470936 -35.876738)
		(width 0.13208)
		(layer "F.Cu")
		(net "PWRGD_P3V3_SSD13_R")
	)
	(via
		(at 371.470936 -35.876738)
		(size 0.508)
		(drill 0.254)
		(layers "F.Cu" "B.Cu")
		(net "PWRGD_P3V3_SSD13_R")
	)
	(via
		(at 340.894162 -213.18728)
		(size 0.4572)
		(drill 0.254)
		(layers "F.Cu" "B.Cu")
		(net "PWRGD_P3V3_SSD13_R")
	)
	(via
		(at 372.422674 -107.612434)
		(size 0.508)
		(drill 0.254)
		(layers "F.Cu" "B.Cu")
		(net "PWRGD_P3V3_SSD13_R")
	)
	(via
		(at 382.911096 -62.051438)
		(size 0.508)
		(drill 0.254)
		(layers "F.Cu" "B.Cu")
		(net "PWRGD_P3V3_SSD13_R")
	)
	(via
		(at 353.866958 -107.900216)
		(size 0.508)
		(drill 0.254)
		(layers "F.Cu" "B.Cu")
		(net "PWRGD_P3V3_SSD13_R")
	)
	(segment
		(start 384.19151 -61.28004)
		(end 383.420112 -62.051438)
		(width 0.15494)
		(layer "In5.Cu")
		(net "PWRGD_P3V3_SSD13_R")
	)
	(segment
		(start 383.420112 -62.051438)
		(end 382.911096 -62.051438)
		(width 0.15494)
		(layer "In5.Cu")
		(net "PWRGD_P3V3_SSD13_R")
	)
	(segment
		(start 379.186948 -92.825316)
		(end 372.422674 -99.58959)
		(width 0.15494)
		(layer "In5.Cu")
		(net "PWRGD_P3V3_SSD13_R")
	)
	(segment
		(start 378.615956 -76.906374)
		(end 379.186948 -77.477366)
		(width 0.15494)
		(layer "In5.Cu")
		(net "PWRGD_P3V3_SSD13_R")
	)
	(segment
		(start 378.615956 -68.408296)
		(end 378.615956 -76.906374)
		(width 0.15494)
		(layer "In5.Cu")
		(net "PWRGD_P3V3_SSD13_R")
	)
	(segment
		(start 371.470936 -35.876738)
		(end 374.162574 -35.876738)
		(width 0.15494)
		(layer "In5.Cu")
		(net "PWRGD_P3V3_SSD13_R")
	)
	(segment
		(start 374.162574 -35.876738)
		(end 384.19151 -45.905674)
		(width 0.15494)
		(layer "In5.Cu")
		(net "PWRGD_P3V3_SSD13_R")
	)
	(segment
		(start 372.422674 -99.58959)
		(end 372.422674 -107.612434)
		(width 0.15494)
		(layer "In5.Cu")
		(net "PWRGD_P3V3_SSD13_R")
	)
	(segment
		(start 384.19151 -45.905674)
		(end 384.19151 -61.28004)
		(width 0.15494)
		(layer "In5.Cu")
		(net "PWRGD_P3V3_SSD13_R")
	)
	(segment
		(start 382.911096 -64.113156)
		(end 378.615956 -68.408296)
		(width 0.15494)
		(layer "In5.Cu")
		(net "PWRGD_P3V3_SSD13_R")
	)
	(segment
		(start 382.911096 -62.051438)
		(end 382.911096 -64.113156)
		(width 0.15494)
		(layer "In5.Cu")
		(net "PWRGD_P3V3_SSD13_R")
	)
	(segment
		(start 379.186948 -77.477366)
		(end 379.186948 -92.825316)
		(width 0.15494)
		(layer "In5.Cu")
		(net "PWRGD_P3V3_SSD13_R")
	)
	(segment
		(start 352.86696 -109.788452)
		(end 352.86696 -119.310912)
		(width 0.15494)
		(layer "In7.Cu")
		(net "PWRGD_P3V3_SSD13_R")
	)
	(segment
		(start 341.291672 -212.78977)
		(end 340.894162 -213.18728)
		(width 0.0889)
		(layer "In7.Cu")
		(net "PWRGD_P3V3_SSD13_R")
	)
	(segment
		(start 347.564456 -185.034174)
		(end 343.155016 -189.443614)
		(width 0.15494)
		(layer "In7.Cu")
		(net "PWRGD_P3V3_SSD13_R")
	)
	(segment
		(start 344.14587 -205.288134)
		(end 343.654126 -205.779878)
		(width 0.15494)
		(layer "In7.Cu")
		(net "PWRGD_P3V3_SSD13_R")
	)
	(segment
		(start 353.866958 -107.900216)
		(end 353.495356 -108.271818)
		(width 0.15494)
		(layer "In7.Cu")
		(net "PWRGD_P3V3_SSD13_R")
	)
	(segment
		(start 343.654126 -206.665322)
		(end 341.291672 -209.027776)
		(width 0.15494)
		(layer "In7.Cu")
		(net "PWRGD_P3V3_SSD13_R")
	)
	(segment
		(start 341.291672 -209.027776)
		(end 341.291672 -211.0486)
		(width 0.15494)
		(layer "In7.Cu")
		(net "PWRGD_P3V3_SSD13_R")
	)
	(segment
		(start 353.495356 -108.271818)
		(end 352.86696 -109.788452)
		(width 0.15494)
		(layer "In7.Cu")
		(net "PWRGD_P3V3_SSD13_R")
	)
	(segment
		(start 345.361006 -167.15486)
		(end 347.564456 -169.35831)
		(width 0.15494)
		(layer "In7.Cu")
		(net "PWRGD_P3V3_SSD13_R")
	)
	(segment
		(start 341.291672 -211.0486)
		(end 341.291672 -212.78977)
		(width 0.0889)
		(layer "In7.Cu")
		(net "PWRGD_P3V3_SSD13_R")
	)
	(segment
		(start 343.155016 -189.443614)
		(end 343.155016 -196.626988)
		(width 0.15494)
		(layer "In7.Cu")
		(net "PWRGD_P3V3_SSD13_R")
	)
	(segment
		(start 352.86696 -119.310912)
		(end 345.361006 -126.816866)
		(width 0.15494)
		(layer "In7.Cu")
		(net "PWRGD_P3V3_SSD13_R")
	)
	(segment
		(start 344.14587 -199.018906)
		(end 344.14587 -205.288134)
		(width 0.15494)
		(layer "In7.Cu")
		(net "PWRGD_P3V3_SSD13_R")
	)
	(segment
		(start 343.155016 -196.626988)
		(end 344.14587 -199.018906)
		(width 0.15494)
		(layer "In7.Cu")
		(net "PWRGD_P3V3_SSD13_R")
	)
	(segment
		(start 343.654126 -205.779878)
		(end 343.654126 -206.665322)
		(width 0.15494)
		(layer "In7.Cu")
		(net "PWRGD_P3V3_SSD13_R")
	)
	(segment
		(start 345.361006 -126.816866)
		(end 345.361006 -167.15486)
		(width 0.15494)
		(layer "In7.Cu")
		(net "PWRGD_P3V3_SSD13_R")
	)
	(segment
		(start 347.564456 -169.35831)
		(end 347.564456 -185.034174)
		(width 0.15494)
		(layer "In7.Cu")
		(net "PWRGD_P3V3_SSD13_R")
	)
	(segment
		(start 362.03382 -107.612434)
		(end 372.422674 -107.612434)
		(width 0.15494)
		(layer "In13.Cu")
		(net "PWRGD_P3V3_SSD13_R")
	)
	(segment
		(start 360.197654 -109.4486)
		(end 362.03382 -107.612434)
		(width 0.15494)
		(layer "In13.Cu")
		(net "PWRGD_P3V3_SSD13_R")
	)
	(segment
		(start 353.866958 -107.900216)
		(end 355.415342 -109.4486)
		(width 0.15494)
		(layer "In13.Cu")
		(net "PWRGD_P3V3_SSD13_R")
	)
	(segment
		(start 355.415342 -109.4486)
		(end 360.197654 -109.4486)
		(width 0.15494)
		(layer "In13.Cu")
		(net "PWRGD_P3V3_SSD13_R")
	)
	(segment
		(start 238.37138 -92.665042)
		(end 238.418878 -92.617544)
		(width 0.13208)
		(layer "F.Cu")
		(net "PEX_USB_HUB_XOUT")
	)
	(segment
		(start 237.78845 -92.665042)
		(end 236.826298 -92.266516)
		(width 0.13208)
		(layer "F.Cu")
		(net "PEX_USB_HUB_XOUT")
	)
	(segment
		(start 236.826298 -92.266516)
		(end 236.433614 -92.266516)
		(width 0.13208)
		(layer "F.Cu")
		(net "PEX_USB_HUB_XOUT")
	)
	(segment
		(start 237.78845 -92.665042)
		(end 238.37138 -92.665042)
		(width 0.13208)
		(layer "F.Cu")
		(net "PEX_USB_HUB_XOUT")
	)
	(via
		(at 237.78845 -92.665042)
		(size 0.508)
		(drill 0.254)
		(layers "F.Cu" "B.Cu")
		(net "PEX_USB_HUB_XOUT")
	)
	(segment
		(start 229.387654 -155.216606)
		(end 229.387654 -154.8257)
		(width 0.1143)
		(layer "F.Cu")
		(net "CLK_100M_PEX0_REF_DN")
	)
	(segment
		(start 229.387654 -154.8257)
		(end 229.7811 -154.432254)
		(width 0.1143)
		(layer "F.Cu")
		(net "CLK_100M_PEX0_REF_DN")
	)
	(segment
		(start 229.846886 -151.229314)
		(end 229.846886 -151.015446)
		(width 0.1143)
		(layer "F.Cu")
		(net "CLK_100M_PEX0_REF_DN")
	)
	(segment
		(start 229.711504 -155.540456)
		(end 229.387654 -155.216606)
		(width 0.1143)
		(layer "F.Cu")
		(net "CLK_100M_PEX0_REF_DN")
	)
	(segment
		(start 229.7811 -154.432254)
		(end 229.7811 -151.2951)
		(width 0.1143)
		(layer "F.Cu")
		(net "CLK_100M_PEX0_REF_DN")
	)
	(segment
		(start 229.7811 -151.2951)
		(end 229.846886 -151.229314)
		(width 0.1143)
		(layer "F.Cu")
		(net "CLK_100M_PEX0_REF_DN")
	)
	(segment
		(start 225.867722 -219.10421)
		(end 225.467926 -219.504006)
		(width 0.13208)
		(layer "F.Cu")
		(net "SMB_NIC7_SCL")
	)
	(via
		(at 213.24062 -218.289632)
		(size 0.508)
		(drill 0.254)
		(layers "F.Cu" "B.Cu")
		(net "SMB_NIC7_SCL")
	)
	(via
		(at 221.007432 -218.996514)
		(size 0.6604)
		(drill 0.3302)
		(layers "F.Cu" "B.Cu")
		(net "SMB_NIC7_SCL")
	)
	(via
		(at 225.467926 -219.504006)
		(size 0.4572)
		(drill 0.254)
		(layers "F.Cu" "B.Cu")
		(net "SMB_NIC7_SCL")
	)
	(via
		(at 218.976956 -218.307666)
		(size 0.508)
		(drill 0.254)
		(layers "F.Cu" "B.Cu")
		(net "SMB_NIC7_SCL")
	)
	(segment
		(start 217.830654 -218.107768)
		(end 217.635836 -218.302586)
		(width 0.13208)
		(layer "B.Cu")
		(net "SMB_NIC7_SCL")
	)
	(segment
		(start 225.467926 -219.504006)
		(end 224.442782 -219.504006)
		(width 0.13208)
		(layer "B.Cu")
		(net "SMB_NIC7_SCL")
	)
	(segment
		(start 217.830654 -218.106752)
		(end 217.830654 -218.107768)
		(width 0.13208)
		(layer "B.Cu")
		(net "SMB_NIC7_SCL")
	)
	(segment
		(start 219.724732 -218.307666)
		(end 218.976956 -218.307666)
		(width 0.13208)
		(layer "B.Cu")
		(net "SMB_NIC7_SCL")
	)
	(segment
		(start 224.442782 -219.504006)
		(end 223.93529 -218.996514)
		(width 0.13208)
		(layer "B.Cu")
		(net "SMB_NIC7_SCL")
	)
	(segment
		(start 213.24062 -218.289632)
		(end 213.24062 -218.358212)
		(width 0.13208)
		(layer "B.Cu")
		(net "SMB_NIC7_SCL")
	)
	(segment
		(start 223.93529 -218.996514)
		(end 221.007432 -218.996514)
		(width 0.13208)
		(layer "B.Cu")
		(net "SMB_NIC7_SCL")
	)
	(segment
		(start 218.481148 -217.811858)
		(end 218.125548 -217.811858)
		(width 0.13208)
		(layer "B.Cu")
		(net "SMB_NIC7_SCL")
	)
	(segment
		(start 220.41358 -218.996514)
		(end 219.724732 -218.307666)
		(width 0.13208)
		(layer "B.Cu")
		(net "SMB_NIC7_SCL")
	)
	(segment
		(start 218.125548 -217.811858)
		(end 217.830654 -218.106752)
		(width 0.13208)
		(layer "B.Cu")
		(net "SMB_NIC7_SCL")
	)
	(segment
		(start 218.976956 -218.307666)
		(end 218.481148 -217.811858)
		(width 0.13208)
		(layer "B.Cu")
		(net "SMB_NIC7_SCL")
	)
	(segment
		(start 213.24062 -218.358212)
		(end 212.882734 -218.716098)
		(width 0.13208)
		(layer "B.Cu")
		(net "SMB_NIC7_SCL")
	)
	(segment
		(start 221.007432 -218.996514)
		(end 220.41358 -218.996514)
		(width 0.13208)
		(layer "B.Cu")
		(net "SMB_NIC7_SCL")
	)
	(segment
		(start 212.882734 -218.716098)
		(end 212.507576 -218.716098)
		(width 0.13208)
		(layer "B.Cu")
		(net "SMB_NIC7_SCL")
	)
	(segment
		(start 213.737444 -218.786456)
		(end 213.24062 -218.289632)
		(width 0.15494)
		(layer "In15.Cu")
		(net "SMB_NIC7_SCL")
	)
	(segment
		(start 218.976956 -218.307666)
		(end 218.976956 -218.313254)
		(width 0.15494)
		(layer "In15.Cu")
		(net "SMB_NIC7_SCL")
	)
	(segment
		(start 218.976956 -218.313254)
		(end 218.503754 -218.786456)
		(width 0.15494)
		(layer "In15.Cu")
		(net "SMB_NIC7_SCL")
	)
	(segment
		(start 218.503754 -218.786456)
		(end 213.737444 -218.786456)
		(width 0.15494)
		(layer "In15.Cu")
		(net "SMB_NIC7_SCL")
	)
	(segment
		(start 166.247318 -55.144162)
		(end 166.75862 -55.144162)
		(width 0.13208)
		(layer "F.Cu")
		(net "SSD5_PWR_EN_R")
	)
	(segment
		(start 167.967152 -57.332626)
		(end 167.967152 -56.354218)
		(width 0.13208)
		(layer "F.Cu")
		(net "SSD5_PWR_EN_R")
	)
	(segment
		(start 167.967152 -56.354218)
		(end 167.967914 -56.353456)
		(width 0.13208)
		(layer "F.Cu")
		(net "SSD5_PWR_EN_R")
	)
	(segment
		(start 166.75862 -55.144162)
		(end 167.967914 -56.353456)
		(width 0.13208)
		(layer "F.Cu")
		(net "SSD5_PWR_EN_R")
	)
	(segment
		(start 168.47566 -58.072274)
		(end 167.967152 -57.563766)
		(width 0.13208)
		(layer "F.Cu")
		(net "SSD5_PWR_EN_R")
	)
	(segment
		(start 167.967152 -57.563766)
		(end 167.967152 -57.332626)
		(width 0.13208)
		(layer "F.Cu")
		(net "SSD5_PWR_EN_R")
	)
	(segment
		(start 162.61461 -65.92189)
		(end 162.61461 -65.100962)
		(width 0.13208)
		(layer "F.Cu")
		(net "SSD5_PWR_EN_R")
	)
	(via
		(at 168.47566 -58.072274)
		(size 0.508)
		(drill 0.254)
		(layers "F.Cu" "B.Cu")
		(net "SSD5_PWR_EN_R")
	)
	(via
		(at 182.948834 -236.65942)
		(size 0.508)
		(drill 0.254)
		(layers "F.Cu" "B.Cu")
		(net "SSD5_PWR_EN_R")
	)
	(via
		(at 344.043 -236.347)
		(size 0.508)
		(drill 0.254)
		(layers "F.Cu" "B.Cu")
		(net "SSD5_PWR_EN_R")
	)
	(via
		(at 162.61461 -65.100962)
		(size 0.508)
		(drill 0.254)
		(layers "F.Cu" "B.Cu")
		(net "SSD5_PWR_EN_R")
	)
	(segment
		(start 344.58529 -234.42676)
		(end 344.58529 -235.80471)
		(width 0.13208)
		(layer "B.Cu")
		(net "SSD5_PWR_EN_R")
	)
	(segment
		(start 345.059 -233.95305)
		(end 344.58529 -234.42676)
		(width 0.13208)
		(layer "B.Cu")
		(net "SSD5_PWR_EN_R")
	)
	(segment
		(start 344.58529 -235.80471)
		(end 344.043 -236.347)
		(width 0.13208)
		(layer "B.Cu")
		(net "SSD5_PWR_EN_R")
	)
	(segment
		(start 168.47566 -58.072274)
		(end 168.283382 -58.264552)
		(width 0.15494)
		(layer "In5.Cu")
		(net "SSD5_PWR_EN_R")
	)
	(segment
		(start 168.283382 -58.264552)
		(end 168.283382 -64.451484)
		(width 0.15494)
		(layer "In5.Cu")
		(net "SSD5_PWR_EN_R")
	)
	(segment
		(start 168.283382 -64.451484)
		(end 167.651176 -65.08369)
		(width 0.15494)
		(layer "In5.Cu")
		(net "SSD5_PWR_EN_R")
	)
	(segment
		(start 180.948076 -221.907862)
		(end 180.948076 -229.679246)
		(width 0.15494)
		(layer "In5.Cu")
		(net "SSD5_PWR_EN_R")
	)
	(segment
		(start 180.948076 -229.679246)
		(end 182.746396 -231.477566)
		(width 0.15494)
		(layer "In5.Cu")
		(net "SSD5_PWR_EN_R")
	)
	(segment
		(start 168.80459 -58.401204)
		(end 168.80459 -66.237104)
		(width 0.15494)
		(layer "In5.Cu")
		(net "SSD5_PWR_EN_R")
	)
	(segment
		(start 172.521372 -114.965226)
		(end 173.404276 -115.84813)
		(width 0.15494)
		(layer "In5.Cu")
		(net "SSD5_PWR_EN_R")
	)
	(segment
		(start 182.948834 -236.034072)
		(end 182.948834 -236.65942)
		(width 0.15494)
		(layer "In5.Cu")
		(net "SSD5_PWR_EN_R")
	)
	(segment
		(start 176.802796 -211.901024)
		(end 180.948076 -221.907862)
		(width 0.15494)
		(layer "In5.Cu")
		(net "SSD5_PWR_EN_R")
	)
	(segment
		(start 172.026834 -180.509672)
		(end 173.234858 -181.717696)
		(width 0.15494)
		(layer "In5.Cu")
		(net "SSD5_PWR_EN_R")
	)
	(segment
		(start 182.746396 -231.477566)
		(end 182.746396 -235.831634)
		(width 0.15494)
		(layer "In5.Cu")
		(net "SSD5_PWR_EN_R")
	)
	(segment
		(start 167.651176 -65.08369)
		(end 164.53231 -65.08369)
		(width 0.15494)
		(layer "In5.Cu")
		(net "SSD5_PWR_EN_R")
	)
	(segment
		(start 168.80459 -66.237104)
		(end 169.91203 -67.344544)
		(width 0.15494)
		(layer "In5.Cu")
		(net "SSD5_PWR_EN_R")
	)
	(segment
		(start 163.97224 -65.64376)
		(end 163.157408 -65.64376)
		(width 0.15494)
		(layer "In5.Cu")
		(net "SSD5_PWR_EN_R")
	)
	(segment
		(start 172.521372 -89.433908)
		(end 172.521372 -114.965226)
		(width 0.15494)
		(layer "In5.Cu")
		(net "SSD5_PWR_EN_R")
	)
	(segment
		(start 172.026834 -120.55602)
		(end 172.026834 -180.509672)
		(width 0.15494)
		(layer "In5.Cu")
		(net "SSD5_PWR_EN_R")
	)
	(segment
		(start 176.802796 -203.578968)
		(end 176.802796 -211.901024)
		(width 0.15494)
		(layer "In5.Cu")
		(net "SSD5_PWR_EN_R")
	)
	(segment
		(start 173.404276 -119.178578)
		(end 172.026834 -120.55602)
		(width 0.15494)
		(layer "In5.Cu")
		(net "SSD5_PWR_EN_R")
	)
	(segment
		(start 164.53231 -65.08369)
		(end 163.97224 -65.64376)
		(width 0.15494)
		(layer "In5.Cu")
		(net "SSD5_PWR_EN_R")
	)
	(segment
		(start 168.47566 -58.072274)
		(end 168.80459 -58.401204)
		(width 0.15494)
		(layer "In5.Cu")
		(net "SSD5_PWR_EN_R")
	)
	(segment
		(start 173.404276 -115.84813)
		(end 173.404276 -119.178578)
		(width 0.15494)
		(layer "In5.Cu")
		(net "SSD5_PWR_EN_R")
	)
	(segment
		(start 173.234858 -200.01103)
		(end 176.802796 -203.578968)
		(width 0.15494)
		(layer "In5.Cu")
		(net "SSD5_PWR_EN_R")
	)
	(segment
		(start 182.746396 -235.831634)
		(end 182.948834 -236.034072)
		(width 0.15494)
		(layer "In5.Cu")
		(net "SSD5_PWR_EN_R")
	)
	(segment
		(start 169.91203 -86.824566)
		(end 172.521372 -89.433908)
		(width 0.15494)
		(layer "In5.Cu")
		(net "SSD5_PWR_EN_R")
	)
	(segment
		(start 173.234858 -181.717696)
		(end 173.234858 -200.01103)
		(width 0.15494)
		(layer "In5.Cu")
		(net "SSD5_PWR_EN_R")
	)
	(segment
		(start 163.157408 -65.64376)
		(end 162.61461 -65.100962)
		(width 0.15494)
		(layer "In5.Cu")
		(net "SSD5_PWR_EN_R")
	)
	(segment
		(start 169.91203 -67.344544)
		(end 169.91203 -86.824566)
		(width 0.15494)
		(layer "In5.Cu")
		(net "SSD5_PWR_EN_R")
	)
	(segment
		(start 184.64022 -236.65942)
		(end 190.861442 -242.880642)
		(width 0.15494)
		(layer "In15.Cu")
		(net "SSD5_PWR_EN_R")
	)
	(segment
		(start 343.002616 -239.35182)
		(end 343.718642 -238.635794)
		(width 0.15494)
		(layer "In15.Cu")
		(net "SSD5_PWR_EN_R")
	)
	(segment
		(start 182.948834 -236.65942)
		(end 184.64022 -236.65942)
		(width 0.15494)
		(layer "In15.Cu")
		(net "SSD5_PWR_EN_R")
	)
	(segment
		(start 333.32674 -242.697)
		(end 340.464648 -242.697)
		(width 0.15494)
		(layer "In15.Cu")
		(net "SSD5_PWR_EN_R")
	)
	(segment
		(start 332.66761 -243.35613)
		(end 333.32674 -242.697)
		(width 0.15494)
		(layer "In15.Cu")
		(net "SSD5_PWR_EN_R")
	)
	(segment
		(start 261.706106 -236.180884)
		(end 262.659622 -236.575854)
		(width 0.15494)
		(layer "In15.Cu")
		(net "SSD5_PWR_EN_R")
	)
	(segment
		(start 275.396706 -244.028468)
		(end 299.908468 -244.028468)
		(width 0.15494)
		(layer "In15.Cu")
		(net "SSD5_PWR_EN_R")
	)
	(segment
		(start 190.861442 -242.880642)
		(end 213.342728 -242.880642)
		(width 0.15494)
		(layer "In15.Cu")
		(net "SSD5_PWR_EN_R")
	)
	(segment
		(start 248.807224 -243.00053)
		(end 255.155954 -236.6518)
		(width 0.15494)
		(layer "In15.Cu")
		(net "SSD5_PWR_EN_R")
	)
	(segment
		(start 328.325988 -245.028212)
		(end 328.579226 -244.774974)
		(width 0.15494)
		(layer "In15.Cu")
		(net "SSD5_PWR_EN_R")
	)
	(segment
		(start 257.524758 -236.180884)
		(end 261.706106 -236.180884)
		(width 0.15494)
		(layer "In15.Cu")
		(net "SSD5_PWR_EN_R")
	)
	(segment
		(start 219.58808 -242.880896)
		(end 238.092742 -242.880896)
		(width 0.15494)
		(layer "In15.Cu")
		(net "SSD5_PWR_EN_R")
	)
	(segment
		(start 274.635722 -243.267484)
		(end 275.396706 -244.028468)
		(width 0.15494)
		(layer "In15.Cu")
		(net "SSD5_PWR_EN_R")
	)
	(segment
		(start 301.776384 -245.18747)
		(end 301.995586 -244.968268)
		(width 0.15494)
		(layer "In15.Cu")
		(net "SSD5_PWR_EN_R")
	)
	(segment
		(start 214.120984 -243.658898)
		(end 218.810078 -243.658898)
		(width 0.15494)
		(layer "In15.Cu")
		(net "SSD5_PWR_EN_R")
	)
	(segment
		(start 329.84313 -244.3734)
		(end 329.84313 -243.63934)
		(width 0.15494)
		(layer "In15.Cu")
		(net "SSD5_PWR_EN_R")
	)
	(segment
		(start 263.737344 -238.774986)
		(end 268.229842 -243.267484)
		(width 0.15494)
		(layer "In15.Cu")
		(net "SSD5_PWR_EN_R")
	)
	(segment
		(start 327.138792 -244.968268)
		(end 327.198736 -245.028212)
		(width 0.15494)
		(layer "In15.Cu")
		(net "SSD5_PWR_EN_R")
	)
	(segment
		(start 329.84313 -243.63934)
		(end 330.12634 -243.35613)
		(width 0.15494)
		(layer "In15.Cu")
		(net "SSD5_PWR_EN_R")
	)
	(segment
		(start 330.12634 -243.35613)
		(end 332.66761 -243.35613)
		(width 0.15494)
		(layer "In15.Cu")
		(net "SSD5_PWR_EN_R")
	)
	(segment
		(start 263.737344 -237.653576)
		(end 263.737344 -238.774986)
		(width 0.15494)
		(layer "In15.Cu")
		(net "SSD5_PWR_EN_R")
	)
	(segment
		(start 238.092742 -242.880896)
		(end 238.212376 -243.00053)
		(width 0.15494)
		(layer "In15.Cu")
		(net "SSD5_PWR_EN_R")
	)
	(segment
		(start 344.043 -237.64367)
		(end 344.043 -236.347)
		(width 0.15494)
		(layer "In15.Cu")
		(net "SSD5_PWR_EN_R")
	)
	(segment
		(start 327.198736 -245.028212)
		(end 328.325988 -245.028212)
		(width 0.15494)
		(layer "In15.Cu")
		(net "SSD5_PWR_EN_R")
	)
	(segment
		(start 268.229842 -243.267484)
		(end 274.635722 -243.267484)
		(width 0.15494)
		(layer "In15.Cu")
		(net "SSD5_PWR_EN_R")
	)
	(segment
		(start 343.718642 -237.968028)
		(end 344.043 -237.64367)
		(width 0.15494)
		(layer "In15.Cu")
		(net "SSD5_PWR_EN_R")
	)
	(segment
		(start 299.908468 -244.028468)
		(end 301.06747 -245.18747)
		(width 0.15494)
		(layer "In15.Cu")
		(net "SSD5_PWR_EN_R")
	)
	(segment
		(start 343.718642 -238.635794)
		(end 343.718642 -237.968028)
		(width 0.15494)
		(layer "In15.Cu")
		(net "SSD5_PWR_EN_R")
	)
	(segment
		(start 340.464648 -242.697)
		(end 343.002616 -240.159032)
		(width 0.15494)
		(layer "In15.Cu")
		(net "SSD5_PWR_EN_R")
	)
	(segment
		(start 301.06747 -245.18747)
		(end 301.776384 -245.18747)
		(width 0.15494)
		(layer "In15.Cu")
		(net "SSD5_PWR_EN_R")
	)
	(segment
		(start 328.579226 -244.774974)
		(end 329.441556 -244.774974)
		(width 0.15494)
		(layer "In15.Cu")
		(net "SSD5_PWR_EN_R")
	)
	(segment
		(start 329.441556 -244.774974)
		(end 329.84313 -244.3734)
		(width 0.15494)
		(layer "In15.Cu")
		(net "SSD5_PWR_EN_R")
	)
	(segment
		(start 262.659622 -236.575854)
		(end 263.737344 -237.653576)
		(width 0.15494)
		(layer "In15.Cu")
		(net "SSD5_PWR_EN_R")
	)
	(segment
		(start 238.212376 -243.00053)
		(end 248.807224 -243.00053)
		(width 0.15494)
		(layer "In15.Cu")
		(net "SSD5_PWR_EN_R")
	)
	(segment
		(start 301.995586 -244.968268)
		(end 327.138792 -244.968268)
		(width 0.15494)
		(layer "In15.Cu")
		(net "SSD5_PWR_EN_R")
	)
	(segment
		(start 255.155954 -236.6518)
		(end 257.524758 -236.180884)
		(width 0.15494)
		(layer "In15.Cu")
		(net "SSD5_PWR_EN_R")
	)
	(segment
		(start 213.342728 -242.880642)
		(end 214.120984 -243.658898)
		(width 0.15494)
		(layer "In15.Cu")
		(net "SSD5_PWR_EN_R")
	)
	(segment
		(start 218.810078 -243.658898)
		(end 219.58808 -242.880896)
		(width 0.15494)
		(layer "In15.Cu")
		(net "SSD5_PWR_EN_R")
	)
	(segment
		(start 343.002616 -240.159032)
		(end 343.002616 -239.35182)
		(width 0.15494)
		(layer "In15.Cu")
		(net "SSD5_PWR_EN_R")
	)
	(segment
		(start 341.293958 -211.18703)
		(end 341.63 -210.850988)
		(width 0.13208)
		(layer "F.Cu")
		(net "SSD13_CLK_EN_N")
	)
	(segment
		(start 342.646 -207.645)
		(end 342.646 -205.63205)
		(width 0.13208)
		(layer "F.Cu")
		(net "SSD13_CLK_EN_N")
	)
	(segment
		(start 341.63 -209.423)
		(end 342.646 -208.407)
		(width 0.13208)
		(layer "F.Cu")
		(net "SSD13_CLK_EN_N")
	)
	(segment
		(start 342.646 -208.407)
		(end 342.646 -207.645)
		(width 0.13208)
		(layer "F.Cu")
		(net "SSD13_CLK_EN_N")
	)
	(segment
		(start 341.63 -210.850988)
		(end 341.63 -209.423)
		(width 0.13208)
		(layer "F.Cu")
		(net "SSD13_CLK_EN_N")
	)
	(via
		(at 342.646 -207.645)
		(size 0.762)
		(drill 0.381)
		(layers "F.Cu" "B.Cu")
		(net "SSD13_CLK_EN_N")
	)
	(segment
		(start 238.821214 -91.650312)
		(end 238.709454 -91.538552)
		(width 0.13208)
		(layer "F.Cu")
		(net "PEX_USB_HUB_XIN")
	)
	(segment
		(start 240.906808 -91.049856)
		(end 240.906808 -91.594178)
		(width 0.13208)
		(layer "F.Cu")
		(net "PEX_USB_HUB_XIN")
	)
	(segment
		(start 239.836452 -91.650312)
		(end 239.836452 -91.01836)
		(width 0.13208)
		(layer "F.Cu")
		(net "PEX_USB_HUB_XIN")
	)
	(segment
		(start 239.963706 -90.891106)
		(end 240.748058 -90.891106)
		(width 0.13208)
		(layer "F.Cu")
		(net "PEX_USB_HUB_XIN")
	)
	(segment
		(start 239.18799 -91.650312)
		(end 238.821214 -91.650312)
		(width 0.13208)
		(layer "F.Cu")
		(net "PEX_USB_HUB_XIN")
	)
	(segment
		(start 237.63605 -91.538552)
		(end 237.407958 -91.766644)
		(width 0.13208)
		(layer "F.Cu")
		(net "PEX_USB_HUB_XIN")
	)
	(segment
		(start 238.709454 -91.538552)
		(end 237.63605 -91.538552)
		(width 0.13208)
		(layer "F.Cu")
		(net "PEX_USB_HUB_XIN")
	)
	(segment
		(start 237.407958 -91.766644)
		(end 236.433614 -91.766644)
		(width 0.13208)
		(layer "F.Cu")
		(net "PEX_USB_HUB_XIN")
	)
	(segment
		(start 239.836452 -91.01836)
		(end 239.963706 -90.891106)
		(width 0.13208)
		(layer "F.Cu")
		(net "PEX_USB_HUB_XIN")
	)
	(segment
		(start 239.18799 -91.650312)
		(end 239.836452 -91.650312)
		(width 0.13208)
		(layer "F.Cu")
		(net "PEX_USB_HUB_XIN")
	)
	(segment
		(start 240.748058 -90.891106)
		(end 240.906808 -91.049856)
		(width 0.13208)
		(layer "F.Cu")
		(net "PEX_USB_HUB_XIN")
	)
	(via
		(at 239.836452 -91.650312)
		(size 0.508)
		(drill 0.254)
		(layers "F.Cu" "B.Cu")
		(net "PEX_USB_HUB_XIN")
	)
	(segment
		(start 229.019354 -154.673046)
		(end 229.4128 -154.2796)
		(width 0.1143)
		(layer "F.Cu")
		(net "CLK_100M_PEX0_REF_DP")
	)
	(segment
		(start 229.019354 -155.216606)
		(end 229.019354 -154.673046)
		(width 0.1143)
		(layer "F.Cu")
		(net "CLK_100M_PEX0_REF_DP")
	)
	(segment
		(start 229.4128 -154.2796)
		(end 229.4128 -151.2824)
		(width 0.1143)
		(layer "F.Cu")
		(net "CLK_100M_PEX0_REF_DP")
	)
	(segment
		(start 229.347014 -151.216614)
		(end 229.347014 -151.015446)
		(width 0.1143)
		(layer "F.Cu")
		(net "CLK_100M_PEX0_REF_DP")
	)
	(segment
		(start 229.4128 -151.2824)
		(end 229.347014 -151.216614)
		(width 0.1143)
		(layer "F.Cu")
		(net "CLK_100M_PEX0_REF_DP")
	)
	(segment
		(start 228.695504 -155.540456)
		(end 229.019354 -155.216606)
		(width 0.1143)
		(layer "F.Cu")
		(net "CLK_100M_PEX0_REF_DP")
	)
	(segment
		(start 208.079086 -207.741266)
		(end 208.30286 -207.833976)
		(width 0.13208)
		(layer "F.Cu")
		(net "SMB_NIC4_R_SDA")
	)
	(segment
		(start 210.83905 -207.391)
		(end 211.200746 -207.391)
		(width 0.13208)
		(layer "F.Cu")
		(net "SMB_NIC4_R_SDA")
	)
	(segment
		(start 210.631278 -207.833976)
		(end 210.83905 -207.626204)
		(width 0.13208)
		(layer "F.Cu")
		(net "SMB_NIC4_R_SDA")
	)
	(segment
		(start 215.96477 -219.859352)
		(end 216.395046 -219.859352)
		(width 0.13208)
		(layer "F.Cu")
		(net "SMB_NIC4_R_SDA")
	)
	(segment
		(start 208.30286 -207.833976)
		(end 210.631278 -207.833976)
		(width 0.13208)
		(layer "F.Cu")
		(net "SMB_NIC4_R_SDA")
	)
	(segment
		(start 215.489536 -220.334586)
		(end 215.96477 -219.859352)
		(width 0.13208)
		(layer "F.Cu")
		(net "SMB_NIC4_R_SDA")
	)
	(segment
		(start 210.83905 -207.626204)
		(end 210.83905 -207.391)
		(width 0.13208)
		(layer "F.Cu")
		(net "SMB_NIC4_R_SDA")
	)
	(segment
		(start 216.395046 -219.859352)
		(end 216.835736 -220.300042)
		(width 0.13208)
		(layer "F.Cu")
		(net "SMB_NIC4_R_SDA")
	)
	(segment
		(start 211.398866 -207.58912)
		(end 212.522054 -207.58912)
		(width 0.13208)
		(layer "F.Cu")
		(net "SMB_NIC4_R_SDA")
	)
	(segment
		(start 216.835736 -220.300042)
		(end 216.835736 -220.334586)
		(width 0.13208)
		(layer "F.Cu")
		(net "SMB_NIC4_R_SDA")
	)
	(segment
		(start 207.73263 -207.741266)
		(end 208.079086 -207.741266)
		(width 0.13208)
		(layer "F.Cu")
		(net "SMB_NIC4_R_SDA")
	)
	(segment
		(start 211.200746 -207.391)
		(end 211.398866 -207.58912)
		(width 0.13208)
		(layer "F.Cu")
		(net "SMB_NIC4_R_SDA")
	)
	(via
		(at 215.489536 -220.334586)
		(size 0.508)
		(drill 0.254)
		(layers "F.Cu" "B.Cu")
		(net "SMB_NIC4_R_SDA")
	)
	(via
		(at 207.73263 -207.741266)
		(size 0.508)
		(drill 0.254)
		(layers "F.Cu" "B.Cu")
		(net "SMB_NIC4_R_SDA")
	)
	(segment
		(start 209.82305 -207.49895)
		(end 212.09 -207.49895)
		(width 0.13208)
		(layer "B.Cu")
		(net "SMB_NIC4_R_SDA")
	)
	(segment
		(start 207.73263 -207.741266)
		(end 209.238088 -207.741266)
		(width 0.13208)
		(layer "B.Cu")
		(net "SMB_NIC4_R_SDA")
	)
	(segment
		(start 209.238088 -207.741266)
		(end 209.82305 -207.49895)
		(width 0.13208)
		(layer "B.Cu")
		(net "SMB_NIC4_R_SDA")
	)
	(segment
		(start 207.757268 -207.765904)
		(end 207.757268 -217.372692)
		(width 0.15494)
		(layer "In7.Cu")
		(net "SMB_NIC4_R_SDA")
	)
	(segment
		(start 215.489536 -220.580966)
		(end 215.489536 -220.334586)
		(width 0.15494)
		(layer "In7.Cu")
		(net "SMB_NIC4_R_SDA")
	)
	(segment
		(start 210.384136 -219.033598)
		(end 210.384136 -219.810584)
		(width 0.15494)
		(layer "In7.Cu")
		(net "SMB_NIC4_R_SDA")
	)
	(segment
		(start 211.400898 -220.827346)
		(end 215.243156 -220.827346)
		(width 0.15494)
		(layer "In7.Cu")
		(net "SMB_NIC4_R_SDA")
	)
	(segment
		(start 215.243156 -220.827346)
		(end 215.489536 -220.580966)
		(width 0.15494)
		(layer "In7.Cu")
		(net "SMB_NIC4_R_SDA")
	)
	(segment
		(start 207.757268 -217.372692)
		(end 209.027776 -218.6432)
		(width 0.15494)
		(layer "In7.Cu")
		(net "SMB_NIC4_R_SDA")
	)
	(segment
		(start 207.73263 -207.741266)
		(end 207.757268 -207.765904)
		(width 0.15494)
		(layer "In7.Cu")
		(net "SMB_NIC4_R_SDA")
	)
	(segment
		(start 209.993738 -218.6432)
		(end 210.384136 -219.033598)
		(width 0.15494)
		(layer "In7.Cu")
		(net "SMB_NIC4_R_SDA")
	)
	(segment
		(start 210.384136 -219.810584)
		(end 211.400898 -220.827346)
		(width 0.15494)
		(layer "In7.Cu")
		(net "SMB_NIC4_R_SDA")
	)
	(segment
		(start 209.027776 -218.6432)
		(end 209.993738 -218.6432)
		(width 0.15494)
		(layer "In7.Cu")
		(net "SMB_NIC4_R_SDA")
	)
	(segment
		(start 150.319486 -390.798304)
		(end 150.319486 -391.771378)
		(width 0.13208)
		(layer "F.Cu")
		(net "PRSNT_GPU_HMC_R_N")
	)
	(via
		(at 150.319486 -391.771378)
		(size 0.508)
		(drill 0.254)
		(layers "F.Cu" "B.Cu")
		(net "PRSNT_GPU_HMC_R_N")
	)
	(segment
		(start 120.310148 -412.090108)
		(end 122.304556 -414.084516)
		(width 0.15494)
		(layer "In9.Cu")
		(net "PRSNT_GPU_HMC_R_N")
	)
	(segment
		(start 140.462 -410.079698)
		(end 140.462 -393.928346)
		(width 0.15494)
		(layer "In9.Cu")
		(net "PRSNT_GPU_HMC_R_N")
	)
	(segment
		(start 149.185376 -393.6492)
		(end 150.319486 -392.51509)
		(width 0.15494)
		(layer "In9.Cu")
		(net "PRSNT_GPU_HMC_R_N")
	)
	(segment
		(start 136.457182 -414.084516)
		(end 140.462 -410.079698)
		(width 0.15494)
		(layer "In9.Cu")
		(net "PRSNT_GPU_HMC_R_N")
	)
	(segment
		(start 122.304556 -414.084516)
		(end 136.457182 -414.084516)
		(width 0.15494)
		(layer "In9.Cu")
		(net "PRSNT_GPU_HMC_R_N")
	)
	(segment
		(start 140.462 -393.928346)
		(end 140.741146 -393.6492)
		(width 0.15494)
		(layer "In9.Cu")
		(net "PRSNT_GPU_HMC_R_N")
	)
	(segment
		(start 140.741146 -393.6492)
		(end 149.185376 -393.6492)
		(width 0.15494)
		(layer "In9.Cu")
		(net "PRSNT_GPU_HMC_R_N")
	)
	(segment
		(start 150.319486 -392.51509)
		(end 150.319486 -391.771378)
		(width 0.15494)
		(layer "In9.Cu")
		(net "PRSNT_GPU_HMC_R_N")
	)
	(segment
		(start 141.967204 -57.563766)
		(end 142.475712 -58.072274)
		(width 0.13208)
		(layer "F.Cu")
		(net "SSD4_PWR_EN_R")
	)
	(segment
		(start 140.24737 -55.144162)
		(end 140.758672 -55.144162)
		(width 0.13208)
		(layer "F.Cu")
		(net "SSD4_PWR_EN_R")
	)
	(segment
		(start 136.614662 -65.92189)
		(end 136.614662 -65.100962)
		(width 0.13208)
		(layer "F.Cu")
		(net "SSD4_PWR_EN_R")
	)
	(segment
		(start 141.967204 -57.332626)
		(end 141.967204 -57.563766)
		(width 0.13208)
		(layer "F.Cu")
		(net "SSD4_PWR_EN_R")
	)
	(segment
		(start 140.758672 -55.144162)
		(end 141.967966 -56.353456)
		(width 0.13208)
		(layer "F.Cu")
		(net "SSD4_PWR_EN_R")
	)
	(segment
		(start 339.728556 -251.017786)
		(end 345.91244 -244.833902)
		(width 0.13208)
		(layer "F.Cu")
		(net "SSD4_PWR_EN_R")
	)
	(segment
		(start 345.91244 -244.833902)
		(end 345.91244 -244.161564)
		(width 0.13208)
		(layer "F.Cu")
		(net "SSD4_PWR_EN_R")
	)
	(segment
		(start 345.91244 -244.161564)
		(end 348.982792 -241.091212)
		(width 0.13208)
		(layer "F.Cu")
		(net "SSD4_PWR_EN_R")
	)
	(segment
		(start 141.967204 -57.332626)
		(end 141.967204 -56.354218)
		(width 0.13208)
		(layer "F.Cu")
		(net "SSD4_PWR_EN_R")
	)
	(segment
		(start 141.967204 -56.354218)
		(end 141.967966 -56.353456)
		(width 0.13208)
		(layer "F.Cu")
		(net "SSD4_PWR_EN_R")
	)
	(via
		(at 339.728556 -251.017786)
		(size 0.508)
		(drill 0.254)
		(layers "F.Cu" "B.Cu")
		(net "SSD4_PWR_EN_R")
	)
	(via
		(at 142.475712 -58.072274)
		(size 0.508)
		(drill 0.254)
		(layers "F.Cu" "B.Cu")
		(net "SSD4_PWR_EN_R")
	)
	(via
		(at 153.030936 -245.304056)
		(size 0.508)
		(drill 0.254)
		(layers "F.Cu" "B.Cu")
		(net "SSD4_PWR_EN_R")
	)
	(via
		(at 136.614662 -65.100962)
		(size 0.508)
		(drill 0.254)
		(layers "F.Cu" "B.Cu")
		(net "SSD4_PWR_EN_R")
	)
	(segment
		(start 141.759686 -64.975232)
		(end 138.935968 -64.975232)
		(width 0.15494)
		(layer "In5.Cu")
		(net "SSD4_PWR_EN_R")
	)
	(segment
		(start 150.239984 -221.003622)
		(end 149.58187 -221.661736)
		(width 0.15494)
		(layer "In5.Cu")
		(net "SSD4_PWR_EN_R")
	)
	(segment
		(start 141.986 -172.1866)
		(end 143.423386 -173.623986)
		(width 0.15494)
		(layer "In5.Cu")
		(net "SSD4_PWR_EN_R")
	)
	(segment
		(start 143.423386 -186.781186)
		(end 148.949664 -192.307464)
		(width 0.15494)
		(layer "In5.Cu")
		(net "SSD4_PWR_EN_R")
	)
	(segment
		(start 142.797784 -58.394346)
		(end 142.797784 -79.197962)
		(width 0.15494)
		(layer "In5.Cu")
		(net "SSD4_PWR_EN_R")
	)
	(segment
		(start 141.045946 -110.6678)
		(end 141.045946 -163.384484)
		(width 0.15494)
		(layer "In5.Cu")
		(net "SSD4_PWR_EN_R")
	)
	(segment
		(start 151.943054 -240.363502)
		(end 153.030936 -241.451384)
		(width 0.15494)
		(layer "In5.Cu")
		(net "SSD4_PWR_EN_R")
	)
	(segment
		(start 142.475712 -58.072274)
		(end 142.797784 -58.394346)
		(width 0.15494)
		(layer "In5.Cu")
		(net "SSD4_PWR_EN_R")
	)
	(segment
		(start 149.58187 -221.661736)
		(end 149.58187 -234.584494)
		(width 0.15494)
		(layer "In5.Cu")
		(net "SSD4_PWR_EN_R")
	)
	(segment
		(start 142.475712 -58.072274)
		(end 142.283434 -58.264552)
		(width 0.15494)
		(layer "In5.Cu")
		(net "SSD4_PWR_EN_R")
	)
	(segment
		(start 142.283434 -58.264552)
		(end 142.283434 -64.451484)
		(width 0.15494)
		(layer "In5.Cu")
		(net "SSD4_PWR_EN_R")
	)
	(segment
		(start 137.15746 -65.64376)
		(end 136.614662 -65.100962)
		(width 0.15494)
		(layer "In5.Cu")
		(net "SSD4_PWR_EN_R")
	)
	(segment
		(start 141.045946 -163.384484)
		(end 141.986 -164.324538)
		(width 0.15494)
		(layer "In5.Cu")
		(net "SSD4_PWR_EN_R")
	)
	(segment
		(start 148.949664 -192.307464)
		(end 150.239984 -195.422266)
		(width 0.15494)
		(layer "In5.Cu")
		(net "SSD4_PWR_EN_R")
	)
	(segment
		(start 153.030936 -241.451384)
		(end 153.030936 -245.304056)
		(width 0.15494)
		(layer "In5.Cu")
		(net "SSD4_PWR_EN_R")
	)
	(segment
		(start 138.935968 -64.975232)
		(end 138.26744 -65.64376)
		(width 0.15494)
		(layer "In5.Cu")
		(net "SSD4_PWR_EN_R")
	)
	(segment
		(start 151.943054 -236.945678)
		(end 151.943054 -240.363502)
		(width 0.15494)
		(layer "In5.Cu")
		(net "SSD4_PWR_EN_R")
	)
	(segment
		(start 141.986 -164.324538)
		(end 141.986 -172.1866)
		(width 0.15494)
		(layer "In5.Cu")
		(net "SSD4_PWR_EN_R")
	)
	(segment
		(start 138.26744 -65.64376)
		(end 137.15746 -65.64376)
		(width 0.15494)
		(layer "In5.Cu")
		(net "SSD4_PWR_EN_R")
	)
	(segment
		(start 150.239984 -195.422266)
		(end 150.239984 -221.003622)
		(width 0.15494)
		(layer "In5.Cu")
		(net "SSD4_PWR_EN_R")
	)
	(segment
		(start 142.797784 -79.197962)
		(end 141.5796 -80.416146)
		(width 0.15494)
		(layer "In5.Cu")
		(net "SSD4_PWR_EN_R")
	)
	(segment
		(start 143.423386 -173.623986)
		(end 143.423386 -186.781186)
		(width 0.15494)
		(layer "In5.Cu")
		(net "SSD4_PWR_EN_R")
	)
	(segment
		(start 141.5796 -80.416146)
		(end 141.5796 -110.134146)
		(width 0.15494)
		(layer "In5.Cu")
		(net "SSD4_PWR_EN_R")
	)
	(segment
		(start 149.58187 -234.584494)
		(end 151.943054 -236.945678)
		(width 0.15494)
		(layer "In5.Cu")
		(net "SSD4_PWR_EN_R")
	)
	(segment
		(start 141.5796 -110.134146)
		(end 141.045946 -110.6678)
		(width 0.15494)
		(layer "In5.Cu")
		(net "SSD4_PWR_EN_R")
	)
	(segment
		(start 142.283434 -64.451484)
		(end 141.759686 -64.975232)
		(width 0.15494)
		(layer "In5.Cu")
		(net "SSD4_PWR_EN_R")
	)
	(segment
		(start 256.17932 -254.55626)
		(end 256.498852 -254.875792)
		(width 0.15494)
		(layer "In15.Cu")
		(net "SSD4_PWR_EN_R")
	)
	(segment
		(start 225.16973 -252.422406)
		(end 225.516186 -252.07595)
		(width 0.15494)
		(layer "In15.Cu")
		(net "SSD4_PWR_EN_R")
	)
	(segment
		(start 257.42011 -255.24206)
		(end 269.61719 -255.24206)
		(width 0.15494)
		(layer "In15.Cu")
		(net "SSD4_PWR_EN_R")
	)
	(segment
		(start 270.15059 -255.77546)
		(end 273.873976 -255.77546)
		(width 0.15494)
		(layer "In15.Cu")
		(net "SSD4_PWR_EN_R")
	)
	(segment
		(start 320.62801 -256.702814)
		(end 320.9798 -256.351024)
		(width 0.15494)
		(layer "In15.Cu")
		(net "SSD4_PWR_EN_R")
	)
	(segment
		(start 153.030936 -245.304056)
		(end 154.196542 -244.13845)
		(width 0.15494)
		(layer "In15.Cu")
		(net "SSD4_PWR_EN_R")
	)
	(segment
		(start 273.873976 -255.77546)
		(end 274.44954 -256.351024)
		(width 0.15494)
		(layer "In15.Cu")
		(net "SSD4_PWR_EN_R")
	)
	(segment
		(start 186.9186 -253.4666)
		(end 224.6376 -253.4666)
		(width 0.15494)
		(layer "In15.Cu")
		(net "SSD4_PWR_EN_R")
	)
	(segment
		(start 154.196542 -244.13845)
		(end 177.59045 -244.13845)
		(width 0.15494)
		(layer "In15.Cu")
		(net "SSD4_PWR_EN_R")
	)
	(segment
		(start 256.498852 -254.875792)
		(end 257.053842 -254.875792)
		(width 0.15494)
		(layer "In15.Cu")
		(net "SSD4_PWR_EN_R")
	)
	(segment
		(start 313.02579 -256.702814)
		(end 320.62801 -256.702814)
		(width 0.15494)
		(layer "In15.Cu")
		(net "SSD4_PWR_EN_R")
	)
	(segment
		(start 312.674 -256.351024)
		(end 313.02579 -256.702814)
		(width 0.15494)
		(layer "In15.Cu")
		(net "SSD4_PWR_EN_R")
	)
	(segment
		(start 177.59045 -244.13845)
		(end 186.9186 -253.4666)
		(width 0.15494)
		(layer "In15.Cu")
		(net "SSD4_PWR_EN_R")
	)
	(segment
		(start 335.34477 -256.351024)
		(end 339.728556 -251.967238)
		(width 0.15494)
		(layer "In15.Cu")
		(net "SSD4_PWR_EN_R")
	)
	(segment
		(start 339.728556 -251.967238)
		(end 339.728556 -251.017786)
		(width 0.15494)
		(layer "In15.Cu")
		(net "SSD4_PWR_EN_R")
	)
	(segment
		(start 320.9798 -256.351024)
		(end 335.34477 -256.351024)
		(width 0.15494)
		(layer "In15.Cu")
		(net "SSD4_PWR_EN_R")
	)
	(segment
		(start 269.61719 -255.24206)
		(end 270.15059 -255.77546)
		(width 0.15494)
		(layer "In15.Cu")
		(net "SSD4_PWR_EN_R")
	)
	(segment
		(start 257.053842 -254.875792)
		(end 257.42011 -255.24206)
		(width 0.15494)
		(layer "In15.Cu")
		(net "SSD4_PWR_EN_R")
	)
	(segment
		(start 228.25075 -252.07595)
		(end 230.73106 -254.55626)
		(width 0.15494)
		(layer "In15.Cu")
		(net "SSD4_PWR_EN_R")
	)
	(segment
		(start 225.516186 -252.07595)
		(end 228.25075 -252.07595)
		(width 0.15494)
		(layer "In15.Cu")
		(net "SSD4_PWR_EN_R")
	)
	(segment
		(start 225.16973 -252.93447)
		(end 225.16973 -252.422406)
		(width 0.15494)
		(layer "In15.Cu")
		(net "SSD4_PWR_EN_R")
	)
	(segment
		(start 224.6376 -253.4666)
		(end 225.16973 -252.93447)
		(width 0.15494)
		(layer "In15.Cu")
		(net "SSD4_PWR_EN_R")
	)
	(segment
		(start 274.44954 -256.351024)
		(end 312.674 -256.351024)
		(width 0.15494)
		(layer "In15.Cu")
		(net "SSD4_PWR_EN_R")
	)
	(segment
		(start 230.73106 -254.55626)
		(end 256.17932 -254.55626)
		(width 0.15494)
		(layer "In15.Cu")
		(net "SSD4_PWR_EN_R")
	)
	(segment
		(start 339.693758 -215.987122)
		(end 339.293962 -215.587326)
		(width 0.13208)
		(layer "F.Cu")
		(net "SSD9_PWRDIS")
	)
	(segment
		(start 336.55 -201.56805)
		(end 336.55 -202.946)
		(width 0.13208)
		(layer "F.Cu")
		(net "SSD9_PWRDIS")
	)
	(via
		(at 339.293962 -215.587326)
		(size 0.4572)
		(drill 0.254)
		(layers "F.Cu" "B.Cu")
		(net "SSD9_PWRDIS")
	)
	(via
		(at 336.55 -202.946)
		(size 0.508)
		(drill 0.254)
		(layers "F.Cu" "B.Cu")
		(net "SSD9_PWRDIS")
	)
	(segment
		(start 339.696298 -215.18499)
		(end 339.293962 -215.587326)
		(width 0.0889)
		(layer "In5.Cu")
		(net "SSD9_PWRDIS")
	)
	(segment
		(start 337.062318 -204.630528)
		(end 337.563714 -205.131924)
		(width 0.15494)
		(layer "In5.Cu")
		(net "SSD9_PWRDIS")
	)
	(segment
		(start 337.563714 -205.131924)
		(end 337.563714 -206.445612)
		(width 0.15494)
		(layer "In5.Cu")
		(net "SSD9_PWRDIS")
	)
	(segment
		(start 339.696298 -212.217)
		(end 339.696298 -215.18499)
		(width 0.0889)
		(layer "In5.Cu")
		(net "SSD9_PWRDIS")
	)
	(segment
		(start 339.696298 -211.864702)
		(end 339.696298 -212.217)
		(width 0.15494)
		(layer "In5.Cu")
		(net "SSD9_PWRDIS")
	)
	(segment
		(start 337.563714 -206.445612)
		(end 339.852 -208.733898)
		(width 0.15494)
		(layer "In5.Cu")
		(net "SSD9_PWRDIS")
	)
	(segment
		(start 339.852 -208.733898)
		(end 339.852 -211.709)
		(width 0.15494)
		(layer "In5.Cu")
		(net "SSD9_PWRDIS")
	)
	(segment
		(start 337.062318 -203.458318)
		(end 337.062318 -204.630528)
		(width 0.15494)
		(layer "In5.Cu")
		(net "SSD9_PWRDIS")
	)
	(segment
		(start 339.852 -211.709)
		(end 339.696298 -211.864702)
		(width 0.15494)
		(layer "In5.Cu")
		(net "SSD9_PWRDIS")
	)
	(segment
		(start 336.55 -202.946)
		(end 337.062318 -203.458318)
		(width 0.15494)
		(layer "In5.Cu")
		(net "SSD9_PWRDIS")
	)
	(segment
		(start 385.149598 -299.699934)
		(end 384.674618 -299.224954)
		(width 0.1143)
		(layer "F.Cu")
		(net "CLK_100M_PEX3_REF_R_DN")
	)
	(segment
		(start 236.342682 -149.0599)
		(end 236.933994 -149.0599)
		(width 0.1143)
		(layer "F.Cu")
		(net "CLK_100M_PEX3_REF_R_DN")
	)
	(segment
		(start 236.933994 -149.0599)
		(end 237.16615 -148.827744)
		(width 0.1143)
		(layer "F.Cu")
		(net "CLK_100M_PEX3_REF_R_DN")
	)
	(segment
		(start 385.149852 -299.699934)
		(end 385.149598 -299.699934)
		(width 0.1143)
		(layer "F.Cu")
		(net "CLK_100M_PEX3_REF_R_DN")
	)
	(segment
		(start 236.019594 -148.736812)
		(end 236.342682 -149.0599)
		(width 0.1143)
		(layer "F.Cu")
		(net "CLK_100M_PEX3_REF_R_DN")
	)
	(via
		(at 237.16615 -148.827744)
		(size 0.508)
		(drill 0.254)
		(layers "F.Cu" "B.Cu")
		(net "CLK_100M_PEX3_REF_R_DN")
	)
	(via
		(at 384.674618 -299.224954)
		(size 0.4064)
		(drill 0.2032)
		(layers "F.Cu" "B.Cu")
		(net "CLK_100M_PEX3_REF_R_DN")
	)
	(segment
		(start 246.234458 -165.3032)
		(end 258.11353 -177.182272)
		(width 0.1143)
		(layer "B.Cu")
		(net "CLK_100M_PEX3_REF_R_DN")
	)
	(segment
		(start 353.101148 -242.3922)
		(end 362.081318 -242.3922)
		(width 0.1143)
		(layer "B.Cu")
		(net "CLK_100M_PEX3_REF_R_DN")
	)
	(segment
		(start 314.792614 -225.434144)
		(end 314.792614 -234.898946)
		(width 0.1143)
		(layer "B.Cu")
		(net "CLK_100M_PEX3_REF_R_DN")
	)
	(segment
		(start 379.265688 -297.180254)
		(end 379.54966 -297.46448)
		(width 0.1143)
		(layer "B.Cu")
		(net "CLK_100M_PEX3_REF_R_DN")
	)
	(segment
		(start 237.42015 -149.081744)
		(end 237.778544 -149.081744)
		(width 0.1143)
		(layer "B.Cu")
		(net "CLK_100M_PEX3_REF_R_DN")
	)
	(segment
		(start 384.849116 -299.60951)
		(end 385.054348 -299.404278)
		(width 0.0889)
		(layer "B.Cu")
		(net "CLK_100M_PEX3_REF_R_DN")
	)
	(segment
		(start 377.7869 -294.818562)
		(end 377.92406 -294.955722)
		(width 0.1143)
		(layer "B.Cu")
		(net "CLK_100M_PEX3_REF_R_DN")
	)
	(segment
		(start 376.618754 -278.7015)
		(end 376.9995 -278.7015)
		(width 0.1143)
		(layer "B.Cu")
		(net "CLK_100M_PEX3_REF_R_DN")
	)
	(segment
		(start 243.038122 -165.3032)
		(end 246.234458 -165.3032)
		(width 0.1143)
		(layer "B.Cu")
		(net "CLK_100M_PEX3_REF_R_DN")
	)
	(segment
		(start 378.787914 -296.702734)
		(end 378.787914 -296.896536)
		(width 0.1143)
		(layer "B.Cu")
		(net "CLK_100M_PEX3_REF_R_DN")
	)
	(segment
		(start 260.11759 -183.312054)
		(end 262.336026 -184.231026)
		(width 0.1143)
		(layer "B.Cu")
		(net "CLK_100M_PEX3_REF_R_DN")
	)
	(segment
		(start 377.7869 -279.4889)
		(end 377.7869 -294.818562)
		(width 0.1143)
		(layer "B.Cu")
		(net "CLK_100M_PEX3_REF_R_DN")
	)
	(segment
		(start 258.11353 -181.308248)
		(end 260.11759 -183.312054)
		(width 0.1143)
		(layer "B.Cu")
		(net "CLK_100M_PEX3_REF_R_DN")
	)
	(segment
		(start 262.336026 -184.231026)
		(end 290.3855 -212.2805)
		(width 0.1143)
		(layer "B.Cu")
		(net "CLK_100M_PEX3_REF_R_DN")
	)
	(segment
		(start 377.92406 -295.357042)
		(end 377.7869 -295.494202)
		(width 0.1143)
		(layer "B.Cu")
		(net "CLK_100M_PEX3_REF_R_DN")
	)
	(segment
		(start 385.054348 -299.313854)
		(end 384.965448 -299.224954)
		(width 0.0889)
		(layer "B.Cu")
		(net "CLK_100M_PEX3_REF_R_DN")
	)
	(segment
		(start 381.584454 -297.942)
		(end 383.169414 -299.52696)
		(width 0.1143)
		(layer "B.Cu")
		(net "CLK_100M_PEX3_REF_R_DN")
	)
	(segment
		(start 362.081318 -242.3922)
		(end 367.1062 -247.417082)
		(width 0.1143)
		(layer "B.Cu")
		(net "CLK_100M_PEX3_REF_R_DN")
	)
	(segment
		(start 367.1062 -269.188946)
		(end 376.618754 -278.7015)
		(width 0.1143)
		(layer "B.Cu")
		(net "CLK_100M_PEX3_REF_R_DN")
	)
	(segment
		(start 383.77495 -299.60951)
		(end 384.849116 -299.60951)
		(width 0.0889)
		(layer "B.Cu")
		(net "CLK_100M_PEX3_REF_R_DN")
	)
	(segment
		(start 352.720148 -242.7732)
		(end 353.101148 -242.3922)
		(width 0.1143)
		(layer "B.Cu")
		(net "CLK_100M_PEX3_REF_R_DN")
	)
	(segment
		(start 383.6924 -299.52696)
		(end 383.77495 -299.60951)
		(width 0.0889)
		(layer "B.Cu")
		(net "CLK_100M_PEX3_REF_R_DN")
	)
	(segment
		(start 237.16615 -148.827744)
		(end 237.42015 -149.081744)
		(width 0.1143)
		(layer "B.Cu")
		(net "CLK_100M_PEX3_REF_R_DN")
	)
	(segment
		(start 384.965448 -299.224954)
		(end 384.674618 -299.224954)
		(width 0.0889)
		(layer "B.Cu")
		(net "CLK_100M_PEX3_REF_R_DN")
	)
	(segment
		(start 239.2045 -156.337254)
		(end 238.595662 -156.946092)
		(width 0.1143)
		(layer "B.Cu")
		(net "CLK_100M_PEX3_REF_R_DN")
	)
	(segment
		(start 383.670302 -299.52696)
		(end 383.6924 -299.52696)
		(width 0.0889)
		(layer "B.Cu")
		(net "CLK_100M_PEX3_REF_R_DN")
	)
	(segment
		(start 238.595662 -160.86074)
		(end 243.038122 -165.3032)
		(width 0.1143)
		(layer "B.Cu")
		(net "CLK_100M_PEX3_REF_R_DN")
	)
	(segment
		(start 379.54966 -297.658282)
		(end 379.833378 -297.942)
		(width 0.1143)
		(layer "B.Cu")
		(net "CLK_100M_PEX3_REF_R_DN")
	)
	(segment
		(start 378.503942 -296.418508)
		(end 378.787914 -296.702734)
		(width 0.1143)
		(layer "B.Cu")
		(net "CLK_100M_PEX3_REF_R_DN")
	)
	(segment
		(start 377.92406 -294.955722)
		(end 377.92406 -295.357042)
		(width 0.1143)
		(layer "B.Cu")
		(net "CLK_100M_PEX3_REF_R_DN")
	)
	(segment
		(start 322.666868 -242.7732)
		(end 352.720148 -242.7732)
		(width 0.1143)
		(layer "B.Cu")
		(net "CLK_100M_PEX3_REF_R_DN")
	)
	(segment
		(start 367.1062 -247.417082)
		(end 367.1062 -269.188946)
		(width 0.1143)
		(layer "B.Cu")
		(net "CLK_100M_PEX3_REF_R_DN")
	)
	(segment
		(start 376.9995 -278.7015)
		(end 377.7869 -279.4889)
		(width 0.1143)
		(layer "B.Cu")
		(net "CLK_100M_PEX3_REF_R_DN")
	)
	(segment
		(start 379.54966 -297.46448)
		(end 379.54966 -297.658282)
		(width 0.1143)
		(layer "B.Cu")
		(net "CLK_100M_PEX3_REF_R_DN")
	)
	(segment
		(start 378.309886 -296.418508)
		(end 378.503942 -296.418508)
		(width 0.1143)
		(layer "B.Cu")
		(net "CLK_100M_PEX3_REF_R_DN")
	)
	(segment
		(start 377.7869 -295.895522)
		(end 378.309886 -296.418508)
		(width 0.1143)
		(layer "B.Cu")
		(net "CLK_100M_PEX3_REF_R_DN")
	)
	(segment
		(start 238.595662 -156.946092)
		(end 238.595662 -160.86074)
		(width 0.1143)
		(layer "B.Cu")
		(net "CLK_100M_PEX3_REF_R_DN")
	)
	(segment
		(start 239.2045 -150.5077)
		(end 239.2045 -156.337254)
		(width 0.1143)
		(layer "B.Cu")
		(net "CLK_100M_PEX3_REF_R_DN")
	)
	(segment
		(start 378.787914 -296.896536)
		(end 379.071632 -297.180254)
		(width 0.1143)
		(layer "B.Cu")
		(net "CLK_100M_PEX3_REF_R_DN")
	)
	(segment
		(start 237.778544 -149.081744)
		(end 239.2045 -150.5077)
		(width 0.1143)
		(layer "B.Cu")
		(net "CLK_100M_PEX3_REF_R_DN")
	)
	(segment
		(start 385.054348 -299.404278)
		(end 385.054348 -299.313854)
		(width 0.0889)
		(layer "B.Cu")
		(net "CLK_100M_PEX3_REF_R_DN")
	)
	(segment
		(start 379.071632 -297.180254)
		(end 379.265688 -297.180254)
		(width 0.1143)
		(layer "B.Cu")
		(net "CLK_100M_PEX3_REF_R_DN")
	)
	(segment
		(start 379.833378 -297.942)
		(end 381.584454 -297.942)
		(width 0.1143)
		(layer "B.Cu")
		(net "CLK_100M_PEX3_REF_R_DN")
	)
	(segment
		(start 314.792614 -234.898946)
		(end 322.666868 -242.7732)
		(width 0.1143)
		(layer "B.Cu")
		(net "CLK_100M_PEX3_REF_R_DN")
	)
	(segment
		(start 290.3855 -212.2805)
		(end 301.63897 -212.2805)
		(width 0.1143)
		(layer "B.Cu")
		(net "CLK_100M_PEX3_REF_R_DN")
	)
	(segment
		(start 377.7869 -295.494202)
		(end 377.7869 -295.895522)
		(width 0.1143)
		(layer "B.Cu")
		(net "CLK_100M_PEX3_REF_R_DN")
	)
	(segment
		(start 383.169414 -299.52696)
		(end 383.670302 -299.52696)
		(width 0.1143)
		(layer "B.Cu")
		(net "CLK_100M_PEX3_REF_R_DN")
	)
	(segment
		(start 301.63897 -212.2805)
		(end 314.792614 -225.434144)
		(width 0.1143)
		(layer "B.Cu")
		(net "CLK_100M_PEX3_REF_R_DN")
	)
	(segment
		(start 258.11353 -177.182272)
		(end 258.11353 -181.308248)
		(width 0.1143)
		(layer "B.Cu")
		(net "CLK_100M_PEX3_REF_R_DN")
	)
	(segment
		(start 225.067622 -221.504256)
		(end 224.667826 -221.904052)
		(width 0.13208)
		(layer "F.Cu")
		(net "SMB_BIC_I2C6_SDA")
	)
	(via
		(at 224.667826 -221.904052)
		(size 0.4572)
		(drill 0.254)
		(layers "F.Cu" "B.Cu")
		(net "SMB_BIC_I2C6_SDA")
	)
	(via
		(at 214.852504 -223.382586)
		(size 0.508)
		(drill 0.254)
		(layers "F.Cu" "B.Cu")
		(net "SMB_BIC_I2C6_SDA")
	)
	(via
		(at 218.245436 -223.4184)
		(size 0.508)
		(drill 0.254)
		(layers "F.Cu" "B.Cu")
		(net "SMB_BIC_I2C6_SDA")
	)
	(via
		(at 221.0562 -223.804226)
		(size 0.6604)
		(drill 0.3302)
		(layers "F.Cu" "B.Cu")
		(net "SMB_BIC_I2C6_SDA")
	)
	(segment
		(start 214.130382 -223.382586)
		(end 214.852504 -223.382586)
		(width 0.13208)
		(layer "B.Cu")
		(net "SMB_BIC_I2C6_SDA")
	)
	(segment
		(start 218.648026 -223.804226)
		(end 221.0562 -223.804226)
		(width 0.13208)
		(layer "B.Cu")
		(net "SMB_BIC_I2C6_SDA")
	)
	(segment
		(start 218.209622 -223.382586)
		(end 218.245436 -223.4184)
		(width 0.13208)
		(layer "B.Cu")
		(net "SMB_BIC_I2C6_SDA")
	)
	(segment
		(start 224.667826 -221.904052)
		(end 222.956374 -221.904052)
		(width 0.13208)
		(layer "B.Cu")
		(net "SMB_BIC_I2C6_SDA")
	)
	(segment
		(start 222.956374 -221.904052)
		(end 221.0562 -223.804226)
		(width 0.13208)
		(layer "B.Cu")
		(net "SMB_BIC_I2C6_SDA")
	)
	(segment
		(start 218.245436 -223.4184)
		(end 218.2622 -223.4184)
		(width 0.13208)
		(layer "B.Cu")
		(net "SMB_BIC_I2C6_SDA")
	)
	(segment
		(start 217.635836 -223.382586)
		(end 218.209622 -223.382586)
		(width 0.13208)
		(layer "B.Cu")
		(net "SMB_BIC_I2C6_SDA")
	)
	(segment
		(start 218.2622 -223.4184)
		(end 218.648026 -223.804226)
		(width 0.13208)
		(layer "B.Cu")
		(net "SMB_BIC_I2C6_SDA")
	)
	(segment
		(start 215.288876 -222.898716)
		(end 214.852504 -223.335088)
		(width 0.15494)
		(layer "In15.Cu")
		(net "SMB_BIC_I2C6_SDA")
	)
	(segment
		(start 217.725752 -222.898716)
		(end 215.288876 -222.898716)
		(width 0.15494)
		(layer "In15.Cu")
		(net "SMB_BIC_I2C6_SDA")
	)
	(segment
		(start 218.245436 -223.4184)
		(end 217.725752 -222.898716)
		(width 0.15494)
		(layer "In15.Cu")
		(net "SMB_BIC_I2C6_SDA")
	)
	(segment
		(start 214.852504 -223.335088)
		(end 214.852504 -223.382586)
		(width 0.15494)
		(layer "In15.Cu")
		(net "SMB_BIC_I2C6_SDA")
	)
	(segment
		(start 216.835736 -212.206586)
		(end 216.200736 -212.206586)
		(width 0.13208)
		(layer "F.Cu")
		(net "RST_BIC_I2C9_SSD_MUX0_R_N")
	)
	(segment
		(start 127.462534 -96.440498)
		(end 128.651 -96.440498)
		(width 0.13208)
		(layer "F.Cu")
		(net "RST_BIC_I2C9_SSD_MUX0_R_N")
	)
	(via
		(at 216.200736 -212.206586)
		(size 0.508)
		(drill 0.254)
		(layers "F.Cu" "B.Cu")
		(net "RST_BIC_I2C9_SSD_MUX0_R_N")
	)
	(via
		(at 215.615266 -91.655646)
		(size 0.508)
		(drill 0.254)
		(layers "F.Cu" "B.Cu")
		(net "RST_BIC_I2C9_SSD_MUX0_R_N")
	)
	(via
		(at 128.651 -96.440498)
		(size 0.508)
		(drill 0.254)
		(layers "F.Cu" "B.Cu")
		(net "RST_BIC_I2C9_SSD_MUX0_R_N")
	)
	(segment
		(start 215.3158 -132.359146)
		(end 212.4202 -129.463546)
		(width 0.15494)
		(layer "In7.Cu")
		(net "RST_BIC_I2C9_SSD_MUX0_R_N")
	)
	(segment
		(start 215.18626 -101.317806)
		(end 215.18626 -101.28758)
		(width 0.15494)
		(layer "In7.Cu")
		(net "RST_BIC_I2C9_SSD_MUX0_R_N")
	)
	(segment
		(start 216.200736 -212.206586)
		(end 216.674446 -211.732876)
		(width 0.15494)
		(layer "In7.Cu")
		(net "RST_BIC_I2C9_SSD_MUX0_R_N")
	)
	(segment
		(start 219.6338 -199.62622)
		(end 219.6338 -197.86473)
		(width 0.15494)
		(layer "In7.Cu")
		(net "RST_BIC_I2C9_SSD_MUX0_R_N")
	)
	(segment
		(start 215.3158 -153.000964)
		(end 215.3158 -132.359146)
		(width 0.15494)
		(layer "In7.Cu")
		(net "RST_BIC_I2C9_SSD_MUX0_R_N")
	)
	(segment
		(start 219.6338 -200.932288)
		(end 219.6338 -200.93178)
		(width 0.15494)
		(layer "In7.Cu")
		(net "RST_BIC_I2C9_SSD_MUX0_R_N")
	)
	(segment
		(start 220.6244 -191.60744)
		(end 220.62694 -191.6049)
		(width 0.15494)
		(layer "In7.Cu")
		(net "RST_BIC_I2C9_SSD_MUX0_R_N")
	)
	(segment
		(start 220.62694 -186.51474)
		(end 219.094558 -184.982358)
		(width 0.15494)
		(layer "In7.Cu")
		(net "RST_BIC_I2C9_SSD_MUX0_R_N")
	)
	(segment
		(start 217.5764 -209.157062)
		(end 217.5764 -205.14564)
		(width 0.15494)
		(layer "In7.Cu")
		(net "RST_BIC_I2C9_SSD_MUX0_R_N")
	)
	(segment
		(start 216.674446 -211.732876)
		(end 216.674446 -210.059016)
		(width 0.15494)
		(layer "In7.Cu")
		(net "RST_BIC_I2C9_SSD_MUX0_R_N")
	)
	(segment
		(start 220.08592 -200.07834)
		(end 219.6338 -199.62622)
		(width 0.15494)
		(layer "In7.Cu")
		(net "RST_BIC_I2C9_SSD_MUX0_R_N")
	)
	(segment
		(start 218.842082 -175.65878)
		(end 218.842082 -174.394114)
		(width 0.15494)
		(layer "In7.Cu")
		(net "RST_BIC_I2C9_SSD_MUX0_R_N")
	)
	(segment
		(start 219.9894 -192.2526)
		(end 220.6244 -191.6176)
		(width 0.15494)
		(layer "In7.Cu")
		(net "RST_BIC_I2C9_SSD_MUX0_R_N")
	)
	(segment
		(start 219.413328 -173.822868)
		(end 219.413328 -169.359326)
		(width 0.15494)
		(layer "In7.Cu")
		(net "RST_BIC_I2C9_SSD_MUX0_R_N")
	)
	(segment
		(start 220.726 -194.5132)
		(end 219.9894 -193.7766)
		(width 0.15494)
		(layer "In7.Cu")
		(net "RST_BIC_I2C9_SSD_MUX0_R_N")
	)
	(segment
		(start 220.08592 -200.47966)
		(end 220.08592 -200.07834)
		(width 0.15494)
		(layer "In7.Cu")
		(net "RST_BIC_I2C9_SSD_MUX0_R_N")
	)
	(segment
		(start 219.6338 -197.86473)
		(end 220.726 -196.77253)
		(width 0.15494)
		(layer "In7.Cu")
		(net "RST_BIC_I2C9_SSD_MUX0_R_N")
	)
	(segment
		(start 213.0298 -119.634)
		(end 213.0298 -103.474266)
		(width 0.15494)
		(layer "In7.Cu")
		(net "RST_BIC_I2C9_SSD_MUX0_R_N")
	)
	(segment
		(start 219.413328 -169.359326)
		(end 219.9894 -168.783254)
		(width 0.15494)
		(layer "In7.Cu")
		(net "RST_BIC_I2C9_SSD_MUX0_R_N")
	)
	(segment
		(start 219.094558 -175.911256)
		(end 218.842082 -175.65878)
		(width 0.15494)
		(layer "In7.Cu")
		(net "RST_BIC_I2C9_SSD_MUX0_R_N")
	)
	(segment
		(start 220.62694 -191.6049)
		(end 220.62694 -186.51474)
		(width 0.15494)
		(layer "In7.Cu")
		(net "RST_BIC_I2C9_SSD_MUX0_R_N")
	)
	(segment
		(start 220.6244 -191.6176)
		(end 220.6244 -191.60744)
		(width 0.15494)
		(layer "In7.Cu")
		(net "RST_BIC_I2C9_SSD_MUX0_R_N")
	)
	(segment
		(start 219.31122 -201.254868)
		(end 219.6338 -200.932288)
		(width 0.15494)
		(layer "In7.Cu")
		(net "RST_BIC_I2C9_SSD_MUX0_R_N")
	)
	(segment
		(start 217.5764 -205.14564)
		(end 219.31122 -203.41082)
		(width 0.15494)
		(layer "In7.Cu")
		(net "RST_BIC_I2C9_SSD_MUX0_R_N")
	)
	(segment
		(start 219.31122 -203.41082)
		(end 219.31122 -201.254868)
		(width 0.15494)
		(layer "In7.Cu")
		(net "RST_BIC_I2C9_SSD_MUX0_R_N")
	)
	(segment
		(start 219.9894 -193.7766)
		(end 219.9894 -192.2526)
		(width 0.15494)
		(layer "In7.Cu")
		(net "RST_BIC_I2C9_SSD_MUX0_R_N")
	)
	(segment
		(start 219.9894 -157.674564)
		(end 215.3158 -153.000964)
		(width 0.15494)
		(layer "In7.Cu")
		(net "RST_BIC_I2C9_SSD_MUX0_R_N")
	)
	(segment
		(start 216.674446 -210.059016)
		(end 217.5764 -209.157062)
		(width 0.15494)
		(layer "In7.Cu")
		(net "RST_BIC_I2C9_SSD_MUX0_R_N")
	)
	(segment
		(start 220.726 -196.77253)
		(end 220.726 -194.5132)
		(width 0.15494)
		(layer "In7.Cu")
		(net "RST_BIC_I2C9_SSD_MUX0_R_N")
	)
	(segment
		(start 218.842082 -174.394114)
		(end 219.413328 -173.822868)
		(width 0.15494)
		(layer "In7.Cu")
		(net "RST_BIC_I2C9_SSD_MUX0_R_N")
	)
	(segment
		(start 219.094558 -184.982358)
		(end 219.094558 -175.911256)
		(width 0.15494)
		(layer "In7.Cu")
		(net "RST_BIC_I2C9_SSD_MUX0_R_N")
	)
	(segment
		(start 213.0298 -103.474266)
		(end 215.18626 -101.317806)
		(width 0.15494)
		(layer "In7.Cu")
		(net "RST_BIC_I2C9_SSD_MUX0_R_N")
	)
	(segment
		(start 219.9894 -168.783254)
		(end 219.9894 -157.674564)
		(width 0.15494)
		(layer "In7.Cu")
		(net "RST_BIC_I2C9_SSD_MUX0_R_N")
	)
	(segment
		(start 215.20023 -101.27361)
		(end 215.20023 -92.070682)
		(width 0.15494)
		(layer "In7.Cu")
		(net "RST_BIC_I2C9_SSD_MUX0_R_N")
	)
	(segment
		(start 212.4202 -120.2436)
		(end 213.0298 -119.634)
		(width 0.15494)
		(layer "In7.Cu")
		(net "RST_BIC_I2C9_SSD_MUX0_R_N")
	)
	(segment
		(start 215.18626 -101.28758)
		(end 215.20023 -101.27361)
		(width 0.15494)
		(layer "In7.Cu")
		(net "RST_BIC_I2C9_SSD_MUX0_R_N")
	)
	(segment
		(start 212.4202 -129.463546)
		(end 212.4202 -120.2436)
		(width 0.15494)
		(layer "In7.Cu")
		(net "RST_BIC_I2C9_SSD_MUX0_R_N")
	)
	(segment
		(start 219.6338 -200.93178)
		(end 220.08592 -200.47966)
		(width 0.15494)
		(layer "In7.Cu")
		(net "RST_BIC_I2C9_SSD_MUX0_R_N")
	)
	(segment
		(start 215.20023 -92.070682)
		(end 215.615266 -91.655646)
		(width 0.15494)
		(layer "In7.Cu")
		(net "RST_BIC_I2C9_SSD_MUX0_R_N")
	)
	(segment
		(start 128.651 -96.440498)
		(end 128.67132 -96.440498)
		(width 0.15494)
		(layer "In15.Cu")
		(net "RST_BIC_I2C9_SSD_MUX0_R_N")
	)
	(segment
		(start 156.00553 -89.30767)
		(end 193.066416 -89.30767)
		(width 0.15494)
		(layer "In15.Cu")
		(net "RST_BIC_I2C9_SSD_MUX0_R_N")
	)
	(segment
		(start 213.193376 -91.655646)
		(end 215.615266 -91.655646)
		(width 0.15494)
		(layer "In15.Cu")
		(net "RST_BIC_I2C9_SSD_MUX0_R_N")
	)
	(segment
		(start 212.92693 -91.3892)
		(end 213.193376 -91.655646)
		(width 0.15494)
		(layer "In15.Cu")
		(net "RST_BIC_I2C9_SSD_MUX0_R_N")
	)
	(segment
		(start 132.412486 -100.181664)
		(end 135.96874 -100.181664)
		(width 0.15494)
		(layer "In15.Cu")
		(net "RST_BIC_I2C9_SSD_MUX0_R_N")
	)
	(segment
		(start 135.96874 -100.181664)
		(end 136.944862 -101.157786)
		(width 0.15494)
		(layer "In15.Cu")
		(net "RST_BIC_I2C9_SSD_MUX0_R_N")
	)
	(segment
		(start 195.147946 -91.3892)
		(end 212.92693 -91.3892)
		(width 0.15494)
		(layer "In15.Cu")
		(net "RST_BIC_I2C9_SSD_MUX0_R_N")
	)
	(segment
		(start 128.67132 -96.440498)
		(end 132.412486 -100.181664)
		(width 0.15494)
		(layer "In15.Cu")
		(net "RST_BIC_I2C9_SSD_MUX0_R_N")
	)
	(segment
		(start 193.066416 -89.30767)
		(end 195.147946 -91.3892)
		(width 0.15494)
		(layer "In15.Cu")
		(net "RST_BIC_I2C9_SSD_MUX0_R_N")
	)
	(segment
		(start 136.944862 -101.157786)
		(end 144.155414 -101.157786)
		(width 0.15494)
		(layer "In15.Cu")
		(net "RST_BIC_I2C9_SSD_MUX0_R_N")
	)
	(segment
		(start 144.155414 -101.157786)
		(end 156.00553 -89.30767)
		(width 0.15494)
		(layer "In15.Cu")
		(net "RST_BIC_I2C9_SSD_MUX0_R_N")
	)
	(segment
		(start 347.091 -234.46105)
		(end 347.091 -235.077)
		(width 0.13208)
		(layer "F.Cu")
		(net "RST_SSD5_PERST_R_N")
	)
	(segment
		(start 156.30398 -24.189944)
		(end 157.364938 -24.189944)
		(width 0.13208)
		(layer "F.Cu")
		(net "RST_SSD5_PERST_R_N")
	)
	(via
		(at 347.091 -235.077)
		(size 0.508)
		(drill 0.254)
		(layers "F.Cu" "B.Cu")
		(net "RST_SSD5_PERST_R_N")
	)
	(via
		(at 156.30398 -24.189944)
		(size 0.508)
		(drill 0.254)
		(layers "F.Cu" "B.Cu")
		(net "RST_SSD5_PERST_R_N")
	)
	(via
		(at 184.199276 -239.286542)
		(size 0.508)
		(drill 0.254)
		(layers "F.Cu" "B.Cu")
		(net "RST_SSD5_PERST_R_N")
	)
	(segment
		(start 184.199276 -228.918516)
		(end 184.199276 -239.286542)
		(width 0.15494)
		(layer "In5.Cu")
		(net "RST_SSD5_PERST_R_N")
	)
	(segment
		(start 182.624476 -221.069408)
		(end 182.624476 -227.191062)
		(width 0.15494)
		(layer "In5.Cu")
		(net "RST_SSD5_PERST_R_N")
	)
	(segment
		(start 163.132262 -27.455114)
		(end 166.037514 -27.455114)
		(width 0.15494)
		(layer "In5.Cu")
		(net "RST_SSD5_PERST_R_N")
	)
	(segment
		(start 156.30398 -24.189944)
		(end 157.04439 -24.930354)
		(width 0.15494)
		(layer "In5.Cu")
		(net "RST_SSD5_PERST_R_N")
	)
	(segment
		(start 161.102548 -26.9494)
		(end 162.626548 -26.9494)
		(width 0.15494)
		(layer "In5.Cu")
		(net "RST_SSD5_PERST_R_N")
	)
	(segment
		(start 166.8018 -28.2194)
		(end 166.8018 -28.944824)
		(width 0.15494)
		(layer "In5.Cu")
		(net "RST_SSD5_PERST_R_N")
	)
	(segment
		(start 182.685436 -227.404676)
		(end 184.199276 -228.918516)
		(width 0.15494)
		(layer "In5.Cu")
		(net "RST_SSD5_PERST_R_N")
	)
	(segment
		(start 157.04439 -24.930354)
		(end 159.083502 -24.930354)
		(width 0.15494)
		(layer "In5.Cu")
		(net "RST_SSD5_PERST_R_N")
	)
	(segment
		(start 166.35857 -32.912304)
		(end 178.74488 -45.298614)
		(width 0.15494)
		(layer "In5.Cu")
		(net "RST_SSD5_PERST_R_N")
	)
	(segment
		(start 166.037514 -27.455114)
		(end 166.8018 -28.2194)
		(width 0.15494)
		(layer "In5.Cu")
		(net "RST_SSD5_PERST_R_N")
	)
	(segment
		(start 175.0822 -181.3814)
		(end 176.68621 -182.98541)
		(width 0.15494)
		(layer "In5.Cu")
		(net "RST_SSD5_PERST_R_N")
	)
	(segment
		(start 178.74488 -78.961234)
		(end 172.678344 -85.02777)
		(width 0.15494)
		(layer "In5.Cu")
		(net "RST_SSD5_PERST_R_N")
	)
	(segment
		(start 178.540156 -202.669902)
		(end 178.540156 -210.13928)
		(width 0.15494)
		(layer "In5.Cu")
		(net "RST_SSD5_PERST_R_N")
	)
	(segment
		(start 159.083502 -24.930354)
		(end 161.102548 -26.9494)
		(width 0.15494)
		(layer "In5.Cu")
		(net "RST_SSD5_PERST_R_N")
	)
	(segment
		(start 182.685436 -227.252022)
		(end 182.685436 -227.404676)
		(width 0.15494)
		(layer "In5.Cu")
		(net "RST_SSD5_PERST_R_N")
	)
	(segment
		(start 176.68621 -200.815956)
		(end 178.540156 -202.669902)
		(width 0.15494)
		(layer "In5.Cu")
		(net "RST_SSD5_PERST_R_N")
	)
	(segment
		(start 178.74488 -45.298614)
		(end 178.74488 -78.961234)
		(width 0.15494)
		(layer "In5.Cu")
		(net "RST_SSD5_PERST_R_N")
	)
	(segment
		(start 182.624476 -227.191062)
		(end 182.685436 -227.252022)
		(width 0.15494)
		(layer "In5.Cu")
		(net "RST_SSD5_PERST_R_N")
	)
	(segment
		(start 178.580796 -211.307426)
		(end 182.624476 -221.069408)
		(width 0.15494)
		(layer "In5.Cu")
		(net "RST_SSD5_PERST_R_N")
	)
	(segment
		(start 172.678344 -87.419942)
		(end 175.0822 -89.823798)
		(width 0.15494)
		(layer "In5.Cu")
		(net "RST_SSD5_PERST_R_N")
	)
	(segment
		(start 176.68621 -182.98541)
		(end 176.68621 -200.815956)
		(width 0.15494)
		(layer "In5.Cu")
		(net "RST_SSD5_PERST_R_N")
	)
	(segment
		(start 172.678344 -85.02777)
		(end 172.678344 -87.419942)
		(width 0.15494)
		(layer "In5.Cu")
		(net "RST_SSD5_PERST_R_N")
	)
	(segment
		(start 166.8018 -28.944824)
		(end 166.35857 -29.388054)
		(width 0.15494)
		(layer "In5.Cu")
		(net "RST_SSD5_PERST_R_N")
	)
	(segment
		(start 178.580796 -210.237578)
		(end 178.580796 -211.307426)
		(width 0.15494)
		(layer "In5.Cu")
		(net "RST_SSD5_PERST_R_N")
	)
	(segment
		(start 162.626548 -26.9494)
		(end 163.132262 -27.455114)
		(width 0.15494)
		(layer "In5.Cu")
		(net "RST_SSD5_PERST_R_N")
	)
	(segment
		(start 166.35857 -29.388054)
		(end 166.35857 -32.912304)
		(width 0.15494)
		(layer "In5.Cu")
		(net "RST_SSD5_PERST_R_N")
	)
	(segment
		(start 175.0822 -89.823798)
		(end 175.0822 -181.3814)
		(width 0.15494)
		(layer "In5.Cu")
		(net "RST_SSD5_PERST_R_N")
	)
	(segment
		(start 178.540156 -210.13928)
		(end 178.580796 -210.237578)
		(width 0.15494)
		(layer "In5.Cu")
		(net "RST_SSD5_PERST_R_N")
	)
	(segment
		(start 220.496638 -245.754398)
		(end 190.107316 -245.754398)
		(width 0.15494)
		(layer "In15.Cu")
		(net "RST_SSD5_PERST_R_N")
	)
	(segment
		(start 236.690154 -246.04726)
		(end 236.484414 -246.253)
		(width 0.15494)
		(layer "In15.Cu")
		(net "RST_SSD5_PERST_R_N")
	)
	(segment
		(start 274.519898 -246.145812)
		(end 274.22348 -245.849394)
		(width 0.15494)
		(layer "In15.Cu")
		(net "RST_SSD5_PERST_R_N")
	)
	(segment
		(start 190.107316 -245.754398)
		(end 185.62447 -241.271552)
		(width 0.15494)
		(layer "In15.Cu")
		(net "RST_SSD5_PERST_R_N")
	)
	(segment
		(start 347.091 -235.077)
		(end 346.55887 -235.60913)
		(width 0.15494)
		(layer "In15.Cu")
		(net "RST_SSD5_PERST_R_N")
	)
	(segment
		(start 304.142902 -247.228106)
		(end 303.068228 -247.673368)
		(width 0.15494)
		(layer "In15.Cu")
		(net "RST_SSD5_PERST_R_N")
	)
	(segment
		(start 303.068228 -247.673368)
		(end 300.589188 -247.673368)
		(width 0.15494)
		(layer "In15.Cu")
		(net "RST_SSD5_PERST_R_N")
	)
	(segment
		(start 328.581004 -247.228106)
		(end 304.142902 -247.228106)
		(width 0.15494)
		(layer "In15.Cu")
		(net "RST_SSD5_PERST_R_N")
	)
	(segment
		(start 346.42806 -239.866424)
		(end 339.071204 -247.22328)
		(width 0.15494)
		(layer "In15.Cu")
		(net "RST_SSD5_PERST_R_N")
	)
	(segment
		(start 253.548388 -245.096284)
		(end 239.404144 -245.096284)
		(width 0.15494)
		(layer "In15.Cu")
		(net "RST_SSD5_PERST_R_N")
	)
	(segment
		(start 232.056432 -247.132602)
		(end 230.81488 -245.89105)
		(width 0.15494)
		(layer "In15.Cu")
		(net "RST_SSD5_PERST_R_N")
	)
	(segment
		(start 223.665542 -245.89105)
		(end 223.230694 -245.456202)
		(width 0.15494)
		(layer "In15.Cu")
		(net "RST_SSD5_PERST_R_N")
	)
	(segment
		(start 238.453168 -246.04726)
		(end 236.690154 -246.04726)
		(width 0.15494)
		(layer "In15.Cu")
		(net "RST_SSD5_PERST_R_N")
	)
	(segment
		(start 299.061632 -246.145812)
		(end 274.519898 -246.145812)
		(width 0.15494)
		(layer "In15.Cu")
		(net "RST_SSD5_PERST_R_N")
	)
	(segment
		(start 239.404144 -245.096284)
		(end 238.453168 -246.04726)
		(width 0.15494)
		(layer "In15.Cu")
		(net "RST_SSD5_PERST_R_N")
	)
	(segment
		(start 234.527598 -247.132602)
		(end 232.056432 -247.132602)
		(width 0.15494)
		(layer "In15.Cu")
		(net "RST_SSD5_PERST_R_N")
	)
	(segment
		(start 346.466922 -239.06226)
		(end 346.42806 -239.101122)
		(width 0.15494)
		(layer "In15.Cu")
		(net "RST_SSD5_PERST_R_N")
	)
	(segment
		(start 223.230694 -245.456202)
		(end 220.794834 -245.456202)
		(width 0.15494)
		(layer "In15.Cu")
		(net "RST_SSD5_PERST_R_N")
	)
	(segment
		(start 274.22348 -245.849394)
		(end 254.301498 -245.849394)
		(width 0.15494)
		(layer "In15.Cu")
		(net "RST_SSD5_PERST_R_N")
	)
	(segment
		(start 230.81488 -245.89105)
		(end 223.665542 -245.89105)
		(width 0.15494)
		(layer "In15.Cu")
		(net "RST_SSD5_PERST_R_N")
	)
	(segment
		(start 235.4072 -246.253)
		(end 234.527598 -247.132602)
		(width 0.15494)
		(layer "In15.Cu")
		(net "RST_SSD5_PERST_R_N")
	)
	(segment
		(start 332.975966 -247.22328)
		(end 332.820772 -247.378474)
		(width 0.15494)
		(layer "In15.Cu")
		(net "RST_SSD5_PERST_R_N")
	)
	(segment
		(start 346.466922 -238.42599)
		(end 346.466922 -239.06226)
		(width 0.15494)
		(layer "In15.Cu")
		(net "RST_SSD5_PERST_R_N")
	)
	(segment
		(start 346.42806 -239.101122)
		(end 346.42806 -239.866424)
		(width 0.15494)
		(layer "In15.Cu")
		(net "RST_SSD5_PERST_R_N")
	)
	(segment
		(start 339.071204 -247.22328)
		(end 332.975966 -247.22328)
		(width 0.15494)
		(layer "In15.Cu")
		(net "RST_SSD5_PERST_R_N")
	)
	(segment
		(start 236.484414 -246.253)
		(end 235.4072 -246.253)
		(width 0.15494)
		(layer "In15.Cu")
		(net "RST_SSD5_PERST_R_N")
	)
	(segment
		(start 332.820772 -247.378474)
		(end 328.731372 -247.378474)
		(width 0.15494)
		(layer "In15.Cu")
		(net "RST_SSD5_PERST_R_N")
	)
	(segment
		(start 254.301498 -245.849394)
		(end 253.548388 -245.096284)
		(width 0.15494)
		(layer "In15.Cu")
		(net "RST_SSD5_PERST_R_N")
	)
	(segment
		(start 300.589188 -247.673368)
		(end 299.061632 -246.145812)
		(width 0.15494)
		(layer "In15.Cu")
		(net "RST_SSD5_PERST_R_N")
	)
	(segment
		(start 184.221882 -239.286542)
		(end 184.199276 -239.286542)
		(width 0.15494)
		(layer "In15.Cu")
		(net "RST_SSD5_PERST_R_N")
	)
	(segment
		(start 220.794834 -245.456202)
		(end 220.496638 -245.754398)
		(width 0.15494)
		(layer "In15.Cu")
		(net "RST_SSD5_PERST_R_N")
	)
	(segment
		(start 346.55887 -235.60913)
		(end 346.55887 -238.334042)
		(width 0.15494)
		(layer "In15.Cu")
		(net "RST_SSD5_PERST_R_N")
	)
	(segment
		(start 185.62447 -241.271552)
		(end 185.62447 -240.68913)
		(width 0.15494)
		(layer "In15.Cu")
		(net "RST_SSD5_PERST_R_N")
	)
	(segment
		(start 185.62447 -240.68913)
		(end 184.221882 -239.286542)
		(width 0.15494)
		(layer "In15.Cu")
		(net "RST_SSD5_PERST_R_N")
	)
	(segment
		(start 328.731372 -247.378474)
		(end 328.581004 -247.228106)
		(width 0.15494)
		(layer "In15.Cu")
		(net "RST_SSD5_PERST_R_N")
	)
	(segment
		(start 346.55887 -238.334042)
		(end 346.466922 -238.42599)
		(width 0.15494)
		(layer "In15.Cu")
		(net "RST_SSD5_PERST_R_N")
	)
	(segment
		(start 343.662 -208.153)
		(end 343.662 -206.8068)
		(width 0.13208)
		(layer "F.Cu")
		(net "SSD14_PWR_EN")
	)
	(segment
		(start 342.093804 -209.721196)
		(end 343.662 -208.153)
		(width 0.13208)
		(layer "F.Cu")
		(net "SSD14_PWR_EN")
	)
	(segment
		(start 343.662 -206.8068)
		(end 343.662 -205.63205)
		(width 0.13208)
		(layer "F.Cu")
		(net "SSD14_PWR_EN")
	)
	(segment
		(start 342.093804 -211.18703)
		(end 342.093804 -209.721196)
		(width 0.13208)
		(layer "F.Cu")
		(net "SSD14_PWR_EN")
	)
	(via
		(at 343.662 -206.8068)
		(size 0.762)
		(drill 0.381)
		(layers "F.Cu" "B.Cu")
		(net "SSD14_PWR_EN")
	)
	(segment
		(start 215.173052 -218.302586)
		(end 216.835736 -218.302586)
		(width 0.13208)
		(layer "F.Cu")
		(net "SMB_NIC5_R_SCL")
	)
	(segment
		(start 209.382868 -201.24801)
		(end 210.518756 -201.24801)
		(width 0.13208)
		(layer "F.Cu")
		(net "SMB_NIC5_R_SCL")
	)
	(segment
		(start 210.518756 -201.24801)
		(end 210.83905 -201.568304)
		(width 0.13208)
		(layer "F.Cu")
		(net "SMB_NIC5_R_SCL")
	)
	(segment
		(start 211.1248 -201.803)
		(end 210.83905 -201.803)
		(width 0.13208)
		(layer "F.Cu")
		(net "SMB_NIC5_R_SCL")
	)
	(segment
		(start 210.83905 -201.568304)
		(end 210.83905 -201.803)
		(width 0.13208)
		(layer "F.Cu")
		(net "SMB_NIC5_R_SCL")
	)
	(segment
		(start 211.68868 -202.36688)
		(end 211.1248 -201.803)
		(width 0.13208)
		(layer "F.Cu")
		(net "SMB_NIC5_R_SCL")
	)
	(segment
		(start 212.522054 -202.36688)
		(end 211.68868 -202.36688)
		(width 0.13208)
		(layer "F.Cu")
		(net "SMB_NIC5_R_SCL")
	)
	(via
		(at 209.382868 -201.24801)
		(size 0.508)
		(drill 0.254)
		(layers "F.Cu" "B.Cu")
		(net "SMB_NIC5_R_SCL")
	)
	(via
		(at 215.173052 -218.302586)
		(size 0.508)
		(drill 0.254)
		(layers "F.Cu" "B.Cu")
		(net "SMB_NIC5_R_SCL")
	)
	(segment
		(start 210.083908 -201.94905)
		(end 209.382868 -201.24801)
		(width 0.13208)
		(layer "B.Cu")
		(net "SMB_NIC5_R_SCL")
	)
	(segment
		(start 212.09 -201.94905)
		(end 210.083908 -201.94905)
		(width 0.13208)
		(layer "B.Cu")
		(net "SMB_NIC5_R_SCL")
	)
	(segment
		(start 211.39404 -207.2386)
		(end 211.39404 -209.43316)
		(width 0.15494)
		(layer "In7.Cu")
		(net "SMB_NIC5_R_SCL")
	)
	(segment
		(start 211.39404 -209.43316)
		(end 210.274408 -210.552792)
		(width 0.15494)
		(layer "In7.Cu")
		(net "SMB_NIC5_R_SCL")
	)
	(segment
		(start 208.93913 -201.691748)
		(end 208.93913 -204.78369)
		(width 0.15494)
		(layer "In7.Cu")
		(net "SMB_NIC5_R_SCL")
	)
	(segment
		(start 215.494616 -216.97061)
		(end 215.494616 -217.981022)
		(width 0.15494)
		(layer "In7.Cu")
		(net "SMB_NIC5_R_SCL")
	)
	(segment
		(start 209.382868 -201.24801)
		(end 208.93913 -201.691748)
		(width 0.15494)
		(layer "In7.Cu")
		(net "SMB_NIC5_R_SCL")
	)
	(segment
		(start 210.82 -214.833454)
		(end 210.82 -215.646254)
		(width 0.15494)
		(layer "In7.Cu")
		(net "SMB_NIC5_R_SCL")
	)
	(segment
		(start 215.313006 -216.789)
		(end 215.494616 -216.97061)
		(width 0.15494)
		(layer "In7.Cu")
		(net "SMB_NIC5_R_SCL")
	)
	(segment
		(start 211.962746 -216.789)
		(end 215.313006 -216.789)
		(width 0.15494)
		(layer "In7.Cu")
		(net "SMB_NIC5_R_SCL")
	)
	(segment
		(start 215.494616 -217.981022)
		(end 215.173052 -218.302586)
		(width 0.15494)
		(layer "In7.Cu")
		(net "SMB_NIC5_R_SCL")
	)
	(segment
		(start 210.274408 -210.552792)
		(end 210.274408 -214.287862)
		(width 0.15494)
		(layer "In7.Cu")
		(net "SMB_NIC5_R_SCL")
	)
	(segment
		(start 208.93913 -204.78369)
		(end 211.39404 -207.2386)
		(width 0.15494)
		(layer "In7.Cu")
		(net "SMB_NIC5_R_SCL")
	)
	(segment
		(start 210.274408 -214.287862)
		(end 210.82 -214.833454)
		(width 0.15494)
		(layer "In7.Cu")
		(net "SMB_NIC5_R_SCL")
	)
	(segment
		(start 210.82 -215.646254)
		(end 211.962746 -216.789)
		(width 0.15494)
		(layer "In7.Cu")
		(net "SMB_NIC5_R_SCL")
	)
	(segment
		(start 129.39522 -187.941966)
		(end 129.114296 -188.22289)
		(width 0.13462)
		(layer "F.Cu")
		(net "CLK_100M_DB2000QL_GPU_REF2_R_DN")
	)
	(segment
		(start 130.23088 -185.421524)
		(end 130.23088 -186.017662)
		(width 0.13462)
		(layer "F.Cu")
		(net "CLK_100M_DB2000QL_GPU_REF2_R_DN")
	)
	(segment
		(start 129.86639 -185.057034)
		(end 130.23088 -185.421524)
		(width 0.13462)
		(layer "F.Cu")
		(net "CLK_100M_DB2000QL_GPU_REF2_R_DN")
	)
	(segment
		(start 130.23088 -186.017662)
		(end 129.39522 -186.853322)
		(width 0.13462)
		(layer "F.Cu")
		(net "CLK_100M_DB2000QL_GPU_REF2_R_DN")
	)
	(segment
		(start 129.39522 -186.853322)
		(end 129.39522 -187.941966)
		(width 0.13462)
		(layer "F.Cu")
		(net "CLK_100M_DB2000QL_GPU_REF2_R_DN")
	)
	(via
		(at 129.114296 -188.22289)
		(size 0.508)
		(drill 0.254)
		(layers "F.Cu" "B.Cu")
		(net "CLK_100M_DB2000QL_GPU_REF2_R_DN")
	)
	(segment
		(start 97.528634 -192.3796)
		(end 108.204 -192.3796)
		(width 0.13462)
		(layer "B.Cu")
		(net "CLK_100M_DB2000QL_GPU_REF2_R_DN")
	)
	(segment
		(start 18.11528 -261.634986)
		(end 18.11528 -250.295664)
		(width 0.13462)
		(layer "B.Cu")
		(net "CLK_100M_DB2000QL_GPU_REF2_R_DN")
	)
	(segment
		(start 20.912582 -268.388338)
		(end 18.11528 -261.634986)
		(width 0.13462)
		(layer "B.Cu")
		(net "CLK_100M_DB2000QL_GPU_REF2_R_DN")
	)
	(segment
		(start 113.582196 -187.001404)
		(end 123.839986 -187.001404)
		(width 0.13462)
		(layer "B.Cu")
		(net "CLK_100M_DB2000QL_GPU_REF2_R_DN")
	)
	(segment
		(start 125.829822 -188.990732)
		(end 129.238502 -188.990732)
		(width 0.13462)
		(layer "B.Cu")
		(net "CLK_100M_DB2000QL_GPU_REF2_R_DN")
	)
	(segment
		(start 25.18283 -326.854058)
		(end 21.21408 -322.885054)
		(width 0.13462)
		(layer "B.Cu")
		(net "CLK_100M_DB2000QL_GPU_REF2_R_DN")
	)
	(segment
		(start 49.310544 -219.1004)
		(end 64.4144 -219.1004)
		(width 0.13462)
		(layer "B.Cu")
		(net "CLK_100M_DB2000QL_GPU_REF2_R_DN")
	)
	(segment
		(start 64.4144 -219.1004)
		(end 89.8398 -193.675)
		(width 0.13462)
		(layer "B.Cu")
		(net "CLK_100M_DB2000QL_GPU_REF2_R_DN")
	)
	(segment
		(start 23.527512 -296.679366)
		(end 23.527512 -277.883112)
		(width 0.13462)
		(layer "B.Cu")
		(net "CLK_100M_DB2000QL_GPU_REF2_R_DN")
	)
	(segment
		(start 45.400722 -401.183602)
		(end 44.588938 -401.183602)
		(width 0.13462)
		(layer "B.Cu")
		(net "CLK_100M_DB2000QL_GPU_REF2_R_DN")
	)
	(segment
		(start 21.21408 -308.224174)
		(end 25.480264 -303.95799)
		(width 0.13462)
		(layer "B.Cu")
		(net "CLK_100M_DB2000QL_GPU_REF2_R_DN")
	)
	(segment
		(start 46.0502 -342.061546)
		(end 45.562012 -341.124286)
		(width 0.13462)
		(layer "B.Cu")
		(net "CLK_100M_DB2000QL_GPU_REF2_R_DN")
	)
	(segment
		(start 129.238502 -188.990732)
		(end 129.408936 -188.820298)
		(width 0.13462)
		(layer "B.Cu")
		(net "CLK_100M_DB2000QL_GPU_REF2_R_DN")
	)
	(segment
		(start 129.408936 -188.51753)
		(end 129.114296 -188.22289)
		(width 0.13462)
		(layer "B.Cu")
		(net "CLK_100M_DB2000QL_GPU_REF2_R_DN")
	)
	(segment
		(start 44.048426 -400.64309)
		(end 44.048426 -391.605008)
		(width 0.13462)
		(layer "B.Cu")
		(net "CLK_100M_DB2000QL_GPU_REF2_R_DN")
	)
	(segment
		(start 45.509942 -401.690078)
		(end 45.509942 -401.292822)
		(width 0.13462)
		(layer "B.Cu")
		(net "CLK_100M_DB2000QL_GPU_REF2_R_DN")
	)
	(segment
		(start 21.21408 -322.885054)
		(end 21.21408 -308.224174)
		(width 0.13462)
		(layer "B.Cu")
		(net "CLK_100M_DB2000QL_GPU_REF2_R_DN")
	)
	(segment
		(start 25.480264 -303.95799)
		(end 25.480264 -298.632118)
		(width 0.13462)
		(layer "B.Cu")
		(net "CLK_100M_DB2000QL_GPU_REF2_R_DN")
	)
	(segment
		(start 45.509942 -401.292822)
		(end 45.400722 -401.183602)
		(width 0.13462)
		(layer "B.Cu")
		(net "CLK_100M_DB2000QL_GPU_REF2_R_DN")
	)
	(segment
		(start 129.408936 -188.820298)
		(end 129.408936 -188.51753)
		(width 0.13462)
		(layer "B.Cu")
		(net "CLK_100M_DB2000QL_GPU_REF2_R_DN")
	)
	(segment
		(start 96.233234 -193.675)
		(end 97.528634 -192.3796)
		(width 0.13462)
		(layer "B.Cu")
		(net "CLK_100M_DB2000QL_GPU_REF2_R_DN")
	)
	(segment
		(start 18.11528 -250.295664)
		(end 49.310544 -219.1004)
		(width 0.13462)
		(layer "B.Cu")
		(net "CLK_100M_DB2000QL_GPU_REF2_R_DN")
	)
	(segment
		(start 20.912582 -275.268182)
		(end 20.912582 -268.388338)
		(width 0.13462)
		(layer "B.Cu")
		(net "CLK_100M_DB2000QL_GPU_REF2_R_DN")
	)
	(segment
		(start 25.480264 -298.632118)
		(end 23.527512 -296.679366)
		(width 0.13462)
		(layer "B.Cu")
		(net "CLK_100M_DB2000QL_GPU_REF2_R_DN")
	)
	(segment
		(start 23.527512 -277.883112)
		(end 20.912582 -275.268182)
		(width 0.13462)
		(layer "B.Cu")
		(net "CLK_100M_DB2000QL_GPU_REF2_R_DN")
	)
	(segment
		(start 49.81448 -365.746792)
		(end 46.0502 -361.982512)
		(width 0.13462)
		(layer "B.Cu")
		(net "CLK_100M_DB2000QL_GPU_REF2_R_DN")
	)
	(segment
		(start 123.839986 -187.001404)
		(end 125.829822 -188.990732)
		(width 0.13462)
		(layer "B.Cu")
		(net "CLK_100M_DB2000QL_GPU_REF2_R_DN")
	)
	(segment
		(start 108.204 -192.3796)
		(end 113.582196 -187.001404)
		(width 0.13462)
		(layer "B.Cu")
		(net "CLK_100M_DB2000QL_GPU_REF2_R_DN")
	)
	(segment
		(start 44.048426 -391.605008)
		(end 49.81448 -385.838954)
		(width 0.13462)
		(layer "B.Cu")
		(net "CLK_100M_DB2000QL_GPU_REF2_R_DN")
	)
	(segment
		(start 46.0502 -361.982512)
		(end 46.0502 -342.061546)
		(width 0.13462)
		(layer "B.Cu")
		(net "CLK_100M_DB2000QL_GPU_REF2_R_DN")
	)
	(segment
		(start 49.81448 -385.838954)
		(end 49.81448 -365.746792)
		(width 0.13462)
		(layer "B.Cu")
		(net "CLK_100M_DB2000QL_GPU_REF2_R_DN")
	)
	(segment
		(start 45.562012 -341.124286)
		(end 25.18283 -326.854058)
		(width 0.13462)
		(layer "B.Cu")
		(net "CLK_100M_DB2000QL_GPU_REF2_R_DN")
	)
	(segment
		(start 44.588938 -401.183602)
		(end 44.048426 -400.64309)
		(width 0.13462)
		(layer "B.Cu")
		(net "CLK_100M_DB2000QL_GPU_REF2_R_DN")
	)
	(segment
		(start 89.8398 -193.675)
		(end 96.233234 -193.675)
		(width 0.13462)
		(layer "B.Cu")
		(net "CLK_100M_DB2000QL_GPU_REF2_R_DN")
	)
	(segment
		(start 334.264 -235.585)
		(end 333.502 -235.585)
		(width 0.13208)
		(layer "F.Cu")
		(net "MB_SWB_PWRGD")
	)
	(segment
		(start 335.29016 -227.583238)
		(end 335.29016 -228.20884)
		(width 0.13208)
		(layer "F.Cu")
		(net "MB_SWB_PWRGD")
	)
	(segment
		(start 333.502 -235.585)
		(end 333.121 -235.204)
		(width 0.13208)
		(layer "F.Cu")
		(net "MB_SWB_PWRGD")
	)
	(segment
		(start 334.89392 -227.186998)
		(end 335.29016 -227.583238)
		(width 0.13208)
		(layer "F.Cu")
		(net "MB_SWB_PWRGD")
	)
	(segment
		(start 334.264 -229.235)
		(end 334.264 -229.489)
		(width 0.13208)
		(layer "F.Cu")
		(net "MB_SWB_PWRGD")
	)
	(segment
		(start 334.518 -236.45495)
		(end 334.518 -235.839)
		(width 0.13208)
		(layer "F.Cu")
		(net "MB_SWB_PWRGD")
	)
	(segment
		(start 333.121 -230.632)
		(end 333.883 -229.87)
		(width 0.13208)
		(layer "F.Cu")
		(net "MB_SWB_PWRGD")
	)
	(segment
		(start 335.29016 -228.20884)
		(end 334.264 -229.235)
		(width 0.13208)
		(layer "F.Cu")
		(net "MB_SWB_PWRGD")
	)
	(segment
		(start 334.518 -235.839)
		(end 334.264 -235.585)
		(width 0.13208)
		(layer "F.Cu")
		(net "MB_SWB_PWRGD")
	)
	(segment
		(start 334.264 -229.489)
		(end 333.883 -229.87)
		(width 0.13208)
		(layer "F.Cu")
		(net "MB_SWB_PWRGD")
	)
	(segment
		(start 333.121 -235.204)
		(end 333.121 -230.632)
		(width 0.13208)
		(layer "F.Cu")
		(net "MB_SWB_PWRGD")
	)
	(via
		(at 333.883 -229.87)
		(size 0.508)
		(drill 0.254)
		(layers "F.Cu" "B.Cu")
		(net "MB_SWB_PWRGD")
	)
	(segment
		(start 111.038894 -89.40673)
		(end 111.038894 -88.928956)
		(width 0.13208)
		(layer "F.Cu")
		(net "SSD6_CLK_EN_R_N")
	)
	(segment
		(start 111.896652 -90.264488)
		(end 111.038894 -89.40673)
		(width 0.13208)
		(layer "F.Cu")
		(net "SSD6_CLK_EN_R_N")
	)
	(segment
		(start 349.123 -234.46105)
		(end 349.123 -235.043472)
		(width 0.13208)
		(layer "F.Cu")
		(net "SSD6_CLK_EN_R_N")
	)
	(segment
		(start 349.123 -235.043472)
		(end 349.089726 -235.076746)
		(width 0.13208)
		(layer "F.Cu")
		(net "SSD6_CLK_EN_R_N")
	)
	(via
		(at 97.705164 -206.782162)
		(size 0.508)
		(drill 0.254)
		(layers "F.Cu" "B.Cu")
		(net "SSD6_CLK_EN_R_N")
	)
	(via
		(at 79.328264 -90.613738)
		(size 0.508)
		(drill 0.254)
		(layers "F.Cu" "B.Cu")
		(net "SSD6_CLK_EN_R_N")
	)
	(via
		(at 111.896652 -90.264488)
		(size 0.508)
		(drill 0.254)
		(layers "F.Cu" "B.Cu")
		(net "SSD6_CLK_EN_R_N")
	)
	(via
		(at 349.089726 -235.076746)
		(size 0.508)
		(drill 0.254)
		(layers "F.Cu" "B.Cu")
		(net "SSD6_CLK_EN_R_N")
	)
	(segment
		(start 89.28354 -131.08813)
		(end 89.28354 -134.228586)
		(width 0.15494)
		(layer "In5.Cu")
		(net "SSD6_CLK_EN_R_N")
	)
	(segment
		(start 79.328264 -91.976448)
		(end 79.751682 -92.399866)
		(width 0.15494)
		(layer "In5.Cu")
		(net "SSD6_CLK_EN_R_N")
	)
	(segment
		(start 78.479396 -108.440474)
		(end 78.479396 -115.146328)
		(width 0.15494)
		(layer "In5.Cu")
		(net "SSD6_CLK_EN_R_N")
	)
	(segment
		(start 79.328264 -90.613738)
		(end 79.328264 -91.976448)
		(width 0.15494)
		(layer "In5.Cu")
		(net "SSD6_CLK_EN_R_N")
	)
	(segment
		(start 97.959164 -206.528162)
		(end 97.705164 -206.782162)
		(width 0.15494)
		(layer "In5.Cu")
		(net "SSD6_CLK_EN_R_N")
	)
	(segment
		(start 80.63103 -117.297962)
		(end 83.500214 -117.297962)
		(width 0.15494)
		(layer "In5.Cu")
		(net "SSD6_CLK_EN_R_N")
	)
	(segment
		(start 89.28354 -134.228586)
		(end 92.64142 -142.33525)
		(width 0.15494)
		(layer "In5.Cu")
		(net "SSD6_CLK_EN_R_N")
	)
	(segment
		(start 99.80803 -204.30617)
		(end 97.959164 -206.155036)
		(width 0.15494)
		(layer "In5.Cu")
		(net "SSD6_CLK_EN_R_N")
	)
	(segment
		(start 92.64142 -178.38801)
		(end 94.135448 -179.882038)
		(width 0.15494)
		(layer "In5.Cu")
		(net "SSD6_CLK_EN_R_N")
	)
	(segment
		(start 83.500214 -117.297962)
		(end 86.10854 -119.906288)
		(width 0.15494)
		(layer "In5.Cu")
		(net "SSD6_CLK_EN_R_N")
	)
	(segment
		(start 86.10854 -127.91313)
		(end 89.28354 -131.08813)
		(width 0.15494)
		(layer "In5.Cu")
		(net "SSD6_CLK_EN_R_N")
	)
	(segment
		(start 79.751682 -92.399866)
		(end 79.751682 -107.168188)
		(width 0.15494)
		(layer "In5.Cu")
		(net "SSD6_CLK_EN_R_N")
	)
	(segment
		(start 97.959164 -206.155036)
		(end 97.959164 -206.528162)
		(width 0.15494)
		(layer "In5.Cu")
		(net "SSD6_CLK_EN_R_N")
	)
	(segment
		(start 94.135448 -179.882038)
		(end 94.135448 -186.008264)
		(width 0.15494)
		(layer "In5.Cu")
		(net "SSD6_CLK_EN_R_N")
	)
	(segment
		(start 86.10854 -119.906288)
		(end 86.10854 -127.91313)
		(width 0.15494)
		(layer "In5.Cu")
		(net "SSD6_CLK_EN_R_N")
	)
	(segment
		(start 94.135448 -186.008264)
		(end 98.044 -189.916816)
		(width 0.15494)
		(layer "In5.Cu")
		(net "SSD6_CLK_EN_R_N")
	)
	(segment
		(start 102.559104 -198.164704)
		(end 102.559104 -203.856336)
		(width 0.15494)
		(layer "In5.Cu")
		(net "SSD6_CLK_EN_R_N")
	)
	(segment
		(start 79.751682 -107.168188)
		(end 78.479396 -108.440474)
		(width 0.15494)
		(layer "In5.Cu")
		(net "SSD6_CLK_EN_R_N")
	)
	(segment
		(start 98.044 -193.6496)
		(end 102.559104 -198.164704)
		(width 0.15494)
		(layer "In5.Cu")
		(net "SSD6_CLK_EN_R_N")
	)
	(segment
		(start 78.479396 -115.146328)
		(end 80.63103 -117.297962)
		(width 0.15494)
		(layer "In5.Cu")
		(net "SSD6_CLK_EN_R_N")
	)
	(segment
		(start 98.044 -189.916816)
		(end 98.044 -193.6496)
		(width 0.15494)
		(layer "In5.Cu")
		(net "SSD6_CLK_EN_R_N")
	)
	(segment
		(start 102.10927 -204.30617)
		(end 99.80803 -204.30617)
		(width 0.15494)
		(layer "In5.Cu")
		(net "SSD6_CLK_EN_R_N")
	)
	(segment
		(start 102.559104 -203.856336)
		(end 102.10927 -204.30617)
		(width 0.15494)
		(layer "In5.Cu")
		(net "SSD6_CLK_EN_R_N")
	)
	(segment
		(start 92.64142 -142.33525)
		(end 92.64142 -178.38801)
		(width 0.15494)
		(layer "In5.Cu")
		(net "SSD6_CLK_EN_R_N")
	)
	(segment
		(start 331.209904 -249.843544)
		(end 330.769468 -250.28398)
		(width 0.15494)
		(layer "In15.Cu")
		(net "SSD6_CLK_EN_R_N")
	)
	(segment
		(start 151.624538 -233.50474)
		(end 149.910292 -232.79354)
		(width 0.15494)
		(layer "In15.Cu")
		(net "SSD6_CLK_EN_R_N")
	)
	(segment
		(start 230.24338 -247.27027)
		(end 223.094042 -247.27027)
		(width 0.15494)
		(layer "In15.Cu")
		(net "SSD6_CLK_EN_R_N")
	)
	(segment
		(start 189.343538 -247.133618)
		(end 185.036714 -242.826794)
		(width 0.15494)
		(layer "In15.Cu")
		(net "SSD6_CLK_EN_R_N")
	)
	(segment
		(start 339.914484 -249.06224)
		(end 333.737966 -249.06224)
		(width 0.15494)
		(layer "In15.Cu")
		(net "SSD6_CLK_EN_R_N")
	)
	(segment
		(start 119.260112 -237.2233)
		(end 114.0968 -232.059988)
		(width 0.15494)
		(layer "In15.Cu")
		(net "SSD6_CLK_EN_R_N")
	)
	(segment
		(start 99.035616 -208.112614)
		(end 97.705164 -206.782162)
		(width 0.15494)
		(layer "In15.Cu")
		(net "SSD6_CLK_EN_R_N")
	)
	(segment
		(start 325.94677 -249.421396)
		(end 303.718722 -249.421396)
		(width 0.15494)
		(layer "In15.Cu")
		(net "SSD6_CLK_EN_R_N")
	)
	(segment
		(start 222.659194 -246.835422)
		(end 221.366334 -246.835422)
		(width 0.15494)
		(layer "In15.Cu")
		(net "SSD6_CLK_EN_R_N")
	)
	(segment
		(start 231.484932 -248.511822)
		(end 230.24338 -247.27027)
		(width 0.15494)
		(layer "In15.Cu")
		(net "SSD6_CLK_EN_R_N")
	)
	(segment
		(start 123.699524 -235.63961)
		(end 122.115834 -237.2233)
		(width 0.15494)
		(layer "In15.Cu")
		(net "SSD6_CLK_EN_R_N")
	)
	(segment
		(start 114.0968 -232.059988)
		(end 114.0968 -212.562948)
		(width 0.15494)
		(layer "In15.Cu")
		(net "SSD6_CLK_EN_R_N")
	)
	(segment
		(start 99.036378 -208.112868)
		(end 99.035616 -208.112614)
		(width 0.15494)
		(layer "In15.Cu")
		(net "SSD6_CLK_EN_R_N")
	)
	(segment
		(start 98.69297 -87.585804)
		(end 99.08794 -87.980774)
		(width 0.15494)
		(layer "In15.Cu")
		(net "SSD6_CLK_EN_R_N")
	)
	(segment
		(start 79.328264 -90.613738)
		(end 80.112362 -91.397836)
		(width 0.15494)
		(layer "In15.Cu")
		(net "SSD6_CLK_EN_R_N")
	)
	(segment
		(start 348.63913 -235.527342)
		(end 348.63913 -237.414562)
		(width 0.15494)
		(layer "In15.Cu")
		(net "SSD6_CLK_EN_R_N")
	)
	(segment
		(start 160.796224 -239.46739)
		(end 155.321254 -233.99242)
		(width 0.15494)
		(layer "In15.Cu")
		(net "SSD6_CLK_EN_R_N")
	)
	(segment
		(start 299.827188 -249.512328)
		(end 298.36872 -248.05386)
		(width 0.15494)
		(layer "In15.Cu")
		(net "SSD6_CLK_EN_R_N")
	)
	(segment
		(start 181.28869 -239.46739)
		(end 160.796224 -239.46739)
		(width 0.15494)
		(layer "In15.Cu")
		(net "SSD6_CLK_EN_R_N")
	)
	(segment
		(start 99.08794 -87.980774)
		(end 103.89489 -87.980774)
		(width 0.15494)
		(layer "In15.Cu")
		(net "SSD6_CLK_EN_R_N")
	)
	(segment
		(start 273.803364 -248.05386)
		(end 273.460972 -247.711468)
		(width 0.15494)
		(layer "In15.Cu")
		(net "SSD6_CLK_EN_R_N")
	)
	(segment
		(start 152.718008 -233.50474)
		(end 151.624538 -233.50474)
		(width 0.15494)
		(layer "In15.Cu")
		(net "SSD6_CLK_EN_R_N")
	)
	(segment
		(start 87.032846 -87.585804)
		(end 98.69297 -87.585804)
		(width 0.15494)
		(layer "In15.Cu")
		(net "SSD6_CLK_EN_R_N")
	)
	(segment
		(start 298.36872 -248.05386)
		(end 273.803364 -248.05386)
		(width 0.15494)
		(layer "In15.Cu")
		(net "SSD6_CLK_EN_R_N")
	)
	(segment
		(start 110.263686 -88.631522)
		(end 111.896652 -90.264488)
		(width 0.15494)
		(layer "In15.Cu")
		(net "SSD6_CLK_EN_R_N")
	)
	(segment
		(start 149.910292 -232.79354)
		(end 141.820646 -232.79354)
		(width 0.15494)
		(layer "In15.Cu")
		(net "SSD6_CLK_EN_R_N")
	)
	(segment
		(start 184.648094 -242.826794)
		(end 181.28869 -239.46739)
		(width 0.15494)
		(layer "In15.Cu")
		(net "SSD6_CLK_EN_R_N")
	)
	(segment
		(start 237.939326 -248.511822)
		(end 231.484932 -248.511822)
		(width 0.15494)
		(layer "In15.Cu")
		(net "SSD6_CLK_EN_R_N")
	)
	(segment
		(start 109.64672 -208.112868)
		(end 99.036378 -208.112868)
		(width 0.15494)
		(layer "In15.Cu")
		(net "SSD6_CLK_EN_R_N")
	)
	(segment
		(start 104.545638 -88.631522)
		(end 110.263686 -88.631522)
		(width 0.15494)
		(layer "In15.Cu")
		(net "SSD6_CLK_EN_R_N")
	)
	(segment
		(start 153.895552 -233.99242)
		(end 152.718008 -233.50474)
		(width 0.15494)
		(layer "In15.Cu")
		(net "SSD6_CLK_EN_R_N")
	)
	(segment
		(start 122.115834 -237.2233)
		(end 119.260112 -237.2233)
		(width 0.15494)
		(layer "In15.Cu")
		(net "SSD6_CLK_EN_R_N")
	)
	(segment
		(start 349.466662 -239.510062)
		(end 339.914484 -249.06224)
		(width 0.15494)
		(layer "In15.Cu")
		(net "SSD6_CLK_EN_R_N")
	)
	(segment
		(start 239.975644 -246.475504)
		(end 237.939326 -248.511822)
		(width 0.15494)
		(layer "In15.Cu")
		(net "SSD6_CLK_EN_R_N")
	)
	(segment
		(start 326.809354 -250.28398)
		(end 325.94677 -249.421396)
		(width 0.15494)
		(layer "In15.Cu")
		(net "SSD6_CLK_EN_R_N")
	)
	(segment
		(start 83.220814 -91.397836)
		(end 87.032846 -87.585804)
		(width 0.15494)
		(layer "In15.Cu")
		(net "SSD6_CLK_EN_R_N")
	)
	(segment
		(start 330.769468 -250.28398)
		(end 326.809354 -250.28398)
		(width 0.15494)
		(layer "In15.Cu")
		(net "SSD6_CLK_EN_R_N")
	)
	(segment
		(start 185.036714 -242.826794)
		(end 184.648094 -242.826794)
		(width 0.15494)
		(layer "In15.Cu")
		(net "SSD6_CLK_EN_R_N")
	)
	(segment
		(start 332.956662 -249.843544)
		(end 331.209904 -249.843544)
		(width 0.15494)
		(layer "In15.Cu")
		(net "SSD6_CLK_EN_R_N")
	)
	(segment
		(start 138.974576 -235.63961)
		(end 123.699524 -235.63961)
		(width 0.15494)
		(layer "In15.Cu")
		(net "SSD6_CLK_EN_R_N")
	)
	(segment
		(start 349.466662 -238.242094)
		(end 349.466662 -239.510062)
		(width 0.15494)
		(layer "In15.Cu")
		(net "SSD6_CLK_EN_R_N")
	)
	(segment
		(start 249.333512 -247.711468)
		(end 248.097548 -246.475504)
		(width 0.15494)
		(layer "In15.Cu")
		(net "SSD6_CLK_EN_R_N")
	)
	(segment
		(start 114.0968 -212.562948)
		(end 109.64672 -208.112868)
		(width 0.15494)
		(layer "In15.Cu")
		(net "SSD6_CLK_EN_R_N")
	)
	(segment
		(start 303.499266 -249.512328)
		(end 299.827188 -249.512328)
		(width 0.15494)
		(layer "In15.Cu")
		(net "SSD6_CLK_EN_R_N")
	)
	(segment
		(start 221.366334 -246.835422)
		(end 221.068138 -247.133618)
		(width 0.15494)
		(layer "In15.Cu")
		(net "SSD6_CLK_EN_R_N")
	)
	(segment
		(start 348.63913 -237.414562)
		(end 349.466662 -238.242094)
		(width 0.15494)
		(layer "In15.Cu")
		(net "SSD6_CLK_EN_R_N")
	)
	(segment
		(start 303.718722 -249.421396)
		(end 303.499266 -249.512328)
		(width 0.15494)
		(layer "In15.Cu")
		(net "SSD6_CLK_EN_R_N")
	)
	(segment
		(start 103.89489 -87.980774)
		(end 104.545638 -88.631522)
		(width 0.15494)
		(layer "In15.Cu")
		(net "SSD6_CLK_EN_R_N")
	)
	(segment
		(start 333.737966 -249.06224)
		(end 332.956662 -249.843544)
		(width 0.15494)
		(layer "In15.Cu")
		(net "SSD6_CLK_EN_R_N")
	)
	(segment
		(start 248.097548 -246.475504)
		(end 239.975644 -246.475504)
		(width 0.15494)
		(layer "In15.Cu")
		(net "SSD6_CLK_EN_R_N")
	)
	(segment
		(start 155.321254 -233.99242)
		(end 153.895552 -233.99242)
		(width 0.15494)
		(layer "In15.Cu")
		(net "SSD6_CLK_EN_R_N")
	)
	(segment
		(start 273.460972 -247.711468)
		(end 249.333512 -247.711468)
		(width 0.15494)
		(layer "In15.Cu")
		(net "SSD6_CLK_EN_R_N")
	)
	(segment
		(start 223.094042 -247.27027)
		(end 222.659194 -246.835422)
		(width 0.15494)
		(layer "In15.Cu")
		(net "SSD6_CLK_EN_R_N")
	)
	(segment
		(start 80.112362 -91.397836)
		(end 83.220814 -91.397836)
		(width 0.15494)
		(layer "In15.Cu")
		(net "SSD6_CLK_EN_R_N")
	)
	(segment
		(start 221.068138 -247.133618)
		(end 189.343538 -247.133618)
		(width 0.15494)
		(layer "In15.Cu")
		(net "SSD6_CLK_EN_R_N")
	)
	(segment
		(start 141.820646 -232.79354)
		(end 138.974576 -235.63961)
		(width 0.15494)
		(layer "In15.Cu")
		(net "SSD6_CLK_EN_R_N")
	)
	(segment
		(start 349.089726 -235.076746)
		(end 348.63913 -235.527342)
		(width 0.15494)
		(layer "In15.Cu")
		(net "SSD6_CLK_EN_R_N")
	)
	(segment
		(start 340.897718 -210.82635)
		(end 341.186008 -210.53806)
		(width 0.13208)
		(layer "F.Cu")
		(net "RST_SSD13_PERST_N")
	)
	(segment
		(start 341.63 -206.8068)
		(end 341.63 -205.63205)
		(width 0.13208)
		(layer "F.Cu")
		(net "RST_SSD13_PERST_N")
	)
	(segment
		(start 341.293958 -211.98713)
		(end 340.897718 -211.59089)
		(width 0.13208)
		(layer "F.Cu")
		(net "RST_SSD13_PERST_N")
	)
	(segment
		(start 341.63 -208.281016)
		(end 341.63 -206.8068)
		(width 0.13208)
		(layer "F.Cu")
		(net "RST_SSD13_PERST_N")
	)
	(segment
		(start 341.186008 -210.53806)
		(end 341.186008 -208.725008)
		(width 0.13208)
		(layer "F.Cu")
		(net "RST_SSD13_PERST_N")
	)
	(segment
		(start 340.897718 -211.59089)
		(end 340.897718 -210.82635)
		(width 0.13208)
		(layer "F.Cu")
		(net "RST_SSD13_PERST_N")
	)
	(segment
		(start 341.186008 -208.725008)
		(end 341.63 -208.281016)
		(width 0.13208)
		(layer "F.Cu")
		(net "RST_SSD13_PERST_N")
	)
	(via
		(at 341.63 -206.8068)
		(size 0.762)
		(drill 0.381)
		(layers "F.Cu" "B.Cu")
		(net "RST_SSD13_PERST_N")
	)
	(segment
		(start 386.099558 -299.699934)
		(end 385.624578 -299.224954)
		(width 0.1143)
		(layer "F.Cu")
		(net "CLK_100M_PEX3_REF_R_DP")
	)
	(segment
		(start 386.099812 -299.699934)
		(end 386.099558 -299.699934)
		(width 0.1143)
		(layer "F.Cu")
		(net "CLK_100M_PEX3_REF_R_DP")
	)
	(segment
		(start 236.019594 -149.752812)
		(end 236.344206 -149.4282)
		(width 0.1143)
		(layer "F.Cu")
		(net "CLK_100M_PEX3_REF_R_DP")
	)
	(segment
		(start 236.344206 -149.4282)
		(end 236.903006 -149.4282)
		(width 0.1143)
		(layer "F.Cu")
		(net "CLK_100M_PEX3_REF_R_DP")
	)
	(segment
		(start 236.903006 -149.4282)
		(end 237.16615 -149.691344)
		(width 0.1143)
		(layer "F.Cu")
		(net "CLK_100M_PEX3_REF_R_DP")
	)
	(via
		(at 385.624578 -299.224954)
		(size 0.4064)
		(drill 0.2032)
		(layers "F.Cu" "B.Cu")
		(net "CLK_100M_PEX3_REF_R_DP")
	)
	(via
		(at 237.16615 -149.691344)
		(size 0.508)
		(drill 0.254)
		(layers "F.Cu" "B.Cu")
		(net "CLK_100M_PEX3_REF_R_DP")
	)
	(segment
		(start 237.62589 -149.450044)
		(end 238.8362 -150.660354)
		(width 0.1143)
		(layer "B.Cu")
		(net "CLK_100M_PEX3_REF_R_DP")
	)
	(segment
		(start 377.4186 -296.048176)
		(end 379.680724 -298.3103)
		(width 0.1143)
		(layer "B.Cu")
		(net "CLK_100M_PEX3_REF_R_DP")
	)
	(segment
		(start 314.424314 -225.586798)
		(end 314.424314 -235.0516)
		(width 0.1143)
		(layer "B.Cu")
		(net "CLK_100M_PEX3_REF_R_DP")
	)
	(segment
		(start 376.4661 -279.0698)
		(end 376.846846 -279.0698)
		(width 0.1143)
		(layer "B.Cu")
		(net "CLK_100M_PEX3_REF_R_DP")
	)
	(segment
		(start 377.4186 -279.641554)
		(end 377.4186 -296.048176)
		(width 0.1143)
		(layer "B.Cu")
		(net "CLK_100M_PEX3_REF_R_DP")
	)
	(segment
		(start 381.4318 -298.3103)
		(end 383.01676 -299.89526)
		(width 0.1143)
		(layer "B.Cu")
		(net "CLK_100M_PEX3_REF_R_DP")
	)
	(segment
		(start 246.081804 -165.6715)
		(end 257.74523 -177.334926)
		(width 0.1143)
		(layer "B.Cu")
		(net "CLK_100M_PEX3_REF_R_DP")
	)
	(segment
		(start 257.74523 -181.460902)
		(end 259.908802 -183.624474)
		(width 0.1143)
		(layer "B.Cu")
		(net "CLK_100M_PEX3_REF_R_DP")
	)
	(segment
		(start 238.8362 -150.660354)
		(end 238.8362 -156.1846)
		(width 0.1143)
		(layer "B.Cu")
		(net "CLK_100M_PEX3_REF_R_DP")
	)
	(segment
		(start 366.7379 -269.3416)
		(end 376.4661 -279.0698)
		(width 0.1143)
		(layer "B.Cu")
		(net "CLK_100M_PEX3_REF_R_DP")
	)
	(segment
		(start 237.40745 -149.450044)
		(end 237.62589 -149.450044)
		(width 0.1143)
		(layer "B.Cu")
		(net "CLK_100M_PEX3_REF_R_DP")
	)
	(segment
		(start 361.928664 -242.7605)
		(end 366.7379 -247.569736)
		(width 0.1143)
		(layer "B.Cu")
		(net "CLK_100M_PEX3_REF_R_DP")
	)
	(segment
		(start 385.257548 -299.301154)
		(end 385.333748 -299.224954)
		(width 0.0889)
		(layer "B.Cu")
		(net "CLK_100M_PEX3_REF_R_DP")
	)
	(segment
		(start 259.908802 -183.624474)
		(end 262.127238 -184.543446)
		(width 0.1143)
		(layer "B.Cu")
		(net "CLK_100M_PEX3_REF_R_DP")
	)
	(segment
		(start 238.227362 -156.793438)
		(end 238.227362 -161.013394)
		(width 0.1143)
		(layer "B.Cu")
		(net "CLK_100M_PEX3_REF_R_DP")
	)
	(segment
		(start 383.01676 -299.89526)
		(end 383.670302 -299.89526)
		(width 0.1143)
		(layer "B.Cu")
		(net "CLK_100M_PEX3_REF_R_DP")
	)
	(segment
		(start 238.8362 -156.1846)
		(end 238.227362 -156.793438)
		(width 0.1143)
		(layer "B.Cu")
		(net "CLK_100M_PEX3_REF_R_DP")
	)
	(segment
		(start 242.885468 -165.6715)
		(end 246.081804 -165.6715)
		(width 0.1143)
		(layer "B.Cu")
		(net "CLK_100M_PEX3_REF_R_DP")
	)
	(segment
		(start 262.127238 -184.543446)
		(end 290.232846 -212.6488)
		(width 0.1143)
		(layer "B.Cu")
		(net "CLK_100M_PEX3_REF_R_DP")
	)
	(segment
		(start 385.333748 -299.224954)
		(end 385.624578 -299.224954)
		(width 0.0889)
		(layer "B.Cu")
		(net "CLK_100M_PEX3_REF_R_DP")
	)
	(segment
		(start 257.74523 -177.334926)
		(end 257.74523 -181.460902)
		(width 0.1143)
		(layer "B.Cu")
		(net "CLK_100M_PEX3_REF_R_DP")
	)
	(segment
		(start 384.933444 -299.81271)
		(end 385.257548 -299.488606)
		(width 0.0889)
		(layer "B.Cu")
		(net "CLK_100M_PEX3_REF_R_DP")
	)
	(segment
		(start 383.6924 -299.89526)
		(end 383.77495 -299.81271)
		(width 0.0889)
		(layer "B.Cu")
		(net "CLK_100M_PEX3_REF_R_DP")
	)
	(segment
		(start 352.872802 -243.1415)
		(end 353.253802 -242.7605)
		(width 0.1143)
		(layer "B.Cu")
		(net "CLK_100M_PEX3_REF_R_DP")
	)
	(segment
		(start 353.253802 -242.7605)
		(end 361.928664 -242.7605)
		(width 0.1143)
		(layer "B.Cu")
		(net "CLK_100M_PEX3_REF_R_DP")
	)
	(segment
		(start 366.7379 -247.569736)
		(end 366.7379 -269.3416)
		(width 0.1143)
		(layer "B.Cu")
		(net "CLK_100M_PEX3_REF_R_DP")
	)
	(segment
		(start 385.257548 -299.488606)
		(end 385.257548 -299.301154)
		(width 0.0889)
		(layer "B.Cu")
		(net "CLK_100M_PEX3_REF_R_DP")
	)
	(segment
		(start 238.227362 -161.013394)
		(end 242.885468 -165.6715)
		(width 0.1143)
		(layer "B.Cu")
		(net "CLK_100M_PEX3_REF_R_DP")
	)
	(segment
		(start 376.846846 -279.0698)
		(end 377.4186 -279.641554)
		(width 0.1143)
		(layer "B.Cu")
		(net "CLK_100M_PEX3_REF_R_DP")
	)
	(segment
		(start 314.424314 -235.0516)
		(end 322.514214 -243.1415)
		(width 0.1143)
		(layer "B.Cu")
		(net "CLK_100M_PEX3_REF_R_DP")
	)
	(segment
		(start 379.680724 -298.3103)
		(end 381.4318 -298.3103)
		(width 0.1143)
		(layer "B.Cu")
		(net "CLK_100M_PEX3_REF_R_DP")
	)
	(segment
		(start 383.77495 -299.81271)
		(end 384.933444 -299.81271)
		(width 0.0889)
		(layer "B.Cu")
		(net "CLK_100M_PEX3_REF_R_DP")
	)
	(segment
		(start 301.486316 -212.6488)
		(end 314.424314 -225.586798)
		(width 0.1143)
		(layer "B.Cu")
		(net "CLK_100M_PEX3_REF_R_DP")
	)
	(segment
		(start 290.232846 -212.6488)
		(end 301.486316 -212.6488)
		(width 0.1143)
		(layer "B.Cu")
		(net "CLK_100M_PEX3_REF_R_DP")
	)
	(segment
		(start 237.16615 -149.691344)
		(end 237.40745 -149.450044)
		(width 0.1143)
		(layer "B.Cu")
		(net "CLK_100M_PEX3_REF_R_DP")
	)
	(segment
		(start 322.514214 -243.1415)
		(end 352.872802 -243.1415)
		(width 0.1143)
		(layer "B.Cu")
		(net "CLK_100M_PEX3_REF_R_DP")
	)
	(segment
		(start 383.670302 -299.89526)
		(end 383.6924 -299.89526)
		(width 0.0889)
		(layer "B.Cu")
		(net "CLK_100M_PEX3_REF_R_DP")
	)
	(segment
		(start 214.732108 -217.768932)
		(end 217.15349 -217.768932)
		(width 0.13208)
		(layer "F.Cu")
		(net "SMB_NIC5_SDA")
	)
	(segment
		(start 220.263466 -217.23731)
		(end 220.203522 -217.297254)
		(width 0.13208)
		(layer "F.Cu")
		(net "SMB_NIC5_SDA")
	)
	(segment
		(start 217.646504 -217.297254)
		(end 217.635836 -217.286586)
		(width 0.13208)
		(layer "F.Cu")
		(net "SMB_NIC5_SDA")
	)
	(segment
		(start 221.293436 -218.26728)
		(end 220.263466 -217.23731)
		(width 0.13208)
		(layer "F.Cu")
		(net "SMB_NIC5_SDA")
	)
	(segment
		(start 214.233506 -217.27033)
		(end 214.732108 -217.768932)
		(width 0.13208)
		(layer "F.Cu")
		(net "SMB_NIC5_SDA")
	)
	(segment
		(start 223.467676 -218.30411)
		(end 223.430846 -218.26728)
		(width 0.13208)
		(layer "F.Cu")
		(net "SMB_NIC5_SDA")
	)
	(segment
		(start 217.15349 -217.768932)
		(end 217.635836 -217.286586)
		(width 0.13208)
		(layer "F.Cu")
		(net "SMB_NIC5_SDA")
	)
	(segment
		(start 223.430846 -218.26728)
		(end 221.293436 -218.26728)
		(width 0.13208)
		(layer "F.Cu")
		(net "SMB_NIC5_SDA")
	)
	(segment
		(start 220.203522 -217.297254)
		(end 217.646504 -217.297254)
		(width 0.13208)
		(layer "F.Cu")
		(net "SMB_NIC5_SDA")
	)
	(via
		(at 220.263466 -217.23731)
		(size 0.762)
		(drill 0.381)
		(layers "F.Cu" "B.Cu")
		(net "SMB_NIC5_SDA")
	)
	(segment
		(start 62.56274 -382.538732)
		(end 62.56274 -383.530094)
		(width 0.13208)
		(layer "F.Cu")
		(net "RST_MB_PERST_2_N")
	)
	(segment
		(start 338.342986 -243.727986)
		(end 338.342986 -242.807998)
		(width 0.13208)
		(layer "F.Cu")
		(net "RST_MB_PERST_2_N")
	)
	(segment
		(start 338.455 -243.84)
		(end 338.342986 -243.727986)
		(width 0.13208)
		(layer "F.Cu")
		(net "RST_MB_PERST_2_N")
	)
	(segment
		(start 62.608714 -383.576068)
		(end 62.195964 -383.576068)
		(width 0.13208)
		(layer "F.Cu")
		(net "RST_MB_PERST_2_N")
	)
	(segment
		(start 338.455 -244.221)
		(end 338.455 -243.84)
		(width 0.13208)
		(layer "F.Cu")
		(net "RST_MB_PERST_2_N")
	)
	(segment
		(start 338.455 -244.70995)
		(end 338.455 -244.221)
		(width 0.13208)
		(layer "F.Cu")
		(net "RST_MB_PERST_2_N")
	)
	(segment
		(start 338.328 -244.83695)
		(end 338.455 -244.70995)
		(width 0.13208)
		(layer "F.Cu")
		(net "RST_MB_PERST_2_N")
	)
	(segment
		(start 62.56274 -383.530094)
		(end 62.608714 -383.576068)
		(width 0.13208)
		(layer "F.Cu")
		(net "RST_MB_PERST_2_N")
	)
	(segment
		(start 62.195964 -383.576068)
		(end 61.85789 -383.914142)
		(width 0.13208)
		(layer "F.Cu")
		(net "RST_MB_PERST_2_N")
	)
	(via
		(at 61.85789 -383.914142)
		(size 0.508)
		(drill 0.254)
		(layers "F.Cu" "B.Cu")
		(net "RST_MB_PERST_2_N")
	)
	(via
		(at 338.455 -244.221)
		(size 0.508)
		(drill 0.254)
		(layers "F.Cu" "B.Cu")
		(net "RST_MB_PERST_2_N")
	)
	(via
		(at 229.33025 -332.562454)
		(size 0.508)
		(drill 0.254)
		(layers "F.Cu" "B.Cu")
		(net "RST_MB_PERST_2_N")
	)
	(via
		(at 200.316592 -361.199176)
		(size 0.508)
		(drill 0.254)
		(layers "F.Cu" "B.Cu")
		(net "RST_MB_PERST_2_N")
	)
	(via
		(at 102.743 -368.935)
		(size 0.508)
		(drill 0.254)
		(layers "F.Cu" "B.Cu")
		(net "RST_MB_PERST_2_N")
	)
	(via
		(at 238.941864 -241.740182)
		(size 0.508)
		(drill 0.254)
		(layers "F.Cu" "B.Cu")
		(net "RST_MB_PERST_2_N")
	)
	(segment
		(start 108.791756 -366.928146)
		(end 114.649758 -361.070144)
		(width 0.13208)
		(layer "B.Cu")
		(net "RST_MB_PERST_2_N")
	)
	(segment
		(start 114.649758 -361.070144)
		(end 200.18756 -361.070144)
		(width 0.13208)
		(layer "B.Cu")
		(net "RST_MB_PERST_2_N")
	)
	(segment
		(start 248.62028 -264.950956)
		(end 257.074416 -285.362904)
		(width 0.13208)
		(layer "B.Cu")
		(net "RST_MB_PERST_2_N")
	)
	(segment
		(start 102.745032 -367.876836)
		(end 103.693722 -366.928146)
		(width 0.13208)
		(layer "B.Cu")
		(net "RST_MB_PERST_2_N")
	)
	(segment
		(start 200.18756 -361.070144)
		(end 200.316592 -361.199176)
		(width 0.13208)
		(layer "B.Cu")
		(net "RST_MB_PERST_2_N")
	)
	(segment
		(start 249.635264 -323.711824)
		(end 245.51005 -327.83653)
		(width 0.13208)
		(layer "B.Cu")
		(net "RST_MB_PERST_2_N")
	)
	(segment
		(start 232.283 -331.653134)
		(end 230.23957 -331.653134)
		(width 0.13208)
		(layer "B.Cu")
		(net "RST_MB_PERST_2_N")
	)
	(segment
		(start 102.745032 -368.932968)
		(end 102.745032 -367.876836)
		(width 0.13208)
		(layer "B.Cu")
		(net "RST_MB_PERST_2_N")
	)
	(segment
		(start 245.51005 -327.83653)
		(end 236.099604 -327.83653)
		(width 0.13208)
		(layer "B.Cu")
		(net "RST_MB_PERST_2_N")
	)
	(segment
		(start 248.62028 -255.704848)
		(end 248.62028 -264.950956)
		(width 0.13208)
		(layer "B.Cu")
		(net "RST_MB_PERST_2_N")
	)
	(segment
		(start 238.941864 -241.740182)
		(end 245.58879 -248.387108)
		(width 0.13208)
		(layer "B.Cu")
		(net "RST_MB_PERST_2_N")
	)
	(segment
		(start 236.099604 -327.83653)
		(end 232.283 -331.653134)
		(width 0.13208)
		(layer "B.Cu")
		(net "RST_MB_PERST_2_N")
	)
	(segment
		(start 245.58879 -248.387108)
		(end 248.62028 -255.704848)
		(width 0.13208)
		(layer "B.Cu")
		(net "RST_MB_PERST_2_N")
	)
	(segment
		(start 102.743 -368.935)
		(end 102.745032 -368.932968)
		(width 0.13208)
		(layer "B.Cu")
		(net "RST_MB_PERST_2_N")
	)
	(segment
		(start 103.693722 -366.928146)
		(end 108.791756 -366.928146)
		(width 0.13208)
		(layer "B.Cu")
		(net "RST_MB_PERST_2_N")
	)
	(segment
		(start 230.23957 -331.653134)
		(end 229.33025 -332.562454)
		(width 0.13208)
		(layer "B.Cu")
		(net "RST_MB_PERST_2_N")
	)
	(segment
		(start 257.074416 -305.751738)
		(end 249.635264 -323.711824)
		(width 0.13208)
		(layer "B.Cu")
		(net "RST_MB_PERST_2_N")
	)
	(segment
		(start 257.074416 -285.362904)
		(end 257.074416 -305.751738)
		(width 0.13208)
		(layer "B.Cu")
		(net "RST_MB_PERST_2_N")
	)
	(segment
		(start 228.717348 -346.868496)
		(end 218.839796 -356.746048)
		(width 0.15494)
		(layer "In5.Cu")
		(net "RST_MB_PERST_2_N")
	)
	(segment
		(start 229.33025 -332.562454)
		(end 228.717348 -333.175356)
		(width 0.15494)
		(layer "In5.Cu")
		(net "RST_MB_PERST_2_N")
	)
	(segment
		(start 200.505568 -361.0102)
		(end 200.316592 -361.199176)
		(width 0.15494)
		(layer "In5.Cu")
		(net "RST_MB_PERST_2_N")
	)
	(segment
		(start 228.717348 -333.175356)
		(end 228.717348 -346.868496)
		(width 0.15494)
		(layer "In5.Cu")
		(net "RST_MB_PERST_2_N")
	)
	(segment
		(start 202.701906 -360.649774)
		(end 201.83221 -361.0102)
		(width 0.15494)
		(layer "In5.Cu")
		(net "RST_MB_PERST_2_N")
	)
	(segment
		(start 201.83221 -361.0102)
		(end 200.505568 -361.0102)
		(width 0.15494)
		(layer "In5.Cu")
		(net "RST_MB_PERST_2_N")
	)
	(segment
		(start 206.605124 -356.746048)
		(end 202.701906 -360.649774)
		(width 0.15494)
		(layer "In5.Cu")
		(net "RST_MB_PERST_2_N")
	)
	(segment
		(start 218.839796 -356.746048)
		(end 206.605124 -356.746048)
		(width 0.15494)
		(layer "In5.Cu")
		(net "RST_MB_PERST_2_N")
	)
	(segment
		(start 70.650354 -390.182354)
		(end 70.650354 -410.830522)
		(width 0.15494)
		(layer "In9.Cu")
		(net "RST_MB_PERST_2_N")
	)
	(segment
		(start 64.382142 -383.914142)
		(end 70.650354 -390.182354)
		(width 0.15494)
		(layer "In9.Cu")
		(net "RST_MB_PERST_2_N")
	)
	(segment
		(start 61.85789 -383.914142)
		(end 64.382142 -383.914142)
		(width 0.15494)
		(layer "In9.Cu")
		(net "RST_MB_PERST_2_N")
	)
	(segment
		(start 70.650354 -410.830522)
		(end 71.90994 -412.090108)
		(width 0.15494)
		(layer "In9.Cu")
		(net "RST_MB_PERST_2_N")
	)
	(segment
		(start 274.843748 -244.109748)
		(end 255.067308 -244.109748)
		(width 0.15494)
		(layer "In13.Cu")
		(net "RST_MB_PERST_2_N")
	)
	(segment
		(start 275.561552 -244.827552)
		(end 274.843748 -244.109748)
		(width 0.15494)
		(layer "In13.Cu")
		(net "RST_MB_PERST_2_N")
	)
	(segment
		(start 303.910746 -245.7958)
		(end 303.303686 -246.40286)
		(width 0.15494)
		(layer "In13.Cu")
		(net "RST_MB_PERST_2_N")
	)
	(segment
		(start 326.236076 -245.237)
		(end 325.679816 -245.79326)
		(width 0.15494)
		(layer "In13.Cu")
		(net "RST_MB_PERST_2_N")
	)
	(segment
		(start 303.303686 -246.40286)
		(end 301.7139 -246.40286)
		(width 0.15494)
		(layer "In13.Cu")
		(net "RST_MB_PERST_2_N")
	)
	(segment
		(start 329.7682 -245.237)
		(end 326.236076 -245.237)
		(width 0.15494)
		(layer "In13.Cu")
		(net "RST_MB_PERST_2_N")
	)
	(segment
		(start 330.17206 -244.83314)
		(end 329.7682 -245.237)
		(width 0.15494)
		(layer "In13.Cu")
		(net "RST_MB_PERST_2_N")
	)
	(segment
		(start 335.03616 -243.77904)
		(end 333.98206 -244.83314)
		(width 0.15494)
		(layer "In13.Cu")
		(net "RST_MB_PERST_2_N")
	)
	(segment
		(start 301.7139 -246.40286)
		(end 300.138592 -244.827552)
		(width 0.15494)
		(layer "In13.Cu")
		(net "RST_MB_PERST_2_N")
	)
	(segment
		(start 338.201 -244.475)
		(end 336.50682 -244.475)
		(width 0.15494)
		(layer "In13.Cu")
		(net "RST_MB_PERST_2_N")
	)
	(segment
		(start 333.98206 -244.83314)
		(end 330.17206 -244.83314)
		(width 0.15494)
		(layer "In13.Cu")
		(net "RST_MB_PERST_2_N")
	)
	(segment
		(start 338.455 -244.221)
		(end 338.201 -244.475)
		(width 0.15494)
		(layer "In13.Cu")
		(net "RST_MB_PERST_2_N")
	)
	(segment
		(start 253.5301 -242.57254)
		(end 239.774222 -242.57254)
		(width 0.15494)
		(layer "In13.Cu")
		(net "RST_MB_PERST_2_N")
	)
	(segment
		(start 239.774222 -242.57254)
		(end 238.941864 -241.740182)
		(width 0.15494)
		(layer "In13.Cu")
		(net "RST_MB_PERST_2_N")
	)
	(segment
		(start 255.067308 -244.109748)
		(end 253.5301 -242.57254)
		(width 0.15494)
		(layer "In13.Cu")
		(net "RST_MB_PERST_2_N")
	)
	(segment
		(start 300.138592 -244.827552)
		(end 275.561552 -244.827552)
		(width 0.15494)
		(layer "In13.Cu")
		(net "RST_MB_PERST_2_N")
	)
	(segment
		(start 325.679816 -245.79326)
		(end 304.050954 -245.79326)
		(width 0.15494)
		(layer "In13.Cu")
		(net "RST_MB_PERST_2_N")
	)
	(segment
		(start 304.050954 -245.79326)
		(end 304.048414 -245.7958)
		(width 0.15494)
		(layer "In13.Cu")
		(net "RST_MB_PERST_2_N")
	)
	(segment
		(start 304.048414 -245.7958)
		(end 303.910746 -245.7958)
		(width 0.15494)
		(layer "In13.Cu")
		(net "RST_MB_PERST_2_N")
	)
	(segment
		(start 336.50682 -244.475)
		(end 335.81086 -243.77904)
		(width 0.15494)
		(layer "In13.Cu")
		(net "RST_MB_PERST_2_N")
	)
	(segment
		(start 335.81086 -243.77904)
		(end 335.03616 -243.77904)
		(width 0.15494)
		(layer "In13.Cu")
		(net "RST_MB_PERST_2_N")
	)
	(segment
		(start 95.8215 -383.527554)
		(end 91.044014 -388.30504)
		(width 0.15494)
		(layer "In15.Cu")
		(net "RST_MB_PERST_2_N")
	)
	(segment
		(start 95.8215 -376.47626)
		(end 95.8215 -383.527554)
		(width 0.15494)
		(layer "In15.Cu")
		(net "RST_MB_PERST_2_N")
	)
	(segment
		(start 91.044014 -388.30504)
		(end 66.248788 -388.30504)
		(width 0.15494)
		(layer "In15.Cu")
		(net "RST_MB_PERST_2_N")
	)
	(segment
		(start 66.248788 -388.30504)
		(end 61.85789 -383.914142)
		(width 0.15494)
		(layer "In15.Cu")
		(net "RST_MB_PERST_2_N")
	)
	(segment
		(start 102.743 -369.55476)
		(end 95.8215 -376.47626)
		(width 0.15494)
		(layer "In15.Cu")
		(net "RST_MB_PERST_2_N")
	)
	(segment
		(start 102.743 -368.935)
		(end 102.743 -369.55476)
		(width 0.15494)
		(layer "In15.Cu")
		(net "RST_MB_PERST_2_N")
	)
	(segment
		(start 345.442286 -244.507004)
		(end 345.442286 -244.032024)
		(width 0.13208)
		(layer "F.Cu")
		(net "SSD2_CLK_EN_R_N")
	)
	(segment
		(start 339.066886 -251.54636)
		(end 339.085936 -251.52731)
		(width 0.13208)
		(layer "F.Cu")
		(net "SSD2_CLK_EN_R_N")
	)
	(segment
		(start 339.085936 -250.863354)
		(end 345.442286 -244.507004)
		(width 0.13208)
		(layer "F.Cu")
		(net "SSD2_CLK_EN_R_N")
	)
	(segment
		(start 110.639098 -82.210148)
		(end 110.913164 -81.936082)
		(width 0.13208)
		(layer "F.Cu")
		(net "SSD2_CLK_EN_R_N")
	)
	(segment
		(start 110.639098 -83.029044)
		(end 110.639098 -82.210148)
		(width 0.13208)
		(layer "F.Cu")
		(net "SSD2_CLK_EN_R_N")
	)
	(segment
		(start 345.442286 -244.032024)
		(end 347.966792 -241.507518)
		(width 0.13208)
		(layer "F.Cu")
		(net "SSD2_CLK_EN_R_N")
	)
	(segment
		(start 347.966792 -241.507518)
		(end 347.966792 -241.091212)
		(width 0.13208)
		(layer "F.Cu")
		(net "SSD2_CLK_EN_R_N")
	)
	(segment
		(start 339.085936 -251.52731)
		(end 339.085936 -250.863354)
		(width 0.13208)
		(layer "F.Cu")
		(net "SSD2_CLK_EN_R_N")
	)
	(via
		(at 339.066886 -251.54636)
		(size 0.508)
		(drill 0.254)
		(layers "F.Cu" "B.Cu")
		(net "SSD2_CLK_EN_R_N")
	)
	(via
		(at 120.393968 -241.946684)
		(size 0.508)
		(drill 0.254)
		(layers "F.Cu" "B.Cu")
		(net "SSD2_CLK_EN_R_N")
	)
	(via
		(at 110.913164 -81.936082)
		(size 0.508)
		(drill 0.254)
		(layers "F.Cu" "B.Cu")
		(net "SSD2_CLK_EN_R_N")
	)
	(via
		(at 88.596724 -80.118458)
		(size 0.508)
		(drill 0.254)
		(layers "F.Cu" "B.Cu")
		(net "SSD2_CLK_EN_R_N")
	)
	(segment
		(start 120.14581 -234.57916)
		(end 119.9642 -235.017564)
		(width 0.15494)
		(layer "In5.Cu")
		(net "SSD2_CLK_EN_R_N")
	)
	(segment
		(start 114.7064 -210.7184)
		(end 114.7064 -221.91726)
		(width 0.15494)
		(layer "In5.Cu")
		(net "SSD2_CLK_EN_R_N")
	)
	(segment
		(start 119.9642 -235.80979)
		(end 120.393968 -236.239558)
		(width 0.15494)
		(layer "In5.Cu")
		(net "SSD2_CLK_EN_R_N")
	)
	(segment
		(start 120.393968 -236.239558)
		(end 120.393968 -241.946684)
		(width 0.15494)
		(layer "In5.Cu")
		(net "SSD2_CLK_EN_R_N")
	)
	(segment
		(start 119.9642 -235.017564)
		(end 119.9642 -235.80979)
		(width 0.15494)
		(layer "In5.Cu")
		(net "SSD2_CLK_EN_R_N")
	)
	(segment
		(start 99.5426 -187.6806)
		(end 99.5426 -193.2686)
		(width 0.15494)
		(layer "In5.Cu")
		(net "SSD2_CLK_EN_R_N")
	)
	(segment
		(start 95.771208 -183.909208)
		(end 99.5426 -187.6806)
		(width 0.15494)
		(layer "In5.Cu")
		(net "SSD2_CLK_EN_R_N")
	)
	(segment
		(start 81.309464 -115.662202)
		(end 84.178394 -115.662202)
		(width 0.15494)
		(layer "In5.Cu")
		(net "SSD2_CLK_EN_R_N")
	)
	(segment
		(start 104.93375 -195.624958)
		(end 104.93375 -200.94575)
		(width 0.15494)
		(layer "In5.Cu")
		(net "SSD2_CLK_EN_R_N")
	)
	(segment
		(start 103.847392 -194.5386)
		(end 104.93375 -195.624958)
		(width 0.15494)
		(layer "In5.Cu")
		(net "SSD2_CLK_EN_R_N")
	)
	(segment
		(start 87.1728 -81.542382)
		(end 87.1728 -85.85962)
		(width 0.15494)
		(layer "In5.Cu")
		(net "SSD2_CLK_EN_R_N")
	)
	(segment
		(start 94.27718 -142.008352)
		(end 94.27718 -177.70983)
		(width 0.15494)
		(layer "In5.Cu")
		(net "SSD2_CLK_EN_R_N")
	)
	(segment
		(start 80.115156 -114.467894)
		(end 81.309464 -115.662202)
		(width 0.15494)
		(layer "In5.Cu")
		(net "SSD2_CLK_EN_R_N")
	)
	(segment
		(start 80.115156 -109.119416)
		(end 80.115156 -114.467894)
		(width 0.15494)
		(layer "In5.Cu")
		(net "SSD2_CLK_EN_R_N")
	)
	(segment
		(start 114.7064 -221.91726)
		(end 120.14581 -227.35667)
		(width 0.15494)
		(layer "In5.Cu")
		(net "SSD2_CLK_EN_R_N")
	)
	(segment
		(start 87.7443 -119.228108)
		(end 87.7443 -127.23495)
		(width 0.15494)
		(layer "In5.Cu")
		(net "SSD2_CLK_EN_R_N")
	)
	(segment
		(start 87.7443 -127.23495)
		(end 90.9193 -130.40995)
		(width 0.15494)
		(layer "In5.Cu")
		(net "SSD2_CLK_EN_R_N")
	)
	(segment
		(start 90.9193 -130.40995)
		(end 90.9193 -133.901688)
		(width 0.15494)
		(layer "In5.Cu")
		(net "SSD2_CLK_EN_R_N")
	)
	(segment
		(start 95.771208 -179.203858)
		(end 95.771208 -183.909208)
		(width 0.15494)
		(layer "In5.Cu")
		(net "SSD2_CLK_EN_R_N")
	)
	(segment
		(start 120.14581 -227.35667)
		(end 120.14581 -234.57916)
		(width 0.15494)
		(layer "In5.Cu")
		(net "SSD2_CLK_EN_R_N")
	)
	(segment
		(start 100.8126 -194.5386)
		(end 103.847392 -194.5386)
		(width 0.15494)
		(layer "In5.Cu")
		(net "SSD2_CLK_EN_R_N")
	)
	(segment
		(start 94.27718 -177.70983)
		(end 95.771208 -179.203858)
		(width 0.15494)
		(layer "In5.Cu")
		(net "SSD2_CLK_EN_R_N")
	)
	(segment
		(start 81.387442 -107.84713)
		(end 80.115156 -109.119416)
		(width 0.15494)
		(layer "In5.Cu")
		(net "SSD2_CLK_EN_R_N")
	)
	(segment
		(start 84.178394 -115.662202)
		(end 87.7443 -119.228108)
		(width 0.15494)
		(layer "In5.Cu")
		(net "SSD2_CLK_EN_R_N")
	)
	(segment
		(start 81.387442 -91.644978)
		(end 81.387442 -107.84713)
		(width 0.15494)
		(layer "In5.Cu")
		(net "SSD2_CLK_EN_R_N")
	)
	(segment
		(start 104.93375 -200.94575)
		(end 114.7064 -210.7184)
		(width 0.15494)
		(layer "In5.Cu")
		(net "SSD2_CLK_EN_R_N")
	)
	(segment
		(start 90.9193 -133.901688)
		(end 94.27718 -142.008352)
		(width 0.15494)
		(layer "In5.Cu")
		(net "SSD2_CLK_EN_R_N")
	)
	(segment
		(start 87.1728 -85.85962)
		(end 81.387442 -91.644978)
		(width 0.15494)
		(layer "In5.Cu")
		(net "SSD2_CLK_EN_R_N")
	)
	(segment
		(start 88.596724 -80.118458)
		(end 87.1728 -81.542382)
		(width 0.15494)
		(layer "In5.Cu")
		(net "SSD2_CLK_EN_R_N")
	)
	(segment
		(start 99.5426 -193.2686)
		(end 100.8126 -194.5386)
		(width 0.15494)
		(layer "In5.Cu")
		(net "SSD2_CLK_EN_R_N")
	)
	(segment
		(start 274.022566 -255.41732)
		(end 274.59813 -255.992884)
		(width 0.15494)
		(layer "In15.Cu")
		(net "SSD2_CLK_EN_R_N")
	)
	(segment
		(start 335.19618 -255.992884)
		(end 339.066886 -252.122178)
		(width 0.15494)
		(layer "In15.Cu")
		(net "SSD2_CLK_EN_R_N")
	)
	(segment
		(start 120.393968 -241.946684)
		(end 121.272554 -242.82527)
		(width 0.15494)
		(layer "In15.Cu")
		(net "SSD2_CLK_EN_R_N")
	)
	(segment
		(start 225.367596 -251.71781)
		(end 228.39934 -251.71781)
		(width 0.15494)
		(layer "In15.Cu")
		(net "SSD2_CLK_EN_R_N")
	)
	(segment
		(start 109.65815 -80.681068)
		(end 89.159334 -80.681068)
		(width 0.15494)
		(layer "In15.Cu")
		(net "SSD2_CLK_EN_R_N")
	)
	(segment
		(start 137.163302 -242.82527)
		(end 143.346932 -236.64164)
		(width 0.15494)
		(layer "In15.Cu")
		(net "SSD2_CLK_EN_R_N")
	)
	(segment
		(start 151.384 -238.70666)
		(end 156.45765 -243.78031)
		(width 0.15494)
		(layer "In15.Cu")
		(net "SSD2_CLK_EN_R_N")
	)
	(segment
		(start 256.803652 -254.517652)
		(end 257.202432 -254.517652)
		(width 0.15494)
		(layer "In15.Cu")
		(net "SSD2_CLK_EN_R_N")
	)
	(segment
		(start 187.06719 -253.10846)
		(end 224.48901 -253.10846)
		(width 0.15494)
		(layer "In15.Cu")
		(net "SSD2_CLK_EN_R_N")
	)
	(segment
		(start 143.346932 -236.64164)
		(end 149.176994 -236.64164)
		(width 0.15494)
		(layer "In15.Cu")
		(net "SSD2_CLK_EN_R_N")
	)
	(segment
		(start 224.81159 -252.78588)
		(end 224.81159 -252.273816)
		(width 0.15494)
		(layer "In15.Cu")
		(net "SSD2_CLK_EN_R_N")
	)
	(segment
		(start 320.548 -255.992884)
		(end 335.19618 -255.992884)
		(width 0.15494)
		(layer "In15.Cu")
		(net "SSD2_CLK_EN_R_N")
	)
	(segment
		(start 270.29918 -255.41732)
		(end 274.022566 -255.41732)
		(width 0.15494)
		(layer "In15.Cu")
		(net "SSD2_CLK_EN_R_N")
	)
	(segment
		(start 269.76578 -254.88392)
		(end 270.29918 -255.41732)
		(width 0.15494)
		(layer "In15.Cu")
		(net "SSD2_CLK_EN_R_N")
	)
	(segment
		(start 110.913164 -81.936082)
		(end 109.65815 -80.681068)
		(width 0.15494)
		(layer "In15.Cu")
		(net "SSD2_CLK_EN_R_N")
	)
	(segment
		(start 89.159334 -80.681068)
		(end 88.596724 -80.118458)
		(width 0.15494)
		(layer "In15.Cu")
		(net "SSD2_CLK_EN_R_N")
	)
	(segment
		(start 230.87965 -254.19812)
		(end 256.48412 -254.19812)
		(width 0.15494)
		(layer "In15.Cu")
		(net "SSD2_CLK_EN_R_N")
	)
	(segment
		(start 151.384 -237.947454)
		(end 151.384 -238.70666)
		(width 0.15494)
		(layer "In15.Cu")
		(net "SSD2_CLK_EN_R_N")
	)
	(segment
		(start 274.59813 -255.992884)
		(end 313.2074 -255.992884)
		(width 0.15494)
		(layer "In15.Cu")
		(net "SSD2_CLK_EN_R_N")
	)
	(segment
		(start 339.066886 -252.122178)
		(end 339.066886 -251.54636)
		(width 0.15494)
		(layer "In15.Cu")
		(net "SSD2_CLK_EN_R_N")
	)
	(segment
		(start 257.5687 -254.88392)
		(end 269.76578 -254.88392)
		(width 0.15494)
		(layer "In15.Cu")
		(net "SSD2_CLK_EN_R_N")
	)
	(segment
		(start 149.176994 -236.64164)
		(end 150.715218 -237.278672)
		(width 0.15494)
		(layer "In15.Cu")
		(net "SSD2_CLK_EN_R_N")
	)
	(segment
		(start 156.45765 -243.78031)
		(end 177.73904 -243.78031)
		(width 0.15494)
		(layer "In15.Cu")
		(net "SSD2_CLK_EN_R_N")
	)
	(segment
		(start 256.48412 -254.19812)
		(end 256.803652 -254.517652)
		(width 0.15494)
		(layer "In15.Cu")
		(net "SSD2_CLK_EN_R_N")
	)
	(segment
		(start 224.48901 -253.10846)
		(end 224.81159 -252.78588)
		(width 0.15494)
		(layer "In15.Cu")
		(net "SSD2_CLK_EN_R_N")
	)
	(segment
		(start 313.55919 -256.344674)
		(end 320.19621 -256.344674)
		(width 0.15494)
		(layer "In15.Cu")
		(net "SSD2_CLK_EN_R_N")
	)
	(segment
		(start 177.73904 -243.78031)
		(end 187.06719 -253.10846)
		(width 0.15494)
		(layer "In15.Cu")
		(net "SSD2_CLK_EN_R_N")
	)
	(segment
		(start 121.272554 -242.82527)
		(end 137.163302 -242.82527)
		(width 0.15494)
		(layer "In15.Cu")
		(net "SSD2_CLK_EN_R_N")
	)
	(segment
		(start 313.2074 -255.992884)
		(end 313.55919 -256.344674)
		(width 0.15494)
		(layer "In15.Cu")
		(net "SSD2_CLK_EN_R_N")
	)
	(segment
		(start 224.81159 -252.273816)
		(end 225.367596 -251.71781)
		(width 0.15494)
		(layer "In15.Cu")
		(net "SSD2_CLK_EN_R_N")
	)
	(segment
		(start 320.19621 -256.344674)
		(end 320.548 -255.992884)
		(width 0.15494)
		(layer "In15.Cu")
		(net "SSD2_CLK_EN_R_N")
	)
	(segment
		(start 150.715218 -237.278672)
		(end 151.384 -237.947454)
		(width 0.15494)
		(layer "In15.Cu")
		(net "SSD2_CLK_EN_R_N")
	)
	(segment
		(start 228.39934 -251.71781)
		(end 230.87965 -254.19812)
		(width 0.15494)
		(layer "In15.Cu")
		(net "SSD2_CLK_EN_R_N")
	)
	(segment
		(start 257.202432 -254.517652)
		(end 257.5687 -254.88392)
		(width 0.15494)
		(layer "In15.Cu")
		(net "SSD2_CLK_EN_R_N")
	)
	(segment
		(start 308.081934 -35.876738)
		(end 308.322472 -35.6362)
		(width 0.13208)
		(layer "F.Cu")
		(net "PWRGD_P3V3_SSD11_R")
	)
	(segment
		(start 308.322472 -35.6362)
		(end 310.81218 -35.6362)
		(width 0.13208)
		(layer "F.Cu")
		(net "PWRGD_P3V3_SSD11_R")
	)
	(segment
		(start 339.693758 -215.187022)
		(end 339.293962 -214.787226)
		(width 0.13208)
		(layer "F.Cu")
		(net "PWRGD_P3V3_SSD11_R")
	)
	(segment
		(start 318.810894 -61.386974)
		(end 318.810894 -62.051438)
		(width 0.13208)
		(layer "F.Cu")
		(net "PWRGD_P3V3_SSD11_R")
	)
	(segment
		(start 310.81218 -35.6362)
		(end 311.408572 -36.232592)
		(width 0.13208)
		(layer "F.Cu")
		(net "PWRGD_P3V3_SSD11_R")
	)
	(segment
		(start 307.370734 -35.876738)
		(end 308.081934 -35.876738)
		(width 0.13208)
		(layer "F.Cu")
		(net "PWRGD_P3V3_SSD11_R")
	)
	(segment
		(start 311.408572 -36.232592)
		(end 311.79516 -36.232592)
		(width 0.13208)
		(layer "F.Cu")
		(net "PWRGD_P3V3_SSD11_R")
	)
	(segment
		(start 307.370734 -35.876738)
		(end 306.627784 -35.876738)
		(width 0.13208)
		(layer "F.Cu")
		(net "PWRGD_P3V3_SSD11_R")
	)
	(via
		(at 307.370734 -35.876738)
		(size 0.508)
		(drill 0.254)
		(layers "F.Cu" "B.Cu")
		(net "PWRGD_P3V3_SSD11_R")
	)
	(via
		(at 321.078352 -81.377028)
		(size 0.508)
		(drill 0.254)
		(layers "F.Cu" "B.Cu")
		(net "PWRGD_P3V3_SSD11_R")
	)
	(via
		(at 339.293962 -214.787226)
		(size 0.4572)
		(drill 0.254)
		(layers "F.Cu" "B.Cu")
		(net "PWRGD_P3V3_SSD11_R")
	)
	(via
		(at 318.810894 -62.051438)
		(size 0.508)
		(drill 0.254)
		(layers "F.Cu" "B.Cu")
		(net "PWRGD_P3V3_SSD11_R")
	)
	(segment
		(start 318.810894 -62.051438)
		(end 319.239392 -62.479936)
		(width 0.15494)
		(layer "In5.Cu")
		(net "PWRGD_P3V3_SSD11_R")
	)
	(segment
		(start 320.070988 -45.807376)
		(end 320.070988 -61.30036)
		(width 0.15494)
		(layer "In5.Cu")
		(net "PWRGD_P3V3_SSD11_R")
	)
	(segment
		(start 320.070988 -61.30036)
		(end 319.31991 -62.051438)
		(width 0.15494)
		(layer "In5.Cu")
		(net "PWRGD_P3V3_SSD11_R")
	)
	(segment
		(start 307.370734 -35.876738)
		(end 310.14035 -35.876738)
		(width 0.15494)
		(layer "In5.Cu")
		(net "PWRGD_P3V3_SSD11_R")
	)
	(segment
		(start 319.239392 -62.479936)
		(end 319.239392 -78.62951)
		(width 0.15494)
		(layer "In5.Cu")
		(net "PWRGD_P3V3_SSD11_R")
	)
	(segment
		(start 319.239392 -78.62951)
		(end 321.078352 -80.46847)
		(width 0.15494)
		(layer "In5.Cu")
		(net "PWRGD_P3V3_SSD11_R")
	)
	(segment
		(start 319.31991 -62.051438)
		(end 318.810894 -62.051438)
		(width 0.15494)
		(layer "In5.Cu")
		(net "PWRGD_P3V3_SSD11_R")
	)
	(segment
		(start 310.14035 -35.876738)
		(end 320.070988 -45.807376)
		(width 0.15494)
		(layer "In5.Cu")
		(net "PWRGD_P3V3_SSD11_R")
	)
	(segment
		(start 321.078352 -80.46847)
		(end 321.078352 -81.377028)
		(width 0.15494)
		(layer "In5.Cu")
		(net "PWRGD_P3V3_SSD11_R")
	)
	(segment
		(start 337.872578 -206.850488)
		(end 337.872578 -210.992212)
		(width 0.15494)
		(layer "In7.Cu")
		(net "PWRGD_P3V3_SSD11_R")
	)
	(segment
		(start 341.330026 -170.9674)
		(end 344.488516 -174.12589)
		(width 0.15494)
		(layer "In7.Cu")
		(net "PWRGD_P3V3_SSD11_R")
	)
	(segment
		(start 339.6488 -163.25469)
		(end 338.655152 -164.248338)
		(width 0.15494)
		(layer "In7.Cu")
		(net "PWRGD_P3V3_SSD11_R")
	)
	(segment
		(start 336.864706 -188.30036)
		(end 336.864706 -199.034146)
		(width 0.15494)
		(layer "In7.Cu")
		(net "PWRGD_P3V3_SSD11_R")
	)
	(segment
		(start 321.078352 -81.377028)
		(end 321.915028 -81.377028)
		(width 0.15494)
		(layer "In7.Cu")
		(net "PWRGD_P3V3_SSD11_R")
	)
	(segment
		(start 322.326 -81.788)
		(end 322.326 -82.677)
		(width 0.15494)
		(layer "In7.Cu")
		(net "PWRGD_P3V3_SSD11_R")
	)
	(segment
		(start 340.500462 -170.9674)
		(end 341.330026 -170.9674)
		(width 0.15494)
		(layer "In7.Cu")
		(net "PWRGD_P3V3_SSD11_R")
	)
	(segment
		(start 337.8962 -187.268866)
		(end 336.864706 -188.30036)
		(width 0.15494)
		(layer "In7.Cu")
		(net "PWRGD_P3V3_SSD11_R")
	)
	(segment
		(start 340.2838 -146.574764)
		(end 340.2838 -147.7264)
		(width 0.15494)
		(layer "In7.Cu")
		(net "PWRGD_P3V3_SSD11_R")
	)
	(segment
		(start 344.488516 -177.306224)
		(end 337.8962 -183.89854)
		(width 0.15494)
		(layer "In7.Cu")
		(net "PWRGD_P3V3_SSD11_R")
	)
	(segment
		(start 319.358772 -117.841014)
		(end 320.21018 -118.692422)
		(width 0.15494)
		(layer "In7.Cu")
		(net "PWRGD_P3V3_SSD11_R")
	)
	(segment
		(start 340.2838 -147.7264)
		(end 341.0204 -148.463)
		(width 0.15494)
		(layer "In7.Cu")
		(net "PWRGD_P3V3_SSD11_R")
	)
	(segment
		(start 321.489324 -94.493334)
		(end 318.765936 -97.216722)
		(width 0.15494)
		(layer "In7.Cu")
		(net "PWRGD_P3V3_SSD11_R")
	)
	(segment
		(start 322.105782 -86.66988)
		(end 321.489324 -87.286338)
		(width 0.15494)
		(layer "In7.Cu")
		(net "PWRGD_P3V3_SSD11_R")
	)
	(segment
		(start 337.872578 -210.992212)
		(end 338.53501 -211.654644)
		(width 0.15494)
		(layer "In7.Cu")
		(net "PWRGD_P3V3_SSD11_R")
	)
	(segment
		(start 318.765936 -97.216722)
		(end 318.765936 -102.14991)
		(width 0.15494)
		(layer "In7.Cu")
		(net "PWRGD_P3V3_SSD11_R")
	)
	(segment
		(start 340.36 -142.540228)
		(end 340.741 -142.921228)
		(width 0.15494)
		(layer "In7.Cu")
		(net "PWRGD_P3V3_SSD11_R")
	)
	(segment
		(start 340.741 -142.921228)
		(end 340.741 -146.117564)
		(width 0.15494)
		(layer "In7.Cu")
		(net "PWRGD_P3V3_SSD11_R")
	)
	(segment
		(start 338.655152 -169.12209)
		(end 340.500462 -170.9674)
		(width 0.15494)
		(layer "In7.Cu")
		(net "PWRGD_P3V3_SSD11_R")
	)
	(segment
		(start 326.03821 -136.355582)
		(end 336.15503 -136.355582)
		(width 0.15494)
		(layer "In7.Cu")
		(net "PWRGD_P3V3_SSD11_R")
	)
	(segment
		(start 321.915028 -81.377028)
		(end 322.326 -81.788)
		(width 0.15494)
		(layer "In7.Cu")
		(net "PWRGD_P3V3_SSD11_R")
	)
	(segment
		(start 336.15503 -136.355582)
		(end 340.36 -140.560552)
		(width 0.15494)
		(layer "In7.Cu")
		(net "PWRGD_P3V3_SSD11_R")
	)
	(segment
		(start 339.6488 -156.743146)
		(end 338.655152 -157.736794)
		(width 0.15494)
		(layer "In7.Cu")
		(net "PWRGD_P3V3_SSD11_R")
	)
	(segment
		(start 337.573112 -206.551022)
		(end 337.872578 -206.850488)
		(width 0.15494)
		(layer "In7.Cu")
		(net "PWRGD_P3V3_SSD11_R")
	)
	(segment
		(start 338.655152 -164.248338)
		(end 338.655152 -169.12209)
		(width 0.15494)
		(layer "In7.Cu")
		(net "PWRGD_P3V3_SSD11_R")
	)
	(segment
		(start 338.53501 -211.654644)
		(end 338.9122 -212.031834)
		(width 0.0889)
		(layer "In7.Cu")
		(net "PWRGD_P3V3_SSD11_R")
	)
	(segment
		(start 320.21018 -118.692422)
		(end 320.21018 -130.527552)
		(width 0.15494)
		(layer "In7.Cu")
		(net "PWRGD_P3V3_SSD11_R")
	)
	(segment
		(start 340.741 -146.117564)
		(end 340.2838 -146.574764)
		(width 0.15494)
		(layer "In7.Cu")
		(net "PWRGD_P3V3_SSD11_R")
	)
	(segment
		(start 337.058 -204.460602)
		(end 337.573112 -204.975714)
		(width 0.15494)
		(layer "In7.Cu")
		(net "PWRGD_P3V3_SSD11_R")
	)
	(segment
		(start 341.0204 -148.463)
		(end 341.0204 -149.225)
		(width 0.15494)
		(layer "In7.Cu")
		(net "PWRGD_P3V3_SSD11_R")
	)
	(segment
		(start 320.21018 -130.527552)
		(end 326.03821 -136.355582)
		(width 0.15494)
		(layer "In7.Cu")
		(net "PWRGD_P3V3_SSD11_R")
	)
	(segment
		(start 338.655152 -159.39897)
		(end 339.6488 -160.392618)
		(width 0.15494)
		(layer "In7.Cu")
		(net "PWRGD_P3V3_SSD11_R")
	)
	(segment
		(start 340.4362 -149.8092)
		(end 340.4362 -155.0162)
		(width 0.15494)
		(layer "In7.Cu")
		(net "PWRGD_P3V3_SSD11_R")
	)
	(segment
		(start 337.058 -199.22744)
		(end 337.058 -204.460602)
		(width 0.15494)
		(layer "In7.Cu")
		(net "PWRGD_P3V3_SSD11_R")
	)
	(segment
		(start 337.573112 -204.975714)
		(end 337.573112 -206.551022)
		(width 0.15494)
		(layer "In7.Cu")
		(net "PWRGD_P3V3_SSD11_R")
	)
	(segment
		(start 338.9122 -214.405464)
		(end 339.293962 -214.787226)
		(width 0.0889)
		(layer "In7.Cu")
		(net "PWRGD_P3V3_SSD11_R")
	)
	(segment
		(start 319.358772 -102.742746)
		(end 319.358772 -117.841014)
		(width 0.15494)
		(layer "In7.Cu")
		(net "PWRGD_P3V3_SSD11_R")
	)
	(segment
		(start 340.36 -140.560552)
		(end 340.36 -142.540228)
		(width 0.15494)
		(layer "In7.Cu")
		(net "PWRGD_P3V3_SSD11_R")
	)
	(segment
		(start 322.105782 -82.897218)
		(end 322.105782 -86.66988)
		(width 0.15494)
		(layer "In7.Cu")
		(net "PWRGD_P3V3_SSD11_R")
	)
	(segment
		(start 336.864706 -199.034146)
		(end 337.058 -199.22744)
		(width 0.15494)
		(layer "In7.Cu")
		(net "PWRGD_P3V3_SSD11_R")
	)
	(segment
		(start 340.4362 -155.0162)
		(end 339.6488 -155.8036)
		(width 0.15494)
		(layer "In7.Cu")
		(net "PWRGD_P3V3_SSD11_R")
	)
	(segment
		(start 322.326 -82.677)
		(end 322.105782 -82.897218)
		(width 0.15494)
		(layer "In7.Cu")
		(net "PWRGD_P3V3_SSD11_R")
	)
	(segment
		(start 321.489324 -87.286338)
		(end 321.489324 -94.493334)
		(width 0.15494)
		(layer "In7.Cu")
		(net "PWRGD_P3V3_SSD11_R")
	)
	(segment
		(start 341.0204 -149.225)
		(end 340.4362 -149.8092)
		(width 0.15494)
		(layer "In7.Cu")
		(net "PWRGD_P3V3_SSD11_R")
	)
	(segment
		(start 338.655152 -157.736794)
		(end 338.655152 -159.39897)
		(width 0.15494)
		(layer "In7.Cu")
		(net "PWRGD_P3V3_SSD11_R")
	)
	(segment
		(start 339.6488 -155.8036)
		(end 339.6488 -156.743146)
		(width 0.15494)
		(layer "In7.Cu")
		(net "PWRGD_P3V3_SSD11_R")
	)
	(segment
		(start 338.9122 -212.031834)
		(end 338.9122 -214.405464)
		(width 0.0889)
		(layer "In7.Cu")
		(net "PWRGD_P3V3_SSD11_R")
	)
	(segment
		(start 339.6488 -160.392618)
		(end 339.6488 -163.25469)
		(width 0.15494)
		(layer "In7.Cu")
		(net "PWRGD_P3V3_SSD11_R")
	)
	(segment
		(start 344.488516 -174.12589)
		(end 344.488516 -177.306224)
		(width 0.15494)
		(layer "In7.Cu")
		(net "PWRGD_P3V3_SSD11_R")
	)
	(segment
		(start 337.8962 -183.89854)
		(end 337.8962 -187.268866)
		(width 0.15494)
		(layer "In7.Cu")
		(net "PWRGD_P3V3_SSD11_R")
	)
	(segment
		(start 318.765936 -102.14991)
		(end 319.358772 -102.742746)
		(width 0.15494)
		(layer "In7.Cu")
		(net "PWRGD_P3V3_SSD11_R")
	)
	(segment
		(start 126.938786 -174.690024)
		(end 126.621286 -175.007524)
		(width 0.1143)
		(layer "F.Cu")
		(net "CLK_100M_DB2000QL_PEX1_S1_DP")
	)
	(segment
		(start 129.971038 -175.400462)
		(end 129.784856 -175.3235)
		(width 0.1143)
		(layer "F.Cu")
		(net "CLK_100M_DB2000QL_PEX1_S1_DP")
	)
	(segment
		(start 128.015746 -175.3235)
		(end 127.38227 -174.690024)
		(width 0.1143)
		(layer "F.Cu")
		(net "CLK_100M_DB2000QL_PEX1_S1_DP")
	)
	(segment
		(start 127.38227 -174.690024)
		(end 126.938786 -174.690024)
		(width 0.1143)
		(layer "F.Cu")
		(net "CLK_100M_DB2000QL_PEX1_S1_DP")
	)
	(segment
		(start 129.784856 -175.3235)
		(end 128.015746 -175.3235)
		(width 0.1143)
		(layer "F.Cu")
		(net "CLK_100M_DB2000QL_PEX1_S1_DP")
	)
	(segment
		(start 109.838998 -89.356692)
		(end 109.838998 -88.928956)
		(width 0.13462)
		(layer "F.Cu")
		(net "CLK_100M_DB800ZL_SSD7_DN")
	)
	(segment
		(start 109.908086 -91.607132)
		(end 109.908086 -89.42578)
		(width 0.13462)
		(layer "F.Cu")
		(net "CLK_100M_DB800ZL_SSD7_DN")
	)
	(segment
		(start 109.908086 -89.42578)
		(end 109.838998 -89.356692)
		(width 0.13462)
		(layer "F.Cu")
		(net "CLK_100M_DB800ZL_SSD7_DN")
	)
	(segment
		(start 109.581696 -91.933522)
		(end 109.908086 -91.607132)
		(width 0.13462)
		(layer "F.Cu")
		(net "CLK_100M_DB800ZL_SSD7_DN")
	)
	(segment
		(start 221.264988 -223.104202)
		(end 223.467676 -223.104202)
		(width 0.13208)
		(layer "F.Cu")
		(net "SMB_NIC3_SDA")
	)
	(segment
		(start 221.121478 -222.960692)
		(end 221.264988 -223.104202)
		(width 0.13208)
		(layer "F.Cu")
		(net "SMB_NIC3_SDA")
	)
	(segment
		(start 214.646256 -224.882964)
		(end 214.10676 -225.42246)
		(width 0.13208)
		(layer "F.Cu")
		(net "SMB_NIC3_SDA")
	)
	(segment
		(start 215.131142 -224.882964)
		(end 214.646256 -224.882964)
		(width 0.13208)
		(layer "F.Cu")
		(net "SMB_NIC3_SDA")
	)
	(segment
		(start 219.403168 -222.960692)
		(end 221.121478 -222.960692)
		(width 0.13208)
		(layer "F.Cu")
		(net "SMB_NIC3_SDA")
	)
	(segment
		(start 219.403168 -222.960692)
		(end 219.403168 -223.577912)
		(width 0.13208)
		(layer "F.Cu")
		(net "SMB_NIC3_SDA")
	)
	(segment
		(start 218.86799 -224.870264)
		(end 218.733116 -225.005138)
		(width 0.13208)
		(layer "F.Cu")
		(net "SMB_NIC3_SDA")
	)
	(segment
		(start 219.403168 -223.577912)
		(end 218.86799 -224.870264)
		(width 0.13208)
		(layer "F.Cu")
		(net "SMB_NIC3_SDA")
	)
	(segment
		(start 218.733116 -225.005138)
		(end 215.253316 -225.005138)
		(width 0.13208)
		(layer "F.Cu")
		(net "SMB_NIC3_SDA")
	)
	(segment
		(start 215.253316 -225.005138)
		(end 215.131142 -224.882964)
		(width 0.13208)
		(layer "F.Cu")
		(net "SMB_NIC3_SDA")
	)
	(via
		(at 219.403168 -222.960692)
		(size 0.762)
		(drill 0.381)
		(layers "F.Cu" "B.Cu")
		(net "SMB_NIC3_SDA")
	)
	(segment
		(start 130.5052 -186.131454)
		(end 130.5052 -185.434224)
		(width 0.13462)
		(layer "F.Cu")
		(net "CLK_100M_DB2000QL_GPU_REF2_R_DP")
	)
	(segment
		(start 130.5052 -185.434224)
		(end 130.88239 -185.057034)
		(width 0.13462)
		(layer "F.Cu")
		(net "CLK_100M_DB2000QL_GPU_REF2_R_DP")
	)
	(segment
		(start 129.66954 -186.967114)
		(end 130.5052 -186.131454)
		(width 0.13462)
		(layer "F.Cu")
		(net "CLK_100M_DB2000QL_GPU_REF2_R_DP")
	)
	(segment
		(start 129.977896 -188.22289)
		(end 129.66954 -187.914534)
		(width 0.13462)
		(layer "F.Cu")
		(net "CLK_100M_DB2000QL_GPU_REF2_R_DP")
	)
	(segment
		(start 129.66954 -187.914534)
		(end 129.66954 -186.967114)
		(width 0.13462)
		(layer "F.Cu")
		(net "CLK_100M_DB2000QL_GPU_REF2_R_DP")
	)
	(via
		(at 129.977896 -188.22289)
		(size 0.508)
		(drill 0.254)
		(layers "F.Cu" "B.Cu")
		(net "CLK_100M_DB2000QL_GPU_REF2_R_DP")
	)
	(segment
		(start 47.98568 -388.055866)
		(end 48.271176 -387.77037)
		(width 0.13462)
		(layer "B.Cu")
		(net "CLK_100M_DB2000QL_GPU_REF2_R_DP")
	)
	(segment
		(start 48.750982 -387.290564)
		(end 50.0888 -385.952746)
		(width 0.13462)
		(layer "B.Cu")
		(net "CLK_100M_DB2000QL_GPU_REF2_R_DP")
	)
	(segment
		(start 45.97527 -390.066276)
		(end 46.169326 -390.066276)
		(width 0.13462)
		(layer "B.Cu")
		(net "CLK_100M_DB2000QL_GPU_REF2_R_DP")
	)
	(segment
		(start 23.801832 -277.76932)
		(end 21.186902 -275.15439)
		(width 0.13462)
		(layer "B.Cu")
		(net "CLK_100M_DB2000QL_GPU_REF2_R_DP")
	)
	(segment
		(start 21.186902 -268.333728)
		(end 18.3896 -261.580376)
		(width 0.13462)
		(layer "B.Cu")
		(net "CLK_100M_DB2000QL_GPU_REF2_R_DP")
	)
	(segment
		(start 129.352294 -189.265052)
		(end 129.683256 -188.93409)
		(width 0.13462)
		(layer "B.Cu")
		(net "CLK_100M_DB2000QL_GPU_REF2_R_DP")
	)
	(segment
		(start 48.750982 -387.48462)
		(end 48.750982 -387.290564)
		(width 0.13462)
		(layer "B.Cu")
		(net "CLK_100M_DB2000QL_GPU_REF2_R_DP")
	)
	(segment
		(start 46.455076 -389.780526)
		(end 46.455076 -389.58647)
		(width 0.13462)
		(layer "B.Cu")
		(net "CLK_100M_DB2000QL_GPU_REF2_R_DP")
	)
	(segment
		(start 97.642426 -192.65392)
		(end 108.317792 -192.65392)
		(width 0.13462)
		(layer "B.Cu")
		(net "CLK_100M_DB2000QL_GPU_REF2_R_DP")
	)
	(segment
		(start 108.317792 -192.65392)
		(end 113.695988 -187.275724)
		(width 0.13462)
		(layer "B.Cu")
		(net "CLK_100M_DB2000QL_GPU_REF2_R_DP")
	)
	(segment
		(start 44.322746 -391.7188)
		(end 45.97527 -390.066276)
		(width 0.13462)
		(layer "B.Cu")
		(net "CLK_100M_DB2000QL_GPU_REF2_R_DP")
	)
	(segment
		(start 46.934374 -389.300974)
		(end 47.220378 -389.015224)
		(width 0.13462)
		(layer "B.Cu")
		(net "CLK_100M_DB2000QL_GPU_REF2_R_DP")
	)
	(segment
		(start 25.35936 -326.642476)
		(end 21.4884 -322.771262)
		(width 0.13462)
		(layer "B.Cu")
		(net "CLK_100M_DB2000QL_GPU_REF2_R_DP")
	)
	(segment
		(start 50.0888 -365.633)
		(end 46.32452 -361.86872)
		(width 0.13462)
		(layer "B.Cu")
		(net "CLK_100M_DB2000QL_GPU_REF2_R_DP")
	)
	(segment
		(start 25.754584 -304.071782)
		(end 25.754584 -298.518326)
		(width 0.13462)
		(layer "B.Cu")
		(net "CLK_100M_DB2000QL_GPU_REF2_R_DP")
	)
	(segment
		(start 47.98568 -388.249922)
		(end 47.98568 -388.055866)
		(width 0.13462)
		(layer "B.Cu")
		(net "CLK_100M_DB2000QL_GPU_REF2_R_DP")
	)
	(segment
		(start 129.683256 -188.51753)
		(end 129.977896 -188.22289)
		(width 0.13462)
		(layer "B.Cu")
		(net "CLK_100M_DB2000QL_GPU_REF2_R_DP")
	)
	(segment
		(start 44.70273 -400.909282)
		(end 44.322746 -400.529298)
		(width 0.13462)
		(layer "B.Cu")
		(net "CLK_100M_DB2000QL_GPU_REF2_R_DP")
	)
	(segment
		(start 18.3896 -250.409456)
		(end 49.424336 -219.37472)
		(width 0.13462)
		(layer "B.Cu")
		(net "CLK_100M_DB2000QL_GPU_REF2_R_DP")
	)
	(segment
		(start 25.754584 -298.518326)
		(end 23.801832 -296.565574)
		(width 0.13462)
		(layer "B.Cu")
		(net "CLK_100M_DB2000QL_GPU_REF2_R_DP")
	)
	(segment
		(start 64.528192 -219.37472)
		(end 89.953592 -193.94932)
		(width 0.13462)
		(layer "B.Cu")
		(net "CLK_100M_DB2000QL_GPU_REF2_R_DP")
	)
	(segment
		(start 44.322746 -400.529298)
		(end 44.322746 -391.7188)
		(width 0.13462)
		(layer "B.Cu")
		(net "CLK_100M_DB2000QL_GPU_REF2_R_DP")
	)
	(segment
		(start 46.32452 -361.86872)
		(end 46.32452 -341.994236)
		(width 0.13462)
		(layer "B.Cu")
		(net "CLK_100M_DB2000QL_GPU_REF2_R_DP")
	)
	(segment
		(start 25.360122 -326.642984)
		(end 25.35936 -326.642476)
		(width 0.13462)
		(layer "B.Cu")
		(net "CLK_100M_DB2000QL_GPU_REF2_R_DP")
	)
	(segment
		(start 21.4884 -322.771262)
		(end 21.4884 -308.337966)
		(width 0.13462)
		(layer "B.Cu")
		(net "CLK_100M_DB2000QL_GPU_REF2_R_DP")
	)
	(segment
		(start 113.695988 -187.275724)
		(end 123.726194 -187.275724)
		(width 0.13462)
		(layer "B.Cu")
		(net "CLK_100M_DB2000QL_GPU_REF2_R_DP")
	)
	(segment
		(start 129.683256 -188.93409)
		(end 129.683256 -188.51753)
		(width 0.13462)
		(layer "B.Cu")
		(net "CLK_100M_DB2000QL_GPU_REF2_R_DP")
	)
	(segment
		(start 47.699676 -388.535672)
		(end 47.98568 -388.249922)
		(width 0.13462)
		(layer "B.Cu")
		(net "CLK_100M_DB2000QL_GPU_REF2_R_DP")
	)
	(segment
		(start 96.347026 -193.94932)
		(end 97.642426 -192.65392)
		(width 0.13462)
		(layer "B.Cu")
		(net "CLK_100M_DB2000QL_GPU_REF2_R_DP")
	)
	(segment
		(start 45.77461 -340.93785)
		(end 25.360122 -326.642984)
		(width 0.13462)
		(layer "B.Cu")
		(net "CLK_100M_DB2000QL_GPU_REF2_R_DP")
	)
	(segment
		(start 125.71603 -189.265052)
		(end 129.352294 -189.265052)
		(width 0.13462)
		(layer "B.Cu")
		(net "CLK_100M_DB2000QL_GPU_REF2_R_DP")
	)
	(segment
		(start 48.271176 -387.77037)
		(end 48.464978 -387.77037)
		(width 0.13462)
		(layer "B.Cu")
		(net "CLK_100M_DB2000QL_GPU_REF2_R_DP")
	)
	(segment
		(start 89.953592 -193.94932)
		(end 96.347026 -193.94932)
		(width 0.13462)
		(layer "B.Cu")
		(net "CLK_100M_DB2000QL_GPU_REF2_R_DP")
	)
	(segment
		(start 46.32452 -341.994236)
		(end 45.77461 -340.93785)
		(width 0.13462)
		(layer "B.Cu")
		(net "CLK_100M_DB2000QL_GPU_REF2_R_DP")
	)
	(segment
		(start 45.388022 -400.909282)
		(end 44.70273 -400.909282)
		(width 0.13462)
		(layer "B.Cu")
		(net "CLK_100M_DB2000QL_GPU_REF2_R_DP")
	)
	(segment
		(start 49.424336 -219.37472)
		(end 64.528192 -219.37472)
		(width 0.13462)
		(layer "B.Cu")
		(net "CLK_100M_DB2000QL_GPU_REF2_R_DP")
	)
	(segment
		(start 123.726194 -187.275724)
		(end 125.71603 -189.265052)
		(width 0.13462)
		(layer "B.Cu")
		(net "CLK_100M_DB2000QL_GPU_REF2_R_DP")
	)
	(segment
		(start 50.0888 -385.952746)
		(end 50.0888 -365.633)
		(width 0.13462)
		(layer "B.Cu")
		(net "CLK_100M_DB2000QL_GPU_REF2_R_DP")
	)
	(segment
		(start 46.740572 -389.300974)
		(end 46.934374 -389.300974)
		(width 0.13462)
		(layer "B.Cu")
		(net "CLK_100M_DB2000QL_GPU_REF2_R_DP")
	)
	(segment
		(start 47.220378 -388.821168)
		(end 47.505874 -388.535672)
		(width 0.13462)
		(layer "B.Cu")
		(net "CLK_100M_DB2000QL_GPU_REF2_R_DP")
	)
	(segment
		(start 23.801832 -296.565574)
		(end 23.801832 -277.76932)
		(width 0.13462)
		(layer "B.Cu")
		(net "CLK_100M_DB2000QL_GPU_REF2_R_DP")
	)
	(segment
		(start 47.505874 -388.535672)
		(end 47.699676 -388.535672)
		(width 0.13462)
		(layer "B.Cu")
		(net "CLK_100M_DB2000QL_GPU_REF2_R_DP")
	)
	(segment
		(start 45.509942 -400.787362)
		(end 45.388022 -400.909282)
		(width 0.13462)
		(layer "B.Cu")
		(net "CLK_100M_DB2000QL_GPU_REF2_R_DP")
	)
	(segment
		(start 46.169326 -390.066276)
		(end 46.455076 -389.780526)
		(width 0.13462)
		(layer "B.Cu")
		(net "CLK_100M_DB2000QL_GPU_REF2_R_DP")
	)
	(segment
		(start 21.4884 -308.337966)
		(end 25.754584 -304.071782)
		(width 0.13462)
		(layer "B.Cu")
		(net "CLK_100M_DB2000QL_GPU_REF2_R_DP")
	)
	(segment
		(start 48.464978 -387.77037)
		(end 48.750982 -387.48462)
		(width 0.13462)
		(layer "B.Cu")
		(net "CLK_100M_DB2000QL_GPU_REF2_R_DP")
	)
	(segment
		(start 47.220378 -389.015224)
		(end 47.220378 -388.821168)
		(width 0.13462)
		(layer "B.Cu")
		(net "CLK_100M_DB2000QL_GPU_REF2_R_DP")
	)
	(segment
		(start 45.509942 -400.390106)
		(end 45.509942 -400.787362)
		(width 0.13462)
		(layer "B.Cu")
		(net "CLK_100M_DB2000QL_GPU_REF2_R_DP")
	)
	(segment
		(start 21.186902 -275.15439)
		(end 21.186902 -268.333728)
		(width 0.13462)
		(layer "B.Cu")
		(net "CLK_100M_DB2000QL_GPU_REF2_R_DP")
	)
	(segment
		(start 46.455076 -389.58647)
		(end 46.740572 -389.300974)
		(width 0.13462)
		(layer "B.Cu")
		(net "CLK_100M_DB2000QL_GPU_REF2_R_DP")
	)
	(segment
		(start 18.3896 -261.580376)
		(end 18.3896 -250.409456)
		(width 0.13462)
		(layer "B.Cu")
		(net "CLK_100M_DB2000QL_GPU_REF2_R_DP")
	)
	(segment
		(start 334.04683 -238.23295)
		(end 333.39405 -238.88573)
		(width 0.13208)
		(layer "F.Cu")
		(net "MB_SWB_PWRGD_R")
	)
	(segment
		(start 333.39405 -238.88573)
		(end 333.39405 -239.769396)
		(width 0.13208)
		(layer "F.Cu")
		(net "MB_SWB_PWRGD_R")
	)
	(segment
		(start 334.518 -237.25505)
		(end 334.518 -238.23295)
		(width 0.13208)
		(layer "F.Cu")
		(net "MB_SWB_PWRGD_R")
	)
	(segment
		(start 334.518 -238.23295)
		(end 334.04683 -238.23295)
		(width 0.13208)
		(layer "F.Cu")
		(net "MB_SWB_PWRGD_R")
	)
	(segment
		(start 334.122014 -240.808002)
		(end 334.122014 -240.49736)
		(width 0.13208)
		(layer "F.Cu")
		(net "MB_SWB_PWRGD_R")
	)
	(segment
		(start 334.122014 -240.49736)
		(end 333.39405 -239.769396)
		(width 0.13208)
		(layer "F.Cu")
		(net "MB_SWB_PWRGD_R")
	)
	(via
		(at 333.39405 -239.769396)
		(size 0.508)
		(drill 0.254)
		(layers "F.Cu" "B.Cu")
		(net "MB_SWB_PWRGD_R")
	)
	(segment
		(start 331.74305 -239.776)
		(end 333.387446 -239.776)
		(width 0.13208)
		(layer "B.Cu")
		(net "MB_SWB_PWRGD_R")
	)
	(segment
		(start 333.387446 -239.776)
		(end 333.39405 -239.769396)
		(width 0.13208)
		(layer "B.Cu")
		(net "MB_SWB_PWRGD_R")
	)
	(segment
		(start 77.601318 -53.051456)
		(end 77.867764 -53.051456)
		(width 0.13208)
		(layer "F.Cu")
		(net "PWRGD_P12V_SSD2")
	)
	(segment
		(start 77.13726 -53.023008)
		(end 77.13726 -52.587398)
		(width 0.13208)
		(layer "F.Cu")
		(net "PWRGD_P12V_SSD2")
	)
	(segment
		(start 77.867764 -52.035456)
		(end 77.867764 -53.051456)
		(width 0.13208)
		(layer "F.Cu")
		(net "PWRGD_P12V_SSD2")
	)
	(segment
		(start 76.147168 -53.644038)
		(end 76.51623 -53.644038)
		(width 0.13208)
		(layer "F.Cu")
		(net "PWRGD_P12V_SSD2")
	)
	(segment
		(start 77.13726 -52.587398)
		(end 77.601318 -53.051456)
		(width 0.13208)
		(layer "F.Cu")
		(net "PWRGD_P12V_SSD2")
	)
	(segment
		(start 76.51623 -53.644038)
		(end 77.13726 -53.023008)
		(width 0.13208)
		(layer "F.Cu")
		(net "PWRGD_P12V_SSD2")
	)
	(via
		(at 77.13726 -52.587398)
		(size 0.508)
		(drill 0.254)
		(layers "F.Cu" "B.Cu")
		(net "PWRGD_P12V_SSD2")
	)
	(segment
		(start 287.683448 -61.487812)
		(end 285.83636 -61.487812)
		(width 0.13208)
		(layer "F.Cu")
		(net "PWRGD_P12V_SSD10_R")
	)
	(segment
		(start 285.83636 -61.487812)
		(end 285.204408 -62.119764)
		(width 0.13208)
		(layer "F.Cu")
		(net "PWRGD_P12V_SSD10_R")
	)
	(segment
		(start 285.829502 -65.511426)
		(end 298.96689 -65.511426)
		(width 0.13208)
		(layer "F.Cu")
		(net "PWRGD_P12V_SSD10_R")
	)
	(segment
		(start 310.867806 -53.051456)
		(end 311.523126 -53.051456)
		(width 0.13208)
		(layer "F.Cu")
		(net "PWRGD_P12V_SSD10_R")
	)
	(segment
		(start 285.204408 -64.886332)
		(end 285.829502 -65.511426)
		(width 0.13208)
		(layer "F.Cu")
		(net "PWRGD_P12V_SSD10_R")
	)
	(segment
		(start 338.093812 -212.786976)
		(end 337.694016 -212.38718)
		(width 0.13208)
		(layer "F.Cu")
		(net "PWRGD_P12V_SSD10_R")
	)
	(segment
		(start 285.204408 -62.119764)
		(end 285.204408 -64.886332)
		(width 0.13208)
		(layer "F.Cu")
		(net "PWRGD_P12V_SSD10_R")
	)
	(via
		(at 298.96689 -65.511426)
		(size 0.508)
		(drill 0.254)
		(layers "F.Cu" "B.Cu")
		(net "PWRGD_P12V_SSD10_R")
	)
	(via
		(at 337.694016 -212.38718)
		(size 0.4572)
		(drill 0.254)
		(layers "F.Cu" "B.Cu")
		(net "PWRGD_P12V_SSD10_R")
	)
	(via
		(at 320.461386 -80.837532)
		(size 0.508)
		(drill 0.254)
		(layers "F.Cu" "B.Cu")
		(net "PWRGD_P12V_SSD10_R")
	)
	(via
		(at 311.523126 -53.051456)
		(size 0.508)
		(drill 0.254)
		(layers "F.Cu" "B.Cu")
		(net "PWRGD_P12V_SSD10_R")
	)
	(segment
		(start 309.461154 -57.501028)
		(end 309.461154 -55.113428)
		(width 0.15494)
		(layer "In5.Cu")
		(net "PWRGD_P12V_SSD10_R")
	)
	(segment
		(start 309.943754 -57.983628)
		(end 309.461154 -57.501028)
		(width 0.15494)
		(layer "In5.Cu")
		(net "PWRGD_P12V_SSD10_R")
	)
	(segment
		(start 312.0898 -56.533034)
		(end 312.0898 -53.61813)
		(width 0.15494)
		(layer "In5.Cu")
		(net "PWRGD_P12V_SSD10_R")
	)
	(segment
		(start 311.425082 -66.279776)
		(end 311.425082 -57.197752)
		(width 0.15494)
		(layer "In5.Cu")
		(net "PWRGD_P12V_SSD10_R")
	)
	(segment
		(start 309.461154 -55.113428)
		(end 311.523126 -53.051456)
		(width 0.15494)
		(layer "In5.Cu")
		(net "PWRGD_P12V_SSD10_R")
	)
	(segment
		(start 309.586376 -64.598042)
		(end 309.943754 -64.240664)
		(width 0.15494)
		(layer "In5.Cu")
		(net "PWRGD_P12V_SSD10_R")
	)
	(segment
		(start 312.0898 -53.61813)
		(end 311.523126 -53.051456)
		(width 0.15494)
		(layer "In5.Cu")
		(net "PWRGD_P12V_SSD10_R")
	)
	(segment
		(start 298.96689 -65.511426)
		(end 302.610774 -65.511426)
		(width 0.15494)
		(layer "In5.Cu")
		(net "PWRGD_P12V_SSD10_R")
	)
	(segment
		(start 318.699642 -73.554336)
		(end 311.425082 -66.279776)
		(width 0.15494)
		(layer "In5.Cu")
		(net "PWRGD_P12V_SSD10_R")
	)
	(segment
		(start 311.425082 -57.197752)
		(end 312.0898 -56.533034)
		(width 0.15494)
		(layer "In5.Cu")
		(net "PWRGD_P12V_SSD10_R")
	)
	(segment
		(start 309.943754 -64.240664)
		(end 309.943754 -57.983628)
		(width 0.15494)
		(layer "In5.Cu")
		(net "PWRGD_P12V_SSD10_R")
	)
	(segment
		(start 320.461386 -80.837532)
		(end 318.699642 -79.075788)
		(width 0.15494)
		(layer "In5.Cu")
		(net "PWRGD_P12V_SSD10_R")
	)
	(segment
		(start 303.524158 -64.598042)
		(end 309.586376 -64.598042)
		(width 0.15494)
		(layer "In5.Cu")
		(net "PWRGD_P12V_SSD10_R")
	)
	(segment
		(start 302.610774 -65.511426)
		(end 303.524158 -64.598042)
		(width 0.15494)
		(layer "In5.Cu")
		(net "PWRGD_P12V_SSD10_R")
	)
	(segment
		(start 318.699642 -79.075788)
		(end 318.699642 -73.554336)
		(width 0.15494)
		(layer "In5.Cu")
		(net "PWRGD_P12V_SSD10_R")
	)
	(segment
		(start 335.8134 -187.350654)
		(end 336.2452 -186.918854)
		(width 0.15494)
		(layer "In7.Cu")
		(net "PWRGD_P12V_SSD10_R")
	)
	(segment
		(start 319.77076 -119.18315)
		(end 318.836548 -118.248938)
		(width 0.15494)
		(layer "In7.Cu")
		(net "PWRGD_P12V_SSD10_R")
	)
	(segment
		(start 336.560414 -207.071468)
		(end 336.560414 -205.264766)
		(width 0.15494)
		(layer "In7.Cu")
		(net "PWRGD_P12V_SSD10_R")
	)
	(segment
		(start 344.049096 -174.201074)
		(end 341.299038 -171.451016)
		(width 0.15494)
		(layer "In7.Cu")
		(net "PWRGD_P12V_SSD10_R")
	)
	(segment
		(start 339.1662 -154.5717)
		(end 339.725 -154.0129)
		(width 0.15494)
		(layer "In7.Cu")
		(net "PWRGD_P12V_SSD10_R")
	)
	(segment
		(start 337.4136 -210.6422)
		(end 337.4136 -207.924654)
		(width 0.15494)
		(layer "In7.Cu")
		(net "PWRGD_P12V_SSD10_R")
	)
	(segment
		(start 339.725 -154.0129)
		(end 339.725 -145.3134)
		(width 0.15494)
		(layer "In7.Cu")
		(net "PWRGD_P12V_SSD10_R")
	)
	(segment
		(start 320.461386 -81.447386)
		(end 320.461386 -80.837532)
		(width 0.15494)
		(layer "In7.Cu")
		(net "PWRGD_P12V_SSD10_R")
	)
	(segment
		(start 338.1502 -169.2148)
		(end 338.1502 -157.6324)
		(width 0.15494)
		(layer "In7.Cu")
		(net "PWRGD_P12V_SSD10_R")
	)
	(segment
		(start 336.042 -199.517)
		(end 335.8134 -199.2884)
		(width 0.15494)
		(layer "In7.Cu")
		(net "PWRGD_P12V_SSD10_R")
	)
	(segment
		(start 341.299038 -171.451016)
		(end 340.386416 -171.451016)
		(width 0.15494)
		(layer "In7.Cu")
		(net "PWRGD_P12V_SSD10_R")
	)
	(segment
		(start 337.2612 -210.7946)
		(end 337.4136 -210.6422)
		(width 0.15494)
		(layer "In7.Cu")
		(net "PWRGD_P12V_SSD10_R")
	)
	(segment
		(start 344.049096 -177.170842)
		(end 344.049096 -174.201074)
		(width 0.15494)
		(layer "In7.Cu")
		(net "PWRGD_P12V_SSD10_R")
	)
	(segment
		(start 336.2452 -186.918854)
		(end 336.2452 -184.974738)
		(width 0.15494)
		(layer "In7.Cu")
		(net "PWRGD_P12V_SSD10_R")
	)
	(segment
		(start 337.694016 -212.38718)
		(end 337.694016 -212.167216)
		(width 0.15494)
		(layer "In7.Cu")
		(net "PWRGD_P12V_SSD10_R")
	)
	(segment
		(start 339.1662 -156.6164)
		(end 339.1662 -154.5717)
		(width 0.15494)
		(layer "In7.Cu")
		(net "PWRGD_P12V_SSD10_R")
	)
	(segment
		(start 318.836548 -102.84206)
		(end 318.326516 -102.332028)
		(width 0.15494)
		(layer "In7.Cu")
		(net "PWRGD_P12V_SSD10_R")
	)
	(segment
		(start 319.77076 -130.91922)
		(end 319.77076 -119.18315)
		(width 0.15494)
		(layer "In7.Cu")
		(net "PWRGD_P12V_SSD10_R")
	)
	(segment
		(start 321.049904 -87.006176)
		(end 321.7164 -86.33968)
		(width 0.15494)
		(layer "In7.Cu")
		(net "PWRGD_P12V_SSD10_R")
	)
	(segment
		(start 338.1502 -157.6324)
		(end 339.1662 -156.6164)
		(width 0.15494)
		(layer "In7.Cu")
		(net "PWRGD_P12V_SSD10_R")
	)
	(segment
		(start 321.7164 -86.33968)
		(end 321.7164 -82.7024)
		(width 0.15494)
		(layer "In7.Cu")
		(net "PWRGD_P12V_SSD10_R")
	)
	(segment
		(start 340.386416 -171.451016)
		(end 338.1502 -169.2148)
		(width 0.15494)
		(layer "In7.Cu")
		(net "PWRGD_P12V_SSD10_R")
	)
	(segment
		(start 336.2452 -184.974738)
		(end 344.049096 -177.170842)
		(width 0.15494)
		(layer "In7.Cu")
		(net "PWRGD_P12V_SSD10_R")
	)
	(segment
		(start 318.836548 -118.248938)
		(end 318.836548 -102.84206)
		(width 0.15494)
		(layer "In7.Cu")
		(net "PWRGD_P12V_SSD10_R")
	)
	(segment
		(start 335.8134 -199.2884)
		(end 335.8134 -187.350654)
		(width 0.15494)
		(layer "In7.Cu")
		(net "PWRGD_P12V_SSD10_R")
	)
	(segment
		(start 318.326516 -97.034604)
		(end 321.049904 -94.311216)
		(width 0.15494)
		(layer "In7.Cu")
		(net "PWRGD_P12V_SSD10_R")
	)
	(segment
		(start 325.646542 -136.795002)
		(end 319.77076 -130.91922)
		(width 0.15494)
		(layer "In7.Cu")
		(net "PWRGD_P12V_SSD10_R")
	)
	(segment
		(start 337.694016 -212.167216)
		(end 337.2612 -211.7344)
		(width 0.15494)
		(layer "In7.Cu")
		(net "PWRGD_P12V_SSD10_R")
	)
	(segment
		(start 337.2612 -211.7344)
		(end 337.2612 -210.7946)
		(width 0.15494)
		(layer "In7.Cu")
		(net "PWRGD_P12V_SSD10_R")
	)
	(segment
		(start 339.36813 -140.208)
		(end 335.955132 -136.795002)
		(width 0.15494)
		(layer "In7.Cu")
		(net "PWRGD_P12V_SSD10_R")
	)
	(segment
		(start 336.560414 -205.264766)
		(end 336.042 -204.746352)
		(width 0.15494)
		(layer "In7.Cu")
		(net "PWRGD_P12V_SSD10_R")
	)
	(segment
		(start 318.326516 -102.332028)
		(end 318.326516 -97.034604)
		(width 0.15494)
		(layer "In7.Cu")
		(net "PWRGD_P12V_SSD10_R")
	)
	(segment
		(start 339.36813 -144.95653)
		(end 339.36813 -140.208)
		(width 0.15494)
		(layer "In7.Cu")
		(net "PWRGD_P12V_SSD10_R")
	)
	(segment
		(start 336.042 -204.746352)
		(end 336.042 -199.517)
		(width 0.15494)
		(layer "In7.Cu")
		(net "PWRGD_P12V_SSD10_R")
	)
	(segment
		(start 339.725 -145.3134)
		(end 339.36813 -144.95653)
		(width 0.15494)
		(layer "In7.Cu")
		(net "PWRGD_P12V_SSD10_R")
	)
	(segment
		(start 321.049904 -94.311216)
		(end 321.049904 -87.006176)
		(width 0.15494)
		(layer "In7.Cu")
		(net "PWRGD_P12V_SSD10_R")
	)
	(segment
		(start 321.7164 -82.7024)
		(end 320.461386 -81.447386)
		(width 0.15494)
		(layer "In7.Cu")
		(net "PWRGD_P12V_SSD10_R")
	)
	(segment
		(start 335.955132 -136.795002)
		(end 325.646542 -136.795002)
		(width 0.15494)
		(layer "In7.Cu")
		(net "PWRGD_P12V_SSD10_R")
	)
	(segment
		(start 337.4136 -207.924654)
		(end 336.560414 -207.071468)
		(width 0.15494)
		(layer "In7.Cu")
		(net "PWRGD_P12V_SSD10_R")
	)
	(segment
		(start 110.182406 -91.619832)
		(end 110.182406 -89.412064)
		(width 0.13462)
		(layer "F.Cu")
		(net "CLK_100M_DB800ZL_SSD7_DP")
	)
	(segment
		(start 110.239048 -89.355422)
		(end 110.239048 -88.928956)
		(width 0.13462)
		(layer "F.Cu")
		(net "CLK_100M_DB800ZL_SSD7_DP")
	)
	(segment
		(start 110.182406 -89.412064)
		(end 110.239048 -89.355422)
		(width 0.13462)
		(layer "F.Cu")
		(net "CLK_100M_DB800ZL_SSD7_DP")
	)
	(segment
		(start 110.496096 -91.933522)
		(end 110.182406 -91.619832)
		(width 0.13462)
		(layer "F.Cu")
		(net "CLK_100M_DB800ZL_SSD7_DP")
	)
	(segment
		(start 236.023658 -150.959566)
		(end 236.359192 -151.2951)
		(width 0.1143)
		(layer "F.Cu")
		(net "CLK_100M_PEX2_REF_R_DN")
	)
	(segment
		(start 269.0495 -299.699934)
		(end 268.57452 -299.224954)
		(width 0.1143)
		(layer "F.Cu")
		(net "CLK_100M_PEX2_REF_R_DN")
	)
	(segment
		(start 236.359192 -151.2951)
		(end 236.925612 -151.2951)
		(width 0.1143)
		(layer "F.Cu")
		(net "CLK_100M_PEX2_REF_R_DN")
	)
	(segment
		(start 236.925612 -151.2951)
		(end 237.170214 -151.050498)
		(width 0.1143)
		(layer "F.Cu")
		(net "CLK_100M_PEX2_REF_R_DN")
	)
	(segment
		(start 269.049754 -299.699934)
		(end 269.0495 -299.699934)
		(width 0.1143)
		(layer "F.Cu")
		(net "CLK_100M_PEX2_REF_R_DN")
	)
	(via
		(at 237.170214 -151.050498)
		(size 0.508)
		(drill 0.254)
		(layers "F.Cu" "B.Cu")
		(net "CLK_100M_PEX2_REF_R_DN")
	)
	(via
		(at 268.57452 -299.224954)
		(size 0.4064)
		(drill 0.2032)
		(layers "F.Cu" "B.Cu")
		(net "CLK_100M_PEX2_REF_R_DN")
	)
	(segment
		(start 243.230146 -215.332818)
		(end 244.3226 -216.425272)
		(width 0.1143)
		(layer "B.Cu")
		(net "CLK_100M_PEX2_REF_R_DN")
	)
	(segment
		(start 253.109222 -188.796676)
		(end 249.835162 -192.070736)
		(width 0.1143)
		(layer "B.Cu")
		(net "CLK_100M_PEX2_REF_R_DN")
	)
	(segment
		(start 237.461044 -156.074872)
		(end 237.461044 -162.310064)
		(width 0.1143)
		(layer "B.Cu")
		(net "CLK_100M_PEX2_REF_R_DN")
	)
	(segment
		(start 243.75237 -212.279484)
		(end 243.5098 -212.865716)
		(width 0.1143)
		(layer "B.Cu")
		(net "CLK_100M_PEX2_REF_R_DN")
	)
	(segment
		(start 267.045694 -299.34789)
		(end 267.329412 -299.631608)
		(width 0.1143)
		(layer "B.Cu")
		(net "CLK_100M_PEX2_REF_R_DN")
	)
	(segment
		(start 245.950486 -208.983072)
		(end 244.606064 -210.327494)
		(width 0.1143)
		(layer "B.Cu")
		(net "CLK_100M_PEX2_REF_R_DN")
	)
	(segment
		(start 256.185924 -274.282662)
		(end 261.71398 -279.810972)
		(width 0.1143)
		(layer "B.Cu")
		(net "CLK_100M_PEX2_REF_R_DN")
	)
	(segment
		(start 243.223796 -221.973648)
		(end 243.223796 -230.86187)
		(width 0.1143)
		(layer "B.Cu")
		(net "CLK_100M_PEX2_REF_R_DN")
	)
	(segment
		(start 249.25401 -192.070736)
		(end 246.888254 -194.436492)
		(width 0.1143)
		(layer "B.Cu")
		(net "CLK_100M_PEX2_REF_R_DN")
	)
	(segment
		(start 268.9479 -299.313854)
		(end 268.859 -299.224954)
		(width 0.0889)
		(layer "B.Cu")
		(net "CLK_100M_PEX2_REF_R_DN")
	)
	(segment
		(start 249.835162 -192.070736)
		(end 249.25401 -192.070736)
		(width 0.1143)
		(layer "B.Cu")
		(net "CLK_100M_PEX2_REF_R_DN")
	)
	(segment
		(start 243.223796 -230.86187)
		(end 252.0188 -239.656874)
		(width 0.1143)
		(layer "B.Cu")
		(net "CLK_100M_PEX2_REF_R_DN")
	)
	(segment
		(start 268.673326 -299.714158)
		(end 268.9479 -299.439584)
		(width 0.0889)
		(layer "B.Cu")
		(net "CLK_100M_PEX2_REF_R_DN")
	)
	(segment
		(start 261.71398 -295.67378)
		(end 261.997698 -295.957498)
		(width 0.1143)
		(layer "B.Cu")
		(net "CLK_100M_PEX2_REF_R_DN")
	)
	(segment
		(start 252.0188 -264.221722)
		(end 256.185924 -274.282662)
		(width 0.1143)
		(layer "B.Cu")
		(net "CLK_100M_PEX2_REF_R_DN")
	)
	(segment
		(start 262.1915 -295.957498)
		(end 262.475726 -296.24147)
		(width 0.1143)
		(layer "B.Cu")
		(net "CLK_100M_PEX2_REF_R_DN")
	)
	(segment
		(start 261.997698 -295.957498)
		(end 262.1915 -295.957498)
		(width 0.1143)
		(layer "B.Cu")
		(net "CLK_100M_PEX2_REF_R_DN")
	)
	(segment
		(start 244.3226 -216.425272)
		(end 244.3226 -217.97772)
		(width 0.1143)
		(layer "B.Cu")
		(net "CLK_100M_PEX2_REF_R_DN")
	)
	(segment
		(start 243.5098 -214.122)
		(end 243.230146 -214.797386)
		(width 0.1143)
		(layer "B.Cu")
		(net "CLK_100M_PEX2_REF_R_DN")
	)
	(segment
		(start 237.461044 -162.310064)
		(end 243.8273 -168.67632)
		(width 0.1143)
		(layer "B.Cu")
		(net "CLK_100M_PEX2_REF_R_DN")
	)
	(segment
		(start 246.888254 -194.436492)
		(end 246.888254 -204.61605)
		(width 0.1143)
		(layer "B.Cu")
		(net "CLK_100M_PEX2_REF_R_DN")
	)
	(segment
		(start 262.475726 -296.24147)
		(end 262.475726 -296.435526)
		(width 0.1143)
		(layer "B.Cu")
		(net "CLK_100M_PEX2_REF_R_DN")
	)
	(segment
		(start 268.859 -299.224954)
		(end 268.57452 -299.224954)
		(width 0.0889)
		(layer "B.Cu")
		(net "CLK_100M_PEX2_REF_R_DN")
	)
	(segment
		(start 237.795054 -151.291798)
		(end 238.1377 -151.634444)
		(width 0.1143)
		(layer "B.Cu")
		(net "CLK_100M_PEX2_REF_R_DN")
	)
	(segment
		(start 265.52779 -297.829986)
		(end 266.567666 -298.869862)
		(width 0.1143)
		(layer "B.Cu")
		(net "CLK_100M_PEX2_REF_R_DN")
	)
	(segment
		(start 244.606064 -210.327494)
		(end 244.606064 -211.42579)
		(width 0.1143)
		(layer "B.Cu")
		(net "CLK_100M_PEX2_REF_R_DN")
	)
	(segment
		(start 263.870186 -297.829986)
		(end 265.52779 -297.829986)
		(width 0.1143)
		(layer "B.Cu")
		(net "CLK_100M_PEX2_REF_R_DN")
	)
	(segment
		(start 266.761722 -298.869862)
		(end 267.045694 -299.154088)
		(width 0.1143)
		(layer "B.Cu")
		(net "CLK_100M_PEX2_REF_R_DN")
	)
	(segment
		(start 243.785644 -218.514676)
		(end 243.785644 -220.61678)
		(width 0.1143)
		(layer "B.Cu")
		(net "CLK_100M_PEX2_REF_R_DN")
	)
	(segment
		(start 244.3226 -217.97772)
		(end 243.785644 -218.514676)
		(width 0.1143)
		(layer "B.Cu")
		(net "CLK_100M_PEX2_REF_R_DN")
	)
	(segment
		(start 266.567666 -298.869862)
		(end 266.761722 -298.869862)
		(width 0.1143)
		(layer "B.Cu")
		(net "CLK_100M_PEX2_REF_R_DN")
	)
	(segment
		(start 267.329412 -299.631608)
		(end 267.535406 -299.631608)
		(width 0.1143)
		(layer "B.Cu")
		(net "CLK_100M_PEX2_REF_R_DN")
	)
	(segment
		(start 237.411514 -151.291798)
		(end 237.795054 -151.291798)
		(width 0.1143)
		(layer "B.Cu")
		(net "CLK_100M_PEX2_REF_R_DN")
	)
	(segment
		(start 268.9479 -299.439584)
		(end 268.9479 -299.313854)
		(width 0.0889)
		(layer "B.Cu")
		(net "CLK_100M_PEX2_REF_R_DN")
	)
	(segment
		(start 237.170214 -151.050498)
		(end 237.411514 -151.291798)
		(width 0.1143)
		(layer "B.Cu")
		(net "CLK_100M_PEX2_REF_R_DN")
	)
	(segment
		(start 253.109222 -179.601876)
		(end 253.109222 -188.796676)
		(width 0.1143)
		(layer "B.Cu")
		(net "CLK_100M_PEX2_REF_R_DN")
	)
	(segment
		(start 238.1377 -155.398216)
		(end 237.461044 -156.074872)
		(width 0.1143)
		(layer "B.Cu")
		(net "CLK_100M_PEX2_REF_R_DN")
	)
	(segment
		(start 243.785644 -220.61678)
		(end 243.223796 -221.973648)
		(width 0.1143)
		(layer "B.Cu")
		(net "CLK_100M_PEX2_REF_R_DN")
	)
	(segment
		(start 267.535406 -299.631608)
		(end 267.557504 -299.631608)
		(width 0.0889)
		(layer "B.Cu")
		(net "CLK_100M_PEX2_REF_R_DN")
	)
	(segment
		(start 261.71398 -279.810972)
		(end 261.71398 -295.67378)
		(width 0.1143)
		(layer "B.Cu")
		(net "CLK_100M_PEX2_REF_R_DN")
	)
	(segment
		(start 246.888254 -204.61605)
		(end 246.253762 -206.147924)
		(width 0.1143)
		(layer "B.Cu")
		(net "CLK_100M_PEX2_REF_R_DN")
	)
	(segment
		(start 243.8273 -168.67632)
		(end 243.8273 -170.319954)
		(width 0.1143)
		(layer "B.Cu")
		(net "CLK_100M_PEX2_REF_R_DN")
	)
	(segment
		(start 246.253762 -208.250282)
		(end 245.950486 -208.983072)
		(width 0.1143)
		(layer "B.Cu")
		(net "CLK_100M_PEX2_REF_R_DN")
	)
	(segment
		(start 267.640054 -299.714158)
		(end 268.673326 -299.714158)
		(width 0.0889)
		(layer "B.Cu")
		(net "CLK_100M_PEX2_REF_R_DN")
	)
	(segment
		(start 267.045694 -299.154088)
		(end 267.045694 -299.34789)
		(width 0.1143)
		(layer "B.Cu")
		(net "CLK_100M_PEX2_REF_R_DN")
	)
	(segment
		(start 243.8273 -170.319954)
		(end 253.109222 -179.601876)
		(width 0.1143)
		(layer "B.Cu")
		(net "CLK_100M_PEX2_REF_R_DN")
	)
	(segment
		(start 246.253762 -206.147924)
		(end 246.253762 -208.250282)
		(width 0.1143)
		(layer "B.Cu")
		(net "CLK_100M_PEX2_REF_R_DN")
	)
	(segment
		(start 252.0188 -239.656874)
		(end 252.0188 -264.221722)
		(width 0.1143)
		(layer "B.Cu")
		(net "CLK_100M_PEX2_REF_R_DN")
	)
	(segment
		(start 238.1377 -151.634444)
		(end 238.1377 -155.398216)
		(width 0.1143)
		(layer "B.Cu")
		(net "CLK_100M_PEX2_REF_R_DN")
	)
	(segment
		(start 244.606064 -211.42579)
		(end 243.75237 -212.279484)
		(width 0.1143)
		(layer "B.Cu")
		(net "CLK_100M_PEX2_REF_R_DN")
	)
	(segment
		(start 243.5098 -212.865716)
		(end 243.5098 -214.122)
		(width 0.1143)
		(layer "B.Cu")
		(net "CLK_100M_PEX2_REF_R_DN")
	)
	(segment
		(start 262.475726 -296.435526)
		(end 263.870186 -297.829986)
		(width 0.1143)
		(layer "B.Cu")
		(net "CLK_100M_PEX2_REF_R_DN")
	)
	(segment
		(start 243.230146 -214.797386)
		(end 243.230146 -215.332818)
		(width 0.1143)
		(layer "B.Cu")
		(net "CLK_100M_PEX2_REF_R_DN")
	)
	(segment
		(start 267.557504 -299.631608)
		(end 267.640054 -299.714158)
		(width 0.0889)
		(layer "B.Cu")
		(net "CLK_100M_PEX2_REF_R_DN")
	)
	(segment
		(start 334.01 -244.83695)
		(end 334.122014 -244.724936)
		(width 0.13208)
		(layer "F.Cu")
		(net "MB_SWB_PWRGD_BUF")
	)
	(segment
		(start 334.122014 -243.84)
		(end 334.122014 -242.807998)
		(width 0.13208)
		(layer "F.Cu")
		(net "MB_SWB_PWRGD_BUF")
	)
	(segment
		(start 334.122014 -244.724936)
		(end 334.122014 -243.84)
		(width 0.13208)
		(layer "F.Cu")
		(net "MB_SWB_PWRGD_BUF")
	)
	(via
		(at 334.122014 -243.84)
		(size 0.508)
		(drill 0.254)
		(layers "F.Cu" "B.Cu")
		(net "MB_SWB_PWRGD_BUF")
	)
	(segment
		(start 111.038894 -82.692748)
		(end 111.166148 -82.565494)
		(width 0.13208)
		(layer "F.Cu")
		(net "SSD3_CLK_EN_R_N")
	)
	(segment
		(start 111.038894 -83.029044)
		(end 111.038894 -82.692748)
		(width 0.13208)
		(layer "F.Cu")
		(net "SSD3_CLK_EN_R_N")
	)
	(segment
		(start 344.043 -234.46105)
		(end 344.043 -235.077)
		(width 0.13208)
		(layer "F.Cu")
		(net "SSD3_CLK_EN_R_N")
	)
	(segment
		(start 111.166148 -82.565494)
		(end 112.089184 -82.565494)
		(width 0.13208)
		(layer "F.Cu")
		(net "SSD3_CLK_EN_R_N")
	)
	(via
		(at 88.481154 -81.120488)
		(size 0.508)
		(drill 0.254)
		(layers "F.Cu" "B.Cu")
		(net "SSD3_CLK_EN_R_N")
	)
	(via
		(at 344.043 -235.077)
		(size 0.508)
		(drill 0.254)
		(layers "F.Cu" "B.Cu")
		(net "SSD3_CLK_EN_R_N")
	)
	(via
		(at 120.53316 -235.544614)
		(size 0.508)
		(drill 0.254)
		(layers "F.Cu" "B.Cu")
		(net "SSD3_CLK_EN_R_N")
	)
	(via
		(at 112.089184 -82.565494)
		(size 0.508)
		(drill 0.254)
		(layers "F.Cu" "B.Cu")
		(net "SSD3_CLK_EN_R_N")
	)
	(segment
		(start 91.27744 -133.83006)
		(end 94.63532 -141.936724)
		(width 0.15494)
		(layer "In5.Cu")
		(net "SSD3_CLK_EN_R_N")
	)
	(segment
		(start 105.537 -200.9394)
		(end 115.1636 -210.566)
		(width 0.15494)
		(layer "In5.Cu")
		(net "SSD3_CLK_EN_R_N")
	)
	(segment
		(start 88.10244 -127.08636)
		(end 91.27744 -130.26136)
		(width 0.15494)
		(layer "In5.Cu")
		(net "SSD3_CLK_EN_R_N")
	)
	(segment
		(start 91.27744 -130.26136)
		(end 91.27744 -133.83006)
		(width 0.15494)
		(layer "In5.Cu")
		(net "SSD3_CLK_EN_R_N")
	)
	(segment
		(start 100.006658 -191.73825)
		(end 101.440488 -193.17208)
		(width 0.15494)
		(layer "In5.Cu")
		(net "SSD3_CLK_EN_R_N")
	)
	(segment
		(start 81.458054 -115.304062)
		(end 84.326984 -115.304062)
		(width 0.15494)
		(layer "In5.Cu")
		(net "SSD3_CLK_EN_R_N")
	)
	(segment
		(start 106.578908 -195.507864)
		(end 106.578908 -198.173086)
		(width 0.15494)
		(layer "In5.Cu")
		(net "SSD3_CLK_EN_R_N")
	)
	(segment
		(start 94.63532 -177.56124)
		(end 96.129348 -179.055268)
		(width 0.15494)
		(layer "In5.Cu")
		(net "SSD3_CLK_EN_R_N")
	)
	(segment
		(start 120.53316 -227.23729)
		(end 120.53316 -235.544614)
		(width 0.15494)
		(layer "In5.Cu")
		(net "SSD3_CLK_EN_R_N")
	)
	(segment
		(start 87.762842 -81.8388)
		(end 87.762842 -85.776308)
		(width 0.15494)
		(layer "In5.Cu")
		(net "SSD3_CLK_EN_R_N")
	)
	(segment
		(start 94.63532 -141.936724)
		(end 94.63532 -177.56124)
		(width 0.15494)
		(layer "In5.Cu")
		(net "SSD3_CLK_EN_R_N")
	)
	(segment
		(start 80.473296 -114.319304)
		(end 81.458054 -115.304062)
		(width 0.15494)
		(layer "In5.Cu")
		(net "SSD3_CLK_EN_R_N")
	)
	(segment
		(start 96.129348 -183.632348)
		(end 100.006658 -187.509658)
		(width 0.15494)
		(layer "In5.Cu")
		(net "SSD3_CLK_EN_R_N")
	)
	(segment
		(start 101.440488 -193.17208)
		(end 104.243124 -193.17208)
		(width 0.15494)
		(layer "In5.Cu")
		(net "SSD3_CLK_EN_R_N")
	)
	(segment
		(start 104.243124 -193.17208)
		(end 106.578908 -195.507864)
		(width 0.15494)
		(layer "In5.Cu")
		(net "SSD3_CLK_EN_R_N")
	)
	(segment
		(start 96.129348 -179.055268)
		(end 96.129348 -183.632348)
		(width 0.15494)
		(layer "In5.Cu")
		(net "SSD3_CLK_EN_R_N")
	)
	(segment
		(start 81.745582 -91.793568)
		(end 81.745582 -107.99572)
		(width 0.15494)
		(layer "In5.Cu")
		(net "SSD3_CLK_EN_R_N")
	)
	(segment
		(start 84.326984 -115.304062)
		(end 88.10244 -119.079518)
		(width 0.15494)
		(layer "In5.Cu")
		(net "SSD3_CLK_EN_R_N")
	)
	(segment
		(start 80.473296 -109.268006)
		(end 80.473296 -114.319304)
		(width 0.15494)
		(layer "In5.Cu")
		(net "SSD3_CLK_EN_R_N")
	)
	(segment
		(start 115.1636 -221.86773)
		(end 120.53316 -227.23729)
		(width 0.15494)
		(layer "In5.Cu")
		(net "SSD3_CLK_EN_R_N")
	)
	(segment
		(start 115.1636 -210.566)
		(end 115.1636 -221.86773)
		(width 0.15494)
		(layer "In5.Cu")
		(net "SSD3_CLK_EN_R_N")
	)
	(segment
		(start 100.006658 -187.509658)
		(end 100.006658 -191.73825)
		(width 0.15494)
		(layer "In5.Cu")
		(net "SSD3_CLK_EN_R_N")
	)
	(segment
		(start 105.537 -199.214994)
		(end 105.537 -200.9394)
		(width 0.15494)
		(layer "In5.Cu")
		(net "SSD3_CLK_EN_R_N")
	)
	(segment
		(start 88.481154 -81.120488)
		(end 87.762842 -81.8388)
		(width 0.15494)
		(layer "In5.Cu")
		(net "SSD3_CLK_EN_R_N")
	)
	(segment
		(start 87.762842 -85.776308)
		(end 81.745582 -91.793568)
		(width 0.15494)
		(layer "In5.Cu")
		(net "SSD3_CLK_EN_R_N")
	)
	(segment
		(start 81.745582 -107.99572)
		(end 80.473296 -109.268006)
		(width 0.15494)
		(layer "In5.Cu")
		(net "SSD3_CLK_EN_R_N")
	)
	(segment
		(start 88.10244 -119.079518)
		(end 88.10244 -127.08636)
		(width 0.15494)
		(layer "In5.Cu")
		(net "SSD3_CLK_EN_R_N")
	)
	(segment
		(start 106.578908 -198.173086)
		(end 105.537 -199.214994)
		(width 0.15494)
		(layer "In5.Cu")
		(net "SSD3_CLK_EN_R_N")
	)
	(segment
		(start 110.685072 -82.565494)
		(end 109.21619 -81.096612)
		(width 0.15494)
		(layer "In15.Cu")
		(net "SSD3_CLK_EN_R_N")
	)
	(segment
		(start 238.241332 -242.522756)
		(end 238.360966 -242.64239)
		(width 0.15494)
		(layer "In15.Cu")
		(net "SSD3_CLK_EN_R_N")
	)
	(segment
		(start 181.922928 -236.110018)
		(end 184.692544 -236.110018)
		(width 0.15494)
		(layer "In15.Cu")
		(net "SSD3_CLK_EN_R_N")
	)
	(segment
		(start 257.487674 -235.822744)
		(end 261.816088 -235.822744)
		(width 0.15494)
		(layer "In15.Cu")
		(net "SSD3_CLK_EN_R_N")
	)
	(segment
		(start 262.83539 -236.244892)
		(end 264.095484 -237.504986)
		(width 0.15494)
		(layer "In15.Cu")
		(net "SSD3_CLK_EN_R_N")
	)
	(segment
		(start 141.265656 -231.51592)
		(end 149.204426 -231.51592)
		(width 0.15494)
		(layer "In15.Cu")
		(net "SSD3_CLK_EN_R_N")
	)
	(segment
		(start 274.784312 -242.909344)
		(end 275.545296 -243.670328)
		(width 0.15494)
		(layer "In15.Cu")
		(net "SSD3_CLK_EN_R_N")
	)
	(segment
		(start 149.243796 -231.47655)
		(end 156.624274 -231.47655)
		(width 0.15494)
		(layer "In15.Cu")
		(net "SSD3_CLK_EN_R_N")
	)
	(segment
		(start 343.360502 -237.819438)
		(end 343.51087 -237.66907)
		(width 0.15494)
		(layer "In15.Cu")
		(net "SSD3_CLK_EN_R_N")
	)
	(segment
		(start 342.354662 -240.300256)
		(end 342.354662 -239.15243)
		(width 0.15494)
		(layer "In15.Cu")
		(net "SSD3_CLK_EN_R_N")
	)
	(segment
		(start 329.854814 -242.992656)
		(end 332.524354 -242.992656)
		(width 0.15494)
		(layer "In15.Cu")
		(net "SSD3_CLK_EN_R_N")
	)
	(segment
		(start 343.51087 -235.60913)
		(end 344.043 -235.077)
		(width 0.15494)
		(layer "In15.Cu")
		(net "SSD3_CLK_EN_R_N")
	)
	(segment
		(start 149.204426 -231.51592)
		(end 149.243796 -231.47655)
		(width 0.15494)
		(layer "In15.Cu")
		(net "SSD3_CLK_EN_R_N")
	)
	(segment
		(start 181.22265 -235.40974)
		(end 181.922928 -236.110018)
		(width 0.15494)
		(layer "In15.Cu")
		(net "SSD3_CLK_EN_R_N")
	)
	(segment
		(start 156.624274 -231.47655)
		(end 160.557464 -235.40974)
		(width 0.15494)
		(layer "In15.Cu")
		(net "SSD3_CLK_EN_R_N")
	)
	(segment
		(start 218.661488 -243.300758)
		(end 219.43949 -242.522756)
		(width 0.15494)
		(layer "In15.Cu")
		(net "SSD3_CLK_EN_R_N")
	)
	(segment
		(start 264.095484 -237.504986)
		(end 264.095484 -238.626396)
		(width 0.15494)
		(layer "In15.Cu")
		(net "SSD3_CLK_EN_R_N")
	)
	(segment
		(start 120.53316 -235.544614)
		(end 122.073924 -234.00385)
		(width 0.15494)
		(layer "In15.Cu")
		(net "SSD3_CLK_EN_R_N")
	)
	(segment
		(start 219.43949 -242.522756)
		(end 238.241332 -242.522756)
		(width 0.15494)
		(layer "In15.Cu")
		(net "SSD3_CLK_EN_R_N")
	)
	(segment
		(start 328.177398 -244.670072)
		(end 329.854814 -242.992656)
		(width 0.15494)
		(layer "In15.Cu")
		(net "SSD3_CLK_EN_R_N")
	)
	(segment
		(start 268.378432 -242.909344)
		(end 274.784312 -242.909344)
		(width 0.15494)
		(layer "In15.Cu")
		(net "SSD3_CLK_EN_R_N")
	)
	(segment
		(start 275.545296 -243.670328)
		(end 301.709074 -243.670328)
		(width 0.15494)
		(layer "In15.Cu")
		(net "SSD3_CLK_EN_R_N")
	)
	(segment
		(start 109.21619 -81.096612)
		(end 88.50503 -81.096612)
		(width 0.15494)
		(layer "In15.Cu")
		(net "SSD3_CLK_EN_R_N")
	)
	(segment
		(start 333.17815 -242.33886)
		(end 340.316058 -242.33886)
		(width 0.15494)
		(layer "In15.Cu")
		(net "SSD3_CLK_EN_R_N")
	)
	(segment
		(start 301.709074 -243.670328)
		(end 302.437038 -244.398292)
		(width 0.15494)
		(layer "In15.Cu")
		(net "SSD3_CLK_EN_R_N")
	)
	(segment
		(start 238.360966 -242.64239)
		(end 248.658634 -242.64239)
		(width 0.15494)
		(layer "In15.Cu")
		(net "SSD3_CLK_EN_R_N")
	)
	(segment
		(start 264.095484 -238.626396)
		(end 268.378432 -242.909344)
		(width 0.15494)
		(layer "In15.Cu")
		(net "SSD3_CLK_EN_R_N")
	)
	(segment
		(start 340.316058 -242.33886)
		(end 342.354662 -240.300256)
		(width 0.15494)
		(layer "In15.Cu")
		(net "SSD3_CLK_EN_R_N")
	)
	(segment
		(start 191.105028 -242.522502)
		(end 213.491318 -242.522502)
		(width 0.15494)
		(layer "In15.Cu")
		(net "SSD3_CLK_EN_R_N")
	)
	(segment
		(start 342.354662 -239.15243)
		(end 343.360502 -238.14659)
		(width 0.15494)
		(layer "In15.Cu")
		(net "SSD3_CLK_EN_R_N")
	)
	(segment
		(start 160.557464 -235.40974)
		(end 181.22265 -235.40974)
		(width 0.15494)
		(layer "In15.Cu")
		(net "SSD3_CLK_EN_R_N")
	)
	(segment
		(start 261.816088 -235.822744)
		(end 262.83539 -236.244892)
		(width 0.15494)
		(layer "In15.Cu")
		(net "SSD3_CLK_EN_R_N")
	)
	(segment
		(start 327.347326 -244.670072)
		(end 328.177398 -244.670072)
		(width 0.15494)
		(layer "In15.Cu")
		(net "SSD3_CLK_EN_R_N")
	)
	(segment
		(start 138.777726 -234.00385)
		(end 141.265656 -231.51592)
		(width 0.15494)
		(layer "In15.Cu")
		(net "SSD3_CLK_EN_R_N")
	)
	(segment
		(start 254.979424 -236.3216)
		(end 257.487674 -235.822744)
		(width 0.15494)
		(layer "In15.Cu")
		(net "SSD3_CLK_EN_R_N")
	)
	(segment
		(start 184.692544 -236.110018)
		(end 191.105028 -242.522502)
		(width 0.15494)
		(layer "In15.Cu")
		(net "SSD3_CLK_EN_R_N")
	)
	(segment
		(start 327.075546 -244.398292)
		(end 327.347326 -244.670072)
		(width 0.15494)
		(layer "In15.Cu")
		(net "SSD3_CLK_EN_R_N")
	)
	(segment
		(start 248.658634 -242.64239)
		(end 254.979424 -236.3216)
		(width 0.15494)
		(layer "In15.Cu")
		(net "SSD3_CLK_EN_R_N")
	)
	(segment
		(start 214.269574 -243.300758)
		(end 218.661488 -243.300758)
		(width 0.15494)
		(layer "In15.Cu")
		(net "SSD3_CLK_EN_R_N")
	)
	(segment
		(start 213.491318 -242.522502)
		(end 214.269574 -243.300758)
		(width 0.15494)
		(layer "In15.Cu")
		(net "SSD3_CLK_EN_R_N")
	)
	(segment
		(start 332.524354 -242.992656)
		(end 333.17815 -242.33886)
		(width 0.15494)
		(layer "In15.Cu")
		(net "SSD3_CLK_EN_R_N")
	)
	(segment
		(start 302.437038 -244.398292)
		(end 327.075546 -244.398292)
		(width 0.15494)
		(layer "In15.Cu")
		(net "SSD3_CLK_EN_R_N")
	)
	(segment
		(start 88.50503 -81.096612)
		(end 88.481154 -81.120488)
		(width 0.15494)
		(layer "In15.Cu")
		(net "SSD3_CLK_EN_R_N")
	)
	(segment
		(start 122.073924 -234.00385)
		(end 138.777726 -234.00385)
		(width 0.15494)
		(layer "In15.Cu")
		(net "SSD3_CLK_EN_R_N")
	)
	(segment
		(start 112.089184 -82.565494)
		(end 110.685072 -82.565494)
		(width 0.15494)
		(layer "In15.Cu")
		(net "SSD3_CLK_EN_R_N")
	)
	(segment
		(start 343.51087 -237.66907)
		(end 343.51087 -235.60913)
		(width 0.15494)
		(layer "In15.Cu")
		(net "SSD3_CLK_EN_R_N")
	)
	(segment
		(start 343.360502 -238.14659)
		(end 343.360502 -237.819438)
		(width 0.15494)
		(layer "In15.Cu")
		(net "SSD3_CLK_EN_R_N")
	)
	(segment
		(start 401.304506 -62.119764)
		(end 401.304506 -64.886332)
		(width 0.13208)
		(layer "F.Cu")
		(net "PWRGD_P12V_SSD14_R")
	)
	(segment
		(start 426.967904 -53.051456)
		(end 427.623224 -53.051456)
		(width 0.13208)
		(layer "F.Cu")
		(net "PWRGD_P12V_SSD14_R")
	)
	(segment
		(start 401.304506 -64.886332)
		(end 402.173694 -65.75552)
		(width 0.13208)
		(layer "F.Cu")
		(net "PWRGD_P12V_SSD14_R")
	)
	(segment
		(start 403.783546 -61.487812)
		(end 401.936458 -61.487812)
		(width 0.13208)
		(layer "F.Cu")
		(net "PWRGD_P12V_SSD14_R")
	)
	(segment
		(start 401.936458 -61.487812)
		(end 401.304506 -62.119764)
		(width 0.13208)
		(layer "F.Cu")
		(net "PWRGD_P12V_SSD14_R")
	)
	(segment
		(start 402.173694 -65.75552)
		(end 415.028634 -65.75552)
		(width 0.13208)
		(layer "F.Cu")
		(net "PWRGD_P12V_SSD14_R")
	)
	(segment
		(start 342.093804 -215.187022)
		(end 341.694008 -214.787226)
		(width 0.13208)
		(layer "F.Cu")
		(net "PWRGD_P12V_SSD14_R")
	)
	(via
		(at 427.623224 -53.051456)
		(size 0.508)
		(drill 0.254)
		(layers "F.Cu" "B.Cu")
		(net "PWRGD_P12V_SSD14_R")
	)
	(via
		(at 415.028634 -65.75552)
		(size 0.508)
		(drill 0.254)
		(layers "F.Cu" "B.Cu")
		(net "PWRGD_P12V_SSD14_R")
	)
	(via
		(at 413.041338 -89.162382)
		(size 0.508)
		(drill 0.254)
		(layers "F.Cu" "B.Cu")
		(net "PWRGD_P12V_SSD14_R")
	)
	(via
		(at 341.694008 -214.787226)
		(size 0.4572)
		(drill 0.254)
		(layers "F.Cu" "B.Cu")
		(net "PWRGD_P12V_SSD14_R")
	)
	(via
		(at 354.718112 -100.953316)
		(size 0.508)
		(drill 0.254)
		(layers "F.Cu" "B.Cu")
		(net "PWRGD_P12V_SSD14_R")
	)
	(segment
		(start 418.307266 -65.75552)
		(end 415.028634 -65.75552)
		(width 0.15494)
		(layer "In5.Cu")
		(net "PWRGD_P12V_SSD14_R")
	)
	(segment
		(start 413.041338 -66.917824)
		(end 414.203642 -65.75552)
		(width 0.15494)
		(layer "In5.Cu")
		(net "PWRGD_P12V_SSD14_R")
	)
	(segment
		(start 413.041338 -89.162382)
		(end 413.041338 -66.917824)
		(width 0.15494)
		(layer "In5.Cu")
		(net "PWRGD_P12V_SSD14_R")
	)
	(segment
		(start 426.043852 -63.72606)
		(end 425.675298 -64.094614)
		(width 0.15494)
		(layer "In5.Cu")
		(net "PWRGD_P12V_SSD14_R")
	)
	(segment
		(start 425.561252 -55.113428)
		(end 425.561252 -57.501028)
		(width 0.15494)
		(layer "In5.Cu")
		(net "PWRGD_P12V_SSD14_R")
	)
	(segment
		(start 419.968172 -64.094614)
		(end 418.307266 -65.75552)
		(width 0.15494)
		(layer "In5.Cu")
		(net "PWRGD_P12V_SSD14_R")
	)
	(segment
		(start 414.203642 -65.75552)
		(end 415.028634 -65.75552)
		(width 0.15494)
		(layer "In5.Cu")
		(net "PWRGD_P12V_SSD14_R")
	)
	(segment
		(start 426.043852 -57.983628)
		(end 426.043852 -63.72606)
		(width 0.15494)
		(layer "In5.Cu")
		(net "PWRGD_P12V_SSD14_R")
	)
	(segment
		(start 425.561252 -57.501028)
		(end 426.043852 -57.983628)
		(width 0.15494)
		(layer "In5.Cu")
		(net "PWRGD_P12V_SSD14_R")
	)
	(segment
		(start 427.623224 -53.051456)
		(end 425.561252 -55.113428)
		(width 0.15494)
		(layer "In5.Cu")
		(net "PWRGD_P12V_SSD14_R")
	)
	(segment
		(start 425.675298 -64.094614)
		(end 419.968172 -64.094614)
		(width 0.15494)
		(layer "In5.Cu")
		(net "PWRGD_P12V_SSD14_R")
	)
	(segment
		(start 352.19513 -172.639482)
		(end 351.767394 -172.211746)
		(width 0.15494)
		(layer "In7.Cu")
		(net "PWRGD_P12V_SSD14_R")
	)
	(segment
		(start 348.742 -206.5274)
		(end 348.742 -205.226158)
		(width 0.15494)
		(layer "In7.Cu")
		(net "PWRGD_P12V_SSD14_R")
	)
	(segment
		(start 353.465638 -185.694066)
		(end 353.465638 -175.67021)
		(width 0.15494)
		(layer "In7.Cu")
		(net "PWRGD_P12V_SSD14_R")
	)
	(segment
		(start 356.371652 -196.558916)
		(end 356.371652 -188.60008)
		(width 0.15494)
		(layer "In7.Cu")
		(net "PWRGD_P12V_SSD14_R")
	)
	(segment
		(start 346.159582 -208.042764)
		(end 347.226636 -208.042764)
		(width 0.15494)
		(layer "In7.Cu")
		(net "PWRGD_P12V_SSD14_R")
	)
	(segment
		(start 354.718112 -102.412038)
		(end 354.718112 -100.953316)
		(width 0.15494)
		(layer "In7.Cu")
		(net "PWRGD_P12V_SSD14_R")
	)
	(segment
		(start 347.476826 -127.579374)
		(end 355.409754 -119.646446)
		(width 0.15494)
		(layer "In7.Cu")
		(net "PWRGD_P12V_SSD14_R")
	)
	(segment
		(start 347.476826 -166.095426)
		(end 347.476826 -127.579374)
		(width 0.15494)
		(layer "In7.Cu")
		(net "PWRGD_P12V_SSD14_R")
	)
	(segment
		(start 355.409754 -119.646446)
		(end 355.409754 -106.13263)
		(width 0.15494)
		(layer "In7.Cu")
		(net "PWRGD_P12V_SSD14_R")
	)
	(segment
		(start 351.767394 -172.211746)
		(end 351.767394 -171.22648)
		(width 0.15494)
		(layer "In7.Cu")
		(net "PWRGD_P12V_SSD14_R")
	)
	(segment
		(start 355.416104 -103.11003)
		(end 354.718112 -102.412038)
		(width 0.15494)
		(layer "In7.Cu")
		(net "PWRGD_P12V_SSD14_R")
	)
	(segment
		(start 342.5698 -213.911434)
		(end 342.5698 -211.632546)
		(width 0.15494)
		(layer "In7.Cu")
		(net "PWRGD_P12V_SSD14_R")
	)
	(segment
		(start 355.409754 -106.13263)
		(end 355.416104 -106.12628)
		(width 0.15494)
		(layer "In7.Cu")
		(net "PWRGD_P12V_SSD14_R")
	)
	(segment
		(start 356.371652 -188.60008)
		(end 353.465638 -185.694066)
		(width 0.15494)
		(layer "In7.Cu")
		(net "PWRGD_P12V_SSD14_R")
	)
	(segment
		(start 353.465638 -175.67021)
		(end 352.19513 -174.399702)
		(width 0.15494)
		(layer "In7.Cu")
		(net "PWRGD_P12V_SSD14_R")
	)
	(segment
		(start 341.694008 -214.787226)
		(end 342.5698 -213.911434)
		(width 0.15494)
		(layer "In7.Cu")
		(net "PWRGD_P12V_SSD14_R")
	)
	(segment
		(start 347.226636 -208.042764)
		(end 348.742 -206.5274)
		(width 0.15494)
		(layer "In7.Cu")
		(net "PWRGD_P12V_SSD14_R")
	)
	(segment
		(start 348.742 -205.226158)
		(end 349.3008 -204.667358)
		(width 0.15494)
		(layer "In7.Cu")
		(net "PWRGD_P12V_SSD14_R")
	)
	(segment
		(start 349.922338 -169.381424)
		(end 349.922338 -168.540938)
		(width 0.15494)
		(layer "In7.Cu")
		(net "PWRGD_P12V_SSD14_R")
	)
	(segment
		(start 349.3008 -203.629768)
		(end 356.371652 -196.558916)
		(width 0.15494)
		(layer "In7.Cu")
		(net "PWRGD_P12V_SSD14_R")
	)
	(segment
		(start 349.3008 -204.667358)
		(end 349.3008 -203.629768)
		(width 0.15494)
		(layer "In7.Cu")
		(net "PWRGD_P12V_SSD14_R")
	)
	(segment
		(start 351.767394 -171.22648)
		(end 349.922338 -169.381424)
		(width 0.15494)
		(layer "In7.Cu")
		(net "PWRGD_P12V_SSD14_R")
	)
	(segment
		(start 342.5698 -211.632546)
		(end 346.159582 -208.042764)
		(width 0.15494)
		(layer "In7.Cu")
		(net "PWRGD_P12V_SSD14_R")
	)
	(segment
		(start 352.19513 -174.399702)
		(end 352.19513 -172.639482)
		(width 0.15494)
		(layer "In7.Cu")
		(net "PWRGD_P12V_SSD14_R")
	)
	(segment
		(start 355.416104 -106.12628)
		(end 355.416104 -103.11003)
		(width 0.15494)
		(layer "In7.Cu")
		(net "PWRGD_P12V_SSD14_R")
	)
	(segment
		(start 349.922338 -168.540938)
		(end 347.476826 -166.095426)
		(width 0.15494)
		(layer "In7.Cu")
		(net "PWRGD_P12V_SSD14_R")
	)
	(segment
		(start 357.0986 -100.203)
		(end 355.8286 -101.473)
		(width 0.15494)
		(layer "In15.Cu")
		(net "PWRGD_P12V_SSD14_R")
	)
	(segment
		(start 406.834848 -90.136472)
		(end 403.080728 -90.136472)
		(width 0.15494)
		(layer "In15.Cu")
		(net "PWRGD_P12V_SSD14_R")
	)
	(segment
		(start 413.041338 -89.162382)
		(end 407.808938 -89.162382)
		(width 0.15494)
		(layer "In15.Cu")
		(net "PWRGD_P12V_SSD14_R")
	)
	(segment
		(start 392.251946 -94.6658)
		(end 384.886454 -94.6658)
		(width 0.15494)
		(layer "In15.Cu")
		(net "PWRGD_P12V_SSD14_R")
	)
	(segment
		(start 407.808938 -89.162382)
		(end 406.834848 -90.136472)
		(width 0.15494)
		(layer "In15.Cu")
		(net "PWRGD_P12V_SSD14_R")
	)
	(segment
		(start 355.237796 -101.473)
		(end 354.718112 -100.953316)
		(width 0.15494)
		(layer "In15.Cu")
		(net "PWRGD_P12V_SSD14_R")
	)
	(segment
		(start 369.706906 -98.933)
		(end 368.436906 -100.203)
		(width 0.15494)
		(layer "In15.Cu")
		(net "PWRGD_P12V_SSD14_R")
	)
	(segment
		(start 355.8286 -101.473)
		(end 355.237796 -101.473)
		(width 0.15494)
		(layer "In15.Cu")
		(net "PWRGD_P12V_SSD14_R")
	)
	(segment
		(start 380.619254 -98.933)
		(end 369.706906 -98.933)
		(width 0.15494)
		(layer "In15.Cu")
		(net "PWRGD_P12V_SSD14_R")
	)
	(segment
		(start 368.436906 -100.203)
		(end 357.0986 -100.203)
		(width 0.15494)
		(layer "In15.Cu")
		(net "PWRGD_P12V_SSD14_R")
	)
	(segment
		(start 403.080728 -90.136472)
		(end 400.6596 -92.5576)
		(width 0.15494)
		(layer "In15.Cu")
		(net "PWRGD_P12V_SSD14_R")
	)
	(segment
		(start 400.6596 -92.5576)
		(end 394.360146 -92.5576)
		(width 0.15494)
		(layer "In15.Cu")
		(net "PWRGD_P12V_SSD14_R")
	)
	(segment
		(start 384.886454 -94.6658)
		(end 380.619254 -98.933)
		(width 0.15494)
		(layer "In15.Cu")
		(net "PWRGD_P12V_SSD14_R")
	)
	(segment
		(start 394.360146 -92.5576)
		(end 392.251946 -94.6658)
		(width 0.15494)
		(layer "In15.Cu")
		(net "PWRGD_P12V_SSD14_R")
	)
	(segment
		(start 114.956336 -89.384378)
		(end 114.642646 -89.070688)
		(width 0.13462)
		(layer "F.Cu")
		(net "CLK_100M_DB800ZL_SSD6_DN")
	)
	(segment
		(start 112.216692 -88.178894)
		(end 111.788956 -88.178894)
		(width 0.13462)
		(layer "F.Cu")
		(net "CLK_100M_DB800ZL_SSD6_DN")
	)
	(segment
		(start 113.904776 -89.070688)
		(end 112.956594 -88.122506)
		(width 0.13462)
		(layer "F.Cu")
		(net "CLK_100M_DB800ZL_SSD6_DN")
	)
	(segment
		(start 112.956594 -88.122506)
		(end 112.27308 -88.122506)
		(width 0.13462)
		(layer "F.Cu")
		(net "CLK_100M_DB800ZL_SSD6_DN")
	)
	(segment
		(start 114.642646 -89.070688)
		(end 113.904776 -89.070688)
		(width 0.13462)
		(layer "F.Cu")
		(net "CLK_100M_DB800ZL_SSD6_DN")
	)
	(segment
		(start 112.27308 -88.122506)
		(end 112.216692 -88.178894)
		(width 0.13462)
		(layer "F.Cu")
		(net "CLK_100M_DB800ZL_SSD6_DN")
	)
	(segment
		(start 131.791964 -187.943744)
		(end 131.503674 -188.232034)
		(width 0.13462)
		(layer "F.Cu")
		(net "CLK_100M_DB2000QL_GPU_REF1_R_DN")
	)
	(segment
		(start 132.26288 -186.525408)
		(end 131.791964 -186.996324)
		(width 0.13462)
		(layer "F.Cu")
		(net "CLK_100M_DB2000QL_GPU_REF1_R_DN")
	)
	(segment
		(start 131.791964 -186.996324)
		(end 131.791964 -187.943744)
		(width 0.13462)
		(layer "F.Cu")
		(net "CLK_100M_DB2000QL_GPU_REF1_R_DN")
	)
	(segment
		(start 132.26288 -185.421524)
		(end 132.26288 -186.525408)
		(width 0.13462)
		(layer "F.Cu")
		(net "CLK_100M_DB2000QL_GPU_REF1_R_DN")
	)
	(segment
		(start 131.89839 -185.057034)
		(end 132.26288 -185.421524)
		(width 0.13462)
		(layer "F.Cu")
		(net "CLK_100M_DB2000QL_GPU_REF1_R_DN")
	)
	(via
		(at 131.503674 -188.232034)
		(size 0.508)
		(drill 0.254)
		(layers "F.Cu" "B.Cu")
		(net "CLK_100M_DB2000QL_GPU_REF1_R_DN")
	)
	(segment
		(start 41.539922 -339.96757)
		(end 27.800046 -330.34605)
		(width 0.13462)
		(layer "B.Cu")
		(net "CLK_100M_DB2000QL_GPU_REF1_R_DN")
	)
	(segment
		(start 62.11951 -218.15552)
		(end 62.25667 -218.29268)
		(width 0.13462)
		(layer "B.Cu")
		(net "CLK_100M_DB2000QL_GPU_REF1_R_DN")
	)
	(segment
		(start 27.435302 -329.92314)
		(end 27.244294 -329.956922)
		(width 0.13462)
		(layer "B.Cu")
		(net "CLK_100M_DB2000QL_GPU_REF1_R_DN")
	)
	(segment
		(start 64.070992 -218.15552)
		(end 89.369392 -192.85712)
		(width 0.13462)
		(layer "B.Cu")
		(net "CLK_100M_DB2000QL_GPU_REF1_R_DN")
	)
	(segment
		(start 20.2184 -268.648688)
		(end 17.399 -261.841742)
		(width 0.13462)
		(layer "B.Cu")
		(net "CLK_100M_DB2000QL_GPU_REF1_R_DN")
	)
	(segment
		(start 24.812244 -303.507394)
		(end 24.812244 -299.125132)
		(width 0.13462)
		(layer "B.Cu")
		(net "CLK_100M_DB2000QL_GPU_REF1_R_DN")
	)
	(segment
		(start 20.3454 -307.974238)
		(end 24.812244 -303.507394)
		(width 0.13462)
		(layer "B.Cu")
		(net "CLK_100M_DB2000QL_GPU_REF1_R_DN")
	)
	(segment
		(start 43.20032 -341.627968)
		(end 41.539922 -339.96757)
		(width 0.13462)
		(layer "B.Cu")
		(net "CLK_100M_DB2000QL_GPU_REF1_R_DN")
	)
	(segment
		(start 27.244294 -329.956922)
		(end 26.913586 -329.725274)
		(width 0.13462)
		(layer "B.Cu")
		(net "CLK_100M_DB2000QL_GPU_REF1_R_DN")
	)
	(segment
		(start 131.791964 -187.943744)
		(end 131.503674 -188.232034)
		(width 0.13462)
		(layer "B.Cu")
		(net "CLK_100M_DB2000QL_GPU_REF1_R_DN")
	)
	(segment
		(start 92.15247 -192.99428)
		(end 92.55633 -192.99428)
		(width 0.13462)
		(layer "B.Cu")
		(net "CLK_100M_DB2000QL_GPU_REF1_R_DN")
	)
	(segment
		(start 49.263046 -218.15552)
		(end 61.03747 -218.15552)
		(width 0.13462)
		(layer "B.Cu")
		(net "CLK_100M_DB2000QL_GPU_REF1_R_DN")
	)
	(segment
		(start 24.877268 -328.299318)
		(end 20.3454 -323.76745)
		(width 0.13462)
		(layer "B.Cu")
		(net "CLK_100M_DB2000QL_GPU_REF1_R_DN")
	)
	(segment
		(start 49.139602 -367.477802)
		(end 43.20032 -361.53852)
		(width 0.13462)
		(layer "B.Cu")
		(net "CLK_100M_DB2000QL_GPU_REF1_R_DN")
	)
	(segment
		(start 17.399 -250.019566)
		(end 49.263046 -218.15552)
		(width 0.13462)
		(layer "B.Cu")
		(net "CLK_100M_DB2000QL_GPU_REF1_R_DN")
	)
	(segment
		(start 61.57849 -218.29268)
		(end 61.71565 -218.15552)
		(width 0.13462)
		(layer "B.Cu")
		(net "CLK_100M_DB2000QL_GPU_REF1_R_DN")
	)
	(segment
		(start 25.993598 -328.91349)
		(end 25.662382 -328.681588)
		(width 0.13462)
		(layer "B.Cu")
		(net "CLK_100M_DB2000QL_GPU_REF1_R_DN")
	)
	(segment
		(start 47.84471 -384.07721)
		(end 48.35779 -384.07721)
		(width 0.13462)
		(layer "B.Cu")
		(net "CLK_100M_DB2000QL_GPU_REF1_R_DN")
	)
	(segment
		(start 61.71565 -218.15552)
		(end 62.11951 -218.15552)
		(width 0.13462)
		(layer "B.Cu")
		(net "CLK_100M_DB2000QL_GPU_REF1_R_DN")
	)
	(segment
		(start 25.662382 -328.681588)
		(end 25.471374 -328.71537)
		(width 0.13462)
		(layer "B.Cu")
		(net "CLK_100M_DB2000QL_GPU_REF1_R_DN")
	)
	(segment
		(start 25.471374 -328.71537)
		(end 24.877268 -328.299318)
		(width 0.13462)
		(layer "B.Cu")
		(net "CLK_100M_DB2000QL_GPU_REF1_R_DN")
	)
	(segment
		(start 92.69349 -192.85712)
		(end 95.458534 -192.85712)
		(width 0.13462)
		(layer "B.Cu")
		(net "CLK_100M_DB2000QL_GPU_REF1_R_DN")
	)
	(segment
		(start 113.523014 -185.848752)
		(end 123.634246 -185.848752)
		(width 0.13462)
		(layer "B.Cu")
		(net "CLK_100M_DB2000QL_GPU_REF1_R_DN")
	)
	(segment
		(start 26.879804 -329.534266)
		(end 26.548842 -329.302364)
		(width 0.13462)
		(layer "B.Cu")
		(net "CLK_100M_DB2000QL_GPU_REF1_R_DN")
	)
	(segment
		(start 26.913586 -329.725274)
		(end 26.879804 -329.534266)
		(width 0.13462)
		(layer "B.Cu")
		(net "CLK_100M_DB2000QL_GPU_REF1_R_DN")
	)
	(segment
		(start 48.35779 -384.07721)
		(end 49.139602 -383.295398)
		(width 0.13462)
		(layer "B.Cu")
		(net "CLK_100M_DB2000QL_GPU_REF1_R_DN")
	)
	(segment
		(start 22.807168 -297.120056)
		(end 22.807168 -278.171656)
		(width 0.13462)
		(layer "B.Cu")
		(net "CLK_100M_DB2000QL_GPU_REF1_R_DN")
	)
	(segment
		(start 61.17463 -218.29268)
		(end 61.57849 -218.29268)
		(width 0.13462)
		(layer "B.Cu")
		(net "CLK_100M_DB2000QL_GPU_REF1_R_DN")
	)
	(segment
		(start 123.634246 -185.848752)
		(end 124.92609 -187.140596)
		(width 0.13462)
		(layer "B.Cu")
		(net "CLK_100M_DB2000QL_GPU_REF1_R_DN")
	)
	(segment
		(start 89.369392 -192.85712)
		(end 92.01531 -192.85712)
		(width 0.13462)
		(layer "B.Cu")
		(net "CLK_100M_DB2000QL_GPU_REF1_R_DN")
	)
	(segment
		(start 17.399 -261.841742)
		(end 17.399 -250.019566)
		(width 0.13462)
		(layer "B.Cu")
		(net "CLK_100M_DB2000QL_GPU_REF1_R_DN")
	)
	(segment
		(start 62.66053 -218.29268)
		(end 62.79769 -218.15552)
		(width 0.13462)
		(layer "B.Cu")
		(net "CLK_100M_DB2000QL_GPU_REF1_R_DN")
	)
	(segment
		(start 26.357834 -329.336146)
		(end 26.027126 -329.104498)
		(width 0.13462)
		(layer "B.Cu")
		(net "CLK_100M_DB2000QL_GPU_REF1_R_DN")
	)
	(segment
		(start 131.664964 -187.140596)
		(end 131.791964 -187.267596)
		(width 0.13462)
		(layer "B.Cu")
		(net "CLK_100M_DB2000QL_GPU_REF1_R_DN")
	)
	(segment
		(start 47.71009 -384.21183)
		(end 47.84471 -384.07721)
		(width 0.13462)
		(layer "B.Cu")
		(net "CLK_100M_DB2000QL_GPU_REF1_R_DN")
	)
	(segment
		(start 92.01531 -192.85712)
		(end 92.15247 -192.99428)
		(width 0.13462)
		(layer "B.Cu")
		(net "CLK_100M_DB2000QL_GPU_REF1_R_DN")
	)
	(segment
		(start 95.458534 -192.85712)
		(end 97.376234 -190.93942)
		(width 0.13462)
		(layer "B.Cu")
		(net "CLK_100M_DB2000QL_GPU_REF1_R_DN")
	)
	(segment
		(start 108.432346 -190.93942)
		(end 113.523014 -185.848752)
		(width 0.13462)
		(layer "B.Cu")
		(net "CLK_100M_DB2000QL_GPU_REF1_R_DN")
	)
	(segment
		(start 131.791964 -187.267596)
		(end 131.791964 -187.943744)
		(width 0.13462)
		(layer "B.Cu")
		(net "CLK_100M_DB2000QL_GPU_REF1_R_DN")
	)
	(segment
		(start 47.71009 -384.590036)
		(end 47.71009 -384.21183)
		(width 0.13462)
		(layer "B.Cu")
		(net "CLK_100M_DB2000QL_GPU_REF1_R_DN")
	)
	(segment
		(start 61.03747 -218.15552)
		(end 61.17463 -218.29268)
		(width 0.13462)
		(layer "B.Cu")
		(net "CLK_100M_DB2000QL_GPU_REF1_R_DN")
	)
	(segment
		(start 43.20032 -361.53852)
		(end 43.20032 -341.627968)
		(width 0.13462)
		(layer "B.Cu")
		(net "CLK_100M_DB2000QL_GPU_REF1_R_DN")
	)
	(segment
		(start 26.548842 -329.302364)
		(end 26.357834 -329.336146)
		(width 0.13462)
		(layer "B.Cu")
		(net "CLK_100M_DB2000QL_GPU_REF1_R_DN")
	)
	(segment
		(start 27.766264 -330.155042)
		(end 27.435302 -329.92314)
		(width 0.13462)
		(layer "B.Cu")
		(net "CLK_100M_DB2000QL_GPU_REF1_R_DN")
	)
	(segment
		(start 92.55633 -192.99428)
		(end 92.69349 -192.85712)
		(width 0.13462)
		(layer "B.Cu")
		(net "CLK_100M_DB2000QL_GPU_REF1_R_DN")
	)
	(segment
		(start 24.812244 -299.125132)
		(end 22.807168 -297.120056)
		(width 0.13462)
		(layer "B.Cu")
		(net "CLK_100M_DB2000QL_GPU_REF1_R_DN")
	)
	(segment
		(start 20.2184 -275.582888)
		(end 20.2184 -268.648688)
		(width 0.13462)
		(layer "B.Cu")
		(net "CLK_100M_DB2000QL_GPU_REF1_R_DN")
	)
	(segment
		(start 62.25667 -218.29268)
		(end 62.66053 -218.29268)
		(width 0.13462)
		(layer "B.Cu")
		(net "CLK_100M_DB2000QL_GPU_REF1_R_DN")
	)
	(segment
		(start 26.027126 -329.104498)
		(end 25.993598 -328.91349)
		(width 0.13462)
		(layer "B.Cu")
		(net "CLK_100M_DB2000QL_GPU_REF1_R_DN")
	)
	(segment
		(start 49.139602 -383.295398)
		(end 49.139602 -367.477802)
		(width 0.13462)
		(layer "B.Cu")
		(net "CLK_100M_DB2000QL_GPU_REF1_R_DN")
	)
	(segment
		(start 27.800046 -330.34605)
		(end 27.766264 -330.155042)
		(width 0.13462)
		(layer "B.Cu")
		(net "CLK_100M_DB2000QL_GPU_REF1_R_DN")
	)
	(segment
		(start 124.92609 -187.140596)
		(end 131.664964 -187.140596)
		(width 0.13462)
		(layer "B.Cu")
		(net "CLK_100M_DB2000QL_GPU_REF1_R_DN")
	)
	(segment
		(start 22.807168 -278.171656)
		(end 20.2184 -275.582888)
		(width 0.13462)
		(layer "B.Cu")
		(net "CLK_100M_DB2000QL_GPU_REF1_R_DN")
	)
	(segment
		(start 62.79769 -218.15552)
		(end 64.070992 -218.15552)
		(width 0.13462)
		(layer "B.Cu")
		(net "CLK_100M_DB2000QL_GPU_REF1_R_DN")
	)
	(segment
		(start 97.376234 -190.93942)
		(end 108.432346 -190.93942)
		(width 0.13462)
		(layer "B.Cu")
		(net "CLK_100M_DB2000QL_GPU_REF1_R_DN")
	)
	(segment
		(start 20.3454 -323.76745)
		(end 20.3454 -307.974238)
		(width 0.13462)
		(layer "B.Cu")
		(net "CLK_100M_DB2000QL_GPU_REF1_R_DN")
	)
	(segment
		(start 332.994 -245.63705)
		(end 332.994 -246.411496)
		(width 0.13208)
		(layer "F.Cu")
		(net "MB_SWB_PWRGD_BUF_R")
	)
	(segment
		(start 334.01 -245.63705)
		(end 332.994 -245.63705)
		(width 0.13208)
		(layer "F.Cu")
		(net "MB_SWB_PWRGD_BUF_R")
	)
	(via
		(at 332.994 -246.411496)
		(size 0.508)
		(drill 0.254)
		(layers "F.Cu" "B.Cu")
		(net "MB_SWB_PWRGD_BUF_R")
	)
	(via
		(at 363.49432 -330.632308)
		(size 0.508)
		(drill 0.254)
		(layers "F.Cu" "B.Cu")
		(net "MB_SWB_PWRGD_BUF_R")
	)
	(via
		(at 335.419446 -263.620504)
		(size 0.508)
		(drill 0.254)
		(layers "F.Cu" "B.Cu")
		(net "MB_SWB_PWRGD_BUF_R")
	)
	(via
		(at 332.259178 -325.98233)
		(size 0.508)
		(drill 0.254)
		(layers "F.Cu" "B.Cu")
		(net "MB_SWB_PWRGD_BUF_R")
	)
	(segment
		(start 336.187288 -263.620504)
		(end 335.419446 -263.620504)
		(width 0.13208)
		(layer "B.Cu")
		(net "MB_SWB_PWRGD_BUF_R")
	)
	(segment
		(start 336.568034 -264.498836)
		(end 336.568034 -264.00125)
		(width 0.13208)
		(layer "B.Cu")
		(net "MB_SWB_PWRGD_BUF_R")
	)
	(segment
		(start 331.154532 -325.722742)
		(end 328.497184 -323.065394)
		(width 0.13208)
		(layer "B.Cu")
		(net "MB_SWB_PWRGD_BUF_R")
	)
	(segment
		(start 328.881486 -273.391884)
		(end 328.881486 -267.964412)
		(width 0.13208)
		(layer "B.Cu")
		(net "MB_SWB_PWRGD_BUF_R")
	)
	(segment
		(start 331.99959 -325.722742)
		(end 331.154532 -325.722742)
		(width 0.13208)
		(layer "B.Cu")
		(net "MB_SWB_PWRGD_BUF_R")
	)
	(segment
		(start 326.91451 -275.35886)
		(end 328.881486 -273.391884)
		(width 0.13208)
		(layer "B.Cu")
		(net "MB_SWB_PWRGD_BUF_R")
	)
	(segment
		(start 328.497184 -323.065394)
		(end 328.497184 -317.335154)
		(width 0.13208)
		(layer "B.Cu")
		(net "MB_SWB_PWRGD_BUF_R")
	)
	(segment
		(start 325.460106 -309.139336)
		(end 326.91451 -307.684932)
		(width 0.13208)
		(layer "B.Cu")
		(net "MB_SWB_PWRGD_BUF_R")
	)
	(segment
		(start 328.497184 -317.335154)
		(end 325.460106 -314.298076)
		(width 0.13208)
		(layer "B.Cu")
		(net "MB_SWB_PWRGD_BUF_R")
	)
	(segment
		(start 326.91451 -307.684932)
		(end 326.91451 -275.35886)
		(width 0.13208)
		(layer "B.Cu")
		(net "MB_SWB_PWRGD_BUF_R")
	)
	(segment
		(start 332.259178 -325.98233)
		(end 331.99959 -325.722742)
		(width 0.13208)
		(layer "B.Cu")
		(net "MB_SWB_PWRGD_BUF_R")
	)
	(segment
		(start 328.881486 -267.964412)
		(end 330.964794 -265.881104)
		(width 0.13208)
		(layer "B.Cu")
		(net "MB_SWB_PWRGD_BUF_R")
	)
	(segment
		(start 335.185766 -265.881104)
		(end 336.568034 -264.498836)
		(width 0.13208)
		(layer "B.Cu")
		(net "MB_SWB_PWRGD_BUF_R")
	)
	(segment
		(start 336.568034 -264.00125)
		(end 336.187288 -263.620504)
		(width 0.13208)
		(layer "B.Cu")
		(net "MB_SWB_PWRGD_BUF_R")
	)
	(segment
		(start 325.460106 -314.298076)
		(end 325.460106 -309.139336)
		(width 0.13208)
		(layer "B.Cu")
		(net "MB_SWB_PWRGD_BUF_R")
	)
	(segment
		(start 330.964794 -265.881104)
		(end 335.185766 -265.881104)
		(width 0.13208)
		(layer "B.Cu")
		(net "MB_SWB_PWRGD_BUF_R")
	)
	(segment
		(start 335.410556 -332.190598)
		(end 332.73365 -329.513692)
		(width 0.15494)
		(layer "In5.Cu")
		(net "MB_SWB_PWRGD_BUF_R")
	)
	(segment
		(start 363.49432 -330.632308)
		(end 363.49432 -331.828648)
		(width 0.15494)
		(layer "In5.Cu")
		(net "MB_SWB_PWRGD_BUF_R")
	)
	(segment
		(start 335.411318 -332.190852)
		(end 335.410556 -332.190598)
		(width 0.15494)
		(layer "In5.Cu")
		(net "MB_SWB_PWRGD_BUF_R")
	)
	(segment
		(start 332.73365 -326.456802)
		(end 332.259178 -325.98233)
		(width 0.15494)
		(layer "In5.Cu")
		(net "MB_SWB_PWRGD_BUF_R")
	)
	(segment
		(start 332.73365 -329.513692)
		(end 332.73365 -326.456802)
		(width 0.15494)
		(layer "In5.Cu")
		(net "MB_SWB_PWRGD_BUF_R")
	)
	(segment
		(start 363.49432 -331.828648)
		(end 363.132116 -332.190852)
		(width 0.15494)
		(layer "In5.Cu")
		(net "MB_SWB_PWRGD_BUF_R")
	)
	(segment
		(start 363.132116 -332.190852)
		(end 335.411318 -332.190852)
		(width 0.15494)
		(layer "In5.Cu")
		(net "MB_SWB_PWRGD_BUF_R")
	)
	(segment
		(start 407.199592 -388.215632)
		(end 408.224482 -387.190742)
		(width 0.15494)
		(layer "In9.Cu")
		(net "MB_SWB_PWRGD_BUF_R")
	)
	(segment
		(start 382.515364 -341.509604)
		(end 378.830078 -337.824318)
		(width 0.15494)
		(layer "In9.Cu")
		(net "MB_SWB_PWRGD_BUF_R")
	)
	(segment
		(start 385.316476 -353.050348)
		(end 383.31521 -353.050348)
		(width 0.15494)
		(layer "In9.Cu")
		(net "MB_SWB_PWRGD_BUF_R")
	)
	(segment
		(start 408.224482 -385.615688)
		(end 408.051 -385.442206)
		(width 0.15494)
		(layer "In9.Cu")
		(net "MB_SWB_PWRGD_BUF_R")
	)
	(segment
		(start 335.419446 -263.620504)
		(end 334.999584 -263.200642)
		(width 0.15494)
		(layer "In9.Cu")
		(net "MB_SWB_PWRGD_BUF_R")
	)
	(segment
		(start 404.734776 -377.083574)
		(end 405.437848 -376.380502)
		(width 0.15494)
		(layer "In9.Cu")
		(net "MB_SWB_PWRGD_BUF_R")
	)
	(segment
		(start 334.999584 -263.200642)
		(end 334.999584 -259.209794)
		(width 0.15494)
		(layer "In9.Cu")
		(net "MB_SWB_PWRGD_BUF_R")
	)
	(segment
		(start 385.723892 -359.205022)
		(end 385.723892 -353.457764)
		(width 0.15494)
		(layer "In9.Cu")
		(net "MB_SWB_PWRGD_BUF_R")
	)
	(segment
		(start 405.437848 -376.380502)
		(end 406.134062 -376.380502)
		(width 0.15494)
		(layer "In9.Cu")
		(net "MB_SWB_PWRGD_BUF_R")
	)
	(segment
		(start 399.858992 -394.99921)
		(end 402.163026 -392.695176)
		(width 0.15494)
		(layer "In9.Cu")
		(net "MB_SWB_PWRGD_BUF_R")
	)
	(segment
		(start 406.697434 -373.39905)
		(end 404.902162 -371.603778)
		(width 0.15494)
		(layer "In9.Cu")
		(net "MB_SWB_PWRGD_BUF_R")
	)
	(segment
		(start 399.858992 -409.221432)
		(end 399.858992 -394.99921)
		(width 0.15494)
		(layer "In9.Cu")
		(net "MB_SWB_PWRGD_BUF_R")
	)
	(segment
		(start 404.902162 -371.603778)
		(end 402.561806 -371.603778)
		(width 0.15494)
		(layer "In9.Cu")
		(net "MB_SWB_PWRGD_BUF_R")
	)
	(segment
		(start 367.079276 -331.715618)
		(end 364.57763 -331.715618)
		(width 0.15494)
		(layer "In9.Cu")
		(net "MB_SWB_PWRGD_BUF_R")
	)
	(segment
		(start 387.461252 -360.942382)
		(end 385.723892 -359.205022)
		(width 0.15494)
		(layer "In9.Cu")
		(net "MB_SWB_PWRGD_BUF_R")
	)
	(segment
		(start 407.199592 -392.32586)
		(end 407.199592 -388.215632)
		(width 0.15494)
		(layer "In9.Cu")
		(net "MB_SWB_PWRGD_BUF_R")
	)
	(segment
		(start 381.033528 -413.233616)
		(end 395.846808 -413.233616)
		(width 0.15494)
		(layer "In9.Cu")
		(net "MB_SWB_PWRGD_BUF_R")
	)
	(segment
		(start 404.734776 -381.493776)
		(end 404.734776 -377.083574)
		(width 0.15494)
		(layer "In9.Cu")
		(net "MB_SWB_PWRGD_BUF_R")
	)
	(segment
		(start 391.90041 -360.942382)
		(end 387.461252 -360.942382)
		(width 0.15494)
		(layer "In9.Cu")
		(net "MB_SWB_PWRGD_BUF_R")
	)
	(segment
		(start 382.515364 -352.250502)
		(end 382.515364 -341.509604)
		(width 0.15494)
		(layer "In9.Cu")
		(net "MB_SWB_PWRGD_BUF_R")
	)
	(segment
		(start 329.914504 -254.124714)
		(end 329.914504 -249.490992)
		(width 0.15494)
		(layer "In9.Cu")
		(net "MB_SWB_PWRGD_BUF_R")
	)
	(segment
		(start 408.224482 -387.190742)
		(end 408.224482 -385.615688)
		(width 0.15494)
		(layer "In9.Cu")
		(net "MB_SWB_PWRGD_BUF_R")
	)
	(segment
		(start 385.723892 -353.457764)
		(end 385.316476 -353.050348)
		(width 0.15494)
		(layer "In9.Cu")
		(net "MB_SWB_PWRGD_BUF_R")
	)
	(segment
		(start 406.830276 -392.695176)
		(end 407.199592 -392.32586)
		(width 0.15494)
		(layer "In9.Cu")
		(net "MB_SWB_PWRGD_BUF_R")
	)
	(segment
		(start 402.561806 -371.603778)
		(end 391.90041 -360.942382)
		(width 0.15494)
		(layer "In9.Cu")
		(net "MB_SWB_PWRGD_BUF_R")
	)
	(segment
		(start 334.999584 -259.209794)
		(end 329.914504 -254.124714)
		(width 0.15494)
		(layer "In9.Cu")
		(net "MB_SWB_PWRGD_BUF_R")
	)
	(segment
		(start 408.051 -385.442206)
		(end 408.051 -384.81)
		(width 0.15494)
		(layer "In9.Cu")
		(net "MB_SWB_PWRGD_BUF_R")
	)
	(segment
		(start 367.634012 -332.270354)
		(end 367.079276 -331.715618)
		(width 0.15494)
		(layer "In9.Cu")
		(net "MB_SWB_PWRGD_BUF_R")
	)
	(segment
		(start 395.846808 -413.233616)
		(end 399.858992 -409.221432)
		(width 0.15494)
		(layer "In9.Cu")
		(net "MB_SWB_PWRGD_BUF_R")
	)
	(segment
		(start 329.914504 -249.490992)
		(end 332.994 -246.411496)
		(width 0.15494)
		(layer "In9.Cu")
		(net "MB_SWB_PWRGD_BUF_R")
	)
	(segment
		(start 406.134062 -376.380502)
		(end 407.06548 -375.449084)
		(width 0.15494)
		(layer "In9.Cu")
		(net "MB_SWB_PWRGD_BUF_R")
	)
	(segment
		(start 402.163026 -392.695176)
		(end 406.830276 -392.695176)
		(width 0.15494)
		(layer "In9.Cu")
		(net "MB_SWB_PWRGD_BUF_R")
	)
	(segment
		(start 367.634012 -334.772)
		(end 367.634012 -332.270354)
		(width 0.15494)
		(layer "In9.Cu")
		(net "MB_SWB_PWRGD_BUF_R")
	)
	(segment
		(start 364.57763 -331.715618)
		(end 363.49432 -330.632308)
		(width 0.15494)
		(layer "In9.Cu")
		(net "MB_SWB_PWRGD_BUF_R")
	)
	(segment
		(start 407.06548 -374.287542)
		(end 406.697434 -373.39905)
		(width 0.15494)
		(layer "In9.Cu")
		(net "MB_SWB_PWRGD_BUF_R")
	)
	(segment
		(start 370.68633 -337.824318)
		(end 367.634012 -334.772)
		(width 0.15494)
		(layer "In9.Cu")
		(net "MB_SWB_PWRGD_BUF_R")
	)
	(segment
		(start 378.830078 -337.824318)
		(end 370.68633 -337.824318)
		(width 0.15494)
		(layer "In9.Cu")
		(net "MB_SWB_PWRGD_BUF_R")
	)
	(segment
		(start 408.051 -384.81)
		(end 404.734776 -381.493776)
		(width 0.15494)
		(layer "In9.Cu")
		(net "MB_SWB_PWRGD_BUF_R")
	)
	(segment
		(start 383.31521 -353.050348)
		(end 382.515364 -352.250502)
		(width 0.15494)
		(layer "In9.Cu")
		(net "MB_SWB_PWRGD_BUF_R")
	)
	(segment
		(start 379.89002 -412.090108)
		(end 381.033528 -413.233616)
		(width 0.15494)
		(layer "In9.Cu")
		(net "MB_SWB_PWRGD_BUF_R")
	)
	(segment
		(start 407.06548 -375.449084)
		(end 407.06548 -374.287542)
		(width 0.15494)
		(layer "In9.Cu")
		(net "MB_SWB_PWRGD_BUF_R")
	)
	(segment
		(start 201.748136 -59.304936)
		(end 201.875136 -59.177936)
		(width 0.13208)
		(layer "F.Cu")
		(net "PWRGD_P3V3_SSD7")
	)
	(segment
		(start 201.875136 -59.177936)
		(end 202.278996 -59.177936)
		(width 0.13208)
		(layer "F.Cu")
		(net "PWRGD_P3V3_SSD7")
	)
	(segment
		(start 202.125072 -57.841896)
		(end 201.741024 -57.457848)
		(width 0.13208)
		(layer "F.Cu")
		(net "PWRGD_P3V3_SSD7")
	)
	(segment
		(start 202.278996 -58.71972)
		(end 202.125072 -58.565796)
		(width 0.13208)
		(layer "F.Cu")
		(net "PWRGD_P3V3_SSD7")
	)
	(segment
		(start 201.741024 -57.457848)
		(end 201.741024 -57.16397)
		(width 0.13208)
		(layer "F.Cu")
		(net "PWRGD_P3V3_SSD7")
	)
	(segment
		(start 201.748136 -61.22416)
		(end 201.748136 -59.304936)
		(width 0.13208)
		(layer "F.Cu")
		(net "PWRGD_P3V3_SSD7")
	)
	(segment
		(start 202.125072 -58.565796)
		(end 202.125072 -57.867296)
		(width 0.13208)
		(layer "F.Cu")
		(net "PWRGD_P3V3_SSD7")
	)
	(segment
		(start 202.278996 -59.177936)
		(end 202.278996 -58.71972)
		(width 0.13208)
		(layer "F.Cu")
		(net "PWRGD_P3V3_SSD7")
	)
	(segment
		(start 201.91095 -61.386974)
		(end 201.748136 -61.22416)
		(width 0.13208)
		(layer "F.Cu")
		(net "PWRGD_P3V3_SSD7")
	)
	(segment
		(start 202.125072 -57.867296)
		(end 202.125072 -57.841896)
		(width 0.13208)
		(layer "F.Cu")
		(net "PWRGD_P3V3_SSD7")
	)
	(via
		(at 202.125072 -57.867296)
		(size 0.508)
		(drill 0.254)
		(layers "F.Cu" "B.Cu")
		(net "PWRGD_P3V3_SSD7")
	)
	(segment
		(start 376.173746 -65.75552)
		(end 389.028686 -65.75552)
		(width 0.13208)
		(layer "F.Cu")
		(net "PWRGD_P12V_SSD13_R")
	)
	(segment
		(start 341.293958 -214.387176)
		(end 340.894162 -213.98738)
		(width 0.13208)
		(layer "F.Cu")
		(net "PWRGD_P12V_SSD13_R")
	)
	(segment
		(start 400.967956 -53.051456)
		(end 401.623276 -53.051456)
		(width 0.13208)
		(layer "F.Cu")
		(net "PWRGD_P12V_SSD13_R")
	)
	(segment
		(start 377.783598 -61.487812)
		(end 375.93651 -61.487812)
		(width 0.13208)
		(layer "F.Cu")
		(net "PWRGD_P12V_SSD13_R")
	)
	(segment
		(start 375.304558 -64.886332)
		(end 376.173746 -65.75552)
		(width 0.13208)
		(layer "F.Cu")
		(net "PWRGD_P12V_SSD13_R")
	)
	(segment
		(start 375.304558 -62.119764)
		(end 375.304558 -64.886332)
		(width 0.13208)
		(layer "F.Cu")
		(net "PWRGD_P12V_SSD13_R")
	)
	(segment
		(start 375.93651 -61.487812)
		(end 375.304558 -62.119764)
		(width 0.13208)
		(layer "F.Cu")
		(net "PWRGD_P12V_SSD13_R")
	)
	(via
		(at 340.894162 -213.98738)
		(size 0.4572)
		(drill 0.254)
		(layers "F.Cu" "B.Cu")
		(net "PWRGD_P12V_SSD13_R")
	)
	(via
		(at 401.623276 -53.051456)
		(size 0.508)
		(drill 0.254)
		(layers "F.Cu" "B.Cu")
		(net "PWRGD_P12V_SSD13_R")
	)
	(via
		(at 353.907344 -109.4994)
		(size 0.508)
		(drill 0.254)
		(layers "F.Cu" "B.Cu")
		(net "PWRGD_P12V_SSD13_R")
	)
	(via
		(at 389.028686 -65.75552)
		(size 0.508)
		(drill 0.254)
		(layers "F.Cu" "B.Cu")
		(net "PWRGD_P12V_SSD13_R")
	)
	(via
		(at 372.529862 -108.859828)
		(size 0.508)
		(drill 0.254)
		(layers "F.Cu" "B.Cu")
		(net "PWRGD_P12V_SSD13_R")
	)
	(segment
		(start 399.199608 -63.963042)
		(end 399.561304 -63.601346)
		(width 0.15494)
		(layer "In5.Cu")
		(net "PWRGD_P12V_SSD13_R")
	)
	(segment
		(start 389.028686 -65.75552)
		(end 392.488166 -65.75552)
		(width 0.15494)
		(layer "In5.Cu")
		(net "PWRGD_P12V_SSD13_R")
	)
	(segment
		(start 383.924556 -68.69938)
		(end 386.868416 -65.75552)
		(width 0.15494)
		(layer "In5.Cu")
		(net "PWRGD_P12V_SSD13_R")
	)
	(segment
		(start 375.55805 -100.468684)
		(end 383.924556 -92.102178)
		(width 0.15494)
		(layer "In5.Cu")
		(net "PWRGD_P12V_SSD13_R")
	)
	(segment
		(start 399.561304 -63.601346)
		(end 399.561304 -55.113428)
		(width 0.15494)
		(layer "In5.Cu")
		(net "PWRGD_P12V_SSD13_R")
	)
	(segment
		(start 394.280644 -63.963042)
		(end 399.199608 -63.963042)
		(width 0.15494)
		(layer "In5.Cu")
		(net "PWRGD_P12V_SSD13_R")
	)
	(segment
		(start 392.488166 -65.75552)
		(end 394.280644 -63.963042)
		(width 0.15494)
		(layer "In5.Cu")
		(net "PWRGD_P12V_SSD13_R")
	)
	(segment
		(start 399.561304 -55.113428)
		(end 401.623276 -53.051456)
		(width 0.15494)
		(layer "In5.Cu")
		(net "PWRGD_P12V_SSD13_R")
	)
	(segment
		(start 375.55805 -105.83164)
		(end 375.55805 -100.468684)
		(width 0.15494)
		(layer "In5.Cu")
		(net "PWRGD_P12V_SSD13_R")
	)
	(segment
		(start 383.924556 -92.102178)
		(end 383.924556 -68.69938)
		(width 0.15494)
		(layer "In5.Cu")
		(net "PWRGD_P12V_SSD13_R")
	)
	(segment
		(start 386.868416 -65.75552)
		(end 389.028686 -65.75552)
		(width 0.15494)
		(layer "In5.Cu")
		(net "PWRGD_P12V_SSD13_R")
	)
	(segment
		(start 372.529862 -108.859828)
		(end 375.55805 -105.83164)
		(width 0.15494)
		(layer "In5.Cu")
		(net "PWRGD_P12V_SSD13_R")
	)
	(segment
		(start 348.443296 -185.468514)
		(end 344.033856 -189.877954)
		(width 0.15494)
		(layer "In7.Cu")
		(net "PWRGD_P12V_SSD13_R")
	)
	(segment
		(start 342.267286 -213.176358)
		(end 342.267286 -213.357714)
		(width 0.0889)
		(layer "In7.Cu")
		(net "PWRGD_P12V_SSD13_R")
	)
	(segment
		(start 353.907344 -119.284242)
		(end 346.138246 -127.05334)
		(width 0.15494)
		(layer "In7.Cu")
		(net "PWRGD_P12V_SSD13_R")
	)
	(segment
		(start 346.138246 -127.05334)
		(end 346.138246 -166.559992)
		(width 0.15494)
		(layer "In7.Cu")
		(net "PWRGD_P12V_SSD13_R")
	)
	(segment
		(start 341.294212 -213.58733)
		(end 340.894162 -213.98738)
		(width 0.0889)
		(layer "In7.Cu")
		(net "PWRGD_P12V_SSD13_R")
	)
	(segment
		(start 344.033856 -196.22135)
		(end 346.202 -201.455528)
		(width 0.15494)
		(layer "In7.Cu")
		(net "PWRGD_P12V_SSD13_R")
	)
	(segment
		(start 342.267286 -213.357714)
		(end 342.03767 -213.58733)
		(width 0.0889)
		(layer "In7.Cu")
		(net "PWRGD_P12V_SSD13_R")
	)
	(segment
		(start 346.202 -204.791818)
		(end 345.694 -205.299818)
		(width 0.15494)
		(layer "In7.Cu")
		(net "PWRGD_P12V_SSD13_R")
	)
	(segment
		(start 342.267286 -209.471514)
		(end 342.267286 -213.176358)
		(width 0.15494)
		(layer "In7.Cu")
		(net "PWRGD_P12V_SSD13_R")
	)
	(segment
		(start 344.033856 -189.877954)
		(end 344.033856 -196.22135)
		(width 0.15494)
		(layer "In7.Cu")
		(net "PWRGD_P12V_SSD13_R")
	)
	(segment
		(start 345.454478 -206.639922)
		(end 345.098878 -206.639922)
		(width 0.15494)
		(layer "In7.Cu")
		(net "PWRGD_P12V_SSD13_R")
	)
	(segment
		(start 345.694 -205.299818)
		(end 345.694 -206.4004)
		(width 0.15494)
		(layer "In7.Cu")
		(net "PWRGD_P12V_SSD13_R")
	)
	(segment
		(start 345.098878 -206.639922)
		(end 342.267286 -209.471514)
		(width 0.15494)
		(layer "In7.Cu")
		(net "PWRGD_P12V_SSD13_R")
	)
	(segment
		(start 346.202 -201.455528)
		(end 346.202 -204.791818)
		(width 0.15494)
		(layer "In7.Cu")
		(net "PWRGD_P12V_SSD13_R")
	)
	(segment
		(start 345.694 -206.4004)
		(end 345.454478 -206.639922)
		(width 0.15494)
		(layer "In7.Cu")
		(net "PWRGD_P12V_SSD13_R")
	)
	(segment
		(start 346.138246 -166.559992)
		(end 348.443296 -168.865042)
		(width 0.15494)
		(layer "In7.Cu")
		(net "PWRGD_P12V_SSD13_R")
	)
	(segment
		(start 353.907344 -109.4994)
		(end 353.907344 -119.284242)
		(width 0.15494)
		(layer "In7.Cu")
		(net "PWRGD_P12V_SSD13_R")
	)
	(segment
		(start 348.443296 -168.865042)
		(end 348.443296 -185.468514)
		(width 0.15494)
		(layer "In7.Cu")
		(net "PWRGD_P12V_SSD13_R")
	)
	(segment
		(start 342.03767 -213.58733)
		(end 341.294212 -213.58733)
		(width 0.0889)
		(layer "In7.Cu")
		(net "PWRGD_P12V_SSD13_R")
	)
	(segment
		(start 354.618544 -110.2106)
		(end 353.907344 -109.4994)
		(width 0.15494)
		(layer "In13.Cu")
		(net "PWRGD_P12V_SSD13_R")
	)
	(segment
		(start 372.529862 -108.859828)
		(end 372.356634 -108.6866)
		(width 0.15494)
		(layer "In13.Cu")
		(net "PWRGD_P12V_SSD13_R")
	)
	(segment
		(start 362.152946 -108.6866)
		(end 360.628946 -110.2106)
		(width 0.15494)
		(layer "In13.Cu")
		(net "PWRGD_P12V_SSD13_R")
	)
	(segment
		(start 360.628946 -110.2106)
		(end 354.618544 -110.2106)
		(width 0.15494)
		(layer "In13.Cu")
		(net "PWRGD_P12V_SSD13_R")
	)
	(segment
		(start 372.356634 -108.6866)
		(end 362.152946 -108.6866)
		(width 0.15494)
		(layer "In13.Cu")
		(net "PWRGD_P12V_SSD13_R")
	)
	(segment
		(start 394.208 -246.3419)
		(end 393.311634 -246.3419)
		(width 0.13208)
		(layer "F.Cu")
		(net "UART_PEX1_SDB_BUF_R_TX")
	)
	(segment
		(start 459.6638 -230.38435)
		(end 460.9846 -230.38435)
		(width 0.13208)
		(layer "F.Cu")
		(net "UART_PEX1_SDB_BUF_R_TX")
	)
	(segment
		(start 462.22285 -230.38435)
		(end 462.2546 -230.3526)
		(width 0.13208)
		(layer "F.Cu")
		(net "UART_PEX1_SDB_BUF_R_TX")
	)
	(segment
		(start 393.282932 -246.313198)
		(end 392.867388 -246.313198)
		(width 0.13208)
		(layer "F.Cu")
		(net "UART_PEX1_SDB_BUF_R_TX")
	)
	(segment
		(start 393.311634 -246.3419)
		(end 393.282932 -246.313198)
		(width 0.13208)
		(layer "F.Cu")
		(net "UART_PEX1_SDB_BUF_R_TX")
	)
	(segment
		(start 460.9846 -230.38435)
		(end 462.22285 -230.38435)
		(width 0.13208)
		(layer "F.Cu")
		(net "UART_PEX1_SDB_BUF_R_TX")
	)
	(via
		(at 462.2546 -230.3526)
		(size 0.508)
		(drill 0.254)
		(layers "F.Cu" "B.Cu")
		(net "UART_PEX1_SDB_BUF_R_TX")
	)
	(via
		(at 376.488198 -245.371112)
		(size 0.508)
		(drill 0.254)
		(layers "F.Cu" "B.Cu")
		(net "UART_PEX1_SDB_BUF_R_TX")
	)
	(via
		(at 394.208 -246.3419)
		(size 0.508)
		(drill 0.254)
		(layers "F.Cu" "B.Cu")
		(net "UART_PEX1_SDB_BUF_R_TX")
	)
	(via
		(at 460.9846 -230.38435)
		(size 0.762)
		(drill 0.381)
		(layers "F.Cu" "B.Cu")
		(net "UART_PEX1_SDB_BUF_R_TX")
	)
	(segment
		(start 375.014998 -244.585998)
		(end 374.3706 -244.585998)
		(width 0.13208)
		(layer "B.Cu")
		(net "UART_PEX1_SDB_BUF_R_TX")
	)
	(segment
		(start 377.67895 -244.729)
		(end 377.13031 -244.729)
		(width 0.13208)
		(layer "B.Cu")
		(net "UART_PEX1_SDB_BUF_R_TX")
	)
	(segment
		(start 394.208 -246.3419)
		(end 395.173708 -247.307608)
		(width 0.13208)
		(layer "B.Cu")
		(net "UART_PEX1_SDB_BUF_R_TX")
	)
	(segment
		(start 459.371446 -252.615954)
		(end 462.2546 -249.7328)
		(width 0.13208)
		(layer "B.Cu")
		(net "UART_PEX1_SDB_BUF_R_TX")
	)
	(segment
		(start 462.2546 -249.7328)
		(end 462.2546 -230.3526)
		(width 0.13208)
		(layer "B.Cu")
		(net "UART_PEX1_SDB_BUF_R_TX")
	)
	(segment
		(start 452.14413 -250.07443)
		(end 452.521828 -250.07443)
		(width 0.13208)
		(layer "B.Cu")
		(net "UART_PEX1_SDB_BUF_R_TX")
	)
	(segment
		(start 375.666 -245.237)
		(end 375.014998 -244.585998)
		(width 0.13208)
		(layer "B.Cu")
		(net "UART_PEX1_SDB_BUF_R_TX")
	)
	(segment
		(start 455.063352 -252.615954)
		(end 459.371446 -252.615954)
		(width 0.13208)
		(layer "B.Cu")
		(net "UART_PEX1_SDB_BUF_R_TX")
	)
	(segment
		(start 376.488198 -245.371112)
		(end 376.354086 -245.237)
		(width 0.13208)
		(layer "B.Cu")
		(net "UART_PEX1_SDB_BUF_R_TX")
	)
	(segment
		(start 452.521828 -250.07443)
		(end 455.063352 -252.615954)
		(width 0.13208)
		(layer "B.Cu")
		(net "UART_PEX1_SDB_BUF_R_TX")
	)
	(segment
		(start 376.354086 -245.237)
		(end 375.666 -245.237)
		(width 0.13208)
		(layer "B.Cu")
		(net "UART_PEX1_SDB_BUF_R_TX")
	)
	(segment
		(start 377.13031 -244.729)
		(end 376.488198 -245.371112)
		(width 0.13208)
		(layer "B.Cu")
		(net "UART_PEX1_SDB_BUF_R_TX")
	)
	(segment
		(start 449.377308 -247.307608)
		(end 452.14413 -250.07443)
		(width 0.13208)
		(layer "B.Cu")
		(net "UART_PEX1_SDB_BUF_R_TX")
	)
	(segment
		(start 395.173708 -247.307608)
		(end 449.377308 -247.307608)
		(width 0.13208)
		(layer "B.Cu")
		(net "UART_PEX1_SDB_BUF_R_TX")
	)
	(segment
		(start 390.49706 -246.3419)
		(end 394.208 -246.3419)
		(width 0.15494)
		(layer "In15.Cu")
		(net "UART_PEX1_SDB_BUF_R_TX")
	)
	(segment
		(start 384.617722 -244.88775)
		(end 387.095746 -244.88775)
		(width 0.15494)
		(layer "In15.Cu")
		(net "UART_PEX1_SDB_BUF_R_TX")
	)
	(segment
		(start 383.135378 -246.370094)
		(end 384.617722 -244.88775)
		(width 0.15494)
		(layer "In15.Cu")
		(net "UART_PEX1_SDB_BUF_R_TX")
	)
	(segment
		(start 387.116066 -244.86743)
		(end 388.91083 -244.86743)
		(width 0.15494)
		(layer "In15.Cu")
		(net "UART_PEX1_SDB_BUF_R_TX")
	)
	(segment
		(start 388.91083 -244.86743)
		(end 388.93115 -244.88775)
		(width 0.15494)
		(layer "In15.Cu")
		(net "UART_PEX1_SDB_BUF_R_TX")
	)
	(segment
		(start 388.93115 -244.88775)
		(end 389.04291 -244.88775)
		(width 0.15494)
		(layer "In15.Cu")
		(net "UART_PEX1_SDB_BUF_R_TX")
	)
	(segment
		(start 376.488198 -245.371112)
		(end 377.48718 -246.370094)
		(width 0.15494)
		(layer "In15.Cu")
		(net "UART_PEX1_SDB_BUF_R_TX")
	)
	(segment
		(start 387.095746 -244.88775)
		(end 387.116066 -244.86743)
		(width 0.15494)
		(layer "In15.Cu")
		(net "UART_PEX1_SDB_BUF_R_TX")
	)
	(segment
		(start 377.48718 -246.370094)
		(end 383.135378 -246.370094)
		(width 0.15494)
		(layer "In15.Cu")
		(net "UART_PEX1_SDB_BUF_R_TX")
	)
	(segment
		(start 389.04291 -244.88775)
		(end 390.49706 -246.3419)
		(width 0.15494)
		(layer "In15.Cu")
		(net "UART_PEX1_SDB_BUF_R_TX")
	)
	(segment
		(start 113.070386 -87.848186)
		(end 112.284764 -87.848186)
		(width 0.13462)
		(layer "F.Cu")
		(net "CLK_100M_DB800ZL_SSD6_DP")
	)
	(segment
		(start 112.215676 -87.779098)
		(end 111.788956 -87.779098)
		(width 0.13462)
		(layer "F.Cu")
		(net "CLK_100M_DB800ZL_SSD6_DP")
	)
	(segment
		(start 114.629946 -88.796368)
		(end 114.018568 -88.796368)
		(width 0.13462)
		(layer "F.Cu")
		(net "CLK_100M_DB800ZL_SSD6_DP")
	)
	(segment
		(start 114.018568 -88.796368)
		(end 113.070386 -87.848186)
		(width 0.13462)
		(layer "F.Cu")
		(net "CLK_100M_DB800ZL_SSD6_DP")
	)
	(segment
		(start 114.956336 -88.469978)
		(end 114.629946 -88.796368)
		(width 0.13462)
		(layer "F.Cu")
		(net "CLK_100M_DB800ZL_SSD6_DP")
	)
	(segment
		(start 112.284764 -87.848186)
		(end 112.215676 -87.779098)
		(width 0.13462)
		(layer "F.Cu")
		(net "CLK_100M_DB800ZL_SSD6_DP")
	)
	(segment
		(start 236.023658 -151.975566)
		(end 236.335824 -151.6634)
		(width 0.1143)
		(layer "F.Cu")
		(net "CLK_100M_PEX2_REF_R_DP")
	)
	(segment
		(start 236.919516 -151.6634)
		(end 237.170214 -151.914098)
		(width 0.1143)
		(layer "F.Cu")
		(net "CLK_100M_PEX2_REF_R_DP")
	)
	(segment
		(start 269.999714 -299.699934)
		(end 269.99946 -299.699934)
		(width 0.1143)
		(layer "F.Cu")
		(net "CLK_100M_PEX2_REF_R_DP")
	)
	(segment
		(start 236.335824 -151.6634)
		(end 236.919516 -151.6634)
		(width 0.1143)
		(layer "F.Cu")
		(net "CLK_100M_PEX2_REF_R_DP")
	)
	(segment
		(start 269.99946 -299.699934)
		(end 269.52448 -299.224954)
		(width 0.1143)
		(layer "F.Cu")
		(net "CLK_100M_PEX2_REF_R_DP")
	)
	(via
		(at 269.52448 -299.224954)
		(size 0.4064)
		(drill 0.2032)
		(layers "F.Cu" "B.Cu")
		(net "CLK_100M_PEX2_REF_R_DP")
	)
	(via
		(at 237.170214 -151.914098)
		(size 0.508)
		(drill 0.254)
		(layers "F.Cu" "B.Cu")
		(net "CLK_100M_PEX2_REF_R_DP")
	)
	(segment
		(start 243.417344 -220.543374)
		(end 242.855496 -221.900242)
		(width 0.1143)
		(layer "B.Cu")
		(net "CLK_100M_PEX2_REF_R_DP")
	)
	(segment
		(start 244.237764 -211.273136)
		(end 243.43995 -212.070696)
		(width 0.1143)
		(layer "B.Cu")
		(net "CLK_100M_PEX2_REF_R_DP")
	)
	(segment
		(start 267.640054 -299.917358)
		(end 268.757654 -299.917358)
		(width 0.0889)
		(layer "B.Cu")
		(net "CLK_100M_PEX2_REF_R_DP")
	)
	(segment
		(start 243.459 -168.828974)
		(end 243.459 -170.472608)
		(width 0.1143)
		(layer "B.Cu")
		(net "CLK_100M_PEX2_REF_R_DP")
	)
	(segment
		(start 255.873504 -274.49145)
		(end 261.34568 -279.963626)
		(width 0.1143)
		(layer "B.Cu")
		(net "CLK_100M_PEX2_REF_R_DP")
	)
	(segment
		(start 243.417344 -218.362022)
		(end 243.417344 -220.543374)
		(width 0.1143)
		(layer "B.Cu")
		(net "CLK_100M_PEX2_REF_R_DP")
	)
	(segment
		(start 242.855496 -221.900242)
		(end 242.855496 -231.014524)
		(width 0.1143)
		(layer "B.Cu")
		(net "CLK_100M_PEX2_REF_R_DP")
	)
	(segment
		(start 267.535406 -299.999908)
		(end 267.557504 -299.999908)
		(width 0.0889)
		(layer "B.Cu")
		(net "CLK_100M_PEX2_REF_R_DP")
	)
	(segment
		(start 243.459 -170.472608)
		(end 252.740922 -179.75453)
		(width 0.1143)
		(layer "B.Cu")
		(net "CLK_100M_PEX2_REF_R_DP")
	)
	(segment
		(start 242.855496 -231.014524)
		(end 251.6505 -239.809528)
		(width 0.1143)
		(layer "B.Cu")
		(net "CLK_100M_PEX2_REF_R_DP")
	)
	(segment
		(start 237.170214 -151.914098)
		(end 237.424214 -151.660098)
		(width 0.1143)
		(layer "B.Cu")
		(net "CLK_100M_PEX2_REF_R_DP")
	)
	(segment
		(start 263.717532 -298.198286)
		(end 265.375136 -298.198286)
		(width 0.1143)
		(layer "B.Cu")
		(net "CLK_100M_PEX2_REF_R_DP")
	)
	(segment
		(start 242.861846 -214.72398)
		(end 242.861846 -215.485472)
		(width 0.1143)
		(layer "B.Cu")
		(net "CLK_100M_PEX2_REF_R_DP")
	)
	(segment
		(start 252.740922 -179.75453)
		(end 252.740922 -188.644022)
		(width 0.1143)
		(layer "B.Cu")
		(net "CLK_100M_PEX2_REF_R_DP")
	)
	(segment
		(start 237.7694 -151.787098)
		(end 237.7694 -155.245562)
		(width 0.1143)
		(layer "B.Cu")
		(net "CLK_100M_PEX2_REF_R_DP")
	)
	(segment
		(start 246.519954 -204.542644)
		(end 245.885462 -206.074518)
		(width 0.1143)
		(layer "B.Cu")
		(net "CLK_100M_PEX2_REF_R_DP")
	)
	(segment
		(start 237.7694 -155.245562)
		(end 237.092744 -155.922218)
		(width 0.1143)
		(layer "B.Cu")
		(net "CLK_100M_PEX2_REF_R_DP")
	)
	(segment
		(start 243.1415 -212.79231)
		(end 243.1415 -214.048594)
		(width 0.1143)
		(layer "B.Cu")
		(net "CLK_100M_PEX2_REF_R_DP")
	)
	(segment
		(start 265.375136 -298.198286)
		(end 267.176758 -299.999908)
		(width 0.1143)
		(layer "B.Cu")
		(net "CLK_100M_PEX2_REF_R_DP")
	)
	(segment
		(start 243.9543 -217.825066)
		(end 243.417344 -218.362022)
		(width 0.1143)
		(layer "B.Cu")
		(net "CLK_100M_PEX2_REF_R_DP")
	)
	(segment
		(start 269.24 -299.224954)
		(end 269.52448 -299.224954)
		(width 0.0889)
		(layer "B.Cu")
		(net "CLK_100M_PEX2_REF_R_DP")
	)
	(segment
		(start 249.682508 -191.702436)
		(end 249.101356 -191.702436)
		(width 0.1143)
		(layer "B.Cu")
		(net "CLK_100M_PEX2_REF_R_DP")
	)
	(segment
		(start 246.519954 -194.283838)
		(end 246.519954 -204.542644)
		(width 0.1143)
		(layer "B.Cu")
		(net "CLK_100M_PEX2_REF_R_DP")
	)
	(segment
		(start 245.638066 -208.774284)
		(end 244.237764 -210.17484)
		(width 0.1143)
		(layer "B.Cu")
		(net "CLK_100M_PEX2_REF_R_DP")
	)
	(segment
		(start 261.34568 -279.963626)
		(end 261.34568 -295.826434)
		(width 0.1143)
		(layer "B.Cu")
		(net "CLK_100M_PEX2_REF_R_DP")
	)
	(segment
		(start 252.740922 -188.644022)
		(end 249.682508 -191.702436)
		(width 0.1143)
		(layer "B.Cu")
		(net "CLK_100M_PEX2_REF_R_DP")
	)
	(segment
		(start 251.6505 -239.809528)
		(end 251.6505 -264.295128)
		(width 0.1143)
		(layer "B.Cu")
		(net "CLK_100M_PEX2_REF_R_DP")
	)
	(segment
		(start 267.557504 -299.999908)
		(end 267.640054 -299.917358)
		(width 0.0889)
		(layer "B.Cu")
		(net "CLK_100M_PEX2_REF_R_DP")
	)
	(segment
		(start 251.6505 -264.295128)
		(end 255.873504 -274.49145)
		(width 0.1143)
		(layer "B.Cu")
		(net "CLK_100M_PEX2_REF_R_DP")
	)
	(segment
		(start 243.1415 -214.048594)
		(end 242.861846 -214.72398)
		(width 0.1143)
		(layer "B.Cu")
		(net "CLK_100M_PEX2_REF_R_DP")
	)
	(segment
		(start 245.885462 -208.176876)
		(end 245.638066 -208.774284)
		(width 0.1143)
		(layer "B.Cu")
		(net "CLK_100M_PEX2_REF_R_DP")
	)
	(segment
		(start 237.6424 -151.660098)
		(end 237.7694 -151.787098)
		(width 0.1143)
		(layer "B.Cu")
		(net "CLK_100M_PEX2_REF_R_DP")
	)
	(segment
		(start 237.092744 -155.922218)
		(end 237.092744 -162.462718)
		(width 0.1143)
		(layer "B.Cu")
		(net "CLK_100M_PEX2_REF_R_DP")
	)
	(segment
		(start 267.176758 -299.999908)
		(end 267.535406 -299.999908)
		(width 0.1143)
		(layer "B.Cu")
		(net "CLK_100M_PEX2_REF_R_DP")
	)
	(segment
		(start 269.1511 -299.523912)
		(end 269.1511 -299.313854)
		(width 0.0889)
		(layer "B.Cu")
		(net "CLK_100M_PEX2_REF_R_DP")
	)
	(segment
		(start 237.092744 -162.462718)
		(end 243.459 -168.828974)
		(width 0.1143)
		(layer "B.Cu")
		(net "CLK_100M_PEX2_REF_R_DP")
	)
	(segment
		(start 244.237764 -210.17484)
		(end 244.237764 -211.273136)
		(width 0.1143)
		(layer "B.Cu")
		(net "CLK_100M_PEX2_REF_R_DP")
	)
	(segment
		(start 245.885462 -206.074518)
		(end 245.885462 -208.176876)
		(width 0.1143)
		(layer "B.Cu")
		(net "CLK_100M_PEX2_REF_R_DP")
	)
	(segment
		(start 243.9543 -216.577926)
		(end 243.9543 -217.825066)
		(width 0.1143)
		(layer "B.Cu")
		(net "CLK_100M_PEX2_REF_R_DP")
	)
	(segment
		(start 261.34568 -295.826434)
		(end 263.717532 -298.198286)
		(width 0.1143)
		(layer "B.Cu")
		(net "CLK_100M_PEX2_REF_R_DP")
	)
	(segment
		(start 243.43995 -212.070696)
		(end 243.1415 -212.79231)
		(width 0.1143)
		(layer "B.Cu")
		(net "CLK_100M_PEX2_REF_R_DP")
	)
	(segment
		(start 249.101356 -191.702436)
		(end 246.519954 -194.283838)
		(width 0.1143)
		(layer "B.Cu")
		(net "CLK_100M_PEX2_REF_R_DP")
	)
	(segment
		(start 237.424214 -151.660098)
		(end 237.6424 -151.660098)
		(width 0.1143)
		(layer "B.Cu")
		(net "CLK_100M_PEX2_REF_R_DP")
	)
	(segment
		(start 242.861846 -215.485472)
		(end 243.9543 -216.577926)
		(width 0.1143)
		(layer "B.Cu")
		(net "CLK_100M_PEX2_REF_R_DP")
	)
	(segment
		(start 268.757654 -299.917358)
		(end 269.1511 -299.523912)
		(width 0.0889)
		(layer "B.Cu")
		(net "CLK_100M_PEX2_REF_R_DP")
	)
	(segment
		(start 269.1511 -299.313854)
		(end 269.24 -299.224954)
		(width 0.0889)
		(layer "B.Cu")
		(net "CLK_100M_PEX2_REF_R_DP")
	)
	(segment
		(start 144.342866 -390.763252)
		(end 144.377918 -390.798304)
		(width 0.13208)
		(layer "F.Cu")
		(net "SMB_GPU1_ALERT_R_N")
	)
	(segment
		(start 144.377918 -390.798304)
		(end 145.239486 -390.798304)
		(width 0.13208)
		(layer "F.Cu")
		(net "SMB_GPU1_ALERT_R_N")
	)
	(via
		(at 144.342866 -390.763252)
		(size 0.508)
		(drill 0.254)
		(layers "F.Cu" "B.Cu")
		(net "SMB_GPU1_ALERT_R_N")
	)
	(segment
		(start 143.129 -390.271)
		(end 140.156946 -390.271)
		(width 0.15494)
		(layer "In9.Cu")
		(net "SMB_GPU1_ALERT_R_N")
	)
	(segment
		(start 137.414 -393.013946)
		(end 137.414 -404.6728)
		(width 0.15494)
		(layer "In9.Cu")
		(net "SMB_GPU1_ALERT_R_N")
	)
	(segment
		(start 140.156946 -390.271)
		(end 137.414 -393.013946)
		(width 0.15494)
		(layer "In9.Cu")
		(net "SMB_GPU1_ALERT_R_N")
	)
	(segment
		(start 137.414 -404.6728)
		(end 136.0678 -406.019)
		(width 0.15494)
		(layer "In9.Cu")
		(net "SMB_GPU1_ALERT_R_N")
	)
	(segment
		(start 136.0678 -406.019)
		(end 133.939026 -406.019)
		(width 0.15494)
		(layer "In9.Cu")
		(net "SMB_GPU1_ALERT_R_N")
	)
	(segment
		(start 143.621252 -390.763252)
		(end 143.129 -390.271)
		(width 0.15494)
		(layer "In9.Cu")
		(net "SMB_GPU1_ALERT_R_N")
	)
	(segment
		(start 133.939026 -406.019)
		(end 133.51002 -405.589994)
		(width 0.15494)
		(layer "In9.Cu")
		(net "SMB_GPU1_ALERT_R_N")
	)
	(segment
		(start 144.342866 -390.763252)
		(end 143.621252 -390.763252)
		(width 0.15494)
		(layer "In9.Cu")
		(net "SMB_GPU1_ALERT_R_N")
	)
	(segment
		(start 108.669582 -90.937842)
		(end 108.669582 -90.741246)
		(width 0.13208)
		(layer "F.Cu")
		(net "SSD7_CLK_EN_R_N")
	)
	(segment
		(start 109.438948 -89.97188)
		(end 109.438948 -88.928956)
		(width 0.13208)
		(layer "F.Cu")
		(net "SSD7_CLK_EN_R_N")
	)
	(segment
		(start 108.41482 -91.192604)
		(end 108.669582 -90.937842)
		(width 0.13208)
		(layer "F.Cu")
		(net "SSD7_CLK_EN_R_N")
	)
	(segment
		(start 108.669582 -90.741246)
		(end 109.438948 -89.97188)
		(width 0.13208)
		(layer "F.Cu")
		(net "SSD7_CLK_EN_R_N")
	)
	(via
		(at 78.473808 -90.64625)
		(size 0.508)
		(drill 0.254)
		(layers "F.Cu" "B.Cu")
		(net "SSD7_CLK_EN_R_N")
	)
	(via
		(at 108.41482 -91.192604)
		(size 0.508)
		(drill 0.254)
		(layers "F.Cu" "B.Cu")
		(net "SSD7_CLK_EN_R_N")
	)
	(via
		(at 349.123 -236.347)
		(size 0.508)
		(drill 0.254)
		(layers "F.Cu" "B.Cu")
		(net "SSD7_CLK_EN_R_N")
	)
	(via
		(at 96.934274 -206.793338)
		(size 0.508)
		(drill 0.254)
		(layers "F.Cu" "B.Cu")
		(net "SSD7_CLK_EN_R_N")
	)
	(segment
		(start 350.139 -233.95305)
		(end 349.571818 -234.520232)
		(width 0.13208)
		(layer "B.Cu")
		(net "SSD7_CLK_EN_R_N")
	)
	(segment
		(start 349.571818 -235.898182)
		(end 349.123 -236.347)
		(width 0.13208)
		(layer "B.Cu")
		(net "SSD7_CLK_EN_R_N")
	)
	(segment
		(start 349.571818 -234.520232)
		(end 349.571818 -235.898182)
		(width 0.13208)
		(layer "B.Cu")
		(net "SSD7_CLK_EN_R_N")
	)
	(segment
		(start 85.7504 -128.06172)
		(end 88.9254 -131.23672)
		(width 0.15494)
		(layer "In5.Cu")
		(net "SSD7_CLK_EN_R_N")
	)
	(segment
		(start 92.28328 -142.52702)
		(end 92.28328 -178.5366)
		(width 0.15494)
		(layer "In5.Cu")
		(net "SSD7_CLK_EN_R_N")
	)
	(segment
		(start 97.188274 -206.539338)
		(end 96.934274 -206.793338)
		(width 0.15494)
		(layer "In5.Cu")
		(net "SSD7_CLK_EN_R_N")
	)
	(segment
		(start 79.393542 -107.019598)
		(end 78.121256 -108.291884)
		(width 0.15494)
		(layer "In5.Cu")
		(net "SSD7_CLK_EN_R_N")
	)
	(segment
		(start 80.48244 -117.656102)
		(end 83.351624 -117.656102)
		(width 0.15494)
		(layer "In5.Cu")
		(net "SSD7_CLK_EN_R_N")
	)
	(segment
		(start 99.792282 -203.813664)
		(end 97.188274 -206.417672)
		(width 0.15494)
		(layer "In5.Cu")
		(net "SSD7_CLK_EN_R_N")
	)
	(segment
		(start 93.777308 -180.030628)
		(end 93.777308 -186.28233)
		(width 0.15494)
		(layer "In5.Cu")
		(net "SSD7_CLK_EN_R_N")
	)
	(segment
		(start 85.7504 -120.054878)
		(end 85.7504 -128.06172)
		(width 0.15494)
		(layer "In5.Cu")
		(net "SSD7_CLK_EN_R_N")
	)
	(segment
		(start 79.393542 -92.69222)
		(end 79.393542 -107.019598)
		(width 0.15494)
		(layer "In5.Cu")
		(net "SSD7_CLK_EN_R_N")
	)
	(segment
		(start 78.473808 -91.772486)
		(end 79.393542 -92.69222)
		(width 0.15494)
		(layer "In5.Cu")
		(net "SSD7_CLK_EN_R_N")
	)
	(segment
		(start 93.777308 -186.28233)
		(end 97.4598 -189.964822)
		(width 0.15494)
		(layer "In5.Cu")
		(net "SSD7_CLK_EN_R_N")
	)
	(segment
		(start 102.145338 -198.385938)
		(end 102.145338 -203.223876)
		(width 0.15494)
		(layer "In5.Cu")
		(net "SSD7_CLK_EN_R_N")
	)
	(segment
		(start 101.55555 -203.813664)
		(end 99.792282 -203.813664)
		(width 0.15494)
		(layer "In5.Cu")
		(net "SSD7_CLK_EN_R_N")
	)
	(segment
		(start 97.4598 -189.964822)
		(end 97.4598 -193.7004)
		(width 0.15494)
		(layer "In5.Cu")
		(net "SSD7_CLK_EN_R_N")
	)
	(segment
		(start 97.4598 -193.7004)
		(end 102.145338 -198.385938)
		(width 0.15494)
		(layer "In5.Cu")
		(net "SSD7_CLK_EN_R_N")
	)
	(segment
		(start 83.351624 -117.656102)
		(end 85.7504 -120.054878)
		(width 0.15494)
		(layer "In5.Cu")
		(net "SSD7_CLK_EN_R_N")
	)
	(segment
		(start 88.9254 -131.23672)
		(end 88.9254 -134.420356)
		(width 0.15494)
		(layer "In5.Cu")
		(net "SSD7_CLK_EN_R_N")
	)
	(segment
		(start 78.121256 -108.291884)
		(end 78.121256 -115.294918)
		(width 0.15494)
		(layer "In5.Cu")
		(net "SSD7_CLK_EN_R_N")
	)
	(segment
		(start 92.28328 -178.5366)
		(end 93.777308 -180.030628)
		(width 0.15494)
		(layer "In5.Cu")
		(net "SSD7_CLK_EN_R_N")
	)
	(segment
		(start 97.188274 -206.417672)
		(end 97.188274 -206.539338)
		(width 0.15494)
		(layer "In5.Cu")
		(net "SSD7_CLK_EN_R_N")
	)
	(segment
		(start 78.473808 -90.64625)
		(end 78.473808 -91.772486)
		(width 0.15494)
		(layer "In5.Cu")
		(net "SSD7_CLK_EN_R_N")
	)
	(segment
		(start 78.121256 -115.294918)
		(end 80.48244 -117.656102)
		(width 0.15494)
		(layer "In5.Cu")
		(net "SSD7_CLK_EN_R_N")
	)
	(segment
		(start 102.145338 -203.223876)
		(end 101.55555 -203.813664)
		(width 0.15494)
		(layer "In5.Cu")
		(net "SSD7_CLK_EN_R_N")
	)
	(segment
		(start 88.9254 -134.420356)
		(end 92.28328 -142.52702)
		(width 0.15494)
		(layer "In5.Cu")
		(net "SSD7_CLK_EN_R_N")
	)
	(segment
		(start 303.570894 -249.870468)
		(end 299.678598 -249.870468)
		(width 0.15494)
		(layer "In15.Cu")
		(net "SSD7_CLK_EN_R_N")
	)
	(segment
		(start 98.611944 -208.471008)
		(end 96.934274 -206.793338)
		(width 0.15494)
		(layer "In15.Cu")
		(net "SSD7_CLK_EN_R_N")
	)
	(segment
		(start 152.64638 -233.86288)
		(end 151.55291 -233.86288)
		(width 0.15494)
		(layer "In15.Cu")
		(net "SSD7_CLK_EN_R_N")
	)
	(segment
		(start 249.083322 -248.069608)
		(end 247.847358 -246.833644)
		(width 0.15494)
		(layer "In15.Cu")
		(net "SSD7_CLK_EN_R_N")
	)
	(segment
		(start 184.499504 -243.184934)
		(end 181.1401 -239.82553)
		(width 0.15494)
		(layer "In15.Cu")
		(net "SSD7_CLK_EN_R_N")
	)
	(segment
		(start 230.09479 -247.62841)
		(end 222.945452 -247.62841)
		(width 0.15494)
		(layer "In15.Cu")
		(net "SSD7_CLK_EN_R_N")
	)
	(segment
		(start 349.824802 -238.048038)
		(end 349.824802 -239.658652)
		(width 0.15494)
		(layer "In15.Cu")
		(net "SSD7_CLK_EN_R_N")
	)
	(segment
		(start 331.479398 -250.64212)
		(end 326.660764 -250.64212)
		(width 0.15494)
		(layer "In15.Cu")
		(net "SSD7_CLK_EN_R_N")
	)
	(segment
		(start 240.124234 -246.833644)
		(end 238.087916 -248.869962)
		(width 0.15494)
		(layer "In15.Cu")
		(net "SSD7_CLK_EN_R_N")
	)
	(segment
		(start 231.336342 -248.869962)
		(end 230.09479 -247.62841)
		(width 0.15494)
		(layer "In15.Cu")
		(net "SSD7_CLK_EN_R_N")
	)
	(segment
		(start 222.510604 -247.193562)
		(end 221.514924 -247.193562)
		(width 0.15494)
		(layer "In15.Cu")
		(net "SSD7_CLK_EN_R_N")
	)
	(segment
		(start 123.848114 -235.99775)
		(end 121.30405 -238.541814)
		(width 0.15494)
		(layer "In15.Cu")
		(net "SSD7_CLK_EN_R_N")
	)
	(segment
		(start 273.654774 -248.412)
		(end 273.312382 -248.069608)
		(width 0.15494)
		(layer "In15.Cu")
		(net "SSD7_CLK_EN_R_N")
	)
	(segment
		(start 104.397048 -88.989662)
		(end 106.211878 -88.989662)
		(width 0.15494)
		(layer "In15.Cu")
		(net "SSD7_CLK_EN_R_N")
	)
	(segment
		(start 189.194948 -247.491758)
		(end 184.888124 -243.184934)
		(width 0.15494)
		(layer "In15.Cu")
		(net "SSD7_CLK_EN_R_N")
	)
	(segment
		(start 333.886556 -249.42038)
		(end 333.105252 -250.201684)
		(width 0.15494)
		(layer "In15.Cu")
		(net "SSD7_CLK_EN_R_N")
	)
	(segment
		(start 113.73866 -212.711538)
		(end 109.49813 -208.471008)
		(width 0.15494)
		(layer "In15.Cu")
		(net "SSD7_CLK_EN_R_N")
	)
	(segment
		(start 103.7463 -88.338914)
		(end 104.397048 -88.989662)
		(width 0.15494)
		(layer "In15.Cu")
		(net "SSD7_CLK_EN_R_N")
	)
	(segment
		(start 83.369404 -91.755976)
		(end 87.181436 -87.943944)
		(width 0.15494)
		(layer "In15.Cu")
		(net "SSD7_CLK_EN_R_N")
	)
	(segment
		(start 247.847358 -246.833644)
		(end 240.124234 -246.833644)
		(width 0.15494)
		(layer "In15.Cu")
		(net "SSD7_CLK_EN_R_N")
	)
	(segment
		(start 87.181436 -87.943944)
		(end 98.54438 -87.943944)
		(width 0.15494)
		(layer "In15.Cu")
		(net "SSD7_CLK_EN_R_N")
	)
	(segment
		(start 98.93935 -88.338914)
		(end 103.7463 -88.338914)
		(width 0.15494)
		(layer "In15.Cu")
		(net "SSD7_CLK_EN_R_N")
	)
	(segment
		(start 349.123 -236.347)
		(end 349.123 -237.346236)
		(width 0.15494)
		(layer "In15.Cu")
		(net "SSD7_CLK_EN_R_N")
	)
	(segment
		(start 155.172664 -234.35056)
		(end 153.823924 -234.35056)
		(width 0.15494)
		(layer "In15.Cu")
		(net "SSD7_CLK_EN_R_N")
	)
	(segment
		(start 349.123 -237.346236)
		(end 349.824802 -238.048038)
		(width 0.15494)
		(layer "In15.Cu")
		(net "SSD7_CLK_EN_R_N")
	)
	(segment
		(start 141.969236 -233.15168)
		(end 139.123166 -235.99775)
		(width 0.15494)
		(layer "In15.Cu")
		(net "SSD7_CLK_EN_R_N")
	)
	(segment
		(start 109.49813 -208.471008)
		(end 98.611944 -208.471008)
		(width 0.15494)
		(layer "In15.Cu")
		(net "SSD7_CLK_EN_R_N")
	)
	(segment
		(start 113.73866 -232.62463)
		(end 113.73866 -212.711538)
		(width 0.15494)
		(layer "In15.Cu")
		(net "SSD7_CLK_EN_R_N")
	)
	(segment
		(start 153.823924 -234.35056)
		(end 152.64638 -233.86288)
		(width 0.15494)
		(layer "In15.Cu")
		(net "SSD7_CLK_EN_R_N")
	)
	(segment
		(start 299.678598 -249.870468)
		(end 298.22013 -248.412)
		(width 0.15494)
		(layer "In15.Cu")
		(net "SSD7_CLK_EN_R_N")
	)
	(segment
		(start 340.063074 -249.42038)
		(end 333.886556 -249.42038)
		(width 0.15494)
		(layer "In15.Cu")
		(net "SSD7_CLK_EN_R_N")
	)
	(segment
		(start 326.660764 -250.64212)
		(end 325.79818 -249.779536)
		(width 0.15494)
		(layer "In15.Cu")
		(net "SSD7_CLK_EN_R_N")
	)
	(segment
		(start 119.655844 -238.541814)
		(end 113.73866 -232.62463)
		(width 0.15494)
		(layer "In15.Cu")
		(net "SSD7_CLK_EN_R_N")
	)
	(segment
		(start 298.22013 -248.412)
		(end 273.654774 -248.412)
		(width 0.15494)
		(layer "In15.Cu")
		(net "SSD7_CLK_EN_R_N")
	)
	(segment
		(start 78.473808 -90.64625)
		(end 79.583534 -91.755976)
		(width 0.15494)
		(layer "In15.Cu")
		(net "SSD7_CLK_EN_R_N")
	)
	(segment
		(start 121.30405 -238.541814)
		(end 119.655844 -238.541814)
		(width 0.15494)
		(layer "In15.Cu")
		(net "SSD7_CLK_EN_R_N")
	)
	(segment
		(start 221.216728 -247.491758)
		(end 189.194948 -247.491758)
		(width 0.15494)
		(layer "In15.Cu")
		(net "SSD7_CLK_EN_R_N")
	)
	(segment
		(start 238.087916 -248.869962)
		(end 231.336342 -248.869962)
		(width 0.15494)
		(layer "In15.Cu")
		(net "SSD7_CLK_EN_R_N")
	)
	(segment
		(start 160.647634 -239.82553)
		(end 155.172664 -234.35056)
		(width 0.15494)
		(layer "In15.Cu")
		(net "SSD7_CLK_EN_R_N")
	)
	(segment
		(start 273.312382 -248.069608)
		(end 249.083322 -248.069608)
		(width 0.15494)
		(layer "In15.Cu")
		(net "SSD7_CLK_EN_R_N")
	)
	(segment
		(start 222.945452 -247.62841)
		(end 222.510604 -247.193562)
		(width 0.15494)
		(layer "In15.Cu")
		(net "SSD7_CLK_EN_R_N")
	)
	(segment
		(start 331.919834 -250.201684)
		(end 331.479398 -250.64212)
		(width 0.15494)
		(layer "In15.Cu")
		(net "SSD7_CLK_EN_R_N")
	)
	(segment
		(start 325.79818 -249.779536)
		(end 303.79035 -249.779536)
		(width 0.15494)
		(layer "In15.Cu")
		(net "SSD7_CLK_EN_R_N")
	)
	(segment
		(start 333.105252 -250.201684)
		(end 331.919834 -250.201684)
		(width 0.15494)
		(layer "In15.Cu")
		(net "SSD7_CLK_EN_R_N")
	)
	(segment
		(start 184.888124 -243.184934)
		(end 184.499504 -243.184934)
		(width 0.15494)
		(layer "In15.Cu")
		(net "SSD7_CLK_EN_R_N")
	)
	(segment
		(start 349.824802 -239.658652)
		(end 340.063074 -249.42038)
		(width 0.15494)
		(layer "In15.Cu")
		(net "SSD7_CLK_EN_R_N")
	)
	(segment
		(start 106.211878 -88.989662)
		(end 108.41482 -91.192604)
		(width 0.15494)
		(layer "In15.Cu")
		(net "SSD7_CLK_EN_R_N")
	)
	(segment
		(start 181.1401 -239.82553)
		(end 160.647634 -239.82553)
		(width 0.15494)
		(layer "In15.Cu")
		(net "SSD7_CLK_EN_R_N")
	)
	(segment
		(start 221.514924 -247.193562)
		(end 221.216728 -247.491758)
		(width 0.15494)
		(layer "In15.Cu")
		(net "SSD7_CLK_EN_R_N")
	)
	(segment
		(start 149.835108 -233.15168)
		(end 141.969236 -233.15168)
		(width 0.15494)
		(layer "In15.Cu")
		(net "SSD7_CLK_EN_R_N")
	)
	(segment
		(start 139.123166 -235.99775)
		(end 123.848114 -235.99775)
		(width 0.15494)
		(layer "In15.Cu")
		(net "SSD7_CLK_EN_R_N")
	)
	(segment
		(start 98.54438 -87.943944)
		(end 98.93935 -88.338914)
		(width 0.15494)
		(layer "In15.Cu")
		(net "SSD7_CLK_EN_R_N")
	)
	(segment
		(start 303.79035 -249.779536)
		(end 303.570894 -249.870468)
		(width 0.15494)
		(layer "In15.Cu")
		(net "SSD7_CLK_EN_R_N")
	)
	(segment
		(start 151.55291 -233.86288)
		(end 149.835108 -233.15168)
		(width 0.15494)
		(layer "In15.Cu")
		(net "SSD7_CLK_EN_R_N")
	)
	(segment
		(start 79.583534 -91.755976)
		(end 83.369404 -91.755976)
		(width 0.15494)
		(layer "In15.Cu")
		(net "SSD7_CLK_EN_R_N")
	)
	(segment
		(start 311.836308 -61.487812)
		(end 311.204356 -62.119764)
		(width 0.13208)
		(layer "F.Cu")
		(net "PWRGD_P12V_SSD11_R")
	)
	(segment
		(start 312.073544 -65.75552)
		(end 324.928484 -65.75552)
		(width 0.13208)
		(layer "F.Cu")
		(net "PWRGD_P12V_SSD11_R")
	)
	(segment
		(start 339.693758 -214.387176)
		(end 339.293962 -213.98738)
		(width 0.13208)
		(layer "F.Cu")
		(net "PWRGD_P12V_SSD11_R")
	)
	(segment
		(start 311.204356 -64.886332)
		(end 312.073544 -65.75552)
		(width 0.13208)
		(layer "F.Cu")
		(net "PWRGD_P12V_SSD11_R")
	)
	(segment
		(start 336.867754 -53.051456)
		(end 337.523074 -53.051456)
		(width 0.13208)
		(layer "F.Cu")
		(net "PWRGD_P12V_SSD11_R")
	)
	(segment
		(start 311.204356 -62.119764)
		(end 311.204356 -64.886332)
		(width 0.13208)
		(layer "F.Cu")
		(net "PWRGD_P12V_SSD11_R")
	)
	(segment
		(start 313.683396 -61.487812)
		(end 311.836308 -61.487812)
		(width 0.13208)
		(layer "F.Cu")
		(net "PWRGD_P12V_SSD11_R")
	)
	(via
		(at 324.928484 -65.75552)
		(size 0.508)
		(drill 0.254)
		(layers "F.Cu" "B.Cu")
		(net "PWRGD_P12V_SSD11_R")
	)
	(via
		(at 339.293962 -213.98738)
		(size 0.4572)
		(drill 0.254)
		(layers "F.Cu" "B.Cu")
		(net "PWRGD_P12V_SSD11_R")
	)
	(via
		(at 337.523074 -53.051456)
		(size 0.508)
		(drill 0.254)
		(layers "F.Cu" "B.Cu")
		(net "PWRGD_P12V_SSD11_R")
	)
	(segment
		(start 335.943702 -64.240664)
		(end 335.943702 -57.983628)
		(width 0.15494)
		(layer "In5.Cu")
		(net "PWRGD_P12V_SSD11_R")
	)
	(segment
		(start 329.519534 -64.60363)
		(end 335.580736 -64.60363)
		(width 0.15494)
		(layer "In5.Cu")
		(net "PWRGD_P12V_SSD11_R")
	)
	(segment
		(start 335.461102 -57.501028)
		(end 335.461102 -55.113428)
		(width 0.15494)
		(layer "In5.Cu")
		(net "PWRGD_P12V_SSD11_R")
	)
	(segment
		(start 324.928484 -65.75552)
		(end 328.367644 -65.75552)
		(width 0.15494)
		(layer "In5.Cu")
		(net "PWRGD_P12V_SSD11_R")
	)
	(segment
		(start 328.367644 -65.75552)
		(end 329.519534 -64.60363)
		(width 0.15494)
		(layer "In5.Cu")
		(net "PWRGD_P12V_SSD11_R")
	)
	(segment
		(start 335.461102 -55.113428)
		(end 337.523074 -53.051456)
		(width 0.15494)
		(layer "In5.Cu")
		(net "PWRGD_P12V_SSD11_R")
	)
	(segment
		(start 335.580736 -64.60363)
		(end 335.943702 -64.240664)
		(width 0.15494)
		(layer "In5.Cu")
		(net "PWRGD_P12V_SSD11_R")
	)
	(segment
		(start 335.943702 -57.983628)
		(end 335.461102 -57.501028)
		(width 0.15494)
		(layer "In5.Cu")
		(net "PWRGD_P12V_SSD11_R")
	)
	(segment
		(start 351.709228 -95.44431)
		(end 350.820228 -94.55531)
		(width 0.15494)
		(layer "In7.Cu")
		(net "PWRGD_P12V_SSD11_R")
	)
	(segment
		(start 343.040716 -58.569098)
		(end 337.523074 -53.051456)
		(width 0.15494)
		(layer "In7.Cu")
		(net "PWRGD_P12V_SSD11_R")
	)
	(segment
		(start 346.5576 -184.124854)
		(end 346.5576 -169.519346)
		(width 0.15494)
		(layer "In7.Cu")
		(net "PWRGD_P12V_SSD11_R")
	)
	(segment
		(start 341.630762 -205.538324)
		(end 342.138 -205.031086)
		(width 0.15494)
		(layer "In7.Cu")
		(net "PWRGD_P12V_SSD11_R")
	)
	(segment
		(start 341.630762 -207.365092)
		(end 341.630762 -205.538324)
		(width 0.15494)
		(layer "In7.Cu")
		(net "PWRGD_P12V_SSD11_R")
	)
	(segment
		(start 339.293962 -213.98738)
		(end 339.693758 -213.587584)
		(width 0.0889)
		(layer "In7.Cu")
		(net "PWRGD_P12V_SSD11_R")
	)
	(segment
		(start 340.351364 -208.64449)
		(end 341.630762 -207.365092)
		(width 0.15494)
		(layer "In7.Cu")
		(net "PWRGD_P12V_SSD11_R")
	)
	(segment
		(start 346.5576 -169.519346)
		(end 343.64422 -166.605966)
		(width 0.15494)
		(layer "In7.Cu")
		(net "PWRGD_P12V_SSD11_R")
	)
	(segment
		(start 343.64422 -142.308834)
		(end 344.644726 -141.308328)
		(width 0.15494)
		(layer "In7.Cu")
		(net "PWRGD_P12V_SSD11_R")
	)
	(segment
		(start 342.138 -205.031086)
		(end 342.138 -199.8472)
		(width 0.15494)
		(layer "In7.Cu")
		(net "PWRGD_P12V_SSD11_R")
	)
	(segment
		(start 340.351364 -211.463636)
		(end 340.351364 -208.64449)
		(width 0.15494)
		(layer "In7.Cu")
		(net "PWRGD_P12V_SSD11_R")
	)
	(segment
		(start 343.64422 -166.605966)
		(end 343.64422 -142.308834)
		(width 0.15494)
		(layer "In7.Cu")
		(net "PWRGD_P12V_SSD11_R")
	)
	(segment
		(start 341.782654 -188.8998)
		(end 346.5576 -184.124854)
		(width 0.15494)
		(layer "In7.Cu")
		(net "PWRGD_P12V_SSD11_R")
	)
	(segment
		(start 341.0458 -198.755)
		(end 341.0458 -189.0268)
		(width 0.15494)
		(layer "In7.Cu")
		(net "PWRGD_P12V_SSD11_R")
	)
	(segment
		(start 340.351364 -211.590636)
		(end 340.351364 -211.463636)
		(width 0.0889)
		(layer "In7.Cu")
		(net "PWRGD_P12V_SSD11_R")
	)
	(segment
		(start 350.820228 -84.324444)
		(end 343.040716 -76.544932)
		(width 0.15494)
		(layer "In7.Cu")
		(net "PWRGD_P12V_SSD11_R")
	)
	(segment
		(start 343.040716 -76.544932)
		(end 343.040716 -58.569098)
		(width 0.15494)
		(layer "In7.Cu")
		(net "PWRGD_P12V_SSD11_R")
	)
	(segment
		(start 344.644726 -141.308328)
		(end 344.644726 -126.519686)
		(width 0.15494)
		(layer "In7.Cu")
		(net "PWRGD_P12V_SSD11_R")
	)
	(segment
		(start 341.1728 -188.8998)
		(end 341.782654 -188.8998)
		(width 0.15494)
		(layer "In7.Cu")
		(net "PWRGD_P12V_SSD11_R")
	)
	(segment
		(start 339.693758 -212.248242)
		(end 340.351364 -211.590636)
		(width 0.0889)
		(layer "In7.Cu")
		(net "PWRGD_P12V_SSD11_R")
	)
	(segment
		(start 339.693758 -213.587584)
		(end 339.693758 -212.248242)
		(width 0.0889)
		(layer "In7.Cu")
		(net "PWRGD_P12V_SSD11_R")
	)
	(segment
		(start 342.138 -199.8472)
		(end 341.0458 -198.755)
		(width 0.15494)
		(layer "In7.Cu")
		(net "PWRGD_P12V_SSD11_R")
	)
	(segment
		(start 351.709228 -119.455184)
		(end 351.709228 -95.44431)
		(width 0.15494)
		(layer "In7.Cu")
		(net "PWRGD_P12V_SSD11_R")
	)
	(segment
		(start 341.0458 -189.0268)
		(end 341.1728 -188.8998)
		(width 0.15494)
		(layer "In7.Cu")
		(net "PWRGD_P12V_SSD11_R")
	)
	(segment
		(start 344.644726 -126.519686)
		(end 351.709228 -119.455184)
		(width 0.15494)
		(layer "In7.Cu")
		(net "PWRGD_P12V_SSD11_R")
	)
	(segment
		(start 350.820228 -94.55531)
		(end 350.820228 -84.324444)
		(width 0.15494)
		(layer "In7.Cu")
		(net "PWRGD_P12V_SSD11_R")
	)
	(segment
		(start 417.53155 -224.027746)
		(end 418.68725 -225.183446)
		(width 0.13208)
		(layer "F.Cu")
		(net "UART_PEX0_SDB_BUF_R_TX")
	)
	(segment
		(start 418.68725 -225.183446)
		(end 418.68725 -225.238564)
		(width 0.13208)
		(layer "F.Cu")
		(net "UART_PEX0_SDB_BUF_R_TX")
	)
	(segment
		(start 455.542396 -235.600494)
		(end 455.542396 -236.314996)
		(width 0.13208)
		(layer "F.Cu")
		(net "UART_PEX0_SDB_BUF_R_TX")
	)
	(via
		(at 376.025156 -241.862356)
		(size 0.508)
		(drill 0.254)
		(layers "F.Cu" "B.Cu")
		(net "UART_PEX0_SDB_BUF_R_TX")
	)
	(via
		(at 455.542396 -236.314996)
		(size 0.508)
		(drill 0.254)
		(layers "F.Cu" "B.Cu")
		(net "UART_PEX0_SDB_BUF_R_TX")
	)
	(via
		(at 418.68725 -225.238564)
		(size 0.508)
		(drill 0.254)
		(layers "F.Cu" "B.Cu")
		(net "UART_PEX0_SDB_BUF_R_TX")
	)
	(segment
		(start 377.41733 -242.773962)
		(end 376.936762 -242.773962)
		(width 0.13208)
		(layer "B.Cu")
		(net "UART_PEX0_SDB_BUF_R_TX")
	)
	(segment
		(start 376.936762 -242.773962)
		(end 376.025156 -241.862356)
		(width 0.13208)
		(layer "B.Cu")
		(net "UART_PEX0_SDB_BUF_R_TX")
	)
	(segment
		(start 376.025156 -241.862356)
		(end 375.438416 -242.449096)
		(width 0.13208)
		(layer "B.Cu")
		(net "UART_PEX0_SDB_BUF_R_TX")
	)
	(segment
		(start 374.728486 -243.286026)
		(end 374.3706 -243.286026)
		(width 0.13208)
		(layer "B.Cu")
		(net "UART_PEX0_SDB_BUF_R_TX")
	)
	(segment
		(start 377.669552 -243.428012)
		(end 377.669552 -243.026184)
		(width 0.13208)
		(layer "B.Cu")
		(net "UART_PEX0_SDB_BUF_R_TX")
	)
	(segment
		(start 377.669552 -243.026184)
		(end 377.41733 -242.773962)
		(width 0.13208)
		(layer "B.Cu")
		(net "UART_PEX0_SDB_BUF_R_TX")
	)
	(segment
		(start 375.438416 -242.576096)
		(end 374.728486 -243.286026)
		(width 0.13208)
		(layer "B.Cu")
		(net "UART_PEX0_SDB_BUF_R_TX")
	)
	(segment
		(start 375.438416 -242.449096)
		(end 375.438416 -242.576096)
		(width 0.13208)
		(layer "B.Cu")
		(net "UART_PEX0_SDB_BUF_R_TX")
	)
	(segment
		(start 376.543316 -239.22736)
		(end 376.543316 -241.344196)
		(width 0.15494)
		(layer "In13.Cu")
		(net "UART_PEX0_SDB_BUF_R_TX")
	)
	(segment
		(start 375.444512 -232.846118)
		(end 376.006614 -233.40822)
		(width 0.15494)
		(layer "In13.Cu")
		(net "UART_PEX0_SDB_BUF_R_TX")
	)
	(segment
		(start 418.68725 -225.238564)
		(end 417.27882 -223.830134)
		(width 0.15494)
		(layer "In13.Cu")
		(net "UART_PEX0_SDB_BUF_R_TX")
	)
	(segment
		(start 444.7794 -237.8964)
		(end 451.3072 -237.8964)
		(width 0.15494)
		(layer "In13.Cu")
		(net "UART_PEX0_SDB_BUF_R_TX")
	)
	(segment
		(start 430.227486 -236.7788)
		(end 443.6618 -236.7788)
		(width 0.15494)
		(layer "In13.Cu")
		(net "UART_PEX0_SDB_BUF_R_TX")
	)
	(segment
		(start 443.6618 -236.7788)
		(end 444.7794 -237.8964)
		(width 0.15494)
		(layer "In13.Cu")
		(net "UART_PEX0_SDB_BUF_R_TX")
	)
	(segment
		(start 453.034654 -234.2896)
		(end 453.517 -234.2896)
		(width 0.15494)
		(layer "In13.Cu")
		(net "UART_PEX0_SDB_BUF_R_TX")
	)
	(segment
		(start 378.491496 -226.3902)
		(end 378.491496 -228.492304)
		(width 0.15494)
		(layer "In13.Cu")
		(net "UART_PEX0_SDB_BUF_R_TX")
	)
	(segment
		(start 376.006614 -233.40822)
		(end 376.006614 -238.690658)
		(width 0.15494)
		(layer "In13.Cu")
		(net "UART_PEX0_SDB_BUF_R_TX")
	)
	(segment
		(start 376.543316 -241.344196)
		(end 376.025156 -241.862356)
		(width 0.15494)
		(layer "In13.Cu")
		(net "UART_PEX0_SDB_BUF_R_TX")
	)
	(segment
		(start 452.6026 -236.601)
		(end 452.6026 -234.721654)
		(width 0.15494)
		(layer "In13.Cu")
		(net "UART_PEX0_SDB_BUF_R_TX")
	)
	(segment
		(start 451.3072 -237.8964)
		(end 452.6026 -236.601)
		(width 0.15494)
		(layer "In13.Cu")
		(net "UART_PEX0_SDB_BUF_R_TX")
	)
	(segment
		(start 375.444512 -231.539288)
		(end 375.444512 -232.846118)
		(width 0.15494)
		(layer "In13.Cu")
		(net "UART_PEX0_SDB_BUF_R_TX")
	)
	(segment
		(start 376.006614 -238.690658)
		(end 376.543316 -239.22736)
		(width 0.15494)
		(layer "In13.Cu")
		(net "UART_PEX0_SDB_BUF_R_TX")
	)
	(segment
		(start 418.68725 -225.238564)
		(end 430.227486 -236.7788)
		(width 0.15494)
		(layer "In13.Cu")
		(net "UART_PEX0_SDB_BUF_R_TX")
	)
	(segment
		(start 417.27882 -223.830134)
		(end 381.051562 -223.830134)
		(width 0.15494)
		(layer "In13.Cu")
		(net "UART_PEX0_SDB_BUF_R_TX")
	)
	(segment
		(start 453.517 -234.2896)
		(end 455.542396 -236.314996)
		(width 0.15494)
		(layer "In13.Cu")
		(net "UART_PEX0_SDB_BUF_R_TX")
	)
	(segment
		(start 381.051562 -223.830134)
		(end 378.491496 -226.3902)
		(width 0.15494)
		(layer "In13.Cu")
		(net "UART_PEX0_SDB_BUF_R_TX")
	)
	(segment
		(start 378.491496 -228.492304)
		(end 375.444512 -231.539288)
		(width 0.15494)
		(layer "In13.Cu")
		(net "UART_PEX0_SDB_BUF_R_TX")
	)
	(segment
		(start 452.6026 -234.721654)
		(end 453.034654 -234.2896)
		(width 0.15494)
		(layer "In13.Cu")
		(net "UART_PEX0_SDB_BUF_R_TX")
	)
	(segment
		(start 114.956336 -87.384382)
		(end 114.638074 -87.06612)
		(width 0.13462)
		(layer "F.Cu")
		(net "CLK_100M_DB800ZL_SSD5_DN")
	)
	(segment
		(start 112.27308 -86.92261)
		(end 112.216692 -86.978998)
		(width 0.13462)
		(layer "F.Cu")
		(net "CLK_100M_DB800ZL_SSD5_DN")
	)
	(segment
		(start 113.066576 -86.92261)
		(end 112.27308 -86.92261)
		(width 0.13462)
		(layer "F.Cu")
		(net "CLK_100M_DB800ZL_SSD5_DN")
	)
	(segment
		(start 112.216692 -86.978998)
		(end 111.788956 -86.978998)
		(width 0.13462)
		(layer "F.Cu")
		(net "CLK_100M_DB800ZL_SSD5_DN")
	)
	(segment
		(start 113.413286 -87.06612)
		(end 113.066576 -86.92261)
		(width 0.13462)
		(layer "F.Cu")
		(net "CLK_100M_DB800ZL_SSD5_DN")
	)
	(segment
		(start 114.638074 -87.06612)
		(end 113.413286 -87.06612)
		(width 0.13462)
		(layer "F.Cu")
		(net "CLK_100M_DB800ZL_SSD5_DN")
	)
	(segment
		(start 132.066284 -187.931044)
		(end 132.066284 -187.110116)
		(width 0.13462)
		(layer "F.Cu")
		(net "CLK_100M_DB2000QL_GPU_REF1_R_DP")
	)
	(segment
		(start 132.5372 -185.434224)
		(end 132.91439 -185.057034)
		(width 0.13462)
		(layer "F.Cu")
		(net "CLK_100M_DB2000QL_GPU_REF1_R_DP")
	)
	(segment
		(start 132.066284 -187.110116)
		(end 132.5372 -186.6392)
		(width 0.13462)
		(layer "F.Cu")
		(net "CLK_100M_DB2000QL_GPU_REF1_R_DP")
	)
	(segment
		(start 132.367274 -188.232034)
		(end 132.066284 -187.931044)
		(width 0.13462)
		(layer "F.Cu")
		(net "CLK_100M_DB2000QL_GPU_REF1_R_DP")
	)
	(segment
		(start 132.5372 -186.6392)
		(end 132.5372 -185.434224)
		(width 0.13462)
		(layer "F.Cu")
		(net "CLK_100M_DB2000QL_GPU_REF1_R_DP")
	)
	(via
		(at 132.367274 -188.232034)
		(size 0.508)
		(drill 0.254)
		(layers "F.Cu" "B.Cu")
		(net "CLK_100M_DB2000QL_GPU_REF1_R_DP")
	)
	(segment
		(start 95.344742 -192.5828)
		(end 97.262442 -190.6651)
		(width 0.13462)
		(layer "B.Cu")
		(net "CLK_100M_DB2000QL_GPU_REF1_R_DP")
	)
	(segment
		(start 63.9572 -217.8812)
		(end 89.2556 -192.5828)
		(width 0.13462)
		(layer "B.Cu")
		(net "CLK_100M_DB2000QL_GPU_REF1_R_DP")
	)
	(segment
		(start 47.71009 -383.66827)
		(end 47.84471 -383.80289)
		(width 0.13462)
		(layer "B.Cu")
		(net "CLK_100M_DB2000QL_GPU_REF1_R_DP")
	)
	(segment
		(start 24.537924 -299.238924)
		(end 22.532848 -297.233848)
		(width 0.13462)
		(layer "B.Cu")
		(net "CLK_100M_DB2000QL_GPU_REF1_R_DP")
	)
	(segment
		(start 113.409222 -185.574432)
		(end 123.748038 -185.574432)
		(width 0.13462)
		(layer "B.Cu")
		(net "CLK_100M_DB2000QL_GPU_REF1_R_DP")
	)
	(segment
		(start 48.865282 -383.181606)
		(end 48.865282 -367.591594)
		(width 0.13462)
		(layer "B.Cu")
		(net "CLK_100M_DB2000QL_GPU_REF1_R_DP")
	)
	(segment
		(start 17.12468 -249.905774)
		(end 49.149254 -217.8812)
		(width 0.13462)
		(layer "B.Cu")
		(net "CLK_100M_DB2000QL_GPU_REF1_R_DP")
	)
	(segment
		(start 47.71009 -383.290064)
		(end 47.71009 -383.66827)
		(width 0.13462)
		(layer "B.Cu")
		(net "CLK_100M_DB2000QL_GPU_REF1_R_DP")
	)
	(segment
		(start 20.07108 -307.860446)
		(end 24.537924 -303.393602)
		(width 0.13462)
		(layer "B.Cu")
		(net "CLK_100M_DB2000QL_GPU_REF1_R_DP")
	)
	(segment
		(start 47.84471 -383.80289)
		(end 48.243998 -383.80289)
		(width 0.13462)
		(layer "B.Cu")
		(net "CLK_100M_DB2000QL_GPU_REF1_R_DP")
	)
	(segment
		(start 132.066284 -187.153804)
		(end 132.066284 -187.931044)
		(width 0.13462)
		(layer "B.Cu")
		(net "CLK_100M_DB2000QL_GPU_REF1_R_DP")
	)
	(segment
		(start 97.262442 -190.6651)
		(end 108.318554 -190.6651)
		(width 0.13462)
		(layer "B.Cu")
		(net "CLK_100M_DB2000QL_GPU_REF1_R_DP")
	)
	(segment
		(start 108.318554 -190.6651)
		(end 113.409222 -185.574432)
		(width 0.13462)
		(layer "B.Cu")
		(net "CLK_100M_DB2000QL_GPU_REF1_R_DP")
	)
	(segment
		(start 48.09998 -366.826292)
		(end 42.926 -361.652312)
		(width 0.13462)
		(layer "B.Cu")
		(net "CLK_100M_DB2000QL_GPU_REF1_R_DP")
	)
	(segment
		(start 131.778756 -186.866276)
		(end 132.066284 -187.153804)
		(width 0.13462)
		(layer "B.Cu")
		(net "CLK_100M_DB2000QL_GPU_REF1_R_DP")
	)
	(segment
		(start 123.748038 -185.574432)
		(end 125.039882 -186.866276)
		(width 0.13462)
		(layer "B.Cu")
		(net "CLK_100M_DB2000QL_GPU_REF1_R_DP")
	)
	(segment
		(start 89.2556 -192.5828)
		(end 95.344742 -192.5828)
		(width 0.13462)
		(layer "B.Cu")
		(net "CLK_100M_DB2000QL_GPU_REF1_R_DP")
	)
	(segment
		(start 19.94408 -268.703298)
		(end 17.12468 -261.896352)
		(width 0.13462)
		(layer "B.Cu")
		(net "CLK_100M_DB2000QL_GPU_REF1_R_DP")
	)
	(segment
		(start 48.385984 -367.306098)
		(end 48.09998 -367.020348)
		(width 0.13462)
		(layer "B.Cu")
		(net "CLK_100M_DB2000QL_GPU_REF1_R_DP")
	)
	(segment
		(start 48.243998 -383.80289)
		(end 48.865282 -383.181606)
		(width 0.13462)
		(layer "B.Cu")
		(net "CLK_100M_DB2000QL_GPU_REF1_R_DP")
	)
	(segment
		(start 42.926 -361.652312)
		(end 42.926 -341.74176)
		(width 0.13462)
		(layer "B.Cu")
		(net "CLK_100M_DB2000QL_GPU_REF1_R_DP")
	)
	(segment
		(start 20.07108 -323.881242)
		(end 20.07108 -307.860446)
		(width 0.13462)
		(layer "B.Cu")
		(net "CLK_100M_DB2000QL_GPU_REF1_R_DP")
	)
	(segment
		(start 125.039882 -186.866276)
		(end 131.778756 -186.866276)
		(width 0.13462)
		(layer "B.Cu")
		(net "CLK_100M_DB2000QL_GPU_REF1_R_DP")
	)
	(segment
		(start 19.94408 -275.69668)
		(end 19.94408 -268.703298)
		(width 0.13462)
		(layer "B.Cu")
		(net "CLK_100M_DB2000QL_GPU_REF1_R_DP")
	)
	(segment
		(start 24.699976 -328.510392)
		(end 20.07108 -323.881242)
		(width 0.13462)
		(layer "B.Cu")
		(net "CLK_100M_DB2000QL_GPU_REF1_R_DP")
	)
	(segment
		(start 41.36263 -340.178644)
		(end 24.699976 -328.510392)
		(width 0.13462)
		(layer "B.Cu")
		(net "CLK_100M_DB2000QL_GPU_REF1_R_DP")
	)
	(segment
		(start 48.865282 -367.591594)
		(end 48.579786 -367.306098)
		(width 0.13462)
		(layer "B.Cu")
		(net "CLK_100M_DB2000QL_GPU_REF1_R_DP")
	)
	(segment
		(start 48.579786 -367.306098)
		(end 48.385984 -367.306098)
		(width 0.13462)
		(layer "B.Cu")
		(net "CLK_100M_DB2000QL_GPU_REF1_R_DP")
	)
	(segment
		(start 49.149254 -217.8812)
		(end 63.9572 -217.8812)
		(width 0.13462)
		(layer "B.Cu")
		(net "CLK_100M_DB2000QL_GPU_REF1_R_DP")
	)
	(segment
		(start 42.926 -341.74176)
		(end 41.36263 -340.178644)
		(width 0.13462)
		(layer "B.Cu")
		(net "CLK_100M_DB2000QL_GPU_REF1_R_DP")
	)
	(segment
		(start 17.12468 -261.896352)
		(end 17.12468 -249.905774)
		(width 0.13462)
		(layer "B.Cu")
		(net "CLK_100M_DB2000QL_GPU_REF1_R_DP")
	)
	(segment
		(start 24.537924 -303.393602)
		(end 24.537924 -299.238924)
		(width 0.13462)
		(layer "B.Cu")
		(net "CLK_100M_DB2000QL_GPU_REF1_R_DP")
	)
	(segment
		(start 48.09998 -367.020348)
		(end 48.09998 -366.826292)
		(width 0.13462)
		(layer "B.Cu")
		(net "CLK_100M_DB2000QL_GPU_REF1_R_DP")
	)
	(segment
		(start 22.532848 -278.285448)
		(end 19.94408 -275.69668)
		(width 0.13462)
		(layer "B.Cu")
		(net "CLK_100M_DB2000QL_GPU_REF1_R_DP")
	)
	(segment
		(start 22.532848 -297.233848)
		(end 22.532848 -278.285448)
		(width 0.13462)
		(layer "B.Cu")
		(net "CLK_100M_DB2000QL_GPU_REF1_R_DP")
	)
	(segment
		(start 132.066284 -187.931044)
		(end 132.367274 -188.232034)
		(width 0.13462)
		(layer "B.Cu")
		(net "CLK_100M_DB2000QL_GPU_REF1_R_DP")
	)
	(segment
		(start 148.680678 -379.396498)
		(end 147.777962 -379.396498)
		(width 0.13208)
		(layer "F.Cu")
		(net "GPU_FPGA_EROT_FATALERR_R_N")
	)
	(via
		(at 147.777962 -379.396498)
		(size 0.508)
		(drill 0.254)
		(layers "F.Cu" "B.Cu")
		(net "GPU_FPGA_EROT_FATALERR_R_N")
	)
	(segment
		(start 147.777962 -379.396498)
		(end 147.777962 -378.054108)
		(width 0.15494)
		(layer "In9.Cu")
		(net "GPU_FPGA_EROT_FATALERR_R_N")
	)
	(segment
		(start 136.423654 -366.6998)
		(end 120.400318 -366.6998)
		(width 0.15494)
		(layer "In9.Cu")
		(net "GPU_FPGA_EROT_FATALERR_R_N")
	)
	(segment
		(start 147.777962 -378.054108)
		(end 136.423654 -366.6998)
		(width 0.15494)
		(layer "In9.Cu")
		(net "GPU_FPGA_EROT_FATALERR_R_N")
	)
	(segment
		(start 120.400318 -366.6998)
		(end 118.11 -368.990118)
		(width 0.15494)
		(layer "In9.Cu")
		(net "GPU_FPGA_EROT_FATALERR_R_N")
	)
	(segment
		(start 141.967966 -52.035456)
		(end 141.967966 -53.051456)
		(width 0.13208)
		(layer "F.Cu")
		(net "PWRGD_P12V_SSD4")
	)
	(segment
		(start 140.24737 -53.644038)
		(end 140.616432 -53.644038)
		(width 0.13208)
		(layer "F.Cu")
		(net "PWRGD_P12V_SSD4")
	)
	(segment
		(start 141.237462 -53.023008)
		(end 141.237462 -52.587398)
		(width 0.13208)
		(layer "F.Cu")
		(net "PWRGD_P12V_SSD4")
	)
	(segment
		(start 140.616432 -53.644038)
		(end 141.237462 -53.023008)
		(width 0.13208)
		(layer "F.Cu")
		(net "PWRGD_P12V_SSD4")
	)
	(segment
		(start 141.70152 -53.051456)
		(end 141.967966 -53.051456)
		(width 0.13208)
		(layer "F.Cu")
		(net "PWRGD_P12V_SSD4")
	)
	(segment
		(start 141.237462 -52.587398)
		(end 141.70152 -53.051456)
		(width 0.13208)
		(layer "F.Cu")
		(net "PWRGD_P12V_SSD4")
	)
	(via
		(at 141.237462 -52.587398)
		(size 0.508)
		(drill 0.254)
		(layers "F.Cu" "B.Cu")
		(net "PWRGD_P12V_SSD4")
	)
	(segment
		(start 290.775644 -36.515548)
		(end 291.596064 -36.515548)
		(width 0.13208)
		(layer "F.Cu")
		(net "PRSNT_SSD10_R_N")
	)
	(segment
		(start 291.309044 -27.04973)
		(end 292.303708 -27.04973)
		(width 0.13208)
		(layer "F.Cu")
		(net "PRSNT_SSD10_R_N")
	)
	(segment
		(start 337.293966 -212.786976)
		(end 336.89417 -212.38718)
		(width 0.13208)
		(layer "F.Cu")
		(net "PRSNT_SSD10_R_N")
	)
	(segment
		(start 292.303708 -27.04973)
		(end 292.320472 -27.066494)
		(width 0.13208)
		(layer "F.Cu")
		(net "PRSNT_SSD10_R_N")
	)
	(segment
		(start 292.320472 -27.066494)
		(end 293.142416 -27.066494)
		(width 0.13208)
		(layer "F.Cu")
		(net "PRSNT_SSD10_R_N")
	)
	(segment
		(start 291.309044 -26.03373)
		(end 291.309044 -27.04973)
		(width 0.13208)
		(layer "F.Cu")
		(net "PRSNT_SSD10_R_N")
	)
	(segment
		(start 233.867706 -221.504256)
		(end 234.267502 -221.904052)
		(width 0.13208)
		(layer "F.Cu")
		(net "PRSNT_SSD10_R_N")
	)
	(via
		(at 234.267502 -221.904052)
		(size 0.4572)
		(drill 0.254)
		(layers "F.Cu" "B.Cu")
		(net "PRSNT_SSD10_R_N")
	)
	(via
		(at 336.89417 -212.38718)
		(size 0.4572)
		(drill 0.254)
		(layers "F.Cu" "B.Cu")
		(net "PRSNT_SSD10_R_N")
	)
	(via
		(at 245.120668 -183.447436)
		(size 0.508)
		(drill 0.254)
		(layers "F.Cu" "B.Cu")
		(net "PRSNT_SSD10_R_N")
	)
	(via
		(at 291.596064 -36.515548)
		(size 0.508)
		(drill 0.254)
		(layers "F.Cu" "B.Cu")
		(net "PRSNT_SSD10_R_N")
	)
	(via
		(at 293.142416 -27.066494)
		(size 0.508)
		(drill 0.254)
		(layers "F.Cu" "B.Cu")
		(net "PRSNT_SSD10_R_N")
	)
	(segment
		(start 309.81523 -94.080584)
		(end 309.81523 -93.612716)
		(width 0.15494)
		(layer "In5.Cu")
		(net "PRSNT_SSD10_R_N")
	)
	(segment
		(start 333.67599 -206.55915)
		(end 332.419706 -206.55915)
		(width 0.15494)
		(layer "In5.Cu")
		(net "PRSNT_SSD10_R_N")
	)
	(segment
		(start 304.259234 -80.791558)
		(end 296.60596 -73.138284)
		(width 0.15494)
		(layer "In5.Cu")
		(net "PRSNT_SSD10_R_N")
	)
	(segment
		(start 320.765678 -134.026148)
		(end 320.765678 -131.32308)
		(width 0.15494)
		(layer "In5.Cu")
		(net "PRSNT_SSD10_R_N")
	)
	(segment
		(start 314.94603 -118.345712)
		(end 314.555632 -117.955314)
		(width 0.15494)
		(layer "In5.Cu")
		(net "PRSNT_SSD10_R_N")
	)
	(segment
		(start 310.176418 -104.696514)
		(end 310.176418 -94.441772)
		(width 0.15494)
		(layer "In5.Cu")
		(net "PRSNT_SSD10_R_N")
	)
	(segment
		(start 329.175872 -142.436342)
		(end 320.765678 -134.026148)
		(width 0.15494)
		(layer "In5.Cu")
		(net "PRSNT_SSD10_R_N")
	)
	(segment
		(start 314.555632 -117.955314)
		(end 313.561222 -117.955314)
		(width 0.15494)
		(layer "In5.Cu")
		(net "PRSNT_SSD10_R_N")
	)
	(segment
		(start 289.963352 -29.734764)
		(end 292.631622 -27.066494)
		(width 0.15494)
		(layer "In5.Cu")
		(net "PRSNT_SSD10_R_N")
	)
	(segment
		(start 336.89417 -212.38718)
		(end 336.89417 -209.77733)
		(width 0.15494)
		(layer "In5.Cu")
		(net "PRSNT_SSD10_R_N")
	)
	(segment
		(start 289.963352 -34.882836)
		(end 289.963352 -29.734764)
		(width 0.15494)
		(layer "In5.Cu")
		(net "PRSNT_SSD10_R_N")
	)
	(segment
		(start 320.765678 -131.32308)
		(end 314.94603 -125.503432)
		(width 0.15494)
		(layer "In5.Cu")
		(net "PRSNT_SSD10_R_N")
	)
	(segment
		(start 310.792114 -105.31221)
		(end 310.176418 -104.696514)
		(width 0.15494)
		(layer "In5.Cu")
		(net "PRSNT_SSD10_R_N")
	)
	(segment
		(start 292.631622 -27.066494)
		(end 293.142416 -27.066494)
		(width 0.15494)
		(layer "In5.Cu")
		(net "PRSNT_SSD10_R_N")
	)
	(segment
		(start 313.561222 -117.955314)
		(end 310.792114 -115.186206)
		(width 0.15494)
		(layer "In5.Cu")
		(net "PRSNT_SSD10_R_N")
	)
	(segment
		(start 291.596064 -36.515548)
		(end 289.963352 -34.882836)
		(width 0.15494)
		(layer "In5.Cu")
		(net "PRSNT_SSD10_R_N")
	)
	(segment
		(start 332.419706 -206.55915)
		(end 331.934312 -207.044544)
		(width 0.15494)
		(layer "In5.Cu")
		(net "PRSNT_SSD10_R_N")
	)
	(segment
		(start 291.60597 -36.525454)
		(end 291.596064 -36.515548)
		(width 0.15494)
		(layer "In5.Cu")
		(net "PRSNT_SSD10_R_N")
	)
	(segment
		(start 328.317098 -202.52309)
		(end 332.437994 -198.402194)
		(width 0.15494)
		(layer "In5.Cu")
		(net "PRSNT_SSD10_R_N")
	)
	(segment
		(start 310.176418 -94.441772)
		(end 309.81523 -94.080584)
		(width 0.15494)
		(layer "In5.Cu")
		(net "PRSNT_SSD10_R_N")
	)
	(segment
		(start 310.792114 -115.186206)
		(end 310.792114 -105.31221)
		(width 0.15494)
		(layer "In5.Cu")
		(net "PRSNT_SSD10_R_N")
	)
	(segment
		(start 291.60597 -39.064946)
		(end 291.60597 -36.525454)
		(width 0.15494)
		(layer "In5.Cu")
		(net "PRSNT_SSD10_R_N")
	)
	(segment
		(start 309.81523 -93.612716)
		(end 304.259234 -88.05672)
		(width 0.15494)
		(layer "In5.Cu")
		(net "PRSNT_SSD10_R_N")
	)
	(segment
		(start 329.387708 -207.044544)
		(end 328.317098 -205.973934)
		(width 0.15494)
		(layer "In5.Cu")
		(net "PRSNT_SSD10_R_N")
	)
	(segment
		(start 331.934312 -207.044544)
		(end 329.387708 -207.044544)
		(width 0.15494)
		(layer "In5.Cu")
		(net "PRSNT_SSD10_R_N")
	)
	(segment
		(start 296.60596 -44.064936)
		(end 291.60597 -39.064946)
		(width 0.15494)
		(layer "In5.Cu")
		(net "PRSNT_SSD10_R_N")
	)
	(segment
		(start 332.437994 -143.869918)
		(end 331.004418 -142.436342)
		(width 0.15494)
		(layer "In5.Cu")
		(net "PRSNT_SSD10_R_N")
	)
	(segment
		(start 328.317098 -205.973934)
		(end 328.317098 -202.52309)
		(width 0.15494)
		(layer "In5.Cu")
		(net "PRSNT_SSD10_R_N")
	)
	(segment
		(start 314.94603 -125.503432)
		(end 314.94603 -118.345712)
		(width 0.15494)
		(layer "In5.Cu")
		(net "PRSNT_SSD10_R_N")
	)
	(segment
		(start 304.259234 -88.05672)
		(end 304.259234 -80.791558)
		(width 0.15494)
		(layer "In5.Cu")
		(net "PRSNT_SSD10_R_N")
	)
	(segment
		(start 332.437994 -198.402194)
		(end 332.437994 -143.869918)
		(width 0.15494)
		(layer "In5.Cu")
		(net "PRSNT_SSD10_R_N")
	)
	(segment
		(start 336.89417 -209.77733)
		(end 333.67599 -206.55915)
		(width 0.15494)
		(layer "In5.Cu")
		(net "PRSNT_SSD10_R_N")
	)
	(segment
		(start 296.60596 -73.138284)
		(end 296.60596 -44.064936)
		(width 0.15494)
		(layer "In5.Cu")
		(net "PRSNT_SSD10_R_N")
	)
	(segment
		(start 331.004418 -142.436342)
		(end 329.175872 -142.436342)
		(width 0.15494)
		(layer "In5.Cu")
		(net "PRSNT_SSD10_R_N")
	)
	(segment
		(start 235.269786 -218.5416)
		(end 235.5342 -218.277186)
		(width 0.15494)
		(layer "In7.Cu")
		(net "PRSNT_SSD10_R_N")
	)
	(segment
		(start 243.00688 -206.672434)
		(end 243.00688 -204.416406)
		(width 0.15494)
		(layer "In7.Cu")
		(net "PRSNT_SSD10_R_N")
	)
	(segment
		(start 233.8578 -221.49435)
		(end 233.8578 -219.2274)
		(width 0.0889)
		(layer "In7.Cu")
		(net "PRSNT_SSD10_R_N")
	)
	(segment
		(start 245.65483 -183.981598)
		(end 245.120668 -183.447436)
		(width 0.15494)
		(layer "In7.Cu")
		(net "PRSNT_SSD10_R_N")
	)
	(segment
		(start 244.36324 -203.058522)
		(end 244.42166 -203.000102)
		(width 0.15494)
		(layer "In7.Cu")
		(net "PRSNT_SSD10_R_N")
	)
	(segment
		(start 244.5258 -188.137038)
		(end 245.65483 -187.008008)
		(width 0.15494)
		(layer "In7.Cu")
		(net "PRSNT_SSD10_R_N")
	)
	(segment
		(start 234.569 -218.821)
		(end 234.8484 -218.5416)
		(width 0.15494)
		(layer "In7.Cu")
		(net "PRSNT_SSD10_R_N")
	)
	(segment
		(start 235.6612 -211.6582)
		(end 237.8964 -211.6582)
		(width 0.15494)
		(layer "In7.Cu")
		(net "PRSNT_SSD10_R_N")
	)
	(segment
		(start 234.267502 -221.904052)
		(end 233.8578 -221.49435)
		(width 0.0889)
		(layer "In7.Cu")
		(net "PRSNT_SSD10_R_N")
	)
	(segment
		(start 238.985806 -210.312)
		(end 240.417858 -208.879948)
		(width 0.15494)
		(layer "In7.Cu")
		(net "PRSNT_SSD10_R_N")
	)
	(segment
		(start 243.00688 -204.416406)
		(end 244.36324 -203.060046)
		(width 0.15494)
		(layer "In7.Cu")
		(net "PRSNT_SSD10_R_N")
	)
	(segment
		(start 235.2548 -213.6648)
		(end 235.2548 -212.0646)
		(width 0.15494)
		(layer "In7.Cu")
		(net "PRSNT_SSD10_R_N")
	)
	(segment
		(start 241.718846 -208.572608)
		(end 242.05819 -208.432146)
		(width 0.15494)
		(layer "In7.Cu")
		(net "PRSNT_SSD10_R_N")
	)
	(segment
		(start 244.42166 -188.248798)
		(end 244.5258 -188.144658)
		(width 0.15494)
		(layer "In7.Cu")
		(net "PRSNT_SSD10_R_N")
	)
	(segment
		(start 242.9256 -206.753714)
		(end 243.00688 -206.672434)
		(width 0.15494)
		(layer "In7.Cu")
		(net "PRSNT_SSD10_R_N")
	)
	(segment
		(start 244.42166 -203.000102)
		(end 244.42166 -188.248798)
		(width 0.15494)
		(layer "In7.Cu")
		(net "PRSNT_SSD10_R_N")
	)
	(segment
		(start 240.417858 -208.879948)
		(end 241.411506 -208.879948)
		(width 0.15494)
		(layer "In7.Cu")
		(net "PRSNT_SSD10_R_N")
	)
	(segment
		(start 237.8964 -211.6582)
		(end 238.144304 -211.410296)
		(width 0.15494)
		(layer "In7.Cu")
		(net "PRSNT_SSD10_R_N")
	)
	(segment
		(start 238.144304 -211.410296)
		(end 238.144304 -210.775296)
		(width 0.15494)
		(layer "In7.Cu")
		(net "PRSNT_SSD10_R_N")
	)
	(segment
		(start 234.8484 -218.5416)
		(end 235.269786 -218.5416)
		(width 0.15494)
		(layer "In7.Cu")
		(net "PRSNT_SSD10_R_N")
	)
	(segment
		(start 241.411506 -208.879948)
		(end 241.718846 -208.572608)
		(width 0.15494)
		(layer "In7.Cu")
		(net "PRSNT_SSD10_R_N")
	)
	(segment
		(start 242.472464 -208.432146)
		(end 242.9256 -207.97901)
		(width 0.15494)
		(layer "In7.Cu")
		(net "PRSNT_SSD10_R_N")
	)
	(segment
		(start 245.65483 -187.008008)
		(end 245.65483 -183.981598)
		(width 0.15494)
		(layer "In7.Cu")
		(net "PRSNT_SSD10_R_N")
	)
	(segment
		(start 242.9256 -207.97901)
		(end 242.9256 -206.753714)
		(width 0.15494)
		(layer "In7.Cu")
		(net "PRSNT_SSD10_R_N")
	)
	(segment
		(start 235.5342 -218.277186)
		(end 235.5342 -213.9442)
		(width 0.15494)
		(layer "In7.Cu")
		(net "PRSNT_SSD10_R_N")
	)
	(segment
		(start 234.2642 -218.821)
		(end 234.569 -218.821)
		(width 0.15494)
		(layer "In7.Cu")
		(net "PRSNT_SSD10_R_N")
	)
	(segment
		(start 233.8578 -219.2274)
		(end 234.2642 -218.821)
		(width 0.15494)
		(layer "In7.Cu")
		(net "PRSNT_SSD10_R_N")
	)
	(segment
		(start 235.5342 -213.9442)
		(end 235.2548 -213.6648)
		(width 0.15494)
		(layer "In7.Cu")
		(net "PRSNT_SSD10_R_N")
	)
	(segment
		(start 242.05819 -208.432146)
		(end 242.472464 -208.432146)
		(width 0.15494)
		(layer "In7.Cu")
		(net "PRSNT_SSD10_R_N")
	)
	(segment
		(start 235.2548 -212.0646)
		(end 235.6612 -211.6582)
		(width 0.15494)
		(layer "In7.Cu")
		(net "PRSNT_SSD10_R_N")
	)
	(segment
		(start 238.144304 -210.775296)
		(end 238.6076 -210.312)
		(width 0.15494)
		(layer "In7.Cu")
		(net "PRSNT_SSD10_R_N")
	)
	(segment
		(start 244.36324 -203.060046)
		(end 244.36324 -203.058522)
		(width 0.15494)
		(layer "In7.Cu")
		(net "PRSNT_SSD10_R_N")
	)
	(segment
		(start 238.6076 -210.312)
		(end 238.985806 -210.312)
		(width 0.15494)
		(layer "In7.Cu")
		(net "PRSNT_SSD10_R_N")
	)
	(segment
		(start 244.5258 -188.144658)
		(end 244.5258 -188.137038)
		(width 0.15494)
		(layer "In7.Cu")
		(net "PRSNT_SSD10_R_N")
	)
	(segment
		(start 325.874888 -208.788)
		(end 331.1652 -208.788)
		(width 0.15494)
		(layer "In13.Cu")
		(net "PRSNT_SSD10_R_N")
	)
	(segment
		(start 262.990076 -190.1698)
		(end 281.515566 -208.69529)
		(width 0.15494)
		(layer "In13.Cu")
		(net "PRSNT_SSD10_R_N")
	)
	(segment
		(start 258.2926 -190.1698)
		(end 262.990076 -190.1698)
		(width 0.15494)
		(layer "In13.Cu")
		(net "PRSNT_SSD10_R_N")
	)
	(segment
		(start 245.120668 -183.447436)
		(end 245.961154 -184.287922)
		(width 0.15494)
		(layer "In13.Cu")
		(net "PRSNT_SSD10_R_N")
	)
	(segment
		(start 301.159164 -208.68513)
		(end 325.772018 -208.68513)
		(width 0.15494)
		(layer "In13.Cu")
		(net "PRSNT_SSD10_R_N")
	)
	(segment
		(start 336.493104 -211.986114)
		(end 336.89417 -212.38718)
		(width 0.0889)
		(layer "In13.Cu")
		(net "PRSNT_SSD10_R_N")
	)
	(segment
		(start 332.469998 -211.845398)
		(end 332.80985 -211.986114)
		(width 0.15494)
		(layer "In13.Cu")
		(net "PRSNT_SSD10_R_N")
	)
	(segment
		(start 332.80985 -211.986114)
		(end 336.493104 -211.986114)
		(width 0.0889)
		(layer "In13.Cu")
		(net "PRSNT_SSD10_R_N")
	)
	(segment
		(start 332.0288 -209.6516)
		(end 332.0288 -211.4042)
		(width 0.15494)
		(layer "In13.Cu")
		(net "PRSNT_SSD10_R_N")
	)
	(segment
		(start 332.0288 -211.4042)
		(end 332.469998 -211.845398)
		(width 0.15494)
		(layer "In13.Cu")
		(net "PRSNT_SSD10_R_N")
	)
	(segment
		(start 301.149004 -208.69529)
		(end 301.159164 -208.68513)
		(width 0.15494)
		(layer "In13.Cu")
		(net "PRSNT_SSD10_R_N")
	)
	(segment
		(start 331.1652 -208.788)
		(end 332.0288 -209.6516)
		(width 0.15494)
		(layer "In13.Cu")
		(net "PRSNT_SSD10_R_N")
	)
	(segment
		(start 245.961154 -184.287922)
		(end 252.410722 -184.287922)
		(width 0.15494)
		(layer "In13.Cu")
		(net "PRSNT_SSD10_R_N")
	)
	(segment
		(start 281.515566 -208.69529)
		(end 301.149004 -208.69529)
		(width 0.15494)
		(layer "In13.Cu")
		(net "PRSNT_SSD10_R_N")
	)
	(segment
		(start 325.772018 -208.68513)
		(end 325.874888 -208.788)
		(width 0.15494)
		(layer "In13.Cu")
		(net "PRSNT_SSD10_R_N")
	)
	(segment
		(start 252.410722 -184.287922)
		(end 258.2926 -190.1698)
		(width 0.15494)
		(layer "In13.Cu")
		(net "PRSNT_SSD10_R_N")
	)
	(segment
		(start 189.049914 -290.199826)
		(end 189.524894 -289.724846)
		(width 0.13208)
		(layer "F.Cu")
		(net "UART_PEX1_SDB_TX")
	)
	(via
		(at 189.524894 -289.724846)
		(size 0.4064)
		(drill 0.2032)
		(layers "F.Cu" "B.Cu")
		(net "UART_PEX1_SDB_TX")
	)
	(via
		(at 189.999874 -290.199826)
		(size 0.6604)
		(drill 0.3302)
		(layers "F.Cu" "B.Cu")
		(net "UART_PEX1_SDB_TX")
	)
	(segment
		(start 191.348868 -290.124896)
		(end 191.273938 -290.199826)
		(width 0.13208)
		(layer "B.Cu")
		(net "UART_PEX1_SDB_TX")
	)
	(segment
		(start 191.273938 -290.199826)
		(end 189.999874 -290.199826)
		(width 0.13208)
		(layer "B.Cu")
		(net "UART_PEX1_SDB_TX")
	)
	(segment
		(start 189.999874 -290.199826)
		(end 189.524894 -289.724846)
		(width 0.13208)
		(layer "B.Cu")
		(net "UART_PEX1_SDB_TX")
	)
	(segment
		(start 191.823848 -290.124896)
		(end 191.348868 -290.124896)
		(width 0.13208)
		(layer "B.Cu")
		(net "UART_PEX1_SDB_TX")
	)
	(segment
		(start 114.634518 -86.7918)
		(end 113.467896 -86.7918)
		(width 0.13462)
		(layer "F.Cu")
		(net "CLK_100M_DB800ZL_SSD5_DP")
	)
	(segment
		(start 113.467896 -86.7918)
		(end 113.121186 -86.64829)
		(width 0.13462)
		(layer "F.Cu")
		(net "CLK_100M_DB800ZL_SSD5_DP")
	)
	(segment
		(start 112.284764 -86.64829)
		(end 112.215422 -86.578948)
		(width 0.13462)
		(layer "F.Cu")
		(net "CLK_100M_DB800ZL_SSD5_DP")
	)
	(segment
		(start 112.215422 -86.578948)
		(end 111.788956 -86.578948)
		(width 0.13462)
		(layer "F.Cu")
		(net "CLK_100M_DB800ZL_SSD5_DP")
	)
	(segment
		(start 114.956336 -86.469982)
		(end 114.634518 -86.7918)
		(width 0.13462)
		(layer "F.Cu")
		(net "CLK_100M_DB800ZL_SSD5_DP")
	)
	(segment
		(start 113.121186 -86.64829)
		(end 112.284764 -86.64829)
		(width 0.13462)
		(layer "F.Cu")
		(net "CLK_100M_DB800ZL_SSD5_DP")
	)
	(segment
		(start 231.6353 -157.647132)
		(end 231.878632 -157.890464)
		(width 0.1143)
		(layer "F.Cu")
		(net "CLK_100M_PEX1_REF_R_DN")
	)
	(segment
		(start 152.949656 -299.699934)
		(end 152.474676 -299.224954)
		(width 0.1143)
		(layer "F.Cu")
		(net "CLK_100M_PEX1_REF_R_DN")
	)
	(segment
		(start 231.954832 -156.360876)
		(end 231.6353 -156.680408)
		(width 0.1143)
		(layer "F.Cu")
		(net "CLK_100M_PEX1_REF_R_DN")
	)
	(segment
		(start 231.6353 -156.680408)
		(end 231.6353 -157.647132)
		(width 0.1143)
		(layer "F.Cu")
		(net "CLK_100M_PEX1_REF_R_DN")
	)
	(segment
		(start 152.94991 -299.699934)
		(end 152.949656 -299.699934)
		(width 0.1143)
		(layer "F.Cu")
		(net "CLK_100M_PEX1_REF_R_DN")
	)
	(via
		(at 152.474676 -299.224954)
		(size 0.4064)
		(drill 0.2032)
		(layers "F.Cu" "B.Cu")
		(net "CLK_100M_PEX1_REF_R_DN")
	)
	(via
		(at 231.878632 -157.890464)
		(size 0.508)
		(drill 0.254)
		(layers "F.Cu" "B.Cu")
		(net "CLK_100M_PEX1_REF_R_DN")
	)
	(segment
		(start 145.308066 -279.203912)
		(end 145.308066 -279.01011)
		(width 0.1143)
		(layer "B.Cu")
		(net "CLK_100M_PEX1_REF_R_DN")
	)
	(segment
		(start 145.591784 -295.500552)
		(end 145.728944 -295.363392)
		(width 0.1143)
		(layer "B.Cu")
		(net "CLK_100M_PEX1_REF_R_DN")
	)
	(segment
		(start 148.958554 -297.9547)
		(end 148.821394 -297.81754)
		(width 0.1143)
		(layer "B.Cu")
		(net "CLK_100M_PEX1_REF_R_DN")
	)
	(segment
		(start 144.068292 -277.964138)
		(end 143.605504 -277.50135)
		(width 0.1143)
		(layer "B.Cu")
		(net "CLK_100M_PEX1_REF_R_DN")
	)
	(segment
		(start 184.365392 -207.213962)
		(end 184.365392 -206.908908)
		(width 0.1143)
		(layer "B.Cu")
		(net "CLK_100M_PEX1_REF_R_DN")
	)
	(segment
		(start 150.651972 -299.052996)
		(end 150.368 -298.76877)
		(width 0.1143)
		(layer "B.Cu")
		(net "CLK_100M_PEX1_REF_R_DN")
	)
	(segment
		(start 150.651972 -299.246798)
		(end 150.651972 -299.052996)
		(width 0.1143)
		(layer "B.Cu")
		(net "CLK_100M_PEX1_REF_R_DN")
	)
	(segment
		(start 231.056942 -159.712914)
		(end 231.340914 -159.428688)
		(width 0.1143)
		(layer "B.Cu")
		(net "CLK_100M_PEX1_REF_R_DN")
	)
	(segment
		(start 152.759156 -299.224954)
		(end 152.848056 -299.313854)
		(width 0.0889)
		(layer "B.Cu")
		(net "CLK_100M_PEX1_REF_R_DN")
	)
	(segment
		(start 143.605504 -277.50135)
		(end 143.300704 -277.50135)
		(width 0.1143)
		(layer "B.Cu")
		(net "CLK_100M_PEX1_REF_R_DN")
	)
	(segment
		(start 148.821394 -297.81754)
		(end 148.420074 -297.81754)
		(width 0.1143)
		(layer "B.Cu")
		(net "CLK_100M_PEX1_REF_R_DN")
	)
	(segment
		(start 203.347828 -176.867312)
		(end 218.429586 -161.785554)
		(width 0.1143)
		(layer "B.Cu")
		(net "CLK_100M_PEX1_REF_R_DN")
	)
	(segment
		(start 145.024094 -278.725884)
		(end 144.830038 -278.725884)
		(width 0.1143)
		(layer "B.Cu")
		(net "CLK_100M_PEX1_REF_R_DN")
	)
	(segment
		(start 145.728944 -294.962072)
		(end 145.591784 -294.824912)
		(width 0.1143)
		(layer "B.Cu")
		(net "CLK_100M_PEX1_REF_R_DN")
	)
	(segment
		(start 150.368 -298.76877)
		(end 150.173944 -298.76877)
		(width 0.1143)
		(layer "B.Cu")
		(net "CLK_100M_PEX1_REF_R_DN")
	)
	(segment
		(start 184.365392 -206.908908)
		(end 203.347828 -187.926472)
		(width 0.1143)
		(layer "B.Cu")
		(net "CLK_100M_PEX1_REF_R_DN")
	)
	(segment
		(start 143.204184 -235.388404)
		(end 156.19095 -235.388404)
		(width 0.1143)
		(layer "B.Cu")
		(net "CLK_100M_PEX1_REF_R_DN")
	)
	(segment
		(start 151.23922 -299.530516)
		(end 150.93569 -299.530516)
		(width 0.1143)
		(layer "B.Cu")
		(net "CLK_100M_PEX1_REF_R_DN")
	)
	(segment
		(start 151.343868 -299.613066)
		(end 151.261318 -299.530516)
		(width 0.0889)
		(layer "B.Cu")
		(net "CLK_100M_PEX1_REF_R_DN")
	)
	(segment
		(start 151.261318 -299.530516)
		(end 151.23922 -299.530516)
		(width 0.0889)
		(layer "B.Cu")
		(net "CLK_100M_PEX1_REF_R_DN")
	)
	(segment
		(start 144.54632 -278.442166)
		(end 144.54632 -278.248364)
		(width 0.1143)
		(layer "B.Cu")
		(net "CLK_100M_PEX1_REF_R_DN")
	)
	(segment
		(start 150.93569 -299.530516)
		(end 150.651972 -299.246798)
		(width 0.1143)
		(layer "B.Cu")
		(net "CLK_100M_PEX1_REF_R_DN")
	)
	(segment
		(start 148.282914 -297.9547)
		(end 147.644612 -297.9547)
		(width 0.1143)
		(layer "B.Cu")
		(net "CLK_100M_PEX1_REF_R_DN")
	)
	(segment
		(start 230.862886 -159.712914)
		(end 231.056942 -159.712914)
		(width 0.1143)
		(layer "B.Cu")
		(net "CLK_100M_PEX1_REF_R_DN")
	)
	(segment
		(start 152.848056 -299.439584)
		(end 152.674574 -299.613066)
		(width 0.0889)
		(layer "B.Cu")
		(net "CLK_100M_PEX1_REF_R_DN")
	)
	(segment
		(start 145.728944 -295.363392)
		(end 145.728944 -294.962072)
		(width 0.1143)
		(layer "B.Cu")
		(net "CLK_100M_PEX1_REF_R_DN")
	)
	(segment
		(start 146.12112 -296.431208)
		(end 145.591784 -295.901872)
		(width 0.1143)
		(layer "B.Cu")
		(net "CLK_100M_PEX1_REF_R_DN")
	)
	(segment
		(start 152.474676 -299.224954)
		(end 152.759156 -299.224954)
		(width 0.0889)
		(layer "B.Cu")
		(net "CLK_100M_PEX1_REF_R_DN")
	)
	(segment
		(start 135.733536 -269.934182)
		(end 135.733536 -242.859052)
		(width 0.1143)
		(layer "B.Cu")
		(net "CLK_100M_PEX1_REF_R_DN")
	)
	(segment
		(start 146.599148 -296.715434)
		(end 146.315176 -296.431208)
		(width 0.1143)
		(layer "B.Cu")
		(net "CLK_100M_PEX1_REF_R_DN")
	)
	(segment
		(start 231.340914 -159.234886)
		(end 231.624632 -158.951168)
		(width 0.1143)
		(layer "B.Cu")
		(net "CLK_100M_PEX1_REF_R_DN")
	)
	(segment
		(start 145.308066 -279.01011)
		(end 145.024094 -278.725884)
		(width 0.1143)
		(layer "B.Cu")
		(net "CLK_100M_PEX1_REF_R_DN")
	)
	(segment
		(start 231.624632 -158.951168)
		(end 231.624632 -158.144464)
		(width 0.1143)
		(layer "B.Cu")
		(net "CLK_100M_PEX1_REF_R_DN")
	)
	(segment
		(start 144.54632 -278.248364)
		(end 144.262348 -277.964138)
		(width 0.1143)
		(layer "B.Cu")
		(net "CLK_100M_PEX1_REF_R_DN")
	)
	(segment
		(start 146.599148 -296.909236)
		(end 146.599148 -296.715434)
		(width 0.1143)
		(layer "B.Cu")
		(net "CLK_100M_PEX1_REF_R_DN")
	)
	(segment
		(start 147.360894 -297.670982)
		(end 147.360894 -297.47718)
		(width 0.1143)
		(layer "B.Cu")
		(net "CLK_100M_PEX1_REF_R_DN")
	)
	(segment
		(start 147.644612 -297.9547)
		(end 147.360894 -297.670982)
		(width 0.1143)
		(layer "B.Cu")
		(net "CLK_100M_PEX1_REF_R_DN")
	)
	(segment
		(start 149.359874 -297.9547)
		(end 148.958554 -297.9547)
		(width 0.1143)
		(layer "B.Cu")
		(net "CLK_100M_PEX1_REF_R_DN")
	)
	(segment
		(start 231.624632 -158.144464)
		(end 231.878632 -157.890464)
		(width 0.1143)
		(layer "B.Cu")
		(net "CLK_100M_PEX1_REF_R_DN")
	)
	(segment
		(start 146.315176 -296.431208)
		(end 146.12112 -296.431208)
		(width 0.1143)
		(layer "B.Cu")
		(net "CLK_100M_PEX1_REF_R_DN")
	)
	(segment
		(start 231.340914 -159.428688)
		(end 231.340914 -159.234886)
		(width 0.1143)
		(layer "B.Cu")
		(net "CLK_100M_PEX1_REF_R_DN")
	)
	(segment
		(start 156.19095 -235.388404)
		(end 184.365392 -207.213962)
		(width 0.1143)
		(layer "B.Cu")
		(net "CLK_100M_PEX1_REF_R_DN")
	)
	(segment
		(start 145.591784 -294.824912)
		(end 145.591784 -279.48763)
		(width 0.1143)
		(layer "B.Cu")
		(net "CLK_100M_PEX1_REF_R_DN")
	)
	(segment
		(start 143.300704 -277.50135)
		(end 135.733536 -269.934182)
		(width 0.1143)
		(layer "B.Cu")
		(net "CLK_100M_PEX1_REF_R_DN")
	)
	(segment
		(start 203.347828 -187.926472)
		(end 203.347828 -176.867312)
		(width 0.1143)
		(layer "B.Cu")
		(net "CLK_100M_PEX1_REF_R_DN")
	)
	(segment
		(start 150.173944 -298.76877)
		(end 149.359874 -297.9547)
		(width 0.1143)
		(layer "B.Cu")
		(net "CLK_100M_PEX1_REF_R_DN")
	)
	(segment
		(start 135.733536 -242.859052)
		(end 143.204184 -235.388404)
		(width 0.1143)
		(layer "B.Cu")
		(net "CLK_100M_PEX1_REF_R_DN")
	)
	(segment
		(start 228.790246 -161.785554)
		(end 230.862886 -159.712914)
		(width 0.1143)
		(layer "B.Cu")
		(net "CLK_100M_PEX1_REF_R_DN")
	)
	(segment
		(start 148.420074 -297.81754)
		(end 148.282914 -297.9547)
		(width 0.1143)
		(layer "B.Cu")
		(net "CLK_100M_PEX1_REF_R_DN")
	)
	(segment
		(start 144.830038 -278.725884)
		(end 144.54632 -278.442166)
		(width 0.1143)
		(layer "B.Cu")
		(net "CLK_100M_PEX1_REF_R_DN")
	)
	(segment
		(start 152.674574 -299.613066)
		(end 151.343868 -299.613066)
		(width 0.0889)
		(layer "B.Cu")
		(net "CLK_100M_PEX1_REF_R_DN")
	)
	(segment
		(start 152.848056 -299.313854)
		(end 152.848056 -299.439584)
		(width 0.0889)
		(layer "B.Cu")
		(net "CLK_100M_PEX1_REF_R_DN")
	)
	(segment
		(start 147.076922 -297.192954)
		(end 146.882866 -297.192954)
		(width 0.1143)
		(layer "B.Cu")
		(net "CLK_100M_PEX1_REF_R_DN")
	)
	(segment
		(start 145.591784 -295.901872)
		(end 145.591784 -295.500552)
		(width 0.1143)
		(layer "B.Cu")
		(net "CLK_100M_PEX1_REF_R_DN")
	)
	(segment
		(start 147.360894 -297.47718)
		(end 147.076922 -297.192954)
		(width 0.1143)
		(layer "B.Cu")
		(net "CLK_100M_PEX1_REF_R_DN")
	)
	(segment
		(start 146.882866 -297.192954)
		(end 146.599148 -296.909236)
		(width 0.1143)
		(layer "B.Cu")
		(net "CLK_100M_PEX1_REF_R_DN")
	)
	(segment
		(start 145.591784 -279.48763)
		(end 145.308066 -279.203912)
		(width 0.1143)
		(layer "B.Cu")
		(net "CLK_100M_PEX1_REF_R_DN")
	)
	(segment
		(start 218.429586 -161.785554)
		(end 228.790246 -161.785554)
		(width 0.1143)
		(layer "B.Cu")
		(net "CLK_100M_PEX1_REF_R_DN")
	)
	(segment
		(start 144.262348 -277.964138)
		(end 144.068292 -277.964138)
		(width 0.1143)
		(layer "B.Cu")
		(net "CLK_100M_PEX1_REF_R_DN")
	)
	(segment
		(start 253.385574 -84.276184)
		(end 254.355346 -83.306412)
		(width 0.13208)
		(layer "F.Cu")
		(net "SMB_CK440_CLK_SDA")
	)
	(segment
		(start 252.451616 -84.276184)
		(end 253.385574 -84.276184)
		(width 0.13208)
		(layer "F.Cu")
		(net "SMB_CK440_CLK_SDA")
	)
	(segment
		(start 251.020834 -86.953598)
		(end 251.020834 -85.706966)
		(width 0.13208)
		(layer "F.Cu")
		(net "SMB_CK440_CLK_SDA")
	)
	(segment
		(start 255.2954 -83.306412)
		(end 256.551938 -83.306412)
		(width 0.0889)
		(layer "F.Cu")
		(net "SMB_CK440_CLK_SDA")
	)
	(segment
		(start 249.914664 -88.039448)
		(end 249.924824 -88.049608)
		(width 0.13208)
		(layer "F.Cu")
		(net "SMB_CK440_CLK_SDA")
	)
	(segment
		(start 251.020834 -85.706966)
		(end 252.451616 -84.276184)
		(width 0.13208)
		(layer "F.Cu")
		(net "SMB_CK440_CLK_SDA")
	)
	(segment
		(start 249.219974 -88.039448)
		(end 249.914664 -88.039448)
		(width 0.13208)
		(layer "F.Cu")
		(net "SMB_CK440_CLK_SDA")
	)
	(segment
		(start 254.355346 -83.306412)
		(end 255.2954 -83.306412)
		(width 0.13208)
		(layer "F.Cu")
		(net "SMB_CK440_CLK_SDA")
	)
	(segment
		(start 249.924824 -88.049608)
		(end 251.020834 -86.953598)
		(width 0.13208)
		(layer "F.Cu")
		(net "SMB_CK440_CLK_SDA")
	)
	(via
		(at 249.924824 -88.049608)
		(size 0.508)
		(drill 0.254)
		(layers "F.Cu" "B.Cu")
		(net "SMB_CK440_CLK_SDA")
	)
	(segment
		(start 232.26776 -221.504256)
		(end 232.667556 -221.904052)
		(width 0.13208)
		(layer "F.Cu")
		(net "PRSNT_SSD6_R_N")
	)
	(segment
		(start 175.2092 -27.04973)
		(end 176.203864 -27.04973)
		(width 0.13208)
		(layer "F.Cu")
		(net "PRSNT_SSD6_R_N")
	)
	(segment
		(start 174.6758 -36.515548)
		(end 175.49622 -36.515548)
		(width 0.13208)
		(layer "F.Cu")
		(net "PRSNT_SSD6_R_N")
	)
	(segment
		(start 175.2092 -26.03373)
		(end 175.2092 -27.04973)
		(width 0.13208)
		(layer "F.Cu")
		(net "PRSNT_SSD6_R_N")
	)
	(segment
		(start 346.093796 -224.786952)
		(end 346.493592 -225.186748)
		(width 0.13208)
		(layer "F.Cu")
		(net "PRSNT_SSD6_R_N")
	)
	(segment
		(start 176.203864 -27.04973)
		(end 176.220628 -27.066494)
		(width 0.13208)
		(layer "F.Cu")
		(net "PRSNT_SSD6_R_N")
	)
	(segment
		(start 176.220628 -27.066494)
		(end 177.042572 -27.066494)
		(width 0.13208)
		(layer "F.Cu")
		(net "PRSNT_SSD6_R_N")
	)
	(via
		(at 183.5404 -220.8784)
		(size 0.508)
		(drill 0.254)
		(layers "F.Cu" "B.Cu")
		(net "PRSNT_SSD6_R_N")
	)
	(via
		(at 346.493592 -225.186748)
		(size 0.4572)
		(drill 0.254)
		(layers "F.Cu" "B.Cu")
		(net "PRSNT_SSD6_R_N")
	)
	(via
		(at 232.667556 -221.904052)
		(size 0.4572)
		(drill 0.254)
		(layers "F.Cu" "B.Cu")
		(net "PRSNT_SSD6_R_N")
	)
	(via
		(at 175.49622 -36.515548)
		(size 0.508)
		(drill 0.254)
		(layers "F.Cu" "B.Cu")
		(net "PRSNT_SSD6_R_N")
	)
	(via
		(at 177.042572 -27.066494)
		(size 0.508)
		(drill 0.254)
		(layers "F.Cu" "B.Cu")
		(net "PRSNT_SSD6_R_N")
	)
	(segment
		(start 182.941722 -80.49006)
		(end 175.5648 -87.866982)
		(width 0.15494)
		(layer "In5.Cu")
		(net "PRSNT_SSD6_R_N")
	)
	(segment
		(start 178.999896 -202.316842)
		(end 178.999896 -209.916776)
		(width 0.15494)
		(layer "In5.Cu")
		(net "PRSNT_SSD6_R_N")
	)
	(segment
		(start 176.438306 -27.066494)
		(end 173.863508 -29.641292)
		(width 0.15494)
		(layer "In5.Cu")
		(net "PRSNT_SSD6_R_N")
	)
	(segment
		(start 175.5648 -87.866982)
		(end 175.5648 -181.1782)
		(width 0.15494)
		(layer "In5.Cu")
		(net "PRSNT_SSD6_R_N")
	)
	(segment
		(start 177.14595 -182.75935)
		(end 177.14595 -200.462896)
		(width 0.15494)
		(layer "In5.Cu")
		(net "PRSNT_SSD6_R_N")
	)
	(segment
		(start 175.5648 -181.1782)
		(end 177.14595 -182.75935)
		(width 0.15494)
		(layer "In5.Cu")
		(net "PRSNT_SSD6_R_N")
	)
	(segment
		(start 175.49622 -36.515548)
		(end 175.506126 -36.525454)
		(width 0.15494)
		(layer "In5.Cu")
		(net "PRSNT_SSD6_R_N")
	)
	(segment
		(start 177.042572 -27.066494)
		(end 176.438306 -27.066494)
		(width 0.15494)
		(layer "In5.Cu")
		(net "PRSNT_SSD6_R_N")
	)
	(segment
		(start 180.48224 -44.577508)
		(end 180.48224 -74.511662)
		(width 0.15494)
		(layer "In5.Cu")
		(net "PRSNT_SSD6_R_N")
	)
	(segment
		(start 173.863508 -29.641292)
		(end 173.863508 -34.882836)
		(width 0.15494)
		(layer "In5.Cu")
		(net "PRSNT_SSD6_R_N")
	)
	(segment
		(start 175.506126 -39.601394)
		(end 180.48224 -44.577508)
		(width 0.15494)
		(layer "In5.Cu")
		(net "PRSNT_SSD6_R_N")
	)
	(segment
		(start 175.506126 -36.525454)
		(end 175.506126 -39.601394)
		(width 0.15494)
		(layer "In5.Cu")
		(net "PRSNT_SSD6_R_N")
	)
	(segment
		(start 182.941722 -76.971144)
		(end 182.941722 -80.49006)
		(width 0.15494)
		(layer "In5.Cu")
		(net "PRSNT_SSD6_R_N")
	)
	(segment
		(start 173.863508 -34.882836)
		(end 175.49622 -36.515548)
		(width 0.15494)
		(layer "In5.Cu")
		(net "PRSNT_SSD6_R_N")
	)
	(segment
		(start 178.999896 -209.916776)
		(end 183.5404 -220.8784)
		(width 0.15494)
		(layer "In5.Cu")
		(net "PRSNT_SSD6_R_N")
	)
	(segment
		(start 180.48224 -74.511662)
		(end 182.941722 -76.971144)
		(width 0.15494)
		(layer "In5.Cu")
		(net "PRSNT_SSD6_R_N")
	)
	(segment
		(start 177.14595 -200.462896)
		(end 178.999896 -202.316842)
		(width 0.15494)
		(layer "In5.Cu")
		(net "PRSNT_SSD6_R_N")
	)
	(segment
		(start 211.93252 -223.43745)
		(end 210.367626 -223.43745)
		(width 0.15494)
		(layer "In13.Cu")
		(net "PRSNT_SSD6_R_N")
	)
	(segment
		(start 232.667556 -221.904052)
		(end 232.267506 -221.504002)
		(width 0.0889)
		(layer "In13.Cu")
		(net "PRSNT_SSD6_R_N")
	)
	(segment
		(start 207.971898 -222.195644)
		(end 184.857644 -222.195644)
		(width 0.15494)
		(layer "In13.Cu")
		(net "PRSNT_SSD6_R_N")
	)
	(segment
		(start 184.857644 -222.195644)
		(end 183.5404 -220.8784)
		(width 0.15494)
		(layer "In13.Cu")
		(net "PRSNT_SSD6_R_N")
	)
	(segment
		(start 215.028526 -224.8916)
		(end 214.3506 -224.8916)
		(width 0.15494)
		(layer "In13.Cu")
		(net "PRSNT_SSD6_R_N")
	)
	(segment
		(start 218.895676 -224.96907)
		(end 215.105996 -224.96907)
		(width 0.15494)
		(layer "In13.Cu")
		(net "PRSNT_SSD6_R_N")
	)
	(segment
		(start 306.074572 -236.977174)
		(end 308.639718 -239.54232)
		(width 0.15494)
		(layer "In13.Cu")
		(net "PRSNT_SSD6_R_N")
	)
	(segment
		(start 344.10904 -233.99496)
		(end 346.71 -231.394)
		(width 0.15494)
		(layer "In13.Cu")
		(net "PRSNT_SSD6_R_N")
	)
	(segment
		(start 346.891102 -225.584258)
		(end 346.493592 -225.186748)
		(width 0.0889)
		(layer "In13.Cu")
		(net "PRSNT_SSD6_R_N")
	)
	(segment
		(start 213.36 -223.901)
		(end 212.39607 -223.901)
		(width 0.15494)
		(layer "In13.Cu")
		(net "PRSNT_SSD6_R_N")
	)
	(segment
		(start 346.964 -227.9142)
		(end 346.964 -227.250498)
		(width 0.15494)
		(layer "In13.Cu")
		(net "PRSNT_SSD6_R_N")
	)
	(segment
		(start 231.467406 -222.557594)
		(end 231.467406 -223.8756)
		(width 0.0889)
		(layer "In13.Cu")
		(net "PRSNT_SSD6_R_N")
	)
	(segment
		(start 232.26776 -222.303848)
		(end 231.721152 -222.303848)
		(width 0.0889)
		(layer "In13.Cu")
		(net "PRSNT_SSD6_R_N")
	)
	(segment
		(start 276.682454 -236.977174)
		(end 306.074572 -236.977174)
		(width 0.15494)
		(layer "In13.Cu")
		(net "PRSNT_SSD6_R_N")
	)
	(segment
		(start 346.891102 -227.1776)
		(end 346.891102 -225.584258)
		(width 0.0889)
		(layer "In13.Cu")
		(net "PRSNT_SSD6_R_N")
	)
	(segment
		(start 214.3506 -224.8916)
		(end 213.36 -223.901)
		(width 0.15494)
		(layer "In13.Cu")
		(net "PRSNT_SSD6_R_N")
	)
	(segment
		(start 215.105996 -224.96907)
		(end 215.028526 -224.8916)
		(width 0.15494)
		(layer "In13.Cu")
		(net "PRSNT_SSD6_R_N")
	)
	(segment
		(start 346.71 -228.1682)
		(end 346.964 -227.9142)
		(width 0.15494)
		(layer "In13.Cu")
		(net "PRSNT_SSD6_R_N")
	)
	(segment
		(start 233.70921 -231.568244)
		(end 244.57279 -231.568244)
		(width 0.15494)
		(layer "In13.Cu")
		(net "PRSNT_SSD6_R_N")
	)
	(segment
		(start 231.469946 -229.32898)
		(end 233.70921 -231.568244)
		(width 0.15494)
		(layer "In13.Cu")
		(net "PRSNT_SSD6_R_N")
	)
	(segment
		(start 341.249762 -235.584238)
		(end 341.50681 -235.32719)
		(width 0.15494)
		(layer "In13.Cu")
		(net "PRSNT_SSD6_R_N")
	)
	(segment
		(start 339.852762 -235.584238)
		(end 341.249762 -235.584238)
		(width 0.15494)
		(layer "In13.Cu")
		(net "PRSNT_SSD6_R_N")
	)
	(segment
		(start 346.964 -227.250498)
		(end 346.891102 -227.1776)
		(width 0.15494)
		(layer "In13.Cu")
		(net "PRSNT_SSD6_R_N")
	)
	(segment
		(start 258.294886 -232.20426)
		(end 271.90954 -232.20426)
		(width 0.15494)
		(layer "In13.Cu")
		(net "PRSNT_SSD6_R_N")
	)
	(segment
		(start 346.71 -231.394)
		(end 346.71 -228.1682)
		(width 0.15494)
		(layer "In13.Cu")
		(net "PRSNT_SSD6_R_N")
	)
	(segment
		(start 231.469946 -224.2566)
		(end 231.469946 -229.32898)
		(width 0.15494)
		(layer "In13.Cu")
		(net "PRSNT_SSD6_R_N")
	)
	(segment
		(start 232.667556 -221.904052)
		(end 232.26776 -222.303848)
		(width 0.0889)
		(layer "In13.Cu")
		(net "PRSNT_SSD6_R_N")
	)
	(segment
		(start 339.374988 -237.280958)
		(end 339.374988 -236.062012)
		(width 0.15494)
		(layer "In13.Cu")
		(net "PRSNT_SSD6_R_N")
	)
	(segment
		(start 338.127086 -238.52886)
		(end 339.374988 -237.280958)
		(width 0.15494)
		(layer "In13.Cu")
		(net "PRSNT_SSD6_R_N")
	)
	(segment
		(start 208.760314 -222.98406)
		(end 207.971898 -222.195644)
		(width 0.15494)
		(layer "In13.Cu")
		(net "PRSNT_SSD6_R_N")
	)
	(segment
		(start 257.43916 -233.059986)
		(end 258.294886 -232.20426)
		(width 0.15494)
		(layer "In13.Cu")
		(net "PRSNT_SSD6_R_N")
	)
	(segment
		(start 341.50681 -234.780582)
		(end 342.292432 -233.99496)
		(width 0.15494)
		(layer "In13.Cu")
		(net "PRSNT_SSD6_R_N")
	)
	(segment
		(start 331.943202 -238.52886)
		(end 338.127086 -238.52886)
		(width 0.15494)
		(layer "In13.Cu")
		(net "PRSNT_SSD6_R_N")
	)
	(segment
		(start 244.57279 -231.568244)
		(end 245.390924 -232.386378)
		(width 0.15494)
		(layer "In13.Cu")
		(net "PRSNT_SSD6_R_N")
	)
	(segment
		(start 339.374988 -236.062012)
		(end 339.852762 -235.584238)
		(width 0.15494)
		(layer "In13.Cu")
		(net "PRSNT_SSD6_R_N")
	)
	(segment
		(start 232.267506 -221.504002)
		(end 223.3422 -221.504002)
		(width 0.0889)
		(layer "In13.Cu")
		(net "PRSNT_SSD6_R_N")
	)
	(segment
		(start 223.3422 -221.504002)
		(end 221.295976 -221.504002)
		(width 0.15494)
		(layer "In13.Cu")
		(net "PRSNT_SSD6_R_N")
	)
	(segment
		(start 342.292432 -233.99496)
		(end 344.10904 -233.99496)
		(width 0.15494)
		(layer "In13.Cu")
		(net "PRSNT_SSD6_R_N")
	)
	(segment
		(start 219.267024 -223.532954)
		(end 219.267024 -224.597722)
		(width 0.15494)
		(layer "In13.Cu")
		(net "PRSNT_SSD6_R_N")
	)
	(segment
		(start 210.367626 -223.43745)
		(end 209.914236 -222.98406)
		(width 0.15494)
		(layer "In13.Cu")
		(net "PRSNT_SSD6_R_N")
	)
	(segment
		(start 341.50681 -235.32719)
		(end 341.50681 -234.780582)
		(width 0.15494)
		(layer "In13.Cu")
		(net "PRSNT_SSD6_R_N")
	)
	(segment
		(start 221.295976 -221.504002)
		(end 219.267024 -223.532954)
		(width 0.15494)
		(layer "In13.Cu")
		(net "PRSNT_SSD6_R_N")
	)
	(segment
		(start 308.639718 -239.54232)
		(end 330.929742 -239.54232)
		(width 0.15494)
		(layer "In13.Cu")
		(net "PRSNT_SSD6_R_N")
	)
	(segment
		(start 212.39607 -223.901)
		(end 211.93252 -223.43745)
		(width 0.15494)
		(layer "In13.Cu")
		(net "PRSNT_SSD6_R_N")
	)
	(segment
		(start 209.914236 -222.98406)
		(end 208.760314 -222.98406)
		(width 0.15494)
		(layer "In13.Cu")
		(net "PRSNT_SSD6_R_N")
	)
	(segment
		(start 247.017032 -233.059986)
		(end 257.43916 -233.059986)
		(width 0.15494)
		(layer "In13.Cu")
		(net "PRSNT_SSD6_R_N")
	)
	(segment
		(start 231.467406 -224.25406)
		(end 231.469946 -224.2566)
		(width 0.15494)
		(layer "In13.Cu")
		(net "PRSNT_SSD6_R_N")
	)
	(segment
		(start 231.721152 -222.303848)
		(end 231.467406 -222.557594)
		(width 0.0889)
		(layer "In13.Cu")
		(net "PRSNT_SSD6_R_N")
	)
	(segment
		(start 330.929742 -239.54232)
		(end 331.943202 -238.52886)
		(width 0.15494)
		(layer "In13.Cu")
		(net "PRSNT_SSD6_R_N")
	)
	(segment
		(start 231.467406 -223.8756)
		(end 231.467406 -224.25406)
		(width 0.15494)
		(layer "In13.Cu")
		(net "PRSNT_SSD6_R_N")
	)
	(segment
		(start 271.90954 -232.20426)
		(end 276.682454 -236.977174)
		(width 0.15494)
		(layer "In13.Cu")
		(net "PRSNT_SSD6_R_N")
	)
	(segment
		(start 219.267024 -224.597722)
		(end 218.895676 -224.96907)
		(width 0.15494)
		(layer "In13.Cu")
		(net "PRSNT_SSD6_R_N")
	)
	(segment
		(start 245.390924 -232.386378)
		(end 247.017032 -233.059986)
		(width 0.15494)
		(layer "In13.Cu")
		(net "PRSNT_SSD6_R_N")
	)
	(segment
		(start 338.893912 -215.187022)
		(end 338.494116 -214.787226)
		(width 0.13208)
		(layer "F.Cu")
		(net "SSD9_PWR_EN")
	)
	(segment
		(start 334.518 -201.56805)
		(end 334.518 -202.946)
		(width 0.13208)
		(layer "F.Cu")
		(net "SSD9_PWR_EN")
	)
	(via
		(at 338.494116 -214.787226)
		(size 0.4572)
		(drill 0.254)
		(layers "F.Cu" "B.Cu")
		(net "SSD9_PWR_EN")
	)
	(via
		(at 334.518 -202.946)
		(size 0.508)
		(drill 0.254)
		(layers "F.Cu" "B.Cu")
		(net "SSD9_PWR_EN")
	)
	(segment
		(start 338.494116 -214.787226)
		(end 338.096606 -214.389716)
		(width 0.0889)
		(layer "In5.Cu")
		(net "SSD9_PWR_EN")
	)
	(segment
		(start 338.096606 -214.389716)
		(end 338.096606 -212.217)
		(width 0.0889)
		(layer "In5.Cu")
		(net "SSD9_PWR_EN")
	)
	(segment
		(start 338.096606 -212.217)
		(end 338.096606 -211.940648)
		(width 0.15494)
		(layer "In5.Cu")
		(net "SSD9_PWR_EN")
	)
	(segment
		(start 335.547716 -206.352648)
		(end 335.547716 -205.915768)
		(width 0.15494)
		(layer "In5.Cu")
		(net "SSD9_PWR_EN")
	)
	(segment
		(start 335.008982 -203.436982)
		(end 334.518 -202.946)
		(width 0.15494)
		(layer "In5.Cu")
		(net "SSD9_PWR_EN")
	)
	(segment
		(start 338.2518 -209.056732)
		(end 335.547716 -206.352648)
		(width 0.15494)
		(layer "In5.Cu")
		(net "SSD9_PWR_EN")
	)
	(segment
		(start 335.008982 -205.377034)
		(end 335.008982 -203.436982)
		(width 0.15494)
		(layer "In5.Cu")
		(net "SSD9_PWR_EN")
	)
	(segment
		(start 338.2518 -211.785454)
		(end 338.2518 -209.056732)
		(width 0.15494)
		(layer "In5.Cu")
		(net "SSD9_PWR_EN")
	)
	(segment
		(start 335.547716 -205.915768)
		(end 335.008982 -205.377034)
		(width 0.15494)
		(layer "In5.Cu")
		(net "SSD9_PWR_EN")
	)
	(segment
		(start 338.096606 -211.940648)
		(end 338.2518 -211.785454)
		(width 0.15494)
		(layer "In5.Cu")
		(net "SSD9_PWR_EN")
	)
	(segment
		(start 72.949816 -290.199826)
		(end 73.424796 -289.724846)
		(width 0.13208)
		(layer "F.Cu")
		(net "UART_PEX0_SDB_TX")
	)
	(via
		(at 73.424796 -289.724846)
		(size 0.4064)
		(drill 0.2032)
		(layers "F.Cu" "B.Cu")
		(net "UART_PEX0_SDB_TX")
	)
	(via
		(at 73.899776 -290.199826)
		(size 0.6604)
		(drill 0.3302)
		(layers "F.Cu" "B.Cu")
		(net "UART_PEX0_SDB_TX")
	)
	(segment
		(start 75.72375 -290.124896)
		(end 75.24877 -290.124896)
		(width 0.13208)
		(layer "B.Cu")
		(net "UART_PEX0_SDB_TX")
	)
	(segment
		(start 75.17384 -290.199826)
		(end 73.899776 -290.199826)
		(width 0.13208)
		(layer "B.Cu")
		(net "UART_PEX0_SDB_TX")
	)
	(segment
		(start 73.424796 -289.724846)
		(end 73.899776 -290.199826)
		(width 0.13208)
		(layer "B.Cu")
		(net "UART_PEX0_SDB_TX")
	)
	(segment
		(start 75.24877 -290.124896)
		(end 75.17384 -290.199826)
		(width 0.13208)
		(layer "B.Cu")
		(net "UART_PEX0_SDB_TX")
	)
	(segment
		(start 114.642646 -85.070696)
		(end 113.440972 -85.070696)
		(width 0.13462)
		(layer "F.Cu")
		(net "CLK_100M_DB800ZL_SSD4_DN")
	)
	(segment
		(start 114.956336 -85.384386)
		(end 114.642646 -85.070696)
		(width 0.13462)
		(layer "F.Cu")
		(net "CLK_100M_DB800ZL_SSD4_DN")
	)
	(segment
		(start 112.27308 -85.322664)
		(end 112.216692 -85.379052)
		(width 0.13462)
		(layer "F.Cu")
		(net "CLK_100M_DB800ZL_SSD4_DN")
	)
	(segment
		(start 112.216692 -85.379052)
		(end 111.788956 -85.379052)
		(width 0.13462)
		(layer "F.Cu")
		(net "CLK_100M_DB800ZL_SSD4_DN")
	)
	(segment
		(start 113.440972 -85.070696)
		(end 112.832642 -85.322664)
		(width 0.13462)
		(layer "F.Cu")
		(net "CLK_100M_DB800ZL_SSD4_DN")
	)
	(segment
		(start 112.832642 -85.322664)
		(end 112.27308 -85.322664)
		(width 0.13462)
		(layer "F.Cu")
		(net "CLK_100M_DB800ZL_SSD4_DN")
	)
	(segment
		(start 134.29488 -185.421524)
		(end 134.29488 -188.076332)
		(width 0.13462)
		(layer "F.Cu")
		(net "CLK_100M_DB2000QL_GPU_REF0_R_DN")
	)
	(segment
		(start 134.29488 -188.076332)
		(end 134.00659 -188.364622)
		(width 0.13462)
		(layer "F.Cu")
		(net "CLK_100M_DB2000QL_GPU_REF0_R_DN")
	)
	(segment
		(start 133.93039 -185.057034)
		(end 134.29488 -185.421524)
		(width 0.13462)
		(layer "F.Cu")
		(net "CLK_100M_DB2000QL_GPU_REF0_R_DN")
	)
	(via
		(at 134.00659 -188.364622)
		(size 0.508)
		(drill 0.254)
		(layers "F.Cu" "B.Cu")
		(net "CLK_100M_DB2000QL_GPU_REF0_R_DN")
	)
	(segment
		(start 27.183588 -331.365352)
		(end 26.852372 -331.13345)
		(width 0.13462)
		(layer "B.Cu")
		(net "CLK_100M_DB2000QL_GPU_REF0_R_DN")
	)
	(segment
		(start 25.444196 -330.314808)
		(end 25.410414 -330.1238)
		(width 0.13462)
		(layer "B.Cu")
		(net "CLK_100M_DB2000QL_GPU_REF0_R_DN")
	)
	(segment
		(start 59.55411 -217.06332)
		(end 59.69127 -217.20048)
		(width 0.13462)
		(layer "B.Cu")
		(net "CLK_100M_DB2000QL_GPU_REF0_R_DN")
	)
	(segment
		(start 19.2786 -307.59781)
		(end 23.869904 -303.006506)
		(width 0.13462)
		(layer "B.Cu")
		(net "CLK_100M_DB2000QL_GPU_REF0_R_DN")
	)
	(segment
		(start 40.109648 -341.506048)
		(end 37.030406 -338.426806)
		(width 0.13462)
		(layer "B.Cu")
		(net "CLK_100M_DB2000QL_GPU_REF0_R_DN")
	)
	(segment
		(start 108.064046 -189.50432)
		(end 112.661954 -184.906412)
		(width 0.13462)
		(layer "B.Cu")
		(net "CLK_100M_DB2000QL_GPU_REF0_R_DN")
	)
	(segment
		(start 45.509942 -383.490216)
		(end 45.509942 -383.11201)
		(width 0.13462)
		(layer "B.Cu")
		(net "CLK_100M_DB2000QL_GPU_REF0_R_DN")
	)
	(segment
		(start 49.008538 -217.06332)
		(end 58.47207 -217.06332)
		(width 0.13462)
		(layer "B.Cu")
		(net "CLK_100M_DB2000QL_GPU_REF0_R_DN")
	)
	(segment
		(start 58.60923 -217.20048)
		(end 59.01309 -217.20048)
		(width 0.13462)
		(layer "B.Cu")
		(net "CLK_100M_DB2000QL_GPU_REF0_R_DN")
	)
	(segment
		(start 37.030406 -338.426806)
		(end 27.21737 -331.556106)
		(width 0.13462)
		(layer "B.Cu")
		(net "CLK_100M_DB2000QL_GPU_REF0_R_DN")
	)
	(segment
		(start 27.217116 -331.55636)
		(end 27.183588 -331.365352)
		(width 0.13462)
		(layer "B.Cu")
		(net "CLK_100M_DB2000QL_GPU_REF0_R_DN")
	)
	(segment
		(start 23.869904 -299.581062)
		(end 21.859494 -297.570652)
		(width 0.13462)
		(layer "B.Cu")
		(net "CLK_100M_DB2000QL_GPU_REF0_R_DN")
	)
	(segment
		(start 25.774904 -330.546202)
		(end 25.444196 -330.314808)
		(width 0.13462)
		(layer "B.Cu")
		(net "CLK_100M_DB2000QL_GPU_REF0_R_DN")
	)
	(segment
		(start 60.09513 -217.20048)
		(end 60.23229 -217.06332)
		(width 0.13462)
		(layer "B.Cu")
		(net "CLK_100M_DB2000QL_GPU_REF0_R_DN")
	)
	(segment
		(start 133.585712 -186.182)
		(end 134.30758 -186.903868)
		(width 0.13462)
		(layer "B.Cu")
		(net "CLK_100M_DB2000QL_GPU_REF0_R_DN")
	)
	(segment
		(start 93.664786 -191.89446)
		(end 94.068646 -191.89446)
		(width 0.13462)
		(layer "B.Cu")
		(net "CLK_100M_DB2000QL_GPU_REF0_R_DN")
	)
	(segment
		(start 16.3322 -262.104378)
		(end 16.3322 -249.739658)
		(width 0.13462)
		(layer "B.Cu")
		(net "CLK_100M_DB2000QL_GPU_REF0_R_DN")
	)
	(segment
		(start 24.888444 -329.92568)
		(end 23.266146 -328.789792)
		(width 0.13462)
		(layer "B.Cu")
		(net "CLK_100M_DB2000QL_GPU_REF0_R_DN")
	)
	(segment
		(start 97.142046 -189.50432)
		(end 108.064046 -189.50432)
		(width 0.13462)
		(layer "B.Cu")
		(net "CLK_100M_DB2000QL_GPU_REF0_R_DN")
	)
	(segment
		(start 16.3322 -249.739658)
		(end 49.008538 -217.06332)
		(width 0.13462)
		(layer "B.Cu")
		(net "CLK_100M_DB2000QL_GPU_REF0_R_DN")
	)
	(segment
		(start 124.036074 -184.906412)
		(end 125.311662 -186.182)
		(width 0.13462)
		(layer "B.Cu")
		(net "CLK_100M_DB2000QL_GPU_REF0_R_DN")
	)
	(segment
		(start 46.05401 -382.97739)
		(end 46.618652 -382.412748)
		(width 0.13462)
		(layer "B.Cu")
		(net "CLK_100M_DB2000QL_GPU_REF0_R_DN")
	)
	(segment
		(start 19.1262 -276.039834)
		(end 19.1262 -268.849856)
		(width 0.13462)
		(layer "B.Cu")
		(net "CLK_100M_DB2000QL_GPU_REF0_R_DN")
	)
	(segment
		(start 60.23229 -217.06332)
		(end 62.481968 -217.06332)
		(width 0.13462)
		(layer "B.Cu")
		(net "CLK_100M_DB2000QL_GPU_REF0_R_DN")
	)
	(segment
		(start 26.297128 -330.744576)
		(end 25.965912 -330.512674)
		(width 0.13462)
		(layer "B.Cu")
		(net "CLK_100M_DB2000QL_GPU_REF0_R_DN")
	)
	(segment
		(start 94.205806 -191.7573)
		(end 94.889066 -191.7573)
		(width 0.13462)
		(layer "B.Cu")
		(net "CLK_100M_DB2000QL_GPU_REF0_R_DN")
	)
	(segment
		(start 45.644562 -382.97739)
		(end 46.05401 -382.97739)
		(width 0.13462)
		(layer "B.Cu")
		(net "CLK_100M_DB2000QL_GPU_REF0_R_DN")
	)
	(segment
		(start 45.509942 -383.11201)
		(end 45.644562 -382.97739)
		(width 0.13462)
		(layer "B.Cu")
		(net "CLK_100M_DB2000QL_GPU_REF0_R_DN")
	)
	(segment
		(start 25.965912 -330.512674)
		(end 25.774904 -330.546202)
		(width 0.13462)
		(layer "B.Cu")
		(net "CLK_100M_DB2000QL_GPU_REF0_R_DN")
	)
	(segment
		(start 93.527626 -191.7573)
		(end 93.664786 -191.89446)
		(width 0.13462)
		(layer "B.Cu")
		(net "CLK_100M_DB2000QL_GPU_REF0_R_DN")
	)
	(segment
		(start 25.410414 -330.1238)
		(end 25.079452 -329.891898)
		(width 0.13462)
		(layer "B.Cu")
		(net "CLK_100M_DB2000QL_GPU_REF0_R_DN")
	)
	(segment
		(start 94.889066 -191.7573)
		(end 97.142046 -189.50432)
		(width 0.13462)
		(layer "B.Cu")
		(net "CLK_100M_DB2000QL_GPU_REF0_R_DN")
	)
	(segment
		(start 94.068646 -191.89446)
		(end 94.205806 -191.7573)
		(width 0.13462)
		(layer "B.Cu")
		(net "CLK_100M_DB2000QL_GPU_REF0_R_DN")
	)
	(segment
		(start 40.109648 -360.116374)
		(end 40.109648 -341.506048)
		(width 0.13462)
		(layer "B.Cu")
		(net "CLK_100M_DB2000QL_GPU_REF0_R_DN")
	)
	(segment
		(start 21.859494 -297.570652)
		(end 21.859494 -278.773128)
		(width 0.13462)
		(layer "B.Cu")
		(net "CLK_100M_DB2000QL_GPU_REF0_R_DN")
	)
	(segment
		(start 125.311662 -186.182)
		(end 133.585712 -186.182)
		(width 0.13462)
		(layer "B.Cu")
		(net "CLK_100M_DB2000QL_GPU_REF0_R_DN")
	)
	(segment
		(start 27.21737 -331.556106)
		(end 27.217116 -331.55636)
		(width 0.13462)
		(layer "B.Cu")
		(net "CLK_100M_DB2000QL_GPU_REF0_R_DN")
	)
	(segment
		(start 26.852372 -331.13345)
		(end 26.661364 -331.166978)
		(width 0.13462)
		(layer "B.Cu")
		(net "CLK_100M_DB2000QL_GPU_REF0_R_DN")
	)
	(segment
		(start 134.30758 -188.063632)
		(end 134.00659 -188.364622)
		(width 0.13462)
		(layer "B.Cu")
		(net "CLK_100M_DB2000QL_GPU_REF0_R_DN")
	)
	(segment
		(start 112.661954 -184.906412)
		(end 124.036074 -184.906412)
		(width 0.13462)
		(layer "B.Cu")
		(net "CLK_100M_DB2000QL_GPU_REF0_R_DN")
	)
	(segment
		(start 134.30758 -186.903868)
		(end 134.30758 -188.063632)
		(width 0.13462)
		(layer "B.Cu")
		(net "CLK_100M_DB2000QL_GPU_REF0_R_DN")
	)
	(segment
		(start 26.330656 -330.935584)
		(end 26.297128 -330.744576)
		(width 0.13462)
		(layer "B.Cu")
		(net "CLK_100M_DB2000QL_GPU_REF0_R_DN")
	)
	(segment
		(start 25.079452 -329.891898)
		(end 24.888444 -329.92568)
		(width 0.13462)
		(layer "B.Cu")
		(net "CLK_100M_DB2000QL_GPU_REF0_R_DN")
	)
	(segment
		(start 59.01309 -217.20048)
		(end 59.15025 -217.06332)
		(width 0.13462)
		(layer "B.Cu")
		(net "CLK_100M_DB2000QL_GPU_REF0_R_DN")
	)
	(segment
		(start 59.69127 -217.20048)
		(end 60.09513 -217.20048)
		(width 0.13462)
		(layer "B.Cu")
		(net "CLK_100M_DB2000QL_GPU_REF0_R_DN")
	)
	(segment
		(start 23.266146 -328.789792)
		(end 19.2786 -324.802246)
		(width 0.13462)
		(layer "B.Cu")
		(net "CLK_100M_DB2000QL_GPU_REF0_R_DN")
	)
	(segment
		(start 62.481968 -217.06332)
		(end 87.787988 -191.7573)
		(width 0.13462)
		(layer "B.Cu")
		(net "CLK_100M_DB2000QL_GPU_REF0_R_DN")
	)
	(segment
		(start 19.2786 -324.802246)
		(end 19.2786 -307.59781)
		(width 0.13462)
		(layer "B.Cu")
		(net "CLK_100M_DB2000QL_GPU_REF0_R_DN")
	)
	(segment
		(start 46.618652 -382.412748)
		(end 46.618652 -366.625378)
		(width 0.13462)
		(layer "B.Cu")
		(net "CLK_100M_DB2000QL_GPU_REF0_R_DN")
	)
	(segment
		(start 21.859494 -278.773128)
		(end 19.1262 -276.039834)
		(width 0.13462)
		(layer "B.Cu")
		(net "CLK_100M_DB2000QL_GPU_REF0_R_DN")
	)
	(segment
		(start 58.47207 -217.06332)
		(end 58.60923 -217.20048)
		(width 0.13462)
		(layer "B.Cu")
		(net "CLK_100M_DB2000QL_GPU_REF0_R_DN")
	)
	(segment
		(start 59.15025 -217.06332)
		(end 59.55411 -217.06332)
		(width 0.13462)
		(layer "B.Cu")
		(net "CLK_100M_DB2000QL_GPU_REF0_R_DN")
	)
	(segment
		(start 46.618652 -366.625378)
		(end 40.109648 -360.116374)
		(width 0.13462)
		(layer "B.Cu")
		(net "CLK_100M_DB2000QL_GPU_REF0_R_DN")
	)
	(segment
		(start 23.869904 -303.006506)
		(end 23.869904 -299.581062)
		(width 0.13462)
		(layer "B.Cu")
		(net "CLK_100M_DB2000QL_GPU_REF0_R_DN")
	)
	(segment
		(start 26.661364 -331.166978)
		(end 26.330656 -330.935584)
		(width 0.13462)
		(layer "B.Cu")
		(net "CLK_100M_DB2000QL_GPU_REF0_R_DN")
	)
	(segment
		(start 87.787988 -191.7573)
		(end 93.527626 -191.7573)
		(width 0.13462)
		(layer "B.Cu")
		(net "CLK_100M_DB2000QL_GPU_REF0_R_DN")
	)
	(segment
		(start 19.1262 -268.849856)
		(end 16.3322 -262.104378)
		(width 0.13462)
		(layer "B.Cu")
		(net "CLK_100M_DB2000QL_GPU_REF0_R_DN")
	)
	(segment
		(start 249.864118 -86.78291)
		(end 250.493276 -86.153752)
		(width 0.13208)
		(layer "F.Cu")
		(net "SMB_CK440_CLK_SCL")
	)
	(segment
		(start 249.219974 -87.150448)
		(end 249.49658 -87.150448)
		(width 0.13208)
		(layer "F.Cu")
		(net "SMB_CK440_CLK_SCL")
	)
	(segment
		(start 250.493276 -86.153752)
		(end 250.493276 -85.57387)
		(width 0.13208)
		(layer "F.Cu")
		(net "SMB_CK440_CLK_SCL")
	)
	(segment
		(start 253.406402 -83.7946)
		(end 254.144526 -83.056476)
		(width 0.13208)
		(layer "F.Cu")
		(net "SMB_CK440_CLK_SCL")
	)
	(segment
		(start 250.493276 -85.57387)
		(end 252.272546 -83.7946)
		(width 0.13208)
		(layer "F.Cu")
		(net "SMB_CK440_CLK_SCL")
	)
	(segment
		(start 249.49658 -87.150448)
		(end 249.864118 -86.78291)
		(width 0.13208)
		(layer "F.Cu")
		(net "SMB_CK440_CLK_SCL")
	)
	(segment
		(start 252.272546 -83.7946)
		(end 253.406402 -83.7946)
		(width 0.13208)
		(layer "F.Cu")
		(net "SMB_CK440_CLK_SCL")
	)
	(segment
		(start 254.144526 -83.056476)
		(end 255.801876 -83.056476)
		(width 0.13208)
		(layer "F.Cu")
		(net "SMB_CK440_CLK_SCL")
	)
	(via
		(at 249.864118 -86.78291)
		(size 0.508)
		(drill 0.254)
		(layers "F.Cu" "B.Cu")
		(net "SMB_CK440_CLK_SCL")
	)
	(segment
		(start 151.35225 -390.78154)
		(end 151.335486 -390.798304)
		(width 0.13208)
		(layer "F.Cu")
		(net "GPU_FPGA_EROT_RECOV_N")
	)
	(segment
		(start 152.461468 -390.78154)
		(end 151.35225 -390.78154)
		(width 0.13208)
		(layer "F.Cu")
		(net "GPU_FPGA_EROT_RECOV_N")
	)
	(segment
		(start 151.335486 -392.738356)
		(end 151.335486 -390.798304)
		(width 0.13208)
		(layer "F.Cu")
		(net "GPU_FPGA_EROT_RECOV_N")
	)
	(via
		(at 151.335486 -392.738356)
		(size 0.508)
		(drill 0.254)
		(layers "F.Cu" "B.Cu")
		(net "GPU_FPGA_EROT_RECOV_N")
	)
	(segment
		(start 150.761192 -392.738356)
		(end 151.335486 -392.738356)
		(width 0.15494)
		(layer "In9.Cu")
		(net "GPU_FPGA_EROT_RECOV_N")
	)
	(segment
		(start 141.020546 -394.0302)
		(end 149.469348 -394.0302)
		(width 0.15494)
		(layer "In9.Cu")
		(net "GPU_FPGA_EROT_RECOV_N")
	)
	(segment
		(start 140.8684 -410.2862)
		(end 140.8684 -394.182346)
		(width 0.15494)
		(layer "In9.Cu")
		(net "GPU_FPGA_EROT_RECOV_N")
	)
	(segment
		(start 136.652 -414.5026)
		(end 140.8684 -410.2862)
		(width 0.15494)
		(layer "In9.Cu")
		(net "GPU_FPGA_EROT_RECOV_N")
	)
	(segment
		(start 140.8684 -394.182346)
		(end 141.020546 -394.0302)
		(width 0.15494)
		(layer "In9.Cu")
		(net "GPU_FPGA_EROT_RECOV_N")
	)
	(segment
		(start 118.322598 -414.5026)
		(end 136.652 -414.5026)
		(width 0.15494)
		(layer "In9.Cu")
		(net "GPU_FPGA_EROT_RECOV_N")
	)
	(segment
		(start 115.910106 -412.090108)
		(end 118.322598 -414.5026)
		(width 0.15494)
		(layer "In9.Cu")
		(net "GPU_FPGA_EROT_RECOV_N")
	)
	(segment
		(start 149.469348 -394.0302)
		(end 150.761192 -392.738356)
		(width 0.15494)
		(layer "In9.Cu")
		(net "GPU_FPGA_EROT_RECOV_N")
	)
	(segment
		(start 72.51446 -65.92189)
		(end 72.51446 -65.100962)
		(width 0.13208)
		(layer "F.Cu")
		(net "SSD2_PWR_EN_R")
	)
	(segment
		(start 77.867002 -57.332626)
		(end 77.867002 -57.563766)
		(width 0.13208)
		(layer "F.Cu")
		(net "SSD2_PWR_EN_R")
	)
	(segment
		(start 333.883 -234.46105)
		(end 333.883 -234.942888)
		(width 0.13208)
		(layer "F.Cu")
		(net "SSD2_PWR_EN_R")
	)
	(segment
		(start 76.65847 -55.144162)
		(end 77.867764 -56.353456)
		(width 0.13208)
		(layer "F.Cu")
		(net "SSD2_PWR_EN_R")
	)
	(segment
		(start 77.867764 -56.353456)
		(end 77.867764 -57.331864)
		(width 0.13208)
		(layer "F.Cu")
		(net "SSD2_PWR_EN_R")
	)
	(segment
		(start 77.867002 -57.563766)
		(end 78.37551 -58.072274)
		(width 0.13208)
		(layer "F.Cu")
		(net "SSD2_PWR_EN_R")
	)
	(segment
		(start 77.867764 -57.331864)
		(end 77.867002 -57.332626)
		(width 0.13208)
		(layer "F.Cu")
		(net "SSD2_PWR_EN_R")
	)
	(segment
		(start 333.883 -234.942888)
		(end 333.722218 -235.10367)
		(width 0.13208)
		(layer "F.Cu")
		(net "SSD2_PWR_EN_R")
	)
	(segment
		(start 76.147168 -55.144162)
		(end 76.65847 -55.144162)
		(width 0.13208)
		(layer "F.Cu")
		(net "SSD2_PWR_EN_R")
	)
	(via
		(at 69.773038 -211.061554)
		(size 0.508)
		(drill 0.254)
		(layers "F.Cu" "B.Cu")
		(net "SSD2_PWR_EN_R")
	)
	(via
		(at 78.37551 -58.072274)
		(size 0.508)
		(drill 0.254)
		(layers "F.Cu" "B.Cu")
		(net "SSD2_PWR_EN_R")
	)
	(via
		(at 72.51446 -65.100962)
		(size 0.508)
		(drill 0.254)
		(layers "F.Cu" "B.Cu")
		(net "SSD2_PWR_EN_R")
	)
	(via
		(at 333.722218 -235.10367)
		(size 0.508)
		(drill 0.254)
		(layers "F.Cu" "B.Cu")
		(net "SSD2_PWR_EN_R")
	)
	(segment
		(start 78.542134 -65.628774)
		(end 78.954122 -66.040762)
		(width 0.15494)
		(layer "In5.Cu")
		(net "SSD2_PWR_EN_R")
	)
	(segment
		(start 67.666616 -205.673198)
		(end 67.666616 -208.955132)
		(width 0.15494)
		(layer "In5.Cu")
		(net "SSD2_PWR_EN_R")
	)
	(segment
		(start 78.37551 -58.072274)
		(end 78.183232 -58.264552)
		(width 0.15494)
		(layer "In5.Cu")
		(net "SSD2_PWR_EN_R")
	)
	(segment
		(start 78.542134 -58.238898)
		(end 78.542134 -65.628774)
		(width 0.15494)
		(layer "In5.Cu")
		(net "SSD2_PWR_EN_R")
	)
	(segment
		(start 78.954122 -75.310238)
		(end 60.4774 -93.78696)
		(width 0.15494)
		(layer "In5.Cu")
		(net "SSD2_PWR_EN_R")
	)
	(segment
		(start 78.954122 -66.040762)
		(end 78.954122 -75.310238)
		(width 0.15494)
		(layer "In5.Cu")
		(net "SSD2_PWR_EN_R")
	)
	(segment
		(start 64.8208 -202.827382)
		(end 67.666616 -205.673198)
		(width 0.15494)
		(layer "In5.Cu")
		(net "SSD2_PWR_EN_R")
	)
	(segment
		(start 64.8208 -183.896)
		(end 64.8208 -202.827382)
		(width 0.15494)
		(layer "In5.Cu")
		(net "SSD2_PWR_EN_R")
	)
	(segment
		(start 78.37551 -58.072274)
		(end 78.542134 -58.238898)
		(width 0.15494)
		(layer "In5.Cu")
		(net "SSD2_PWR_EN_R")
	)
	(segment
		(start 78.183232 -64.451484)
		(end 77.659484 -64.975232)
		(width 0.15494)
		(layer "In5.Cu")
		(net "SSD2_PWR_EN_R")
	)
	(segment
		(start 67.666616 -208.955132)
		(end 69.773038 -211.061554)
		(width 0.15494)
		(layer "In5.Cu")
		(net "SSD2_PWR_EN_R")
	)
	(segment
		(start 59.450986 -156.283914)
		(end 59.450986 -178.526186)
		(width 0.15494)
		(layer "In5.Cu")
		(net "SSD2_PWR_EN_R")
	)
	(segment
		(start 59.450986 -178.526186)
		(end 64.8208 -183.896)
		(width 0.15494)
		(layer "In5.Cu")
		(net "SSD2_PWR_EN_R")
	)
	(segment
		(start 73.731374 -65.64376)
		(end 73.057258 -65.64376)
		(width 0.15494)
		(layer "In5.Cu")
		(net "SSD2_PWR_EN_R")
	)
	(segment
		(start 60.4774 -155.2575)
		(end 59.450986 -156.283914)
		(width 0.15494)
		(layer "In5.Cu")
		(net "SSD2_PWR_EN_R")
	)
	(segment
		(start 74.399902 -64.975232)
		(end 73.731374 -65.64376)
		(width 0.15494)
		(layer "In5.Cu")
		(net "SSD2_PWR_EN_R")
	)
	(segment
		(start 60.4774 -93.78696)
		(end 60.4774 -155.2575)
		(width 0.15494)
		(layer "In5.Cu")
		(net "SSD2_PWR_EN_R")
	)
	(segment
		(start 77.659484 -64.975232)
		(end 74.399902 -64.975232)
		(width 0.15494)
		(layer "In5.Cu")
		(net "SSD2_PWR_EN_R")
	)
	(segment
		(start 73.057258 -65.64376)
		(end 72.51446 -65.100962)
		(width 0.15494)
		(layer "In5.Cu")
		(net "SSD2_PWR_EN_R")
	)
	(segment
		(start 78.183232 -58.264552)
		(end 78.183232 -64.451484)
		(width 0.15494)
		(layer "In5.Cu")
		(net "SSD2_PWR_EN_R")
	)
	(segment
		(start 75.098402 -205.73619)
		(end 69.773038 -211.061554)
		(width 0.15494)
		(layer "In15.Cu")
		(net "SSD2_PWR_EN_R")
	)
	(segment
		(start 102.220776 -207.181958)
		(end 98.729292 -205.73619)
		(width 0.15494)
		(layer "In15.Cu")
		(net "SSD2_PWR_EN_R")
	)
	(segment
		(start 147.645374 -230.02748)
		(end 146.873214 -230.79964)
		(width 0.15494)
		(layer "In15.Cu")
		(net "SSD2_PWR_EN_R")
	)
	(segment
		(start 340.83752 -234.23499)
		(end 341.47887 -234.87634)
		(width 0.15494)
		(layer "In15.Cu")
		(net "SSD2_PWR_EN_R")
	)
	(segment
		(start 110.01629 -207.181958)
		(end 102.220776 -207.181958)
		(width 0.15494)
		(layer "In15.Cu")
		(net "SSD2_PWR_EN_R")
	)
	(segment
		(start 161.310574 -234.13212)
		(end 157.205934 -230.02748)
		(width 0.15494)
		(layer "In15.Cu")
		(net "SSD2_PWR_EN_R")
	)
	(segment
		(start 265.731244 -237.948216)
		(end 265.731244 -236.826806)
		(width 0.15494)
		(layer "In15.Cu")
		(net "SSD2_PWR_EN_R")
	)
	(segment
		(start 269.056612 -241.273584)
		(end 265.731244 -237.948216)
		(width 0.15494)
		(layer "In15.Cu")
		(net "SSD2_PWR_EN_R")
	)
	(segment
		(start 157.205934 -230.02748)
		(end 147.645374 -230.02748)
		(width 0.15494)
		(layer "In15.Cu")
		(net "SSD2_PWR_EN_R")
	)
	(segment
		(start 337.2231 -234.23499)
		(end 340.83752 -234.23499)
		(width 0.15494)
		(layer "In15.Cu")
		(net "SSD2_PWR_EN_R")
	)
	(segment
		(start 127.186944 -233.02087)
		(end 115.021868 -220.855794)
		(width 0.15494)
		(layer "In15.Cu")
		(net "SSD2_PWR_EN_R")
	)
	(segment
		(start 215.00719 -240.71326)
		(end 214.52459 -240.23066)
		(width 0.15494)
		(layer "In15.Cu")
		(net "SSD2_PWR_EN_R")
	)
	(segment
		(start 219.504514 -240.71326)
		(end 215.00719 -240.71326)
		(width 0.15494)
		(layer "In15.Cu")
		(net "SSD2_PWR_EN_R")
	)
	(segment
		(start 256.948432 -234.185206)
		(end 256.615946 -233.85272)
		(width 0.15494)
		(layer "In15.Cu")
		(net "SSD2_PWR_EN_R")
	)
	(segment
		(start 233.244898 -240.273332)
		(end 232.80243 -240.7158)
		(width 0.15494)
		(layer "In15.Cu")
		(net "SSD2_PWR_EN_R")
	)
	(segment
		(start 337.406742 -240.690146)
		(end 332.512924 -240.690146)
		(width 0.15494)
		(layer "In15.Cu")
		(net "SSD2_PWR_EN_R")
	)
	(segment
		(start 326.793098 -242.762532)
		(end 303.115218 -242.762532)
		(width 0.15494)
		(layer "In15.Cu")
		(net "SSD2_PWR_EN_R")
	)
	(segment
		(start 146.873214 -230.79964)
		(end 140.968476 -230.79964)
		(width 0.15494)
		(layer "In15.Cu")
		(net "SSD2_PWR_EN_R")
	)
	(segment
		(start 328.108818 -242.424712)
		(end 327.130918 -242.424712)
		(width 0.15494)
		(layer "In15.Cu")
		(net "SSD2_PWR_EN_R")
	)
	(segment
		(start 329.176634 -241.356896)
		(end 328.108818 -242.424712)
		(width 0.15494)
		(layer "In15.Cu")
		(net "SSD2_PWR_EN_R")
	)
	(segment
		(start 263.69899 -234.794552)
		(end 262.227822 -234.185206)
		(width 0.15494)
		(layer "In15.Cu")
		(net "SSD2_PWR_EN_R")
	)
	(segment
		(start 115.021868 -220.855794)
		(end 115.021868 -212.187536)
		(width 0.15494)
		(layer "In15.Cu")
		(net "SSD2_PWR_EN_R")
	)
	(segment
		(start 240.891822 -240.273332)
		(end 233.244898 -240.273332)
		(width 0.15494)
		(layer "In15.Cu")
		(net "SSD2_PWR_EN_R")
	)
	(segment
		(start 334.342232 -234.512104)
		(end 336.945986 -234.512104)
		(width 0.15494)
		(layer "In15.Cu")
		(net "SSD2_PWR_EN_R")
	)
	(segment
		(start 115.021868 -212.187536)
		(end 110.01629 -207.181958)
		(width 0.15494)
		(layer "In15.Cu")
		(net "SSD2_PWR_EN_R")
	)
	(segment
		(start 333.750666 -235.10367)
		(end 334.342232 -234.512104)
		(width 0.15494)
		(layer "In15.Cu")
		(net "SSD2_PWR_EN_R")
	)
	(segment
		(start 333.722218 -235.10367)
		(end 333.750666 -235.10367)
		(width 0.15494)
		(layer "In15.Cu")
		(net "SSD2_PWR_EN_R")
	)
	(segment
		(start 331.846174 -241.356896)
		(end 329.176634 -241.356896)
		(width 0.15494)
		(layer "In15.Cu")
		(net "SSD2_PWR_EN_R")
	)
	(segment
		(start 341.47887 -234.87634)
		(end 341.47887 -236.618018)
		(width 0.15494)
		(layer "In15.Cu")
		(net "SSD2_PWR_EN_R")
	)
	(segment
		(start 336.945986 -234.512104)
		(end 337.2231 -234.23499)
		(width 0.15494)
		(layer "In15.Cu")
		(net "SSD2_PWR_EN_R")
	)
	(segment
		(start 231.317546 -240.7158)
		(end 230.900224 -240.298478)
		(width 0.15494)
		(layer "In15.Cu")
		(net "SSD2_PWR_EN_R")
	)
	(segment
		(start 138.747246 -233.02087)
		(end 127.186944 -233.02087)
		(width 0.15494)
		(layer "In15.Cu")
		(net "SSD2_PWR_EN_R")
	)
	(segment
		(start 185.262774 -234.13212)
		(end 161.310574 -234.13212)
		(width 0.15494)
		(layer "In15.Cu")
		(net "SSD2_PWR_EN_R")
	)
	(segment
		(start 98.729292 -205.73619)
		(end 75.098402 -205.73619)
		(width 0.15494)
		(layer "In15.Cu")
		(net "SSD2_PWR_EN_R")
	)
	(segment
		(start 262.227822 -234.185206)
		(end 256.948432 -234.185206)
		(width 0.15494)
		(layer "In15.Cu")
		(net "SSD2_PWR_EN_R")
	)
	(segment
		(start 232.80243 -240.7158)
		(end 231.317546 -240.7158)
		(width 0.15494)
		(layer "In15.Cu")
		(net "SSD2_PWR_EN_R")
	)
	(segment
		(start 254.716534 -233.85272)
		(end 247.701054 -240.8682)
		(width 0.15494)
		(layer "In15.Cu")
		(net "SSD2_PWR_EN_R")
	)
	(segment
		(start 219.919296 -240.298478)
		(end 219.504514 -240.71326)
		(width 0.15494)
		(layer "In15.Cu")
		(net "SSD2_PWR_EN_R")
	)
	(segment
		(start 302.387254 -242.034568)
		(end 276.223476 -242.034568)
		(width 0.15494)
		(layer "In15.Cu")
		(net "SSD2_PWR_EN_R")
	)
	(segment
		(start 276.223476 -242.034568)
		(end 275.462492 -241.273584)
		(width 0.15494)
		(layer "In15.Cu")
		(net "SSD2_PWR_EN_R")
	)
	(segment
		(start 256.615946 -233.85272)
		(end 254.716534 -233.85272)
		(width 0.15494)
		(layer "In15.Cu")
		(net "SSD2_PWR_EN_R")
	)
	(segment
		(start 230.900224 -240.298478)
		(end 219.919296 -240.298478)
		(width 0.15494)
		(layer "In15.Cu")
		(net "SSD2_PWR_EN_R")
	)
	(segment
		(start 341.47887 -236.618018)
		(end 337.406742 -240.690146)
		(width 0.15494)
		(layer "In15.Cu")
		(net "SSD2_PWR_EN_R")
	)
	(segment
		(start 303.115218 -242.762532)
		(end 302.387254 -242.034568)
		(width 0.15494)
		(layer "In15.Cu")
		(net "SSD2_PWR_EN_R")
	)
	(segment
		(start 140.968476 -230.79964)
		(end 138.747246 -233.02087)
		(width 0.15494)
		(layer "In15.Cu")
		(net "SSD2_PWR_EN_R")
	)
	(segment
		(start 332.512924 -240.690146)
		(end 331.846174 -241.356896)
		(width 0.15494)
		(layer "In15.Cu")
		(net "SSD2_PWR_EN_R")
	)
	(segment
		(start 191.361314 -240.23066)
		(end 185.262774 -234.13212)
		(width 0.15494)
		(layer "In15.Cu")
		(net "SSD2_PWR_EN_R")
	)
	(segment
		(start 327.130918 -242.424712)
		(end 326.793098 -242.762532)
		(width 0.15494)
		(layer "In15.Cu")
		(net "SSD2_PWR_EN_R")
	)
	(segment
		(start 275.462492 -241.273584)
		(end 269.056612 -241.273584)
		(width 0.15494)
		(layer "In15.Cu")
		(net "SSD2_PWR_EN_R")
	)
	(segment
		(start 247.701054 -240.8682)
		(end 241.48669 -240.8682)
		(width 0.15494)
		(layer "In15.Cu")
		(net "SSD2_PWR_EN_R")
	)
	(segment
		(start 214.52459 -240.23066)
		(end 191.361314 -240.23066)
		(width 0.15494)
		(layer "In15.Cu")
		(net "SSD2_PWR_EN_R")
	)
	(segment
		(start 265.731244 -236.826806)
		(end 263.69899 -234.794552)
		(width 0.15494)
		(layer "In15.Cu")
		(net "SSD2_PWR_EN_R")
	)
	(segment
		(start 241.48669 -240.8682)
		(end 240.891822 -240.273332)
		(width 0.15494)
		(layer "In15.Cu")
		(net "SSD2_PWR_EN_R")
	)
	(segment
		(start 338.093812 -215.187022)
		(end 337.694016 -214.787226)
		(width 0.13208)
		(layer "F.Cu")
		(net "SSD8_PWR_EN")
	)
	(segment
		(start 333.502 -201.56805)
		(end 333.502 -202.184)
		(width 0.13208)
		(layer "F.Cu")
		(net "SSD8_PWR_EN")
	)
	(via
		(at 337.694016 -214.787226)
		(size 0.4572)
		(drill 0.254)
		(layers "F.Cu" "B.Cu")
		(net "SSD8_PWR_EN")
	)
	(via
		(at 333.502 -202.184)
		(size 0.508)
		(drill 0.254)
		(layers "F.Cu" "B.Cu")
		(net "SSD8_PWR_EN")
	)
	(segment
		(start 334.021684 -205.291944)
		(end 334.021684 -204.010768)
		(width 0.15494)
		(layer "In5.Cu")
		(net "SSD8_PWR_EN")
	)
	(segment
		(start 334.52816 -205.79842)
		(end 334.021684 -205.291944)
		(width 0.15494)
		(layer "In5.Cu")
		(net "SSD8_PWR_EN")
	)
	(segment
		(start 337.694016 -214.631016)
		(end 337.296506 -214.233506)
		(width 0.0889)
		(layer "In5.Cu")
		(net "SSD8_PWR_EN")
	)
	(segment
		(start 334.52816 -206.445866)
		(end 334.52816 -205.79842)
		(width 0.15494)
		(layer "In5.Cu")
		(net "SSD8_PWR_EN")
	)
	(segment
		(start 337.296506 -212.0138)
		(end 337.25231 -211.969604)
		(width 0.15494)
		(layer "In5.Cu")
		(net "SSD8_PWR_EN")
	)
	(segment
		(start 337.296506 -212.217)
		(end 337.296506 -212.0138)
		(width 0.15494)
		(layer "In5.Cu")
		(net "SSD8_PWR_EN")
	)
	(segment
		(start 337.296506 -214.233506)
		(end 337.296506 -212.217)
		(width 0.0889)
		(layer "In5.Cu")
		(net "SSD8_PWR_EN")
	)
	(segment
		(start 337.25231 -211.969604)
		(end 337.25231 -209.170016)
		(width 0.15494)
		(layer "In5.Cu")
		(net "SSD8_PWR_EN")
	)
	(segment
		(start 337.25231 -209.170016)
		(end 334.52816 -206.445866)
		(width 0.15494)
		(layer "In5.Cu")
		(net "SSD8_PWR_EN")
	)
	(segment
		(start 333.502 -203.491084)
		(end 333.502 -202.184)
		(width 0.15494)
		(layer "In5.Cu")
		(net "SSD8_PWR_EN")
	)
	(segment
		(start 334.021684 -204.010768)
		(end 333.502 -203.491084)
		(width 0.15494)
		(layer "In5.Cu")
		(net "SSD8_PWR_EN")
	)
	(segment
		(start 337.694016 -214.787226)
		(end 337.694016 -214.631016)
		(width 0.0889)
		(layer "In5.Cu")
		(net "SSD8_PWR_EN")
	)
	(segment
		(start 112.284764 -85.048344)
		(end 112.215422 -84.979002)
		(width 0.13462)
		(layer "F.Cu")
		(net "CLK_100M_DB800ZL_SSD4_DP")
	)
	(segment
		(start 114.956336 -84.469986)
		(end 114.629946 -84.796376)
		(width 0.13462)
		(layer "F.Cu")
		(net "CLK_100M_DB800ZL_SSD4_DP")
	)
	(segment
		(start 112.215422 -84.979002)
		(end 111.788956 -84.979002)
		(width 0.13462)
		(layer "F.Cu")
		(net "CLK_100M_DB800ZL_SSD4_DP")
	)
	(segment
		(start 113.386362 -84.796376)
		(end 112.778032 -85.048344)
		(width 0.13462)
		(layer "F.Cu")
		(net "CLK_100M_DB800ZL_SSD4_DP")
	)
	(segment
		(start 112.778032 -85.048344)
		(end 112.284764 -85.048344)
		(width 0.13462)
		(layer "F.Cu")
		(net "CLK_100M_DB800ZL_SSD4_DP")
	)
	(segment
		(start 114.629946 -84.796376)
		(end 113.386362 -84.796376)
		(width 0.13462)
		(layer "F.Cu")
		(net "CLK_100M_DB800ZL_SSD4_DP")
	)
	(segment
		(start 230.938832 -156.360876)
		(end 231.267 -156.689044)
		(width 0.1143)
		(layer "F.Cu")
		(net "CLK_100M_PEX1_REF_R_DP")
	)
	(segment
		(start 231.267 -156.689044)
		(end 231.267 -157.638496)
		(width 0.1143)
		(layer "F.Cu")
		(net "CLK_100M_PEX1_REF_R_DP")
	)
	(segment
		(start 153.89987 -299.699934)
		(end 153.899616 -299.699934)
		(width 0.1143)
		(layer "F.Cu")
		(net "CLK_100M_PEX1_REF_R_DP")
	)
	(segment
		(start 153.899616 -299.699934)
		(end 153.424636 -299.224954)
		(width 0.1143)
		(layer "F.Cu")
		(net "CLK_100M_PEX1_REF_R_DP")
	)
	(segment
		(start 231.267 -157.638496)
		(end 231.015032 -157.890464)
		(width 0.1143)
		(layer "F.Cu")
		(net "CLK_100M_PEX1_REF_R_DP")
	)
	(via
		(at 153.424636 -299.224954)
		(size 0.4064)
		(drill 0.2032)
		(layers "F.Cu" "B.Cu")
		(net "CLK_100M_PEX1_REF_R_DP")
	)
	(via
		(at 231.015032 -157.890464)
		(size 0.508)
		(drill 0.254)
		(layers "F.Cu" "B.Cu")
		(net "CLK_100M_PEX1_REF_R_DP")
	)
	(segment
		(start 228.637592 -161.417254)
		(end 231.256332 -158.798514)
		(width 0.1143)
		(layer "B.Cu")
		(net "CLK_100M_PEX1_REF_R_DP")
	)
	(segment
		(start 183.997092 -207.061308)
		(end 183.997092 -206.756254)
		(width 0.1143)
		(layer "B.Cu")
		(net "CLK_100M_PEX1_REF_R_DP")
	)
	(segment
		(start 135.365236 -242.706398)
		(end 143.05153 -235.020104)
		(width 0.1143)
		(layer "B.Cu")
		(net "CLK_100M_PEX1_REF_R_DP")
	)
	(segment
		(start 150.783036 -299.898816)
		(end 149.20722 -298.323)
		(width 0.1143)
		(layer "B.Cu")
		(net "CLK_100M_PEX1_REF_R_DP")
	)
	(segment
		(start 143.14805 -277.86965)
		(end 135.365236 -270.086836)
		(width 0.1143)
		(layer "B.Cu")
		(net "CLK_100M_PEX1_REF_R_DP")
	)
	(segment
		(start 143.05153 -235.020104)
		(end 156.038296 -235.020104)
		(width 0.1143)
		(layer "B.Cu")
		(net "CLK_100M_PEX1_REF_R_DP")
	)
	(segment
		(start 183.997092 -206.756254)
		(end 202.979528 -187.773818)
		(width 0.1143)
		(layer "B.Cu")
		(net "CLK_100M_PEX1_REF_R_DP")
	)
	(segment
		(start 231.256332 -158.131764)
		(end 231.015032 -157.890464)
		(width 0.1143)
		(layer "B.Cu")
		(net "CLK_100M_PEX1_REF_R_DP")
	)
	(segment
		(start 152.758902 -299.816266)
		(end 151.343868 -299.816266)
		(width 0.0889)
		(layer "B.Cu")
		(net "CLK_100M_PEX1_REF_R_DP")
	)
	(segment
		(start 145.223484 -296.054526)
		(end 145.223484 -279.640284)
		(width 0.1143)
		(layer "B.Cu")
		(net "CLK_100M_PEX1_REF_R_DP")
	)
	(segment
		(start 156.038296 -235.020104)
		(end 183.997092 -207.061308)
		(width 0.1143)
		(layer "B.Cu")
		(net "CLK_100M_PEX1_REF_R_DP")
	)
	(segment
		(start 151.261318 -299.898816)
		(end 151.23922 -299.898816)
		(width 0.0889)
		(layer "B.Cu")
		(net "CLK_100M_PEX1_REF_R_DP")
	)
	(segment
		(start 153.051256 -299.313854)
		(end 153.051256 -299.523912)
		(width 0.0889)
		(layer "B.Cu")
		(net "CLK_100M_PEX1_REF_R_DP")
	)
	(segment
		(start 153.051256 -299.523912)
		(end 152.758902 -299.816266)
		(width 0.0889)
		(layer "B.Cu")
		(net "CLK_100M_PEX1_REF_R_DP")
	)
	(segment
		(start 151.23922 -299.898816)
		(end 150.783036 -299.898816)
		(width 0.1143)
		(layer "B.Cu")
		(net "CLK_100M_PEX1_REF_R_DP")
	)
	(segment
		(start 231.256332 -158.798514)
		(end 231.256332 -158.131764)
		(width 0.1143)
		(layer "B.Cu")
		(net "CLK_100M_PEX1_REF_R_DP")
	)
	(segment
		(start 151.343868 -299.816266)
		(end 151.261318 -299.898816)
		(width 0.0889)
		(layer "B.Cu")
		(net "CLK_100M_PEX1_REF_R_DP")
	)
	(segment
		(start 153.140156 -299.224954)
		(end 153.051256 -299.313854)
		(width 0.0889)
		(layer "B.Cu")
		(net "CLK_100M_PEX1_REF_R_DP")
	)
	(segment
		(start 147.491958 -298.323)
		(end 145.223484 -296.054526)
		(width 0.1143)
		(layer "B.Cu")
		(net "CLK_100M_PEX1_REF_R_DP")
	)
	(segment
		(start 143.45285 -277.86965)
		(end 143.14805 -277.86965)
		(width 0.1143)
		(layer "B.Cu")
		(net "CLK_100M_PEX1_REF_R_DP")
	)
	(segment
		(start 218.276932 -161.417254)
		(end 228.637592 -161.417254)
		(width 0.1143)
		(layer "B.Cu")
		(net "CLK_100M_PEX1_REF_R_DP")
	)
	(segment
		(start 202.979528 -176.714658)
		(end 218.276932 -161.417254)
		(width 0.1143)
		(layer "B.Cu")
		(net "CLK_100M_PEX1_REF_R_DP")
	)
	(segment
		(start 153.424636 -299.224954)
		(end 153.140156 -299.224954)
		(width 0.0889)
		(layer "B.Cu")
		(net "CLK_100M_PEX1_REF_R_DP")
	)
	(segment
		(start 149.20722 -298.323)
		(end 147.491958 -298.323)
		(width 0.1143)
		(layer "B.Cu")
		(net "CLK_100M_PEX1_REF_R_DP")
	)
	(segment
		(start 202.979528 -187.773818)
		(end 202.979528 -176.714658)
		(width 0.1143)
		(layer "B.Cu")
		(net "CLK_100M_PEX1_REF_R_DP")
	)
	(segment
		(start 135.365236 -270.086836)
		(end 135.365236 -242.706398)
		(width 0.1143)
		(layer "B.Cu")
		(net "CLK_100M_PEX1_REF_R_DP")
	)
	(segment
		(start 145.223484 -279.640284)
		(end 143.45285 -277.86965)
		(width 0.1143)
		(layer "B.Cu")
		(net "CLK_100M_PEX1_REF_R_DP")
	)
	(segment
		(start 350.139 -235.077)
		(end 349.615252 -235.600748)
		(width 0.13208)
		(layer "F.Cu")
		(net "SSD6_PWR_EN_R")
	)
	(segment
		(start 349.615252 -235.600748)
		(end 349.615252 -236.787436)
		(width 0.13208)
		(layer "F.Cu")
		(net "SSD6_PWR_EN_R")
	)
	(segment
		(start 188.614558 -65.92189)
		(end 188.614558 -65.100962)
		(width 0.13208)
		(layer "F.Cu")
		(net "SSD6_PWR_EN_R")
	)
	(segment
		(start 192.247266 -55.144162)
		(end 192.758568 -55.144162)
		(width 0.13208)
		(layer "F.Cu")
		(net "SSD6_PWR_EN_R")
	)
	(segment
		(start 350.139 -234.46105)
		(end 350.139 -235.077)
		(width 0.13208)
		(layer "F.Cu")
		(net "SSD6_PWR_EN_R")
	)
	(segment
		(start 350.126046 -237.29823)
		(end 350.139762 -237.29823)
		(width 0.13208)
		(layer "F.Cu")
		(net "SSD6_PWR_EN_R")
	)
	(segment
		(start 349.615252 -236.787436)
		(end 350.126046 -237.29823)
		(width 0.13208)
		(layer "F.Cu")
		(net "SSD6_PWR_EN_R")
	)
	(segment
		(start 193.967862 -57.032144)
		(end 193.967862 -56.353456)
		(width 0.13208)
		(layer "F.Cu")
		(net "SSD6_PWR_EN_R")
	)
	(segment
		(start 192.758568 -55.144162)
		(end 193.967862 -56.353456)
		(width 0.13208)
		(layer "F.Cu")
		(net "SSD6_PWR_EN_R")
	)
	(via
		(at 188.614558 -65.100962)
		(size 0.508)
		(drill 0.254)
		(layers "F.Cu" "B.Cu")
		(net "SSD6_PWR_EN_R")
	)
	(via
		(at 184.687464 -243.668804)
		(size 0.508)
		(drill 0.254)
		(layers "F.Cu" "B.Cu")
		(net "SSD6_PWR_EN_R")
	)
	(via
		(at 350.139 -235.077)
		(size 0.508)
		(drill 0.254)
		(layers "F.Cu" "B.Cu")
		(net "SSD6_PWR_EN_R")
	)
	(via
		(at 193.967862 -57.032144)
		(size 0.508)
		(drill 0.254)
		(layers "F.Cu" "B.Cu")
		(net "SSD6_PWR_EN_R")
	)
	(segment
		(start 188.64834 -81.35366)
		(end 193.94424 -76.05776)
		(width 0.15494)
		(layer "In5.Cu")
		(net "SSD6_PWR_EN_R")
	)
	(segment
		(start 179.626514 -210.02625)
		(end 179.626514 -202.207114)
		(width 0.15494)
		(layer "In5.Cu")
		(net "SSD6_PWR_EN_R")
	)
	(segment
		(start 176.026318 -88.246204)
		(end 182.918862 -81.35366)
		(width 0.15494)
		(layer "In5.Cu")
		(net "SSD6_PWR_EN_R")
	)
	(segment
		(start 184.687464 -243.668804)
		(end 184.630822 -243.612162)
		(width 0.15494)
		(layer "In5.Cu")
		(net "SSD6_PWR_EN_R")
	)
	(segment
		(start 193.967862 -57.032144)
		(end 193.967862 -64.239902)
		(width 0.15494)
		(layer "In5.Cu")
		(net "SSD6_PWR_EN_R")
	)
	(segment
		(start 184.0738 -221.564454)
		(end 184.0738 -220.763338)
		(width 0.15494)
		(layer "In5.Cu")
		(net "SSD6_PWR_EN_R")
	)
	(segment
		(start 182.918862 -81.35366)
		(end 188.64834 -81.35366)
		(width 0.15494)
		(layer "In5.Cu")
		(net "SSD6_PWR_EN_R")
	)
	(segment
		(start 184.0738 -220.763338)
		(end 179.626514 -210.02625)
		(width 0.15494)
		(layer "In5.Cu")
		(net "SSD6_PWR_EN_R")
	)
	(segment
		(start 194.67195 -57.736232)
		(end 193.967862 -57.032144)
		(width 0.15494)
		(layer "In5.Cu")
		(net "SSD6_PWR_EN_R")
	)
	(segment
		(start 194.67195 -67.86245)
		(end 194.67195 -57.736232)
		(width 0.15494)
		(layer "In5.Cu")
		(net "SSD6_PWR_EN_R")
	)
	(segment
		(start 179.626514 -202.207114)
		(end 177.723292 -200.303892)
		(width 0.15494)
		(layer "In5.Cu")
		(net "SSD6_PWR_EN_R")
	)
	(segment
		(start 185.1406 -238.995712)
		(end 185.1406 -229.2096)
		(width 0.15494)
		(layer "In5.Cu")
		(net "SSD6_PWR_EN_R")
	)
	(segment
		(start 183.145176 -227.061522)
		(end 183.084216 -227.000562)
		(width 0.15494)
		(layer "In5.Cu")
		(net "SSD6_PWR_EN_R")
	)
	(segment
		(start 183.145176 -227.214176)
		(end 183.145176 -227.061522)
		(width 0.15494)
		(layer "In5.Cu")
		(net "SSD6_PWR_EN_R")
	)
	(segment
		(start 193.94424 -76.05776)
		(end 193.94424 -68.59016)
		(width 0.15494)
		(layer "In5.Cu")
		(net "SSD6_PWR_EN_R")
	)
	(segment
		(start 176.026318 -180.801518)
		(end 176.026318 -88.246204)
		(width 0.15494)
		(layer "In5.Cu")
		(net "SSD6_PWR_EN_R")
	)
	(segment
		(start 183.084216 -227.000562)
		(end 183.084216 -222.554038)
		(width 0.15494)
		(layer "In5.Cu")
		(net "SSD6_PWR_EN_R")
	)
	(segment
		(start 184.630822 -239.50549)
		(end 185.1406 -238.995712)
		(width 0.15494)
		(layer "In5.Cu")
		(net "SSD6_PWR_EN_R")
	)
	(segment
		(start 193.94424 -68.59016)
		(end 194.67195 -67.86245)
		(width 0.15494)
		(layer "In5.Cu")
		(net "SSD6_PWR_EN_R")
	)
	(segment
		(start 193.229484 -64.97828)
		(end 190.496952 -64.97828)
		(width 0.15494)
		(layer "In5.Cu")
		(net "SSD6_PWR_EN_R")
	)
	(segment
		(start 184.630822 -243.612162)
		(end 184.630822 -239.50549)
		(width 0.15494)
		(layer "In5.Cu")
		(net "SSD6_PWR_EN_R")
	)
	(segment
		(start 185.1406 -229.2096)
		(end 183.145176 -227.214176)
		(width 0.15494)
		(layer "In5.Cu")
		(net "SSD6_PWR_EN_R")
	)
	(segment
		(start 190.496952 -64.97828)
		(end 189.831472 -65.64376)
		(width 0.15494)
		(layer "In5.Cu")
		(net "SSD6_PWR_EN_R")
	)
	(segment
		(start 193.967862 -64.239902)
		(end 193.229484 -64.97828)
		(width 0.15494)
		(layer "In5.Cu")
		(net "SSD6_PWR_EN_R")
	)
	(segment
		(start 183.084216 -222.554038)
		(end 184.0738 -221.564454)
		(width 0.15494)
		(layer "In5.Cu")
		(net "SSD6_PWR_EN_R")
	)
	(segment
		(start 177.723292 -182.498492)
		(end 176.026318 -180.801518)
		(width 0.15494)
		(layer "In5.Cu")
		(net "SSD6_PWR_EN_R")
	)
	(segment
		(start 177.723292 -200.303892)
		(end 177.723292 -182.498492)
		(width 0.15494)
		(layer "In5.Cu")
		(net "SSD6_PWR_EN_R")
	)
	(segment
		(start 189.157356 -65.64376)
		(end 188.614558 -65.100962)
		(width 0.15494)
		(layer "In5.Cu")
		(net "SSD6_PWR_EN_R")
	)
	(segment
		(start 189.831472 -65.64376)
		(end 189.157356 -65.64376)
		(width 0.15494)
		(layer "In5.Cu")
		(net "SSD6_PWR_EN_R")
	)
	(segment
		(start 231.187752 -249.228102)
		(end 229.9462 -247.98655)
		(width 0.15494)
		(layer "In15.Cu")
		(net "SSD6_PWR_EN_R")
	)
	(segment
		(start 304.254662 -250.747276)
		(end 303.735994 -250.228608)
		(width 0.15494)
		(layer "In15.Cu")
		(net "SSD6_PWR_EN_R")
	)
	(segment
		(start 229.9462 -247.98655)
		(end 222.796862 -247.98655)
		(width 0.15494)
		(layer "In15.Cu")
		(net "SSD6_PWR_EN_R")
	)
	(segment
		(start 299.530008 -250.228608)
		(end 298.07154 -248.77014)
		(width 0.15494)
		(layer "In15.Cu")
		(net "SSD6_PWR_EN_R")
	)
	(segment
		(start 334.035146 -249.77852)
		(end 332.997302 -250.816364)
		(width 0.15494)
		(layer "In15.Cu")
		(net "SSD6_PWR_EN_R")
	)
	(segment
		(start 240.272824 -247.191784)
		(end 238.236506 -249.228102)
		(width 0.15494)
		(layer "In15.Cu")
		(net "SSD6_PWR_EN_R")
	)
	(segment
		(start 340.211664 -249.77852)
		(end 334.035146 -249.77852)
		(width 0.15494)
		(layer "In15.Cu")
		(net "SSD6_PWR_EN_R")
	)
	(segment
		(start 221.663514 -247.551702)
		(end 221.365318 -247.849898)
		(width 0.15494)
		(layer "In15.Cu")
		(net "SSD6_PWR_EN_R")
	)
	(segment
		(start 222.362014 -247.551702)
		(end 221.663514 -247.551702)
		(width 0.15494)
		(layer "In15.Cu")
		(net "SSD6_PWR_EN_R")
	)
	(segment
		(start 273.506184 -248.77014)
		(end 273.163792 -248.427748)
		(width 0.15494)
		(layer "In15.Cu")
		(net "SSD6_PWR_EN_R")
	)
	(segment
		(start 188.868558 -247.849898)
		(end 184.687464 -243.668804)
		(width 0.15494)
		(layer "In15.Cu")
		(net "SSD6_PWR_EN_R")
	)
	(segment
		(start 247.698768 -247.191784)
		(end 240.272824 -247.191784)
		(width 0.15494)
		(layer "In15.Cu")
		(net "SSD6_PWR_EN_R")
	)
	(segment
		(start 332.997302 -251.352304)
		(end 332.32598 -252.023626)
		(width 0.15494)
		(layer "In15.Cu")
		(net "SSD6_PWR_EN_R")
	)
	(segment
		(start 349.65513 -235.56087)
		(end 349.65513 -237.371636)
		(width 0.15494)
		(layer "In15.Cu")
		(net "SSD6_PWR_EN_R")
	)
	(segment
		(start 332.997302 -250.816364)
		(end 332.997302 -251.352304)
		(width 0.15494)
		(layer "In15.Cu")
		(net "SSD6_PWR_EN_R")
	)
	(segment
		(start 326.25919 -250.747276)
		(end 304.254662 -250.747276)
		(width 0.15494)
		(layer "In15.Cu")
		(net "SSD6_PWR_EN_R")
	)
	(segment
		(start 350.182942 -237.899448)
		(end 350.182942 -239.807242)
		(width 0.15494)
		(layer "In15.Cu")
		(net "SSD6_PWR_EN_R")
	)
	(segment
		(start 221.365318 -247.849898)
		(end 188.868558 -247.849898)
		(width 0.15494)
		(layer "In15.Cu")
		(net "SSD6_PWR_EN_R")
	)
	(segment
		(start 298.07154 -248.77014)
		(end 273.506184 -248.77014)
		(width 0.15494)
		(layer "In15.Cu")
		(net "SSD6_PWR_EN_R")
	)
	(segment
		(start 248.934732 -248.427748)
		(end 247.698768 -247.191784)
		(width 0.15494)
		(layer "In15.Cu")
		(net "SSD6_PWR_EN_R")
	)
	(segment
		(start 222.796862 -247.98655)
		(end 222.362014 -247.551702)
		(width 0.15494)
		(layer "In15.Cu")
		(net "SSD6_PWR_EN_R")
	)
	(segment
		(start 350.139 -235.077)
		(end 349.65513 -235.56087)
		(width 0.15494)
		(layer "In15.Cu")
		(net "SSD6_PWR_EN_R")
	)
	(segment
		(start 273.163792 -248.427748)
		(end 248.934732 -248.427748)
		(width 0.15494)
		(layer "In15.Cu")
		(net "SSD6_PWR_EN_R")
	)
	(segment
		(start 332.32598 -252.023626)
		(end 327.53554 -252.023626)
		(width 0.15494)
		(layer "In15.Cu")
		(net "SSD6_PWR_EN_R")
	)
	(segment
		(start 327.53554 -252.023626)
		(end 326.25919 -250.747276)
		(width 0.15494)
		(layer "In15.Cu")
		(net "SSD6_PWR_EN_R")
	)
	(segment
		(start 238.236506 -249.228102)
		(end 231.187752 -249.228102)
		(width 0.15494)
		(layer "In15.Cu")
		(net "SSD6_PWR_EN_R")
	)
	(segment
		(start 350.182942 -239.807242)
		(end 340.211664 -249.77852)
		(width 0.15494)
		(layer "In15.Cu")
		(net "SSD6_PWR_EN_R")
	)
	(segment
		(start 303.735994 -250.228608)
		(end 299.530008 -250.228608)
		(width 0.15494)
		(layer "In15.Cu")
		(net "SSD6_PWR_EN_R")
	)
	(segment
		(start 349.65513 -237.371636)
		(end 350.182942 -237.899448)
		(width 0.15494)
		(layer "In15.Cu")
		(net "SSD6_PWR_EN_R")
	)
	(segment
		(start 336.897726 -211.59089)
		(end 336.897726 -210.55965)
		(width 0.13208)
		(layer "F.Cu")
		(net "RST_SSD9_PERST_N")
	)
	(segment
		(start 335.534 -209.195924)
		(end 335.534 -206.8068)
		(width 0.13208)
		(layer "F.Cu")
		(net "RST_SSD9_PERST_N")
	)
	(segment
		(start 336.897726 -210.55965)
		(end 335.534 -209.195924)
		(width 0.13208)
		(layer "F.Cu")
		(net "RST_SSD9_PERST_N")
	)
	(segment
		(start 337.293966 -211.98713)
		(end 336.897726 -211.59089)
		(width 0.13208)
		(layer "F.Cu")
		(net "RST_SSD9_PERST_N")
	)
	(segment
		(start 335.534 -206.8068)
		(end 335.534 -205.63205)
		(width 0.13208)
		(layer "F.Cu")
		(net "RST_SSD9_PERST_N")
	)
	(via
		(at 335.534 -206.8068)
		(size 0.762)
		(drill 0.381)
		(layers "F.Cu" "B.Cu")
		(net "RST_SSD9_PERST_N")
	)
	(segment
		(start 113.8174 -83.058)
		(end 112.765586 -84.109814)
		(width 0.13462)
		(layer "F.Cu")
		(net "CLK_100M_DB800ZL_SSD3_DN")
	)
	(segment
		(start 112.216692 -84.178902)
		(end 111.788956 -84.178902)
		(width 0.13462)
		(layer "F.Cu")
		(net "CLK_100M_DB800ZL_SSD3_DN")
	)
	(segment
		(start 114.956336 -83.38439)
		(end 114.629946 -83.058)
		(width 0.13462)
		(layer "F.Cu")
		(net "CLK_100M_DB800ZL_SSD3_DN")
	)
	(segment
		(start 112.765586 -84.109814)
		(end 112.28578 -84.109814)
		(width 0.13462)
		(layer "F.Cu")
		(net "CLK_100M_DB800ZL_SSD3_DN")
	)
	(segment
		(start 114.629946 -83.058)
		(end 113.8174 -83.058)
		(width 0.13462)
		(layer "F.Cu")
		(net "CLK_100M_DB800ZL_SSD3_DN")
	)
	(segment
		(start 112.28578 -84.109814)
		(end 112.216692 -84.178902)
		(width 0.13462)
		(layer "F.Cu")
		(net "CLK_100M_DB800ZL_SSD3_DN")
	)
	(segment
		(start 134.94639 -185.057034)
		(end 134.5692 -185.434224)
		(width 0.13462)
		(layer "F.Cu")
		(net "CLK_100M_DB2000QL_GPU_REF0_R_DP")
	)
	(segment
		(start 134.5692 -185.434224)
		(end 134.5692 -188.063632)
		(width 0.13462)
		(layer "F.Cu")
		(net "CLK_100M_DB2000QL_GPU_REF0_R_DP")
	)
	(segment
		(start 134.5692 -188.063632)
		(end 134.87019 -188.364622)
		(width 0.13462)
		(layer "F.Cu")
		(net "CLK_100M_DB2000QL_GPU_REF0_R_DP")
	)
	(via
		(at 134.87019 -188.364622)
		(size 0.508)
		(drill 0.254)
		(layers "F.Cu" "B.Cu")
		(net "CLK_100M_DB2000QL_GPU_REF0_R_DP")
	)
	(segment
		(start 62.368176 -216.789)
		(end 87.674196 -191.48298)
		(width 0.13462)
		(layer "B.Cu")
		(net "CLK_100M_DB2000QL_GPU_REF0_R_DP")
	)
	(segment
		(start 134.5819 -188.050932)
		(end 134.5692 -188.063632)
		(width 0.13462)
		(layer "B.Cu")
		(net "CLK_100M_DB2000QL_GPU_REF0_R_DP")
	)
	(segment
		(start 48.894746 -216.789)
		(end 62.368176 -216.789)
		(width 0.13462)
		(layer "B.Cu")
		(net "CLK_100M_DB2000QL_GPU_REF0_R_DP")
	)
	(segment
		(start 46.344332 -366.73917)
		(end 45.744384 -366.139222)
		(width 0.13462)
		(layer "B.Cu")
		(net "CLK_100M_DB2000QL_GPU_REF0_R_DP")
	)
	(segment
		(start 21.585174 -297.684444)
		(end 21.585174 -278.88692)
		(width 0.13462)
		(layer "B.Cu")
		(net "CLK_100M_DB2000QL_GPU_REF0_R_DP")
	)
	(segment
		(start 19.00428 -324.916038)
		(end 19.00428 -307.484018)
		(width 0.13462)
		(layer "B.Cu")
		(net "CLK_100M_DB2000QL_GPU_REF0_R_DP")
	)
	(segment
		(start 112.548162 -184.632092)
		(end 124.149866 -184.632092)
		(width 0.13462)
		(layer "B.Cu")
		(net "CLK_100M_DB2000QL_GPU_REF0_R_DP")
	)
	(segment
		(start 23.089108 -329.000866)
		(end 19.00428 -324.916038)
		(width 0.13462)
		(layer "B.Cu")
		(net "CLK_100M_DB2000QL_GPU_REF0_R_DP")
	)
	(segment
		(start 45.744384 -366.139222)
		(end 45.550328 -366.139222)
		(width 0.13462)
		(layer "B.Cu")
		(net "CLK_100M_DB2000QL_GPU_REF0_R_DP")
	)
	(segment
		(start 18.85188 -268.904466)
		(end 16.05788 -262.158988)
		(width 0.13462)
		(layer "B.Cu")
		(net "CLK_100M_DB2000QL_GPU_REF0_R_DP")
	)
	(segment
		(start 16.05788 -249.625866)
		(end 48.894746 -216.789)
		(width 0.13462)
		(layer "B.Cu")
		(net "CLK_100M_DB2000QL_GPU_REF0_R_DP")
	)
	(segment
		(start 45.940218 -382.70307)
		(end 46.344332 -382.298956)
		(width 0.13462)
		(layer "B.Cu")
		(net "CLK_100M_DB2000QL_GPU_REF0_R_DP")
	)
	(segment
		(start 21.585174 -278.88692)
		(end 18.85188 -276.153626)
		(width 0.13462)
		(layer "B.Cu")
		(net "CLK_100M_DB2000QL_GPU_REF0_R_DP")
	)
	(segment
		(start 39.835328 -341.61984)
		(end 36.853368 -338.63788)
		(width 0.13462)
		(layer "B.Cu")
		(net "CLK_100M_DB2000QL_GPU_REF0_R_DP")
	)
	(segment
		(start 23.595584 -299.694854)
		(end 21.585174 -297.684444)
		(width 0.13462)
		(layer "B.Cu")
		(net "CLK_100M_DB2000QL_GPU_REF0_R_DP")
	)
	(segment
		(start 87.674196 -191.48298)
		(end 94.775274 -191.48298)
		(width 0.13462)
		(layer "B.Cu")
		(net "CLK_100M_DB2000QL_GPU_REF0_R_DP")
	)
	(segment
		(start 134.5692 -188.063632)
		(end 134.87019 -188.364622)
		(width 0.13462)
		(layer "B.Cu")
		(net "CLK_100M_DB2000QL_GPU_REF0_R_DP")
	)
	(segment
		(start 45.509942 -382.56845)
		(end 45.644562 -382.70307)
		(width 0.13462)
		(layer "B.Cu")
		(net "CLK_100M_DB2000QL_GPU_REF0_R_DP")
	)
	(segment
		(start 46.344332 -382.298956)
		(end 46.344332 -366.73917)
		(width 0.13462)
		(layer "B.Cu")
		(net "CLK_100M_DB2000QL_GPU_REF0_R_DP")
	)
	(segment
		(start 45.264578 -365.853472)
		(end 45.264578 -365.659416)
		(width 0.13462)
		(layer "B.Cu")
		(net "CLK_100M_DB2000QL_GPU_REF0_R_DP")
	)
	(segment
		(start 39.835328 -360.230166)
		(end 39.835328 -341.61984)
		(width 0.13462)
		(layer "B.Cu")
		(net "CLK_100M_DB2000QL_GPU_REF0_R_DP")
	)
	(segment
		(start 23.595584 -302.892714)
		(end 23.595584 -299.694854)
		(width 0.13462)
		(layer "B.Cu")
		(net "CLK_100M_DB2000QL_GPU_REF0_R_DP")
	)
	(segment
		(start 45.550328 -366.139222)
		(end 45.264578 -365.853472)
		(width 0.13462)
		(layer "B.Cu")
		(net "CLK_100M_DB2000QL_GPU_REF0_R_DP")
	)
	(segment
		(start 44.979082 -365.37392)
		(end 44.78528 -365.37392)
		(width 0.13462)
		(layer "B.Cu")
		(net "CLK_100M_DB2000QL_GPU_REF0_R_DP")
	)
	(segment
		(start 133.699504 -185.90768)
		(end 134.5819 -186.790076)
		(width 0.13462)
		(layer "B.Cu")
		(net "CLK_100M_DB2000QL_GPU_REF0_R_DP")
	)
	(segment
		(start 44.78528 -365.37392)
		(end 44.499276 -365.08817)
		(width 0.13462)
		(layer "B.Cu")
		(net "CLK_100M_DB2000QL_GPU_REF0_R_DP")
	)
	(segment
		(start 124.149866 -184.632092)
		(end 125.425454 -185.90768)
		(width 0.13462)
		(layer "B.Cu")
		(net "CLK_100M_DB2000QL_GPU_REF0_R_DP")
	)
	(segment
		(start 94.775274 -191.48298)
		(end 97.028254 -189.23)
		(width 0.13462)
		(layer "B.Cu")
		(net "CLK_100M_DB2000QL_GPU_REF0_R_DP")
	)
	(segment
		(start 125.425454 -185.90768)
		(end 133.699504 -185.90768)
		(width 0.13462)
		(layer "B.Cu")
		(net "CLK_100M_DB2000QL_GPU_REF0_R_DP")
	)
	(segment
		(start 45.509942 -382.18999)
		(end 45.509942 -382.56845)
		(width 0.13462)
		(layer "B.Cu")
		(net "CLK_100M_DB2000QL_GPU_REF0_R_DP")
	)
	(segment
		(start 107.950254 -189.23)
		(end 112.548162 -184.632092)
		(width 0.13462)
		(layer "B.Cu")
		(net "CLK_100M_DB2000QL_GPU_REF0_R_DP")
	)
	(segment
		(start 19.00428 -307.484018)
		(end 23.595584 -302.892714)
		(width 0.13462)
		(layer "B.Cu")
		(net "CLK_100M_DB2000QL_GPU_REF0_R_DP")
	)
	(segment
		(start 36.853368 -338.63788)
		(end 23.089108 -329.000866)
		(width 0.13462)
		(layer "B.Cu")
		(net "CLK_100M_DB2000QL_GPU_REF0_R_DP")
	)
	(segment
		(start 45.264578 -365.659416)
		(end 44.979082 -365.37392)
		(width 0.13462)
		(layer "B.Cu")
		(net "CLK_100M_DB2000QL_GPU_REF0_R_DP")
	)
	(segment
		(start 44.499276 -365.08817)
		(end 44.499276 -364.894114)
		(width 0.13462)
		(layer "B.Cu")
		(net "CLK_100M_DB2000QL_GPU_REF0_R_DP")
	)
	(segment
		(start 44.499276 -364.894114)
		(end 39.835328 -360.230166)
		(width 0.13462)
		(layer "B.Cu")
		(net "CLK_100M_DB2000QL_GPU_REF0_R_DP")
	)
	(segment
		(start 134.5819 -186.790076)
		(end 134.5819 -188.050932)
		(width 0.13462)
		(layer "B.Cu")
		(net "CLK_100M_DB2000QL_GPU_REF0_R_DP")
	)
	(segment
		(start 18.85188 -276.153626)
		(end 18.85188 -268.904466)
		(width 0.13462)
		(layer "B.Cu")
		(net "CLK_100M_DB2000QL_GPU_REF0_R_DP")
	)
	(segment
		(start 16.05788 -262.158988)
		(end 16.05788 -249.625866)
		(width 0.13462)
		(layer "B.Cu")
		(net "CLK_100M_DB2000QL_GPU_REF0_R_DP")
	)
	(segment
		(start 97.028254 -189.23)
		(end 107.950254 -189.23)
		(width 0.13462)
		(layer "B.Cu")
		(net "CLK_100M_DB2000QL_GPU_REF0_R_DP")
	)
	(segment
		(start 45.644562 -382.70307)
		(end 45.940218 -382.70307)
		(width 0.13462)
		(layer "B.Cu")
		(net "CLK_100M_DB2000QL_GPU_REF0_R_DP")
	)
	(segment
		(start 150.125176 -57.867296)
		(end 150.125176 -57.841896)
		(width 0.13208)
		(layer "F.Cu")
		(net "PWRGD_P3V3_SSD5")
	)
	(segment
		(start 150.2791 -58.71972)
		(end 150.125176 -58.565796)
		(width 0.13208)
		(layer "F.Cu")
		(net "PWRGD_P3V3_SSD5")
	)
	(segment
		(start 150.125176 -57.841896)
		(end 149.741128 -57.457848)
		(width 0.13208)
		(layer "F.Cu")
		(net "PWRGD_P3V3_SSD5")
	)
	(segment
		(start 150.125176 -58.565796)
		(end 150.125176 -57.867296)
		(width 0.13208)
		(layer "F.Cu")
		(net "PWRGD_P3V3_SSD5")
	)
	(segment
		(start 149.74824 -59.343544)
		(end 149.913848 -59.177936)
		(width 0.13208)
		(layer "F.Cu")
		(net "PWRGD_P3V3_SSD5")
	)
	(segment
		(start 149.741128 -57.457848)
		(end 149.741128 -57.16397)
		(width 0.13208)
		(layer "F.Cu")
		(net "PWRGD_P3V3_SSD5")
	)
	(segment
		(start 149.74824 -61.22416)
		(end 149.74824 -59.343544)
		(width 0.13208)
		(layer "F.Cu")
		(net "PWRGD_P3V3_SSD5")
	)
	(segment
		(start 150.2791 -59.177936)
		(end 150.2791 -58.71972)
		(width 0.13208)
		(layer "F.Cu")
		(net "PWRGD_P3V3_SSD5")
	)
	(segment
		(start 149.911054 -61.386974)
		(end 149.74824 -61.22416)
		(width 0.13208)
		(layer "F.Cu")
		(net "PWRGD_P3V3_SSD5")
	)
	(segment
		(start 149.913848 -59.177936)
		(end 150.2791 -59.177936)
		(width 0.13208)
		(layer "F.Cu")
		(net "PWRGD_P3V3_SSD5")
	)
	(via
		(at 150.125176 -57.867296)
		(size 0.508)
		(drill 0.254)
		(layers "F.Cu" "B.Cu")
		(net "PWRGD_P3V3_SSD5")
	)
	(segment
		(start 342.893904 -212.786976)
		(end 343.2937 -212.38718)
		(width 0.13208)
		(layer "F.Cu")
		(net "SSD14_CLK_EN_N")
	)
	(via
		(at 343.2937 -212.38718)
		(size 0.4572)
		(drill 0.254)
		(layers "F.Cu" "B.Cu")
		(net "SSD14_CLK_EN_N")
	)
	(via
		(at 343.662 -209.296)
		(size 0.6604)
		(drill 0.3302)
		(layers "F.Cu" "B.Cu")
		(net "SSD14_CLK_EN_N")
	)
	(segment
		(start 343.408 -211.604098)
		(end 343.2937 -211.718398)
		(width 0.13208)
		(layer "B.Cu")
		(net "SSD14_CLK_EN_N")
	)
	(segment
		(start 343.154 -208.17205)
		(end 343.662 -208.68005)
		(width 0.13208)
		(layer "B.Cu")
		(net "SSD14_CLK_EN_N")
	)
	(segment
		(start 343.2937 -211.718398)
		(end 343.2937 -212.38718)
		(width 0.13208)
		(layer "B.Cu")
		(net "SSD14_CLK_EN_N")
	)
	(segment
		(start 343.662 -209.931)
		(end 343.408 -210.185)
		(width 0.13208)
		(layer "B.Cu")
		(net "SSD14_CLK_EN_N")
	)
	(segment
		(start 343.662 -208.68005)
		(end 343.662 -209.296)
		(width 0.13208)
		(layer "B.Cu")
		(net "SSD14_CLK_EN_N")
	)
	(segment
		(start 343.408 -210.185)
		(end 343.408 -211.604098)
		(width 0.13208)
		(layer "B.Cu")
		(net "SSD14_CLK_EN_N")
	)
	(segment
		(start 343.662 -209.296)
		(end 343.662 -209.931)
		(width 0.13208)
		(layer "B.Cu")
		(net "SSD14_CLK_EN_N")
	)
	(segment
		(start 76.147168 -54.144164)
		(end 76.575412 -54.144164)
		(width 0.13208)
		(layer "F.Cu")
		(net "P12V_SSD2_OCP")
	)
	(segment
		(start 76.756006 -53.96357)
		(end 77.154024 -53.96357)
		(width 0.13208)
		(layer "F.Cu")
		(net "P12V_SSD2_OCP")
	)
	(segment
		(start 76.575412 -54.144164)
		(end 76.756006 -53.96357)
		(width 0.13208)
		(layer "F.Cu")
		(net "P12V_SSD2_OCP")
	)
	(segment
		(start 77.867764 -54.067456)
		(end 77.763878 -53.96357)
		(width 0.13208)
		(layer "F.Cu")
		(net "P12V_SSD2_OCP")
	)
	(segment
		(start 77.763878 -53.96357)
		(end 77.154024 -53.96357)
		(width 0.13208)
		(layer "F.Cu")
		(net "P12V_SSD2_OCP")
	)
	(via
		(at 77.154024 -53.96357)
		(size 0.508)
		(drill 0.254)
		(layers "F.Cu" "B.Cu")
		(net "P12V_SSD2_OCP")
	)
	(segment
		(start 112.651794 -83.835494)
		(end 112.272064 -83.835494)
		(width 0.13462)
		(layer "F.Cu")
		(net "CLK_100M_DB800ZL_SSD3_DP")
	)
	(segment
		(start 112.215676 -83.779106)
		(end 111.788956 -83.779106)
		(width 0.13462)
		(layer "F.Cu")
		(net "CLK_100M_DB800ZL_SSD3_DP")
	)
	(segment
		(start 112.272064 -83.835494)
		(end 112.215676 -83.779106)
		(width 0.13462)
		(layer "F.Cu")
		(net "CLK_100M_DB800ZL_SSD3_DP")
	)
	(segment
		(start 113.703608 -82.78368)
		(end 112.651794 -83.835494)
		(width 0.13462)
		(layer "F.Cu")
		(net "CLK_100M_DB800ZL_SSD3_DP")
	)
	(segment
		(start 114.956336 -82.46999)
		(end 114.642646 -82.78368)
		(width 0.13462)
		(layer "F.Cu")
		(net "CLK_100M_DB800ZL_SSD3_DP")
	)
	(segment
		(start 114.642646 -82.78368)
		(end 113.703608 -82.78368)
		(width 0.13462)
		(layer "F.Cu")
		(net "CLK_100M_DB800ZL_SSD3_DP")
	)
	(segment
		(start 36.849558 -299.699934)
		(end 36.374578 -299.224954)
		(width 0.1143)
		(layer "F.Cu")
		(net "CLK_100M_PEX0_REF_R_DN")
	)
	(segment
		(start 229.711504 -156.340556)
		(end 229.3874 -156.66466)
		(width 0.1143)
		(layer "F.Cu")
		(net "CLK_100M_PEX0_REF_R_DN")
	)
	(segment
		(start 229.3874 -156.66466)
		(end 229.3874 -157.62224)
		(width 0.1143)
		(layer "F.Cu")
		(net "CLK_100M_PEX0_REF_R_DN")
	)
	(segment
		(start 229.3874 -157.62224)
		(end 229.635304 -157.870144)
		(width 0.1143)
		(layer "F.Cu")
		(net "CLK_100M_PEX0_REF_R_DN")
	)
	(segment
		(start 36.849812 -299.699934)
		(end 36.849558 -299.699934)
		(width 0.1143)
		(layer "F.Cu")
		(net "CLK_100M_PEX0_REF_R_DN")
	)
	(via
		(at 229.635304 -157.870144)
		(size 0.508)
		(drill 0.254)
		(layers "F.Cu" "B.Cu")
		(net "CLK_100M_PEX0_REF_R_DN")
	)
	(via
		(at 36.374578 -299.224954)
		(size 0.4064)
		(drill 0.2032)
		(layers "F.Cu" "B.Cu")
		(net "CLK_100M_PEX0_REF_R_DN")
	)
	(segment
		(start 25.354534 -292.097714)
		(end 25.354534 -291.696394)
		(width 0.1143)
		(layer "B.Cu")
		(net "CLK_100M_PEX0_REF_R_DN")
	)
	(segment
		(start 35.3568 -299.61205)
		(end 35.334702 -299.61205)
		(width 0.0889)
		(layer "B.Cu")
		(net "CLK_100M_PEX0_REF_R_DN")
	)
	(segment
		(start 25.354534 -289.532314)
		(end 25.217374 -289.395154)
		(width 0.1143)
		(layer "B.Cu")
		(net "CLK_100M_PEX0_REF_R_DN")
	)
	(segment
		(start 96.748854 -196.5833)
		(end 98.589846 -194.742308)
		(width 0.1143)
		(layer "B.Cu")
		(net "CLK_100M_PEX0_REF_R_DN")
	)
	(segment
		(start 114.73942 -188.7347)
		(end 123.088146 -188.7347)
		(width 0.1143)
		(layer "B.Cu")
		(net "CLK_100M_PEX0_REF_R_DN")
	)
	(segment
		(start 36.374578 -299.224954)
		(end 36.665408 -299.224954)
		(width 0.0889)
		(layer "B.Cu")
		(net "CLK_100M_PEX0_REF_R_DN")
	)
	(segment
		(start 25.217374 -290.073334)
		(end 25.354534 -289.936174)
		(width 0.1143)
		(layer "B.Cu")
		(net "CLK_100M_PEX0_REF_R_DN")
	)
	(segment
		(start 25.217374 -295.465754)
		(end 25.354534 -295.328594)
		(width 0.1143)
		(layer "B.Cu")
		(net "CLK_100M_PEX0_REF_R_DN")
	)
	(segment
		(start 25.217374 -290.477194)
		(end 25.217374 -290.073334)
		(width 0.1143)
		(layer "B.Cu")
		(net "CLK_100M_PEX0_REF_R_DN")
	)
	(segment
		(start 25.217374 -293.311834)
		(end 25.354534 -293.174674)
		(width 0.1143)
		(layer "B.Cu")
		(net "CLK_100M_PEX0_REF_R_DN")
	)
	(segment
		(start 29.477462 -296.518076)
		(end 29.340302 -296.655236)
		(width 0.1143)
		(layer "B.Cu")
		(net "CLK_100M_PEX0_REF_R_DN")
	)
	(segment
		(start 33.490154 -297.9293)
		(end 31.691326 -297.9293)
		(width 0.1143)
		(layer "B.Cu")
		(net "CLK_100M_PEX0_REF_R_DN")
	)
	(segment
		(start 25.217374 -295.867074)
		(end 25.217374 -295.465754)
		(width 0.1143)
		(layer "B.Cu")
		(net "CLK_100M_PEX0_REF_R_DN")
	)
	(segment
		(start 36.741608 -299.301154)
		(end 36.741608 -299.603668)
		(width 0.0889)
		(layer "B.Cu")
		(net "CLK_100M_PEX0_REF_R_DN")
	)
	(segment
		(start 36.665408 -299.224954)
		(end 36.741608 -299.301154)
		(width 0.0889)
		(layer "B.Cu")
		(net "CLK_100M_PEX0_REF_R_DN")
	)
	(segment
		(start 25.354534 -294.251634)
		(end 25.354534 -293.850314)
		(width 0.1143)
		(layer "B.Cu")
		(net "CLK_100M_PEX0_REF_R_DN")
	)
	(segment
		(start 25.217374 -293.713154)
		(end 25.217374 -293.311834)
		(width 0.1143)
		(layer "B.Cu")
		(net "CLK_100M_PEX0_REF_R_DN")
	)
	(segment
		(start 30.015942 -296.655236)
		(end 29.878782 -296.518076)
		(width 0.1143)
		(layer "B.Cu")
		(net "CLK_100M_PEX0_REF_R_DN")
	)
	(segment
		(start 98.589846 -194.742308)
		(end 107.820206 -194.742308)
		(width 0.1143)
		(layer "B.Cu")
		(net "CLK_100M_PEX0_REF_R_DN")
	)
	(segment
		(start 25.217374 -289.395154)
		(end 25.217374 -277.101046)
		(width 0.1143)
		(layer "B.Cu")
		(net "CLK_100M_PEX0_REF_R_DN")
	)
	(segment
		(start 19.7358 -251.108718)
		(end 49.801018 -221.0435)
		(width 0.1143)
		(layer "B.Cu")
		(net "CLK_100M_PEX0_REF_R_DN")
	)
	(segment
		(start 25.217374 -292.234874)
		(end 25.354534 -292.097714)
		(width 0.1143)
		(layer "B.Cu")
		(net "CLK_100M_PEX0_REF_R_DN")
	)
	(segment
		(start 30.417262 -296.655236)
		(end 30.015942 -296.655236)
		(width 0.1143)
		(layer "B.Cu")
		(net "CLK_100M_PEX0_REF_R_DN")
	)
	(segment
		(start 22.541992 -274.425664)
		(end 22.541992 -267.56868)
		(width 0.1143)
		(layer "B.Cu")
		(net "CLK_100M_PEX0_REF_R_DN")
	)
	(segment
		(start 124.967746 -190.6143)
		(end 137.50544 -190.6143)
		(width 0.1143)
		(layer "B.Cu")
		(net "CLK_100M_PEX0_REF_R_DN")
	)
	(segment
		(start 49.801018 -221.0435)
		(end 70.561454 -221.0435)
		(width 0.1143)
		(layer "B.Cu")
		(net "CLK_100M_PEX0_REF_R_DN")
	)
	(segment
		(start 208.375758 -158.951676)
		(end 228.982524 -158.951676)
		(width 0.1143)
		(layer "B.Cu")
		(net "CLK_100M_PEX0_REF_R_DN")
	)
	(segment
		(start 123.088146 -188.7347)
		(end 124.967746 -190.6143)
		(width 0.1143)
		(layer "B.Cu")
		(net "CLK_100M_PEX0_REF_R_DN")
	)
	(segment
		(start 25.354534 -290.614354)
		(end 25.217374 -290.477194)
		(width 0.1143)
		(layer "B.Cu")
		(net "CLK_100M_PEX0_REF_R_DN")
	)
	(segment
		(start 29.878782 -296.518076)
		(end 29.477462 -296.518076)
		(width 0.1143)
		(layer "B.Cu")
		(net "CLK_100M_PEX0_REF_R_DN")
	)
	(segment
		(start 35.334702 -299.61205)
		(end 35.172904 -299.61205)
		(width 0.1143)
		(layer "B.Cu")
		(net "CLK_100M_PEX0_REF_R_DN")
	)
	(segment
		(start 25.217374 -291.155374)
		(end 25.354534 -291.018214)
		(width 0.1143)
		(layer "B.Cu")
		(net "CLK_100M_PEX0_REF_R_DN")
	)
	(segment
		(start 25.217374 -294.790114)
		(end 25.217374 -294.388794)
		(width 0.1143)
		(layer "B.Cu")
		(net "CLK_100M_PEX0_REF_R_DN")
	)
	(segment
		(start 229.388162 -158.117286)
		(end 229.635304 -157.870144)
		(width 0.1143)
		(layer "B.Cu")
		(net "CLK_100M_PEX0_REF_R_DN")
	)
	(segment
		(start 35.172904 -299.61205)
		(end 33.490154 -297.9293)
		(width 0.1143)
		(layer "B.Cu")
		(net "CLK_100M_PEX0_REF_R_DN")
	)
	(segment
		(start 28.400502 -296.518076)
		(end 28.263342 -296.655236)
		(width 0.1143)
		(layer "B.Cu")
		(net "CLK_100M_PEX0_REF_R_DN")
	)
	(segment
		(start 28.938982 -296.655236)
		(end 28.801822 -296.518076)
		(width 0.1143)
		(layer "B.Cu")
		(net "CLK_100M_PEX0_REF_R_DN")
	)
	(segment
		(start 95.021654 -196.5833)
		(end 96.748854 -196.5833)
		(width 0.1143)
		(layer "B.Cu")
		(net "CLK_100M_PEX0_REF_R_DN")
	)
	(segment
		(start 25.354534 -294.927274)
		(end 25.217374 -294.790114)
		(width 0.1143)
		(layer "B.Cu")
		(net "CLK_100M_PEX0_REF_R_DN")
	)
	(segment
		(start 26.005536 -296.655236)
		(end 25.217374 -295.867074)
		(width 0.1143)
		(layer "B.Cu")
		(net "CLK_100M_PEX0_REF_R_DN")
	)
	(segment
		(start 36.741608 -299.603668)
		(end 36.650676 -299.6946)
		(width 0.0889)
		(layer "B.Cu")
		(net "CLK_100M_PEX0_REF_R_DN")
	)
	(segment
		(start 109.44352 -194.0306)
		(end 114.73942 -188.7347)
		(width 0.1143)
		(layer "B.Cu")
		(net "CLK_100M_PEX0_REF_R_DN")
	)
	(segment
		(start 108.531914 -194.0306)
		(end 109.44352 -194.0306)
		(width 0.1143)
		(layer "B.Cu")
		(net "CLK_100M_PEX0_REF_R_DN")
	)
	(segment
		(start 25.354534 -293.174674)
		(end 25.354534 -292.773354)
		(width 0.1143)
		(layer "B.Cu")
		(net "CLK_100M_PEX0_REF_R_DN")
	)
	(segment
		(start 36.650676 -299.6946)
		(end 35.43935 -299.6946)
		(width 0.0889)
		(layer "B.Cu")
		(net "CLK_100M_PEX0_REF_R_DN")
	)
	(segment
		(start 180.180234 -187.1472)
		(end 208.375758 -158.951676)
		(width 0.1143)
		(layer "B.Cu")
		(net "CLK_100M_PEX0_REF_R_DN")
	)
	(segment
		(start 25.217374 -277.101046)
		(end 22.541992 -274.425664)
		(width 0.1143)
		(layer "B.Cu")
		(net "CLK_100M_PEX0_REF_R_DN")
	)
	(segment
		(start 29.340302 -296.655236)
		(end 28.938982 -296.655236)
		(width 0.1143)
		(layer "B.Cu")
		(net "CLK_100M_PEX0_REF_R_DN")
	)
	(segment
		(start 137.50544 -190.6143)
		(end 140.97254 -187.1472)
		(width 0.1143)
		(layer "B.Cu")
		(net "CLK_100M_PEX0_REF_R_DN")
	)
	(segment
		(start 35.43935 -299.6946)
		(end 35.3568 -299.61205)
		(width 0.0889)
		(layer "B.Cu")
		(net "CLK_100M_PEX0_REF_R_DN")
	)
	(segment
		(start 229.388162 -158.546038)
		(end 229.388162 -158.117286)
		(width 0.1143)
		(layer "B.Cu")
		(net "CLK_100M_PEX0_REF_R_DN")
	)
	(segment
		(start 25.354534 -293.850314)
		(end 25.217374 -293.713154)
		(width 0.1143)
		(layer "B.Cu")
		(net "CLK_100M_PEX0_REF_R_DN")
	)
	(segment
		(start 140.97254 -187.1472)
		(end 180.180234 -187.1472)
		(width 0.1143)
		(layer "B.Cu")
		(net "CLK_100M_PEX0_REF_R_DN")
	)
	(segment
		(start 31.691326 -297.9293)
		(end 30.417262 -296.655236)
		(width 0.1143)
		(layer "B.Cu")
		(net "CLK_100M_PEX0_REF_R_DN")
	)
	(segment
		(start 25.354534 -292.773354)
		(end 25.217374 -292.636194)
		(width 0.1143)
		(layer "B.Cu")
		(net "CLK_100M_PEX0_REF_R_DN")
	)
	(segment
		(start 25.217374 -294.388794)
		(end 25.354534 -294.251634)
		(width 0.1143)
		(layer "B.Cu")
		(net "CLK_100M_PEX0_REF_R_DN")
	)
	(segment
		(start 25.354534 -291.696394)
		(end 25.217374 -291.559234)
		(width 0.1143)
		(layer "B.Cu")
		(net "CLK_100M_PEX0_REF_R_DN")
	)
	(segment
		(start 25.354534 -291.018214)
		(end 25.354534 -290.614354)
		(width 0.1143)
		(layer "B.Cu")
		(net "CLK_100M_PEX0_REF_R_DN")
	)
	(segment
		(start 25.217374 -291.559234)
		(end 25.217374 -291.155374)
		(width 0.1143)
		(layer "B.Cu")
		(net "CLK_100M_PEX0_REF_R_DN")
	)
	(segment
		(start 19.7358 -260.793992)
		(end 19.7358 -251.108718)
		(width 0.1143)
		(layer "B.Cu")
		(net "CLK_100M_PEX0_REF_R_DN")
	)
	(segment
		(start 70.561454 -221.0435)
		(end 95.021654 -196.5833)
		(width 0.1143)
		(layer "B.Cu")
		(net "CLK_100M_PEX0_REF_R_DN")
	)
	(segment
		(start 228.982524 -158.951676)
		(end 229.388162 -158.546038)
		(width 0.1143)
		(layer "B.Cu")
		(net "CLK_100M_PEX0_REF_R_DN")
	)
	(segment
		(start 107.820206 -194.742308)
		(end 108.531914 -194.0306)
		(width 0.1143)
		(layer "B.Cu")
		(net "CLK_100M_PEX0_REF_R_DN")
	)
	(segment
		(start 25.354534 -289.936174)
		(end 25.354534 -289.532314)
		(width 0.1143)
		(layer "B.Cu")
		(net "CLK_100M_PEX0_REF_R_DN")
	)
	(segment
		(start 25.217374 -292.636194)
		(end 25.217374 -292.234874)
		(width 0.1143)
		(layer "B.Cu")
		(net "CLK_100M_PEX0_REF_R_DN")
	)
	(segment
		(start 28.263342 -296.655236)
		(end 26.005536 -296.655236)
		(width 0.1143)
		(layer "B.Cu")
		(net "CLK_100M_PEX0_REF_R_DN")
	)
	(segment
		(start 25.354534 -295.328594)
		(end 25.354534 -294.927274)
		(width 0.1143)
		(layer "B.Cu")
		(net "CLK_100M_PEX0_REF_R_DN")
	)
	(segment
		(start 28.801822 -296.518076)
		(end 28.400502 -296.518076)
		(width 0.1143)
		(layer "B.Cu")
		(net "CLK_100M_PEX0_REF_R_DN")
	)
	(segment
		(start 22.541992 -267.56868)
		(end 19.7358 -260.793992)
		(width 0.1143)
		(layer "B.Cu")
		(net "CLK_100M_PEX0_REF_R_DN")
	)
	(segment
		(start 208.303876 -24.189944)
		(end 209.364834 -24.189944)
		(width 0.13208)
		(layer "F.Cu")
		(net "RST_SSD7_PERST_R_N")
	)
	(segment
		(start 246.5578 -207.7212)
		(end 246.5578 -211.073746)
		(width 0.13208)
		(layer "F.Cu")
		(net "RST_SSD7_PERST_R_N")
	)
	(segment
		(start 245.7196 -211.911946)
		(end 245.7196 -218.388946)
		(width 0.13208)
		(layer "F.Cu")
		(net "RST_SSD7_PERST_R_N")
	)
	(segment
		(start 244.463062 -229.53599)
		(end 244.463062 -230.340662)
		(width 0.13208)
		(layer "F.Cu")
		(net "RST_SSD7_PERST_R_N")
	)
	(segment
		(start 244.696996 -229.063804)
		(end 244.631464 -229.129336)
		(width 0.13208)
		(layer "F.Cu")
		(net "RST_SSD7_PERST_R_N")
	)
	(segment
		(start 245.7196 -218.388946)
		(end 244.696996 -219.41155)
		(width 0.13208)
		(layer "F.Cu")
		(net "RST_SSD7_PERST_R_N")
	)
	(segment
		(start 244.631464 -229.129336)
		(end 244.463062 -229.53599)
		(width 0.13208)
		(layer "F.Cu")
		(net "RST_SSD7_PERST_R_N")
	)
	(segment
		(start 246.5578 -211.073746)
		(end 245.7196 -211.911946)
		(width 0.13208)
		(layer "F.Cu")
		(net "RST_SSD7_PERST_R_N")
	)
	(segment
		(start 244.696996 -219.41155)
		(end 244.696996 -229.063804)
		(width 0.13208)
		(layer "F.Cu")
		(net "RST_SSD7_PERST_R_N")
	)
	(segment
		(start 247.015 -207.264)
		(end 246.5578 -207.7212)
		(width 0.13208)
		(layer "F.Cu")
		(net "RST_SSD7_PERST_R_N")
	)
	(segment
		(start 250.105164 -192.320926)
		(end 247.015 -195.41109)
		(width 0.13208)
		(layer "F.Cu")
		(net "RST_SSD7_PERST_R_N")
	)
	(segment
		(start 249.739658 -235.617258)
		(end 249.739658 -246.01551)
		(width 0.13208)
		(layer "F.Cu")
		(net "RST_SSD7_PERST_R_N")
	)
	(segment
		(start 247.015 -195.41109)
		(end 247.015 -207.264)
		(width 0.13208)
		(layer "F.Cu")
		(net "RST_SSD7_PERST_R_N")
	)
	(segment
		(start 244.463062 -230.340662)
		(end 249.739658 -235.617258)
		(width 0.13208)
		(layer "F.Cu")
		(net "RST_SSD7_PERST_R_N")
	)
	(segment
		(start 254.698754 -192.320926)
		(end 250.105164 -192.320926)
		(width 0.13208)
		(layer "F.Cu")
		(net "RST_SSD7_PERST_R_N")
	)
	(via
		(at 249.739658 -246.01551)
		(size 0.508)
		(drill 0.254)
		(layers "F.Cu" "B.Cu")
		(net "RST_SSD7_PERST_R_N")
	)
	(via
		(at 208.303876 -24.189944)
		(size 0.508)
		(drill 0.254)
		(layers "F.Cu" "B.Cu")
		(net "RST_SSD7_PERST_R_N")
	)
	(via
		(at 223.235774 -169.457624)
		(size 0.508)
		(drill 0.254)
		(layers "F.Cu" "B.Cu")
		(net "RST_SSD7_PERST_R_N")
	)
	(via
		(at 347.091 -236.347)
		(size 0.508)
		(drill 0.254)
		(layers "F.Cu" "B.Cu")
		(net "RST_SSD7_PERST_R_N")
	)
	(via
		(at 254.698754 -192.320926)
		(size 0.508)
		(drill 0.254)
		(layers "F.Cu" "B.Cu")
		(net "RST_SSD7_PERST_R_N")
	)
	(via
		(at 254.425704 -172.21581)
		(size 0.508)
		(drill 0.254)
		(layers "F.Cu" "B.Cu")
		(net "RST_SSD7_PERST_R_N")
	)
	(segment
		(start 348.107 -233.95305)
		(end 347.63329 -234.42676)
		(width 0.13208)
		(layer "B.Cu")
		(net "RST_SSD7_PERST_R_N")
	)
	(segment
		(start 347.63329 -234.42676)
		(end 347.63329 -235.80471)
		(width 0.13208)
		(layer "B.Cu")
		(net "RST_SSD7_PERST_R_N")
	)
	(segment
		(start 347.63329 -235.80471)
		(end 347.091 -236.347)
		(width 0.13208)
		(layer "B.Cu")
		(net "RST_SSD7_PERST_R_N")
	)
	(segment
		(start 213.815422 -106.933746)
		(end 221.883478 -115.001802)
		(width 0.15494)
		(layer "In5.Cu")
		(net "RST_SSD7_PERST_R_N")
	)
	(segment
		(start 209.044286 -24.930354)
		(end 211.083398 -24.930354)
		(width 0.15494)
		(layer "In5.Cu")
		(net "RST_SSD7_PERST_R_N")
	)
	(segment
		(start 254.425704 -192.047876)
		(end 254.425704 -172.21581)
		(width 0.15494)
		(layer "In5.Cu")
		(net "RST_SSD7_PERST_R_N")
	)
	(segment
		(start 218.03741 -27.455114)
		(end 218.7448 -28.162504)
		(width 0.15494)
		(layer "In5.Cu")
		(net "RST_SSD7_PERST_R_N")
	)
	(segment
		(start 221.883478 -115.001802)
		(end 221.883478 -130.338068)
		(width 0.15494)
		(layer "In5.Cu")
		(net "RST_SSD7_PERST_R_N")
	)
	(segment
		(start 218.00058 -36.1315)
		(end 223.23298 -41.3639)
		(width 0.15494)
		(layer "In5.Cu")
		(net "RST_SSD7_PERST_R_N")
	)
	(segment
		(start 222.862902 -75.089004)
		(end 222.141796 -75.089004)
		(width 0.15494)
		(layer "In5.Cu")
		(net "RST_SSD7_PERST_R_N")
	)
	(segment
		(start 213.102444 -26.9494)
		(end 214.626444 -26.9494)
		(width 0.15494)
		(layer "In5.Cu")
		(net "RST_SSD7_PERST_R_N")
	)
	(segment
		(start 218.7448 -29.136086)
		(end 218.00058 -29.880306)
		(width 0.15494)
		(layer "In5.Cu")
		(net "RST_SSD7_PERST_R_N")
	)
	(segment
		(start 220.429328 -76.801472)
		(end 220.429328 -87.649558)
		(width 0.15494)
		(layer "In5.Cu")
		(net "RST_SSD7_PERST_R_N")
	)
	(segment
		(start 215.8492 -100.278438)
		(end 213.815422 -105.188512)
		(width 0.15494)
		(layer "In5.Cu")
		(net "RST_SSD7_PERST_R_N")
	)
	(segment
		(start 214.626444 -26.9494)
		(end 215.132158 -27.455114)
		(width 0.15494)
		(layer "In5.Cu")
		(net "RST_SSD7_PERST_R_N")
	)
	(segment
		(start 212.75548 -161.008568)
		(end 220.021912 -168.275)
		(width 0.15494)
		(layer "In5.Cu")
		(net "RST_SSD7_PERST_R_N")
	)
	(segment
		(start 211.083398 -24.930354)
		(end 213.102444 -26.9494)
		(width 0.15494)
		(layer "In5.Cu")
		(net "RST_SSD7_PERST_R_N")
	)
	(segment
		(start 218.00058 -29.880306)
		(end 218.00058 -36.1315)
		(width 0.15494)
		(layer "In5.Cu")
		(net "RST_SSD7_PERST_R_N")
	)
	(segment
		(start 212.75548 -139.466066)
		(end 212.75548 -161.008568)
		(width 0.15494)
		(layer "In5.Cu")
		(net "RST_SSD7_PERST_R_N")
	)
	(segment
		(start 213.815422 -105.188512)
		(end 213.815422 -106.933746)
		(width 0.15494)
		(layer "In5.Cu")
		(net "RST_SSD7_PERST_R_N")
	)
	(segment
		(start 221.883478 -130.338068)
		(end 212.75548 -139.466066)
		(width 0.15494)
		(layer "In5.Cu")
		(net "RST_SSD7_PERST_R_N")
	)
	(segment
		(start 222.25 -63.87084)
		(end 222.25 -73.202546)
		(width 0.15494)
		(layer "In5.Cu")
		(net "RST_SSD7_PERST_R_N")
	)
	(segment
		(start 223.145858 -74.806048)
		(end 222.862902 -75.089004)
		(width 0.15494)
		(layer "In5.Cu")
		(net "RST_SSD7_PERST_R_N")
	)
	(segment
		(start 220.754194 -90.247216)
		(end 215.8492 -95.15221)
		(width 0.15494)
		(layer "In5.Cu")
		(net "RST_SSD7_PERST_R_N")
	)
	(segment
		(start 215.8492 -95.15221)
		(end 215.8492 -100.278438)
		(width 0.15494)
		(layer "In5.Cu")
		(net "RST_SSD7_PERST_R_N")
	)
	(segment
		(start 215.132158 -27.455114)
		(end 218.03741 -27.455114)
		(width 0.15494)
		(layer "In5.Cu")
		(net "RST_SSD7_PERST_R_N")
	)
	(segment
		(start 223.23298 -41.3639)
		(end 223.23298 -62.88786)
		(width 0.15494)
		(layer "In5.Cu")
		(net "RST_SSD7_PERST_R_N")
	)
	(segment
		(start 220.021912 -168.275)
		(end 222.05315 -168.275)
		(width 0.15494)
		(layer "In5.Cu")
		(net "RST_SSD7_PERST_R_N")
	)
	(segment
		(start 223.23298 -62.88786)
		(end 222.25 -63.87084)
		(width 0.15494)
		(layer "In5.Cu")
		(net "RST_SSD7_PERST_R_N")
	)
	(segment
		(start 222.05315 -168.275)
		(end 223.235774 -169.457624)
		(width 0.15494)
		(layer "In5.Cu")
		(net "RST_SSD7_PERST_R_N")
	)
	(segment
		(start 208.303876 -24.189944)
		(end 209.044286 -24.930354)
		(width 0.15494)
		(layer "In5.Cu")
		(net "RST_SSD7_PERST_R_N")
	)
	(segment
		(start 220.754194 -87.974424)
		(end 220.754194 -90.247216)
		(width 0.15494)
		(layer "In5.Cu")
		(net "RST_SSD7_PERST_R_N")
	)
	(segment
		(start 254.698754 -192.320926)
		(end 254.425704 -192.047876)
		(width 0.15494)
		(layer "In5.Cu")
		(net "RST_SSD7_PERST_R_N")
	)
	(segment
		(start 220.429328 -87.649558)
		(end 220.754194 -87.974424)
		(width 0.15494)
		(layer "In5.Cu")
		(net "RST_SSD7_PERST_R_N")
	)
	(segment
		(start 218.7448 -28.162504)
		(end 218.7448 -29.136086)
		(width 0.15494)
		(layer "In5.Cu")
		(net "RST_SSD7_PERST_R_N")
	)
	(segment
		(start 222.25 -73.202546)
		(end 223.145858 -74.098404)
		(width 0.15494)
		(layer "In5.Cu")
		(net "RST_SSD7_PERST_R_N")
	)
	(segment
		(start 223.145858 -74.098404)
		(end 223.145858 -74.806048)
		(width 0.15494)
		(layer "In5.Cu")
		(net "RST_SSD7_PERST_R_N")
	)
	(segment
		(start 222.141796 -75.089004)
		(end 220.429328 -76.801472)
		(width 0.15494)
		(layer "In5.Cu")
		(net "RST_SSD7_PERST_R_N")
	)
	(segment
		(start 347.434662 -238.36376)
		(end 347.434662 -238.82731)
		(width 0.15494)
		(layer "In15.Cu")
		(net "RST_SSD7_PERST_R_N")
	)
	(segment
		(start 223.768158 -169.990008)
		(end 223.235774 -169.457624)
		(width 0.15494)
		(layer "In15.Cu")
		(net "RST_SSD7_PERST_R_N")
	)
	(segment
		(start 333.166466 -247.68302)
		(end 332.948026 -247.90146)
		(width 0.15494)
		(layer "In15.Cu")
		(net "RST_SSD7_PERST_R_N")
	)
	(segment
		(start 304.235358 -247.687846)
		(end 303.159922 -248.133108)
		(width 0.15494)
		(layer "In15.Cu")
		(net "RST_SSD7_PERST_R_N")
	)
	(segment
		(start 254.425704 -172.21581)
		(end 254.391414 -172.21581)
		(width 0.15494)
		(layer "In15.Cu")
		(net "RST_SSD7_PERST_R_N")
	)
	(segment
		(start 326.24395 -247.687846)
		(end 304.235358 -247.687846)
		(width 0.15494)
		(layer "In15.Cu")
		(net "RST_SSD7_PERST_R_N")
	)
	(segment
		(start 254.391414 -172.21581)
		(end 254.385064 -172.20946)
		(width 0.15494)
		(layer "In15.Cu")
		(net "RST_SSD7_PERST_R_N")
	)
	(segment
		(start 274.329398 -246.605552)
		(end 274.03298 -246.309134)
		(width 0.15494)
		(layer "In15.Cu")
		(net "RST_SSD7_PERST_R_N")
	)
	(segment
		(start 346.8878 -240.056924)
		(end 339.261704 -247.68302)
		(width 0.15494)
		(layer "In15.Cu")
		(net "RST_SSD7_PERST_R_N")
	)
	(segment
		(start 298.871132 -246.605552)
		(end 274.329398 -246.605552)
		(width 0.15494)
		(layer "In15.Cu")
		(net "RST_SSD7_PERST_R_N")
	)
	(segment
		(start 347.091 -236.347)
		(end 347.091 -238.020098)
		(width 0.15494)
		(layer "In15.Cu")
		(net "RST_SSD7_PERST_R_N")
	)
	(segment
		(start 237.32236 -169.990008)
		(end 223.768158 -169.990008)
		(width 0.15494)
		(layer "In15.Cu")
		(net "RST_SSD7_PERST_R_N")
	)
	(segment
		(start 339.261704 -247.68302)
		(end 333.166466 -247.68302)
		(width 0.15494)
		(layer "In15.Cu")
		(net "RST_SSD7_PERST_R_N")
	)
	(segment
		(start 253.40691 -246.01551)
		(end 249.739658 -246.01551)
		(width 0.15494)
		(layer "In15.Cu")
		(net "RST_SSD7_PERST_R_N")
	)
	(segment
		(start 300.398688 -248.133108)
		(end 298.871132 -246.605552)
		(width 0.15494)
		(layer "In15.Cu")
		(net "RST_SSD7_PERST_R_N")
	)
	(segment
		(start 346.8878 -239.374172)
		(end 346.8878 -240.056924)
		(width 0.15494)
		(layer "In15.Cu")
		(net "RST_SSD7_PERST_R_N")
	)
	(segment
		(start 331.201268 -247.90146)
		(end 330.906882 -248.195846)
		(width 0.15494)
		(layer "In15.Cu")
		(net "RST_SSD7_PERST_R_N")
	)
	(segment
		(start 330.906882 -248.195846)
		(end 326.75195 -248.195846)
		(width 0.15494)
		(layer "In15.Cu")
		(net "RST_SSD7_PERST_R_N")
	)
	(segment
		(start 239.541812 -172.20946)
		(end 237.32236 -169.990008)
		(width 0.15494)
		(layer "In15.Cu")
		(net "RST_SSD7_PERST_R_N")
	)
	(segment
		(start 274.03298 -246.309134)
		(end 253.700534 -246.309134)
		(width 0.15494)
		(layer "In15.Cu")
		(net "RST_SSD7_PERST_R_N")
	)
	(segment
		(start 347.434662 -238.82731)
		(end 346.8878 -239.374172)
		(width 0.15494)
		(layer "In15.Cu")
		(net "RST_SSD7_PERST_R_N")
	)
	(segment
		(start 254.385064 -172.20946)
		(end 239.541812 -172.20946)
		(width 0.15494)
		(layer "In15.Cu")
		(net "RST_SSD7_PERST_R_N")
	)
	(segment
		(start 332.948026 -247.90146)
		(end 331.201268 -247.90146)
		(width 0.15494)
		(layer "In15.Cu")
		(net "RST_SSD7_PERST_R_N")
	)
	(segment
		(start 253.700534 -246.309134)
		(end 253.40691 -246.01551)
		(width 0.15494)
		(layer "In15.Cu")
		(net "RST_SSD7_PERST_R_N")
	)
	(segment
		(start 326.75195 -248.195846)
		(end 326.24395 -247.687846)
		(width 0.15494)
		(layer "In15.Cu")
		(net "RST_SSD7_PERST_R_N")
	)
	(segment
		(start 347.091 -238.020098)
		(end 347.434662 -238.36376)
		(width 0.15494)
		(layer "In15.Cu")
		(net "RST_SSD7_PERST_R_N")
	)
	(segment
		(start 303.159922 -248.133108)
		(end 300.398688 -248.133108)
		(width 0.15494)
		(layer "In15.Cu")
		(net "RST_SSD7_PERST_R_N")
	)
	(segment
		(start 335.534 -201.56805)
		(end 335.534 -202.184)
		(width 0.13208)
		(layer "F.Cu")
		(net "RST_SSD10_PERST_N")
	)
	(segment
		(start 338.893912 -214.387176)
		(end 338.494116 -213.98738)
		(width 0.13208)
		(layer "F.Cu")
		(net "RST_SSD10_PERST_N")
	)
	(via
		(at 335.534 -202.184)
		(size 0.508)
		(drill 0.254)
		(layers "F.Cu" "B.Cu")
		(net "RST_SSD10_PERST_N")
	)
	(via
		(at 338.494116 -213.98738)
		(size 0.4572)
		(drill 0.254)
		(layers "F.Cu" "B.Cu")
		(net "RST_SSD10_PERST_N")
	)
	(segment
		(start 338.891626 -211.94268)
		(end 338.891626 -212.217)
		(width 0.15494)
		(layer "In5.Cu")
		(net "RST_SSD10_PERST_N")
	)
	(segment
		(start 338.7344 -208.834228)
		(end 338.7344 -211.785454)
		(width 0.15494)
		(layer "In5.Cu")
		(net "RST_SSD10_PERST_N")
	)
	(segment
		(start 338.891626 -212.217)
		(end 338.891626 -213.58987)
		(width 0.0889)
		(layer "In5.Cu")
		(net "RST_SSD10_PERST_N")
	)
	(segment
		(start 335.534 -202.184)
		(end 336.052668 -202.702668)
		(width 0.15494)
		(layer "In5.Cu")
		(net "RST_SSD10_PERST_N")
	)
	(segment
		(start 338.7344 -211.785454)
		(end 338.891626 -211.94268)
		(width 0.15494)
		(layer "In5.Cu")
		(net "RST_SSD10_PERST_N")
	)
	(segment
		(start 338.891626 -213.58987)
		(end 338.494116 -213.98738)
		(width 0.0889)
		(layer "In5.Cu")
		(net "RST_SSD10_PERST_N")
	)
	(segment
		(start 336.052668 -202.702668)
		(end 336.052668 -204.6097)
		(width 0.15494)
		(layer "In5.Cu")
		(net "RST_SSD10_PERST_N")
	)
	(segment
		(start 336.550762 -205.107794)
		(end 336.550762 -206.65059)
		(width 0.15494)
		(layer "In5.Cu")
		(net "RST_SSD10_PERST_N")
	)
	(segment
		(start 336.550762 -206.65059)
		(end 338.7344 -208.834228)
		(width 0.15494)
		(layer "In5.Cu")
		(net "RST_SSD10_PERST_N")
	)
	(segment
		(start 336.052668 -204.6097)
		(end 336.550762 -205.107794)
		(width 0.15494)
		(layer "In5.Cu")
		(net "RST_SSD10_PERST_N")
	)
	(segment
		(start 76.479908 -52.994814)
		(end 76.479908 -51.670966)
		(width 0.13208)
		(layer "F.Cu")
		(net "P12V_SSD2_SS")
	)
	(segment
		(start 77.131418 -51.019456)
		(end 77.867764 -51.019456)
		(width 0.13208)
		(layer "F.Cu")
		(net "P12V_SSD2_SS")
	)
	(segment
		(start 76.330556 -53.144166)
		(end 76.479908 -52.994814)
		(width 0.13208)
		(layer "F.Cu")
		(net "P12V_SSD2_SS")
	)
	(segment
		(start 76.147168 -53.144166)
		(end 76.330556 -53.144166)
		(width 0.13208)
		(layer "F.Cu")
		(net "P12V_SSD2_SS")
	)
	(segment
		(start 76.479908 -51.670966)
		(end 77.131418 -51.019456)
		(width 0.13208)
		(layer "F.Cu")
		(net "P12V_SSD2_SS")
	)
	(via
		(at 77.131418 -51.019456)
		(size 0.508)
		(drill 0.254)
		(layers "F.Cu" "B.Cu")
		(net "P12V_SSD2_SS")
	)
	(segment
		(start 110.1852 -82.54746)
		(end 110.239048 -82.601308)
		(width 0.13462)
		(layer "F.Cu")
		(net "CLK_100M_DB800ZL_SSD2_DN")
	)
	(segment
		(start 110.1852 -80.533494)
		(end 110.1852 -82.54746)
		(width 0.13462)
		(layer "F.Cu")
		(net "CLK_100M_DB800ZL_SSD2_DN")
	)
	(segment
		(start 110.49635 -80.222344)
		(end 110.1852 -80.533494)
		(width 0.13462)
		(layer "F.Cu")
		(net "CLK_100M_DB800ZL_SSD2_DN")
	)
	(segment
		(start 110.239048 -82.601308)
		(end 110.239048 -83.029044)
		(width 0.13462)
		(layer "F.Cu")
		(net "CLK_100M_DB800ZL_SSD2_DN")
	)
	(segment
		(start 131.577588 -180.506878)
		(end 131.577588 -182.0291)
		(width 0.13462)
		(layer "F.Cu")
		(net "CLK_100M_DB2000QL_GPU_REF2_DN")
	)
	(segment
		(start 130.236214 -183.370474)
		(end 130.236214 -183.88711)
		(width 0.13462)
		(layer "F.Cu")
		(net "CLK_100M_DB2000QL_GPU_REF2_DN")
	)
	(segment
		(start 131.471162 -180.400452)
		(end 131.577588 -180.506878)
		(width 0.13462)
		(layer "F.Cu")
		(net "CLK_100M_DB2000QL_GPU_REF2_DN")
	)
	(segment
		(start 131.577588 -182.0291)
		(end 130.236214 -183.370474)
		(width 0.13462)
		(layer "F.Cu")
		(net "CLK_100M_DB2000QL_GPU_REF2_DN")
	)
	(segment
		(start 130.236214 -183.88711)
		(end 129.86639 -184.256934)
		(width 0.13462)
		(layer "F.Cu")
		(net "CLK_100M_DB2000QL_GPU_REF2_DN")
	)
	(segment
		(start 256.177034 -255.688592)
		(end 256.177034 -255.992376)
		(width 0.13208)
		(layer "F.Cu")
		(net "LED_PEX2_SYS_ERR_N")
	)
	(segment
		(start 256.933446 -256.748788)
		(end 256.992628 -256.748788)
		(width 0.13208)
		(layer "F.Cu")
		(net "LED_PEX2_SYS_ERR_N")
	)
	(segment
		(start 256.177034 -254.850646)
		(end 256.177034 -255.688592)
		(width 0.13208)
		(layer "F.Cu")
		(net "LED_PEX2_SYS_ERR_N")
	)
	(segment
		(start 256.177034 -255.992376)
		(end 256.933446 -256.748788)
		(width 0.13208)
		(layer "F.Cu")
		(net "LED_PEX2_SYS_ERR_N")
	)
	(via
		(at 256.177034 -255.688592)
		(size 0.508)
		(drill 0.254)
		(layers "F.Cu" "B.Cu")
		(net "LED_PEX2_SYS_ERR_N")
	)
	(via
		(at 301.719234 -232.799636)
		(size 0.6604)
		(drill 0.3302)
		(layers "F.Cu" "B.Cu")
		(net "RST_GPU_PERST_2_BUF_N")
	)
	(segment
		(start 300.774354 -235.074714)
		(end 300.774354 -233.744516)
		(width 0.13208)
		(layer "B.Cu")
		(net "RST_GPU_PERST_2_BUF_N")
	)
	(segment
		(start 301.058326 -235.358686)
		(end 300.774354 -235.074714)
		(width 0.13208)
		(layer "B.Cu")
		(net "RST_GPU_PERST_2_BUF_N")
	)
	(segment
		(start 300.774354 -233.744516)
		(end 301.719234 -232.799636)
		(width 0.13208)
		(layer "B.Cu")
		(net "RST_GPU_PERST_2_BUF_N")
	)
	(segment
		(start 301.536354 -236.336586)
		(end 301.536354 -235.358686)
		(width 0.13208)
		(layer "B.Cu")
		(net "RST_GPU_PERST_2_BUF_N")
	)
	(segment
		(start 301.536354 -235.358686)
		(end 301.058326 -235.358686)
		(width 0.13208)
		(layer "B.Cu")
		(net "RST_GPU_PERST_2_BUF_N")
	)
	(segment
		(start 301.719234 -232.799636)
		(end 301.719234 -231.220518)
		(width 0.13208)
		(layer "B.Cu")
		(net "RST_GPU_PERST_2_BUF_N")
	)
	(segment
		(start 333.907638 -251.977652)
		(end 334.245458 -252.315472)
		(width 0.13208)
		(layer "F.Cu")
		(net "SSD2_PWRDIS_R")
	)
	(segment
		(start 336.145124 -245.07317)
		(end 335.505806 -245.712488)
		(width 0.13208)
		(layer "F.Cu")
		(net "SSD2_PWRDIS_R")
	)
	(segment
		(start 76.134468 -28.469082)
		(end 76.134468 -28.550108)
		(width 0.13208)
		(layer "F.Cu")
		(net "SSD2_PWRDIS_R")
	)
	(segment
		(start 335.50606 -236.497622)
		(end 335.50606 -238.80826)
		(width 0.13208)
		(layer "F.Cu")
		(net "SSD2_PWRDIS_R")
	)
	(segment
		(start 334.245458 -252.315472)
		(end 337.259422 -252.315472)
		(width 0.13208)
		(layer "F.Cu")
		(net "SSD2_PWRDIS_R")
	)
	(segment
		(start 337.693762 -251.881132)
		(end 337.693762 -251.736352)
		(width 0.13208)
		(layer "F.Cu")
		(net "SSD2_PWRDIS_R")
	)
	(segment
		(start 335.661 -234.9246)
		(end 335.661 -236.342682)
		(width 0.13208)
		(layer "F.Cu")
		(net "SSD2_PWRDIS_R")
	)
	(segment
		(start 333.907638 -249.877072)
		(end 333.907638 -251.977652)
		(width 0.13208)
		(layer "F.Cu")
		(net "SSD2_PWRDIS_R")
	)
	(segment
		(start 335.19745 -234.46105)
		(end 335.661 -234.9246)
		(width 0.13208)
		(layer "F.Cu")
		(net "SSD2_PWRDIS_R")
	)
	(segment
		(start 76.134468 -28.550108)
		(end 76.664312 -29.079952)
		(width 0.13208)
		(layer "F.Cu")
		(net "SSD2_PWRDIS_R")
	)
	(segment
		(start 334.899 -234.46105)
		(end 335.19745 -234.46105)
		(width 0.13208)
		(layer "F.Cu")
		(net "SSD2_PWRDIS_R")
	)
	(segment
		(start 337.259422 -252.315472)
		(end 337.693762 -251.881132)
		(width 0.13208)
		(layer "F.Cu")
		(net "SSD2_PWRDIS_R")
	)
	(segment
		(start 335.505806 -245.712488)
		(end 335.505806 -248.278904)
		(width 0.13208)
		(layer "F.Cu")
		(net "SSD2_PWRDIS_R")
	)
	(segment
		(start 336.145124 -239.447324)
		(end 336.145124 -245.07317)
		(width 0.13208)
		(layer "F.Cu")
		(net "SSD2_PWRDIS_R")
	)
	(segment
		(start 67.264788 -25.390094)
		(end 66.19113 -25.390094)
		(width 0.13208)
		(layer "F.Cu")
		(net "SSD2_PWRDIS_R")
	)
	(segment
		(start 335.661 -236.342682)
		(end 335.50606 -236.497622)
		(width 0.13208)
		(layer "F.Cu")
		(net "SSD2_PWRDIS_R")
	)
	(segment
		(start 335.505806 -248.278904)
		(end 333.907638 -249.877072)
		(width 0.13208)
		(layer "F.Cu")
		(net "SSD2_PWRDIS_R")
	)
	(segment
		(start 335.50606 -238.80826)
		(end 336.145124 -239.447324)
		(width 0.13208)
		(layer "F.Cu")
		(net "SSD2_PWRDIS_R")
	)
	(via
		(at 76.134468 -28.469082)
		(size 0.508)
		(drill 0.254)
		(layers "F.Cu" "B.Cu")
		(net "SSD2_PWRDIS_R")
	)
	(via
		(at 337.693762 -251.736352)
		(size 0.508)
		(drill 0.254)
		(layers "F.Cu" "B.Cu")
		(net "SSD2_PWRDIS_R")
	)
	(via
		(at 66.19113 -25.390094)
		(size 0.508)
		(drill 0.254)
		(layers "F.Cu" "B.Cu")
		(net "SSD2_PWRDIS_R")
	)
	(via
		(at 121.02465 -241.871246)
		(size 0.508)
		(drill 0.254)
		(layers "F.Cu" "B.Cu")
		(net "SSD2_PWRDIS_R")
	)
	(segment
		(start 123.952 -185.979054)
		(end 123.952 -199.263254)
		(width 0.15494)
		(layer "In5.Cu")
		(net "SSD2_PWRDIS_R")
	)
	(segment
		(start 72.358758 -27.432)
		(end 72.841612 -27.914854)
		(width 0.15494)
		(layer "In5.Cu")
		(net "SSD2_PWRDIS_R")
	)
	(segment
		(start 88.8238 -46.634146)
		(end 88.8238 -77.876146)
		(width 0.15494)
		(layer "In5.Cu")
		(net "SSD2_PWRDIS_R")
	)
	(segment
		(start 75.58024 -27.914854)
		(end 76.134468 -28.469082)
		(width 0.15494)
		(layer "In5.Cu")
		(net "SSD2_PWRDIS_R")
	)
	(segment
		(start 118.11 -213.817454)
		(end 118.778528 -214.485982)
		(width 0.15494)
		(layer "In5.Cu")
		(net "SSD2_PWRDIS_R")
	)
	(segment
		(start 115.976654 -92.3036)
		(end 118.3894 -94.716346)
		(width 0.15494)
		(layer "In5.Cu")
		(net "SSD2_PWRDIS_R")
	)
	(segment
		(start 72.841612 -27.914854)
		(end 75.58024 -27.914854)
		(width 0.15494)
		(layer "In5.Cu")
		(net "SSD2_PWRDIS_R")
	)
	(segment
		(start 121.01703 -227.21443)
		(end 121.01703 -241.863626)
		(width 0.15494)
		(layer "In5.Cu")
		(net "SSD2_PWRDIS_R")
	)
	(segment
		(start 91.44 -80.492346)
		(end 91.44 -84.307934)
		(width 0.15494)
		(layer "In5.Cu")
		(net "SSD2_PWRDIS_R")
	)
	(segment
		(start 70.834504 -27.432)
		(end 72.358758 -27.432)
		(width 0.15494)
		(layer "In5.Cu")
		(net "SSD2_PWRDIS_R")
	)
	(segment
		(start 118.778528 -224.975928)
		(end 121.01703 -227.21443)
		(width 0.15494)
		(layer "In5.Cu")
		(net "SSD2_PWRDIS_R")
	)
	(segment
		(start 66.19113 -25.390094)
		(end 68.792598 -25.390094)
		(width 0.15494)
		(layer "In5.Cu")
		(net "SSD2_PWRDIS_R")
	)
	(segment
		(start 123.952 -199.263254)
		(end 119.0752 -204.140054)
		(width 0.15494)
		(layer "In5.Cu")
		(net "SSD2_PWRDIS_R")
	)
	(segment
		(start 91.44 -84.307934)
		(end 99.435666 -92.3036)
		(width 0.15494)
		(layer "In5.Cu")
		(net "SSD2_PWRDIS_R")
	)
	(segment
		(start 121.151142 -125.970538)
		(end 120.4214 -126.70028)
		(width 0.15494)
		(layer "In5.Cu")
		(net "SSD2_PWRDIS_R")
	)
	(segment
		(start 120.5357 -117.697758)
		(end 121.151142 -118.3132)
		(width 0.15494)
		(layer "In5.Cu")
		(net "SSD2_PWRDIS_R")
	)
	(segment
		(start 118.3894 -94.716346)
		(end 118.3894 -101.449378)
		(width 0.15494)
		(layer "In5.Cu")
		(net "SSD2_PWRDIS_R")
	)
	(segment
		(start 68.792598 -25.390094)
		(end 70.834504 -27.432)
		(width 0.15494)
		(layer "In5.Cu")
		(net "SSD2_PWRDIS_R")
	)
	(segment
		(start 88.8238 -77.876146)
		(end 91.44 -80.492346)
		(width 0.15494)
		(layer "In5.Cu")
		(net "SSD2_PWRDIS_R")
	)
	(segment
		(start 120.4214 -182.448454)
		(end 123.952 -185.979054)
		(width 0.15494)
		(layer "In5.Cu")
		(net "SSD2_PWRDIS_R")
	)
	(segment
		(start 121.151142 -118.3132)
		(end 121.151142 -125.970538)
		(width 0.15494)
		(layer "In5.Cu")
		(net "SSD2_PWRDIS_R")
	)
	(segment
		(start 76.134468 -28.469082)
		(end 76.134468 -33.944814)
		(width 0.15494)
		(layer "In5.Cu")
		(net "SSD2_PWRDIS_R")
	)
	(segment
		(start 121.01703 -241.863626)
		(end 121.02465 -241.871246)
		(width 0.15494)
		(layer "In5.Cu")
		(net "SSD2_PWRDIS_R")
	)
	(segment
		(start 118.3894 -101.449378)
		(end 120.5357 -103.595678)
		(width 0.15494)
		(layer "In5.Cu")
		(net "SSD2_PWRDIS_R")
	)
	(segment
		(start 119.0752 -211.193126)
		(end 118.11 -212.158326)
		(width 0.15494)
		(layer "In5.Cu")
		(net "SSD2_PWRDIS_R")
	)
	(segment
		(start 119.0752 -204.140054)
		(end 119.0752 -211.193126)
		(width 0.15494)
		(layer "In5.Cu")
		(net "SSD2_PWRDIS_R")
	)
	(segment
		(start 120.4214 -126.70028)
		(end 120.4214 -182.448454)
		(width 0.15494)
		(layer "In5.Cu")
		(net "SSD2_PWRDIS_R")
	)
	(segment
		(start 76.134468 -33.944814)
		(end 88.8238 -46.634146)
		(width 0.15494)
		(layer "In5.Cu")
		(net "SSD2_PWRDIS_R")
	)
	(segment
		(start 120.5357 -103.595678)
		(end 120.5357 -117.697758)
		(width 0.15494)
		(layer "In5.Cu")
		(net "SSD2_PWRDIS_R")
	)
	(segment
		(start 118.778528 -214.485982)
		(end 118.778528 -224.975928)
		(width 0.15494)
		(layer "In5.Cu")
		(net "SSD2_PWRDIS_R")
	)
	(segment
		(start 118.11 -212.158326)
		(end 118.11 -213.817454)
		(width 0.15494)
		(layer "In5.Cu")
		(net "SSD2_PWRDIS_R")
	)
	(segment
		(start 99.435666 -92.3036)
		(end 115.976654 -92.3036)
		(width 0.15494)
		(layer "In5.Cu")
		(net "SSD2_PWRDIS_R")
	)
	(segment
		(start 252.030738 -252.714252)
		(end 235.780072 -252.714252)
		(width 0.15494)
		(layer "In15.Cu")
		(net "SSD2_PWRDIS_R")
	)
	(segment
		(start 275.11121 -254.48641)
		(end 274.572222 -253.947422)
		(width 0.15494)
		(layer "In15.Cu")
		(net "SSD2_PWRDIS_R")
	)
	(segment
		(start 326.36968 -254.835406)
		(end 325.288148 -253.753874)
		(width 0.15494)
		(layer "In15.Cu")
		(net "SSD2_PWRDIS_R")
	)
	(segment
		(start 337.693762 -251.736352)
		(end 337.693762 -252.194822)
		(width 0.15494)
		(layer "In15.Cu")
		(net "SSD2_PWRDIS_R")
	)
	(segment
		(start 258.064 -253.630684)
		(end 258.064 -253.277624)
		(width 0.15494)
		(layer "In15.Cu")
		(net "SSD2_PWRDIS_R")
	)
	(segment
		(start 257.769106 -252.98273)
		(end 257.73253 -252.98273)
		(width 0.15494)
		(layer "In15.Cu")
		(net "SSD2_PWRDIS_R")
	)
	(segment
		(start 189.598554 -251.22886)
		(end 188.709554 -250.33986)
		(width 0.15494)
		(layer "In15.Cu")
		(net "SSD2_PWRDIS_R")
	)
	(segment
		(start 152.057354 -236.3216)
		(end 150.91283 -236.3216)
		(width 0.15494)
		(layer "In15.Cu")
		(net "SSD2_PWRDIS_R")
	)
	(segment
		(start 307.611272 -253.753874)
		(end 306.878736 -254.48641)
		(width 0.15494)
		(layer "In15.Cu")
		(net "SSD2_PWRDIS_R")
	)
	(segment
		(start 149.195028 -235.6104)
		(end 142.981426 -235.6104)
		(width 0.15494)
		(layer "In15.Cu")
		(net "SSD2_PWRDIS_R")
	)
	(segment
		(start 274.572222 -253.947422)
		(end 258.380738 -253.947422)
		(width 0.15494)
		(layer "In15.Cu")
		(net "SSD2_PWRDIS_R")
	)
	(segment
		(start 142.981426 -235.6104)
		(end 137.302748 -241.289078)
		(width 0.15494)
		(layer "In15.Cu")
		(net "SSD2_PWRDIS_R")
	)
	(segment
		(start 252.1712 -252.57379)
		(end 252.030738 -252.714252)
		(width 0.15494)
		(layer "In15.Cu")
		(net "SSD2_PWRDIS_R")
	)
	(segment
		(start 306.878736 -254.48641)
		(end 275.11121 -254.48641)
		(width 0.15494)
		(layer "In15.Cu")
		(net "SSD2_PWRDIS_R")
	)
	(segment
		(start 230.021892 -252.039882)
		(end 228.78034 -250.79833)
		(width 0.15494)
		(layer "In15.Cu")
		(net "SSD2_PWRDIS_R")
	)
	(segment
		(start 224.556066 -251.22886)
		(end 189.598554 -251.22886)
		(width 0.15494)
		(layer "In15.Cu")
		(net "SSD2_PWRDIS_R")
	)
	(segment
		(start 337.693762 -252.194822)
		(end 335.053178 -254.835406)
		(width 0.15494)
		(layer "In15.Cu")
		(net "SSD2_PWRDIS_R")
	)
	(segment
		(start 137.302748 -241.289078)
		(end 121.606818 -241.289078)
		(width 0.15494)
		(layer "In15.Cu")
		(net "SSD2_PWRDIS_R")
	)
	(segment
		(start 121.606818 -241.289078)
		(end 121.02465 -241.871246)
		(width 0.15494)
		(layer "In15.Cu")
		(net "SSD2_PWRDIS_R")
	)
	(segment
		(start 224.986596 -250.79833)
		(end 224.556066 -251.22886)
		(width 0.15494)
		(layer "In15.Cu")
		(net "SSD2_PWRDIS_R")
	)
	(segment
		(start 153.222452 -236.8042)
		(end 152.057354 -236.3216)
		(width 0.15494)
		(layer "In15.Cu")
		(net "SSD2_PWRDIS_R")
	)
	(segment
		(start 258.380738 -253.947422)
		(end 258.064 -253.630684)
		(width 0.15494)
		(layer "In15.Cu")
		(net "SSD2_PWRDIS_R")
	)
	(segment
		(start 160.16986 -242.86083)
		(end 154.11323 -236.8042)
		(width 0.15494)
		(layer "In15.Cu")
		(net "SSD2_PWRDIS_R")
	)
	(segment
		(start 235.105702 -252.039882)
		(end 230.021892 -252.039882)
		(width 0.15494)
		(layer "In15.Cu")
		(net "SSD2_PWRDIS_R")
	)
	(segment
		(start 257.32359 -252.57379)
		(end 252.1712 -252.57379)
		(width 0.15494)
		(layer "In15.Cu")
		(net "SSD2_PWRDIS_R")
	)
	(segment
		(start 150.91283 -236.3216)
		(end 149.195028 -235.6104)
		(width 0.15494)
		(layer "In15.Cu")
		(net "SSD2_PWRDIS_R")
	)
	(segment
		(start 228.78034 -250.79833)
		(end 224.986596 -250.79833)
		(width 0.15494)
		(layer "In15.Cu")
		(net "SSD2_PWRDIS_R")
	)
	(segment
		(start 185.59907 -250.33986)
		(end 178.12004 -242.86083)
		(width 0.15494)
		(layer "In15.Cu")
		(net "SSD2_PWRDIS_R")
	)
	(segment
		(start 258.064 -253.277624)
		(end 257.769106 -252.98273)
		(width 0.15494)
		(layer "In15.Cu")
		(net "SSD2_PWRDIS_R")
	)
	(segment
		(start 178.12004 -242.86083)
		(end 160.16986 -242.86083)
		(width 0.15494)
		(layer "In15.Cu")
		(net "SSD2_PWRDIS_R")
	)
	(segment
		(start 235.780072 -252.714252)
		(end 235.105702 -252.039882)
		(width 0.15494)
		(layer "In15.Cu")
		(net "SSD2_PWRDIS_R")
	)
	(segment
		(start 335.053178 -254.835406)
		(end 326.36968 -254.835406)
		(width 0.15494)
		(layer "In15.Cu")
		(net "SSD2_PWRDIS_R")
	)
	(segment
		(start 325.288148 -253.753874)
		(end 307.611272 -253.753874)
		(width 0.15494)
		(layer "In15.Cu")
		(net "SSD2_PWRDIS_R")
	)
	(segment
		(start 188.709554 -250.33986)
		(end 185.59907 -250.33986)
		(width 0.15494)
		(layer "In15.Cu")
		(net "SSD2_PWRDIS_R")
	)
	(segment
		(start 257.73253 -252.98273)
		(end 257.32359 -252.57379)
		(width 0.15494)
		(layer "In15.Cu")
		(net "SSD2_PWRDIS_R")
	)
	(segment
		(start 154.11323 -236.8042)
		(end 153.222452 -236.8042)
		(width 0.15494)
		(layer "In15.Cu")
		(net "SSD2_PWRDIS_R")
	)
	(segment
		(start 282.081986 -35.876738)
		(end 281.370786 -35.876738)
		(width 0.13208)
		(layer "F.Cu")
		(net "PWRGD_P3V3_SSD10_R")
	)
	(segment
		(start 284.786832 -35.6108)
		(end 282.347924 -35.6108)
		(width 0.13208)
		(layer "F.Cu")
		(net "PWRGD_P3V3_SSD10_R")
	)
	(segment
		(start 282.347924 -35.6108)
		(end 282.081986 -35.876738)
		(width 0.13208)
		(layer "F.Cu")
		(net "PWRGD_P3V3_SSD10_R")
	)
	(segment
		(start 338.093812 -211.98713)
		(end 337.694016 -211.587334)
		(width 0.13208)
		(layer "F.Cu")
		(net "PWRGD_P3V3_SSD10_R")
	)
	(segment
		(start 285.795212 -36.232592)
		(end 285.408624 -36.232592)
		(width 0.13208)
		(layer "F.Cu")
		(net "PWRGD_P3V3_SSD10_R")
	)
	(segment
		(start 292.810946 -61.386974)
		(end 292.810946 -62.051438)
		(width 0.13208)
		(layer "F.Cu")
		(net "PWRGD_P3V3_SSD10_R")
	)
	(segment
		(start 285.408624 -36.232592)
		(end 284.786832 -35.6108)
		(width 0.13208)
		(layer "F.Cu")
		(net "PWRGD_P3V3_SSD10_R")
	)
	(segment
		(start 280.627836 -35.876738)
		(end 281.370786 -35.876738)
		(width 0.13208)
		(layer "F.Cu")
		(net "PWRGD_P3V3_SSD10_R")
	)
	(via
		(at 292.810946 -62.051438)
		(size 0.508)
		(drill 0.254)
		(layers "F.Cu" "B.Cu")
		(net "PWRGD_P3V3_SSD10_R")
	)
	(via
		(at 358.09682 -88.302846)
		(size 0.508)
		(drill 0.254)
		(layers "F.Cu" "B.Cu")
		(net "PWRGD_P3V3_SSD10_R")
	)
	(via
		(at 281.370786 -35.876738)
		(size 0.508)
		(drill 0.254)
		(layers "F.Cu" "B.Cu")
		(net "PWRGD_P3V3_SSD10_R")
	)
	(via
		(at 337.694016 -211.587334)
		(size 0.4572)
		(drill 0.254)
		(layers "F.Cu" "B.Cu")
		(net "PWRGD_P3V3_SSD10_R")
	)
	(via
		(at 300.070266 -80.276446)
		(size 0.508)
		(drill 0.254)
		(layers "F.Cu" "B.Cu")
		(net "PWRGD_P3V3_SSD10_R")
	)
	(segment
		(start 300.070266 -80.276446)
		(end 299.592746 -79.798926)
		(width 0.15494)
		(layer "In5.Cu")
		(net "PWRGD_P3V3_SSD10_R")
	)
	(segment
		(start 294.05072 -61.32068)
		(end 293.319962 -62.051438)
		(width 0.15494)
		(layer "In5.Cu")
		(net "PWRGD_P3V3_SSD10_R")
	)
	(segment
		(start 293.739824 -66.495676)
		(end 292.810946 -65.566798)
		(width 0.15494)
		(layer "In5.Cu")
		(net "PWRGD_P3V3_SSD10_R")
	)
	(segment
		(start 299.592746 -79.798926)
		(end 297.307 -79.798926)
		(width 0.15494)
		(layer "In5.Cu")
		(net "PWRGD_P3V3_SSD10_R")
	)
	(segment
		(start 293.739824 -76.23175)
		(end 293.739824 -66.495676)
		(width 0.15494)
		(layer "In5.Cu")
		(net "PWRGD_P3V3_SSD10_R")
	)
	(segment
		(start 294.05072 -45.865034)
		(end 294.05072 -61.32068)
		(width 0.15494)
		(layer "In5.Cu")
		(net "PWRGD_P3V3_SSD10_R")
	)
	(segment
		(start 284.062424 -35.876738)
		(end 294.05072 -45.865034)
		(width 0.15494)
		(layer "In5.Cu")
		(net "PWRGD_P3V3_SSD10_R")
	)
	(segment
		(start 292.810946 -65.566798)
		(end 292.810946 -62.051438)
		(width 0.15494)
		(layer "In5.Cu")
		(net "PWRGD_P3V3_SSD10_R")
	)
	(segment
		(start 293.319962 -62.051438)
		(end 292.810946 -62.051438)
		(width 0.15494)
		(layer "In5.Cu")
		(net "PWRGD_P3V3_SSD10_R")
	)
	(segment
		(start 297.307 -79.798926)
		(end 293.739824 -76.23175)
		(width 0.15494)
		(layer "In5.Cu")
		(net "PWRGD_P3V3_SSD10_R")
	)
	(segment
		(start 281.370786 -35.876738)
		(end 284.062424 -35.876738)
		(width 0.15494)
		(layer "In5.Cu")
		(net "PWRGD_P3V3_SSD10_R")
	)
	(segment
		(start 353.231958 -187.725812)
		(end 353.231958 -170.986958)
		(width 0.15494)
		(layer "In9.Cu")
		(net "PWRGD_P3V3_SSD10_R")
	)
	(segment
		(start 345.189556 -204.893164)
		(end 345.189556 -203.907644)
		(width 0.15494)
		(layer "In9.Cu")
		(net "PWRGD_P3V3_SSD10_R")
	)
	(segment
		(start 351.2058 -160.1724)
		(end 351.3836 -159.9946)
		(width 0.15494)
		(layer "In9.Cu")
		(net "PWRGD_P3V3_SSD10_R")
	)
	(segment
		(start 340.232746 -207.694276)
		(end 343.460324 -207.694276)
		(width 0.15494)
		(layer "In9.Cu")
		(net "PWRGD_P3V3_SSD10_R")
	)
	(segment
		(start 352.6536 -116.495576)
		(end 361.4928 -107.656376)
		(width 0.15494)
		(layer "In9.Cu")
		(net "PWRGD_P3V3_SSD10_R")
	)
	(segment
		(start 355.8286 -197.0278)
		(end 355.8286 -190.322454)
		(width 0.15494)
		(layer "In9.Cu")
		(net "PWRGD_P3V3_SSD10_R")
	)
	(segment
		(start 350.8248 -140.589)
		(end 350.8248 -124.6378)
		(width 0.15494)
		(layer "In9.Cu")
		(net "PWRGD_P3V3_SSD10_R")
	)
	(segment
		(start 337.694016 -210.233006)
		(end 340.232746 -207.694276)
		(width 0.15494)
		(layer "In9.Cu")
		(net "PWRGD_P3V3_SSD10_R")
	)
	(segment
		(start 351.9678 -153.3906)
		(end 350.7486 -152.1714)
		(width 0.15494)
		(layer "In9.Cu")
		(net "PWRGD_P3V3_SSD10_R")
	)
	(segment
		(start 351.3836 -159.9946)
		(end 351.3836 -157.8356)
		(width 0.15494)
		(layer "In9.Cu")
		(net "PWRGD_P3V3_SSD10_R")
	)
	(segment
		(start 337.694016 -211.587334)
		(end 337.694016 -210.233006)
		(width 0.15494)
		(layer "In9.Cu")
		(net "PWRGD_P3V3_SSD10_R")
	)
	(segment
		(start 351.2058 -160.720532)
		(end 351.2058 -160.1724)
		(width 0.15494)
		(layer "In9.Cu")
		(net "PWRGD_P3V3_SSD10_R")
	)
	(segment
		(start 353.231958 -170.986958)
		(end 351.8916 -169.6466)
		(width 0.15494)
		(layer "In9.Cu")
		(net "PWRGD_P3V3_SSD10_R")
	)
	(segment
		(start 355.8286 -190.322454)
		(end 353.231958 -187.725812)
		(width 0.15494)
		(layer "In9.Cu")
		(net "PWRGD_P3V3_SSD10_R")
	)
	(segment
		(start 344.696796 -206.457804)
		(end 344.696796 -205.385924)
		(width 0.15494)
		(layer "In9.Cu")
		(net "PWRGD_P3V3_SSD10_R")
	)
	(segment
		(start 350.8248 -124.6378)
		(end 352.6536 -122.809)
		(width 0.15494)
		(layer "In9.Cu")
		(net "PWRGD_P3V3_SSD10_R")
	)
	(segment
		(start 352.6536 -122.809)
		(end 352.6536 -116.495576)
		(width 0.15494)
		(layer "In9.Cu")
		(net "PWRGD_P3V3_SSD10_R")
	)
	(segment
		(start 350.7486 -152.1714)
		(end 350.7486 -140.6652)
		(width 0.15494)
		(layer "In9.Cu")
		(net "PWRGD_P3V3_SSD10_R")
	)
	(segment
		(start 350.7486 -140.6652)
		(end 350.8248 -140.589)
		(width 0.15494)
		(layer "In9.Cu")
		(net "PWRGD_P3V3_SSD10_R")
	)
	(segment
		(start 351.8916 -161.406332)
		(end 351.2058 -160.720532)
		(width 0.15494)
		(layer "In9.Cu")
		(net "PWRGD_P3V3_SSD10_R")
	)
	(segment
		(start 345.189556 -203.907644)
		(end 346.329508 -202.767692)
		(width 0.15494)
		(layer "In9.Cu")
		(net "PWRGD_P3V3_SSD10_R")
	)
	(segment
		(start 361.4928 -91.698826)
		(end 358.09682 -88.302846)
		(width 0.15494)
		(layer "In9.Cu")
		(net "PWRGD_P3V3_SSD10_R")
	)
	(segment
		(start 350.088708 -202.767692)
		(end 355.8286 -197.0278)
		(width 0.15494)
		(layer "In9.Cu")
		(net "PWRGD_P3V3_SSD10_R")
	)
	(segment
		(start 351.8916 -169.6466)
		(end 351.8916 -161.406332)
		(width 0.15494)
		(layer "In9.Cu")
		(net "PWRGD_P3V3_SSD10_R")
	)
	(segment
		(start 343.460324 -207.694276)
		(end 344.696796 -206.457804)
		(width 0.15494)
		(layer "In9.Cu")
		(net "PWRGD_P3V3_SSD10_R")
	)
	(segment
		(start 351.3836 -157.8356)
		(end 351.9678 -157.2514)
		(width 0.15494)
		(layer "In9.Cu")
		(net "PWRGD_P3V3_SSD10_R")
	)
	(segment
		(start 351.9678 -157.2514)
		(end 351.9678 -153.3906)
		(width 0.15494)
		(layer "In9.Cu")
		(net "PWRGD_P3V3_SSD10_R")
	)
	(segment
		(start 361.4928 -107.656376)
		(end 361.4928 -91.698826)
		(width 0.15494)
		(layer "In9.Cu")
		(net "PWRGD_P3V3_SSD10_R")
	)
	(segment
		(start 346.329508 -202.767692)
		(end 350.088708 -202.767692)
		(width 0.15494)
		(layer "In9.Cu")
		(net "PWRGD_P3V3_SSD10_R")
	)
	(segment
		(start 344.696796 -205.385924)
		(end 345.189556 -204.893164)
		(width 0.15494)
		(layer "In9.Cu")
		(net "PWRGD_P3V3_SSD10_R")
	)
	(segment
		(start 302.140112 -78.2066)
		(end 311.302146 -78.2066)
		(width 0.15494)
		(layer "In15.Cu")
		(net "PWRGD_P3V3_SSD10_R")
	)
	(segment
		(start 300.070266 -80.276446)
		(end 302.140112 -78.2066)
		(width 0.15494)
		(layer "In15.Cu")
		(net "PWRGD_P3V3_SSD10_R")
	)
	(segment
		(start 329.5396 -79.629)
		(end 331.2668 -81.3562)
		(width 0.15494)
		(layer "In15.Cu")
		(net "PWRGD_P3V3_SSD10_R")
	)
	(segment
		(start 351.2312 -87.6046)
		(end 353.250754 -87.6046)
		(width 0.15494)
		(layer "In15.Cu")
		(net "PWRGD_P3V3_SSD10_R")
	)
	(segment
		(start 353.250754 -87.6046)
		(end 353.949 -88.302846)
		(width 0.15494)
		(layer "In15.Cu")
		(net "PWRGD_P3V3_SSD10_R")
	)
	(segment
		(start 353.949 -88.302846)
		(end 358.09682 -88.302846)
		(width 0.15494)
		(layer "In15.Cu")
		(net "PWRGD_P3V3_SSD10_R")
	)
	(segment
		(start 312.83275 -76.675996)
		(end 317.594996 -76.675996)
		(width 0.15494)
		(layer "In15.Cu")
		(net "PWRGD_P3V3_SSD10_R")
	)
	(segment
		(start 350.419416 -86.462362)
		(end 350.419416 -86.792816)
		(width 0.15494)
		(layer "In15.Cu")
		(net "PWRGD_P3V3_SSD10_R")
	)
	(segment
		(start 345.313254 -81.3562)
		(end 350.419416 -86.462362)
		(width 0.15494)
		(layer "In15.Cu")
		(net "PWRGD_P3V3_SSD10_R")
	)
	(segment
		(start 320.548 -79.629)
		(end 329.5396 -79.629)
		(width 0.15494)
		(layer "In15.Cu")
		(net "PWRGD_P3V3_SSD10_R")
	)
	(segment
		(start 317.594996 -76.675996)
		(end 320.548 -79.629)
		(width 0.15494)
		(layer "In15.Cu")
		(net "PWRGD_P3V3_SSD10_R")
	)
	(segment
		(start 311.302146 -78.2066)
		(end 312.83275 -76.675996)
		(width 0.15494)
		(layer "In15.Cu")
		(net "PWRGD_P3V3_SSD10_R")
	)
	(segment
		(start 331.2668 -81.3562)
		(end 345.313254 -81.3562)
		(width 0.15494)
		(layer "In15.Cu")
		(net "PWRGD_P3V3_SSD10_R")
	)
	(segment
		(start 350.419416 -86.792816)
		(end 351.2312 -87.6046)
		(width 0.15494)
		(layer "In15.Cu")
		(net "PWRGD_P3V3_SSD10_R")
	)
	(segment
		(start 109.58195 -80.222344)
		(end 109.91088 -80.551274)
		(width 0.13462)
		(layer "F.Cu")
		(net "CLK_100M_DB800ZL_SSD2_DP")
	)
	(segment
		(start 109.91088 -80.551274)
		(end 109.91088 -82.530696)
		(width 0.13462)
		(layer "F.Cu")
		(net "CLK_100M_DB800ZL_SSD2_DP")
	)
	(segment
		(start 109.838998 -82.602578)
		(end 109.838998 -83.029044)
		(width 0.13462)
		(layer "F.Cu")
		(net "CLK_100M_DB800ZL_SSD2_DP")
	)
	(segment
		(start 109.91088 -82.530696)
		(end 109.838998 -82.602578)
		(width 0.13462)
		(layer "F.Cu")
		(net "CLK_100M_DB800ZL_SSD2_DP")
	)
	(segment
		(start 37.799518 -299.699934)
		(end 37.324538 -299.224954)
		(width 0.1143)
		(layer "F.Cu")
		(net "CLK_100M_PEX0_REF_R_DP")
	)
	(segment
		(start 229.0191 -156.664152)
		(end 229.0191 -157.622748)
		(width 0.1143)
		(layer "F.Cu")
		(net "CLK_100M_PEX0_REF_R_DP")
	)
	(segment
		(start 37.799772 -299.699934)
		(end 37.799518 -299.699934)
		(width 0.1143)
		(layer "F.Cu")
		(net "CLK_100M_PEX0_REF_R_DP")
	)
	(segment
		(start 228.695504 -156.340556)
		(end 229.0191 -156.664152)
		(width 0.1143)
		(layer "F.Cu")
		(net "CLK_100M_PEX0_REF_R_DP")
	)
	(segment
		(start 229.0191 -157.622748)
		(end 228.771704 -157.870144)
		(width 0.1143)
		(layer "F.Cu")
		(net "CLK_100M_PEX0_REF_R_DP")
	)
	(via
		(at 37.324538 -299.224954)
		(size 0.4064)
		(drill 0.2032)
		(layers "F.Cu" "B.Cu")
		(net "CLK_100M_PEX0_REF_R_DP")
	)
	(via
		(at 228.771704 -157.870144)
		(size 0.508)
		(drill 0.254)
		(layers "F.Cu" "B.Cu")
		(net "CLK_100M_PEX0_REF_R_DP")
	)
	(segment
		(start 70.4088 -220.6752)
		(end 94.869 -196.215)
		(width 0.1143)
		(layer "B.Cu")
		(net "CLK_100M_PEX0_REF_R_DP")
	)
	(segment
		(start 35.02025 -299.98035)
		(end 33.3375 -298.2976)
		(width 0.1143)
		(layer "B.Cu")
		(net "CLK_100M_PEX0_REF_R_DP")
	)
	(segment
		(start 180.02758 -186.7789)
		(end 208.223104 -158.583376)
		(width 0.1143)
		(layer "B.Cu")
		(net "CLK_100M_PEX0_REF_R_DP")
	)
	(segment
		(start 36.735004 -299.8978)
		(end 35.43935 -299.8978)
		(width 0.0889)
		(layer "B.Cu")
		(net "CLK_100M_PEX0_REF_R_DP")
	)
	(segment
		(start 36.944808 -299.687996)
		(end 36.735004 -299.8978)
		(width 0.0889)
		(layer "B.Cu")
		(net "CLK_100M_PEX0_REF_R_DP")
	)
	(segment
		(start 36.944808 -299.313854)
		(end 36.944808 -299.687996)
		(width 0.0889)
		(layer "B.Cu")
		(net "CLK_100M_PEX0_REF_R_DP")
	)
	(segment
		(start 108.37926 -193.6623)
		(end 109.290866 -193.6623)
		(width 0.1143)
		(layer "B.Cu")
		(net "CLK_100M_PEX0_REF_R_DP")
	)
	(segment
		(start 35.43935 -299.8978)
		(end 35.3568 -299.98035)
		(width 0.0889)
		(layer "B.Cu")
		(net "CLK_100M_PEX0_REF_R_DP")
	)
	(segment
		(start 107.667552 -194.374008)
		(end 108.37926 -193.6623)
		(width 0.1143)
		(layer "B.Cu")
		(net "CLK_100M_PEX0_REF_R_DP")
	)
	(segment
		(start 140.819886 -186.7789)
		(end 180.02758 -186.7789)
		(width 0.1143)
		(layer "B.Cu")
		(net "CLK_100M_PEX0_REF_R_DP")
	)
	(segment
		(start 96.5962 -196.215)
		(end 98.437192 -194.374008)
		(width 0.1143)
		(layer "B.Cu")
		(net "CLK_100M_PEX0_REF_R_DP")
	)
	(segment
		(start 24.849074 -277.2537)
		(end 22.173692 -274.578318)
		(width 0.1143)
		(layer "B.Cu")
		(net "CLK_100M_PEX0_REF_R_DP")
	)
	(segment
		(start 98.437192 -194.374008)
		(end 107.667552 -194.374008)
		(width 0.1143)
		(layer "B.Cu")
		(net "CLK_100M_PEX0_REF_R_DP")
	)
	(segment
		(start 22.173692 -267.642086)
		(end 19.3675 -260.867398)
		(width 0.1143)
		(layer "B.Cu")
		(net "CLK_100M_PEX0_REF_R_DP")
	)
	(segment
		(start 123.2408 -188.3664)
		(end 125.1204 -190.246)
		(width 0.1143)
		(layer "B.Cu")
		(net "CLK_100M_PEX0_REF_R_DP")
	)
	(segment
		(start 37.033708 -299.224954)
		(end 36.944808 -299.313854)
		(width 0.0889)
		(layer "B.Cu")
		(net "CLK_100M_PEX0_REF_R_DP")
	)
	(segment
		(start 22.173692 -274.578318)
		(end 22.173692 -267.642086)
		(width 0.1143)
		(layer "B.Cu")
		(net "CLK_100M_PEX0_REF_R_DP")
	)
	(segment
		(start 33.3375 -298.2976)
		(end 31.538672 -298.2976)
		(width 0.1143)
		(layer "B.Cu")
		(net "CLK_100M_PEX0_REF_R_DP")
	)
	(segment
		(start 125.1204 -190.246)
		(end 137.352786 -190.246)
		(width 0.1143)
		(layer "B.Cu")
		(net "CLK_100M_PEX0_REF_R_DP")
	)
	(segment
		(start 114.586766 -188.3664)
		(end 123.2408 -188.3664)
		(width 0.1143)
		(layer "B.Cu")
		(net "CLK_100M_PEX0_REF_R_DP")
	)
	(segment
		(start 229.019862 -158.118302)
		(end 228.771704 -157.870144)
		(width 0.1143)
		(layer "B.Cu")
		(net "CLK_100M_PEX0_REF_R_DP")
	)
	(segment
		(start 19.3675 -250.956064)
		(end 49.648364 -220.6752)
		(width 0.1143)
		(layer "B.Cu")
		(net "CLK_100M_PEX0_REF_R_DP")
	)
	(segment
		(start 19.3675 -260.867398)
		(end 19.3675 -250.956064)
		(width 0.1143)
		(layer "B.Cu")
		(net "CLK_100M_PEX0_REF_R_DP")
	)
	(segment
		(start 49.648364 -220.6752)
		(end 70.4088 -220.6752)
		(width 0.1143)
		(layer "B.Cu")
		(net "CLK_100M_PEX0_REF_R_DP")
	)
	(segment
		(start 35.334702 -299.98035)
		(end 35.02025 -299.98035)
		(width 0.1143)
		(layer "B.Cu")
		(net "CLK_100M_PEX0_REF_R_DP")
	)
	(segment
		(start 35.3568 -299.98035)
		(end 35.334702 -299.98035)
		(width 0.0889)
		(layer "B.Cu")
		(net "CLK_100M_PEX0_REF_R_DP")
	)
	(segment
		(start 31.538672 -298.2976)
		(end 30.264608 -297.023536)
		(width 0.1143)
		(layer "B.Cu")
		(net "CLK_100M_PEX0_REF_R_DP")
	)
	(segment
		(start 94.869 -196.215)
		(end 96.5962 -196.215)
		(width 0.1143)
		(layer "B.Cu")
		(net "CLK_100M_PEX0_REF_R_DP")
	)
	(segment
		(start 24.849074 -296.019728)
		(end 24.849074 -277.2537)
		(width 0.1143)
		(layer "B.Cu")
		(net "CLK_100M_PEX0_REF_R_DP")
	)
	(segment
		(start 109.290866 -193.6623)
		(end 114.586766 -188.3664)
		(width 0.1143)
		(layer "B.Cu")
		(net "CLK_100M_PEX0_REF_R_DP")
	)
	(segment
		(start 30.264608 -297.023536)
		(end 25.852882 -297.023536)
		(width 0.1143)
		(layer "B.Cu")
		(net "CLK_100M_PEX0_REF_R_DP")
	)
	(segment
		(start 37.324538 -299.224954)
		(end 37.033708 -299.224954)
		(width 0.0889)
		(layer "B.Cu")
		(net "CLK_100M_PEX0_REF_R_DP")
	)
	(segment
		(start 137.352786 -190.246)
		(end 140.819886 -186.7789)
		(width 0.1143)
		(layer "B.Cu")
		(net "CLK_100M_PEX0_REF_R_DP")
	)
	(segment
		(start 229.019862 -158.393384)
		(end 229.019862 -158.118302)
		(width 0.1143)
		(layer "B.Cu")
		(net "CLK_100M_PEX0_REF_R_DP")
	)
	(segment
		(start 208.223104 -158.583376)
		(end 228.82987 -158.583376)
		(width 0.1143)
		(layer "B.Cu")
		(net "CLK_100M_PEX0_REF_R_DP")
	)
	(segment
		(start 228.82987 -158.583376)
		(end 229.019862 -158.393384)
		(width 0.1143)
		(layer "B.Cu")
		(net "CLK_100M_PEX0_REF_R_DP")
	)
	(segment
		(start 25.852882 -297.023536)
		(end 24.849074 -296.019728)
		(width 0.1143)
		(layer "B.Cu")
		(net "CLK_100M_PEX0_REF_R_DP")
	)
	(segment
		(start 130.510534 -183.885078)
		(end 130.510534 -183.484266)
		(width 0.13462)
		(layer "F.Cu")
		(net "CLK_100M_DB2000QL_GPU_REF2_DP")
	)
	(segment
		(start 130.510534 -183.484266)
		(end 131.851908 -182.142892)
		(width 0.13462)
		(layer "F.Cu")
		(net "CLK_100M_DB2000QL_GPU_REF2_DP")
	)
	(segment
		(start 131.851908 -180.519578)
		(end 131.971034 -180.400452)
		(width 0.13462)
		(layer "F.Cu")
		(net "CLK_100M_DB2000QL_GPU_REF2_DP")
	)
	(segment
		(start 131.851908 -182.142892)
		(end 131.851908 -180.519578)
		(width 0.13462)
		(layer "F.Cu")
		(net "CLK_100M_DB2000QL_GPU_REF2_DP")
	)
	(segment
		(start 130.88239 -184.256934)
		(end 130.510534 -183.885078)
		(width 0.13462)
		(layer "F.Cu")
		(net "CLK_100M_DB2000QL_GPU_REF2_DP")
	)
	(segment
		(start 222.754952 -67.830192)
		(end 222.754952 -62.250828)
		(width 0.13208)
		(layer "F.Cu")
		(net "SMB_BIC_I2C6_MUX_SSD_0_7_ADC_R_SDA")
	)
	(segment
		(start 223.634808 -61.370972)
		(end 223.634808 -49.663096)
		(width 0.13208)
		(layer "F.Cu")
		(net "SMB_BIC_I2C6_MUX_SSD_0_7_ADC_R_SDA")
	)
	(segment
		(start 278.885904 -86.481158)
		(end 278.885904 -83.051904)
		(width 0.13208)
		(layer "F.Cu")
		(net "SMB_BIC_I2C6_MUX_SSD_0_7_ADC_R_SDA")
	)
	(segment
		(start 227.100384 -72.175624)
		(end 222.754952 -67.830192)
		(width 0.13208)
		(layer "F.Cu")
		(net "SMB_BIC_I2C6_MUX_SSD_0_7_ADC_R_SDA")
	)
	(segment
		(start 376.712734 -81.9658)
		(end 377.53544 -81.9658)
		(width 0.13208)
		(layer "F.Cu")
		(net "SMB_BIC_I2C6_MUX_SSD_0_7_ADC_R_SDA")
	)
	(segment
		(start 238.932466 -72.175624)
		(end 227.100384 -72.175624)
		(width 0.13208)
		(layer "F.Cu")
		(net "SMB_BIC_I2C6_MUX_SSD_0_7_ADC_R_SDA")
	)
	(segment
		(start 221.415102 -48.93691)
		(end 220.74378 -48.93691)
		(width 0.13208)
		(layer "F.Cu")
		(net "SMB_BIC_I2C6_MUX_SSD_0_7_ADC_R_SDA")
	)
	(segment
		(start 223.634808 -49.663096)
		(end 222.908622 -48.93691)
		(width 0.13208)
		(layer "F.Cu")
		(net "SMB_BIC_I2C6_MUX_SSD_0_7_ADC_R_SDA")
	)
	(segment
		(start 142.743936 -48.93691)
		(end 143.415258 -48.93691)
		(width 0.13208)
		(layer "F.Cu")
		(net "SMB_BIC_I2C6_MUX_SSD_0_7_ADC_R_SDA")
	)
	(segment
		(start 377.53544 -81.9658)
		(end 378.452634 -81.9658)
		(width 0.13208)
		(layer "F.Cu")
		(net "SMB_BIC_I2C6_MUX_SSD_0_7_ADC_R_SDA")
	)
	(segment
		(start 239.568482 -71.539608)
		(end 238.932466 -72.175624)
		(width 0.13208)
		(layer "F.Cu")
		(net "SMB_BIC_I2C6_MUX_SSD_0_7_ADC_R_SDA")
	)
	(segment
		(start 222.908622 -48.93691)
		(end 221.415102 -48.93691)
		(width 0.13208)
		(layer "F.Cu")
		(net "SMB_BIC_I2C6_MUX_SSD_0_7_ADC_R_SDA")
	)
	(segment
		(start 270.133572 -74.299572)
		(end 260.31444 -74.299572)
		(width 0.13208)
		(layer "F.Cu")
		(net "SMB_BIC_I2C6_MUX_SSD_0_7_ADC_R_SDA")
	)
	(segment
		(start 194.743832 -48.93691)
		(end 195.415154 -48.93691)
		(width 0.13208)
		(layer "F.Cu")
		(net "SMB_BIC_I2C6_MUX_SSD_0_7_ADC_R_SDA")
	)
	(segment
		(start 78.643734 -48.93691)
		(end 79.315056 -48.93691)
		(width 0.13208)
		(layer "F.Cu")
		(net "SMB_BIC_I2C6_MUX_SSD_0_7_ADC_R_SDA")
	)
	(segment
		(start 222.754952 -62.250828)
		(end 223.634808 -61.370972)
		(width 0.13208)
		(layer "F.Cu")
		(net "SMB_BIC_I2C6_MUX_SSD_0_7_ADC_R_SDA")
	)
	(segment
		(start 278.885904 -83.051904)
		(end 270.133572 -74.299572)
		(width 0.13208)
		(layer "F.Cu")
		(net "SMB_BIC_I2C6_MUX_SSD_0_7_ADC_R_SDA")
	)
	(segment
		(start 168.743884 -48.93691)
		(end 169.415206 -48.93691)
		(width 0.13208)
		(layer "F.Cu")
		(net "SMB_BIC_I2C6_MUX_SSD_0_7_ADC_R_SDA")
	)
	(segment
		(start 260.31444 -74.299572)
		(end 259.741416 -73.726548)
		(width 0.13208)
		(layer "F.Cu")
		(net "SMB_BIC_I2C6_MUX_SSD_0_7_ADC_R_SDA")
	)
	(segment
		(start 26.643838 -48.93691)
		(end 27.31516 -48.93691)
		(width 0.13208)
		(layer "F.Cu")
		(net "SMB_BIC_I2C6_MUX_SSD_0_7_ADC_R_SDA")
	)
	(segment
		(start 104.643682 -48.93691)
		(end 105.315004 -48.93691)
		(width 0.13208)
		(layer "F.Cu")
		(net "SMB_BIC_I2C6_MUX_SSD_0_7_ADC_R_SDA")
	)
	(segment
		(start 52.643786 -48.93691)
		(end 53.315108 -48.93691)
		(width 0.13208)
		(layer "F.Cu")
		(net "SMB_BIC_I2C6_MUX_SSD_0_7_ADC_R_SDA")
	)
	(via
		(at 53.315108 -48.93691)
		(size 0.508)
		(drill 0.254)
		(layers "F.Cu" "B.Cu")
		(net "SMB_BIC_I2C6_MUX_SSD_0_7_ADC_R_SDA")
	)
	(via
		(at 169.415206 -48.93691)
		(size 0.508)
		(drill 0.254)
		(layers "F.Cu" "B.Cu")
		(net "SMB_BIC_I2C6_MUX_SSD_0_7_ADC_R_SDA")
	)
	(via
		(at 27.31516 -48.93691)
		(size 0.508)
		(drill 0.254)
		(layers "F.Cu" "B.Cu")
		(net "SMB_BIC_I2C6_MUX_SSD_0_7_ADC_R_SDA")
	)
	(via
		(at 278.885904 -86.481158)
		(size 0.508)
		(drill 0.254)
		(layers "F.Cu" "B.Cu")
		(net "SMB_BIC_I2C6_MUX_SSD_0_7_ADC_R_SDA")
	)
	(via
		(at 105.315004 -48.93691)
		(size 0.508)
		(drill 0.254)
		(layers "F.Cu" "B.Cu")
		(net "SMB_BIC_I2C6_MUX_SSD_0_7_ADC_R_SDA")
	)
	(via
		(at 79.315056 -48.93691)
		(size 0.508)
		(drill 0.254)
		(layers "F.Cu" "B.Cu")
		(net "SMB_BIC_I2C6_MUX_SSD_0_7_ADC_R_SDA")
	)
	(via
		(at 195.415154 -48.93691)
		(size 0.508)
		(drill 0.254)
		(layers "F.Cu" "B.Cu")
		(net "SMB_BIC_I2C6_MUX_SSD_0_7_ADC_R_SDA")
	)
	(via
		(at 221.415102 -48.93691)
		(size 0.508)
		(drill 0.254)
		(layers "F.Cu" "B.Cu")
		(net "SMB_BIC_I2C6_MUX_SSD_0_7_ADC_R_SDA")
	)
	(via
		(at 259.741416 -73.726548)
		(size 0.508)
		(drill 0.254)
		(layers "F.Cu" "B.Cu")
		(net "SMB_BIC_I2C6_MUX_SSD_0_7_ADC_R_SDA")
	)
	(via
		(at 377.53544 -81.9658)
		(size 0.508)
		(drill 0.254)
		(layers "F.Cu" "B.Cu")
		(net "SMB_BIC_I2C6_MUX_SSD_0_7_ADC_R_SDA")
	)
	(via
		(at 239.568482 -71.539608)
		(size 0.508)
		(drill 0.254)
		(layers "F.Cu" "B.Cu")
		(net "SMB_BIC_I2C6_MUX_SSD_0_7_ADC_R_SDA")
	)
	(via
		(at 143.415258 -48.93691)
		(size 0.508)
		(drill 0.254)
		(layers "F.Cu" "B.Cu")
		(net "SMB_BIC_I2C6_MUX_SSD_0_7_ADC_R_SDA")
	)
	(segment
		(start 106.322622 -48.32731)
		(end 106.335322 -48.31461)
		(width 0.13208)
		(layer "B.Cu")
		(net "SMB_BIC_I2C6_MUX_SSD_0_7_ADC_R_SDA")
	)
	(segment
		(start 195.415154 -48.93691)
		(end 196.024754 -48.32731)
		(width 0.13208)
		(layer "B.Cu")
		(net "SMB_BIC_I2C6_MUX_SSD_0_7_ADC_R_SDA")
	)
	(segment
		(start 196.024754 -48.32731)
		(end 196.422772 -48.32731)
		(width 0.13208)
		(layer "B.Cu")
		(net "SMB_BIC_I2C6_MUX_SSD_0_7_ADC_R_SDA")
	)
	(segment
		(start 104.357678 -49.894236)
		(end 105.315004 -48.93691)
		(width 0.13208)
		(layer "B.Cu")
		(net "SMB_BIC_I2C6_MUX_SSD_0_7_ADC_R_SDA")
	)
	(segment
		(start 194.438778 -49.913286)
		(end 195.415154 -48.93691)
		(width 0.13208)
		(layer "B.Cu")
		(net "SMB_BIC_I2C6_MUX_SSD_0_7_ADC_R_SDA")
	)
	(segment
		(start 28.335478 -48.31461)
		(end 41.559226 -48.31461)
		(width 0.13208)
		(layer "B.Cu")
		(net "SMB_BIC_I2C6_MUX_SSD_0_7_ADC_R_SDA")
	)
	(segment
		(start 95.138748 -49.894236)
		(end 104.357678 -49.894236)
		(width 0.13208)
		(layer "B.Cu")
		(net "SMB_BIC_I2C6_MUX_SSD_0_7_ADC_R_SDA")
	)
	(segment
		(start 170.435524 -48.31461)
		(end 183.659272 -48.31461)
		(width 0.13208)
		(layer "B.Cu")
		(net "SMB_BIC_I2C6_MUX_SSD_0_7_ADC_R_SDA")
	)
	(segment
		(start 142.467584 -49.884584)
		(end 143.415258 -48.93691)
		(width 0.13208)
		(layer "B.Cu")
		(net "SMB_BIC_I2C6_MUX_SSD_0_7_ADC_R_SDA")
	)
	(segment
		(start 131.659376 -48.31461)
		(end 133.22935 -49.884584)
		(width 0.13208)
		(layer "B.Cu")
		(net "SMB_BIC_I2C6_MUX_SSD_0_7_ADC_R_SDA")
	)
	(segment
		(start 105.315004 -48.93691)
		(end 105.924604 -48.32731)
		(width 0.13208)
		(layer "B.Cu")
		(net "SMB_BIC_I2C6_MUX_SSD_0_7_ADC_R_SDA")
	)
	(segment
		(start 27.31516 -48.93691)
		(end 27.92476 -48.32731)
		(width 0.13208)
		(layer "B.Cu")
		(net "SMB_BIC_I2C6_MUX_SSD_0_7_ADC_R_SDA")
	)
	(segment
		(start 53.924708 -48.32731)
		(end 67.55384 -48.32731)
		(width 0.13208)
		(layer "B.Cu")
		(net "SMB_BIC_I2C6_MUX_SSD_0_7_ADC_R_SDA")
	)
	(segment
		(start 159.23895 -49.894236)
		(end 168.45788 -49.894236)
		(width 0.13208)
		(layer "B.Cu")
		(net "SMB_BIC_I2C6_MUX_SSD_0_7_ADC_R_SDA")
	)
	(segment
		(start 168.45788 -49.894236)
		(end 169.415206 -48.93691)
		(width 0.13208)
		(layer "B.Cu")
		(net "SMB_BIC_I2C6_MUX_SSD_0_7_ADC_R_SDA")
	)
	(segment
		(start 53.315108 -48.93691)
		(end 53.924708 -48.32731)
		(width 0.13208)
		(layer "B.Cu")
		(net "SMB_BIC_I2C6_MUX_SSD_0_7_ADC_R_SDA")
	)
	(segment
		(start 157.659324 -48.31461)
		(end 159.23895 -49.894236)
		(width 0.13208)
		(layer "B.Cu")
		(net "SMB_BIC_I2C6_MUX_SSD_0_7_ADC_R_SDA")
	)
	(segment
		(start 185.257948 -49.913286)
		(end 194.438778 -49.913286)
		(width 0.13208)
		(layer "B.Cu")
		(net "SMB_BIC_I2C6_MUX_SSD_0_7_ADC_R_SDA")
	)
	(segment
		(start 211.296504 -49.951894)
		(end 220.400118 -49.951894)
		(width 0.13208)
		(layer "B.Cu")
		(net "SMB_BIC_I2C6_MUX_SSD_0_7_ADC_R_SDA")
	)
	(segment
		(start 105.924604 -48.32731)
		(end 106.322622 -48.32731)
		(width 0.13208)
		(layer "B.Cu")
		(net "SMB_BIC_I2C6_MUX_SSD_0_7_ADC_R_SDA")
	)
	(segment
		(start 143.415258 -48.93691)
		(end 144.037558 -48.31461)
		(width 0.13208)
		(layer "B.Cu")
		(net "SMB_BIC_I2C6_MUX_SSD_0_7_ADC_R_SDA")
	)
	(segment
		(start 144.037558 -48.31461)
		(end 157.659324 -48.31461)
		(width 0.13208)
		(layer "B.Cu")
		(net "SMB_BIC_I2C6_MUX_SSD_0_7_ADC_R_SDA")
	)
	(segment
		(start 196.435472 -48.31461)
		(end 209.65922 -48.31461)
		(width 0.13208)
		(layer "B.Cu")
		(net "SMB_BIC_I2C6_MUX_SSD_0_7_ADC_R_SDA")
	)
	(segment
		(start 169.415206 -48.93691)
		(end 170.024806 -48.32731)
		(width 0.13208)
		(layer "B.Cu")
		(net "SMB_BIC_I2C6_MUX_SSD_0_7_ADC_R_SDA")
	)
	(segment
		(start 170.024806 -48.32731)
		(end 170.422824 -48.32731)
		(width 0.13208)
		(layer "B.Cu")
		(net "SMB_BIC_I2C6_MUX_SSD_0_7_ADC_R_SDA")
	)
	(segment
		(start 78.240128 -50.011838)
		(end 79.315056 -48.93691)
		(width 0.13208)
		(layer "B.Cu")
		(net "SMB_BIC_I2C6_MUX_SSD_0_7_ADC_R_SDA")
	)
	(segment
		(start 41.559226 -48.31461)
		(end 43.186858 -49.942242)
		(width 0.13208)
		(layer "B.Cu")
		(net "SMB_BIC_I2C6_MUX_SSD_0_7_ADC_R_SDA")
	)
	(segment
		(start 209.65922 -48.31461)
		(end 211.296504 -49.951894)
		(width 0.13208)
		(layer "B.Cu")
		(net "SMB_BIC_I2C6_MUX_SSD_0_7_ADC_R_SDA")
	)
	(segment
		(start 28.322778 -48.32731)
		(end 28.335478 -48.31461)
		(width 0.13208)
		(layer "B.Cu")
		(net "SMB_BIC_I2C6_MUX_SSD_0_7_ADC_R_SDA")
	)
	(segment
		(start 52.309776 -49.942242)
		(end 53.315108 -48.93691)
		(width 0.13208)
		(layer "B.Cu")
		(net "SMB_BIC_I2C6_MUX_SSD_0_7_ADC_R_SDA")
	)
	(segment
		(start 170.422824 -48.32731)
		(end 170.435524 -48.31461)
		(width 0.13208)
		(layer "B.Cu")
		(net "SMB_BIC_I2C6_MUX_SSD_0_7_ADC_R_SDA")
	)
	(segment
		(start 79.937356 -48.31461)
		(end 93.559122 -48.31461)
		(width 0.13208)
		(layer "B.Cu")
		(net "SMB_BIC_I2C6_MUX_SSD_0_7_ADC_R_SDA")
	)
	(segment
		(start 67.55384 -48.32731)
		(end 69.238368 -50.011838)
		(width 0.13208)
		(layer "B.Cu")
		(net "SMB_BIC_I2C6_MUX_SSD_0_7_ADC_R_SDA")
	)
	(segment
		(start 93.559122 -48.31461)
		(end 95.138748 -49.894236)
		(width 0.13208)
		(layer "B.Cu")
		(net "SMB_BIC_I2C6_MUX_SSD_0_7_ADC_R_SDA")
	)
	(segment
		(start 27.92476 -48.32731)
		(end 28.322778 -48.32731)
		(width 0.13208)
		(layer "B.Cu")
		(net "SMB_BIC_I2C6_MUX_SSD_0_7_ADC_R_SDA")
	)
	(segment
		(start 106.335322 -48.31461)
		(end 131.659376 -48.31461)
		(width 0.13208)
		(layer "B.Cu")
		(net "SMB_BIC_I2C6_MUX_SSD_0_7_ADC_R_SDA")
	)
	(segment
		(start 183.659272 -48.31461)
		(end 185.257948 -49.913286)
		(width 0.13208)
		(layer "B.Cu")
		(net "SMB_BIC_I2C6_MUX_SSD_0_7_ADC_R_SDA")
	)
	(segment
		(start 69.238368 -50.011838)
		(end 78.240128 -50.011838)
		(width 0.13208)
		(layer "B.Cu")
		(net "SMB_BIC_I2C6_MUX_SSD_0_7_ADC_R_SDA")
	)
	(segment
		(start 79.315056 -48.93691)
		(end 79.937356 -48.31461)
		(width 0.13208)
		(layer "B.Cu")
		(net "SMB_BIC_I2C6_MUX_SSD_0_7_ADC_R_SDA")
	)
	(segment
		(start 220.400118 -49.951894)
		(end 221.415102 -48.93691)
		(width 0.13208)
		(layer "B.Cu")
		(net "SMB_BIC_I2C6_MUX_SSD_0_7_ADC_R_SDA")
	)
	(segment
		(start 43.186858 -49.942242)
		(end 52.309776 -49.942242)
		(width 0.13208)
		(layer "B.Cu")
		(net "SMB_BIC_I2C6_MUX_SSD_0_7_ADC_R_SDA")
	)
	(segment
		(start 133.22935 -49.884584)
		(end 142.467584 -49.884584)
		(width 0.13208)
		(layer "B.Cu")
		(net "SMB_BIC_I2C6_MUX_SSD_0_7_ADC_R_SDA")
	)
	(segment
		(start 196.422772 -48.32731)
		(end 196.435472 -48.31461)
		(width 0.13208)
		(layer "B.Cu")
		(net "SMB_BIC_I2C6_MUX_SSD_0_7_ADC_R_SDA")
	)
	(segment
		(start 241.05489 -70.0532)
		(end 256.452624 -70.0532)
		(width 0.15494)
		(layer "In11.Cu")
		(net "SMB_BIC_I2C6_MUX_SSD_0_7_ADC_R_SDA")
	)
	(segment
		(start 239.568482 -71.539608)
		(end 241.05489 -70.0532)
		(width 0.15494)
		(layer "In11.Cu")
		(net "SMB_BIC_I2C6_MUX_SSD_0_7_ADC_R_SDA")
	)
	(segment
		(start 256.452624 -70.0532)
		(end 259.741416 -73.341992)
		(width 0.15494)
		(layer "In11.Cu")
		(net "SMB_BIC_I2C6_MUX_SSD_0_7_ADC_R_SDA")
	)
	(segment
		(start 259.741416 -73.341992)
		(end 259.741416 -73.726548)
		(width 0.15494)
		(layer "In11.Cu")
		(net "SMB_BIC_I2C6_MUX_SSD_0_7_ADC_R_SDA")
	)
	(segment
		(start 337.059778 -95.273114)
		(end 338.992464 -97.2058)
		(width 0.15494)
		(layer "In13.Cu")
		(net "SMB_BIC_I2C6_MUX_SSD_0_7_ADC_R_SDA")
	)
	(segment
		(start 374.079516 -83.255358)
		(end 374.26138 -83.255358)
		(width 0.15494)
		(layer "In13.Cu")
		(net "SMB_BIC_I2C6_MUX_SSD_0_7_ADC_R_SDA")
	)
	(segment
		(start 372.51005 -82.308446)
		(end 372.51005 -82.126582)
		(width 0.15494)
		(layer "In13.Cu")
		(net "SMB_BIC_I2C6_MUX_SSD_0_7_ADC_R_SDA")
	)
	(segment
		(start 278.885904 -86.912958)
		(end 279.531826 -87.55888)
		(width 0.15494)
		(layer "In13.Cu")
		(net "SMB_BIC_I2C6_MUX_SSD_0_7_ADC_R_SDA")
	)
	(segment
		(start 338.992464 -97.2058)
		(end 353.034346 -97.2058)
		(width 0.15494)
		(layer "In13.Cu")
		(net "SMB_BIC_I2C6_MUX_SSD_0_7_ADC_R_SDA")
	)
	(segment
		(start 372.51005 -82.126582)
		(end 372.639082 -81.99755)
		(width 0.15494)
		(layer "In13.Cu")
		(net "SMB_BIC_I2C6_MUX_SSD_0_7_ADC_R_SDA")
	)
	(segment
		(start 279.531826 -87.55888)
		(end 314.160408 -87.55888)
		(width 0.15494)
		(layer "In13.Cu")
		(net "SMB_BIC_I2C6_MUX_SSD_0_7_ADC_R_SDA")
	)
	(segment
		(start 278.885904 -86.481158)
		(end 278.885904 -86.912958)
		(width 0.15494)
		(layer "In13.Cu")
		(net "SMB_BIC_I2C6_MUX_SSD_0_7_ADC_R_SDA")
	)
	(segment
		(start 315.344048 -88.74252)
		(end 326.562974 -88.74252)
		(width 0.15494)
		(layer "In13.Cu")
		(net "SMB_BIC_I2C6_MUX_SSD_0_7_ADC_R_SDA")
	)
	(segment
		(start 372.820946 -81.99755)
		(end 374.079516 -83.255358)
		(width 0.15494)
		(layer "In13.Cu")
		(net "SMB_BIC_I2C6_MUX_SSD_0_7_ADC_R_SDA")
	)
	(segment
		(start 368.5159 -84.957158)
		(end 368.76482 -84.957158)
		(width 0.15494)
		(layer "In13.Cu")
		(net "SMB_BIC_I2C6_MUX_SSD_0_7_ADC_R_SDA")
	)
	(segment
		(start 326.562974 -88.74252)
		(end 327.812654 -89.9922)
		(width 0.15494)
		(layer "In13.Cu")
		(net "SMB_BIC_I2C6_MUX_SSD_0_7_ADC_R_SDA")
	)
	(segment
		(start 376.696224 -81.9658)
		(end 377.53544 -81.9658)
		(width 0.15494)
		(layer "In13.Cu")
		(net "SMB_BIC_I2C6_MUX_SSD_0_7_ADC_R_SDA")
	)
	(segment
		(start 376.165364 -82.49666)
		(end 376.696224 -81.9658)
		(width 0.15494)
		(layer "In13.Cu")
		(net "SMB_BIC_I2C6_MUX_SSD_0_7_ADC_R_SDA")
	)
	(segment
		(start 363.231684 -87.008462)
		(end 364.893098 -87.008462)
		(width 0.15494)
		(layer "In13.Cu")
		(net "SMB_BIC_I2C6_MUX_SSD_0_7_ADC_R_SDA")
	)
	(segment
		(start 366.847882 -85.053678)
		(end 368.418872 -85.053678)
		(width 0.15494)
		(layer "In13.Cu")
		(net "SMB_BIC_I2C6_MUX_SSD_0_7_ADC_R_SDA")
	)
	(segment
		(start 373.76862 -83.748118)
		(end 373.76862 -83.566254)
		(width 0.15494)
		(layer "In13.Cu")
		(net "SMB_BIC_I2C6_MUX_SSD_0_7_ADC_R_SDA")
	)
	(segment
		(start 372.639082 -81.99755)
		(end 372.820946 -81.99755)
		(width 0.15494)
		(layer "In13.Cu")
		(net "SMB_BIC_I2C6_MUX_SSD_0_7_ADC_R_SDA")
	)
	(segment
		(start 333.883 -89.9922)
		(end 337.059778 -93.168978)
		(width 0.15494)
		(layer "In13.Cu")
		(net "SMB_BIC_I2C6_MUX_SSD_0_7_ADC_R_SDA")
	)
	(segment
		(start 314.160408 -87.55888)
		(end 315.344048 -88.74252)
		(width 0.15494)
		(layer "In13.Cu")
		(net "SMB_BIC_I2C6_MUX_SSD_0_7_ADC_R_SDA")
	)
	(segment
		(start 327.812654 -89.9922)
		(end 333.883 -89.9922)
		(width 0.15494)
		(layer "In13.Cu")
		(net "SMB_BIC_I2C6_MUX_SSD_0_7_ADC_R_SDA")
	)
	(segment
		(start 368.76482 -84.957158)
		(end 369.44427 -84.277708)
		(width 0.15494)
		(layer "In13.Cu")
		(net "SMB_BIC_I2C6_MUX_SSD_0_7_ADC_R_SDA")
	)
	(segment
		(start 364.893098 -87.008462)
		(end 366.847882 -85.053678)
		(width 0.15494)
		(layer "In13.Cu")
		(net "SMB_BIC_I2C6_MUX_SSD_0_7_ADC_R_SDA")
	)
	(segment
		(start 353.034346 -97.2058)
		(end 363.231684 -87.008462)
		(width 0.15494)
		(layer "In13.Cu")
		(net "SMB_BIC_I2C6_MUX_SSD_0_7_ADC_R_SDA")
	)
	(segment
		(start 369.44427 -84.277708)
		(end 373.23903 -84.277708)
		(width 0.15494)
		(layer "In13.Cu")
		(net "SMB_BIC_I2C6_MUX_SSD_0_7_ADC_R_SDA")
	)
	(segment
		(start 368.418872 -85.053678)
		(end 368.515138 -84.957412)
		(width 0.15494)
		(layer "In13.Cu")
		(net "SMB_BIC_I2C6_MUX_SSD_0_7_ADC_R_SDA")
	)
	(segment
		(start 373.76862 -83.566254)
		(end 372.51005 -82.308446)
		(width 0.15494)
		(layer "In13.Cu")
		(net "SMB_BIC_I2C6_MUX_SSD_0_7_ADC_R_SDA")
	)
	(segment
		(start 368.515138 -84.957412)
		(end 368.5159 -84.957158)
		(width 0.15494)
		(layer "In13.Cu")
		(net "SMB_BIC_I2C6_MUX_SSD_0_7_ADC_R_SDA")
	)
	(segment
		(start 375.020078 -82.49666)
		(end 376.165364 -82.49666)
		(width 0.15494)
		(layer "In13.Cu")
		(net "SMB_BIC_I2C6_MUX_SSD_0_7_ADC_R_SDA")
	)
	(segment
		(start 374.26138 -83.255358)
		(end 375.020078 -82.49666)
		(width 0.15494)
		(layer "In13.Cu")
		(net "SMB_BIC_I2C6_MUX_SSD_0_7_ADC_R_SDA")
	)
	(segment
		(start 373.23903 -84.277708)
		(end 373.76862 -83.748118)
		(width 0.15494)
		(layer "In13.Cu")
		(net "SMB_BIC_I2C6_MUX_SSD_0_7_ADC_R_SDA")
	)
	(segment
		(start 337.059778 -93.168978)
		(end 337.059778 -95.273114)
		(width 0.15494)
		(layer "In13.Cu")
		(net "SMB_BIC_I2C6_MUX_SSD_0_7_ADC_R_SDA")
	)
	(segment
		(start 254.45847 -255.08458)
		(end 254.45847 -255.910588)
		(width 0.13208)
		(layer "F.Cu")
		(net "PEX2_SYS_ERR_3V3_N")
	)
	(segment
		(start 254.33147 -256.35204)
		(end 253.708408 -256.35204)
		(width 0.13208)
		(layer "F.Cu")
		(net "PEX2_SYS_ERR_3V3_N")
	)
	(segment
		(start 254.692404 -254.850646)
		(end 254.45847 -255.08458)
		(width 0.13208)
		(layer "F.Cu")
		(net "PEX2_SYS_ERR_3V3_N")
	)
	(segment
		(start 255.227074 -254.850646)
		(end 254.692404 -254.850646)
		(width 0.13208)
		(layer "F.Cu")
		(net "PEX2_SYS_ERR_3V3_N")
	)
	(segment
		(start 254.45847 -255.910588)
		(end 254.45847 -256.22504)
		(width 0.13208)
		(layer "F.Cu")
		(net "PEX2_SYS_ERR_3V3_N")
	)
	(segment
		(start 254.45847 -256.22504)
		(end 254.33147 -256.35204)
		(width 0.13208)
		(layer "F.Cu")
		(net "PEX2_SYS_ERR_3V3_N")
	)
	(via
		(at 254.45847 -255.910588)
		(size 0.508)
		(drill 0.254)
		(layers "F.Cu" "B.Cu")
		(net "PEX2_SYS_ERR_3V3_N")
	)
	(segment
		(start 336.493866 -226.387152)
		(end 336.09407 -226.786948)
		(width 0.13208)
		(layer "F.Cu")
		(net "RST_GPU_PERST_2_N")
	)
	(via
		(at 336.09407 -226.786948)
		(size 0.4572)
		(drill 0.254)
		(layers "F.Cu" "B.Cu")
		(net "RST_GPU_PERST_2_N")
	)
	(via
		(at 301.004732 -224.40265)
		(size 0.508)
		(drill 0.254)
		(layers "F.Cu" "B.Cu")
		(net "RST_GPU_PERST_2_N")
	)
	(via
		(at 300.380908 -223.302068)
		(size 0.6604)
		(drill 0.3302)
		(layers "F.Cu" "B.Cu")
		(net "RST_GPU_PERST_2_N")
	)
	(segment
		(start 300.591474 -222.094552)
		(end 300.591474 -222.529146)
		(width 0.13208)
		(layer "B.Cu")
		(net "RST_GPU_PERST_2_N")
	)
	(segment
		(start 300.380908 -222.739712)
		(end 300.380908 -223.302068)
		(width 0.13208)
		(layer "B.Cu")
		(net "RST_GPU_PERST_2_N")
	)
	(segment
		(start 300.591474 -222.529146)
		(end 300.380908 -222.739712)
		(width 0.13208)
		(layer "B.Cu")
		(net "RST_GPU_PERST_2_N")
	)
	(segment
		(start 300.380908 -223.302068)
		(end 300.72457 -223.64573)
		(width 0.13208)
		(layer "B.Cu")
		(net "RST_GPU_PERST_2_N")
	)
	(segment
		(start 300.72457 -224.122488)
		(end 301.004732 -224.40265)
		(width 0.13208)
		(layer "B.Cu")
		(net "RST_GPU_PERST_2_N")
	)
	(segment
		(start 300.72457 -223.64573)
		(end 300.72457 -224.122488)
		(width 0.13208)
		(layer "B.Cu")
		(net "RST_GPU_PERST_2_N")
	)
	(segment
		(start 301.607474 -222.094552)
		(end 300.591474 -222.094552)
		(width 0.13208)
		(layer "B.Cu")
		(net "RST_GPU_PERST_2_N")
	)
	(segment
		(start 301.607474 -223.199452)
		(end 301.607474 -222.094552)
		(width 0.13208)
		(layer "B.Cu")
		(net "RST_GPU_PERST_2_N")
	)
	(segment
		(start 334.1624 -226.386898)
		(end 331.314044 -226.386898)
		(width 0.15494)
		(layer "In13.Cu")
		(net "RST_GPU_PERST_2_N")
	)
	(segment
		(start 336.09407 -226.786948)
		(end 335.69402 -226.386898)
		(width 0.0889)
		(layer "In13.Cu")
		(net "RST_GPU_PERST_2_N")
	)
	(segment
		(start 330.913486 -225.98634)
		(end 326.427846 -225.98634)
		(width 0.15494)
		(layer "In13.Cu")
		(net "RST_GPU_PERST_2_N")
	)
	(segment
		(start 301.97044 -225.368358)
		(end 301.004732 -224.40265)
		(width 0.15494)
		(layer "In13.Cu")
		(net "RST_GPU_PERST_2_N")
	)
	(segment
		(start 335.69402 -226.386898)
		(end 334.1624 -226.386898)
		(width 0.0889)
		(layer "In13.Cu")
		(net "RST_GPU_PERST_2_N")
	)
	(segment
		(start 326.427846 -225.98634)
		(end 325.345806 -227.06838)
		(width 0.15494)
		(layer "In13.Cu")
		(net "RST_GPU_PERST_2_N")
	)
	(segment
		(start 324.74154 -227.06838)
		(end 323.041518 -225.368358)
		(width 0.15494)
		(layer "In13.Cu")
		(net "RST_GPU_PERST_2_N")
	)
	(segment
		(start 323.041518 -225.368358)
		(end 301.97044 -225.368358)
		(width 0.15494)
		(layer "In13.Cu")
		(net "RST_GPU_PERST_2_N")
	)
	(segment
		(start 325.345806 -227.06838)
		(end 324.74154 -227.06838)
		(width 0.15494)
		(layer "In13.Cu")
		(net "RST_GPU_PERST_2_N")
	)
	(segment
		(start 331.314044 -226.386898)
		(end 330.913486 -225.98634)
		(width 0.15494)
		(layer "In13.Cu")
		(net "RST_GPU_PERST_2_N")
	)
	(segment
		(start 86.178898 -59.177936)
		(end 86.178898 -58.71972)
		(width 0.13208)
		(layer "F.Cu")
		(net "PWRGD_P3V3_SSD3")
	)
	(segment
		(start 85.640926 -57.457848)
		(end 85.640926 -57.16397)
		(width 0.13208)
		(layer "F.Cu")
		(net "PWRGD_P3V3_SSD3")
	)
	(segment
		(start 85.648038 -61.22416)
		(end 85.648038 -59.343544)
		(width 0.13208)
		(layer "F.Cu")
		(net "PWRGD_P3V3_SSD3")
	)
	(segment
		(start 86.024974 -58.565796)
		(end 86.024974 -57.867296)
		(width 0.13208)
		(layer "F.Cu")
		(net "PWRGD_P3V3_SSD3")
	)
	(segment
		(start 86.024974 -57.867296)
		(end 86.024974 -57.841896)
		(width 0.13208)
		(layer "F.Cu")
		(net "PWRGD_P3V3_SSD3")
	)
	(segment
		(start 86.178898 -58.71972)
		(end 86.024974 -58.565796)
		(width 0.13208)
		(layer "F.Cu")
		(net "PWRGD_P3V3_SSD3")
	)
	(segment
		(start 85.648038 -59.343544)
		(end 85.813646 -59.177936)
		(width 0.13208)
		(layer "F.Cu")
		(net "PWRGD_P3V3_SSD3")
	)
	(segment
		(start 85.810852 -61.386974)
		(end 85.648038 -61.22416)
		(width 0.13208)
		(layer "F.Cu")
		(net "PWRGD_P3V3_SSD3")
	)
	(segment
		(start 86.024974 -57.841896)
		(end 85.640926 -57.457848)
		(width 0.13208)
		(layer "F.Cu")
		(net "PWRGD_P3V3_SSD3")
	)
	(segment
		(start 85.813646 -59.177936)
		(end 86.178898 -59.177936)
		(width 0.13208)
		(layer "F.Cu")
		(net "PWRGD_P3V3_SSD3")
	)
	(via
		(at 86.024974 -57.867296)
		(size 0.508)
		(drill 0.254)
		(layers "F.Cu" "B.Cu")
		(net "PWRGD_P3V3_SSD3")
	)
	(segment
		(start 339.693758 -213.587076)
		(end 339.293962 -213.18728)
		(width 0.13208)
		(layer "F.Cu")
		(net "SSD11_CLK_EN_N")
	)
	(via
		(at 339.293962 -213.18728)
		(size 0.4572)
		(drill 0.254)
		(layers "F.Cu" "B.Cu")
		(net "SSD11_CLK_EN_N")
	)
	(via
		(at 338.0359 -210.9089)
		(size 0.6604)
		(drill 0.3302)
		(layers "F.Cu" "B.Cu")
		(net "SSD11_CLK_EN_N")
	)
	(segment
		(start 338.894166 -211.767166)
		(end 338.0359 -210.9089)
		(width 0.13208)
		(layer "B.Cu")
		(net "SSD11_CLK_EN_N")
	)
	(segment
		(start 339.293962 -213.18728)
		(end 338.894166 -212.787484)
		(width 0.0889)
		(layer "B.Cu")
		(net "SSD11_CLK_EN_N")
	)
	(segment
		(start 336.296 -209.169)
		(end 336.296 -208.17205)
		(width 0.13208)
		(layer "B.Cu")
		(net "SSD11_CLK_EN_N")
	)
	(segment
		(start 338.0359 -210.9089)
		(end 336.296 -209.169)
		(width 0.13208)
		(layer "B.Cu")
		(net "SSD11_CLK_EN_N")
	)
	(segment
		(start 338.894166 -212.787484)
		(end 338.894166 -211.767166)
		(width 0.0889)
		(layer "B.Cu")
		(net "SSD11_CLK_EN_N")
	)
	(segment
		(start 108.1786 -82.540856)
		(end 108.239052 -82.601308)
		(width 0.13462)
		(layer "F.Cu")
		(net "CLK_100M_DB800ZL_SSD1_DN")
	)
	(segment
		(start 108.496354 -80.222344)
		(end 108.1786 -80.540098)
		(width 0.13462)
		(layer "F.Cu")
		(net "CLK_100M_DB800ZL_SSD1_DN")
	)
	(segment
		(start 108.1786 -80.540098)
		(end 108.1786 -82.540856)
		(width 0.13462)
		(layer "F.Cu")
		(net "CLK_100M_DB800ZL_SSD1_DN")
	)
	(segment
		(start 108.239052 -82.601308)
		(end 108.239052 -83.029044)
		(width 0.13462)
		(layer "F.Cu")
		(net "CLK_100M_DB800ZL_SSD1_DN")
	)
	(segment
		(start 34.653728 -311.015888)
		(end 34.58083 -311.015888)
		(width 0.13208)
		(layer "F.Cu")
		(net "PU_PEX0_ATPG_MODE_L")
	)
	(segment
		(start 34.58083 -311.015888)
		(end 32.69996 -309.135018)
		(width 0.13208)
		(layer "F.Cu")
		(net "PU_PEX0_ATPG_MODE_L")
	)
	(via
		(at 35.524948 -311.015888)
		(size 0.6604)
		(drill 0.3302)
		(layers "F.Cu" "B.Cu")
		(net "PU_PEX0_ATPG_MODE_L")
	)
	(via
		(at 34.653728 -311.015888)
		(size 0.508)
		(drill 0.254)
		(layers "F.Cu" "B.Cu")
		(net "PU_PEX0_ATPG_MODE_L")
	)
	(via
		(at 50.14976 -309.199788)
		(size 0.4064)
		(drill 0.2032)
		(layers "F.Cu" "B.Cu")
		(net "PU_PEX0_ATPG_MODE_L")
	)
	(segment
		(start 34.653728 -311.015888)
		(end 35.524948 -311.015888)
		(width 0.13208)
		(layer "B.Cu")
		(net "PU_PEX0_ATPG_MODE_L")
	)
	(segment
		(start 35.924236 -310.6166)
		(end 35.524948 -311.015888)
		(width 0.13208)
		(layer "B.Cu")
		(net "PU_PEX0_ATPG_MODE_L")
	)
	(segment
		(start 49.54778 -310.6166)
		(end 35.924236 -310.6166)
		(width 0.13208)
		(layer "B.Cu")
		(net "PU_PEX0_ATPG_MODE_L")
	)
	(segment
		(start 49.67478 -310.4896)
		(end 49.54778 -310.6166)
		(width 0.13208)
		(layer "B.Cu")
		(net "PU_PEX0_ATPG_MODE_L")
	)
	(segment
		(start 50.14976 -309.199788)
		(end 49.67478 -309.674768)
		(width 0.13208)
		(layer "B.Cu")
		(net "PU_PEX0_ATPG_MODE_L")
	)
	(segment
		(start 49.67478 -309.674768)
		(end 49.67478 -310.4896)
		(width 0.13208)
		(layer "B.Cu")
		(net "PU_PEX0_ATPG_MODE_L")
	)
	(segment
		(start 132.47116 -180.400452)
		(end 132.577586 -180.506878)
		(width 0.13462)
		(layer "F.Cu")
		(net "CLK_100M_DB2000QL_GPU_REF1_DN")
	)
	(segment
		(start 132.577586 -183.061356)
		(end 132.26288 -183.376062)
		(width 0.13462)
		(layer "F.Cu")
		(net "CLK_100M_DB2000QL_GPU_REF1_DN")
	)
	(segment
		(start 132.577586 -180.506878)
		(end 132.577586 -183.061356)
		(width 0.13462)
		(layer "F.Cu")
		(net "CLK_100M_DB2000QL_GPU_REF1_DN")
	)
	(segment
		(start 132.26288 -183.892444)
		(end 131.89839 -184.256934)
		(width 0.13462)
		(layer "F.Cu")
		(net "CLK_100M_DB2000QL_GPU_REF1_DN")
	)
	(segment
		(start 132.26288 -183.376062)
		(end 132.26288 -183.892444)
		(width 0.13462)
		(layer "F.Cu")
		(net "CLK_100M_DB2000QL_GPU_REF1_DN")
	)
	(segment
		(start 401.960588 -21.05279)
		(end 401.960588 -20.789392)
		(width 0.13208)
		(layer "F.Cu")
		(net "SMB_SSD13_ISO_EN")
	)
	(segment
		(start 402.754846 -22.561296)
		(end 402.754846 -21.847048)
		(width 0.13208)
		(layer "F.Cu")
		(net "SMB_SSD13_ISO_EN")
	)
	(segment
		(start 402.754846 -21.847048)
		(end 401.960588 -21.05279)
		(width 0.13208)
		(layer "F.Cu")
		(net "SMB_SSD13_ISO_EN")
	)
	(via
		(at 402.754846 -21.847048)
		(size 0.508)
		(drill 0.254)
		(layers "F.Cu" "B.Cu")
		(net "SMB_SSD13_ISO_EN")
	)
	(segment
		(start 78.643734 -49.95291)
		(end 79.315056 -49.95291)
		(width 0.13208)
		(layer "F.Cu")
		(net "SMB_BIC_I2C6_MUX_SSD_0_7_ADC_R_SCL")
	)
	(segment
		(start 220.74378 -49.95291)
		(end 221.415102 -49.95291)
		(width 0.13208)
		(layer "F.Cu")
		(net "SMB_BIC_I2C6_MUX_SSD_0_7_ADC_R_SCL")
	)
	(segment
		(start 104.643682 -49.95291)
		(end 105.315004 -49.95291)
		(width 0.13208)
		(layer "F.Cu")
		(net "SMB_BIC_I2C6_MUX_SSD_0_7_ADC_R_SCL")
	)
	(segment
		(start 52.643786 -49.95291)
		(end 53.315108 -49.95291)
		(width 0.13208)
		(layer "F.Cu")
		(net "SMB_BIC_I2C6_MUX_SSD_0_7_ADC_R_SCL")
	)
	(segment
		(start 222.130874 -50.1269)
		(end 223.139 -50.1269)
		(width 0.13208)
		(layer "F.Cu")
		(net "SMB_BIC_I2C6_MUX_SSD_0_7_ADC_R_SCL")
	)
	(segment
		(start 191.829182 -49.94148)
		(end 192.083436 -49.94148)
		(width 0.13208)
		(layer "F.Cu")
		(net "SMB_BIC_I2C6_MUX_SSD_0_7_ADC_R_SCL")
	)
	(segment
		(start 142.743936 -49.95291)
		(end 143.415258 -49.95291)
		(width 0.13208)
		(layer "F.Cu")
		(net "SMB_BIC_I2C6_MUX_SSD_0_7_ADC_R_SCL")
	)
	(segment
		(start 26.643838 -49.95291)
		(end 27.31516 -49.95291)
		(width 0.13208)
		(layer "F.Cu")
		(net "SMB_BIC_I2C6_MUX_SSD_0_7_ADC_R_SCL")
	)
	(segment
		(start 222.130874 -50.1269)
		(end 221.956884 -49.95291)
		(width 0.13208)
		(layer "F.Cu")
		(net "SMB_BIC_I2C6_MUX_SSD_0_7_ADC_R_SCL")
	)
	(segment
		(start 168.743884 -49.95291)
		(end 169.415206 -49.95291)
		(width 0.13208)
		(layer "F.Cu")
		(net "SMB_BIC_I2C6_MUX_SSD_0_7_ADC_R_SCL")
	)
	(segment
		(start 221.956884 -49.95291)
		(end 221.415102 -49.95291)
		(width 0.13208)
		(layer "F.Cu")
		(net "SMB_BIC_I2C6_MUX_SSD_0_7_ADC_R_SCL")
	)
	(segment
		(start 191.308228 -50.462434)
		(end 191.829182 -49.94148)
		(width 0.13208)
		(layer "F.Cu")
		(net "SMB_BIC_I2C6_MUX_SSD_0_7_ADC_R_SCL")
	)
	(via
		(at 105.315004 -49.95291)
		(size 0.508)
		(drill 0.254)
		(layers "F.Cu" "B.Cu")
		(net "SMB_BIC_I2C6_MUX_SSD_0_7_ADC_R_SCL")
	)
	(via
		(at 191.308228 -50.462434)
		(size 0.508)
		(drill 0.254)
		(layers "F.Cu" "B.Cu")
		(net "SMB_BIC_I2C6_MUX_SSD_0_7_ADC_R_SCL")
	)
	(via
		(at 79.315056 -49.95291)
		(size 0.508)
		(drill 0.254)
		(layers "F.Cu" "B.Cu")
		(net "SMB_BIC_I2C6_MUX_SSD_0_7_ADC_R_SCL")
	)
	(via
		(at 221.415102 -49.95291)
		(size 0.508)
		(drill 0.254)
		(layers "F.Cu" "B.Cu")
		(net "SMB_BIC_I2C6_MUX_SSD_0_7_ADC_R_SCL")
	)
	(via
		(at 53.315108 -49.95291)
		(size 0.508)
		(drill 0.254)
		(layers "F.Cu" "B.Cu")
		(net "SMB_BIC_I2C6_MUX_SSD_0_7_ADC_R_SCL")
	)
	(via
		(at 143.415258 -49.95291)
		(size 0.508)
		(drill 0.254)
		(layers "F.Cu" "B.Cu")
		(net "SMB_BIC_I2C6_MUX_SSD_0_7_ADC_R_SCL")
	)
	(via
		(at 27.31516 -49.95291)
		(size 0.508)
		(drill 0.254)
		(layers "F.Cu" "B.Cu")
		(net "SMB_BIC_I2C6_MUX_SSD_0_7_ADC_R_SCL")
	)
	(via
		(at 169.415206 -49.95291)
		(size 0.508)
		(drill 0.254)
		(layers "F.Cu" "B.Cu")
		(net "SMB_BIC_I2C6_MUX_SSD_0_7_ADC_R_SCL")
	)
	(segment
		(start 133.048248 -50.321464)
		(end 143.046704 -50.321464)
		(width 0.13208)
		(layer "B.Cu")
		(net "SMB_BIC_I2C6_MUX_SSD_0_7_ADC_R_SCL")
	)
	(segment
		(start 170.616626 -48.75149)
		(end 183.47817 -48.75149)
		(width 0.13208)
		(layer "B.Cu")
		(net "SMB_BIC_I2C6_MUX_SSD_0_7_ADC_R_SCL")
	)
	(segment
		(start 191.308228 -50.462434)
		(end 191.94145 -50.462434)
		(width 0.13208)
		(layer "B.Cu")
		(net "SMB_BIC_I2C6_MUX_SSD_0_7_ADC_R_SCL")
	)
	(segment
		(start 67.372738 -48.76419)
		(end 69.057266 -50.448718)
		(width 0.13208)
		(layer "B.Cu")
		(net "SMB_BIC_I2C6_MUX_SSD_0_7_ADC_R_SCL")
	)
	(segment
		(start 93.37802 -48.75149)
		(end 94.957646 -50.331116)
		(width 0.13208)
		(layer "B.Cu")
		(net "SMB_BIC_I2C6_MUX_SSD_0_7_ADC_R_SCL")
	)
	(segment
		(start 209.478118 -48.75149)
		(end 211.115402 -50.388774)
		(width 0.13208)
		(layer "B.Cu")
		(net "SMB_BIC_I2C6_MUX_SSD_0_7_ADC_R_SCL")
	)
	(segment
		(start 53.315108 -49.95291)
		(end 54.503828 -48.76419)
		(width 0.13208)
		(layer "B.Cu")
		(net "SMB_BIC_I2C6_MUX_SSD_0_7_ADC_R_SCL")
	)
	(segment
		(start 144.616678 -48.75149)
		(end 157.478222 -48.75149)
		(width 0.13208)
		(layer "B.Cu")
		(net "SMB_BIC_I2C6_MUX_SSD_0_7_ADC_R_SCL")
	)
	(segment
		(start 106.516424 -48.75149)
		(end 131.478274 -48.75149)
		(width 0.13208)
		(layer "B.Cu")
		(net "SMB_BIC_I2C6_MUX_SSD_0_7_ADC_R_SCL")
	)
	(segment
		(start 94.957646 -50.331116)
		(end 104.936798 -50.331116)
		(width 0.13208)
		(layer "B.Cu")
		(net "SMB_BIC_I2C6_MUX_SSD_0_7_ADC_R_SCL")
	)
	(segment
		(start 78.819248 -50.448718)
		(end 79.315056 -49.95291)
		(width 0.13208)
		(layer "B.Cu")
		(net "SMB_BIC_I2C6_MUX_SSD_0_7_ADC_R_SCL")
	)
	(segment
		(start 211.115402 -50.388774)
		(end 220.979238 -50.388774)
		(width 0.13208)
		(layer "B.Cu")
		(net "SMB_BIC_I2C6_MUX_SSD_0_7_ADC_R_SCL")
	)
	(segment
		(start 105.315004 -49.95291)
		(end 106.516424 -48.75149)
		(width 0.13208)
		(layer "B.Cu")
		(net "SMB_BIC_I2C6_MUX_SSD_0_7_ADC_R_SCL")
	)
	(segment
		(start 143.415258 -49.95291)
		(end 144.616678 -48.75149)
		(width 0.13208)
		(layer "B.Cu")
		(net "SMB_BIC_I2C6_MUX_SSD_0_7_ADC_R_SCL")
	)
	(segment
		(start 104.936798 -50.331116)
		(end 105.315004 -49.95291)
		(width 0.13208)
		(layer "B.Cu")
		(net "SMB_BIC_I2C6_MUX_SSD_0_7_ADC_R_SCL")
	)
	(segment
		(start 169.415206 -49.95291)
		(end 170.616626 -48.75149)
		(width 0.13208)
		(layer "B.Cu")
		(net "SMB_BIC_I2C6_MUX_SSD_0_7_ADC_R_SCL")
	)
	(segment
		(start 196.616574 -48.75149)
		(end 209.478118 -48.75149)
		(width 0.13208)
		(layer "B.Cu")
		(net "SMB_BIC_I2C6_MUX_SSD_0_7_ADC_R_SCL")
	)
	(segment
		(start 143.046704 -50.321464)
		(end 143.415258 -49.95291)
		(width 0.13208)
		(layer "B.Cu")
		(net "SMB_BIC_I2C6_MUX_SSD_0_7_ADC_R_SCL")
	)
	(segment
		(start 185.189114 -50.462434)
		(end 191.308228 -50.462434)
		(width 0.13208)
		(layer "B.Cu")
		(net "SMB_BIC_I2C6_MUX_SSD_0_7_ADC_R_SCL")
	)
	(segment
		(start 169.037 -50.331116)
		(end 169.415206 -49.95291)
		(width 0.13208)
		(layer "B.Cu")
		(net "SMB_BIC_I2C6_MUX_SSD_0_7_ADC_R_SCL")
	)
	(segment
		(start 183.47817 -48.75149)
		(end 185.189114 -50.462434)
		(width 0.13208)
		(layer "B.Cu")
		(net "SMB_BIC_I2C6_MUX_SSD_0_7_ADC_R_SCL")
	)
	(segment
		(start 28.51658 -48.75149)
		(end 41.378124 -48.75149)
		(width 0.13208)
		(layer "B.Cu")
		(net "SMB_BIC_I2C6_MUX_SSD_0_7_ADC_R_SCL")
	)
	(segment
		(start 159.057848 -50.331116)
		(end 169.037 -50.331116)
		(width 0.13208)
		(layer "B.Cu")
		(net "SMB_BIC_I2C6_MUX_SSD_0_7_ADC_R_SCL")
	)
	(segment
		(start 41.378124 -48.75149)
		(end 43.005756 -50.379122)
		(width 0.13208)
		(layer "B.Cu")
		(net "SMB_BIC_I2C6_MUX_SSD_0_7_ADC_R_SCL")
	)
	(segment
		(start 80.516476 -48.75149)
		(end 93.37802 -48.75149)
		(width 0.13208)
		(layer "B.Cu")
		(net "SMB_BIC_I2C6_MUX_SSD_0_7_ADC_R_SCL")
	)
	(segment
		(start 43.005756 -50.379122)
		(end 52.888896 -50.379122)
		(width 0.13208)
		(layer "B.Cu")
		(net "SMB_BIC_I2C6_MUX_SSD_0_7_ADC_R_SCL")
	)
	(segment
		(start 191.94145 -50.462434)
		(end 192.053718 -50.350166)
		(width 0.13208)
		(layer "B.Cu")
		(net "SMB_BIC_I2C6_MUX_SSD_0_7_ADC_R_SCL")
	)
	(segment
		(start 131.478274 -48.75149)
		(end 133.048248 -50.321464)
		(width 0.13208)
		(layer "B.Cu")
		(net "SMB_BIC_I2C6_MUX_SSD_0_7_ADC_R_SCL")
	)
	(segment
		(start 27.31516 -49.95291)
		(end 28.51658 -48.75149)
		(width 0.13208)
		(layer "B.Cu")
		(net "SMB_BIC_I2C6_MUX_SSD_0_7_ADC_R_SCL")
	)
	(segment
		(start 192.053718 -50.350166)
		(end 195.017898 -50.350166)
		(width 0.13208)
		(layer "B.Cu")
		(net "SMB_BIC_I2C6_MUX_SSD_0_7_ADC_R_SCL")
	)
	(segment
		(start 157.478222 -48.75149)
		(end 159.057848 -50.331116)
		(width 0.13208)
		(layer "B.Cu")
		(net "SMB_BIC_I2C6_MUX_SSD_0_7_ADC_R_SCL")
	)
	(segment
		(start 54.503828 -48.76419)
		(end 67.372738 -48.76419)
		(width 0.13208)
		(layer "B.Cu")
		(net "SMB_BIC_I2C6_MUX_SSD_0_7_ADC_R_SCL")
	)
	(segment
		(start 52.888896 -50.379122)
		(end 53.315108 -49.95291)
		(width 0.13208)
		(layer "B.Cu")
		(net "SMB_BIC_I2C6_MUX_SSD_0_7_ADC_R_SCL")
	)
	(segment
		(start 79.315056 -49.95291)
		(end 80.516476 -48.75149)
		(width 0.13208)
		(layer "B.Cu")
		(net "SMB_BIC_I2C6_MUX_SSD_0_7_ADC_R_SCL")
	)
	(segment
		(start 195.017898 -50.350166)
		(end 196.616574 -48.75149)
		(width 0.13208)
		(layer "B.Cu")
		(net "SMB_BIC_I2C6_MUX_SSD_0_7_ADC_R_SCL")
	)
	(segment
		(start 220.979238 -50.388774)
		(end 221.415102 -49.95291)
		(width 0.13208)
		(layer "B.Cu")
		(net "SMB_BIC_I2C6_MUX_SSD_0_7_ADC_R_SCL")
	)
	(segment
		(start 69.057266 -50.448718)
		(end 78.819248 -50.448718)
		(width 0.13208)
		(layer "B.Cu")
		(net "SMB_BIC_I2C6_MUX_SSD_0_7_ADC_R_SCL")
	)
	(segment
		(start 256.075434 -257.22326)
		(end 255.954276 -257.102102)
		(width 0.13208)
		(layer "F.Cu")
		(net "PEX2_SYS_ERR_N_G")
	)
	(segment
		(start 256.075434 -257.73126)
		(end 256.075434 -257.22326)
		(width 0.13208)
		(layer "F.Cu")
		(net "PEX2_SYS_ERR_N_G")
	)
	(segment
		(start 255.508252 -258.649978)
		(end 255.508252 -257.852164)
		(width 0.13208)
		(layer "F.Cu")
		(net "PEX2_SYS_ERR_N_G")
	)
	(segment
		(start 255.508252 -259.295392)
		(end 255.508252 -258.649978)
		(width 0.13208)
		(layer "F.Cu")
		(net "PEX2_SYS_ERR_N_G")
	)
	(segment
		(start 255.424686 -259.378958)
		(end 255.508252 -259.295392)
		(width 0.13208)
		(layer "F.Cu")
		(net "PEX2_SYS_ERR_N_G")
	)
	(segment
		(start 255.32842 -259.475224)
		(end 255.32842 -260.407658)
		(width 0.13208)
		(layer "F.Cu")
		(net "PEX2_SYS_ERR_N_G")
	)
	(segment
		(start 255.424686 -259.378958)
		(end 255.32842 -259.475224)
		(width 0.13208)
		(layer "F.Cu")
		(net "PEX2_SYS_ERR_N_G")
	)
	(segment
		(start 255.508252 -257.852164)
		(end 255.95453 -257.852164)
		(width 0.13208)
		(layer "F.Cu")
		(net "PEX2_SYS_ERR_N_G")
	)
	(segment
		(start 255.95453 -257.852164)
		(end 256.075434 -257.73126)
		(width 0.13208)
		(layer "F.Cu")
		(net "PEX2_SYS_ERR_N_G")
	)
	(segment
		(start 255.954276 -257.102102)
		(end 255.508252 -257.102102)
		(width 0.13208)
		(layer "F.Cu")
		(net "PEX2_SYS_ERR_N_G")
	)
	(via
		(at 255.508252 -258.649978)
		(size 0.508)
		(drill 0.254)
		(layers "F.Cu" "B.Cu")
		(net "PEX2_SYS_ERR_N_G")
	)
	(segment
		(start 182.303928 -24.189944)
		(end 183.364886 -24.189944)
		(width 0.13208)
		(layer "F.Cu")
		(net "RST_SSD6_PERST_R_N")
	)
	(via
		(at 346.075 -236.347)
		(size 0.508)
		(drill 0.254)
		(layers "F.Cu" "B.Cu")
		(net "RST_SSD6_PERST_R_N")
	)
	(via
		(at 186.384692 -241.347244)
		(size 0.508)
		(drill 0.254)
		(layers "F.Cu" "B.Cu")
		(net "RST_SSD6_PERST_R_N")
	)
	(via
		(at 182.303928 -24.189944)
		(size 0.508)
		(drill 0.254)
		(layers "F.Cu" "B.Cu")
		(net "RST_SSD6_PERST_R_N")
	)
	(segment
		(start 347.091 -233.95305)
		(end 346.61729 -234.42676)
		(width 0.13208)
		(layer "B.Cu")
		(net "RST_SSD6_PERST_R_N")
	)
	(segment
		(start 346.61729 -235.80471)
		(end 346.075 -236.347)
		(width 0.13208)
		(layer "B.Cu")
		(net "RST_SSD6_PERST_R_N")
	)
	(segment
		(start 346.61729 -234.42676)
		(end 346.61729 -235.80471)
		(width 0.13208)
		(layer "B.Cu")
		(net "RST_SSD6_PERST_R_N")
	)
	(segment
		(start 177.885852 -160.268158)
		(end 177.885852 -135.060944)
		(width 0.15494)
		(layer "In5.Cu")
		(net "RST_SSD6_PERST_R_N")
	)
	(segment
		(start 192.9384 -28.3464)
		(end 192.928748 -28.3464)
		(width 0.15494)
		(layer "In5.Cu")
		(net "RST_SSD6_PERST_R_N")
	)
	(segment
		(start 180.210714 -172.735494)
		(end 180.210714 -166.266114)
		(width 0.15494)
		(layer "In5.Cu")
		(net "RST_SSD6_PERST_R_N")
	)
	(segment
		(start 177.885852 -135.060944)
		(end 177.927 -135.019796)
		(width 0.15494)
		(layer "In5.Cu")
		(net "RST_SSD6_PERST_R_N")
	)
	(segment
		(start 183.247538 -214.126572)
		(end 183.247538 -201.320146)
		(width 0.15494)
		(layer "In5.Cu")
		(net "RST_SSD6_PERST_R_N")
	)
	(segment
		(start 183.247538 -201.320146)
		(end 183.6928 -200.874884)
		(width 0.15494)
		(layer "In5.Cu")
		(net "RST_SSD6_PERST_R_N")
	)
	(segment
		(start 204.799184 -63.752222)
		(end 204.799184 -45.447712)
		(width 0.15494)
		(layer "In5.Cu")
		(net "RST_SSD6_PERST_R_N")
	)
	(segment
		(start 186.136534 -221.101412)
		(end 183.247538 -214.126572)
		(width 0.15494)
		(layer "In5.Cu")
		(net "RST_SSD6_PERST_R_N")
	)
	(segment
		(start 195.4784 -73.073006)
		(end 204.799184 -63.752222)
		(width 0.15494)
		(layer "In5.Cu")
		(net "RST_SSD6_PERST_R_N")
	)
	(segment
		(start 177.927 -135.019796)
		(end 177.927 -89.626694)
		(width 0.15494)
		(layer "In5.Cu")
		(net "RST_SSD6_PERST_R_N")
	)
	(segment
		(start 187.102496 -26.9494)
		(end 185.08345 -24.930354)
		(width 0.15494)
		(layer "In5.Cu")
		(net "RST_SSD6_PERST_R_N")
	)
	(segment
		(start 192.693798 -33.342326)
		(end 192.693544 -33.342326)
		(width 0.15494)
		(layer "In5.Cu")
		(net "RST_SSD6_PERST_R_N")
	)
	(segment
		(start 186.9186 -228.7778)
		(end 186.136534 -227.995734)
		(width 0.15494)
		(layer "In5.Cu")
		(net "RST_SSD6_PERST_R_N")
	)
	(segment
		(start 183.6928 -200.874884)
		(end 183.6928 -197.91426)
		(width 0.15494)
		(layer "In5.Cu")
		(net "RST_SSD6_PERST_R_N")
	)
	(segment
		(start 189.28461 -82.88782)
		(end 195.4784 -76.69403)
		(width 0.15494)
		(layer "In5.Cu")
		(net "RST_SSD6_PERST_R_N")
	)
	(segment
		(start 192.558162 -29.133038)
		(end 192.9384 -28.7528)
		(width 0.15494)
		(layer "In5.Cu")
		(net "RST_SSD6_PERST_R_N")
	)
	(segment
		(start 181.811676 -184.057036)
		(end 177.995072 -180.240432)
		(width 0.15494)
		(layer "In5.Cu")
		(net "RST_SSD6_PERST_R_N")
	)
	(segment
		(start 204.799184 -45.447712)
		(end 192.693798 -33.342326)
		(width 0.15494)
		(layer "In5.Cu")
		(net "RST_SSD6_PERST_R_N")
	)
	(segment
		(start 177.927 -89.626694)
		(end 184.665874 -82.88782)
		(width 0.15494)
		(layer "In5.Cu")
		(net "RST_SSD6_PERST_R_N")
	)
	(segment
		(start 188.626496 -26.9494)
		(end 187.102496 -26.9494)
		(width 0.15494)
		(layer "In5.Cu")
		(net "RST_SSD6_PERST_R_N")
	)
	(segment
		(start 192.9384 -28.7528)
		(end 192.9384 -28.3464)
		(width 0.15494)
		(layer "In5.Cu")
		(net "RST_SSD6_PERST_R_N")
	)
	(segment
		(start 177.995072 -174.951136)
		(end 180.210714 -172.735494)
		(width 0.15494)
		(layer "In5.Cu")
		(net "RST_SSD6_PERST_R_N")
	)
	(segment
		(start 181.811676 -196.033136)
		(end 181.811676 -184.057036)
		(width 0.15494)
		(layer "In5.Cu")
		(net "RST_SSD6_PERST_R_N")
	)
	(segment
		(start 186.384692 -241.347244)
		(end 186.9186 -240.813336)
		(width 0.15494)
		(layer "In5.Cu")
		(net "RST_SSD6_PERST_R_N")
	)
	(segment
		(start 192.928748 -28.3464)
		(end 192.037462 -27.455114)
		(width 0.15494)
		(layer "In5.Cu")
		(net "RST_SSD6_PERST_R_N")
	)
	(segment
		(start 183.044338 -24.930354)
		(end 182.303928 -24.189944)
		(width 0.15494)
		(layer "In5.Cu")
		(net "RST_SSD6_PERST_R_N")
	)
	(segment
		(start 180.210714 -166.266114)
		(end 178.8414 -164.8968)
		(width 0.15494)
		(layer "In5.Cu")
		(net "RST_SSD6_PERST_R_N")
	)
	(segment
		(start 178.8414 -164.8968)
		(end 178.8414 -161.223706)
		(width 0.15494)
		(layer "In5.Cu")
		(net "RST_SSD6_PERST_R_N")
	)
	(segment
		(start 195.4784 -76.69403)
		(end 195.4784 -73.073006)
		(width 0.15494)
		(layer "In5.Cu")
		(net "RST_SSD6_PERST_R_N")
	)
	(segment
		(start 192.037462 -27.455114)
		(end 189.13221 -27.455114)
		(width 0.15494)
		(layer "In5.Cu")
		(net "RST_SSD6_PERST_R_N")
	)
	(segment
		(start 177.995072 -180.240432)
		(end 177.995072 -174.951136)
		(width 0.15494)
		(layer "In5.Cu")
		(net "RST_SSD6_PERST_R_N")
	)
	(segment
		(start 192.693544 -33.342326)
		(end 192.558162 -33.206944)
		(width 0.15494)
		(layer "In5.Cu")
		(net "RST_SSD6_PERST_R_N")
	)
	(segment
		(start 192.558162 -33.206944)
		(end 192.558162 -29.133038)
		(width 0.15494)
		(layer "In5.Cu")
		(net "RST_SSD6_PERST_R_N")
	)
	(segment
		(start 185.08345 -24.930354)
		(end 183.044338 -24.930354)
		(width 0.15494)
		(layer "In5.Cu")
		(net "RST_SSD6_PERST_R_N")
	)
	(segment
		(start 178.8414 -161.223706)
		(end 177.885852 -160.268158)
		(width 0.15494)
		(layer "In5.Cu")
		(net "RST_SSD6_PERST_R_N")
	)
	(segment
		(start 189.13221 -27.455114)
		(end 188.626496 -26.9494)
		(width 0.15494)
		(layer "In5.Cu")
		(net "RST_SSD6_PERST_R_N")
	)
	(segment
		(start 186.9186 -240.813336)
		(end 186.9186 -228.7778)
		(width 0.15494)
		(layer "In5.Cu")
		(net "RST_SSD6_PERST_R_N")
	)
	(segment
		(start 183.6928 -197.91426)
		(end 181.811676 -196.033136)
		(width 0.15494)
		(layer "In5.Cu")
		(net "RST_SSD6_PERST_R_N")
	)
	(segment
		(start 184.665874 -82.88782)
		(end 189.28461 -82.88782)
		(width 0.15494)
		(layer "In5.Cu")
		(net "RST_SSD6_PERST_R_N")
	)
	(segment
		(start 186.136534 -227.995734)
		(end 186.136534 -221.101412)
		(width 0.15494)
		(layer "In5.Cu")
		(net "RST_SSD6_PERST_R_N")
	)
	(segment
		(start 332.46187 -246.259096)
		(end 332.79334 -245.927626)
		(width 0.15494)
		(layer "In15.Cu")
		(net "RST_SSD6_PERST_R_N")
	)
	(segment
		(start 338.826094 -246.73687)
		(end 345.3892 -240.173764)
		(width 0.15494)
		(layer "In15.Cu")
		(net "RST_SSD6_PERST_R_N")
	)
	(segment
		(start 299.252132 -245.686072)
		(end 300.779688 -247.213628)
		(width 0.15494)
		(layer "In15.Cu")
		(net "RST_SSD6_PERST_R_N")
	)
	(segment
		(start 274.710398 -245.686072)
		(end 299.252132 -245.686072)
		(width 0.15494)
		(layer "In15.Cu")
		(net "RST_SSD6_PERST_R_N")
	)
	(segment
		(start 208.240884 -245.294658)
		(end 208.993486 -244.542056)
		(width 0.15494)
		(layer "In15.Cu")
		(net "RST_SSD6_PERST_R_N")
	)
	(segment
		(start 236.925866 -245.58752)
		(end 238.262668 -245.58752)
		(width 0.15494)
		(layer "In15.Cu")
		(net "RST_SSD6_PERST_R_N")
	)
	(segment
		(start 300.779688 -247.213628)
		(end 302.976026 -247.213628)
		(width 0.15494)
		(layer "In15.Cu")
		(net "RST_SSD6_PERST_R_N")
	)
	(segment
		(start 220.306138 -245.294658)
		(end 220.604334 -244.996462)
		(width 0.15494)
		(layer "In15.Cu")
		(net "RST_SSD6_PERST_R_N")
	)
	(segment
		(start 345.3892 -240.173764)
		(end 345.3892 -239.518444)
		(width 0.15494)
		(layer "In15.Cu")
		(net "RST_SSD6_PERST_R_N")
	)
	(segment
		(start 213.442804 -245.294658)
		(end 220.306138 -245.294658)
		(width 0.15494)
		(layer "In15.Cu")
		(net "RST_SSD6_PERST_R_N")
	)
	(segment
		(start 223.856042 -245.43131)
		(end 232.035096 -245.43131)
		(width 0.15494)
		(layer "In15.Cu")
		(net "RST_SSD6_PERST_R_N")
	)
	(segment
		(start 239.213898 -244.63629)
		(end 253.738634 -244.63629)
		(width 0.15494)
		(layer "In15.Cu")
		(net "RST_SSD6_PERST_R_N")
	)
	(segment
		(start 254.491998 -245.389654)
		(end 274.41398 -245.389654)
		(width 0.15494)
		(layer "In15.Cu")
		(net "RST_SSD6_PERST_R_N")
	)
	(segment
		(start 345.3892 -239.518444)
		(end 346.007182 -238.900462)
		(width 0.15494)
		(layer "In15.Cu")
		(net "RST_SSD6_PERST_R_N")
	)
	(segment
		(start 274.41398 -245.389654)
		(end 274.710398 -245.686072)
		(width 0.15494)
		(layer "In15.Cu")
		(net "RST_SSD6_PERST_R_N")
	)
	(segment
		(start 208.993486 -244.542056)
		(end 212.690202 -244.542056)
		(width 0.15494)
		(layer "In15.Cu")
		(net "RST_SSD6_PERST_R_N")
	)
	(segment
		(start 332.123796 -246.918734)
		(end 332.46187 -246.58066)
		(width 0.15494)
		(layer "In15.Cu")
		(net "RST_SSD6_PERST_R_N")
	)
	(segment
		(start 346.075 -238.167672)
		(end 346.075 -236.347)
		(width 0.15494)
		(layer "In15.Cu")
		(net "RST_SSD6_PERST_R_N")
	)
	(segment
		(start 232.912158 -244.554248)
		(end 235.892594 -244.554248)
		(width 0.15494)
		(layer "In15.Cu")
		(net "RST_SSD6_PERST_R_N")
	)
	(segment
		(start 333.610458 -245.927626)
		(end 334.419702 -246.73687)
		(width 0.15494)
		(layer "In15.Cu")
		(net "RST_SSD6_PERST_R_N")
	)
	(segment
		(start 302.976026 -247.213628)
		(end 304.050954 -246.768366)
		(width 0.15494)
		(layer "In15.Cu")
		(net "RST_SSD6_PERST_R_N")
	)
	(segment
		(start 346.007182 -238.23549)
		(end 346.075 -238.167672)
		(width 0.15494)
		(layer "In15.Cu")
		(net "RST_SSD6_PERST_R_N")
	)
	(segment
		(start 328.921872 -246.918734)
		(end 332.123796 -246.918734)
		(width 0.15494)
		(layer "In15.Cu")
		(net "RST_SSD6_PERST_R_N")
	)
	(segment
		(start 220.604334 -244.996462)
		(end 223.421194 -244.996462)
		(width 0.15494)
		(layer "In15.Cu")
		(net "RST_SSD6_PERST_R_N")
	)
	(segment
		(start 332.79334 -245.927626)
		(end 333.610458 -245.927626)
		(width 0.15494)
		(layer "In15.Cu")
		(net "RST_SSD6_PERST_R_N")
	)
	(segment
		(start 328.771504 -246.768366)
		(end 328.921872 -246.918734)
		(width 0.15494)
		(layer "In15.Cu")
		(net "RST_SSD6_PERST_R_N")
	)
	(segment
		(start 212.690202 -244.542056)
		(end 213.442804 -245.294658)
		(width 0.15494)
		(layer "In15.Cu")
		(net "RST_SSD6_PERST_R_N")
	)
	(segment
		(start 190.332106 -245.294658)
		(end 208.240884 -245.294658)
		(width 0.15494)
		(layer "In15.Cu")
		(net "RST_SSD6_PERST_R_N")
	)
	(segment
		(start 232.035096 -245.43131)
		(end 232.912158 -244.554248)
		(width 0.15494)
		(layer "In15.Cu")
		(net "RST_SSD6_PERST_R_N")
	)
	(segment
		(start 332.46187 -246.58066)
		(end 332.46187 -246.259096)
		(width 0.15494)
		(layer "In15.Cu")
		(net "RST_SSD6_PERST_R_N")
	)
	(segment
		(start 253.738634 -244.63629)
		(end 254.491998 -245.389654)
		(width 0.15494)
		(layer "In15.Cu")
		(net "RST_SSD6_PERST_R_N")
	)
	(segment
		(start 235.892594 -244.554248)
		(end 236.925866 -245.58752)
		(width 0.15494)
		(layer "In15.Cu")
		(net "RST_SSD6_PERST_R_N")
	)
	(segment
		(start 346.007182 -238.900462)
		(end 346.007182 -238.23549)
		(width 0.15494)
		(layer "In15.Cu")
		(net "RST_SSD6_PERST_R_N")
	)
	(segment
		(start 223.421194 -244.996462)
		(end 223.856042 -245.43131)
		(width 0.15494)
		(layer "In15.Cu")
		(net "RST_SSD6_PERST_R_N")
	)
	(segment
		(start 334.419702 -246.73687)
		(end 338.826094 -246.73687)
		(width 0.15494)
		(layer "In15.Cu")
		(net "RST_SSD6_PERST_R_N")
	)
	(segment
		(start 186.384692 -241.347244)
		(end 190.332106 -245.294658)
		(width 0.15494)
		(layer "In15.Cu")
		(net "RST_SSD6_PERST_R_N")
	)
	(segment
		(start 304.050954 -246.768366)
		(end 328.771504 -246.768366)
		(width 0.15494)
		(layer "In15.Cu")
		(net "RST_SSD6_PERST_R_N")
	)
	(segment
		(start 238.262668 -245.58752)
		(end 239.213898 -244.63629)
		(width 0.15494)
		(layer "In15.Cu")
		(net "RST_SSD6_PERST_R_N")
	)
	(segment
		(start 341.293958 -212.786976)
		(end 340.894162 -212.38718)
		(width 0.13208)
		(layer "F.Cu")
		(net "SSD13_PWRDIS")
	)
	(via
		(at 340.894162 -212.38718)
		(size 0.4572)
		(drill 0.254)
		(layers "F.Cu" "B.Cu")
		(net "SSD13_PWRDIS")
	)
	(via
		(at 341.376 -209.677)
		(size 0.6604)
		(drill 0.3302)
		(layers "F.Cu" "B.Cu")
		(net "SSD13_PWRDIS")
	)
	(segment
		(start 341.376 -208.68005)
		(end 340.868 -208.17205)
		(width 0.13208)
		(layer "B.Cu")
		(net "SSD13_PWRDIS")
	)
	(segment
		(start 341.249 -212.032342)
		(end 341.249 -211.328)
		(width 0.13208)
		(layer "B.Cu")
		(net "SSD13_PWRDIS")
	)
	(segment
		(start 340.894162 -212.38718)
		(end 341.249 -212.032342)
		(width 0.13208)
		(layer "B.Cu")
		(net "SSD13_PWRDIS")
	)
	(segment
		(start 341.376 -211.201)
		(end 341.376 -209.677)
		(width 0.13208)
		(layer "B.Cu")
		(net "SSD13_PWRDIS")
	)
	(segment
		(start 341.249 -211.328)
		(end 341.376 -211.201)
		(width 0.13208)
		(layer "B.Cu")
		(net "SSD13_PWRDIS")
	)
	(segment
		(start 341.376 -209.677)
		(end 341.376 -208.68005)
		(width 0.13208)
		(layer "B.Cu")
		(net "SSD13_PWRDIS")
	)
	(segment
		(start 107.581954 -80.222344)
		(end 107.90428 -80.54467)
		(width 0.13462)
		(layer "F.Cu")
		(net "CLK_100M_DB800ZL_SSD1_DP")
	)
	(segment
		(start 107.839002 -82.602578)
		(end 107.839002 -83.029044)
		(width 0.13462)
		(layer "F.Cu")
		(net "CLK_100M_DB800ZL_SSD1_DP")
	)
	(segment
		(start 107.90428 -82.5373)
		(end 107.839002 -82.602578)
		(width 0.13462)
		(layer "F.Cu")
		(net "CLK_100M_DB800ZL_SSD1_DP")
	)
	(segment
		(start 107.90428 -80.54467)
		(end 107.90428 -82.5373)
		(width 0.13462)
		(layer "F.Cu")
		(net "CLK_100M_DB800ZL_SSD1_DP")
	)
	(segment
		(start 250.829318 -78.29804)
		(end 250.683522 -78.152244)
		(width 0.13208)
		(layer "F.Cu")
		(net "XTAL_CK440_25M_R_XIN")
	)
	(segment
		(start 249.825002 -78.152244)
		(end 249.698002 -78.279244)
		(width 0.13208)
		(layer "F.Cu")
		(net "XTAL_CK440_25M_R_XIN")
	)
	(segment
		(start 249.698002 -78.279244)
		(end 249.698002 -79.229458)
		(width 0.13208)
		(layer "F.Cu")
		(net "XTAL_CK440_25M_R_XIN")
	)
	(segment
		(start 251.56287 -79.779368)
		(end 250.829318 -79.779368)
		(width 0.13208)
		(layer "F.Cu")
		(net "XTAL_CK440_25M_R_XIN")
	)
	(segment
		(start 251.56287 -79.779368)
		(end 251.705364 -79.921862)
		(width 0.13208)
		(layer "F.Cu")
		(net "XTAL_CK440_25M_R_XIN")
	)
	(segment
		(start 250.683522 -78.152244)
		(end 249.825002 -78.152244)
		(width 0.13208)
		(layer "F.Cu")
		(net "XTAL_CK440_25M_R_XIN")
	)
	(segment
		(start 251.705364 -79.921862)
		(end 252.628908 -79.921862)
		(width 0.13208)
		(layer "F.Cu")
		(net "XTAL_CK440_25M_R_XIN")
	)
	(segment
		(start 250.829318 -79.779368)
		(end 250.829318 -78.29804)
		(width 0.13208)
		(layer "F.Cu")
		(net "XTAL_CK440_25M_R_XIN")
	)
	(via
		(at 250.829318 -79.779368)
		(size 0.508)
		(drill 0.254)
		(layers "F.Cu" "B.Cu")
		(net "XTAL_CK440_25M_R_XIN")
	)
	(segment
		(start 27.823922 -312.557922)
		(end 26.822654 -311.556654)
		(width 0.13208)
		(layer "F.Cu")
		(net "PU_PEX0_TR_TCK")
	)
	(segment
		(start 34.403792 -313.669934)
		(end 33.64738 -313.669934)
		(width 0.13208)
		(layer "F.Cu")
		(net "PU_PEX0_TR_TCK")
	)
	(segment
		(start 33.64738 -313.669934)
		(end 30.962346 -312.557922)
		(width 0.13208)
		(layer "F.Cu")
		(net "PU_PEX0_TR_TCK")
	)
	(segment
		(start 30.962346 -312.557922)
		(end 27.823922 -312.557922)
		(width 0.13208)
		(layer "F.Cu")
		(net "PU_PEX0_TR_TCK")
	)
	(segment
		(start 54.899814 -309.199788)
		(end 55.374794 -308.724808)
		(width 0.13208)
		(layer "F.Cu")
		(net "PU_PEX0_TR_TCK")
	)
	(via
		(at 34.403792 -313.669934)
		(size 0.508)
		(drill 0.254)
		(layers "F.Cu" "B.Cu")
		(net "PU_PEX0_TR_TCK")
	)
	(via
		(at 55.374794 -308.724808)
		(size 0.4064)
		(drill 0.2032)
		(layers "F.Cu" "B.Cu")
		(net "PU_PEX0_TR_TCK")
	)
	(segment
		(start 34.403792 -315.962792)
		(end 34.403792 -313.669934)
		(width 0.13208)
		(layer "B.Cu")
		(net "PU_PEX0_TR_TCK")
	)
	(segment
		(start 55.374794 -309.450994)
		(end 55.6514 -309.7276)
		(width 0.13208)
		(layer "B.Cu")
		(net "PU_PEX0_TR_TCK")
	)
	(segment
		(start 56.0832 -317.2714)
		(end 35.7124 -317.2714)
		(width 0.13208)
		(layer "B.Cu")
		(net "PU_PEX0_TR_TCK")
	)
	(segment
		(start 56.3118 -309.9054)
		(end 56.3118 -317.0428)
		(width 0.13208)
		(layer "B.Cu")
		(net "PU_PEX0_TR_TCK")
	)
	(segment
		(start 55.374794 -308.724808)
		(end 55.374794 -309.450994)
		(width 0.13208)
		(layer "B.Cu")
		(net "PU_PEX0_TR_TCK")
	)
	(segment
		(start 56.134 -309.7276)
		(end 56.3118 -309.9054)
		(width 0.13208)
		(layer "B.Cu")
		(net "PU_PEX0_TR_TCK")
	)
	(segment
		(start 55.6514 -309.7276)
		(end 56.134 -309.7276)
		(width 0.13208)
		(layer "B.Cu")
		(net "PU_PEX0_TR_TCK")
	)
	(segment
		(start 56.3118 -317.0428)
		(end 56.0832 -317.2714)
		(width 0.13208)
		(layer "B.Cu")
		(net "PU_PEX0_TR_TCK")
	)
	(segment
		(start 35.7124 -317.2714)
		(end 34.403792 -315.962792)
		(width 0.13208)
		(layer "B.Cu")
		(net "PU_PEX0_TR_TCK")
	)
	(segment
		(start 132.851906 -183.175148)
		(end 132.851906 -180.519578)
		(width 0.13462)
		(layer "F.Cu")
		(net "CLK_100M_DB2000QL_GPU_REF1_DP")
	)
	(segment
		(start 132.91439 -184.256934)
		(end 132.5372 -183.879744)
		(width 0.13462)
		(layer "F.Cu")
		(net "CLK_100M_DB2000QL_GPU_REF1_DP")
	)
	(segment
		(start 132.5372 -183.489854)
		(end 132.851906 -183.175148)
		(width 0.13462)
		(layer "F.Cu")
		(net "CLK_100M_DB2000QL_GPU_REF1_DP")
	)
	(segment
		(start 132.851906 -180.519578)
		(end 132.971032 -180.400452)
		(width 0.13462)
		(layer "F.Cu")
		(net "CLK_100M_DB2000QL_GPU_REF1_DP")
	)
	(segment
		(start 132.5372 -183.879744)
		(end 132.5372 -183.489854)
		(width 0.13462)
		(layer "F.Cu")
		(net "CLK_100M_DB2000QL_GPU_REF1_DP")
	)
	(segment
		(start 310.485282 -16.439388)
		(end 310.485282 -15.370302)
		(width 0.13208)
		(layer "F.Cu")
		(net "SMB_ISO_SSD10_SCL")
	)
	(segment
		(start 308.821582 -18.990818)
		(end 308.267862 -18.437098)
		(width 0.13208)
		(layer "F.Cu")
		(net "SMB_ISO_SSD10_SCL")
	)
	(segment
		(start 310.040782 -18.990818)
		(end 308.821582 -18.990818)
		(width 0.13208)
		(layer "F.Cu")
		(net "SMB_ISO_SSD10_SCL")
	)
	(segment
		(start 310.659272 -23.355554)
		(end 310.659272 -23.965154)
		(width 0.13208)
		(layer "F.Cu")
		(net "SMB_ISO_SSD10_SCL")
	)
	(segment
		(start 307.456332 -17.669256)
		(end 308.224174 -18.437098)
		(width 0.13208)
		(layer "F.Cu")
		(net "SMB_ISO_SSD10_SCL")
	)
	(segment
		(start 310.485282 -18.546318)
		(end 310.040782 -18.990818)
		(width 0.13208)
		(layer "F.Cu")
		(net "SMB_ISO_SSD10_SCL")
	)
	(segment
		(start 308.224174 -18.437098)
		(end 308.267862 -18.437098)
		(width 0.13208)
		(layer "F.Cu")
		(net "SMB_ISO_SSD10_SCL")
	)
	(segment
		(start 307.456332 -17.419574)
		(end 307.456332 -17.669256)
		(width 0.13208)
		(layer "F.Cu")
		(net "SMB_ISO_SSD10_SCL")
	)
	(segment
		(start 310.485282 -16.439388)
		(end 310.485282 -18.546318)
		(width 0.13208)
		(layer "F.Cu")
		(net "SMB_ISO_SSD10_SCL")
	)
	(via
		(at 310.659272 -23.965154)
		(size 0.508)
		(drill 0.254)
		(layers "F.Cu" "B.Cu")
		(net "SMB_ISO_SSD10_SCL")
	)
	(via
		(at 310.485282 -15.370302)
		(size 0.508)
		(drill 0.254)
		(layers "F.Cu" "B.Cu")
		(net "SMB_ISO_SSD10_SCL")
	)
	(segment
		(start 311.944258 -17.436338)
		(end 310.485282 -15.977362)
		(width 0.13208)
		(layer "B.Cu")
		(net "SMB_ISO_SSD10_SCL")
	)
	(segment
		(start 310.659272 -23.965154)
		(end 311.944258 -22.680168)
		(width 0.13208)
		(layer "B.Cu")
		(net "SMB_ISO_SSD10_SCL")
	)
	(segment
		(start 310.485282 -15.977362)
		(end 310.485282 -15.370302)
		(width 0.13208)
		(layer "B.Cu")
		(net "SMB_ISO_SSD10_SCL")
	)
	(segment
		(start 311.944258 -22.680168)
		(end 311.944258 -17.436338)
		(width 0.13208)
		(layer "B.Cu")
		(net "SMB_ISO_SSD10_SCL")
	)
	(via
		(at 304.076608 -224.129346)
		(size 0.6604)
		(drill 0.3302)
		(layers "F.Cu" "B.Cu")
		(net "RST_GPU_PERST_1_BUF_N")
	)
	(segment
		(start 304.076608 -223.748346)
		(end 303.527714 -223.199452)
		(width 0.13208)
		(layer "B.Cu")
		(net "RST_GPU_PERST_1_BUF_N")
	)
	(segment
		(start 302.877474 -222.094552)
		(end 302.877474 -223.199452)
		(width 0.13208)
		(layer "B.Cu")
		(net "RST_GPU_PERST_1_BUF_N")
	)
	(segment
		(start 303.527714 -223.199452)
		(end 302.877474 -223.199452)
		(width 0.13208)
		(layer "B.Cu")
		(net "RST_GPU_PERST_1_BUF_N")
	)
	(segment
		(start 304.076608 -225.320606)
		(end 304.076608 -224.129346)
		(width 0.13208)
		(layer "B.Cu")
		(net "RST_GPU_PERST_1_BUF_N")
	)
	(segment
		(start 304.076608 -224.129346)
		(end 304.076608 -223.748346)
		(width 0.13208)
		(layer "B.Cu")
		(net "RST_GPU_PERST_1_BUF_N")
	)
	(segment
		(start 303.01946 -226.377754)
		(end 304.076608 -225.320606)
		(width 0.13208)
		(layer "B.Cu")
		(net "RST_GPU_PERST_1_BUF_N")
	)
	(segment
		(start 303.01946 -227.520754)
		(end 303.01946 -226.377754)
		(width 0.13208)
		(layer "B.Cu")
		(net "RST_GPU_PERST_1_BUF_N")
	)
	(segment
		(start 258.654296 -204.544168)
		(end 258.806188 -204.69606)
		(width 0.13208)
		(layer "F.Cu")
		(net "JTAG_FPGA_TDI")
	)
	(segment
		(start 257.754374 -205.821026)
		(end 257.295904 -205.362556)
		(width 0.13208)
		(layer "F.Cu")
		(net "JTAG_FPGA_TDI")
	)
	(segment
		(start 257.628644 -204.544168)
		(end 258.654296 -204.544168)
		(width 0.13208)
		(layer "F.Cu")
		(net "JTAG_FPGA_TDI")
	)
	(segment
		(start 257.295904 -205.362556)
		(end 257.295904 -204.876908)
		(width 0.13208)
		(layer "F.Cu")
		(net "JTAG_FPGA_TDI")
	)
	(segment
		(start 257.295904 -204.876908)
		(end 257.628644 -204.544168)
		(width 0.13208)
		(layer "F.Cu")
		(net "JTAG_FPGA_TDI")
	)
	(segment
		(start 340.493858 -224.786952)
		(end 340.094062 -225.186748)
		(width 0.13208)
		(layer "F.Cu")
		(net "JTAG_FPGA_TDI")
	)
	(via
		(at 336.41538 -230.680768)
		(size 0.7112)
		(drill 0.3556)
		(layers "F.Cu" "B.Cu")
		(net "JTAG_FPGA_TDI")
	)
	(via
		(at 257.754374 -205.821026)
		(size 0.508)
		(drill 0.254)
		(layers "F.Cu" "B.Cu")
		(net "JTAG_FPGA_TDI")
	)
	(via
		(at 340.094062 -225.186748)
		(size 0.4572)
		(drill 0.254)
		(layers "F.Cu" "B.Cu")
		(net "JTAG_FPGA_TDI")
	)
	(segment
		(start 333.002636 -231.515412)
		(end 330.207366 -231.515412)
		(width 0.13208)
		(layer "B.Cu")
		(net "JTAG_FPGA_TDI")
	)
	(segment
		(start 333.83728 -230.680768)
		(end 333.002636 -231.515412)
		(width 0.13208)
		(layer "B.Cu")
		(net "JTAG_FPGA_TDI")
	)
	(segment
		(start 338.77377 -229.955598)
		(end 338.0486 -230.680768)
		(width 0.13208)
		(layer "B.Cu")
		(net "JTAG_FPGA_TDI")
	)
	(segment
		(start 258.012438 -206.583788)
		(end 257.754374 -205.960726)
		(width 0.13208)
		(layer "B.Cu")
		(net "JTAG_FPGA_TDI")
	)
	(segment
		(start 257.754374 -205.960726)
		(end 257.754374 -205.821026)
		(width 0.13208)
		(layer "B.Cu")
		(net "JTAG_FPGA_TDI")
	)
	(segment
		(start 339.521292 -228.097842)
		(end 339.158326 -228.097842)
		(width 0.13208)
		(layer "B.Cu")
		(net "JTAG_FPGA_TDI")
	)
	(segment
		(start 258.012438 -207.145128)
		(end 258.012438 -206.583788)
		(width 0.13208)
		(layer "B.Cu")
		(net "JTAG_FPGA_TDI")
	)
	(segment
		(start 340.094062 -225.186748)
		(end 339.695536 -225.585274)
		(width 0.0889)
		(layer "B.Cu")
		(net "JTAG_FPGA_TDI")
	)
	(segment
		(start 338.77377 -228.482398)
		(end 338.77377 -229.955598)
		(width 0.13208)
		(layer "B.Cu")
		(net "JTAG_FPGA_TDI")
	)
	(segment
		(start 339.158326 -228.097842)
		(end 338.77377 -228.482398)
		(width 0.13208)
		(layer "B.Cu")
		(net "JTAG_FPGA_TDI")
	)
	(segment
		(start 339.695536 -225.585274)
		(end 339.695536 -227.923598)
		(width 0.0889)
		(layer "B.Cu")
		(net "JTAG_FPGA_TDI")
	)
	(segment
		(start 256.43332 -207.507078)
		(end 257.650488 -207.507078)
		(width 0.13208)
		(layer "B.Cu")
		(net "JTAG_FPGA_TDI")
	)
	(segment
		(start 257.650488 -207.507078)
		(end 258.012438 -207.145128)
		(width 0.13208)
		(layer "B.Cu")
		(net "JTAG_FPGA_TDI")
	)
	(segment
		(start 336.41538 -230.680768)
		(end 333.83728 -230.680768)
		(width 0.13208)
		(layer "B.Cu")
		(net "JTAG_FPGA_TDI")
	)
	(segment
		(start 339.695536 -227.923598)
		(end 339.521292 -228.097842)
		(width 0.13208)
		(layer "B.Cu")
		(net "JTAG_FPGA_TDI")
	)
	(segment
		(start 338.0486 -230.680768)
		(end 336.41538 -230.680768)
		(width 0.13208)
		(layer "B.Cu")
		(net "JTAG_FPGA_TDI")
	)
	(segment
		(start 262.58012 -205.863698)
		(end 259.782564 -205.863698)
		(width 0.15494)
		(layer "In13.Cu")
		(net "JTAG_FPGA_TDI")
	)
	(segment
		(start 333.386176 -224.01022)
		(end 331.83957 -224.01022)
		(width 0.15494)
		(layer "In13.Cu")
		(net "JTAG_FPGA_TDI")
	)
	(segment
		(start 296.223944 -218.350846)
		(end 295.773348 -217.90025)
		(width 0.15494)
		(layer "In13.Cu")
		(net "JTAG_FPGA_TDI")
	)
	(segment
		(start 257.955288 -205.620112)
		(end 257.754374 -205.821026)
		(width 0.15494)
		(layer "In13.Cu")
		(net "JTAG_FPGA_TDI")
	)
	(segment
		(start 334.162908 -224.786952)
		(end 333.386176 -224.01022)
		(width 0.15494)
		(layer "In13.Cu")
		(net "JTAG_FPGA_TDI")
	)
	(segment
		(start 324.686168 -218.84513)
		(end 324.191884 -218.350846)
		(width 0.15494)
		(layer "In13.Cu")
		(net "JTAG_FPGA_TDI")
	)
	(segment
		(start 331.83957 -224.01022)
		(end 327.00087 -219.17152)
		(width 0.15494)
		(layer "In13.Cu")
		(net "JTAG_FPGA_TDI")
	)
	(segment
		(start 340.094062 -225.186748)
		(end 339.694266 -224.786952)
		(width 0.0889)
		(layer "In13.Cu")
		(net "JTAG_FPGA_TDI")
	)
	(segment
		(start 327.00087 -219.17152)
		(end 327.00087 -218.972384)
		(width 0.15494)
		(layer "In13.Cu")
		(net "JTAG_FPGA_TDI")
	)
	(segment
		(start 279.597104 -217.90025)
		(end 268.948916 -207.252062)
		(width 0.15494)
		(layer "In13.Cu")
		(net "JTAG_FPGA_TDI")
	)
	(segment
		(start 263.968484 -207.252062)
		(end 262.58012 -205.863698)
		(width 0.15494)
		(layer "In13.Cu")
		(net "JTAG_FPGA_TDI")
	)
	(segment
		(start 259.538978 -205.620112)
		(end 257.955288 -205.620112)
		(width 0.15494)
		(layer "In13.Cu")
		(net "JTAG_FPGA_TDI")
	)
	(segment
		(start 268.948916 -207.252062)
		(end 263.968484 -207.252062)
		(width 0.15494)
		(layer "In13.Cu")
		(net "JTAG_FPGA_TDI")
	)
	(segment
		(start 326.873616 -218.84513)
		(end 324.686168 -218.84513)
		(width 0.15494)
		(layer "In13.Cu")
		(net "JTAG_FPGA_TDI")
	)
	(segment
		(start 295.773348 -217.90025)
		(end 279.597104 -217.90025)
		(width 0.15494)
		(layer "In13.Cu")
		(net "JTAG_FPGA_TDI")
	)
	(segment
		(start 324.191884 -218.350846)
		(end 296.223944 -218.350846)
		(width 0.15494)
		(layer "In13.Cu")
		(net "JTAG_FPGA_TDI")
	)
	(segment
		(start 339.694266 -224.786952)
		(end 334.162908 -224.786952)
		(width 0.0889)
		(layer "In13.Cu")
		(net "JTAG_FPGA_TDI")
	)
	(segment
		(start 259.782564 -205.863698)
		(end 259.538978 -205.620112)
		(width 0.15494)
		(layer "In13.Cu")
		(net "JTAG_FPGA_TDI")
	)
	(segment
		(start 327.00087 -218.972384)
		(end 326.873616 -218.84513)
		(width 0.15494)
		(layer "In13.Cu")
		(net "JTAG_FPGA_TDI")
	)
	(segment
		(start 102.147116 -55.144162)
		(end 102.658418 -55.144162)
		(width 0.13208)
		(layer "F.Cu")
		(net "SSD3_PWR_EN_R")
	)
	(segment
		(start 103.86695 -56.354218)
		(end 103.867712 -56.353456)
		(width 0.13208)
		(layer "F.Cu")
		(net "SSD3_PWR_EN_R")
	)
	(segment
		(start 98.514408 -65.92189)
		(end 98.514408 -65.100962)
		(width 0.13208)
		(layer "F.Cu")
		(net "SSD3_PWR_EN_R")
	)
	(segment
		(start 103.86695 -57.563766)
		(end 104.375458 -58.072274)
		(width 0.13208)
		(layer "F.Cu")
		(net "SSD3_PWR_EN_R")
	)
	(segment
		(start 103.86695 -57.332626)
		(end 103.86695 -57.563766)
		(width 0.13208)
		(layer "F.Cu")
		(net "SSD3_PWR_EN_R")
	)
	(segment
		(start 103.86695 -57.332626)
		(end 103.86695 -56.354218)
		(width 0.13208)
		(layer "F.Cu")
		(net "SSD3_PWR_EN_R")
	)
	(segment
		(start 102.658418 -55.144162)
		(end 103.867712 -56.353456)
		(width 0.13208)
		(layer "F.Cu")
		(net "SSD3_PWR_EN_R")
	)
	(via
		(at 339.979 -236.347)
		(size 0.508)
		(drill 0.254)
		(layers "F.Cu" "B.Cu")
		(net "SSD3_PWR_EN_R")
	)
	(via
		(at 119.818404 -224.46107)
		(size 0.508)
		(drill 0.254)
		(layers "F.Cu" "B.Cu")
		(net "SSD3_PWR_EN_R")
	)
	(via
		(at 98.514408 -65.100962)
		(size 0.508)
		(drill 0.254)
		(layers "F.Cu" "B.Cu")
		(net "SSD3_PWR_EN_R")
	)
	(via
		(at 104.375458 -58.072274)
		(size 0.508)
		(drill 0.254)
		(layers "F.Cu" "B.Cu")
		(net "SSD3_PWR_EN_R")
	)
	(segment
		(start 340.995 -233.95305)
		(end 340.52129 -234.42676)
		(width 0.13208)
		(layer "B.Cu")
		(net "SSD3_PWR_EN_R")
	)
	(segment
		(start 340.52129 -235.80471)
		(end 339.979 -236.347)
		(width 0.13208)
		(layer "B.Cu")
		(net "SSD3_PWR_EN_R")
	)
	(segment
		(start 340.52129 -234.42676)
		(end 340.52129 -235.80471)
		(width 0.13208)
		(layer "B.Cu")
		(net "SSD3_PWR_EN_R")
	)
	(segment
		(start 121.45518 -117.316504)
		(end 122.960892 -118.822216)
		(width 0.15494)
		(layer "In5.Cu")
		(net "SSD3_PWR_EN_R")
	)
	(segment
		(start 119.205248 -213.515194)
		(end 119.818404 -214.12835)
		(width 0.15494)
		(layer "In5.Cu")
		(net "SSD3_PWR_EN_R")
	)
	(segment
		(start 104.874314 -58.57113)
		(end 104.874314 -66.40703)
		(width 0.15494)
		(layer "In5.Cu")
		(net "SSD3_PWR_EN_R")
	)
	(segment
		(start 109.42955 -74.41311)
		(end 114.192812 -79.176372)
		(width 0.15494)
		(layer "In5.Cu")
		(net "SSD3_PWR_EN_R")
	)
	(segment
		(start 119.818404 -214.12835)
		(end 119.818404 -224.46107)
		(width 0.15494)
		(layer "In5.Cu")
		(net "SSD3_PWR_EN_R")
	)
	(segment
		(start 99.731322 -65.64376)
		(end 99.057206 -65.64376)
		(width 0.15494)
		(layer "In5.Cu")
		(net "SSD3_PWR_EN_R")
	)
	(segment
		(start 120.8278 -203.987146)
		(end 120.8278 -211.048854)
		(width 0.15494)
		(layer "In5.Cu")
		(net "SSD3_PWR_EN_R")
	)
	(segment
		(start 119.205248 -212.671406)
		(end 119.205248 -213.515194)
		(width 0.15494)
		(layer "In5.Cu")
		(net "SSD3_PWR_EN_R")
	)
	(segment
		(start 117.210078 -79.176372)
		(end 123.4694 -85.435694)
		(width 0.15494)
		(layer "In5.Cu")
		(net "SSD3_PWR_EN_R")
	)
	(segment
		(start 121.3739 -127.048514)
		(end 121.3739 -181.825646)
		(width 0.15494)
		(layer "In5.Cu")
		(net "SSD3_PWR_EN_R")
	)
	(segment
		(start 121.45518 -104.24922)
		(end 121.45518 -117.316504)
		(width 0.15494)
		(layer "In5.Cu")
		(net "SSD3_PWR_EN_R")
	)
	(segment
		(start 123.4694 -85.435694)
		(end 123.4694 -102.235)
		(width 0.15494)
		(layer "In5.Cu")
		(net "SSD3_PWR_EN_R")
	)
	(segment
		(start 122.960892 -125.461522)
		(end 121.3739 -127.048514)
		(width 0.15494)
		(layer "In5.Cu")
		(net "SSD3_PWR_EN_R")
	)
	(segment
		(start 104.874314 -66.40703)
		(end 109.42955 -70.962266)
		(width 0.15494)
		(layer "In5.Cu")
		(net "SSD3_PWR_EN_R")
	)
	(segment
		(start 123.4694 -102.235)
		(end 121.45518 -104.24922)
		(width 0.15494)
		(layer "In5.Cu")
		(net "SSD3_PWR_EN_R")
	)
	(segment
		(start 104.18318 -64.451484)
		(end 103.550974 -65.08369)
		(width 0.15494)
		(layer "In5.Cu")
		(net "SSD3_PWR_EN_R")
	)
	(segment
		(start 104.375458 -58.072274)
		(end 104.18318 -58.264552)
		(width 0.15494)
		(layer "In5.Cu")
		(net "SSD3_PWR_EN_R")
	)
	(segment
		(start 103.550974 -65.08369)
		(end 100.291392 -65.08369)
		(width 0.15494)
		(layer "In5.Cu")
		(net "SSD3_PWR_EN_R")
	)
	(segment
		(start 104.375458 -58.072274)
		(end 104.874314 -58.57113)
		(width 0.15494)
		(layer "In5.Cu")
		(net "SSD3_PWR_EN_R")
	)
	(segment
		(start 122.960892 -118.822216)
		(end 122.960892 -125.461522)
		(width 0.15494)
		(layer "In5.Cu")
		(net "SSD3_PWR_EN_R")
	)
	(segment
		(start 114.192812 -79.176372)
		(end 117.210078 -79.176372)
		(width 0.15494)
		(layer "In5.Cu")
		(net "SSD3_PWR_EN_R")
	)
	(segment
		(start 99.057206 -65.64376)
		(end 98.514408 -65.100962)
		(width 0.15494)
		(layer "In5.Cu")
		(net "SSD3_PWR_EN_R")
	)
	(segment
		(start 109.42955 -70.962266)
		(end 109.42955 -74.41311)
		(width 0.15494)
		(layer "In5.Cu")
		(net "SSD3_PWR_EN_R")
	)
	(segment
		(start 125.0442 -185.495946)
		(end 125.0442 -199.770746)
		(width 0.15494)
		(layer "In5.Cu")
		(net "SSD3_PWR_EN_R")
	)
	(segment
		(start 120.8278 -211.048854)
		(end 119.205248 -212.671406)
		(width 0.15494)
		(layer "In5.Cu")
		(net "SSD3_PWR_EN_R")
	)
	(segment
		(start 125.0442 -199.770746)
		(end 120.8278 -203.987146)
		(width 0.15494)
		(layer "In5.Cu")
		(net "SSD3_PWR_EN_R")
	)
	(segment
		(start 121.3739 -181.825646)
		(end 125.0442 -185.495946)
		(width 0.15494)
		(layer "In5.Cu")
		(net "SSD3_PWR_EN_R")
	)
	(segment
		(start 100.291392 -65.08369)
		(end 99.731322 -65.64376)
		(width 0.15494)
		(layer "In5.Cu")
		(net "SSD3_PWR_EN_R")
	)
	(segment
		(start 104.18318 -58.264552)
		(end 104.18318 -64.451484)
		(width 0.15494)
		(layer "In5.Cu")
		(net "SSD3_PWR_EN_R")
	)
	(segment
		(start 121.176288 -224.46107)
		(end 119.818404 -224.46107)
		(width 0.15494)
		(layer "In15.Cu")
		(net "SSD3_PWR_EN_R")
	)
	(segment
		(start 146.101816 -228.594666)
		(end 144.636744 -230.059738)
		(width 0.15494)
		(layer "In15.Cu")
		(net "SSD3_PWR_EN_R")
	)
	(segment
		(start 266.805664 -236.381036)
		(end 264.151364 -233.726736)
		(width 0.15494)
		(layer "In15.Cu")
		(net "SSD3_PWR_EN_R")
	)
	(segment
		(start 223.5962 -238.9632)
		(end 223.0882 -238.4552)
		(width 0.15494)
		(layer "In15.Cu")
		(net "SSD3_PWR_EN_R")
	)
	(segment
		(start 338.100416 -237.39221)
		(end 336.710528 -238.782098)
		(width 0.15494)
		(layer "In15.Cu")
		(net "SSD3_PWR_EN_R")
	)
	(segment
		(start 275.807424 -240.098326)
		(end 269.401544 -240.098326)
		(width 0.15494)
		(layer "In15.Cu")
		(net "SSD3_PWR_EN_R")
	)
	(segment
		(start 338.48929 -235.97108)
		(end 338.100416 -236.359954)
		(width 0.15494)
		(layer "In15.Cu")
		(net "SSD3_PWR_EN_R")
	)
	(segment
		(start 324.525894 -240.960148)
		(end 276.669246 -240.960148)
		(width 0.15494)
		(layer "In15.Cu")
		(net "SSD3_PWR_EN_R")
	)
	(segment
		(start 215.852502 -239.18545)
		(end 214.836248 -238.169196)
		(width 0.15494)
		(layer "In15.Cu")
		(net "SSD3_PWR_EN_R")
	)
	(segment
		(start 257.836416 -232.7148)
		(end 254.110744 -232.7148)
		(width 0.15494)
		(layer "In15.Cu")
		(net "SSD3_PWR_EN_R")
	)
	(segment
		(start 139.378436 -231.37622)
		(end 136.58342 -231.37622)
		(width 0.15494)
		(layer "In15.Cu")
		(net "SSD3_PWR_EN_R")
	)
	(segment
		(start 336.710528 -238.782098)
		(end 332.900782 -238.782098)
		(width 0.15494)
		(layer "In15.Cu")
		(net "SSD3_PWR_EN_R")
	)
	(segment
		(start 261.824216 -232.22204)
		(end 258.329176 -232.22204)
		(width 0.15494)
		(layer "In15.Cu")
		(net "SSD3_PWR_EN_R")
	)
	(segment
		(start 328.87031 -240.14303)
		(end 328.32421 -240.68913)
		(width 0.15494)
		(layer "In15.Cu")
		(net "SSD3_PWR_EN_R")
	)
	(segment
		(start 241.602514 -239.395)
		(end 241.01425 -238.806736)
		(width 0.15494)
		(layer "In15.Cu")
		(net "SSD3_PWR_EN_R")
	)
	(segment
		(start 131.514088 -231.990392)
		(end 128.70561 -231.990392)
		(width 0.15494)
		(layer "In15.Cu")
		(net "SSD3_PWR_EN_R")
	)
	(segment
		(start 144.636744 -230.059738)
		(end 140.694918 -230.059738)
		(width 0.15494)
		(layer "In15.Cu")
		(net "SSD3_PWR_EN_R")
	)
	(segment
		(start 247.430544 -239.395)
		(end 241.602514 -239.395)
		(width 0.15494)
		(layer "In15.Cu")
		(net "SSD3_PWR_EN_R")
	)
	(segment
		(start 241.01425 -238.806736)
		(end 230.461058 -238.806736)
		(width 0.15494)
		(layer "In15.Cu")
		(net "SSD3_PWR_EN_R")
	)
	(segment
		(start 222.4024 -238.4552)
		(end 221.67215 -239.18545)
		(width 0.15494)
		(layer "In15.Cu")
		(net "SSD3_PWR_EN_R")
	)
	(segment
		(start 230.456486 -238.811308)
		(end 230.100378 -238.4552)
		(width 0.15494)
		(layer "In15.Cu")
		(net "SSD3_PWR_EN_R")
	)
	(segment
		(start 128.70561 -231.990392)
		(end 121.176288 -224.46107)
		(width 0.15494)
		(layer "In15.Cu")
		(net "SSD3_PWR_EN_R")
	)
	(segment
		(start 136.58342 -231.37622)
		(end 136.233662 -231.026462)
		(width 0.15494)
		(layer "In15.Cu")
		(net "SSD3_PWR_EN_R")
	)
	(segment
		(start 185.965592 -232.9942)
		(end 162.26536 -232.9942)
		(width 0.15494)
		(layer "In15.Cu")
		(net "SSD3_PWR_EN_R")
	)
	(segment
		(start 339.60308 -235.97108)
		(end 338.48929 -235.97108)
		(width 0.15494)
		(layer "In15.Cu")
		(net "SSD3_PWR_EN_R")
	)
	(segment
		(start 328.32421 -240.68913)
		(end 327.33234 -240.68913)
		(width 0.15494)
		(layer "In15.Cu")
		(net "SSD3_PWR_EN_R")
	)
	(segment
		(start 269.401544 -240.098326)
		(end 266.805664 -237.502446)
		(width 0.15494)
		(layer "In15.Cu")
		(net "SSD3_PWR_EN_R")
	)
	(segment
		(start 262.747252 -233.145076)
		(end 261.824216 -232.22204)
		(width 0.15494)
		(layer "In15.Cu")
		(net "SSD3_PWR_EN_R")
	)
	(segment
		(start 332.900782 -238.782098)
		(end 331.53985 -240.14303)
		(width 0.15494)
		(layer "In15.Cu")
		(net "SSD3_PWR_EN_R")
	)
	(segment
		(start 258.329176 -232.22204)
		(end 257.836416 -232.7148)
		(width 0.15494)
		(layer "In15.Cu")
		(net "SSD3_PWR_EN_R")
	)
	(segment
		(start 326.37095 -241.65052)
		(end 325.216266 -241.65052)
		(width 0.15494)
		(layer "In15.Cu")
		(net "SSD3_PWR_EN_R")
	)
	(segment
		(start 230.100378 -238.4552)
		(end 225.5774 -238.4552)
		(width 0.15494)
		(layer "In15.Cu")
		(net "SSD3_PWR_EN_R")
	)
	(segment
		(start 225.5774 -238.4552)
		(end 225.0694 -238.9632)
		(width 0.15494)
		(layer "In15.Cu")
		(net "SSD3_PWR_EN_R")
	)
	(segment
		(start 225.0694 -238.9632)
		(end 223.5962 -238.9632)
		(width 0.15494)
		(layer "In15.Cu")
		(net "SSD3_PWR_EN_R")
	)
	(segment
		(start 339.979 -236.347)
		(end 339.60308 -235.97108)
		(width 0.15494)
		(layer "In15.Cu")
		(net "SSD3_PWR_EN_R")
	)
	(segment
		(start 331.53985 -240.14303)
		(end 328.87031 -240.14303)
		(width 0.15494)
		(layer "In15.Cu")
		(net "SSD3_PWR_EN_R")
	)
	(segment
		(start 325.216266 -241.65052)
		(end 324.525894 -240.960148)
		(width 0.15494)
		(layer "In15.Cu")
		(net "SSD3_PWR_EN_R")
	)
	(segment
		(start 132.478018 -231.026462)
		(end 131.514088 -231.990392)
		(width 0.15494)
		(layer "In15.Cu")
		(net "SSD3_PWR_EN_R")
	)
	(segment
		(start 254.110744 -232.7148)
		(end 247.430544 -239.395)
		(width 0.15494)
		(layer "In15.Cu")
		(net "SSD3_PWR_EN_R")
	)
	(segment
		(start 162.26536 -232.9942)
		(end 157.865826 -228.594666)
		(width 0.15494)
		(layer "In15.Cu")
		(net "SSD3_PWR_EN_R")
	)
	(segment
		(start 266.805664 -237.502446)
		(end 266.805664 -236.381036)
		(width 0.15494)
		(layer "In15.Cu")
		(net "SSD3_PWR_EN_R")
	)
	(segment
		(start 338.100416 -236.359954)
		(end 338.100416 -237.39221)
		(width 0.15494)
		(layer "In15.Cu")
		(net "SSD3_PWR_EN_R")
	)
	(segment
		(start 157.865826 -228.594666)
		(end 146.101816 -228.594666)
		(width 0.15494)
		(layer "In15.Cu")
		(net "SSD3_PWR_EN_R")
	)
	(segment
		(start 140.694918 -230.059738)
		(end 139.378436 -231.37622)
		(width 0.15494)
		(layer "In15.Cu")
		(net "SSD3_PWR_EN_R")
	)
	(segment
		(start 191.140588 -238.169196)
		(end 185.965592 -232.9942)
		(width 0.15494)
		(layer "In15.Cu")
		(net "SSD3_PWR_EN_R")
	)
	(segment
		(start 223.0882 -238.4552)
		(end 222.4024 -238.4552)
		(width 0.15494)
		(layer "In15.Cu")
		(net "SSD3_PWR_EN_R")
	)
	(segment
		(start 327.33234 -240.68913)
		(end 326.37095 -241.65052)
		(width 0.15494)
		(layer "In15.Cu")
		(net "SSD3_PWR_EN_R")
	)
	(segment
		(start 276.669246 -240.960148)
		(end 275.807424 -240.098326)
		(width 0.15494)
		(layer "In15.Cu")
		(net "SSD3_PWR_EN_R")
	)
	(segment
		(start 221.67215 -239.18545)
		(end 215.852502 -239.18545)
		(width 0.15494)
		(layer "In15.Cu")
		(net "SSD3_PWR_EN_R")
	)
	(segment
		(start 136.233662 -231.026462)
		(end 132.478018 -231.026462)
		(width 0.15494)
		(layer "In15.Cu")
		(net "SSD3_PWR_EN_R")
	)
	(segment
		(start 230.461058 -238.806736)
		(end 230.456486 -238.811308)
		(width 0.15494)
		(layer "In15.Cu")
		(net "SSD3_PWR_EN_R")
	)
	(segment
		(start 214.836248 -238.169196)
		(end 191.140588 -238.169196)
		(width 0.15494)
		(layer "In15.Cu")
		(net "SSD3_PWR_EN_R")
	)
	(segment
		(start 264.151364 -233.726736)
		(end 262.747252 -233.145076)
		(width 0.15494)
		(layer "In15.Cu")
		(net "SSD3_PWR_EN_R")
	)
	(segment
		(start 398.182084 -35.876738)
		(end 397.470884 -35.876738)
		(width 0.13208)
		(layer "F.Cu")
		(net "PWRGD_P3V3_SSD14_R")
	)
	(segment
		(start 401.535138 -36.232592)
		(end 400.964146 -35.6616)
		(width 0.13208)
		(layer "F.Cu")
		(net "PWRGD_P3V3_SSD14_R")
	)
	(segment
		(start 396.727934 -35.876738)
		(end 397.470884 -35.876738)
		(width 0.13208)
		(layer "F.Cu")
		(net "PWRGD_P3V3_SSD14_R")
	)
	(segment
		(start 342.093804 -211.98713)
		(end 341.694008 -211.587334)
		(width 0.13208)
		(layer "F.Cu")
		(net "PWRGD_P3V3_SSD14_R")
	)
	(segment
		(start 400.964146 -35.6616)
		(end 398.397222 -35.6616)
		(width 0.13208)
		(layer "F.Cu")
		(net "PWRGD_P3V3_SSD14_R")
	)
	(segment
		(start 401.89531 -36.232592)
		(end 401.535138 -36.232592)
		(width 0.13208)
		(layer "F.Cu")
		(net "PWRGD_P3V3_SSD14_R")
	)
	(segment
		(start 398.397222 -35.6616)
		(end 398.182084 -35.876738)
		(width 0.13208)
		(layer "F.Cu")
		(net "PWRGD_P3V3_SSD14_R")
	)
	(segment
		(start 408.911044 -61.386974)
		(end 408.911044 -62.051438)
		(width 0.13208)
		(layer "F.Cu")
		(net "PWRGD_P3V3_SSD14_R")
	)
	(via
		(at 405.519636 -96.45904)
		(size 0.508)
		(drill 0.254)
		(layers "F.Cu" "B.Cu")
		(net "PWRGD_P3V3_SSD14_R")
	)
	(via
		(at 408.911044 -62.051438)
		(size 0.508)
		(drill 0.254)
		(layers "F.Cu" "B.Cu")
		(net "PWRGD_P3V3_SSD14_R")
	)
	(via
		(at 341.694008 -211.587334)
		(size 0.4572)
		(drill 0.254)
		(layers "F.Cu" "B.Cu")
		(net "PWRGD_P3V3_SSD14_R")
	)
	(via
		(at 353.874832 -108.739686)
		(size 0.508)
		(drill 0.254)
		(layers "F.Cu" "B.Cu")
		(net "PWRGD_P3V3_SSD14_R")
	)
	(via
		(at 397.470884 -35.876738)
		(size 0.508)
		(drill 0.254)
		(layers "F.Cu" "B.Cu")
		(net "PWRGD_P3V3_SSD14_R")
	)
	(segment
		(start 409.42006 -62.051438)
		(end 408.911044 -62.051438)
		(width 0.15494)
		(layer "In5.Cu")
		(net "PWRGD_P3V3_SSD14_R")
	)
	(segment
		(start 408.911044 -62.051438)
		(end 408.911044 -64.113156)
		(width 0.15494)
		(layer "In5.Cu")
		(net "PWRGD_P3V3_SSD14_R")
	)
	(segment
		(start 400.191224 -35.876738)
		(end 410.150818 -45.836332)
		(width 0.15494)
		(layer "In5.Cu")
		(net "PWRGD_P3V3_SSD14_R")
	)
	(segment
		(start 410.150818 -61.32068)
		(end 409.42006 -62.051438)
		(width 0.15494)
		(layer "In5.Cu")
		(net "PWRGD_P3V3_SSD14_R")
	)
	(segment
		(start 410.150818 -45.836332)
		(end 410.150818 -61.32068)
		(width 0.15494)
		(layer "In5.Cu")
		(net "PWRGD_P3V3_SSD14_R")
	)
	(segment
		(start 403.591522 -69.432678)
		(end 403.591522 -94.530926)
		(width 0.15494)
		(layer "In5.Cu")
		(net "PWRGD_P3V3_SSD14_R")
	)
	(segment
		(start 408.911044 -64.113156)
		(end 403.591522 -69.432678)
		(width 0.15494)
		(layer "In5.Cu")
		(net "PWRGD_P3V3_SSD14_R")
	)
	(segment
		(start 397.470884 -35.876738)
		(end 400.191224 -35.876738)
		(width 0.15494)
		(layer "In5.Cu")
		(net "PWRGD_P3V3_SSD14_R")
	)
	(segment
		(start 403.591522 -94.530926)
		(end 405.519636 -96.45904)
		(width 0.15494)
		(layer "In5.Cu")
		(net "PWRGD_P3V3_SSD14_R")
	)
	(segment
		(start 343.594436 -189.695836)
		(end 348.003876 -185.286396)
		(width 0.15494)
		(layer "In7.Cu")
		(net "PWRGD_P3V3_SSD14_R")
	)
	(segment
		(start 341.827866 -209.275426)
		(end 344.68943 -206.413862)
		(width 0.15494)
		(layer "In7.Cu")
		(net "PWRGD_P3V3_SSD14_R")
	)
	(segment
		(start 348.003876 -169.162476)
		(end 345.719146 -166.877746)
		(width 0.15494)
		(layer "In7.Cu")
		(net "PWRGD_P3V3_SSD14_R")
	)
	(segment
		(start 344.68943 -206.413862)
		(end 344.68943 -205.497176)
		(width 0.15494)
		(layer "In7.Cu")
		(net "PWRGD_P3V3_SSD14_R")
	)
	(segment
		(start 353.57308 -109.041438)
		(end 353.874832 -108.739686)
		(width 0.15494)
		(layer "In7.Cu")
		(net "PWRGD_P3V3_SSD14_R")
	)
	(segment
		(start 353.34702 -119.270526)
		(end 353.34702 -109.587538)
		(width 0.15494)
		(layer "In7.Cu")
		(net "PWRGD_P3V3_SSD14_R")
	)
	(segment
		(start 344.68943 -205.497176)
		(end 345.186 -205.000606)
		(width 0.15494)
		(layer "In7.Cu")
		(net "PWRGD_P3V3_SSD14_R")
	)
	(segment
		(start 353.313492 -119.37111)
		(end 353.34702 -119.270526)
		(width 0.15494)
		(layer "In7.Cu")
		(net "PWRGD_P3V3_SSD14_R")
	)
	(segment
		(start 345.186 -200.273412)
		(end 343.594436 -196.43217)
		(width 0.15494)
		(layer "In7.Cu")
		(net "PWRGD_P3V3_SSD14_R")
	)
	(segment
		(start 345.719146 -166.877746)
		(end 345.719146 -126.965456)
		(width 0.15494)
		(layer "In7.Cu")
		(net "PWRGD_P3V3_SSD14_R")
	)
	(segment
		(start 345.719146 -126.965456)
		(end 353.313492 -119.37111)
		(width 0.15494)
		(layer "In7.Cu")
		(net "PWRGD_P3V3_SSD14_R")
	)
	(segment
		(start 353.34702 -109.587538)
		(end 353.57308 -109.041438)
		(width 0.15494)
		(layer "In7.Cu")
		(net "PWRGD_P3V3_SSD14_R")
	)
	(segment
		(start 345.186 -205.000606)
		(end 345.186 -200.273412)
		(width 0.15494)
		(layer "In7.Cu")
		(net "PWRGD_P3V3_SSD14_R")
	)
	(segment
		(start 341.694008 -211.587334)
		(end 341.694008 -210.702398)
		(width 0.15494)
		(layer "In7.Cu")
		(net "PWRGD_P3V3_SSD14_R")
	)
	(segment
		(start 348.003876 -185.286396)
		(end 348.003876 -169.162476)
		(width 0.15494)
		(layer "In7.Cu")
		(net "PWRGD_P3V3_SSD14_R")
	)
	(segment
		(start 343.594436 -196.43217)
		(end 343.594436 -189.695836)
		(width 0.15494)
		(layer "In7.Cu")
		(net "PWRGD_P3V3_SSD14_R")
	)
	(segment
		(start 341.694008 -210.702398)
		(end 341.827866 -210.56854)
		(width 0.15494)
		(layer "In7.Cu")
		(net "PWRGD_P3V3_SSD14_R")
	)
	(segment
		(start 341.827866 -210.56854)
		(end 341.827866 -209.275426)
		(width 0.15494)
		(layer "In7.Cu")
		(net "PWRGD_P3V3_SSD14_R")
	)
	(segment
		(start 377.440444 -108.183934)
		(end 379.949202 -105.675176)
		(width 0.15494)
		(layer "In13.Cu")
		(net "PWRGD_P3V3_SSD14_R")
	)
	(segment
		(start 362.020866 -108.183934)
		(end 377.440444 -108.183934)
		(width 0.15494)
		(layer "In13.Cu")
		(net "PWRGD_P3V3_SSD14_R")
	)
	(segment
		(start 360.3752 -109.8296)
		(end 362.020866 -108.183934)
		(width 0.15494)
		(layer "In13.Cu")
		(net "PWRGD_P3V3_SSD14_R")
	)
	(segment
		(start 354.964746 -109.8296)
		(end 360.3752 -109.8296)
		(width 0.15494)
		(layer "In13.Cu")
		(net "PWRGD_P3V3_SSD14_R")
	)
	(segment
		(start 353.874832 -108.739686)
		(end 354.964746 -109.8296)
		(width 0.15494)
		(layer "In13.Cu")
		(net "PWRGD_P3V3_SSD14_R")
	)
	(segment
		(start 379.949202 -105.675176)
		(end 379.949202 -102.498144)
		(width 0.15494)
		(layer "In13.Cu")
		(net "PWRGD_P3V3_SSD14_R")
	)
	(segment
		(start 403.680422 -98.298254)
		(end 405.519636 -96.45904)
		(width 0.15494)
		(layer "In13.Cu")
		(net "PWRGD_P3V3_SSD14_R")
	)
	(segment
		(start 384.149092 -98.298254)
		(end 403.680422 -98.298254)
		(width 0.15494)
		(layer "In13.Cu")
		(net "PWRGD_P3V3_SSD14_R")
	)
	(segment
		(start 379.949202 -102.498144)
		(end 384.149092 -98.298254)
		(width 0.15494)
		(layer "In13.Cu")
		(net "PWRGD_P3V3_SSD14_R")
	)
	(segment
		(start 106.969814 -82.53222)
		(end 107.038902 -82.601308)
		(width 0.13462)
		(layer "F.Cu")
		(net "CLK_100M_DB800ZL_SSD0_DN")
	)
	(segment
		(start 106.169968 -80.998314)
		(end 106.969814 -81.79816)
		(width 0.13462)
		(layer "F.Cu")
		(net "CLK_100M_DB800ZL_SSD0_DN")
	)
	(segment
		(start 106.496358 -80.222344)
		(end 106.169968 -80.548734)
		(width 0.13462)
		(layer "F.Cu")
		(net "CLK_100M_DB800ZL_SSD0_DN")
	)
	(segment
		(start 106.969814 -81.79816)
		(end 106.969814 -82.53222)
		(width 0.13462)
		(layer "F.Cu")
		(net "CLK_100M_DB800ZL_SSD0_DN")
	)
	(segment
		(start 106.169968 -80.548734)
		(end 106.169968 -80.998314)
		(width 0.13462)
		(layer "F.Cu")
		(net "CLK_100M_DB800ZL_SSD0_DN")
	)
	(segment
		(start 107.038902 -82.601308)
		(end 107.038902 -83.029044)
		(width 0.13462)
		(layer "F.Cu")
		(net "CLK_100M_DB800ZL_SSD0_DN")
	)
	(segment
		(start 31.908496 -311.613296)
		(end 30.867858 -311.613296)
		(width 0.13208)
		(layer "F.Cu")
		(net "PU_PEX0_PAD_TRI_L")
	)
	(segment
		(start 34.403792 -312.268108)
		(end 34.3535 -312.3184)
		(width 0.13208)
		(layer "F.Cu")
		(net "PU_PEX0_PAD_TRI_L")
	)
	(segment
		(start 30.867858 -311.613296)
		(end 30.54477 -311.290208)
		(width 0.13208)
		(layer "F.Cu")
		(net "PU_PEX0_PAD_TRI_L")
	)
	(segment
		(start 32.6136 -312.3184)
		(end 31.908496 -311.613296)
		(width 0.13208)
		(layer "F.Cu")
		(net "PU_PEX0_PAD_TRI_L")
	)
	(segment
		(start 34.3535 -312.3184)
		(end 32.6136 -312.3184)
		(width 0.13208)
		(layer "F.Cu")
		(net "PU_PEX0_PAD_TRI_L")
	)
	(via
		(at 34.403792 -312.268108)
		(size 0.508)
		(drill 0.254)
		(layers "F.Cu" "B.Cu")
		(net "PU_PEX0_PAD_TRI_L")
	)
	(via
		(at 51.099974 -309.199788)
		(size 0.4064)
		(drill 0.2032)
		(layers "F.Cu" "B.Cu")
		(net "PU_PEX0_PAD_TRI_L")
	)
	(segment
		(start 50.393346 -312.4708)
		(end 35.635946 -312.4708)
		(width 0.13208)
		(layer "B.Cu")
		(net "PU_PEX0_PAD_TRI_L")
	)
	(segment
		(start 35.635946 -312.4708)
		(end 35.433254 -312.268108)
		(width 0.13208)
		(layer "B.Cu")
		(net "PU_PEX0_PAD_TRI_L")
	)
	(segment
		(start 51.099974 -309.199788)
		(end 50.624994 -309.674768)
		(width 0.13208)
		(layer "B.Cu")
		(net "PU_PEX0_PAD_TRI_L")
	)
	(segment
		(start 50.624994 -309.674768)
		(end 50.624994 -312.239152)
		(width 0.13208)
		(layer "B.Cu")
		(net "PU_PEX0_PAD_TRI_L")
	)
	(segment
		(start 35.433254 -312.268108)
		(end 34.403792 -312.268108)
		(width 0.13208)
		(layer "B.Cu")
		(net "PU_PEX0_PAD_TRI_L")
	)
	(segment
		(start 50.624994 -312.239152)
		(end 50.393346 -312.4708)
		(width 0.13208)
		(layer "B.Cu")
		(net "PU_PEX0_PAD_TRI_L")
	)
	(segment
		(start 134.292594 -182.661306)
		(end 134.292594 -183.89473)
		(width 0.13462)
		(layer "F.Cu")
		(net "CLK_100M_DB2000QL_GPU_REF0_DN")
	)
	(segment
		(start 133.577584 -181.946296)
		(end 134.292594 -182.661306)
		(width 0.13462)
		(layer "F.Cu")
		(net "CLK_100M_DB2000QL_GPU_REF0_DN")
	)
	(segment
		(start 133.471158 -180.400452)
		(end 133.577584 -180.506878)
		(width 0.13462)
		(layer "F.Cu")
		(net "CLK_100M_DB2000QL_GPU_REF0_DN")
	)
	(segment
		(start 134.292594 -183.89473)
		(end 133.93039 -184.256934)
		(width 0.13462)
		(layer "F.Cu")
		(net "CLK_100M_DB2000QL_GPU_REF0_DN")
	)
	(segment
		(start 133.577584 -180.506878)
		(end 133.577584 -181.946296)
		(width 0.13462)
		(layer "F.Cu")
		(net "CLK_100M_DB2000QL_GPU_REF0_DN")
	)
	(segment
		(start 372.326408 -19.453098)
		(end 372.368064 -19.453098)
		(width 0.13208)
		(layer "F.Cu")
		(net "SMB_ISO_SSD12_SDA")
	)
	(segment
		(start 375.76252 -23.337266)
		(end 375.76252 -23.946866)
		(width 0.13208)
		(layer "F.Cu")
		(net "SMB_ISO_SSD12_SDA")
	)
	(segment
		(start 371.556534 -20.467574)
		(end 371.556534 -20.222972)
		(width 0.13208)
		(layer "F.Cu")
		(net "SMB_ISO_SSD12_SDA")
	)
	(segment
		(start 375.311924 -15.351252)
		(end 375.311924 -16.363188)
		(width 0.13208)
		(layer "F.Cu")
		(net "SMB_ISO_SSD12_SDA")
	)
	(segment
		(start 374.316244 -19.453098)
		(end 372.368064 -19.453098)
		(width 0.13208)
		(layer "F.Cu")
		(net "SMB_ISO_SSD12_SDA")
	)
	(segment
		(start 375.235724 -16.439388)
		(end 375.235724 -18.533618)
		(width 0.13208)
		(layer "F.Cu")
		(net "SMB_ISO_SSD12_SDA")
	)
	(segment
		(start 371.556534 -20.222972)
		(end 372.326408 -19.453098)
		(width 0.13208)
		(layer "F.Cu")
		(net "SMB_ISO_SSD12_SDA")
	)
	(segment
		(start 375.311924 -16.363188)
		(end 375.235724 -16.439388)
		(width 0.13208)
		(layer "F.Cu")
		(net "SMB_ISO_SSD12_SDA")
	)
	(segment
		(start 375.235724 -18.533618)
		(end 374.316244 -19.453098)
		(width 0.13208)
		(layer "F.Cu")
		(net "SMB_ISO_SSD12_SDA")
	)
	(via
		(at 375.76252 -23.946866)
		(size 0.508)
		(drill 0.254)
		(layers "F.Cu" "B.Cu")
		(net "SMB_ISO_SSD12_SDA")
	)
	(via
		(at 375.311924 -15.351252)
		(size 0.508)
		(drill 0.254)
		(layers "F.Cu" "B.Cu")
		(net "SMB_ISO_SSD12_SDA")
	)
	(segment
		(start 375.76252 -23.946866)
		(end 377.335542 -22.373844)
		(width 0.13208)
		(layer "B.Cu")
		(net "SMB_ISO_SSD12_SDA")
	)
	(segment
		(start 375.311924 -15.420594)
		(end 375.311924 -15.351252)
		(width 0.13208)
		(layer "B.Cu")
		(net "SMB_ISO_SSD12_SDA")
	)
	(segment
		(start 377.335542 -22.373844)
		(end 377.335542 -17.444212)
		(width 0.13208)
		(layer "B.Cu")
		(net "SMB_ISO_SSD12_SDA")
	)
	(segment
		(start 377.335542 -17.444212)
		(end 375.311924 -15.420594)
		(width 0.13208)
		(layer "B.Cu")
		(net "SMB_ISO_SSD12_SDA")
	)
	(via
		(at 231.423718 -333.78902)
		(size 0.508)
		(drill 0.254)
		(layers "F.Cu" "B.Cu")
		(net "RST_GPU_PERST_0_BUF_R_N")
	)
	(via
		(at 55.273956 -378.376434)
		(size 0.508)
		(drill 0.254)
		(layers "F.Cu" "B.Cu")
		(net "RST_GPU_PERST_0_BUF_R_N")
	)
	(via
		(at 242.62715 -200.401936)
		(size 0.508)
		(drill 0.254)
		(layers "F.Cu" "B.Cu")
		(net "RST_GPU_PERST_0_BUF_R_N")
	)
	(via
		(at 104.394 -369.443)
		(size 0.508)
		(drill 0.254)
		(layers "F.Cu" "B.Cu")
		(net "RST_GPU_PERST_0_BUF_R_N")
	)
	(via
		(at 299.780706 -220.58122)
		(size 0.508)
		(drill 0.254)
		(layers "F.Cu" "B.Cu")
		(net "RST_GPU_PERST_0_BUF_R_N")
	)
	(via
		(at 200.570338 -362.589572)
		(size 0.508)
		(drill 0.254)
		(layers "F.Cu" "B.Cu")
		(net "RST_GPU_PERST_0_BUF_R_N")
	)
	(segment
		(start 239.391952 -232.667302)
		(end 239.391952 -230.810308)
		(width 0.13208)
		(layer "B.Cu")
		(net "RST_GPU_PERST_0_BUF_R_N")
	)
	(segment
		(start 115.598702 -362.289344)
		(end 198.16191 -362.289344)
		(width 0.13208)
		(layer "B.Cu")
		(net "RST_GPU_PERST_0_BUF_R_N")
	)
	(segment
		(start 241.516916 -219.459556)
		(end 241.516916 -209.411316)
		(width 0.13208)
		(layer "B.Cu")
		(net "RST_GPU_PERST_0_BUF_R_N")
	)
	(segment
		(start 259.371338 -299.630592)
		(end 259.371338 -284.77337)
		(width 0.13208)
		(layer "B.Cu")
		(net "RST_GPU_PERST_0_BUF_R_N")
	)
	(segment
		(start 239.391952 -230.810308)
		(end 237.827312 -229.245668)
		(width 0.13208)
		(layer "B.Cu")
		(net "RST_GPU_PERST_0_BUF_R_N")
	)
	(segment
		(start 200.273412 -362.886498)
		(end 200.570338 -362.589572)
		(width 0.13208)
		(layer "B.Cu")
		(net "RST_GPU_PERST_0_BUF_R_N")
	)
	(segment
		(start 236.539024 -328.673714)
		(end 248.849388 -328.673714)
		(width 0.13208)
		(layer "B.Cu")
		(net "RST_GPU_PERST_0_BUF_R_N")
	)
	(segment
		(start 240.956592 -203.605892)
		(end 240.970816 -203.588874)
		(width 0.13208)
		(layer "B.Cu")
		(net "RST_GPU_PERST_0_BUF_R_N")
	)
	(segment
		(start 259.371338 -284.77337)
		(end 259.253228 -284.65526)
		(width 0.13208)
		(layer "B.Cu")
		(net "RST_GPU_PERST_0_BUF_R_N")
	)
	(segment
		(start 231.423718 -333.78902)
		(end 236.539024 -328.673714)
		(width 0.13208)
		(layer "B.Cu")
		(net "RST_GPU_PERST_0_BUF_R_N")
	)
	(segment
		(start 260.362954 -300.027086)
		(end 259.767832 -300.027086)
		(width 0.13208)
		(layer "B.Cu")
		(net "RST_GPU_PERST_0_BUF_R_N")
	)
	(segment
		(start 259.253228 -284.65526)
		(end 259.253228 -281.81808)
		(width 0.13208)
		(layer "B.Cu")
		(net "RST_GPU_PERST_0_BUF_R_N")
	)
	(segment
		(start 198.759064 -362.886498)
		(end 200.273412 -362.886498)
		(width 0.13208)
		(layer "B.Cu")
		(net "RST_GPU_PERST_0_BUF_R_N")
	)
	(segment
		(start 241.491516 -221.591632)
		(end 241.846354 -221.236794)
		(width 0.13208)
		(layer "B.Cu")
		(net "RST_GPU_PERST_0_BUF_R_N")
	)
	(segment
		(start 239.386872 -237.492286)
		(end 239.386872 -232.672382)
		(width 0.13208)
		(layer "B.Cu")
		(net "RST_GPU_PERST_0_BUF_R_N")
	)
	(segment
		(start 237.827312 -229.245668)
		(end 237.827312 -226.628452)
		(width 0.13208)
		(layer "B.Cu")
		(net "RST_GPU_PERST_0_BUF_R_N")
	)
	(segment
		(start 250.17476 -255.327658)
		(end 245.191534 -243.296948)
		(width 0.13208)
		(layer "B.Cu")
		(net "RST_GPU_PERST_0_BUF_R_N")
	)
	(segment
		(start 240.891314 -223.413828)
		(end 240.891314 -221.868238)
		(width 0.13208)
		(layer "B.Cu")
		(net "RST_GPU_PERST_0_BUF_R_N")
	)
	(segment
		(start 241.846354 -219.788994)
		(end 241.516916 -219.459556)
		(width 0.13208)
		(layer "B.Cu")
		(net "RST_GPU_PERST_0_BUF_R_N")
	)
	(segment
		(start 240.970816 -203.588874)
		(end 242.112546 -202.447144)
		(width 0.13208)
		(layer "B.Cu")
		(net "RST_GPU_PERST_0_BUF_R_N")
	)
	(segment
		(start 260.737604 -300.401736)
		(end 260.362954 -300.027086)
		(width 0.13208)
		(layer "B.Cu")
		(net "RST_GPU_PERST_0_BUF_R_N")
	)
	(segment
		(start 238.681514 -225.77425)
		(end 238.962946 -225.094546)
		(width 0.13208)
		(layer "B.Cu")
		(net "RST_GPU_PERST_0_BUF_R_N")
	)
	(segment
		(start 240.956592 -208.850992)
		(end 240.956592 -203.605892)
		(width 0.13208)
		(layer "B.Cu")
		(net "RST_GPU_PERST_0_BUF_R_N")
	)
	(segment
		(start 259.767832 -300.027086)
		(end 259.371338 -299.630592)
		(width 0.13208)
		(layer "B.Cu")
		(net "RST_GPU_PERST_0_BUF_R_N")
	)
	(segment
		(start 238.962946 -224.973896)
		(end 239.358424 -224.578418)
		(width 0.13208)
		(layer "B.Cu")
		(net "RST_GPU_PERST_0_BUF_R_N")
	)
	(segment
		(start 259.253228 -281.81808)
		(end 255.94818 -278.513032)
		(width 0.13208)
		(layer "B.Cu")
		(net "RST_GPU_PERST_0_BUF_R_N")
	)
	(segment
		(start 250.20016 -264.635996)
		(end 250.20016 -255.389126)
		(width 0.13208)
		(layer "B.Cu")
		(net "RST_GPU_PERST_0_BUF_R_N")
	)
	(segment
		(start 238.962946 -225.094546)
		(end 238.962946 -224.973896)
		(width 0.13208)
		(layer "B.Cu")
		(net "RST_GPU_PERST_0_BUF_R_N")
	)
	(segment
		(start 105.114852 -368.722148)
		(end 109.165898 -368.722148)
		(width 0.13208)
		(layer "B.Cu")
		(net "RST_GPU_PERST_0_BUF_R_N")
	)
	(segment
		(start 239.386872 -232.672382)
		(end 239.391952 -232.667302)
		(width 0.13208)
		(layer "B.Cu")
		(net "RST_GPU_PERST_0_BUF_R_N")
	)
	(segment
		(start 245.191534 -243.296948)
		(end 239.386872 -237.492286)
		(width 0.13208)
		(layer "B.Cu")
		(net "RST_GPU_PERST_0_BUF_R_N")
	)
	(segment
		(start 237.827312 -226.628452)
		(end 238.681514 -225.77425)
		(width 0.13208)
		(layer "B.Cu")
		(net "RST_GPU_PERST_0_BUF_R_N")
	)
	(segment
		(start 240.891314 -221.868238)
		(end 241.16792 -221.591632)
		(width 0.13208)
		(layer "B.Cu")
		(net "RST_GPU_PERST_0_BUF_R_N")
	)
	(segment
		(start 248.849388 -328.673714)
		(end 249.679714 -327.843388)
		(width 0.13208)
		(layer "B.Cu")
		(net "RST_GPU_PERST_0_BUF_R_N")
	)
	(segment
		(start 255.94818 -278.513032)
		(end 250.20016 -264.635996)
		(width 0.13208)
		(layer "B.Cu")
		(net "RST_GPU_PERST_0_BUF_R_N")
	)
	(segment
		(start 242.112546 -202.447144)
		(end 242.112546 -200.91654)
		(width 0.13208)
		(layer "B.Cu")
		(net "RST_GPU_PERST_0_BUF_R_N")
	)
	(segment
		(start 104.394 -369.443)
		(end 105.114852 -368.722148)
		(width 0.13208)
		(layer "B.Cu")
		(net "RST_GPU_PERST_0_BUF_R_N")
	)
	(segment
		(start 241.846354 -221.236794)
		(end 241.846354 -219.788994)
		(width 0.13208)
		(layer "B.Cu")
		(net "RST_GPU_PERST_0_BUF_R_N")
	)
	(segment
		(start 109.165898 -368.722148)
		(end 115.598702 -362.289344)
		(width 0.13208)
		(layer "B.Cu")
		(net "RST_GPU_PERST_0_BUF_R_N")
	)
	(segment
		(start 299.067474 -221.294452)
		(end 299.780706 -220.58122)
		(width 0.13208)
		(layer "B.Cu")
		(net "RST_GPU_PERST_0_BUF_R_N")
	)
	(segment
		(start 239.726724 -224.578418)
		(end 240.891314 -223.413828)
		(width 0.13208)
		(layer "B.Cu")
		(net "RST_GPU_PERST_0_BUF_R_N")
	)
	(segment
		(start 250.20016 -255.389126)
		(end 250.17476 -255.327658)
		(width 0.13208)
		(layer "B.Cu")
		(net "RST_GPU_PERST_0_BUF_R_N")
	)
	(segment
		(start 241.16792 -221.591632)
		(end 241.491516 -221.591632)
		(width 0.13208)
		(layer "B.Cu")
		(net "RST_GPU_PERST_0_BUF_R_N")
	)
	(segment
		(start 198.16191 -362.289344)
		(end 198.759064 -362.886498)
		(width 0.13208)
		(layer "B.Cu")
		(net "RST_GPU_PERST_0_BUF_R_N")
	)
	(segment
		(start 260.737604 -301.145194)
		(end 260.737604 -300.401736)
		(width 0.13208)
		(layer "B.Cu")
		(net "RST_GPU_PERST_0_BUF_R_N")
	)
	(segment
		(start 241.516916 -209.411316)
		(end 240.956592 -208.850992)
		(width 0.13208)
		(layer "B.Cu")
		(net "RST_GPU_PERST_0_BUF_R_N")
	)
	(segment
		(start 242.112546 -200.91654)
		(end 242.62715 -200.401936)
		(width 0.13208)
		(layer "B.Cu")
		(net "RST_GPU_PERST_0_BUF_R_N")
	)
	(segment
		(start 239.358424 -224.578418)
		(end 239.726724 -224.578418)
		(width 0.13208)
		(layer "B.Cu")
		(net "RST_GPU_PERST_0_BUF_R_N")
	)
	(segment
		(start 249.679714 -327.843388)
		(end 260.737604 -301.145194)
		(width 0.13208)
		(layer "B.Cu")
		(net "RST_GPU_PERST_0_BUF_R_N")
	)
	(segment
		(start 231.423718 -333.78902)
		(end 230.67645 -333.78902)
		(width 0.15494)
		(layer "In5.Cu")
		(net "RST_GPU_PERST_0_BUF_R_N")
	)
	(segment
		(start 206.986632 -357.665528)
		(end 203.222606 -361.429554)
		(width 0.15494)
		(layer "In5.Cu")
		(net "RST_GPU_PERST_0_BUF_R_N")
	)
	(segment
		(start 219.220796 -357.665528)
		(end 206.986632 -357.665528)
		(width 0.15494)
		(layer "In5.Cu")
		(net "RST_GPU_PERST_0_BUF_R_N")
	)
	(segment
		(start 201.722228 -362.0516)
		(end 201.10831 -362.0516)
		(width 0.15494)
		(layer "In5.Cu")
		(net "RST_GPU_PERST_0_BUF_R_N")
	)
	(segment
		(start 203.222606 -361.429554)
		(end 201.722228 -362.0516)
		(width 0.15494)
		(layer "In5.Cu")
		(net "RST_GPU_PERST_0_BUF_R_N")
	)
	(segment
		(start 201.10831 -362.0516)
		(end 200.570338 -362.589572)
		(width 0.15494)
		(layer "In5.Cu")
		(net "RST_GPU_PERST_0_BUF_R_N")
	)
	(segment
		(start 230.67645 -333.78902)
		(end 230.3018 -334.16367)
		(width 0.15494)
		(layer "In5.Cu")
		(net "RST_GPU_PERST_0_BUF_R_N")
	)
	(segment
		(start 230.3018 -334.16367)
		(end 230.3018 -346.584524)
		(width 0.15494)
		(layer "In5.Cu")
		(net "RST_GPU_PERST_0_BUF_R_N")
	)
	(segment
		(start 230.3018 -346.584524)
		(end 219.220796 -357.665528)
		(width 0.15494)
		(layer "In5.Cu")
		(net "RST_GPU_PERST_0_BUF_R_N")
	)
	(segment
		(start 50.9016 -370.104162)
		(end 49.787556 -368.990118)
		(width 0.15494)
		(layer "In9.Cu")
		(net "RST_GPU_PERST_0_BUF_R_N")
	)
	(segment
		(start 49.787556 -368.990118)
		(end 47.71009 -368.990118)
		(width 0.15494)
		(layer "In9.Cu")
		(net "RST_GPU_PERST_0_BUF_R_N")
	)
	(segment
		(start 55.273956 -378.376434)
		(end 50.9016 -374.004078)
		(width 0.15494)
		(layer "In9.Cu")
		(net "RST_GPU_PERST_0_BUF_R_N")
	)
	(segment
		(start 50.9016 -374.004078)
		(end 50.9016 -370.104162)
		(width 0.15494)
		(layer "In9.Cu")
		(net "RST_GPU_PERST_0_BUF_R_N")
	)
	(segment
		(start 294.737028 -219.410534)
		(end 295.907714 -220.58122)
		(width 0.15494)
		(layer "In13.Cu")
		(net "RST_GPU_PERST_0_BUF_R_N")
	)
	(segment
		(start 273.3294 -213.180676)
		(end 273.3294 -217.9574)
		(width 0.15494)
		(layer "In13.Cu")
		(net "RST_GPU_PERST_0_BUF_R_N")
	)
	(segment
		(start 295.907714 -220.58122)
		(end 299.780706 -220.58122)
		(width 0.15494)
		(layer "In13.Cu")
		(net "RST_GPU_PERST_0_BUF_R_N")
	)
	(segment
		(start 258.911344 -208.788)
		(end 260.322822 -208.788)
		(width 0.15494)
		(layer "In13.Cu")
		(net "RST_GPU_PERST_0_BUF_R_N")
	)
	(segment
		(start 260.661404 -208.449418)
		(end 268.598142 -208.449418)
		(width 0.15494)
		(layer "In13.Cu")
		(net "RST_GPU_PERST_0_BUF_R_N")
	)
	(segment
		(start 246.964962 -202.057508)
		(end 253.041404 -202.057508)
		(width 0.15494)
		(layer "In13.Cu")
		(net "RST_GPU_PERST_0_BUF_R_N")
	)
	(segment
		(start 273.3294 -217.9574)
		(end 274.782534 -219.410534)
		(width 0.15494)
		(layer "In13.Cu")
		(net "RST_GPU_PERST_0_BUF_R_N")
	)
	(segment
		(start 242.62715 -200.401936)
		(end 245.30939 -200.401936)
		(width 0.15494)
		(layer "In13.Cu")
		(net "RST_GPU_PERST_0_BUF_R_N")
	)
	(segment
		(start 245.30939 -200.401936)
		(end 246.964962 -202.057508)
		(width 0.15494)
		(layer "In13.Cu")
		(net "RST_GPU_PERST_0_BUF_R_N")
	)
	(segment
		(start 256.8956 -205.911704)
		(end 256.8956 -206.772256)
		(width 0.15494)
		(layer "In13.Cu")
		(net "RST_GPU_PERST_0_BUF_R_N")
	)
	(segment
		(start 256.8956 -206.772256)
		(end 258.911344 -208.788)
		(width 0.15494)
		(layer "In13.Cu")
		(net "RST_GPU_PERST_0_BUF_R_N")
	)
	(segment
		(start 274.782534 -219.410534)
		(end 294.737028 -219.410534)
		(width 0.15494)
		(layer "In13.Cu")
		(net "RST_GPU_PERST_0_BUF_R_N")
	)
	(segment
		(start 260.322822 -208.788)
		(end 260.661404 -208.449418)
		(width 0.15494)
		(layer "In13.Cu")
		(net "RST_GPU_PERST_0_BUF_R_N")
	)
	(segment
		(start 253.041404 -202.057508)
		(end 256.8956 -205.911704)
		(width 0.15494)
		(layer "In13.Cu")
		(net "RST_GPU_PERST_0_BUF_R_N")
	)
	(segment
		(start 268.598142 -208.449418)
		(end 273.3294 -213.180676)
		(width 0.15494)
		(layer "In13.Cu")
		(net "RST_GPU_PERST_0_BUF_R_N")
	)
	(segment
		(start 91.604338 -389.4074)
		(end 96.74098 -384.270758)
		(width 0.15494)
		(layer "In15.Cu")
		(net "RST_GPU_PERST_0_BUF_R_N")
	)
	(segment
		(start 96.74098 -384.270758)
		(end 96.74098 -377.09602)
		(width 0.15494)
		(layer "In15.Cu")
		(net "RST_GPU_PERST_0_BUF_R_N")
	)
	(segment
		(start 56.0578 -379.160278)
		(end 56.0578 -383.895854)
		(width 0.15494)
		(layer "In15.Cu")
		(net "RST_GPU_PERST_0_BUF_R_N")
	)
	(segment
		(start 55.273956 -378.376434)
		(end 56.0578 -379.160278)
		(width 0.15494)
		(layer "In15.Cu")
		(net "RST_GPU_PERST_0_BUF_R_N")
	)
	(segment
		(start 63.248794 -387.7056)
		(end 64.950594 -389.4074)
		(width 0.15494)
		(layer "In15.Cu")
		(net "RST_GPU_PERST_0_BUF_R_N")
	)
	(segment
		(start 96.74098 -377.09602)
		(end 104.394 -369.443)
		(width 0.15494)
		(layer "In15.Cu")
		(net "RST_GPU_PERST_0_BUF_R_N")
	)
	(segment
		(start 59.867546 -387.7056)
		(end 63.248794 -387.7056)
		(width 0.15494)
		(layer "In15.Cu")
		(net "RST_GPU_PERST_0_BUF_R_N")
	)
	(segment
		(start 56.0578 -383.895854)
		(end 59.867546 -387.7056)
		(width 0.15494)
		(layer "In15.Cu")
		(net "RST_GPU_PERST_0_BUF_R_N")
	)
	(segment
		(start 64.950594 -389.4074)
		(end 91.604338 -389.4074)
		(width 0.15494)
		(layer "In15.Cu")
		(net "RST_GPU_PERST_0_BUF_R_N")
	)
	(via
		(at 302.933354 -233.307636)
		(size 0.6604)
		(drill 0.3302)
		(layers "F.Cu" "B.Cu")
		(net "RST_GPU_PERST_1_R_N")
	)
	(segment
		(start 302.933354 -233.307636)
		(end 302.369474 -232.743756)
		(width 0.13208)
		(layer "B.Cu")
		(net "RST_GPU_PERST_1_R_N")
	)
	(segment
		(start 302.552354 -234.558586)
		(end 302.933354 -234.177586)
		(width 0.13208)
		(layer "B.Cu")
		(net "RST_GPU_PERST_1_R_N")
	)
	(segment
		(start 302.369474 -232.743756)
		(end 302.369474 -231.220518)
		(width 0.13208)
		(layer "B.Cu")
		(net "RST_GPU_PERST_1_R_N")
	)
	(segment
		(start 302.933354 -234.177586)
		(end 302.933354 -233.307636)
		(width 0.13208)
		(layer "B.Cu")
		(net "RST_GPU_PERST_1_R_N")
	)
	(segment
		(start 250.163584 -200.24598)
		(end 249.343418 -199.425814)
		(width 0.13208)
		(layer "F.Cu")
		(net "JTAG_FPGA_TCK")
	)
	(segment
		(start 251.378212 -194.586098)
		(end 251.96546 -195.173346)
		(width 0.13208)
		(layer "F.Cu")
		(net "JTAG_FPGA_TCK")
	)
	(segment
		(start 249.343418 -199.425814)
		(end 249.343418 -195.681092)
		(width 0.13208)
		(layer "F.Cu")
		(net "JTAG_FPGA_TCK")
	)
	(segment
		(start 258.14528 -191.654684)
		(end 256.0701 -191.654684)
		(width 0.13208)
		(layer "F.Cu")
		(net "JTAG_FPGA_TCK")
	)
	(segment
		(start 341.293958 -225.587052)
		(end 340.894162 -225.986848)
		(width 0.13208)
		(layer "F.Cu")
		(net "JTAG_FPGA_TCK")
	)
	(segment
		(start 254.139954 -192.955164)
		(end 252.98146 -194.113658)
		(width 0.13208)
		(layer "F.Cu")
		(net "JTAG_FPGA_TCK")
	)
	(segment
		(start 250.438412 -194.586098)
		(end 251.378212 -194.586098)
		(width 0.13208)
		(layer "F.Cu")
		(net "JTAG_FPGA_TCK")
	)
	(segment
		(start 254.76962 -192.955164)
		(end 254.139954 -192.955164)
		(width 0.13208)
		(layer "F.Cu")
		(net "JTAG_FPGA_TCK")
	)
	(segment
		(start 251.96546 -195.173346)
		(end 252.98146 -195.173346)
		(width 0.13208)
		(layer "F.Cu")
		(net "JTAG_FPGA_TCK")
	)
	(segment
		(start 256.0701 -191.654684)
		(end 254.76962 -192.955164)
		(width 0.13208)
		(layer "F.Cu")
		(net "JTAG_FPGA_TCK")
	)
	(segment
		(start 250.574556 -200.24598)
		(end 250.163584 -200.24598)
		(width 0.13208)
		(layer "F.Cu")
		(net "JTAG_FPGA_TCK")
	)
	(segment
		(start 249.343418 -195.681092)
		(end 250.438412 -194.586098)
		(width 0.13208)
		(layer "F.Cu")
		(net "JTAG_FPGA_TCK")
	)
	(segment
		(start 250.798076 -200.02246)
		(end 250.574556 -200.24598)
		(width 0.13208)
		(layer "F.Cu")
		(net "JTAG_FPGA_TCK")
	)
	(segment
		(start 252.98146 -194.113658)
		(end 252.98146 -195.173346)
		(width 0.13208)
		(layer "F.Cu")
		(net "JTAG_FPGA_TCK")
	)
	(via
		(at 250.798076 -200.02246)
		(size 0.508)
		(drill 0.254)
		(layers "F.Cu" "B.Cu")
		(net "JTAG_FPGA_TCK")
	)
	(via
		(at 340.894162 -225.986848)
		(size 0.4572)
		(drill 0.254)
		(layers "F.Cu" "B.Cu")
		(net "JTAG_FPGA_TCK")
	)
	(segment
		(start 260.744462 -203.084684)
		(end 259.733288 -202.07351)
		(width 0.15494)
		(layer "In13.Cu")
		(net "JTAG_FPGA_TCK")
	)
	(segment
		(start 263.920224 -203.084684)
		(end 260.744462 -203.084684)
		(width 0.15494)
		(layer "In13.Cu")
		(net "JTAG_FPGA_TCK")
	)
	(segment
		(start 332.145894 -222.64878)
		(end 330.03236 -220.535246)
		(width 0.15494)
		(layer "In13.Cu")
		(net "JTAG_FPGA_TCK")
	)
	(segment
		(start 251.021596 -200.24598)
		(end 250.798076 -200.02246)
		(width 0.15494)
		(layer "In13.Cu")
		(net "JTAG_FPGA_TCK")
	)
	(segment
		(start 326.820276 -216.767156)
		(end 325.800466 -216.767156)
		(width 0.15494)
		(layer "In13.Cu")
		(net "JTAG_FPGA_TCK")
	)
	(segment
		(start 324.25513 -216.126568)
		(end 322.544948 -216.126568)
		(width 0.15494)
		(layer "In13.Cu")
		(net "JTAG_FPGA_TCK")
	)
	(segment
		(start 322.04025 -216.106248)
		(end 318.873632 -212.93963)
		(width 0.15494)
		(layer "In13.Cu")
		(net "JTAG_FPGA_TCK")
	)
	(segment
		(start 333.540862 -223.418146)
		(end 332.382622 -223.418146)
		(width 0.15494)
		(layer "In13.Cu")
		(net "JTAG_FPGA_TCK")
	)
	(segment
		(start 322.524628 -216.106248)
		(end 322.04025 -216.106248)
		(width 0.15494)
		(layer "In13.Cu")
		(net "JTAG_FPGA_TCK")
	)
	(segment
		(start 330.03236 -220.535246)
		(end 330.03236 -219.97924)
		(width 0.15494)
		(layer "In13.Cu")
		(net "JTAG_FPGA_TCK")
	)
	(segment
		(start 318.873632 -212.93963)
		(end 276.207728 -212.93963)
		(width 0.15494)
		(layer "In13.Cu")
		(net "JTAG_FPGA_TCK")
	)
	(segment
		(start 332.145894 -223.181418)
		(end 332.145894 -222.64878)
		(width 0.15494)
		(layer "In13.Cu")
		(net "JTAG_FPGA_TCK")
	)
	(segment
		(start 330.03236 -219.97924)
		(end 326.820276 -216.767156)
		(width 0.15494)
		(layer "In13.Cu")
		(net "JTAG_FPGA_TCK")
	)
	(segment
		(start 334.108552 -223.985836)
		(end 333.540862 -223.418146)
		(width 0.15494)
		(layer "In13.Cu")
		(net "JTAG_FPGA_TCK")
	)
	(segment
		(start 266.135104 -202.867006)
		(end 264.137902 -202.867006)
		(width 0.15494)
		(layer "In13.Cu")
		(net "JTAG_FPGA_TCK")
	)
	(segment
		(start 332.382622 -223.418146)
		(end 332.145894 -223.181418)
		(width 0.15494)
		(layer "In13.Cu")
		(net "JTAG_FPGA_TCK")
	)
	(segment
		(start 340.493858 -224.224342)
		(end 340.255352 -223.985836)
		(width 0.0889)
		(layer "In13.Cu")
		(net "JTAG_FPGA_TCK")
	)
	(segment
		(start 340.894162 -225.986848)
		(end 340.493858 -225.586544)
		(width 0.0889)
		(layer "In13.Cu")
		(net "JTAG_FPGA_TCK")
	)
	(segment
		(start 340.255352 -223.985836)
		(end 334.108552 -223.985836)
		(width 0.0889)
		(layer "In13.Cu")
		(net "JTAG_FPGA_TCK")
	)
	(segment
		(start 276.207728 -212.93963)
		(end 266.135104 -202.867006)
		(width 0.15494)
		(layer "In13.Cu")
		(net "JTAG_FPGA_TCK")
	)
	(segment
		(start 254.57531 -202.07351)
		(end 252.74778 -200.24598)
		(width 0.15494)
		(layer "In13.Cu")
		(net "JTAG_FPGA_TCK")
	)
	(segment
		(start 264.137902 -202.867006)
		(end 263.920224 -203.084684)
		(width 0.15494)
		(layer "In13.Cu")
		(net "JTAG_FPGA_TCK")
	)
	(segment
		(start 325.800466 -216.767156)
		(end 324.25513 -216.126568)
		(width 0.15494)
		(layer "In13.Cu")
		(net "JTAG_FPGA_TCK")
	)
	(segment
		(start 252.74778 -200.24598)
		(end 251.021596 -200.24598)
		(width 0.15494)
		(layer "In13.Cu")
		(net "JTAG_FPGA_TCK")
	)
	(segment
		(start 322.544948 -216.126568)
		(end 322.524628 -216.106248)
		(width 0.15494)
		(layer "In13.Cu")
		(net "JTAG_FPGA_TCK")
	)
	(segment
		(start 340.493858 -225.586544)
		(end 340.493858 -224.224342)
		(width 0.0889)
		(layer "In13.Cu")
		(net "JTAG_FPGA_TCK")
	)
	(segment
		(start 259.733288 -202.07351)
		(end 254.57531 -202.07351)
		(width 0.15494)
		(layer "In13.Cu")
		(net "JTAG_FPGA_TCK")
	)
	(segment
		(start 336.55 -207.645)
		(end 336.55 -205.63205)
		(width 0.13208)
		(layer "F.Cu")
		(net "SSD9_CLK_EN_N")
	)
	(segment
		(start 337.293966 -211.18703)
		(end 337.293966 -208.388966)
		(width 0.13208)
		(layer "F.Cu")
		(net "SSD9_CLK_EN_N")
	)
	(segment
		(start 337.293966 -208.388966)
		(end 336.55 -207.645)
		(width 0.13208)
		(layer "F.Cu")
		(net "SSD9_CLK_EN_N")
	)
	(via
		(at 336.55 -207.645)
		(size 0.762)
		(drill 0.381)
		(layers "F.Cu" "B.Cu")
		(net "SSD9_CLK_EN_N")
	)
	(segment
		(start 106.695494 -82.545936)
		(end 106.639106 -82.602324)
		(width 0.13462)
		(layer "F.Cu")
		(net "CLK_100M_DB800ZL_SSD0_DP")
	)
	(segment
		(start 106.639106 -82.602324)
		(end 106.639106 -83.029044)
		(width 0.13462)
		(layer "F.Cu")
		(net "CLK_100M_DB800ZL_SSD0_DP")
	)
	(segment
		(start 105.895648 -80.536034)
		(end 105.895648 -81.112106)
		(width 0.13462)
		(layer "F.Cu")
		(net "CLK_100M_DB800ZL_SSD0_DP")
	)
	(segment
		(start 106.695494 -81.911952)
		(end 106.695494 -82.545936)
		(width 0.13462)
		(layer "F.Cu")
		(net "CLK_100M_DB800ZL_SSD0_DP")
	)
	(segment
		(start 105.895648 -81.112106)
		(end 106.695494 -81.911952)
		(width 0.13462)
		(layer "F.Cu")
		(net "CLK_100M_DB800ZL_SSD0_DP")
	)
	(segment
		(start 105.581958 -80.222344)
		(end 105.895648 -80.536034)
		(width 0.13462)
		(layer "F.Cu")
		(net "CLK_100M_DB800ZL_SSD0_DP")
	)
	(segment
		(start 133.851904 -181.832504)
		(end 133.851904 -180.519578)
		(width 0.13462)
		(layer "F.Cu")
		(net "CLK_100M_DB2000QL_GPU_REF0_DP")
	)
	(segment
		(start 134.94639 -184.256934)
		(end 134.566914 -183.877458)
		(width 0.13462)
		(layer "F.Cu")
		(net "CLK_100M_DB2000QL_GPU_REF0_DP")
	)
	(segment
		(start 134.566914 -183.877458)
		(end 134.566914 -182.547514)
		(width 0.13462)
		(layer "F.Cu")
		(net "CLK_100M_DB2000QL_GPU_REF0_DP")
	)
	(segment
		(start 133.851904 -180.519578)
		(end 133.97103 -180.400452)
		(width 0.13462)
		(layer "F.Cu")
		(net "CLK_100M_DB2000QL_GPU_REF0_DP")
	)
	(segment
		(start 134.566914 -182.547514)
		(end 133.851904 -181.832504)
		(width 0.13462)
		(layer "F.Cu")
		(net "CLK_100M_DB2000QL_GPU_REF0_DP")
	)
	(segment
		(start 334.027526 -7.916672)
		(end 334.527906 -8.417052)
		(width 0.13208)
		(layer "F.Cu")
		(net "SMB_ISO_SSD11_SCL")
	)
	(segment
		(start 332.956662 -10.945622)
		(end 333.206344 -10.945622)
		(width 0.13208)
		(layer "F.Cu")
		(net "SMB_ISO_SSD11_SCL")
	)
	(segment
		(start 334.527906 -8.417052)
		(end 334.527906 -9.580372)
		(width 0.13208)
		(layer "F.Cu")
		(net "SMB_ISO_SSD11_SCL")
	)
	(segment
		(start 331.976476 -7.916672)
		(end 334.027526 -7.916672)
		(width 0.13208)
		(layer "F.Cu")
		(net "SMB_ISO_SSD11_SCL")
	)
	(segment
		(start 330.90739 -7.916672)
		(end 331.976476 -7.916672)
		(width 0.13208)
		(layer "F.Cu")
		(net "SMB_ISO_SSD11_SCL")
	)
	(segment
		(start 338.892642 -7.742682)
		(end 339.502242 -7.742682)
		(width 0.13208)
		(layer "F.Cu")
		(net "SMB_ISO_SSD11_SCL")
	)
	(segment
		(start 333.974186 -10.17778)
		(end 333.974186 -10.134092)
		(width 0.13208)
		(layer "F.Cu")
		(net "SMB_ISO_SSD11_SCL")
	)
	(segment
		(start 334.527906 -9.580372)
		(end 333.974186 -10.134092)
		(width 0.13208)
		(layer "F.Cu")
		(net "SMB_ISO_SSD11_SCL")
	)
	(segment
		(start 333.206344 -10.945622)
		(end 333.974186 -10.17778)
		(width 0.13208)
		(layer "F.Cu")
		(net "SMB_ISO_SSD11_SCL")
	)
	(via
		(at 339.502242 -7.742682)
		(size 0.508)
		(drill 0.254)
		(layers "F.Cu" "B.Cu")
		(net "SMB_ISO_SSD11_SCL")
	)
	(via
		(at 330.90739 -7.916672)
		(size 0.508)
		(drill 0.254)
		(layers "F.Cu" "B.Cu")
		(net "SMB_ISO_SSD11_SCL")
	)
	(segment
		(start 332.642972 -6.515354)
		(end 331.241654 -7.916672)
		(width 0.13208)
		(layer "B.Cu")
		(net "SMB_ISO_SSD11_SCL")
	)
	(segment
		(start 338.614004 -7.521956)
		(end 337.091782 -7.521956)
		(width 0.13208)
		(layer "B.Cu")
		(net "SMB_ISO_SSD11_SCL")
	)
	(segment
		(start 337.091782 -7.521956)
		(end 336.08518 -6.515354)
		(width 0.13208)
		(layer "B.Cu")
		(net "SMB_ISO_SSD11_SCL")
	)
	(segment
		(start 338.83473 -7.742682)
		(end 338.614004 -7.521956)
		(width 0.13208)
		(layer "B.Cu")
		(net "SMB_ISO_SSD11_SCL")
	)
	(segment
		(start 331.241654 -7.916672)
		(end 330.90739 -7.916672)
		(width 0.13208)
		(layer "B.Cu")
		(net "SMB_ISO_SSD11_SCL")
	)
	(segment
		(start 339.502242 -7.742682)
		(end 338.83473 -7.742682)
		(width 0.13208)
		(layer "B.Cu")
		(net "SMB_ISO_SSD11_SCL")
	)
	(segment
		(start 336.08518 -6.515354)
		(end 332.642972 -6.515354)
		(width 0.13208)
		(layer "B.Cu")
		(net "SMB_ISO_SSD11_SCL")
	)
	(segment
		(start 61.766196 -363.75467)
		(end 61.170058 -364.350808)
		(width 0.13208)
		(layer "F.Cu")
		(net "SMB_GPU_1_R_SCL")
	)
	(segment
		(start 100.42398 -381.259588)
		(end 100.42398 -380.341632)
		(width 0.13208)
		(layer "F.Cu")
		(net "SMB_GPU_1_R_SCL")
	)
	(segment
		(start 99.411282 -373.614696)
		(end 99.411282 -369.845336)
		(width 0.13208)
		(layer "F.Cu")
		(net "SMB_GPU_1_R_SCL")
	)
	(segment
		(start 93.320616 -363.75467)
		(end 61.766196 -363.75467)
		(width 0.13208)
		(layer "F.Cu")
		(net "SMB_GPU_1_R_SCL")
	)
	(segment
		(start 100.961698 -375.165112)
		(end 99.411282 -373.614696)
		(width 0.13208)
		(layer "F.Cu")
		(net "SMB_GPU_1_R_SCL")
	)
	(segment
		(start 61.170058 -378.586492)
		(end 58.991754 -380.764796)
		(width 0.13208)
		(layer "F.Cu")
		(net "SMB_GPU_1_R_SCL")
	)
	(segment
		(start 61.170058 -364.350808)
		(end 61.170058 -378.586492)
		(width 0.13208)
		(layer "F.Cu")
		(net "SMB_GPU_1_R_SCL")
	)
	(segment
		(start 56.76265 -380.764796)
		(end 56.602122 -380.604268)
		(width 0.13208)
		(layer "F.Cu")
		(net "SMB_GPU_1_R_SCL")
	)
	(segment
		(start 99.411282 -369.845336)
		(end 93.320616 -363.75467)
		(width 0.13208)
		(layer "F.Cu")
		(net "SMB_GPU_1_R_SCL")
	)
	(segment
		(start 58.991754 -380.764796)
		(end 56.76265 -380.764796)
		(width 0.13208)
		(layer "F.Cu")
		(net "SMB_GPU_1_R_SCL")
	)
	(segment
		(start 100.961698 -379.803914)
		(end 100.961698 -375.165112)
		(width 0.13208)
		(layer "F.Cu")
		(net "SMB_GPU_1_R_SCL")
	)
	(segment
		(start 100.42398 -380.341632)
		(end 100.961698 -379.803914)
		(width 0.13208)
		(layer "F.Cu")
		(net "SMB_GPU_1_R_SCL")
	)
	(via
		(at 56.602122 -380.604268)
		(size 0.508)
		(drill 0.254)
		(layers "F.Cu" "B.Cu")
		(net "SMB_GPU_1_R_SCL")
	)
	(via
		(at 100.42398 -381.259588)
		(size 0.508)
		(drill 0.254)
		(layers "F.Cu" "B.Cu")
		(net "SMB_GPU_1_R_SCL")
	)
	(segment
		(start 100.42398 -381.258572)
		(end 100.42398 -381.259588)
		(width 0.13208)
		(layer "B.Cu")
		(net "SMB_GPU_1_R_SCL")
	)
	(segment
		(start 101.232462 -380.45009)
		(end 100.42398 -381.258572)
		(width 0.13208)
		(layer "B.Cu")
		(net "SMB_GPU_1_R_SCL")
	)
	(segment
		(start 47.795942 -380.604268)
		(end 56.602122 -380.604268)
		(width 0.15494)
		(layer "In9.Cu")
		(net "SMB_GPU_1_R_SCL")
	)
	(segment
		(start 47.71009 -380.69012)
		(end 47.795942 -380.604268)
		(width 0.15494)
		(layer "In9.Cu")
		(net "SMB_GPU_1_R_SCL")
	)
	(segment
		(start 335.693766 -226.387152)
		(end 335.29397 -226.786948)
		(width 0.13208)
		(layer "F.Cu")
		(net "RST_GPU_PERST_1_N")
	)
	(via
		(at 300.140116 -227.246434)
		(size 0.508)
		(drill 0.254)
		(layers "F.Cu" "B.Cu")
		(net "RST_GPU_PERST_1_N")
	)
	(via
		(at 303.951894 -234.416854)
		(size 0.6604)
		(drill 0.3302)
		(layers "F.Cu" "B.Cu")
		(net "RST_GPU_PERST_1_N")
	)
	(via
		(at 335.29397 -226.786948)
		(size 0.4572)
		(drill 0.254)
		(layers "F.Cu" "B.Cu")
		(net "RST_GPU_PERST_1_N")
	)
	(segment
		(start 303.951894 -230.494332)
		(end 303.951894 -234.416854)
		(width 0.13208)
		(layer "B.Cu")
		(net "RST_GPU_PERST_1_N")
	)
	(segment
		(start 300.404276 -230.253794)
		(end 303.711356 -230.253794)
		(width 0.13208)
		(layer "B.Cu")
		(net "RST_GPU_PERST_1_N")
	)
	(segment
		(start 303.951894 -234.416854)
		(end 303.951894 -235.944664)
		(width 0.13208)
		(layer "B.Cu")
		(net "RST_GPU_PERST_1_N")
	)
	(segment
		(start 300.140116 -227.246434)
		(end 300.140116 -229.989634)
		(width 0.13208)
		(layer "B.Cu")
		(net "RST_GPU_PERST_1_N")
	)
	(segment
		(start 303.711356 -230.253794)
		(end 303.951894 -230.494332)
		(width 0.13208)
		(layer "B.Cu")
		(net "RST_GPU_PERST_1_N")
	)
	(segment
		(start 302.552354 -236.336586)
		(end 303.559972 -236.336586)
		(width 0.13208)
		(layer "B.Cu")
		(net "RST_GPU_PERST_1_N")
	)
	(segment
		(start 300.140116 -229.989634)
		(end 300.404276 -230.253794)
		(width 0.13208)
		(layer "B.Cu")
		(net "RST_GPU_PERST_1_N")
	)
	(segment
		(start 303.951894 -235.944664)
		(end 303.559972 -236.336586)
		(width 0.13208)
		(layer "B.Cu")
		(net "RST_GPU_PERST_1_N")
	)
	(segment
		(start 302.552354 -235.358686)
		(end 302.552354 -236.336586)
		(width 0.13208)
		(layer "B.Cu")
		(net "RST_GPU_PERST_1_N")
	)
	(segment
		(start 331.126084 -226.849178)
		(end 332.837536 -226.849178)
		(width 0.15494)
		(layer "In13.Cu")
		(net "RST_GPU_PERST_1_N")
	)
	(segment
		(start 324.506844 -227.5078)
		(end 324.53072 -227.5078)
		(width 0.15494)
		(layer "In13.Cu")
		(net "RST_GPU_PERST_1_N")
	)
	(segment
		(start 324.55104 -227.52812)
		(end 328.372978 -227.52812)
		(width 0.15494)
		(layer "In13.Cu")
		(net "RST_GPU_PERST_1_N")
	)
	(segment
		(start 330.743306 -226.4664)
		(end 331.126084 -226.849178)
		(width 0.15494)
		(layer "In13.Cu")
		(net "RST_GPU_PERST_1_N")
	)
	(segment
		(start 332.837536 -226.849178)
		(end 333.292958 -227.3046)
		(width 0.15494)
		(layer "In13.Cu")
		(net "RST_GPU_PERST_1_N")
	)
	(segment
		(start 300.140116 -227.246434)
		(end 300.892464 -227.246434)
		(width 0.15494)
		(layer "In13.Cu")
		(net "RST_GPU_PERST_1_N")
	)
	(segment
		(start 323.06514 -226.066096)
		(end 324.506844 -227.5078)
		(width 0.15494)
		(layer "In13.Cu")
		(net "RST_GPU_PERST_1_N")
	)
	(segment
		(start 328.372978 -227.52812)
		(end 329.434698 -226.4664)
		(width 0.15494)
		(layer "In13.Cu")
		(net "RST_GPU_PERST_1_N")
	)
	(segment
		(start 300.892464 -227.246434)
		(end 302.072802 -226.066096)
		(width 0.15494)
		(layer "In13.Cu")
		(net "RST_GPU_PERST_1_N")
	)
	(segment
		(start 334.776318 -227.3046)
		(end 335.29397 -226.786948)
		(width 0.15494)
		(layer "In13.Cu")
		(net "RST_GPU_PERST_1_N")
	)
	(segment
		(start 324.53072 -227.5078)
		(end 324.55104 -227.52812)
		(width 0.15494)
		(layer "In13.Cu")
		(net "RST_GPU_PERST_1_N")
	)
	(segment
		(start 333.292958 -227.3046)
		(end 334.776318 -227.3046)
		(width 0.15494)
		(layer "In13.Cu")
		(net "RST_GPU_PERST_1_N")
	)
	(segment
		(start 302.072802 -226.066096)
		(end 323.06514 -226.066096)
		(width 0.15494)
		(layer "In13.Cu")
		(net "RST_GPU_PERST_1_N")
	)
	(segment
		(start 329.434698 -226.4664)
		(end 330.743306 -226.4664)
		(width 0.15494)
		(layer "In13.Cu")
		(net "RST_GPU_PERST_1_N")
	)
	(segment
		(start 258.135882 -207.021684)
		(end 257.898138 -207.021684)
		(width 0.13208)
		(layer "F.Cu")
		(net "JTAG_FPGA_TDO")
	)
	(segment
		(start 257.898138 -207.021684)
		(end 257.510534 -206.63408)
		(width 0.13208)
		(layer "F.Cu")
		(net "JTAG_FPGA_TDO")
	)
	(segment
		(start 258.14528 -207.031082)
		(end 258.135882 -207.021684)
		(width 0.13208)
		(layer "F.Cu")
		(net "JTAG_FPGA_TDO")
	)
	(segment
		(start 258.14528 -208.019396)
		(end 258.14528 -207.031082)
		(width 0.13208)
		(layer "F.Cu")
		(net "JTAG_FPGA_TDO")
	)
	(via
		(at 257.510534 -206.63408)
		(size 0.508)
		(drill 0.254)
		(layers "F.Cu" "B.Cu")
		(net "JTAG_FPGA_TDO")
	)
	(via
		(at 256.833624 -205.711806)
		(size 0.7112)
		(drill 0.3556)
		(layers "F.Cu" "B.Cu")
		(net "JTAG_FPGA_TDO")
	)
	(via
		(at 322.945252 -218.908884)
		(size 0.508)
		(drill 0.254)
		(layers "F.Cu" "B.Cu")
		(net "JTAG_FPGA_TDO")
	)
	(segment
		(start 322.512182 -219.556838)
		(end 322.945252 -218.908884)
		(width 0.13208)
		(layer "B.Cu")
		(net "JTAG_FPGA_TDO")
	)
	(segment
		(start 256.491232 -205.711806)
		(end 256.833624 -205.711806)
		(width 0.13208)
		(layer "B.Cu")
		(net "JTAG_FPGA_TDO")
	)
	(segment
		(start 255.416304 -204.636878)
		(end 256.491232 -205.711806)
		(width 0.13208)
		(layer "B.Cu")
		(net "JTAG_FPGA_TDO")
	)
	(segment
		(start 257.510534 -206.388716)
		(end 257.510534 -206.63408)
		(width 0.13208)
		(layer "B.Cu")
		(net "JTAG_FPGA_TDO")
	)
	(segment
		(start 255.416304 -203.57465)
		(end 255.416304 -204.636878)
		(width 0.13208)
		(layer "B.Cu")
		(net "JTAG_FPGA_TDO")
	)
	(segment
		(start 256.833624 -205.711806)
		(end 257.510534 -206.388716)
		(width 0.13208)
		(layer "B.Cu")
		(net "JTAG_FPGA_TDO")
	)
	(segment
		(start 279.3492 -218.369388)
		(end 295.37025 -218.369388)
		(width 0.15494)
		(layer "In13.Cu")
		(net "JTAG_FPGA_TDO")
	)
	(segment
		(start 322.447158 -219.406978)
		(end 322.945252 -218.908884)
		(width 0.15494)
		(layer "In13.Cu")
		(net "JTAG_FPGA_TDO")
	)
	(segment
		(start 257.510534 -206.63408)
		(end 257.911854 -207.0354)
		(width 0.15494)
		(layer "In13.Cu")
		(net "JTAG_FPGA_TDO")
	)
	(segment
		(start 268.96949 -207.989678)
		(end 279.3492 -218.369388)
		(width 0.15494)
		(layer "In13.Cu")
		(net "JTAG_FPGA_TDO")
	)
	(segment
		(start 260.823202 -207.989678)
		(end 268.96949 -207.989678)
		(width 0.15494)
		(layer "In13.Cu")
		(net "JTAG_FPGA_TDO")
	)
	(segment
		(start 257.911854 -207.0354)
		(end 259.868924 -207.0354)
		(width 0.15494)
		(layer "In13.Cu")
		(net "JTAG_FPGA_TDO")
	)
	(segment
		(start 296.40784 -219.406978)
		(end 322.447158 -219.406978)
		(width 0.15494)
		(layer "In13.Cu")
		(net "JTAG_FPGA_TDO")
	)
	(segment
		(start 295.37025 -218.369388)
		(end 296.40784 -219.406978)
		(width 0.15494)
		(layer "In13.Cu")
		(net "JTAG_FPGA_TDO")
	)
	(segment
		(start 259.868924 -207.0354)
		(end 260.823202 -207.989678)
		(width 0.15494)
		(layer "In13.Cu")
		(net "JTAG_FPGA_TDO")
	)
	(segment
		(start 240.320576 -27.066494)
		(end 241.14252 -27.066494)
		(width 0.13208)
		(layer "F.Cu")
		(net "PRSNT_SSD8_R_N")
	)
	(segment
		(start 334.89392 -211.98713)
		(end 334.494124 -211.587334)
		(width 0.13208)
		(layer "F.Cu")
		(net "PRSNT_SSD8_R_N")
	)
	(segment
		(start 239.309148 -27.04973)
		(end 240.303812 -27.04973)
		(width 0.13208)
		(layer "F.Cu")
		(net "PRSNT_SSD8_R_N")
	)
	(segment
		(start 238.775748 -36.515548)
		(end 239.596168 -36.515548)
		(width 0.13208)
		(layer "F.Cu")
		(net "PRSNT_SSD8_R_N")
	)
	(segment
		(start 239.309148 -26.03373)
		(end 239.309148 -27.04973)
		(width 0.13208)
		(layer "F.Cu")
		(net "PRSNT_SSD8_R_N")
	)
	(segment
		(start 240.303812 -27.04973)
		(end 240.320576 -27.066494)
		(width 0.13208)
		(layer "F.Cu")
		(net "PRSNT_SSD8_R_N")
	)
	(segment
		(start 234.667552 -220.704156)
		(end 235.067348 -221.103952)
		(width 0.13208)
		(layer "F.Cu")
		(net "PRSNT_SSD8_R_N")
	)
	(via
		(at 245.895876 -203.147168)
		(size 0.508)
		(drill 0.254)
		(layers "F.Cu" "B.Cu")
		(net "PRSNT_SSD8_R_N")
	)
	(via
		(at 239.596168 -36.515548)
		(size 0.508)
		(drill 0.254)
		(layers "F.Cu" "B.Cu")
		(net "PRSNT_SSD8_R_N")
	)
	(via
		(at 245.359682 -193.946018)
		(size 0.508)
		(drill 0.254)
		(layers "F.Cu" "B.Cu")
		(net "PRSNT_SSD8_R_N")
	)
	(via
		(at 241.14252 -27.066494)
		(size 0.508)
		(drill 0.254)
		(layers "F.Cu" "B.Cu")
		(net "PRSNT_SSD8_R_N")
	)
	(via
		(at 235.067348 -221.103952)
		(size 0.4572)
		(drill 0.254)
		(layers "F.Cu" "B.Cu")
		(net "PRSNT_SSD8_R_N")
	)
	(via
		(at 334.494124 -211.587334)
		(size 0.4572)
		(drill 0.254)
		(layers "F.Cu" "B.Cu")
		(net "PRSNT_SSD8_R_N")
	)
	(segment
		(start 240.570258 -27.066494)
		(end 241.14252 -27.066494)
		(width 0.15494)
		(layer "In5.Cu")
		(net "PRSNT_SSD8_R_N")
	)
	(segment
		(start 254.71755 -166.236396)
		(end 257.494786 -163.45916)
		(width 0.15494)
		(layer "In5.Cu")
		(net "PRSNT_SSD8_R_N")
	)
	(segment
		(start 235.458 -179.731416)
		(end 234.0864 -178.359816)
		(width 0.15494)
		(layer "In5.Cu")
		(net "PRSNT_SSD8_R_N")
	)
	(segment
		(start 237.963456 -34.882836)
		(end 237.963456 -29.673296)
		(width 0.15494)
		(layer "In5.Cu")
		(net "PRSNT_SSD8_R_N")
	)
	(segment
		(start 257.494786 -163.45916)
		(end 257.494786 -115.489736)
		(width 0.15494)
		(layer "In5.Cu")
		(net "PRSNT_SSD8_R_N")
	)
	(segment
		(start 235.458 -182.9054)
		(end 235.458 -179.731416)
		(width 0.15494)
		(layer "In5.Cu")
		(net "PRSNT_SSD8_R_N")
	)
	(segment
		(start 257.494786 -115.489736)
		(end 245.264178 -103.259128)
		(width 0.15494)
		(layer "In5.Cu")
		(net "PRSNT_SSD8_R_N")
	)
	(segment
		(start 236.59338 -184.04078)
		(end 235.458 -182.9054)
		(width 0.15494)
		(layer "In5.Cu")
		(net "PRSNT_SSD8_R_N")
	)
	(segment
		(start 245.359682 -185.923682)
		(end 244.8306 -185.3946)
		(width 0.15494)
		(layer "In5.Cu")
		(net "PRSNT_SSD8_R_N")
	)
	(segment
		(start 242.852702 -185.3946)
		(end 242.2398 -186.007502)
		(width 0.15494)
		(layer "In5.Cu")
		(net "PRSNT_SSD8_R_N")
	)
	(segment
		(start 245.359682 -193.946018)
		(end 245.359682 -185.923682)
		(width 0.15494)
		(layer "In5.Cu")
		(net "PRSNT_SSD8_R_N")
	)
	(segment
		(start 234.0864 -178.359816)
		(end 234.0864 -170.637454)
		(width 0.15494)
		(layer "In5.Cu")
		(net "PRSNT_SSD8_R_N")
	)
	(segment
		(start 245.264178 -42.183558)
		(end 239.596168 -36.515548)
		(width 0.15494)
		(layer "In5.Cu")
		(net "PRSNT_SSD8_R_N")
	)
	(segment
		(start 240.007902 -186.007502)
		(end 238.04118 -184.04078)
		(width 0.15494)
		(layer "In5.Cu")
		(net "PRSNT_SSD8_R_N")
	)
	(segment
		(start 237.963456 -29.673296)
		(end 240.570258 -27.066494)
		(width 0.15494)
		(layer "In5.Cu")
		(net "PRSNT_SSD8_R_N")
	)
	(segment
		(start 238.04118 -184.04078)
		(end 236.59338 -184.04078)
		(width 0.15494)
		(layer "In5.Cu")
		(net "PRSNT_SSD8_R_N")
	)
	(segment
		(start 244.8306 -185.3946)
		(end 242.852702 -185.3946)
		(width 0.15494)
		(layer "In5.Cu")
		(net "PRSNT_SSD8_R_N")
	)
	(segment
		(start 242.2398 -186.007502)
		(end 240.007902 -186.007502)
		(width 0.15494)
		(layer "In5.Cu")
		(net "PRSNT_SSD8_R_N")
	)
	(segment
		(start 239.596168 -36.515548)
		(end 237.963456 -34.882836)
		(width 0.15494)
		(layer "In5.Cu")
		(net "PRSNT_SSD8_R_N")
	)
	(segment
		(start 234.0864 -170.637454)
		(end 238.487458 -166.236396)
		(width 0.15494)
		(layer "In5.Cu")
		(net "PRSNT_SSD8_R_N")
	)
	(segment
		(start 238.487458 -166.236396)
		(end 254.71755 -166.236396)
		(width 0.15494)
		(layer "In5.Cu")
		(net "PRSNT_SSD8_R_N")
	)
	(segment
		(start 245.264178 -103.259128)
		(end 245.264178 -42.183558)
		(width 0.15494)
		(layer "In5.Cu")
		(net "PRSNT_SSD8_R_N")
	)
	(segment
		(start 235.067348 -221.103952)
		(end 236.9566 -219.2147)
		(width 0.15494)
		(layer "In7.Cu")
		(net "PRSNT_SSD8_R_N")
	)
	(segment
		(start 245.895876 -203.147168)
		(end 245.364 -202.615292)
		(width 0.15494)
		(layer "In7.Cu")
		(net "PRSNT_SSD8_R_N")
	)
	(segment
		(start 236.2708 -213.4616)
		(end 237.236 -212.4964)
		(width 0.15494)
		(layer "In7.Cu")
		(net "PRSNT_SSD8_R_N")
	)
	(segment
		(start 241.65306 -210.01101)
		(end 241.65306 -209.655664)
		(width 0.15494)
		(layer "In7.Cu")
		(net "PRSNT_SSD8_R_N")
	)
	(segment
		(start 245.364 -202.615292)
		(end 245.364 -198.348346)
		(width 0.15494)
		(layer "In7.Cu")
		(net "PRSNT_SSD8_R_N")
	)
	(segment
		(start 236.9566 -219.2147)
		(end 236.9566 -217.17)
		(width 0.15494)
		(layer "In7.Cu")
		(net "PRSNT_SSD8_R_N")
	)
	(segment
		(start 240.79581 -210.48726)
		(end 241.17681 -210.48726)
		(width 0.15494)
		(layer "In7.Cu")
		(net "PRSNT_SSD8_R_N")
	)
	(segment
		(start 238.78667 -212.4964)
		(end 240.79581 -210.48726)
		(width 0.15494)
		(layer "In7.Cu")
		(net "PRSNT_SSD8_R_N")
	)
	(segment
		(start 242.264184 -209.148426)
		(end 242.769644 -209.148426)
		(width 0.15494)
		(layer "In7.Cu")
		(net "PRSNT_SSD8_R_N")
	)
	(segment
		(start 242.08613 -209.222086)
		(end 242.264184 -209.148426)
		(width 0.15494)
		(layer "In7.Cu")
		(net "PRSNT_SSD8_R_N")
	)
	(segment
		(start 241.17681 -210.48726)
		(end 241.65306 -210.01101)
		(width 0.15494)
		(layer "In7.Cu")
		(net "PRSNT_SSD8_R_N")
	)
	(segment
		(start 243.664994 -208.253076)
		(end 243.664994 -207.518254)
		(width 0.15494)
		(layer "In7.Cu")
		(net "PRSNT_SSD8_R_N")
	)
	(segment
		(start 243.72316 -204.99324)
		(end 245.569232 -203.147168)
		(width 0.15494)
		(layer "In7.Cu")
		(net "PRSNT_SSD8_R_N")
	)
	(segment
		(start 241.66703 -209.641694)
		(end 241.66703 -209.641186)
		(width 0.15494)
		(layer "In7.Cu")
		(net "PRSNT_SSD8_R_N")
	)
	(segment
		(start 236.2708 -216.4842)
		(end 236.2708 -213.4616)
		(width 0.15494)
		(layer "In7.Cu")
		(net "PRSNT_SSD8_R_N")
	)
	(segment
		(start 241.65306 -209.655664)
		(end 241.66703 -209.641694)
		(width 0.15494)
		(layer "In7.Cu")
		(net "PRSNT_SSD8_R_N")
	)
	(segment
		(start 245.364 -198.348346)
		(end 246.15775 -197.554596)
		(width 0.15494)
		(layer "In7.Cu")
		(net "PRSNT_SSD8_R_N")
	)
	(segment
		(start 243.72316 -207.460088)
		(end 243.72316 -204.99324)
		(width 0.15494)
		(layer "In7.Cu")
		(net "PRSNT_SSD8_R_N")
	)
	(segment
		(start 236.9566 -217.17)
		(end 236.2708 -216.4842)
		(width 0.15494)
		(layer "In7.Cu")
		(net "PRSNT_SSD8_R_N")
	)
	(segment
		(start 241.66703 -209.641186)
		(end 242.08613 -209.222086)
		(width 0.15494)
		(layer "In7.Cu")
		(net "PRSNT_SSD8_R_N")
	)
	(segment
		(start 242.769644 -209.148426)
		(end 243.664994 -208.253076)
		(width 0.15494)
		(layer "In7.Cu")
		(net "PRSNT_SSD8_R_N")
	)
	(segment
		(start 245.569232 -203.147168)
		(end 245.895876 -203.147168)
		(width 0.15494)
		(layer "In7.Cu")
		(net "PRSNT_SSD8_R_N")
	)
	(segment
		(start 237.236 -212.4964)
		(end 238.78667 -212.4964)
		(width 0.15494)
		(layer "In7.Cu")
		(net "PRSNT_SSD8_R_N")
	)
	(segment
		(start 243.664994 -207.518254)
		(end 243.72316 -207.460088)
		(width 0.15494)
		(layer "In7.Cu")
		(net "PRSNT_SSD8_R_N")
	)
	(segment
		(start 246.15775 -194.744086)
		(end 245.359682 -193.946018)
		(width 0.15494)
		(layer "In7.Cu")
		(net "PRSNT_SSD8_R_N")
	)
	(segment
		(start 246.15775 -197.554596)
		(end 246.15775 -194.744086)
		(width 0.15494)
		(layer "In7.Cu")
		(net "PRSNT_SSD8_R_N")
	)
	(segment
		(start 249.236992 -204.866748)
		(end 247.615456 -204.866748)
		(width 0.15494)
		(layer "In15.Cu")
		(net "PRSNT_SSD8_R_N")
	)
	(segment
		(start 251.5108 -204.724)
		(end 250.7996 -204.0128)
		(width 0.15494)
		(layer "In15.Cu")
		(net "PRSNT_SSD8_R_N")
	)
	(segment
		(start 265.107166 -214.152988)
		(end 264.718038 -214.542116)
		(width 0.15494)
		(layer "In15.Cu")
		(net "PRSNT_SSD8_R_N")
	)
	(segment
		(start 325.2216 -207.8228)
		(end 300.624494 -207.8228)
		(width 0.15494)
		(layer "In15.Cu")
		(net "PRSNT_SSD8_R_N")
	)
	(segment
		(start 332.711044 -211.984844)
		(end 332.5368 -211.8106)
		(width 0.0889)
		(layer "In15.Cu")
		(net "PRSNT_SSD8_R_N")
	)
	(segment
		(start 283.204666 -214.152988)
		(end 265.107166 -214.152988)
		(width 0.15494)
		(layer "In15.Cu")
		(net "PRSNT_SSD8_R_N")
	)
	(segment
		(start 247.615456 -204.866748)
		(end 245.895876 -203.147168)
		(width 0.15494)
		(layer "In15.Cu")
		(net "PRSNT_SSD8_R_N")
	)
	(segment
		(start 332.5368 -211.8106)
		(end 332.223364 -211.8106)
		(width 0.15494)
		(layer "In15.Cu")
		(net "PRSNT_SSD8_R_N")
	)
	(segment
		(start 334.494124 -211.587334)
		(end 334.096614 -211.984844)
		(width 0.0889)
		(layer "In15.Cu")
		(net "PRSNT_SSD8_R_N")
	)
	(segment
		(start 288.109914 -209.24774)
		(end 283.204666 -214.152988)
		(width 0.15494)
		(layer "In15.Cu")
		(net "PRSNT_SSD8_R_N")
	)
	(segment
		(start 256.5654 -207.199484)
		(end 256.5654 -205.8416)
		(width 0.15494)
		(layer "In15.Cu")
		(net "PRSNT_SSD8_R_N")
	)
	(segment
		(start 300.624494 -207.8228)
		(end 299.199554 -209.24774)
		(width 0.15494)
		(layer "In15.Cu")
		(net "PRSNT_SSD8_R_N")
	)
	(segment
		(start 264.718038 -214.542116)
		(end 263.337802 -214.542116)
		(width 0.15494)
		(layer "In15.Cu")
		(net "PRSNT_SSD8_R_N")
	)
	(segment
		(start 325.5264 -207.518)
		(end 325.2216 -207.8228)
		(width 0.15494)
		(layer "In15.Cu")
		(net "PRSNT_SSD8_R_N")
	)
	(segment
		(start 263.337802 -214.542116)
		(end 261.973568 -213.177882)
		(width 0.15494)
		(layer "In15.Cu")
		(net "PRSNT_SSD8_R_N")
	)
	(segment
		(start 261.973568 -213.177882)
		(end 261.973568 -212.607652)
		(width 0.15494)
		(layer "In15.Cu")
		(net "PRSNT_SSD8_R_N")
	)
	(segment
		(start 299.199554 -209.24774)
		(end 288.109914 -209.24774)
		(width 0.15494)
		(layer "In15.Cu")
		(net "PRSNT_SSD8_R_N")
	)
	(segment
		(start 329.545188 -209.132424)
		(end 328.283824 -209.132424)
		(width 0.15494)
		(layer "In15.Cu")
		(net "PRSNT_SSD8_R_N")
	)
	(segment
		(start 250.7996 -204.0128)
		(end 250.09094 -204.0128)
		(width 0.15494)
		(layer "In15.Cu")
		(net "PRSNT_SSD8_R_N")
	)
	(segment
		(start 255.4478 -204.724)
		(end 251.5108 -204.724)
		(width 0.15494)
		(layer "In15.Cu")
		(net "PRSNT_SSD8_R_N")
	)
	(segment
		(start 250.09094 -204.0128)
		(end 249.236992 -204.866748)
		(width 0.15494)
		(layer "In15.Cu")
		(net "PRSNT_SSD8_R_N")
	)
	(segment
		(start 332.223364 -211.8106)
		(end 329.545188 -209.132424)
		(width 0.15494)
		(layer "In15.Cu")
		(net "PRSNT_SSD8_R_N")
	)
	(segment
		(start 261.973568 -212.607652)
		(end 256.5654 -207.199484)
		(width 0.15494)
		(layer "In15.Cu")
		(net "PRSNT_SSD8_R_N")
	)
	(segment
		(start 334.096614 -211.984844)
		(end 332.711044 -211.984844)
		(width 0.0889)
		(layer "In15.Cu")
		(net "PRSNT_SSD8_R_N")
	)
	(segment
		(start 326.6694 -207.518)
		(end 325.5264 -207.518)
		(width 0.15494)
		(layer "In15.Cu")
		(net "PRSNT_SSD8_R_N")
	)
	(segment
		(start 328.283824 -209.132424)
		(end 326.6694 -207.518)
		(width 0.15494)
		(layer "In15.Cu")
		(net "PRSNT_SSD8_R_N")
	)
	(segment
		(start 256.5654 -205.8416)
		(end 255.4478 -204.724)
		(width 0.15494)
		(layer "In15.Cu")
		(net "PRSNT_SSD8_R_N")
	)
	(segment
		(start 428.754794 -22.561296)
		(end 428.754794 -21.847048)
		(width 0.13208)
		(layer "F.Cu")
		(net "SMB_SSD14_ISO_EN")
	)
	(segment
		(start 428.754794 -21.847048)
		(end 427.960536 -21.05279)
		(width 0.13208)
		(layer "F.Cu")
		(net "SMB_SSD14_ISO_EN")
	)
	(segment
		(start 427.960536 -21.05279)
		(end 427.960536 -20.789392)
		(width 0.13208)
		(layer "F.Cu")
		(net "SMB_SSD14_ISO_EN")
	)
	(via
		(at 428.754794 -21.847048)
		(size 0.508)
		(drill 0.254)
		(layers "F.Cu" "B.Cu")
		(net "SMB_SSD14_ISO_EN")
	)
	(segment
		(start 58.286142 -384.702812)
		(end 57.650634 -384.702812)
		(width 0.13208)
		(layer "F.Cu")
		(net "GPU_PEX_STRAP1_R")
	)
	(via
		(at 57.650634 -384.702812)
		(size 0.508)
		(drill 0.254)
		(layers "F.Cu" "B.Cu")
		(net "GPU_PEX_STRAP1_R")
	)
	(segment
		(start 57.25922 -385.094226)
		(end 56.158638 -385.094226)
		(width 0.15494)
		(layer "In9.Cu")
		(net "GPU_PEX_STRAP1_R")
	)
	(segment
		(start 55.219854 -385.393946)
		(end 48.4886 -392.1252)
		(width 0.15494)
		(layer "In9.Cu")
		(net "GPU_PEX_STRAP1_R")
	)
	(segment
		(start 57.650634 -384.702812)
		(end 57.25922 -385.094226)
		(width 0.15494)
		(layer "In9.Cu")
		(net "GPU_PEX_STRAP1_R")
	)
	(segment
		(start 48.4886 -392.1252)
		(end 48.4886 -401.350734)
		(width 0.15494)
		(layer "In9.Cu")
		(net "GPU_PEX_STRAP1_R")
	)
	(segment
		(start 56.158638 -385.094226)
		(end 55.858918 -385.393946)
		(width 0.15494)
		(layer "In9.Cu")
		(net "GPU_PEX_STRAP1_R")
	)
	(segment
		(start 48.349154 -401.49018)
		(end 47.71009 -401.49018)
		(width 0.15494)
		(layer "In9.Cu")
		(net "GPU_PEX_STRAP1_R")
	)
	(segment
		(start 55.858918 -385.393946)
		(end 55.219854 -385.393946)
		(width 0.15494)
		(layer "In9.Cu")
		(net "GPU_PEX_STRAP1_R")
	)
	(segment
		(start 48.4886 -401.350734)
		(end 48.349154 -401.49018)
		(width 0.15494)
		(layer "In9.Cu")
		(net "GPU_PEX_STRAP1_R")
	)
	(segment
		(start 334.518 -205.63205)
		(end 334.518 -207.645)
		(width 0.13208)
		(layer "F.Cu")
		(net "RST_SSD8_PERST_N")
	)
	(segment
		(start 335.693766 -210.058)
		(end 334.518 -208.882234)
		(width 0.13208)
		(layer "F.Cu")
		(net "RST_SSD8_PERST_N")
	)
	(segment
		(start 335.693766 -211.18703)
		(end 335.693766 -210.058)
		(width 0.0889)
		(layer "F.Cu")
		(net "RST_SSD8_PERST_N")
	)
	(segment
		(start 334.518 -208.882234)
		(end 334.518 -207.645)
		(width 0.13208)
		(layer "F.Cu")
		(net "RST_SSD8_PERST_N")
	)
	(via
		(at 334.518 -207.645)
		(size 0.762)
		(drill 0.381)
		(layers "F.Cu" "B.Cu")
		(net "RST_SSD8_PERST_N")
	)
	(segment
		(start 50.47996 -52.994814)
		(end 50.47996 -51.670966)
		(width 0.13208)
		(layer "F.Cu")
		(net "P12V_SSD1_SS")
	)
	(segment
		(start 50.14722 -53.144166)
		(end 50.330608 -53.144166)
		(width 0.13208)
		(layer "F.Cu")
		(net "P12V_SSD1_SS")
	)
	(segment
		(start 50.47996 -51.670966)
		(end 51.13147 -51.019456)
		(width 0.13208)
		(layer "F.Cu")
		(net "P12V_SSD1_SS")
	)
	(segment
		(start 50.330608 -53.144166)
		(end 50.47996 -52.994814)
		(width 0.13208)
		(layer "F.Cu")
		(net "P12V_SSD1_SS")
	)
	(segment
		(start 51.13147 -51.019456)
		(end 51.867816 -51.019456)
		(width 0.13208)
		(layer "F.Cu")
		(net "P12V_SSD1_SS")
	)
	(via
		(at 51.13147 -51.019456)
		(size 0.508)
		(drill 0.254)
		(layers "F.Cu" "B.Cu")
		(net "P12V_SSD1_SS")
	)
	(via
		(at 443.439296 -250.712732)
		(size 0.508)
		(drill 0.254)
		(layers "F.Cu" "B.Cu")
		(net "UART_PEX3_SDB_R_TX")
	)
	(via
		(at 370.717826 -251.315728)
		(size 0.508)
		(drill 0.254)
		(layers "F.Cu" "B.Cu")
		(net "UART_PEX3_SDB_R_TX")
	)
	(segment
		(start 370.717826 -251.315728)
		(end 370.717826 -248.705878)
		(width 0.13208)
		(layer "B.Cu")
		(net "UART_PEX3_SDB_R_TX")
	)
	(segment
		(start 371.331744 -248.09196)
		(end 372.035324 -248.09196)
		(width 0.13208)
		(layer "B.Cu")
		(net "UART_PEX3_SDB_R_TX")
	)
	(segment
		(start 424.63974 -289.324796)
		(end 425.557696 -288.40684)
		(width 0.13208)
		(layer "B.Cu")
		(net "UART_PEX3_SDB_R_TX")
	)
	(segment
		(start 370.717826 -248.705878)
		(end 371.331744 -248.09196)
		(width 0.13208)
		(layer "B.Cu")
		(net "UART_PEX3_SDB_R_TX")
	)
	(segment
		(start 425.557696 -288.40684)
		(end 425.557696 -268.594332)
		(width 0.13208)
		(layer "B.Cu")
		(net "UART_PEX3_SDB_R_TX")
	)
	(segment
		(start 424.02379 -289.324796)
		(end 424.63974 -289.324796)
		(width 0.13208)
		(layer "B.Cu")
		(net "UART_PEX3_SDB_R_TX")
	)
	(segment
		(start 425.557696 -268.594332)
		(end 443.439296 -250.712732)
		(width 0.13208)
		(layer "B.Cu")
		(net "UART_PEX3_SDB_R_TX")
	)
	(segment
		(start 387.63321 -251.15266)
		(end 387.63321 -250.672092)
		(width 0.15494)
		(layer "In13.Cu")
		(net "UART_PEX3_SDB_R_TX")
	)
	(segment
		(start 388.149846 -248.448068)
		(end 388.287514 -248.3104)
		(width 0.15494)
		(layer "In13.Cu")
		(net "UART_PEX3_SDB_R_TX")
	)
	(segment
		(start 441.0329 -248.3104)
		(end 443.435232 -250.712732)
		(width 0.15494)
		(layer "In13.Cu")
		(net "UART_PEX3_SDB_R_TX")
	)
	(segment
		(start 370.717826 -251.315728)
		(end 371.741954 -252.339856)
		(width 0.15494)
		(layer "In13.Cu")
		(net "UART_PEX3_SDB_R_TX")
	)
	(segment
		(start 388.149846 -250.155456)
		(end 388.149846 -248.448068)
		(width 0.15494)
		(layer "In13.Cu")
		(net "UART_PEX3_SDB_R_TX")
	)
	(segment
		(start 388.287514 -248.3104)
		(end 441.0329 -248.3104)
		(width 0.15494)
		(layer "In13.Cu")
		(net "UART_PEX3_SDB_R_TX")
	)
	(segment
		(start 386.446014 -252.339856)
		(end 387.63321 -251.15266)
		(width 0.15494)
		(layer "In13.Cu")
		(net "UART_PEX3_SDB_R_TX")
	)
	(segment
		(start 371.741954 -252.339856)
		(end 386.446014 -252.339856)
		(width 0.15494)
		(layer "In13.Cu")
		(net "UART_PEX3_SDB_R_TX")
	)
	(segment
		(start 443.435232 -250.712732)
		(end 443.439296 -250.712732)
		(width 0.15494)
		(layer "In13.Cu")
		(net "UART_PEX3_SDB_R_TX")
	)
	(segment
		(start 387.63321 -250.672092)
		(end 388.149846 -250.155456)
		(width 0.15494)
		(layer "In13.Cu")
		(net "UART_PEX3_SDB_R_TX")
	)
	(segment
		(start 374.759474 -23.355554)
		(end 374.759474 -23.965154)
		(width 0.13208)
		(layer "F.Cu")
		(net "SMB_ISO_SSD12_SCL")
	)
	(segment
		(start 371.556534 -17.669256)
		(end 372.324376 -18.437098)
		(width 0.13208)
		(layer "F.Cu")
		(net "SMB_ISO_SSD12_SCL")
	)
	(segment
		(start 372.324376 -18.437098)
		(end 372.368064 -18.437098)
		(width 0.13208)
		(layer "F.Cu")
		(net "SMB_ISO_SSD12_SCL")
	)
	(segment
		(start 371.556534 -17.419574)
		(end 371.556534 -17.669256)
		(width 0.13208)
		(layer "F.Cu")
		(net "SMB_ISO_SSD12_SCL")
	)
	(segment
		(start 374.585484 -18.428462)
		(end 374.023128 -18.990818)
		(width 0.13208)
		(layer "F.Cu")
		(net "SMB_ISO_SSD12_SCL")
	)
	(segment
		(start 374.023128 -18.990818)
		(end 372.921784 -18.990818)
		(width 0.13208)
		(layer "F.Cu")
		(net "SMB_ISO_SSD12_SCL")
	)
	(segment
		(start 374.585484 -16.439388)
		(end 374.585484 -18.428462)
		(width 0.13208)
		(layer "F.Cu")
		(net "SMB_ISO_SSD12_SCL")
	)
	(segment
		(start 374.585484 -15.370302)
		(end 374.585484 -16.439388)
		(width 0.13208)
		(layer "F.Cu")
		(net "SMB_ISO_SSD12_SCL")
	)
	(segment
		(start 372.921784 -18.990818)
		(end 372.368064 -18.437098)
		(width 0.13208)
		(layer "F.Cu")
		(net "SMB_ISO_SSD12_SCL")
	)
	(via
		(at 374.759474 -23.965154)
		(size 0.508)
		(drill 0.254)
		(layers "F.Cu" "B.Cu")
		(net "SMB_ISO_SSD12_SCL")
	)
	(via
		(at 374.585484 -15.370302)
		(size 0.508)
		(drill 0.254)
		(layers "F.Cu" "B.Cu")
		(net "SMB_ISO_SSD12_SCL")
	)
	(segment
		(start 374.759474 -23.965154)
		(end 376.025156 -22.699472)
		(width 0.13208)
		(layer "B.Cu")
		(net "SMB_ISO_SSD12_SCL")
	)
	(segment
		(start 376.025156 -16.809974)
		(end 374.585484 -15.370302)
		(width 0.13208)
		(layer "B.Cu")
		(net "SMB_ISO_SSD12_SCL")
	)
	(segment
		(start 376.025156 -22.699472)
		(end 376.025156 -16.809974)
		(width 0.13208)
		(layer "B.Cu")
		(net "SMB_ISO_SSD12_SCL")
	)
	(via
		(at 300.901608 -225.145346)
		(size 0.6604)
		(drill 0.3302)
		(layers "F.Cu" "B.Cu")
		(net "RST_GPU_PERST_0_BUF_N")
	)
	(segment
		(start 300.195488 -224.439226)
		(end 300.195488 -223.917256)
		(width 0.13208)
		(layer "B.Cu")
		(net "RST_GPU_PERST_0_BUF_N")
	)
	(segment
		(start 300.195488 -223.917256)
		(end 299.477684 -223.199452)
		(width 0.13208)
		(layer "B.Cu")
		(net "RST_GPU_PERST_0_BUF_N")
	)
	(segment
		(start 299.067474 -222.094552)
		(end 299.067474 -223.199452)
		(width 0.13208)
		(layer "B.Cu")
		(net "RST_GPU_PERST_0_BUF_N")
	)
	(segment
		(start 299.477684 -223.199452)
		(end 299.067474 -223.199452)
		(width 0.13208)
		(layer "B.Cu")
		(net "RST_GPU_PERST_0_BUF_N")
	)
	(segment
		(start 300.901608 -225.145346)
		(end 300.195488 -224.439226)
		(width 0.13208)
		(layer "B.Cu")
		(net "RST_GPU_PERST_0_BUF_N")
	)
	(segment
		(start 300.901608 -225.597466)
		(end 300.901608 -225.145346)
		(width 0.13208)
		(layer "B.Cu")
		(net "RST_GPU_PERST_0_BUF_N")
	)
	(segment
		(start 301.719234 -227.520754)
		(end 301.719234 -226.415092)
		(width 0.13208)
		(layer "B.Cu")
		(net "RST_GPU_PERST_0_BUF_N")
	)
	(segment
		(start 301.719234 -226.415092)
		(end 300.901608 -225.597466)
		(width 0.13208)
		(layer "B.Cu")
		(net "RST_GPU_PERST_0_BUF_N")
	)
	(segment
		(start 258.14528 -197.097396)
		(end 258.14528 -196.081396)
		(width 0.13208)
		(layer "F.Cu")
		(net "JTAG_FPGA_TMS")
	)
	(segment
		(start 256.02946 -194.538346)
		(end 256.60223 -194.538346)
		(width 0.13208)
		(layer "F.Cu")
		(net "JTAG_FPGA_TMS")
	)
	(segment
		(start 341.293958 -226.387152)
		(end 340.894162 -226.786948)
		(width 0.13208)
		(layer "F.Cu")
		(net "JTAG_FPGA_TMS")
	)
	(segment
		(start 256.02946 -195.173346)
		(end 256.02946 -194.538346)
		(width 0.13208)
		(layer "F.Cu")
		(net "JTAG_FPGA_TMS")
	)
	(segment
		(start 256.60223 -194.538346)
		(end 258.14528 -196.081396)
		(width 0.13208)
		(layer "F.Cu")
		(net "JTAG_FPGA_TMS")
	)
	(via
		(at 331.669644 -220.396816)
		(size 0.508)
		(drill 0.254)
		(layers "F.Cu" "B.Cu")
		(net "JTAG_FPGA_TMS")
	)
	(via
		(at 256.02946 -194.538346)
		(size 0.508)
		(drill 0.254)
		(layers "F.Cu" "B.Cu")
		(net "JTAG_FPGA_TMS")
	)
	(via
		(at 340.894162 -226.786948)
		(size 0.4572)
		(drill 0.254)
		(layers "F.Cu" "B.Cu")
		(net "JTAG_FPGA_TMS")
	)
	(segment
		(start 330.950316 -220.396816)
		(end 331.669644 -220.396816)
		(width 0.13208)
		(layer "B.Cu")
		(net "JTAG_FPGA_TMS")
	)
	(segment
		(start 327.414128 -220.20149)
		(end 330.75499 -220.20149)
		(width 0.13208)
		(layer "B.Cu")
		(net "JTAG_FPGA_TMS")
	)
	(segment
		(start 330.75499 -220.20149)
		(end 330.950316 -220.396816)
		(width 0.13208)
		(layer "B.Cu")
		(net "JTAG_FPGA_TMS")
	)
	(segment
		(start 324.642734 -214.1474)
		(end 325.283576 -214.788242)
		(width 0.15494)
		(layer "In13.Cu")
		(net "JTAG_FPGA_TMS")
	)
	(segment
		(start 255.799082 -198.999094)
		(end 257.158744 -200.358756)
		(width 0.15494)
		(layer "In13.Cu")
		(net "JTAG_FPGA_TMS")
	)
	(segment
		(start 321.381882 -214.1474)
		(end 324.642734 -214.1474)
		(width 0.15494)
		(layer "In13.Cu")
		(net "JTAG_FPGA_TMS")
	)
	(segment
		(start 256.02946 -194.538346)
		(end 256.02946 -197.285102)
		(width 0.15494)
		(layer "In13.Cu")
		(net "JTAG_FPGA_TMS")
	)
	(segment
		(start 255.799082 -197.51548)
		(end 255.799082 -198.999094)
		(width 0.15494)
		(layer "In13.Cu")
		(net "JTAG_FPGA_TMS")
	)
	(segment
		(start 331.669644 -220.316044)
		(end 331.669644 -220.396816)
		(width 0.15494)
		(layer "In13.Cu")
		(net "JTAG_FPGA_TMS")
	)
	(segment
		(start 256.02946 -197.285102)
		(end 255.799082 -197.51548)
		(width 0.15494)
		(layer "In13.Cu")
		(net "JTAG_FPGA_TMS")
	)
	(segment
		(start 266.231116 -200.358756)
		(end 277.89251 -212.02015)
		(width 0.15494)
		(layer "In13.Cu")
		(net "JTAG_FPGA_TMS")
	)
	(segment
		(start 341.056976 -223.18726)
		(end 341.291672 -223.421956)
		(width 0.0889)
		(layer "In13.Cu")
		(net "JTAG_FPGA_TMS")
	)
	(segment
		(start 257.158744 -200.358756)
		(end 266.231116 -200.358756)
		(width 0.15494)
		(layer "In13.Cu")
		(net "JTAG_FPGA_TMS")
	)
	(segment
		(start 331.669644 -220.832934)
		(end 334.02397 -223.18726)
		(width 0.15494)
		(layer "In13.Cu")
		(net "JTAG_FPGA_TMS")
	)
	(segment
		(start 331.669644 -220.396816)
		(end 331.669644 -220.832934)
		(width 0.15494)
		(layer "In13.Cu")
		(net "JTAG_FPGA_TMS")
	)
	(segment
		(start 341.291672 -226.389438)
		(end 340.894162 -226.786948)
		(width 0.0889)
		(layer "In13.Cu")
		(net "JTAG_FPGA_TMS")
	)
	(segment
		(start 327.92543 -216.097612)
		(end 327.92543 -216.57183)
		(width 0.15494)
		(layer "In13.Cu")
		(net "JTAG_FPGA_TMS")
	)
	(segment
		(start 319.254632 -212.02015)
		(end 321.381882 -214.1474)
		(width 0.15494)
		(layer "In13.Cu")
		(net "JTAG_FPGA_TMS")
	)
	(segment
		(start 325.283576 -214.788242)
		(end 326.61606 -214.788242)
		(width 0.15494)
		(layer "In13.Cu")
		(net "JTAG_FPGA_TMS")
	)
	(segment
		(start 277.89251 -212.02015)
		(end 319.254632 -212.02015)
		(width 0.15494)
		(layer "In13.Cu")
		(net "JTAG_FPGA_TMS")
	)
	(segment
		(start 327.92543 -216.57183)
		(end 331.669644 -220.316044)
		(width 0.15494)
		(layer "In13.Cu")
		(net "JTAG_FPGA_TMS")
	)
	(segment
		(start 326.61606 -214.788242)
		(end 327.92543 -216.097612)
		(width 0.15494)
		(layer "In13.Cu")
		(net "JTAG_FPGA_TMS")
	)
	(segment
		(start 334.02397 -223.18726)
		(end 341.056976 -223.18726)
		(width 0.0889)
		(layer "In13.Cu")
		(net "JTAG_FPGA_TMS")
	)
	(segment
		(start 341.291672 -223.421956)
		(end 341.291672 -226.389438)
		(width 0.0889)
		(layer "In13.Cu")
		(net "JTAG_FPGA_TMS")
	)
	(segment
		(start 337.293966 -213.587076)
		(end 336.89417 -213.18728)
		(width 0.13208)
		(layer "F.Cu")
		(net "PRSNT_SSD9_R_N")
	)
	(segment
		(start 266.30376 -27.04973)
		(end 266.320524 -27.066494)
		(width 0.13208)
		(layer "F.Cu")
		(net "PRSNT_SSD9_R_N")
	)
	(segment
		(start 265.309096 -27.04973)
		(end 266.30376 -27.04973)
		(width 0.13208)
		(layer "F.Cu")
		(net "PRSNT_SSD9_R_N")
	)
	(segment
		(start 265.309096 -26.03373)
		(end 265.309096 -27.04973)
		(width 0.13208)
		(layer "F.Cu")
		(net "PRSNT_SSD9_R_N")
	)
	(segment
		(start 264.775696 -36.515548)
		(end 265.596116 -36.515548)
		(width 0.13208)
		(layer "F.Cu")
		(net "PRSNT_SSD9_R_N")
	)
	(segment
		(start 235.867448 -221.103952)
		(end 235.467652 -220.704156)
		(width 0.13208)
		(layer "F.Cu")
		(net "PRSNT_SSD9_R_N")
	)
	(segment
		(start 266.320524 -27.066494)
		(end 267.142468 -27.066494)
		(width 0.13208)
		(layer "F.Cu")
		(net "PRSNT_SSD9_R_N")
	)
	(via
		(at 245.760748 -203.957428)
		(size 0.508)
		(drill 0.254)
		(layers "F.Cu" "B.Cu")
		(net "PRSNT_SSD9_R_N")
	)
	(via
		(at 265.596116 -36.515548)
		(size 0.508)
		(drill 0.254)
		(layers "F.Cu" "B.Cu")
		(net "PRSNT_SSD9_R_N")
	)
	(via
		(at 267.142468 -27.066494)
		(size 0.508)
		(drill 0.254)
		(layers "F.Cu" "B.Cu")
		(net "PRSNT_SSD9_R_N")
	)
	(via
		(at 336.89417 -213.18728)
		(size 0.4572)
		(drill 0.254)
		(layers "F.Cu" "B.Cu")
		(net "PRSNT_SSD9_R_N")
	)
	(via
		(at 235.867448 -221.103952)
		(size 0.4572)
		(drill 0.254)
		(layers "F.Cu" "B.Cu")
		(net "PRSNT_SSD9_R_N")
	)
	(segment
		(start 278.238458 -78.617064)
		(end 277.141686 -77.520292)
		(width 0.15494)
		(layer "In5.Cu")
		(net "PRSNT_SSD9_R_N")
	)
	(segment
		(start 266.593066 -27.066494)
		(end 267.142468 -27.066494)
		(width 0.15494)
		(layer "In5.Cu")
		(net "PRSNT_SSD9_R_N")
	)
	(segment
		(start 265.596116 -36.515548)
		(end 263.963404 -34.882836)
		(width 0.15494)
		(layer "In5.Cu")
		(net "PRSNT_SSD9_R_N")
	)
	(segment
		(start 270.666972 -74.09688)
		(end 270.666972 -41.586404)
		(width 0.15494)
		(layer "In5.Cu")
		(net "PRSNT_SSD9_R_N")
	)
	(segment
		(start 278.238458 -89.969086)
		(end 278.238458 -78.617064)
		(width 0.15494)
		(layer "In5.Cu")
		(net "PRSNT_SSD9_R_N")
	)
	(segment
		(start 256.43459 -113.786158)
		(end 256.43459 -111.055658)
		(width 0.15494)
		(layer "In5.Cu")
		(net "PRSNT_SSD9_R_N")
	)
	(segment
		(start 277.141686 -77.520292)
		(end 274.090384 -77.520292)
		(width 0.15494)
		(layer "In5.Cu")
		(net "PRSNT_SSD9_R_N")
	)
	(segment
		(start 256.43459 -111.055658)
		(end 269.280894 -98.209354)
		(width 0.15494)
		(layer "In5.Cu")
		(net "PRSNT_SSD9_R_N")
	)
	(segment
		(start 248.720102 -201.342498)
		(end 248.720102 -193.371724)
		(width 0.15494)
		(layer "In5.Cu")
		(net "PRSNT_SSD9_R_N")
	)
	(segment
		(start 263.963404 -29.696156)
		(end 266.593066 -27.066494)
		(width 0.15494)
		(layer "In5.Cu")
		(net "PRSNT_SSD9_R_N")
	)
	(segment
		(start 251.990098 -190.101728)
		(end 251.990098 -169.921682)
		(width 0.15494)
		(layer "In5.Cu")
		(net "PRSNT_SSD9_R_N")
	)
	(segment
		(start 251.990098 -169.921682)
		(end 257.852926 -164.058854)
		(width 0.15494)
		(layer "In5.Cu")
		(net "PRSNT_SSD9_R_N")
	)
	(segment
		(start 263.963404 -34.882836)
		(end 263.963404 -29.696156)
		(width 0.15494)
		(layer "In5.Cu")
		(net "PRSNT_SSD9_R_N")
	)
	(segment
		(start 257.852926 -164.058854)
		(end 257.852926 -115.204494)
		(width 0.15494)
		(layer "In5.Cu")
		(net "PRSNT_SSD9_R_N")
	)
	(segment
		(start 246.105172 -203.957428)
		(end 248.720102 -201.342498)
		(width 0.15494)
		(layer "In5.Cu")
		(net "PRSNT_SSD9_R_N")
	)
	(segment
		(start 245.760748 -203.957428)
		(end 246.105172 -203.957428)
		(width 0.15494)
		(layer "In5.Cu")
		(net "PRSNT_SSD9_R_N")
	)
	(segment
		(start 269.99819 -98.209354)
		(end 278.238458 -89.969086)
		(width 0.15494)
		(layer "In5.Cu")
		(net "PRSNT_SSD9_R_N")
	)
	(segment
		(start 248.720102 -193.371724)
		(end 251.990098 -190.101728)
		(width 0.15494)
		(layer "In5.Cu")
		(net "PRSNT_SSD9_R_N")
	)
	(segment
		(start 274.090384 -77.520292)
		(end 270.666972 -74.09688)
		(width 0.15494)
		(layer "In5.Cu")
		(net "PRSNT_SSD9_R_N")
	)
	(segment
		(start 269.280894 -98.209354)
		(end 269.99819 -98.209354)
		(width 0.15494)
		(layer "In5.Cu")
		(net "PRSNT_SSD9_R_N")
	)
	(segment
		(start 257.852926 -115.204494)
		(end 256.43459 -113.786158)
		(width 0.15494)
		(layer "In5.Cu")
		(net "PRSNT_SSD9_R_N")
	)
	(segment
		(start 270.666972 -41.586404)
		(end 265.596116 -36.515548)
		(width 0.15494)
		(layer "In5.Cu")
		(net "PRSNT_SSD9_R_N")
	)
	(segment
		(start 242.384834 -209.506566)
		(end 242.254278 -209.560668)
		(width 0.15494)
		(layer "In7.Cu")
		(net "PRSNT_SSD9_R_N")
	)
	(segment
		(start 237.49 -216.972388)
		(end 237.363 -217.099388)
		(width 0.15494)
		(layer "In7.Cu")
		(net "PRSNT_SSD9_R_N")
	)
	(segment
		(start 244.1448 -205.196694)
		(end 244.1448 -207.545178)
		(width 0.15494)
		(layer "In7.Cu")
		(net "PRSNT_SSD9_R_N")
	)
	(segment
		(start 242.02517 -209.789776)
		(end 242.02517 -210.14563)
		(width 0.15494)
		(layer "In7.Cu")
		(net "PRSNT_SSD9_R_N")
	)
	(segment
		(start 242.02517 -210.14563)
		(end 241.3254 -210.8454)
		(width 0.15494)
		(layer "In7.Cu")
		(net "PRSNT_SSD9_R_N")
	)
	(segment
		(start 240.9444 -210.8454)
		(end 238.9124 -212.8774)
		(width 0.15494)
		(layer "In7.Cu")
		(net "PRSNT_SSD9_R_N")
	)
	(segment
		(start 235.867448 -220.951552)
		(end 235.867448 -221.103952)
		(width 0.15494)
		(layer "In7.Cu")
		(net "PRSNT_SSD9_R_N")
	)
	(segment
		(start 238.0996 -212.8774)
		(end 237.49 -213.487)
		(width 0.15494)
		(layer "In7.Cu")
		(net "PRSNT_SSD9_R_N")
	)
	(segment
		(start 237.363 -219.456)
		(end 235.867448 -220.951552)
		(width 0.15494)
		(layer "In7.Cu")
		(net "PRSNT_SSD9_R_N")
	)
	(segment
		(start 244.67312 -204.668374)
		(end 244.1448 -205.196694)
		(width 0.15494)
		(layer "In7.Cu")
		(net "PRSNT_SSD9_R_N")
	)
	(segment
		(start 237.49 -213.487)
		(end 237.49 -216.972388)
		(width 0.15494)
		(layer "In7.Cu")
		(net "PRSNT_SSD9_R_N")
	)
	(segment
		(start 244.1448 -207.545178)
		(end 244.023134 -207.666844)
		(width 0.15494)
		(layer "In7.Cu")
		(net "PRSNT_SSD9_R_N")
	)
	(segment
		(start 245.760748 -203.957428)
		(end 245.049802 -204.668374)
		(width 0.15494)
		(layer "In7.Cu")
		(net "PRSNT_SSD9_R_N")
	)
	(segment
		(start 244.023134 -208.401666)
		(end 242.918234 -209.506566)
		(width 0.15494)
		(layer "In7.Cu")
		(net "PRSNT_SSD9_R_N")
	)
	(segment
		(start 242.918234 -209.506566)
		(end 242.384834 -209.506566)
		(width 0.15494)
		(layer "In7.Cu")
		(net "PRSNT_SSD9_R_N")
	)
	(segment
		(start 244.023134 -207.666844)
		(end 244.023134 -208.401666)
		(width 0.15494)
		(layer "In7.Cu")
		(net "PRSNT_SSD9_R_N")
	)
	(segment
		(start 241.3254 -210.8454)
		(end 240.9444 -210.8454)
		(width 0.15494)
		(layer "In7.Cu")
		(net "PRSNT_SSD9_R_N")
	)
	(segment
		(start 237.363 -217.099388)
		(end 237.363 -219.456)
		(width 0.15494)
		(layer "In7.Cu")
		(net "PRSNT_SSD9_R_N")
	)
	(segment
		(start 245.049802 -204.668374)
		(end 244.67312 -204.668374)
		(width 0.15494)
		(layer "In7.Cu")
		(net "PRSNT_SSD9_R_N")
	)
	(segment
		(start 242.254278 -209.560668)
		(end 242.02517 -209.789776)
		(width 0.15494)
		(layer "In7.Cu")
		(net "PRSNT_SSD9_R_N")
	)
	(segment
		(start 238.9124 -212.8774)
		(end 238.0996 -212.8774)
		(width 0.15494)
		(layer "In7.Cu")
		(net "PRSNT_SSD9_R_N")
	)
	(segment
		(start 332.8162 -213.4616)
		(end 332.211934 -213.4616)
		(width 0.15494)
		(layer "In15.Cu")
		(net "PRSNT_SSD9_R_N")
	)
	(segment
		(start 328.052176 -210.7692)
		(end 324.5866 -210.7692)
		(width 0.15494)
		(layer "In15.Cu")
		(net "PRSNT_SSD9_R_N")
	)
	(segment
		(start 247.51792 -205.7146)
		(end 245.760748 -203.957428)
		(width 0.15494)
		(layer "In15.Cu")
		(net "PRSNT_SSD9_R_N")
	)
	(segment
		(start 288.948368 -210.07832)
		(end 284.15742 -214.869268)
		(width 0.15494)
		(layer "In15.Cu")
		(net "PRSNT_SSD9_R_N")
	)
	(segment
		(start 250.871482 -205.7146)
		(end 247.51792 -205.7146)
		(width 0.15494)
		(layer "In15.Cu")
		(net "PRSNT_SSD9_R_N")
	)
	(segment
		(start 251.633482 -206.4766)
		(end 250.871482 -205.7146)
		(width 0.15494)
		(layer "In15.Cu")
		(net "PRSNT_SSD9_R_N")
	)
	(segment
		(start 263.040622 -215.258396)
		(end 261.257288 -213.475062)
		(width 0.15494)
		(layer "In15.Cu")
		(net "PRSNT_SSD9_R_N")
	)
	(segment
		(start 265.404346 -214.869268)
		(end 265.015218 -215.258396)
		(width 0.15494)
		(layer "In15.Cu")
		(net "PRSNT_SSD9_R_N")
	)
	(segment
		(start 332.211934 -213.4616)
		(end 330.606654 -211.85632)
		(width 0.15494)
		(layer "In15.Cu")
		(net "PRSNT_SSD9_R_N")
	)
	(segment
		(start 324.5866 -210.7692)
		(end 323.89572 -210.07832)
		(width 0.15494)
		(layer "In15.Cu")
		(net "PRSNT_SSD9_R_N")
	)
	(segment
		(start 333.348076 -213.56193)
		(end 333.247746 -213.4616)
		(width 0.0889)
		(layer "In15.Cu")
		(net "PRSNT_SSD9_R_N")
	)
	(segment
		(start 257.66141 -210.437984)
		(end 253.700026 -206.4766)
		(width 0.15494)
		(layer "In15.Cu")
		(net "PRSNT_SSD9_R_N")
	)
	(segment
		(start 323.89572 -210.07832)
		(end 288.948368 -210.07832)
		(width 0.15494)
		(layer "In15.Cu")
		(net "PRSNT_SSD9_R_N")
	)
	(segment
		(start 336.89417 -213.18728)
		(end 336.51952 -213.56193)
		(width 0.0889)
		(layer "In15.Cu")
		(net "PRSNT_SSD9_R_N")
	)
	(segment
		(start 257.94462 -210.918044)
		(end 257.66141 -210.634834)
		(width 0.15494)
		(layer "In15.Cu")
		(net "PRSNT_SSD9_R_N")
	)
	(segment
		(start 261.257288 -213.063582)
		(end 259.11175 -210.918044)
		(width 0.15494)
		(layer "In15.Cu")
		(net "PRSNT_SSD9_R_N")
	)
	(segment
		(start 329.139296 -211.85632)
		(end 328.052176 -210.7692)
		(width 0.15494)
		(layer "In15.Cu")
		(net "PRSNT_SSD9_R_N")
	)
	(segment
		(start 333.247746 -213.4616)
		(end 332.8162 -213.4616)
		(width 0.0889)
		(layer "In15.Cu")
		(net "PRSNT_SSD9_R_N")
	)
	(segment
		(start 265.015218 -215.258396)
		(end 263.040622 -215.258396)
		(width 0.15494)
		(layer "In15.Cu")
		(net "PRSNT_SSD9_R_N")
	)
	(segment
		(start 257.66141 -210.634834)
		(end 257.66141 -210.437984)
		(width 0.15494)
		(layer "In15.Cu")
		(net "PRSNT_SSD9_R_N")
	)
	(segment
		(start 259.11175 -210.918044)
		(end 257.94462 -210.918044)
		(width 0.15494)
		(layer "In15.Cu")
		(net "PRSNT_SSD9_R_N")
	)
	(segment
		(start 284.15742 -214.869268)
		(end 265.404346 -214.869268)
		(width 0.15494)
		(layer "In15.Cu")
		(net "PRSNT_SSD9_R_N")
	)
	(segment
		(start 261.257288 -213.475062)
		(end 261.257288 -213.063582)
		(width 0.15494)
		(layer "In15.Cu")
		(net "PRSNT_SSD9_R_N")
	)
	(segment
		(start 330.606654 -211.85632)
		(end 329.139296 -211.85632)
		(width 0.15494)
		(layer "In15.Cu")
		(net "PRSNT_SSD9_R_N")
	)
	(segment
		(start 253.700026 -206.4766)
		(end 251.633482 -206.4766)
		(width 0.15494)
		(layer "In15.Cu")
		(net "PRSNT_SSD9_R_N")
	)
	(segment
		(start 336.51952 -213.56193)
		(end 333.348076 -213.56193)
		(width 0.0889)
		(layer "In15.Cu")
		(net "PRSNT_SSD9_R_N")
	)
	(via
		(at 318.045592 -260.660642)
		(size 0.508)
		(drill 0.254)
		(layers "F.Cu" "B.Cu")
		(net "UART_PEX2_SDB_R_TX")
	)
	(via
		(at 370.315998 -245.544848)
		(size 0.508)
		(drill 0.254)
		(layers "F.Cu" "B.Cu")
		(net "UART_PEX2_SDB_R_TX")
	)
	(segment
		(start 310.435244 -282.257246)
		(end 310.435244 -289.051746)
		(width 0.13208)
		(layer "B.Cu")
		(net "UART_PEX2_SDB_R_TX")
	)
	(segment
		(start 310.162194 -289.324796)
		(end 307.923692 -289.324796)
		(width 0.13208)
		(layer "B.Cu")
		(net "UART_PEX2_SDB_R_TX")
	)
	(segment
		(start 370.621052 -246.791988)
		(end 372.035324 -246.791988)
		(width 0.13208)
		(layer "B.Cu")
		(net "UART_PEX2_SDB_R_TX")
	)
	(segment
		(start 309.457598 -270.913352)
		(end 309.457598 -281.813)
		(width 0.13208)
		(layer "B.Cu")
		(net "UART_PEX2_SDB_R_TX")
	)
	(segment
		(start 309.457598 -281.813)
		(end 309.756048 -282.11145)
		(width 0.13208)
		(layer "B.Cu")
		(net "UART_PEX2_SDB_R_TX")
	)
	(segment
		(start 309.756048 -282.11145)
		(end 310.289448 -282.11145)
		(width 0.13208)
		(layer "B.Cu")
		(net "UART_PEX2_SDB_R_TX")
	)
	(segment
		(start 310.435244 -289.051746)
		(end 310.162194 -289.324796)
		(width 0.13208)
		(layer "B.Cu")
		(net "UART_PEX2_SDB_R_TX")
	)
	(segment
		(start 370.315998 -245.544848)
		(end 370.315998 -246.486934)
		(width 0.13208)
		(layer "B.Cu")
		(net "UART_PEX2_SDB_R_TX")
	)
	(segment
		(start 370.315998 -246.486934)
		(end 370.621052 -246.791988)
		(width 0.13208)
		(layer "B.Cu")
		(net "UART_PEX2_SDB_R_TX")
	)
	(segment
		(start 317.48349 -261.628128)
		(end 317.48349 -262.88746)
		(width 0.13208)
		(layer "B.Cu")
		(net "UART_PEX2_SDB_R_TX")
	)
	(segment
		(start 317.48349 -262.88746)
		(end 309.457598 -270.913352)
		(width 0.13208)
		(layer "B.Cu")
		(net "UART_PEX2_SDB_R_TX")
	)
	(segment
		(start 318.045592 -260.660642)
		(end 318.045592 -261.066026)
		(width 0.13208)
		(layer "B.Cu")
		(net "UART_PEX2_SDB_R_TX")
	)
	(segment
		(start 318.045592 -261.066026)
		(end 317.48349 -261.628128)
		(width 0.13208)
		(layer "B.Cu")
		(net "UART_PEX2_SDB_R_TX")
	)
	(segment
		(start 310.289448 -282.11145)
		(end 310.435244 -282.257246)
		(width 0.13208)
		(layer "B.Cu")
		(net "UART_PEX2_SDB_R_TX")
	)
	(segment
		(start 337.574128 -259.209794)
		(end 330.872338 -259.209794)
		(width 0.15494)
		(layer "In15.Cu")
		(net "UART_PEX2_SDB_R_TX")
	)
	(segment
		(start 363.271562 -247.079262)
		(end 349.70466 -247.079262)
		(width 0.15494)
		(layer "In15.Cu")
		(net "UART_PEX2_SDB_R_TX")
	)
	(segment
		(start 349.70466 -247.079262)
		(end 337.574128 -259.209794)
		(width 0.15494)
		(layer "In15.Cu")
		(net "UART_PEX2_SDB_R_TX")
	)
	(segment
		(start 364.260638 -246.090186)
		(end 363.271562 -247.079262)
		(width 0.15494)
		(layer "In15.Cu")
		(net "UART_PEX2_SDB_R_TX")
	)
	(segment
		(start 369.77066 -246.090186)
		(end 364.260638 -246.090186)
		(width 0.15494)
		(layer "In15.Cu")
		(net "UART_PEX2_SDB_R_TX")
	)
	(segment
		(start 330.491592 -259.59054)
		(end 319.115694 -259.59054)
		(width 0.15494)
		(layer "In15.Cu")
		(net "UART_PEX2_SDB_R_TX")
	)
	(segment
		(start 319.115694 -259.59054)
		(end 318.045592 -260.660642)
		(width 0.15494)
		(layer "In15.Cu")
		(net "UART_PEX2_SDB_R_TX")
	)
	(segment
		(start 330.872338 -259.209794)
		(end 330.491592 -259.59054)
		(width 0.15494)
		(layer "In15.Cu")
		(net "UART_PEX2_SDB_R_TX")
	)
	(segment
		(start 370.315998 -245.544848)
		(end 369.77066 -246.090186)
		(width 0.15494)
		(layer "In15.Cu")
		(net "UART_PEX2_SDB_R_TX")
	)
	(segment
		(start 454.840848 -20.755102)
		(end 454.840848 -21.68525)
		(width 0.13208)
		(layer "F.Cu")
		(net "SMB_SSD15_ISO_EN")
	)
	(segment
		(start 454.806558 -20.789392)
		(end 454.840848 -20.755102)
		(width 0.13208)
		(layer "F.Cu")
		(net "SMB_SSD15_ISO_EN")
	)
	(segment
		(start 454.754742 -21.771356)
		(end 454.754742 -22.561296)
		(width 0.13208)
		(layer "F.Cu")
		(net "SMB_SSD15_ISO_EN")
	)
	(segment
		(start 453.960484 -20.789392)
		(end 454.806558 -20.789392)
		(width 0.13208)
		(layer "F.Cu")
		(net "SMB_SSD15_ISO_EN")
	)
	(segment
		(start 454.840848 -21.68525)
		(end 454.754742 -21.771356)
		(width 0.13208)
		(layer "F.Cu")
		(net "SMB_SSD15_ISO_EN")
	)
	(via
		(at 454.840848 -20.755102)
		(size 0.508)
		(drill 0.254)
		(layers "F.Cu" "B.Cu")
		(net "SMB_SSD15_ISO_EN")
	)
	(segment
		(start 93.56979 -363.31779)
		(end 61.515498 -363.31779)
		(width 0.13208)
		(layer "F.Cu")
		(net "SMB_GPU_1_R_SDA")
	)
	(segment
		(start 101.49078 -374.968262)
		(end 100.026724 -373.504206)
		(width 0.13208)
		(layer "F.Cu")
		(net "SMB_GPU_1_R_SDA")
	)
	(segment
		(start 55.81142 -380.093982)
		(end 55.377334 -379.659896)
		(width 0.13208)
		(layer "F.Cu")
		(net "SMB_GPU_1_R_SDA")
	)
	(segment
		(start 101.281738 -381.243586)
		(end 101.49078 -381.034544)
		(width 0.13208)
		(layer "F.Cu")
		(net "SMB_GPU_1_R_SDA")
	)
	(segment
		(start 60.683902 -378.37618)
		(end 58.80227 -380.257812)
		(width 0.13208)
		(layer "F.Cu")
		(net "SMB_GPU_1_R_SDA")
	)
	(segment
		(start 56.945784 -380.093982)
		(end 55.81142 -380.093982)
		(width 0.13208)
		(layer "F.Cu")
		(net "SMB_GPU_1_R_SDA")
	)
	(segment
		(start 60.683902 -364.149386)
		(end 60.683902 -378.37618)
		(width 0.13208)
		(layer "F.Cu")
		(net "SMB_GPU_1_R_SDA")
	)
	(segment
		(start 100.026724 -369.774724)
		(end 93.56979 -363.31779)
		(width 0.13208)
		(layer "F.Cu")
		(net "SMB_GPU_1_R_SDA")
	)
	(segment
		(start 61.515498 -363.31779)
		(end 60.683902 -364.149386)
		(width 0.13208)
		(layer "F.Cu")
		(net "SMB_GPU_1_R_SDA")
	)
	(segment
		(start 57.109614 -380.257812)
		(end 56.945784 -380.093982)
		(width 0.13208)
		(layer "F.Cu")
		(net "SMB_GPU_1_R_SDA")
	)
	(segment
		(start 58.80227 -380.257812)
		(end 57.109614 -380.257812)
		(width 0.13208)
		(layer "F.Cu")
		(net "SMB_GPU_1_R_SDA")
	)
	(segment
		(start 100.026724 -373.504206)
		(end 100.026724 -369.774724)
		(width 0.13208)
		(layer "F.Cu")
		(net "SMB_GPU_1_R_SDA")
	)
	(segment
		(start 101.49078 -381.034544)
		(end 101.49078 -374.968262)
		(width 0.13208)
		(layer "F.Cu")
		(net "SMB_GPU_1_R_SDA")
	)
	(via
		(at 101.281738 -381.243586)
		(size 0.508)
		(drill 0.254)
		(layers "F.Cu" "B.Cu")
		(net "SMB_GPU_1_R_SDA")
	)
	(via
		(at 55.377334 -379.659896)
		(size 0.508)
		(drill 0.254)
		(layers "F.Cu" "B.Cu")
		(net "SMB_GPU_1_R_SDA")
	)
	(segment
		(start 100.488496 -378.690124)
		(end 101.909118 -380.110746)
		(width 0.13208)
		(layer "B.Cu")
		(net "SMB_GPU_1_R_SDA")
	)
	(segment
		(start 100.358194 -378.690124)
		(end 100.488496 -378.690124)
		(width 0.13208)
		(layer "B.Cu")
		(net "SMB_GPU_1_R_SDA")
	)
	(segment
		(start 101.909118 -380.110746)
		(end 101.909118 -380.616206)
		(width 0.13208)
		(layer "B.Cu")
		(net "SMB_GPU_1_R_SDA")
	)
	(segment
		(start 101.909118 -380.616206)
		(end 101.281738 -381.243586)
		(width 0.13208)
		(layer "B.Cu")
		(net "SMB_GPU_1_R_SDA")
	)
	(segment
		(start 55.193946 -379.843284)
		(end 48.163226 -379.843284)
		(width 0.15494)
		(layer "In9.Cu")
		(net "SMB_GPU_1_R_SDA")
	)
	(segment
		(start 55.377334 -379.659896)
		(end 55.193946 -379.843284)
		(width 0.15494)
		(layer "In9.Cu")
		(net "SMB_GPU_1_R_SDA")
	)
	(segment
		(start 48.163226 -379.843284)
		(end 47.71009 -379.390148)
		(width 0.15494)
		(layer "In9.Cu")
		(net "SMB_GPU_1_R_SDA")
	)
	(via
		(at 300.012354 -233.434636)
		(size 0.6604)
		(drill 0.3302)
		(layers "F.Cu" "B.Cu")
		(net "RST_GPU_PERST_0_R_N")
	)
	(segment
		(start 300.012354 -234.558586)
		(end 300.012354 -233.434636)
		(width 0.13208)
		(layer "B.Cu")
		(net "RST_GPU_PERST_0_R_N")
	)
	(segment
		(start 301.069248 -232.377742)
		(end 301.069248 -231.220518)
		(width 0.13208)
		(layer "B.Cu")
		(net "RST_GPU_PERST_0_R_N")
	)
	(segment
		(start 300.012354 -233.434636)
		(end 301.069248 -232.377742)
		(width 0.13208)
		(layer "B.Cu")
		(net "RST_GPU_PERST_0_R_N")
	)
	(segment
		(start 244.78361 -61.856366)
		(end 244.78361 -64.948054)
		(width 0.13208)
		(layer "F.Cu")
		(net "PWRGD_P12V_SSD8_R")
	)
	(segment
		(start 243.372386 -60.445142)
		(end 244.78361 -61.856366)
		(width 0.13208)
		(layer "F.Cu")
		(net "PWRGD_P12V_SSD8_R")
	)
	(segment
		(start 241.624612 -60.445142)
		(end 243.372386 -60.445142)
		(width 0.13208)
		(layer "F.Cu")
		(net "PWRGD_P12V_SSD8_R")
	)
	(segment
		(start 244.78361 -64.948054)
		(end 245.591076 -65.75552)
		(width 0.13208)
		(layer "F.Cu")
		(net "PWRGD_P12V_SSD8_R")
	)
	(segment
		(start 258.86791 -53.051456)
		(end 259.52323 -53.051456)
		(width 0.13208)
		(layer "F.Cu")
		(net "PWRGD_P12V_SSD8_R")
	)
	(segment
		(start 334.89392 -211.18703)
		(end 334.494124 -210.787234)
		(width 0.13208)
		(layer "F.Cu")
		(net "PWRGD_P12V_SSD8_R")
	)
	(segment
		(start 245.591076 -65.75552)
		(end 246.92864 -65.75552)
		(width 0.13208)
		(layer "F.Cu")
		(net "PWRGD_P12V_SSD8_R")
	)
	(via
		(at 342.839802 -94.464632)
		(size 0.508)
		(drill 0.254)
		(layers "F.Cu" "B.Cu")
		(net "PWRGD_P12V_SSD8_R")
	)
	(via
		(at 259.52323 -53.051456)
		(size 0.508)
		(drill 0.254)
		(layers "F.Cu" "B.Cu")
		(net "PWRGD_P12V_SSD8_R")
	)
	(via
		(at 334.494124 -210.787234)
		(size 0.4572)
		(drill 0.254)
		(layers "F.Cu" "B.Cu")
		(net "PWRGD_P12V_SSD8_R")
	)
	(via
		(at 277.510494 -89.756996)
		(size 0.508)
		(drill 0.254)
		(layers "F.Cu" "B.Cu")
		(net "PWRGD_P12V_SSD8_R")
	)
	(via
		(at 246.92864 -65.75552)
		(size 0.508)
		(drill 0.254)
		(layers "F.Cu" "B.Cu")
		(net "PWRGD_P12V_SSD8_R")
	)
	(segment
		(start 257.461258 -57.501028)
		(end 257.943858 -57.983628)
		(width 0.15494)
		(layer "In5.Cu")
		(net "PWRGD_P12V_SSD8_R")
	)
	(segment
		(start 259.38607 -58.114692)
		(end 259.38607 -68.231512)
		(width 0.15494)
		(layer "In5.Cu")
		(net "PWRGD_P12V_SSD8_R")
	)
	(segment
		(start 259.52323 -53.051456)
		(end 259.090922 -53.051456)
		(width 0.15494)
		(layer "In5.Cu")
		(net "PWRGD_P12V_SSD8_R")
	)
	(segment
		(start 259.090922 -53.051456)
		(end 257.461258 -54.68112)
		(width 0.15494)
		(layer "In5.Cu")
		(net "PWRGD_P12V_SSD8_R")
	)
	(segment
		(start 258.9403 -53.940202)
		(end 258.9403 -57.668922)
		(width 0.15494)
		(layer "In5.Cu")
		(net "PWRGD_P12V_SSD8_R")
	)
	(segment
		(start 259.52323 -53.357272)
		(end 258.9403 -53.940202)
		(width 0.15494)
		(layer "In5.Cu")
		(net "PWRGD_P12V_SSD8_R")
	)
	(segment
		(start 257.943858 -64.240664)
		(end 257.64109 -64.543432)
		(width 0.15494)
		(layer "In5.Cu")
		(net "PWRGD_P12V_SSD8_R")
	)
	(segment
		(start 273.166078 -87.005922)
		(end 274.358608 -87.005922)
		(width 0.15494)
		(layer "In5.Cu")
		(net "PWRGD_P12V_SSD8_R")
	)
	(segment
		(start 257.64109 -64.543432)
		(end 251.201174 -64.543432)
		(width 0.15494)
		(layer "In5.Cu")
		(net "PWRGD_P12V_SSD8_R")
	)
	(segment
		(start 250.23318 -65.511426)
		(end 247.172734 -65.511426)
		(width 0.15494)
		(layer "In5.Cu")
		(net "PWRGD_P12V_SSD8_R")
	)
	(segment
		(start 269.236698 -83.076542)
		(end 273.166078 -87.005922)
		(width 0.15494)
		(layer "In5.Cu")
		(net "PWRGD_P12V_SSD8_R")
	)
	(segment
		(start 274.358608 -87.005922)
		(end 277.109682 -89.756996)
		(width 0.15494)
		(layer "In5.Cu")
		(net "PWRGD_P12V_SSD8_R")
	)
	(segment
		(start 259.38607 -68.231512)
		(end 269.236698 -78.08214)
		(width 0.15494)
		(layer "In5.Cu")
		(net "PWRGD_P12V_SSD8_R")
	)
	(segment
		(start 251.201174 -64.543432)
		(end 250.23318 -65.511426)
		(width 0.15494)
		(layer "In5.Cu")
		(net "PWRGD_P12V_SSD8_R")
	)
	(segment
		(start 259.52323 -53.051456)
		(end 259.52323 -53.357272)
		(width 0.15494)
		(layer "In5.Cu")
		(net "PWRGD_P12V_SSD8_R")
	)
	(segment
		(start 277.109682 -89.756996)
		(end 277.510494 -89.756996)
		(width 0.15494)
		(layer "In5.Cu")
		(net "PWRGD_P12V_SSD8_R")
	)
	(segment
		(start 247.172734 -65.511426)
		(end 246.92864 -65.75552)
		(width 0.15494)
		(layer "In5.Cu")
		(net "PWRGD_P12V_SSD8_R")
	)
	(segment
		(start 257.461258 -54.68112)
		(end 257.461258 -57.501028)
		(width 0.15494)
		(layer "In5.Cu")
		(net "PWRGD_P12V_SSD8_R")
	)
	(segment
		(start 258.9403 -57.668922)
		(end 259.38607 -58.114692)
		(width 0.15494)
		(layer "In5.Cu")
		(net "PWRGD_P12V_SSD8_R")
	)
	(segment
		(start 269.236698 -78.08214)
		(end 269.236698 -83.076542)
		(width 0.15494)
		(layer "In5.Cu")
		(net "PWRGD_P12V_SSD8_R")
	)
	(segment
		(start 257.943858 -57.983628)
		(end 257.943858 -64.240664)
		(width 0.15494)
		(layer "In5.Cu")
		(net "PWRGD_P12V_SSD8_R")
	)
	(segment
		(start 343.696544 -142.289022)
		(end 344.3478 -141.637766)
		(width 0.15494)
		(layer "In9.Cu")
		(net "PWRGD_P12V_SSD8_R")
	)
	(segment
		(start 340.938104 -180.803296)
		(end 340.938104 -176.784254)
		(width 0.15494)
		(layer "In9.Cu")
		(net "PWRGD_P12V_SSD8_R")
	)
	(segment
		(start 332.994 -198.890636)
		(end 333.5782 -198.306436)
		(width 0.15494)
		(layer "In9.Cu")
		(net "PWRGD_P12V_SSD8_R")
	)
	(segment
		(start 338.3534 -185.9788)
		(end 338.7852 -185.547)
		(width 0.15494)
		(layer "In9.Cu")
		(net "PWRGD_P12V_SSD8_R")
	)
	(segment
		(start 332.994 -206.642462)
		(end 332.994 -198.890636)
		(width 0.15494)
		(layer "In9.Cu")
		(net "PWRGD_P12V_SSD8_R")
	)
	(segment
		(start 339.87613 -181.86527)
		(end 340.938104 -180.803296)
		(width 0.15494)
		(layer "In9.Cu")
		(net "PWRGD_P12V_SSD8_R")
	)
	(segment
		(start 344.3478 -141.637766)
		(end 344.3478 -139.268454)
		(width 0.15494)
		(layer "In9.Cu")
		(net "PWRGD_P12V_SSD8_R")
	)
	(segment
		(start 338.7852 -185.547)
		(end 339.3694 -185.547)
		(width 0.15494)
		(layer "In9.Cu")
		(net "PWRGD_P12V_SSD8_R")
	)
	(segment
		(start 344.3478 -139.268454)
		(end 345.4908 -138.125454)
		(width 0.15494)
		(layer "In9.Cu")
		(net "PWRGD_P12V_SSD8_R")
	)
	(segment
		(start 343.092024 -175.499522)
		(end 343.696544 -174.895002)
		(width 0.15494)
		(layer "In9.Cu")
		(net "PWRGD_P12V_SSD8_R")
	)
	(segment
		(start 345.4908 -138.125454)
		(end 345.4908 -122.478546)
		(width 0.15494)
		(layer "In9.Cu")
		(net "PWRGD_P12V_SSD8_R")
	)
	(segment
		(start 334.494124 -210.787234)
		(end 334.494124 -208.142586)
		(width 0.15494)
		(layer "In9.Cu")
		(net "PWRGD_P12V_SSD8_R")
	)
	(segment
		(start 342.222836 -175.499522)
		(end 343.092024 -175.499522)
		(width 0.15494)
		(layer "In9.Cu")
		(net "PWRGD_P12V_SSD8_R")
	)
	(segment
		(start 345.4908 -122.478546)
		(end 346.8878 -121.081546)
		(width 0.15494)
		(layer "In9.Cu")
		(net "PWRGD_P12V_SSD8_R")
	)
	(segment
		(start 340.938104 -176.784254)
		(end 342.222836 -175.499522)
		(width 0.15494)
		(layer "In9.Cu")
		(net "PWRGD_P12V_SSD8_R")
	)
	(segment
		(start 346.8878 -121.081546)
		(end 346.8878 -98.51263)
		(width 0.15494)
		(layer "In9.Cu")
		(net "PWRGD_P12V_SSD8_R")
	)
	(segment
		(start 343.696544 -174.895002)
		(end 343.696544 -142.289022)
		(width 0.15494)
		(layer "In9.Cu")
		(net "PWRGD_P12V_SSD8_R")
	)
	(segment
		(start 333.5782 -198.306436)
		(end 333.5782 -191.899794)
		(width 0.15494)
		(layer "In9.Cu")
		(net "PWRGD_P12V_SSD8_R")
	)
	(segment
		(start 334.494124 -208.142586)
		(end 332.994 -206.642462)
		(width 0.15494)
		(layer "In9.Cu")
		(net "PWRGD_P12V_SSD8_R")
	)
	(segment
		(start 339.3694 -185.547)
		(end 339.87613 -185.04027)
		(width 0.15494)
		(layer "In9.Cu")
		(net "PWRGD_P12V_SSD8_R")
	)
	(segment
		(start 346.8878 -98.51263)
		(end 342.839802 -94.464632)
		(width 0.15494)
		(layer "In9.Cu")
		(net "PWRGD_P12V_SSD8_R")
	)
	(segment
		(start 333.5782 -191.899794)
		(end 338.3534 -187.124594)
		(width 0.15494)
		(layer "In9.Cu")
		(net "PWRGD_P12V_SSD8_R")
	)
	(segment
		(start 338.3534 -187.124594)
		(end 338.3534 -185.9788)
		(width 0.15494)
		(layer "In9.Cu")
		(net "PWRGD_P12V_SSD8_R")
	)
	(segment
		(start 339.87613 -185.04027)
		(end 339.87613 -181.86527)
		(width 0.15494)
		(layer "In9.Cu")
		(net "PWRGD_P12V_SSD8_R")
	)
	(segment
		(start 315.315346 -90.9574)
		(end 316.255146 -90.0176)
		(width 0.15494)
		(layer "In15.Cu")
		(net "PWRGD_P12V_SSD8_R")
	)
	(segment
		(start 331.266546 -92.456)
		(end 331.665072 -92.057474)
		(width 0.15494)
		(layer "In15.Cu")
		(net "PWRGD_P12V_SSD8_R")
	)
	(segment
		(start 281.609546 -89.916)
		(end 310.997346 -89.916)
		(width 0.15494)
		(layer "In15.Cu")
		(net "PWRGD_P12V_SSD8_R")
	)
	(segment
		(start 335.2292 -93.726)
		(end 342.10117 -93.726)
		(width 0.15494)
		(layer "In15.Cu")
		(net "PWRGD_P12V_SSD8_R")
	)
	(segment
		(start 316.255146 -90.0176)
		(end 323.951854 -90.0176)
		(width 0.15494)
		(layer "In15.Cu")
		(net "PWRGD_P12V_SSD8_R")
	)
	(segment
		(start 310.997346 -89.916)
		(end 312.038746 -90.9574)
		(width 0.15494)
		(layer "In15.Cu")
		(net "PWRGD_P12V_SSD8_R")
	)
	(segment
		(start 277.510494 -89.756996)
		(end 278.007572 -89.259918)
		(width 0.15494)
		(layer "In15.Cu")
		(net "PWRGD_P12V_SSD8_R")
	)
	(segment
		(start 342.10117 -93.726)
		(end 342.839802 -94.464632)
		(width 0.15494)
		(layer "In15.Cu")
		(net "PWRGD_P12V_SSD8_R")
	)
	(segment
		(start 278.007572 -89.259918)
		(end 280.953464 -89.259918)
		(width 0.15494)
		(layer "In15.Cu")
		(net "PWRGD_P12V_SSD8_R")
	)
	(segment
		(start 312.038746 -90.9574)
		(end 315.315346 -90.9574)
		(width 0.15494)
		(layer "In15.Cu")
		(net "PWRGD_P12V_SSD8_R")
	)
	(segment
		(start 323.951854 -90.0176)
		(end 326.390254 -92.456)
		(width 0.15494)
		(layer "In15.Cu")
		(net "PWRGD_P12V_SSD8_R")
	)
	(segment
		(start 331.665072 -92.057474)
		(end 333.560674 -92.057474)
		(width 0.15494)
		(layer "In15.Cu")
		(net "PWRGD_P12V_SSD8_R")
	)
	(segment
		(start 333.560674 -92.057474)
		(end 335.2292 -93.726)
		(width 0.15494)
		(layer "In15.Cu")
		(net "PWRGD_P12V_SSD8_R")
	)
	(segment
		(start 326.390254 -92.456)
		(end 331.266546 -92.456)
		(width 0.15494)
		(layer "In15.Cu")
		(net "PWRGD_P12V_SSD8_R")
	)
	(segment
		(start 280.953464 -89.259918)
		(end 281.609546 -89.916)
		(width 0.15494)
		(layer "In15.Cu")
		(net "PWRGD_P12V_SSD8_R")
	)
	(segment
		(start 166.247318 -54.144164)
		(end 166.675562 -54.144164)
		(width 0.13208)
		(layer "F.Cu")
		(net "P12V_SSD5_OCP")
	)
	(segment
		(start 166.675562 -54.144164)
		(end 166.856156 -53.96357)
		(width 0.13208)
		(layer "F.Cu")
		(net "P12V_SSD5_OCP")
	)
	(segment
		(start 167.967914 -54.067456)
		(end 167.864028 -53.96357)
		(width 0.13208)
		(layer "F.Cu")
		(net "P12V_SSD5_OCP")
	)
	(segment
		(start 167.864028 -53.96357)
		(end 167.254174 -53.96357)
		(width 0.13208)
		(layer "F.Cu")
		(net "P12V_SSD5_OCP")
	)
	(segment
		(start 166.856156 -53.96357)
		(end 167.254174 -53.96357)
		(width 0.13208)
		(layer "F.Cu")
		(net "P12V_SSD5_OCP")
	)
	(via
		(at 167.254174 -53.96357)
		(size 0.508)
		(drill 0.254)
		(layers "F.Cu" "B.Cu")
		(net "P12V_SSD5_OCP")
	)
	(via
		(at 385.43738 -245.737634)
		(size 0.6604)
		(drill 0.3302)
		(layers "F.Cu" "B.Cu")
		(net "UART_PEX3_SDB_BUF_R_RX")
	)
	(segment
		(start 385.43738 -245.737634)
		(end 385.425696 -245.749318)
		(width 0.13208)
		(layer "B.Cu")
		(net "UART_PEX3_SDB_BUF_R_RX")
	)
	(segment
		(start 385.425696 -245.749318)
		(end 385.425696 -246.911876)
		(width 0.13208)
		(layer "B.Cu")
		(net "UART_PEX3_SDB_BUF_R_RX")
	)
	(segment
		(start 386.192014 -244.983)
		(end 385.43738 -245.737634)
		(width 0.13208)
		(layer "B.Cu")
		(net "UART_PEX3_SDB_BUF_R_RX")
	)
	(segment
		(start 386.192014 -244.204998)
		(end 386.192014 -244.983)
		(width 0.13208)
		(layer "B.Cu")
		(net "UART_PEX3_SDB_BUF_R_RX")
	)
	(segment
		(start 427.31182 -16.363188)
		(end 427.31182 -15.351252)
		(width 0.13208)
		(layer "F.Cu")
		(net "SMB_ISO_SSD14_SDA")
	)
	(segment
		(start 427.23562 -16.439388)
		(end 427.31182 -16.363188)
		(width 0.13208)
		(layer "F.Cu")
		(net "SMB_ISO_SSD14_SDA")
	)
	(segment
		(start 426.31614 -19.453098)
		(end 427.23562 -18.533618)
		(width 0.13208)
		(layer "F.Cu")
		(net "SMB_ISO_SSD14_SDA")
	)
	(segment
		(start 423.55643 -20.222972)
		(end 424.326304 -19.453098)
		(width 0.13208)
		(layer "F.Cu")
		(net "SMB_ISO_SSD14_SDA")
	)
	(segment
		(start 427.23562 -18.533618)
		(end 427.23562 -16.439388)
		(width 0.13208)
		(layer "F.Cu")
		(net "SMB_ISO_SSD14_SDA")
	)
	(segment
		(start 423.55643 -20.467574)
		(end 423.55643 -20.222972)
		(width 0.13208)
		(layer "F.Cu")
		(net "SMB_ISO_SSD14_SDA")
	)
	(segment
		(start 427.762416 -23.337266)
		(end 427.762416 -23.946866)
		(width 0.13208)
		(layer "F.Cu")
		(net "SMB_ISO_SSD14_SDA")
	)
	(segment
		(start 424.36796 -19.453098)
		(end 426.31614 -19.453098)
		(width 0.13208)
		(layer "F.Cu")
		(net "SMB_ISO_SSD14_SDA")
	)
	(segment
		(start 424.326304 -19.453098)
		(end 424.36796 -19.453098)
		(width 0.13208)
		(layer "F.Cu")
		(net "SMB_ISO_SSD14_SDA")
	)
	(via
		(at 427.31182 -15.351252)
		(size 0.508)
		(drill 0.254)
		(layers "F.Cu" "B.Cu")
		(net "SMB_ISO_SSD14_SDA")
	)
	(via
		(at 427.762416 -23.946866)
		(size 0.508)
		(drill 0.254)
		(layers "F.Cu" "B.Cu")
		(net "SMB_ISO_SSD14_SDA")
	)
	(segment
		(start 429.34509 -22.364192)
		(end 429.34509 -17.453864)
		(width 0.13208)
		(layer "B.Cu")
		(net "SMB_ISO_SSD14_SDA")
	)
	(segment
		(start 427.31182 -15.420594)
		(end 427.31182 -15.351252)
		(width 0.13208)
		(layer "B.Cu")
		(net "SMB_ISO_SSD14_SDA")
	)
	(segment
		(start 427.762416 -23.946866)
		(end 429.34509 -22.364192)
		(width 0.13208)
		(layer "B.Cu")
		(net "SMB_ISO_SSD14_SDA")
	)
	(segment
		(start 429.34509 -17.453864)
		(end 427.31182 -15.420594)
		(width 0.13208)
		(layer "B.Cu")
		(net "SMB_ISO_SSD14_SDA")
	)
	(segment
		(start 57.059068 -384.973068)
		(end 56.66486 -384.973068)
		(width 0.13208)
		(layer "F.Cu")
		(net "GPU_BASE_FPGA_READY")
	)
	(segment
		(start 57.804812 -385.718812)
		(end 57.059068 -384.973068)
		(width 0.13208)
		(layer "F.Cu")
		(net "GPU_BASE_FPGA_READY")
	)
	(segment
		(start 56.66486 -384.973068)
		(end 56.66486 -385.659884)
		(width 0.13208)
		(layer "F.Cu")
		(net "GPU_BASE_FPGA_READY")
	)
	(segment
		(start 56.66486 -385.659884)
		(end 56.723788 -385.718812)
		(width 0.13208)
		(layer "F.Cu")
		(net "GPU_BASE_FPGA_READY")
	)
	(segment
		(start 58.286142 -385.718812)
		(end 57.804812 -385.718812)
		(width 0.13208)
		(layer "F.Cu")
		(net "GPU_BASE_FPGA_READY")
	)
	(via
		(at 56.723788 -385.718812)
		(size 0.508)
		(drill 0.254)
		(layers "F.Cu" "B.Cu")
		(net "GPU_BASE_FPGA_READY")
	)
	(segment
		(start 56.723788 -386.179314)
		(end 53.038502 -389.8646)
		(width 0.15494)
		(layer "In9.Cu")
		(net "GPU_BASE_FPGA_READY")
	)
	(segment
		(start 53.038502 -389.8646)
		(end 51.257454 -389.8646)
		(width 0.15494)
		(layer "In9.Cu")
		(net "GPU_BASE_FPGA_READY")
	)
	(segment
		(start 48.8696 -392.252454)
		(end 48.8696 -401.630642)
		(width 0.15494)
		(layer "In9.Cu")
		(net "GPU_BASE_FPGA_READY")
	)
	(segment
		(start 48.8696 -401.630642)
		(end 47.71009 -402.790152)
		(width 0.15494)
		(layer "In9.Cu")
		(net "GPU_BASE_FPGA_READY")
	)
	(segment
		(start 56.723788 -385.718812)
		(end 56.723788 -386.179314)
		(width 0.15494)
		(layer "In9.Cu")
		(net "GPU_BASE_FPGA_READY")
	)
	(segment
		(start 51.257454 -389.8646)
		(end 48.8696 -392.252454)
		(width 0.15494)
		(layer "In9.Cu")
		(net "GPU_BASE_FPGA_READY")
	)
	(segment
		(start 335.693766 -228.313488)
		(end 335.693766 -227.987098)
		(width 0.13208)
		(layer "F.Cu")
		(net "RST_GPU_PERST_0_N")
	)
	(segment
		(start 335.407 -228.600254)
		(end 335.693766 -228.313488)
		(width 0.13208)
		(layer "F.Cu")
		(net "RST_GPU_PERST_0_N")
	)
	(segment
		(start 335.153 -228.981)
		(end 335.407 -228.727)
		(width 0.13208)
		(layer "F.Cu")
		(net "RST_GPU_PERST_0_N")
	)
	(segment
		(start 335.407 -228.727)
		(end 335.407 -228.600254)
		(width 0.13208)
		(layer "F.Cu")
		(net "RST_GPU_PERST_0_N")
	)
	(via
		(at 335.153 -228.981)
		(size 0.508)
		(drill 0.254)
		(layers "F.Cu" "B.Cu")
		(net "RST_GPU_PERST_0_N")
	)
	(via
		(at 298.313094 -232.28681)
		(size 0.508)
		(drill 0.254)
		(layers "F.Cu" "B.Cu")
		(net "RST_GPU_PERST_0_N")
	)
	(segment
		(start 298.569126 -235.900468)
		(end 298.569126 -232.542842)
		(width 0.13208)
		(layer "B.Cu")
		(net "RST_GPU_PERST_0_N")
	)
	(segment
		(start 300.012354 -235.358686)
		(end 300.012354 -236.336586)
		(width 0.13208)
		(layer "B.Cu")
		(net "RST_GPU_PERST_0_N")
	)
	(segment
		(start 299.005244 -236.336586)
		(end 298.569126 -235.900468)
		(width 0.13208)
		(layer "B.Cu")
		(net "RST_GPU_PERST_0_N")
	)
	(segment
		(start 300.012354 -236.336586)
		(end 299.005244 -236.336586)
		(width 0.13208)
		(layer "B.Cu")
		(net "RST_GPU_PERST_0_N")
	)
	(segment
		(start 298.569126 -232.542842)
		(end 298.313094 -232.28681)
		(width 0.13208)
		(layer "B.Cu")
		(net "RST_GPU_PERST_0_N")
	)
	(segment
		(start 323.553328 -231.48798)
		(end 323.147436 -231.893872)
		(width 0.15494)
		(layer "In13.Cu")
		(net "RST_GPU_PERST_0_N")
	)
	(segment
		(start 326.5932 -231.9528)
		(end 325.092314 -231.9528)
		(width 0.15494)
		(layer "In13.Cu")
		(net "RST_GPU_PERST_0_N")
	)
	(segment
		(start 333.78267 -229.2858)
		(end 331.62367 -231.4448)
		(width 0.15494)
		(layer "In13.Cu")
		(net "RST_GPU_PERST_0_N")
	)
	(segment
		(start 324.627494 -231.48798)
		(end 323.553328 -231.48798)
		(width 0.15494)
		(layer "In13.Cu")
		(net "RST_GPU_PERST_0_N")
	)
	(segment
		(start 325.092314 -231.9528)
		(end 324.627494 -231.48798)
		(width 0.15494)
		(layer "In13.Cu")
		(net "RST_GPU_PERST_0_N")
	)
	(segment
		(start 298.706032 -231.893872)
		(end 298.313094 -232.28681)
		(width 0.15494)
		(layer "In13.Cu")
		(net "RST_GPU_PERST_0_N")
	)
	(segment
		(start 334.8482 -229.2858)
		(end 333.78267 -229.2858)
		(width 0.15494)
		(layer "In13.Cu")
		(net "RST_GPU_PERST_0_N")
	)
	(segment
		(start 335.153 -228.981)
		(end 334.8482 -229.2858)
		(width 0.15494)
		(layer "In13.Cu")
		(net "RST_GPU_PERST_0_N")
	)
	(segment
		(start 327.1012 -231.4448)
		(end 326.5932 -231.9528)
		(width 0.15494)
		(layer "In13.Cu")
		(net "RST_GPU_PERST_0_N")
	)
	(segment
		(start 323.147436 -231.893872)
		(end 298.706032 -231.893872)
		(width 0.15494)
		(layer "In13.Cu")
		(net "RST_GPU_PERST_0_N")
	)
	(segment
		(start 331.62367 -231.4448)
		(end 327.1012 -231.4448)
		(width 0.15494)
		(layer "In13.Cu")
		(net "RST_GPU_PERST_0_N")
	)
	(segment
		(start 340.493858 -215.187022)
		(end 340.094062 -214.787226)
		(width 0.13208)
		(layer "F.Cu")
		(net "SSD11_PWRDIS")
	)
	(segment
		(start 337.566 -201.56805)
		(end 337.566 -202.184)
		(width 0.13208)
		(layer "F.Cu")
		(net "SSD11_PWRDIS")
	)
	(via
		(at 337.566 -202.184)
		(size 0.508)
		(drill 0.254)
		(layers "F.Cu" "B.Cu")
		(net "SSD11_PWRDIS")
	)
	(via
		(at 340.094062 -214.787226)
		(size 0.4572)
		(drill 0.254)
		(layers "F.Cu" "B.Cu")
		(net "SSD11_PWRDIS")
	)
	(segment
		(start 338.593684 -206.435452)
		(end 338.593684 -205.001368)
		(width 0.15494)
		(layer "In5.Cu")
		(net "SSD11_PWRDIS")
	)
	(segment
		(start 338.593684 -205.001368)
		(end 338.09305 -204.500734)
		(width 0.15494)
		(layer "In5.Cu")
		(net "SSD11_PWRDIS")
	)
	(segment
		(start 338.09305 -204.500734)
		(end 338.09305 -202.71105)
		(width 0.15494)
		(layer "In5.Cu")
		(net "SSD11_PWRDIS")
	)
	(segment
		(start 340.491572 -214.389716)
		(end 340.491572 -212.217)
		(width 0.0889)
		(layer "In5.Cu")
		(net "SSD11_PWRDIS")
	)
	(segment
		(start 338.09305 -202.71105)
		(end 337.566 -202.184)
		(width 0.15494)
		(layer "In5.Cu")
		(net "SSD11_PWRDIS")
	)
	(segment
		(start 340.094062 -214.787226)
		(end 340.491572 -214.389716)
		(width 0.0889)
		(layer "In5.Cu")
		(net "SSD11_PWRDIS")
	)
	(segment
		(start 340.491572 -208.33334)
		(end 338.593684 -206.435452)
		(width 0.15494)
		(layer "In5.Cu")
		(net "SSD11_PWRDIS")
	)
	(segment
		(start 340.491572 -212.217)
		(end 340.491572 -208.33334)
		(width 0.15494)
		(layer "In5.Cu")
		(net "SSD11_PWRDIS")
	)
	(segment
		(start 400.585432 -15.370302)
		(end 400.585432 -16.439388)
		(width 0.13208)
		(layer "F.Cu")
		(net "SMB_ISO_SSD13_SCL")
	)
	(segment
		(start 397.556482 -17.669256)
		(end 398.324324 -18.437098)
		(width 0.13208)
		(layer "F.Cu")
		(net "SMB_ISO_SSD13_SCL")
	)
	(segment
		(start 400.585432 -16.439388)
		(end 400.585432 -18.337022)
		(width 0.13208)
		(layer "F.Cu")
		(net "SMB_ISO_SSD13_SCL")
	)
	(segment
		(start 399.931636 -18.990818)
		(end 398.921732 -18.990818)
		(width 0.13208)
		(layer "F.Cu")
		(net "SMB_ISO_SSD13_SCL")
	)
	(segment
		(start 400.759422 -23.355554)
		(end 400.759422 -23.965154)
		(width 0.13208)
		(layer "F.Cu")
		(net "SMB_ISO_SSD13_SCL")
	)
	(segment
		(start 398.324324 -18.437098)
		(end 398.368012 -18.437098)
		(width 0.13208)
		(layer "F.Cu")
		(net "SMB_ISO_SSD13_SCL")
	)
	(segment
		(start 400.585432 -18.337022)
		(end 399.931636 -18.990818)
		(width 0.13208)
		(layer "F.Cu")
		(net "SMB_ISO_SSD13_SCL")
	)
	(segment
		(start 397.556482 -17.419574)
		(end 397.556482 -17.669256)
		(width 0.13208)
		(layer "F.Cu")
		(net "SMB_ISO_SSD13_SCL")
	)
	(segment
		(start 398.921732 -18.990818)
		(end 398.368012 -18.437098)
		(width 0.13208)
		(layer "F.Cu")
		(net "SMB_ISO_SSD13_SCL")
	)
	(via
		(at 400.585432 -15.370302)
		(size 0.508)
		(drill 0.254)
		(layers "F.Cu" "B.Cu")
		(net "SMB_ISO_SSD13_SCL")
	)
	(via
		(at 400.759422 -23.965154)
		(size 0.508)
		(drill 0.254)
		(layers "F.Cu" "B.Cu")
		(net "SMB_ISO_SSD13_SCL")
	)
	(segment
		(start 402.101812 -16.886682)
		(end 400.585432 -15.370302)
		(width 0.13208)
		(layer "B.Cu")
		(net "SMB_ISO_SSD13_SCL")
	)
	(segment
		(start 400.759422 -23.965154)
		(end 402.101812 -22.622764)
		(width 0.13208)
		(layer "B.Cu")
		(net "SMB_ISO_SSD13_SCL")
	)
	(segment
		(start 402.101812 -22.622764)
		(end 402.101812 -16.886682)
		(width 0.13208)
		(layer "B.Cu")
		(net "SMB_ISO_SSD13_SCL")
	)
	(segment
		(start 357.565706 -232.457244)
		(end 357.565706 -231.428798)
		(width 0.13208)
		(layer "F.Cu")
		(net "FPGA_JTAGENB")
	)
	(segment
		(start 344.49385 -224.786952)
		(end 344.893646 -225.186748)
		(width 0.13208)
		(layer "F.Cu")
		(net "FPGA_JTAGENB")
	)
	(segment
		(start 357.565706 -232.457244)
		(end 356.80904 -232.457244)
		(width 0.13208)
		(layer "F.Cu")
		(net "FPGA_JTAGENB")
	)
	(via
		(at 344.893646 -225.186748)
		(size 0.4572)
		(drill 0.254)
		(layers "F.Cu" "B.Cu")
		(net "FPGA_JTAGENB")
	)
	(via
		(at 356.80904 -232.457244)
		(size 0.508)
		(drill 0.254)
		(layers "F.Cu" "B.Cu")
		(net "FPGA_JTAGENB")
	)
	(segment
		(start 347.299534 -230.53421)
		(end 345.293696 -228.528372)
		(width 0.15494)
		(layer "In7.Cu")
		(net "FPGA_JTAGENB")
	)
	(segment
		(start 345.293696 -225.586798)
		(end 344.893646 -225.186748)
		(width 0.0889)
		(layer "In7.Cu")
		(net "FPGA_JTAGENB")
	)
	(segment
		(start 353.190556 -232.974388)
		(end 347.299534 -230.53421)
		(width 0.15494)
		(layer "In7.Cu")
		(net "FPGA_JTAGENB")
	)
	(segment
		(start 345.293696 -227.0252)
		(end 345.293696 -225.586798)
		(width 0.0889)
		(layer "In7.Cu")
		(net "FPGA_JTAGENB")
	)
	(segment
		(start 345.293696 -228.528372)
		(end 345.293696 -227.0252)
		(width 0.15494)
		(layer "In7.Cu")
		(net "FPGA_JTAGENB")
	)
	(segment
		(start 356.80904 -232.457244)
		(end 356.291896 -232.974388)
		(width 0.15494)
		(layer "In7.Cu")
		(net "FPGA_JTAGENB")
	)
	(segment
		(start 356.291896 -232.974388)
		(end 353.190556 -232.974388)
		(width 0.15494)
		(layer "In7.Cu")
		(net "FPGA_JTAGENB")
	)
	(segment
		(start 342.093804 -212.786976)
		(end 341.694008 -212.38718)
		(width 0.13208)
		(layer "F.Cu")
		(net "RST_SSD14_PERST_N")
	)
	(via
		(at 341.694008 -212.38718)
		(size 0.4572)
		(drill 0.254)
		(layers "F.Cu" "B.Cu")
		(net "RST_SSD14_PERST_N")
	)
	(via
		(at 342.392 -211.328)
		(size 0.6604)
		(drill 0.3302)
		(layers "F.Cu" "B.Cu")
		(net "RST_SSD14_PERST_N")
	)
	(segment
		(start 342.011 -210.439)
		(end 342.011 -208.17205)
		(width 0.13208)
		(layer "B.Cu")
		(net "RST_SSD14_PERST_N")
	)
	(segment
		(start 341.694008 -212.38718)
		(end 342.392 -211.689188)
		(width 0.13208)
		(layer "B.Cu")
		(net "RST_SSD14_PERST_N")
	)
	(segment
		(start 342.392 -211.689188)
		(end 342.392 -211.328)
		(width 0.13208)
		(layer "B.Cu")
		(net "RST_SSD14_PERST_N")
	)
	(segment
		(start 342.392 -210.82)
		(end 342.011 -210.439)
		(width 0.13208)
		(layer "B.Cu")
		(net "RST_SSD14_PERST_N")
	)
	(segment
		(start 342.392 -211.328)
		(end 342.392 -210.82)
		(width 0.13208)
		(layer "B.Cu")
		(net "RST_SSD14_PERST_N")
	)
	(via
		(at 388.390638 -245.64086)
		(size 0.6604)
		(drill 0.3302)
		(layers "F.Cu" "B.Cu")
		(net "UART_PEX2_SDB_BUF_R_RX")
	)
	(segment
		(start 388.202678 -246.256048)
		(end 388.202678 -246.765064)
		(width 0.13208)
		(layer "B.Cu")
		(net "UART_PEX2_SDB_BUF_R_RX")
	)
	(segment
		(start 387.618986 -244.993668)
		(end 388.125716 -244.993668)
		(width 0.13208)
		(layer "B.Cu")
		(net "UART_PEX2_SDB_BUF_R_RX")
	)
	(segment
		(start 387.491986 -244.204998)
		(end 387.491986 -244.866668)
		(width 0.13208)
		(layer "B.Cu")
		(net "UART_PEX2_SDB_BUF_R_RX")
	)
	(segment
		(start 388.125716 -244.993668)
		(end 388.390638 -245.25859)
		(width 0.13208)
		(layer "B.Cu")
		(net "UART_PEX2_SDB_BUF_R_RX")
	)
	(segment
		(start 388.390638 -245.64086)
		(end 388.390638 -246.068088)
		(width 0.13208)
		(layer "B.Cu")
		(net "UART_PEX2_SDB_BUF_R_RX")
	)
	(segment
		(start 388.390638 -246.068088)
		(end 388.202678 -246.256048)
		(width 0.13208)
		(layer "B.Cu")
		(net "UART_PEX2_SDB_BUF_R_RX")
	)
	(segment
		(start 387.491986 -244.866668)
		(end 387.618986 -244.993668)
		(width 0.13208)
		(layer "B.Cu")
		(net "UART_PEX2_SDB_BUF_R_RX")
	)
	(segment
		(start 388.390638 -245.25859)
		(end 388.390638 -245.64086)
		(width 0.13208)
		(layer "B.Cu")
		(net "UART_PEX2_SDB_BUF_R_RX")
	)
	(segment
		(start 285.86049 -20.789392)
		(end 285.86049 -21.05279)
		(width 0.13208)
		(layer "F.Cu")
		(net "SMB_SSD9_ISO_EN")
	)
	(segment
		(start 285.86049 -21.05279)
		(end 286.654748 -21.847048)
		(width 0.13208)
		(layer "F.Cu")
		(net "SMB_SSD9_ISO_EN")
	)
	(segment
		(start 286.654748 -21.847048)
		(end 286.654748 -22.561296)
		(width 0.13208)
		(layer "F.Cu")
		(net "SMB_SSD9_ISO_EN")
	)
	(via
		(at 286.654748 -21.847048)
		(size 0.508)
		(drill 0.254)
		(layers "F.Cu" "B.Cu")
		(net "SMB_SSD9_ISO_EN")
	)
	(segment
		(start 341.293958 -215.187022)
		(end 340.894162 -214.787226)
		(width 0.13208)
		(layer "F.Cu")
		(net "PRSNT_SSD13_R_N")
	)
	(segment
		(start 381.409194 -26.03373)
		(end 381.409194 -27.04973)
		(width 0.13208)
		(layer "F.Cu")
		(net "PRSNT_SSD13_R_N")
	)
	(segment
		(start 382.420622 -27.066494)
		(end 383.242566 -27.066494)
		(width 0.13208)
		(layer "F.Cu")
		(net "PRSNT_SSD13_R_N")
	)
	(segment
		(start 380.875794 -36.515548)
		(end 381.696214 -36.515548)
		(width 0.13208)
		(layer "F.Cu")
		(net "PRSNT_SSD13_R_N")
	)
	(segment
		(start 233.867706 -222.304102)
		(end 234.267502 -222.703898)
		(width 0.13208)
		(layer "F.Cu")
		(net "PRSNT_SSD13_R_N")
	)
	(segment
		(start 382.403858 -27.04973)
		(end 382.420622 -27.066494)
		(width 0.13208)
		(layer "F.Cu")
		(net "PRSNT_SSD13_R_N")
	)
	(segment
		(start 381.409194 -27.04973)
		(end 382.403858 -27.04973)
		(width 0.13208)
		(layer "F.Cu")
		(net "PRSNT_SSD13_R_N")
	)
	(via
		(at 340.894162 -214.787226)
		(size 0.4572)
		(drill 0.254)
		(layers "F.Cu" "B.Cu")
		(net "PRSNT_SSD13_R_N")
	)
	(via
		(at 381.696214 -36.515548)
		(size 0.508)
		(drill 0.254)
		(layers "F.Cu" "B.Cu")
		(net "PRSNT_SSD13_R_N")
	)
	(via
		(at 234.267502 -222.703898)
		(size 0.4572)
		(drill 0.254)
		(layers "F.Cu" "B.Cu")
		(net "PRSNT_SSD13_R_N")
	)
	(via
		(at 374.709944 -104.770428)
		(size 0.508)
		(drill 0.254)
		(layers "F.Cu" "B.Cu")
		(net "PRSNT_SSD13_R_N")
	)
	(via
		(at 383.242566 -27.066494)
		(size 0.508)
		(drill 0.254)
		(layers "F.Cu" "B.Cu")
		(net "PRSNT_SSD13_R_N")
	)
	(via
		(at 246.593106 -185.400442)
		(size 0.508)
		(drill 0.254)
		(layers "F.Cu" "B.Cu")
		(net "PRSNT_SSD13_R_N")
	)
	(via
		(at 352.32975 -105.997248)
		(size 0.508)
		(drill 0.254)
		(layers "F.Cu" "B.Cu")
		(net "PRSNT_SSD13_R_N")
	)
	(segment
		(start 381.70612 -39.064946)
		(end 381.70612 -36.525454)
		(width 0.15494)
		(layer "In5.Cu")
		(net "PRSNT_SSD13_R_N")
	)
	(segment
		(start 380.063502 -34.882836)
		(end 380.063502 -29.696664)
		(width 0.15494)
		(layer "In5.Cu")
		(net "PRSNT_SSD13_R_N")
	)
	(segment
		(start 381.696214 -36.515548)
		(end 380.063502 -34.882836)
		(width 0.15494)
		(layer "In5.Cu")
		(net "PRSNT_SSD13_R_N")
	)
	(segment
		(start 380.063502 -29.696664)
		(end 382.693672 -27.066494)
		(width 0.15494)
		(layer "In5.Cu")
		(net "PRSNT_SSD13_R_N")
	)
	(segment
		(start 381.70612 -36.525454)
		(end 381.696214 -36.515548)
		(width 0.15494)
		(layer "In5.Cu")
		(net "PRSNT_SSD13_R_N")
	)
	(segment
		(start 383.345436 -68.706238)
		(end 386.74675 -65.304924)
		(width 0.15494)
		(layer "In5.Cu")
		(net "PRSNT_SSD13_R_N")
	)
	(segment
		(start 382.693672 -27.066494)
		(end 383.242566 -27.066494)
		(width 0.15494)
		(layer "In5.Cu")
		(net "PRSNT_SSD13_R_N")
	)
	(segment
		(start 374.99036 -100.529644)
		(end 383.345436 -92.174568)
		(width 0.15494)
		(layer "In5.Cu")
		(net "PRSNT_SSD13_R_N")
	)
	(segment
		(start 374.99036 -104.490012)
		(end 374.99036 -100.529644)
		(width 0.15494)
		(layer "In5.Cu")
		(net "PRSNT_SSD13_R_N")
	)
	(segment
		(start 374.709944 -104.770428)
		(end 374.99036 -104.490012)
		(width 0.15494)
		(layer "In5.Cu")
		(net "PRSNT_SSD13_R_N")
	)
	(segment
		(start 386.74675 -65.304924)
		(end 386.74675 -44.105576)
		(width 0.15494)
		(layer "In5.Cu")
		(net "PRSNT_SSD13_R_N")
	)
	(segment
		(start 383.345436 -92.174568)
		(end 383.345436 -68.706238)
		(width 0.15494)
		(layer "In5.Cu")
		(net "PRSNT_SSD13_R_N")
	)
	(segment
		(start 386.74675 -44.105576)
		(end 381.70612 -39.064946)
		(width 0.15494)
		(layer "In5.Cu")
		(net "PRSNT_SSD13_R_N")
	)
	(segment
		(start 340.802976 -208.863438)
		(end 342.622886 -207.043528)
		(width 0.15494)
		(layer "In7.Cu")
		(net "PRSNT_SSD13_R_N")
	)
	(segment
		(start 234.6452 -219.303854)
		(end 234.91063 -219.038424)
		(width 0.0889)
		(layer "In7.Cu")
		(net "PRSNT_SSD13_R_N")
	)
	(segment
		(start 240.64722 -210.12912)
		(end 241.02822 -210.12912)
		(width 0.15494)
		(layer "In7.Cu")
		(net "PRSNT_SSD13_R_N")
	)
	(segment
		(start 345.002866 -126.668276)
		(end 352.138234 -119.532908)
		(width 0.15494)
		(layer "In7.Cu")
		(net "PRSNT_SSD13_R_N")
	)
	(segment
		(start 352.138234 -119.532908)
		(end 352.138234 -106.768138)
		(width 0.15494)
		(layer "In7.Cu")
		(net "PRSNT_SSD13_R_N")
	)
	(segment
		(start 342.622886 -207.043528)
		(end 342.622886 -205.688692)
		(width 0.15494)
		(layer "In7.Cu")
		(net "PRSNT_SSD13_R_N")
	)
	(segment
		(start 241.29492 -209.507074)
		(end 241.30889 -209.493104)
		(width 0.15494)
		(layer "In7.Cu")
		(net "PRSNT_SSD13_R_N")
	)
	(segment
		(start 340.894162 -214.787226)
		(end 340.494112 -214.387176)
		(width 0.0889)
		(layer "In7.Cu")
		(net "PRSNT_SSD13_R_N")
	)
	(segment
		(start 340.494112 -214.387176)
		(end 340.494112 -212.073744)
		(width 0.0889)
		(layer "In7.Cu")
		(net "PRSNT_SSD13_R_N")
	)
	(segment
		(start 241.30889 -209.492596)
		(end 241.910362 -208.891124)
		(width 0.15494)
		(layer "In7.Cu")
		(net "PRSNT_SSD13_R_N")
	)
	(segment
		(start 342.622886 -205.688692)
		(end 343.12987 -205.181708)
		(width 0.15494)
		(layer "In7.Cu")
		(net "PRSNT_SSD13_R_N")
	)
	(segment
		(start 234.6452 -222.3262)
		(end 234.6452 -219.303854)
		(width 0.0889)
		(layer "In7.Cu")
		(net "PRSNT_SSD13_R_N")
	)
	(segment
		(start 246.593106 -186.584082)
		(end 246.593106 -185.400442)
		(width 0.15494)
		(layer "In7.Cu")
		(net "PRSNT_SSD13_R_N")
	)
	(segment
		(start 242.621054 -208.790286)
		(end 243.28374 -208.1276)
		(width 0.15494)
		(layer "In7.Cu")
		(net "PRSNT_SSD13_R_N")
	)
	(segment
		(start 352.138234 -106.768138)
		(end 352.32975 -106.576622)
		(width 0.15494)
		(layer "In7.Cu")
		(net "PRSNT_SSD13_R_N")
	)
	(segment
		(start 243.28374 -206.902304)
		(end 243.36502 -206.821024)
		(width 0.15494)
		(layer "In7.Cu")
		(net "PRSNT_SSD13_R_N")
	)
	(segment
		(start 241.29492 -209.86242)
		(end 241.29492 -209.507074)
		(width 0.15494)
		(layer "In7.Cu")
		(net "PRSNT_SSD13_R_N")
	)
	(segment
		(start 343.12987 -205.181708)
		(end 343.12987 -197.907402)
		(width 0.15494)
		(layer "In7.Cu")
		(net "PRSNT_SSD13_R_N")
	)
	(segment
		(start 340.802976 -211.76488)
		(end 340.802976 -208.863438)
		(width 0.15494)
		(layer "In7.Cu")
		(net "PRSNT_SSD13_R_N")
	)
	(segment
		(start 244.72138 -203.207112)
		(end 244.7798 -203.148692)
		(width 0.15494)
		(layer "In7.Cu")
		(net "PRSNT_SSD13_R_N")
	)
	(segment
		(start 241.910362 -208.891124)
		(end 242.153694 -208.790286)
		(width 0.15494)
		(layer "In7.Cu")
		(net "PRSNT_SSD13_R_N")
	)
	(segment
		(start 235.9152 -213.277704)
		(end 237.128304 -212.0646)
		(width 0.15494)
		(layer "In7.Cu")
		(net "PRSNT_SSD13_R_N")
	)
	(segment
		(start 244.72138 -203.208636)
		(end 244.72138 -203.207112)
		(width 0.15494)
		(layer "In7.Cu")
		(net "PRSNT_SSD13_R_N")
	)
	(segment
		(start 342.58123 -196.582538)
		(end 342.58123 -189.117224)
		(width 0.15494)
		(layer "In7.Cu")
		(net "PRSNT_SSD13_R_N")
	)
	(segment
		(start 347.023436 -184.675018)
		(end 347.023436 -169.325036)
		(width 0.15494)
		(layer "In7.Cu")
		(net "PRSNT_SSD13_R_N")
	)
	(segment
		(start 340.494112 -212.073744)
		(end 340.622128 -211.945728)
		(width 0.0889)
		(layer "In7.Cu")
		(net "PRSNT_SSD13_R_N")
	)
	(segment
		(start 236.039152 -219.038424)
		(end 236.536992 -218.540584)
		(width 0.15494)
		(layer "In7.Cu")
		(net "PRSNT_SSD13_R_N")
	)
	(segment
		(start 244.7798 -203.148692)
		(end 244.7798 -188.397388)
		(width 0.15494)
		(layer "In7.Cu")
		(net "PRSNT_SSD13_R_N")
	)
	(segment
		(start 352.32975 -106.576622)
		(end 352.32975 -105.997248)
		(width 0.15494)
		(layer "In7.Cu")
		(net "PRSNT_SSD13_R_N")
	)
	(segment
		(start 340.622128 -211.945728)
		(end 340.802976 -211.76488)
		(width 0.15494)
		(layer "In7.Cu")
		(net "PRSNT_SSD13_R_N")
	)
	(segment
		(start 241.02822 -210.12912)
		(end 241.29492 -209.86242)
		(width 0.15494)
		(layer "In7.Cu")
		(net "PRSNT_SSD13_R_N")
	)
	(segment
		(start 243.36502 -204.564996)
		(end 244.72138 -203.208636)
		(width 0.15494)
		(layer "In7.Cu")
		(net "PRSNT_SSD13_R_N")
	)
	(segment
		(start 235.9152 -216.6874)
		(end 235.9152 -213.277704)
		(width 0.15494)
		(layer "In7.Cu")
		(net "PRSNT_SSD13_R_N")
	)
	(segment
		(start 236.536992 -218.540584)
		(end 236.536992 -217.309192)
		(width 0.15494)
		(layer "In7.Cu")
		(net "PRSNT_SSD13_R_N")
	)
	(segment
		(start 241.30889 -209.493104)
		(end 241.30889 -209.492596)
		(width 0.15494)
		(layer "In7.Cu")
		(net "PRSNT_SSD13_R_N")
	)
	(segment
		(start 243.28374 -208.1276)
		(end 243.28374 -206.902304)
		(width 0.15494)
		(layer "In7.Cu")
		(net "PRSNT_SSD13_R_N")
	)
	(segment
		(start 238.71174 -212.0646)
		(end 240.64722 -210.12912)
		(width 0.15494)
		(layer "In7.Cu")
		(net "PRSNT_SSD13_R_N")
	)
	(segment
		(start 236.536992 -217.309192)
		(end 235.9152 -216.6874)
		(width 0.15494)
		(layer "In7.Cu")
		(net "PRSNT_SSD13_R_N")
	)
	(segment
		(start 243.36502 -206.821024)
		(end 243.36502 -204.564996)
		(width 0.15494)
		(layer "In7.Cu")
		(net "PRSNT_SSD13_R_N")
	)
	(segment
		(start 347.023436 -169.325036)
		(end 345.002866 -167.304466)
		(width 0.15494)
		(layer "In7.Cu")
		(net "PRSNT_SSD13_R_N")
	)
	(segment
		(start 237.128304 -212.0646)
		(end 238.71174 -212.0646)
		(width 0.15494)
		(layer "In7.Cu")
		(net "PRSNT_SSD13_R_N")
	)
	(segment
		(start 342.58123 -189.117224)
		(end 347.023436 -184.675018)
		(width 0.15494)
		(layer "In7.Cu")
		(net "PRSNT_SSD13_R_N")
	)
	(segment
		(start 343.12987 -197.907402)
		(end 342.58123 -196.582538)
		(width 0.15494)
		(layer "In7.Cu")
		(net "PRSNT_SSD13_R_N")
	)
	(segment
		(start 244.7798 -188.397388)
		(end 246.593106 -186.584082)
		(width 0.15494)
		(layer "In7.Cu")
		(net "PRSNT_SSD13_R_N")
	)
	(segment
		(start 234.91063 -219.038424)
		(end 236.039152 -219.038424)
		(width 0.15494)
		(layer "In7.Cu")
		(net "PRSNT_SSD13_R_N")
	)
	(segment
		(start 242.153694 -208.790286)
		(end 242.621054 -208.790286)
		(width 0.15494)
		(layer "In7.Cu")
		(net "PRSNT_SSD13_R_N")
	)
	(segment
		(start 345.002866 -167.304466)
		(end 345.002866 -126.668276)
		(width 0.15494)
		(layer "In7.Cu")
		(net "PRSNT_SSD13_R_N")
	)
	(segment
		(start 234.267502 -222.703898)
		(end 234.6452 -222.3262)
		(width 0.0889)
		(layer "In7.Cu")
		(net "PRSNT_SSD13_R_N")
	)
	(segment
		(start 256.332228 -190.487046)
		(end 256.332228 -189.815724)
		(width 0.15494)
		(layer "In13.Cu")
		(net "PRSNT_SSD13_R_N")
	)
	(segment
		(start 334.1624 -214.387684)
		(end 333.981044 -214.56904)
		(width 0.15494)
		(layer "In13.Cu")
		(net "PRSNT_SSD13_R_N")
	)
	(segment
		(start 352.32975 -105.997248)
		(end 353.309428 -105.01757)
		(width 0.15494)
		(layer "In13.Cu")
		(net "PRSNT_SSD13_R_N")
	)
	(segment
		(start 337.166204 -214.387684)
		(end 334.1624 -214.387684)
		(width 0.0889)
		(layer "In13.Cu")
		(net "PRSNT_SSD13_R_N")
	)
	(segment
		(start 246.903748 -185.0898)
		(end 246.593106 -185.400442)
		(width 0.15494)
		(layer "In13.Cu")
		(net "PRSNT_SSD13_R_N")
	)
	(segment
		(start 340.49462 -213.686644)
		(end 340.39302 -213.585044)
		(width 0.0889)
		(layer "In13.Cu")
		(net "PRSNT_SSD13_R_N")
	)
	(segment
		(start 353.309428 -105.01757)
		(end 374.462802 -105.01757)
		(width 0.15494)
		(layer "In13.Cu")
		(net "PRSNT_SSD13_R_N")
	)
	(segment
		(start 328.18959 -209.60588)
		(end 327.1266 -210.66887)
		(width 0.15494)
		(layer "In13.Cu")
		(net "PRSNT_SSD13_R_N")
	)
	(segment
		(start 260.792214 -194.7672)
		(end 259.454142 -194.7672)
		(width 0.15494)
		(layer "In13.Cu")
		(net "PRSNT_SSD13_R_N")
	)
	(segment
		(start 337.295998 -213.789768)
		(end 337.295998 -214.25789)
		(width 0.0889)
		(layer "In13.Cu")
		(net "PRSNT_SSD13_R_N")
	)
	(segment
		(start 333.981044 -214.56904)
		(end 332.618334 -214.56904)
		(width 0.15494)
		(layer "In13.Cu")
		(net "PRSNT_SSD13_R_N")
	)
	(segment
		(start 327.1266 -210.66887)
		(end 322.58381 -210.66887)
		(width 0.15494)
		(layer "In13.Cu")
		(net "PRSNT_SSD13_R_N")
	)
	(segment
		(start 340.894162 -214.56269)
		(end 340.49462 -214.163148)
		(width 0.0889)
		(layer "In13.Cu")
		(net "PRSNT_SSD13_R_N")
	)
	(segment
		(start 340.894162 -214.787226)
		(end 340.894162 -214.56269)
		(width 0.0889)
		(layer "In13.Cu")
		(net "PRSNT_SSD13_R_N")
	)
	(segment
		(start 329.49515 -209.60588)
		(end 328.18959 -209.60588)
		(width 0.15494)
		(layer "In13.Cu")
		(net "PRSNT_SSD13_R_N")
	)
)
